(kicad_pcb
	(version 20260206)
	(generator "pcbnew")
	(generator_version "10.0")
	(general
		(thickness 1.6)
		(legacy_teardrops no)
	)
	(paper "A4")
	(layers
		(0 "F.Cu" signal "TOP")
		(4 "In1.Cu" signal "L2GND")
		(6 "In2.Cu" signal "L3")
		(8 "In3.Cu" signal "L4GND")
		(10 "In4.Cu" signal "L5")
		(12 "In5.Cu" signal "L6GND")
		(14 "In6.Cu" signal "L7VCC")
		(16 "In7.Cu" signal "L8VCC")
		(18 "In8.Cu" signal "L9GND")
		(20 "In9.Cu" signal "L10")
		(22 "In10.Cu" signal "L11GND")
		(24 "In11.Cu" signal "L12")
		(26 "In12.Cu" signal "L13GND")
		(2 "B.Cu" signal "BOTTOM")
		(9 "F.Adhes" user "F.Adhesive")
		(11 "B.Adhes" user "B.Adhesive")
		(13 "F.Paste" user "Package Geometry/Pastemask Top")
		(15 "B.Paste" user "Package Geometry/Pastemask Bottom")
		(5 "F.SilkS" user "Ref Des/Silkscreen Top")
		(7 "B.SilkS" user "Ref Des/Silkscreen Bottom")
		(1 "F.Mask" user "Board Geometry/Soldermask Top")
		(3 "B.Mask" user "Board Geometry/Soldermask Bottom")
		(17 "Dwgs.User" user "User.Drawings")
		(19 "Cmts.User" user "User.Comments")
		(21 "Eco1.User" user "User.Eco1")
		(23 "Eco2.User" user "User.Eco2")
		(25 "Edge.Cuts" user "Board Geometry/Outline")
		(27 "Margin" user)
		(31 "F.CrtYd" user "Package Geometry/Place Bound Top")
		(29 "B.CrtYd" user "Package Geometry/Place Bound Bottom")
		(35 "F.Fab" user "Ref Des/Assembly Top")
		(33 "B.Fab" user "Ref Des/Assembly Bottom")
	)
	(setup
		(pad_to_mask_clearance 0)
		(allow_soldermask_bridges_in_footprints no)
		(tenting
			(front yes)
			(back yes)
		)
		(covering
			(front no)
			(back no)
		)
		(plugging
			(front no)
			(back no)
		)
		(capping no)
		(filling no)
		(pcbplotparams
			(layerselection 0x00000000_00000000_55555555_5755f5ff)
			(plot_on_all_layers_selection 0x00000000_00000000_00000000_00000000)
			(disableapertmacros no)
			(usegerberextensions no)
			(usegerberattributes yes)
			(usegerberadvancedattributes yes)
			(creategerberjobfile yes)
			(dashed_line_dash_ratio 12)
			(dashed_line_gap_ratio 3)
			(svgprecision 4)
			(plotframeref no)
			(mode 1)
			(useauxorigin no)
			(pdf_front_fp_property_popups yes)
			(pdf_back_fp_property_popups yes)
			(pdf_metadata yes)
			(pdf_single_document no)
			(dxfpolygonmode yes)
			(dxfimperialunits yes)
			(dxfusepcbnewfont yes)
			(psnegative no)
			(psa4output no)
			(plot_black_and_white yes)
			(sketchpadsonfab no)
			(plotpadnumbers no)
			(hidednponfab no)
			(sketchdnponfab yes)
			(crossoutdnponfab yes)
			(subtractmaskfromsilk no)
			(outputformat 1)
			(mirror no)
			(drillshape 1)
			(scaleselection 1)
			(outputdirectory "")
		)
	)
	(segment
		(start 94.36608 -137.108184)
		(end 94.36608 -137.573004)
		(width 0.14224)
		(layer "In2.Cu")
		(net "M_M_CLK_DP<2>")
	)
	(segment
		(start 94.252288 -138.151616)
		(end 94.36608 -138.265408)
		(width 0.14224)
		(layer "In2.Cu")
		(net "M_M_CLK_DP<2>")
	)
	(segment
		(start 94.013782 -129.976372)
		(end 94.013782 -130.441192)
		(width 0.14224)
		(layer "In2.Cu")
		(net "M_M_CLK_DP<2>")
	)
	(segment
		(start 94.04096 -131.593844)
		(end 93.927168 -131.707636)
		(width 0.14224)
		(layer "In2.Cu")
		(net "M_M_CLK_DP<2>")
	)
	(segment
		(start 92.576142 -98.36912)
		(end 92.599764 -98.410268)
		(width 0.0889)
		(layer "In2.Cu")
		(net "M_M_CLK_DP<2>")
	)
	(segment
		(start 93.641672 -146.674078)
		(end 93.641672 -146.785076)
		(width 0.14224)
		(layer "In2.Cu")
		(net "M_M_CLK_DP<2>")
	)
	(segment
		(start 93.210888 -103.847392)
		(end 93.210888 -126.758192)
		(width 0.14224)
		(layer "In2.Cu")
		(net "M_M_CLK_DP<2>")
	)
	(segment
		(start 92.932758 -93.23324)
		(end 92.824808 -93.34119)
		(width 0.0889)
		(layer "In2.Cu")
		(net "M_M_CLK_DP<2>")
	)
	(segment
		(start 94.352364 -145.042382)
		(end 94.252288 -145.142458)
		(width 0.14224)
		(layer "In2.Cu")
		(net "M_M_CLK_DP<2>")
	)
	(segment
		(start 92.592398 -94.01302)
		(end 92.586048 -94.023688)
		(width 0.0889)
		(layer "In2.Cu")
		(net "M_M_CLK_DP<2>")
	)
	(segment
		(start 92.669868 -100.2157)
		(end 92.874084 -100.419916)
		(width 0.0889)
		(layer "In2.Cu")
		(net "M_M_CLK_DP<2>")
	)
	(segment
		(start 93.927168 -131.707636)
		(end 93.927168 -132.172456)
		(width 0.14224)
		(layer "In2.Cu")
		(net "M_M_CLK_DP<2>")
	)
	(segment
		(start 93.927168 -129.889758)
		(end 94.013782 -129.976372)
		(width 0.14224)
		(layer "In2.Cu")
		(net "M_M_CLK_DP<2>")
	)
	(segment
		(start 94.252288 -134.679944)
		(end 94.36608 -134.793736)
		(width 0.14224)
		(layer "In2.Cu")
		(net "M_M_CLK_DP<2>")
	)
	(segment
		(start 92.874084 -100.419916)
		(end 92.874084 -101.89972)
		(width 0.0889)
		(layer "In2.Cu")
		(net "M_M_CLK_DP<2>")
	)
	(segment
		(start 92.581222 -96.396302)
		(end 92.586048 -96.404938)
		(width 0.0889)
		(layer "In2.Cu")
		(net "M_M_CLK_DP<2>")
	)
	(segment
		(start 92.669868 -99.535234)
		(end 92.669868 -100.2157)
		(width 0.0889)
		(layer "In2.Cu")
		(net "M_M_CLK_DP<2>")
	)
	(segment
		(start 94.04096 -132.286248)
		(end 94.04096 -132.751068)
		(width 0.14224)
		(layer "In2.Cu")
		(net "M_M_CLK_DP<2>")
	)
	(segment
		(start 92.698062 -147.617688)
		(end 91.811348 -147.617688)
		(width 0.14224)
		(layer "In2.Cu")
		(net "M_M_CLK_DP<2>")
	)
	(segment
		(start 93.927168 -133.32968)
		(end 94.252288 -133.6548)
		(width 0.14224)
		(layer "In2.Cu")
		(net "M_M_CLK_DP<2>")
	)
	(segment
		(start 94.252288 -133.6548)
		(end 94.252288 -134.679944)
		(width 0.14224)
		(layer "In2.Cu")
		(net "M_M_CLK_DP<2>")
	)
	(segment
		(start 94.252288 -143.99895)
		(end 94.252288 -144.477486)
		(width 0.14224)
		(layer "In2.Cu")
		(net "M_M_CLK_DP<2>")
	)
	(segment
		(start 94.352364 -144.577562)
		(end 94.352364 -145.042382)
		(width 0.14224)
		(layer "In2.Cu")
		(net "M_M_CLK_DP<2>")
	)
	(segment
		(start 94.252288 -138.84402)
		(end 94.252288 -139.30884)
		(width 0.14224)
		(layer "In2.Cu")
		(net "M_M_CLK_DP<2>")
	)
	(segment
		(start 94.739968 -139.79652)
		(end 94.739968 -141.8082)
		(width 0.14224)
		(layer "In2.Cu")
		(net "M_M_CLK_DP<2>")
	)
	(segment
		(start 94.04096 -131.129024)
		(end 94.04096 -131.593844)
		(width 0.14224)
		(layer "In2.Cu")
		(net "M_M_CLK_DP<2>")
	)
	(segment
		(start 92.576142 -99.359974)
		(end 92.597986 -99.398328)
		(width 0.0889)
		(layer "In2.Cu")
		(net "M_M_CLK_DP<2>")
	)
	(segment
		(start 94.252288 -135.372348)
		(end 94.252288 -135.837168)
		(width 0.14224)
		(layer "In2.Cu")
		(net "M_M_CLK_DP<2>")
	)
	(segment
		(start 94.252288 -135.837168)
		(end 94.36608 -135.95096)
		(width 0.14224)
		(layer "In2.Cu")
		(net "M_M_CLK_DP<2>")
	)
	(segment
		(start 94.252288 -136.994392)
		(end 94.36608 -137.108184)
		(width 0.14224)
		(layer "In2.Cu")
		(net "M_M_CLK_DP<2>")
	)
	(segment
		(start 94.252288 -143.306546)
		(end 94.36608 -143.420338)
		(width 0.14224)
		(layer "In2.Cu")
		(net "M_M_CLK_DP<2>")
	)
	(segment
		(start 94.36608 -135.95096)
		(end 94.36608 -136.41578)
		(width 0.14224)
		(layer "In2.Cu")
		(net "M_M_CLK_DP<2>")
	)
	(segment
		(start 94.252288 -146.063462)
		(end 93.641672 -146.674078)
		(width 0.14224)
		(layer "In2.Cu")
		(net "M_M_CLK_DP<2>")
	)
	(segment
		(start 94.04096 -132.751068)
		(end 93.927168 -132.86486)
		(width 0.14224)
		(layer "In2.Cu")
		(net "M_M_CLK_DP<2>")
	)
	(segment
		(start 93.927168 -130.527806)
		(end 93.927168 -131.015232)
		(width 0.14224)
		(layer "In2.Cu")
		(net "M_M_CLK_DP<2>")
	)
	(segment
		(start 93.927168 -132.86486)
		(end 93.927168 -133.32968)
		(width 0.14224)
		(layer "In2.Cu")
		(net "M_M_CLK_DP<2>")
	)
	(arc
		(start 92.824808 -93.34119)
		(mid 92.706762 -93.517859)
		(end 92.665296 -93.726254)
		(width 0.0889)
		(layer "In2.Cu")
		(net "M_M_CLK_DP<2>")
	)
	(arc
		(start 92.586048 -98.97745)
		(mid 92.53243 -99.167456)
		(end 92.576142 -99.359974)
		(width 0.0889)
		(layer "In2.Cu")
		(net "M_M_CLK_DP<2>")
	)
	(arc
		(start 92.586048 -94.023688)
		(mid 92.532549 -94.223586)
		(end 92.586048 -94.423484)
		(width 0.0889)
		(layer "In2.Cu")
		(net "M_M_CLK_DP<2>")
	)
	(arc
		(start 92.586048 -96.995488)
		(mid 92.532578 -97.190551)
		(end 92.581222 -97.386902)
		(width 0.0889)
		(layer "In2.Cu")
		(net "M_M_CLK_DP<2>")
	)
	(arc
		(start 92.592398 -96.415606)
		(mid 92.665196 -96.706369)
		(end 92.586048 -96.995488)
		(width 0.0889)
		(layer "In2.Cu")
		(net "M_M_CLK_DP<2>")
	)
	(arc
		(start 92.592398 -95.425006)
		(mid 92.665196 -95.715769)
		(end 92.586048 -96.004888)
		(width 0.0889)
		(layer "In2.Cu")
		(net "M_M_CLK_DP<2>")
	)
	(arc
		(start 92.586048 -97.986596)
		(mid 92.53243 -98.176602)
		(end 92.576142 -98.36912)
		(width 0.0889)
		(layer "In2.Cu")
		(net "M_M_CLK_DP<2>")
	)
	(arc
		(start 92.665296 -93.726254)
		(mid 92.647108 -93.874282)
		(end 92.592398 -94.01302)
		(width 0.0889)
		(layer "In2.Cu")
		(net "M_M_CLK_DP<2>")
	)
	(arc
		(start 92.586048 -95.014288)
		(mid 92.532578 -95.209351)
		(end 92.581222 -95.405702)
		(width 0.0889)
		(layer "In2.Cu")
		(net "M_M_CLK_DP<2>")
	)
	(arc
		(start 92.586048 -94.423484)
		(mid 92.665179 -94.718886)
		(end 92.586048 -95.014288)
		(width 0.0889)
		(layer "In2.Cu")
		(net "M_M_CLK_DP<2>")
	)
	(arc
		(start 92.586048 -96.004888)
		(mid 92.532578 -96.199951)
		(end 92.581222 -96.396302)
		(width 0.0889)
		(layer "In2.Cu")
		(net "M_M_CLK_DP<2>")
	)
	(arc
		(start 92.596716 -97.41408)
		(mid 92.665315 -97.701714)
		(end 92.586048 -97.986596)
		(width 0.0889)
		(layer "In2.Cu")
		(net "M_M_CLK_DP<2>")
	)
	(arc
		(start 92.599764 -98.410268)
		(mid 92.665358 -98.695607)
		(end 92.586048 -98.97745)
		(width 0.0889)
		(layer "In2.Cu")
		(net "M_M_CLK_DP<2>")
	)
	(segment
		(start 94.649798 -93.23324)
		(end 95.221298 -93.23324)
		(width 0.1016)
		(layer "F.Cu")
		(net "M_M_CLK_DP<0>")
	)
	(segment
		(start 91.749372 -152.273)
		(end 91.749372 -153.571956)
		(width 0.1651)
		(layer "F.Cu")
		(net "M_M_CLK_DP<0>")
	)
	(via
		(at 94.649798 -93.23324)
		(size 0.508)
		(drill 0.254)
		(layers "F.Cu" "B.Cu")
		(net "M_M_CLK_DP<0>")
	)
	(via
		(at 91.749372 -153.571956)
		(size 0.508)
		(drill 0.254)
		(layers "F.Cu" "B.Cu")
		(net "M_M_CLK_DP<0>")
	)
	(segment
		(start 95.116396 -154.667966)
		(end 92.421202 -154.667966)
		(width 0.14224)
		(layer "In2.Cu")
		(net "M_M_CLK_DP<0>")
	)
	(segment
		(start 96.433386 -130.135122)
		(end 96.433386 -151.359362)
		(width 0.14224)
		(layer "In2.Cu")
		(net "M_M_CLK_DP<0>")
	)
	(segment
		(start 95.576644 -153.083514)
		(end 95.576644 -154.207718)
		(width 0.14224)
		(layer "In2.Cu")
		(net "M_M_CLK_DP<0>")
	)
	(segment
		(start 93.195902 -151.99487)
		(end 93.195902 -152.500838)
		(width 0.14224)
		(layer "In2.Cu")
		(net "M_M_CLK_DP<0>")
	)
	(segment
		(start 93.35135 -152.656286)
		(end 95.149416 -152.656286)
		(width 0.14224)
		(layer "In2.Cu")
		(net "M_M_CLK_DP<0>")
	)
	(segment
		(start 94.607888 -102.856792)
		(end 94.887288 -103.136192)
		(width 0.14224)
		(layer "In2.Cu")
		(net "M_M_CLK_DP<0>")
	)
	(segment
		(start 94.649798 -93.23324)
		(end 94.542864 -93.340174)
		(width 0.0889)
		(layer "In2.Cu")
		(net "M_M_CLK_DP<0>")
	)
	(segment
		(start 95.576644 -154.207718)
		(end 95.116396 -154.667966)
		(width 0.14224)
		(layer "In2.Cu")
		(net "M_M_CLK_DP<0>")
	)
	(segment
		(start 94.582488 -100.37572)
		(end 94.582488 -101.933756)
		(width 0.0889)
		(layer "In2.Cu")
		(net "M_M_CLK_DP<0>")
	)
	(segment
		(start 92.421202 -154.667966)
		(end 92.028772 -154.275536)
		(width 0.14224)
		(layer "In2.Cu")
		(net "M_M_CLK_DP<0>")
	)
	(segment
		(start 94.303088 -95.414338)
		(end 94.309438 -95.425006)
		(width 0.0889)
		(layer "In2.Cu")
		(net "M_M_CLK_DP<0>")
	)
	(segment
		(start 94.460568 -100.2538)
		(end 94.582488 -100.37572)
		(width 0.0889)
		(layer "In2.Cu")
		(net "M_M_CLK_DP<0>")
	)
	(segment
		(start 94.607888 -101.959156)
		(end 94.607888 -101.981254)
		(width 0.0889)
		(layer "In2.Cu")
		(net "M_M_CLK_DP<0>")
	)
	(segment
		(start 94.303088 -96.404938)
		(end 94.309438 -96.415606)
		(width 0.0889)
		(layer "In2.Cu")
		(net "M_M_CLK_DP<0>")
	)
	(segment
		(start 94.3102 -98.398838)
		(end 94.309438 -98.396806)
		(width 0.0889)
		(layer "In2.Cu")
		(net "M_M_CLK_DP<0>")
	)
	(segment
		(start 93.35135 -151.839422)
		(end 93.195902 -151.99487)
		(width 0.14224)
		(layer "In2.Cu")
		(net "M_M_CLK_DP<0>")
	)
	(segment
		(start 94.607888 -101.981254)
		(end 94.607888 -102.856792)
		(width 0.14224)
		(layer "In2.Cu")
		(net "M_M_CLK_DP<0>")
	)
	(segment
		(start 94.303088 -97.395538)
		(end 94.309438 -97.406206)
		(width 0.0889)
		(layer "In2.Cu")
		(net "M_M_CLK_DP<0>")
	)
	(segment
		(start 94.887288 -125.935232)
		(end 95.95104 -126.998984)
		(width 0.14224)
		(layer "In2.Cu")
		(net "M_M_CLK_DP<0>")
	)
	(segment
		(start 94.582488 -101.933756)
		(end 94.607888 -101.959156)
		(width 0.0889)
		(layer "In2.Cu")
		(net "M_M_CLK_DP<0>")
	)
	(segment
		(start 92.028772 -154.275536)
		(end 92.028772 -153.851356)
		(width 0.14224)
		(layer "In2.Cu")
		(net "M_M_CLK_DP<0>")
	)
	(segment
		(start 94.298262 -95.405702)
		(end 94.303088 -95.414338)
		(width 0.0889)
		(layer "In2.Cu")
		(net "M_M_CLK_DP<0>")
	)
	(segment
		(start 95.95104 -126.998984)
		(end 95.95104 -129.652776)
		(width 0.14224)
		(layer "In2.Cu")
		(net "M_M_CLK_DP<0>")
	)
	(segment
		(start 92.028772 -153.851356)
		(end 91.749372 -153.571956)
		(width 0.14224)
		(layer "In2.Cu")
		(net "M_M_CLK_DP<0>")
	)
	(segment
		(start 94.298262 -98.377502)
		(end 94.3102 -98.398838)
		(width 0.0889)
		(layer "In2.Cu")
		(net "M_M_CLK_DP<0>")
	)
	(segment
		(start 94.309438 -94.01302)
		(end 94.303088 -94.023688)
		(width 0.0889)
		(layer "In2.Cu")
		(net "M_M_CLK_DP<0>")
	)
	(segment
		(start 94.298262 -96.396302)
		(end 94.303088 -96.404938)
		(width 0.0889)
		(layer "In2.Cu")
		(net "M_M_CLK_DP<0>")
	)
	(segment
		(start 95.149416 -152.656286)
		(end 95.576644 -153.083514)
		(width 0.14224)
		(layer "In2.Cu")
		(net "M_M_CLK_DP<0>")
	)
	(segment
		(start 95.953326 -151.839422)
		(end 93.35135 -151.839422)
		(width 0.14224)
		(layer "In2.Cu")
		(net "M_M_CLK_DP<0>")
	)
	(segment
		(start 95.95104 -129.652776)
		(end 96.433386 -130.135122)
		(width 0.14224)
		(layer "In2.Cu")
		(net "M_M_CLK_DP<0>")
	)
	(segment
		(start 94.314264 -99.395534)
		(end 94.460568 -99.621086)
		(width 0.0889)
		(layer "In2.Cu")
		(net "M_M_CLK_DP<0>")
	)
	(segment
		(start 93.195902 -152.500838)
		(end 93.35135 -152.656286)
		(width 0.14224)
		(layer "In2.Cu")
		(net "M_M_CLK_DP<0>")
	)
	(segment
		(start 94.460568 -99.621086)
		(end 94.460568 -100.2538)
		(width 0.0889)
		(layer "In2.Cu")
		(net "M_M_CLK_DP<0>")
	)
	(segment
		(start 96.433386 -151.359362)
		(end 95.953326 -151.839422)
		(width 0.14224)
		(layer "In2.Cu")
		(net "M_M_CLK_DP<0>")
	)
	(segment
		(start 94.298262 -97.386902)
		(end 94.303088 -97.395538)
		(width 0.0889)
		(layer "In2.Cu")
		(net "M_M_CLK_DP<0>")
	)
	(segment
		(start 94.887288 -103.136192)
		(end 94.887288 -125.935232)
		(width 0.14224)
		(layer "In2.Cu")
		(net "M_M_CLK_DP<0>")
	)
	(arc
		(start 94.303088 -94.423484)
		(mid 94.382219 -94.718886)
		(end 94.303088 -95.014288)
		(width 0.0889)
		(layer "In2.Cu")
		(net "M_M_CLK_DP<0>")
	)
	(arc
		(start 94.309438 -96.415606)
		(mid 94.382236 -96.706369)
		(end 94.303088 -96.995488)
		(width 0.0889)
		(layer "In2.Cu")
		(net "M_M_CLK_DP<0>")
	)
	(arc
		(start 94.309438 -95.425006)
		(mid 94.382236 -95.715769)
		(end 94.303088 -96.004888)
		(width 0.0889)
		(layer "In2.Cu")
		(net "M_M_CLK_DP<0>")
	)
	(arc
		(start 94.309438 -98.396806)
		(mid 94.382236 -98.687569)
		(end 94.303088 -98.976688)
		(width 0.0889)
		(layer "In2.Cu")
		(net "M_M_CLK_DP<0>")
	)
	(arc
		(start 94.309438 -97.406206)
		(mid 94.382236 -97.696969)
		(end 94.303088 -97.986088)
		(width 0.0889)
		(layer "In2.Cu")
		(net "M_M_CLK_DP<0>")
	)
	(arc
		(start 94.303088 -96.995488)
		(mid 94.249618 -97.190551)
		(end 94.298262 -97.386902)
		(width 0.0889)
		(layer "In2.Cu")
		(net "M_M_CLK_DP<0>")
	)
	(arc
		(start 94.303088 -95.014288)
		(mid 94.249618 -95.209351)
		(end 94.298262 -95.405702)
		(width 0.0889)
		(layer "In2.Cu")
		(net "M_M_CLK_DP<0>")
	)
	(arc
		(start 94.303088 -96.004888)
		(mid 94.249618 -96.199951)
		(end 94.298262 -96.396302)
		(width 0.0889)
		(layer "In2.Cu")
		(net "M_M_CLK_DP<0>")
	)
	(arc
		(start 94.303088 -97.986088)
		(mid 94.249618 -98.181151)
		(end 94.298262 -98.377502)
		(width 0.0889)
		(layer "In2.Cu")
		(net "M_M_CLK_DP<0>")
	)
	(arc
		(start 94.303088 -94.023688)
		(mid 94.249589 -94.223586)
		(end 94.303088 -94.423484)
		(width 0.0889)
		(layer "In2.Cu")
		(net "M_M_CLK_DP<0>")
	)
	(arc
		(start 94.303088 -98.976688)
		(mid 94.249578 -99.187703)
		(end 94.314264 -99.395534)
		(width 0.0889)
		(layer "In2.Cu")
		(net "M_M_CLK_DP<0>")
	)
	(arc
		(start 94.542864 -93.340174)
		(mid 94.424039 -93.518008)
		(end 94.382336 -93.727778)
		(width 0.0889)
		(layer "In2.Cu")
		(net "M_M_CLK_DP<0>")
	)
	(arc
		(start 94.382336 -93.727778)
		(mid 94.363956 -93.875019)
		(end 94.309438 -94.01302)
		(width 0.0889)
		(layer "In2.Cu")
		(net "M_M_CLK_DP<0>")
	)
	(segment
		(start 92.645738 -91.747086)
		(end 92.074238 -91.747086)
		(width 0.1016)
		(layer "F.Cu")
		(net "M_M_CLK_DN<3>")
	)
	(via
		(at 92.52331 -148.771356)
		(size 0.508)
		(drill 0.254)
		(layers "F.Cu" "B.Cu")
		(net "M_M_CLK_DN<3>")
	)
	(via
		(at 92.074238 -91.747086)
		(size 0.508)
		(drill 0.254)
		(layers "F.Cu" "B.Cu")
		(net "M_M_CLK_DN<3>")
	)
	(segment
		(start 92.59951 -147.478496)
		(end 92.59951 -148.695156)
		(width 0.1651)
		(layer "B.Cu")
		(net "M_M_CLK_DN<3>")
	)
	(segment
		(start 92.59951 -148.695156)
		(end 92.52331 -148.771356)
		(width 0.1651)
		(layer "B.Cu")
		(net "M_M_CLK_DN<3>")
	)
	(segment
		(start 94.572328 -132.98424)
		(end 94.572328 -129.596642)
		(width 0.14224)
		(layer "In2.Cu")
		(net "M_M_CLK_DN<3>")
	)
	(segment
		(start 94.890336 -147.35175)
		(end 94.890336 -146.88693)
		(width 0.14224)
		(layer "In2.Cu")
		(net "M_M_CLK_DN<3>")
	)
	(segment
		(start 94.890336 -148.044154)
		(end 95.004128 -147.930362)
		(width 0.14224)
		(layer "In2.Cu")
		(net "M_M_CLK_DN<3>")
	)
	(segment
		(start 94.827598 -134.396734)
		(end 94.827598 -133.931914)
		(width 0.14224)
		(layer "In2.Cu")
		(net "M_M_CLK_DN<3>")
	)
	(segment
		(start 93.279468 -95.414338)
		(end 93.284294 -95.405702)
		(width 0.0889)
		(layer "In2.Cu")
		(net "M_M_CLK_DN<3>")
	)
	(segment
		(start 93.273118 -96.415606)
		(end 93.279468 -96.404938)
		(width 0.0889)
		(layer "In2.Cu")
		(net "M_M_CLK_DN<3>")
	)
	(segment
		(start 93.823028 -149.7076)
		(end 94.503494 -149.7076)
		(width 0.14224)
		(layer "In2.Cu")
		(net "M_M_CLK_DN<3>")
	)
	(segment
		(start 93.279468 -96.404938)
		(end 93.284294 -96.396302)
		(width 0.0889)
		(layer "In2.Cu")
		(net "M_M_CLK_DN<3>")
	)
	(segment
		(start 95.435928 -144.94764)
		(end 95.435928 -144.48282)
		(width 0.14224)
		(layer "In2.Cu")
		(net "M_M_CLK_DN<3>")
	)
	(segment
		(start 93.709236 -149.593808)
		(end 93.823028 -149.7076)
		(width 0.14224)
		(layer "In2.Cu")
		(net "M_M_CLK_DN<3>")
	)
	(segment
		(start 92.29598 -149.397212)
		(end 92.606368 -149.7076)
		(width 0.14224)
		(layer "In2.Cu")
		(net "M_M_CLK_DN<3>")
	)
	(segment
		(start 94.458536 -129.01803)
		(end 94.572328 -128.904238)
		(width 0.14224)
		(layer "In2.Cu")
		(net "M_M_CLK_DN<3>")
	)
	(segment
		(start 93.279468 -93.433138)
		(end 93.284294 -93.424502)
		(width 0.0889)
		(layer "In2.Cu")
		(net "M_M_CLK_DN<3>")
	)
	(segment
		(start 92.947744 -92.83319)
		(end 92.914978 -92.83319)
		(width 0.0889)
		(layer "In2.Cu")
		(net "M_M_CLK_DN<3>")
	)
	(segment
		(start 95.322136 -141.98473)
		(end 95.435928 -141.870938)
		(width 0.14224)
		(layer "In2.Cu")
		(net "M_M_CLK_DN<3>")
	)
	(segment
		(start 93.779848 -126.489714)
		(end 93.779848 -103.604314)
		(width 0.14224)
		(layer "In2.Cu")
		(net "M_M_CLK_DN<3>")
	)
	(segment
		(start 93.273118 -97.406206)
		(end 93.279468 -97.395538)
		(width 0.0889)
		(layer "In2.Cu")
		(net "M_M_CLK_DN<3>")
	)
	(segment
		(start 95.435928 -139.608306)
		(end 94.94139 -139.113768)
		(width 0.14224)
		(layer "In2.Cu")
		(net "M_M_CLK_DN<3>")
	)
	(segment
		(start 94.94139 -134.510526)
		(end 94.827598 -134.396734)
		(width 0.14224)
		(layer "In2.Cu")
		(net "M_M_CLK_DN<3>")
	)
	(segment
		(start 93.244416 -149.593808)
		(end 93.709236 -149.593808)
		(width 0.14224)
		(layer "In2.Cu")
		(net "M_M_CLK_DN<3>")
	)
	(segment
		(start 94.458536 -127.860806)
		(end 94.572328 -127.747014)
		(width 0.14224)
		(layer "In2.Cu")
		(net "M_M_CLK_DN<3>")
	)
	(segment
		(start 95.435928 -144.48282)
		(end 95.322136 -144.369028)
		(width 0.14224)
		(layer "In2.Cu")
		(net "M_M_CLK_DN<3>")
	)
	(segment
		(start 95.435928 -140.713714)
		(end 95.435928 -139.608306)
		(width 0.14224)
		(layer "In2.Cu")
		(net "M_M_CLK_DN<3>")
	)
	(segment
		(start 93.130624 -149.7076)
		(end 93.244416 -149.593808)
		(width 0.14224)
		(layer "In2.Cu")
		(net "M_M_CLK_DN<3>")
	)
	(segment
		(start 93.494098 -102.088442)
		(end 93.494098 -102.066344)
		(width 0.0889)
		(layer "In2.Cu")
		(net "M_M_CLK_DN<3>")
	)
	(segment
		(start 94.572328 -127.747014)
		(end 94.572328 -127.282194)
		(width 0.14224)
		(layer "In2.Cu")
		(net "M_M_CLK_DN<3>")
	)
	(segment
		(start 95.435928 -143.790416)
		(end 95.435928 -142.563342)
		(width 0.14224)
		(layer "In2.Cu")
		(net "M_M_CLK_DN<3>")
	)
	(segment
		(start 93.533468 -102.026974)
		(end 93.533468 -100.333048)
		(width 0.0889)
		(layer "In2.Cu")
		(net "M_M_CLK_DN<3>")
	)
	(segment
		(start 95.004128 -147.930362)
		(end 95.004128 -147.465542)
		(width 0.14224)
		(layer "In2.Cu")
		(net "M_M_CLK_DN<3>")
	)
	(segment
		(start 92.191332 -91.864434)
		(end 92.074238 -91.747086)
		(width 0.0889)
		(layer "In2.Cu")
		(net "M_M_CLK_DN<3>")
	)
	(segment
		(start 94.572328 -127.282194)
		(end 93.779848 -126.489714)
		(width 0.14224)
		(layer "In2.Cu")
		(net "M_M_CLK_DN<3>")
	)
	(segment
		(start 94.458536 -129.48285)
		(end 94.458536 -129.01803)
		(width 0.14224)
		(layer "In2.Cu")
		(net "M_M_CLK_DN<3>")
	)
	(segment
		(start 94.458536 -128.325626)
		(end 94.458536 -127.860806)
		(width 0.14224)
		(layer "In2.Cu")
		(net "M_M_CLK_DN<3>")
	)
	(segment
		(start 95.004128 -146.773138)
		(end 95.004128 -145.37944)
		(width 0.14224)
		(layer "In2.Cu")
		(net "M_M_CLK_DN<3>")
	)
	(segment
		(start 93.494098 -103.318564)
		(end 93.494098 -102.088442)
		(width 0.14224)
		(layer "In2.Cu")
		(net "M_M_CLK_DN<3>")
	)
	(segment
		(start 92.29598 -148.998686)
		(end 92.29598 -149.397212)
		(width 0.14224)
		(layer "In2.Cu")
		(net "M_M_CLK_DN<3>")
	)
	(segment
		(start 93.273118 -98.396806)
		(end 93.279468 -98.386138)
		(width 0.0889)
		(layer "In2.Cu")
		(net "M_M_CLK_DN<3>")
	)
	(segment
		(start 94.890336 -148.508974)
		(end 94.890336 -148.044154)
		(width 0.14224)
		(layer "In2.Cu")
		(net "M_M_CLK_DN<3>")
	)
	(segment
		(start 94.890336 -146.88693)
		(end 95.004128 -146.773138)
		(width 0.14224)
		(layer "In2.Cu")
		(net "M_M_CLK_DN<3>")
	)
	(segment
		(start 94.572328 -128.904238)
		(end 94.572328 -128.439418)
		(width 0.14224)
		(layer "In2.Cu")
		(net "M_M_CLK_DN<3>")
	)
	(segment
		(start 93.779848 -103.604314)
		(end 93.494098 -103.318564)
		(width 0.14224)
		(layer "In2.Cu")
		(net "M_M_CLK_DN<3>")
	)
	(segment
		(start 93.24467 -99.43719)
		(end 93.284294 -99.368102)
		(width 0.0889)
		(layer "In2.Cu")
		(net "M_M_CLK_DN<3>")
	)
	(segment
		(start 93.279468 -94.023688)
		(end 93.273118 -94.01302)
		(width 0.0889)
		(layer "In2.Cu")
		(net "M_M_CLK_DN<3>")
	)
	(segment
		(start 93.279468 -97.395538)
		(end 93.284294 -97.386902)
		(width 0.0889)
		(layer "In2.Cu")
		(net "M_M_CLK_DN<3>")
	)
	(segment
		(start 92.606368 -149.7076)
		(end 93.130624 -149.7076)
		(width 0.14224)
		(layer "In2.Cu")
		(net "M_M_CLK_DN<3>")
	)
	(segment
		(start 94.572328 -128.439418)
		(end 94.458536 -128.325626)
		(width 0.14224)
		(layer "In2.Cu")
		(net "M_M_CLK_DN<3>")
	)
	(segment
		(start 94.94139 -133.818122)
		(end 94.94139 -133.353302)
		(width 0.14224)
		(layer "In2.Cu")
		(net "M_M_CLK_DN<3>")
	)
	(segment
		(start 93.19768 -99.99726)
		(end 93.19768 -99.48418)
		(width 0.0889)
		(layer "In2.Cu")
		(net "M_M_CLK_DN<3>")
	)
	(segment
		(start 94.94139 -133.353302)
		(end 94.572328 -132.98424)
		(width 0.14224)
		(layer "In2.Cu")
		(net "M_M_CLK_DN<3>")
	)
	(segment
		(start 94.572328 -129.596642)
		(end 94.458536 -129.48285)
		(width 0.14224)
		(layer "In2.Cu")
		(net "M_M_CLK_DN<3>")
	)
	(segment
		(start 95.004128 -145.37944)
		(end 95.435928 -144.94764)
		(width 0.14224)
		(layer "In2.Cu")
		(net "M_M_CLK_DN<3>")
	)
	(segment
		(start 94.827598 -133.931914)
		(end 94.94139 -133.818122)
		(width 0.14224)
		(layer "In2.Cu")
		(net "M_M_CLK_DN<3>")
	)
	(segment
		(start 95.004128 -148.622766)
		(end 94.890336 -148.508974)
		(width 0.14224)
		(layer "In2.Cu")
		(net "M_M_CLK_DN<3>")
	)
	(segment
		(start 95.322136 -143.904208)
		(end 95.435928 -143.790416)
		(width 0.14224)
		(layer "In2.Cu")
		(net "M_M_CLK_DN<3>")
	)
	(segment
		(start 93.279468 -98.386138)
		(end 93.284294 -98.377502)
		(width 0.0889)
		(layer "In2.Cu")
		(net "M_M_CLK_DN<3>")
	)
	(segment
		(start 95.435928 -141.870938)
		(end 95.435928 -141.406118)
		(width 0.14224)
		(layer "In2.Cu")
		(net "M_M_CLK_DN<3>")
	)
	(segment
		(start 95.322136 -140.827506)
		(end 95.435928 -140.713714)
		(width 0.14224)
		(layer "In2.Cu")
		(net "M_M_CLK_DN<3>")
	)
	(segment
		(start 92.52331 -148.771356)
		(end 92.29598 -148.998686)
		(width 0.14224)
		(layer "In2.Cu")
		(net "M_M_CLK_DN<3>")
	)
	(segment
		(start 93.533468 -100.333048)
		(end 93.19768 -99.99726)
		(width 0.0889)
		(layer "In2.Cu")
		(net "M_M_CLK_DN<3>")
	)
	(segment
		(start 93.19768 -99.48418)
		(end 93.24467 -99.43719)
		(width 0.0889)
		(layer "In2.Cu")
		(net "M_M_CLK_DN<3>")
	)
	(segment
		(start 95.004128 -149.206966)
		(end 95.004128 -148.622766)
		(width 0.14224)
		(layer "In2.Cu")
		(net "M_M_CLK_DN<3>")
	)
	(segment
		(start 95.435928 -141.406118)
		(end 95.322136 -141.292326)
		(width 0.14224)
		(layer "In2.Cu")
		(net "M_M_CLK_DN<3>")
	)
	(segment
		(start 94.94139 -139.113768)
		(end 94.94139 -134.510526)
		(width 0.14224)
		(layer "In2.Cu")
		(net "M_M_CLK_DN<3>")
	)
	(segment
		(start 95.322136 -141.292326)
		(end 95.322136 -140.827506)
		(width 0.14224)
		(layer "In2.Cu")
		(net "M_M_CLK_DN<3>")
	)
	(segment
		(start 95.322136 -142.44955)
		(end 95.322136 -141.98473)
		(width 0.14224)
		(layer "In2.Cu")
		(net "M_M_CLK_DN<3>")
	)
	(segment
		(start 95.322136 -144.369028)
		(end 95.322136 -143.904208)
		(width 0.14224)
		(layer "In2.Cu")
		(net "M_M_CLK_DN<3>")
	)
	(segment
		(start 94.503494 -149.7076)
		(end 95.004128 -149.206966)
		(width 0.14224)
		(layer "In2.Cu")
		(net "M_M_CLK_DN<3>")
	)
	(segment
		(start 95.435928 -142.563342)
		(end 95.322136 -142.44955)
		(width 0.14224)
		(layer "In2.Cu")
		(net "M_M_CLK_DN<3>")
	)
	(segment
		(start 95.004128 -147.465542)
		(end 94.890336 -147.35175)
		(width 0.14224)
		(layer "In2.Cu")
		(net "M_M_CLK_DN<3>")
	)
	(segment
		(start 93.494098 -102.066344)
		(end 93.533468 -102.026974)
		(width 0.0889)
		(layer "In2.Cu")
		(net "M_M_CLK_DN<3>")
	)
	(segment
		(start 93.273118 -95.425006)
		(end 93.279468 -95.414338)
		(width 0.0889)
		(layer "In2.Cu")
		(net "M_M_CLK_DN<3>")
	)
	(arc
		(start 92.914978 -92.83319)
		(mid 92.503401 -92.648752)
		(end 92.341954 -92.227654)
		(width 0.0889)
		(layer "In2.Cu")
		(net "M_M_CLK_DN<3>")
	)
	(arc
		(start 93.279468 -94.423484)
		(mid 93.332967 -94.223586)
		(end 93.279468 -94.023688)
		(width 0.0889)
		(layer "In2.Cu")
		(net "M_M_CLK_DN<3>")
	)
	(arc
		(start 93.279468 -97.986088)
		(mid 93.200246 -97.69697)
		(end 93.273118 -97.406206)
		(width 0.0889)
		(layer "In2.Cu")
		(net "M_M_CLK_DN<3>")
	)
	(arc
		(start 93.279468 -96.995488)
		(mid 93.200246 -96.70637)
		(end 93.273118 -96.415606)
		(width 0.0889)
		(layer "In2.Cu")
		(net "M_M_CLK_DN<3>")
	)
	(arc
		(start 93.279468 -95.014288)
		(mid 93.200337 -94.718886)
		(end 93.279468 -94.423484)
		(width 0.0889)
		(layer "In2.Cu")
		(net "M_M_CLK_DN<3>")
	)
	(arc
		(start 93.284294 -93.424502)
		(mid 93.280547 -93.035246)
		(end 92.947744 -92.83319)
		(width 0.0889)
		(layer "In2.Cu")
		(net "M_M_CLK_DN<3>")
	)
	(arc
		(start 93.284294 -96.396302)
		(mid 93.333049 -96.19995)
		(end 93.279468 -96.004888)
		(width 0.0889)
		(layer "In2.Cu")
		(net "M_M_CLK_DN<3>")
	)
	(arc
		(start 93.284294 -95.405702)
		(mid 93.333049 -95.20935)
		(end 93.279468 -95.014288)
		(width 0.0889)
		(layer "In2.Cu")
		(net "M_M_CLK_DN<3>")
	)
	(arc
		(start 93.279468 -98.976688)
		(mid 93.200246 -98.68757)
		(end 93.273118 -98.396806)
		(width 0.0889)
		(layer "In2.Cu")
		(net "M_M_CLK_DN<3>")
	)
	(arc
		(start 93.284294 -98.377502)
		(mid 93.333049 -98.18115)
		(end 93.279468 -97.986088)
		(width 0.0889)
		(layer "In2.Cu")
		(net "M_M_CLK_DN<3>")
	)
	(arc
		(start 92.341954 -92.227654)
		(mid 92.302757 -92.031069)
		(end 92.191332 -91.864434)
		(width 0.0889)
		(layer "In2.Cu")
		(net "M_M_CLK_DN<3>")
	)
	(arc
		(start 93.279468 -96.004888)
		(mid 93.200246 -95.71577)
		(end 93.273118 -95.425006)
		(width 0.0889)
		(layer "In2.Cu")
		(net "M_M_CLK_DN<3>")
	)
	(arc
		(start 93.273118 -94.01302)
		(mid 93.20032 -93.722257)
		(end 93.279468 -93.433138)
		(width 0.0889)
		(layer "In2.Cu")
		(net "M_M_CLK_DN<3>")
	)
	(arc
		(start 93.284294 -97.386902)
		(mid 93.333049 -97.19055)
		(end 93.279468 -96.995488)
		(width 0.0889)
		(layer "In2.Cu")
		(net "M_M_CLK_DN<3>")
	)
	(arc
		(start 93.284294 -99.368102)
		(mid 93.333049 -99.17175)
		(end 93.279468 -98.976688)
		(width 0.0889)
		(layer "In2.Cu")
		(net "M_M_CLK_DN<3>")
	)
	(segment
		(start 94.362778 -91.747086)
		(end 93.791278 -91.747086)
		(width 0.1016)
		(layer "F.Cu")
		(net "M_M_CLK_DN<1>")
	)
	(segment
		(start 92.59951 -156.87294)
		(end 92.59951 -155.509468)
		(width 0.1651)
		(layer "F.Cu")
		(net "M_M_CLK_DN<1>")
	)
	(via
		(at 93.791278 -91.747086)
		(size 0.508)
		(drill 0.254)
		(layers "F.Cu" "B.Cu")
		(net "M_M_CLK_DN<1>")
	)
	(via
		(at 92.59951 -155.509468)
		(size 0.508)
		(drill 0.254)
		(layers "F.Cu" "B.Cu")
		(net "M_M_CLK_DN<1>")
	)
	(segment
		(start 95.001334 -95.405702)
		(end 94.996508 -95.414338)
		(width 0.0889)
		(layer "In2.Cu")
		(net "M_M_CLK_DN<1>")
	)
	(segment
		(start 95.247968 -100.320094)
		(end 95.247968 -101.963728)
		(width 0.0889)
		(layer "In2.Cu")
		(net "M_M_CLK_DN<1>")
	)
	(segment
		(start 95.341694 -155.64104)
		(end 95.012764 -155.96997)
		(width 0.14224)
		(layer "In2.Cu")
		(net "M_M_CLK_DN<1>")
	)
	(segment
		(start 95.001334 -93.424502)
		(end 94.996508 -93.433138)
		(width 0.0889)
		(layer "In2.Cu")
		(net "M_M_CLK_DN<1>")
	)
	(segment
		(start 96.905318 -152.38857)
		(end 97.01911 -152.502362)
		(width 0.14224)
		(layer "In2.Cu")
		(net "M_M_CLK_DN<1>")
	)
	(segment
		(start 96.93275 -138.00709)
		(end 96.93275 -138.47191)
		(width 0.14224)
		(layer "In2.Cu")
		(net "M_M_CLK_DN<1>")
	)
	(segment
		(start 96.67367 -126.868174)
		(end 96.67367 -129.309622)
		(width 0.14224)
		(layer "In2.Cu")
		(net "M_M_CLK_DN<1>")
	)
	(segment
		(start 97.01911 -154.124406)
		(end 96.320864 -154.822652)
		(width 0.14224)
		(layer "In2.Cu")
		(net "M_M_CLK_DN<1>")
	)
	(segment
		(start 95.001334 -97.386902)
		(end 94.996508 -97.395538)
		(width 0.0889)
		(layer "In2.Cu")
		(net "M_M_CLK_DN<1>")
	)
	(segment
		(start 96.67367 -129.309622)
		(end 97.046542 -129.682494)
		(width 0.14224)
		(layer "In2.Cu")
		(net "M_M_CLK_DN<1>")
	)
	(segment
		(start 92.271088 -156.183076)
		(end 92.271088 -155.83789)
		(width 0.14224)
		(layer "In2.Cu")
		(net "M_M_CLK_DN<1>")
	)
	(segment
		(start 97.046542 -140.487146)
		(end 96.934528 -140.59916)
		(width 0.14224)
		(layer "In2.Cu")
		(net "M_M_CLK_DN<1>")
	)
	(segment
		(start 96.905318 -153.080974)
		(end 96.905318 -153.545794)
		(width 0.14224)
		(layer "In2.Cu")
		(net "M_M_CLK_DN<1>")
	)
	(segment
		(start 97.046542 -139.050522)
		(end 96.93275 -139.164314)
		(width 0.14224)
		(layer "In2.Cu")
		(net "M_M_CLK_DN<1>")
	)
	(segment
		(start 96.320864 -154.822652)
		(end 96.160082 -154.822652)
		(width 0.14224)
		(layer "In2.Cu")
		(net "M_M_CLK_DN<1>")
	)
	(segment
		(start 95.507048 -102.943914)
		(end 95.507048 -125.701552)
		(width 0.14224)
		(layer "In2.Cu")
		(net "M_M_CLK_DN<1>")
	)
	(segment
		(start 97.01911 -151.809958)
		(end 96.905318 -151.92375)
		(width 0.14224)
		(layer "In2.Cu")
		(net "M_M_CLK_DN<1>")
	)
	(segment
		(start 95.831152 -155.151582)
		(end 95.831152 -155.312364)
		(width 0.14224)
		(layer "In2.Cu")
		(net "M_M_CLK_DN<1>")
	)
	(segment
		(start 95.247968 -101.963728)
		(end 95.202248 -102.009448)
		(width 0.0889)
		(layer "In2.Cu")
		(net "M_M_CLK_DN<1>")
	)
	(segment
		(start 97.01911 -152.967182)
		(end 96.905318 -153.080974)
		(width 0.14224)
		(layer "In2.Cu")
		(net "M_M_CLK_DN<1>")
	)
	(segment
		(start 95.202248 -102.031546)
		(end 95.202248 -102.639114)
		(width 0.14224)
		(layer "In2.Cu")
		(net "M_M_CLK_DN<1>")
	)
	(segment
		(start 96.934528 -140.59916)
		(end 96.934528 -142.25016)
		(width 0.14224)
		(layer "In2.Cu")
		(net "M_M_CLK_DN<1>")
	)
	(segment
		(start 95.012764 -155.96997)
		(end 95.012764 -156.130752)
		(width 0.14224)
		(layer "In2.Cu")
		(net "M_M_CLK_DN<1>")
	)
	(segment
		(start 97.01911 -152.502362)
		(end 97.01911 -152.967182)
		(width 0.14224)
		(layer "In2.Cu")
		(net "M_M_CLK_DN<1>")
	)
	(segment
		(start 96.905318 -153.545794)
		(end 97.01911 -153.659586)
		(width 0.14224)
		(layer "In2.Cu")
		(net "M_M_CLK_DN<1>")
	)
	(segment
		(start 95.001334 -98.377502)
		(end 94.996508 -98.386138)
		(width 0.0889)
		(layer "In2.Cu")
		(net "M_M_CLK_DN<1>")
	)
	(segment
		(start 92.54744 -156.459428)
		(end 92.271088 -156.183076)
		(width 0.14224)
		(layer "In2.Cu")
		(net "M_M_CLK_DN<1>")
	)
	(segment
		(start 96.93275 -136.157462)
		(end 97.046542 -136.271254)
		(width 0.14224)
		(layer "In2.Cu")
		(net "M_M_CLK_DN<1>")
	)
	(segment
		(start 94.996508 -96.404938)
		(end 94.990158 -96.415606)
		(width 0.0889)
		(layer "In2.Cu")
		(net "M_M_CLK_DN<1>")
	)
	(segment
		(start 94.996508 -98.386138)
		(end 94.990158 -98.396806)
		(width 0.0889)
		(layer "In2.Cu")
		(net "M_M_CLK_DN<1>")
	)
	(segment
		(start 95.001334 -96.396302)
		(end 94.996508 -96.404938)
		(width 0.0889)
		(layer "In2.Cu")
		(net "M_M_CLK_DN<1>")
	)
	(segment
		(start 97.01911 -153.659586)
		(end 97.01911 -154.124406)
		(width 0.14224)
		(layer "In2.Cu")
		(net "M_M_CLK_DN<1>")
	)
	(segment
		(start 95.012764 -156.130752)
		(end 94.684088 -156.459428)
		(width 0.14224)
		(layer "In2.Cu")
		(net "M_M_CLK_DN<1>")
	)
	(segment
		(start 97.046542 -137.428478)
		(end 97.046542 -137.893298)
		(width 0.14224)
		(layer "In2.Cu")
		(net "M_M_CLK_DN<1>")
	)
	(segment
		(start 96.93275 -139.629134)
		(end 97.046542 -139.742926)
		(width 0.14224)
		(layer "In2.Cu")
		(net "M_M_CLK_DN<1>")
	)
	(segment
		(start 97.046542 -136.271254)
		(end 97.046542 -136.736074)
		(width 0.14224)
		(layer "In2.Cu")
		(net "M_M_CLK_DN<1>")
	)
	(segment
		(start 97.046542 -137.893298)
		(end 96.93275 -138.00709)
		(width 0.14224)
		(layer "In2.Cu")
		(net "M_M_CLK_DN<1>")
	)
	(segment
		(start 95.507048 -125.701552)
		(end 96.67367 -126.868174)
		(width 0.14224)
		(layer "In2.Cu")
		(net "M_M_CLK_DN<1>")
	)
	(segment
		(start 94.990158 -94.01302)
		(end 94.996508 -94.023688)
		(width 0.0889)
		(layer "In2.Cu")
		(net "M_M_CLK_DN<1>")
	)
	(segment
		(start 97.046542 -136.736074)
		(end 96.93275 -136.849866)
		(width 0.14224)
		(layer "In2.Cu")
		(net "M_M_CLK_DN<1>")
	)
	(segment
		(start 95.00108 -99.368864)
		(end 94.917768 -99.518216)
		(width 0.0889)
		(layer "In2.Cu")
		(net "M_M_CLK_DN<1>")
	)
	(segment
		(start 97.046542 -129.682494)
		(end 97.046542 -135.57885)
		(width 0.14224)
		(layer "In2.Cu")
		(net "M_M_CLK_DN<1>")
	)
	(segment
		(start 95.202248 -102.009448)
		(end 95.202248 -102.031546)
		(width 0.0889)
		(layer "In2.Cu")
		(net "M_M_CLK_DN<1>")
	)
	(segment
		(start 93.847158 -156.363924)
		(end 93.382338 -156.363924)
		(width 0.14224)
		(layer "In2.Cu")
		(net "M_M_CLK_DN<1>")
	)
	(segment
		(start 96.93275 -136.849866)
		(end 96.93275 -137.314686)
		(width 0.14224)
		(layer "In2.Cu")
		(net "M_M_CLK_DN<1>")
	)
	(segment
		(start 97.046542 -135.57885)
		(end 96.93275 -135.692642)
		(width 0.14224)
		(layer "In2.Cu")
		(net "M_M_CLK_DN<1>")
	)
	(segment
		(start 97.01911 -142.334742)
		(end 97.01911 -151.809958)
		(width 0.14224)
		(layer "In2.Cu")
		(net "M_M_CLK_DN<1>")
	)
	(segment
		(start 93.791278 -91.747086)
		(end 93.909642 -91.865196)
		(width 0.0889)
		(layer "In2.Cu")
		(net "M_M_CLK_DN<1>")
	)
	(segment
		(start 96.93275 -138.47191)
		(end 97.046542 -138.585702)
		(width 0.14224)
		(layer "In2.Cu")
		(net "M_M_CLK_DN<1>")
	)
	(segment
		(start 96.905318 -151.92375)
		(end 96.905318 -152.38857)
		(width 0.14224)
		(layer "In2.Cu")
		(net "M_M_CLK_DN<1>")
	)
	(segment
		(start 92.271088 -155.83789)
		(end 92.59951 -155.509468)
		(width 0.14224)
		(layer "In2.Cu")
		(net "M_M_CLK_DN<1>")
	)
	(segment
		(start 94.917768 -99.518216)
		(end 94.917768 -99.989894)
		(width 0.0889)
		(layer "In2.Cu")
		(net "M_M_CLK_DN<1>")
	)
	(segment
		(start 94.632018 -92.83319)
		(end 94.664784 -92.83319)
		(width 0.0889)
		(layer "In2.Cu")
		(net "M_M_CLK_DN<1>")
	)
	(segment
		(start 96.160082 -154.822652)
		(end 95.831152 -155.151582)
		(width 0.14224)
		(layer "In2.Cu")
		(net "M_M_CLK_DN<1>")
	)
	(segment
		(start 94.996508 -95.414338)
		(end 94.990158 -95.425006)
		(width 0.0889)
		(layer "In2.Cu")
		(net "M_M_CLK_DN<1>")
	)
	(segment
		(start 96.93275 -139.164314)
		(end 96.93275 -139.629134)
		(width 0.14224)
		(layer "In2.Cu")
		(net "M_M_CLK_DN<1>")
	)
	(segment
		(start 95.202248 -102.639114)
		(end 95.507048 -102.943914)
		(width 0.14224)
		(layer "In2.Cu")
		(net "M_M_CLK_DN<1>")
	)
	(segment
		(start 93.942662 -156.459428)
		(end 93.847158 -156.363924)
		(width 0.14224)
		(layer "In2.Cu")
		(net "M_M_CLK_DN<1>")
	)
	(segment
		(start 96.934528 -142.25016)
		(end 97.01911 -142.334742)
		(width 0.14224)
		(layer "In2.Cu")
		(net "M_M_CLK_DN<1>")
	)
	(segment
		(start 94.684088 -156.459428)
		(end 93.942662 -156.459428)
		(width 0.14224)
		(layer "In2.Cu")
		(net "M_M_CLK_DN<1>")
	)
	(segment
		(start 97.046542 -138.585702)
		(end 97.046542 -139.050522)
		(width 0.14224)
		(layer "In2.Cu")
		(net "M_M_CLK_DN<1>")
	)
	(segment
		(start 94.996508 -97.395538)
		(end 94.990158 -97.406206)
		(width 0.0889)
		(layer "In2.Cu")
		(net "M_M_CLK_DN<1>")
	)
	(segment
		(start 93.286834 -156.459428)
		(end 92.54744 -156.459428)
		(width 0.14224)
		(layer "In2.Cu")
		(net "M_M_CLK_DN<1>")
	)
	(segment
		(start 94.996508 -98.976688)
		(end 94.996762 -98.976942)
		(width 0.0889)
		(layer "In2.Cu")
		(net "M_M_CLK_DN<1>")
	)
	(segment
		(start 96.93275 -135.692642)
		(end 96.93275 -136.157462)
		(width 0.14224)
		(layer "In2.Cu")
		(net "M_M_CLK_DN<1>")
	)
	(segment
		(start 96.93275 -137.314686)
		(end 97.046542 -137.428478)
		(width 0.14224)
		(layer "In2.Cu")
		(net "M_M_CLK_DN<1>")
	)
	(segment
		(start 93.382338 -156.363924)
		(end 93.286834 -156.459428)
		(width 0.14224)
		(layer "In2.Cu")
		(net "M_M_CLK_DN<1>")
	)
	(segment
		(start 95.831152 -155.312364)
		(end 95.502476 -155.64104)
		(width 0.14224)
		(layer "In2.Cu")
		(net "M_M_CLK_DN<1>")
	)
	(segment
		(start 97.046542 -139.742926)
		(end 97.046542 -140.487146)
		(width 0.14224)
		(layer "In2.Cu")
		(net "M_M_CLK_DN<1>")
	)
	(segment
		(start 94.917768 -99.989894)
		(end 95.247968 -100.320094)
		(width 0.0889)
		(layer "In2.Cu")
		(net "M_M_CLK_DN<1>")
	)
	(segment
		(start 95.502476 -155.64104)
		(end 95.341694 -155.64104)
		(width 0.14224)
		(layer "In2.Cu")
		(net "M_M_CLK_DN<1>")
	)
	(arc
		(start 94.996508 -96.004888)
		(mid 95.049978 -96.199951)
		(end 95.001334 -96.396302)
		(width 0.0889)
		(layer "In2.Cu")
		(net "M_M_CLK_DN<1>")
	)
	(arc
		(start 94.996762 -98.976942)
		(mid 95.050202 -99.17235)
		(end 95.00108 -99.368864)
		(width 0.0889)
		(layer "In2.Cu")
		(net "M_M_CLK_DN<1>")
	)
	(arc
		(start 94.996508 -94.023688)
		(mid 95.050007 -94.223586)
		(end 94.996508 -94.423484)
		(width 0.0889)
		(layer "In2.Cu")
		(net "M_M_CLK_DN<1>")
	)
	(arc
		(start 94.058994 -92.22613)
		(mid 94.219939 -92.648178)
		(end 94.632018 -92.83319)
		(width 0.0889)
		(layer "In2.Cu")
		(net "M_M_CLK_DN<1>")
	)
	(arc
		(start 94.996508 -96.995488)
		(mid 95.049978 -97.190551)
		(end 95.001334 -97.386902)
		(width 0.0889)
		(layer "In2.Cu")
		(net "M_M_CLK_DN<1>")
	)
	(arc
		(start 94.990158 -97.406206)
		(mid 94.91736 -97.696969)
		(end 94.996508 -97.986088)
		(width 0.0889)
		(layer "In2.Cu")
		(net "M_M_CLK_DN<1>")
	)
	(arc
		(start 94.990158 -96.415606)
		(mid 94.91736 -96.706369)
		(end 94.996508 -96.995488)
		(width 0.0889)
		(layer "In2.Cu")
		(net "M_M_CLK_DN<1>")
	)
	(arc
		(start 94.996508 -97.986088)
		(mid 95.049978 -98.181151)
		(end 95.001334 -98.377502)
		(width 0.0889)
		(layer "In2.Cu")
		(net "M_M_CLK_DN<1>")
	)
	(arc
		(start 94.664784 -92.83319)
		(mid 94.997702 -93.035181)
		(end 95.001334 -93.424502)
		(width 0.0889)
		(layer "In2.Cu")
		(net "M_M_CLK_DN<1>")
	)
	(arc
		(start 94.996508 -95.014288)
		(mid 95.049978 -95.209351)
		(end 95.001334 -95.405702)
		(width 0.0889)
		(layer "In2.Cu")
		(net "M_M_CLK_DN<1>")
	)
	(arc
		(start 93.909642 -91.865196)
		(mid 94.020208 -92.030809)
		(end 94.058994 -92.22613)
		(width 0.0889)
		(layer "In2.Cu")
		(net "M_M_CLK_DN<1>")
	)
	(arc
		(start 94.996508 -93.433138)
		(mid 94.917286 -93.722256)
		(end 94.990158 -94.01302)
		(width 0.0889)
		(layer "In2.Cu")
		(net "M_M_CLK_DN<1>")
	)
	(arc
		(start 94.996508 -94.423484)
		(mid 94.917377 -94.718886)
		(end 94.996508 -95.014288)
		(width 0.0889)
		(layer "In2.Cu")
		(net "M_M_CLK_DN<1>")
	)
	(arc
		(start 94.990158 -95.425006)
		(mid 94.91736 -95.715769)
		(end 94.996508 -96.004888)
		(width 0.0889)
		(layer "In2.Cu")
		(net "M_M_CLK_DN<1>")
	)
	(arc
		(start 94.990158 -98.396806)
		(mid 94.91736 -98.687569)
		(end 94.996508 -98.976688)
		(width 0.0889)
		(layer "In2.Cu")
		(net "M_M_CLK_DN<1>")
	)
	(segment
		(start 92.645738 -93.72854)
		(end 92.074238 -93.72854)
		(width 0.1016)
		(layer "F.Cu")
		(net "M_M_CLK_DN<2>")
	)
	(via
		(at 92.788994 -150.785068)
		(size 0.508)
		(drill 0.254)
		(layers "F.Cu" "B.Cu")
		(net "M_M_CLK_DN<2>")
	)
	(via
		(at 92.074238 -93.72854)
		(size 0.508)
		(drill 0.254)
		(layers "F.Cu" "B.Cu")
		(net "M_M_CLK_DN<2>")
	)
	(segment
		(start 92.59951 -150.974552)
		(end 92.788994 -150.785068)
		(width 0.1651)
		(layer "B.Cu")
		(net "M_M_CLK_DN<2>")
	)
	(segment
		(start 92.59951 -152.078436)
		(end 92.59951 -150.974552)
		(width 0.1651)
		(layer "B.Cu")
		(net "M_M_CLK_DN<2>")
	)
	(segment
		(start 93.657928 -127.586232)
		(end 93.657928 -133.44144)
		(width 0.14224)
		(layer "In2.Cu")
		(net "M_M_CLK_DN<2>")
	)
	(segment
		(start 92.407232 -99.448874)
		(end 92.410788 -99.454716)
		(width 0.0889)
		(layer "In2.Cu")
		(net "M_M_CLK_DN<2>")
	)
	(segment
		(start 93.983048 -142.18412)
		(end 93.983048 -145.951702)
		(width 0.14224)
		(layer "In2.Cu")
		(net "M_M_CLK_DN<2>")
	)
	(segment
		(start 91.123262 -147.924774)
		(end 91.123262 -151.662892)
		(width 0.14224)
		(layer "In2.Cu")
		(net "M_M_CLK_DN<2>")
	)
	(segment
		(start 93.983048 -133.76656)
		(end 93.983048 -139.4206)
		(width 0.14224)
		(layer "In2.Cu")
		(net "M_M_CLK_DN<2>")
	)
	(segment
		(start 92.4306 -99.489514)
		(end 92.479368 -99.582224)
		(width 0.0889)
		(layer "In2.Cu")
		(net "M_M_CLK_DN<2>")
	)
	(segment
		(start 94.470728 -139.90828)
		(end 94.470728 -141.69644)
		(width 0.14224)
		(layer "In2.Cu")
		(net "M_M_CLK_DN<2>")
	)
	(segment
		(start 91.699588 -147.348448)
		(end 91.123262 -147.924774)
		(width 0.14224)
		(layer "In2.Cu")
		(net "M_M_CLK_DN<2>")
	)
	(segment
		(start 92.420948 -96.500188)
		(end 92.425774 -96.508824)
		(width 0.0889)
		(layer "In2.Cu")
		(net "M_M_CLK_DN<2>")
	)
	(segment
		(start 92.414598 -95.49892)
		(end 92.420948 -95.509588)
		(width 0.0889)
		(layer "In2.Cu")
		(net "M_M_CLK_DN<2>")
	)
	(segment
		(start 92.683584 -100.49891)
		(end 92.683584 -101.878638)
		(width 0.0889)
		(layer "In2.Cu")
		(net "M_M_CLK_DN<2>")
	)
	(segment
		(start 92.367354 -93.55963)
		(end 92.446094 -93.580966)
		(width 0.0889)
		(layer "In2.Cu")
		(net "M_M_CLK_DN<2>")
	)
	(segment
		(start 92.420948 -94.518988)
		(end 92.425774 -94.527624)
		(width 0.0889)
		(layer "In2.Cu")
		(net "M_M_CLK_DN<2>")
	)
	(segment
		(start 92.941648 -103.959914)
		(end 92.941648 -126.869952)
		(width 0.14224)
		(layer "In2.Cu")
		(net "M_M_CLK_DN<2>")
	)
	(segment
		(start 91.961208 -151.947372)
		(end 92.495878 -151.412702)
		(width 0.14224)
		(layer "In2.Cu")
		(net "M_M_CLK_DN<2>")
	)
	(segment
		(start 92.420948 -95.509588)
		(end 92.425774 -95.518224)
		(width 0.0889)
		(layer "In2.Cu")
		(net "M_M_CLK_DN<2>")
	)
	(segment
		(start 91.123262 -151.662892)
		(end 91.407742 -151.947372)
		(width 0.14224)
		(layer "In2.Cu")
		(net "M_M_CLK_DN<2>")
	)
	(segment
		(start 93.983048 -139.4206)
		(end 94.470728 -139.90828)
		(width 0.14224)
		(layer "In2.Cu")
		(net "M_M_CLK_DN<2>")
	)
	(segment
		(start 92.414598 -97.48012)
		(end 92.42806 -97.50298)
		(width 0.0889)
		(layer "In2.Cu")
		(net "M_M_CLK_DN<2>")
	)
	(segment
		(start 94.470728 -141.69644)
		(end 93.983048 -142.18412)
		(width 0.14224)
		(layer "In2.Cu")
		(net "M_M_CLK_DN<2>")
	)
	(segment
		(start 92.683584 -101.878638)
		(end 92.637864 -101.924358)
		(width 0.0889)
		(layer "In2.Cu")
		(net "M_M_CLK_DN<2>")
	)
	(segment
		(start 92.495878 -151.078184)
		(end 92.788994 -150.785068)
		(width 0.14224)
		(layer "In2.Cu")
		(net "M_M_CLK_DN<2>")
	)
	(segment
		(start 91.407742 -151.947372)
		(end 91.961208 -151.947372)
		(width 0.14224)
		(layer "In2.Cu")
		(net "M_M_CLK_DN<2>")
	)
	(segment
		(start 92.408502 -98.46056)
		(end 92.430854 -98.499168)
		(width 0.0889)
		(layer "In2.Cu")
		(net "M_M_CLK_DN<2>")
	)
	(segment
		(start 92.637864 -103.65613)
		(end 92.941648 -103.959914)
		(width 0.14224)
		(layer "In2.Cu")
		(net "M_M_CLK_DN<2>")
	)
	(segment
		(start 92.586302 -147.348448)
		(end 91.699588 -147.348448)
		(width 0.14224)
		(layer "In2.Cu")
		(net "M_M_CLK_DN<2>")
	)
	(segment
		(start 92.410788 -99.454716)
		(end 92.4306 -99.489514)
		(width 0.0889)
		(layer "In2.Cu")
		(net "M_M_CLK_DN<2>")
	)
	(segment
		(start 92.420948 -93.928438)
		(end 92.414598 -93.939106)
		(width 0.0889)
		(layer "In2.Cu")
		(net "M_M_CLK_DN<2>")
	)
	(segment
		(start 93.983048 -145.951702)
		(end 92.586302 -147.348448)
		(width 0.14224)
		(layer "In2.Cu")
		(net "M_M_CLK_DN<2>")
	)
	(segment
		(start 93.657928 -133.44144)
		(end 93.983048 -133.76656)
		(width 0.14224)
		(layer "In2.Cu")
		(net "M_M_CLK_DN<2>")
	)
	(segment
		(start 92.414598 -96.48952)
		(end 92.420948 -96.500188)
		(width 0.0889)
		(layer "In2.Cu")
		(net "M_M_CLK_DN<2>")
	)
	(segment
		(start 92.495878 -151.412702)
		(end 92.495878 -151.078184)
		(width 0.14224)
		(layer "In2.Cu")
		(net "M_M_CLK_DN<2>")
	)
	(segment
		(start 92.074238 -93.72854)
		(end 92.367354 -93.55963)
		(width 0.0889)
		(layer "In2.Cu")
		(net "M_M_CLK_DN<2>")
	)
	(segment
		(start 92.479368 -99.582224)
		(end 92.479368 -100.294694)
		(width 0.0889)
		(layer "In2.Cu")
		(net "M_M_CLK_DN<2>")
	)
	(segment
		(start 92.941648 -126.869952)
		(end 93.657928 -127.586232)
		(width 0.14224)
		(layer "In2.Cu")
		(net "M_M_CLK_DN<2>")
	)
	(segment
		(start 92.637864 -101.924358)
		(end 92.637864 -103.65613)
		(width 0.14224)
		(layer "In2.Cu")
		(net "M_M_CLK_DN<2>")
	)
	(segment
		(start 92.479368 -100.294694)
		(end 92.683584 -100.49891)
		(width 0.0889)
		(layer "In2.Cu")
		(net "M_M_CLK_DN<2>")
	)
	(arc
		(start 92.425774 -95.518224)
		(mid 92.474529 -95.714576)
		(end 92.420948 -95.909638)
		(width 0.0889)
		(layer "In2.Cu")
		(net "M_M_CLK_DN<2>")
	)
	(arc
		(start 92.420948 -96.900238)
		(mid 92.341726 -97.189356)
		(end 92.414598 -97.48012)
		(width 0.0889)
		(layer "In2.Cu")
		(net "M_M_CLK_DN<2>")
	)
	(arc
		(start 92.42806 -97.50298)
		(mid 92.474701 -97.697964)
		(end 92.420948 -97.891092)
		(width 0.0889)
		(layer "In2.Cu")
		(net "M_M_CLK_DN<2>")
	)
	(arc
		(start 92.420948 -97.891092)
		(mid 92.341579 -98.174241)
		(end 92.408502 -98.46056)
		(width 0.0889)
		(layer "In2.Cu")
		(net "M_M_CLK_DN<2>")
	)
	(arc
		(start 92.420948 -94.919038)
		(mid 92.341726 -95.208156)
		(end 92.414598 -95.49892)
		(width 0.0889)
		(layer "In2.Cu")
		(net "M_M_CLK_DN<2>")
	)
	(arc
		(start 92.474288 -93.727016)
		(mid 92.460956 -93.83126)
		(end 92.420948 -93.928438)
		(width 0.0889)
		(layer "In2.Cu")
		(net "M_M_CLK_DN<2>")
	)
	(arc
		(start 92.420948 -95.909638)
		(mid 92.341726 -96.198756)
		(end 92.414598 -96.48952)
		(width 0.0889)
		(layer "In2.Cu")
		(net "M_M_CLK_DN<2>")
	)
	(arc
		(start 92.425774 -96.508824)
		(mid 92.474529 -96.705176)
		(end 92.420948 -96.900238)
		(width 0.0889)
		(layer "In2.Cu")
		(net "M_M_CLK_DN<2>")
	)
	(arc
		(start 92.425774 -94.527624)
		(mid 92.474529 -94.723976)
		(end 92.420948 -94.919038)
		(width 0.0889)
		(layer "In2.Cu")
		(net "M_M_CLK_DN<2>")
	)
	(arc
		(start 92.446094 -93.580966)
		(mid 92.467033 -93.65267)
		(end 92.474288 -93.727016)
		(width 0.0889)
		(layer "In2.Cu")
		(net "M_M_CLK_DN<2>")
	)
	(arc
		(start 92.430854 -98.499168)
		(mid 92.47453 -98.691685)
		(end 92.420948 -98.881692)
		(width 0.0889)
		(layer "In2.Cu")
		(net "M_M_CLK_DN<2>")
	)
	(arc
		(start 92.420948 -98.881692)
		(mid 92.341609 -99.163534)
		(end 92.407232 -99.448874)
		(width 0.0889)
		(layer "In2.Cu")
		(net "M_M_CLK_DN<2>")
	)
	(arc
		(start 92.414598 -93.939106)
		(mid 92.3418 -94.229869)
		(end 92.420948 -94.518988)
		(width 0.0889)
		(layer "In2.Cu")
		(net "M_M_CLK_DN<2>")
	)
	(segment
		(start 94.362778 -93.72854)
		(end 93.791278 -93.72854)
		(width 0.1016)
		(layer "F.Cu")
		(net "M_M_CLK_DN<0>")
	)
	(segment
		(start 92.59951 -152.273)
		(end 92.59951 -153.571956)
		(width 0.1651)
		(layer "F.Cu")
		(net "M_M_CLK_DN<0>")
	)
	(via
		(at 93.791278 -93.72854)
		(size 0.508)
		(drill 0.254)
		(layers "F.Cu" "B.Cu")
		(net "M_M_CLK_DN<0>")
	)
	(via
		(at 92.59951 -153.571956)
		(size 0.508)
		(drill 0.254)
		(layers "F.Cu" "B.Cu")
		(net "M_M_CLK_DN<0>")
	)
	(segment
		(start 96.164146 -130.246882)
		(end 96.164146 -132.258054)
		(width 0.14224)
		(layer "In2.Cu")
		(net "M_M_CLK_DN<0>")
	)
	(segment
		(start 92.298012 -154.163776)
		(end 92.298012 -153.873454)
		(width 0.14224)
		(layer "In2.Cu")
		(net "M_M_CLK_DN<0>")
	)
	(segment
		(start 96.164146 -151.247602)
		(end 95.841566 -151.570182)
		(width 0.14224)
		(layer "In2.Cu")
		(net "M_M_CLK_DN<0>")
	)
	(segment
		(start 94.338648 -102.969314)
		(end 94.618048 -103.248714)
		(width 0.14224)
		(layer "In2.Cu")
		(net "M_M_CLK_DN<0>")
	)
	(segment
		(start 96.164146 -135.729726)
		(end 96.050354 -135.843518)
		(width 0.14224)
		(layer "In2.Cu")
		(net "M_M_CLK_DN<0>")
	)
	(segment
		(start 95.004636 -154.398726)
		(end 93.968316 -154.398726)
		(width 0.14224)
		(layer "In2.Cu")
		(net "M_M_CLK_DN<0>")
	)
	(segment
		(start 94.270068 -100.332794)
		(end 94.391988 -100.454714)
		(width 0.0889)
		(layer "In2.Cu")
		(net "M_M_CLK_DN<0>")
	)
	(segment
		(start 96.050354 -136.308338)
		(end 96.164146 -136.42213)
		(width 0.14224)
		(layer "In2.Cu")
		(net "M_M_CLK_DN<0>")
	)
	(segment
		(start 96.050354 -132.836666)
		(end 96.164146 -132.950458)
		(width 0.14224)
		(layer "In2.Cu")
		(net "M_M_CLK_DN<0>")
	)
	(segment
		(start 94.369382 -152.925526)
		(end 95.037656 -152.925526)
		(width 0.14224)
		(layer "In2.Cu")
		(net "M_M_CLK_DN<0>")
	)
	(segment
		(start 92.926662 -151.88311)
		(end 92.926662 -152.612598)
		(width 0.14224)
		(layer "In2.Cu")
		(net "M_M_CLK_DN<0>")
	)
	(segment
		(start 96.164146 -136.42213)
		(end 96.164146 -145.437352)
		(width 0.14224)
		(layer "In2.Cu")
		(net "M_M_CLK_DN<0>")
	)
	(segment
		(start 92.298012 -153.873454)
		(end 92.59951 -153.571956)
		(width 0.14224)
		(layer "In2.Cu")
		(net "M_M_CLK_DN<0>")
	)
	(segment
		(start 93.2942 -154.398726)
		(end 92.532962 -154.398726)
		(width 0.14224)
		(layer "In2.Cu")
		(net "M_M_CLK_DN<0>")
	)
	(segment
		(start 93.818202 -153.011886)
		(end 94.283022 -153.011886)
		(width 0.14224)
		(layer "In2.Cu")
		(net "M_M_CLK_DN<0>")
	)
	(segment
		(start 96.164146 -132.258054)
		(end 96.050354 -132.371846)
		(width 0.14224)
		(layer "In2.Cu")
		(net "M_M_CLK_DN<0>")
	)
	(segment
		(start 94.283022 -153.011886)
		(end 94.369382 -152.925526)
		(width 0.14224)
		(layer "In2.Cu")
		(net "M_M_CLK_DN<0>")
	)
	(segment
		(start 96.050354 -134.686294)
		(end 96.050354 -135.151114)
		(width 0.14224)
		(layer "In2.Cu")
		(net "M_M_CLK_DN<0>")
	)
	(segment
		(start 94.391988 -100.454714)
		(end 94.391988 -101.897434)
		(width 0.0889)
		(layer "In2.Cu")
		(net "M_M_CLK_DN<0>")
	)
	(segment
		(start 94.131638 -98.47072)
		(end 94.137988 -98.481388)
		(width 0.0889)
		(layer "In2.Cu")
		(net "M_M_CLK_DN<0>")
	)
	(segment
		(start 96.050354 -135.151114)
		(end 96.164146 -135.264906)
		(width 0.14224)
		(layer "In2.Cu")
		(net "M_M_CLK_DN<0>")
	)
	(segment
		(start 96.164146 -132.950458)
		(end 96.164146 -133.415278)
		(width 0.14224)
		(layer "In2.Cu")
		(net "M_M_CLK_DN<0>")
	)
	(segment
		(start 93.863668 -154.294078)
		(end 93.398848 -154.294078)
		(width 0.14224)
		(layer "In2.Cu")
		(net "M_M_CLK_DN<0>")
	)
	(segment
		(start 95.6818 -127.110744)
		(end 95.6818 -129.764536)
		(width 0.14224)
		(layer "In2.Cu")
		(net "M_M_CLK_DN<0>")
	)
	(segment
		(start 93.23959 -151.570182)
		(end 92.926662 -151.88311)
		(width 0.14224)
		(layer "In2.Cu")
		(net "M_M_CLK_DN<0>")
	)
	(segment
		(start 93.968316 -154.398726)
		(end 93.863668 -154.294078)
		(width 0.14224)
		(layer "In2.Cu")
		(net "M_M_CLK_DN<0>")
	)
	(segment
		(start 96.050354 -149.046946)
		(end 96.050354 -149.511766)
		(width 0.14224)
		(layer "In2.Cu")
		(net "M_M_CLK_DN<0>")
	)
	(segment
		(start 93.398848 -154.294078)
		(end 93.2942 -154.398726)
		(width 0.14224)
		(layer "In2.Cu")
		(net "M_M_CLK_DN<0>")
	)
	(segment
		(start 96.050354 -146.015964)
		(end 96.164146 -146.129756)
		(width 0.14224)
		(layer "In2.Cu")
		(net "M_M_CLK_DN<0>")
	)
	(segment
		(start 94.618048 -103.248714)
		(end 94.618048 -126.046992)
		(width 0.14224)
		(layer "In2.Cu")
		(net "M_M_CLK_DN<0>")
	)
	(segment
		(start 92.926662 -152.612598)
		(end 93.23959 -152.925526)
		(width 0.14224)
		(layer "In2.Cu")
		(net "M_M_CLK_DN<0>")
	)
	(segment
		(start 96.050354 -132.371846)
		(end 96.050354 -132.836666)
		(width 0.14224)
		(layer "In2.Cu")
		(net "M_M_CLK_DN<0>")
	)
	(segment
		(start 94.154498 -99.49942)
		(end 94.270068 -99.677474)
		(width 0.0889)
		(layer "In2.Cu")
		(net "M_M_CLK_DN<0>")
	)
	(segment
		(start 96.164146 -134.107682)
		(end 96.164146 -134.572502)
		(width 0.14224)
		(layer "In2.Cu")
		(net "M_M_CLK_DN<0>")
	)
	(segment
		(start 96.050354 -133.52907)
		(end 96.050354 -133.99389)
		(width 0.14224)
		(layer "In2.Cu")
		(net "M_M_CLK_DN<0>")
	)
	(segment
		(start 93.791278 -93.72854)
		(end 94.084394 -93.55963)
		(width 0.0889)
		(layer "In2.Cu")
		(net "M_M_CLK_DN<0>")
	)
	(segment
		(start 93.731842 -152.925526)
		(end 93.818202 -153.011886)
		(width 0.14224)
		(layer "In2.Cu")
		(net "M_M_CLK_DN<0>")
	)
	(segment
		(start 94.287594 -151.483568)
		(end 93.822774 -151.483568)
		(width 0.14224)
		(layer "In2.Cu")
		(net "M_M_CLK_DN<0>")
	)
	(segment
		(start 94.137988 -96.500188)
		(end 94.142814 -96.508824)
		(width 0.0889)
		(layer "In2.Cu")
		(net "M_M_CLK_DN<0>")
	)
	(segment
		(start 95.307404 -154.095958)
		(end 95.004636 -154.398726)
		(width 0.14224)
		(layer "In2.Cu")
		(net "M_M_CLK_DN<0>")
	)
	(segment
		(start 92.532962 -154.398726)
		(end 92.298012 -154.163776)
		(width 0.14224)
		(layer "In2.Cu")
		(net "M_M_CLK_DN<0>")
	)
	(segment
		(start 95.307404 -153.195274)
		(end 95.307404 -154.095958)
		(width 0.14224)
		(layer "In2.Cu")
		(net "M_M_CLK_DN<0>")
	)
	(segment
		(start 94.137988 -95.509588)
		(end 94.142814 -95.518224)
		(width 0.0889)
		(layer "In2.Cu")
		(net "M_M_CLK_DN<0>")
	)
	(segment
		(start 96.164146 -145.437352)
		(end 96.050354 -145.551144)
		(width 0.14224)
		(layer "In2.Cu")
		(net "M_M_CLK_DN<0>")
	)
	(segment
		(start 96.164146 -133.415278)
		(end 96.050354 -133.52907)
		(width 0.14224)
		(layer "In2.Cu")
		(net "M_M_CLK_DN<0>")
	)
	(segment
		(start 96.050354 -145.551144)
		(end 96.050354 -146.015964)
		(width 0.14224)
		(layer "In2.Cu")
		(net "M_M_CLK_DN<0>")
	)
	(segment
		(start 94.338648 -101.950774)
		(end 94.338648 -102.969314)
		(width 0.14224)
		(layer "In2.Cu")
		(net "M_M_CLK_DN<0>")
	)
	(segment
		(start 95.841566 -151.570182)
		(end 94.374208 -151.570182)
		(width 0.14224)
		(layer "In2.Cu")
		(net "M_M_CLK_DN<0>")
	)
	(segment
		(start 94.131638 -97.48012)
		(end 94.137988 -97.490788)
		(width 0.0889)
		(layer "In2.Cu")
		(net "M_M_CLK_DN<0>")
	)
	(segment
		(start 94.618048 -126.046992)
		(end 95.6818 -127.110744)
		(width 0.14224)
		(layer "In2.Cu")
		(net "M_M_CLK_DN<0>")
	)
	(segment
		(start 94.137988 -93.928438)
		(end 94.131638 -93.939106)
		(width 0.0889)
		(layer "In2.Cu")
		(net "M_M_CLK_DN<0>")
	)
	(segment
		(start 96.164146 -149.625558)
		(end 96.164146 -150.090378)
		(width 0.14224)
		(layer "In2.Cu")
		(net "M_M_CLK_DN<0>")
	)
	(segment
		(start 93.73616 -151.570182)
		(end 93.23959 -151.570182)
		(width 0.14224)
		(layer "In2.Cu")
		(net "M_M_CLK_DN<0>")
	)
	(segment
		(start 96.164146 -135.264906)
		(end 96.164146 -135.729726)
		(width 0.14224)
		(layer "In2.Cu")
		(net "M_M_CLK_DN<0>")
	)
	(segment
		(start 96.164146 -150.090378)
		(end 96.050354 -150.20417)
		(width 0.14224)
		(layer "In2.Cu")
		(net "M_M_CLK_DN<0>")
	)
	(segment
		(start 94.270068 -99.677474)
		(end 94.270068 -100.332794)
		(width 0.0889)
		(layer "In2.Cu")
		(net "M_M_CLK_DN<0>")
	)
	(segment
		(start 96.164146 -146.129756)
		(end 96.164146 -148.933154)
		(width 0.14224)
		(layer "In2.Cu")
		(net "M_M_CLK_DN<0>")
	)
	(segment
		(start 94.137988 -98.481388)
		(end 94.142814 -98.490024)
		(width 0.0889)
		(layer "In2.Cu")
		(net "M_M_CLK_DN<0>")
	)
	(segment
		(start 96.164146 -148.933154)
		(end 96.050354 -149.046946)
		(width 0.14224)
		(layer "In2.Cu")
		(net "M_M_CLK_DN<0>")
	)
	(segment
		(start 93.23959 -152.925526)
		(end 93.731842 -152.925526)
		(width 0.14224)
		(layer "In2.Cu")
		(net "M_M_CLK_DN<0>")
	)
	(segment
		(start 94.374208 -151.570182)
		(end 94.287594 -151.483568)
		(width 0.14224)
		(layer "In2.Cu")
		(net "M_M_CLK_DN<0>")
	)
	(segment
		(start 96.050354 -150.20417)
		(end 96.050354 -150.66899)
		(width 0.14224)
		(layer "In2.Cu")
		(net "M_M_CLK_DN<0>")
	)
	(segment
		(start 96.050354 -135.843518)
		(end 96.050354 -136.308338)
		(width 0.14224)
		(layer "In2.Cu")
		(net "M_M_CLK_DN<0>")
	)
	(segment
		(start 94.154244 -99.49942)
		(end 94.154498 -99.49942)
		(width 0.0889)
		(layer "In2.Cu")
		(net "M_M_CLK_DN<0>")
	)
	(segment
		(start 94.391988 -101.897434)
		(end 94.338648 -101.950774)
		(width 0.0889)
		(layer "In2.Cu")
		(net "M_M_CLK_DN<0>")
	)
	(segment
		(start 94.137988 -97.490788)
		(end 94.142814 -97.499424)
		(width 0.0889)
		(layer "In2.Cu")
		(net "M_M_CLK_DN<0>")
	)
	(segment
		(start 94.137988 -94.518988)
		(end 94.142814 -94.527624)
		(width 0.0889)
		(layer "In2.Cu")
		(net "M_M_CLK_DN<0>")
	)
	(segment
		(start 96.050354 -149.511766)
		(end 96.164146 -149.625558)
		(width 0.14224)
		(layer "In2.Cu")
		(net "M_M_CLK_DN<0>")
	)
	(segment
		(start 96.050354 -133.99389)
		(end 96.164146 -134.107682)
		(width 0.14224)
		(layer "In2.Cu")
		(net "M_M_CLK_DN<0>")
	)
	(segment
		(start 94.084394 -93.55963)
		(end 94.163134 -93.580966)
		(width 0.0889)
		(layer "In2.Cu")
		(net "M_M_CLK_DN<0>")
	)
	(segment
		(start 93.822774 -151.483568)
		(end 93.73616 -151.570182)
		(width 0.14224)
		(layer "In2.Cu")
		(net "M_M_CLK_DN<0>")
	)
	(segment
		(start 94.131638 -95.49892)
		(end 94.137988 -95.509588)
		(width 0.0889)
		(layer "In2.Cu")
		(net "M_M_CLK_DN<0>")
	)
	(segment
		(start 96.050354 -150.66899)
		(end 96.164146 -150.782782)
		(width 0.14224)
		(layer "In2.Cu")
		(net "M_M_CLK_DN<0>")
	)
	(segment
		(start 96.164146 -150.782782)
		(end 96.164146 -151.247602)
		(width 0.14224)
		(layer "In2.Cu")
		(net "M_M_CLK_DN<0>")
	)
	(segment
		(start 96.164146 -134.572502)
		(end 96.050354 -134.686294)
		(width 0.14224)
		(layer "In2.Cu")
		(net "M_M_CLK_DN<0>")
	)
	(segment
		(start 94.131638 -96.48952)
		(end 94.137988 -96.500188)
		(width 0.0889)
		(layer "In2.Cu")
		(net "M_M_CLK_DN<0>")
	)
	(segment
		(start 95.037656 -152.925526)
		(end 95.307404 -153.195274)
		(width 0.14224)
		(layer "In2.Cu")
		(net "M_M_CLK_DN<0>")
	)
	(segment
		(start 95.6818 -129.764536)
		(end 96.164146 -130.246882)
		(width 0.14224)
		(layer "In2.Cu")
		(net "M_M_CLK_DN<0>")
	)
	(arc
		(start 94.142814 -96.508824)
		(mid 94.191569 -96.705176)
		(end 94.137988 -96.900238)
		(width 0.0889)
		(layer "In2.Cu")
		(net "M_M_CLK_DN<0>")
	)
	(arc
		(start 94.191328 -93.728032)
		(mid 94.177862 -93.83175)
		(end 94.137988 -93.928438)
		(width 0.0889)
		(layer "In2.Cu")
		(net "M_M_CLK_DN<0>")
	)
	(arc
		(start 94.142814 -97.499424)
		(mid 94.191569 -97.695776)
		(end 94.137988 -97.890838)
		(width 0.0889)
		(layer "In2.Cu")
		(net "M_M_CLK_DN<0>")
	)
	(arc
		(start 94.142814 -94.527624)
		(mid 94.191569 -94.723976)
		(end 94.137988 -94.919038)
		(width 0.0889)
		(layer "In2.Cu")
		(net "M_M_CLK_DN<0>")
	)
	(arc
		(start 94.137988 -98.881438)
		(mid 94.059004 -99.19271)
		(end 94.154244 -99.49942)
		(width 0.0889)
		(layer "In2.Cu")
		(net "M_M_CLK_DN<0>")
	)
	(arc
		(start 94.137988 -97.890838)
		(mid 94.058766 -98.179956)
		(end 94.131638 -98.47072)
		(width 0.0889)
		(layer "In2.Cu")
		(net "M_M_CLK_DN<0>")
	)
	(arc
		(start 94.137988 -96.900238)
		(mid 94.058766 -97.189356)
		(end 94.131638 -97.48012)
		(width 0.0889)
		(layer "In2.Cu")
		(net "M_M_CLK_DN<0>")
	)
	(arc
		(start 94.142814 -98.490024)
		(mid 94.191569 -98.686376)
		(end 94.137988 -98.881438)
		(width 0.0889)
		(layer "In2.Cu")
		(net "M_M_CLK_DN<0>")
	)
	(arc
		(start 94.163134 -93.580966)
		(mid 94.184169 -93.653169)
		(end 94.191328 -93.728032)
		(width 0.0889)
		(layer "In2.Cu")
		(net "M_M_CLK_DN<0>")
	)
	(arc
		(start 94.137988 -95.909638)
		(mid 94.058766 -96.198756)
		(end 94.131638 -96.48952)
		(width 0.0889)
		(layer "In2.Cu")
		(net "M_M_CLK_DN<0>")
	)
	(arc
		(start 94.137988 -94.919038)
		(mid 94.058766 -95.208156)
		(end 94.131638 -95.49892)
		(width 0.0889)
		(layer "In2.Cu")
		(net "M_M_CLK_DN<0>")
	)
	(arc
		(start 94.131638 -93.939106)
		(mid 94.05884 -94.229869)
		(end 94.137988 -94.518988)
		(width 0.0889)
		(layer "In2.Cu")
		(net "M_M_CLK_DN<0>")
	)
	(arc
		(start 94.142814 -95.518224)
		(mid 94.191569 -95.714576)
		(end 94.137988 -95.909638)
		(width 0.0889)
		(layer "In2.Cu")
		(net "M_M_CLK_DN<0>")
	)
	(segment
		(start 87.494872 -91.747086)
		(end 86.923372 -91.747086)
		(width 0.1016)
		(layer "F.Cu")
		(net "M_M_CKE<3>")
	)
	(via
		(at 78.999334 -148.771356)
		(size 0.4572)
		(drill 0.2032)
		(layers "F.Cu" "B.Cu")
		(net "M_M_CKE<3>")
	)
	(via
		(at 86.923372 -91.747086)
		(size 0.508)
		(drill 0.254)
		(layers "F.Cu" "B.Cu")
		(net "M_M_CKE<3>")
	)
	(segment
		(start 78.999334 -147.478496)
		(end 78.999334 -148.771356)
		(width 0.1651)
		(layer "B.Cu")
		(net "M_M_CKE<3>")
	)
	(segment
		(start 80.286098 -140.20927)
		(end 80.286098 -135.40867)
		(width 0.14224)
		(layer "In2.Cu")
		(net "M_M_CKE<3>")
	)
	(segment
		(start 80.263746 -131.951222)
		(end 80.363568 -131.8514)
		(width 0.14224)
		(layer "In2.Cu")
		(net "M_M_CKE<3>")
	)
	(segment
		(start 80.363568 -135.3312)
		(end 80.363568 -134.7978)
		(width 0.14224)
		(layer "In2.Cu")
		(net "M_M_CKE<3>")
	)
	(segment
		(start 80.286098 -146.538188)
		(end 80.286098 -144.37233)
		(width 0.14224)
		(layer "In2.Cu")
		(net "M_M_CKE<3>")
	)
	(segment
		(start 80.312768 -129.921)
		(end 80.236568 -129.8448)
		(width 0.14224)
		(layer "In2.Cu")
		(net "M_M_CKE<3>")
	)
	(segment
		(start 80.160368 -130.6576)
		(end 80.312768 -130.5052)
		(width 0.14224)
		(layer "In2.Cu")
		(net "M_M_CKE<3>")
	)
	(segment
		(start 80.263746 -144.349978)
		(end 80.263746 -140.231622)
		(width 0.14224)
		(layer "In2.Cu")
		(net "M_M_CKE<3>")
	)
	(segment
		(start 80.263746 -140.231622)
		(end 80.286098 -140.20927)
		(width 0.14224)
		(layer "In2.Cu")
		(net "M_M_CKE<3>")
	)
	(segment
		(start 86.571836 -96.508824)
		(end 86.576662 -96.500188)
		(width 0.0889)
		(layer "In2.Cu")
		(net "M_M_CKE<3>")
	)
	(segment
		(start 80.236568 -127.4572)
		(end 86.307168 -121.3866)
		(width 0.14224)
		(layer "In2.Cu")
		(net "M_M_CKE<3>")
	)
	(segment
		(start 80.160368 -131.1148)
		(end 80.160368 -130.6576)
		(width 0.14224)
		(layer "In2.Cu")
		(net "M_M_CKE<3>")
	)
	(segment
		(start 80.363568 -131.8514)
		(end 80.363568 -131.318)
		(width 0.14224)
		(layer "In2.Cu")
		(net "M_M_CKE<3>")
	)
	(segment
		(start 86.434168 -101.131116)
		(end 86.434168 -99.2886)
		(width 0.0889)
		(layer "In2.Cu")
		(net "M_M_CKE<3>")
	)
	(segment
		(start 80.286098 -144.37233)
		(end 80.263746 -144.349978)
		(width 0.14224)
		(layer "In2.Cu")
		(net "M_M_CKE<3>")
	)
	(segment
		(start 78.999334 -147.824952)
		(end 80.286098 -146.538188)
		(width 0.14224)
		(layer "In2.Cu")
		(net "M_M_CKE<3>")
	)
	(segment
		(start 86.307168 -101.258116)
		(end 86.434168 -101.131116)
		(width 0.0889)
		(layer "In2.Cu")
		(net "M_M_CKE<3>")
	)
	(segment
		(start 86.307168 -101.500178)
		(end 86.307168 -101.258116)
		(width 0.0889)
		(layer "In2.Cu")
		(net "M_M_CKE<3>")
	)
	(segment
		(start 86.583012 -93.939106)
		(end 86.576662 -93.928438)
		(width 0.0889)
		(layer "In2.Cu")
		(net "M_M_CKE<3>")
	)
	(segment
		(start 80.363568 -131.318)
		(end 80.160368 -131.1148)
		(width 0.14224)
		(layer "In2.Cu")
		(net "M_M_CKE<3>")
	)
	(segment
		(start 78.999334 -148.771356)
		(end 78.999334 -147.824952)
		(width 0.14224)
		(layer "In2.Cu")
		(net "M_M_CKE<3>")
	)
	(segment
		(start 86.576662 -97.490788)
		(end 86.583012 -97.48012)
		(width 0.0889)
		(layer "In2.Cu")
		(net "M_M_CKE<3>")
	)
	(segment
		(start 80.286098 -135.40867)
		(end 80.363568 -135.3312)
		(width 0.14224)
		(layer "In2.Cu")
		(net "M_M_CKE<3>")
	)
	(segment
		(start 86.571836 -92.546424)
		(end 86.593934 -92.50807)
		(width 0.0889)
		(layer "In2.Cu")
		(net "M_M_CKE<3>")
	)
	(segment
		(start 86.571836 -95.518224)
		(end 86.576662 -95.509588)
		(width 0.0889)
		(layer "In2.Cu")
		(net "M_M_CKE<3>")
	)
	(segment
		(start 86.576662 -98.481388)
		(end 86.583012 -98.47072)
		(width 0.0889)
		(layer "In2.Cu")
		(net "M_M_CKE<3>")
	)
	(segment
		(start 80.363568 -134.7978)
		(end 80.263746 -134.697978)
		(width 0.14224)
		(layer "In2.Cu")
		(net "M_M_CKE<3>")
	)
	(segment
		(start 86.571836 -97.499424)
		(end 86.576662 -97.490788)
		(width 0.0889)
		(layer "In2.Cu")
		(net "M_M_CKE<3>")
	)
	(segment
		(start 80.263746 -134.697978)
		(end 80.263746 -131.951222)
		(width 0.14224)
		(layer "In2.Cu")
		(net "M_M_CKE<3>")
	)
	(segment
		(start 86.593934 -92.50807)
		(end 86.923372 -91.747086)
		(width 0.0889)
		(layer "In2.Cu")
		(net "M_M_CKE<3>")
	)
	(segment
		(start 80.236568 -129.8448)
		(end 80.236568 -127.4572)
		(width 0.14224)
		(layer "In2.Cu")
		(net "M_M_CKE<3>")
	)
	(segment
		(start 86.49843 -99.224338)
		(end 86.49843 -98.754438)
		(width 0.0889)
		(layer "In2.Cu")
		(net "M_M_CKE<3>")
	)
	(segment
		(start 86.571836 -94.527624)
		(end 86.576662 -94.518988)
		(width 0.0889)
		(layer "In2.Cu")
		(net "M_M_CKE<3>")
	)
	(segment
		(start 86.576662 -96.500188)
		(end 86.583012 -96.48952)
		(width 0.0889)
		(layer "In2.Cu")
		(net "M_M_CKE<3>")
	)
	(segment
		(start 86.576662 -95.509588)
		(end 86.583012 -95.49892)
		(width 0.0889)
		(layer "In2.Cu")
		(net "M_M_CKE<3>")
	)
	(segment
		(start 86.307168 -121.3866)
		(end 86.307168 -101.500178)
		(width 0.14224)
		(layer "In2.Cu")
		(net "M_M_CKE<3>")
	)
	(segment
		(start 86.434168 -99.2886)
		(end 86.49843 -99.224338)
		(width 0.0889)
		(layer "In2.Cu")
		(net "M_M_CKE<3>")
	)
	(segment
		(start 80.312768 -130.5052)
		(end 80.312768 -129.921)
		(width 0.14224)
		(layer "In2.Cu")
		(net "M_M_CKE<3>")
	)
	(arc
		(start 86.576662 -94.518988)
		(mid 86.655884 -94.22987)
		(end 86.583012 -93.939106)
		(width 0.0889)
		(layer "In2.Cu")
		(net "M_M_CKE<3>")
	)
	(arc
		(start 86.583012 -96.48952)
		(mid 86.65581 -96.198757)
		(end 86.576662 -95.909638)
		(width 0.0889)
		(layer "In2.Cu")
		(net "M_M_CKE<3>")
	)
	(arc
		(start 86.576662 -92.937838)
		(mid 86.523192 -92.742775)
		(end 86.571836 -92.546424)
		(width 0.0889)
		(layer "In2.Cu")
		(net "M_M_CKE<3>")
	)
	(arc
		(start 86.583012 -98.47072)
		(mid 86.65581 -98.179957)
		(end 86.576662 -97.890838)
		(width 0.0889)
		(layer "In2.Cu")
		(net "M_M_CKE<3>")
	)
	(arc
		(start 86.576662 -93.528642)
		(mid 86.655793 -93.23324)
		(end 86.576662 -92.937838)
		(width 0.0889)
		(layer "In2.Cu")
		(net "M_M_CKE<3>")
	)
	(arc
		(start 86.576662 -96.900238)
		(mid 86.523192 -96.705175)
		(end 86.571836 -96.508824)
		(width 0.0889)
		(layer "In2.Cu")
		(net "M_M_CKE<3>")
	)
	(arc
		(start 86.576662 -97.890838)
		(mid 86.523192 -97.695775)
		(end 86.571836 -97.499424)
		(width 0.0889)
		(layer "In2.Cu")
		(net "M_M_CKE<3>")
	)
	(arc
		(start 86.583012 -95.49892)
		(mid 86.65581 -95.208157)
		(end 86.576662 -94.919038)
		(width 0.0889)
		(layer "In2.Cu")
		(net "M_M_CKE<3>")
	)
	(arc
		(start 86.576662 -95.909638)
		(mid 86.523192 -95.714575)
		(end 86.571836 -95.518224)
		(width 0.0889)
		(layer "In2.Cu")
		(net "M_M_CKE<3>")
	)
	(arc
		(start 86.576662 -94.919038)
		(mid 86.523192 -94.723975)
		(end 86.571836 -94.527624)
		(width 0.0889)
		(layer "In2.Cu")
		(net "M_M_CKE<3>")
	)
	(arc
		(start 86.49843 -98.754438)
		(mid 86.519863 -98.612847)
		(end 86.576662 -98.481388)
		(width 0.0889)
		(layer "In2.Cu")
		(net "M_M_CKE<3>")
	)
	(arc
		(start 86.576662 -93.928438)
		(mid 86.523163 -93.72854)
		(end 86.576662 -93.528642)
		(width 0.0889)
		(layer "In2.Cu")
		(net "M_M_CKE<3>")
	)
	(arc
		(start 86.583012 -97.48012)
		(mid 86.65581 -97.189357)
		(end 86.576662 -96.900238)
		(width 0.0889)
		(layer "In2.Cu")
		(net "M_M_CKE<3>")
	)
	(segment
		(start 87.494872 -93.72854)
		(end 86.923372 -93.72854)
		(width 0.1016)
		(layer "F.Cu")
		(net "M_M_CKE<2>")
	)
	(via
		(at 79.849472 -150.788878)
		(size 0.4572)
		(drill 0.2032)
		(layers "F.Cu" "B.Cu")
		(net "M_M_CKE<2>")
	)
	(via
		(at 86.923372 -93.72854)
		(size 0.508)
		(drill 0.254)
		(layers "F.Cu" "B.Cu")
		(net "M_M_CKE<2>")
	)
	(segment
		(start 79.849472 -152.078436)
		(end 79.849472 -150.788878)
		(width 0.1651)
		(layer "B.Cu")
		(net "M_M_CKE<2>")
	)
	(segment
		(start 87.263732 -98.47072)
		(end 87.270082 -98.481388)
		(width 0.0889)
		(layer "In2.Cu")
		(net "M_M_CKE<2>")
	)
	(segment
		(start 81.133442 -144.314926)
		(end 81.074768 -144.3736)
		(width 0.14224)
		(layer "In2.Cu")
		(net "M_M_CKE<2>")
	)
	(segment
		(start 81.201768 -130.6576)
		(end 81.201768 -131.1402)
		(width 0.14224)
		(layer "In2.Cu")
		(net "M_M_CKE<2>")
	)
	(segment
		(start 81.074768 -130.0226)
		(end 81.074768 -130.5306)
		(width 0.14224)
		(layer "In2.Cu")
		(net "M_M_CKE<2>")
	)
	(segment
		(start 81.176368 -129.921)
		(end 81.074768 -130.0226)
		(width 0.14224)
		(layer "In2.Cu")
		(net "M_M_CKE<2>")
	)
	(segment
		(start 87.263732 -95.49892)
		(end 87.270082 -95.509588)
		(width 0.0889)
		(layer "In2.Cu")
		(net "M_M_CKE<2>")
	)
	(segment
		(start 86.815168 -101.571806)
		(end 86.815168 -121.6152)
		(width 0.14224)
		(layer "In2.Cu")
		(net "M_M_CKE<2>")
	)
	(segment
		(start 79.849472 -150.314406)
		(end 79.849472 -150.788878)
		(width 0.14224)
		(layer "In2.Cu")
		(net "M_M_CKE<2>")
	)
	(segment
		(start 81.201768 -131.1402)
		(end 81.049368 -131.2926)
		(width 0.14224)
		(layer "In2.Cu")
		(net "M_M_CKE<2>")
	)
	(segment
		(start 81.133188 -132.03682)
		(end 81.133188 -134.76478)
		(width 0.14224)
		(layer "In2.Cu")
		(net "M_M_CKE<2>")
	)
	(segment
		(start 87.270082 -97.490788)
		(end 87.274908 -97.499424)
		(width 0.0889)
		(layer "In2.Cu")
		(net "M_M_CKE<2>")
	)
	(segment
		(start 81.107026 -134.790942)
		(end 81.107026 -139.515342)
		(width 0.14224)
		(layer "In2.Cu")
		(net "M_M_CKE<2>")
	)
	(segment
		(start 87.270082 -95.509588)
		(end 87.274908 -95.518224)
		(width 0.0889)
		(layer "In2.Cu")
		(net "M_M_CKE<2>")
	)
	(segment
		(start 86.815168 -121.6152)
		(end 81.176368 -127.254)
		(width 0.14224)
		(layer "In2.Cu")
		(net "M_M_CKE<2>")
	)
	(segment
		(start 81.176368 -127.254)
		(end 81.176368 -129.921)
		(width 0.14224)
		(layer "In2.Cu")
		(net "M_M_CKE<2>")
	)
	(segment
		(start 81.074768 -130.5306)
		(end 81.201768 -130.6576)
		(width 0.14224)
		(layer "In2.Cu")
		(net "M_M_CKE<2>")
	)
	(segment
		(start 81.049368 -131.953)
		(end 81.133188 -132.03682)
		(width 0.14224)
		(layer "In2.Cu")
		(net "M_M_CKE<2>")
	)
	(segment
		(start 81.049368 -140.666216)
		(end 81.133442 -140.75029)
		(width 0.14224)
		(layer "In2.Cu")
		(net "M_M_CKE<2>")
	)
	(segment
		(start 81.049368 -131.2926)
		(end 81.049368 -131.953)
		(width 0.14224)
		(layer "In2.Cu")
		(net "M_M_CKE<2>")
	)
	(segment
		(start 87.297768 -100.838)
		(end 86.815168 -101.3206)
		(width 0.0889)
		(layer "In2.Cu")
		(net "M_M_CKE<2>")
	)
	(segment
		(start 79.412846 -149.87778)
		(end 79.849472 -150.314406)
		(width 0.14224)
		(layer "In2.Cu")
		(net "M_M_CKE<2>")
	)
	(segment
		(start 81.074768 -145.6944)
		(end 81.107026 -145.726658)
		(width 0.14224)
		(layer "In2.Cu")
		(net "M_M_CKE<2>")
	)
	(segment
		(start 81.107026 -146.576542)
		(end 79.412846 -148.270722)
		(width 0.14224)
		(layer "In2.Cu")
		(net "M_M_CKE<2>")
	)
	(segment
		(start 87.270082 -98.481388)
		(end 87.274908 -98.490024)
		(width 0.0889)
		(layer "In2.Cu")
		(net "M_M_CKE<2>")
	)
	(segment
		(start 81.107026 -139.515342)
		(end 81.049368 -139.573)
		(width 0.14224)
		(layer "In2.Cu")
		(net "M_M_CKE<2>")
	)
	(segment
		(start 81.133442 -140.75029)
		(end 81.133442 -144.314926)
		(width 0.14224)
		(layer "In2.Cu")
		(net "M_M_CKE<2>")
	)
	(segment
		(start 87.270082 -96.500188)
		(end 87.274908 -96.508824)
		(width 0.0889)
		(layer "In2.Cu")
		(net "M_M_CKE<2>")
	)
	(segment
		(start 81.074768 -144.3736)
		(end 81.074768 -145.6944)
		(width 0.14224)
		(layer "In2.Cu")
		(net "M_M_CKE<2>")
	)
	(segment
		(start 79.412846 -148.270722)
		(end 79.412846 -149.87778)
		(width 0.14224)
		(layer "In2.Cu")
		(net "M_M_CKE<2>")
	)
	(segment
		(start 81.049368 -139.573)
		(end 81.049368 -140.666216)
		(width 0.14224)
		(layer "In2.Cu")
		(net "M_M_CKE<2>")
	)
	(segment
		(start 81.133188 -134.76478)
		(end 81.107026 -134.790942)
		(width 0.14224)
		(layer "In2.Cu")
		(net "M_M_CKE<2>")
	)
	(segment
		(start 81.107026 -145.726658)
		(end 81.107026 -146.576542)
		(width 0.14224)
		(layer "In2.Cu")
		(net "M_M_CKE<2>")
	)
	(segment
		(start 87.297768 -99.5934)
		(end 87.297768 -100.838)
		(width 0.0889)
		(layer "In2.Cu")
		(net "M_M_CKE<2>")
	)
	(segment
		(start 86.815168 -101.3206)
		(end 86.815168 -101.571806)
		(width 0.0889)
		(layer "In2.Cu")
		(net "M_M_CKE<2>")
	)
	(segment
		(start 87.263732 -97.48012)
		(end 87.270082 -97.490788)
		(width 0.0889)
		(layer "In2.Cu")
		(net "M_M_CKE<2>")
	)
	(segment
		(start 87.263732 -96.48952)
		(end 87.270082 -96.500188)
		(width 0.0889)
		(layer "In2.Cu")
		(net "M_M_CKE<2>")
	)
	(segment
		(start 87.242142 -99.417886)
		(end 87.242142 -99.459034)
		(width 0.0889)
		(layer "In2.Cu")
		(net "M_M_CKE<2>")
	)
	(segment
		(start 87.270082 -94.518988)
		(end 87.274908 -94.527624)
		(width 0.0889)
		(layer "In2.Cu")
		(net "M_M_CKE<2>")
	)
	(arc
		(start 87.270082 -98.881438)
		(mid 87.191626 -99.146309)
		(end 87.242142 -99.417886)
		(width 0.0889)
		(layer "In2.Cu")
		(net "M_M_CKE<2>")
	)
	(arc
		(start 87.274908 -97.499424)
		(mid 87.323663 -97.695776)
		(end 87.270082 -97.890838)
		(width 0.0889)
		(layer "In2.Cu")
		(net "M_M_CKE<2>")
	)
	(arc
		(start 87.274908 -96.508824)
		(mid 87.323663 -96.705176)
		(end 87.270082 -96.900238)
		(width 0.0889)
		(layer "In2.Cu")
		(net "M_M_CKE<2>")
	)
	(arc
		(start 87.242142 -99.459034)
		(mid 87.256604 -99.531741)
		(end 87.297768 -99.5934)
		(width 0.0889)
		(layer "In2.Cu")
		(net "M_M_CKE<2>")
	)
	(arc
		(start 87.270082 -97.890838)
		(mid 87.19086 -98.179956)
		(end 87.263732 -98.47072)
		(width 0.0889)
		(layer "In2.Cu")
		(net "M_M_CKE<2>")
	)
	(arc
		(start 87.274908 -95.518224)
		(mid 87.323663 -95.714576)
		(end 87.270082 -95.909638)
		(width 0.0889)
		(layer "In2.Cu")
		(net "M_M_CKE<2>")
	)
	(arc
		(start 87.270082 -96.900238)
		(mid 87.19086 -97.189356)
		(end 87.263732 -97.48012)
		(width 0.0889)
		(layer "In2.Cu")
		(net "M_M_CKE<2>")
	)
	(arc
		(start 87.274908 -98.490024)
		(mid 87.323663 -98.686376)
		(end 87.270082 -98.881438)
		(width 0.0889)
		(layer "In2.Cu")
		(net "M_M_CKE<2>")
	)
	(arc
		(start 86.923372 -93.72854)
		(mid 86.935388 -93.968631)
		(end 87.043768 -94.1832)
		(width 0.0889)
		(layer "In2.Cu")
		(net "M_M_CKE<2>")
	)
	(arc
		(start 87.270082 -95.909638)
		(mid 87.19086 -96.198756)
		(end 87.263732 -96.48952)
		(width 0.0889)
		(layer "In2.Cu")
		(net "M_M_CKE<2>")
	)
	(arc
		(start 87.274908 -94.527624)
		(mid 87.323663 -94.723976)
		(end 87.270082 -94.919038)
		(width 0.0889)
		(layer "In2.Cu")
		(net "M_M_CKE<2>")
	)
	(arc
		(start 87.043768 -94.1832)
		(mid 87.163943 -94.346364)
		(end 87.270082 -94.518988)
		(width 0.0889)
		(layer "In2.Cu")
		(net "M_M_CKE<2>")
	)
	(arc
		(start 87.270082 -94.919038)
		(mid 87.19086 -95.208156)
		(end 87.263732 -95.49892)
		(width 0.0889)
		(layer "In2.Cu")
		(net "M_M_CKE<2>")
	)
	(segment
		(start 78.999334 -154.905456)
		(end 78.999334 -156.87294)
		(width 0.1651)
		(layer "F.Cu")
		(net "M_M_CKE<1>")
	)
	(segment
		(start 87.494872 -90.756486)
		(end 86.923372 -90.756486)
		(width 0.1016)
		(layer "F.Cu")
		(net "M_M_CKE<1>")
	)
	(via
		(at 86.923372 -90.756486)
		(size 0.508)
		(drill 0.254)
		(layers "F.Cu" "B.Cu")
		(net "M_M_CKE<1>")
	)
	(via
		(at 78.999334 -154.905456)
		(size 0.508)
		(drill 0.254)
		(layers "F.Cu" "B.Cu")
		(net "M_M_CKE<1>")
	)
	(segment
		(start 78.999334 -154.286966)
		(end 78.999334 -154.905456)
		(width 0.14224)
		(layer "In2.Cu")
		(net "M_M_CKE<1>")
	)
	(segment
		(start 78.737968 -150.213568)
		(end 78.55839 -150.393146)
		(width 0.14224)
		(layer "In2.Cu")
		(net "M_M_CKE<1>")
	)
	(segment
		(start 86.416388 -95.405702)
		(end 86.411562 -95.414338)
		(width 0.0889)
		(layer "In2.Cu")
		(net "M_M_CKE<1>")
	)
	(segment
		(start 86.346284 -91.680284)
		(end 86.346284 -91.87434)
		(width 0.0889)
		(layer "In2.Cu")
		(net "M_M_CKE<1>")
	)
	(segment
		(start 78.458568 -151.6888)
		(end 78.458568 -153.7462)
		(width 0.14224)
		(layer "In2.Cu")
		(net "M_M_CKE<1>")
	)
	(segment
		(start 79.525368 -131.1656)
		(end 79.347568 -131.3434)
		(width 0.14224)
		(layer "In2.Cu")
		(net "M_M_CKE<1>")
	)
	(segment
		(start 78.588108 -149.04974)
		(end 78.737968 -149.1996)
		(width 0.14224)
		(layer "In2.Cu")
		(net "M_M_CKE<1>")
	)
	(segment
		(start 79.412846 -140.222478)
		(end 79.435452 -140.245084)
		(width 0.14224)
		(layer "In2.Cu")
		(net "M_M_CKE<1>")
	)
	(segment
		(start 86.281768 -98.541078)
		(end 86.281768 -99.1616)
		(width 0.0889)
		(layer "In2.Cu")
		(net "M_M_CKE<1>")
	)
	(segment
		(start 86.230968 -100.8634)
		(end 85.799168 -101.2952)
		(width 0.0889)
		(layer "In2.Cu")
		(net "M_M_CKE<1>")
	)
	(segment
		(start 79.322168 -130.048)
		(end 79.322168 -130.429)
		(width 0.14224)
		(layer "In2.Cu")
		(net "M_M_CKE<1>")
	)
	(segment
		(start 86.327234 -98.495612)
		(end 86.281768 -98.541078)
		(width 0.0889)
		(layer "In2.Cu")
		(net "M_M_CKE<1>")
	)
	(segment
		(start 79.439008 -135.39724)
		(end 79.525368 -135.4836)
		(width 0.14224)
		(layer "In2.Cu")
		(net "M_M_CKE<1>")
	)
	(segment
		(start 86.416388 -98.377502)
		(end 86.411562 -98.386138)
		(width 0.0889)
		(layer "In2.Cu")
		(net "M_M_CKE<1>")
	)
	(segment
		(start 79.474568 -127.4318)
		(end 79.474568 -129.8956)
		(width 0.14224)
		(layer "In2.Cu")
		(net "M_M_CKE<1>")
	)
	(segment
		(start 85.799168 -121.1072)
		(end 79.474568 -127.4318)
		(width 0.14224)
		(layer "In2.Cu")
		(net "M_M_CKE<1>")
	)
	(segment
		(start 79.412846 -135.977122)
		(end 79.412846 -140.222478)
		(width 0.14224)
		(layer "In2.Cu")
		(net "M_M_CKE<1>")
	)
	(segment
		(start 86.923372 -91.103196)
		(end 86.346284 -91.680284)
		(width 0.0889)
		(layer "In2.Cu")
		(net "M_M_CKE<1>")
	)
	(segment
		(start 79.439008 -132.04444)
		(end 79.439008 -135.39724)
		(width 0.14224)
		(layer "In2.Cu")
		(net "M_M_CKE<1>")
	)
	(segment
		(start 86.411562 -96.404938)
		(end 86.405212 -96.415606)
		(width 0.0889)
		(layer "In2.Cu")
		(net "M_M_CKE<1>")
	)
	(segment
		(start 78.55839 -151.588978)
		(end 78.458568 -151.6888)
		(width 0.14224)
		(layer "In2.Cu")
		(net "M_M_CKE<1>")
	)
	(segment
		(start 79.322168 -130.429)
		(end 79.525368 -130.6322)
		(width 0.14224)
		(layer "In2.Cu")
		(net "M_M_CKE<1>")
	)
	(segment
		(start 86.416388 -92.433902)
		(end 86.411562 -92.442538)
		(width 0.0889)
		(layer "In2.Cu")
		(net "M_M_CKE<1>")
	)
	(segment
		(start 79.525368 -135.4836)
		(end 79.525368 -135.8646)
		(width 0.14224)
		(layer "In2.Cu")
		(net "M_M_CKE<1>")
	)
	(segment
		(start 78.458568 -153.7462)
		(end 78.999334 -154.286966)
		(width 0.14224)
		(layer "In2.Cu")
		(net "M_M_CKE<1>")
	)
	(segment
		(start 86.230968 -99.2124)
		(end 86.230968 -100.8634)
		(width 0.0889)
		(layer "In2.Cu")
		(net "M_M_CKE<1>")
	)
	(segment
		(start 85.799168 -101.520498)
		(end 85.799168 -121.1072)
		(width 0.14224)
		(layer "In2.Cu")
		(net "M_M_CKE<1>")
	)
	(segment
		(start 79.347568 -131.953)
		(end 79.439008 -132.04444)
		(width 0.14224)
		(layer "In2.Cu")
		(net "M_M_CKE<1>")
	)
	(segment
		(start 79.409036 -144.362932)
		(end 79.409036 -146.598132)
		(width 0.14224)
		(layer "In2.Cu")
		(net "M_M_CKE<1>")
	)
	(segment
		(start 79.347568 -131.3434)
		(end 79.347568 -131.953)
		(width 0.14224)
		(layer "In2.Cu")
		(net "M_M_CKE<1>")
	)
	(segment
		(start 86.416388 -96.396302)
		(end 86.411562 -96.404938)
		(width 0.0889)
		(layer "In2.Cu")
		(net "M_M_CKE<1>")
	)
	(segment
		(start 79.525368 -135.8646)
		(end 79.412846 -135.977122)
		(width 0.14224)
		(layer "In2.Cu")
		(net "M_M_CKE<1>")
	)
	(segment
		(start 78.737968 -149.1996)
		(end 78.737968 -150.213568)
		(width 0.14224)
		(layer "In2.Cu")
		(net "M_M_CKE<1>")
	)
	(segment
		(start 79.435452 -140.245084)
		(end 79.435452 -144.336516)
		(width 0.14224)
		(layer "In2.Cu")
		(net "M_M_CKE<1>")
	)
	(segment
		(start 85.799168 -101.2952)
		(end 85.799168 -101.520498)
		(width 0.0889)
		(layer "In2.Cu")
		(net "M_M_CKE<1>")
	)
	(segment
		(start 86.411562 -92.442538)
		(end 86.405212 -92.453206)
		(width 0.0889)
		(layer "In2.Cu")
		(net "M_M_CKE<1>")
	)
	(segment
		(start 86.281768 -99.1616)
		(end 86.230968 -99.2124)
		(width 0.0889)
		(layer "In2.Cu")
		(net "M_M_CKE<1>")
	)
	(segment
		(start 78.55839 -150.393146)
		(end 78.55839 -151.588978)
		(width 0.14224)
		(layer "In2.Cu")
		(net "M_M_CKE<1>")
	)
	(segment
		(start 86.923372 -90.756486)
		(end 86.923372 -91.103196)
		(width 0.0889)
		(layer "In2.Cu")
		(net "M_M_CKE<1>")
	)
	(segment
		(start 86.411562 -95.414338)
		(end 86.405212 -95.425006)
		(width 0.0889)
		(layer "In2.Cu")
		(net "M_M_CKE<1>")
	)
	(segment
		(start 79.525368 -130.6322)
		(end 79.525368 -131.1656)
		(width 0.14224)
		(layer "In2.Cu")
		(net "M_M_CKE<1>")
	)
	(segment
		(start 86.411562 -97.395538)
		(end 86.405212 -97.406206)
		(width 0.0889)
		(layer "In2.Cu")
		(net "M_M_CKE<1>")
	)
	(segment
		(start 78.588108 -147.41906)
		(end 78.588108 -149.04974)
		(width 0.14224)
		(layer "In2.Cu")
		(net "M_M_CKE<1>")
	)
	(segment
		(start 86.405212 -94.01302)
		(end 86.411562 -94.023688)
		(width 0.0889)
		(layer "In2.Cu")
		(net "M_M_CKE<1>")
	)
	(segment
		(start 79.409036 -146.598132)
		(end 78.588108 -147.41906)
		(width 0.14224)
		(layer "In2.Cu")
		(net "M_M_CKE<1>")
	)
	(segment
		(start 86.416388 -97.386902)
		(end 86.411562 -97.395538)
		(width 0.0889)
		(layer "In2.Cu")
		(net "M_M_CKE<1>")
	)
	(segment
		(start 86.416388 -93.424502)
		(end 86.411562 -93.433138)
		(width 0.0889)
		(layer "In2.Cu")
		(net "M_M_CKE<1>")
	)
	(segment
		(start 79.474568 -129.8956)
		(end 79.322168 -130.048)
		(width 0.14224)
		(layer "In2.Cu")
		(net "M_M_CKE<1>")
	)
	(segment
		(start 79.435452 -144.336516)
		(end 79.409036 -144.362932)
		(width 0.14224)
		(layer "In2.Cu")
		(net "M_M_CKE<1>")
	)
	(arc
		(start 86.411562 -93.033088)
		(mid 86.465032 -93.228151)
		(end 86.416388 -93.424502)
		(width 0.0889)
		(layer "In2.Cu")
		(net "M_M_CKE<1>")
	)
	(arc
		(start 86.411562 -94.023688)
		(mid 86.465061 -94.223586)
		(end 86.411562 -94.423484)
		(width 0.0889)
		(layer "In2.Cu")
		(net "M_M_CKE<1>")
	)
	(arc
		(start 86.411562 -94.423484)
		(mid 86.332431 -94.718886)
		(end 86.411562 -95.014288)
		(width 0.0889)
		(layer "In2.Cu")
		(net "M_M_CKE<1>")
	)
	(arc
		(start 86.411562 -92.042488)
		(mid 86.465032 -92.237551)
		(end 86.416388 -92.433902)
		(width 0.0889)
		(layer "In2.Cu")
		(net "M_M_CKE<1>")
	)
	(arc
		(start 86.405212 -96.415606)
		(mid 86.332414 -96.706369)
		(end 86.411562 -96.995488)
		(width 0.0889)
		(layer "In2.Cu")
		(net "M_M_CKE<1>")
	)
	(arc
		(start 86.411562 -98.386138)
		(mid 86.37341 -98.443966)
		(end 86.327234 -98.495612)
		(width 0.0889)
		(layer "In2.Cu")
		(net "M_M_CKE<1>")
	)
	(arc
		(start 86.411562 -93.433138)
		(mid 86.33234 -93.722256)
		(end 86.405212 -94.01302)
		(width 0.0889)
		(layer "In2.Cu")
		(net "M_M_CKE<1>")
	)
	(arc
		(start 86.405212 -92.453206)
		(mid 86.332414 -92.743969)
		(end 86.411562 -93.033088)
		(width 0.0889)
		(layer "In2.Cu")
		(net "M_M_CKE<1>")
	)
	(arc
		(start 86.346284 -91.87434)
		(mid 86.372465 -91.960922)
		(end 86.411562 -92.042488)
		(width 0.0889)
		(layer "In2.Cu")
		(net "M_M_CKE<1>")
	)
	(arc
		(start 86.411562 -96.995488)
		(mid 86.465032 -97.190551)
		(end 86.416388 -97.386902)
		(width 0.0889)
		(layer "In2.Cu")
		(net "M_M_CKE<1>")
	)
	(arc
		(start 86.411562 -97.986088)
		(mid 86.465032 -98.181151)
		(end 86.416388 -98.377502)
		(width 0.0889)
		(layer "In2.Cu")
		(net "M_M_CKE<1>")
	)
	(arc
		(start 86.411562 -95.014288)
		(mid 86.465032 -95.209351)
		(end 86.416388 -95.405702)
		(width 0.0889)
		(layer "In2.Cu")
		(net "M_M_CKE<1>")
	)
	(arc
		(start 86.405212 -97.406206)
		(mid 86.332414 -97.696969)
		(end 86.411562 -97.986088)
		(width 0.0889)
		(layer "In2.Cu")
		(net "M_M_CKE<1>")
	)
	(arc
		(start 86.411562 -96.004888)
		(mid 86.465032 -96.199951)
		(end 86.416388 -96.396302)
		(width 0.0889)
		(layer "In2.Cu")
		(net "M_M_CKE<1>")
	)
	(arc
		(start 86.405212 -95.425006)
		(mid 86.332414 -95.715769)
		(end 86.411562 -96.004888)
		(width 0.0889)
		(layer "In2.Cu")
		(net "M_M_CKE<1>")
	)
	(segment
		(start 79.849472 -152.273)
		(end 79.849472 -154.252168)
		(width 0.1651)
		(layer "F.Cu")
		(net "M_M_CKE<0>")
	)
	(segment
		(start 88.353392 -92.24264)
		(end 87.781892 -92.24264)
		(width 0.1016)
		(layer "F.Cu")
		(net "M_M_CKE<0>")
	)
	(via
		(at 79.849472 -154.252168)
		(size 0.508)
		(drill 0.254)
		(layers "F.Cu" "B.Cu")
		(net "M_M_CKE<0>")
	)
	(via
		(at 87.781892 -92.24264)
		(size 0.508)
		(drill 0.254)
		(layers "F.Cu" "B.Cu")
		(net "M_M_CKE<0>")
	)
	(segment
		(start 81.999074 -139.557506)
		(end 81.999074 -140.653262)
		(width 0.14224)
		(layer "In2.Cu")
		(net "M_M_CKE<0>")
	)
	(segment
		(start 81.976722 -134.709154)
		(end 82.114644 -134.847076)
		(width 0.14224)
		(layer "In2.Cu")
		(net "M_M_CKE<0>")
	)
	(segment
		(start 87.348568 -92.675964)
		(end 87.348568 -93.346524)
		(width 0.0889)
		(layer "In2.Cu")
		(net "M_M_CKE<0>")
	)
	(segment
		(start 87.348568 -93.346524)
		(end 87.435182 -93.433138)
		(width 0.0889)
		(layer "In2.Cu")
		(net "M_M_CKE<0>")
	)
	(segment
		(start 87.435182 -97.395538)
		(end 87.441532 -97.406206)
		(width 0.0889)
		(layer "In2.Cu")
		(net "M_M_CKE<0>")
	)
	(segment
		(start 87.435182 -98.386138)
		(end 87.441532 -98.396806)
		(width 0.0889)
		(layer "In2.Cu")
		(net "M_M_CKE<0>")
	)
	(segment
		(start 81.976722 -133.718046)
		(end 81.976722 -134.709154)
		(width 0.14224)
		(layer "In2.Cu")
		(net "M_M_CKE<0>")
	)
	(segment
		(start 83.589368 -127.6604)
		(end 81.912968 -129.3368)
		(width 0.14224)
		(layer "In2.Cu")
		(net "M_M_CKE<0>")
	)
	(segment
		(start 82.065368 -131.318)
		(end 82.065368 -133.6294)
		(width 0.14224)
		(layer "In2.Cu")
		(net "M_M_CKE<0>")
	)
	(segment
		(start 81.987898 -139.54633)
		(end 81.999074 -139.557506)
		(width 0.14224)
		(layer "In2.Cu")
		(net "M_M_CKE<0>")
	)
	(segment
		(start 87.781892 -92.24264)
		(end 87.348568 -92.675964)
		(width 0.0889)
		(layer "In2.Cu")
		(net "M_M_CKE<0>")
	)
	(segment
		(start 87.430356 -98.377502)
		(end 87.435182 -98.386138)
		(width 0.0889)
		(layer "In2.Cu")
		(net "M_M_CKE<0>")
	)
	(segment
		(start 81.991708 -138.52906)
		(end 81.987898 -138.53287)
		(width 0.14224)
		(layer "In2.Cu")
		(net "M_M_CKE<0>")
	)
	(segment
		(start 79.849472 -152.299924)
		(end 79.849472 -154.252168)
		(width 0.14224)
		(layer "In2.Cu")
		(net "M_M_CKE<0>")
	)
	(segment
		(start 87.435182 -95.414338)
		(end 87.441532 -95.425006)
		(width 0.0889)
		(layer "In2.Cu")
		(net "M_M_CKE<0>")
	)
	(segment
		(start 81.987898 -144.32153)
		(end 82.065368 -144.399)
		(width 0.14224)
		(layer "In2.Cu")
		(net "M_M_CKE<0>")
	)
	(segment
		(start 80.263746 -149.832822)
		(end 80.263746 -151.88565)
		(width 0.14224)
		(layer "In2.Cu")
		(net "M_M_CKE<0>")
	)
	(segment
		(start 82.039968 -130.5052)
		(end 81.912968 -130.6322)
		(width 0.14224)
		(layer "In2.Cu")
		(net "M_M_CKE<0>")
	)
	(segment
		(start 81.987898 -146.45767)
		(end 80.286098 -148.15947)
		(width 0.14224)
		(layer "In2.Cu")
		(net "M_M_CKE<0>")
	)
	(segment
		(start 87.323168 -101.510338)
		(end 87.323168 -121.825766)
		(width 0.14224)
		(layer "In2.Cu")
		(net "M_M_CKE<0>")
	)
	(segment
		(start 82.065368 -144.399)
		(end 82.065368 -145.233136)
		(width 0.14224)
		(layer "In2.Cu")
		(net "M_M_CKE<0>")
	)
	(segment
		(start 81.912968 -131.1656)
		(end 82.065368 -131.318)
		(width 0.14224)
		(layer "In2.Cu")
		(net "M_M_CKE<0>")
	)
	(segment
		(start 87.323168 -121.825766)
		(end 83.589368 -125.559566)
		(width 0.14224)
		(layer "In2.Cu")
		(net "M_M_CKE<0>")
	)
	(segment
		(start 81.991708 -135.719566)
		(end 81.991708 -138.52906)
		(width 0.14224)
		(layer "In2.Cu")
		(net "M_M_CKE<0>")
	)
	(segment
		(start 81.912968 -129.3368)
		(end 81.912968 -129.794)
		(width 0.14224)
		(layer "In2.Cu")
		(net "M_M_CKE<0>")
	)
	(segment
		(start 82.065368 -133.6294)
		(end 81.976722 -133.718046)
		(width 0.14224)
		(layer "In2.Cu")
		(net "M_M_CKE<0>")
	)
	(segment
		(start 87.441532 -94.01302)
		(end 87.435182 -94.023688)
		(width 0.0889)
		(layer "In2.Cu")
		(net "M_M_CKE<0>")
	)
	(segment
		(start 83.589368 -125.559566)
		(end 83.589368 -127.6604)
		(width 0.14224)
		(layer "In2.Cu")
		(net "M_M_CKE<0>")
	)
	(segment
		(start 87.430356 -99.368102)
		(end 87.526368 -99.537774)
		(width 0.0889)
		(layer "In2.Cu")
		(net "M_M_CKE<0>")
	)
	(segment
		(start 87.526368 -99.537774)
		(end 87.526368 -101.08184)
		(width 0.0889)
		(layer "In2.Cu")
		(net "M_M_CKE<0>")
	)
	(segment
		(start 81.987898 -138.53287)
		(end 81.987898 -139.54633)
		(width 0.14224)
		(layer "In2.Cu")
		(net "M_M_CKE<0>")
	)
	(segment
		(start 82.114644 -135.59663)
		(end 81.991708 -135.719566)
		(width 0.14224)
		(layer "In2.Cu")
		(net "M_M_CKE<0>")
	)
	(segment
		(start 87.430356 -96.396302)
		(end 87.435182 -96.404938)
		(width 0.0889)
		(layer "In2.Cu")
		(net "M_M_CKE<0>")
	)
	(segment
		(start 81.987898 -145.310606)
		(end 81.987898 -146.45767)
		(width 0.14224)
		(layer "In2.Cu")
		(net "M_M_CKE<0>")
	)
	(segment
		(start 87.430356 -97.386902)
		(end 87.435182 -97.395538)
		(width 0.0889)
		(layer "In2.Cu")
		(net "M_M_CKE<0>")
	)
	(segment
		(start 81.912968 -129.794)
		(end 82.039968 -129.921)
		(width 0.14224)
		(layer "In2.Cu")
		(net "M_M_CKE<0>")
	)
	(segment
		(start 81.965292 -143.463264)
		(end 81.987898 -143.48587)
		(width 0.14224)
		(layer "In2.Cu")
		(net "M_M_CKE<0>")
	)
	(segment
		(start 81.999074 -140.653262)
		(end 81.965292 -140.687044)
		(width 0.14224)
		(layer "In2.Cu")
		(net "M_M_CKE<0>")
	)
	(segment
		(start 87.323168 -101.28504)
		(end 87.323168 -101.510338)
		(width 0.0889)
		(layer "In2.Cu")
		(net "M_M_CKE<0>")
	)
	(segment
		(start 81.987898 -143.48587)
		(end 81.987898 -144.32153)
		(width 0.14224)
		(layer "In2.Cu")
		(net "M_M_CKE<0>")
	)
	(segment
		(start 82.039968 -129.921)
		(end 82.039968 -130.5052)
		(width 0.14224)
		(layer "In2.Cu")
		(net "M_M_CKE<0>")
	)
	(segment
		(start 80.263746 -151.88565)
		(end 79.849472 -152.299924)
		(width 0.14224)
		(layer "In2.Cu")
		(net "M_M_CKE<0>")
	)
	(segment
		(start 87.430356 -95.405702)
		(end 87.435182 -95.414338)
		(width 0.0889)
		(layer "In2.Cu")
		(net "M_M_CKE<0>")
	)
	(segment
		(start 87.526368 -101.08184)
		(end 87.323168 -101.28504)
		(width 0.0889)
		(layer "In2.Cu")
		(net "M_M_CKE<0>")
	)
	(segment
		(start 81.965292 -140.687044)
		(end 81.965292 -143.463264)
		(width 0.14224)
		(layer "In2.Cu")
		(net "M_M_CKE<0>")
	)
	(segment
		(start 87.435182 -96.404938)
		(end 87.441532 -96.415606)
		(width 0.0889)
		(layer "In2.Cu")
		(net "M_M_CKE<0>")
	)
	(segment
		(start 81.912968 -130.6322)
		(end 81.912968 -131.1656)
		(width 0.14224)
		(layer "In2.Cu")
		(net "M_M_CKE<0>")
	)
	(segment
		(start 80.286098 -149.81047)
		(end 80.263746 -149.832822)
		(width 0.14224)
		(layer "In2.Cu")
		(net "M_M_CKE<0>")
	)
	(segment
		(start 82.114644 -134.847076)
		(end 82.114644 -135.59663)
		(width 0.14224)
		(layer "In2.Cu")
		(net "M_M_CKE<0>")
	)
	(segment
		(start 82.065368 -145.233136)
		(end 81.987898 -145.310606)
		(width 0.14224)
		(layer "In2.Cu")
		(net "M_M_CKE<0>")
	)
	(segment
		(start 80.286098 -148.15947)
		(end 80.286098 -149.81047)
		(width 0.14224)
		(layer "In2.Cu")
		(net "M_M_CKE<0>")
	)
	(arc
		(start 87.441532 -96.415606)
		(mid 87.51433 -96.706369)
		(end 87.435182 -96.995488)
		(width 0.0889)
		(layer "In2.Cu")
		(net "M_M_CKE<0>")
	)
	(arc
		(start 87.441532 -97.406206)
		(mid 87.51433 -97.696969)
		(end 87.435182 -97.986088)
		(width 0.0889)
		(layer "In2.Cu")
		(net "M_M_CKE<0>")
	)
	(arc
		(start 87.435182 -96.004888)
		(mid 87.381712 -96.199951)
		(end 87.430356 -96.396302)
		(width 0.0889)
		(layer "In2.Cu")
		(net "M_M_CKE<0>")
	)
	(arc
		(start 87.435182 -96.995488)
		(mid 87.381712 -97.190551)
		(end 87.430356 -97.386902)
		(width 0.0889)
		(layer "In2.Cu")
		(net "M_M_CKE<0>")
	)
	(arc
		(start 87.435182 -98.976688)
		(mid 87.381712 -99.171751)
		(end 87.430356 -99.368102)
		(width 0.0889)
		(layer "In2.Cu")
		(net "M_M_CKE<0>")
	)
	(arc
		(start 87.441532 -95.425006)
		(mid 87.51433 -95.715769)
		(end 87.435182 -96.004888)
		(width 0.0889)
		(layer "In2.Cu")
		(net "M_M_CKE<0>")
	)
	(arc
		(start 87.435182 -94.023688)
		(mid 87.381683 -94.223586)
		(end 87.435182 -94.423484)
		(width 0.0889)
		(layer "In2.Cu")
		(net "M_M_CKE<0>")
	)
	(arc
		(start 87.435182 -93.433138)
		(mid 87.514404 -93.722256)
		(end 87.441532 -94.01302)
		(width 0.0889)
		(layer "In2.Cu")
		(net "M_M_CKE<0>")
	)
	(arc
		(start 87.441532 -98.396806)
		(mid 87.51433 -98.687569)
		(end 87.435182 -98.976688)
		(width 0.0889)
		(layer "In2.Cu")
		(net "M_M_CKE<0>")
	)
	(arc
		(start 87.435182 -95.014288)
		(mid 87.381712 -95.209351)
		(end 87.430356 -95.405702)
		(width 0.0889)
		(layer "In2.Cu")
		(net "M_M_CKE<0>")
	)
	(arc
		(start 87.435182 -97.986088)
		(mid 87.381712 -98.181151)
		(end 87.430356 -98.377502)
		(width 0.0889)
		(layer "In2.Cu")
		(net "M_M_CKE<0>")
	)
	(arc
		(start 87.435182 -94.423484)
		(mid 87.514313 -94.718886)
		(end 87.435182 -95.014288)
		(width 0.0889)
		(layer "In2.Cu")
		(net "M_M_CKE<0>")
	)
	(segment
		(start 102.947724 -91.747086)
		(end 102.376224 -91.747086)
		(width 0.1016)
		(layer "F.Cu")
		(net "M_M_C<2>")
	)
	(segment
		(start 111.299498 -156.87294)
		(end 111.299498 -154.905456)
		(width 0.1651)
		(layer "F.Cu")
		(net "M_M_C<2>")
	)
	(via
		(at 102.376224 -91.747086)
		(size 0.508)
		(drill 0.254)
		(layers "F.Cu" "B.Cu")
		(net "M_M_C<2>")
	)
	(via
		(at 111.299498 -154.905456)
		(size 0.508)
		(drill 0.254)
		(layers "F.Cu" "B.Cu")
		(net "M_M_C<2>")
	)
	(via
		(at 111.300006 -148.773388)
		(size 0.4572)
		(drill 0.2032)
		(layers "F.Cu" "B.Cu")
		(net "M_M_C<2>")
	)
	(segment
		(start 111.299498 -147.478496)
		(end 111.299498 -148.77288)
		(width 0.10795)
		(layer "B.Cu")
		(net "M_M_C<2>")
	)
	(segment
		(start 111.299498 -148.77288)
		(end 111.300006 -148.773388)
		(width 0.10795)
		(layer "B.Cu")
		(net "M_M_C<2>")
	)
	(segment
		(start 113.256568 -130.5052)
		(end 113.510568 -130.7592)
		(width 0.14224)
		(layer "In11.Cu")
		(net "M_M_C<2>")
	)
	(segment
		(start 113.510568 -136.8044)
		(end 113.510568 -139.319)
		(width 0.14224)
		(layer "In11.Cu")
		(net "M_M_C<2>")
	)
	(segment
		(start 105.814622 -101.473254)
		(end 105.814622 -101.997764)
		(width 0.0889)
		(layer "In11.Cu")
		(net "M_M_C<2>")
	)
	(segment
		(start 113.510568 -129.7432)
		(end 113.256568 -129.9972)
		(width 0.14224)
		(layer "In11.Cu")
		(net "M_M_C<2>")
	)
	(segment
		(start 104.404668 -100.7237)
		(end 105.065068 -100.7237)
		(width 0.0889)
		(layer "In11.Cu")
		(net "M_M_C<2>")
	)
	(segment
		(start 113.510568 -126.492)
		(end 113.510568 -129.7432)
		(width 0.14224)
		(layer "In11.Cu")
		(net "M_M_C<2>")
	)
	(segment
		(start 103.655368 -92.382086)
		(end 103.655368 -99.9744)
		(width 0.0889)
		(layer "In11.Cu")
		(net "M_M_C<2>")
	)
	(segment
		(start 111.299498 -149.32533)
		(end 111.299498 -148.773896)
		(width 0.14224)
		(layer "In11.Cu")
		(net "M_M_C<2>")
	)
	(segment
		(start 105.814622 -118.796054)
		(end 113.510568 -126.492)
		(width 0.14224)
		(layer "In11.Cu")
		(net "M_M_C<2>")
	)
	(segment
		(start 113.40719 -134.92607)
		(end 113.434368 -134.953248)
		(width 0.14224)
		(layer "In11.Cu")
		(net "M_M_C<2>")
	)
	(segment
		(start 113.510568 -131.4704)
		(end 113.40719 -131.573778)
		(width 0.14224)
		(layer "In11.Cu")
		(net "M_M_C<2>")
	)
	(segment
		(start 111.299498 -148.773896)
		(end 111.300006 -148.773388)
		(width 0.14224)
		(layer "In11.Cu")
		(net "M_M_C<2>")
	)
	(segment
		(start 113.535968 -141.5542)
		(end 113.535968 -144.0942)
		(width 0.14224)
		(layer "In11.Cu")
		(net "M_M_C<2>")
	)
	(segment
		(start 113.413286 -144.216882)
		(end 113.413286 -146.660108)
		(width 0.14224)
		(layer "In11.Cu")
		(net "M_M_C<2>")
	)
	(segment
		(start 111.935768 -153.6446)
		(end 111.935768 -151.257)
		(width 0.14224)
		(layer "In11.Cu")
		(net "M_M_C<2>")
	)
	(segment
		(start 113.535968 -144.0942)
		(end 113.413286 -144.216882)
		(width 0.14224)
		(layer "In11.Cu")
		(net "M_M_C<2>")
	)
	(segment
		(start 111.299498 -154.905456)
		(end 111.299498 -154.28087)
		(width 0.14224)
		(layer "In11.Cu")
		(net "M_M_C<2>")
	)
	(segment
		(start 113.413286 -146.660108)
		(end 111.300006 -148.773388)
		(width 0.14224)
		(layer "In11.Cu")
		(net "M_M_C<2>")
	)
	(segment
		(start 113.434368 -134.953248)
		(end 113.434368 -136.7282)
		(width 0.14224)
		(layer "In11.Cu")
		(net "M_M_C<2>")
	)
	(segment
		(start 113.40719 -131.573778)
		(end 113.40719 -134.92607)
		(width 0.14224)
		(layer "In11.Cu")
		(net "M_M_C<2>")
	)
	(segment
		(start 102.376224 -91.747086)
		(end 103.020368 -91.747086)
		(width 0.0889)
		(layer "In11.Cu")
		(net "M_M_C<2>")
	)
	(segment
		(start 111.935768 -151.257)
		(end 111.71174 -151.032972)
		(width 0.14224)
		(layer "In11.Cu")
		(net "M_M_C<2>")
	)
	(segment
		(start 103.655368 -99.9744)
		(end 104.404668 -100.7237)
		(width 0.0889)
		(layer "In11.Cu")
		(net "M_M_C<2>")
	)
	(segment
		(start 113.510568 -139.319)
		(end 113.376964 -139.452604)
		(width 0.14224)
		(layer "In11.Cu")
		(net "M_M_C<2>")
	)
	(segment
		(start 113.454434 -141.472666)
		(end 113.535968 -141.5542)
		(width 0.14224)
		(layer "In11.Cu")
		(net "M_M_C<2>")
	)
	(segment
		(start 111.71174 -149.737572)
		(end 111.299498 -149.32533)
		(width 0.14224)
		(layer "In11.Cu")
		(net "M_M_C<2>")
	)
	(segment
		(start 113.434368 -136.7282)
		(end 113.510568 -136.8044)
		(width 0.14224)
		(layer "In11.Cu")
		(net "M_M_C<2>")
	)
	(segment
		(start 113.376964 -139.452604)
		(end 113.376964 -140.150596)
		(width 0.14224)
		(layer "In11.Cu")
		(net "M_M_C<2>")
	)
	(segment
		(start 105.065068 -100.7237)
		(end 105.814622 -101.473254)
		(width 0.0889)
		(layer "In11.Cu")
		(net "M_M_C<2>")
	)
	(segment
		(start 113.454434 -140.228066)
		(end 113.454434 -141.472666)
		(width 0.14224)
		(layer "In11.Cu")
		(net "M_M_C<2>")
	)
	(segment
		(start 111.299498 -154.28087)
		(end 111.935768 -153.6446)
		(width 0.14224)
		(layer "In11.Cu")
		(net "M_M_C<2>")
	)
	(segment
		(start 111.71174 -151.032972)
		(end 111.71174 -149.737572)
		(width 0.14224)
		(layer "In11.Cu")
		(net "M_M_C<2>")
	)
	(segment
		(start 113.510568 -130.7592)
		(end 113.510568 -131.4704)
		(width 0.14224)
		(layer "In11.Cu")
		(net "M_M_C<2>")
	)
	(segment
		(start 113.256568 -129.9972)
		(end 113.256568 -130.5052)
		(width 0.14224)
		(layer "In11.Cu")
		(net "M_M_C<2>")
	)
	(segment
		(start 113.376964 -140.150596)
		(end 113.454434 -140.228066)
		(width 0.14224)
		(layer "In11.Cu")
		(net "M_M_C<2>")
	)
	(segment
		(start 105.814622 -101.997764)
		(end 105.814622 -118.796054)
		(width 0.14224)
		(layer "In11.Cu")
		(net "M_M_C<2>")
	)
	(segment
		(start 103.020368 -91.747086)
		(end 103.655368 -92.382086)
		(width 0.0889)
		(layer "In11.Cu")
		(net "M_M_C<2>")
	)
	(segment
		(start 82.399378 -156.87294)
		(end 82.399378 -154.905456)
		(width 0.1651)
		(layer "F.Cu")
		(net "M_M_BG<1>")
	)
	(segment
		(start 89.211912 -91.747086)
		(end 88.640412 -91.747086)
		(width 0.1016)
		(layer "F.Cu")
		(net "M_M_BG<1>")
	)
	(via
		(at 88.640412 -91.747086)
		(size 0.508)
		(drill 0.254)
		(layers "F.Cu" "B.Cu")
		(net "M_M_BG<1>")
	)
	(via
		(at 82.399378 -154.905456)
		(size 0.508)
		(drill 0.254)
		(layers "F.Cu" "B.Cu")
		(net "M_M_BG<1>")
	)
	(via
		(at 82.399378 -148.771356)
		(size 0.4572)
		(drill 0.2032)
		(layers "F.Cu" "B.Cu")
		(net "M_M_BG<1>")
	)
	(segment
		(start 82.399378 -148.771356)
		(end 82.399378 -147.478496)
		(width 0.1651)
		(layer "B.Cu")
		(net "M_M_BG<1>")
	)
	(segment
		(start 86.441788 -125.849126)
		(end 85.113368 -127.177546)
		(width 0.14224)
		(layer "In2.Cu")
		(net "M_M_BG<1>")
	)
	(segment
		(start 84.478368 -130.556)
		(end 84.579968 -130.6576)
		(width 0.14224)
		(layer "In2.Cu")
		(net "M_M_BG<1>")
	)
	(segment
		(start 85.113368 -127.177546)
		(end 85.113368 -128.860296)
		(width 0.14224)
		(layer "In2.Cu")
		(net "M_M_BG<1>")
	)
	(segment
		(start 89.075768 -101.092)
		(end 88.802972 -101.364796)
		(width 0.0889)
		(layer "In2.Cu")
		(net "M_M_BG<1>")
	)
	(segment
		(start 88.166194 -123.837192)
		(end 87.974932 -123.64593)
		(width 0.14224)
		(layer "In2.Cu")
		(net "M_M_BG<1>")
	)
	(segment
		(start 82.399378 -148.771356)
		(end 82.399378 -149.269958)
		(width 0.14224)
		(layer "In2.Cu")
		(net "M_M_BG<1>")
	)
	(segment
		(start 82.399378 -149.269958)
		(end 82.943954 -149.814534)
		(width 0.14224)
		(layer "In2.Cu")
		(net "M_M_BG<1>")
	)
	(segment
		(start 84.427568 -131.2926)
		(end 84.427568 -133.5532)
		(width 0.14224)
		(layer "In2.Cu")
		(net "M_M_BG<1>")
	)
	(segment
		(start 84.532978 -135.816848)
		(end 84.532978 -139.49299)
		(width 0.14224)
		(layer "In2.Cu")
		(net "M_M_BG<1>")
	)
	(segment
		(start 87.974932 -123.64593)
		(end 87.687404 -123.64593)
		(width 0.14224)
		(layer "In2.Cu")
		(net "M_M_BG<1>")
	)
	(segment
		(start 88.847168 -102.7176)
		(end 88.847168 -103.049324)
		(width 0.0889)
		(layer "In2.Cu")
		(net "M_M_BG<1>")
	)
	(segment
		(start 84.376768 -145.476468)
		(end 84.536534 -145.636234)
		(width 0.14224)
		(layer "In2.Cu")
		(net "M_M_BG<1>")
	)
	(segment
		(start 87.01659 -124.986796)
		(end 86.851744 -124.82195)
		(width 0.14224)
		(layer "In2.Cu")
		(net "M_M_BG<1>")
	)
	(segment
		(start 82.816446 -150.556722)
		(end 82.816446 -151.079454)
		(width 0.14224)
		(layer "In2.Cu")
		(net "M_M_BG<1>")
	)
	(segment
		(start 84.536534 -145.636234)
		(end 84.536534 -146.6342)
		(width 0.14224)
		(layer "In2.Cu")
		(net "M_M_BG<1>")
	)
	(segment
		(start 86.441788 -125.561598)
		(end 86.441788 -125.849126)
		(width 0.14224)
		(layer "In2.Cu")
		(net "M_M_BG<1>")
	)
	(segment
		(start 88.453722 -123.837192)
		(end 88.166194 -123.837192)
		(width 0.14224)
		(layer "In2.Cu")
		(net "M_M_BG<1>")
	)
	(segment
		(start 86.851744 -124.82195)
		(end 86.567518 -124.82195)
		(width 0.14224)
		(layer "In2.Cu")
		(net "M_M_BG<1>")
	)
	(segment
		(start 88.977978 -96.484948)
		(end 88.986868 -96.500188)
		(width 0.0889)
		(layer "In2.Cu")
		(net "M_M_BG<1>")
	)
	(segment
		(start 88.847168 -103.049324)
		(end 88.847168 -123.443746)
		(width 0.14224)
		(layer "In2.Cu")
		(net "M_M_BG<1>")
	)
	(segment
		(start 88.802972 -102.673404)
		(end 88.847168 -102.7176)
		(width 0.0889)
		(layer "In2.Cu")
		(net "M_M_BG<1>")
	)
	(segment
		(start 82.943954 -149.814534)
		(end 82.943954 -150.429214)
		(width 0.14224)
		(layer "In2.Cu")
		(net "M_M_BG<1>")
	)
	(segment
		(start 87.40013 -124.220732)
		(end 87.591392 -124.411994)
		(width 0.14224)
		(layer "In2.Cu")
		(net "M_M_BG<1>")
	)
	(segment
		(start 87.304118 -124.986796)
		(end 87.01659 -124.986796)
		(width 0.14224)
		(layer "In2.Cu")
		(net "M_M_BG<1>")
	)
	(segment
		(start 87.591392 -124.411994)
		(end 87.591392 -124.699522)
		(width 0.14224)
		(layer "In2.Cu")
		(net "M_M_BG<1>")
	)
	(segment
		(start 82.943954 -150.429214)
		(end 82.816446 -150.556722)
		(width 0.14224)
		(layer "In2.Cu")
		(net "M_M_BG<1>")
	)
	(segment
		(start 82.940906 -151.203914)
		(end 82.940906 -153.810462)
		(width 0.14224)
		(layer "In2.Cu")
		(net "M_M_BG<1>")
	)
	(segment
		(start 84.452968 -135.736838)
		(end 84.532978 -135.816848)
		(width 0.14224)
		(layer "In2.Cu")
		(net "M_M_BG<1>")
	)
	(segment
		(start 84.514436 -144.312132)
		(end 84.376768 -144.4498)
		(width 0.14224)
		(layer "In2.Cu")
		(net "M_M_BG<1>")
	)
	(segment
		(start 84.536534 -146.6342)
		(end 82.399378 -148.771356)
		(width 0.14224)
		(layer "In2.Cu")
		(net "M_M_BG<1>")
	)
	(segment
		(start 84.376768 -144.4498)
		(end 84.376768 -145.476468)
		(width 0.14224)
		(layer "In2.Cu")
		(net "M_M_BG<1>")
	)
	(segment
		(start 84.402168 -140.365988)
		(end 84.525358 -140.489178)
		(width 0.14224)
		(layer "In2.Cu")
		(net "M_M_BG<1>")
	)
	(segment
		(start 84.525358 -140.489178)
		(end 84.525358 -141.73581)
		(width 0.14224)
		(layer "In2.Cu")
		(net "M_M_BG<1>")
	)
	(segment
		(start 88.802972 -101.364796)
		(end 88.802972 -102.673404)
		(width 0.0889)
		(layer "In2.Cu")
		(net "M_M_BG<1>")
	)
	(segment
		(start 82.816446 -151.079454)
		(end 82.940906 -151.203914)
		(width 0.14224)
		(layer "In2.Cu")
		(net "M_M_BG<1>")
	)
	(segment
		(start 84.532978 -139.49299)
		(end 84.402168 -139.6238)
		(width 0.14224)
		(layer "In2.Cu")
		(net "M_M_BG<1>")
	)
	(segment
		(start 88.977978 -98.466148)
		(end 88.986868 -98.481388)
		(width 0.0889)
		(layer "In2.Cu")
		(net "M_M_BG<1>")
	)
	(segment
		(start 84.605368 -129.8448)
		(end 84.478368 -129.9718)
		(width 0.14224)
		(layer "In2.Cu")
		(net "M_M_BG<1>")
	)
	(segment
		(start 86.280244 -125.109224)
		(end 86.280244 -125.400054)
		(width 0.14224)
		(layer "In2.Cu")
		(net "M_M_BG<1>")
	)
	(segment
		(start 84.376768 -143.3576)
		(end 84.514436 -143.495268)
		(width 0.14224)
		(layer "In2.Cu")
		(net "M_M_BG<1>")
	)
	(segment
		(start 84.529168 -133.6548)
		(end 84.529168 -134.6962)
		(width 0.14224)
		(layer "In2.Cu")
		(net "M_M_BG<1>")
	)
	(segment
		(start 84.427568 -133.5532)
		(end 84.529168 -133.6548)
		(width 0.14224)
		(layer "In2.Cu")
		(net "M_M_BG<1>")
	)
	(segment
		(start 88.977978 -97.475548)
		(end 88.986868 -97.490788)
		(width 0.0889)
		(layer "In2.Cu")
		(net "M_M_BG<1>")
	)
	(segment
		(start 85.113368 -128.860296)
		(end 84.605368 -129.368296)
		(width 0.14224)
		(layer "In2.Cu")
		(net "M_M_BG<1>")
	)
	(segment
		(start 88.847168 -123.443746)
		(end 88.453722 -123.837192)
		(width 0.14224)
		(layer "In2.Cu")
		(net "M_M_BG<1>")
	)
	(segment
		(start 86.567518 -124.82195)
		(end 86.280244 -125.109224)
		(width 0.14224)
		(layer "In2.Cu")
		(net "M_M_BG<1>")
	)
	(segment
		(start 88.977978 -95.494348)
		(end 88.986868 -95.509588)
		(width 0.0889)
		(layer "In2.Cu")
		(net "M_M_BG<1>")
	)
	(segment
		(start 82.399378 -154.35199)
		(end 82.399378 -154.905456)
		(width 0.14224)
		(layer "In2.Cu")
		(net "M_M_BG<1>")
	)
	(segment
		(start 84.529168 -134.6962)
		(end 84.452968 -134.7724)
		(width 0.14224)
		(layer "In2.Cu")
		(net "M_M_BG<1>")
	)
	(segment
		(start 84.478368 -129.9718)
		(end 84.478368 -130.556)
		(width 0.14224)
		(layer "In2.Cu")
		(net "M_M_BG<1>")
	)
	(segment
		(start 84.579968 -131.1402)
		(end 84.427568 -131.2926)
		(width 0.14224)
		(layer "In2.Cu")
		(net "M_M_BG<1>")
	)
	(segment
		(start 89.075768 -98.810318)
		(end 89.075768 -101.092)
		(width 0.0889)
		(layer "In2.Cu")
		(net "M_M_BG<1>")
	)
	(segment
		(start 87.40013 -123.933204)
		(end 87.40013 -124.220732)
		(width 0.14224)
		(layer "In2.Cu")
		(net "M_M_BG<1>")
	)
	(segment
		(start 84.514436 -143.495268)
		(end 84.514436 -144.312132)
		(width 0.14224)
		(layer "In2.Cu")
		(net "M_M_BG<1>")
	)
	(segment
		(start 88.970104 -92.508832)
		(end 88.986868 -92.537788)
		(width 0.0889)
		(layer "In2.Cu")
		(net "M_M_BG<1>")
	)
	(segment
		(start 84.452968 -134.7724)
		(end 84.452968 -135.736838)
		(width 0.14224)
		(layer "In2.Cu")
		(net "M_M_BG<1>")
	)
	(segment
		(start 82.940906 -153.810462)
		(end 82.399378 -154.35199)
		(width 0.14224)
		(layer "In2.Cu")
		(net "M_M_BG<1>")
	)
	(segment
		(start 84.579968 -130.6576)
		(end 84.579968 -131.1402)
		(width 0.14224)
		(layer "In2.Cu")
		(net "M_M_BG<1>")
	)
	(segment
		(start 84.525358 -141.73581)
		(end 84.376768 -141.8844)
		(width 0.14224)
		(layer "In2.Cu")
		(net "M_M_BG<1>")
	)
	(segment
		(start 84.376768 -141.8844)
		(end 84.376768 -143.3576)
		(width 0.14224)
		(layer "In2.Cu")
		(net "M_M_BG<1>")
	)
	(segment
		(start 84.605368 -129.368296)
		(end 84.605368 -129.8448)
		(width 0.14224)
		(layer "In2.Cu")
		(net "M_M_BG<1>")
	)
	(segment
		(start 87.687404 -123.64593)
		(end 87.40013 -123.933204)
		(width 0.14224)
		(layer "In2.Cu")
		(net "M_M_BG<1>")
	)
	(segment
		(start 84.402168 -139.6238)
		(end 84.402168 -140.365988)
		(width 0.14224)
		(layer "In2.Cu")
		(net "M_M_BG<1>")
	)
	(segment
		(start 88.986868 -93.928438)
		(end 88.980518 -93.939106)
		(width 0.0889)
		(layer "In2.Cu")
		(net "M_M_BG<1>")
	)
	(segment
		(start 87.591392 -124.699522)
		(end 87.304118 -124.986796)
		(width 0.14224)
		(layer "In2.Cu")
		(net "M_M_BG<1>")
	)
	(segment
		(start 88.980518 -93.517974)
		(end 88.986868 -93.528642)
		(width 0.0889)
		(layer "In2.Cu")
		(net "M_M_BG<1>")
	)
	(segment
		(start 86.280244 -125.400054)
		(end 86.441788 -125.561598)
		(width 0.14224)
		(layer "In2.Cu")
		(net "M_M_BG<1>")
	)
	(segment
		(start 88.640412 -91.747086)
		(end 88.970104 -92.508832)
		(width 0.0889)
		(layer "In2.Cu")
		(net "M_M_BG<1>")
	)
	(arc
		(start 88.986868 -96.899984)
		(mid 88.907679 -97.186599)
		(end 88.977978 -97.475548)
		(width 0.0889)
		(layer "In2.Cu")
		(net "M_M_BG<1>")
	)
	(arc
		(start 88.980518 -93.939106)
		(mid 88.90772 -94.229869)
		(end 88.986868 -94.518988)
		(width 0.0889)
		(layer "In2.Cu")
		(net "M_M_BG<1>")
	)
	(arc
		(start 88.986868 -92.537788)
		(mid 89.040401 -92.737686)
		(end 88.986868 -92.937584)
		(width 0.0889)
		(layer "In2.Cu")
		(net "M_M_BG<1>")
	)
	(arc
		(start 88.986868 -95.909384)
		(mid 88.907679 -96.195999)
		(end 88.977978 -96.484948)
		(width 0.0889)
		(layer "In2.Cu")
		(net "M_M_BG<1>")
	)
	(arc
		(start 88.986868 -92.937584)
		(mid 88.907519 -93.226956)
		(end 88.980518 -93.517974)
		(width 0.0889)
		(layer "In2.Cu")
		(net "M_M_BG<1>")
	)
	(arc
		(start 88.986868 -96.500188)
		(mid 89.040401 -96.700086)
		(end 88.986868 -96.899984)
		(width 0.0889)
		(layer "In2.Cu")
		(net "M_M_BG<1>")
	)
	(arc
		(start 88.986868 -94.518988)
		(mid 89.040401 -94.718886)
		(end 88.986868 -94.918784)
		(width 0.0889)
		(layer "In2.Cu")
		(net "M_M_BG<1>")
	)
	(arc
		(start 88.986868 -98.481388)
		(mid 89.053196 -98.639944)
		(end 89.075768 -98.810318)
		(width 0.0889)
		(layer "In2.Cu")
		(net "M_M_BG<1>")
	)
	(arc
		(start 88.986868 -97.490788)
		(mid 89.040401 -97.690686)
		(end 88.986868 -97.890584)
		(width 0.0889)
		(layer "In2.Cu")
		(net "M_M_BG<1>")
	)
	(arc
		(start 88.986868 -97.890584)
		(mid 88.907679 -98.177199)
		(end 88.977978 -98.466148)
		(width 0.0889)
		(layer "In2.Cu")
		(net "M_M_BG<1>")
	)
	(arc
		(start 88.986868 -94.918784)
		(mid 88.907679 -95.205399)
		(end 88.977978 -95.494348)
		(width 0.0889)
		(layer "In2.Cu")
		(net "M_M_BG<1>")
	)
	(arc
		(start 88.986868 -93.528642)
		(mid 89.040401 -93.72854)
		(end 88.986868 -93.928438)
		(width 0.0889)
		(layer "In2.Cu")
		(net "M_M_BG<1>")
	)
	(arc
		(start 88.986868 -95.509588)
		(mid 89.040401 -95.709486)
		(end 88.986868 -95.909384)
		(width 0.0889)
		(layer "In2.Cu")
		(net "M_M_BG<1>")
	)
	(segment
		(start 88.353392 -89.27084)
		(end 87.781892 -89.27084)
		(width 0.1016)
		(layer "F.Cu")
		(net "M_M_BG<0>")
	)
	(segment
		(start 82.399378 -152.273)
		(end 82.399378 -153.542746)
		(width 0.1651)
		(layer "F.Cu")
		(net "M_M_BG<0>")
	)
	(via
		(at 82.399378 -153.542746)
		(size 0.508)
		(drill 0.254)
		(layers "F.Cu" "B.Cu")
		(net "M_M_BG<0>")
	)
	(via
		(at 82.399378 -150.788878)
		(size 0.4572)
		(drill 0.2032)
		(layers "F.Cu" "B.Cu")
		(net "M_M_BG<0>")
	)
	(via
		(at 87.781892 -89.27084)
		(size 0.508)
		(drill 0.254)
		(layers "F.Cu" "B.Cu")
		(net "M_M_BG<0>")
	)
	(segment
		(start 82.399378 -152.078436)
		(end 82.399378 -150.788878)
		(width 0.1651)
		(layer "B.Cu")
		(net "M_M_BG<0>")
	)
	(segment
		(start 81.854548 -151.741124)
		(end 82.009488 -151.896064)
		(width 0.14224)
		(layer "In2.Cu")
		(net "M_M_BG<0>")
	)
	(segment
		(start 81.987898 -149.592792)
		(end 82.399378 -150.004272)
		(width 0.14224)
		(layer "In2.Cu")
		(net "M_M_BG<0>")
	)
	(segment
		(start 88.293702 -99.472242)
		(end 88.237568 -99.57181)
		(width 0.0889)
		(layer "In2.Cu")
		(net "M_M_BG<0>")
	)
	(segment
		(start 82.009488 -151.896064)
		(end 82.244438 -151.896064)
		(width 0.14224)
		(layer "In2.Cu")
		(net "M_M_BG<0>")
	)
	(segment
		(start 82.244438 -153.018744)
		(end 82.399378 -153.173684)
		(width 0.14224)
		(layer "In2.Cu")
		(net "M_M_BG<0>")
	)
	(segment
		(start 83.663536 -136.76122)
		(end 83.663536 -140.866368)
		(width 0.14224)
		(layer "In2.Cu")
		(net "M_M_BG<0>")
	)
	(segment
		(start 82.244438 -151.334724)
		(end 82.009488 -151.334724)
		(width 0.14224)
		(layer "In2.Cu")
		(net "M_M_BG<0>")
	)
	(segment
		(start 88.293702 -96.500188)
		(end 88.288876 -96.508824)
		(width 0.0889)
		(layer "In2.Cu")
		(net "M_M_BG<0>")
	)
	(segment
		(start 83.663536 -140.866368)
		(end 83.689444 -140.892276)
		(width 0.14224)
		(layer "In2.Cu")
		(net "M_M_BG<0>")
	)
	(segment
		(start 82.244438 -152.457404)
		(end 81.903316 -152.457404)
		(width 0.14224)
		(layer "In2.Cu")
		(net "M_M_BG<0>")
	)
	(segment
		(start 82.399378 -153.173684)
		(end 82.399378 -153.542746)
		(width 0.14224)
		(layer "In2.Cu")
		(net "M_M_BG<0>")
	)
	(segment
		(start 81.854548 -151.489664)
		(end 81.854548 -151.741124)
		(width 0.14224)
		(layer "In2.Cu")
		(net "M_M_BG<0>")
	)
	(segment
		(start 83.685888 -131.26212)
		(end 83.685888 -135.025384)
		(width 0.14224)
		(layer "In2.Cu")
		(net "M_M_BG<0>")
	)
	(segment
		(start 83.6422 -129.846832)
		(end 83.767168 -129.9718)
		(width 0.14224)
		(layer "In2.Cu")
		(net "M_M_BG<0>")
	)
	(segment
		(start 88.300052 -97.48012)
		(end 88.293702 -97.490788)
		(width 0.0889)
		(layer "In2.Cu")
		(net "M_M_BG<0>")
	)
	(segment
		(start 88.300052 -92.52712)
		(end 88.293702 -92.537788)
		(width 0.0889)
		(layer "In2.Cu")
		(net "M_M_BG<0>")
	)
	(segment
		(start 88.339168 -122.2756)
		(end 84.605368 -126.0094)
		(width 0.14224)
		(layer "In2.Cu")
		(net "M_M_BG<0>")
	)
	(segment
		(start 81.903316 -153.018744)
		(end 82.244438 -153.018744)
		(width 0.14224)
		(layer "In2.Cu")
		(net "M_M_BG<0>")
	)
	(segment
		(start 83.614768 -130.6576)
		(end 83.614768 -131.191)
		(width 0.14224)
		(layer "In2.Cu")
		(net "M_M_BG<0>")
	)
	(segment
		(start 88.293702 -95.509588)
		(end 88.288876 -95.518224)
		(width 0.0889)
		(layer "In2.Cu")
		(net "M_M_BG<0>")
	)
	(segment
		(start 83.689444 -140.892276)
		(end 83.689444 -145.010124)
		(width 0.14224)
		(layer "In2.Cu")
		(net "M_M_BG<0>")
	)
	(segment
		(start 81.903316 -152.457404)
		(end 81.748376 -152.612344)
		(width 0.14224)
		(layer "In2.Cu")
		(net "M_M_BG<0>")
	)
	(segment
		(start 81.748376 -152.863804)
		(end 81.903316 -153.018744)
		(width 0.14224)
		(layer "In2.Cu")
		(net "M_M_BG<0>")
	)
	(segment
		(start 88.237568 -100.06584)
		(end 88.339168 -100.16744)
		(width 0.0889)
		(layer "In2.Cu")
		(net "M_M_BG<0>")
	)
	(segment
		(start 82.399378 -152.302464)
		(end 82.244438 -152.457404)
		(width 0.14224)
		(layer "In2.Cu")
		(net "M_M_BG<0>")
	)
	(segment
		(start 82.399378 -151.179784)
		(end 82.244438 -151.334724)
		(width 0.14224)
		(layer "In2.Cu")
		(net "M_M_BG<0>")
	)
	(segment
		(start 88.300052 -96.48952)
		(end 88.293702 -96.500188)
		(width 0.0889)
		(layer "In2.Cu")
		(net "M_M_BG<0>")
	)
	(segment
		(start 88.339168 -100.16744)
		(end 88.339168 -100.528374)
		(width 0.0889)
		(layer "In2.Cu")
		(net "M_M_BG<0>")
	)
	(segment
		(start 88.293702 -92.537788)
		(end 88.288876 -92.546424)
		(width 0.0889)
		(layer "In2.Cu")
		(net "M_M_BG<0>")
	)
	(segment
		(start 81.748376 -152.612344)
		(end 81.748376 -152.863804)
		(width 0.14224)
		(layer "In2.Cu")
		(net "M_M_BG<0>")
	)
	(segment
		(start 83.767168 -130.5052)
		(end 83.614768 -130.6576)
		(width 0.14224)
		(layer "In2.Cu")
		(net "M_M_BG<0>")
	)
	(segment
		(start 88.293702 -91.547188)
		(end 88.288876 -91.555824)
		(width 0.0889)
		(layer "In2.Cu")
		(net "M_M_BG<0>")
	)
	(segment
		(start 83.659726 -135.051546)
		(end 83.659726 -136.75741)
		(width 0.14224)
		(layer "In2.Cu")
		(net "M_M_BG<0>")
	)
	(segment
		(start 87.781892 -89.27084)
		(end 88.252808 -89.904316)
		(width 0.0889)
		(layer "In2.Cu")
		(net "M_M_BG<0>")
	)
	(segment
		(start 81.987898 -148.31187)
		(end 81.987898 -149.592792)
		(width 0.14224)
		(layer "In2.Cu")
		(net "M_M_BG<0>")
	)
	(segment
		(start 82.009488 -151.334724)
		(end 81.854548 -151.489664)
		(width 0.14224)
		(layer "In2.Cu")
		(net "M_M_BG<0>")
	)
	(segment
		(start 83.663282 -145.036286)
		(end 83.663282 -146.636486)
		(width 0.14224)
		(layer "In2.Cu")
		(net "M_M_BG<0>")
	)
	(segment
		(start 83.6422 -129.410968)
		(end 83.6422 -129.846832)
		(width 0.14224)
		(layer "In2.Cu")
		(net "M_M_BG<0>")
	)
	(segment
		(start 83.767168 -129.9718)
		(end 83.767168 -130.5052)
		(width 0.14224)
		(layer "In2.Cu")
		(net "M_M_BG<0>")
	)
	(segment
		(start 88.237568 -99.57181)
		(end 88.237568 -100.06584)
		(width 0.0889)
		(layer "In2.Cu")
		(net "M_M_BG<0>")
	)
	(segment
		(start 83.659726 -136.75741)
		(end 83.663536 -136.76122)
		(width 0.14224)
		(layer "In2.Cu")
		(net "M_M_BG<0>")
	)
	(segment
		(start 88.293702 -94.518988)
		(end 88.288876 -94.527624)
		(width 0.0889)
		(layer "In2.Cu")
		(net "M_M_BG<0>")
	)
	(segment
		(start 83.663282 -146.636486)
		(end 81.987898 -148.31187)
		(width 0.14224)
		(layer "In2.Cu")
		(net "M_M_BG<0>")
	)
	(segment
		(start 82.244438 -151.896064)
		(end 82.399378 -152.051004)
		(width 0.14224)
		(layer "In2.Cu")
		(net "M_M_BG<0>")
	)
	(segment
		(start 88.293702 -97.490788)
		(end 88.288876 -97.499424)
		(width 0.0889)
		(layer "In2.Cu")
		(net "M_M_BG<0>")
	)
	(segment
		(start 88.293702 -98.481388)
		(end 88.288876 -98.490024)
		(width 0.0889)
		(layer "In2.Cu")
		(net "M_M_BG<0>")
	)
	(segment
		(start 88.300052 -95.49892)
		(end 88.293702 -95.509588)
		(width 0.0889)
		(layer "In2.Cu")
		(net "M_M_BG<0>")
	)
	(segment
		(start 83.614768 -131.191)
		(end 83.685888 -131.26212)
		(width 0.14224)
		(layer "In2.Cu")
		(net "M_M_BG<0>")
	)
	(segment
		(start 88.300052 -91.53652)
		(end 88.293702 -91.547188)
		(width 0.0889)
		(layer "In2.Cu")
		(net "M_M_BG<0>")
	)
	(segment
		(start 84.605368 -128.4478)
		(end 83.6422 -129.410968)
		(width 0.14224)
		(layer "In2.Cu")
		(net "M_M_BG<0>")
	)
	(segment
		(start 82.399378 -150.004272)
		(end 82.399378 -150.788878)
		(width 0.14224)
		(layer "In2.Cu")
		(net "M_M_BG<0>")
	)
	(segment
		(start 83.689444 -145.010124)
		(end 83.663282 -145.036286)
		(width 0.14224)
		(layer "In2.Cu")
		(net "M_M_BG<0>")
	)
	(segment
		(start 83.685888 -135.025384)
		(end 83.659726 -135.051546)
		(width 0.14224)
		(layer "In2.Cu")
		(net "M_M_BG<0>")
	)
	(segment
		(start 88.339168 -100.528374)
		(end 88.339168 -122.2756)
		(width 0.14224)
		(layer "In2.Cu")
		(net "M_M_BG<0>")
	)
	(segment
		(start 84.605368 -126.0094)
		(end 84.605368 -128.4478)
		(width 0.14224)
		(layer "In2.Cu")
		(net "M_M_BG<0>")
	)
	(segment
		(start 88.293702 -93.928438)
		(end 88.300052 -93.939106)
		(width 0.0889)
		(layer "In2.Cu")
		(net "M_M_BG<0>")
	)
	(segment
		(start 88.293702 -98.481642)
		(end 88.293702 -98.481388)
		(width 0.0889)
		(layer "In2.Cu")
		(net "M_M_BG<0>")
	)
	(segment
		(start 82.399378 -150.788878)
		(end 82.399378 -151.179784)
		(width 0.14224)
		(layer "In2.Cu")
		(net "M_M_BG<0>")
	)
	(segment
		(start 88.293702 -90.556588)
		(end 88.288876 -90.565224)
		(width 0.0889)
		(layer "In2.Cu")
		(net "M_M_BG<0>")
	)
	(segment
		(start 88.300052 -90.54592)
		(end 88.293702 -90.556588)
		(width 0.0889)
		(layer "In2.Cu")
		(net "M_M_BG<0>")
	)
	(segment
		(start 82.399378 -152.051004)
		(end 82.399378 -152.302464)
		(width 0.14224)
		(layer "In2.Cu")
		(net "M_M_BG<0>")
	)
	(arc
		(start 88.293702 -96.900238)
		(mid 88.372924 -97.189356)
		(end 88.300052 -97.48012)
		(width 0.0889)
		(layer "In2.Cu")
		(net "M_M_BG<0>")
	)
	(arc
		(start 88.293702 -95.909638)
		(mid 88.372924 -96.198756)
		(end 88.300052 -96.48952)
		(width 0.0889)
		(layer "In2.Cu")
		(net "M_M_BG<0>")
	)
	(arc
		(start 88.288876 -90.565224)
		(mid 88.240121 -90.761576)
		(end 88.293702 -90.956638)
		(width 0.0889)
		(layer "In2.Cu")
		(net "M_M_BG<0>")
	)
	(arc
		(start 88.293702 -91.947238)
		(mid 88.372924 -92.236356)
		(end 88.300052 -92.52712)
		(width 0.0889)
		(layer "In2.Cu")
		(net "M_M_BG<0>")
	)
	(arc
		(start 88.288876 -98.490024)
		(mid 88.240121 -98.686376)
		(end 88.293702 -98.881438)
		(width 0.0889)
		(layer "In2.Cu")
		(net "M_M_BG<0>")
	)
	(arc
		(start 88.293702 -97.890838)
		(mid 88.372833 -98.18624)
		(end 88.293702 -98.481642)
		(width 0.0889)
		(layer "In2.Cu")
		(net "M_M_BG<0>")
	)
	(arc
		(start 88.293702 -90.956638)
		(mid 88.372924 -91.245756)
		(end 88.300052 -91.53652)
		(width 0.0889)
		(layer "In2.Cu")
		(net "M_M_BG<0>")
	)
	(arc
		(start 88.293702 -93.528642)
		(mid 88.240203 -93.72854)
		(end 88.293702 -93.928438)
		(width 0.0889)
		(layer "In2.Cu")
		(net "M_M_BG<0>")
	)
	(arc
		(start 88.252808 -89.904316)
		(mid 88.371318 -90.218116)
		(end 88.300052 -90.54592)
		(width 0.0889)
		(layer "In2.Cu")
		(net "M_M_BG<0>")
	)
	(arc
		(start 88.288876 -96.508824)
		(mid 88.240121 -96.705176)
		(end 88.293702 -96.900238)
		(width 0.0889)
		(layer "In2.Cu")
		(net "M_M_BG<0>")
	)
	(arc
		(start 88.288876 -94.527624)
		(mid 88.240121 -94.723976)
		(end 88.293702 -94.919038)
		(width 0.0889)
		(layer "In2.Cu")
		(net "M_M_BG<0>")
	)
	(arc
		(start 88.288876 -92.546424)
		(mid 88.240121 -92.742776)
		(end 88.293702 -92.937838)
		(width 0.0889)
		(layer "In2.Cu")
		(net "M_M_BG<0>")
	)
	(arc
		(start 88.293702 -98.881438)
		(mid 88.372833 -99.17684)
		(end 88.293702 -99.472242)
		(width 0.0889)
		(layer "In2.Cu")
		(net "M_M_BG<0>")
	)
	(arc
		(start 88.293702 -94.919038)
		(mid 88.372924 -95.208156)
		(end 88.300052 -95.49892)
		(width 0.0889)
		(layer "In2.Cu")
		(net "M_M_BG<0>")
	)
	(arc
		(start 88.288876 -97.499424)
		(mid 88.240121 -97.695776)
		(end 88.293702 -97.890838)
		(width 0.0889)
		(layer "In2.Cu")
		(net "M_M_BG<0>")
	)
	(arc
		(start 88.288876 -95.518224)
		(mid 88.240121 -95.714576)
		(end 88.293702 -95.909638)
		(width 0.0889)
		(layer "In2.Cu")
		(net "M_M_BG<0>")
	)
	(arc
		(start 88.293702 -92.937838)
		(mid 88.372833 -93.23324)
		(end 88.293702 -93.528642)
		(width 0.0889)
		(layer "In2.Cu")
		(net "M_M_BG<0>")
	)
	(arc
		(start 88.300052 -93.939106)
		(mid 88.37285 -94.229869)
		(end 88.293702 -94.518988)
		(width 0.0889)
		(layer "In2.Cu")
		(net "M_M_BG<0>")
	)
	(arc
		(start 88.288876 -91.555824)
		(mid 88.240121 -91.752176)
		(end 88.293702 -91.947238)
		(width 0.0889)
		(layer "In2.Cu")
		(net "M_M_BG<0>")
	)
	(segment
		(start 101.949504 -156.87294)
		(end 101.949504 -155.615132)
		(width 0.1651)
		(layer "F.Cu")
		(net "M_M_BA<1>")
	)
	(segment
		(start 93.504258 -90.26144)
		(end 92.932758 -90.26144)
		(width 0.1016)
		(layer "F.Cu")
		(net "M_M_BA<1>")
	)
	(via
		(at 92.932758 -90.26144)
		(size 0.508)
		(drill 0.254)
		(layers "F.Cu" "B.Cu")
		(net "M_M_BA<1>")
	)
	(via
		(at 101.949758 -148.773388)
		(size 0.4572)
		(drill 0.2032)
		(layers "F.Cu" "B.Cu")
		(net "M_M_BA<1>")
	)
	(via
		(at 101.949504 -155.615132)
		(size 0.508)
		(drill 0.254)
		(layers "F.Cu" "B.Cu")
		(net "M_M_BA<1>")
	)
	(segment
		(start 101.949504 -148.773134)
		(end 101.949758 -148.773388)
		(width 0.1651)
		(layer "B.Cu")
		(net "M_M_BA<1>")
	)
	(segment
		(start 101.949504 -147.478496)
		(end 101.949504 -148.773134)
		(width 0.1651)
		(layer "B.Cu")
		(net "M_M_BA<1>")
	)
	(segment
		(start 96.543368 -136.7536)
		(end 96.543368 -145.951448)
		(width 0.14224)
		(layer "In11.Cu")
		(net "M_M_BA<1>")
	)
	(segment
		(start 101.593142 -151.226774)
		(end 101.593142 -153.808938)
		(width 0.14224)
		(layer "In11.Cu")
		(net "M_M_BA<1>")
	)
	(segment
		(start 93.088968 -100.1522)
		(end 93.228668 -100.2919)
		(width 0.0889)
		(layer "In11.Cu")
		(net "M_M_BA<1>")
	)
	(segment
		(start 101.509322 -151.142954)
		(end 101.593142 -151.226774)
		(width 0.14224)
		(layer "In11.Cu")
		(net "M_M_BA<1>")
	)
	(segment
		(start 101.593142 -153.808938)
		(end 101.472238 -153.929842)
		(width 0.14224)
		(layer "In11.Cu")
		(net "M_M_BA<1>")
	)
	(segment
		(start 101.949758 -148.773388)
		(end 101.949758 -150.109428)
		(width 0.14224)
		(layer "In11.Cu")
		(net "M_M_BA<1>")
	)
	(segment
		(start 101.949758 -150.109428)
		(end 101.509322 -150.549864)
		(width 0.14224)
		(layer "In11.Cu")
		(net "M_M_BA<1>")
	)
	(segment
		(start 96.543368 -145.951448)
		(end 97.983802 -147.391882)
		(width 0.14224)
		(layer "In11.Cu")
		(net "M_M_BA<1>")
	)
	(segment
		(start 95.832168 -127.714502)
		(end 95.832168 -136.0424)
		(width 0.14224)
		(layer "In11.Cu")
		(net "M_M_BA<1>")
	)
	(segment
		(start 95.832168 -136.0424)
		(end 96.543368 -136.7536)
		(width 0.14224)
		(layer "In11.Cu")
		(net "M_M_BA<1>")
	)
	(segment
		(start 101.472238 -153.929842)
		(end 101.472238 -154.517598)
		(width 0.14224)
		(layer "In11.Cu")
		(net "M_M_BA<1>")
	)
	(segment
		(start 101.509322 -150.549864)
		(end 101.509322 -151.142954)
		(width 0.14224)
		(layer "In11.Cu")
		(net "M_M_BA<1>")
	)
	(segment
		(start 93.228668 -100.2919)
		(end 94.679516 -101.742748)
		(width 0.14224)
		(layer "In11.Cu")
		(net "M_M_BA<1>")
	)
	(segment
		(start 92.932758 -90.26144)
		(end 93.24467 -90.981276)
		(width 0.0889)
		(layer "In11.Cu")
		(net "M_M_BA<1>")
	)
	(segment
		(start 94.679516 -126.56185)
		(end 95.832168 -127.714502)
		(width 0.14224)
		(layer "In11.Cu")
		(net "M_M_BA<1>")
	)
	(segment
		(start 93.088968 -98.106992)
		(end 93.088968 -100.1522)
		(width 0.0889)
		(layer "In11.Cu")
		(net "M_M_BA<1>")
	)
	(segment
		(start 101.472238 -154.517598)
		(end 101.949504 -154.994864)
		(width 0.14224)
		(layer "In11.Cu")
		(net "M_M_BA<1>")
	)
	(segment
		(start 94.679516 -101.742748)
		(end 94.679516 -126.56185)
		(width 0.14224)
		(layer "In11.Cu")
		(net "M_M_BA<1>")
	)
	(segment
		(start 100.568252 -147.391882)
		(end 101.949758 -148.773388)
		(width 0.14224)
		(layer "In11.Cu")
		(net "M_M_BA<1>")
	)
	(segment
		(start 97.983802 -147.391882)
		(end 100.568252 -147.391882)
		(width 0.14224)
		(layer "In11.Cu")
		(net "M_M_BA<1>")
	)
	(segment
		(start 101.949504 -154.994864)
		(end 101.949504 -155.615132)
		(width 0.14224)
		(layer "In11.Cu")
		(net "M_M_BA<1>")
	)
	(arc
		(start 93.279468 -95.014288)
		(mid 93.332967 -95.214186)
		(end 93.279468 -95.414084)
		(width 0.0889)
		(layer "In11.Cu")
		(net "M_M_BA<1>")
	)
	(arc
		(start 93.279468 -96.404684)
		(mid 93.200337 -96.700086)
		(end 93.279468 -96.995488)
		(width 0.0889)
		(layer "In11.Cu")
		(net "M_M_BA<1>")
	)
	(arc
		(start 93.279468 -96.004888)
		(mid 93.332967 -96.204786)
		(end 93.279468 -96.404684)
		(width 0.0889)
		(layer "In11.Cu")
		(net "M_M_BA<1>")
	)
	(arc
		(start 93.279468 -91.051888)
		(mid 93.332967 -91.251786)
		(end 93.279468 -91.451684)
		(width 0.0889)
		(layer "In11.Cu")
		(net "M_M_BA<1>")
	)
	(arc
		(start 93.279468 -94.423484)
		(mid 93.200337 -94.718886)
		(end 93.279468 -95.014288)
		(width 0.0889)
		(layer "In11.Cu")
		(net "M_M_BA<1>")
	)
	(arc
		(start 93.24467 -90.981276)
		(mid 93.260888 -91.017164)
		(end 93.279468 -91.051888)
		(width 0.0889)
		(layer "In11.Cu")
		(net "M_M_BA<1>")
	)
	(arc
		(start 93.279468 -92.042488)
		(mid 93.332967 -92.242386)
		(end 93.279468 -92.442284)
		(width 0.0889)
		(layer "In11.Cu")
		(net "M_M_BA<1>")
	)
	(arc
		(start 93.279468 -92.442284)
		(mid 93.200337 -92.737686)
		(end 93.279468 -93.033088)
		(width 0.0889)
		(layer "In11.Cu")
		(net "M_M_BA<1>")
	)
	(arc
		(start 93.279468 -95.414084)
		(mid 93.200337 -95.709486)
		(end 93.279468 -96.004888)
		(width 0.0889)
		(layer "In11.Cu")
		(net "M_M_BA<1>")
	)
	(arc
		(start 93.279468 -93.033088)
		(mid 93.332967 -93.232986)
		(end 93.279468 -93.432884)
		(width 0.0889)
		(layer "In11.Cu")
		(net "M_M_BA<1>")
	)
	(arc
		(start 93.279468 -94.023688)
		(mid 93.332967 -94.223586)
		(end 93.279468 -94.423484)
		(width 0.0889)
		(layer "In11.Cu")
		(net "M_M_BA<1>")
	)
	(arc
		(start 93.279468 -96.995488)
		(mid 93.332967 -97.195386)
		(end 93.279468 -97.395284)
		(width 0.0889)
		(layer "In11.Cu")
		(net "M_M_BA<1>")
	)
	(arc
		(start 93.279468 -91.451684)
		(mid 93.200337 -91.747086)
		(end 93.279468 -92.042488)
		(width 0.0889)
		(layer "In11.Cu")
		(net "M_M_BA<1>")
	)
	(arc
		(start 93.279468 -97.395284)
		(mid 93.137463 -97.738619)
		(end 93.088968 -98.106992)
		(width 0.0889)
		(layer "In11.Cu")
		(net "M_M_BA<1>")
	)
	(arc
		(start 93.279468 -93.432884)
		(mid 93.200337 -93.728286)
		(end 93.279468 -94.023688)
		(width 0.0889)
		(layer "In11.Cu")
		(net "M_M_BA<1>")
	)
	(segment
		(start 102.799388 -152.273)
		(end 102.799388 -153.542746)
		(width 0.1651)
		(layer "F.Cu")
		(net "M_M_BA<0>")
	)
	(segment
		(start 96.938338 -93.23324)
		(end 96.366838 -93.23324)
		(width 0.1016)
		(layer "F.Cu")
		(net "M_M_BA<0>")
	)
	(via
		(at 96.366838 -93.23324)
		(size 0.508)
		(drill 0.254)
		(layers "F.Cu" "B.Cu")
		(net "M_M_BA<0>")
	)
	(via
		(at 102.799642 -150.788878)
		(size 0.4572)
		(drill 0.2032)
		(layers "F.Cu" "B.Cu")
		(net "M_M_BA<0>")
	)
	(via
		(at 102.799388 -153.542746)
		(size 0.508)
		(drill 0.254)
		(layers "F.Cu" "B.Cu")
		(net "M_M_BA<0>")
	)
	(segment
		(start 102.799388 -152.078436)
		(end 102.799388 -150.789132)
		(width 0.1651)
		(layer "B.Cu")
		(net "M_M_BA<0>")
	)
	(segment
		(start 102.799388 -150.789132)
		(end 102.799642 -150.788878)
		(width 0.1651)
		(layer "B.Cu")
		(net "M_M_BA<0>")
	)
	(segment
		(start 98.447098 -125.77445)
		(end 98.447098 -126.061978)
		(width 0.14224)
		(layer "In2.Cu")
		(net "M_M_BA<0>")
	)
	(segment
		(start 98.73234 -125.489208)
		(end 98.447098 -125.77445)
		(width 0.14224)
		(layer "In2.Cu")
		(net "M_M_BA<0>")
	)
	(segment
		(start 96.713548 -96.404938)
		(end 96.707198 -96.415606)
		(width 0.0889)
		(layer "In2.Cu")
		(net "M_M_BA<0>")
	)
	(segment
		(start 101.535738 -135.39597)
		(end 101.535738 -140.80363)
		(width 0.14224)
		(layer "In2.Cu")
		(net "M_M_BA<0>")
	)
	(segment
		(start 101.512624 -140.826744)
		(end 101.512624 -141.468856)
		(width 0.14224)
		(layer "In2.Cu")
		(net "M_M_BA<0>")
	)
	(segment
		(start 98.157538 -124.914406)
		(end 98.445066 -124.914406)
		(width 0.14224)
		(layer "In2.Cu")
		(net "M_M_BA<0>")
	)
	(segment
		(start 96.713548 -95.414338)
		(end 96.707198 -95.425006)
		(width 0.0889)
		(layer "In2.Cu")
		(net "M_M_BA<0>")
	)
	(segment
		(start 102.799642 -149.588474)
		(end 102.799642 -150.788878)
		(width 0.14224)
		(layer "In2.Cu")
		(net "M_M_BA<0>")
	)
	(segment
		(start 101.571044 -130.603244)
		(end 101.571044 -131.243324)
		(width 0.14224)
		(layer "In2.Cu")
		(net "M_M_BA<0>")
	)
	(segment
		(start 98.447098 -126.061978)
		(end 101.563932 -129.178812)
		(width 0.14224)
		(layer "In2.Cu")
		(net "M_M_BA<0>")
	)
	(segment
		(start 98.445066 -124.914406)
		(end 98.73234 -125.20168)
		(width 0.14224)
		(layer "In2.Cu")
		(net "M_M_BA<0>")
	)
	(segment
		(start 102.652322 -150.936198)
		(end 102.652322 -153.39568)
		(width 0.14224)
		(layer "In2.Cu")
		(net "M_M_BA<0>")
	)
	(segment
		(start 96.718374 -98.377502)
		(end 96.713548 -98.386138)
		(width 0.0889)
		(layer "In2.Cu")
		(net "M_M_BA<0>")
	)
	(segment
		(start 98.73234 -125.20168)
		(end 98.73234 -125.489208)
		(width 0.14224)
		(layer "In2.Cu")
		(net "M_M_BA<0>")
	)
	(segment
		(start 96.366838 -93.23324)
		(end 96.66859 -93.927168)
		(width 0.0889)
		(layer "In2.Cu")
		(net "M_M_BA<0>")
	)
	(segment
		(start 101.535738 -140.80363)
		(end 101.512624 -140.826744)
		(width 0.14224)
		(layer "In2.Cu")
		(net "M_M_BA<0>")
	)
	(segment
		(start 101.563932 -129.178812)
		(end 101.563932 -129.828036)
		(width 0.14224)
		(layer "In2.Cu")
		(net "M_M_BA<0>")
	)
	(segment
		(start 97.330768 -102.318312)
		(end 97.330768 -124.945648)
		(width 0.14224)
		(layer "In2.Cu")
		(net "M_M_BA<0>")
	)
	(segment
		(start 101.534976 -143.105632)
		(end 101.534976 -147.275296)
		(width 0.14224)
		(layer "In2.Cu")
		(net "M_M_BA<0>")
	)
	(segment
		(start 102.652322 -153.39568)
		(end 102.799388 -153.542746)
		(width 0.14224)
		(layer "In2.Cu")
		(net "M_M_BA<0>")
	)
	(segment
		(start 101.563932 -129.828036)
		(end 101.448108 -129.94386)
		(width 0.14224)
		(layer "In2.Cu")
		(net "M_M_BA<0>")
	)
	(segment
		(start 101.534976 -133.845808)
		(end 101.534976 -135.395208)
		(width 0.14224)
		(layer "In2.Cu")
		(net "M_M_BA<0>")
	)
	(segment
		(start 97.584768 -125.199648)
		(end 97.872296 -125.199648)
		(width 0.14224)
		(layer "In2.Cu")
		(net "M_M_BA<0>")
	)
	(segment
		(start 96.713548 -97.395538)
		(end 96.707198 -97.406206)
		(width 0.0889)
		(layer "In2.Cu")
		(net "M_M_BA<0>")
	)
	(segment
		(start 101.448108 -129.94386)
		(end 101.448108 -130.480308)
		(width 0.14224)
		(layer "In2.Cu")
		(net "M_M_BA<0>")
	)
	(segment
		(start 101.534976 -135.395208)
		(end 101.535738 -135.39597)
		(width 0.14224)
		(layer "In2.Cu")
		(net "M_M_BA<0>")
	)
	(segment
		(start 96.768158 -99.36861)
		(end 96.768158 -101.226366)
		(width 0.0889)
		(layer "In2.Cu")
		(net "M_M_BA<0>")
	)
	(segment
		(start 101.686614 -142.953994)
		(end 101.534976 -143.105632)
		(width 0.14224)
		(layer "In2.Cu")
		(net "M_M_BA<0>")
	)
	(segment
		(start 101.470968 -133.7818)
		(end 101.534976 -133.845808)
		(width 0.14224)
		(layer "In2.Cu")
		(net "M_M_BA<0>")
	)
	(segment
		(start 102.799642 -150.788878)
		(end 102.652322 -150.936198)
		(width 0.14224)
		(layer "In2.Cu")
		(net "M_M_BA<0>")
	)
	(segment
		(start 97.330768 -101.788976)
		(end 97.330768 -102.318312)
		(width 0.0889)
		(layer "In2.Cu")
		(net "M_M_BA<0>")
	)
	(segment
		(start 102.361746 -148.102066)
		(end 102.361746 -149.150578)
		(width 0.14224)
		(layer "In2.Cu")
		(net "M_M_BA<0>")
	)
	(segment
		(start 96.718374 -97.386902)
		(end 96.713548 -97.395538)
		(width 0.0889)
		(layer "In2.Cu")
		(net "M_M_BA<0>")
	)
	(segment
		(start 96.718374 -96.396302)
		(end 96.713548 -96.404938)
		(width 0.0889)
		(layer "In2.Cu")
		(net "M_M_BA<0>")
	)
	(segment
		(start 97.872296 -125.199648)
		(end 98.157538 -124.914406)
		(width 0.14224)
		(layer "In2.Cu")
		(net "M_M_BA<0>")
	)
	(segment
		(start 97.330768 -124.945648)
		(end 97.584768 -125.199648)
		(width 0.14224)
		(layer "In2.Cu")
		(net "M_M_BA<0>")
	)
	(segment
		(start 102.361746 -149.150578)
		(end 102.799642 -149.588474)
		(width 0.14224)
		(layer "In2.Cu")
		(net "M_M_BA<0>")
	)
	(segment
		(start 96.707198 -94.01302)
		(end 96.713548 -94.023688)
		(width 0.0889)
		(layer "In2.Cu")
		(net "M_M_BA<0>")
	)
	(segment
		(start 101.571044 -131.243324)
		(end 101.470968 -131.3434)
		(width 0.14224)
		(layer "In2.Cu")
		(net "M_M_BA<0>")
	)
	(segment
		(start 101.534976 -147.275296)
		(end 102.361746 -148.102066)
		(width 0.14224)
		(layer "In2.Cu")
		(net "M_M_BA<0>")
	)
	(segment
		(start 96.771968 -99.3648)
		(end 96.768158 -99.36861)
		(width 0.0889)
		(layer "In2.Cu")
		(net "M_M_BA<0>")
	)
	(segment
		(start 101.448108 -130.480308)
		(end 101.571044 -130.603244)
		(width 0.14224)
		(layer "In2.Cu")
		(net "M_M_BA<0>")
	)
	(segment
		(start 96.718374 -95.405702)
		(end 96.713548 -95.414338)
		(width 0.0889)
		(layer "In2.Cu")
		(net "M_M_BA<0>")
	)
	(segment
		(start 96.713548 -98.386138)
		(end 96.707198 -98.396806)
		(width 0.0889)
		(layer "In2.Cu")
		(net "M_M_BA<0>")
	)
	(segment
		(start 96.768158 -101.226366)
		(end 97.330768 -101.788976)
		(width 0.0889)
		(layer "In2.Cu")
		(net "M_M_BA<0>")
	)
	(segment
		(start 101.512624 -141.468856)
		(end 101.686614 -141.642846)
		(width 0.14224)
		(layer "In2.Cu")
		(net "M_M_BA<0>")
	)
	(segment
		(start 101.686614 -141.642846)
		(end 101.686614 -142.953994)
		(width 0.14224)
		(layer "In2.Cu")
		(net "M_M_BA<0>")
	)
	(segment
		(start 101.470968 -131.3434)
		(end 101.470968 -133.7818)
		(width 0.14224)
		(layer "In2.Cu")
		(net "M_M_BA<0>")
	)
	(arc
		(start 96.707198 -97.406206)
		(mid 96.6344 -97.696969)
		(end 96.713548 -97.986088)
		(width 0.0889)
		(layer "In2.Cu")
		(net "M_M_BA<0>")
	)
	(arc
		(start 96.713548 -96.995488)
		(mid 96.767018 -97.190551)
		(end 96.718374 -97.386902)
		(width 0.0889)
		(layer "In2.Cu")
		(net "M_M_BA<0>")
	)
	(arc
		(start 96.713548 -95.014288)
		(mid 96.767018 -95.209351)
		(end 96.718374 -95.405702)
		(width 0.0889)
		(layer "In2.Cu")
		(net "M_M_BA<0>")
	)
	(arc
		(start 96.713548 -96.004888)
		(mid 96.767018 -96.199951)
		(end 96.718374 -96.396302)
		(width 0.0889)
		(layer "In2.Cu")
		(net "M_M_BA<0>")
	)
	(arc
		(start 96.707198 -95.425006)
		(mid 96.6344 -95.715769)
		(end 96.713548 -96.004888)
		(width 0.0889)
		(layer "In2.Cu")
		(net "M_M_BA<0>")
	)
	(arc
		(start 96.713548 -97.986088)
		(mid 96.767018 -98.181151)
		(end 96.718374 -98.377502)
		(width 0.0889)
		(layer "In2.Cu")
		(net "M_M_BA<0>")
	)
	(arc
		(start 96.713548 -94.023688)
		(mid 96.767047 -94.223586)
		(end 96.713548 -94.423484)
		(width 0.0889)
		(layer "In2.Cu")
		(net "M_M_BA<0>")
	)
	(arc
		(start 96.707198 -98.396806)
		(mid 96.6344 -98.687569)
		(end 96.713548 -98.976688)
		(width 0.0889)
		(layer "In2.Cu")
		(net "M_M_BA<0>")
	)
	(arc
		(start 96.713548 -98.976688)
		(mid 96.779557 -99.165212)
		(end 96.771968 -99.3648)
		(width 0.0889)
		(layer "In2.Cu")
		(net "M_M_BA<0>")
	)
	(arc
		(start 96.66859 -93.927168)
		(mid 96.68618 -93.970865)
		(end 96.707198 -94.01302)
		(width 0.0889)
		(layer "In2.Cu")
		(net "M_M_BA<0>")
	)
	(arc
		(start 96.713548 -94.423484)
		(mid 96.634417 -94.718886)
		(end 96.713548 -95.014288)
		(width 0.0889)
		(layer "In2.Cu")
		(net "M_M_BA<0>")
	)
	(arc
		(start 96.707198 -96.415606)
		(mid 96.6344 -96.706369)
		(end 96.713548 -96.995488)
		(width 0.0889)
		(layer "In2.Cu")
		(net "M_M_BA<0>")
	)
	(segment
		(start 89.211912 -90.756486)
		(end 88.640412 -90.756486)
		(width 0.1651)
		(layer "F.Cu")
		(net "M_M_ALERT_N")
	)
	(segment
		(start 83.249516 -156.87294)
		(end 83.249516 -155.564078)
		(width 0.1651)
		(layer "F.Cu")
		(net "M_M_ALERT_N")
	)
	(via
		(at 83.249516 -155.564078)
		(size 0.508)
		(drill 0.254)
		(layers "F.Cu" "B.Cu")
		(net "M_M_ALERT_N")
	)
	(via
		(at 83.249516 -148.771356)
		(size 0.4572)
		(drill 0.2032)
		(layers "F.Cu" "B.Cu")
		(net "M_M_ALERT_N")
	)
	(via
		(at 88.640412 -90.756486)
		(size 0.508)
		(drill 0.254)
		(layers "F.Cu" "B.Cu")
		(net "M_M_ALERT_N")
	)
	(segment
		(start 83.249516 -148.771356)
		(end 83.249516 -147.478496)
		(width 0.1651)
		(layer "B.Cu")
		(net "M_M_ALERT_N")
	)
	(segment
		(start 89.634314 -138.261344)
		(end 89.634314 -139.971526)
		(width 0.14224)
		(layer "In11.Cu")
		(net "M_M_ALERT_N")
	)
	(segment
		(start 83.249516 -154.949652)
		(end 83.249516 -155.564078)
		(width 0.14224)
		(layer "In11.Cu")
		(net "M_M_ALERT_N")
	)
	(segment
		(start 88.970104 -91.518232)
		(end 88.986868 -91.547188)
		(width 0.0889)
		(layer "In11.Cu")
		(net "M_M_ALERT_N")
	)
	(segment
		(start 89.579196 -132.132832)
		(end 90.599768 -133.153404)
		(width 0.14224)
		(layer "In11.Cu")
		(net "M_M_ALERT_N")
	)
	(segment
		(start 90.599768 -128.737106)
		(end 89.520522 -129.816352)
		(width 0.14224)
		(layer "In11.Cu")
		(net "M_M_ALERT_N")
	)
	(segment
		(start 86.215982 -146.325844)
		(end 85.983826 -146.558)
		(width 0.14224)
		(layer "In11.Cu")
		(net "M_M_ALERT_N")
	)
	(segment
		(start 90.462608 -134.71144)
		(end 90.320876 -134.853172)
		(width 0.14224)
		(layer "In11.Cu")
		(net "M_M_ALERT_N")
	)
	(segment
		(start 89.634314 -139.971526)
		(end 88.783414 -140.822426)
		(width 0.14224)
		(layer "In11.Cu")
		(net "M_M_ALERT_N")
	)
	(segment
		(start 90.463116 -136.186164)
		(end 90.463116 -137.432542)
		(width 0.14224)
		(layer "In11.Cu")
		(net "M_M_ALERT_N")
	)
	(segment
		(start 90.703908 -96.500188)
		(end 90.708734 -96.508824)
		(width 0.0889)
		(layer "In11.Cu")
		(net "M_M_ALERT_N")
	)
	(segment
		(start 82.812636 -149.208236)
		(end 82.812636 -151.217884)
		(width 0.14224)
		(layer "In11.Cu")
		(net "M_M_ALERT_N")
	)
	(segment
		(start 91.285568 -101.981)
		(end 92.139516 -102.834948)
		(width 0.14224)
		(layer "In11.Cu")
		(net "M_M_ALERT_N")
	)
	(segment
		(start 90.697558 -96.48952)
		(end 90.703908 -96.500188)
		(width 0.0889)
		(layer "In11.Cu")
		(net "M_M_ALERT_N")
	)
	(segment
		(start 84.376768 -147.644104)
		(end 83.249516 -148.771356)
		(width 0.14224)
		(layer "In11.Cu")
		(net "M_M_ALERT_N")
	)
	(segment
		(start 90.320876 -134.853172)
		(end 90.320876 -136.043924)
		(width 0.14224)
		(layer "In11.Cu")
		(net "M_M_ALERT_N")
	)
	(segment
		(start 87.910416 -142.389352)
		(end 87.910416 -144.319752)
		(width 0.14224)
		(layer "In11.Cu")
		(net "M_M_ALERT_N")
	)
	(segment
		(start 84.630768 -146.558)
		(end 84.376768 -146.812)
		(width 0.14224)
		(layer "In11.Cu")
		(net "M_M_ALERT_N")
	)
	(segment
		(start 92.139516 -102.834948)
		(end 92.139516 -124.665486)
		(width 0.14224)
		(layer "In11.Cu")
		(net "M_M_ALERT_N")
	)
	(segment
		(start 88.783414 -141.516354)
		(end 87.910416 -142.389352)
		(width 0.14224)
		(layer "In11.Cu")
		(net "M_M_ALERT_N")
	)
	(segment
		(start 82.209894 -153.999946)
		(end 82.29981 -153.999946)
		(width 0.14224)
		(layer "In11.Cu")
		(net "M_M_ALERT_N")
	)
	(segment
		(start 81.912968 -153.70302)
		(end 82.209894 -153.999946)
		(width 0.14224)
		(layer "In11.Cu")
		(net "M_M_ALERT_N")
	)
	(segment
		(start 87.348568 -144.6022)
		(end 86.215982 -145.734786)
		(width 0.14224)
		(layer "In11.Cu")
		(net "M_M_ALERT_N")
	)
	(segment
		(start 89.520522 -130.474466)
		(end 89.732358 -130.686302)
		(width 0.14224)
		(layer "In11.Cu")
		(net "M_M_ALERT_N")
	)
	(segment
		(start 90.462608 -134.02056)
		(end 90.462608 -134.71144)
		(width 0.14224)
		(layer "In11.Cu")
		(net "M_M_ALERT_N")
	)
	(segment
		(start 84.376768 -146.812)
		(end 84.376768 -147.644104)
		(width 0.14224)
		(layer "In11.Cu")
		(net "M_M_ALERT_N")
	)
	(segment
		(start 87.627968 -144.6022)
		(end 87.348568 -144.6022)
		(width 0.14224)
		(layer "In11.Cu")
		(net "M_M_ALERT_N")
	)
	(segment
		(start 89.732358 -130.686302)
		(end 89.732358 -131.236974)
		(width 0.14224)
		(layer "In11.Cu")
		(net "M_M_ALERT_N")
	)
	(segment
		(start 88.640412 -90.756486)
		(end 88.970104 -91.518232)
		(width 0.0889)
		(layer "In11.Cu")
		(net "M_M_ALERT_N")
	)
	(segment
		(start 86.215982 -145.734786)
		(end 86.215982 -146.325844)
		(width 0.14224)
		(layer "In11.Cu")
		(net "M_M_ALERT_N")
	)
	(segment
		(start 90.339418 -94.31909)
		(end 90.375232 -94.31909)
		(width 0.0889)
		(layer "In11.Cu")
		(net "M_M_ALERT_N")
	)
	(segment
		(start 87.910416 -144.319752)
		(end 87.627968 -144.6022)
		(width 0.14224)
		(layer "In11.Cu")
		(net "M_M_ALERT_N")
	)
	(segment
		(start 89.477088 -93.82379)
		(end 89.516712 -93.82379)
		(width 0.0889)
		(layer "In11.Cu")
		(net "M_M_ALERT_N")
	)
	(segment
		(start 89.520522 -129.816352)
		(end 89.520522 -130.474466)
		(width 0.14224)
		(layer "In11.Cu")
		(net "M_M_ALERT_N")
	)
	(segment
		(start 90.320876 -136.043924)
		(end 90.463116 -136.186164)
		(width 0.14224)
		(layer "In11.Cu")
		(net "M_M_ALERT_N")
	)
	(segment
		(start 90.987372 -98.88982)
		(end 90.987372 -101.682804)
		(width 0.0889)
		(layer "In11.Cu")
		(net "M_M_ALERT_N")
	)
	(segment
		(start 88.977978 -92.522548)
		(end 88.986868 -92.537788)
		(width 0.0889)
		(layer "In11.Cu")
		(net "M_M_ALERT_N")
	)
	(segment
		(start 90.599768 -126.205234)
		(end 90.599768 -128.737106)
		(width 0.14224)
		(layer "In11.Cu")
		(net "M_M_ALERT_N")
	)
	(segment
		(start 89.579196 -131.390136)
		(end 89.579196 -132.132832)
		(width 0.14224)
		(layer "In11.Cu")
		(net "M_M_ALERT_N")
	)
	(segment
		(start 90.697558 -95.49892)
		(end 90.703908 -95.509588)
		(width 0.0889)
		(layer "In11.Cu")
		(net "M_M_ALERT_N")
	)
	(segment
		(start 89.732358 -131.236974)
		(end 89.579196 -131.390136)
		(width 0.14224)
		(layer "In11.Cu")
		(net "M_M_ALERT_N")
	)
	(segment
		(start 82.812636 -151.217884)
		(end 81.912968 -152.117552)
		(width 0.14224)
		(layer "In11.Cu")
		(net "M_M_ALERT_N")
	)
	(segment
		(start 81.912968 -152.117552)
		(end 81.912968 -153.70302)
		(width 0.14224)
		(layer "In11.Cu")
		(net "M_M_ALERT_N")
	)
	(segment
		(start 82.29981 -153.999946)
		(end 83.249516 -154.949652)
		(width 0.14224)
		(layer "In11.Cu")
		(net "M_M_ALERT_N")
	)
	(segment
		(start 90.784172 -96.804734)
		(end 90.784172 -98.68662)
		(width 0.0889)
		(layer "In11.Cu")
		(net "M_M_ALERT_N")
	)
	(segment
		(start 92.139516 -124.665486)
		(end 90.599768 -126.205234)
		(width 0.14224)
		(layer "In11.Cu")
		(net "M_M_ALERT_N")
	)
	(segment
		(start 83.249516 -148.771356)
		(end 82.812636 -149.208236)
		(width 0.14224)
		(layer "In11.Cu")
		(net "M_M_ALERT_N")
	)
	(segment
		(start 88.783414 -140.822426)
		(end 88.783414 -141.516354)
		(width 0.14224)
		(layer "In11.Cu")
		(net "M_M_ALERT_N")
	)
	(segment
		(start 90.987372 -101.682804)
		(end 91.285568 -101.981)
		(width 0.0889)
		(layer "In11.Cu")
		(net "M_M_ALERT_N")
	)
	(segment
		(start 85.983826 -146.558)
		(end 84.630768 -146.558)
		(width 0.14224)
		(layer "In11.Cu")
		(net "M_M_ALERT_N")
	)
	(segment
		(start 90.784172 -98.68662)
		(end 90.987372 -98.88982)
		(width 0.0889)
		(layer "In11.Cu")
		(net "M_M_ALERT_N")
	)
	(segment
		(start 90.599768 -133.8834)
		(end 90.462608 -134.02056)
		(width 0.14224)
		(layer "In11.Cu")
		(net "M_M_ALERT_N")
	)
	(segment
		(start 90.599768 -133.153404)
		(end 90.599768 -133.8834)
		(width 0.14224)
		(layer "In11.Cu")
		(net "M_M_ALERT_N")
	)
	(segment
		(start 90.463116 -137.432542)
		(end 89.634314 -138.261344)
		(width 0.14224)
		(layer "In11.Cu")
		(net "M_M_ALERT_N")
	)
	(segment
		(start 90.703908 -95.509588)
		(end 90.708734 -95.518224)
		(width 0.0889)
		(layer "In11.Cu")
		(net "M_M_ALERT_N")
	)
	(arc
		(start 90.708734 -95.518224)
		(mid 90.757489 -95.714576)
		(end 90.703908 -95.909638)
		(width 0.0889)
		(layer "In11.Cu")
		(net "M_M_ALERT_N")
	)
	(arc
		(start 90.708734 -96.508824)
		(mid 90.764979 -96.652053)
		(end 90.784172 -96.804734)
		(width 0.0889)
		(layer "In11.Cu")
		(net "M_M_ALERT_N")
	)
	(arc
		(start 88.986868 -92.937584)
		(mid 88.98145 -93.519311)
		(end 89.477088 -93.82379)
		(width 0.0889)
		(layer "In11.Cu")
		(net "M_M_ALERT_N")
	)
	(arc
		(start 90.703908 -95.909638)
		(mid 90.624686 -96.198756)
		(end 90.697558 -96.48952)
		(width 0.0889)
		(layer "In11.Cu")
		(net "M_M_ALERT_N")
	)
	(arc
		(start 90.375232 -94.31909)
		(mid 90.708201 -94.526638)
		(end 90.703908 -94.919038)
		(width 0.0889)
		(layer "In11.Cu")
		(net "M_M_ALERT_N")
	)
	(arc
		(start 88.986868 -91.946984)
		(mid 88.907679 -92.233599)
		(end 88.977978 -92.522548)
		(width 0.0889)
		(layer "In11.Cu")
		(net "M_M_ALERT_N")
	)
	(arc
		(start 89.845388 -94.023688)
		(mid 90.053996 -94.23562)
		(end 90.339418 -94.31909)
		(width 0.0889)
		(layer "In11.Cu")
		(net "M_M_ALERT_N")
	)
	(arc
		(start 88.986868 -91.547188)
		(mid 89.040401 -91.747086)
		(end 88.986868 -91.946984)
		(width 0.0889)
		(layer "In11.Cu")
		(net "M_M_ALERT_N")
	)
	(arc
		(start 88.986868 -92.537788)
		(mid 89.040401 -92.737686)
		(end 88.986868 -92.937584)
		(width 0.0889)
		(layer "In11.Cu")
		(net "M_M_ALERT_N")
	)
	(arc
		(start 89.516712 -93.82379)
		(mid 89.706641 -93.88166)
		(end 89.845388 -94.023688)
		(width 0.0889)
		(layer "In11.Cu")
		(net "M_M_ALERT_N")
	)
	(arc
		(start 90.703908 -94.919038)
		(mid 90.624686 -95.208156)
		(end 90.697558 -95.49892)
		(width 0.0889)
		(layer "In11.Cu")
		(net "M_M_ALERT_N")
	)
	(segment
		(start 81.549494 -152.273)
		(end 81.549494 -154.252168)
		(width 0.1651)
		(layer "F.Cu")
		(net "M_M_ACT_N")
	)
	(segment
		(start 88.353392 -90.26144)
		(end 87.781892 -90.26144)
		(width 0.1651)
		(layer "F.Cu")
		(net "M_M_ACT_N")
	)
	(via
		(at 81.549494 -154.252168)
		(size 0.508)
		(drill 0.254)
		(layers "F.Cu" "B.Cu")
		(net "M_M_ACT_N")
	)
	(via
		(at 87.781892 -90.26144)
		(size 0.508)
		(drill 0.254)
		(layers "F.Cu" "B.Cu")
		(net "M_M_ACT_N")
	)
	(via
		(at 81.549494 -150.788878)
		(size 0.4572)
		(drill 0.2032)
		(layers "F.Cu" "B.Cu")
		(net "M_M_ACT_N")
	)
	(segment
		(start 81.549494 -152.078436)
		(end 81.549494 -150.788878)
		(width 0.1651)
		(layer "B.Cu")
		(net "M_M_ACT_N")
	)
	(segment
		(start 88.133428 -99.368102)
		(end 87.831168 -99.889056)
		(width 0.0889)
		(layer "In2.Cu")
		(net "M_M_ACT_N")
	)
	(segment
		(start 88.133428 -93.424502)
		(end 88.128602 -93.433138)
		(width 0.0889)
		(layer "In2.Cu")
		(net "M_M_ACT_N")
	)
	(segment
		(start 88.128602 -92.442538)
		(end 88.122252 -92.453206)
		(width 0.0889)
		(layer "In2.Cu")
		(net "M_M_ACT_N")
	)
	(segment
		(start 82.664808 -138.126724)
		(end 82.502756 -138.288776)
		(width 0.14224)
		(layer "In2.Cu")
		(net "M_M_ACT_N")
	)
	(segment
		(start 88.128602 -96.404938)
		(end 88.122252 -96.415606)
		(width 0.0889)
		(layer "In2.Cu")
		(net "M_M_ACT_N")
	)
	(segment
		(start 82.903568 -129.361946)
		(end 82.903568 -129.9464)
		(width 0.14224)
		(layer "In2.Cu")
		(net "M_M_ACT_N")
	)
	(segment
		(start 88.128602 -95.414338)
		(end 88.122252 -95.425006)
		(width 0.0889)
		(layer "In2.Cu")
		(net "M_M_ACT_N")
	)
	(segment
		(start 82.925666 -138.126724)
		(end 82.664808 -138.126724)
		(width 0.14224)
		(layer "In2.Cu")
		(net "M_M_ACT_N")
	)
	(segment
		(start 82.492088 -136.898126)
		(end 82.492088 -137.272014)
		(width 0.14224)
		(layer "In2.Cu")
		(net "M_M_ACT_N")
	)
	(segment
		(start 81.549494 -150.559262)
		(end 81.549494 -150.788878)
		(width 0.14224)
		(layer "In2.Cu")
		(net "M_M_ACT_N")
	)
	(segment
		(start 88.122252 -94.01302)
		(end 88.128602 -94.023688)
		(width 0.0889)
		(layer "In2.Cu")
		(net "M_M_ACT_N")
	)
	(segment
		(start 88.128602 -97.395538)
		(end 88.122252 -97.406206)
		(width 0.0889)
		(layer "In2.Cu")
		(net "M_M_ACT_N")
	)
	(segment
		(start 88.128602 -91.451938)
		(end 88.122252 -91.462606)
		(width 0.0889)
		(layer "In2.Cu")
		(net "M_M_ACT_N")
	)
	(segment
		(start 82.816446 -145.023078)
		(end 82.816446 -146.518122)
		(width 0.14224)
		(layer "In2.Cu")
		(net "M_M_ACT_N")
	)
	(segment
		(start 82.854038 -130.60807)
		(end 82.854038 -131.18973)
		(width 0.14224)
		(layer "In2.Cu")
		(net "M_M_ACT_N")
	)
	(segment
		(start 88.133428 -95.405702)
		(end 88.128602 -95.414338)
		(width 0.0889)
		(layer "In2.Cu")
		(net "M_M_ACT_N")
	)
	(segment
		(start 81.262474 -153.965148)
		(end 81.549494 -154.252168)
		(width 0.14224)
		(layer "In2.Cu")
		(net "M_M_ACT_N")
	)
	(segment
		(start 82.903568 -129.9464)
		(end 82.797142 -130.052826)
		(width 0.14224)
		(layer "In2.Cu")
		(net "M_M_ACT_N")
	)
	(segment
		(start 81.549494 -150.788878)
		(end 81.262474 -151.075898)
		(width 0.14224)
		(layer "In2.Cu")
		(net "M_M_ACT_N")
	)
	(segment
		(start 83.09483 -137.95756)
		(end 82.925666 -138.126724)
		(width 0.14224)
		(layer "In2.Cu")
		(net "M_M_ACT_N")
	)
	(segment
		(start 87.831168 -99.889056)
		(end 87.831168 -101.332792)
		(width 0.0889)
		(layer "In2.Cu")
		(net "M_M_ACT_N")
	)
	(segment
		(start 88.133428 -98.377502)
		(end 88.128602 -98.386138)
		(width 0.0889)
		(layer "In2.Cu")
		(net "M_M_ACT_N")
	)
	(segment
		(start 82.502756 -138.288776)
		(end 82.502756 -138.588496)
		(width 0.14224)
		(layer "In2.Cu")
		(net "M_M_ACT_N")
	)
	(segment
		(start 81.10728 -148.227288)
		(end 81.10728 -150.117048)
		(width 0.14224)
		(layer "In2.Cu")
		(net "M_M_ACT_N")
	)
	(segment
		(start 82.797142 -130.052826)
		(end 82.797142 -130.551174)
		(width 0.14224)
		(layer "In2.Cu")
		(net "M_M_ACT_N")
	)
	(segment
		(start 81.262474 -151.075898)
		(end 81.262474 -153.965148)
		(width 0.14224)
		(layer "In2.Cu")
		(net "M_M_ACT_N")
	)
	(segment
		(start 88.133428 -96.396302)
		(end 88.128602 -96.404938)
		(width 0.0889)
		(layer "In2.Cu")
		(net "M_M_ACT_N")
	)
	(segment
		(start 82.797142 -130.551174)
		(end 82.854038 -130.60807)
		(width 0.14224)
		(layer "In2.Cu")
		(net "M_M_ACT_N")
	)
	(segment
		(start 82.812636 -131.231132)
		(end 82.812636 -136.577578)
		(width 0.14224)
		(layer "In2.Cu")
		(net "M_M_ACT_N")
	)
	(segment
		(start 82.816446 -146.518122)
		(end 81.10728 -148.227288)
		(width 0.14224)
		(layer "In2.Cu")
		(net "M_M_ACT_N")
	)
	(segment
		(start 82.502756 -138.588496)
		(end 82.812636 -138.898376)
		(width 0.14224)
		(layer "In2.Cu")
		(net "M_M_ACT_N")
	)
	(segment
		(start 84.097368 -128.168146)
		(end 82.903568 -129.361946)
		(width 0.14224)
		(layer "In2.Cu")
		(net "M_M_ACT_N")
	)
	(segment
		(start 82.854038 -131.18973)
		(end 82.812636 -131.231132)
		(width 0.14224)
		(layer "In2.Cu")
		(net "M_M_ACT_N")
	)
	(segment
		(start 82.954114 -137.426954)
		(end 83.09483 -137.56767)
		(width 0.14224)
		(layer "In2.Cu")
		(net "M_M_ACT_N")
	)
	(segment
		(start 87.831168 -122.036332)
		(end 84.097368 -125.770132)
		(width 0.14224)
		(layer "In2.Cu")
		(net "M_M_ACT_N")
	)
	(segment
		(start 88.133428 -97.386902)
		(end 88.128602 -97.395538)
		(width 0.0889)
		(layer "In2.Cu")
		(net "M_M_ACT_N")
	)
	(segment
		(start 84.097368 -125.770132)
		(end 84.097368 -128.168146)
		(width 0.14224)
		(layer "In2.Cu")
		(net "M_M_ACT_N")
	)
	(segment
		(start 82.812636 -136.577578)
		(end 82.492088 -136.898126)
		(width 0.14224)
		(layer "In2.Cu")
		(net "M_M_ACT_N")
	)
	(segment
		(start 81.10728 -150.117048)
		(end 81.549494 -150.559262)
		(width 0.14224)
		(layer "In2.Cu")
		(net "M_M_ACT_N")
	)
	(segment
		(start 82.812636 -138.898376)
		(end 82.812636 -145.019268)
		(width 0.14224)
		(layer "In2.Cu")
		(net "M_M_ACT_N")
	)
	(segment
		(start 88.128602 -98.386138)
		(end 88.122252 -98.396806)
		(width 0.0889)
		(layer "In2.Cu")
		(net "M_M_ACT_N")
	)
	(segment
		(start 82.647028 -137.426954)
		(end 82.954114 -137.426954)
		(width 0.14224)
		(layer "In2.Cu")
		(net "M_M_ACT_N")
	)
	(segment
		(start 87.831168 -101.332792)
		(end 87.831168 -122.036332)
		(width 0.14224)
		(layer "In2.Cu")
		(net "M_M_ACT_N")
	)
	(segment
		(start 88.133428 -92.433902)
		(end 88.128602 -92.442538)
		(width 0.0889)
		(layer "In2.Cu")
		(net "M_M_ACT_N")
	)
	(segment
		(start 87.781892 -90.26144)
		(end 88.063324 -90.883994)
		(width 0.0889)
		(layer "In2.Cu")
		(net "M_M_ACT_N")
	)
	(segment
		(start 82.492088 -137.272014)
		(end 82.647028 -137.426954)
		(width 0.14224)
		(layer "In2.Cu")
		(net "M_M_ACT_N")
	)
	(segment
		(start 88.133428 -91.443302)
		(end 88.128602 -91.451938)
		(width 0.0889)
		(layer "In2.Cu")
		(net "M_M_ACT_N")
	)
	(segment
		(start 83.09483 -137.56767)
		(end 83.09483 -137.95756)
		(width 0.14224)
		(layer "In2.Cu")
		(net "M_M_ACT_N")
	)
	(segment
		(start 82.812636 -145.019268)
		(end 82.816446 -145.023078)
		(width 0.14224)
		(layer "In2.Cu")
		(net "M_M_ACT_N")
	)
	(arc
		(start 88.128602 -91.051888)
		(mid 88.182072 -91.246951)
		(end 88.133428 -91.443302)
		(width 0.0889)
		(layer "In2.Cu")
		(net "M_M_ACT_N")
	)
	(arc
		(start 88.128602 -94.423484)
		(mid 88.049471 -94.718886)
		(end 88.128602 -95.014288)
		(width 0.0889)
		(layer "In2.Cu")
		(net "M_M_ACT_N")
	)
	(arc
		(start 88.128602 -96.995488)
		(mid 88.182072 -97.190551)
		(end 88.133428 -97.386902)
		(width 0.0889)
		(layer "In2.Cu")
		(net "M_M_ACT_N")
	)
	(arc
		(start 88.122252 -95.425006)
		(mid 88.049454 -95.715769)
		(end 88.128602 -96.004888)
		(width 0.0889)
		(layer "In2.Cu")
		(net "M_M_ACT_N")
	)
	(arc
		(start 88.122252 -98.396806)
		(mid 88.049454 -98.687569)
		(end 88.128602 -98.976688)
		(width 0.0889)
		(layer "In2.Cu")
		(net "M_M_ACT_N")
	)
	(arc
		(start 88.063324 -90.883994)
		(mid 88.089532 -90.970441)
		(end 88.128602 -91.051888)
		(width 0.0889)
		(layer "In2.Cu")
		(net "M_M_ACT_N")
	)
	(arc
		(start 88.128602 -94.023688)
		(mid 88.182101 -94.223586)
		(end 88.128602 -94.423484)
		(width 0.0889)
		(layer "In2.Cu")
		(net "M_M_ACT_N")
	)
	(arc
		(start 88.122252 -97.406206)
		(mid 88.049454 -97.696969)
		(end 88.128602 -97.986088)
		(width 0.0889)
		(layer "In2.Cu")
		(net "M_M_ACT_N")
	)
	(arc
		(start 88.128602 -93.033088)
		(mid 88.182072 -93.228151)
		(end 88.133428 -93.424502)
		(width 0.0889)
		(layer "In2.Cu")
		(net "M_M_ACT_N")
	)
	(arc
		(start 88.122252 -91.462606)
		(mid 88.049454 -91.753369)
		(end 88.128602 -92.042488)
		(width 0.0889)
		(layer "In2.Cu")
		(net "M_M_ACT_N")
	)
	(arc
		(start 88.122252 -92.453206)
		(mid 88.049454 -92.743969)
		(end 88.128602 -93.033088)
		(width 0.0889)
		(layer "In2.Cu")
		(net "M_M_ACT_N")
	)
	(arc
		(start 88.122252 -96.415606)
		(mid 88.049454 -96.706369)
		(end 88.128602 -96.995488)
		(width 0.0889)
		(layer "In2.Cu")
		(net "M_M_ACT_N")
	)
	(arc
		(start 88.128602 -97.986088)
		(mid 88.182072 -98.181151)
		(end 88.133428 -98.377502)
		(width 0.0889)
		(layer "In2.Cu")
		(net "M_M_ACT_N")
	)
	(arc
		(start 88.128602 -95.014288)
		(mid 88.182072 -95.209351)
		(end 88.133428 -95.405702)
		(width 0.0889)
		(layer "In2.Cu")
		(net "M_M_ACT_N")
	)
	(arc
		(start 88.128602 -92.042488)
		(mid 88.182072 -92.237551)
		(end 88.133428 -92.433902)
		(width 0.0889)
		(layer "In2.Cu")
		(net "M_M_ACT_N")
	)
	(arc
		(start 88.128602 -98.976688)
		(mid 88.182072 -99.171751)
		(end 88.133428 -99.368102)
		(width 0.0889)
		(layer "In2.Cu")
		(net "M_M_ACT_N")
	)
	(arc
		(start 88.128602 -93.433138)
		(mid 88.04938 -93.722256)
		(end 88.122252 -94.01302)
		(width 0.0889)
		(layer "In2.Cu")
		(net "M_M_ACT_N")
	)
	(arc
		(start 88.128602 -96.004888)
		(mid 88.182072 -96.199951)
		(end 88.133428 -96.396302)
		(width 0.0889)
		(layer "In2.Cu")
		(net "M_M_ACT_N")
	)
	(segment
		(start 96.079818 -97.690686)
		(end 95.508318 -97.690686)
		(width 0.1651)
		(layer "F.Cu")
		(net "M_L_PAR")
	)
	(segment
		(start 100.249482 -146.013932)
		(end 100.249736 -146.013678)
		(width 0.1651)
		(layer "F.Cu")
		(net "M_L_PAR")
	)
	(segment
		(start 100.249736 -146.013678)
		(end 100.249736 -145.988278)
		(width 0.1651)
		(layer "F.Cu")
		(net "M_L_PAR")
	)
	(segment
		(start 100.249482 -147.27174)
		(end 100.249482 -146.013932)
		(width 0.1651)
		(layer "F.Cu")
		(net "M_L_PAR")
	)
	(via
		(at 95.508318 -97.690686)
		(size 0.508)
		(drill 0.254)
		(layers "F.Cu" "B.Cu")
		(net "M_L_PAR")
	)
	(via
		(at 100.249736 -145.988278)
		(size 0.4572)
		(drill 0.2032)
		(layers "F.Cu" "B.Cu")
		(net "M_L_PAR")
	)
	(via
		(at 100.249228 -139.850368)
		(size 0.508)
		(drill 0.254)
		(layers "F.Cu" "B.Cu")
		(net "M_L_PAR")
	)
	(segment
		(start 100.249482 -137.877296)
		(end 100.249482 -139.850114)
		(width 0.1651)
		(layer "B.Cu")
		(net "M_L_PAR")
	)
	(segment
		(start 100.249482 -139.850114)
		(end 100.249228 -139.850368)
		(width 0.1651)
		(layer "B.Cu")
		(net "M_L_PAR")
	)
	(segment
		(start 100.249228 -140.48486)
		(end 100.68433 -140.919962)
		(width 0.14224)
		(layer "In4.Cu")
		(net "M_L_PAR")
	)
	(segment
		(start 96.009968 -101.565456)
		(end 97.076768 -102.632256)
		(width 0.0889)
		(layer "In4.Cu")
		(net "M_L_PAR")
	)
	(segment
		(start 100.531168 -144.2212)
		(end 100.759768 -144.4498)
		(width 0.14224)
		(layer "In4.Cu")
		(net "M_L_PAR")
	)
	(segment
		(start 100.249228 -139.850368)
		(end 100.249228 -140.48486)
		(width 0.14224)
		(layer "In4.Cu")
		(net "M_L_PAR")
	)
	(segment
		(start 100.68433 -140.919962)
		(end 100.68433 -141.528038)
		(width 0.14224)
		(layer "In4.Cu")
		(net "M_L_PAR")
	)
	(segment
		(start 100.531168 -141.6812)
		(end 100.531168 -144.2212)
		(width 0.14224)
		(layer "In4.Cu")
		(net "M_L_PAR")
	)
	(segment
		(start 95.837756 -98.45167)
		(end 95.859854 -98.490024)
		(width 0.0889)
		(layer "In4.Cu")
		(net "M_L_PAR")
	)
	(segment
		(start 100.759768 -144.8562)
		(end 100.249228 -145.36674)
		(width 0.14224)
		(layer "In4.Cu")
		(net "M_L_PAR")
	)
	(segment
		(start 97.076768 -126.1364)
		(end 98.549968 -127.6096)
		(width 0.14224)
		(layer "In4.Cu")
		(net "M_L_PAR")
	)
	(segment
		(start 99.792028 -129.15646)
		(end 99.792028 -139.393168)
		(width 0.14224)
		(layer "In4.Cu")
		(net "M_L_PAR")
	)
	(segment
		(start 98.549968 -127.9144)
		(end 99.792028 -129.15646)
		(width 0.14224)
		(layer "In4.Cu")
		(net "M_L_PAR")
	)
	(segment
		(start 100.68433 -141.528038)
		(end 100.531168 -141.6812)
		(width 0.14224)
		(layer "In4.Cu")
		(net "M_L_PAR")
	)
	(segment
		(start 98.549968 -127.6096)
		(end 98.549968 -127.9144)
		(width 0.14224)
		(layer "In4.Cu")
		(net "M_L_PAR")
	)
	(segment
		(start 97.076768 -103.388922)
		(end 97.076768 -126.1364)
		(width 0.14224)
		(layer "In4.Cu")
		(net "M_L_PAR")
	)
	(segment
		(start 97.076768 -102.632256)
		(end 97.076768 -103.388922)
		(width 0.0889)
		(layer "In4.Cu")
		(net "M_L_PAR")
	)
	(segment
		(start 95.508318 -97.690686)
		(end 95.837756 -98.45167)
		(width 0.0889)
		(layer "In4.Cu")
		(net "M_L_PAR")
	)
	(segment
		(start 100.759768 -144.4498)
		(end 100.759768 -144.8562)
		(width 0.14224)
		(layer "In4.Cu")
		(net "M_L_PAR")
	)
	(segment
		(start 100.249228 -145.98777)
		(end 100.249736 -145.988278)
		(width 0.14224)
		(layer "In4.Cu")
		(net "M_L_PAR")
	)
	(segment
		(start 100.249228 -145.36674)
		(end 100.249228 -145.98777)
		(width 0.14224)
		(layer "In4.Cu")
		(net "M_L_PAR")
	)
	(segment
		(start 96.009968 -100.0506)
		(end 96.009968 -101.565456)
		(width 0.0889)
		(layer "In4.Cu")
		(net "M_L_PAR")
	)
	(segment
		(start 99.792028 -139.393168)
		(end 100.249228 -139.850368)
		(width 0.14224)
		(layer "In4.Cu")
		(net "M_L_PAR")
	)
	(arc
		(start 95.859854 -98.490024)
		(mid 95.908609 -98.686376)
		(end 95.855028 -98.881438)
		(width 0.0889)
		(layer "In4.Cu")
		(net "M_L_PAR")
	)
	(arc
		(start 95.855028 -98.881438)
		(mid 95.775897 -99.17684)
		(end 95.855028 -99.472242)
		(width 0.0889)
		(layer "In4.Cu")
		(net "M_L_PAR")
	)
	(arc
		(start 95.855028 -99.472242)
		(mid 95.970556 -99.751225)
		(end 96.009968 -100.0506)
		(width 0.0889)
		(layer "In4.Cu")
		(net "M_L_PAR")
	)
	(segment
		(start 101.230684 -94.718886)
		(end 100.659184 -94.718886)
		(width 0.1016)
		(layer "F.Cu")
		(net "M_L_ODT<3>")
	)
	(via
		(at 111.299498 -141.188186)
		(size 0.4572)
		(drill 0.2032)
		(layers "F.Cu" "B.Cu")
		(net "M_L_ODT<3>")
	)
	(via
		(at 100.659184 -94.718886)
		(size 0.508)
		(drill 0.254)
		(layers "F.Cu" "B.Cu")
		(net "M_L_ODT<3>")
	)
	(segment
		(start 111.299498 -142.477236)
		(end 111.299498 -141.188186)
		(width 0.1651)
		(layer "B.Cu")
		(net "M_L_ODT<3>")
	)
	(segment
		(start 111.299498 -139.90193)
		(end 110.872016 -139.474448)
		(width 0.14224)
		(layer "In4.Cu")
		(net "M_L_ODT<3>")
	)
	(segment
		(start 101.177344 -96.415606)
		(end 101.170994 -96.404938)
		(width 0.0889)
		(layer "In4.Cu")
		(net "M_L_ODT<3>")
	)
	(segment
		(start 110.039658 -136.100058)
		(end 109.670342 -135.730742)
		(width 0.14224)
		(layer "In4.Cu")
		(net "M_L_ODT<3>")
	)
	(segment
		(start 101.801168 -97.7138)
		(end 101.683058 -97.59569)
		(width 0.0889)
		(layer "In4.Cu")
		(net "M_L_ODT<3>")
	)
	(segment
		(start 109.960664 -131.933696)
		(end 109.960664 -131.362704)
		(width 0.14224)
		(layer "In4.Cu")
		(net "M_L_ODT<3>")
	)
	(segment
		(start 101.170994 -96.404938)
		(end 101.166168 -96.396302)
		(width 0.0889)
		(layer "In4.Cu")
		(net "M_L_ODT<3>")
	)
	(segment
		(start 110.074456 -131.248912)
		(end 110.074456 -130.650488)
		(width 0.14224)
		(layer "In4.Cu")
		(net "M_L_ODT<3>")
	)
	(segment
		(start 109.960664 -131.362704)
		(end 110.074456 -131.248912)
		(width 0.14224)
		(layer "In4.Cu")
		(net "M_L_ODT<3>")
	)
	(segment
		(start 110.872016 -139.474448)
		(end 110.872016 -138.890248)
		(width 0.14224)
		(layer "In4.Cu")
		(net "M_L_ODT<3>")
	)
	(segment
		(start 110.05312 -129.822448)
		(end 110.05312 -128.89611)
		(width 0.14224)
		(layer "In4.Cu")
		(net "M_L_ODT<3>")
	)
	(segment
		(start 110.036102 -134.665466)
		(end 110.036102 -132.009134)
		(width 0.14224)
		(layer "In4.Cu")
		(net "M_L_ODT<3>")
	)
	(segment
		(start 102.893368 -101.9048)
		(end 102.893368 -98.552)
		(width 0.0889)
		(layer "In4.Cu")
		(net "M_L_ODT<3>")
	)
	(segment
		(start 110.872016 -138.890248)
		(end 110.039658 -138.05789)
		(width 0.14224)
		(layer "In4.Cu")
		(net "M_L_ODT<3>")
	)
	(segment
		(start 109.954568 -129.921)
		(end 110.05312 -129.822448)
		(width 0.14224)
		(layer "In4.Cu")
		(net "M_L_ODT<3>")
	)
	(segment
		(start 101.177344 -95.425006)
		(end 101.170994 -95.414338)
		(width 0.0889)
		(layer "In4.Cu")
		(net "M_L_ODT<3>")
	)
	(segment
		(start 103.172768 -103.056436)
		(end 103.172768 -102.8192)
		(width 0.0889)
		(layer "In4.Cu")
		(net "M_L_ODT<3>")
	)
	(segment
		(start 110.074456 -130.650488)
		(end 109.954568 -130.5306)
		(width 0.14224)
		(layer "In4.Cu")
		(net "M_L_ODT<3>")
	)
	(segment
		(start 109.954568 -130.5306)
		(end 109.954568 -129.921)
		(width 0.14224)
		(layer "In4.Cu")
		(net "M_L_ODT<3>")
	)
	(segment
		(start 102.055168 -97.7138)
		(end 101.801168 -97.7138)
		(width 0.0889)
		(layer "In4.Cu")
		(net "M_L_ODT<3>")
	)
	(segment
		(start 103.172768 -121.0564)
		(end 103.172768 -103.056436)
		(width 0.14224)
		(layer "In4.Cu")
		(net "M_L_ODT<3>")
	)
	(segment
		(start 101.683058 -97.59569)
		(end 101.506528 -97.59569)
		(width 0.0889)
		(layer "In4.Cu")
		(net "M_L_ODT<3>")
	)
	(segment
		(start 103.172768 -102.8192)
		(end 102.791768 -102.4382)
		(width 0.0889)
		(layer "In4.Cu")
		(net "M_L_ODT<3>")
	)
	(segment
		(start 111.299498 -141.188186)
		(end 111.299498 -139.90193)
		(width 0.14224)
		(layer "In4.Cu")
		(net "M_L_ODT<3>")
	)
	(segment
		(start 109.670342 -135.031226)
		(end 110.036102 -134.665466)
		(width 0.14224)
		(layer "In4.Cu")
		(net "M_L_ODT<3>")
	)
	(segment
		(start 110.05312 -128.89611)
		(end 106.228388 -125.071378)
		(width 0.14224)
		(layer "In4.Cu")
		(net "M_L_ODT<3>")
	)
	(segment
		(start 102.893368 -98.552)
		(end 102.055168 -97.7138)
		(width 0.0889)
		(layer "In4.Cu")
		(net "M_L_ODT<3>")
	)
	(segment
		(start 110.039658 -138.05789)
		(end 110.039658 -136.100058)
		(width 0.14224)
		(layer "In4.Cu")
		(net "M_L_ODT<3>")
	)
	(segment
		(start 106.228388 -124.11202)
		(end 103.172768 -121.0564)
		(width 0.14224)
		(layer "In4.Cu")
		(net "M_L_ODT<3>")
	)
	(segment
		(start 102.791768 -102.0064)
		(end 102.893368 -101.9048)
		(width 0.0889)
		(layer "In4.Cu")
		(net "M_L_ODT<3>")
	)
	(segment
		(start 102.791768 -102.4382)
		(end 102.791768 -102.0064)
		(width 0.0889)
		(layer "In4.Cu")
		(net "M_L_ODT<3>")
	)
	(segment
		(start 106.228388 -125.071378)
		(end 106.228388 -124.11202)
		(width 0.14224)
		(layer "In4.Cu")
		(net "M_L_ODT<3>")
	)
	(segment
		(start 101.15423 -95.384874)
		(end 100.659184 -94.718886)
		(width 0.0889)
		(layer "In4.Cu")
		(net "M_L_ODT<3>")
	)
	(segment
		(start 101.170994 -95.414338)
		(end 101.15423 -95.384874)
		(width 0.0889)
		(layer "In4.Cu")
		(net "M_L_ODT<3>")
	)
	(segment
		(start 110.036102 -132.009134)
		(end 109.960664 -131.933696)
		(width 0.14224)
		(layer "In4.Cu")
		(net "M_L_ODT<3>")
	)
	(segment
		(start 109.670342 -135.730742)
		(end 109.670342 -135.031226)
		(width 0.14224)
		(layer "In4.Cu")
		(net "M_L_ODT<3>")
	)
	(arc
		(start 101.170994 -96.995488)
		(mid 101.250216 -96.70637)
		(end 101.177344 -96.415606)
		(width 0.0889)
		(layer "In4.Cu")
		(net "M_L_ODT<3>")
	)
	(arc
		(start 101.166168 -96.396302)
		(mid 101.117413 -96.19995)
		(end 101.170994 -96.004888)
		(width 0.0889)
		(layer "In4.Cu")
		(net "M_L_ODT<3>")
	)
	(arc
		(start 101.170994 -96.004888)
		(mid 101.250216 -95.71577)
		(end 101.177344 -95.425006)
		(width 0.0889)
		(layer "In4.Cu")
		(net "M_L_ODT<3>")
	)
	(arc
		(start 101.506528 -97.59569)
		(mid 101.168359 -97.390892)
		(end 101.170994 -96.995488)
		(width 0.0889)
		(layer "In4.Cu")
		(net "M_L_ODT<3>")
	)
	(segment
		(start 99.513898 -96.700086)
		(end 98.942398 -96.700086)
		(width 0.1016)
		(layer "F.Cu")
		(net "M_L_ODT<2>")
	)
	(via
		(at 98.942398 -96.700086)
		(size 0.508)
		(drill 0.254)
		(layers "F.Cu" "B.Cu")
		(net "M_L_ODT<2>")
	)
	(via
		(at 107.899454 -141.183868)
		(size 0.4572)
		(drill 0.2032)
		(layers "F.Cu" "B.Cu")
		(net "M_L_ODT<2>")
	)
	(segment
		(start 107.899454 -142.477236)
		(end 107.899454 -141.183868)
		(width 0.1651)
		(layer "B.Cu")
		(net "M_L_ODT<2>")
	)
	(segment
		(start 107.46486 -139.420092)
		(end 107.693968 -139.6492)
		(width 0.14224)
		(layer "In4.Cu")
		(net "M_L_ODT<2>")
	)
	(segment
		(start 107.46486 -138.912092)
		(end 107.46486 -139.420092)
		(width 0.14224)
		(layer "In4.Cu")
		(net "M_L_ODT<2>")
	)
	(segment
		(start 101.140768 -103.2002)
		(end 101.140768 -103.411528)
		(width 0.0889)
		(layer "In4.Cu")
		(net "M_L_ODT<2>")
	)
	(segment
		(start 106.576368 -134.6708)
		(end 106.576368 -135.972804)
		(width 0.14224)
		(layer "In4.Cu")
		(net "M_L_ODT<2>")
	)
	(segment
		(start 99.437952 -97.366836)
		(end 99.454208 -97.395538)
		(width 0.0889)
		(layer "In4.Cu")
		(net "M_L_ODT<2>")
	)
	(segment
		(start 106.636566 -134.070598)
		(end 106.636566 -134.610602)
		(width 0.14224)
		(layer "In4.Cu")
		(net "M_L_ODT<2>")
	)
	(segment
		(start 101.140768 -121.657872)
		(end 104.196388 -124.713492)
		(width 0.14224)
		(layer "In4.Cu")
		(net "M_L_ODT<2>")
	)
	(segment
		(start 99.388168 -99.4156)
		(end 100.505768 -100.5332)
		(width 0.0889)
		(layer "In4.Cu")
		(net "M_L_ODT<2>")
	)
	(segment
		(start 100.505768 -102.5652)
		(end 101.140768 -103.2002)
		(width 0.0889)
		(layer "In4.Cu")
		(net "M_L_ODT<2>")
	)
	(segment
		(start 106.576368 -135.972804)
		(end 106.636566 -136.033002)
		(width 0.14224)
		(layer "In4.Cu")
		(net "M_L_ODT<2>")
	)
	(segment
		(start 107.693968 -140.323062)
		(end 107.899454 -140.528548)
		(width 0.14224)
		(layer "In4.Cu")
		(net "M_L_ODT<2>")
	)
	(segment
		(start 106.636566 -134.610602)
		(end 106.576368 -134.6708)
		(width 0.14224)
		(layer "In4.Cu")
		(net "M_L_ODT<2>")
	)
	(segment
		(start 106.644948 -129.85242)
		(end 106.551476 -129.945892)
		(width 0.14224)
		(layer "In4.Cu")
		(net "M_L_ODT<2>")
	)
	(segment
		(start 106.636566 -136.033002)
		(end 106.636566 -138.083798)
		(width 0.14224)
		(layer "In4.Cu")
		(net "M_L_ODT<2>")
	)
	(segment
		(start 106.56697 -134.001002)
		(end 106.636566 -134.070598)
		(width 0.14224)
		(layer "In4.Cu")
		(net "M_L_ODT<2>")
	)
	(segment
		(start 99.454208 -98.386138)
		(end 99.463098 -98.401378)
		(width 0.0889)
		(layer "In4.Cu")
		(net "M_L_ODT<2>")
	)
	(segment
		(start 98.942398 -96.700086)
		(end 99.437952 -97.366836)
		(width 0.0889)
		(layer "In4.Cu")
		(net "M_L_ODT<2>")
	)
	(segment
		(start 106.66349 -131.205478)
		(end 106.56697 -131.301998)
		(width 0.14224)
		(layer "In4.Cu")
		(net "M_L_ODT<2>")
	)
	(segment
		(start 104.196388 -124.713492)
		(end 104.196388 -125.913642)
		(width 0.14224)
		(layer "In4.Cu")
		(net "M_L_ODT<2>")
	)
	(segment
		(start 104.196388 -125.913642)
		(end 106.644948 -128.362202)
		(width 0.14224)
		(layer "In4.Cu")
		(net "M_L_ODT<2>")
	)
	(segment
		(start 106.551476 -129.945892)
		(end 106.551476 -130.531108)
		(width 0.14224)
		(layer "In4.Cu")
		(net "M_L_ODT<2>")
	)
	(segment
		(start 106.644948 -128.362202)
		(end 106.644948 -129.85242)
		(width 0.14224)
		(layer "In4.Cu")
		(net "M_L_ODT<2>")
	)
	(segment
		(start 99.388168 -99.223322)
		(end 99.388168 -99.4156)
		(width 0.0889)
		(layer "In4.Cu")
		(net "M_L_ODT<2>")
	)
	(segment
		(start 106.636566 -138.083798)
		(end 107.46486 -138.912092)
		(width 0.14224)
		(layer "In4.Cu")
		(net "M_L_ODT<2>")
	)
	(segment
		(start 106.56697 -131.301998)
		(end 106.56697 -134.001002)
		(width 0.14224)
		(layer "In4.Cu")
		(net "M_L_ODT<2>")
	)
	(segment
		(start 107.693968 -139.6492)
		(end 107.693968 -140.323062)
		(width 0.14224)
		(layer "In4.Cu")
		(net "M_L_ODT<2>")
	)
	(segment
		(start 106.66349 -130.643122)
		(end 106.66349 -131.205478)
		(width 0.14224)
		(layer "In4.Cu")
		(net "M_L_ODT<2>")
	)
	(segment
		(start 101.140768 -103.411528)
		(end 101.140768 -121.657872)
		(width 0.14224)
		(layer "In4.Cu")
		(net "M_L_ODT<2>")
	)
	(segment
		(start 107.899454 -140.528548)
		(end 107.899454 -141.183868)
		(width 0.14224)
		(layer "In4.Cu")
		(net "M_L_ODT<2>")
	)
	(segment
		(start 100.505768 -100.5332)
		(end 100.505768 -102.5652)
		(width 0.0889)
		(layer "In4.Cu")
		(net "M_L_ODT<2>")
	)
	(segment
		(start 99.454208 -97.395538)
		(end 99.463098 -97.410778)
		(width 0.0889)
		(layer "In4.Cu")
		(net "M_L_ODT<2>")
	)
	(segment
		(start 106.551476 -130.531108)
		(end 106.66349 -130.643122)
		(width 0.14224)
		(layer "In4.Cu")
		(net "M_L_ODT<2>")
	)
	(arc
		(start 99.463098 -97.410778)
		(mid 99.533495 -97.699729)
		(end 99.454208 -97.986342)
		(width 0.0889)
		(layer "In4.Cu")
		(net "M_L_ODT<2>")
	)
	(arc
		(start 99.454208 -98.976942)
		(mid 99.404954 -99.095782)
		(end 99.388168 -99.223322)
		(width 0.0889)
		(layer "In4.Cu")
		(net "M_L_ODT<2>")
	)
	(arc
		(start 99.463098 -98.401378)
		(mid 99.533495 -98.690329)
		(end 99.454208 -98.976942)
		(width 0.0889)
		(layer "In4.Cu")
		(net "M_L_ODT<2>")
	)
	(arc
		(start 99.454208 -97.986342)
		(mid 99.400675 -98.18624)
		(end 99.454208 -98.386138)
		(width 0.0889)
		(layer "In4.Cu")
		(net "M_L_ODT<2>")
	)
	(segment
		(start 111.299498 -142.6718)
		(end 111.299498 -143.97228)
		(width 0.1651)
		(layer "F.Cu")
		(net "M_L_ODT<1>")
	)
	(segment
		(start 111.299498 -143.97228)
		(end 111.300006 -143.972788)
		(width 0.1651)
		(layer "F.Cu")
		(net "M_L_ODT<1>")
	)
	(segment
		(start 100.372164 -95.21444)
		(end 99.800664 -95.21444)
		(width 0.1016)
		(layer "F.Cu")
		(net "M_L_ODT<1>")
	)
	(via
		(at 111.300006 -143.972788)
		(size 0.4572)
		(drill 0.2032)
		(layers "F.Cu" "B.Cu")
		(net "M_L_ODT<1>")
	)
	(via
		(at 99.800664 -95.21444)
		(size 0.508)
		(drill 0.254)
		(layers "F.Cu" "B.Cu")
		(net "M_L_ODT<1>")
	)
	(segment
		(start 109.065568 -131.1656)
		(end 109.252258 -131.35229)
		(width 0.14224)
		(layer "In4.Cu")
		(net "M_L_ODT<1>")
	)
	(segment
		(start 102.664768 -121.224548)
		(end 105.720388 -124.280168)
		(width 0.14224)
		(layer "In4.Cu")
		(net "M_L_ODT<1>")
	)
	(segment
		(start 108.963968 -128.525524)
		(end 108.963968 -129.6416)
		(width 0.14224)
		(layer "In4.Cu")
		(net "M_L_ODT<1>")
	)
	(segment
		(start 109.252258 -131.35229)
		(end 109.252258 -131.91871)
		(width 0.14224)
		(layer "In4.Cu")
		(net "M_L_ODT<1>")
	)
	(segment
		(start 110.036102 -138.816334)
		(end 110.036102 -139.403074)
		(width 0.14224)
		(layer "In4.Cu")
		(net "M_L_ODT<1>")
	)
	(segment
		(start 109.252258 -131.91871)
		(end 109.166406 -132.004562)
		(width 0.14224)
		(layer "In4.Cu")
		(net "M_L_ODT<1>")
	)
	(segment
		(start 102.664768 -103.2256)
		(end 102.664768 -103.547926)
		(width 0.0889)
		(layer "In4.Cu")
		(net "M_L_ODT<1>")
	)
	(segment
		(start 99.800664 -95.21444)
		(end 100.6221 -95.309436)
		(width 0.0889)
		(layer "In4.Cu")
		(net "M_L_ODT<1>")
	)
	(segment
		(start 101.059488 -97.685606)
		(end 101.059488 -99.48672)
		(width 0.0889)
		(layer "In4.Cu")
		(net "M_L_ODT<1>")
	)
	(segment
		(start 100.999544 -96.48952)
		(end 101.005894 -96.500188)
		(width 0.0889)
		(layer "In4.Cu")
		(net "M_L_ODT<1>")
	)
	(segment
		(start 110.883192 -143.555974)
		(end 111.300006 -143.972788)
		(width 0.14224)
		(layer "In4.Cu")
		(net "M_L_ODT<1>")
	)
	(segment
		(start 101.059488 -99.48672)
		(end 101.470968 -99.8982)
		(width 0.0889)
		(layer "In4.Cu")
		(net "M_L_ODT<1>")
	)
	(segment
		(start 101.953568 -102.5144)
		(end 102.664768 -103.2256)
		(width 0.0889)
		(layer "In4.Cu")
		(net "M_L_ODT<1>")
	)
	(segment
		(start 109.065568 -130.7338)
		(end 109.065568 -131.1656)
		(width 0.14224)
		(layer "In4.Cu")
		(net "M_L_ODT<1>")
	)
	(segment
		(start 101.005894 -96.500188)
		(end 101.01072 -96.508824)
		(width 0.0889)
		(layer "In4.Cu")
		(net "M_L_ODT<1>")
	)
	(segment
		(start 110.036102 -139.403074)
		(end 110.67415 -140.041122)
		(width 0.14224)
		(layer "In4.Cu")
		(net "M_L_ODT<1>")
	)
	(segment
		(start 109.166406 -132.004562)
		(end 109.166406 -135.408162)
		(width 0.14224)
		(layer "In4.Cu")
		(net "M_L_ODT<1>")
	)
	(segment
		(start 101.470968 -101.5746)
		(end 101.953568 -102.0572)
		(width 0.0889)
		(layer "In4.Cu")
		(net "M_L_ODT<1>")
	)
	(segment
		(start 100.999544 -97.48012)
		(end 101.005894 -97.490788)
		(width 0.0889)
		(layer "In4.Cu")
		(net "M_L_ODT<1>")
	)
	(segment
		(start 110.67415 -140.041122)
		(end 110.67415 -140.724382)
		(width 0.14224)
		(layer "In4.Cu")
		(net "M_L_ODT<1>")
	)
	(segment
		(start 109.217968 -129.8956)
		(end 109.217968 -130.5814)
		(width 0.14224)
		(layer "In4.Cu")
		(net "M_L_ODT<1>")
	)
	(segment
		(start 109.15904 -137.939272)
		(end 110.036102 -138.816334)
		(width 0.14224)
		(layer "In4.Cu")
		(net "M_L_ODT<1>")
	)
	(segment
		(start 100.6221 -95.309436)
		(end 100.67036 -95.309436)
		(width 0.0889)
		(layer "In4.Cu")
		(net "M_L_ODT<1>")
	)
	(segment
		(start 101.953568 -102.0572)
		(end 101.953568 -102.5144)
		(width 0.0889)
		(layer "In4.Cu")
		(net "M_L_ODT<1>")
	)
	(segment
		(start 110.883192 -140.933424)
		(end 110.883192 -143.555974)
		(width 0.14224)
		(layer "In4.Cu")
		(net "M_L_ODT<1>")
	)
	(segment
		(start 109.166406 -135.408162)
		(end 109.15904 -135.415528)
		(width 0.14224)
		(layer "In4.Cu")
		(net "M_L_ODT<1>")
	)
	(segment
		(start 109.217968 -130.5814)
		(end 109.065568 -130.7338)
		(width 0.14224)
		(layer "In4.Cu")
		(net "M_L_ODT<1>")
	)
	(segment
		(start 108.963968 -129.6416)
		(end 109.217968 -129.8956)
		(width 0.14224)
		(layer "In4.Cu")
		(net "M_L_ODT<1>")
	)
	(segment
		(start 105.720388 -124.280168)
		(end 105.720388 -125.281944)
		(width 0.14224)
		(layer "In4.Cu")
		(net "M_L_ODT<1>")
	)
	(segment
		(start 110.67415 -140.724382)
		(end 110.883192 -140.933424)
		(width 0.14224)
		(layer "In4.Cu")
		(net "M_L_ODT<1>")
	)
	(segment
		(start 105.720388 -125.281944)
		(end 108.963968 -128.525524)
		(width 0.14224)
		(layer "In4.Cu")
		(net "M_L_ODT<1>")
	)
	(segment
		(start 101.470968 -99.8982)
		(end 101.470968 -101.5746)
		(width 0.0889)
		(layer "In4.Cu")
		(net "M_L_ODT<1>")
	)
	(segment
		(start 102.664768 -103.547926)
		(end 102.664768 -121.224548)
		(width 0.14224)
		(layer "In4.Cu")
		(net "M_L_ODT<1>")
	)
	(segment
		(start 109.15904 -135.415528)
		(end 109.15904 -137.939272)
		(width 0.14224)
		(layer "In4.Cu")
		(net "M_L_ODT<1>")
	)
	(arc
		(start 100.67036 -95.309436)
		(mid 101.008529 -95.514234)
		(end 101.005894 -95.909638)
		(width 0.0889)
		(layer "In4.Cu")
		(net "M_L_ODT<1>")
	)
	(arc
		(start 101.01072 -96.508824)
		(mid 101.059475 -96.705176)
		(end 101.005894 -96.900238)
		(width 0.0889)
		(layer "In4.Cu")
		(net "M_L_ODT<1>")
	)
	(arc
		(start 101.005894 -95.909638)
		(mid 100.926672 -96.198756)
		(end 100.999544 -96.48952)
		(width 0.0889)
		(layer "In4.Cu")
		(net "M_L_ODT<1>")
	)
	(arc
		(start 101.005894 -97.490788)
		(mid 101.045833 -97.58458)
		(end 101.059488 -97.685606)
		(width 0.0889)
		(layer "In4.Cu")
		(net "M_L_ODT<1>")
	)
	(arc
		(start 101.005894 -96.900238)
		(mid 100.926672 -97.189356)
		(end 100.999544 -97.48012)
		(width 0.0889)
		(layer "In4.Cu")
		(net "M_L_ODT<1>")
	)
	(segment
		(start 98.655378 -96.20504)
		(end 98.083878 -96.20504)
		(width 0.1016)
		(layer "F.Cu")
		(net "M_L_ODT<0>")
	)
	(segment
		(start 107.899454 -142.6718)
		(end 107.899454 -143.968978)
		(width 0.1651)
		(layer "F.Cu")
		(net "M_L_ODT<0>")
	)
	(via
		(at 98.083878 -96.20504)
		(size 0.508)
		(drill 0.254)
		(layers "F.Cu" "B.Cu")
		(net "M_L_ODT<0>")
	)
	(via
		(at 107.899454 -143.968978)
		(size 0.508)
		(drill 0.254)
		(layers "F.Cu" "B.Cu")
		(net "M_L_ODT<0>")
	)
	(segment
		(start 100.632768 -103.178356)
		(end 100.632768 -103.36149)
		(width 0.0889)
		(layer "In4.Cu")
		(net "M_L_ODT<0>")
	)
	(segment
		(start 106.852974 -140.672058)
		(end 107.170474 -140.672058)
		(width 0.14224)
		(layer "In4.Cu")
		(net "M_L_ODT<0>")
	)
	(segment
		(start 107.47248 -140.974064)
		(end 107.47248 -143.542004)
		(width 0.14224)
		(layer "In4.Cu")
		(net "M_L_ODT<0>")
	)
	(segment
		(start 105.839768 -134.0104)
		(end 105.765092 -134.085076)
		(width 0.14224)
		(layer "In4.Cu")
		(net "M_L_ODT<0>")
	)
	(segment
		(start 99.159568 -99.5172)
		(end 100.226368 -100.584)
		(width 0.0889)
		(layer "In4.Cu")
		(net "M_L_ODT<0>")
	)
	(segment
		(start 105.890568 -129.9972)
		(end 105.890568 -130.5306)
		(width 0.14224)
		(layer "In4.Cu")
		(net "M_L_ODT<0>")
	)
	(segment
		(start 105.839768 -131.2672)
		(end 105.839768 -134.0104)
		(width 0.14224)
		(layer "In4.Cu")
		(net "M_L_ODT<0>")
	)
	(segment
		(start 106.632502 -139.491466)
		(end 106.576368 -139.5476)
		(width 0.14224)
		(layer "In4.Cu")
		(net "M_L_ODT<0>")
	)
	(segment
		(start 105.738168 -131.1656)
		(end 105.839768 -131.2672)
		(width 0.14224)
		(layer "In4.Cu")
		(net "M_L_ODT<0>")
	)
	(segment
		(start 99.159568 -99.040696)
		(end 99.159568 -99.5172)
		(width 0.0889)
		(layer "In4.Cu")
		(net "M_L_ODT<0>")
	)
	(segment
		(start 105.765092 -136.06526)
		(end 105.76306 -136.067292)
		(width 0.14224)
		(layer "In4.Cu")
		(net "M_L_ODT<0>")
	)
	(segment
		(start 105.611168 -129.7178)
		(end 105.890568 -129.9972)
		(width 0.14224)
		(layer "In4.Cu")
		(net "M_L_ODT<0>")
	)
	(segment
		(start 106.576368 -140.395452)
		(end 106.852974 -140.672058)
		(width 0.14224)
		(layer "In4.Cu")
		(net "M_L_ODT<0>")
	)
	(segment
		(start 99.279964 -98.466148)
		(end 99.288854 -98.481388)
		(width 0.0889)
		(layer "In4.Cu")
		(net "M_L_ODT<0>")
	)
	(segment
		(start 106.576368 -139.5476)
		(end 106.576368 -140.395452)
		(width 0.14224)
		(layer "In4.Cu")
		(net "M_L_ODT<0>")
	)
	(segment
		(start 107.170474 -140.672058)
		(end 107.47248 -140.974064)
		(width 0.14224)
		(layer "In4.Cu")
		(net "M_L_ODT<0>")
	)
	(segment
		(start 105.765092 -134.085076)
		(end 105.765092 -136.06526)
		(width 0.14224)
		(layer "In4.Cu")
		(net "M_L_ODT<0>")
	)
	(segment
		(start 100.226368 -100.584)
		(end 100.226368 -102.771956)
		(width 0.0889)
		(layer "In4.Cu")
		(net "M_L_ODT<0>")
	)
	(segment
		(start 98.083878 -96.20504)
		(end 98.430588 -96.995488)
		(width 0.0889)
		(layer "In4.Cu")
		(net "M_L_ODT<0>")
	)
	(segment
		(start 105.76306 -137.972292)
		(end 106.632502 -138.841734)
		(width 0.14224)
		(layer "In4.Cu")
		(net "M_L_ODT<0>")
	)
	(segment
		(start 106.632502 -138.841734)
		(end 106.632502 -139.491466)
		(width 0.14224)
		(layer "In4.Cu")
		(net "M_L_ODT<0>")
	)
	(segment
		(start 100.632768 -121.827036)
		(end 103.655368 -124.849636)
		(width 0.14224)
		(layer "In4.Cu")
		(net "M_L_ODT<0>")
	)
	(segment
		(start 105.76306 -136.067292)
		(end 105.76306 -137.972292)
		(width 0.14224)
		(layer "In4.Cu")
		(net "M_L_ODT<0>")
	)
	(segment
		(start 105.738168 -130.683)
		(end 105.738168 -131.1656)
		(width 0.14224)
		(layer "In4.Cu")
		(net "M_L_ODT<0>")
	)
	(segment
		(start 105.611168 -128.046988)
		(end 105.611168 -129.7178)
		(width 0.14224)
		(layer "In4.Cu")
		(net "M_L_ODT<0>")
	)
	(segment
		(start 98.920808 -97.290636)
		(end 98.942398 -97.290636)
		(width 0.0889)
		(layer "In4.Cu")
		(net "M_L_ODT<0>")
	)
	(segment
		(start 100.632768 -103.36149)
		(end 100.632768 -121.827036)
		(width 0.14224)
		(layer "In4.Cu")
		(net "M_L_ODT<0>")
	)
	(segment
		(start 99.200462 -98.999802)
		(end 99.159568 -99.040696)
		(width 0.0889)
		(layer "In4.Cu")
		(net "M_L_ODT<0>")
	)
	(segment
		(start 107.47248 -143.542004)
		(end 107.899454 -143.968978)
		(width 0.14224)
		(layer "In4.Cu")
		(net "M_L_ODT<0>")
	)
	(segment
		(start 105.890568 -130.5306)
		(end 105.738168 -130.683)
		(width 0.14224)
		(layer "In4.Cu")
		(net "M_L_ODT<0>")
	)
	(segment
		(start 100.226368 -102.771956)
		(end 100.632768 -103.178356)
		(width 0.0889)
		(layer "In4.Cu")
		(net "M_L_ODT<0>")
	)
	(segment
		(start 103.655368 -126.091188)
		(end 105.611168 -128.046988)
		(width 0.14224)
		(layer "In4.Cu")
		(net "M_L_ODT<0>")
	)
	(segment
		(start 103.655368 -124.849636)
		(end 103.655368 -126.091188)
		(width 0.14224)
		(layer "In4.Cu")
		(net "M_L_ODT<0>")
	)
	(arc
		(start 99.288854 -98.881184)
		(mid 99.248105 -98.943062)
		(end 99.200462 -98.999802)
		(width 0.0889)
		(layer "In4.Cu")
		(net "M_L_ODT<0>")
	)
	(arc
		(start 98.430588 -96.995488)
		(mid 98.637592 -97.206352)
		(end 98.920808 -97.290636)
		(width 0.0889)
		(layer "In4.Cu")
		(net "M_L_ODT<0>")
	)
	(arc
		(start 99.288854 -97.890584)
		(mid 99.209665 -98.177199)
		(end 99.279964 -98.466148)
		(width 0.0889)
		(layer "In4.Cu")
		(net "M_L_ODT<0>")
	)
	(arc
		(start 99.288854 -98.481388)
		(mid 99.342387 -98.681286)
		(end 99.288854 -98.881184)
		(width 0.0889)
		(layer "In4.Cu")
		(net "M_L_ODT<0>")
	)
	(arc
		(start 98.942398 -97.290636)
		(mid 99.288824 -97.490613)
		(end 99.288854 -97.890584)
		(width 0.0889)
		(layer "In4.Cu")
		(net "M_L_ODT<0>")
	)
	(segment
		(start 84.949538 -143.970502)
		(end 84.949284 -143.970756)
		(width 0.1651)
		(layer "F.Cu")
		(net "M_L_MA<9>")
	)
	(segment
		(start 90.928698 -97.690686)
		(end 90.357198 -97.690686)
		(width 0.1016)
		(layer "F.Cu")
		(net "M_L_MA<9>")
	)
	(segment
		(start 84.949538 -142.6718)
		(end 84.949538 -143.970502)
		(width 0.1651)
		(layer "F.Cu")
		(net "M_L_MA<9>")
	)
	(via
		(at 84.949538 -141.187678)
		(size 0.4572)
		(drill 0.2032)
		(layers "F.Cu" "B.Cu")
		(net "M_L_MA<9>")
	)
	(via
		(at 84.949284 -143.970756)
		(size 0.4572)
		(drill 0.2032)
		(layers "F.Cu" "B.Cu")
		(net "M_L_MA<9>")
	)
	(via
		(at 90.357198 -97.690686)
		(size 0.508)
		(drill 0.254)
		(layers "F.Cu" "B.Cu")
		(net "M_L_MA<9>")
	)
	(segment
		(start 84.949538 -142.477236)
		(end 84.949538 -141.187678)
		(width 0.1651)
		(layer "B.Cu")
		(net "M_L_MA<9>")
	)
	(segment
		(start 89.3064 -132.813552)
		(end 89.450418 -132.95757)
		(width 0.14224)
		(layer "In11.Cu")
		(net "M_L_MA<9>")
	)
	(segment
		(start 88.847168 -130.5306)
		(end 88.720168 -130.6576)
		(width 0.14224)
		(layer "In11.Cu")
		(net "M_L_MA<9>")
	)
	(segment
		(start 85.418676 -140.71854)
		(end 84.949538 -141.187678)
		(width 0.14224)
		(layer "In11.Cu")
		(net "M_L_MA<9>")
	)
	(segment
		(start 86.339172 -140.133324)
		(end 86.189566 -140.28293)
		(width 0.14224)
		(layer "In11.Cu")
		(net "M_L_MA<9>")
	)
	(segment
		(start 90.517472 -102.482904)
		(end 91.326716 -103.292148)
		(width 0.0889)
		(layer "In11.Cu")
		(net "M_L_MA<9>")
	)
	(segment
		(start 91.326716 -103.576374)
		(end 91.326716 -124.317252)
		(width 0.14224)
		(layer "In11.Cu")
		(net "M_L_MA<9>")
	)
	(segment
		(start 89.284556 -133.476492)
		(end 88.938608 -133.476492)
		(width 0.14224)
		(layer "In11.Cu")
		(net "M_L_MA<9>")
	)
	(segment
		(start 88.720168 -131.1656)
		(end 88.821768 -131.2672)
		(width 0.14224)
		(layer "In11.Cu")
		(net "M_L_MA<9>")
	)
	(segment
		(start 86.692232 -140.133324)
		(end 86.339172 -140.133324)
		(width 0.14224)
		(layer "In11.Cu")
		(net "M_L_MA<9>")
	)
	(segment
		(start 91.326716 -124.317252)
		(end 89.831672 -125.812296)
		(width 0.14224)
		(layer "In11.Cu")
		(net "M_L_MA<9>")
	)
	(segment
		(start 86.852506 -140.293598)
		(end 86.692232 -140.133324)
		(width 0.14224)
		(layer "In11.Cu")
		(net "M_L_MA<9>")
	)
	(segment
		(start 88.821768 -132.660136)
		(end 88.975184 -132.813552)
		(width 0.14224)
		(layer "In11.Cu")
		(net "M_L_MA<9>")
	)
	(segment
		(start 90.517472 -100.41382)
		(end 90.517472 -102.482904)
		(width 0.0889)
		(layer "In11.Cu")
		(net "M_L_MA<9>")
	)
	(segment
		(start 88.720168 -130.6576)
		(end 88.720168 -131.1656)
		(width 0.14224)
		(layer "In11.Cu")
		(net "M_L_MA<9>")
	)
	(segment
		(start 90.02776 -98.45167)
		(end 89.945972 -98.593148)
		(width 0.0889)
		(layer "In11.Cu")
		(net "M_L_MA<9>")
	)
	(segment
		(start 89.945972 -99.84232)
		(end 90.517472 -100.41382)
		(width 0.0889)
		(layer "In11.Cu")
		(net "M_L_MA<9>")
	)
	(segment
		(start 88.847168 -130.0226)
		(end 88.847168 -130.5306)
		(width 0.14224)
		(layer "In11.Cu")
		(net "M_L_MA<9>")
	)
	(segment
		(start 90.02903 -98.448876)
		(end 90.02776 -98.45167)
		(width 0.0889)
		(layer "In11.Cu")
		(net "M_L_MA<9>")
	)
	(segment
		(start 88.783668 -135.3947)
		(end 88.761316 -135.417052)
		(width 0.14224)
		(layer "In11.Cu")
		(net "M_L_MA<9>")
	)
	(segment
		(start 88.761316 -135.417052)
		(end 88.761316 -137.596372)
		(width 0.14224)
		(layer "In11.Cu")
		(net "M_L_MA<9>")
	)
	(segment
		(start 88.661494 -129.836926)
		(end 88.847168 -130.0226)
		(width 0.14224)
		(layer "In11.Cu")
		(net "M_L_MA<9>")
	)
	(segment
		(start 89.450418 -133.31063)
		(end 89.284556 -133.476492)
		(width 0.14224)
		(layer "In11.Cu")
		(net "M_L_MA<9>")
	)
	(segment
		(start 88.783668 -133.631432)
		(end 88.783668 -135.3947)
		(width 0.14224)
		(layer "In11.Cu")
		(net "M_L_MA<9>")
	)
	(segment
		(start 86.852506 -140.5636)
		(end 86.852506 -140.293598)
		(width 0.14224)
		(layer "In11.Cu")
		(net "M_L_MA<9>")
	)
	(segment
		(start 88.821768 -131.2672)
		(end 88.821768 -132.660136)
		(width 0.14224)
		(layer "In11.Cu")
		(net "M_L_MA<9>")
	)
	(segment
		(start 88.938608 -133.476492)
		(end 88.783668 -133.631432)
		(width 0.14224)
		(layer "In11.Cu")
		(net "M_L_MA<9>")
	)
	(segment
		(start 89.450418 -132.95757)
		(end 89.450418 -133.31063)
		(width 0.14224)
		(layer "In11.Cu")
		(net "M_L_MA<9>")
	)
	(segment
		(start 87.932514 -140.453872)
		(end 87.667846 -140.71854)
		(width 0.14224)
		(layer "In11.Cu")
		(net "M_L_MA<9>")
	)
	(segment
		(start 88.761316 -137.596372)
		(end 87.932514 -138.425174)
		(width 0.14224)
		(layer "In11.Cu")
		(net "M_L_MA<9>")
	)
	(segment
		(start 86.189566 -140.28293)
		(end 86.189566 -140.5636)
		(width 0.14224)
		(layer "In11.Cu")
		(net "M_L_MA<9>")
	)
	(segment
		(start 87.932514 -138.425174)
		(end 87.932514 -140.453872)
		(width 0.14224)
		(layer "In11.Cu")
		(net "M_L_MA<9>")
	)
	(segment
		(start 86.189566 -140.5636)
		(end 86.034626 -140.71854)
		(width 0.14224)
		(layer "In11.Cu")
		(net "M_L_MA<9>")
	)
	(segment
		(start 88.661494 -129.32791)
		(end 88.661494 -129.836926)
		(width 0.14224)
		(layer "In11.Cu")
		(net "M_L_MA<9>")
	)
	(segment
		(start 84.949538 -141.187678)
		(end 84.949538 -143.970502)
		(width 0.14224)
		(layer "In11.Cu")
		(net "M_L_MA<9>")
	)
	(segment
		(start 88.975184 -132.813552)
		(end 89.3064 -132.813552)
		(width 0.14224)
		(layer "In11.Cu")
		(net "M_L_MA<9>")
	)
	(segment
		(start 91.326716 -103.292148)
		(end 91.326716 -103.576374)
		(width 0.0889)
		(layer "In11.Cu")
		(net "M_L_MA<9>")
	)
	(segment
		(start 89.945972 -98.593148)
		(end 89.945972 -99.84232)
		(width 0.0889)
		(layer "In11.Cu")
		(net "M_L_MA<9>")
	)
	(segment
		(start 89.831672 -128.157732)
		(end 88.661494 -129.32791)
		(width 0.14224)
		(layer "In11.Cu")
		(net "M_L_MA<9>")
	)
	(segment
		(start 87.007446 -140.71854)
		(end 86.852506 -140.5636)
		(width 0.14224)
		(layer "In11.Cu")
		(net "M_L_MA<9>")
	)
	(segment
		(start 87.667846 -140.71854)
		(end 87.007446 -140.71854)
		(width 0.14224)
		(layer "In11.Cu")
		(net "M_L_MA<9>")
	)
	(segment
		(start 84.949538 -143.970502)
		(end 84.949284 -143.970756)
		(width 0.14224)
		(layer "In11.Cu")
		(net "M_L_MA<9>")
	)
	(segment
		(start 86.034626 -140.71854)
		(end 85.418676 -140.71854)
		(width 0.14224)
		(layer "In11.Cu")
		(net "M_L_MA<9>")
	)
	(segment
		(start 90.357198 -97.690686)
		(end 90.02903 -98.448876)
		(width 0.0889)
		(layer "In11.Cu")
		(net "M_L_MA<9>")
	)
	(segment
		(start 89.831672 -125.812296)
		(end 89.831672 -128.157732)
		(width 0.14224)
		(layer "In11.Cu")
		(net "M_L_MA<9>")
	)
	(segment
		(start 90.070178 -93.23324)
		(end 89.498678 -93.23324)
		(width 0.1016)
		(layer "F.Cu")
		(net "M_L_MA<8>")
	)
	(segment
		(start 86.64956 -142.6718)
		(end 86.64956 -143.972788)
		(width 0.1651)
		(layer "F.Cu")
		(net "M_L_MA<8>")
	)
	(via
		(at 89.498678 -93.23324)
		(size 0.508)
		(drill 0.254)
		(layers "F.Cu" "B.Cu")
		(net "M_L_MA<8>")
	)
	(via
		(at 86.64956 -141.187678)
		(size 0.4572)
		(drill 0.2032)
		(layers "F.Cu" "B.Cu")
		(net "M_L_MA<8>")
	)
	(via
		(at 86.64956 -143.972788)
		(size 0.4572)
		(drill 0.2032)
		(layers "F.Cu" "B.Cu")
		(net "M_L_MA<8>")
	)
	(segment
		(start 86.64956 -142.477236)
		(end 86.64956 -141.187678)
		(width 0.1651)
		(layer "B.Cu")
		(net "M_L_MA<8>")
	)
	(segment
		(start 89.152222 -95.414338)
		(end 89.161112 -95.429578)
		(width 0.0889)
		(layer "In4.Cu")
		(net "M_L_MA<8>")
	)
	(segment
		(start 85.756242 -143.485616)
		(end 85.515704 -143.485616)
		(width 0.14224)
		(layer "In4.Cu")
		(net "M_L_MA<8>")
	)
	(segment
		(start 89.380568 -100.33)
		(end 90.11666 -101.066092)
		(width 0.0889)
		(layer "In4.Cu")
		(net "M_L_MA<8>")
	)
	(segment
		(start 85.407754 -142.282926)
		(end 85.247226 -142.443454)
		(width 0.14224)
		(layer "In4.Cu")
		(net "M_L_MA<8>")
	)
	(segment
		(start 85.889846 -141.746732)
		(end 85.889846 -142.127986)
		(width 0.14224)
		(layer "In4.Cu")
		(net "M_L_MA<8>")
	)
	(segment
		(start 85.734906 -142.844266)
		(end 85.889846 -142.999206)
		(width 0.14224)
		(layer "In4.Cu")
		(net "M_L_MA<8>")
	)
	(segment
		(start 89.498678 -93.23324)
		(end 89.168732 -93.99524)
		(width 0.0889)
		(layer "In4.Cu")
		(net "M_L_MA<8>")
	)
	(segment
		(start 86.630002 -145.308066)
		(end 86.806278 -145.13179)
		(width 0.14224)
		(layer "In4.Cu")
		(net "M_L_MA<8>")
	)
	(segment
		(start 86.806278 -145.13179)
		(end 86.806278 -144.129506)
		(width 0.14224)
		(layer "In4.Cu")
		(net "M_L_MA<8>")
	)
	(segment
		(start 89.168732 -93.99524)
		(end 89.152222 -94.023688)
		(width 0.0889)
		(layer "In4.Cu")
		(net "M_L_MA<8>")
	)
	(segment
		(start 85.247226 -142.694914)
		(end 85.396578 -142.844266)
		(width 0.14224)
		(layer "In4.Cu")
		(net "M_L_MA<8>")
	)
	(segment
		(start 89.152222 -96.404938)
		(end 89.161112 -96.420178)
		(width 0.0889)
		(layer "In4.Cu")
		(net "M_L_MA<8>")
	)
	(segment
		(start 89.380568 -98.8568)
		(end 89.380568 -100.33)
		(width 0.0889)
		(layer "In4.Cu")
		(net "M_L_MA<8>")
	)
	(segment
		(start 85.36305 -143.63827)
		(end 85.36305 -144.1831)
		(width 0.14224)
		(layer "In4.Cu")
		(net "M_L_MA<8>")
	)
	(segment
		(start 86.307168 -131.191)
		(end 86.19236 -131.305808)
		(width 0.14224)
		(layer "In4.Cu")
		(net "M_L_MA<8>")
	)
	(segment
		(start 86.806278 -144.129506)
		(end 86.64956 -143.972788)
		(width 0.14224)
		(layer "In4.Cu")
		(net "M_L_MA<8>")
	)
	(segment
		(start 86.281768 -129.421382)
		(end 86.281768 -129.921)
		(width 0.14224)
		(layer "In4.Cu")
		(net "M_L_MA<8>")
	)
	(segment
		(start 86.234778 -134.74319)
		(end 86.192106 -134.785862)
		(width 0.14224)
		(layer "In4.Cu")
		(net "M_L_MA<8>")
	)
	(segment
		(start 85.734906 -142.282926)
		(end 85.407754 -142.282926)
		(width 0.14224)
		(layer "In4.Cu")
		(net "M_L_MA<8>")
	)
	(segment
		(start 86.967568 -128.735582)
		(end 86.281768 -129.421382)
		(width 0.14224)
		(layer "In4.Cu")
		(net "M_L_MA<8>")
	)
	(segment
		(start 85.889846 -142.127986)
		(end 85.734906 -142.282926)
		(width 0.14224)
		(layer "In4.Cu")
		(net "M_L_MA<8>")
	)
	(segment
		(start 90.11666 -101.066092)
		(end 90.11666 -103.562658)
		(width 0.0889)
		(layer "In4.Cu")
		(net "M_L_MA<8>")
	)
	(segment
		(start 86.307168 -130.6576)
		(end 86.307168 -131.191)
		(width 0.14224)
		(layer "In4.Cu")
		(net "M_L_MA<8>")
	)
	(segment
		(start 86.212172 -140.189204)
		(end 86.64956 -140.626592)
		(width 0.14224)
		(layer "In4.Cu")
		(net "M_L_MA<8>")
	)
	(segment
		(start 86.64956 -140.626592)
		(end 86.64956 -141.187678)
		(width 0.14224)
		(layer "In4.Cu")
		(net "M_L_MA<8>")
	)
	(segment
		(start 85.945472 -145.142458)
		(end 86.11108 -145.308066)
		(width 0.14224)
		(layer "In4.Cu")
		(net "M_L_MA<8>")
	)
	(segment
		(start 85.36305 -144.1831)
		(end 85.945472 -144.765522)
		(width 0.14224)
		(layer "In4.Cu")
		(net "M_L_MA<8>")
	)
	(segment
		(start 89.152222 -97.395538)
		(end 89.161112 -97.410778)
		(width 0.0889)
		(layer "In4.Cu")
		(net "M_L_MA<8>")
	)
	(segment
		(start 90.11666 -103.562658)
		(end 90.11666 -123.556268)
		(width 0.14224)
		(layer "In4.Cu")
		(net "M_L_MA<8>")
	)
	(segment
		(start 86.154768 -130.048)
		(end 86.154768 -130.5052)
		(width 0.14224)
		(layer "In4.Cu")
		(net "M_L_MA<8>")
	)
	(segment
		(start 86.19236 -134.073392)
		(end 86.234778 -134.11581)
		(width 0.14224)
		(layer "In4.Cu")
		(net "M_L_MA<8>")
	)
	(segment
		(start 86.281768 -129.921)
		(end 86.154768 -130.048)
		(width 0.14224)
		(layer "In4.Cu")
		(net "M_L_MA<8>")
	)
	(segment
		(start 86.192106 -135.317738)
		(end 86.212172 -135.337804)
		(width 0.14224)
		(layer "In4.Cu")
		(net "M_L_MA<8>")
	)
	(segment
		(start 85.396578 -142.844266)
		(end 85.734906 -142.844266)
		(width 0.14224)
		(layer "In4.Cu")
		(net "M_L_MA<8>")
	)
	(segment
		(start 86.11108 -145.308066)
		(end 86.630002 -145.308066)
		(width 0.14224)
		(layer "In4.Cu")
		(net "M_L_MA<8>")
	)
	(segment
		(start 86.234778 -134.11581)
		(end 86.234778 -134.74319)
		(width 0.14224)
		(layer "In4.Cu")
		(net "M_L_MA<8>")
	)
	(segment
		(start 89.152222 -94.423484)
		(end 89.158572 -94.434152)
		(width 0.0889)
		(layer "In4.Cu")
		(net "M_L_MA<8>")
	)
	(segment
		(start 85.945472 -144.765522)
		(end 85.945472 -145.142458)
		(width 0.14224)
		(layer "In4.Cu")
		(net "M_L_MA<8>")
	)
	(segment
		(start 86.212172 -135.337804)
		(end 86.212172 -140.189204)
		(width 0.14224)
		(layer "In4.Cu")
		(net "M_L_MA<8>")
	)
	(segment
		(start 85.515704 -143.485616)
		(end 85.36305 -143.63827)
		(width 0.14224)
		(layer "In4.Cu")
		(net "M_L_MA<8>")
	)
	(segment
		(start 85.889846 -143.352012)
		(end 85.756242 -143.485616)
		(width 0.14224)
		(layer "In4.Cu")
		(net "M_L_MA<8>")
	)
	(segment
		(start 86.192106 -134.785862)
		(end 86.192106 -135.317738)
		(width 0.14224)
		(layer "In4.Cu")
		(net "M_L_MA<8>")
	)
	(segment
		(start 86.19236 -131.305808)
		(end 86.19236 -134.073392)
		(width 0.14224)
		(layer "In4.Cu")
		(net "M_L_MA<8>")
	)
	(segment
		(start 86.154768 -130.5052)
		(end 86.307168 -130.6576)
		(width 0.14224)
		(layer "In4.Cu")
		(net "M_L_MA<8>")
	)
	(segment
		(start 86.967568 -126.70536)
		(end 86.967568 -128.735582)
		(width 0.14224)
		(layer "In4.Cu")
		(net "M_L_MA<8>")
	)
	(segment
		(start 90.11666 -123.556268)
		(end 86.967568 -126.70536)
		(width 0.14224)
		(layer "In4.Cu")
		(net "M_L_MA<8>")
	)
	(segment
		(start 85.889846 -142.999206)
		(end 85.889846 -143.352012)
		(width 0.14224)
		(layer "In4.Cu")
		(net "M_L_MA<8>")
	)
	(segment
		(start 86.64956 -141.187678)
		(end 86.4489 -141.187678)
		(width 0.14224)
		(layer "In4.Cu")
		(net "M_L_MA<8>")
	)
	(segment
		(start 85.247226 -142.443454)
		(end 85.247226 -142.694914)
		(width 0.14224)
		(layer "In4.Cu")
		(net "M_L_MA<8>")
	)
	(segment
		(start 86.4489 -141.187678)
		(end 85.889846 -141.746732)
		(width 0.14224)
		(layer "In4.Cu")
		(net "M_L_MA<8>")
	)
	(arc
		(start 89.152222 -94.023688)
		(mid 89.098689 -94.223586)
		(end 89.152222 -94.423484)
		(width 0.0889)
		(layer "In4.Cu")
		(net "M_L_MA<8>")
	)
	(arc
		(start 89.158572 -94.434152)
		(mid 89.231492 -94.725169)
		(end 89.152222 -95.014542)
		(width 0.0889)
		(layer "In4.Cu")
		(net "M_L_MA<8>")
	)
	(arc
		(start 89.161112 -95.429578)
		(mid 89.231509 -95.718529)
		(end 89.152222 -96.005142)
		(width 0.0889)
		(layer "In4.Cu")
		(net "M_L_MA<8>")
	)
	(arc
		(start 89.152222 -97.986342)
		(mid 89.098689 -98.18624)
		(end 89.152222 -98.386138)
		(width 0.0889)
		(layer "In4.Cu")
		(net "M_L_MA<8>")
	)
	(arc
		(start 89.161112 -96.420178)
		(mid 89.231509 -96.709129)
		(end 89.152222 -96.995742)
		(width 0.0889)
		(layer "In4.Cu")
		(net "M_L_MA<8>")
	)
	(arc
		(start 89.161112 -97.410778)
		(mid 89.231509 -97.699729)
		(end 89.152222 -97.986342)
		(width 0.0889)
		(layer "In4.Cu")
		(net "M_L_MA<8>")
	)
	(arc
		(start 89.152222 -96.995742)
		(mid 89.098689 -97.19564)
		(end 89.152222 -97.395538)
		(width 0.0889)
		(layer "In4.Cu")
		(net "M_L_MA<8>")
	)
	(arc
		(start 89.253568 -98.552)
		(mid 89.330756 -98.698699)
		(end 89.380568 -98.8568)
		(width 0.0889)
		(layer "In4.Cu")
		(net "M_L_MA<8>")
	)
	(arc
		(start 89.152222 -98.386138)
		(mid 89.201852 -98.469706)
		(end 89.253568 -98.552)
		(width 0.0889)
		(layer "In4.Cu")
		(net "M_L_MA<8>")
	)
	(arc
		(start 89.152222 -95.014542)
		(mid 89.098689 -95.21444)
		(end 89.152222 -95.414338)
		(width 0.0889)
		(layer "In4.Cu")
		(net "M_L_MA<8>")
	)
	(arc
		(start 89.152222 -96.005142)
		(mid 89.098689 -96.20504)
		(end 89.152222 -96.404938)
		(width 0.0889)
		(layer "In4.Cu")
		(net "M_L_MA<8>")
	)
	(segment
		(start 89.211912 -93.72854)
		(end 88.640412 -93.72854)
		(width 0.1016)
		(layer "F.Cu")
		(net "M_L_MA<7>")
	)
	(segment
		(start 85.799422 -145.988278)
		(end 85.799422 -147.27174)
		(width 0.1651)
		(layer "F.Cu")
		(net "M_L_MA<7>")
	)
	(via
		(at 85.799422 -139.170156)
		(size 0.4572)
		(drill 0.2032)
		(layers "F.Cu" "B.Cu")
		(net "M_L_MA<7>")
	)
	(via
		(at 85.799422 -145.988278)
		(size 0.4572)
		(drill 0.2032)
		(layers "F.Cu" "B.Cu")
		(net "M_L_MA<7>")
	)
	(via
		(at 88.640412 -93.72854)
		(size 0.508)
		(drill 0.254)
		(layers "F.Cu" "B.Cu")
		(net "M_L_MA<7>")
	)
	(segment
		(start 85.799422 -139.170156)
		(end 85.799422 -137.877296)
		(width 0.1651)
		(layer "B.Cu")
		(net "M_L_MA<7>")
	)
	(segment
		(start 85.799422 -139.170156)
		(end 85.799422 -139.826746)
		(width 0.14224)
		(layer "In4.Cu")
		(net "M_L_MA<7>")
	)
	(segment
		(start 85.361272 -134.740904)
		(end 85.383624 -134.763256)
		(width 0.14224)
		(layer "In4.Cu")
		(net "M_L_MA<7>")
	)
	(segment
		(start 85.050376 -140.752576)
		(end 84.771992 -140.752576)
		(width 0.14224)
		(layer "In4.Cu")
		(net "M_L_MA<7>")
	)
	(segment
		(start 89.094056 -100.424488)
		(end 89.888568 -101.219)
		(width 0.0889)
		(layer "In4.Cu")
		(net "M_L_MA<7>")
	)
	(segment
		(start 89.60866 -103.213408)
		(end 89.60866 -103.5558)
		(width 0.0889)
		(layer "In4.Cu")
		(net "M_L_MA<7>")
	)
	(segment
		(start 86.08822 -127.84074)
		(end 86.29142 -128.04394)
		(width 0.14224)
		(layer "In4.Cu")
		(net "M_L_MA<7>")
	)
	(segment
		(start 84.812632 -144.490186)
		(end 85.024976 -144.490186)
		(width 0.14224)
		(layer "In4.Cu")
		(net "M_L_MA<7>")
	)
	(segment
		(start 84.527644 -140.996924)
		(end 84.527644 -144.205198)
		(width 0.14224)
		(layer "In4.Cu")
		(net "M_L_MA<7>")
	)
	(segment
		(start 89.35593 -123.598178)
		(end 88.89619 -123.598178)
		(width 0.14224)
		(layer "In4.Cu")
		(net "M_L_MA<7>")
	)
	(segment
		(start 88.551258 -123.94311)
		(end 88.551258 -124.40285)
		(width 0.14224)
		(layer "In4.Cu")
		(net "M_L_MA<7>")
	)
	(segment
		(start 85.436964 -130.486404)
		(end 85.316568 -130.6068)
		(width 0.14224)
		(layer "In4.Cu")
		(net "M_L_MA<7>")
	)
	(segment
		(start 88.977978 -98.466148)
		(end 88.986868 -98.481388)
		(width 0.0889)
		(layer "In4.Cu")
		(net "M_L_MA<7>")
	)
	(segment
		(start 88.89619 -123.598178)
		(end 88.551258 -123.94311)
		(width 0.14224)
		(layer "In4.Cu")
		(net "M_L_MA<7>")
	)
	(segment
		(start 85.426042 -145.614898)
		(end 85.799422 -145.988278)
		(width 0.14224)
		(layer "In4.Cu")
		(net "M_L_MA<7>")
	)
	(segment
		(start 85.519768 -128.65354)
		(end 85.316568 -128.85674)
		(width 0.14224)
		(layer "In4.Cu")
		(net "M_L_MA<7>")
	)
	(segment
		(start 84.527644 -144.205198)
		(end 84.812632 -144.490186)
		(width 0.14224)
		(layer "In4.Cu")
		(net "M_L_MA<7>")
	)
	(segment
		(start 89.888568 -101.219)
		(end 89.888568 -102.9335)
		(width 0.0889)
		(layer "In4.Cu")
		(net "M_L_MA<7>")
	)
	(segment
		(start 85.426042 -144.891252)
		(end 85.426042 -145.614898)
		(width 0.14224)
		(layer "In4.Cu")
		(net "M_L_MA<7>")
	)
	(segment
		(start 89.888568 -102.9335)
		(end 89.60866 -103.213408)
		(width 0.0889)
		(layer "In4.Cu")
		(net "M_L_MA<7>")
	)
	(segment
		(start 88.206326 -124.747782)
		(end 87.746586 -124.747782)
		(width 0.14224)
		(layer "In4.Cu")
		(net "M_L_MA<7>")
	)
	(segment
		(start 85.383624 -134.763256)
		(end 85.383624 -138.754358)
		(width 0.14224)
		(layer "In4.Cu")
		(net "M_L_MA<7>")
	)
	(segment
		(start 89.60866 -123.345448)
		(end 89.35593 -123.598178)
		(width 0.14224)
		(layer "In4.Cu")
		(net "M_L_MA<7>")
	)
	(segment
		(start 85.418168 -131.2926)
		(end 85.418168 -134.0358)
		(width 0.14224)
		(layer "In4.Cu")
		(net "M_L_MA<7>")
	)
	(segment
		(start 89.094056 -98.69678)
		(end 89.094056 -100.424488)
		(width 0.0889)
		(layer "In4.Cu")
		(net "M_L_MA<7>")
	)
	(segment
		(start 85.356192 -127.677164)
		(end 85.519768 -127.84074)
		(width 0.14224)
		(layer "In4.Cu")
		(net "M_L_MA<7>")
	)
	(segment
		(start 85.024976 -144.490186)
		(end 85.426042 -144.891252)
		(width 0.14224)
		(layer "In4.Cu")
		(net "M_L_MA<7>")
	)
	(segment
		(start 85.357716 -140.445236)
		(end 85.050376 -140.752576)
		(width 0.14224)
		(layer "In4.Cu")
		(net "M_L_MA<7>")
	)
	(segment
		(start 85.361272 -134.092696)
		(end 85.361272 -134.740904)
		(width 0.14224)
		(layer "In4.Cu")
		(net "M_L_MA<7>")
	)
	(segment
		(start 85.383624 -138.754358)
		(end 85.799422 -139.170156)
		(width 0.14224)
		(layer "In4.Cu")
		(net "M_L_MA<7>")
	)
	(segment
		(start 85.316568 -131.191)
		(end 85.418168 -131.2926)
		(width 0.14224)
		(layer "In4.Cu")
		(net "M_L_MA<7>")
	)
	(segment
		(start 85.316568 -130.6068)
		(end 85.316568 -131.191)
		(width 0.14224)
		(layer "In4.Cu")
		(net "M_L_MA<7>")
	)
	(segment
		(start 88.977978 -96.484948)
		(end 88.986868 -96.500188)
		(width 0.0889)
		(layer "In4.Cu")
		(net "M_L_MA<7>")
	)
	(segment
		(start 87.401654 -125.092714)
		(end 87.401654 -125.552454)
		(width 0.14224)
		(layer "In4.Cu")
		(net "M_L_MA<7>")
	)
	(segment
		(start 87.401654 -125.552454)
		(end 85.986366 -126.967742)
		(width 0.14224)
		(layer "In4.Cu")
		(net "M_L_MA<7>")
	)
	(segment
		(start 85.356192 -127.154432)
		(end 85.356192 -127.677164)
		(width 0.14224)
		(layer "In4.Cu")
		(net "M_L_MA<7>")
	)
	(segment
		(start 85.799422 -139.826746)
		(end 85.357716 -140.268452)
		(width 0.14224)
		(layer "In4.Cu")
		(net "M_L_MA<7>")
	)
	(segment
		(start 85.542882 -126.967742)
		(end 85.356192 -127.154432)
		(width 0.14224)
		(layer "In4.Cu")
		(net "M_L_MA<7>")
	)
	(segment
		(start 85.316568 -129.8702)
		(end 85.436964 -129.990596)
		(width 0.14224)
		(layer "In4.Cu")
		(net "M_L_MA<7>")
	)
	(segment
		(start 86.29142 -128.45034)
		(end 86.08822 -128.65354)
		(width 0.14224)
		(layer "In4.Cu")
		(net "M_L_MA<7>")
	)
	(segment
		(start 85.436964 -129.990596)
		(end 85.436964 -130.486404)
		(width 0.14224)
		(layer "In4.Cu")
		(net "M_L_MA<7>")
	)
	(segment
		(start 85.986366 -126.967742)
		(end 85.542882 -126.967742)
		(width 0.14224)
		(layer "In4.Cu")
		(net "M_L_MA<7>")
	)
	(segment
		(start 88.551258 -124.40285)
		(end 88.206326 -124.747782)
		(width 0.14224)
		(layer "In4.Cu")
		(net "M_L_MA<7>")
	)
	(segment
		(start 86.08822 -128.65354)
		(end 85.519768 -128.65354)
		(width 0.14224)
		(layer "In4.Cu")
		(net "M_L_MA<7>")
	)
	(segment
		(start 89.60866 -103.5558)
		(end 89.60866 -123.345448)
		(width 0.14224)
		(layer "In4.Cu")
		(net "M_L_MA<7>")
	)
	(segment
		(start 85.316568 -128.85674)
		(end 85.316568 -129.8702)
		(width 0.14224)
		(layer "In4.Cu")
		(net "M_L_MA<7>")
	)
	(segment
		(start 88.977978 -95.494348)
		(end 88.986868 -95.509588)
		(width 0.0889)
		(layer "In4.Cu")
		(net "M_L_MA<7>")
	)
	(segment
		(start 85.418168 -134.0358)
		(end 85.361272 -134.092696)
		(width 0.14224)
		(layer "In4.Cu")
		(net "M_L_MA<7>")
	)
	(segment
		(start 87.746586 -124.747782)
		(end 87.401654 -125.092714)
		(width 0.14224)
		(layer "In4.Cu")
		(net "M_L_MA<7>")
	)
	(segment
		(start 86.29142 -128.04394)
		(end 86.29142 -128.45034)
		(width 0.14224)
		(layer "In4.Cu")
		(net "M_L_MA<7>")
	)
	(segment
		(start 85.357716 -140.268452)
		(end 85.357716 -140.445236)
		(width 0.14224)
		(layer "In4.Cu")
		(net "M_L_MA<7>")
	)
	(segment
		(start 88.977978 -97.475548)
		(end 88.986868 -97.490788)
		(width 0.0889)
		(layer "In4.Cu")
		(net "M_L_MA<7>")
	)
	(segment
		(start 85.519768 -127.84074)
		(end 86.08822 -127.84074)
		(width 0.14224)
		(layer "In4.Cu")
		(net "M_L_MA<7>")
	)
	(segment
		(start 84.771992 -140.752576)
		(end 84.527644 -140.996924)
		(width 0.14224)
		(layer "In4.Cu")
		(net "M_L_MA<7>")
	)
	(arc
		(start 88.986868 -97.890584)
		(mid 88.907679 -98.177199)
		(end 88.977978 -98.466148)
		(width 0.0889)
		(layer "In4.Cu")
		(net "M_L_MA<7>")
	)
	(arc
		(start 88.986868 -95.909384)
		(mid 88.907679 -96.195999)
		(end 88.977978 -96.484948)
		(width 0.0889)
		(layer "In4.Cu")
		(net "M_L_MA<7>")
	)
	(arc
		(start 88.986868 -98.481388)
		(mid 89.044042 -98.587303)
		(end 89.094056 -98.69678)
		(width 0.0889)
		(layer "In4.Cu")
		(net "M_L_MA<7>")
	)
	(arc
		(start 88.986868 -94.918784)
		(mid 88.907679 -95.205399)
		(end 88.977978 -95.494348)
		(width 0.0889)
		(layer "In4.Cu")
		(net "M_L_MA<7>")
	)
	(arc
		(start 88.986868 -94.518988)
		(mid 89.040401 -94.718886)
		(end 88.986868 -94.918784)
		(width 0.0889)
		(layer "In4.Cu")
		(net "M_L_MA<7>")
	)
	(arc
		(start 88.986868 -95.509588)
		(mid 89.040401 -95.709486)
		(end 88.986868 -95.909384)
		(width 0.0889)
		(layer "In4.Cu")
		(net "M_L_MA<7>")
	)
	(arc
		(start 88.986868 -96.899984)
		(mid 88.907679 -97.186599)
		(end 88.977978 -97.475548)
		(width 0.0889)
		(layer "In4.Cu")
		(net "M_L_MA<7>")
	)
	(arc
		(start 88.640412 -93.72854)
		(mid 88.716025 -94.087105)
		(end 88.929972 -94.384622)
		(width 0.0889)
		(layer "In4.Cu")
		(net "M_L_MA<7>")
	)
	(arc
		(start 88.986868 -96.500188)
		(mid 89.040401 -96.700086)
		(end 88.986868 -96.899984)
		(width 0.0889)
		(layer "In4.Cu")
		(net "M_L_MA<7>")
	)
	(arc
		(start 88.986868 -97.490788)
		(mid 89.040401 -97.690686)
		(end 88.986868 -97.890584)
		(width 0.0889)
		(layer "In4.Cu")
		(net "M_L_MA<7>")
	)
	(arc
		(start 88.929972 -94.384622)
		(mid 88.954264 -94.453564)
		(end 88.986868 -94.518988)
		(width 0.0889)
		(layer "In4.Cu")
		(net "M_L_MA<7>")
	)
	(segment
		(start 90.928698 -94.718886)
		(end 90.357198 -94.718886)
		(width 0.1016)
		(layer "F.Cu")
		(net "M_L_MA<6>")
	)
	(segment
		(start 87.499444 -142.6718)
		(end 87.499444 -143.972788)
		(width 0.1651)
		(layer "F.Cu")
		(net "M_L_MA<6>")
	)
	(via
		(at 90.357198 -94.718886)
		(size 0.508)
		(drill 0.254)
		(layers "F.Cu" "B.Cu")
		(net "M_L_MA<6>")
	)
	(via
		(at 87.499444 -141.187678)
		(size 0.4572)
		(drill 0.2032)
		(layers "F.Cu" "B.Cu")
		(net "M_L_MA<6>")
	)
	(via
		(at 87.499444 -143.972788)
		(size 0.4572)
		(drill 0.2032)
		(layers "F.Cu" "B.Cu")
		(net "M_L_MA<6>")
	)
	(segment
		(start 87.499444 -142.477236)
		(end 87.499444 -141.187678)
		(width 0.1651)
		(layer "B.Cu")
		(net "M_L_MA<6>")
	)
	(segment
		(start 87.00135 -135.551418)
		(end 87.00135 -136.025382)
		(width 0.14224)
		(layer "In4.Cu")
		(net "M_L_MA<6>")
	)
	(segment
		(start 86.505034 -143.453104)
		(end 87.344504 -143.453104)
		(width 0.14224)
		(layer "In4.Cu")
		(net "M_L_MA<6>")
	)
	(segment
		(start 87.109554 -130.515614)
		(end 87.033608 -130.59156)
		(width 0.14224)
		(layer "In4.Cu")
		(net "M_L_MA<6>")
	)
	(segment
		(start 87.499444 -140.60805)
		(end 87.499444 -141.187678)
		(width 0.14224)
		(layer "In4.Cu")
		(net "M_L_MA<6>")
	)
	(segment
		(start 87.344504 -143.453104)
		(end 87.499444 -143.608044)
		(width 0.14224)
		(layer "In4.Cu")
		(net "M_L_MA<6>")
	)
	(segment
		(start 86.456266 -141.769084)
		(end 86.317582 -141.907768)
		(width 0.14224)
		(layer "In4.Cu")
		(net "M_L_MA<6>")
	)
	(segment
		(start 87.04453 -129.870962)
		(end 87.109554 -129.935986)
		(width 0.14224)
		(layer "In4.Cu")
		(net "M_L_MA<6>")
	)
	(segment
		(start 90.372184 -96.109536)
		(end 90.339418 -96.109536)
		(width 0.0889)
		(layer "In4.Cu")
		(net "M_L_MA<6>")
	)
	(segment
		(start 87.069168 -131.9276)
		(end 87.069168 -134.7216)
		(width 0.14224)
		(layer "In4.Cu")
		(net "M_L_MA<6>")
	)
	(segment
		(start 86.355428 -143.303498)
		(end 86.505034 -143.453104)
		(width 0.14224)
		(layer "In4.Cu")
		(net "M_L_MA<6>")
	)
	(segment
		(start 87.499444 -141.187678)
		(end 87.499444 -141.614144)
		(width 0.14224)
		(layer "In4.Cu")
		(net "M_L_MA<6>")
	)
	(segment
		(start 87.702898 -142.891764)
		(end 86.515702 -142.891764)
		(width 0.14224)
		(layer "In4.Cu")
		(net "M_L_MA<6>")
	)
	(segment
		(start 87.499444 -141.614144)
		(end 87.344504 -141.769084)
		(width 0.14224)
		(layer "In4.Cu")
		(net "M_L_MA<6>")
	)
	(segment
		(start 87.069168 -134.7216)
		(end 87.145368 -134.7978)
		(width 0.14224)
		(layer "In4.Cu")
		(net "M_L_MA<6>")
	)
	(segment
		(start 86.355428 -143.052038)
		(end 86.355428 -143.303498)
		(width 0.14224)
		(layer "In4.Cu")
		(net "M_L_MA<6>")
	)
	(segment
		(start 89.653872 -100.222304)
		(end 90.338402 -100.906834)
		(width 0.0889)
		(layer "In4.Cu")
		(net "M_L_MA<6>")
	)
	(segment
		(start 86.317582 -141.907768)
		(end 86.317582 -142.159228)
		(width 0.14224)
		(layer "In4.Cu")
		(net "M_L_MA<6>")
	)
	(segment
		(start 87.145368 -135.4074)
		(end 87.00135 -135.551418)
		(width 0.14224)
		(layer "In4.Cu")
		(net "M_L_MA<6>")
	)
	(segment
		(start 87.475568 -128.946148)
		(end 87.04453 -129.377186)
		(width 0.14224)
		(layer "In4.Cu")
		(net "M_L_MA<6>")
	)
	(segment
		(start 87.109554 -129.935986)
		(end 87.109554 -130.515614)
		(width 0.14224)
		(layer "In4.Cu")
		(net "M_L_MA<6>")
	)
	(segment
		(start 87.08771 -140.196316)
		(end 87.499444 -140.60805)
		(width 0.14224)
		(layer "In4.Cu")
		(net "M_L_MA<6>")
	)
	(segment
		(start 87.04453 -129.377186)
		(end 87.04453 -129.870962)
		(width 0.14224)
		(layer "In4.Cu")
		(net "M_L_MA<6>")
	)
	(segment
		(start 89.850214 -97.386902)
		(end 89.845388 -97.395538)
		(width 0.0889)
		(layer "In4.Cu")
		(net "M_L_MA<6>")
	)
	(segment
		(start 87.499444 -143.608044)
		(end 87.499444 -143.972788)
		(width 0.14224)
		(layer "In4.Cu")
		(net "M_L_MA<6>")
	)
	(segment
		(start 90.357198 -94.718886)
		(end 90.65895 -95.413068)
		(width 0.0889)
		(layer "In4.Cu")
		(net "M_L_MA<6>")
	)
	(segment
		(start 87.08771 -136.111742)
		(end 87.08771 -140.196316)
		(width 0.14224)
		(layer "In4.Cu")
		(net "M_L_MA<6>")
	)
	(segment
		(start 90.703908 -95.509588)
		(end 90.708734 -95.518224)
		(width 0.0889)
		(layer "In4.Cu")
		(net "M_L_MA<6>")
	)
	(segment
		(start 87.00135 -136.025382)
		(end 87.08771 -136.111742)
		(width 0.14224)
		(layer "In4.Cu")
		(net "M_L_MA<6>")
	)
	(segment
		(start 90.697558 -95.49892)
		(end 90.703908 -95.509588)
		(width 0.0889)
		(layer "In4.Cu")
		(net "M_L_MA<6>")
	)
	(segment
		(start 86.488778 -142.330424)
		(end 87.724234 -142.330424)
		(width 0.14224)
		(layer "In4.Cu")
		(net "M_L_MA<6>")
	)
	(segment
		(start 86.515702 -142.891764)
		(end 86.355428 -143.052038)
		(width 0.14224)
		(layer "In4.Cu")
		(net "M_L_MA<6>")
	)
	(segment
		(start 87.344504 -141.769084)
		(end 86.456266 -141.769084)
		(width 0.14224)
		(layer "In4.Cu")
		(net "M_L_MA<6>")
	)
	(segment
		(start 87.724234 -142.330424)
		(end 87.868506 -142.474696)
		(width 0.14224)
		(layer "In4.Cu")
		(net "M_L_MA<6>")
	)
	(segment
		(start 87.109554 -131.282186)
		(end 87.109554 -131.887214)
		(width 0.14224)
		(layer "In4.Cu")
		(net "M_L_MA<6>")
	)
	(segment
		(start 89.845388 -97.395538)
		(end 89.839038 -97.406206)
		(width 0.0889)
		(layer "In4.Cu")
		(net "M_L_MA<6>")
	)
	(segment
		(start 87.145368 -134.7978)
		(end 87.145368 -135.4074)
		(width 0.14224)
		(layer "In4.Cu")
		(net "M_L_MA<6>")
	)
	(segment
		(start 87.868506 -142.474696)
		(end 87.868506 -142.726156)
		(width 0.14224)
		(layer "In4.Cu")
		(net "M_L_MA<6>")
	)
	(segment
		(start 90.62466 -123.767088)
		(end 87.475568 -126.91618)
		(width 0.14224)
		(layer "In4.Cu")
		(net "M_L_MA<6>")
	)
	(segment
		(start 90.62466 -103.428292)
		(end 90.62466 -103.627428)
		(width 0.0889)
		(layer "In4.Cu")
		(net "M_L_MA<6>")
	)
	(segment
		(start 87.033608 -130.59156)
		(end 87.033608 -131.20624)
		(width 0.14224)
		(layer "In4.Cu")
		(net "M_L_MA<6>")
	)
	(segment
		(start 89.850214 -98.377502)
		(end 89.653872 -98.72853)
		(width 0.0889)
		(layer "In4.Cu")
		(net "M_L_MA<6>")
	)
	(segment
		(start 86.317582 -142.159228)
		(end 86.488778 -142.330424)
		(width 0.14224)
		(layer "In4.Cu")
		(net "M_L_MA<6>")
	)
	(segment
		(start 89.653872 -98.72853)
		(end 89.653872 -100.222304)
		(width 0.0889)
		(layer "In4.Cu")
		(net "M_L_MA<6>")
	)
	(segment
		(start 87.475568 -126.91618)
		(end 87.475568 -128.946148)
		(width 0.14224)
		(layer "In4.Cu")
		(net "M_L_MA<6>")
	)
	(segment
		(start 90.338402 -103.142034)
		(end 90.62466 -103.428292)
		(width 0.0889)
		(layer "In4.Cu")
		(net "M_L_MA<6>")
	)
	(segment
		(start 87.868506 -142.726156)
		(end 87.702898 -142.891764)
		(width 0.14224)
		(layer "In4.Cu")
		(net "M_L_MA<6>")
	)
	(segment
		(start 87.109554 -131.887214)
		(end 87.069168 -131.9276)
		(width 0.14224)
		(layer "In4.Cu")
		(net "M_L_MA<6>")
	)
	(segment
		(start 87.033608 -131.20624)
		(end 87.109554 -131.282186)
		(width 0.14224)
		(layer "In4.Cu")
		(net "M_L_MA<6>")
	)
	(segment
		(start 90.62466 -103.627428)
		(end 90.62466 -123.767088)
		(width 0.14224)
		(layer "In4.Cu")
		(net "M_L_MA<6>")
	)
	(segment
		(start 90.338402 -100.906834)
		(end 90.338402 -103.142034)
		(width 0.0889)
		(layer "In4.Cu")
		(net "M_L_MA<6>")
	)
	(arc
		(start 90.708734 -95.518224)
		(mid 90.704987 -95.90748)
		(end 90.372184 -96.109536)
		(width 0.0889)
		(layer "In4.Cu")
		(net "M_L_MA<6>")
	)
	(arc
		(start 90.65895 -95.413068)
		(mid 90.67654 -95.456765)
		(end 90.697558 -95.49892)
		(width 0.0889)
		(layer "In4.Cu")
		(net "M_L_MA<6>")
	)
	(arc
		(start 89.845388 -97.986088)
		(mid 89.898858 -98.181151)
		(end 89.850214 -98.377502)
		(width 0.0889)
		(layer "In4.Cu")
		(net "M_L_MA<6>")
	)
	(arc
		(start 89.839038 -97.406206)
		(mid 89.76624 -97.696969)
		(end 89.845388 -97.986088)
		(width 0.0889)
		(layer "In4.Cu")
		(net "M_L_MA<6>")
	)
	(arc
		(start 89.845388 -96.995488)
		(mid 89.898858 -97.190551)
		(end 89.850214 -97.386902)
		(width 0.0889)
		(layer "In4.Cu")
		(net "M_L_MA<6>")
	)
	(arc
		(start 90.339418 -96.109536)
		(mid 89.841167 -96.412376)
		(end 89.845388 -96.995488)
		(width 0.0889)
		(layer "In4.Cu")
		(net "M_L_MA<6>")
	)
	(segment
		(start 87.499444 -145.988278)
		(end 87.499444 -147.27174)
		(width 0.1651)
		(layer "F.Cu")
		(net "M_L_MA<5>")
	)
	(segment
		(start 91.787218 -95.21444)
		(end 91.215718 -95.21444)
		(width 0.1016)
		(layer "F.Cu")
		(net "M_L_MA<5>")
	)
	(via
		(at 87.499444 -145.988278)
		(size 0.4572)
		(drill 0.2032)
		(layers "F.Cu" "B.Cu")
		(net "M_L_MA<5>")
	)
	(via
		(at 87.499444 -139.172188)
		(size 0.4572)
		(drill 0.2032)
		(layers "F.Cu" "B.Cu")
		(net "M_L_MA<5>")
	)
	(via
		(at 91.215718 -95.21444)
		(size 0.508)
		(drill 0.254)
		(layers "F.Cu" "B.Cu")
		(net "M_L_MA<5>")
	)
	(segment
		(start 87.499444 -139.172188)
		(end 87.499444 -137.877296)
		(width 0.1651)
		(layer "B.Cu")
		(net "M_L_MA<5>")
	)
	(segment
		(start 88.302846 -143.198342)
		(end 87.910162 -143.591026)
		(width 0.14224)
		(layer "In4.Cu")
		(net "M_L_MA<5>")
	)
	(segment
		(start 87.910162 -141.53388)
		(end 88.302846 -141.926564)
		(width 0.14224)
		(layer "In4.Cu")
		(net "M_L_MA<5>")
	)
	(segment
		(start 88.446864 -127.085852)
		(end 88.686386 -127.325374)
		(width 0.14224)
		(layer "In4.Cu")
		(net "M_L_MA<5>")
	)
	(segment
		(start 87.499444 -139.718796)
		(end 87.910162 -140.129514)
		(width 0.14224)
		(layer "In4.Cu")
		(net "M_L_MA<5>")
	)
	(segment
		(start 88.009984 -131.17068)
		(end 87.776558 -131.404106)
		(width 0.14224)
		(layer "In4.Cu")
		(net "M_L_MA<5>")
	)
	(segment
		(start 88.686386 -127.704342)
		(end 87.983568 -128.40716)
		(width 0.14224)
		(layer "In4.Cu")
		(net "M_L_MA<5>")
	)
	(segment
		(start 90.010488 -97.490788)
		(end 90.005662 -97.499424)
		(width 0.0889)
		(layer "In4.Cu")
		(net "M_L_MA<5>")
	)
	(segment
		(start 87.983568 -129.73812)
		(end 87.7316 -129.990088)
		(width 0.14224)
		(layer "In4.Cu")
		(net "M_L_MA<5>")
	)
	(segment
		(start 87.932768 -135.4328)
		(end 87.932768 -138.1252)
		(width 0.14224)
		(layer "In4.Cu")
		(net "M_L_MA<5>")
	)
	(segment
		(start 89.521792 -125.861572)
		(end 89.88171 -126.22149)
		(width 0.14224)
		(layer "In4.Cu")
		(net "M_L_MA<5>")
	)
	(segment
		(start 89.014554 -126.503938)
		(end 88.734138 -126.503938)
		(width 0.14224)
		(layer "In4.Cu")
		(net "M_L_MA<5>")
	)
	(segment
		(start 91.13266 -125.286008)
		(end 90.78849 -125.630178)
		(width 0.14224)
		(layer "In4.Cu")
		(net "M_L_MA<5>")
	)
	(segment
		(start 90.121994 -125.31217)
		(end 89.809066 -125.31217)
		(width 0.14224)
		(layer "In4.Cu")
		(net "M_L_MA<5>")
	)
	(segment
		(start 90.010488 -98.481388)
		(end 89.957402 -98.576384)
		(width 0.0889)
		(layer "In4.Cu")
		(net "M_L_MA<5>")
	)
	(segment
		(start 87.913972 -132.257292)
		(end 87.913972 -134.714996)
		(width 0.14224)
		(layer "In4.Cu")
		(net "M_L_MA<5>")
	)
	(segment
		(start 89.957402 -98.576384)
		(end 89.957402 -100.144834)
		(width 0.0889)
		(layer "In4.Cu")
		(net "M_L_MA<5>")
	)
	(segment
		(start 89.957402 -100.144834)
		(end 90.528902 -100.716334)
		(width 0.0889)
		(layer "In4.Cu")
		(net "M_L_MA<5>")
	)
	(segment
		(start 91.13266 -103.555292)
		(end 91.13266 -103.780844)
		(width 0.0889)
		(layer "In4.Cu")
		(net "M_L_MA<5>")
	)
	(segment
		(start 90.78849 -125.630178)
		(end 90.440002 -125.630178)
		(width 0.14224)
		(layer "In4.Cu")
		(net "M_L_MA<5>")
	)
	(segment
		(start 87.910162 -144.463262)
		(end 87.499444 -144.87398)
		(width 0.14224)
		(layer "In4.Cu")
		(net "M_L_MA<5>")
	)
	(segment
		(start 87.932768 -138.1252)
		(end 87.499444 -138.558524)
		(width 0.14224)
		(layer "In4.Cu")
		(net "M_L_MA<5>")
	)
	(segment
		(start 87.499444 -139.172188)
		(end 87.499444 -139.718796)
		(width 0.14224)
		(layer "In4.Cu")
		(net "M_L_MA<5>")
	)
	(segment
		(start 87.7316 -129.990088)
		(end 87.7316 -130.405632)
		(width 0.14224)
		(layer "In4.Cu")
		(net "M_L_MA<5>")
	)
	(segment
		(start 87.913972 -134.714996)
		(end 87.856568 -134.7724)
		(width 0.14224)
		(layer "In4.Cu")
		(net "M_L_MA<5>")
	)
	(segment
		(start 87.7316 -130.405632)
		(end 88.009984 -130.684016)
		(width 0.14224)
		(layer "In4.Cu")
		(net "M_L_MA<5>")
	)
	(segment
		(start 88.686386 -127.325374)
		(end 88.686386 -127.704342)
		(width 0.14224)
		(layer "In4.Cu")
		(net "M_L_MA<5>")
	)
	(segment
		(start 91.13266 -103.780844)
		(end 91.13266 -125.286008)
		(width 0.14224)
		(layer "In4.Cu")
		(net "M_L_MA<5>")
	)
	(segment
		(start 87.856568 -134.7724)
		(end 87.856568 -135.3566)
		(width 0.14224)
		(layer "In4.Cu")
		(net "M_L_MA<5>")
	)
	(segment
		(start 89.306908 -126.796292)
		(end 89.014554 -126.503938)
		(width 0.14224)
		(layer "In4.Cu")
		(net "M_L_MA<5>")
	)
	(segment
		(start 88.734138 -126.503938)
		(end 88.446864 -126.791212)
		(width 0.14224)
		(layer "In4.Cu")
		(net "M_L_MA<5>")
	)
	(segment
		(start 88.009984 -130.684016)
		(end 88.009984 -131.17068)
		(width 0.14224)
		(layer "In4.Cu")
		(net "M_L_MA<5>")
	)
	(segment
		(start 90.885772 -95.976186)
		(end 90.869008 -96.004888)
		(width 0.0889)
		(layer "In4.Cu")
		(net "M_L_MA<5>")
	)
	(segment
		(start 91.215718 -95.21444)
		(end 90.885772 -95.976186)
		(width 0.0889)
		(layer "In4.Cu")
		(net "M_L_MA<5>")
	)
	(segment
		(start 87.856568 -135.3566)
		(end 87.932768 -135.4328)
		(width 0.14224)
		(layer "In4.Cu")
		(net "M_L_MA<5>")
	)
	(segment
		(start 89.88171 -126.22149)
		(end 89.88171 -126.509018)
		(width 0.14224)
		(layer "In4.Cu")
		(net "M_L_MA<5>")
	)
	(segment
		(start 87.910162 -140.129514)
		(end 87.910162 -141.53388)
		(width 0.14224)
		(layer "In4.Cu")
		(net "M_L_MA<5>")
	)
	(segment
		(start 87.910162 -143.591026)
		(end 87.910162 -144.463262)
		(width 0.14224)
		(layer "In4.Cu")
		(net "M_L_MA<5>")
	)
	(segment
		(start 87.776558 -131.404106)
		(end 87.776558 -132.119878)
		(width 0.14224)
		(layer "In4.Cu")
		(net "M_L_MA<5>")
	)
	(segment
		(start 87.499444 -144.87398)
		(end 87.499444 -145.988278)
		(width 0.14224)
		(layer "In4.Cu")
		(net "M_L_MA<5>")
	)
	(segment
		(start 87.983568 -128.40716)
		(end 87.983568 -129.73812)
		(width 0.14224)
		(layer "In4.Cu")
		(net "M_L_MA<5>")
	)
	(segment
		(start 90.378788 -96.300036)
		(end 90.346022 -96.300036)
		(width 0.0889)
		(layer "In4.Cu")
		(net "M_L_MA<5>")
	)
	(segment
		(start 90.016838 -98.47072)
		(end 90.010488 -98.481388)
		(width 0.0889)
		(layer "In4.Cu")
		(net "M_L_MA<5>")
	)
	(segment
		(start 87.776558 -132.119878)
		(end 87.913972 -132.257292)
		(width 0.14224)
		(layer "In4.Cu")
		(net "M_L_MA<5>")
	)
	(segment
		(start 89.809066 -125.31217)
		(end 89.521792 -125.599444)
		(width 0.14224)
		(layer "In4.Cu")
		(net "M_L_MA<5>")
	)
	(segment
		(start 90.528902 -100.716334)
		(end 90.528902 -102.951534)
		(width 0.0889)
		(layer "In4.Cu")
		(net "M_L_MA<5>")
	)
	(segment
		(start 89.594436 -126.796292)
		(end 89.306908 -126.796292)
		(width 0.14224)
		(layer "In4.Cu")
		(net "M_L_MA<5>")
	)
	(segment
		(start 90.528902 -102.951534)
		(end 91.13266 -103.555292)
		(width 0.0889)
		(layer "In4.Cu")
		(net "M_L_MA<5>")
	)
	(segment
		(start 88.302846 -141.926564)
		(end 88.302846 -143.198342)
		(width 0.14224)
		(layer "In4.Cu")
		(net "M_L_MA<5>")
	)
	(segment
		(start 89.88171 -126.509018)
		(end 89.594436 -126.796292)
		(width 0.14224)
		(layer "In4.Cu")
		(net "M_L_MA<5>")
	)
	(segment
		(start 90.440002 -125.630178)
		(end 90.121994 -125.31217)
		(width 0.14224)
		(layer "In4.Cu")
		(net "M_L_MA<5>")
	)
	(segment
		(start 89.521792 -125.599444)
		(end 89.521792 -125.861572)
		(width 0.14224)
		(layer "In4.Cu")
		(net "M_L_MA<5>")
	)
	(segment
		(start 88.446864 -126.791212)
		(end 88.446864 -127.085852)
		(width 0.14224)
		(layer "In4.Cu")
		(net "M_L_MA<5>")
	)
	(segment
		(start 87.499444 -138.558524)
		(end 87.499444 -139.172188)
		(width 0.14224)
		(layer "In4.Cu")
		(net "M_L_MA<5>")
	)
	(segment
		(start 90.016838 -97.48012)
		(end 90.010488 -97.490788)
		(width 0.0889)
		(layer "In4.Cu")
		(net "M_L_MA<5>")
	)
	(arc
		(start 90.869008 -96.004888)
		(mid 90.662004 -96.215752)
		(end 90.378788 -96.300036)
		(width 0.0889)
		(layer "In4.Cu")
		(net "M_L_MA<5>")
	)
	(arc
		(start 90.010488 -96.900238)
		(mid 90.08971 -97.189356)
		(end 90.016838 -97.48012)
		(width 0.0889)
		(layer "In4.Cu")
		(net "M_L_MA<5>")
	)
	(arc
		(start 90.005662 -97.499424)
		(mid 89.956907 -97.695776)
		(end 90.010488 -97.890838)
		(width 0.0889)
		(layer "In4.Cu")
		(net "M_L_MA<5>")
	)
	(arc
		(start 90.010488 -97.890838)
		(mid 90.08971 -98.179956)
		(end 90.016838 -98.47072)
		(width 0.0889)
		(layer "In4.Cu")
		(net "M_L_MA<5>")
	)
	(arc
		(start 90.346022 -96.300036)
		(mid 90.007853 -96.504834)
		(end 90.010488 -96.900238)
		(width 0.0889)
		(layer "In4.Cu")
		(net "M_L_MA<5>")
	)
	(segment
		(start 90.928698 -96.700086)
		(end 90.357198 -96.700086)
		(width 0.1016)
		(layer "F.Cu")
		(net "M_L_MA<4>")
	)
	(segment
		(start 88.349582 -145.988278)
		(end 88.349582 -147.27174)
		(width 0.1651)
		(layer "F.Cu")
		(net "M_L_MA<4>")
	)
	(via
		(at 88.349582 -139.172188)
		(size 0.4572)
		(drill 0.2032)
		(layers "F.Cu" "B.Cu")
		(net "M_L_MA<4>")
	)
	(via
		(at 90.357198 -96.700086)
		(size 0.508)
		(drill 0.254)
		(layers "F.Cu" "B.Cu")
		(net "M_L_MA<4>")
	)
	(via
		(at 88.349582 -145.988278)
		(size 0.4572)
		(drill 0.2032)
		(layers "F.Cu" "B.Cu")
		(net "M_L_MA<4>")
	)
	(segment
		(start 88.349582 -139.172188)
		(end 88.349582 -137.877296)
		(width 0.1651)
		(layer "B.Cu")
		(net "M_L_MA<4>")
	)
	(segment
		(start 91.342972 -101.454204)
		(end 91.342972 -103.206804)
		(width 0.0889)
		(layer "In4.Cu")
		(net "M_L_MA<4>")
	)
	(segment
		(start 88.349582 -139.172188)
		(end 88.349582 -139.850368)
		(width 0.14224)
		(layer "In4.Cu")
		(net "M_L_MA<4>")
	)
	(segment
		(start 88.787224 -135.391144)
		(end 88.720168 -135.4582)
		(width 0.14224)
		(layer "In4.Cu")
		(net "M_L_MA<4>")
	)
	(segment
		(start 88.349582 -138.444986)
		(end 88.349582 -139.172188)
		(width 0.14224)
		(layer "In4.Cu")
		(net "M_L_MA<4>")
	)
	(segment
		(start 88.349582 -145.227802)
		(end 88.349582 -145.988278)
		(width 0.14224)
		(layer "In4.Cu")
		(net "M_L_MA<4>")
	)
	(segment
		(start 88.757252 -136.130284)
		(end 88.757252 -138.037316)
		(width 0.14224)
		(layer "In4.Cu")
		(net "M_L_MA<4>")
	)
	(segment
		(start 90.357198 -96.700086)
		(end 90.686636 -97.46107)
		(width 0.0889)
		(layer "In4.Cu")
		(net "M_L_MA<4>")
	)
	(segment
		(start 88.787224 -131.885944)
		(end 88.787224 -135.391144)
		(width 0.14224)
		(layer "In4.Cu")
		(net "M_L_MA<4>")
	)
	(segment
		(start 88.694768 -130.6322)
		(end 88.694768 -131.064)
		(width 0.14224)
		(layer "In4.Cu")
		(net "M_L_MA<4>")
	)
	(segment
		(start 91.64066 -103.72979)
		(end 91.64066 -125.468888)
		(width 0.14224)
		(layer "In4.Cu")
		(net "M_L_MA<4>")
	)
	(segment
		(start 90.686636 -97.46107)
		(end 90.708734 -97.499424)
		(width 0.0889)
		(layer "In4.Cu")
		(net "M_L_MA<4>")
	)
	(segment
		(start 88.349582 -139.850368)
		(end 88.567768 -140.068554)
		(width 0.14224)
		(layer "In4.Cu")
		(net "M_L_MA<4>")
	)
	(segment
		(start 88.720168 -135.4582)
		(end 88.720168 -136.0932)
		(width 0.14224)
		(layer "In4.Cu")
		(net "M_L_MA<4>")
	)
	(segment
		(start 91.342972 -103.206804)
		(end 91.64066 -103.504492)
		(width 0.0889)
		(layer "In4.Cu")
		(net "M_L_MA<4>")
	)
	(segment
		(start 88.491568 -128.61798)
		(end 88.491568 -129.6162)
		(width 0.14224)
		(layer "In4.Cu")
		(net "M_L_MA<4>")
	)
	(segment
		(start 88.787224 -144.79016)
		(end 88.349582 -145.227802)
		(width 0.14224)
		(layer "In4.Cu")
		(net "M_L_MA<4>")
	)
	(segment
		(start 88.720168 -136.0932)
		(end 88.757252 -136.130284)
		(width 0.14224)
		(layer "In4.Cu")
		(net "M_L_MA<4>")
	)
	(segment
		(start 88.847168 -129.9718)
		(end 88.847168 -130.4798)
		(width 0.14224)
		(layer "In4.Cu")
		(net "M_L_MA<4>")
	)
	(segment
		(start 91.64066 -103.504492)
		(end 91.64066 -103.72979)
		(width 0.0889)
		(layer "In4.Cu")
		(net "M_L_MA<4>")
	)
	(segment
		(start 88.491568 -129.6162)
		(end 88.847168 -129.9718)
		(width 0.14224)
		(layer "In4.Cu")
		(net "M_L_MA<4>")
	)
	(segment
		(start 88.847168 -131.826)
		(end 88.787224 -131.885944)
		(width 0.14224)
		(layer "In4.Cu")
		(net "M_L_MA<4>")
	)
	(segment
		(start 91.64066 -125.468888)
		(end 88.491568 -128.61798)
		(width 0.14224)
		(layer "In4.Cu")
		(net "M_L_MA<4>")
	)
	(segment
		(start 90.828368 -100.9396)
		(end 91.342972 -101.454204)
		(width 0.0889)
		(layer "In4.Cu")
		(net "M_L_MA<4>")
	)
	(segment
		(start 88.694768 -131.064)
		(end 88.847168 -131.2164)
		(width 0.14224)
		(layer "In4.Cu")
		(net "M_L_MA<4>")
	)
	(segment
		(start 90.828368 -98.7298)
		(end 90.828368 -100.9396)
		(width 0.0889)
		(layer "In4.Cu")
		(net "M_L_MA<4>")
	)
	(segment
		(start 88.757252 -138.037316)
		(end 88.349582 -138.444986)
		(width 0.14224)
		(layer "In4.Cu")
		(net "M_L_MA<4>")
	)
	(segment
		(start 88.847168 -131.2164)
		(end 88.847168 -131.826)
		(width 0.14224)
		(layer "In4.Cu")
		(net "M_L_MA<4>")
	)
	(segment
		(start 88.787224 -140.884656)
		(end 88.787224 -144.79016)
		(width 0.14224)
		(layer "In4.Cu")
		(net "M_L_MA<4>")
	)
	(segment
		(start 88.567768 -140.068554)
		(end 88.567768 -140.6652)
		(width 0.14224)
		(layer "In4.Cu")
		(net "M_L_MA<4>")
	)
	(segment
		(start 88.567768 -140.6652)
		(end 88.787224 -140.884656)
		(width 0.14224)
		(layer "In4.Cu")
		(net "M_L_MA<4>")
	)
	(segment
		(start 88.847168 -130.4798)
		(end 88.694768 -130.6322)
		(width 0.14224)
		(layer "In4.Cu")
		(net "M_L_MA<4>")
	)
	(arc
		(start 90.787474 -98.593402)
		(mid 90.824139 -98.656724)
		(end 90.828368 -98.7298)
		(width 0.0889)
		(layer "In4.Cu")
		(net "M_L_MA<4>")
	)
	(arc
		(start 90.703908 -97.890838)
		(mid 90.62891 -98.256016)
		(end 90.787474 -98.593402)
		(width 0.0889)
		(layer "In4.Cu")
		(net "M_L_MA<4>")
	)
	(arc
		(start 90.708734 -97.499424)
		(mid 90.757489 -97.695776)
		(end 90.703908 -97.890838)
		(width 0.0889)
		(layer "In4.Cu")
		(net "M_L_MA<4>")
	)
	(segment
		(start 91.787218 -96.20504)
		(end 91.215718 -96.20504)
		(width 0.1016)
		(layer "F.Cu")
		(net "M_L_MA<3>")
	)
	(segment
		(start 89.199466 -142.6718)
		(end 89.199466 -143.972788)
		(width 0.1651)
		(layer "F.Cu")
		(net "M_L_MA<3>")
	)
	(via
		(at 89.199466 -143.972788)
		(size 0.4572)
		(drill 0.2032)
		(layers "F.Cu" "B.Cu")
		(net "M_L_MA<3>")
	)
	(via
		(at 91.215718 -96.20504)
		(size 0.508)
		(drill 0.254)
		(layers "F.Cu" "B.Cu")
		(net "M_L_MA<3>")
	)
	(via
		(at 89.199466 -141.187678)
		(size 0.4572)
		(drill 0.2032)
		(layers "F.Cu" "B.Cu")
		(net "M_L_MA<3>")
	)
	(segment
		(start 89.199466 -142.477236)
		(end 89.199466 -141.187678)
		(width 0.1651)
		(layer "B.Cu")
		(net "M_L_MA<3>")
	)
	(segment
		(start 90.869008 -97.395538)
		(end 90.875358 -97.406206)
		(width 0.0889)
		(layer "In4.Cu")
		(net "M_L_MA<3>")
	)
	(segment
		(start 91.215718 -96.20504)
		(end 90.885772 -96.966786)
		(width 0.0889)
		(layer "In4.Cu")
		(net "M_L_MA<3>")
	)
	(segment
		(start 89.199466 -141.187678)
		(end 89.199466 -143.972788)
		(width 0.14224)
		(layer "In4.Cu")
		(net "M_L_MA<3>")
	)
	(segment
		(start 88.761316 -139.512548)
		(end 89.04605 -139.797282)
		(width 0.14224)
		(layer "In4.Cu")
		(net "M_L_MA<3>")
	)
	(segment
		(start 89.451434 -130.398266)
		(end 89.692226 -130.639058)
		(width 0.14224)
		(layer "In4.Cu")
		(net "M_L_MA<3>")
	)
	(segment
		(start 89.710768 -129.8194)
		(end 89.451434 -130.078734)
		(width 0.14224)
		(layer "In4.Cu")
		(net "M_L_MA<3>")
	)
	(segment
		(start 92.14866 -103.716074)
		(end 92.14866 -125.679454)
		(width 0.14224)
		(layer "In4.Cu")
		(net "M_L_MA<3>")
	)
	(segment
		(start 89.199466 -140.645642)
		(end 89.199466 -141.187678)
		(width 0.14224)
		(layer "In4.Cu")
		(net "M_L_MA<3>")
	)
	(segment
		(start 90.864182 -97.386902)
		(end 90.869008 -97.395538)
		(width 0.0889)
		(layer "In4.Cu")
		(net "M_L_MA<3>")
	)
	(segment
		(start 92.14866 -125.679454)
		(end 89.710768 -128.117346)
		(width 0.14224)
		(layer "In4.Cu")
		(net "M_L_MA<3>")
	)
	(segment
		(start 90.885772 -96.966786)
		(end 90.869008 -96.995488)
		(width 0.0889)
		(layer "In4.Cu")
		(net "M_L_MA<3>")
	)
	(segment
		(start 88.761316 -138.769852)
		(end 88.761316 -139.512548)
		(width 0.14224)
		(layer "In4.Cu")
		(net "M_L_MA<3>")
	)
	(segment
		(start 89.710768 -128.117346)
		(end 89.710768 -129.8194)
		(width 0.14224)
		(layer "In4.Cu")
		(net "M_L_MA<3>")
	)
	(segment
		(start 89.692226 -131.107942)
		(end 89.583768 -131.2164)
		(width 0.14224)
		(layer "In4.Cu")
		(net "M_L_MA<3>")
	)
	(segment
		(start 89.04605 -140.492226)
		(end 89.199466 -140.645642)
		(width 0.14224)
		(layer "In4.Cu")
		(net "M_L_MA<3>")
	)
	(segment
		(start 89.63787 -132.083302)
		(end 89.63787 -136.992106)
		(width 0.14224)
		(layer "In4.Cu")
		(net "M_L_MA<3>")
	)
	(segment
		(start 91.082368 -100.6602)
		(end 91.647772 -101.225604)
		(width 0.0889)
		(layer "In4.Cu")
		(net "M_L_MA<3>")
	)
	(segment
		(start 91.647772 -101.225604)
		(end 91.647772 -102.953058)
		(width 0.0889)
		(layer "In4.Cu")
		(net "M_L_MA<3>")
	)
	(segment
		(start 89.583768 -132.0292)
		(end 89.63787 -132.083302)
		(width 0.14224)
		(layer "In4.Cu")
		(net "M_L_MA<3>")
	)
	(segment
		(start 91.647772 -102.953058)
		(end 92.14866 -103.453946)
		(width 0.0889)
		(layer "In4.Cu")
		(net "M_L_MA<3>")
	)
	(segment
		(start 89.451434 -130.078734)
		(end 89.451434 -130.398266)
		(width 0.14224)
		(layer "In4.Cu")
		(net "M_L_MA<3>")
	)
	(segment
		(start 89.329768 -137.300208)
		(end 89.329768 -138.2014)
		(width 0.14224)
		(layer "In4.Cu")
		(net "M_L_MA<3>")
	)
	(segment
		(start 91.082368 -98.7044)
		(end 91.082368 -100.6602)
		(width 0.0889)
		(layer "In4.Cu")
		(net "M_L_MA<3>")
	)
	(segment
		(start 89.329768 -138.2014)
		(end 88.761316 -138.769852)
		(width 0.14224)
		(layer "In4.Cu")
		(net "M_L_MA<3>")
	)
	(segment
		(start 89.04605 -139.797282)
		(end 89.04605 -140.492226)
		(width 0.14224)
		(layer "In4.Cu")
		(net "M_L_MA<3>")
	)
	(segment
		(start 89.583768 -131.2164)
		(end 89.583768 -132.0292)
		(width 0.14224)
		(layer "In4.Cu")
		(net "M_L_MA<3>")
	)
	(segment
		(start 89.692226 -130.639058)
		(end 89.692226 -131.107942)
		(width 0.14224)
		(layer "In4.Cu")
		(net "M_L_MA<3>")
	)
	(segment
		(start 89.63787 -136.992106)
		(end 89.329768 -137.300208)
		(width 0.14224)
		(layer "In4.Cu")
		(net "M_L_MA<3>")
	)
	(segment
		(start 92.14866 -103.453946)
		(end 92.14866 -103.716074)
		(width 0.0889)
		(layer "In4.Cu")
		(net "M_L_MA<3>")
	)
	(arc
		(start 90.946732 -98.482658)
		(mid 91.03046 -98.583798)
		(end 91.082368 -98.7044)
		(width 0.0889)
		(layer "In4.Cu")
		(net "M_L_MA<3>")
	)
	(arc
		(start 90.869008 -97.986088)
		(mid 90.820192 -98.248108)
		(end 90.946732 -98.482658)
		(width 0.0889)
		(layer "In4.Cu")
		(net "M_L_MA<3>")
	)
	(arc
		(start 90.875358 -97.406206)
		(mid 90.948156 -97.696969)
		(end 90.869008 -97.986088)
		(width 0.0889)
		(layer "In4.Cu")
		(net "M_L_MA<3>")
	)
	(arc
		(start 90.869008 -96.995488)
		(mid 90.815538 -97.190551)
		(end 90.864182 -97.386902)
		(width 0.0889)
		(layer "In4.Cu")
		(net "M_L_MA<3>")
	)
	(segment
		(start 90.049604 -146.013678)
		(end 90.049604 -145.988278)
		(width 0.1651)
		(layer "F.Cu")
		(net "M_L_MA<2>")
	)
	(segment
		(start 92.645738 -97.690686)
		(end 92.074238 -97.690686)
		(width 0.1016)
		(layer "F.Cu")
		(net "M_L_MA<2>")
	)
	(segment
		(start 90.04935 -147.27174)
		(end 90.04935 -146.013932)
		(width 0.1651)
		(layer "F.Cu")
		(net "M_L_MA<2>")
	)
	(segment
		(start 90.04935 -146.013932)
		(end 90.049604 -146.013678)
		(width 0.1651)
		(layer "F.Cu")
		(net "M_L_MA<2>")
	)
	(via
		(at 92.074238 -97.690686)
		(size 0.508)
		(drill 0.254)
		(layers "F.Cu" "B.Cu")
		(net "M_L_MA<2>")
	)
	(via
		(at 90.049604 -145.988278)
		(size 0.4572)
		(drill 0.2032)
		(layers "F.Cu" "B.Cu")
		(net "M_L_MA<2>")
	)
	(via
		(at 90.04935 -139.172188)
		(size 0.4572)
		(drill 0.2032)
		(layers "F.Cu" "B.Cu")
		(net "M_L_MA<2>")
	)
	(segment
		(start 90.04935 -137.877296)
		(end 90.04935 -139.172188)
		(width 0.1651)
		(layer "B.Cu")
		(net "M_L_MA<2>")
	)
	(segment
		(start 93.16466 -103.808276)
		(end 93.16466 -127.028956)
		(width 0.14224)
		(layer "In4.Cu")
		(net "M_L_MA<2>")
	)
	(segment
		(start 91.673172 -100.260404)
		(end 92.257372 -100.844604)
		(width 0.0889)
		(layer "In4.Cu")
		(net "M_L_MA<2>")
	)
	(segment
		(start 90.860626 -129.877058)
		(end 90.860626 -130.584956)
		(width 0.14224)
		(layer "In4.Cu")
		(net "M_L_MA<2>")
	)
	(segment
		(start 91.387168 -134.112)
		(end 91.387168 -136.974072)
		(width 0.14224)
		(layer "In4.Cu")
		(net "M_L_MA<2>")
	)
	(segment
		(start 92.48267 -128.79324)
		(end 90.874596 -128.79324)
		(width 0.14224)
		(layer "In4.Cu")
		(net "M_L_MA<2>")
	)
	(segment
		(start 92.769944 -128.505966)
		(end 92.48267 -128.79324)
		(width 0.14224)
		(layer "In4.Cu")
		(net "M_L_MA<2>")
	)
	(segment
		(start 90.874596 -128.79324)
		(end 90.69578 -128.972056)
		(width 0.14224)
		(layer "In4.Cu")
		(net "M_L_MA<2>")
	)
	(segment
		(start 91.183968 -137.763758)
		(end 90.04935 -138.898376)
		(width 0.14224)
		(layer "In4.Cu")
		(net "M_L_MA<2>")
	)
	(segment
		(start 92.769944 -127.423672)
		(end 92.769944 -128.505966)
		(width 0.14224)
		(layer "In4.Cu")
		(net "M_L_MA<2>")
	)
	(segment
		(start 90.049604 -139.850368)
		(end 90.365834 -140.166598)
		(width 0.14224)
		(layer "In4.Cu")
		(net "M_L_MA<2>")
	)
	(segment
		(start 91.107768 -131.395724)
		(end 91.107768 -133.8326)
		(width 0.14224)
		(layer "In4.Cu")
		(net "M_L_MA<2>")
	)
	(segment
		(start 92.257372 -102.673658)
		(end 93.16466 -103.580946)
		(width 0.0889)
		(layer "In4.Cu")
		(net "M_L_MA<2>")
	)
	(segment
		(start 92.074238 -97.690686)
		(end 91.673172 -98.56216)
		(width 0.0889)
		(layer "In4.Cu")
		(net "M_L_MA<2>")
	)
	(segment
		(start 90.365834 -140.859002)
		(end 90.47607 -140.969238)
		(width 0.14224)
		(layer "In4.Cu")
		(net "M_L_MA<2>")
	)
	(segment
		(start 90.739976 -130.705606)
		(end 90.739976 -131.027932)
		(width 0.14224)
		(layer "In4.Cu")
		(net "M_L_MA<2>")
	)
	(segment
		(start 90.69578 -128.972056)
		(end 90.69578 -129.712212)
		(width 0.14224)
		(layer "In4.Cu")
		(net "M_L_MA<2>")
	)
	(segment
		(start 90.47607 -144.359122)
		(end 90.049604 -144.785588)
		(width 0.14224)
		(layer "In4.Cu")
		(net "M_L_MA<2>")
	)
	(segment
		(start 91.107768 -133.8326)
		(end 91.387168 -134.112)
		(width 0.14224)
		(layer "In4.Cu")
		(net "M_L_MA<2>")
	)
	(segment
		(start 90.739976 -131.027932)
		(end 91.107768 -131.395724)
		(width 0.14224)
		(layer "In4.Cu")
		(net "M_L_MA<2>")
	)
	(segment
		(start 90.860626 -130.584956)
		(end 90.739976 -130.705606)
		(width 0.14224)
		(layer "In4.Cu")
		(net "M_L_MA<2>")
	)
	(segment
		(start 91.387168 -136.974072)
		(end 91.183968 -137.177272)
		(width 0.14224)
		(layer "In4.Cu")
		(net "M_L_MA<2>")
	)
	(segment
		(start 92.257372 -100.844604)
		(end 92.257372 -102.673658)
		(width 0.0889)
		(layer "In4.Cu")
		(net "M_L_MA<2>")
	)
	(segment
		(start 91.673172 -98.56216)
		(end 91.673172 -100.260404)
		(width 0.0889)
		(layer "In4.Cu")
		(net "M_L_MA<2>")
	)
	(segment
		(start 90.049604 -144.785588)
		(end 90.049604 -145.988278)
		(width 0.14224)
		(layer "In4.Cu")
		(net "M_L_MA<2>")
	)
	(segment
		(start 90.365834 -140.166598)
		(end 90.365834 -140.859002)
		(width 0.14224)
		(layer "In4.Cu")
		(net "M_L_MA<2>")
	)
	(segment
		(start 90.47607 -140.969238)
		(end 90.47607 -144.359122)
		(width 0.14224)
		(layer "In4.Cu")
		(net "M_L_MA<2>")
	)
	(segment
		(start 90.69578 -129.712212)
		(end 90.860626 -129.877058)
		(width 0.14224)
		(layer "In4.Cu")
		(net "M_L_MA<2>")
	)
	(segment
		(start 90.049604 -139.172442)
		(end 90.049604 -139.850368)
		(width 0.14224)
		(layer "In4.Cu")
		(net "M_L_MA<2>")
	)
	(segment
		(start 90.04935 -139.172188)
		(end 90.049604 -139.172442)
		(width 0.14224)
		(layer "In4.Cu")
		(net "M_L_MA<2>")
	)
	(segment
		(start 91.183968 -137.177272)
		(end 91.183968 -137.763758)
		(width 0.14224)
		(layer "In4.Cu")
		(net "M_L_MA<2>")
	)
	(segment
		(start 93.16466 -127.028956)
		(end 92.769944 -127.423672)
		(width 0.14224)
		(layer "In4.Cu")
		(net "M_L_MA<2>")
	)
	(segment
		(start 93.16466 -103.580946)
		(end 93.16466 -103.808276)
		(width 0.0889)
		(layer "In4.Cu")
		(net "M_L_MA<2>")
	)
	(segment
		(start 90.04935 -138.898376)
		(end 90.04935 -139.172188)
		(width 0.14224)
		(layer "In4.Cu")
		(net "M_L_MA<2>")
	)
	(segment
		(start 91.787218 -98.18624)
		(end 91.215718 -98.18624)
		(width 0.1016)
		(layer "F.Cu")
		(net "M_L_MA<1>")
	)
	(segment
		(start 90.04935 -142.6718)
		(end 90.04935 -143.972788)
		(width 0.1651)
		(layer "F.Cu")
		(net "M_L_MA<1>")
	)
	(via
		(at 91.215718 -98.18624)
		(size 0.508)
		(drill 0.254)
		(layers "F.Cu" "B.Cu")
		(net "M_L_MA<1>")
	)
	(via
		(at 90.049604 -141.187678)
		(size 0.4572)
		(drill 0.2032)
		(layers "F.Cu" "B.Cu")
		(net "M_L_MA<1>")
	)
	(via
		(at 90.04935 -143.972788)
		(size 0.4572)
		(drill 0.2032)
		(layers "F.Cu" "B.Cu")
		(net "M_L_MA<1>")
	)
	(segment
		(start 90.049604 -141.213078)
		(end 90.049604 -141.187678)
		(width 0.1651)
		(layer "B.Cu")
		(net "M_L_MA<1>")
	)
	(segment
		(start 90.04935 -142.477236)
		(end 90.04935 -141.213332)
		(width 0.1651)
		(layer "B.Cu")
		(net "M_L_MA<1>")
	)
	(segment
		(start 90.04935 -141.213332)
		(end 90.049604 -141.213078)
		(width 0.1651)
		(layer "B.Cu")
		(net "M_L_MA<1>")
	)
	(segment
		(start 89.634568 -140.1572)
		(end 89.95537 -140.478002)
		(width 0.14224)
		(layer "In4.Cu")
		(net "M_L_MA<1>")
	)
	(segment
		(start 91.368372 -98.674174)
		(end 91.368372 -100.489004)
		(width 0.0889)
		(layer "In4.Cu")
		(net "M_L_MA<1>")
	)
	(segment
		(start 91.752674 -126.888494)
		(end 91.4654 -127.175768)
		(width 0.14224)
		(layer "In4.Cu")
		(net "M_L_MA<1>")
	)
	(segment
		(start 90.541856 -128.099312)
		(end 90.150696 -128.490472)
		(width 0.14224)
		(layer "In4.Cu")
		(net "M_L_MA<1>")
	)
	(segment
		(start 90.599768 -133.25602)
		(end 90.599768 -133.9596)
		(width 0.14224)
		(layer "In4.Cu")
		(net "M_L_MA<1>")
	)
	(segment
		(start 90.463116 -137.880852)
		(end 89.634568 -138.7094)
		(width 0.14224)
		(layer "In4.Cu")
		(net "M_L_MA<1>")
	)
	(segment
		(start 91.749372 -128.034796)
		(end 91.462098 -128.32207)
		(width 0.14224)
		(layer "In4.Cu")
		(net "M_L_MA<1>")
	)
	(segment
		(start 90.28049 -130.581654)
		(end 90.28049 -131.216146)
		(width 0.14224)
		(layer "In4.Cu")
		(net "M_L_MA<1>")
	)
	(segment
		(start 90.358468 -134.845552)
		(end 90.358468 -136.11606)
		(width 0.14224)
		(layer "In4.Cu")
		(net "M_L_MA<1>")
	)
	(segment
		(start 92.437966 -126.888494)
		(end 91.752674 -126.888494)
		(width 0.14224)
		(layer "In4.Cu")
		(net "M_L_MA<1>")
	)
	(segment
		(start 90.150696 -128.490472)
		(end 90.150696 -129.757932)
		(width 0.14224)
		(layer "In4.Cu")
		(net "M_L_MA<1>")
	)
	(segment
		(start 90.464894 -134.094474)
		(end 90.464894 -134.739126)
		(width 0.14224)
		(layer "In4.Cu")
		(net "M_L_MA<1>")
	)
	(segment
		(start 90.412824 -132.330444)
		(end 90.412824 -133.069076)
		(width 0.14224)
		(layer "In4.Cu")
		(net "M_L_MA<1>")
	)
	(segment
		(start 91.952572 -102.77475)
		(end 92.65666 -103.478838)
		(width 0.0889)
		(layer "In4.Cu")
		(net "M_L_MA<1>")
	)
	(segment
		(start 91.952572 -101.073204)
		(end 91.952572 -102.77475)
		(width 0.0889)
		(layer "In4.Cu")
		(net "M_L_MA<1>")
	)
	(segment
		(start 92.65666 -103.75011)
		(end 92.65666 -126.6698)
		(width 0.14224)
		(layer "In4.Cu")
		(net "M_L_MA<1>")
	)
	(segment
		(start 91.215718 -98.18624)
		(end 91.215718 -98.52152)
		(width 0.0889)
		(layer "In4.Cu")
		(net "M_L_MA<1>")
	)
	(segment
		(start 90.442288 -130.049524)
		(end 90.442288 -130.419856)
		(width 0.14224)
		(layer "In4.Cu")
		(net "M_L_MA<1>")
	)
	(segment
		(start 90.951812 -128.099312)
		(end 90.541856 -128.099312)
		(width 0.14224)
		(layer "In4.Cu")
		(net "M_L_MA<1>")
	)
	(segment
		(start 91.4654 -127.463296)
		(end 91.749372 -127.747268)
		(width 0.14224)
		(layer "In4.Cu")
		(net "M_L_MA<1>")
	)
	(segment
		(start 90.28049 -131.216146)
		(end 90.599768 -131.535424)
		(width 0.14224)
		(layer "In4.Cu")
		(net "M_L_MA<1>")
	)
	(segment
		(start 89.634568 -138.7094)
		(end 89.634568 -140.1572)
		(width 0.14224)
		(layer "In4.Cu")
		(net "M_L_MA<1>")
	)
	(segment
		(start 91.4654 -127.175768)
		(end 91.4654 -127.463296)
		(width 0.14224)
		(layer "In4.Cu")
		(net "M_L_MA<1>")
	)
	(segment
		(start 89.95537 -141.093444)
		(end 90.049604 -141.187678)
		(width 0.14224)
		(layer "In4.Cu")
		(net "M_L_MA<1>")
	)
	(segment
		(start 91.17457 -128.32207)
		(end 90.951812 -128.099312)
		(width 0.14224)
		(layer "In4.Cu")
		(net "M_L_MA<1>")
	)
	(segment
		(start 91.368372 -100.489004)
		(end 91.952572 -101.073204)
		(width 0.0889)
		(layer "In4.Cu")
		(net "M_L_MA<1>")
	)
	(segment
		(start 90.442288 -130.419856)
		(end 90.28049 -130.581654)
		(width 0.14224)
		(layer "In4.Cu")
		(net "M_L_MA<1>")
	)
	(segment
		(start 90.150696 -129.757932)
		(end 90.442288 -130.049524)
		(width 0.14224)
		(layer "In4.Cu")
		(net "M_L_MA<1>")
	)
	(segment
		(start 89.95537 -140.478002)
		(end 89.95537 -141.093444)
		(width 0.14224)
		(layer "In4.Cu")
		(net "M_L_MA<1>")
	)
	(segment
		(start 90.412824 -133.069076)
		(end 90.599768 -133.25602)
		(width 0.14224)
		(layer "In4.Cu")
		(net "M_L_MA<1>")
	)
	(segment
		(start 91.462098 -128.32207)
		(end 91.17457 -128.32207)
		(width 0.14224)
		(layer "In4.Cu")
		(net "M_L_MA<1>")
	)
	(segment
		(start 90.049604 -141.187678)
		(end 90.049604 -143.972534)
		(width 0.14224)
		(layer "In4.Cu")
		(net "M_L_MA<1>")
	)
	(segment
		(start 90.463116 -136.220708)
		(end 90.463116 -137.880852)
		(width 0.14224)
		(layer "In4.Cu")
		(net "M_L_MA<1>")
	)
	(segment
		(start 90.599768 -131.535424)
		(end 90.599768 -132.1435)
		(width 0.14224)
		(layer "In4.Cu")
		(net "M_L_MA<1>")
	)
	(segment
		(start 90.599768 -132.1435)
		(end 90.412824 -132.330444)
		(width 0.14224)
		(layer "In4.Cu")
		(net "M_L_MA<1>")
	)
	(segment
		(start 91.215718 -98.52152)
		(end 91.368372 -98.674174)
		(width 0.0889)
		(layer "In4.Cu")
		(net "M_L_MA<1>")
	)
	(segment
		(start 90.049604 -143.972534)
		(end 90.04935 -143.972788)
		(width 0.14224)
		(layer "In4.Cu")
		(net "M_L_MA<1>")
	)
	(segment
		(start 90.599768 -133.9596)
		(end 90.464894 -134.094474)
		(width 0.14224)
		(layer "In4.Cu")
		(net "M_L_MA<1>")
	)
	(segment
		(start 92.65666 -126.6698)
		(end 92.437966 -126.888494)
		(width 0.14224)
		(layer "In4.Cu")
		(net "M_L_MA<1>")
	)
	(segment
		(start 91.749372 -127.747268)
		(end 91.749372 -128.034796)
		(width 0.14224)
		(layer "In4.Cu")
		(net "M_L_MA<1>")
	)
	(segment
		(start 90.464894 -134.739126)
		(end 90.358468 -134.845552)
		(width 0.14224)
		(layer "In4.Cu")
		(net "M_L_MA<1>")
	)
	(segment
		(start 92.65666 -103.478838)
		(end 92.65666 -103.75011)
		(width 0.0889)
		(layer "In4.Cu")
		(net "M_L_MA<1>")
	)
	(segment
		(start 90.358468 -136.11606)
		(end 90.463116 -136.220708)
		(width 0.14224)
		(layer "In4.Cu")
		(net "M_L_MA<1>")
	)
	(segment
		(start 100.372164 -96.20504)
		(end 99.800664 -96.20504)
		(width 0.1016)
		(layer "F.Cu")
		(net "M_L_MA<17>")
	)
	(segment
		(start 110.44936 -147.27174)
		(end 110.44936 -145.988786)
		(width 0.1651)
		(layer "F.Cu")
		(net "M_L_MA<17>")
	)
	(segment
		(start 110.44936 -145.988786)
		(end 110.449868 -145.988278)
		(width 0.1651)
		(layer "F.Cu")
		(net "M_L_MA<17>")
	)
	(via
		(at 99.800664 -96.20504)
		(size 0.508)
		(drill 0.254)
		(layers "F.Cu" "B.Cu")
		(net "M_L_MA<17>")
	)
	(via
		(at 110.449868 -139.172188)
		(size 0.4572)
		(drill 0.2032)
		(layers "F.Cu" "B.Cu")
		(net "M_L_MA<17>")
	)
	(via
		(at 110.449868 -145.988278)
		(size 0.4572)
		(drill 0.2032)
		(layers "F.Cu" "B.Cu")
		(net "M_L_MA<17>")
	)
	(segment
		(start 110.44936 -137.877296)
		(end 110.44936 -139.17168)
		(width 0.1651)
		(layer "B.Cu")
		(net "M_L_MA<17>")
	)
	(segment
		(start 110.44936 -139.17168)
		(end 110.449868 -139.172188)
		(width 0.1651)
		(layer "B.Cu")
		(net "M_L_MA<17>")
	)
	(segment
		(start 102.639368 -103.0224)
		(end 102.639368 -120.700546)
		(width 0.14224)
		(layer "In11.Cu")
		(net "M_L_MA<17>")
	)
	(segment
		(start 109.344968 -129.1082)
		(end 109.163358 -129.28981)
		(width 0.14224)
		(layer "In11.Cu")
		(net "M_L_MA<17>")
	)
	(segment
		(start 110.548928 -139.271248)
		(end 110.548928 -140.453872)
		(width 0.14224)
		(layer "In11.Cu")
		(net "M_L_MA<17>")
	)
	(segment
		(start 101.877368 -101.5238)
		(end 101.877368 -102.2604)
		(width 0.14224)
		(layer "In11.Cu")
		(net "M_L_MA<17>")
	)
	(segment
		(start 109.344968 -127.406146)
		(end 109.344968 -129.1082)
		(width 0.14224)
		(layer "In11.Cu")
		(net "M_L_MA<17>")
	)
	(segment
		(start 109.141768 -130.7084)
		(end 109.141768 -131.2418)
		(width 0.14224)
		(layer "In11.Cu")
		(net "M_L_MA<17>")
	)
	(segment
		(start 109.217968 -131.318)
		(end 109.217968 -132.747766)
		(width 0.14224)
		(layer "In11.Cu")
		(net "M_L_MA<17>")
	)
	(segment
		(start 100.607368 -99.696778)
		(end 100.607368 -100.2538)
		(width 0.14224)
		(layer "In11.Cu")
		(net "M_L_MA<17>")
	)
	(segment
		(start 109.39653 -133.812788)
		(end 109.159294 -134.050024)
		(width 0.14224)
		(layer "In11.Cu")
		(net "M_L_MA<17>")
	)
	(segment
		(start 109.163358 -129.76479)
		(end 109.321092 -129.922524)
		(width 0.14224)
		(layer "In11.Cu")
		(net "M_L_MA<17>")
	)
	(segment
		(start 109.217968 -132.747766)
		(end 109.39653 -132.926328)
		(width 0.14224)
		(layer "In11.Cu")
		(net "M_L_MA<17>")
	)
	(segment
		(start 110.558834 -144.676114)
		(end 110.558834 -145.369534)
		(width 0.14224)
		(layer "In11.Cu")
		(net "M_L_MA<17>")
	)
	(segment
		(start 100.607368 -100.2538)
		(end 101.877368 -101.5238)
		(width 0.14224)
		(layer "In11.Cu")
		(net "M_L_MA<17>")
	)
	(segment
		(start 100.130864 -96.966786)
		(end 100.147374 -96.995234)
		(width 0.0889)
		(layer "In11.Cu")
		(net "M_L_MA<17>")
	)
	(segment
		(start 100.607368 -99.287584)
		(end 100.607368 -99.696778)
		(width 0.0889)
		(layer "In11.Cu")
		(net "M_L_MA<17>")
	)
	(segment
		(start 110.449868 -139.172188)
		(end 110.548928 -139.271248)
		(width 0.14224)
		(layer "In11.Cu")
		(net "M_L_MA<17>")
	)
	(segment
		(start 100.200714 -98.88093)
		(end 100.607368 -99.287584)
		(width 0.0889)
		(layer "In11.Cu")
		(net "M_L_MA<17>")
	)
	(segment
		(start 110.012226 -142.321534)
		(end 110.041944 -142.351252)
		(width 0.14224)
		(layer "In11.Cu")
		(net "M_L_MA<17>")
	)
	(segment
		(start 101.877368 -102.2604)
		(end 102.639368 -103.0224)
		(width 0.14224)
		(layer "In11.Cu")
		(net "M_L_MA<17>")
	)
	(segment
		(start 110.012226 -140.990574)
		(end 110.012226 -142.321534)
		(width 0.14224)
		(layer "In11.Cu")
		(net "M_L_MA<17>")
	)
	(segment
		(start 109.163358 -129.28981)
		(end 109.163358 -129.76479)
		(width 0.14224)
		(layer "In11.Cu")
		(net "M_L_MA<17>")
	)
	(segment
		(start 109.321092 -129.922524)
		(end 109.321092 -130.529076)
		(width 0.14224)
		(layer "In11.Cu")
		(net "M_L_MA<17>")
	)
	(segment
		(start 100.200714 -98.19513)
		(end 100.200714 -98.88093)
		(width 0.0889)
		(layer "In11.Cu")
		(net "M_L_MA<17>")
	)
	(segment
		(start 99.800664 -96.20504)
		(end 100.130864 -96.966786)
		(width 0.0889)
		(layer "In11.Cu")
		(net "M_L_MA<17>")
	)
	(segment
		(start 110.041944 -144.159224)
		(end 110.558834 -144.676114)
		(width 0.14224)
		(layer "In11.Cu")
		(net "M_L_MA<17>")
	)
	(segment
		(start 109.321092 -130.529076)
		(end 109.141768 -130.7084)
		(width 0.14224)
		(layer "In11.Cu")
		(net "M_L_MA<17>")
	)
	(segment
		(start 110.449868 -145.4785)
		(end 110.449868 -145.988278)
		(width 0.14224)
		(layer "In11.Cu")
		(net "M_L_MA<17>")
	)
	(segment
		(start 110.548928 -140.453872)
		(end 110.012226 -140.990574)
		(width 0.14224)
		(layer "In11.Cu")
		(net "M_L_MA<17>")
	)
	(segment
		(start 110.041944 -142.351252)
		(end 110.041944 -144.159224)
		(width 0.14224)
		(layer "In11.Cu")
		(net "M_L_MA<17>")
	)
	(segment
		(start 109.141768 -131.2418)
		(end 109.217968 -131.318)
		(width 0.14224)
		(layer "In11.Cu")
		(net "M_L_MA<17>")
	)
	(segment
		(start 110.558834 -145.369534)
		(end 110.449868 -145.4785)
		(width 0.14224)
		(layer "In11.Cu")
		(net "M_L_MA<17>")
	)
	(segment
		(start 109.159294 -137.881614)
		(end 110.449868 -139.172188)
		(width 0.14224)
		(layer "In11.Cu")
		(net "M_L_MA<17>")
	)
	(segment
		(start 102.639368 -120.700546)
		(end 109.344968 -127.406146)
		(width 0.14224)
		(layer "In11.Cu")
		(net "M_L_MA<17>")
	)
	(segment
		(start 109.39653 -132.926328)
		(end 109.39653 -133.812788)
		(width 0.14224)
		(layer "In11.Cu")
		(net "M_L_MA<17>")
	)
	(segment
		(start 109.159294 -134.050024)
		(end 109.159294 -137.881614)
		(width 0.14224)
		(layer "In11.Cu")
		(net "M_L_MA<17>")
	)
	(arc
		(start 100.147374 -97.39503)
		(mid 100.068243 -97.690432)
		(end 100.147374 -97.985834)
		(width 0.0889)
		(layer "In11.Cu")
		(net "M_L_MA<17>")
	)
	(arc
		(start 100.147374 -96.995234)
		(mid 100.200873 -97.195132)
		(end 100.147374 -97.39503)
		(width 0.0889)
		(layer "In11.Cu")
		(net "M_L_MA<17>")
	)
	(arc
		(start 100.147374 -97.985834)
		(mid 100.188455 -98.086813)
		(end 100.200714 -98.19513)
		(width 0.0889)
		(layer "In11.Cu")
		(net "M_L_MA<17>")
	)
	(segment
		(start 103.649526 -142.6718)
		(end 103.649526 -143.968978)
		(width 0.1651)
		(layer "F.Cu")
		(net "M_L_MA<16>")
	)
	(segment
		(start 96.938338 -95.21444)
		(end 96.366838 -95.21444)
		(width 0.1016)
		(layer "F.Cu")
		(net "M_L_MA<16>")
	)
	(via
		(at 103.649526 -143.968978)
		(size 0.508)
		(drill 0.254)
		(layers "F.Cu" "B.Cu")
		(net "M_L_MA<16>")
	)
	(via
		(at 103.649526 -141.183868)
		(size 0.4572)
		(drill 0.2032)
		(layers "F.Cu" "B.Cu")
		(net "M_L_MA<16>")
	)
	(via
		(at 96.366838 -95.21444)
		(size 0.508)
		(drill 0.254)
		(layers "F.Cu" "B.Cu")
		(net "M_L_MA<16>")
	)
	(segment
		(start 103.649526 -142.477236)
		(end 103.649526 -141.183868)
		(width 0.1651)
		(layer "B.Cu")
		(net "M_L_MA<16>")
	)
	(segment
		(start 103.649526 -140.817092)
		(end 103.210614 -140.37818)
		(width 0.14224)
		(layer "In4.Cu")
		(net "M_L_MA<16>")
	)
	(segment
		(start 103.660194 -142.764002)
		(end 103.801672 -142.622524)
		(width 0.14224)
		(layer "In4.Cu")
		(net "M_L_MA<16>")
	)
	(segment
		(start 101.928168 -127.23876)
		(end 98.600768 -123.91136)
		(width 0.14224)
		(layer "In4.Cu")
		(net "M_L_MA<16>")
	)
	(segment
		(start 96.873822 -97.499424)
		(end 96.878648 -97.490788)
		(width 0.0889)
		(layer "In4.Cu")
		(net "M_L_MA<16>")
	)
	(segment
		(start 103.210614 -138.798046)
		(end 102.385368 -137.9728)
		(width 0.14224)
		(layer "In4.Cu")
		(net "M_L_MA<16>")
	)
	(segment
		(start 103.210614 -140.37818)
		(end 103.210614 -138.798046)
		(width 0.14224)
		(layer "In4.Cu")
		(net "M_L_MA<16>")
	)
	(segment
		(start 104.780842 -143.18488)
		(end 104.599486 -143.366236)
		(width 0.14224)
		(layer "In4.Cu")
		(net "M_L_MA<16>")
	)
	(segment
		(start 103.218742 -142.566898)
		(end 103.415846 -142.764002)
		(width 0.14224)
		(layer "In4.Cu")
		(net "M_L_MA<16>")
	)
	(segment
		(start 103.801672 -142.303754)
		(end 103.956612 -142.148814)
		(width 0.14224)
		(layer "In4.Cu")
		(net "M_L_MA<16>")
	)
	(segment
		(start 96.878648 -98.481388)
		(end 96.884998 -98.47072)
		(width 0.0889)
		(layer "In4.Cu")
		(net "M_L_MA<16>")
	)
	(segment
		(start 103.24592 -143.797528)
		(end 103.41737 -143.968978)
		(width 0.14224)
		(layer "In4.Cu")
		(net "M_L_MA<16>")
	)
	(segment
		(start 97.051368 -101.1936)
		(end 97.051368 -99.1616)
		(width 0.0889)
		(layer "In4.Cu")
		(net "M_L_MA<16>")
	)
	(segment
		(start 96.878648 -97.490788)
		(end 96.884998 -97.48012)
		(width 0.0889)
		(layer "In4.Cu")
		(net "M_L_MA<16>")
	)
	(segment
		(start 102.385368 -137.9728)
		(end 102.385368 -135.9662)
		(width 0.14224)
		(layer "In4.Cu")
		(net "M_L_MA<16>")
	)
	(segment
		(start 103.41737 -143.968978)
		(end 103.649526 -143.968978)
		(width 0.14224)
		(layer "In4.Cu")
		(net "M_L_MA<16>")
	)
	(segment
		(start 102.283768 -131.1148)
		(end 102.283768 -130.6576)
		(width 0.14224)
		(layer "In4.Cu")
		(net "M_L_MA<16>")
	)
	(segment
		(start 102.3747 -135.955532)
		(end 102.3747 -131.989068)
		(width 0.14224)
		(layer "In4.Cu")
		(net "M_L_MA<16>")
	)
	(segment
		(start 98.600768 -103.097584)
		(end 98.428048 -102.924864)
		(width 0.0889)
		(layer "In4.Cu")
		(net "M_L_MA<16>")
	)
	(segment
		(start 96.873822 -98.490024)
		(end 96.878648 -98.481388)
		(width 0.0889)
		(layer "In4.Cu")
		(net "M_L_MA<16>")
	)
	(segment
		(start 103.649526 -141.183868)
		(end 103.424482 -141.183868)
		(width 0.14224)
		(layer "In4.Cu")
		(net "M_L_MA<16>")
	)
	(segment
		(start 101.928168 -127.584454)
		(end 101.928168 -127.23876)
		(width 0.14224)
		(layer "In4.Cu")
		(net "M_L_MA<16>")
	)
	(segment
		(start 96.873822 -96.508824)
		(end 96.878648 -96.500188)
		(width 0.0889)
		(layer "In4.Cu")
		(net "M_L_MA<16>")
	)
	(segment
		(start 96.878648 -96.500188)
		(end 96.884998 -96.48952)
		(width 0.0889)
		(layer "In4.Cu")
		(net "M_L_MA<16>")
	)
	(segment
		(start 101.50348 -128.57861)
		(end 101.50348 -128.009142)
		(width 0.14224)
		(layer "In4.Cu")
		(net "M_L_MA<16>")
	)
	(segment
		(start 103.415846 -142.764002)
		(end 103.660194 -142.764002)
		(width 0.14224)
		(layer "In4.Cu")
		(net "M_L_MA<16>")
	)
	(segment
		(start 102.436168 -130.5052)
		(end 102.436168 -129.9972)
		(width 0.14224)
		(layer "In4.Cu")
		(net "M_L_MA<16>")
	)
	(segment
		(start 103.424482 -141.183868)
		(end 103.218742 -141.389608)
		(width 0.14224)
		(layer "In4.Cu")
		(net "M_L_MA<16>")
	)
	(segment
		(start 103.801672 -142.622524)
		(end 103.801672 -142.303754)
		(width 0.14224)
		(layer "In4.Cu")
		(net "M_L_MA<16>")
	)
	(segment
		(start 103.218742 -141.389608)
		(end 103.218742 -142.566898)
		(width 0.14224)
		(layer "In4.Cu")
		(net "M_L_MA<16>")
	)
	(segment
		(start 104.618028 -142.148814)
		(end 104.780842 -142.311628)
		(width 0.14224)
		(layer "In4.Cu")
		(net "M_L_MA<16>")
	)
	(segment
		(start 103.24592 -143.521176)
		(end 103.24592 -143.797528)
		(width 0.14224)
		(layer "In4.Cu")
		(net "M_L_MA<16>")
	)
	(segment
		(start 103.956612 -142.148814)
		(end 104.618028 -142.148814)
		(width 0.14224)
		(layer "In4.Cu")
		(net "M_L_MA<16>")
	)
	(segment
		(start 98.600768 -123.91136)
		(end 98.600768 -103.283766)
		(width 0.14224)
		(layer "In4.Cu")
		(net "M_L_MA<16>")
	)
	(segment
		(start 102.461568 -131.2926)
		(end 102.283768 -131.1148)
		(width 0.14224)
		(layer "In4.Cu")
		(net "M_L_MA<16>")
	)
	(segment
		(start 102.309168 -129.8702)
		(end 102.309168 -129.384298)
		(width 0.14224)
		(layer "In4.Cu")
		(net "M_L_MA<16>")
	)
	(segment
		(start 103.649526 -141.183868)
		(end 103.649526 -140.817092)
		(width 0.14224)
		(layer "In4.Cu")
		(net "M_L_MA<16>")
	)
	(segment
		(start 102.461568 -131.9022)
		(end 102.461568 -131.2926)
		(width 0.14224)
		(layer "In4.Cu")
		(net "M_L_MA<16>")
	)
	(segment
		(start 102.309168 -129.384298)
		(end 101.50348 -128.57861)
		(width 0.14224)
		(layer "In4.Cu")
		(net "M_L_MA<16>")
	)
	(segment
		(start 103.40086 -143.366236)
		(end 103.24592 -143.521176)
		(width 0.14224)
		(layer "In4.Cu")
		(net "M_L_MA<16>")
	)
	(segment
		(start 101.50348 -128.009142)
		(end 101.928168 -127.584454)
		(width 0.14224)
		(layer "In4.Cu")
		(net "M_L_MA<16>")
	)
	(segment
		(start 98.428048 -102.57028)
		(end 97.051368 -101.1936)
		(width 0.0889)
		(layer "In4.Cu")
		(net "M_L_MA<16>")
	)
	(segment
		(start 98.428048 -102.924864)
		(end 98.428048 -102.57028)
		(width 0.0889)
		(layer "In4.Cu")
		(net "M_L_MA<16>")
	)
	(segment
		(start 98.600768 -103.283766)
		(end 98.600768 -103.097584)
		(width 0.0889)
		(layer "In4.Cu")
		(net "M_L_MA<16>")
	)
	(segment
		(start 102.436168 -129.9972)
		(end 102.309168 -129.8702)
		(width 0.14224)
		(layer "In4.Cu")
		(net "M_L_MA<16>")
	)
	(segment
		(start 102.3747 -131.989068)
		(end 102.461568 -131.9022)
		(width 0.14224)
		(layer "In4.Cu")
		(net "M_L_MA<16>")
	)
	(segment
		(start 102.385368 -135.9662)
		(end 102.3747 -135.955532)
		(width 0.14224)
		(layer "In4.Cu")
		(net "M_L_MA<16>")
	)
	(segment
		(start 104.780842 -142.311628)
		(end 104.780842 -143.18488)
		(width 0.14224)
		(layer "In4.Cu")
		(net "M_L_MA<16>")
	)
	(segment
		(start 102.283768 -130.6576)
		(end 102.436168 -130.5052)
		(width 0.14224)
		(layer "In4.Cu")
		(net "M_L_MA<16>")
	)
	(segment
		(start 104.599486 -143.366236)
		(end 103.40086 -143.366236)
		(width 0.14224)
		(layer "In4.Cu")
		(net "M_L_MA<16>")
	)
	(arc
		(start 96.878648 -98.881438)
		(mid 96.825178 -98.686375)
		(end 96.873822 -98.490024)
		(width 0.0889)
		(layer "In4.Cu")
		(net "M_L_MA<16>")
	)
	(arc
		(start 96.878648 -97.890838)
		(mid 96.825178 -97.695775)
		(end 96.873822 -97.499424)
		(width 0.0889)
		(layer "In4.Cu")
		(net "M_L_MA<16>")
	)
	(arc
		(start 97.051368 -99.1616)
		(mid 96.962946 -99.02279)
		(end 96.878648 -98.881438)
		(width 0.0889)
		(layer "In4.Cu")
		(net "M_L_MA<16>")
	)
	(arc
		(start 96.878648 -95.909638)
		(mid 96.841998 -95.824827)
		(end 96.825816 -95.73387)
		(width 0.0889)
		(layer "In4.Cu")
		(net "M_L_MA<16>")
	)
	(arc
		(start 96.884998 -97.48012)
		(mid 96.957796 -97.189357)
		(end 96.878648 -96.900238)
		(width 0.0889)
		(layer "In4.Cu")
		(net "M_L_MA<16>")
	)
	(arc
		(start 96.884998 -98.47072)
		(mid 96.957796 -98.179957)
		(end 96.878648 -97.890838)
		(width 0.0889)
		(layer "In4.Cu")
		(net "M_L_MA<16>")
	)
	(arc
		(start 96.884998 -96.48952)
		(mid 96.957796 -96.198757)
		(end 96.878648 -95.909638)
		(width 0.0889)
		(layer "In4.Cu")
		(net "M_L_MA<16>")
	)
	(arc
		(start 96.878648 -96.900238)
		(mid 96.825178 -96.705175)
		(end 96.873822 -96.508824)
		(width 0.0889)
		(layer "In4.Cu")
		(net "M_L_MA<16>")
	)
	(arc
		(start 96.825816 -95.73387)
		(mid 96.694638 -95.387267)
		(end 96.366838 -95.21444)
		(width 0.0889)
		(layer "In4.Cu")
		(net "M_L_MA<16>")
	)
	(segment
		(start 107.04957 -142.6718)
		(end 107.04957 -143.972534)
		(width 0.1651)
		(layer "F.Cu")
		(net "M_L_MA<15>")
	)
	(segment
		(start 96.938338 -96.20504)
		(end 96.366838 -96.20504)
		(width 0.1016)
		(layer "F.Cu")
		(net "M_L_MA<15>")
	)
	(segment
		(start 107.04957 -143.972534)
		(end 107.049824 -143.972788)
		(width 0.1651)
		(layer "F.Cu")
		(net "M_L_MA<15>")
	)
	(via
		(at 107.049824 -141.187678)
		(size 0.4572)
		(drill 0.2032)
		(layers "F.Cu" "B.Cu")
		(net "M_L_MA<15>")
	)
	(via
		(at 107.049824 -143.972788)
		(size 0.4572)
		(drill 0.2032)
		(layers "F.Cu" "B.Cu")
		(net "M_L_MA<15>")
	)
	(via
		(at 96.366838 -96.20504)
		(size 0.508)
		(drill 0.254)
		(layers "F.Cu" "B.Cu")
		(net "M_L_MA<15>")
	)
	(segment
		(start 107.04957 -141.187932)
		(end 107.049824 -141.187678)
		(width 0.10795)
		(layer "B.Cu")
		(net "M_L_MA<15>")
	)
	(segment
		(start 107.04957 -142.477236)
		(end 107.04957 -141.187932)
		(width 0.10795)
		(layer "B.Cu")
		(net "M_L_MA<15>")
	)
	(segment
		(start 98.549968 -100.8634)
		(end 98.549968 -102.6922)
		(width 0.14224)
		(layer "In11.Cu")
		(net "M_L_MA<15>")
	)
	(segment
		(start 96.848168 -97.3836)
		(end 96.746568 -97.4852)
		(width 0.14224)
		(layer "In11.Cu")
		(net "M_L_MA<15>")
	)
	(segment
		(start 97.076768 -99.3902)
		(end 98.549968 -100.8634)
		(width 0.14224)
		(layer "In11.Cu")
		(net "M_L_MA<15>")
	)
	(segment
		(start 108.180632 -142.786608)
		(end 108.335572 -142.941548)
		(width 0.14224)
		(layer "In11.Cu")
		(net "M_L_MA<15>")
	)
	(segment
		(start 105.76306 -138.063732)
		(end 106.636566 -138.937238)
		(width 0.14224)
		(layer "In11.Cu")
		(net "M_L_MA<15>")
	)
	(segment
		(start 108.335572 -143.193008)
		(end 108.180632 -143.347948)
		(width 0.14224)
		(layer "In11.Cu")
		(net "M_L_MA<15>")
	)
	(segment
		(start 107.204764 -142.225268)
		(end 107.049824 -142.380208)
		(width 0.14224)
		(layer "In11.Cu")
		(net "M_L_MA<15>")
	)
	(segment
		(start 107.049824 -143.502888)
		(end 107.049824 -143.972788)
		(width 0.14224)
		(layer "In11.Cu")
		(net "M_L_MA<15>")
	)
	(segment
		(start 96.746568 -98.4758)
		(end 96.746568 -98.8822)
		(width 0.14224)
		(layer "In11.Cu")
		(net "M_L_MA<15>")
	)
	(segment
		(start 106.525568 -139.6238)
		(end 106.525568 -140.663422)
		(width 0.14224)
		(layer "In11.Cu")
		(net "M_L_MA<15>")
	)
	(segment
		(start 104.976168 -131.2164)
		(end 104.874568 -131.318)
		(width 0.14224)
		(layer "In11.Cu")
		(net "M_L_MA<15>")
	)
	(segment
		(start 105.76306 -136.016492)
		(end 105.76306 -138.063732)
		(width 0.14224)
		(layer "In11.Cu")
		(net "M_L_MA<15>")
	)
	(segment
		(start 104.976168 -130.6322)
		(end 104.976168 -131.2164)
		(width 0.14224)
		(layer "In11.Cu")
		(net "M_L_MA<15>")
	)
	(segment
		(start 108.180632 -143.347948)
		(end 107.204764 -143.347948)
		(width 0.14224)
		(layer "In11.Cu")
		(net "M_L_MA<15>")
	)
	(segment
		(start 106.636566 -139.512802)
		(end 106.525568 -139.6238)
		(width 0.14224)
		(layer "In11.Cu")
		(net "M_L_MA<15>")
	)
	(segment
		(start 96.366838 -96.20504)
		(end 96.366838 -96.521016)
		(width 0.14224)
		(layer "In11.Cu")
		(net "M_L_MA<15>")
	)
	(segment
		(start 97.076768 -99.2124)
		(end 97.076768 -99.3902)
		(width 0.14224)
		(layer "In11.Cu")
		(net "M_L_MA<15>")
	)
	(segment
		(start 104.874568 -131.318)
		(end 104.874568 -133.8834)
		(width 0.14224)
		(layer "In11.Cu")
		(net "M_L_MA<15>")
	)
	(segment
		(start 96.848168 -97.002346)
		(end 96.848168 -97.3836)
		(width 0.14224)
		(layer "In11.Cu")
		(net "M_L_MA<15>")
	)
	(segment
		(start 107.204764 -143.347948)
		(end 107.049824 -143.502888)
		(width 0.14224)
		(layer "In11.Cu")
		(net "M_L_MA<15>")
	)
	(segment
		(start 108.303822 -142.075662)
		(end 108.154216 -142.225268)
		(width 0.14224)
		(layer "In11.Cu")
		(net "M_L_MA<15>")
	)
	(segment
		(start 96.746568 -98.8822)
		(end 97.076768 -99.2124)
		(width 0.14224)
		(layer "In11.Cu")
		(net "M_L_MA<15>")
	)
	(segment
		(start 104.874568 -129.9718)
		(end 104.874568 -130.5306)
		(width 0.14224)
		(layer "In11.Cu")
		(net "M_L_MA<15>")
	)
	(segment
		(start 108.303822 -141.824202)
		(end 108.303822 -142.075662)
		(width 0.14224)
		(layer "In11.Cu")
		(net "M_L_MA<15>")
	)
	(segment
		(start 96.882204 -98.052636)
		(end 96.882204 -98.340164)
		(width 0.14224)
		(layer "In11.Cu")
		(net "M_L_MA<15>")
	)
	(segment
		(start 104.823768 -126.649226)
		(end 104.823768 -129.2098)
		(width 0.14224)
		(layer "In11.Cu")
		(net "M_L_MA<15>")
	)
	(segment
		(start 107.049824 -142.380208)
		(end 107.049824 -142.631668)
		(width 0.14224)
		(layer "In11.Cu")
		(net "M_L_MA<15>")
	)
	(segment
		(start 96.882204 -98.340164)
		(end 96.746568 -98.4758)
		(width 0.14224)
		(layer "In11.Cu")
		(net "M_L_MA<15>")
	)
	(segment
		(start 107.049824 -141.187678)
		(end 107.049824 -141.508988)
		(width 0.14224)
		(layer "In11.Cu")
		(net "M_L_MA<15>")
	)
	(segment
		(start 106.636566 -138.937238)
		(end 106.636566 -139.512802)
		(width 0.14224)
		(layer "In11.Cu")
		(net "M_L_MA<15>")
	)
	(segment
		(start 104.874568 -130.5306)
		(end 104.976168 -130.6322)
		(width 0.14224)
		(layer "In11.Cu")
		(net "M_L_MA<15>")
	)
	(segment
		(start 96.746568 -97.917)
		(end 96.882204 -98.052636)
		(width 0.14224)
		(layer "In11.Cu")
		(net "M_L_MA<15>")
	)
	(segment
		(start 108.143548 -141.663928)
		(end 108.303822 -141.824202)
		(width 0.14224)
		(layer "In11.Cu")
		(net "M_L_MA<15>")
	)
	(segment
		(start 104.874568 -133.8834)
		(end 104.9274 -133.936232)
		(width 0.14224)
		(layer "In11.Cu")
		(net "M_L_MA<15>")
	)
	(segment
		(start 96.366838 -96.521016)
		(end 96.848168 -97.002346)
		(width 0.14224)
		(layer "In11.Cu")
		(net "M_L_MA<15>")
	)
	(segment
		(start 99.962716 -104.104948)
		(end 99.962716 -121.788174)
		(width 0.14224)
		(layer "In11.Cu")
		(net "M_L_MA<15>")
	)
	(segment
		(start 107.204764 -142.786608)
		(end 108.180632 -142.786608)
		(width 0.14224)
		(layer "In11.Cu")
		(net "M_L_MA<15>")
	)
	(segment
		(start 107.049824 -141.508988)
		(end 107.204764 -141.663928)
		(width 0.14224)
		(layer "In11.Cu")
		(net "M_L_MA<15>")
	)
	(segment
		(start 106.525568 -140.663422)
		(end 107.049824 -141.187678)
		(width 0.14224)
		(layer "In11.Cu")
		(net "M_L_MA<15>")
	)
	(segment
		(start 105.001568 -129.8448)
		(end 104.874568 -129.9718)
		(width 0.14224)
		(layer "In11.Cu")
		(net "M_L_MA<15>")
	)
	(segment
		(start 104.823768 -129.2098)
		(end 105.001568 -129.3876)
		(width 0.14224)
		(layer "In11.Cu")
		(net "M_L_MA<15>")
	)
	(segment
		(start 107.049824 -142.631668)
		(end 107.204764 -142.786608)
		(width 0.14224)
		(layer "In11.Cu")
		(net "M_L_MA<15>")
	)
	(segment
		(start 108.335572 -142.941548)
		(end 108.335572 -143.193008)
		(width 0.14224)
		(layer "In11.Cu")
		(net "M_L_MA<15>")
	)
	(segment
		(start 108.154216 -142.225268)
		(end 107.204764 -142.225268)
		(width 0.14224)
		(layer "In11.Cu")
		(net "M_L_MA<15>")
	)
	(segment
		(start 104.9274 -135.180832)
		(end 105.76306 -136.016492)
		(width 0.14224)
		(layer "In11.Cu")
		(net "M_L_MA<15>")
	)
	(segment
		(start 99.962716 -121.788174)
		(end 104.823768 -126.649226)
		(width 0.14224)
		(layer "In11.Cu")
		(net "M_L_MA<15>")
	)
	(segment
		(start 98.549968 -102.6922)
		(end 99.962716 -104.104948)
		(width 0.14224)
		(layer "In11.Cu")
		(net "M_L_MA<15>")
	)
	(segment
		(start 105.001568 -129.3876)
		(end 105.001568 -129.8448)
		(width 0.14224)
		(layer "In11.Cu")
		(net "M_L_MA<15>")
	)
	(segment
		(start 96.746568 -97.4852)
		(end 96.746568 -97.917)
		(width 0.14224)
		(layer "In11.Cu")
		(net "M_L_MA<15>")
	)
	(segment
		(start 107.204764 -141.663928)
		(end 108.143548 -141.663928)
		(width 0.14224)
		(layer "In11.Cu")
		(net "M_L_MA<15>")
	)
	(segment
		(start 104.9274 -133.936232)
		(end 104.9274 -135.180832)
		(width 0.14224)
		(layer "In11.Cu")
		(net "M_L_MA<15>")
	)
	(segment
		(start 105.349548 -145.988532)
		(end 105.349802 -145.988278)
		(width 0.1651)
		(layer "F.Cu")
		(net "M_L_MA<14>")
	)
	(segment
		(start 105.349548 -147.27174)
		(end 105.349548 -145.988532)
		(width 0.1651)
		(layer "F.Cu")
		(net "M_L_MA<14>")
	)
	(segment
		(start 97.796858 -94.718886)
		(end 97.225358 -94.718886)
		(width 0.1016)
		(layer "F.Cu")
		(net "M_L_MA<14>")
	)
	(via
		(at 105.349802 -139.172188)
		(size 0.4572)
		(drill 0.2032)
		(layers "F.Cu" "B.Cu")
		(net "M_L_MA<14>")
	)
	(via
		(at 97.225358 -94.718886)
		(size 0.508)
		(drill 0.254)
		(layers "F.Cu" "B.Cu")
		(net "M_L_MA<14>")
	)
	(via
		(at 105.349802 -145.988278)
		(size 0.4572)
		(drill 0.2032)
		(layers "F.Cu" "B.Cu")
		(net "M_L_MA<14>")
	)
	(segment
		(start 105.349548 -137.877296)
		(end 105.349548 -139.171934)
		(width 0.1651)
		(layer "B.Cu")
		(net "M_L_MA<14>")
	)
	(segment
		(start 105.349548 -139.171934)
		(end 105.349802 -139.172188)
		(width 0.1651)
		(layer "B.Cu")
		(net "M_L_MA<14>")
	)
	(segment
		(start 103.091742 -125.220476)
		(end 102.68839 -125.623828)
		(width 0.14224)
		(layer "In4.Cu")
		(net "M_L_MA<14>")
	)
	(segment
		(start 102.841806 -124.746512)
		(end 103.091742 -124.996448)
		(width 0.14224)
		(layer "In4.Cu")
		(net "M_L_MA<14>")
	)
	(segment
		(start 104.908604 -138.048746)
		(end 105.349802 -138.489944)
		(width 0.14224)
		(layer "In4.Cu")
		(net "M_L_MA<14>")
	)
	(segment
		(start 97.572068 -96.500188)
		(end 97.576894 -96.508824)
		(width 0.0889)
		(layer "In4.Cu")
		(net "M_L_MA<14>")
	)
	(segment
		(start 100.124768 -122.009662)
		(end 101.634544 -123.519438)
		(width 0.14224)
		(layer "In4.Cu")
		(net "M_L_MA<14>")
	)
	(segment
		(start 104.874568 -134.7724)
		(end 104.874568 -135.3058)
		(width 0.14224)
		(layer "In4.Cu")
		(net "M_L_MA<14>")
	)
	(segment
		(start 98.483928 -98.81616)
		(end 98.740468 -99.0727)
		(width 0.0889)
		(layer "In4.Cu")
		(net "M_L_MA<14>")
	)
	(segment
		(start 97.225358 -94.718886)
		(end 97.554796 -95.47987)
		(width 0.0889)
		(layer "In4.Cu")
		(net "M_L_MA<14>")
	)
	(segment
		(start 100.124768 -103.297736)
		(end 100.124768 -122.009662)
		(width 0.14224)
		(layer "In4.Cu")
		(net "M_L_MA<14>")
	)
	(segment
		(start 105.349294 -145.448274)
		(end 105.349802 -145.448782)
		(width 0.14224)
		(layer "In4.Cu")
		(net "M_L_MA<14>")
	)
	(segment
		(start 104.874568 -135.3058)
		(end 104.908604 -135.339836)
		(width 0.14224)
		(layer "In4.Cu")
		(net "M_L_MA<14>")
	)
	(segment
		(start 102.628192 -124.746512)
		(end 102.841806 -124.746512)
		(width 0.14224)
		(layer "In4.Cu")
		(net "M_L_MA<14>")
	)
	(segment
		(start 104.976168 -130.7084)
		(end 104.976168 -131.0894)
		(width 0.14224)
		(layer "In4.Cu")
		(net "M_L_MA<14>")
	)
	(segment
		(start 98.066098 -97.78619)
		(end 98.098864 -97.78619)
		(width 0.0889)
		(layer "In4.Cu")
		(net "M_L_MA<14>")
	)
	(segment
		(start 104.874568 -130.6068)
		(end 104.976168 -130.7084)
		(width 0.14224)
		(layer "In4.Cu")
		(net "M_L_MA<14>")
	)
	(segment
		(start 105.026968 -128.181354)
		(end 105.026968 -129.7432)
		(width 0.14224)
		(layer "In4.Cu")
		(net "M_L_MA<14>")
	)
	(segment
		(start 104.934766 -134.095998)
		(end 104.934766 -134.712202)
		(width 0.14224)
		(layer "In4.Cu")
		(net "M_L_MA<14>")
	)
	(segment
		(start 100.124768 -103.0478)
		(end 100.124768 -103.297736)
		(width 0.0889)
		(layer "In4.Cu")
		(net "M_L_MA<14>")
	)
	(segment
		(start 99.946968 -102.87)
		(end 100.124768 -103.0478)
		(width 0.0889)
		(layer "In4.Cu")
		(net "M_L_MA<14>")
	)
	(segment
		(start 102.000558 -125.154944)
		(end 102.21976 -125.154944)
		(width 0.14224)
		(layer "In4.Cu")
		(net "M_L_MA<14>")
	)
	(segment
		(start 101.634544 -123.519438)
		(end 101.634544 -124.78893)
		(width 0.14224)
		(layer "In4.Cu")
		(net "M_L_MA<14>")
	)
	(segment
		(start 105.349802 -145.448782)
		(end 105.349802 -145.988278)
		(width 0.14224)
		(layer "In4.Cu")
		(net "M_L_MA<14>")
	)
	(segment
		(start 102.68839 -125.623828)
		(end 102.68839 -125.842776)
		(width 0.14224)
		(layer "In4.Cu")
		(net "M_L_MA<14>")
	)
	(segment
		(start 105.026968 -129.7432)
		(end 104.874568 -129.8956)
		(width 0.14224)
		(layer "In4.Cu")
		(net "M_L_MA<14>")
	)
	(segment
		(start 105.349802 -139.172188)
		(end 105.759504 -139.58189)
		(width 0.14224)
		(layer "In4.Cu")
		(net "M_L_MA<14>")
	)
	(segment
		(start 101.634544 -124.78893)
		(end 102.000558 -125.154944)
		(width 0.14224)
		(layer "In4.Cu")
		(net "M_L_MA<14>")
	)
	(segment
		(start 104.874568 -129.8956)
		(end 104.874568 -130.6068)
		(width 0.14224)
		(layer "In4.Cu")
		(net "M_L_MA<14>")
	)
	(segment
		(start 104.874568 -131.191)
		(end 104.874568 -134.0358)
		(width 0.14224)
		(layer "In4.Cu")
		(net "M_L_MA<14>")
	)
	(segment
		(start 102.68839 -125.842776)
		(end 105.026968 -128.181354)
		(width 0.14224)
		(layer "In4.Cu")
		(net "M_L_MA<14>")
	)
	(segment
		(start 99.946968 -102.0826)
		(end 99.946968 -102.87)
		(width 0.0889)
		(layer "In4.Cu")
		(net "M_L_MA<14>")
	)
	(segment
		(start 104.874568 -134.0358)
		(end 104.934766 -134.095998)
		(width 0.14224)
		(layer "In4.Cu")
		(net "M_L_MA<14>")
	)
	(segment
		(start 105.759504 -139.58189)
		(end 105.759504 -145.038064)
		(width 0.14224)
		(layer "In4.Cu")
		(net "M_L_MA<14>")
	)
	(segment
		(start 102.21976 -125.154944)
		(end 102.628192 -124.746512)
		(width 0.14224)
		(layer "In4.Cu")
		(net "M_L_MA<14>")
	)
	(segment
		(start 97.554796 -95.47987)
		(end 97.576894 -95.518224)
		(width 0.0889)
		(layer "In4.Cu")
		(net "M_L_MA<14>")
	)
	(segment
		(start 97.565718 -96.48952)
		(end 97.572068 -96.500188)
		(width 0.0889)
		(layer "In4.Cu")
		(net "M_L_MA<14>")
	)
	(segment
		(start 104.934766 -134.712202)
		(end 104.874568 -134.7724)
		(width 0.14224)
		(layer "In4.Cu")
		(net "M_L_MA<14>")
	)
	(segment
		(start 103.091742 -124.996448)
		(end 103.091742 -125.220476)
		(width 0.14224)
		(layer "In4.Cu")
		(net "M_L_MA<14>")
	)
	(segment
		(start 105.759504 -145.038064)
		(end 105.349294 -145.448274)
		(width 0.14224)
		(layer "In4.Cu")
		(net "M_L_MA<14>")
	)
	(segment
		(start 105.349802 -138.489944)
		(end 105.349802 -139.172188)
		(width 0.14224)
		(layer "In4.Cu")
		(net "M_L_MA<14>")
	)
	(segment
		(start 98.740468 -100.8761)
		(end 99.946968 -102.0826)
		(width 0.0889)
		(layer "In4.Cu")
		(net "M_L_MA<14>")
	)
	(segment
		(start 98.740468 -99.0727)
		(end 98.740468 -100.8761)
		(width 0.0889)
		(layer "In4.Cu")
		(net "M_L_MA<14>")
	)
	(segment
		(start 98.483928 -98.195384)
		(end 98.483928 -98.81616)
		(width 0.0889)
		(layer "In4.Cu")
		(net "M_L_MA<14>")
	)
	(segment
		(start 104.976168 -131.0894)
		(end 104.874568 -131.191)
		(width 0.14224)
		(layer "In4.Cu")
		(net "M_L_MA<14>")
	)
	(segment
		(start 104.908604 -135.339836)
		(end 104.908604 -138.048746)
		(width 0.14224)
		(layer "In4.Cu")
		(net "M_L_MA<14>")
	)
	(arc
		(start 97.572068 -95.909638)
		(mid 97.492846 -96.198756)
		(end 97.565718 -96.48952)
		(width 0.0889)
		(layer "In4.Cu")
		(net "M_L_MA<14>")
	)
	(arc
		(start 97.572068 -96.900238)
		(mid 97.567739 -97.48341)
		(end 98.066098 -97.78619)
		(width 0.0889)
		(layer "In4.Cu")
		(net "M_L_MA<14>")
	)
	(arc
		(start 97.576894 -96.508824)
		(mid 97.625649 -96.705176)
		(end 97.572068 -96.900238)
		(width 0.0889)
		(layer "In4.Cu")
		(net "M_L_MA<14>")
	)
	(arc
		(start 98.098864 -97.78619)
		(mid 98.375359 -97.911825)
		(end 98.483928 -98.195384)
		(width 0.0889)
		(layer "In4.Cu")
		(net "M_L_MA<14>")
	)
	(arc
		(start 97.576894 -95.518224)
		(mid 97.625649 -95.714576)
		(end 97.572068 -95.909638)
		(width 0.0889)
		(layer "In4.Cu")
		(net "M_L_MA<14>")
	)
	(segment
		(start 108.749338 -145.988786)
		(end 108.749846 -145.988278)
		(width 0.1651)
		(layer "F.Cu")
		(net "M_L_MA<13>")
	)
	(segment
		(start 108.749338 -147.27174)
		(end 108.749338 -145.988786)
		(width 0.1651)
		(layer "F.Cu")
		(net "M_L_MA<13>")
	)
	(segment
		(start 97.796858 -96.700086)
		(end 97.225358 -96.700086)
		(width 0.1016)
		(layer "F.Cu")
		(net "M_L_MA<13>")
	)
	(via
		(at 97.225358 -96.700086)
		(size 0.508)
		(drill 0.254)
		(layers "F.Cu" "B.Cu")
		(net "M_L_MA<13>")
	)
	(via
		(at 108.749846 -145.988278)
		(size 0.4572)
		(drill 0.2032)
		(layers "F.Cu" "B.Cu")
		(net "M_L_MA<13>")
	)
	(via
		(at 108.749846 -139.172188)
		(size 0.4572)
		(drill 0.2032)
		(layers "F.Cu" "B.Cu")
		(net "M_L_MA<13>")
	)
	(segment
		(start 108.749338 -139.17168)
		(end 108.749846 -139.172188)
		(width 0.1651)
		(layer "B.Cu")
		(net "M_L_MA<13>")
	)
	(segment
		(start 108.749338 -137.877296)
		(end 108.749338 -139.17168)
		(width 0.1651)
		(layer "B.Cu")
		(net "M_L_MA<13>")
	)
	(segment
		(start 106.393742 -135.224774)
		(end 106.393742 -135.780018)
		(width 0.14224)
		(layer "In11.Cu")
		(net "M_L_MA<13>")
	)
	(segment
		(start 100.470716 -103.952548)
		(end 100.470716 -121.577354)
		(width 0.14224)
		(layer "In11.Cu")
		(net "M_L_MA<13>")
	)
	(segment
		(start 106.795062 -137.725912)
		(end 106.640122 -137.880852)
		(width 0.14224)
		(layer "In11.Cu")
		(net "M_L_MA<13>")
	)
	(segment
		(start 105.759504 -134.590536)
		(end 106.393742 -135.224774)
		(width 0.14224)
		(layer "In11.Cu")
		(net "M_L_MA<13>")
	)
	(segment
		(start 97.610168 -97.9678)
		(end 97.610168 -98.3996)
		(width 0.14224)
		(layer "In11.Cu")
		(net "M_L_MA<13>")
	)
	(segment
		(start 97.610168 -98.3996)
		(end 97.737168 -98.5266)
		(width 0.14224)
		(layer "In11.Cu")
		(net "M_L_MA<13>")
	)
	(segment
		(start 107.084368 -138.627612)
		(end 108.20527 -138.627612)
		(width 0.14224)
		(layer "In11.Cu")
		(net "M_L_MA<13>")
	)
	(segment
		(start 105.687368 -129.3114)
		(end 105.687368 -129.8448)
		(width 0.14224)
		(layer "In11.Cu")
		(net "M_L_MA<13>")
	)
	(segment
		(start 105.712768 -130.6576)
		(end 105.712768 -131.2164)
		(width 0.14224)
		(layer "In11.Cu")
		(net "M_L_MA<13>")
	)
	(segment
		(start 97.508568 -96.983296)
		(end 97.508568 -97.3074)
		(width 0.14224)
		(layer "In11.Cu")
		(net "M_L_MA<13>")
	)
	(segment
		(start 100.470716 -121.577354)
		(end 105.839768 -126.946406)
		(width 0.14224)
		(layer "In11.Cu")
		(net "M_L_MA<13>")
	)
	(segment
		(start 99.007168 -100.6348)
		(end 99.007168 -102.489)
		(width 0.14224)
		(layer "In11.Cu")
		(net "M_L_MA<13>")
	)
	(segment
		(start 97.508568 -97.3074)
		(end 97.686368 -97.4852)
		(width 0.14224)
		(layer "In11.Cu")
		(net "M_L_MA<13>")
	)
	(segment
		(start 106.032046 -132.217922)
		(end 105.759504 -132.490464)
		(width 0.14224)
		(layer "In11.Cu")
		(net "M_L_MA<13>")
	)
	(segment
		(start 107.402884 -137.725912)
		(end 106.795062 -137.725912)
		(width 0.14224)
		(layer "In11.Cu")
		(net "M_L_MA<13>")
	)
	(segment
		(start 105.839768 -126.946406)
		(end 105.839768 -129.159)
		(width 0.14224)
		(layer "In11.Cu")
		(net "M_L_MA<13>")
	)
	(segment
		(start 105.839768 -129.159)
		(end 105.687368 -129.3114)
		(width 0.14224)
		(layer "In11.Cu")
		(net "M_L_MA<13>")
	)
	(segment
		(start 106.89209 -137.062972)
		(end 107.423712 -137.062972)
		(width 0.14224)
		(layer "In11.Cu")
		(net "M_L_MA<13>")
	)
	(segment
		(start 109.189012 -141.506956)
		(end 109.159294 -141.536674)
		(width 0.14224)
		(layer "In11.Cu")
		(net "M_L_MA<13>")
	)
	(segment
		(start 105.687368 -129.8448)
		(end 105.839768 -129.9972)
		(width 0.14224)
		(layer "In11.Cu")
		(net "M_L_MA<13>")
	)
	(segment
		(start 107.568238 -137.207498)
		(end 107.568238 -137.560558)
		(width 0.14224)
		(layer "In11.Cu")
		(net "M_L_MA<13>")
	)
	(segment
		(start 109.159294 -144.289526)
		(end 108.749338 -144.699482)
		(width 0.14224)
		(layer "In11.Cu")
		(net "M_L_MA<13>")
	)
	(segment
		(start 106.393742 -135.780018)
		(end 106.640122 -136.026398)
		(width 0.14224)
		(layer "In11.Cu")
		(net "M_L_MA<13>")
	)
	(segment
		(start 108.749338 -144.699482)
		(end 108.749338 -145.98777)
		(width 0.14224)
		(layer "In11.Cu")
		(net "M_L_MA<13>")
	)
	(segment
		(start 106.640122 -138.183366)
		(end 107.084368 -138.627612)
		(width 0.14224)
		(layer "In11.Cu")
		(net "M_L_MA<13>")
	)
	(segment
		(start 98.600768 -100.2284)
		(end 99.007168 -100.6348)
		(width 0.14224)
		(layer "In11.Cu")
		(net "M_L_MA<13>")
	)
	(segment
		(start 106.640122 -137.880852)
		(end 106.640122 -138.183366)
		(width 0.14224)
		(layer "In11.Cu")
		(net "M_L_MA<13>")
	)
	(segment
		(start 97.686368 -97.8916)
		(end 97.610168 -97.9678)
		(width 0.14224)
		(layer "In11.Cu")
		(net "M_L_MA<13>")
	)
	(segment
		(start 105.839768 -130.5306)
		(end 105.712768 -130.6576)
		(width 0.14224)
		(layer "In11.Cu")
		(net "M_L_MA<13>")
	)
	(segment
		(start 109.189012 -139.611354)
		(end 109.189012 -141.506956)
		(width 0.14224)
		(layer "In11.Cu")
		(net "M_L_MA<13>")
	)
	(segment
		(start 105.839768 -129.9972)
		(end 105.839768 -130.5306)
		(width 0.14224)
		(layer "In11.Cu")
		(net "M_L_MA<13>")
	)
	(segment
		(start 97.686368 -97.4852)
		(end 97.686368 -97.8916)
		(width 0.14224)
		(layer "In11.Cu")
		(net "M_L_MA<13>")
	)
	(segment
		(start 109.159294 -141.536674)
		(end 109.159294 -144.289526)
		(width 0.14224)
		(layer "In11.Cu")
		(net "M_L_MA<13>")
	)
	(segment
		(start 108.20527 -138.627612)
		(end 108.749846 -139.172188)
		(width 0.14224)
		(layer "In11.Cu")
		(net "M_L_MA<13>")
	)
	(segment
		(start 108.749338 -145.98777)
		(end 108.749846 -145.988278)
		(width 0.14224)
		(layer "In11.Cu")
		(net "M_L_MA<13>")
	)
	(segment
		(start 97.737168 -98.8568)
		(end 98.600768 -99.7204)
		(width 0.14224)
		(layer "In11.Cu")
		(net "M_L_MA<13>")
	)
	(segment
		(start 105.712768 -131.2164)
		(end 106.032046 -131.535678)
		(width 0.14224)
		(layer "In11.Cu")
		(net "M_L_MA<13>")
	)
	(segment
		(start 108.749846 -139.172188)
		(end 109.189012 -139.611354)
		(width 0.14224)
		(layer "In11.Cu")
		(net "M_L_MA<13>")
	)
	(segment
		(start 98.600768 -99.7204)
		(end 98.600768 -100.2284)
		(width 0.14224)
		(layer "In11.Cu")
		(net "M_L_MA<13>")
	)
	(segment
		(start 97.737168 -98.5266)
		(end 97.737168 -98.8568)
		(width 0.14224)
		(layer "In11.Cu")
		(net "M_L_MA<13>")
	)
	(segment
		(start 107.568238 -137.560558)
		(end 107.402884 -137.725912)
		(width 0.14224)
		(layer "In11.Cu")
		(net "M_L_MA<13>")
	)
	(segment
		(start 106.032046 -131.535678)
		(end 106.032046 -132.217922)
		(width 0.14224)
		(layer "In11.Cu")
		(net "M_L_MA<13>")
	)
	(segment
		(start 107.423712 -137.062972)
		(end 107.568238 -137.207498)
		(width 0.14224)
		(layer "In11.Cu")
		(net "M_L_MA<13>")
	)
	(segment
		(start 97.225358 -96.700086)
		(end 97.508568 -96.983296)
		(width 0.14224)
		(layer "In11.Cu")
		(net "M_L_MA<13>")
	)
	(segment
		(start 105.759504 -132.490464)
		(end 105.759504 -134.590536)
		(width 0.14224)
		(layer "In11.Cu")
		(net "M_L_MA<13>")
	)
	(segment
		(start 106.640122 -136.811004)
		(end 106.89209 -137.062972)
		(width 0.14224)
		(layer "In11.Cu")
		(net "M_L_MA<13>")
	)
	(segment
		(start 99.007168 -102.489)
		(end 100.470716 -103.952548)
		(width 0.14224)
		(layer "In11.Cu")
		(net "M_L_MA<13>")
	)
	(segment
		(start 106.640122 -136.026398)
		(end 106.640122 -136.811004)
		(width 0.14224)
		(layer "In11.Cu")
		(net "M_L_MA<13>")
	)
	(segment
		(start 90.070178 -95.21444)
		(end 89.498678 -95.21444)
		(width 0.1016)
		(layer "F.Cu")
		(net "M_L_MA<12>")
	)
	(segment
		(start 84.0994 -142.6718)
		(end 84.0994 -143.970756)
		(width 0.1651)
		(layer "F.Cu")
		(net "M_L_MA<12>")
	)
	(via
		(at 89.498678 -95.21444)
		(size 0.508)
		(drill 0.254)
		(layers "F.Cu" "B.Cu")
		(net "M_L_MA<12>")
	)
	(via
		(at 84.0994 -143.970756)
		(size 0.4572)
		(drill 0.2032)
		(layers "F.Cu" "B.Cu")
		(net "M_L_MA<12>")
	)
	(via
		(at 84.0994 -141.187678)
		(size 0.4572)
		(drill 0.2032)
		(layers "F.Cu" "B.Cu")
		(net "M_L_MA<12>")
	)
	(segment
		(start 84.0994 -142.477236)
		(end 84.0994 -141.187678)
		(width 0.1651)
		(layer "B.Cu")
		(net "M_L_MA<12>")
	)
	(segment
		(start 87.018368 -129.8448)
		(end 87.145368 -129.9718)
		(width 0.14224)
		(layer "In11.Cu")
		(net "M_L_MA<12>")
	)
	(segment
		(start 87.119968 -131.9276)
		(end 87.069168 -131.9784)
		(width 0.14224)
		(layer "In11.Cu")
		(net "M_L_MA<12>")
	)
	(segment
		(start 89.498678 -95.21444)
		(end 89.168224 -95.977964)
		(width 0.0889)
		(layer "In11.Cu")
		(net "M_L_MA<12>")
	)
	(segment
		(start 87.145368 -130.5306)
		(end 87.018368 -130.6576)
		(width 0.14224)
		(layer "In11.Cu")
		(net "M_L_MA<12>")
	)
	(segment
		(start 87.018368 -129.2352)
		(end 87.018368 -129.8448)
		(width 0.14224)
		(layer "In11.Cu")
		(net "M_L_MA<12>")
	)
	(segment
		(start 86.459568 -135.7884)
		(end 86.212172 -136.035796)
		(width 0.14224)
		(layer "In11.Cu")
		(net "M_L_MA<12>")
	)
	(segment
		(start 90.310716 -103.038148)
		(end 90.310716 -103.586534)
		(width 0.0889)
		(layer "In11.Cu")
		(net "M_L_MA<12>")
	)
	(segment
		(start 90.310716 -103.586534)
		(end 90.310716 -123.733052)
		(width 0.14224)
		(layer "In11.Cu")
		(net "M_L_MA<12>")
	)
	(segment
		(start 87.018368 -130.6576)
		(end 87.018368 -131.2164)
		(width 0.14224)
		(layer "In11.Cu")
		(net "M_L_MA<12>")
	)
	(segment
		(start 89.349072 -100.121466)
		(end 89.958672 -100.731066)
		(width 0.0889)
		(layer "In11.Cu")
		(net "M_L_MA<12>")
	)
	(segment
		(start 83.663282 -138.897614)
		(end 83.663282 -140.75156)
		(width 0.14224)
		(layer "In11.Cu")
		(net "M_L_MA<12>")
	)
	(segment
		(start 87.069168 -131.9784)
		(end 87.069168 -135.079232)
		(width 0.14224)
		(layer "In11.Cu")
		(net "M_L_MA<12>")
	)
	(segment
		(start 87.145368 -129.9718)
		(end 87.145368 -130.5306)
		(width 0.14224)
		(layer "In11.Cu")
		(net "M_L_MA<12>")
	)
	(segment
		(start 87.018368 -131.2164)
		(end 87.119968 -131.318)
		(width 0.14224)
		(layer "In11.Cu")
		(net "M_L_MA<12>")
	)
	(segment
		(start 83.663282 -140.75156)
		(end 84.0994 -141.187678)
		(width 0.14224)
		(layer "In11.Cu")
		(net "M_L_MA<12>")
	)
	(segment
		(start 89.958672 -100.731066)
		(end 89.958672 -102.686104)
		(width 0.0889)
		(layer "In11.Cu")
		(net "M_L_MA<12>")
	)
	(segment
		(start 89.958672 -102.686104)
		(end 90.310716 -103.038148)
		(width 0.0889)
		(layer "In11.Cu")
		(net "M_L_MA<12>")
	)
	(segment
		(start 87.475568 -128.778)
		(end 87.018368 -129.2352)
		(width 0.14224)
		(layer "In11.Cu")
		(net "M_L_MA<12>")
	)
	(segment
		(start 90.310716 -123.733052)
		(end 87.475568 -126.5682)
		(width 0.14224)
		(layer "In11.Cu")
		(net "M_L_MA<12>")
	)
	(segment
		(start 89.168224 -95.977964)
		(end 89.152222 -96.005142)
		(width 0.0889)
		(layer "In11.Cu")
		(net "M_L_MA<12>")
	)
	(segment
		(start 86.212172 -136.035796)
		(end 86.212172 -136.821164)
		(width 0.14224)
		(layer "In11.Cu")
		(net "M_L_MA<12>")
	)
	(segment
		(start 87.119968 -131.318)
		(end 87.119968 -131.9276)
		(width 0.14224)
		(layer "In11.Cu")
		(net "M_L_MA<12>")
	)
	(segment
		(start 86.459568 -135.688832)
		(end 86.459568 -135.7884)
		(width 0.14224)
		(layer "In11.Cu")
		(net "M_L_MA<12>")
	)
	(segment
		(start 89.152222 -97.395538)
		(end 89.161112 -97.410778)
		(width 0.0889)
		(layer "In11.Cu")
		(net "M_L_MA<12>")
	)
	(segment
		(start 84.553552 -138.007344)
		(end 83.663282 -138.897614)
		(width 0.14224)
		(layer "In11.Cu")
		(net "M_L_MA<12>")
	)
	(segment
		(start 89.152222 -96.404938)
		(end 89.161112 -96.420178)
		(width 0.0889)
		(layer "In11.Cu")
		(net "M_L_MA<12>")
	)
	(segment
		(start 89.349072 -98.728276)
		(end 89.349072 -100.121466)
		(width 0.0889)
		(layer "In11.Cu")
		(net "M_L_MA<12>")
	)
	(segment
		(start 86.212172 -136.821164)
		(end 85.025992 -138.007344)
		(width 0.14224)
		(layer "In11.Cu")
		(net "M_L_MA<12>")
	)
	(segment
		(start 87.475568 -126.5682)
		(end 87.475568 -128.778)
		(width 0.14224)
		(layer "In11.Cu")
		(net "M_L_MA<12>")
	)
	(segment
		(start 85.025992 -138.007344)
		(end 84.553552 -138.007344)
		(width 0.14224)
		(layer "In11.Cu")
		(net "M_L_MA<12>")
	)
	(segment
		(start 84.0994 -141.187678)
		(end 84.0994 -143.970756)
		(width 0.14224)
		(layer "In11.Cu")
		(net "M_L_MA<12>")
	)
	(segment
		(start 87.069168 -135.079232)
		(end 86.459568 -135.688832)
		(width 0.14224)
		(layer "In11.Cu")
		(net "M_L_MA<12>")
	)
	(arc
		(start 89.152222 -97.986342)
		(mid 89.098689 -98.18624)
		(end 89.152222 -98.386138)
		(width 0.0889)
		(layer "In11.Cu")
		(net "M_L_MA<12>")
	)
	(arc
		(start 89.161112 -97.410778)
		(mid 89.231509 -97.699729)
		(end 89.152222 -97.986342)
		(width 0.0889)
		(layer "In11.Cu")
		(net "M_L_MA<12>")
	)
	(arc
		(start 89.161112 -96.420178)
		(mid 89.231509 -96.709129)
		(end 89.152222 -96.995742)
		(width 0.0889)
		(layer "In11.Cu")
		(net "M_L_MA<12>")
	)
	(arc
		(start 89.152222 -96.995742)
		(mid 89.098689 -97.19564)
		(end 89.152222 -97.395538)
		(width 0.0889)
		(layer "In11.Cu")
		(net "M_L_MA<12>")
	)
	(arc
		(start 89.152222 -96.005142)
		(mid 89.098689 -96.20504)
		(end 89.152222 -96.404938)
		(width 0.0889)
		(layer "In11.Cu")
		(net "M_L_MA<12>")
	)
	(arc
		(start 89.152222 -98.386138)
		(mid 89.250752 -98.557147)
		(end 89.349072 -98.728276)
		(width 0.0889)
		(layer "In11.Cu")
		(net "M_L_MA<12>")
	)
	(segment
		(start 90.070178 -96.20504)
		(end 89.498678 -96.20504)
		(width 0.1016)
		(layer "F.Cu")
		(net "M_L_MA<11>")
	)
	(segment
		(start 84.949538 -145.988278)
		(end 84.949538 -147.27174)
		(width 0.1651)
		(layer "F.Cu")
		(net "M_L_MA<11>")
	)
	(via
		(at 84.949284 -139.170156)
		(size 0.4572)
		(drill 0.2032)
		(layers "F.Cu" "B.Cu")
		(net "M_L_MA<11>")
	)
	(via
		(at 84.949538 -145.988278)
		(size 0.4572)
		(drill 0.2032)
		(layers "F.Cu" "B.Cu")
		(net "M_L_MA<11>")
	)
	(via
		(at 89.498678 -96.20504)
		(size 0.508)
		(drill 0.254)
		(layers "F.Cu" "B.Cu")
		(net "M_L_MA<11>")
	)
	(segment
		(start 84.949538 -137.877296)
		(end 84.949538 -139.169902)
		(width 0.1651)
		(layer "B.Cu")
		(net "M_L_MA<11>")
	)
	(segment
		(start 84.949538 -139.169902)
		(end 84.949284 -139.170156)
		(width 0.1651)
		(layer "B.Cu")
		(net "M_L_MA<11>")
	)
	(segment
		(start 88.992456 -126.12624)
		(end 89.315036 -126.44882)
		(width 0.14224)
		(layer "In11.Cu")
		(net "M_L_MA<11>")
	)
	(segment
		(start 88.085168 -129.7432)
		(end 87.865966 -129.962402)
		(width 0.14224)
		(layer "In11.Cu")
		(net "M_L_MA<11>")
	)
	(segment
		(start 88.00846 -130.657092)
		(end 88.00846 -131.191508)
		(width 0.14224)
		(layer "In11.Cu")
		(net "M_L_MA<11>")
	)
	(segment
		(start 88.087708 -127.910082)
		(end 88.467946 -127.910082)
		(width 0.14224)
		(layer "In11.Cu")
		(net "M_L_MA<11>")
	)
	(segment
		(start 84.469478 -144.25549)
		(end 84.469478 -145.508218)
		(width 0.14224)
		(layer "In11.Cu")
		(net "M_L_MA<11>")
	)
	(segment
		(start 87.932768 -127.755142)
		(end 88.087708 -127.910082)
		(width 0.14224)
		(layer "In11.Cu")
		(net "M_L_MA<11>")
	)
	(segment
		(start 89.650062 -98.725482)
		(end 89.650062 -100.00361)
		(width 0.0889)
		(layer "In11.Cu")
		(net "M_L_MA<11>")
	)
	(segment
		(start 87.910416 -131.289552)
		(end 87.910416 -134.718552)
		(width 0.14224)
		(layer "In11.Cu")
		(net "M_L_MA<11>")
	)
	(segment
		(start 87.932768 -129.2352)
		(end 88.085168 -129.3876)
		(width 0.14224)
		(layer "In11.Cu")
		(net "M_L_MA<11>")
	)
	(segment
		(start 88.61298 -128.055116)
		(end 88.61298 -128.408176)
		(width 0.14224)
		(layer "In11.Cu")
		(net "M_L_MA<11>")
	)
	(segment
		(start 87.704168 -135.1788)
		(end 87.084154 -135.798814)
		(width 0.14224)
		(layer "In11.Cu")
		(net "M_L_MA<11>")
	)
	(segment
		(start 87.932768 -126.952756)
		(end 87.932768 -127.755142)
		(width 0.14224)
		(layer "In11.Cu")
		(net "M_L_MA<11>")
	)
	(segment
		(start 90.818716 -103.215948)
		(end 90.818716 -103.562658)
		(width 0.0889)
		(layer "In11.Cu")
		(net "M_L_MA<11>")
	)
	(segment
		(start 88.085168 -129.3876)
		(end 88.085168 -129.7432)
		(width 0.14224)
		(layer "In11.Cu")
		(net "M_L_MA<11>")
	)
	(segment
		(start 87.084154 -137.035286)
		(end 84.949284 -139.170156)
		(width 0.14224)
		(layer "In11.Cu")
		(net "M_L_MA<11>")
	)
	(segment
		(start 88.448134 -128.573022)
		(end 88.087708 -128.573022)
		(width 0.14224)
		(layer "In11.Cu")
		(net "M_L_MA<11>")
	)
	(segment
		(start 84.357718 -140.776452)
		(end 84.529168 -140.947902)
		(width 0.14224)
		(layer "In11.Cu")
		(net "M_L_MA<11>")
	)
	(segment
		(start 84.357718 -139.761722)
		(end 84.357718 -140.776452)
		(width 0.14224)
		(layer "In11.Cu")
		(net "M_L_MA<11>")
	)
	(segment
		(start 90.250772 -102.648004)
		(end 90.818716 -103.215948)
		(width 0.0889)
		(layer "In11.Cu")
		(net "M_L_MA<11>")
	)
	(segment
		(start 87.910416 -134.718552)
		(end 87.704168 -134.9248)
		(width 0.14224)
		(layer "In11.Cu")
		(net "M_L_MA<11>")
	)
	(segment
		(start 88.00846 -131.191508)
		(end 87.910416 -131.289552)
		(width 0.14224)
		(layer "In11.Cu")
		(net "M_L_MA<11>")
	)
	(segment
		(start 84.469478 -145.508218)
		(end 84.949538 -145.988278)
		(width 0.14224)
		(layer "In11.Cu")
		(net "M_L_MA<11>")
	)
	(segment
		(start 87.084154 -135.798814)
		(end 87.084154 -137.035286)
		(width 0.14224)
		(layer "In11.Cu")
		(net "M_L_MA<11>")
	)
	(segment
		(start 89.315036 -126.760986)
		(end 89.027762 -127.04826)
		(width 0.14224)
		(layer "In11.Cu")
		(net "M_L_MA<11>")
	)
	(segment
		(start 90.250772 -100.60432)
		(end 90.250772 -102.648004)
		(width 0.0889)
		(layer "In11.Cu")
		(net "M_L_MA<11>")
	)
	(segment
		(start 89.845388 -97.395538)
		(end 89.839038 -97.406206)
		(width 0.0889)
		(layer "In11.Cu")
		(net "M_L_MA<11>")
	)
	(segment
		(start 89.850214 -98.377502)
		(end 89.650062 -98.725482)
		(width 0.0889)
		(layer "In11.Cu")
		(net "M_L_MA<11>")
	)
	(segment
		(start 88.459564 -126.742952)
		(end 88.142572 -126.742952)
		(width 0.14224)
		(layer "In11.Cu")
		(net "M_L_MA<11>")
	)
	(segment
		(start 84.529168 -140.947902)
		(end 84.529168 -144.1958)
		(width 0.14224)
		(layer "In11.Cu")
		(net "M_L_MA<11>")
	)
	(segment
		(start 89.650062 -100.00361)
		(end 90.250772 -100.60432)
		(width 0.0889)
		(layer "In11.Cu")
		(net "M_L_MA<11>")
	)
	(segment
		(start 88.764872 -127.04826)
		(end 88.459564 -126.742952)
		(width 0.14224)
		(layer "In11.Cu")
		(net "M_L_MA<11>")
	)
	(segment
		(start 88.087708 -128.573022)
		(end 87.932768 -128.727962)
		(width 0.14224)
		(layer "In11.Cu")
		(net "M_L_MA<11>")
	)
	(segment
		(start 90.818716 -124.012452)
		(end 88.992456 -125.838712)
		(width 0.14224)
		(layer "In11.Cu")
		(net "M_L_MA<11>")
	)
	(segment
		(start 84.949284 -139.170156)
		(end 84.357718 -139.761722)
		(width 0.14224)
		(layer "In11.Cu")
		(net "M_L_MA<11>")
	)
	(segment
		(start 88.992456 -125.838712)
		(end 88.992456 -126.12624)
		(width 0.14224)
		(layer "In11.Cu")
		(net "M_L_MA<11>")
	)
	(segment
		(start 88.142572 -126.742952)
		(end 87.932768 -126.952756)
		(width 0.14224)
		(layer "In11.Cu")
		(net "M_L_MA<11>")
	)
	(segment
		(start 87.932768 -128.727962)
		(end 87.932768 -129.2352)
		(width 0.14224)
		(layer "In11.Cu")
		(net "M_L_MA<11>")
	)
	(segment
		(start 87.704168 -134.9248)
		(end 87.704168 -135.1788)
		(width 0.14224)
		(layer "In11.Cu")
		(net "M_L_MA<11>")
	)
	(segment
		(start 89.315036 -126.44882)
		(end 89.315036 -126.760986)
		(width 0.14224)
		(layer "In11.Cu")
		(net "M_L_MA<11>")
	)
	(segment
		(start 87.865966 -130.514598)
		(end 88.00846 -130.657092)
		(width 0.14224)
		(layer "In11.Cu")
		(net "M_L_MA<11>")
	)
	(segment
		(start 89.027762 -127.04826)
		(end 88.764872 -127.04826)
		(width 0.14224)
		(layer "In11.Cu")
		(net "M_L_MA<11>")
	)
	(segment
		(start 88.61298 -128.408176)
		(end 88.448134 -128.573022)
		(width 0.14224)
		(layer "In11.Cu")
		(net "M_L_MA<11>")
	)
	(segment
		(start 90.818716 -103.562658)
		(end 90.818716 -124.012452)
		(width 0.14224)
		(layer "In11.Cu")
		(net "M_L_MA<11>")
	)
	(segment
		(start 89.850214 -97.386902)
		(end 89.845388 -97.395538)
		(width 0.0889)
		(layer "In11.Cu")
		(net "M_L_MA<11>")
	)
	(segment
		(start 84.529168 -144.1958)
		(end 84.469478 -144.25549)
		(width 0.14224)
		(layer "In11.Cu")
		(net "M_L_MA<11>")
	)
	(segment
		(start 88.467946 -127.910082)
		(end 88.61298 -128.055116)
		(width 0.14224)
		(layer "In11.Cu")
		(net "M_L_MA<11>")
	)
	(segment
		(start 87.865966 -129.962402)
		(end 87.865966 -130.514598)
		(width 0.14224)
		(layer "In11.Cu")
		(net "M_L_MA<11>")
	)
	(arc
		(start 89.498678 -96.20504)
		(mid 89.650336 -96.609781)
		(end 89.845388 -96.995488)
		(width 0.0889)
		(layer "In11.Cu")
		(net "M_L_MA<11>")
	)
	(arc
		(start 89.839038 -97.406206)
		(mid 89.76624 -97.696969)
		(end 89.845388 -97.986088)
		(width 0.0889)
		(layer "In11.Cu")
		(net "M_L_MA<11>")
	)
	(arc
		(start 89.845388 -97.986088)
		(mid 89.898858 -98.181151)
		(end 89.850214 -98.377502)
		(width 0.0889)
		(layer "In11.Cu")
		(net "M_L_MA<11>")
	)
	(arc
		(start 89.845388 -96.995488)
		(mid 89.898858 -97.190551)
		(end 89.850214 -97.386902)
		(width 0.0889)
		(layer "In11.Cu")
		(net "M_L_MA<11>")
	)
	(segment
		(start 102.799388 -146.013932)
		(end 102.799642 -146.013678)
		(width 0.1651)
		(layer "F.Cu")
		(net "M_L_MA<10>")
	)
	(segment
		(start 102.799642 -146.013678)
		(end 102.799642 -145.988278)
		(width 0.1651)
		(layer "F.Cu")
		(net "M_L_MA<10>")
	)
	(segment
		(start 102.799388 -147.27174)
		(end 102.799388 -146.013932)
		(width 0.1651)
		(layer "F.Cu")
		(net "M_L_MA<10>")
	)
	(segment
		(start 94.362778 -96.700086)
		(end 93.791278 -96.700086)
		(width 0.1016)
		(layer "F.Cu")
		(net "M_L_MA<10>")
	)
	(via
		(at 102.799642 -139.172188)
		(size 0.4572)
		(drill 0.2032)
		(layers "F.Cu" "B.Cu")
		(net "M_L_MA<10>")
	)
	(via
		(at 102.799642 -145.988278)
		(size 0.4572)
		(drill 0.2032)
		(layers "F.Cu" "B.Cu")
		(net "M_L_MA<10>")
	)
	(via
		(at 93.791278 -96.700086)
		(size 0.508)
		(drill 0.254)
		(layers "F.Cu" "B.Cu")
		(net "M_L_MA<10>")
	)
	(segment
		(start 102.799388 -139.171934)
		(end 102.799642 -139.172188)
		(width 0.1651)
		(layer "B.Cu")
		(net "M_L_MA<10>")
	)
	(segment
		(start 102.799388 -137.877296)
		(end 102.799388 -139.171934)
		(width 0.1651)
		(layer "B.Cu")
		(net "M_L_MA<10>")
	)
	(segment
		(start 96.695768 -103.1748)
		(end 96.508316 -103.362252)
		(width 0.0889)
		(layer "In11.Cu")
		(net "M_L_MA<10>")
	)
	(segment
		(start 94.315026 -97.517458)
		(end 94.315026 -97.941638)
		(width 0.0889)
		(layer "In11.Cu")
		(net "M_L_MA<10>")
	)
	(segment
		(start 102.799642 -144.666716)
		(end 102.799642 -145.988278)
		(width 0.14224)
		(layer "In11.Cu")
		(net "M_L_MA<10>")
	)
	(segment
		(start 96.508316 -103.362252)
		(end 96.508316 -104.319324)
		(width 0.0889)
		(layer "In11.Cu")
		(net "M_L_MA<10>")
	)
	(segment
		(start 96.508316 -125.491748)
		(end 99.198684 -128.182116)
		(width 0.14224)
		(layer "In11.Cu")
		(net "M_L_MA<10>")
	)
	(segment
		(start 94.303088 -98.386138)
		(end 94.309438 -98.396806)
		(width 0.0889)
		(layer "In11.Cu")
		(net "M_L_MA<10>")
	)
	(segment
		(start 94.460568 -99.568)
		(end 94.460568 -99.7712)
		(width 0.0889)
		(layer "In11.Cu")
		(net "M_L_MA<10>")
	)
	(segment
		(start 102.389686 -140.321792)
		(end 102.389686 -144.25676)
		(width 0.14224)
		(layer "In11.Cu")
		(net "M_L_MA<10>")
	)
	(segment
		(start 100.785168 -130.048)
		(end 100.785168 -130.4544)
		(width 0.14224)
		(layer "In11.Cu")
		(net "M_L_MA<10>")
	)
	(segment
		(start 101.533198 -137.905744)
		(end 102.799642 -139.172188)
		(width 0.14224)
		(layer "In11.Cu")
		(net "M_L_MA<10>")
	)
	(segment
		(start 99.198684 -128.461516)
		(end 100.785168 -130.048)
		(width 0.14224)
		(layer "In11.Cu")
		(net "M_L_MA<10>")
	)
	(segment
		(start 96.695768 -102.0064)
		(end 96.695768 -103.1748)
		(width 0.0889)
		(layer "In11.Cu")
		(net "M_L_MA<10>")
	)
	(segment
		(start 96.508316 -104.319324)
		(end 96.508316 -125.491748)
		(width 0.14224)
		(layer "In11.Cu")
		(net "M_L_MA<10>")
	)
	(segment
		(start 93.791278 -96.700086)
		(end 94.155768 -97.064576)
		(width 0.0889)
		(layer "In11.Cu")
		(net "M_L_MA<10>")
	)
	(segment
		(start 102.389686 -144.25676)
		(end 102.799642 -144.666716)
		(width 0.14224)
		(layer "In11.Cu")
		(net "M_L_MA<10>")
	)
	(segment
		(start 100.785168 -130.4544)
		(end 100.661978 -130.57759)
		(width 0.14224)
		(layer "In11.Cu")
		(net "M_L_MA<10>")
	)
	(segment
		(start 99.198684 -128.182116)
		(end 99.198684 -128.461516)
		(width 0.14224)
		(layer "In11.Cu")
		(net "M_L_MA<10>")
	)
	(segment
		(start 100.661978 -130.57759)
		(end 100.661978 -135.243316)
		(width 0.14224)
		(layer "In11.Cu")
		(net "M_L_MA<10>")
	)
	(segment
		(start 94.298262 -98.377502)
		(end 94.303088 -98.386138)
		(width 0.0889)
		(layer "In11.Cu")
		(net "M_L_MA<10>")
	)
	(segment
		(start 102.799642 -139.911836)
		(end 102.389686 -140.321792)
		(width 0.14224)
		(layer "In11.Cu")
		(net "M_L_MA<10>")
	)
	(segment
		(start 102.799642 -139.172188)
		(end 102.799642 -139.911836)
		(width 0.14224)
		(layer "In11.Cu")
		(net "M_L_MA<10>")
	)
	(segment
		(start 94.155768 -97.064576)
		(end 94.155768 -97.3582)
		(width 0.0889)
		(layer "In11.Cu")
		(net "M_L_MA<10>")
	)
	(segment
		(start 94.460568 -99.7712)
		(end 96.695768 -102.0064)
		(width 0.0889)
		(layer "In11.Cu")
		(net "M_L_MA<10>")
	)
	(segment
		(start 100.661978 -135.243316)
		(end 101.533198 -136.114536)
		(width 0.14224)
		(layer "In11.Cu")
		(net "M_L_MA<10>")
	)
	(segment
		(start 101.533198 -136.114536)
		(end 101.533198 -137.905744)
		(width 0.14224)
		(layer "In11.Cu")
		(net "M_L_MA<10>")
	)
	(segment
		(start 94.155768 -97.3582)
		(end 94.315026 -97.517458)
		(width 0.0889)
		(layer "In11.Cu")
		(net "M_L_MA<10>")
	)
	(arc
		(start 94.309438 -98.396806)
		(mid 94.382236 -98.687569)
		(end 94.303088 -98.976688)
		(width 0.0889)
		(layer "In11.Cu")
		(net "M_L_MA<10>")
	)
	(arc
		(start 94.303088 -98.976688)
		(mid 94.249618 -99.171751)
		(end 94.298262 -99.368102)
		(width 0.0889)
		(layer "In11.Cu")
		(net "M_L_MA<10>")
	)
	(arc
		(start 94.315026 -97.941638)
		(mid 94.312003 -97.964658)
		(end 94.303088 -97.986088)
		(width 0.0889)
		(layer "In11.Cu")
		(net "M_L_MA<10>")
	)
	(arc
		(start 94.298262 -99.368102)
		(mid 94.370251 -99.475489)
		(end 94.460568 -99.568)
		(width 0.0889)
		(layer "In11.Cu")
		(net "M_L_MA<10>")
	)
	(arc
		(start 94.303088 -97.986088)
		(mid 94.249618 -98.181151)
		(end 94.298262 -98.377502)
		(width 0.0889)
		(layer "In11.Cu")
		(net "M_L_MA<10>")
	)
	(segment
		(start 101.099366 -142.6718)
		(end 101.099366 -143.968978)
		(width 0.1651)
		(layer "F.Cu")
		(net "M_L_MA<0>")
	)
	(segment
		(start 96.938338 -98.18624)
		(end 96.366838 -98.18624)
		(width 0.1016)
		(layer "F.Cu")
		(net "M_L_MA<0>")
	)
	(via
		(at 101.099366 -141.183868)
		(size 0.4572)
		(drill 0.2032)
		(layers "F.Cu" "B.Cu")
		(net "M_L_MA<0>")
	)
	(via
		(at 96.366838 -98.18624)
		(size 0.508)
		(drill 0.254)
		(layers "F.Cu" "B.Cu")
		(net "M_L_MA<0>")
	)
	(via
		(at 101.099366 -143.968978)
		(size 0.508)
		(drill 0.254)
		(layers "F.Cu" "B.Cu")
		(net "M_L_MA<0>")
	)
	(segment
		(start 101.099366 -142.477236)
		(end 101.099366 -141.183868)
		(width 0.1651)
		(layer "B.Cu")
		(net "M_L_MA<0>")
	)
	(segment
		(start 99.128326 -127.552958)
		(end 98.733356 -127.157988)
		(width 0.14224)
		(layer "In4.Cu")
		(net "M_L_MA<0>")
	)
	(segment
		(start 99.860354 -128.437894)
		(end 99.860354 -128.150366)
		(width 0.14224)
		(layer "In4.Cu")
		(net "M_L_MA<0>")
	)
	(segment
		(start 100.454968 -129.667)
		(end 100.454968 -129.032508)
		(width 0.14224)
		(layer "In4.Cu")
		(net "M_L_MA<0>")
	)
	(segment
		(start 99.337876 -126.373636)
		(end 99.337876 -126.086108)
		(width 0.14224)
		(layer "In4.Cu")
		(net "M_L_MA<0>")
	)
	(segment
		(start 100.200206 -126.948438)
		(end 99.912678 -126.948438)
		(width 0.14224)
		(layer "In4.Cu")
		(net "M_L_MA<0>")
	)
	(segment
		(start 99.912678 -126.948438)
		(end 99.308158 -127.552958)
		(width 0.14224)
		(layer "In4.Cu")
		(net "M_L_MA<0>")
	)
	(segment
		(start 99.337876 -126.086108)
		(end 99.050602 -125.798834)
		(width 0.14224)
		(layer "In4.Cu")
		(net "M_L_MA<0>")
	)
	(segment
		(start 97.584768 -126.060708)
		(end 97.584768 -125.777752)
		(width 0.14224)
		(layer "In4.Cu")
		(net "M_L_MA<0>")
	)
	(segment
		(start 99.050602 -125.798834)
		(end 98.763074 -125.798834)
		(width 0.14224)
		(layer "In4.Cu")
		(net "M_L_MA<0>")
	)
	(segment
		(start 100.665534 -138.928094)
		(end 100.665534 -135.374634)
		(width 0.14224)
		(layer "In4.Cu")
		(net "M_L_MA<0>")
	)
	(segment
		(start 98.163634 -126.398274)
		(end 97.922334 -126.398274)
		(width 0.14224)
		(layer "In4.Cu")
		(net "M_L_MA<0>")
	)
	(segment
		(start 99.308158 -127.552958)
		(end 99.128326 -127.552958)
		(width 0.14224)
		(layer "In4.Cu")
		(net "M_L_MA<0>")
	)
	(segment
		(start 100.642166 -138.951462)
		(end 100.665534 -138.928094)
		(width 0.14224)
		(layer "In4.Cu")
		(net "M_L_MA<0>")
	)
	(segment
		(start 100.48748 -127.52324)
		(end 100.48748 -127.235712)
		(width 0.14224)
		(layer "In4.Cu")
		(net "M_L_MA<0>")
	)
	(segment
		(start 100.73259 -134.61873)
		(end 100.663756 -134.549896)
		(width 0.14224)
		(layer "In4.Cu")
		(net "M_L_MA<0>")
	)
	(segment
		(start 96.314768 -101.423216)
		(end 96.314768 -100.129594)
		(width 0.0889)
		(layer "In4.Cu")
		(net "M_L_MA<0>")
	)
	(segment
		(start 98.103944 -124.765308)
		(end 97.584768 -124.246132)
		(width 0.14224)
		(layer "In4.Cu")
		(net "M_L_MA<0>")
	)
	(segment
		(start 101.099366 -139.919202)
		(end 100.642166 -139.462002)
		(width 0.14224)
		(layer "In4.Cu")
		(net "M_L_MA<0>")
	)
	(segment
		(start 98.733356 -126.978156)
		(end 99.337876 -126.373636)
		(width 0.14224)
		(layer "In4.Cu")
		(net "M_L_MA<0>")
	)
	(segment
		(start 99.860354 -128.150366)
		(end 100.48748 -127.52324)
		(width 0.14224)
		(layer "In4.Cu")
		(net "M_L_MA<0>")
	)
	(segment
		(start 97.584768 -103.310436)
		(end 97.584768 -102.693216)
		(width 0.0889)
		(layer "In4.Cu")
		(net "M_L_MA<0>")
	)
	(segment
		(start 101.099366 -141.183868)
		(end 101.099366 -139.919202)
		(width 0.14224)
		(layer "In4.Cu")
		(net "M_L_MA<0>")
	)
	(segment
		(start 100.414582 -130.875786)
		(end 100.837492 -130.452876)
		(width 0.14224)
		(layer "In4.Cu")
		(net "M_L_MA<0>")
	)
	(segment
		(start 97.584768 -125.777752)
		(end 98.103944 -125.258576)
		(width 0.14224)
		(layer "In4.Cu")
		(net "M_L_MA<0>")
	)
	(segment
		(start 100.663756 -134.549896)
		(end 100.663756 -131.740148)
		(width 0.14224)
		(layer "In4.Cu")
		(net "M_L_MA<0>")
	)
	(segment
		(start 97.584768 -124.246132)
		(end 97.584768 -103.310436)
		(width 0.14224)
		(layer "In4.Cu")
		(net "M_L_MA<0>")
	)
	(segment
		(start 100.837492 -130.049524)
		(end 100.454968 -129.667)
		(width 0.14224)
		(layer "In4.Cu")
		(net "M_L_MA<0>")
	)
	(segment
		(start 101.099366 -141.183868)
		(end 101.099366 -143.968978)
		(width 0.14224)
		(layer "In4.Cu")
		(net "M_L_MA<0>")
	)
	(segment
		(start 100.663756 -131.740148)
		(end 100.414582 -131.490974)
		(width 0.14224)
		(layer "In4.Cu")
		(net "M_L_MA<0>")
	)
	(segment
		(start 97.922334 -126.398274)
		(end 97.584768 -126.060708)
		(width 0.14224)
		(layer "In4.Cu")
		(net "M_L_MA<0>")
	)
	(segment
		(start 100.48748 -127.235712)
		(end 100.200206 -126.948438)
		(width 0.14224)
		(layer "In4.Cu")
		(net "M_L_MA<0>")
	)
	(segment
		(start 100.454968 -129.032508)
		(end 99.860354 -128.437894)
		(width 0.14224)
		(layer "In4.Cu")
		(net "M_L_MA<0>")
	)
	(segment
		(start 100.414582 -131.490974)
		(end 100.414582 -130.875786)
		(width 0.14224)
		(layer "In4.Cu")
		(net "M_L_MA<0>")
	)
	(segment
		(start 96.020128 -99.376738)
		(end 96.015302 -99.368102)
		(width 0.0889)
		(layer "In4.Cu")
		(net "M_L_MA<0>")
	)
	(segment
		(start 98.763074 -125.798834)
		(end 98.163634 -126.398274)
		(width 0.14224)
		(layer "In4.Cu")
		(net "M_L_MA<0>")
	)
	(segment
		(start 98.103944 -125.258576)
		(end 98.103944 -124.765308)
		(width 0.14224)
		(layer "In4.Cu")
		(net "M_L_MA<0>")
	)
	(segment
		(start 100.837492 -130.452876)
		(end 100.837492 -130.049524)
		(width 0.14224)
		(layer "In4.Cu")
		(net "M_L_MA<0>")
	)
	(segment
		(start 100.642166 -139.462002)
		(end 100.642166 -138.951462)
		(width 0.14224)
		(layer "In4.Cu")
		(net "M_L_MA<0>")
	)
	(segment
		(start 100.73259 -135.307578)
		(end 100.73259 -134.61873)
		(width 0.14224)
		(layer "In4.Cu")
		(net "M_L_MA<0>")
	)
	(segment
		(start 98.733356 -127.157988)
		(end 98.733356 -126.978156)
		(width 0.14224)
		(layer "In4.Cu")
		(net "M_L_MA<0>")
	)
	(segment
		(start 100.665534 -135.374634)
		(end 100.73259 -135.307578)
		(width 0.14224)
		(layer "In4.Cu")
		(net "M_L_MA<0>")
	)
	(segment
		(start 97.584768 -102.693216)
		(end 96.314768 -101.423216)
		(width 0.0889)
		(layer "In4.Cu")
		(net "M_L_MA<0>")
	)
	(arc
		(start 96.314768 -100.129594)
		(mid 96.295478 -99.958792)
		(end 96.238568 -99.7966)
		(width 0.0889)
		(layer "In4.Cu")
		(net "M_L_MA<0>")
	)
	(arc
		(start 96.238568 -99.7966)
		(mid 96.132484 -99.585037)
		(end 96.020128 -99.376738)
		(width 0.0889)
		(layer "In4.Cu")
		(net "M_L_MA<0>")
	)
	(arc
		(start 96.08185 -98.824034)
		(mid 96.089535 -98.788803)
		(end 96.095058 -98.753168)
		(width 0.0889)
		(layer "In4.Cu")
		(net "M_L_MA<0>")
	)
	(arc
		(start 96.095058 -98.753168)
		(mid 96.098384 -98.716152)
		(end 96.099376 -98.679)
		(width 0.0889)
		(layer "In4.Cu")
		(net "M_L_MA<0>")
	)
	(arc
		(start 96.020128 -98.976688)
		(mid 96.05632 -98.902517)
		(end 96.08185 -98.824034)
		(width 0.0889)
		(layer "In4.Cu")
		(net "M_L_MA<0>")
	)
	(arc
		(start 96.015302 -99.368102)
		(mid 95.966547 -99.17175)
		(end 96.020128 -98.976688)
		(width 0.0889)
		(layer "In4.Cu")
		(net "M_L_MA<0>")
	)
	(arc
		(start 96.099376 -98.679)
		(mid 96.170544 -98.398655)
		(end 96.366838 -98.18624)
		(width 0.0889)
		(layer "In4.Cu")
		(net "M_L_MA<0>")
	)
	(segment
		(start 75.962764 -125.403102)
		(end 75.65009 -125.715776)
		(width 0.1651)
		(layer "F.Cu")
		(net "M_L_ECC<7>")
	)
	(segment
		(start 84.920582 -99.17811)
		(end 84.920582 -100.328476)
		(width 0.0889)
		(layer "F.Cu")
		(net "M_L_ECC<7>")
	)
	(segment
		(start 76.26096 -113.567464)
		(end 76.26096 -123.990608)
		(width 0.1651)
		(layer "F.Cu")
		(net "M_L_ECC<7>")
	)
	(segment
		(start 77.06106 -115.7732)
		(end 76.93406 -115.6462)
		(width 0.1651)
		(layer "F.Cu")
		(net "M_L_ECC<7>")
	)
	(segment
		(start 75.962764 -124.288804)
		(end 75.962764 -125.403102)
		(width 0.1651)
		(layer "F.Cu")
		(net "M_L_ECC<7>")
	)
	(segment
		(start 74.749406 -142.6718)
		(end 74.749406 -143.941546)
		(width 0.1651)
		(layer "F.Cu")
		(net "M_L_ECC<7>")
	)
	(segment
		(start 76.93406 -115.6462)
		(end 76.93406 -113.542064)
		(width 0.1651)
		(layer "F.Cu")
		(net "M_L_ECC<7>")
	)
	(segment
		(start 84.952332 -103.796338)
		(end 84.263992 -104.484678)
		(width 0.1016)
		(layer "F.Cu")
		(net "M_L_ECC<7>")
	)
	(segment
		(start 84.952332 -100.360226)
		(end 84.952332 -100.492814)
		(width 0.0889)
		(layer "F.Cu")
		(net "M_L_ECC<7>")
	)
	(segment
		(start 84.920582 -100.328476)
		(end 84.952332 -100.360226)
		(width 0.0889)
		(layer "F.Cu")
		(net "M_L_ECC<7>")
	)
	(segment
		(start 76.93406 -113.542064)
		(end 76.78166 -113.389664)
		(width 0.1651)
		(layer "F.Cu")
		(net "M_L_ECC<7>")
	)
	(segment
		(start 76.78166 -113.389664)
		(end 76.43876 -113.389664)
		(width 0.1651)
		(layer "F.Cu")
		(net "M_L_ECC<7>")
	)
	(segment
		(start 84.263992 -104.484678)
		(end 84.263992 -105.36301)
		(width 0.1016)
		(layer "F.Cu")
		(net "M_L_ECC<7>")
	)
	(segment
		(start 84.952332 -100.492814)
		(end 84.952332 -103.796338)
		(width 0.1016)
		(layer "F.Cu")
		(net "M_L_ECC<7>")
	)
	(segment
		(start 79.370682 -110.440978)
		(end 77.60716 -112.2045)
		(width 0.1651)
		(layer "F.Cu")
		(net "M_L_ECC<7>")
	)
	(segment
		(start 84.919312 -99.17684)
		(end 84.920582 -99.17811)
		(width 0.0889)
		(layer "F.Cu")
		(net "M_L_ECC<7>")
	)
	(segment
		(start 77.48016 -115.7732)
		(end 77.06106 -115.7732)
		(width 0.1651)
		(layer "F.Cu")
		(net "M_L_ECC<7>")
	)
	(segment
		(start 79.563214 -110.063788)
		(end 79.563214 -110.248446)
		(width 0.1016)
		(layer "F.Cu")
		(net "M_L_ECC<7>")
	)
	(segment
		(start 77.60716 -115.6462)
		(end 77.48016 -115.7732)
		(width 0.1651)
		(layer "F.Cu")
		(net "M_L_ECC<7>")
	)
	(segment
		(start 79.563214 -110.248446)
		(end 79.370682 -110.440978)
		(width 0.1016)
		(layer "F.Cu")
		(net "M_L_ECC<7>")
	)
	(segment
		(start 76.26096 -123.990608)
		(end 75.962764 -124.288804)
		(width 0.1651)
		(layer "F.Cu")
		(net "M_L_ECC<7>")
	)
	(segment
		(start 76.43876 -113.389664)
		(end 76.26096 -113.567464)
		(width 0.1651)
		(layer "F.Cu")
		(net "M_L_ECC<7>")
	)
	(segment
		(start 77.60716 -112.2045)
		(end 77.60716 -115.6462)
		(width 0.1651)
		(layer "F.Cu")
		(net "M_L_ECC<7>")
	)
	(segment
		(start 84.263992 -105.36301)
		(end 79.563214 -110.063788)
		(width 0.1016)
		(layer "F.Cu")
		(net "M_L_ECC<7>")
	)
	(via
		(at 74.749406 -143.941546)
		(size 0.508)
		(drill 0.254)
		(layers "F.Cu" "B.Cu")
		(net "M_L_ECC<7>")
	)
	(via
		(at 75.59929 -139.932156)
		(size 0.508)
		(drill 0.254)
		(layers "F.Cu" "B.Cu")
		(net "M_L_ECC<7>")
	)
	(via
		(at 75.65009 -125.715776)
		(size 0.508)
		(drill 0.254)
		(layers "F.Cu" "B.Cu")
		(net "M_L_ECC<7>")
	)
	(segment
		(start 75.599544 -137.877296)
		(end 75.59929 -137.877296)
		(width 0.1651)
		(layer "B.Cu")
		(net "M_L_ECC<7>")
	)
	(segment
		(start 75.59929 -137.877296)
		(end 75.59929 -139.932156)
		(width 0.1651)
		(layer "B.Cu")
		(net "M_L_ECC<7>")
	)
	(segment
		(start 74.910696 -141.785848)
		(end 75.193144 -141.5034)
		(width 0.14224)
		(layer "In9.Cu")
		(net "M_L_ECC<7>")
	)
	(segment
		(start 75.021694 -143.941546)
		(end 75.199494 -143.763746)
		(width 0.14224)
		(layer "In9.Cu")
		(net "M_L_ECC<7>")
	)
	(segment
		(start 75.193144 -141.5034)
		(end 75.193144 -140.834618)
		(width 0.14224)
		(layer "In9.Cu")
		(net "M_L_ECC<7>")
	)
	(segment
		(start 74.749406 -143.941546)
		(end 75.021694 -143.941546)
		(width 0.14224)
		(layer "In9.Cu")
		(net "M_L_ECC<7>")
	)
	(segment
		(start 74.910696 -142.059152)
		(end 74.910696 -141.785848)
		(width 0.14224)
		(layer "In9.Cu")
		(net "M_L_ECC<7>")
	)
	(segment
		(start 75.167744 -142.3162)
		(end 74.910696 -142.059152)
		(width 0.14224)
		(layer "In9.Cu")
		(net "M_L_ECC<7>")
	)
	(segment
		(start 75.193144 -140.834618)
		(end 75.148694 -140.790168)
		(width 0.14224)
		(layer "In9.Cu")
		(net "M_L_ECC<7>")
	)
	(segment
		(start 75.148694 -140.790168)
		(end 75.148694 -140.3604)
		(width 0.14224)
		(layer "In9.Cu")
		(net "M_L_ECC<7>")
	)
	(segment
		(start 75.148694 -140.3604)
		(end 75.576938 -139.932156)
		(width 0.14224)
		(layer "In9.Cu")
		(net "M_L_ECC<7>")
	)
	(segment
		(start 75.199494 -143.44015)
		(end 74.910696 -143.151352)
		(width 0.14224)
		(layer "In9.Cu")
		(net "M_L_ECC<7>")
	)
	(segment
		(start 75.576938 -139.932156)
		(end 75.59929 -139.932156)
		(width 0.14224)
		(layer "In9.Cu")
		(net "M_L_ECC<7>")
	)
	(segment
		(start 74.910696 -142.878048)
		(end 75.167744 -142.621)
		(width 0.14224)
		(layer "In9.Cu")
		(net "M_L_ECC<7>")
	)
	(segment
		(start 75.167744 -142.621)
		(end 75.167744 -142.3162)
		(width 0.14224)
		(layer "In9.Cu")
		(net "M_L_ECC<7>")
	)
	(segment
		(start 74.910696 -143.151352)
		(end 74.910696 -142.878048)
		(width 0.14224)
		(layer "In9.Cu")
		(net "M_L_ECC<7>")
	)
	(segment
		(start 75.199494 -143.763746)
		(end 75.199494 -143.44015)
		(width 0.14224)
		(layer "In9.Cu")
		(net "M_L_ECC<7>")
	)
	(segment
		(start 76.180696 -131.205478)
		(end 75.901296 -131.484878)
		(width 0.14224)
		(layer "In11.Cu")
		(net "M_L_ECC<7>")
	)
	(segment
		(start 75.977496 -134.129272)
		(end 75.977496 -134.568438)
		(width 0.14224)
		(layer "In11.Cu")
		(net "M_L_ECC<7>")
	)
	(segment
		(start 75.977496 -134.568438)
		(end 76.12126 -134.712202)
		(width 0.14224)
		(layer "In11.Cu")
		(net "M_L_ECC<7>")
	)
	(segment
		(start 76.12126 -134.712202)
		(end 76.12126 -136.017254)
		(width 0.14224)
		(layer "In11.Cu")
		(net "M_L_ECC<7>")
	)
	(segment
		(start 75.865228 -126.97714)
		(end 75.865228 -127.55626)
		(width 0.14224)
		(layer "In11.Cu")
		(net "M_L_ECC<7>")
	)
	(segment
		(start 75.952096 -127.643128)
		(end 75.952096 -129.859278)
		(width 0.14224)
		(layer "In11.Cu")
		(net "M_L_ECC<7>")
	)
	(segment
		(start 75.952096 -138.828272)
		(end 75.952096 -139.590272)
		(width 0.14224)
		(layer "In11.Cu")
		(net "M_L_ECC<7>")
	)
	(segment
		(start 75.952096 -136.5758)
		(end 76.020168 -136.643872)
		(width 0.14224)
		(layer "In11.Cu")
		(net "M_L_ECC<7>")
	)
	(segment
		(start 76.020168 -131.970272)
		(end 76.020168 -134.0866)
		(width 0.14224)
		(layer "In11.Cu")
		(net "M_L_ECC<7>")
	)
	(segment
		(start 75.952096 -136.186418)
		(end 75.952096 -136.5758)
		(width 0.14224)
		(layer "In11.Cu")
		(net "M_L_ECC<7>")
	)
	(segment
		(start 75.65009 -125.715776)
		(end 76.172568 -126.238254)
		(width 0.14224)
		(layer "In11.Cu")
		(net "M_L_ECC<7>")
	)
	(segment
		(start 75.952096 -129.859278)
		(end 76.180696 -130.087878)
		(width 0.14224)
		(layer "In11.Cu")
		(net "M_L_ECC<7>")
	)
	(segment
		(start 76.020168 -136.643872)
		(end 76.020168 -138.7602)
		(width 0.14224)
		(layer "In11.Cu")
		(net "M_L_ECC<7>")
	)
	(segment
		(start 75.941174 -139.590272)
		(end 75.59929 -139.932156)
		(width 0.14224)
		(layer "In11.Cu")
		(net "M_L_ECC<7>")
	)
	(segment
		(start 76.020168 -138.7602)
		(end 75.952096 -138.828272)
		(width 0.14224)
		(layer "In11.Cu")
		(net "M_L_ECC<7>")
	)
	(segment
		(start 76.12126 -136.017254)
		(end 75.952096 -136.186418)
		(width 0.14224)
		(layer "In11.Cu")
		(net "M_L_ECC<7>")
	)
	(segment
		(start 76.172568 -126.238254)
		(end 76.172568 -126.6698)
		(width 0.14224)
		(layer "In11.Cu")
		(net "M_L_ECC<7>")
	)
	(segment
		(start 75.952096 -139.590272)
		(end 75.941174 -139.590272)
		(width 0.14224)
		(layer "In11.Cu")
		(net "M_L_ECC<7>")
	)
	(segment
		(start 75.865228 -127.55626)
		(end 75.952096 -127.643128)
		(width 0.14224)
		(layer "In11.Cu")
		(net "M_L_ECC<7>")
	)
	(segment
		(start 76.172568 -126.6698)
		(end 75.865228 -126.97714)
		(width 0.14224)
		(layer "In11.Cu")
		(net "M_L_ECC<7>")
	)
	(segment
		(start 75.901296 -131.8514)
		(end 76.020168 -131.970272)
		(width 0.14224)
		(layer "In11.Cu")
		(net "M_L_ECC<7>")
	)
	(segment
		(start 75.901296 -131.484878)
		(end 75.901296 -131.8514)
		(width 0.14224)
		(layer "In11.Cu")
		(net "M_L_ECC<7>")
	)
	(segment
		(start 76.180696 -130.087878)
		(end 76.180696 -131.205478)
		(width 0.14224)
		(layer "In11.Cu")
		(net "M_L_ECC<7>")
	)
	(segment
		(start 76.020168 -134.0866)
		(end 75.977496 -134.129272)
		(width 0.14224)
		(layer "In11.Cu")
		(net "M_L_ECC<7>")
	)
	(segment
		(start 75.599544 -147.27174)
		(end 75.599544 -146.304)
		(width 0.1651)
		(layer "F.Cu")
		(net "M_L_ECC<6>")
	)
	(segment
		(start 75.613768 -123.355862)
		(end 75.613768 -123.698)
		(width 0.1651)
		(layer "F.Cu")
		(net "M_L_ECC<6>")
	)
	(segment
		(start 84.647532 -103.669846)
		(end 83.959192 -104.358186)
		(width 0.1016)
		(layer "F.Cu")
		(net "M_L_ECC<6>")
	)
	(segment
		(start 83.959192 -105.111042)
		(end 79.433674 -109.63656)
		(width 0.1016)
		(layer "F.Cu")
		(net "M_L_ECC<6>")
	)
	(segment
		(start 75.448668 -121.844562)
		(end 75.613768 -122.009662)
		(width 0.1651)
		(layer "F.Cu")
		(net "M_L_ECC<6>")
	)
	(segment
		(start 75.613768 -121.006362)
		(end 75.448668 -121.171462)
		(width 0.1651)
		(layer "F.Cu")
		(net "M_L_ECC<6>")
	)
	(segment
		(start 84.65185 -99.675188)
		(end 84.65185 -100.117148)
		(width 0.0889)
		(layer "F.Cu")
		(net "M_L_ECC<6>")
	)
	(segment
		(start 84.919312 -97.19564)
		(end 84.531962 -97.58299)
		(width 0.0889)
		(layer "F.Cu")
		(net "M_L_ECC<6>")
	)
	(segment
		(start 84.647532 -100.121466)
		(end 84.647532 -100.492814)
		(width 0.0889)
		(layer "F.Cu")
		(net "M_L_ECC<6>")
	)
	(segment
		(start 75.599544 -145.8214)
		(end 75.599544 -145.516854)
		(width 0.1651)
		(layer "F.Cu")
		(net "M_L_ECC<6>")
	)
	(segment
		(start 74.89698 -121.336562)
		(end 74.89698 -121.679462)
		(width 0.1651)
		(layer "F.Cu")
		(net "M_L_ECC<6>")
	)
	(segment
		(start 79.037434 -109.867192)
		(end 75.613768 -113.290858)
		(width 0.1651)
		(layer "F.Cu")
		(net "M_L_ECC<6>")
	)
	(segment
		(start 75.06208 -121.844562)
		(end 75.448668 -121.844562)
		(width 0.1651)
		(layer "F.Cu")
		(net "M_L_ECC<6>")
	)
	(segment
		(start 75.448668 -122.517662)
		(end 75.06208 -122.517662)
		(width 0.1651)
		(layer "F.Cu")
		(net "M_L_ECC<6>")
	)
	(segment
		(start 75.731624 -145.95348)
		(end 75.599544 -145.8214)
		(width 0.1651)
		(layer "F.Cu")
		(net "M_L_ECC<6>")
	)
	(segment
		(start 75.599544 -146.304)
		(end 75.731624 -146.17192)
		(width 0.1651)
		(layer "F.Cu")
		(net "M_L_ECC<6>")
	)
	(segment
		(start 84.531962 -98.59264)
		(end 84.638388 -98.699066)
		(width 0.0889)
		(layer "F.Cu")
		(net "M_L_ECC<6>")
	)
	(segment
		(start 75.06208 -121.171462)
		(end 74.89698 -121.336562)
		(width 0.1651)
		(layer "F.Cu")
		(net "M_L_ECC<6>")
	)
	(segment
		(start 84.572602 -99.376738)
		(end 84.581492 -99.391978)
		(width 0.0889)
		(layer "F.Cu")
		(net "M_L_ECC<6>")
	)
	(segment
		(start 75.731624 -146.17192)
		(end 75.731624 -145.95348)
		(width 0.1651)
		(layer "F.Cu")
		(net "M_L_ECC<6>")
	)
	(segment
		(start 75.613768 -122.009662)
		(end 75.613768 -122.352562)
		(width 0.1651)
		(layer "F.Cu")
		(net "M_L_ECC<6>")
	)
	(segment
		(start 75.448668 -121.171462)
		(end 75.06208 -121.171462)
		(width 0.1651)
		(layer "F.Cu")
		(net "M_L_ECC<6>")
	)
	(segment
		(start 75.599544 -145.516854)
		(end 75.59929 -145.5166)
		(width 0.1651)
		(layer "F.Cu")
		(net "M_L_ECC<6>")
	)
	(segment
		(start 75.613768 -113.290858)
		(end 75.613768 -121.006362)
		(width 0.1651)
		(layer "F.Cu")
		(net "M_L_ECC<6>")
	)
	(segment
		(start 84.638388 -98.699066)
		(end 84.638388 -98.87839)
		(width 0.0889)
		(layer "F.Cu")
		(net "M_L_ECC<6>")
	)
	(segment
		(start 75.319636 -124.703332)
		(end 74.775568 -125.2474)
		(width 0.1651)
		(layer "F.Cu")
		(net "M_L_ECC<6>")
	)
	(segment
		(start 75.06208 -123.190762)
		(end 75.448668 -123.190762)
		(width 0.1651)
		(layer "F.Cu")
		(net "M_L_ECC<6>")
	)
	(segment
		(start 79.268066 -109.63656)
		(end 79.037434 -109.867192)
		(width 0.1016)
		(layer "F.Cu")
		(net "M_L_ECC<6>")
	)
	(segment
		(start 84.647532 -100.492814)
		(end 84.647532 -103.669846)
		(width 0.1016)
		(layer "F.Cu")
		(net "M_L_ECC<6>")
	)
	(segment
		(start 74.89698 -121.679462)
		(end 75.06208 -121.844562)
		(width 0.1651)
		(layer "F.Cu")
		(net "M_L_ECC<6>")
	)
	(segment
		(start 75.613768 -122.352562)
		(end 75.448668 -122.517662)
		(width 0.1651)
		(layer "F.Cu")
		(net "M_L_ECC<6>")
	)
	(segment
		(start 75.448668 -123.190762)
		(end 75.613768 -123.355862)
		(width 0.1651)
		(layer "F.Cu")
		(net "M_L_ECC<6>")
	)
	(segment
		(start 74.89698 -122.682762)
		(end 74.89698 -123.025662)
		(width 0.1651)
		(layer "F.Cu")
		(net "M_L_ECC<6>")
	)
	(segment
		(start 84.567776 -99.368102)
		(end 84.572602 -99.376738)
		(width 0.0889)
		(layer "F.Cu")
		(net "M_L_ECC<6>")
	)
	(segment
		(start 75.319636 -123.992132)
		(end 75.319636 -124.703332)
		(width 0.1651)
		(layer "F.Cu")
		(net "M_L_ECC<6>")
	)
	(segment
		(start 83.959192 -104.358186)
		(end 83.959192 -105.111042)
		(width 0.1016)
		(layer "F.Cu")
		(net "M_L_ECC<6>")
	)
	(segment
		(start 74.89698 -123.025662)
		(end 75.06208 -123.190762)
		(width 0.1651)
		(layer "F.Cu")
		(net "M_L_ECC<6>")
	)
	(segment
		(start 84.65185 -100.117148)
		(end 84.647532 -100.121466)
		(width 0.0889)
		(layer "F.Cu")
		(net "M_L_ECC<6>")
	)
	(segment
		(start 75.613768 -123.698)
		(end 75.319636 -123.992132)
		(width 0.1651)
		(layer "F.Cu")
		(net "M_L_ECC<6>")
	)
	(segment
		(start 84.531962 -97.58299)
		(end 84.531962 -98.59264)
		(width 0.0889)
		(layer "F.Cu")
		(net "M_L_ECC<6>")
	)
	(segment
		(start 75.06208 -122.517662)
		(end 74.89698 -122.682762)
		(width 0.1651)
		(layer "F.Cu")
		(net "M_L_ECC<6>")
	)
	(segment
		(start 79.433674 -109.63656)
		(end 79.268066 -109.63656)
		(width 0.1016)
		(layer "F.Cu")
		(net "M_L_ECC<6>")
	)
	(via
		(at 74.775568 -125.2474)
		(size 0.508)
		(drill 0.254)
		(layers "F.Cu" "B.Cu")
		(net "M_L_ECC<6>")
	)
	(via
		(at 74.749406 -141.213078)
		(size 0.508)
		(drill 0.254)
		(layers "F.Cu" "B.Cu")
		(net "M_L_ECC<6>")
	)
	(via
		(at 75.59929 -145.5166)
		(size 0.508)
		(drill 0.254)
		(layers "F.Cu" "B.Cu")
		(net "M_L_ECC<6>")
	)
	(arc
		(start 84.581492 -99.391978)
		(mid 84.634413 -99.529174)
		(end 84.65185 -99.675188)
		(width 0.0889)
		(layer "F.Cu")
		(net "M_L_ECC<6>")
	)
	(arc
		(start 84.638388 -98.87839)
		(mid 84.521701 -99.111511)
		(end 84.567776 -99.368102)
		(width 0.0889)
		(layer "F.Cu")
		(net "M_L_ECC<6>")
	)
	(segment
		(start 74.749406 -142.477236)
		(end 74.749406 -141.213078)
		(width 0.1651)
		(layer "B.Cu")
		(net "M_L_ECC<6>")
	)
	(segment
		(start 74.316336 -141.646148)
		(end 74.316336 -144.233646)
		(width 0.14224)
		(layer "In9.Cu")
		(net "M_L_ECC<6>")
	)
	(segment
		(start 74.316336 -144.233646)
		(end 75.59929 -145.5166)
		(width 0.14224)
		(layer "In9.Cu")
		(net "M_L_ECC<6>")
	)
	(segment
		(start 74.749406 -141.213078)
		(end 74.316336 -141.646148)
		(width 0.14224)
		(layer "In9.Cu")
		(net "M_L_ECC<6>")
	)
	(segment
		(start 75.317096 -136.5758)
		(end 75.181968 -136.710928)
		(width 0.14224)
		(layer "In11.Cu")
		(net "M_L_ECC<6>")
	)
	(segment
		(start 75.266296 -131.9276)
		(end 75.181968 -132.011928)
		(width 0.14224)
		(layer "In11.Cu")
		(net "M_L_ECC<6>")
	)
	(segment
		(start 75.181968 -136.710928)
		(end 75.181968 -138.7348)
		(width 0.14224)
		(layer "In11.Cu")
		(net "M_L_ECC<6>")
	)
	(segment
		(start 75.317096 -129.859278)
		(end 75.113896 -130.062478)
		(width 0.14224)
		(layer "In11.Cu")
		(net "M_L_ECC<6>")
	)
	(segment
		(start 75.113896 -130.062478)
		(end 75.113896 -131.307078)
		(width 0.14224)
		(layer "In11.Cu")
		(net "M_L_ECC<6>")
	)
	(segment
		(start 75.317096 -127.643128)
		(end 75.317096 -129.859278)
		(width 0.14224)
		(layer "In11.Cu")
		(net "M_L_ECC<6>")
	)
	(segment
		(start 75.181968 -134.0866)
		(end 75.266296 -134.170928)
		(width 0.14224)
		(layer "In11.Cu")
		(net "M_L_ECC<6>")
	)
	(segment
		(start 75.181968 -138.7348)
		(end 75.317096 -138.869928)
		(width 0.14224)
		(layer "In11.Cu")
		(net "M_L_ECC<6>")
	)
	(segment
		(start 75.266296 -134.517638)
		(end 74.993754 -134.79018)
		(width 0.14224)
		(layer "In11.Cu")
		(net "M_L_ECC<6>")
	)
	(segment
		(start 75.207368 -125.6792)
		(end 75.207368 -127.5334)
		(width 0.14224)
		(layer "In11.Cu")
		(net "M_L_ECC<6>")
	)
	(segment
		(start 75.266296 -134.170928)
		(end 75.266296 -134.517638)
		(width 0.14224)
		(layer "In11.Cu")
		(net "M_L_ECC<6>")
	)
	(segment
		(start 75.181968 -132.011928)
		(end 75.181968 -134.0866)
		(width 0.14224)
		(layer "In11.Cu")
		(net "M_L_ECC<6>")
	)
	(segment
		(start 74.580496 -141.044168)
		(end 74.749406 -141.213078)
		(width 0.14224)
		(layer "In11.Cu")
		(net "M_L_ECC<6>")
	)
	(segment
		(start 74.775568 -125.2474)
		(end 75.207368 -125.6792)
		(width 0.14224)
		(layer "In11.Cu")
		(net "M_L_ECC<6>")
	)
	(segment
		(start 75.317096 -138.869928)
		(end 75.317096 -139.333478)
		(width 0.14224)
		(layer "In11.Cu")
		(net "M_L_ECC<6>")
	)
	(segment
		(start 75.266296 -131.459478)
		(end 75.266296 -131.9276)
		(width 0.14224)
		(layer "In11.Cu")
		(net "M_L_ECC<6>")
	)
	(segment
		(start 74.993754 -135.932926)
		(end 75.317096 -136.256268)
		(width 0.14224)
		(layer "In11.Cu")
		(net "M_L_ECC<6>")
	)
	(segment
		(start 74.993754 -134.79018)
		(end 74.993754 -135.932926)
		(width 0.14224)
		(layer "In11.Cu")
		(net "M_L_ECC<6>")
	)
	(segment
		(start 75.317096 -136.256268)
		(end 75.317096 -136.5758)
		(width 0.14224)
		(layer "In11.Cu")
		(net "M_L_ECC<6>")
	)
	(segment
		(start 74.580496 -140.070078)
		(end 74.580496 -141.044168)
		(width 0.14224)
		(layer "In11.Cu")
		(net "M_L_ECC<6>")
	)
	(segment
		(start 75.317096 -139.333478)
		(end 74.580496 -140.070078)
		(width 0.14224)
		(layer "In11.Cu")
		(net "M_L_ECC<6>")
	)
	(segment
		(start 75.113896 -131.307078)
		(end 75.266296 -131.459478)
		(width 0.14224)
		(layer "In11.Cu")
		(net "M_L_ECC<6>")
	)
	(segment
		(start 75.207368 -127.5334)
		(end 75.317096 -127.643128)
		(width 0.14224)
		(layer "In11.Cu")
		(net "M_L_ECC<6>")
	)
	(segment
		(start 82.079592 -101.32314)
		(end 82.00898 -101.493828)
		(width 0.0889)
		(layer "F.Cu")
		(net "M_L_ECC<5>")
	)
	(segment
		(start 82.050382 -99.996244)
		(end 82.050382 -100.319332)
		(width 0.0889)
		(layer "F.Cu")
		(net "M_L_ECC<5>")
	)
	(segment
		(start 70.165214 -116.657882)
		(end 69.993764 -116.829332)
		(width 0.1651)
		(layer "F.Cu")
		(net "M_L_ECC<5>")
	)
	(segment
		(start 70.127368 -115.438682)
		(end 70.127368 -115.857782)
		(width 0.1651)
		(layer "F.Cu")
		(net "M_L_ECC<5>")
	)
	(segment
		(start 81.9023 -99.60229)
		(end 81.9023 -99.740974)
		(width 0.0889)
		(layer "F.Cu")
		(net "M_L_ECC<5>")
	)
	(segment
		(start 69.993764 -114.467132)
		(end 70.165214 -114.638582)
		(width 0.1651)
		(layer "F.Cu")
		(net "M_L_ECC<5>")
	)
	(segment
		(start 70.505066 -115.311682)
		(end 70.254368 -115.311682)
		(width 0.1651)
		(layer "F.Cu")
		(net "M_L_ECC<5>")
	)
	(segment
		(start 76.56068 -106.747564)
		(end 76.389738 -106.918506)
		(width 0.1016)
		(layer "F.Cu")
		(net "M_L_ECC<5>")
	)
	(segment
		(start 70.505066 -116.657882)
		(end 70.165214 -116.657882)
		(width 0.1651)
		(layer "F.Cu")
		(net "M_L_ECC<5>")
	)
	(segment
		(start 82.014314 -98.45167)
		(end 81.992216 -98.490024)
		(width 0.0889)
		(layer "F.Cu")
		(net "M_L_ECC<5>")
	)
	(segment
		(start 70.505066 -114.638582)
		(end 70.670166 -114.803682)
		(width 0.1651)
		(layer "F.Cu")
		(net "M_L_ECC<5>")
	)
	(segment
		(start 69.993764 -124.046996)
		(end 70.051168 -124.1044)
		(width 0.1651)
		(layer "F.Cu")
		(net "M_L_ECC<5>")
	)
	(segment
		(start 82.104992 -102.346506)
		(end 82.168492 -102.410006)
		(width 0.0889)
		(layer "F.Cu")
		(net "M_L_ECC<5>")
	)
	(segment
		(start 82.079592 -101.05644)
		(end 82.079592 -101.32314)
		(width 0.0889)
		(layer "F.Cu")
		(net "M_L_ECC<5>")
	)
	(segment
		(start 70.670166 -114.803682)
		(end 70.670166 -115.146582)
		(width 0.1651)
		(layer "F.Cu")
		(net "M_L_ECC<5>")
	)
	(segment
		(start 70.670166 -115.146582)
		(end 70.505066 -115.311682)
		(width 0.1651)
		(layer "F.Cu")
		(net "M_L_ECC<5>")
	)
	(segment
		(start 82.168492 -102.410006)
		(end 82.168492 -103.004112)
		(width 0.1016)
		(layer "F.Cu")
		(net "M_L_ECC<5>")
	)
	(segment
		(start 78.42504 -106.747564)
		(end 76.56068 -106.747564)
		(width 0.1016)
		(layer "F.Cu")
		(net "M_L_ECC<5>")
	)
	(segment
		(start 70.127368 -115.857782)
		(end 70.254368 -115.984782)
		(width 0.1651)
		(layer "F.Cu")
		(net "M_L_ECC<5>")
	)
	(segment
		(start 82.07629 -99.17684)
		(end 82.07629 -99.300792)
		(width 0.0889)
		(layer "F.Cu")
		(net "M_L_ECC<5>")
	)
	(segment
		(start 81.915762 -100.552504)
		(end 81.915762 -100.772468)
		(width 0.0889)
		(layer "F.Cu")
		(net "M_L_ECC<5>")
	)
	(segment
		(start 70.254368 -115.984782)
		(end 70.505066 -115.984782)
		(width 0.1651)
		(layer "F.Cu")
		(net "M_L_ECC<5>")
	)
	(segment
		(start 70.505066 -115.984782)
		(end 70.670166 -116.149882)
		(width 0.1651)
		(layer "F.Cu")
		(net "M_L_ECC<5>")
	)
	(segment
		(start 82.104992 -101.906832)
		(end 82.104992 -102.346506)
		(width 0.0889)
		(layer "F.Cu")
		(net "M_L_ECC<5>")
	)
	(segment
		(start 82.00898 -101.493828)
		(end 82.00898 -101.69906)
		(width 0.0889)
		(layer "F.Cu")
		(net "M_L_ECC<5>")
	)
	(segment
		(start 82.07629 -99.300792)
		(end 81.9023 -99.60229)
		(width 0.0889)
		(layer "F.Cu")
		(net "M_L_ECC<5>")
	)
	(segment
		(start 69.993764 -116.829332)
		(end 69.993764 -124.046996)
		(width 0.1651)
		(layer "F.Cu")
		(net "M_L_ECC<5>")
	)
	(segment
		(start 81.915762 -100.772468)
		(end 82.079592 -101.05644)
		(width 0.0889)
		(layer "F.Cu")
		(net "M_L_ECC<5>")
	)
	(segment
		(start 76.389738 -106.918506)
		(end 69.993764 -113.31448)
		(width 0.1651)
		(layer "F.Cu")
		(net "M_L_ECC<5>")
	)
	(segment
		(start 68.799456 -142.6718)
		(end 68.799456 -143.941546)
		(width 0.1651)
		(layer "F.Cu")
		(net "M_L_ECC<5>")
	)
	(segment
		(start 70.670166 -116.149882)
		(end 70.670166 -116.492782)
		(width 0.1651)
		(layer "F.Cu")
		(net "M_L_ECC<5>")
	)
	(segment
		(start 82.050382 -100.319332)
		(end 81.915762 -100.552504)
		(width 0.0889)
		(layer "F.Cu")
		(net "M_L_ECC<5>")
	)
	(segment
		(start 82.343752 -97.690686)
		(end 82.014314 -98.45167)
		(width 0.0889)
		(layer "F.Cu")
		(net "M_L_ECC<5>")
	)
	(segment
		(start 82.168492 -103.004112)
		(end 78.42504 -106.747564)
		(width 0.1016)
		(layer "F.Cu")
		(net "M_L_ECC<5>")
	)
	(segment
		(start 70.165214 -114.638582)
		(end 70.505066 -114.638582)
		(width 0.1651)
		(layer "F.Cu")
		(net "M_L_ECC<5>")
	)
	(segment
		(start 69.771768 -125.410976)
		(end 69.593968 -125.410976)
		(width 0.1651)
		(layer "F.Cu")
		(net "M_L_ECC<5>")
	)
	(segment
		(start 70.254368 -115.311682)
		(end 70.127368 -115.438682)
		(width 0.1651)
		(layer "F.Cu")
		(net "M_L_ECC<5>")
	)
	(segment
		(start 69.993764 -113.31448)
		(end 69.993764 -114.467132)
		(width 0.1651)
		(layer "F.Cu")
		(net "M_L_ECC<5>")
	)
	(segment
		(start 82.00898 -101.69906)
		(end 82.104992 -101.906832)
		(width 0.0889)
		(layer "F.Cu")
		(net "M_L_ECC<5>")
	)
	(segment
		(start 70.051168 -124.1044)
		(end 70.051168 -125.131576)
		(width 0.1651)
		(layer "F.Cu")
		(net "M_L_ECC<5>")
	)
	(segment
		(start 70.051168 -125.131576)
		(end 69.771768 -125.410976)
		(width 0.1651)
		(layer "F.Cu")
		(net "M_L_ECC<5>")
	)
	(segment
		(start 81.9023 -99.740974)
		(end 82.050382 -99.996244)
		(width 0.0889)
		(layer "F.Cu")
		(net "M_L_ECC<5>")
	)
	(segment
		(start 70.670166 -116.492782)
		(end 70.505066 -116.657882)
		(width 0.1651)
		(layer "F.Cu")
		(net "M_L_ECC<5>")
	)
	(via
		(at 69.593968 -125.410976)
		(size 0.508)
		(drill 0.254)
		(layers "F.Cu" "B.Cu")
		(net "M_L_ECC<5>")
	)
	(via
		(at 68.799456 -143.941546)
		(size 0.508)
		(drill 0.254)
		(layers "F.Cu" "B.Cu")
		(net "M_L_ECC<5>")
	)
	(via
		(at 69.57314 -139.932156)
		(size 0.508)
		(drill 0.254)
		(layers "F.Cu" "B.Cu")
		(net "M_L_ECC<5>")
	)
	(arc
		(start 81.992216 -98.490024)
		(mid 81.943461 -98.686376)
		(end 81.997042 -98.881438)
		(width 0.0889)
		(layer "F.Cu")
		(net "M_L_ECC<5>")
	)
	(arc
		(start 81.997042 -98.881438)
		(mid 82.056109 -99.023924)
		(end 82.07629 -99.17684)
		(width 0.0889)
		(layer "F.Cu")
		(net "M_L_ECC<5>")
	)
	(segment
		(start 69.64934 -137.877296)
		(end 69.64934 -139.855956)
		(width 0.1651)
		(layer "B.Cu")
		(net "M_L_ECC<5>")
	)
	(segment
		(start 69.64934 -139.855956)
		(end 69.57314 -139.932156)
		(width 0.1651)
		(layer "B.Cu")
		(net "M_L_ECC<5>")
	)
	(segment
		(start 68.960746 -142.154656)
		(end 68.960746 -141.817344)
		(width 0.14224)
		(layer "In9.Cu")
		(net "M_L_ECC<5>")
	)
	(segment
		(start 69.122544 -140.9192)
		(end 69.122544 -140.3604)
		(width 0.14224)
		(layer "In9.Cu")
		(net "M_L_ECC<5>")
	)
	(segment
		(start 68.960746 -141.817344)
		(end 69.249544 -141.528546)
		(width 0.14224)
		(layer "In9.Cu")
		(net "M_L_ECC<5>")
	)
	(segment
		(start 68.960746 -143.297656)
		(end 68.960746 -142.985744)
		(width 0.14224)
		(layer "In9.Cu")
		(net "M_L_ECC<5>")
	)
	(segment
		(start 69.249544 -141.528546)
		(end 69.249544 -141.0462)
		(width 0.14224)
		(layer "In9.Cu")
		(net "M_L_ECC<5>")
	)
	(segment
		(start 69.122544 -140.3604)
		(end 69.550788 -139.932156)
		(width 0.14224)
		(layer "In9.Cu")
		(net "M_L_ECC<5>")
	)
	(segment
		(start 69.224144 -143.561054)
		(end 68.960746 -143.297656)
		(width 0.14224)
		(layer "In9.Cu")
		(net "M_L_ECC<5>")
	)
	(segment
		(start 69.198744 -142.747746)
		(end 69.198744 -142.392654)
		(width 0.14224)
		(layer "In9.Cu")
		(net "M_L_ECC<5>")
	)
	(segment
		(start 68.799456 -143.941546)
		(end 69.071744 -143.941546)
		(width 0.14224)
		(layer "In9.Cu")
		(net "M_L_ECC<5>")
	)
	(segment
		(start 69.198744 -142.392654)
		(end 68.960746 -142.154656)
		(width 0.14224)
		(layer "In9.Cu")
		(net "M_L_ECC<5>")
	)
	(segment
		(start 69.249544 -141.0462)
		(end 69.122544 -140.9192)
		(width 0.14224)
		(layer "In9.Cu")
		(net "M_L_ECC<5>")
	)
	(segment
		(start 68.960746 -142.985744)
		(end 69.198744 -142.747746)
		(width 0.14224)
		(layer "In9.Cu")
		(net "M_L_ECC<5>")
	)
	(segment
		(start 69.224144 -143.789146)
		(end 69.224144 -143.561054)
		(width 0.14224)
		(layer "In9.Cu")
		(net "M_L_ECC<5>")
	)
	(segment
		(start 69.071744 -143.941546)
		(end 69.224144 -143.789146)
		(width 0.14224)
		(layer "In9.Cu")
		(net "M_L_ECC<5>")
	)
	(segment
		(start 69.550788 -139.932156)
		(end 69.57314 -139.932156)
		(width 0.14224)
		(layer "In9.Cu")
		(net "M_L_ECC<5>")
	)
	(segment
		(start 70.076568 -136.643872)
		(end 70.076568 -138.6586)
		(width 0.14224)
		(layer "In11.Cu")
		(net "M_L_ECC<5>")
	)
	(segment
		(start 69.957696 -138.777472)
		(end 69.957696 -139.5476)
		(width 0.14224)
		(layer "In11.Cu")
		(net "M_L_ECC<5>")
	)
	(segment
		(start 69.983096 -134.180072)
		(end 69.983096 -134.670038)
		(width 0.14224)
		(layer "In11.Cu")
		(net "M_L_ECC<5>")
	)
	(segment
		(start 70.046596 -129.795778)
		(end 70.046596 -131.370578)
		(width 0.14224)
		(layer "In11.Cu")
		(net "M_L_ECC<5>")
	)
	(segment
		(start 70.110096 -134.797038)
		(end 70.110096 -135.853424)
		(width 0.14224)
		(layer "In11.Cu")
		(net "M_L_ECC<5>")
	)
	(segment
		(start 70.110096 -135.853424)
		(end 69.957696 -136.005824)
		(width 0.14224)
		(layer "In11.Cu")
		(net "M_L_ECC<5>")
	)
	(segment
		(start 70.046596 -131.370578)
		(end 69.983096 -131.434078)
		(width 0.14224)
		(layer "In11.Cu")
		(net "M_L_ECC<5>")
	)
	(segment
		(start 70.000368 -127.8636)
		(end 70.000368 -129.74955)
		(width 0.14224)
		(layer "In11.Cu")
		(net "M_L_ECC<5>")
	)
	(segment
		(start 69.957696 -139.5476)
		(end 69.57314 -139.932156)
		(width 0.14224)
		(layer "In11.Cu")
		(net "M_L_ECC<5>")
	)
	(segment
		(start 69.593968 -125.410976)
		(end 70.051168 -125.868176)
		(width 0.14224)
		(layer "In11.Cu")
		(net "M_L_ECC<5>")
	)
	(segment
		(start 69.983096 -131.434078)
		(end 69.983096 -131.9276)
		(width 0.14224)
		(layer "In11.Cu")
		(net "M_L_ECC<5>")
	)
	(segment
		(start 70.051168 -125.868176)
		(end 70.051168 -127.8128)
		(width 0.14224)
		(layer "In11.Cu")
		(net "M_L_ECC<5>")
	)
	(segment
		(start 69.983096 -131.9276)
		(end 70.076568 -132.021072)
		(width 0.14224)
		(layer "In11.Cu")
		(net "M_L_ECC<5>")
	)
	(segment
		(start 70.076568 -132.021072)
		(end 70.076568 -134.0866)
		(width 0.14224)
		(layer "In11.Cu")
		(net "M_L_ECC<5>")
	)
	(segment
		(start 70.076568 -134.0866)
		(end 69.983096 -134.180072)
		(width 0.14224)
		(layer "In11.Cu")
		(net "M_L_ECC<5>")
	)
	(segment
		(start 70.000368 -129.74955)
		(end 70.046596 -129.795778)
		(width 0.14224)
		(layer "In11.Cu")
		(net "M_L_ECC<5>")
	)
	(segment
		(start 69.957696 -136.525)
		(end 70.076568 -136.643872)
		(width 0.14224)
		(layer "In11.Cu")
		(net "M_L_ECC<5>")
	)
	(segment
		(start 69.957696 -136.005824)
		(end 69.957696 -136.525)
		(width 0.14224)
		(layer "In11.Cu")
		(net "M_L_ECC<5>")
	)
	(segment
		(start 70.076568 -138.6586)
		(end 69.957696 -138.777472)
		(width 0.14224)
		(layer "In11.Cu")
		(net "M_L_ECC<5>")
	)
	(segment
		(start 70.051168 -127.8128)
		(end 70.000368 -127.8636)
		(width 0.14224)
		(layer "In11.Cu")
		(net "M_L_ECC<5>")
	)
	(segment
		(start 69.983096 -134.670038)
		(end 70.110096 -134.797038)
		(width 0.14224)
		(layer "In11.Cu")
		(net "M_L_ECC<5>")
	)
	(segment
		(start 69.295264 -113.073942)
		(end 69.295264 -124.403104)
		(width 0.1651)
		(layer "F.Cu")
		(net "M_L_ECC<4>")
	)
	(segment
		(start 81.712308 -99.549966)
		(end 81.712308 -99.811332)
		(width 0.0889)
		(layer "F.Cu")
		(net "M_L_ECC<4>")
	)
	(segment
		(start 81.712308 -99.811332)
		(end 81.859882 -100.066602)
		(width 0.0889)
		(layer "F.Cu")
		(net "M_L_ECC<4>")
	)
	(segment
		(start 81.836768 -102.44328)
		(end 81.836768 -102.761034)
		(width 0.1016)
		(layer "F.Cu")
		(net "M_L_ECC<4>")
	)
	(segment
		(start 81.802732 -101.763576)
		(end 81.901792 -101.978206)
		(width 0.0889)
		(layer "F.Cu")
		(net "M_L_ECC<4>")
	)
	(segment
		(start 81.874868 -101.290628)
		(end 81.802732 -101.453442)
		(width 0.0889)
		(layer "F.Cu")
		(net "M_L_ECC<4>")
	)
	(segment
		(start 69.64934 -145.946368)
		(end 69.551296 -145.415)
		(width 0.1651)
		(layer "F.Cu")
		(net "M_L_ECC<4>")
	)
	(segment
		(start 81.901792 -101.978206)
		(end 81.901792 -102.378256)
		(width 0.0889)
		(layer "F.Cu")
		(net "M_L_ECC<4>")
	)
	(segment
		(start 69.049138 -126.655576)
		(end 68.857368 -126.655576)
		(width 0.1651)
		(layer "F.Cu")
		(net "M_L_ECC<4>")
	)
	(segment
		(start 81.725262 -100.501196)
		(end 81.725262 -100.823776)
		(width 0.0889)
		(layer "F.Cu")
		(net "M_L_ECC<4>")
	)
	(segment
		(start 76.028042 -106.341164)
		(end 69.295264 -113.073942)
		(width 0.1651)
		(layer "F.Cu")
		(net "M_L_ECC<4>")
	)
	(segment
		(start 81.885536 -99.17684)
		(end 81.885536 -99.249738)
		(width 0.0889)
		(layer "F.Cu")
		(net "M_L_ECC<4>")
	)
	(segment
		(start 81.901792 -102.378256)
		(end 81.836768 -102.44328)
		(width 0.0889)
		(layer "F.Cu")
		(net "M_L_ECC<4>")
	)
	(segment
		(start 69.314568 -125.781054)
		(end 69.314568 -126.390146)
		(width 0.1651)
		(layer "F.Cu")
		(net "M_L_ECC<4>")
	)
	(segment
		(start 69.111368 -125.577854)
		(end 69.314568 -125.781054)
		(width 0.1651)
		(layer "F.Cu")
		(net "M_L_ECC<4>")
	)
	(segment
		(start 81.874868 -101.08311)
		(end 81.874868 -101.290628)
		(width 0.0889)
		(layer "F.Cu")
		(net "M_L_ECC<4>")
	)
	(segment
		(start 81.859882 -100.268024)
		(end 81.725262 -100.501196)
		(width 0.0889)
		(layer "F.Cu")
		(net "M_L_ECC<4>")
	)
	(segment
		(start 81.836768 -102.761034)
		(end 78.256638 -106.341164)
		(width 0.127)
		(layer "F.Cu")
		(net "M_L_ECC<4>")
	)
	(segment
		(start 81.885536 -99.249738)
		(end 81.712308 -99.549966)
		(width 0.0889)
		(layer "F.Cu")
		(net "M_L_ECC<4>")
	)
	(segment
		(start 69.295264 -124.403104)
		(end 69.111368 -124.587)
		(width 0.1651)
		(layer "F.Cu")
		(net "M_L_ECC<4>")
	)
	(segment
		(start 69.111368 -124.587)
		(end 69.111368 -125.577854)
		(width 0.1651)
		(layer "F.Cu")
		(net "M_L_ECC<4>")
	)
	(segment
		(start 81.725262 -100.823776)
		(end 81.874868 -101.08311)
		(width 0.0889)
		(layer "F.Cu")
		(net "M_L_ECC<4>")
	)
	(segment
		(start 69.314568 -126.390146)
		(end 69.049138 -126.655576)
		(width 0.1651)
		(layer "F.Cu")
		(net "M_L_ECC<4>")
	)
	(segment
		(start 78.256638 -106.341164)
		(end 76.028042 -106.341164)
		(width 0.127)
		(layer "F.Cu")
		(net "M_L_ECC<4>")
	)
	(segment
		(start 69.64934 -147.27174)
		(end 69.64934 -145.946368)
		(width 0.1651)
		(layer "F.Cu")
		(net "M_L_ECC<4>")
	)
	(segment
		(start 81.802732 -101.453442)
		(end 81.802732 -101.763576)
		(width 0.0889)
		(layer "F.Cu")
		(net "M_L_ECC<4>")
	)
	(segment
		(start 81.859882 -100.066602)
		(end 81.859882 -100.268024)
		(width 0.0889)
		(layer "F.Cu")
		(net "M_L_ECC<4>")
	)
	(via
		(at 68.799456 -141.213078)
		(size 0.508)
		(drill 0.254)
		(layers "F.Cu" "B.Cu")
		(net "M_L_ECC<4>")
	)
	(via
		(at 68.857368 -126.655576)
		(size 0.508)
		(drill 0.254)
		(layers "F.Cu" "B.Cu")
		(net "M_L_ECC<4>")
	)
	(via
		(at 69.551296 -145.415)
		(size 0.508)
		(drill 0.254)
		(layers "F.Cu" "B.Cu")
		(net "M_L_ECC<4>")
	)
	(arc
		(start 81.825592 -98.396806)
		(mid 81.752794 -98.687569)
		(end 81.831942 -98.976688)
		(width 0.0889)
		(layer "F.Cu")
		(net "M_L_ECC<4>")
	)
	(arc
		(start 83.202272 -97.19564)
		(mid 82.769345 -97.260723)
		(end 82.332576 -97.290636)
		(width 0.0889)
		(layer "F.Cu")
		(net "M_L_ECC<4>")
	)
	(arc
		(start 82.332576 -97.290636)
		(mid 82.138726 -97.346986)
		(end 81.997042 -97.490788)
		(width 0.0889)
		(layer "F.Cu")
		(net "M_L_ECC<4>")
	)
	(arc
		(start 81.997042 -97.490788)
		(mid 81.976092 -97.532627)
		(end 81.960212 -97.57664)
		(width 0.0889)
		(layer "F.Cu")
		(net "M_L_ECC<4>")
	)
	(arc
		(start 81.831942 -98.976688)
		(mid 81.871929 -99.073234)
		(end 81.885536 -99.17684)
		(width 0.0889)
		(layer "F.Cu")
		(net "M_L_ECC<4>")
	)
	(arc
		(start 81.944464 -97.716086)
		(mid 81.925465 -98.063509)
		(end 81.825592 -98.396806)
		(width 0.0889)
		(layer "F.Cu")
		(net "M_L_ECC<4>")
	)
	(arc
		(start 81.960212 -97.57664)
		(mid 81.946156 -97.645667)
		(end 81.944464 -97.716086)
		(width 0.0889)
		(layer "F.Cu")
		(net "M_L_ECC<4>")
	)
	(segment
		(start 68.799456 -142.477236)
		(end 68.799456 -141.213078)
		(width 0.1651)
		(layer "B.Cu")
		(net "M_L_ECC<4>")
	)
	(segment
		(start 69.300344 -145.415)
		(end 69.551296 -145.415)
		(width 0.14224)
		(layer "In9.Cu")
		(net "M_L_ECC<4>")
	)
	(segment
		(start 68.366386 -144.17929)
		(end 68.524374 -144.337278)
		(width 0.14224)
		(layer "In9.Cu")
		(net "M_L_ECC<4>")
	)
	(segment
		(start 68.366386 -141.646148)
		(end 68.366386 -144.17929)
		(width 0.14224)
		(layer "In9.Cu")
		(net "M_L_ECC<4>")
	)
	(segment
		(start 68.524374 -144.63903)
		(end 69.300344 -145.415)
		(width 0.14224)
		(layer "In9.Cu")
		(net "M_L_ECC<4>")
	)
	(segment
		(start 68.799456 -141.213078)
		(end 68.366386 -141.646148)
		(width 0.14224)
		(layer "In9.Cu")
		(net "M_L_ECC<4>")
	)
	(segment
		(start 68.524374 -144.337278)
		(end 68.524374 -144.63903)
		(width 0.14224)
		(layer "In9.Cu")
		(net "M_L_ECC<4>")
	)
	(segment
		(start 69.238368 -134.0358)
		(end 69.297296 -134.094728)
		(width 0.14224)
		(layer "In11.Cu")
		(net "M_L_ECC<4>")
	)
	(segment
		(start 69.322696 -129.732278)
		(end 69.068696 -129.986278)
		(width 0.14224)
		(layer "In11.Cu")
		(net "M_L_ECC<4>")
	)
	(segment
		(start 69.297296 -134.094728)
		(end 69.297296 -134.485126)
		(width 0.14224)
		(layer "In11.Cu")
		(net "M_L_ECC<4>")
	)
	(segment
		(start 68.857368 -126.655576)
		(end 68.857368 -128.721612)
		(width 0.14224)
		(layer "In11.Cu")
		(net "M_L_ECC<4>")
	)
	(segment
		(start 68.79844 -139.845034)
		(end 68.79844 -141.212062)
		(width 0.1016)
		(layer "In11.Cu")
		(net "M_L_ECC<4>")
	)
	(segment
		(start 69.068696 -131.180078)
		(end 69.297296 -131.408678)
		(width 0.14224)
		(layer "In11.Cu")
		(net "M_L_ECC<4>")
	)
	(segment
		(start 69.238368 -131.961128)
		(end 69.238368 -134.0358)
		(width 0.14224)
		(layer "In11.Cu")
		(net "M_L_ECC<4>")
	)
	(segment
		(start 69.284596 -136.180068)
		(end 69.284596 -136.652)
		(width 0.14224)
		(layer "In11.Cu")
		(net "M_L_ECC<4>")
	)
	(segment
		(start 69.284596 -138.882628)
		(end 69.284596 -139.358878)
		(width 0.14224)
		(layer "In11.Cu")
		(net "M_L_ECC<4>")
	)
	(segment
		(start 69.068696 -129.986278)
		(end 69.068696 -131.180078)
		(width 0.14224)
		(layer "In11.Cu")
		(net "M_L_ECC<4>")
	)
	(segment
		(start 69.297296 -131.408678)
		(end 69.297296 -131.9022)
		(width 0.14224)
		(layer "In11.Cu")
		(net "M_L_ECC<4>")
	)
	(segment
		(start 69.031104 -135.926576)
		(end 69.284596 -136.180068)
		(width 0.14224)
		(layer "In11.Cu")
		(net "M_L_ECC<4>")
	)
	(segment
		(start 68.857368 -128.721612)
		(end 69.322696 -129.18694)
		(width 0.14224)
		(layer "In11.Cu")
		(net "M_L_ECC<4>")
	)
	(segment
		(start 69.238368 -138.8364)
		(end 69.284596 -138.882628)
		(width 0.14224)
		(layer "In11.Cu")
		(net "M_L_ECC<4>")
	)
	(segment
		(start 69.284596 -139.358878)
		(end 68.79844 -139.845034)
		(width 0.1016)
		(layer "In11.Cu")
		(net "M_L_ECC<4>")
	)
	(segment
		(start 69.031104 -134.751318)
		(end 69.031104 -135.926576)
		(width 0.14224)
		(layer "In11.Cu")
		(net "M_L_ECC<4>")
	)
	(segment
		(start 69.297296 -134.485126)
		(end 69.031104 -134.751318)
		(width 0.14224)
		(layer "In11.Cu")
		(net "M_L_ECC<4>")
	)
	(segment
		(start 69.297296 -131.9022)
		(end 69.238368 -131.961128)
		(width 0.14224)
		(layer "In11.Cu")
		(net "M_L_ECC<4>")
	)
	(segment
		(start 69.284596 -136.652)
		(end 69.238368 -136.698228)
		(width 0.14224)
		(layer "In11.Cu")
		(net "M_L_ECC<4>")
	)
	(segment
		(start 69.238368 -136.698228)
		(end 69.238368 -138.8364)
		(width 0.14224)
		(layer "In11.Cu")
		(net "M_L_ECC<4>")
	)
	(segment
		(start 68.79844 -141.212062)
		(end 68.799456 -141.213078)
		(width 0.1016)
		(layer "In11.Cu")
		(net "M_L_ECC<4>")
	)
	(segment
		(start 69.322696 -129.18694)
		(end 69.322696 -129.732278)
		(width 0.14224)
		(layer "In11.Cu")
		(net "M_L_ECC<4>")
	)
	(segment
		(start 78.925166 -112.70869)
		(end 78.925166 -121.793)
		(width 0.1651)
		(layer "F.Cu")
		(net "M_L_ECC<3>")
	)
	(segment
		(start 80.167734 -111.466122)
		(end 78.925166 -112.70869)
		(width 0.1651)
		(layer "F.Cu")
		(net "M_L_ECC<3>")
	)
	(segment
		(start 76.449428 -142.6718)
		(end 76.449428 -143.941546)
		(width 0.1651)
		(layer "F.Cu")
		(net "M_L_ECC<3>")
	)
	(segment
		(start 78.086966 -119.186452)
		(end 77.744066 -119.186452)
		(width 0.1651)
		(layer "F.Cu")
		(net "M_L_ECC<3>")
	)
	(segment
		(start 77.578966 -119.351552)
		(end 77.578966 -125.085602)
		(width 0.1651)
		(layer "F.Cu")
		(net "M_L_ECC<3>")
	)
	(segment
		(start 78.252066 -121.793)
		(end 78.252066 -119.351552)
		(width 0.1651)
		(layer "F.Cu")
		(net "M_L_ECC<3>")
	)
	(segment
		(start 78.252066 -119.351552)
		(end 78.086966 -119.186452)
		(width 0.1651)
		(layer "F.Cu")
		(net "M_L_ECC<3>")
	)
	(segment
		(start 85.574632 -100.492814)
		(end 85.574632 -104.054402)
		(width 0.127)
		(layer "F.Cu")
		(net "M_L_ECC<3>")
	)
	(segment
		(start 84.886292 -105.872026)
		(end 80.305402 -110.452916)
		(width 0.127)
		(layer "F.Cu")
		(net "M_L_ECC<3>")
	)
	(segment
		(start 78.798166 -121.92)
		(end 78.379066 -121.92)
		(width 0.1651)
		(layer "F.Cu")
		(net "M_L_ECC<3>")
	)
	(segment
		(start 85.403182 -99.482148)
		(end 85.403182 -99.956112)
		(width 0.0889)
		(layer "F.Cu")
		(net "M_L_ECC<3>")
	)
	(segment
		(start 85.495892 -99.313492)
		(end 85.403182 -99.482148)
		(width 0.0889)
		(layer "F.Cu")
		(net "M_L_ECC<3>")
	)
	(segment
		(start 80.305402 -110.452916)
		(end 80.305402 -111.328454)
		(width 0.127)
		(layer "F.Cu")
		(net "M_L_ECC<3>")
	)
	(segment
		(start 78.925166 -121.793)
		(end 78.798166 -121.92)
		(width 0.1651)
		(layer "F.Cu")
		(net "M_L_ECC<3>")
	)
	(segment
		(start 85.574632 -100.127562)
		(end 85.574632 -100.492814)
		(width 0.0889)
		(layer "F.Cu")
		(net "M_L_ECC<3>")
	)
	(segment
		(start 85.574632 -104.054402)
		(end 84.886292 -104.742742)
		(width 0.127)
		(layer "F.Cu")
		(net "M_L_ECC<3>")
	)
	(segment
		(start 84.886292 -104.742742)
		(end 84.886292 -105.872026)
		(width 0.127)
		(layer "F.Cu")
		(net "M_L_ECC<3>")
	)
	(segment
		(start 77.315568 -125.349)
		(end 77.315568 -125.6538)
		(width 0.1651)
		(layer "F.Cu")
		(net "M_L_ECC<3>")
	)
	(segment
		(start 77.578966 -125.085602)
		(end 77.315568 -125.349)
		(width 0.1651)
		(layer "F.Cu")
		(net "M_L_ECC<3>")
	)
	(segment
		(start 85.777832 -98.681286)
		(end 85.495892 -99.313492)
		(width 0.0889)
		(layer "F.Cu")
		(net "M_L_ECC<3>")
	)
	(segment
		(start 85.403182 -99.956112)
		(end 85.574632 -100.127562)
		(width 0.0889)
		(layer "F.Cu")
		(net "M_L_ECC<3>")
	)
	(segment
		(start 78.379066 -121.92)
		(end 78.252066 -121.793)
		(width 0.1651)
		(layer "F.Cu")
		(net "M_L_ECC<3>")
	)
	(segment
		(start 80.305402 -111.328454)
		(end 80.167734 -111.466122)
		(width 0.127)
		(layer "F.Cu")
		(net "M_L_ECC<3>")
	)
	(segment
		(start 77.744066 -119.186452)
		(end 77.578966 -119.351552)
		(width 0.1651)
		(layer "F.Cu")
		(net "M_L_ECC<3>")
	)
	(via
		(at 77.299312 -139.932156)
		(size 0.508)
		(drill 0.254)
		(layers "F.Cu" "B.Cu")
		(net "M_L_ECC<3>")
	)
	(via
		(at 77.315568 -125.6538)
		(size 0.508)
		(drill 0.254)
		(layers "F.Cu" "B.Cu")
		(net "M_L_ECC<3>")
	)
	(via
		(at 76.449428 -143.941546)
		(size 0.508)
		(drill 0.254)
		(layers "F.Cu" "B.Cu")
		(net "M_L_ECC<3>")
	)
	(segment
		(start 77.299566 -138.626342)
		(end 77.299312 -138.626596)
		(width 0.1651)
		(layer "B.Cu")
		(net "M_L_ECC<3>")
	)
	(segment
		(start 77.299566 -137.877296)
		(end 77.299566 -138.626342)
		(width 0.1651)
		(layer "B.Cu")
		(net "M_L_ECC<3>")
	)
	(segment
		(start 77.299312 -138.626596)
		(end 77.299312 -139.932156)
		(width 0.1651)
		(layer "B.Cu")
		(net "M_L_ECC<3>")
	)
	(segment
		(start 76.848716 -140.790168)
		(end 76.893166 -140.834618)
		(width 0.14224)
		(layer "In9.Cu")
		(net "M_L_ECC<3>")
	)
	(segment
		(start 76.899516 -143.763746)
		(end 76.721716 -143.941546)
		(width 0.14224)
		(layer "In9.Cu")
		(net "M_L_ECC<3>")
	)
	(segment
		(start 76.867766 -142.621)
		(end 76.610718 -142.878048)
		(width 0.14224)
		(layer "In9.Cu")
		(net "M_L_ECC<3>")
	)
	(segment
		(start 76.899516 -143.44015)
		(end 76.899516 -143.763746)
		(width 0.14224)
		(layer "In9.Cu")
		(net "M_L_ECC<3>")
	)
	(segment
		(start 76.610718 -143.151352)
		(end 76.899516 -143.44015)
		(width 0.14224)
		(layer "In9.Cu")
		(net "M_L_ECC<3>")
	)
	(segment
		(start 76.893166 -141.5034)
		(end 76.610718 -141.785848)
		(width 0.14224)
		(layer "In9.Cu")
		(net "M_L_ECC<3>")
	)
	(segment
		(start 76.893166 -140.834618)
		(end 76.893166 -141.5034)
		(width 0.14224)
		(layer "In9.Cu")
		(net "M_L_ECC<3>")
	)
	(segment
		(start 76.610718 -141.785848)
		(end 76.610718 -142.059152)
		(width 0.14224)
		(layer "In9.Cu")
		(net "M_L_ECC<3>")
	)
	(segment
		(start 76.848716 -140.3604)
		(end 76.848716 -140.790168)
		(width 0.14224)
		(layer "In9.Cu")
		(net "M_L_ECC<3>")
	)
	(segment
		(start 76.867766 -142.3162)
		(end 76.867766 -142.621)
		(width 0.14224)
		(layer "In9.Cu")
		(net "M_L_ECC<3>")
	)
	(segment
		(start 76.721716 -143.941546)
		(end 76.449428 -143.941546)
		(width 0.14224)
		(layer "In9.Cu")
		(net "M_L_ECC<3>")
	)
	(segment
		(start 77.27696 -139.932156)
		(end 76.848716 -140.3604)
		(width 0.14224)
		(layer "In9.Cu")
		(net "M_L_ECC<3>")
	)
	(segment
		(start 77.299312 -139.932156)
		(end 77.27696 -139.932156)
		(width 0.14224)
		(layer "In9.Cu")
		(net "M_L_ECC<3>")
	)
	(segment
		(start 76.610718 -142.059152)
		(end 76.867766 -142.3162)
		(width 0.14224)
		(layer "In9.Cu")
		(net "M_L_ECC<3>")
	)
	(segment
		(start 76.610718 -142.878048)
		(end 76.610718 -143.151352)
		(width 0.14224)
		(layer "In9.Cu")
		(net "M_L_ECC<3>")
	)
	(segment
		(start 77.791564 -134.706106)
		(end 77.791564 -136.125204)
		(width 0.14224)
		(layer "In11.Cu")
		(net "M_L_ECC<3>")
	)
	(segment
		(start 77.628496 -139.61618)
		(end 77.299312 -139.945364)
		(width 0.14224)
		(layer "In11.Cu")
		(net "M_L_ECC<3>")
	)
	(segment
		(start 77.806296 -131.268978)
		(end 77.666596 -131.408678)
		(width 0.14224)
		(layer "In11.Cu")
		(net "M_L_ECC<3>")
	)
	(segment
		(start 77.806296 -130.113278)
		(end 77.806296 -131.268978)
		(width 0.14224)
		(layer "In11.Cu")
		(net "M_L_ECC<3>")
	)
	(segment
		(start 77.653896 -129.960878)
		(end 77.806296 -130.113278)
		(width 0.14224)
		(layer "In11.Cu")
		(net "M_L_ECC<3>")
	)
	(segment
		(start 77.666596 -131.408678)
		(end 77.666596 -134.581138)
		(width 0.14224)
		(layer "In11.Cu")
		(net "M_L_ECC<3>")
	)
	(segment
		(start 77.666596 -134.581138)
		(end 77.791564 -134.706106)
		(width 0.14224)
		(layer "In11.Cu")
		(net "M_L_ECC<3>")
	)
	(segment
		(start 77.628496 -136.288272)
		(end 77.628496 -139.61618)
		(width 0.14224)
		(layer "In11.Cu")
		(net "M_L_ECC<3>")
	)
	(segment
		(start 77.299312 -139.945364)
		(end 77.299312 -139.932156)
		(width 0.14224)
		(layer "In11.Cu")
		(net "M_L_ECC<3>")
	)
	(segment
		(start 77.791564 -136.125204)
		(end 77.628496 -136.288272)
		(width 0.14224)
		(layer "In11.Cu")
		(net "M_L_ECC<3>")
	)
	(segment
		(start 77.653896 -129.658872)
		(end 77.653896 -129.960878)
		(width 0.14224)
		(layer "In11.Cu")
		(net "M_L_ECC<3>")
	)
	(segment
		(start 77.315568 -125.6538)
		(end 77.867764 -126.205996)
		(width 0.14224)
		(layer "In11.Cu")
		(net "M_L_ECC<3>")
	)
	(segment
		(start 77.867764 -126.205996)
		(end 77.867764 -129.445004)
		(width 0.14224)
		(layer "In11.Cu")
		(net "M_L_ECC<3>")
	)
	(segment
		(start 77.867764 -129.445004)
		(end 77.653896 -129.658872)
		(width 0.14224)
		(layer "In11.Cu")
		(net "M_L_ECC<3>")
	)
	(segment
		(start 77.299566 -147.27174)
		(end 77.299312 -147.27174)
		(width 0.1651)
		(layer "F.Cu")
		(net "M_L_ECC<2>")
	)
	(segment
		(start 77.299312 -147.27174)
		(end 77.299312 -146.280632)
		(width 0.1651)
		(layer "F.Cu")
		(net "M_L_ECC<2>")
	)
	(segment
		(start 85.172804 -99.495864)
		(end 85.172804 -100.069904)
		(width 0.0889)
		(layer "F.Cu")
		(net "M_L_ECC<2>")
	)
	(segment
		(start 85.270086 -99.317302)
		(end 85.172804 -99.495864)
		(width 0.0889)
		(layer "F.Cu")
		(net "M_L_ECC<2>")
	)
	(segment
		(start 77.599286 -117.9068)
		(end 77.599286 -117.225318)
		(width 0.1651)
		(layer "F.Cu")
		(net "M_L_ECC<2>")
	)
	(segment
		(start 84.568792 -105.614978)
		(end 79.937102 -110.246668)
		(width 0.1016)
		(layer "F.Cu")
		(net "M_L_ECC<2>")
	)
	(segment
		(start 85.777832 -97.690686)
		(end 85.777832 -97.691448)
		(width 0.0889)
		(layer "F.Cu")
		(net "M_L_ECC<2>")
	)
	(segment
		(start 85.172804 -100.069904)
		(end 85.257132 -100.154232)
		(width 0.0889)
		(layer "F.Cu")
		(net "M_L_ECC<2>")
	)
	(segment
		(start 77.091286 -117.060218)
		(end 76.934568 -117.216936)
		(width 0.1651)
		(layer "F.Cu")
		(net "M_L_ECC<2>")
	)
	(segment
		(start 76.934568 -124.841)
		(end 76.477368 -125.2982)
		(width 0.1651)
		(layer "F.Cu")
		(net "M_L_ECC<2>")
	)
	(segment
		(start 79.937102 -110.246668)
		(end 79.937102 -110.790228)
		(width 0.1016)
		(layer "F.Cu")
		(net "M_L_ECC<2>")
	)
	(segment
		(start 77.299312 -145.793968)
		(end 77.299312 -145.5166)
		(width 0.1651)
		(layer "F.Cu")
		(net "M_L_ECC<2>")
	)
	(segment
		(start 77.430884 -145.92554)
		(end 77.299312 -145.793968)
		(width 0.1651)
		(layer "F.Cu")
		(net "M_L_ECC<2>")
	)
	(segment
		(start 78.272386 -112.454944)
		(end 78.272386 -117.9068)
		(width 0.1651)
		(layer "F.Cu")
		(net "M_L_ECC<2>")
	)
	(segment
		(start 77.599286 -117.225318)
		(end 77.434186 -117.060218)
		(width 0.1651)
		(layer "F.Cu")
		(net "M_L_ECC<2>")
	)
	(segment
		(start 79.937102 -110.790228)
		(end 79.776828 -110.950502)
		(width 0.1016)
		(layer "F.Cu")
		(net "M_L_ECC<2>")
	)
	(segment
		(start 77.726286 -118.0338)
		(end 77.599286 -117.9068)
		(width 0.1651)
		(layer "F.Cu")
		(net "M_L_ECC<2>")
	)
	(segment
		(start 78.272386 -117.9068)
		(end 78.145386 -118.0338)
		(width 0.1651)
		(layer "F.Cu")
		(net "M_L_ECC<2>")
	)
	(segment
		(start 85.257132 -100.154232)
		(end 85.257132 -100.492814)
		(width 0.0889)
		(layer "F.Cu")
		(net "M_L_ECC<2>")
	)
	(segment
		(start 78.145386 -118.0338)
		(end 77.726286 -118.0338)
		(width 0.1651)
		(layer "F.Cu")
		(net "M_L_ECC<2>")
	)
	(segment
		(start 77.430884 -146.14906)
		(end 77.430884 -145.92554)
		(width 0.1651)
		(layer "F.Cu")
		(net "M_L_ECC<2>")
	)
	(segment
		(start 84.568792 -104.61117)
		(end 84.568792 -105.614978)
		(width 0.1016)
		(layer "F.Cu")
		(net "M_L_ECC<2>")
	)
	(segment
		(start 77.299312 -146.280632)
		(end 77.430884 -146.14906)
		(width 0.1651)
		(layer "F.Cu")
		(net "M_L_ECC<2>")
	)
	(segment
		(start 79.776828 -110.950502)
		(end 78.272386 -112.454944)
		(width 0.1651)
		(layer "F.Cu")
		(net "M_L_ECC<2>")
	)
	(segment
		(start 85.257132 -103.92283)
		(end 84.568792 -104.61117)
		(width 0.1016)
		(layer "F.Cu")
		(net "M_L_ECC<2>")
	)
	(segment
		(start 76.934568 -117.216936)
		(end 76.934568 -124.841)
		(width 0.1651)
		(layer "F.Cu")
		(net "M_L_ECC<2>")
	)
	(segment
		(start 85.777832 -97.691448)
		(end 85.299804 -98.33356)
		(width 0.0889)
		(layer "F.Cu")
		(net "M_L_ECC<2>")
	)
	(segment
		(start 77.434186 -117.060218)
		(end 77.091286 -117.060218)
		(width 0.1651)
		(layer "F.Cu")
		(net "M_L_ECC<2>")
	)
	(segment
		(start 85.257132 -100.492814)
		(end 85.257132 -103.92283)
		(width 0.1016)
		(layer "F.Cu")
		(net "M_L_ECC<2>")
	)
	(via
		(at 77.299312 -145.5166)
		(size 0.508)
		(drill 0.254)
		(layers "F.Cu" "B.Cu")
		(net "M_L_ECC<2>")
	)
	(via
		(at 76.449428 -141.213078)
		(size 0.508)
		(drill 0.254)
		(layers "F.Cu" "B.Cu")
		(net "M_L_ECC<2>")
	)
	(via
		(at 76.477368 -125.2982)
		(size 0.508)
		(drill 0.254)
		(layers "F.Cu" "B.Cu")
		(net "M_L_ECC<2>")
	)
	(arc
		(start 85.299804 -98.33356)
		(mid 85.18767 -98.650107)
		(end 85.266022 -98.976688)
		(width 0.0889)
		(layer "F.Cu")
		(net "M_L_ECC<2>")
	)
	(arc
		(start 85.266022 -98.976688)
		(mid 85.312565 -99.146471)
		(end 85.270086 -99.317302)
		(width 0.0889)
		(layer "F.Cu")
		(net "M_L_ECC<2>")
	)
	(segment
		(start 76.449428 -142.477236)
		(end 76.449428 -141.213078)
		(width 0.1651)
		(layer "B.Cu")
		(net "M_L_ECC<2>")
	)
	(segment
		(start 77.299312 -145.5166)
		(end 76.016358 -144.233646)
		(width 0.14224)
		(layer "In9.Cu")
		(net "M_L_ECC<2>")
	)
	(segment
		(start 76.016358 -141.646148)
		(end 76.449428 -141.213078)
		(width 0.14224)
		(layer "In9.Cu")
		(net "M_L_ECC<2>")
	)
	(segment
		(start 76.016358 -144.233646)
		(end 76.016358 -141.646148)
		(width 0.14224)
		(layer "In9.Cu")
		(net "M_L_ECC<2>")
	)
	(segment
		(start 76.815696 -129.960878)
		(end 76.815696 -131.332478)
		(width 0.14224)
		(layer "In11.Cu")
		(net "M_L_ECC<2>")
	)
	(segment
		(start 76.815696 -131.332478)
		(end 77.018896 -131.535678)
		(width 0.14224)
		(layer "In11.Cu")
		(net "M_L_ECC<2>")
	)
	(segment
		(start 76.883768 -127.482854)
		(end 76.942696 -127.541782)
		(width 0.14224)
		(layer "In11.Cu")
		(net "M_L_ECC<2>")
	)
	(segment
		(start 76.104496 -140.235178)
		(end 76.104496 -140.868146)
		(width 0.14224)
		(layer "In11.Cu")
		(net "M_L_ECC<2>")
	)
	(segment
		(start 76.883768 -125.7046)
		(end 76.883768 -127.482854)
		(width 0.14224)
		(layer "In11.Cu")
		(net "M_L_ECC<2>")
	)
	(segment
		(start 76.739496 -135.976868)
		(end 76.968096 -136.205468)
		(width 0.14224)
		(layer "In11.Cu")
		(net "M_L_ECC<2>")
	)
	(segment
		(start 77.018896 -134.492238)
		(end 76.739496 -134.771638)
		(width 0.14224)
		(layer "In11.Cu")
		(net "M_L_ECC<2>")
	)
	(segment
		(start 76.968096 -136.205468)
		(end 76.968096 -136.6266)
		(width 0.14224)
		(layer "In11.Cu")
		(net "M_L_ECC<2>")
	)
	(segment
		(start 76.968096 -136.6266)
		(end 76.858368 -136.736328)
		(width 0.14224)
		(layer "In11.Cu")
		(net "M_L_ECC<2>")
	)
	(segment
		(start 76.942696 -129.833878)
		(end 76.815696 -129.960878)
		(width 0.14224)
		(layer "In11.Cu")
		(net "M_L_ECC<2>")
	)
	(segment
		(start 76.968096 -138.819128)
		(end 76.968096 -139.371578)
		(width 0.14224)
		(layer "In11.Cu")
		(net "M_L_ECC<2>")
	)
	(segment
		(start 76.968096 -139.371578)
		(end 76.104496 -140.235178)
		(width 0.14224)
		(layer "In11.Cu")
		(net "M_L_ECC<2>")
	)
	(segment
		(start 76.739496 -134.771638)
		(end 76.739496 -135.976868)
		(width 0.14224)
		(layer "In11.Cu")
		(net "M_L_ECC<2>")
	)
	(segment
		(start 76.477368 -125.2982)
		(end 76.883768 -125.7046)
		(width 0.14224)
		(layer "In11.Cu")
		(net "M_L_ECC<2>")
	)
	(segment
		(start 77.018896 -131.535678)
		(end 77.018896 -134.492238)
		(width 0.14224)
		(layer "In11.Cu")
		(net "M_L_ECC<2>")
	)
	(segment
		(start 76.104496 -140.868146)
		(end 76.449428 -141.213078)
		(width 0.14224)
		(layer "In11.Cu")
		(net "M_L_ECC<2>")
	)
	(segment
		(start 76.858368 -136.736328)
		(end 76.858368 -138.7094)
		(width 0.14224)
		(layer "In11.Cu")
		(net "M_L_ECC<2>")
	)
	(segment
		(start 76.858368 -138.7094)
		(end 76.968096 -138.819128)
		(width 0.14224)
		(layer "In11.Cu")
		(net "M_L_ECC<2>")
	)
	(segment
		(start 76.942696 -127.541782)
		(end 76.942696 -129.833878)
		(width 0.14224)
		(layer "In11.Cu")
		(net "M_L_ECC<2>")
	)
	(segment
		(start 71.501508 -122.921268)
		(end 71.336408 -123.086368)
		(width 0.1651)
		(layer "F.Cu")
		(net "M_L_ECC<1>")
	)
	(segment
		(start 71.329804 -118.88343)
		(end 71.329804 -119.22633)
		(width 0.1651)
		(layer "F.Cu")
		(net "M_L_ECC<1>")
	)
	(segment
		(start 77.365352 -107.775248)
		(end 72.006968 -113.133632)
		(width 0.1651)
		(layer "F.Cu")
		(net "M_L_ECC<1>")
	)
	(segment
		(start 71.329804 -120.57253)
		(end 71.494904 -120.73763)
		(width 0.1651)
		(layer "F.Cu")
		(net "M_L_ECC<1>")
	)
	(segment
		(start 71.336408 -122.083068)
		(end 71.501508 -122.248168)
		(width 0.1651)
		(layer "F.Cu")
		(net "M_L_ECC<1>")
	)
	(segment
		(start 71.670164 -124.373132)
		(end 71.670164 -124.785374)
		(width 0.1651)
		(layer "F.Cu")
		(net "M_L_ECC<1>")
	)
	(segment
		(start 72.006968 -121.339864)
		(end 71.771764 -121.575068)
		(width 0.1651)
		(layer "F.Cu")
		(net "M_L_ECC<1>")
	)
	(segment
		(start 83.123532 -103.037386)
		(end 82.435192 -103.725726)
		(width 0.1016)
		(layer "F.Cu")
		(net "M_L_ECC<1>")
	)
	(segment
		(start 71.494904 -120.73763)
		(end 71.841868 -120.73763)
		(width 0.1651)
		(layer "F.Cu")
		(net "M_L_ECC<1>")
	)
	(segment
		(start 83.123532 -100.492814)
		(end 83.123532 -103.037386)
		(width 0.1016)
		(layer "F.Cu")
		(net "M_L_ECC<1>")
	)
	(segment
		(start 78.751938 -107.534456)
		(end 77.606144 -107.534456)
		(width 0.1016)
		(layer "F.Cu")
		(net "M_L_ECC<1>")
	)
	(segment
		(start 72.032622 -119.55018)
		(end 72.032622 -119.89308)
		(width 0.1651)
		(layer "F.Cu")
		(net "M_L_ECC<1>")
	)
	(segment
		(start 71.861172 -120.06453)
		(end 71.494904 -120.06453)
		(width 0.1651)
		(layer "F.Cu")
		(net "M_L_ECC<1>")
	)
	(segment
		(start 71.72198 -122.921268)
		(end 71.501508 -122.921268)
		(width 0.1651)
		(layer "F.Cu")
		(net "M_L_ECC<1>")
	)
	(segment
		(start 71.336408 -123.086368)
		(end 71.336408 -123.429268)
		(width 0.1651)
		(layer "F.Cu")
		(net "M_L_ECC<1>")
	)
	(segment
		(start 71.841868 -117.37213)
		(end 71.651368 -117.37213)
		(width 0.1651)
		(layer "F.Cu")
		(net "M_L_ECC<1>")
	)
	(segment
		(start 71.524368 -117.49913)
		(end 71.524368 -117.91823)
		(width 0.1651)
		(layer "F.Cu")
		(net "M_L_ECC<1>")
	)
	(segment
		(start 71.88708 -122.756168)
		(end 71.72198 -122.921268)
		(width 0.1651)
		(layer "F.Cu")
		(net "M_L_ECC<1>")
	)
	(segment
		(start 72.006968 -113.133632)
		(end 72.006968 -117.20703)
		(width 0.1651)
		(layer "F.Cu")
		(net "M_L_ECC<1>")
	)
	(segment
		(start 71.494904 -118.71833)
		(end 71.329804 -118.88343)
		(width 0.1651)
		(layer "F.Cu")
		(net "M_L_ECC<1>")
	)
	(segment
		(start 71.329804 -119.22633)
		(end 71.494904 -119.39143)
		(width 0.1651)
		(layer "F.Cu")
		(net "M_L_ECC<1>")
	)
	(segment
		(start 71.494904 -120.06453)
		(end 71.329804 -120.22963)
		(width 0.1651)
		(layer "F.Cu")
		(net "M_L_ECC<1>")
	)
	(segment
		(start 83.202272 -99.17684)
		(end 83.123532 -99.25558)
		(width 0.0889)
		(layer "F.Cu")
		(net "M_L_ECC<1>")
	)
	(segment
		(start 71.651368 -118.04523)
		(end 71.879968 -118.04523)
		(width 0.1651)
		(layer "F.Cu")
		(net "M_L_ECC<1>")
	)
	(segment
		(start 72.026018 -118.19128)
		(end 72.026018 -118.53418)
		(width 0.1651)
		(layer "F.Cu")
		(net "M_L_ECC<1>")
	)
	(segment
		(start 72.032622 -119.89308)
		(end 71.861172 -120.06453)
		(width 0.1651)
		(layer "F.Cu")
		(net "M_L_ECC<1>")
	)
	(segment
		(start 72.026018 -118.53418)
		(end 71.841868 -118.71833)
		(width 0.1651)
		(layer "F.Cu")
		(net "M_L_ECC<1>")
	)
	(segment
		(start 72.006968 -120.90273)
		(end 72.006968 -121.339864)
		(width 0.1651)
		(layer "F.Cu")
		(net "M_L_ECC<1>")
	)
	(segment
		(start 71.88708 -123.759468)
		(end 71.88708 -124.156216)
		(width 0.1651)
		(layer "F.Cu")
		(net "M_L_ECC<1>")
	)
	(segment
		(start 71.841868 -120.73763)
		(end 72.006968 -120.90273)
		(width 0.1651)
		(layer "F.Cu")
		(net "M_L_ECC<1>")
	)
	(segment
		(start 71.501508 -122.248168)
		(end 71.72198 -122.248168)
		(width 0.1651)
		(layer "F.Cu")
		(net "M_L_ECC<1>")
	)
	(segment
		(start 82.435192 -103.851202)
		(end 78.751938 -107.534456)
		(width 0.1016)
		(layer "F.Cu")
		(net "M_L_ECC<1>")
	)
	(segment
		(start 71.88708 -124.156216)
		(end 71.670164 -124.373132)
		(width 0.1651)
		(layer "F.Cu")
		(net "M_L_ECC<1>")
	)
	(segment
		(start 71.336408 -123.429268)
		(end 71.501508 -123.594368)
		(width 0.1651)
		(layer "F.Cu")
		(net "M_L_ECC<1>")
	)
	(segment
		(start 82.435192 -103.725726)
		(end 82.435192 -103.851202)
		(width 0.1016)
		(layer "F.Cu")
		(net "M_L_ECC<1>")
	)
	(segment
		(start 71.879968 -118.04523)
		(end 72.026018 -118.19128)
		(width 0.1651)
		(layer "F.Cu")
		(net "M_L_ECC<1>")
	)
	(segment
		(start 71.72198 -123.594368)
		(end 71.88708 -123.759468)
		(width 0.1651)
		(layer "F.Cu")
		(net "M_L_ECC<1>")
	)
	(segment
		(start 71.501508 -121.575068)
		(end 71.336408 -121.740168)
		(width 0.1651)
		(layer "F.Cu")
		(net "M_L_ECC<1>")
	)
	(segment
		(start 71.524368 -117.91823)
		(end 71.651368 -118.04523)
		(width 0.1651)
		(layer "F.Cu")
		(net "M_L_ECC<1>")
	)
	(segment
		(start 70.499478 -142.6718)
		(end 70.499478 -143.941546)
		(width 0.1651)
		(layer "F.Cu")
		(net "M_L_ECC<1>")
	)
	(segment
		(start 71.873872 -119.39143)
		(end 72.032622 -119.55018)
		(width 0.1651)
		(layer "F.Cu")
		(net "M_L_ECC<1>")
	)
	(segment
		(start 71.329804 -120.22963)
		(end 71.329804 -120.57253)
		(width 0.1651)
		(layer "F.Cu")
		(net "M_L_ECC<1>")
	)
	(segment
		(start 71.651368 -117.37213)
		(end 71.524368 -117.49913)
		(width 0.1651)
		(layer "F.Cu")
		(net "M_L_ECC<1>")
	)
	(segment
		(start 71.501508 -123.594368)
		(end 71.72198 -123.594368)
		(width 0.1651)
		(layer "F.Cu")
		(net "M_L_ECC<1>")
	)
	(segment
		(start 71.88708 -122.413268)
		(end 71.88708 -122.756168)
		(width 0.1651)
		(layer "F.Cu")
		(net "M_L_ECC<1>")
	)
	(segment
		(start 77.606144 -107.534456)
		(end 77.365352 -107.775248)
		(width 0.1016)
		(layer "F.Cu")
		(net "M_L_ECC<1>")
	)
	(segment
		(start 71.841868 -118.71833)
		(end 71.494904 -118.71833)
		(width 0.1651)
		(layer "F.Cu")
		(net "M_L_ECC<1>")
	)
	(segment
		(start 83.123532 -99.25558)
		(end 83.123532 -100.492814)
		(width 0.0889)
		(layer "F.Cu")
		(net "M_L_ECC<1>")
	)
	(segment
		(start 71.72198 -122.248168)
		(end 71.88708 -122.413268)
		(width 0.1651)
		(layer "F.Cu")
		(net "M_L_ECC<1>")
	)
	(segment
		(start 71.494904 -119.39143)
		(end 71.873872 -119.39143)
		(width 0.1651)
		(layer "F.Cu")
		(net "M_L_ECC<1>")
	)
	(segment
		(start 71.670164 -124.785374)
		(end 71.171562 -125.283976)
		(width 0.1651)
		(layer "F.Cu")
		(net "M_L_ECC<1>")
	)
	(segment
		(start 71.771764 -121.575068)
		(end 71.501508 -121.575068)
		(width 0.1651)
		(layer "F.Cu")
		(net "M_L_ECC<1>")
	)
	(segment
		(start 72.006968 -117.20703)
		(end 71.841868 -117.37213)
		(width 0.1651)
		(layer "F.Cu")
		(net "M_L_ECC<1>")
	)
	(segment
		(start 71.336408 -121.740168)
		(end 71.336408 -122.083068)
		(width 0.1651)
		(layer "F.Cu")
		(net "M_L_ECC<1>")
	)
	(via
		(at 71.171562 -139.932156)
		(size 0.508)
		(drill 0.254)
		(layers "F.Cu" "B.Cu")
		(net "M_L_ECC<1>")
	)
	(via
		(at 71.171562 -125.283976)
		(size 0.508)
		(drill 0.254)
		(layers "F.Cu" "B.Cu")
		(net "M_L_ECC<1>")
	)
	(via
		(at 70.499478 -143.941546)
		(size 0.508)
		(drill 0.254)
		(layers "F.Cu" "B.Cu")
		(net "M_L_ECC<1>")
	)
	(segment
		(start 71.349362 -137.877296)
		(end 71.349362 -139.251182)
		(width 0.1651)
		(layer "B.Cu")
		(net "M_L_ECC<1>")
	)
	(segment
		(start 71.171562 -139.428982)
		(end 71.171562 -139.932156)
		(width 0.1651)
		(layer "B.Cu")
		(net "M_L_ECC<1>")
	)
	(segment
		(start 71.349362 -139.251182)
		(end 71.171562 -139.428982)
		(width 0.1651)
		(layer "B.Cu")
		(net "M_L_ECC<1>")
	)
	(segment
		(start 70.720966 -140.3604)
		(end 71.14921 -139.932156)
		(width 0.14224)
		(layer "In9.Cu")
		(net "M_L_ECC<1>")
	)
	(segment
		(start 70.660768 -141.715744)
		(end 70.951344 -141.425168)
		(width 0.14224)
		(layer "In9.Cu")
		(net "M_L_ECC<1>")
	)
	(segment
		(start 71.14921 -139.932156)
		(end 71.171562 -139.932156)
		(width 0.14224)
		(layer "In9.Cu")
		(net "M_L_ECC<1>")
	)
	(segment
		(start 70.900544 -143.4846)
		(end 70.660768 -143.244824)
		(width 0.14224)
		(layer "In9.Cu")
		(net "M_L_ECC<1>")
	)
	(segment
		(start 70.720966 -140.790168)
		(end 70.720966 -140.3604)
		(width 0.14224)
		(layer "In9.Cu")
		(net "M_L_ECC<1>")
	)
	(segment
		(start 70.875144 -142.7226)
		(end 70.875144 -142.2908)
		(width 0.14224)
		(layer "In9.Cu")
		(net "M_L_ECC<1>")
	)
	(segment
		(start 70.660768 -143.244824)
		(end 70.660768 -142.936976)
		(width 0.14224)
		(layer "In9.Cu")
		(net "M_L_ECC<1>")
	)
	(segment
		(start 70.660768 -142.076424)
		(end 70.660768 -141.715744)
		(width 0.14224)
		(layer "In9.Cu")
		(net "M_L_ECC<1>")
	)
	(segment
		(start 70.499478 -143.941546)
		(end 70.748398 -143.941546)
		(width 0.14224)
		(layer "In9.Cu")
		(net "M_L_ECC<1>")
	)
	(segment
		(start 70.875144 -142.2908)
		(end 70.660768 -142.076424)
		(width 0.14224)
		(layer "In9.Cu")
		(net "M_L_ECC<1>")
	)
	(segment
		(start 70.951344 -141.020546)
		(end 70.720966 -140.790168)
		(width 0.14224)
		(layer "In9.Cu")
		(net "M_L_ECC<1>")
	)
	(segment
		(start 70.900544 -143.7894)
		(end 70.900544 -143.4846)
		(width 0.14224)
		(layer "In9.Cu")
		(net "M_L_ECC<1>")
	)
	(segment
		(start 70.951344 -141.425168)
		(end 70.951344 -141.020546)
		(width 0.14224)
		(layer "In9.Cu")
		(net "M_L_ECC<1>")
	)
	(segment
		(start 70.748398 -143.941546)
		(end 70.900544 -143.7894)
		(width 0.14224)
		(layer "In9.Cu")
		(net "M_L_ECC<1>")
	)
	(segment
		(start 70.660768 -142.936976)
		(end 70.875144 -142.7226)
		(width 0.14224)
		(layer "In9.Cu")
		(net "M_L_ECC<1>")
	)
	(segment
		(start 71.659496 -128.475994)
		(end 71.659496 -131.681728)
		(width 0.14224)
		(layer "In11.Cu")
		(net "M_L_ECC<1>")
	)
	(segment
		(start 71.659496 -138.879072)
		(end 71.659496 -139.355322)
		(width 0.14224)
		(layer "In11.Cu")
		(net "M_L_ECC<1>")
	)
	(segment
		(start 71.778368 -136.694672)
		(end 71.778368 -138.7602)
		(width 0.14224)
		(layer "In11.Cu")
		(net "M_L_ECC<1>")
	)
	(segment
		(start 71.778368 -134.0612)
		(end 71.659496 -134.180072)
		(width 0.14224)
		(layer "In11.Cu")
		(net "M_L_ECC<1>")
	)
	(segment
		(start 71.659496 -136.5758)
		(end 71.778368 -136.694672)
		(width 0.14224)
		(layer "In11.Cu")
		(net "M_L_ECC<1>")
	)
	(segment
		(start 71.778368 -138.7602)
		(end 71.659496 -138.879072)
		(width 0.14224)
		(layer "In11.Cu")
		(net "M_L_ECC<1>")
	)
	(segment
		(start 71.778368 -131.8006)
		(end 71.778368 -134.0612)
		(width 0.14224)
		(layer "In11.Cu")
		(net "M_L_ECC<1>")
	)
	(segment
		(start 71.171562 -127.98806)
		(end 71.659496 -128.475994)
		(width 0.14224)
		(layer "In11.Cu")
		(net "M_L_ECC<1>")
	)
	(segment
		(start 71.171562 -139.843256)
		(end 71.171562 -139.932156)
		(width 0.14224)
		(layer "In11.Cu")
		(net "M_L_ECC<1>")
	)
	(segment
		(start 71.659496 -131.681728)
		(end 71.778368 -131.8006)
		(width 0.14224)
		(layer "In11.Cu")
		(net "M_L_ECC<1>")
	)
	(segment
		(start 71.659496 -134.180072)
		(end 71.659496 -136.5758)
		(width 0.14224)
		(layer "In11.Cu")
		(net "M_L_ECC<1>")
	)
	(segment
		(start 71.171562 -125.283976)
		(end 71.171562 -127.98806)
		(width 0.14224)
		(layer "In11.Cu")
		(net "M_L_ECC<1>")
	)
	(segment
		(start 71.659496 -139.355322)
		(end 71.171562 -139.843256)
		(width 0.14224)
		(layer "In11.Cu")
		(net "M_L_ECC<1>")
	)
	(segment
		(start 82.818732 -99.559618)
		(end 82.818732 -100.492814)
		(width 0.0889)
		(layer "F.Cu")
		(net "M_L_ECC<0>")
	)
	(segment
		(start 82.818732 -102.910894)
		(end 78.588616 -107.14101)
		(width 0.1016)
		(layer "F.Cu")
		(net "M_L_ECC<0>")
	)
	(segment
		(start 70.635368 -123.7742)
		(end 70.704964 -123.843796)
		(width 0.1651)
		(layer "F.Cu")
		(net "M_L_ECC<0>")
	)
	(segment
		(start 70.704964 -123.843796)
		(end 70.704964 -125.469396)
		(width 0.1651)
		(layer "F.Cu")
		(net "M_L_ECC<0>")
	)
	(segment
		(start 71.342504 -112.870996)
		(end 71.342504 -113.238788)
		(width 0.1651)
		(layer "F.Cu")
		(net "M_L_ECC<0>")
	)
	(segment
		(start 71.342504 -113.238788)
		(end 71.177404 -113.403888)
		(width 0.1651)
		(layer "F.Cu")
		(net "M_L_ECC<0>")
	)
	(segment
		(start 82.584544 -99.32543)
		(end 82.818732 -99.559618)
		(width 0.0889)
		(layer "F.Cu")
		(net "M_L_ECC<0>")
	)
	(segment
		(start 70.965568 -125.73)
		(end 70.965568 -126.189486)
		(width 0.1651)
		(layer "F.Cu")
		(net "M_L_ECC<0>")
	)
	(segment
		(start 82.818732 -100.492814)
		(end 82.818732 -102.910894)
		(width 0.1016)
		(layer "F.Cu")
		(net "M_L_ECC<0>")
	)
	(segment
		(start 82.584544 -98.922078)
		(end 82.584544 -99.32543)
		(width 0.0889)
		(layer "F.Cu")
		(net "M_L_ECC<0>")
	)
	(segment
		(start 76.705968 -107.507532)
		(end 71.342504 -112.870996)
		(width 0.1651)
		(layer "F.Cu")
		(net "M_L_ECC<0>")
	)
	(segment
		(start 77.07249 -107.14101)
		(end 76.705968 -107.507532)
		(width 0.1016)
		(layer "F.Cu")
		(net "M_L_ECC<0>")
	)
	(segment
		(start 70.635368 -117.434614)
		(end 70.635368 -123.7742)
		(width 0.1651)
		(layer "F.Cu")
		(net "M_L_ECC<0>")
	)
	(segment
		(start 71.177404 -113.403888)
		(end 70.889368 -113.403888)
		(width 0.1651)
		(layer "F.Cu")
		(net "M_L_ECC<0>")
	)
	(segment
		(start 71.342504 -114.242088)
		(end 71.342504 -116.727478)
		(width 0.1651)
		(layer "F.Cu")
		(net "M_L_ECC<0>")
	)
	(segment
		(start 70.889368 -114.076988)
		(end 71.177404 -114.076988)
		(width 0.1651)
		(layer "F.Cu")
		(net "M_L_ECC<0>")
	)
	(segment
		(start 70.965568 -126.189486)
		(end 70.499478 -126.655576)
		(width 0.1651)
		(layer "F.Cu")
		(net "M_L_ECC<0>")
	)
	(segment
		(start 70.704964 -125.469396)
		(end 70.965568 -125.73)
		(width 0.1651)
		(layer "F.Cu")
		(net "M_L_ECC<0>")
	)
	(segment
		(start 71.177404 -114.076988)
		(end 71.342504 -114.242088)
		(width 0.1651)
		(layer "F.Cu")
		(net "M_L_ECC<0>")
	)
	(segment
		(start 78.588616 -107.14101)
		(end 77.07249 -107.14101)
		(width 0.1016)
		(layer "F.Cu")
		(net "M_L_ECC<0>")
	)
	(segment
		(start 70.762368 -113.949988)
		(end 70.889368 -114.076988)
		(width 0.1651)
		(layer "F.Cu")
		(net "M_L_ECC<0>")
	)
	(segment
		(start 70.762368 -113.530888)
		(end 70.762368 -113.949988)
		(width 0.1651)
		(layer "F.Cu")
		(net "M_L_ECC<0>")
	)
	(segment
		(start 70.889368 -113.403888)
		(end 70.762368 -113.530888)
		(width 0.1651)
		(layer "F.Cu")
		(net "M_L_ECC<0>")
	)
	(segment
		(start 82.343752 -98.681286)
		(end 82.584544 -98.922078)
		(width 0.0889)
		(layer "F.Cu")
		(net "M_L_ECC<0>")
	)
	(segment
		(start 71.342504 -116.727478)
		(end 70.635368 -117.434614)
		(width 0.1651)
		(layer "F.Cu")
		(net "M_L_ECC<0>")
	)
	(segment
		(start 71.349362 -147.277582)
		(end 71.171562 -145.415)
		(width 0.1651)
		(layer "F.Cu")
		(net "M_L_ECC<0>")
	)
	(segment
		(start 71.349362 -147.27174)
		(end 71.349362 -147.277582)
		(width 0.1651)
		(layer "F.Cu")
		(net "M_L_ECC<0>")
	)
	(via
		(at 70.499478 -126.655576)
		(size 0.508)
		(drill 0.254)
		(layers "F.Cu" "B.Cu")
		(net "M_L_ECC<0>")
	)
	(via
		(at 71.171562 -145.415)
		(size 0.508)
		(drill 0.254)
		(layers "F.Cu" "B.Cu")
		(net "M_L_ECC<0>")
	)
	(via
		(at 70.499478 -141.213078)
		(size 0.508)
		(drill 0.254)
		(layers "F.Cu" "B.Cu")
		(net "M_L_ECC<0>")
	)
	(segment
		(start 70.499478 -142.477236)
		(end 70.499478 -141.213078)
		(width 0.1651)
		(layer "B.Cu")
		(net "M_L_ECC<0>")
	)
	(segment
		(start 70.875398 -145.415)
		(end 70.066408 -144.60601)
		(width 0.14224)
		(layer "In9.Cu")
		(net "M_L_ECC<0>")
	)
	(segment
		(start 70.066408 -141.646148)
		(end 70.499478 -141.213078)
		(width 0.14224)
		(layer "In9.Cu")
		(net "M_L_ECC<0>")
	)
	(segment
		(start 71.171562 -145.415)
		(end 70.875398 -145.415)
		(width 0.14224)
		(layer "In9.Cu")
		(net "M_L_ECC<0>")
	)
	(segment
		(start 70.066408 -144.60601)
		(end 70.066408 -141.646148)
		(width 0.14224)
		(layer "In9.Cu")
		(net "M_L_ECC<0>")
	)
	(segment
		(start 70.135496 -140.209778)
		(end 70.135496 -140.849096)
		(width 0.14224)
		(layer "In11.Cu")
		(net "M_L_ECC<0>")
	)
	(segment
		(start 70.973696 -134.484618)
		(end 70.694296 -134.764018)
		(width 0.14224)
		(layer "In11.Cu")
		(net "M_L_ECC<0>")
	)
	(segment
		(start 70.914768 -134.0866)
		(end 70.973696 -134.145528)
		(width 0.14224)
		(layer "In11.Cu")
		(net "M_L_ECC<0>")
	)
	(segment
		(start 71.024496 -129.719578)
		(end 70.681596 -130.062478)
		(width 0.14224)
		(layer "In11.Cu")
		(net "M_L_ECC<0>")
	)
	(segment
		(start 70.681596 -130.062478)
		(end 70.681596 -131.141978)
		(width 0.14224)
		(layer "In11.Cu")
		(net "M_L_ECC<0>")
	)
	(segment
		(start 70.694296 -135.949182)
		(end 70.986396 -136.241282)
		(width 0.14224)
		(layer "In11.Cu")
		(net "M_L_ECC<0>")
	)
	(segment
		(start 70.986396 -136.5758)
		(end 70.914768 -136.647428)
		(width 0.14224)
		(layer "In11.Cu")
		(net "M_L_ECC<0>")
	)
	(segment
		(start 70.973696 -131.434078)
		(end 70.973696 -131.9784)
		(width 0.14224)
		(layer "In11.Cu")
		(net "M_L_ECC<0>")
	)
	(segment
		(start 70.694296 -134.764018)
		(end 70.694296 -135.949182)
		(width 0.14224)
		(layer "In11.Cu")
		(net "M_L_ECC<0>")
	)
	(segment
		(start 70.914768 -136.647428)
		(end 70.914768 -138.811)
		(width 0.14224)
		(layer "In11.Cu")
		(net "M_L_ECC<0>")
	)
	(segment
		(start 70.499478 -126.655576)
		(end 70.499478 -128.280668)
		(width 0.14224)
		(layer "In11.Cu")
		(net "M_L_ECC<0>")
	)
	(segment
		(start 71.024496 -128.805686)
		(end 71.024496 -129.719578)
		(width 0.14224)
		(layer "In11.Cu")
		(net "M_L_ECC<0>")
	)
	(segment
		(start 70.499478 -128.280668)
		(end 71.024496 -128.805686)
		(width 0.14224)
		(layer "In11.Cu")
		(net "M_L_ECC<0>")
	)
	(segment
		(start 70.914768 -132.037328)
		(end 70.914768 -134.0866)
		(width 0.14224)
		(layer "In11.Cu")
		(net "M_L_ECC<0>")
	)
	(segment
		(start 70.914768 -138.811)
		(end 70.986396 -138.882628)
		(width 0.14224)
		(layer "In11.Cu")
		(net "M_L_ECC<0>")
	)
	(segment
		(start 70.986396 -136.241282)
		(end 70.986396 -136.5758)
		(width 0.14224)
		(layer "In11.Cu")
		(net "M_L_ECC<0>")
	)
	(segment
		(start 70.986396 -138.882628)
		(end 70.986396 -139.358878)
		(width 0.14224)
		(layer "In11.Cu")
		(net "M_L_ECC<0>")
	)
	(segment
		(start 70.986396 -139.358878)
		(end 70.135496 -140.209778)
		(width 0.14224)
		(layer "In11.Cu")
		(net "M_L_ECC<0>")
	)
	(segment
		(start 70.973696 -134.145528)
		(end 70.973696 -134.484618)
		(width 0.14224)
		(layer "In11.Cu")
		(net "M_L_ECC<0>")
	)
	(segment
		(start 70.681596 -131.141978)
		(end 70.973696 -131.434078)
		(width 0.14224)
		(layer "In11.Cu")
		(net "M_L_ECC<0>")
	)
	(segment
		(start 70.135496 -140.849096)
		(end 70.499478 -141.213078)
		(width 0.14224)
		(layer "In11.Cu")
		(net "M_L_ECC<0>")
	)
	(segment
		(start 70.973696 -131.9784)
		(end 70.914768 -132.037328)
		(width 0.14224)
		(layer "In11.Cu")
		(net "M_L_ECC<0>")
	)
	(segment
		(start 34.799524 -143.294354)
		(end 34.363406 -143.730472)
		(width 0.1651)
		(layer "F.Cu")
		(net "M_L_DQS_DP<9>")
	)
	(segment
		(start 34.360358 -144.956784)
		(end 34.74212 -145.338546)
		(width 0.1651)
		(layer "F.Cu")
		(net "M_L_DQS_DP<9>")
	)
	(segment
		(start 73.758806 -85.803486)
		(end 73.187306 -85.803486)
		(width 0.1651)
		(layer "F.Cu")
		(net "M_L_DQS_DP<9>")
	)
	(segment
		(start 34.799524 -142.6718)
		(end 34.799524 -143.294354)
		(width 0.1651)
		(layer "F.Cu")
		(net "M_L_DQS_DP<9>")
	)
	(segment
		(start 34.363406 -143.730472)
		(end 34.278824 -143.914368)
		(width 0.1651)
		(layer "F.Cu")
		(net "M_L_DQS_DP<9>")
	)
	(segment
		(start 34.278824 -144.732502)
		(end 34.360358 -144.956784)
		(width 0.1651)
		(layer "F.Cu")
		(net "M_L_DQS_DP<9>")
	)
	(segment
		(start 34.278824 -143.914368)
		(end 34.278824 -144.732502)
		(width 0.1651)
		(layer "F.Cu")
		(net "M_L_DQS_DP<9>")
	)
	(via
		(at 34.74212 -145.338546)
		(size 0.508)
		(drill 0.254)
		(layers "F.Cu" "B.Cu")
		(net "M_L_DQS_DP<9>")
	)
	(via
		(at 34.74212 -139.827)
		(size 0.508)
		(drill 0.254)
		(layers "F.Cu" "B.Cu")
		(net "M_L_DQS_DP<9>")
	)
	(via
		(at 73.187306 -85.803486)
		(size 0.508)
		(drill 0.254)
		(layers "F.Cu" "B.Cu")
		(net "M_L_DQS_DP<9>")
	)
	(segment
		(start 34.266124 -141.270736)
		(end 34.266124 -140.375132)
		(width 0.1651)
		(layer "B.Cu")
		(net "M_L_DQS_DP<9>")
	)
	(segment
		(start 34.3535 -140.21562)
		(end 34.74212 -139.827)
		(width 0.1651)
		(layer "B.Cu")
		(net "M_L_DQS_DP<9>")
	)
	(segment
		(start 34.799524 -142.477236)
		(end 34.799524 -141.859254)
		(width 0.1651)
		(layer "B.Cu")
		(net "M_L_DQS_DP<9>")
	)
	(segment
		(start 34.266124 -140.375132)
		(end 34.3535 -140.21562)
		(width 0.1651)
		(layer "B.Cu")
		(net "M_L_DQS_DP<9>")
	)
	(segment
		(start 34.799524 -141.859254)
		(end 34.34334 -141.40307)
		(width 0.1651)
		(layer "B.Cu")
		(net "M_L_DQS_DP<9>")
	)
	(segment
		(start 34.34334 -141.40307)
		(end 34.266124 -141.270736)
		(width 0.1651)
		(layer "B.Cu")
		(net "M_L_DQS_DP<9>")
	)
	(segment
		(start 66.229738 -84.60105)
		(end 66.695828 -84.60105)
		(width 0.0889)
		(layer "In4.Cu")
		(net "M_L_DQS_DP<9>")
	)
	(segment
		(start 63.942468 -84.56168)
		(end 66.16827 -84.56168)
		(width 0.14224)
		(layer "In4.Cu")
		(net "M_L_DQS_DP<9>")
	)
	(segment
		(start 34.445448 -128.59639)
		(end 34.445448 -119.861584)
		(width 0.14224)
		(layer "In4.Cu")
		(net "M_L_DQS_DP<9>")
	)
	(segment
		(start 71.45528 -84.222336)
		(end 71.488046 -84.222336)
		(width 0.0889)
		(layer "In4.Cu")
		(net "M_L_DQS_DP<9>")
	)
	(segment
		(start 35.639756 -119.26189)
		(end 35.639756 -118.830344)
		(width 0.14224)
		(layer "In4.Cu")
		(net "M_L_DQS_DP<9>")
	)
	(segment
		(start 55.349902 -97.098612)
		(end 55.349902 -93.154246)
		(width 0.14224)
		(layer "In4.Cu")
		(net "M_L_DQS_DP<9>")
	)
	(segment
		(start 34.74212 -139.827)
		(end 34.991294 -139.827)
		(width 0.14224)
		(layer "In4.Cu")
		(net "M_L_DQS_DP<9>")
	)
	(segment
		(start 55.349902 -93.154246)
		(end 63.942468 -84.56168)
		(width 0.14224)
		(layer "In4.Cu")
		(net "M_L_DQS_DP<9>")
	)
	(segment
		(start 34.445448 -118.284752)
		(end 34.445448 -117.681248)
		(width 0.14224)
		(layer "In4.Cu")
		(net "M_L_DQS_DP<9>")
	)
	(segment
		(start 34.237168 -140.2588)
		(end 34.237168 -144.833594)
		(width 0.14224)
		(layer "In4.Cu")
		(net "M_L_DQS_DP<9>")
	)
	(segment
		(start 69.735446 -83.231736)
		(end 69.771006 -83.231736)
		(width 0.0889)
		(layer "In4.Cu")
		(net "M_L_DQS_DP<9>")
	)
	(segment
		(start 34.824416 -119.482616)
		(end 35.41903 -119.482616)
		(width 0.14224)
		(layer "In4.Cu")
		(net "M_L_DQS_DP<9>")
	)
	(segment
		(start 66.695828 -84.60105)
		(end 66.812668 -84.71789)
		(width 0.0889)
		(layer "In4.Cu")
		(net "M_L_DQS_DP<9>")
	)
	(segment
		(start 67.833494 -84.222336)
		(end 68.051172 -84.222336)
		(width 0.0889)
		(layer "In4.Cu")
		(net "M_L_DQS_DP<9>")
	)
	(segment
		(start 70.60057 -83.72729)
		(end 70.633336 -83.72729)
		(width 0.0889)
		(layer "In4.Cu")
		(net "M_L_DQS_DP<9>")
	)
	(segment
		(start 68.873116 -83.72729)
		(end 68.905882 -83.72729)
		(width 0.0889)
		(layer "In4.Cu")
		(net "M_L_DQS_DP<9>")
	)
	(segment
		(start 67.484752 -84.520786)
		(end 67.484498 -84.520532)
		(width 0.0889)
		(layer "In4.Cu")
		(net "M_L_DQS_DP<9>")
	)
	(segment
		(start 34.769552 -118.608856)
		(end 34.445448 -118.284752)
		(width 0.14224)
		(layer "In4.Cu")
		(net "M_L_DQS_DP<9>")
	)
	(segment
		(start 34.237168 -144.833594)
		(end 34.74212 -145.338546)
		(width 0.14224)
		(layer "In4.Cu")
		(net "M_L_DQS_DP<9>")
	)
	(segment
		(start 34.991294 -139.827)
		(end 35.2552 -139.563094)
		(width 0.14224)
		(layer "In4.Cu")
		(net "M_L_DQS_DP<9>")
	)
	(segment
		(start 35.2552 -139.563094)
		(end 35.2552 -129.406142)
		(width 0.14224)
		(layer "In4.Cu")
		(net "M_L_DQS_DP<9>")
	)
	(segment
		(start 67.484752 -84.52104)
		(end 67.484752 -84.520786)
		(width 0.0889)
		(layer "In4.Cu")
		(net "M_L_DQS_DP<9>")
	)
	(segment
		(start 72.89419 -85.634576)
		(end 73.187306 -85.803486)
		(width 0.0889)
		(layer "In4.Cu")
		(net "M_L_DQS_DP<9>")
	)
	(segment
		(start 72.870314 -85.545422)
		(end 72.89419 -85.634576)
		(width 0.0889)
		(layer "In4.Cu")
		(net "M_L_DQS_DP<9>")
	)
	(segment
		(start 35.2552 -129.406142)
		(end 34.445448 -128.59639)
		(width 0.14224)
		(layer "In4.Cu")
		(net "M_L_DQS_DP<9>")
	)
	(segment
		(start 66.190368 -84.56168)
		(end 66.229738 -84.60105)
		(width 0.0889)
		(layer "In4.Cu")
		(net "M_L_DQS_DP<9>")
	)
	(segment
		(start 37.866574 -114.260122)
		(end 37.866574 -113.431828)
		(width 0.14224)
		(layer "In4.Cu")
		(net "M_L_DQS_DP<9>")
	)
	(segment
		(start 37.866574 -113.431828)
		(end 42.398442 -108.89996)
		(width 0.14224)
		(layer "In4.Cu")
		(net "M_L_DQS_DP<9>")
	)
	(segment
		(start 34.668968 -139.827)
		(end 34.237168 -140.2588)
		(width 0.14224)
		(layer "In4.Cu")
		(net "M_L_DQS_DP<9>")
	)
	(segment
		(start 35.418268 -118.608856)
		(end 34.769552 -118.608856)
		(width 0.14224)
		(layer "In4.Cu")
		(net "M_L_DQS_DP<9>")
	)
	(segment
		(start 66.16827 -84.56168)
		(end 66.190368 -84.56168)
		(width 0.0889)
		(layer "In4.Cu")
		(net "M_L_DQS_DP<9>")
	)
	(segment
		(start 34.74212 -139.827)
		(end 34.668968 -139.827)
		(width 0.14224)
		(layer "In4.Cu")
		(net "M_L_DQS_DP<9>")
	)
	(segment
		(start 34.445448 -119.861584)
		(end 34.824416 -119.482616)
		(width 0.14224)
		(layer "In4.Cu")
		(net "M_L_DQS_DP<9>")
	)
	(segment
		(start 72.31761 -84.71789)
		(end 72.350376 -84.71789)
		(width 0.0889)
		(layer "In4.Cu")
		(net "M_L_DQS_DP<9>")
	)
	(segment
		(start 66.812668 -84.71789)
		(end 67.26936 -84.71789)
		(width 0.0889)
		(layer "In4.Cu")
		(net "M_L_DQS_DP<9>")
	)
	(segment
		(start 42.398442 -108.89996)
		(end 43.548554 -108.89996)
		(width 0.14224)
		(layer "In4.Cu")
		(net "M_L_DQS_DP<9>")
	)
	(segment
		(start 34.445448 -117.681248)
		(end 37.866574 -114.260122)
		(width 0.14224)
		(layer "In4.Cu")
		(net "M_L_DQS_DP<9>")
	)
	(segment
		(start 43.548554 -108.89996)
		(end 55.349902 -97.098612)
		(width 0.14224)
		(layer "In4.Cu")
		(net "M_L_DQS_DP<9>")
	)
	(segment
		(start 35.41903 -119.482616)
		(end 35.639756 -119.26189)
		(width 0.14224)
		(layer "In4.Cu")
		(net "M_L_DQS_DP<9>")
	)
	(segment
		(start 35.639756 -118.830344)
		(end 35.418268 -118.608856)
		(width 0.14224)
		(layer "In4.Cu")
		(net "M_L_DQS_DP<9>")
	)
	(arc
		(start 71.488046 -84.222336)
		(mid 71.77347 -84.305803)
		(end 71.982076 -84.517738)
		(width 0.0889)
		(layer "In4.Cu")
		(net "M_L_DQS_DP<9>")
	)
	(arc
		(start 70.633336 -83.72729)
		(mid 70.916553 -83.811571)
		(end 71.123556 -84.022438)
		(width 0.0889)
		(layer "In4.Cu")
		(net "M_L_DQS_DP<9>")
	)
	(arc
		(start 67.515994 -84.467446)
		(mid 67.654508 -84.318669)
		(end 67.833494 -84.222336)
		(width 0.0889)
		(layer "In4.Cu")
		(net "M_L_DQS_DP<9>")
	)
	(arc
		(start 68.382896 -84.022438)
		(mid 68.5899 -83.811574)
		(end 68.873116 -83.72729)
		(width 0.0889)
		(layer "In4.Cu")
		(net "M_L_DQS_DP<9>")
	)
	(arc
		(start 68.051172 -84.222336)
		(mid 68.242814 -84.16517)
		(end 68.382896 -84.022438)
		(width 0.0889)
		(layer "In4.Cu")
		(net "M_L_DQS_DP<9>")
	)
	(arc
		(start 69.771006 -83.231736)
		(mid 70.05643 -83.315203)
		(end 70.265036 -83.527138)
		(width 0.0889)
		(layer "In4.Cu")
		(net "M_L_DQS_DP<9>")
	)
	(arc
		(start 67.26936 -84.71789)
		(mid 67.394116 -84.638128)
		(end 67.484752 -84.52104)
		(width 0.0889)
		(layer "In4.Cu")
		(net "M_L_DQS_DP<9>")
	)
	(arc
		(start 70.265036 -83.527138)
		(mid 70.406719 -83.670942)
		(end 70.60057 -83.72729)
		(width 0.0889)
		(layer "In4.Cu")
		(net "M_L_DQS_DP<9>")
	)
	(arc
		(start 67.484498 -84.520532)
		(mid 67.499585 -84.493596)
		(end 67.515994 -84.467446)
		(width 0.0889)
		(layer "In4.Cu")
		(net "M_L_DQS_DP<9>")
	)
	(arc
		(start 68.905882 -83.72729)
		(mid 69.099732 -83.67094)
		(end 69.241416 -83.527138)
		(width 0.0889)
		(layer "In4.Cu")
		(net "M_L_DQS_DP<9>")
	)
	(arc
		(start 71.123556 -84.022438)
		(mid 71.263635 -84.165174)
		(end 71.45528 -84.222336)
		(width 0.0889)
		(layer "In4.Cu")
		(net "M_L_DQS_DP<9>")
	)
	(arc
		(start 72.350376 -84.71789)
		(mid 72.829193 -84.994102)
		(end 72.870314 -85.545422)
		(width 0.0889)
		(layer "In4.Cu")
		(net "M_L_DQS_DP<9>")
	)
	(arc
		(start 71.982076 -84.517738)
		(mid 72.123759 -84.661542)
		(end 72.31761 -84.71789)
		(width 0.0889)
		(layer "In4.Cu")
		(net "M_L_DQS_DP<9>")
	)
	(arc
		(start 69.241416 -83.527138)
		(mid 69.450024 -83.315206)
		(end 69.735446 -83.231736)
		(width 0.0889)
		(layer "In4.Cu")
		(net "M_L_DQS_DP<9>")
	)
	(segment
		(start 74.57059 -117.700552)
		(end 74.131932 -117.700552)
		(width 0.1651)
		(layer "F.Cu")
		(net "M_L_DQS_DP<8>")
	)
	(segment
		(start 74.128376 -118.434866)
		(end 74.591926 -118.434866)
		(width 0.1651)
		(layer "F.Cu")
		(net "M_L_DQS_DP<8>")
	)
	(segment
		(start 73.693528 -144.61236)
		(end 73.437496 -144.61236)
		(width 0.1651)
		(layer "F.Cu")
		(net "M_L_DQS_DP<8>")
	)
	(segment
		(start 73.934574 -119.844566)
		(end 73.934574 -120.174766)
		(width 0.1651)
		(layer "F.Cu")
		(net "M_L_DQS_DP<8>")
	)
	(segment
		(start 73.937368 -146.2278)
		(end 73.937368 -144.8562)
		(width 0.1651)
		(layer "F.Cu")
		(net "M_L_DQS_DP<8>")
	)
	(segment
		(start 74.131932 -117.700552)
		(end 73.9521 -117.880384)
		(width 0.1651)
		(layer "F.Cu")
		(net "M_L_DQS_DP<8>")
	)
	(segment
		(start 78.830678 -109.163866)
		(end 78.653386 -109.341158)
		(width 0.1016)
		(layer "F.Cu")
		(net "M_L_DQS_DP<8>")
	)
	(segment
		(start 74.927968 -119.343424)
		(end 74.591926 -119.679466)
		(width 0.1651)
		(layer "F.Cu")
		(net "M_L_DQS_DP<8>")
	)
	(segment
		(start 84.441792 -99.897438)
		(end 84.342732 -99.996498)
		(width 0.0889)
		(layer "F.Cu")
		(net "M_L_DQS_DP<8>")
	)
	(segment
		(start 73.934574 -120.174766)
		(end 74.235564 -120.475756)
		(width 0.1651)
		(layer "F.Cu")
		(net "M_L_DQS_DP<8>")
	)
	(segment
		(start 73.9521 -118.25859)
		(end 74.128376 -118.434866)
		(width 0.1651)
		(layer "F.Cu")
		(net "M_L_DQS_DP<8>")
	)
	(segment
		(start 73.9521 -117.880384)
		(end 73.9521 -118.25859)
		(width 0.1651)
		(layer "F.Cu")
		(net "M_L_DQS_DP<8>")
	)
	(segment
		(start 74.235564 -120.475756)
		(end 74.235564 -125.171708)
		(width 0.1651)
		(layer "F.Cu")
		(net "M_L_DQS_DP<8>")
	)
	(segment
		(start 74.099674 -119.679466)
		(end 73.934574 -119.844566)
		(width 0.1651)
		(layer "F.Cu")
		(net "M_L_DQS_DP<8>")
	)
	(segment
		(start 84.441792 -99.600766)
		(end 84.441792 -99.897438)
		(width 0.0889)
		(layer "F.Cu")
		(net "M_L_DQS_DP<8>")
	)
	(segment
		(start 74.907902 -113.086642)
		(end 74.907902 -117.36324)
		(width 0.1651)
		(layer "F.Cu")
		(net "M_L_DQS_DP<8>")
	)
	(segment
		(start 74.235564 -125.171708)
		(end 73.437496 -125.969776)
		(width 0.1651)
		(layer "F.Cu")
		(net "M_L_DQS_DP<8>")
	)
	(segment
		(start 73.899522 -147.27174)
		(end 73.899522 -146.265646)
		(width 0.1651)
		(layer "F.Cu")
		(net "M_L_DQS_DP<8>")
	)
	(segment
		(start 84.342732 -99.996498)
		(end 84.342732 -100.492814)
		(width 0.0889)
		(layer "F.Cu")
		(net "M_L_DQS_DP<8>")
	)
	(segment
		(start 84.342732 -100.492814)
		(end 84.342732 -103.543354)
		(width 0.1016)
		(layer "F.Cu")
		(net "M_L_DQS_DP<8>")
	)
	(segment
		(start 74.591926 -118.434866)
		(end 74.927968 -118.770908)
		(width 0.1651)
		(layer "F.Cu")
		(net "M_L_DQS_DP<8>")
	)
	(segment
		(start 83.654392 -104.231694)
		(end 83.654392 -104.859074)
		(width 0.1016)
		(layer "F.Cu")
		(net "M_L_DQS_DP<8>")
	)
	(segment
		(start 84.390738 -99.443286)
		(end 84.407248 -99.471734)
		(width 0.0889)
		(layer "F.Cu")
		(net "M_L_DQS_DP<8>")
	)
	(segment
		(start 74.927968 -118.770908)
		(end 74.927968 -119.343424)
		(width 0.1651)
		(layer "F.Cu")
		(net "M_L_DQS_DP<8>")
	)
	(segment
		(start 74.907902 -117.36324)
		(end 74.57059 -117.700552)
		(width 0.1651)
		(layer "F.Cu")
		(net "M_L_DQS_DP<8>")
	)
	(segment
		(start 73.899522 -146.265646)
		(end 73.937368 -146.2278)
		(width 0.1651)
		(layer "F.Cu")
		(net "M_L_DQS_DP<8>")
	)
	(segment
		(start 84.342732 -103.543354)
		(end 83.654392 -104.231694)
		(width 0.1016)
		(layer "F.Cu")
		(net "M_L_DQS_DP<8>")
	)
	(segment
		(start 84.060792 -98.681286)
		(end 84.390738 -99.443286)
		(width 0.0889)
		(layer "F.Cu")
		(net "M_L_DQS_DP<8>")
	)
	(segment
		(start 73.937368 -144.8562)
		(end 73.693528 -144.61236)
		(width 0.1651)
		(layer "F.Cu")
		(net "M_L_DQS_DP<8>")
	)
	(segment
		(start 79.3496 -109.163866)
		(end 78.830678 -109.163866)
		(width 0.1016)
		(layer "F.Cu")
		(net "M_L_DQS_DP<8>")
	)
	(segment
		(start 83.654392 -104.859074)
		(end 79.3496 -109.163866)
		(width 0.1016)
		(layer "F.Cu")
		(net "M_L_DQS_DP<8>")
	)
	(segment
		(start 74.591926 -119.679466)
		(end 74.099674 -119.679466)
		(width 0.1651)
		(layer "F.Cu")
		(net "M_L_DQS_DP<8>")
	)
	(segment
		(start 78.653386 -109.341158)
		(end 74.907902 -113.086642)
		(width 0.1651)
		(layer "F.Cu")
		(net "M_L_DQS_DP<8>")
	)
	(via
		(at 73.437496 -144.61236)
		(size 0.508)
		(drill 0.254)
		(layers "F.Cu" "B.Cu")
		(net "M_L_DQS_DP<8>")
	)
	(via
		(at 73.437496 -140.541756)
		(size 0.508)
		(drill 0.254)
		(layers "F.Cu" "B.Cu")
		(net "M_L_DQS_DP<8>")
	)
	(via
		(at 73.437496 -125.969776)
		(size 0.508)
		(drill 0.254)
		(layers "F.Cu" "B.Cu")
		(net "M_L_DQS_DP<8>")
	)
	(arc
		(start 84.407248 -99.471734)
		(mid 84.432976 -99.533983)
		(end 84.441792 -99.600766)
		(width 0.0889)
		(layer "F.Cu")
		(net "M_L_DQS_DP<8>")
	)
	(segment
		(start 73.937368 -140.2842)
		(end 73.679812 -140.541756)
		(width 0.1651)
		(layer "B.Cu")
		(net "M_L_DQS_DP<8>")
	)
	(segment
		(start 73.937368 -139.065)
		(end 73.937368 -140.2842)
		(width 0.1651)
		(layer "B.Cu")
		(net "M_L_DQS_DP<8>")
	)
	(segment
		(start 73.679812 -140.541756)
		(end 73.437496 -140.541756)
		(width 0.1651)
		(layer "B.Cu")
		(net "M_L_DQS_DP<8>")
	)
	(segment
		(start 73.899522 -137.877296)
		(end 73.899522 -139.027154)
		(width 0.1651)
		(layer "B.Cu")
		(net "M_L_DQS_DP<8>")
	)
	(segment
		(start 73.899522 -139.027154)
		(end 73.937368 -139.065)
		(width 0.1651)
		(layer "B.Cu")
		(net "M_L_DQS_DP<8>")
	)
	(segment
		(start 73.618344 -141.6558)
		(end 73.872344 -141.4018)
		(width 0.14224)
		(layer "In9.Cu")
		(net "M_L_DQS_DP<8>")
	)
	(segment
		(start 73.260204 -142.899892)
		(end 73.440544 -142.719552)
		(width 0.14224)
		(layer "In9.Cu")
		(net "M_L_DQS_DP<8>")
	)
	(segment
		(start 73.897744 -144.152112)
		(end 73.897744 -143.7132)
		(width 0.14224)
		(layer "In9.Cu")
		(net "M_L_DQS_DP<8>")
	)
	(segment
		(start 73.440544 -142.4432)
		(end 73.262744 -142.2654)
		(width 0.14224)
		(layer "In9.Cu")
		(net "M_L_DQS_DP<8>")
	)
	(segment
		(start 73.440544 -142.719552)
		(end 73.440544 -142.4432)
		(width 0.14224)
		(layer "In9.Cu")
		(net "M_L_DQS_DP<8>")
	)
	(segment
		(start 73.062846 -143.263366)
		(end 73.062846 -143.037052)
		(width 0.14224)
		(layer "In9.Cu")
		(net "M_L_DQS_DP<8>")
	)
	(segment
		(start 73.200006 -142.899892)
		(end 73.260204 -142.899892)
		(width 0.14224)
		(layer "In9.Cu")
		(net "M_L_DQS_DP<8>")
	)
	(segment
		(start 73.897744 -143.7132)
		(end 73.643744 -143.4592)
		(width 0.14224)
		(layer "In9.Cu")
		(net "M_L_DQS_DP<8>")
	)
	(segment
		(start 73.062846 -142.150592)
		(end 73.062846 -141.826234)
		(width 0.14224)
		(layer "In9.Cu")
		(net "M_L_DQS_DP<8>")
	)
	(segment
		(start 73.872344 -140.976604)
		(end 73.437496 -140.541756)
		(width 0.14224)
		(layer "In9.Cu")
		(net "M_L_DQS_DP<8>")
	)
	(segment
		(start 73.437496 -144.61236)
		(end 73.897744 -144.152112)
		(width 0.14224)
		(layer "In9.Cu")
		(net "M_L_DQS_DP<8>")
	)
	(segment
		(start 73.062846 -141.826234)
		(end 73.23328 -141.6558)
		(width 0.14224)
		(layer "In9.Cu")
		(net "M_L_DQS_DP<8>")
	)
	(segment
		(start 73.25868 -143.4592)
		(end 73.062846 -143.263366)
		(width 0.14224)
		(layer "In9.Cu")
		(net "M_L_DQS_DP<8>")
	)
	(segment
		(start 73.872344 -141.4018)
		(end 73.872344 -140.976604)
		(width 0.14224)
		(layer "In9.Cu")
		(net "M_L_DQS_DP<8>")
	)
	(segment
		(start 73.262744 -142.2654)
		(end 73.177654 -142.2654)
		(width 0.14224)
		(layer "In9.Cu")
		(net "M_L_DQS_DP<8>")
	)
	(segment
		(start 73.643744 -143.4592)
		(end 73.25868 -143.4592)
		(width 0.14224)
		(layer "In9.Cu")
		(net "M_L_DQS_DP<8>")
	)
	(segment
		(start 73.062846 -143.037052)
		(end 73.200006 -142.899892)
		(width 0.14224)
		(layer "In9.Cu")
		(net "M_L_DQS_DP<8>")
	)
	(segment
		(start 73.23328 -141.6558)
		(end 73.618344 -141.6558)
		(width 0.14224)
		(layer "In9.Cu")
		(net "M_L_DQS_DP<8>")
	)
	(segment
		(start 73.177654 -142.2654)
		(end 73.062846 -142.150592)
		(width 0.14224)
		(layer "In9.Cu")
		(net "M_L_DQS_DP<8>")
	)
	(segment
		(start 73.437496 -125.969776)
		(end 73.886568 -126.418848)
		(width 0.14224)
		(layer "In11.Cu")
		(net "M_L_DQS_DP<8>")
	)
	(segment
		(start 73.708768 -132.804408)
		(end 73.708768 -133.35)
		(width 0.14224)
		(layer "In11.Cu")
		(net "M_L_DQS_DP<8>")
	)
	(segment
		(start 74.219816 -137.309352)
		(end 73.978008 -137.55116)
		(width 0.14224)
		(layer "In11.Cu")
		(net "M_L_DQS_DP<8>")
	)
	(segment
		(start 73.43775 -140.541756)
		(end 73.437496 -140.541756)
		(width 0.14224)
		(layer "In11.Cu")
		(net "M_L_DQS_DP<8>")
	)
	(segment
		(start 74.219816 -133.861048)
		(end 74.219816 -137.309352)
		(width 0.14224)
		(layer "In11.Cu")
		(net "M_L_DQS_DP<8>")
	)
	(segment
		(start 73.708768 -133.35)
		(end 74.219816 -133.861048)
		(width 0.14224)
		(layer "In11.Cu")
		(net "M_L_DQS_DP<8>")
	)
	(segment
		(start 73.978008 -137.55116)
		(end 73.978008 -138.41984)
		(width 0.14224)
		(layer "In11.Cu")
		(net "M_L_DQS_DP<8>")
	)
	(segment
		(start 73.886568 -127.647446)
		(end 74.219816 -127.980694)
		(width 0.14224)
		(layer "In11.Cu")
		(net "M_L_DQS_DP<8>")
	)
	(segment
		(start 74.219816 -132.29336)
		(end 73.708768 -132.804408)
		(width 0.14224)
		(layer "In11.Cu")
		(net "M_L_DQS_DP<8>")
	)
	(segment
		(start 74.219816 -127.980694)
		(end 74.219816 -132.29336)
		(width 0.14224)
		(layer "In11.Cu")
		(net "M_L_DQS_DP<8>")
	)
	(segment
		(start 74.219816 -138.661648)
		(end 74.219816 -139.75969)
		(width 0.14224)
		(layer "In11.Cu")
		(net "M_L_DQS_DP<8>")
	)
	(segment
		(start 73.978008 -138.41984)
		(end 74.219816 -138.661648)
		(width 0.14224)
		(layer "In11.Cu")
		(net "M_L_DQS_DP<8>")
	)
	(segment
		(start 73.886568 -126.418848)
		(end 73.886568 -127.647446)
		(width 0.14224)
		(layer "In11.Cu")
		(net "M_L_DQS_DP<8>")
	)
	(segment
		(start 74.219816 -139.75969)
		(end 73.43775 -140.541756)
		(width 0.14224)
		(layer "In11.Cu")
		(net "M_L_DQS_DP<8>")
	)
	(segment
		(start 147.849336 -147.27174)
		(end 147.84959 -147.27174)
		(width 0.1651)
		(layer "F.Cu")
		(net "M_L_DQS_DP<7>")
	)
	(segment
		(start 147.84959 -147.27174)
		(end 147.84959 -146.265646)
		(width 0.1651)
		(layer "F.Cu")
		(net "M_L_DQS_DP<7>")
	)
	(segment
		(start 147.643596 -144.61236)
		(end 147.387564 -144.61236)
		(width 0.1651)
		(layer "F.Cu")
		(net "M_L_DQS_DP<7>")
	)
	(segment
		(start 147.887436 -144.8562)
		(end 147.643596 -144.61236)
		(width 0.1651)
		(layer "F.Cu")
		(net "M_L_DQS_DP<7>")
	)
	(segment
		(start 120.787668 -95.033084)
		(end 121.359168 -95.033084)
		(width 0.1651)
		(layer "F.Cu")
		(net "M_L_DQS_DP<7>")
	)
	(segment
		(start 147.84959 -146.265646)
		(end 147.887436 -146.2278)
		(width 0.1651)
		(layer "F.Cu")
		(net "M_L_DQS_DP<7>")
	)
	(segment
		(start 147.887436 -146.2278)
		(end 147.887436 -144.8562)
		(width 0.1651)
		(layer "F.Cu")
		(net "M_L_DQS_DP<7>")
	)
	(via
		(at 147.387564 -140.541756)
		(size 0.508)
		(drill 0.254)
		(layers "F.Cu" "B.Cu")
		(net "M_L_DQS_DP<7>")
	)
	(via
		(at 121.359168 -95.033084)
		(size 0.508)
		(drill 0.254)
		(layers "F.Cu" "B.Cu")
		(net "M_L_DQS_DP<7>")
	)
	(via
		(at 147.387564 -144.61236)
		(size 0.508)
		(drill 0.254)
		(layers "F.Cu" "B.Cu")
		(net "M_L_DQS_DP<7>")
	)
	(segment
		(start 147.84959 -139.027154)
		(end 147.887436 -139.065)
		(width 0.1651)
		(layer "B.Cu")
		(net "M_L_DQS_DP<7>")
	)
	(segment
		(start 147.62988 -140.541756)
		(end 147.387564 -140.541756)
		(width 0.1651)
		(layer "B.Cu")
		(net "M_L_DQS_DP<7>")
	)
	(segment
		(start 147.84959 -137.877296)
		(end 147.84959 -139.027154)
		(width 0.1651)
		(layer "B.Cu")
		(net "M_L_DQS_DP<7>")
	)
	(segment
		(start 147.887436 -140.2842)
		(end 147.62988 -140.541756)
		(width 0.1651)
		(layer "B.Cu")
		(net "M_L_DQS_DP<7>")
	)
	(segment
		(start 147.849336 -137.877296)
		(end 147.84959 -137.877296)
		(width 0.1651)
		(layer "B.Cu")
		(net "M_L_DQS_DP<7>")
	)
	(segment
		(start 147.887436 -139.065)
		(end 147.887436 -140.2842)
		(width 0.1651)
		(layer "B.Cu")
		(net "M_L_DQS_DP<7>")
	)
	(segment
		(start 146.13382 -122.3772)
		(end 146.541236 -122.784616)
		(width 0.14224)
		(layer "In4.Cu")
		(net "M_L_DQS_DP<7>")
	)
	(segment
		(start 124.782072 -105.339388)
		(end 124.814838 -105.339388)
		(width 0.0889)
		(layer "In4.Cu")
		(net "M_L_DQS_DP<7>")
	)
	(segment
		(start 147.127722 -142.2654)
		(end 147.212812 -142.2654)
		(width 0.14224)
		(layer "In4.Cu")
		(net "M_L_DQS_DP<7>")
	)
	(segment
		(start 147.847812 -144.152112)
		(end 147.387564 -144.61236)
		(width 0.14224)
		(layer "In4.Cu")
		(net "M_L_DQS_DP<7>")
	)
	(segment
		(start 145.22196 -122.056144)
		(end 145.543016 -122.3772)
		(width 0.14224)
		(layer "In4.Cu")
		(net "M_L_DQS_DP<7>")
	)
	(segment
		(start 147.150074 -142.899892)
		(end 147.012914 -143.037052)
		(width 0.14224)
		(layer "In4.Cu")
		(net "M_L_DQS_DP<7>")
	)
	(segment
		(start 147.822412 -141.4018)
		(end 147.568412 -141.6558)
		(width 0.14224)
		(layer "In4.Cu")
		(net "M_L_DQS_DP<7>")
	)
	(segment
		(start 147.012914 -143.263366)
		(end 147.208748 -143.4592)
		(width 0.14224)
		(layer "In4.Cu")
		(net "M_L_DQS_DP<7>")
	)
	(segment
		(start 145.543016 -122.3772)
		(end 146.13382 -122.3772)
		(width 0.14224)
		(layer "In4.Cu")
		(net "M_L_DQS_DP<7>")
	)
	(segment
		(start 125.290834 -105.883964)
		(end 126.46787 -107.061)
		(width 0.0889)
		(layer "In4.Cu")
		(net "M_L_DQS_DP<7>")
	)
	(segment
		(start 146.361912 -123.408948)
		(end 146.361912 -123.627388)
		(width 0.14224)
		(layer "In4.Cu")
		(net "M_L_DQS_DP<7>")
	)
	(segment
		(start 146.541236 -122.784616)
		(end 146.541236 -123.229624)
		(width 0.14224)
		(layer "In4.Cu")
		(net "M_L_DQS_DP<7>")
	)
	(segment
		(start 142.790418 -120.288812)
		(end 144.042892 -120.288812)
		(width 0.14224)
		(layer "In4.Cu")
		(net "M_L_DQS_DP<7>")
	)
	(segment
		(start 121.877328 -101.261418)
		(end 121.870978 -101.272086)
		(width 0.0889)
		(layer "In4.Cu")
		(net "M_L_DQS_DP<7>")
	)
	(segment
		(start 122.202702 -101.872034)
		(end 122.235468 -101.872034)
		(width 0.0889)
		(layer "In4.Cu")
		(net "M_L_DQS_DP<7>")
	)
	(segment
		(start 147.010628 -123.699016)
		(end 147.453096 -123.699016)
		(width 0.14224)
		(layer "In4.Cu")
		(net "M_L_DQS_DP<7>")
	)
	(segment
		(start 121.870978 -100.281486)
		(end 121.866152 -100.290122)
		(width 0.0889)
		(layer "In4.Cu")
		(net "M_L_DQS_DP<7>")
	)
	(segment
		(start 126.46787 -107.061)
		(end 126.983998 -107.061)
		(width 0.0889)
		(layer "In4.Cu")
		(net "M_L_DQS_DP<7>")
	)
	(segment
		(start 123.919742 -104.843834)
		(end 123.952508 -104.843834)
		(width 0.0889)
		(layer "In4.Cu")
		(net "M_L_DQS_DP<7>")
	)
	(segment
		(start 121.877328 -99.280218)
		(end 121.870978 -99.290886)
		(width 0.0889)
		(layer "In4.Cu")
		(net "M_L_DQS_DP<7>")
	)
	(segment
		(start 145.22196 -121.46788)
		(end 145.22196 -122.056144)
		(width 0.14224)
		(layer "In4.Cu")
		(net "M_L_DQS_DP<7>")
	)
	(segment
		(start 123.065032 -104.348788)
		(end 123.097798 -104.348788)
		(width 0.0889)
		(layer "In4.Cu")
		(net "M_L_DQS_DP<7>")
	)
	(segment
		(start 129.523236 -107.02163)
		(end 142.790418 -120.288812)
		(width 0.14224)
		(layer "In4.Cu")
		(net "M_L_DQS_DP<7>")
	)
	(segment
		(start 147.390612 -142.4432)
		(end 147.390612 -142.719552)
		(width 0.14224)
		(layer "In4.Cu")
		(net "M_L_DQS_DP<7>")
	)
	(segment
		(start 122.724672 -103.1494)
		(end 122.729498 -103.158036)
		(width 0.0889)
		(layer "In4.Cu")
		(net "M_L_DQS_DP<7>")
	)
	(segment
		(start 146.361912 -123.627388)
		(end 146.612864 -123.87834)
		(width 0.14224)
		(layer "In4.Cu")
		(net "M_L_DQS_DP<7>")
	)
	(segment
		(start 146.541236 -123.229624)
		(end 146.361912 -123.408948)
		(width 0.14224)
		(layer "In4.Cu")
		(net "M_L_DQS_DP<7>")
	)
	(segment
		(start 148.169884 -124.415804)
		(end 148.169884 -139.759436)
		(width 0.14224)
		(layer "In4.Cu")
		(net "M_L_DQS_DP<7>")
	)
	(segment
		(start 147.208748 -143.4592)
		(end 147.593812 -143.4592)
		(width 0.14224)
		(layer "In4.Cu")
		(net "M_L_DQS_DP<7>")
	)
	(segment
		(start 121.870978 -98.300794)
		(end 121.870978 -98.30054)
		(width 0.0889)
		(layer "In4.Cu")
		(net "M_L_DQS_DP<7>")
	)
	(segment
		(start 147.390612 -142.719552)
		(end 147.210272 -142.899892)
		(width 0.14224)
		(layer "In4.Cu")
		(net "M_L_DQS_DP<7>")
	)
	(segment
		(start 121.877328 -100.270818)
		(end 121.870978 -100.281486)
		(width 0.0889)
		(layer "In4.Cu")
		(net "M_L_DQS_DP<7>")
	)
	(segment
		(start 147.012914 -142.150592)
		(end 147.127722 -142.2654)
		(width 0.14224)
		(layer "In4.Cu")
		(net "M_L_DQS_DP<7>")
	)
	(segment
		(start 147.568412 -141.6558)
		(end 147.183348 -141.6558)
		(width 0.14224)
		(layer "In4.Cu")
		(net "M_L_DQS_DP<7>")
	)
	(segment
		(start 147.012914 -141.826234)
		(end 147.012914 -142.150592)
		(width 0.14224)
		(layer "In4.Cu")
		(net "M_L_DQS_DP<7>")
	)
	(segment
		(start 125.290834 -105.611168)
		(end 125.290834 -105.883964)
		(width 0.0889)
		(layer "In4.Cu")
		(net "M_L_DQS_DP<7>")
	)
	(segment
		(start 147.012914 -143.037052)
		(end 147.012914 -143.263366)
		(width 0.14224)
		(layer "In4.Cu")
		(net "M_L_DQS_DP<7>")
	)
	(segment
		(start 127.023368 -107.02163)
		(end 127.045466 -107.02163)
		(width 0.0889)
		(layer "In4.Cu")
		(net "M_L_DQS_DP<7>")
	)
	(segment
		(start 147.847812 -143.7132)
		(end 147.847812 -144.152112)
		(width 0.14224)
		(layer "In4.Cu")
		(net "M_L_DQS_DP<7>")
	)
	(segment
		(start 146.612864 -123.87834)
		(end 146.831304 -123.87834)
		(width 0.14224)
		(layer "In4.Cu")
		(net "M_L_DQS_DP<7>")
	)
	(segment
		(start 147.183348 -141.6558)
		(end 147.012914 -141.826234)
		(width 0.14224)
		(layer "In4.Cu")
		(net "M_L_DQS_DP<7>")
	)
	(segment
		(start 127.045466 -107.02163)
		(end 129.523236 -107.02163)
		(width 0.14224)
		(layer "In4.Cu")
		(net "M_L_DQS_DP<7>")
	)
	(segment
		(start 148.169884 -139.759436)
		(end 147.387564 -140.541756)
		(width 0.14224)
		(layer "In4.Cu")
		(net "M_L_DQS_DP<7>")
	)
	(segment
		(start 147.387564 -140.541756)
		(end 147.822412 -140.976604)
		(width 0.14224)
		(layer "In4.Cu")
		(net "M_L_DQS_DP<7>")
	)
	(segment
		(start 147.453096 -123.699016)
		(end 148.169884 -124.415804)
		(width 0.14224)
		(layer "In4.Cu")
		(net "M_L_DQS_DP<7>")
	)
	(segment
		(start 147.212812 -142.2654)
		(end 147.390612 -142.4432)
		(width 0.14224)
		(layer "In4.Cu")
		(net "M_L_DQS_DP<7>")
	)
	(segment
		(start 144.042892 -120.288812)
		(end 145.22196 -121.46788)
		(width 0.14224)
		(layer "In4.Cu")
		(net "M_L_DQS_DP<7>")
	)
	(segment
		(start 121.870978 -101.272086)
		(end 121.866152 -101.280722)
		(width 0.0889)
		(layer "In4.Cu")
		(net "M_L_DQS_DP<7>")
	)
	(segment
		(start 147.593812 -143.4592)
		(end 147.847812 -143.7132)
		(width 0.14224)
		(layer "In4.Cu")
		(net "M_L_DQS_DP<7>")
	)
	(segment
		(start 121.870978 -99.290886)
		(end 121.866152 -99.299522)
		(width 0.0889)
		(layer "In4.Cu")
		(net "M_L_DQS_DP<7>")
	)
	(segment
		(start 122.729498 -103.158036)
		(end 122.735848 -103.168704)
		(width 0.0889)
		(layer "In4.Cu")
		(net "M_L_DQS_DP<7>")
	)
	(segment
		(start 146.831304 -123.87834)
		(end 147.010628 -123.699016)
		(width 0.14224)
		(layer "In4.Cu")
		(net "M_L_DQS_DP<7>")
	)
	(segment
		(start 147.822412 -140.976604)
		(end 147.822412 -141.4018)
		(width 0.14224)
		(layer "In4.Cu")
		(net "M_L_DQS_DP<7>")
	)
	(segment
		(start 126.983998 -107.061)
		(end 127.023368 -107.02163)
		(width 0.0889)
		(layer "In4.Cu")
		(net "M_L_DQS_DP<7>")
	)
	(segment
		(start 147.210272 -142.899892)
		(end 147.150074 -142.899892)
		(width 0.14224)
		(layer "In4.Cu")
		(net "M_L_DQS_DP<7>")
	)
	(arc
		(start 124.814838 -105.339388)
		(mid 125.086255 -105.41675)
		(end 125.290834 -105.611168)
		(width 0.0889)
		(layer "In4.Cu")
		(net "M_L_DQS_DP<7>")
	)
	(arc
		(start 123.588018 -104.643936)
		(mid 123.728097 -104.786672)
		(end 123.919742 -104.843834)
		(width 0.0889)
		(layer "In4.Cu")
		(net "M_L_DQS_DP<7>")
	)
	(arc
		(start 121.870978 -97.310194)
		(mid 121.817479 -97.510092)
		(end 121.870978 -97.70999)
		(width 0.0889)
		(layer "In4.Cu")
		(net "M_L_DQS_DP<7>")
	)
	(arc
		(start 121.755916 -96.076008)
		(mid 121.763614 -96.406609)
		(end 121.870978 -96.71939)
		(width 0.0889)
		(layer "In4.Cu")
		(net "M_L_DQS_DP<7>")
	)
	(arc
		(start 121.870978 -99.690936)
		(mid 121.9502 -99.980054)
		(end 121.877328 -100.270818)
		(width 0.0889)
		(layer "In4.Cu")
		(net "M_L_DQS_DP<7>")
	)
	(arc
		(start 121.866152 -101.280722)
		(mid 121.869899 -101.669978)
		(end 122.202702 -101.872034)
		(width 0.0889)
		(layer "In4.Cu")
		(net "M_L_DQS_DP<7>")
	)
	(arc
		(start 124.446538 -105.139236)
		(mid 124.588221 -105.28304)
		(end 124.782072 -105.339388)
		(width 0.0889)
		(layer "In4.Cu")
		(net "M_L_DQS_DP<7>")
	)
	(arc
		(start 121.918222 -98.804476)
		(mid 121.947941 -99.046654)
		(end 121.877328 -99.280218)
		(width 0.0889)
		(layer "In4.Cu")
		(net "M_L_DQS_DP<7>")
	)
	(arc
		(start 121.870978 -98.700844)
		(mid 121.897129 -98.751507)
		(end 121.918222 -98.804476)
		(width 0.0889)
		(layer "In4.Cu")
		(net "M_L_DQS_DP<7>")
	)
	(arc
		(start 121.870978 -96.71939)
		(mid 121.950109 -97.014792)
		(end 121.870978 -97.310194)
		(width 0.0889)
		(layer "In4.Cu")
		(net "M_L_DQS_DP<7>")
	)
	(arc
		(start 123.097798 -104.348788)
		(mid 123.381015 -104.433069)
		(end 123.588018 -104.643936)
		(width 0.0889)
		(layer "In4.Cu")
		(net "M_L_DQS_DP<7>")
	)
	(arc
		(start 122.235468 -101.872034)
		(mid 122.733719 -102.174874)
		(end 122.729498 -102.757986)
		(width 0.0889)
		(layer "In4.Cu")
		(net "M_L_DQS_DP<7>")
	)
	(arc
		(start 121.866152 -100.290122)
		(mid 121.817397 -100.486474)
		(end 121.870978 -100.681536)
		(width 0.0889)
		(layer "In4.Cu")
		(net "M_L_DQS_DP<7>")
	)
	(arc
		(start 121.870978 -100.681536)
		(mid 121.9502 -100.970654)
		(end 121.877328 -101.261418)
		(width 0.0889)
		(layer "In4.Cu")
		(net "M_L_DQS_DP<7>")
	)
	(arc
		(start 122.735848 -103.168704)
		(mid 122.808646 -103.459467)
		(end 122.729498 -103.748586)
		(width 0.0889)
		(layer "In4.Cu")
		(net "M_L_DQS_DP<7>")
	)
	(arc
		(start 123.952508 -104.843834)
		(mid 124.237932 -104.927301)
		(end 124.446538 -105.139236)
		(width 0.0889)
		(layer "In4.Cu")
		(net "M_L_DQS_DP<7>")
	)
	(arc
		(start 121.870978 -97.70999)
		(mid 121.950109 -98.005392)
		(end 121.870978 -98.300794)
		(width 0.0889)
		(layer "In4.Cu")
		(net "M_L_DQS_DP<7>")
	)
	(arc
		(start 121.870978 -98.30054)
		(mid 121.817352 -98.500692)
		(end 121.870978 -98.700844)
		(width 0.0889)
		(layer "In4.Cu")
		(net "M_L_DQS_DP<7>")
	)
	(arc
		(start 122.729498 -102.757986)
		(mid 122.676028 -102.953049)
		(end 122.724672 -103.1494)
		(width 0.0889)
		(layer "In4.Cu")
		(net "M_L_DQS_DP<7>")
	)
	(arc
		(start 121.359168 -95.033084)
		(mid 121.510852 -95.438185)
		(end 121.705878 -95.824294)
		(width 0.0889)
		(layer "In4.Cu")
		(net "M_L_DQS_DP<7>")
	)
	(arc
		(start 121.866152 -99.299522)
		(mid 121.817397 -99.495874)
		(end 121.870978 -99.690936)
		(width 0.0889)
		(layer "In4.Cu")
		(net "M_L_DQS_DP<7>")
	)
	(arc
		(start 121.705878 -95.824294)
		(mid 121.751591 -95.946031)
		(end 121.755916 -96.076008)
		(width 0.0889)
		(layer "In4.Cu")
		(net "M_L_DQS_DP<7>")
	)
	(arc
		(start 122.729498 -103.748586)
		(mid 122.72675 -104.144053)
		(end 123.065032 -104.348788)
		(width 0.0889)
		(layer "In4.Cu")
		(net "M_L_DQS_DP<7>")
	)
	(segment
		(start 138.865864 -123.526296)
		(end 138.510264 -123.170696)
		(width 0.1651)
		(layer "F.Cu")
		(net "M_L_DQS_DP<6>")
	)
	(segment
		(start 138.293602 -144.61236)
		(end 138.03757 -144.61236)
		(width 0.1651)
		(layer "F.Cu")
		(net "M_L_DQS_DP<6>")
	)
	(segment
		(start 120.978168 -104.5718)
		(end 120.978168 -103.450136)
		(width 0.0889)
		(layer "F.Cu")
		(net "M_L_DQS_DP<6>")
	)
	(segment
		(start 121.282968 -104.8766)
		(end 120.978168 -104.5718)
		(width 0.0889)
		(layer "F.Cu")
		(net "M_L_DQS_DP<6>")
	)
	(segment
		(start 138.624564 -121.3993)
		(end 138.521948 -121.296684)
		(width 0.1651)
		(layer "F.Cu")
		(net "M_L_DQS_DP<6>")
	)
	(segment
		(start 138.675364 -122.6566)
		(end 138.972798 -122.6566)
		(width 0.1651)
		(layer "F.Cu")
		(net "M_L_DQS_DP<6>")
	)
	(segment
		(start 121.117614 -102.729538)
		(end 120.787668 -101.967538)
		(width 0.0889)
		(layer "F.Cu")
		(net "M_L_DQS_DP<6>")
	)
	(segment
		(start 138.510264 -122.8217)
		(end 138.675364 -122.6566)
		(width 0.1651)
		(layer "F.Cu")
		(net "M_L_DQS_DP<6>")
	)
	(segment
		(start 138.03757 -126.029974)
		(end 138.865864 -125.20168)
		(width 0.1651)
		(layer "F.Cu")
		(net "M_L_DQS_DP<6>")
	)
	(segment
		(start 122.39498 -105.867454)
		(end 121.404126 -104.8766)
		(width 0.1016)
		(layer "F.Cu")
		(net "M_L_DQS_DP<6>")
	)
	(segment
		(start 120.978168 -103.450136)
		(end 121.131076 -103.193342)
		(width 0.0889)
		(layer "F.Cu")
		(net "M_L_DQS_DP<6>")
	)
	(segment
		(start 138.537442 -146.2278)
		(end 138.537442 -144.8562)
		(width 0.1651)
		(layer "F.Cu")
		(net "M_L_DQS_DP<6>")
	)
	(segment
		(start 121.134124 -102.757986)
		(end 121.117614 -102.729538)
		(width 0.0889)
		(layer "F.Cu")
		(net "M_L_DQS_DP<6>")
	)
	(segment
		(start 138.521948 -113.540794)
		(end 134.719568 -109.738414)
		(width 0.1651)
		(layer "F.Cu")
		(net "M_L_DQS_DP<6>")
	)
	(segment
		(start 138.510264 -123.170696)
		(end 138.510264 -122.8217)
		(width 0.1651)
		(layer "F.Cu")
		(net "M_L_DQS_DP<6>")
	)
	(segment
		(start 138.499596 -146.265646)
		(end 138.537442 -146.2278)
		(width 0.1651)
		(layer "F.Cu")
		(net "M_L_DQS_DP<6>")
	)
	(segment
		(start 139.27074 -122.358658)
		(end 139.27074 -121.697242)
		(width 0.1651)
		(layer "F.Cu")
		(net "M_L_DQS_DP<6>")
	)
	(segment
		(start 134.362698 -109.32033)
		(end 134.162038 -109.32033)
		(width 0.1016)
		(layer "F.Cu")
		(net "M_L_DQS_DP<6>")
	)
	(segment
		(start 138.521948 -121.296684)
		(end 138.521948 -113.540794)
		(width 0.1651)
		(layer "F.Cu")
		(net "M_L_DQS_DP<6>")
	)
	(segment
		(start 134.162038 -109.32033)
		(end 130.709162 -105.867454)
		(width 0.1016)
		(layer "F.Cu")
		(net "M_L_DQS_DP<6>")
	)
	(segment
		(start 138.499596 -147.27174)
		(end 138.499596 -146.265646)
		(width 0.1651)
		(layer "F.Cu")
		(net "M_L_DQS_DP<6>")
	)
	(segment
		(start 139.27074 -121.697242)
		(end 138.972798 -121.3993)
		(width 0.1651)
		(layer "F.Cu")
		(net "M_L_DQS_DP<6>")
	)
	(segment
		(start 130.709162 -105.867454)
		(end 122.39498 -105.867454)
		(width 0.1016)
		(layer "F.Cu")
		(net "M_L_DQS_DP<6>")
	)
	(segment
		(start 138.972798 -121.3993)
		(end 138.624564 -121.3993)
		(width 0.1651)
		(layer "F.Cu")
		(net "M_L_DQS_DP<6>")
	)
	(segment
		(start 138.537442 -144.8562)
		(end 138.293602 -144.61236)
		(width 0.1651)
		(layer "F.Cu")
		(net "M_L_DQS_DP<6>")
	)
	(segment
		(start 138.499342 -147.27174)
		(end 138.499596 -147.27174)
		(width 0.1651)
		(layer "F.Cu")
		(net "M_L_DQS_DP<6>")
	)
	(segment
		(start 138.03757 -126.037086)
		(end 138.03757 -126.029974)
		(width 0.1651)
		(layer "F.Cu")
		(net "M_L_DQS_DP<6>")
	)
	(segment
		(start 138.972798 -122.6566)
		(end 139.27074 -122.358658)
		(width 0.1651)
		(layer "F.Cu")
		(net "M_L_DQS_DP<6>")
	)
	(segment
		(start 121.404126 -104.8766)
		(end 121.282968 -104.8766)
		(width 0.1016)
		(layer "F.Cu")
		(net "M_L_DQS_DP<6>")
	)
	(segment
		(start 138.865864 -125.20168)
		(end 138.865864 -123.526296)
		(width 0.1651)
		(layer "F.Cu")
		(net "M_L_DQS_DP<6>")
	)
	(segment
		(start 134.719568 -109.6772)
		(end 134.362698 -109.32033)
		(width 0.1016)
		(layer "F.Cu")
		(net "M_L_DQS_DP<6>")
	)
	(segment
		(start 134.719568 -109.738414)
		(end 134.719568 -109.6772)
		(width 0.1016)
		(layer "F.Cu")
		(net "M_L_DQS_DP<6>")
	)
	(via
		(at 138.03757 -140.541756)
		(size 0.508)
		(drill 0.254)
		(layers "F.Cu" "B.Cu")
		(net "M_L_DQS_DP<6>")
	)
	(via
		(at 138.03757 -144.61236)
		(size 0.508)
		(drill 0.254)
		(layers "F.Cu" "B.Cu")
		(net "M_L_DQS_DP<6>")
	)
	(via
		(at 138.03757 -126.037086)
		(size 0.508)
		(drill 0.254)
		(layers "F.Cu" "B.Cu")
		(net "M_L_DQS_DP<6>")
	)
	(arc
		(start 121.131076 -103.193342)
		(mid 121.191667 -102.976086)
		(end 121.134124 -102.757986)
		(width 0.0889)
		(layer "F.Cu")
		(net "M_L_DQS_DP<6>")
	)
	(segment
		(start 138.537442 -140.2842)
		(end 138.279886 -140.541756)
		(width 0.1651)
		(layer "B.Cu")
		(net "M_L_DQS_DP<6>")
	)
	(segment
		(start 138.499596 -139.027154)
		(end 138.537442 -139.065)
		(width 0.1651)
		(layer "B.Cu")
		(net "M_L_DQS_DP<6>")
	)
	(segment
		(start 138.499342 -137.877296)
		(end 138.499596 -137.877296)
		(width 0.1651)
		(layer "B.Cu")
		(net "M_L_DQS_DP<6>")
	)
	(segment
		(start 138.279886 -140.541756)
		(end 138.03757 -140.541756)
		(width 0.1651)
		(layer "B.Cu")
		(net "M_L_DQS_DP<6>")
	)
	(segment
		(start 138.499596 -137.877296)
		(end 138.499596 -139.027154)
		(width 0.1651)
		(layer "B.Cu")
		(net "M_L_DQS_DP<6>")
	)
	(segment
		(start 138.537442 -139.065)
		(end 138.537442 -140.2842)
		(width 0.1651)
		(layer "B.Cu")
		(net "M_L_DQS_DP<6>")
	)
	(segment
		(start 138.478768 -126.478284)
		(end 138.478768 -127.4064)
		(width 0.14224)
		(layer "In4.Cu")
		(net "M_L_DQS_DP<6>")
	)
	(segment
		(start 138.03757 -126.037086)
		(end 138.478768 -126.478284)
		(width 0.14224)
		(layer "In4.Cu")
		(net "M_L_DQS_DP<6>")
	)
	(segment
		(start 138.473434 -133.253734)
		(end 138.81989 -133.60019)
		(width 0.14224)
		(layer "In4.Cu")
		(net "M_L_DQS_DP<6>")
	)
	(segment
		(start 138.81989 -136.96442)
		(end 138.421872 -137.362438)
		(width 0.14224)
		(layer "In4.Cu")
		(net "M_L_DQS_DP<6>")
	)
	(segment
		(start 138.81989 -132.06095)
		(end 138.473434 -132.407406)
		(width 0.14224)
		(layer "In4.Cu")
		(net "M_L_DQS_DP<6>")
	)
	(segment
		(start 138.473434 -132.407406)
		(end 138.473434 -133.253734)
		(width 0.14224)
		(layer "In4.Cu")
		(net "M_L_DQS_DP<6>")
	)
	(segment
		(start 138.478768 -127.4064)
		(end 138.81989 -127.747522)
		(width 0.14224)
		(layer "In4.Cu")
		(net "M_L_DQS_DP<6>")
	)
	(segment
		(start 138.421872 -138.0236)
		(end 138.81989 -138.421618)
		(width 0.14224)
		(layer "In4.Cu")
		(net "M_L_DQS_DP<6>")
	)
	(segment
		(start 138.421872 -137.362438)
		(end 138.421872 -138.0236)
		(width 0.14224)
		(layer "In4.Cu")
		(net "M_L_DQS_DP<6>")
	)
	(segment
		(start 138.81989 -127.747522)
		(end 138.81989 -132.06095)
		(width 0.14224)
		(layer "In4.Cu")
		(net "M_L_DQS_DP<6>")
	)
	(segment
		(start 138.81989 -133.60019)
		(end 138.81989 -136.96442)
		(width 0.14224)
		(layer "In4.Cu")
		(net "M_L_DQS_DP<6>")
	)
	(segment
		(start 138.81989 -139.759436)
		(end 138.03757 -140.541756)
		(width 0.14224)
		(layer "In4.Cu")
		(net "M_L_DQS_DP<6>")
	)
	(segment
		(start 138.81989 -138.421618)
		(end 138.81989 -139.759436)
		(width 0.14224)
		(layer "In4.Cu")
		(net "M_L_DQS_DP<6>")
	)
	(segment
		(start 137.860278 -142.899892)
		(end 138.040618 -142.719552)
		(width 0.14224)
		(layer "In9.Cu")
		(net "M_L_DQS_DP<6>")
	)
	(segment
		(start 138.497818 -144.152112)
		(end 138.497818 -143.7132)
		(width 0.14224)
		(layer "In9.Cu")
		(net "M_L_DQS_DP<6>")
	)
	(segment
		(start 138.03757 -144.61236)
		(end 138.497818 -144.152112)
		(width 0.14224)
		(layer "In9.Cu")
		(net "M_L_DQS_DP<6>")
	)
	(segment
		(start 137.66292 -142.150592)
		(end 137.66292 -141.826234)
		(width 0.14224)
		(layer "In9.Cu")
		(net "M_L_DQS_DP<6>")
	)
	(segment
		(start 137.66292 -143.037052)
		(end 137.80008 -142.899892)
		(width 0.14224)
		(layer "In9.Cu")
		(net "M_L_DQS_DP<6>")
	)
	(segment
		(start 137.862818 -142.2654)
		(end 137.777728 -142.2654)
		(width 0.14224)
		(layer "In9.Cu")
		(net "M_L_DQS_DP<6>")
	)
	(segment
		(start 138.040618 -142.4432)
		(end 137.862818 -142.2654)
		(width 0.14224)
		(layer "In9.Cu")
		(net "M_L_DQS_DP<6>")
	)
	(segment
		(start 137.80008 -142.899892)
		(end 137.860278 -142.899892)
		(width 0.14224)
		(layer "In9.Cu")
		(net "M_L_DQS_DP<6>")
	)
	(segment
		(start 138.472418 -141.4018)
		(end 138.472418 -140.976604)
		(width 0.14224)
		(layer "In9.Cu")
		(net "M_L_DQS_DP<6>")
	)
	(segment
		(start 138.040618 -142.719552)
		(end 138.040618 -142.4432)
		(width 0.14224)
		(layer "In9.Cu")
		(net "M_L_DQS_DP<6>")
	)
	(segment
		(start 137.66292 -143.263366)
		(end 137.66292 -143.037052)
		(width 0.14224)
		(layer "In9.Cu")
		(net "M_L_DQS_DP<6>")
	)
	(segment
		(start 138.472418 -140.976604)
		(end 138.03757 -140.541756)
		(width 0.14224)
		(layer "In9.Cu")
		(net "M_L_DQS_DP<6>")
	)
	(segment
		(start 137.777728 -142.2654)
		(end 137.66292 -142.150592)
		(width 0.14224)
		(layer "In9.Cu")
		(net "M_L_DQS_DP<6>")
	)
	(segment
		(start 138.218418 -141.6558)
		(end 138.472418 -141.4018)
		(width 0.14224)
		(layer "In9.Cu")
		(net "M_L_DQS_DP<6>")
	)
	(segment
		(start 138.243818 -143.4592)
		(end 137.858754 -143.4592)
		(width 0.14224)
		(layer "In9.Cu")
		(net "M_L_DQS_DP<6>")
	)
	(segment
		(start 138.497818 -143.7132)
		(end 138.243818 -143.4592)
		(width 0.14224)
		(layer "In9.Cu")
		(net "M_L_DQS_DP<6>")
	)
	(segment
		(start 137.858754 -143.4592)
		(end 137.66292 -143.263366)
		(width 0.14224)
		(layer "In9.Cu")
		(net "M_L_DQS_DP<6>")
	)
	(segment
		(start 137.66292 -141.826234)
		(end 137.833354 -141.6558)
		(width 0.14224)
		(layer "In9.Cu")
		(net "M_L_DQS_DP<6>")
	)
	(segment
		(start 137.833354 -141.6558)
		(end 138.218418 -141.6558)
		(width 0.14224)
		(layer "In9.Cu")
		(net "M_L_DQS_DP<6>")
	)
	(segment
		(start 120.279414 -112.8649)
		(end 120.673368 -112.8649)
		(width 0.1016)
		(layer "F.Cu")
		(net "M_L_DQS_DP<5>")
	)
	(segment
		(start 126.515368 -117.9068)
		(end 129.10439 -120.495822)
		(width 0.1651)
		(layer "F.Cu")
		(net "M_L_DQS_DP<5>")
	)
	(segment
		(start 130.033268 -122.410728)
		(end 130.033268 -123.224544)
		(width 0.1651)
		(layer "F.Cu")
		(net "M_L_DQS_DP<5>")
	)
	(segment
		(start 129.480564 -125.23343)
		(end 128.687576 -126.026418)
		(width 0.1651)
		(layer "F.Cu")
		(net "M_L_DQS_DP<5>")
	)
	(segment
		(start 128.943608 -144.61236)
		(end 128.687576 -144.61236)
		(width 0.1651)
		(layer "F.Cu")
		(net "M_L_DQS_DP<5>")
	)
	(segment
		(start 115.827302 -103.90124)
		(end 115.956588 -104.030526)
		(width 0.0889)
		(layer "F.Cu")
		(net "M_L_DQS_DP<5>")
	)
	(segment
		(start 115.941348 -103.268018)
		(end 115.827302 -103.382064)
		(width 0.0889)
		(layer "F.Cu")
		(net "M_L_DQS_DP<5>")
	)
	(segment
		(start 115.966748 -102.729538)
		(end 115.983258 -102.757986)
		(width 0.0889)
		(layer "F.Cu")
		(net "M_L_DQS_DP<5>")
	)
	(segment
		(start 116.058188 -108.643674)
		(end 120.279414 -112.8649)
		(width 0.1016)
		(layer "F.Cu")
		(net "M_L_DQS_DP<5>")
	)
	(segment
		(start 129.156968 -123.9774)
		(end 129.480564 -124.300996)
		(width 0.1651)
		(layer "F.Cu")
		(net "M_L_DQS_DP<5>")
	)
	(segment
		(start 129.10439 -120.495822)
		(end 129.10439 -121.91492)
		(width 0.1651)
		(layer "F.Cu")
		(net "M_L_DQS_DP<5>")
	)
	(segment
		(start 121.155968 -113.411)
		(end 125.651768 -117.9068)
		(width 0.1651)
		(layer "F.Cu")
		(net "M_L_DQS_DP<5>")
	)
	(segment
		(start 115.827302 -103.382064)
		(end 115.827302 -103.90124)
		(width 0.0889)
		(layer "F.Cu")
		(net "M_L_DQS_DP<5>")
	)
	(segment
		(start 129.480564 -124.300996)
		(end 129.480564 -125.23343)
		(width 0.1651)
		(layer "F.Cu")
		(net "M_L_DQS_DP<5>")
	)
	(segment
		(start 129.156968 -123.66879)
		(end 129.156968 -123.9774)
		(width 0.1651)
		(layer "F.Cu")
		(net "M_L_DQS_DP<5>")
	)
	(segment
		(start 129.149602 -146.265646)
		(end 129.187448 -146.2278)
		(width 0.1651)
		(layer "F.Cu")
		(net "M_L_DQS_DP<5>")
	)
	(segment
		(start 129.735326 -123.522486)
		(end 129.303272 -123.522486)
		(width 0.1651)
		(layer "F.Cu")
		(net "M_L_DQS_DP<5>")
	)
	(segment
		(start 115.956588 -104.030526)
		(end 115.956588 -105.802938)
		(width 0.0889)
		(layer "F.Cu")
		(net "M_L_DQS_DP<5>")
	)
	(segment
		(start 121.155968 -113.3475)
		(end 121.155968 -113.411)
		(width 0.1016)
		(layer "F.Cu")
		(net "M_L_DQS_DP<5>")
	)
	(segment
		(start 129.735326 -122.112786)
		(end 130.033268 -122.410728)
		(width 0.1651)
		(layer "F.Cu")
		(net "M_L_DQS_DP<5>")
	)
	(segment
		(start 129.302256 -122.112786)
		(end 129.735326 -122.112786)
		(width 0.1651)
		(layer "F.Cu")
		(net "M_L_DQS_DP<5>")
	)
	(segment
		(start 116.058188 -105.904538)
		(end 116.058188 -108.643674)
		(width 0.1016)
		(layer "F.Cu")
		(net "M_L_DQS_DP<5>")
	)
	(segment
		(start 129.187448 -146.2278)
		(end 129.187448 -144.8562)
		(width 0.1651)
		(layer "F.Cu")
		(net "M_L_DQS_DP<5>")
	)
	(segment
		(start 115.98021 -103.202486)
		(end 115.941348 -103.268018)
		(width 0.0889)
		(layer "F.Cu")
		(net "M_L_DQS_DP<5>")
	)
	(segment
		(start 129.10439 -121.91492)
		(end 129.302256 -122.112786)
		(width 0.1651)
		(layer "F.Cu")
		(net "M_L_DQS_DP<5>")
	)
	(segment
		(start 129.187448 -144.8562)
		(end 128.943608 -144.61236)
		(width 0.1651)
		(layer "F.Cu")
		(net "M_L_DQS_DP<5>")
	)
	(segment
		(start 129.149602 -147.27174)
		(end 129.149602 -146.265646)
		(width 0.1651)
		(layer "F.Cu")
		(net "M_L_DQS_DP<5>")
	)
	(segment
		(start 115.956588 -105.802938)
		(end 116.058188 -105.904538)
		(width 0.0889)
		(layer "F.Cu")
		(net "M_L_DQS_DP<5>")
	)
	(segment
		(start 115.636802 -101.967538)
		(end 115.966748 -102.729538)
		(width 0.0889)
		(layer "F.Cu")
		(net "M_L_DQS_DP<5>")
	)
	(segment
		(start 125.651768 -117.9068)
		(end 126.515368 -117.9068)
		(width 0.1651)
		(layer "F.Cu")
		(net "M_L_DQS_DP<5>")
	)
	(segment
		(start 120.673368 -112.8649)
		(end 121.155968 -113.3475)
		(width 0.1016)
		(layer "F.Cu")
		(net "M_L_DQS_DP<5>")
	)
	(segment
		(start 129.149348 -147.27174)
		(end 129.149602 -147.27174)
		(width 0.1651)
		(layer "F.Cu")
		(net "M_L_DQS_DP<5>")
	)
	(segment
		(start 129.303272 -123.522486)
		(end 129.156968 -123.66879)
		(width 0.1651)
		(layer "F.Cu")
		(net "M_L_DQS_DP<5>")
	)
	(segment
		(start 130.033268 -123.224544)
		(end 129.735326 -123.522486)
		(width 0.1651)
		(layer "F.Cu")
		(net "M_L_DQS_DP<5>")
	)
	(via
		(at 128.687576 -140.541756)
		(size 0.508)
		(drill 0.254)
		(layers "F.Cu" "B.Cu")
		(net "M_L_DQS_DP<5>")
	)
	(via
		(at 128.687576 -126.026418)
		(size 0.508)
		(drill 0.254)
		(layers "F.Cu" "B.Cu")
		(net "M_L_DQS_DP<5>")
	)
	(via
		(at 128.687576 -144.61236)
		(size 0.508)
		(drill 0.254)
		(layers "F.Cu" "B.Cu")
		(net "M_L_DQS_DP<5>")
	)
	(arc
		(start 115.983258 -102.757986)
		(mid 116.042059 -102.980658)
		(end 115.98021 -103.202486)
		(width 0.0889)
		(layer "F.Cu")
		(net "M_L_DQS_DP<5>")
	)
	(segment
		(start 128.929892 -140.541756)
		(end 128.687576 -140.541756)
		(width 0.1651)
		(layer "B.Cu")
		(net "M_L_DQS_DP<5>")
	)
	(segment
		(start 129.187448 -139.065)
		(end 129.187448 -140.2842)
		(width 0.1651)
		(layer "B.Cu")
		(net "M_L_DQS_DP<5>")
	)
	(segment
		(start 129.149602 -139.027154)
		(end 129.187448 -139.065)
		(width 0.1651)
		(layer "B.Cu")
		(net "M_L_DQS_DP<5>")
	)
	(segment
		(start 129.149602 -137.877296)
		(end 129.149602 -139.027154)
		(width 0.1651)
		(layer "B.Cu")
		(net "M_L_DQS_DP<5>")
	)
	(segment
		(start 129.149348 -137.877296)
		(end 129.149602 -137.877296)
		(width 0.1651)
		(layer "B.Cu")
		(net "M_L_DQS_DP<5>")
	)
	(segment
		(start 129.187448 -140.2842)
		(end 128.929892 -140.541756)
		(width 0.1651)
		(layer "B.Cu")
		(net "M_L_DQS_DP<5>")
	)
	(segment
		(start 128.312926 -143.037052)
		(end 128.312926 -143.263366)
		(width 0.14224)
		(layer "In9.Cu")
		(net "M_L_DQS_DP<5>")
	)
	(segment
		(start 128.690624 -142.719552)
		(end 128.510284 -142.899892)
		(width 0.14224)
		(layer "In9.Cu")
		(net "M_L_DQS_DP<5>")
	)
	(segment
		(start 129.147824 -143.7132)
		(end 129.147824 -144.152112)
		(width 0.14224)
		(layer "In9.Cu")
		(net "M_L_DQS_DP<5>")
	)
	(segment
		(start 128.690624 -142.4432)
		(end 128.690624 -142.719552)
		(width 0.14224)
		(layer "In9.Cu")
		(net "M_L_DQS_DP<5>")
	)
	(segment
		(start 129.147824 -144.152112)
		(end 128.687576 -144.61236)
		(width 0.14224)
		(layer "In9.Cu")
		(net "M_L_DQS_DP<5>")
	)
	(segment
		(start 128.48336 -141.6558)
		(end 128.312926 -141.826234)
		(width 0.14224)
		(layer "In9.Cu")
		(net "M_L_DQS_DP<5>")
	)
	(segment
		(start 128.427734 -142.2654)
		(end 128.512824 -142.2654)
		(width 0.14224)
		(layer "In9.Cu")
		(net "M_L_DQS_DP<5>")
	)
	(segment
		(start 128.450086 -142.899892)
		(end 128.312926 -143.037052)
		(width 0.14224)
		(layer "In9.Cu")
		(net "M_L_DQS_DP<5>")
	)
	(segment
		(start 128.687576 -140.541756)
		(end 128.687576 -140.54201)
		(width 0.14224)
		(layer "In9.Cu")
		(net "M_L_DQS_DP<5>")
	)
	(segment
		(start 128.512824 -142.2654)
		(end 128.690624 -142.4432)
		(width 0.14224)
		(layer "In9.Cu")
		(net "M_L_DQS_DP<5>")
	)
	(segment
		(start 128.868424 -141.6558)
		(end 128.48336 -141.6558)
		(width 0.14224)
		(layer "In9.Cu")
		(net "M_L_DQS_DP<5>")
	)
	(segment
		(start 128.50876 -143.4592)
		(end 128.893824 -143.4592)
		(width 0.14224)
		(layer "In9.Cu")
		(net "M_L_DQS_DP<5>")
	)
	(segment
		(start 128.312926 -141.826234)
		(end 128.312926 -142.150592)
		(width 0.14224)
		(layer "In9.Cu")
		(net "M_L_DQS_DP<5>")
	)
	(segment
		(start 129.122424 -141.4018)
		(end 128.868424 -141.6558)
		(width 0.14224)
		(layer "In9.Cu")
		(net "M_L_DQS_DP<5>")
	)
	(segment
		(start 128.312926 -142.150592)
		(end 128.427734 -142.2654)
		(width 0.14224)
		(layer "In9.Cu")
		(net "M_L_DQS_DP<5>")
	)
	(segment
		(start 128.893824 -143.4592)
		(end 129.147824 -143.7132)
		(width 0.14224)
		(layer "In9.Cu")
		(net "M_L_DQS_DP<5>")
	)
	(segment
		(start 129.122424 -140.976858)
		(end 129.122424 -141.4018)
		(width 0.14224)
		(layer "In9.Cu")
		(net "M_L_DQS_DP<5>")
	)
	(segment
		(start 128.312926 -143.263366)
		(end 128.50876 -143.4592)
		(width 0.14224)
		(layer "In9.Cu")
		(net "M_L_DQS_DP<5>")
	)
	(segment
		(start 128.510284 -142.899892)
		(end 128.450086 -142.899892)
		(width 0.14224)
		(layer "In9.Cu")
		(net "M_L_DQS_DP<5>")
	)
	(segment
		(start 128.687576 -140.54201)
		(end 129.122424 -140.976858)
		(width 0.14224)
		(layer "In9.Cu")
		(net "M_L_DQS_DP<5>")
	)
	(segment
		(start 128.902968 -127.1016)
		(end 129.131568 -126.873)
		(width 0.14224)
		(layer "In11.Cu")
		(net "M_L_DQS_DP<5>")
	)
	(segment
		(start 129.131568 -126.47041)
		(end 128.687576 -126.026418)
		(width 0.14224)
		(layer "In11.Cu")
		(net "M_L_DQS_DP<5>")
	)
	(segment
		(start 129.469896 -139.666472)
		(end 129.469896 -128.176782)
		(width 0.14224)
		(layer "In11.Cu")
		(net "M_L_DQS_DP<5>")
	)
	(segment
		(start 129.131568 -140.0048)
		(end 129.469896 -139.666472)
		(width 0.14224)
		(layer "In11.Cu")
		(net "M_L_DQS_DP<5>")
	)
	(segment
		(start 129.131568 -140.097764)
		(end 129.131568 -140.0048)
		(width 0.14224)
		(layer "In11.Cu")
		(net "M_L_DQS_DP<5>")
	)
	(segment
		(start 128.902968 -127.609854)
		(end 128.902968 -127.1016)
		(width 0.14224)
		(layer "In11.Cu")
		(net "M_L_DQS_DP<5>")
	)
	(segment
		(start 129.131568 -126.873)
		(end 129.131568 -126.47041)
		(width 0.14224)
		(layer "In11.Cu")
		(net "M_L_DQS_DP<5>")
	)
	(segment
		(start 128.687576 -140.541756)
		(end 129.131568 -140.097764)
		(width 0.14224)
		(layer "In11.Cu")
		(net "M_L_DQS_DP<5>")
	)
	(segment
		(start 129.469896 -128.176782)
		(end 128.902968 -127.609854)
		(width 0.14224)
		(layer "In11.Cu")
		(net "M_L_DQS_DP<5>")
	)
	(segment
		(start 119.8372 -144.8562)
		(end 119.59336 -144.61236)
		(width 0.1651)
		(layer "F.Cu")
		(net "M_L_DQS_DP<4>")
	)
	(segment
		(start 107.910376 -98.500184)
		(end 108.481876 -98.500184)
		(width 0.1651)
		(layer "F.Cu")
		(net "M_L_DQS_DP<4>")
	)
	(segment
		(start 119.799354 -147.27174)
		(end 119.799354 -146.265646)
		(width 0.1651)
		(layer "F.Cu")
		(net "M_L_DQS_DP<4>")
	)
	(segment
		(start 119.799354 -146.265646)
		(end 119.8372 -146.2278)
		(width 0.1651)
		(layer "F.Cu")
		(net "M_L_DQS_DP<4>")
	)
	(segment
		(start 119.59336 -144.61236)
		(end 119.337328 -144.61236)
		(width 0.1651)
		(layer "F.Cu")
		(net "M_L_DQS_DP<4>")
	)
	(segment
		(start 119.8372 -146.2278)
		(end 119.8372 -144.8562)
		(width 0.1651)
		(layer "F.Cu")
		(net "M_L_DQS_DP<4>")
	)
	(via
		(at 119.337328 -144.61236)
		(size 0.508)
		(drill 0.254)
		(layers "F.Cu" "B.Cu")
		(net "M_L_DQS_DP<4>")
	)
	(via
		(at 108.481876 -98.500184)
		(size 0.508)
		(drill 0.254)
		(layers "F.Cu" "B.Cu")
		(net "M_L_DQS_DP<4>")
	)
	(via
		(at 119.337328 -140.541756)
		(size 0.508)
		(drill 0.254)
		(layers "F.Cu" "B.Cu")
		(net "M_L_DQS_DP<4>")
	)
	(segment
		(start 119.8372 -139.065)
		(end 119.8372 -140.2842)
		(width 0.1651)
		(layer "B.Cu")
		(net "M_L_DQS_DP<4>")
	)
	(segment
		(start 119.799354 -139.027154)
		(end 119.8372 -139.065)
		(width 0.1651)
		(layer "B.Cu")
		(net "M_L_DQS_DP<4>")
	)
	(segment
		(start 119.799354 -137.877296)
		(end 119.799354 -139.027154)
		(width 0.1651)
		(layer "B.Cu")
		(net "M_L_DQS_DP<4>")
	)
	(segment
		(start 119.8372 -140.2842)
		(end 119.579644 -140.541756)
		(width 0.1651)
		(layer "B.Cu")
		(net "M_L_DQS_DP<4>")
	)
	(segment
		(start 119.579644 -140.541756)
		(end 119.337328 -140.541756)
		(width 0.1651)
		(layer "B.Cu")
		(net "M_L_DQS_DP<4>")
	)
	(segment
		(start 119.809768 -128.31318)
		(end 120.170702 -128.674114)
		(width 0.14224)
		(layer "In4.Cu")
		(net "M_L_DQS_DP<4>")
	)
	(segment
		(start 119.34063 -142.4432)
		(end 119.34063 -142.719552)
		(width 0.14224)
		(layer "In4.Cu")
		(net "M_L_DQS_DP<4>")
	)
	(segment
		(start 108.993686 -100.186998)
		(end 109.039406 -100.266246)
		(width 0.0889)
		(layer "In4.Cu")
		(net "M_L_DQS_DP<4>")
	)
	(segment
		(start 119.007382 -125.638306)
		(end 119.230394 -125.861318)
		(width 0.14224)
		(layer "In4.Cu")
		(net "M_L_DQS_DP<4>")
	)
	(segment
		(start 119.77243 -140.976604)
		(end 119.77243 -141.4018)
		(width 0.14224)
		(layer "In4.Cu")
		(net "M_L_DQS_DP<4>")
	)
	(segment
		(start 119.75592 -125.861318)
		(end 120.134888 -126.240286)
		(width 0.14224)
		(layer "In4.Cu")
		(net "M_L_DQS_DP<4>")
	)
	(segment
		(start 119.100092 -142.899892)
		(end 118.962932 -143.037052)
		(width 0.14224)
		(layer "In4.Cu")
		(net "M_L_DQS_DP<4>")
	)
	(segment
		(start 119.317516 -128.31318)
		(end 119.809768 -128.31318)
		(width 0.14224)
		(layer "In4.Cu")
		(net "M_L_DQS_DP<4>")
	)
	(segment
		(start 120.170702 -128.674114)
		(end 120.170702 -139.708636)
		(width 0.14224)
		(layer "In4.Cu")
		(net "M_L_DQS_DP<4>")
	)
	(segment
		(start 119.77243 -141.4018)
		(end 119.51843 -141.6558)
		(width 0.14224)
		(layer "In4.Cu")
		(net "M_L_DQS_DP<4>")
	)
	(segment
		(start 119.51843 -141.6558)
		(end 119.133366 -141.6558)
		(width 0.14224)
		(layer "In4.Cu")
		(net "M_L_DQS_DP<4>")
	)
	(segment
		(start 109.039406 -100.266246)
		(end 109.982508 -101.209348)
		(width 0.0889)
		(layer "In4.Cu")
		(net "M_L_DQS_DP<4>")
	)
	(segment
		(start 119.16283 -142.2654)
		(end 119.34063 -142.4432)
		(width 0.14224)
		(layer "In4.Cu")
		(net "M_L_DQS_DP<4>")
	)
	(segment
		(start 120.134888 -126.240286)
		(end 120.134888 -126.89459)
		(width 0.14224)
		(layer "In4.Cu")
		(net "M_L_DQS_DP<4>")
	)
	(segment
		(start 109.982508 -102.914196)
		(end 110.243112 -103.1748)
		(width 0.0889)
		(layer "In4.Cu")
		(net "M_L_DQS_DP<4>")
	)
	(segment
		(start 119.107204 -127.46736)
		(end 119.107204 -128.102868)
		(width 0.14224)
		(layer "In4.Cu")
		(net "M_L_DQS_DP<4>")
	)
	(segment
		(start 119.79783 -143.7132)
		(end 119.79783 -144.152112)
		(width 0.14224)
		(layer "In4.Cu")
		(net "M_L_DQS_DP<4>")
	)
	(segment
		(start 119.34063 -142.719552)
		(end 119.16029 -142.899892)
		(width 0.14224)
		(layer "In4.Cu")
		(net "M_L_DQS_DP<4>")
	)
	(segment
		(start 119.16029 -142.899892)
		(end 119.100092 -142.899892)
		(width 0.14224)
		(layer "In4.Cu")
		(net "M_L_DQS_DP<4>")
	)
	(segment
		(start 119.301006 -127.273558)
		(end 119.107204 -127.46736)
		(width 0.14224)
		(layer "In4.Cu")
		(net "M_L_DQS_DP<4>")
	)
	(segment
		(start 119.75592 -127.273558)
		(end 119.301006 -127.273558)
		(width 0.14224)
		(layer "In4.Cu")
		(net "M_L_DQS_DP<4>")
	)
	(segment
		(start 118.962932 -143.037052)
		(end 118.962932 -143.263366)
		(width 0.14224)
		(layer "In4.Cu")
		(net "M_L_DQS_DP<4>")
	)
	(segment
		(start 118.962932 -142.150592)
		(end 119.07774 -142.2654)
		(width 0.14224)
		(layer "In4.Cu")
		(net "M_L_DQS_DP<4>")
	)
	(segment
		(start 110.243112 -106.50093)
		(end 110.282482 -106.5403)
		(width 0.0889)
		(layer "In4.Cu")
		(net "M_L_DQS_DP<4>")
	)
	(segment
		(start 110.282482 -106.562398)
		(end 110.282482 -116.296948)
		(width 0.14224)
		(layer "In4.Cu")
		(net "M_L_DQS_DP<4>")
	)
	(segment
		(start 120.170702 -139.708636)
		(end 119.337582 -140.541756)
		(width 0.14224)
		(layer "In4.Cu")
		(net "M_L_DQS_DP<4>")
	)
	(segment
		(start 119.337582 -140.541756)
		(end 119.77243 -140.976604)
		(width 0.14224)
		(layer "In4.Cu")
		(net "M_L_DQS_DP<4>")
	)
	(segment
		(start 119.133366 -141.6558)
		(end 118.962932 -141.826234)
		(width 0.14224)
		(layer "In4.Cu")
		(net "M_L_DQS_DP<4>")
	)
	(segment
		(start 110.282482 -116.296948)
		(end 119.007382 -125.021848)
		(width 0.14224)
		(layer "In4.Cu")
		(net "M_L_DQS_DP<4>")
	)
	(segment
		(start 119.337582 -144.61236)
		(end 119.337328 -144.61236)
		(width 0.14224)
		(layer "In4.Cu")
		(net "M_L_DQS_DP<4>")
	)
	(segment
		(start 119.107204 -128.102868)
		(end 119.317516 -128.31318)
		(width 0.14224)
		(layer "In4.Cu")
		(net "M_L_DQS_DP<4>")
	)
	(segment
		(start 119.158766 -143.4592)
		(end 119.54383 -143.4592)
		(width 0.14224)
		(layer "In4.Cu")
		(net "M_L_DQS_DP<4>")
	)
	(segment
		(start 110.282482 -106.5403)
		(end 110.282482 -106.562398)
		(width 0.0889)
		(layer "In4.Cu")
		(net "M_L_DQS_DP<4>")
	)
	(segment
		(start 119.07774 -142.2654)
		(end 119.16283 -142.2654)
		(width 0.14224)
		(layer "In4.Cu")
		(net "M_L_DQS_DP<4>")
	)
	(segment
		(start 119.337328 -140.541756)
		(end 119.337582 -140.541756)
		(width 0.14224)
		(layer "In4.Cu")
		(net "M_L_DQS_DP<4>")
	)
	(segment
		(start 120.134888 -126.89459)
		(end 119.75592 -127.273558)
		(width 0.14224)
		(layer "In4.Cu")
		(net "M_L_DQS_DP<4>")
	)
	(segment
		(start 118.962932 -141.826234)
		(end 118.962932 -142.150592)
		(width 0.14224)
		(layer "In4.Cu")
		(net "M_L_DQS_DP<4>")
	)
	(segment
		(start 119.79783 -144.152112)
		(end 119.337582 -144.61236)
		(width 0.14224)
		(layer "In4.Cu")
		(net "M_L_DQS_DP<4>")
	)
	(segment
		(start 119.54383 -143.4592)
		(end 119.79783 -143.7132)
		(width 0.14224)
		(layer "In4.Cu")
		(net "M_L_DQS_DP<4>")
	)
	(segment
		(start 109.982508 -101.209348)
		(end 109.982508 -102.914196)
		(width 0.0889)
		(layer "In4.Cu")
		(net "M_L_DQS_DP<4>")
	)
	(segment
		(start 110.243112 -103.1748)
		(end 110.243112 -106.50093)
		(width 0.0889)
		(layer "In4.Cu")
		(net "M_L_DQS_DP<4>")
	)
	(segment
		(start 119.230394 -125.861318)
		(end 119.75592 -125.861318)
		(width 0.14224)
		(layer "In4.Cu")
		(net "M_L_DQS_DP<4>")
	)
	(segment
		(start 118.962932 -143.263366)
		(end 119.158766 -143.4592)
		(width 0.14224)
		(layer "In4.Cu")
		(net "M_L_DQS_DP<4>")
	)
	(segment
		(start 119.007382 -125.021848)
		(end 119.007382 -125.638306)
		(width 0.14224)
		(layer "In4.Cu")
		(net "M_L_DQS_DP<4>")
	)
	(arc
		(start 108.917232 -99.845114)
		(mid 108.929342 -100.021895)
		(end 108.993686 -100.186998)
		(width 0.0889)
		(layer "In4.Cu")
		(net "M_L_DQS_DP<4>")
	)
	(arc
		(start 108.481876 -98.500184)
		(mid 108.633478 -98.905197)
		(end 108.828586 -99.29114)
		(width 0.0889)
		(layer "In4.Cu")
		(net "M_L_DQS_DP<4>")
	)
	(arc
		(start 108.828586 -99.29114)
		(mid 108.869378 -99.365387)
		(end 108.907072 -99.441254)
		(width 0.0889)
		(layer "In4.Cu")
		(net "M_L_DQS_DP<4>")
	)
	(arc
		(start 108.928154 -99.606354)
		(mid 108.92495 -99.725837)
		(end 108.917232 -99.845114)
		(width 0.0889)
		(layer "In4.Cu")
		(net "M_L_DQS_DP<4>")
	)
	(arc
		(start 108.907072 -99.441254)
		(mid 108.930659 -99.522138)
		(end 108.928154 -99.606354)
		(width 0.0889)
		(layer "In4.Cu")
		(net "M_L_DQS_DP<4>")
	)
	(segment
		(start 79.239618 -101.424486)
		(end 79.256128 -101.452934)
		(width 0.0889)
		(layer "F.Cu")
		(net "M_L_DQS_DP<3>")
	)
	(segment
		(start 63.866268 -112.605058)
		(end 70.44944 -106.021886)
		(width 0.1651)
		(layer "F.Cu")
		(net "M_L_DQS_DP<3>")
	)
	(segment
		(start 64.549528 -146.265646)
		(end 64.587374 -146.2278)
		(width 0.1651)
		(layer "F.Cu")
		(net "M_L_DQS_DP<3>")
	)
	(segment
		(start 64.483488 -114.093752)
		(end 64.134238 -113.744502)
		(width 0.1651)
		(layer "F.Cu")
		(net "M_L_DQS_DP<3>")
	)
	(segment
		(start 63.866268 -113.607342)
		(end 63.866268 -112.605058)
		(width 0.1651)
		(layer "F.Cu")
		(net "M_L_DQS_DP<3>")
	)
	(segment
		(start 63.772288 -115.20043)
		(end 63.950596 -115.022122)
		(width 0.1651)
		(layer "F.Cu")
		(net "M_L_DQS_DP<3>")
	)
	(segment
		(start 74.733404 -104.356154)
		(end 76.830174 -104.356154)
		(width 0.1016)
		(layer "F.Cu")
		(net "M_L_DQS_DP<3>")
	)
	(segment
		(start 63.950596 -115.715542)
		(end 63.772288 -115.537234)
		(width 0.1651)
		(layer "F.Cu")
		(net "M_L_DQS_DP<3>")
	)
	(segment
		(start 64.134238 -115.022122)
		(end 64.483488 -114.672872)
		(width 0.1651)
		(layer "F.Cu")
		(net "M_L_DQS_DP<3>")
	)
	(segment
		(start 64.003428 -113.744502)
		(end 63.866268 -113.607342)
		(width 0.1651)
		(layer "F.Cu")
		(net "M_L_DQS_DP<3>")
	)
	(segment
		(start 64.531494 -116.993162)
		(end 64.833754 -116.690902)
		(width 0.1651)
		(layer "F.Cu")
		(net "M_L_DQS_DP<3>")
	)
	(segment
		(start 63.950596 -115.022122)
		(end 64.134238 -115.022122)
		(width 0.1651)
		(layer "F.Cu")
		(net "M_L_DQS_DP<3>")
	)
	(segment
		(start 70.44944 -106.021886)
		(end 72.808592 -106.021886)
		(width 0.1651)
		(layer "F.Cu")
		(net "M_L_DQS_DP<3>")
	)
	(segment
		(start 63.772288 -115.537234)
		(end 63.772288 -115.20043)
		(width 0.1651)
		(layer "F.Cu")
		(net "M_L_DQS_DP<3>")
	)
	(segment
		(start 64.587374 -146.2278)
		(end 64.587374 -144.8562)
		(width 0.1651)
		(layer "F.Cu")
		(net "M_L_DQS_DP<3>")
	)
	(segment
		(start 64.833754 -116.690902)
		(end 64.833754 -116.011452)
		(width 0.1651)
		(layer "F.Cu")
		(net "M_L_DQS_DP<3>")
	)
	(segment
		(start 79.23276 -101.939852)
		(end 79.100172 -102.745286)
		(width 0.0889)
		(layer "F.Cu")
		(net "M_L_DQS_DP<3>")
	)
	(segment
		(start 64.310768 -121.012966)
		(end 63.772288 -120.474486)
		(width 0.1651)
		(layer "F.Cu")
		(net "M_L_DQS_DP<3>")
	)
	(segment
		(start 64.134238 -113.744502)
		(end 64.003428 -113.744502)
		(width 0.1651)
		(layer "F.Cu")
		(net "M_L_DQS_DP<3>")
	)
	(segment
		(start 63.772288 -117.17147)
		(end 63.950596 -116.993162)
		(width 0.1651)
		(layer "F.Cu")
		(net "M_L_DQS_DP<3>")
	)
	(segment
		(start 79.100172 -102.745286)
		(end 79.087218 -102.75824)
		(width 0.0889)
		(layer "F.Cu")
		(net "M_L_DQS_DP<3>")
	)
	(segment
		(start 64.537844 -115.715542)
		(end 63.950596 -115.715542)
		(width 0.1651)
		(layer "F.Cu")
		(net "M_L_DQS_DP<3>")
	)
	(segment
		(start 79.087218 -102.75824)
		(end 77.489304 -104.356154)
		(width 0.1016)
		(layer "F.Cu")
		(net "M_L_DQS_DP<3>")
	)
	(segment
		(start 64.833754 -116.011452)
		(end 64.537844 -115.715542)
		(width 0.1651)
		(layer "F.Cu")
		(net "M_L_DQS_DP<3>")
	)
	(segment
		(start 63.950596 -116.993162)
		(end 64.531494 -116.993162)
		(width 0.1651)
		(layer "F.Cu")
		(net "M_L_DQS_DP<3>")
	)
	(segment
		(start 64.310768 -123.691142)
		(end 64.310768 -121.012966)
		(width 0.1651)
		(layer "F.Cu")
		(net "M_L_DQS_DP<3>")
	)
	(segment
		(start 64.862964 -124.243338)
		(end 64.310768 -123.691142)
		(width 0.1651)
		(layer "F.Cu")
		(net "M_L_DQS_DP<3>")
	)
	(segment
		(start 72.808592 -106.019346)
		(end 73.070212 -106.019346)
		(width 0.1016)
		(layer "F.Cu")
		(net "M_L_DQS_DP<3>")
	)
	(segment
		(start 64.549528 -147.27174)
		(end 64.549528 -146.265646)
		(width 0.1651)
		(layer "F.Cu")
		(net "M_L_DQS_DP<3>")
	)
	(segment
		(start 64.862964 -125.161294)
		(end 64.862964 -124.243338)
		(width 0.1651)
		(layer "F.Cu")
		(net "M_L_DQS_DP<3>")
	)
	(segment
		(start 72.808592 -106.021886)
		(end 72.808592 -106.019346)
		(width 0.1651)
		(layer "F.Cu")
		(net "M_L_DQS_DP<3>")
	)
	(segment
		(start 64.087502 -125.936756)
		(end 64.862964 -125.161294)
		(width 0.1651)
		(layer "F.Cu")
		(net "M_L_DQS_DP<3>")
	)
	(segment
		(start 63.772288 -120.474486)
		(end 63.772288 -117.17147)
		(width 0.1651)
		(layer "F.Cu")
		(net "M_L_DQS_DP<3>")
	)
	(segment
		(start 64.483488 -114.672872)
		(end 64.483488 -114.093752)
		(width 0.1651)
		(layer "F.Cu")
		(net "M_L_DQS_DP<3>")
	)
	(segment
		(start 78.909672 -100.662486)
		(end 79.239618 -101.424486)
		(width 0.0889)
		(layer "F.Cu")
		(net "M_L_DQS_DP<3>")
	)
	(segment
		(start 73.070212 -106.019346)
		(end 74.733404 -104.356154)
		(width 0.1016)
		(layer "F.Cu")
		(net "M_L_DQS_DP<3>")
	)
	(segment
		(start 64.343534 -144.61236)
		(end 64.087502 -144.61236)
		(width 0.1651)
		(layer "F.Cu")
		(net "M_L_DQS_DP<3>")
	)
	(segment
		(start 77.489304 -104.356154)
		(end 76.830174 -104.356154)
		(width 0.1016)
		(layer "F.Cu")
		(net "M_L_DQS_DP<3>")
	)
	(segment
		(start 64.587374 -144.8562)
		(end 64.343534 -144.61236)
		(width 0.1651)
		(layer "F.Cu")
		(net "M_L_DQS_DP<3>")
	)
	(segment
		(start 79.252826 -101.90607)
		(end 79.23276 -101.939852)
		(width 0.0889)
		(layer "F.Cu")
		(net "M_L_DQS_DP<3>")
	)
	(via
		(at 64.087502 -144.61236)
		(size 0.508)
		(drill 0.254)
		(layers "F.Cu" "B.Cu")
		(net "M_L_DQS_DP<3>")
	)
	(via
		(at 64.087502 -140.541756)
		(size 0.508)
		(drill 0.254)
		(layers "F.Cu" "B.Cu")
		(net "M_L_DQS_DP<3>")
	)
	(via
		(at 64.087502 -125.936756)
		(size 0.508)
		(drill 0.254)
		(layers "F.Cu" "B.Cu")
		(net "M_L_DQS_DP<3>")
	)
	(arc
		(start 79.256128 -101.452934)
		(mid 79.31604 -101.679953)
		(end 79.252826 -101.90607)
		(width 0.0889)
		(layer "F.Cu")
		(net "M_L_DQS_DP<3>")
	)
	(segment
		(start 64.329818 -140.541756)
		(end 64.087502 -140.541756)
		(width 0.1651)
		(layer "B.Cu")
		(net "M_L_DQS_DP<3>")
	)
	(segment
		(start 64.587374 -140.2842)
		(end 64.329818 -140.541756)
		(width 0.1651)
		(layer "B.Cu")
		(net "M_L_DQS_DP<3>")
	)
	(segment
		(start 64.549528 -139.027154)
		(end 64.587374 -139.065)
		(width 0.1651)
		(layer "B.Cu")
		(net "M_L_DQS_DP<3>")
	)
	(segment
		(start 64.587374 -139.065)
		(end 64.587374 -140.2842)
		(width 0.1651)
		(layer "B.Cu")
		(net "M_L_DQS_DP<3>")
	)
	(segment
		(start 64.549528 -137.877296)
		(end 64.549528 -139.027154)
		(width 0.1651)
		(layer "B.Cu")
		(net "M_L_DQS_DP<3>")
	)
	(segment
		(start 63.91275 -142.2654)
		(end 63.82766 -142.2654)
		(width 0.14224)
		(layer "In4.Cu")
		(net "M_L_DQS_DP<3>")
	)
	(segment
		(start 64.539368 -127.3048)
		(end 64.539368 -126.2634)
		(width 0.14224)
		(layer "In4.Cu")
		(net "M_L_DQS_DP<3>")
	)
	(segment
		(start 63.712852 -142.150592)
		(end 63.712852 -141.826234)
		(width 0.14224)
		(layer "In4.Cu")
		(net "M_L_DQS_DP<3>")
	)
	(segment
		(start 63.883286 -141.6558)
		(end 64.26835 -141.6558)
		(width 0.14224)
		(layer "In4.Cu")
		(net "M_L_DQS_DP<3>")
	)
	(segment
		(start 63.712852 -141.826234)
		(end 63.883286 -141.6558)
		(width 0.14224)
		(layer "In4.Cu")
		(net "M_L_DQS_DP<3>")
	)
	(segment
		(start 64.26835 -141.6558)
		(end 64.52235 -141.4018)
		(width 0.14224)
		(layer "In4.Cu")
		(net "M_L_DQS_DP<3>")
	)
	(segment
		(start 64.087502 -140.541756)
		(end 64.087756 -140.541756)
		(width 0.14224)
		(layer "In4.Cu")
		(net "M_L_DQS_DP<3>")
	)
	(segment
		(start 64.087756 -140.541756)
		(end 64.869822 -139.75969)
		(width 0.14224)
		(layer "In4.Cu")
		(net "M_L_DQS_DP<3>")
	)
	(segment
		(start 64.869822 -139.75969)
		(end 64.869822 -133.782054)
		(width 0.14224)
		(layer "In4.Cu")
		(net "M_L_DQS_DP<3>")
	)
	(segment
		(start 64.869822 -127.635254)
		(end 64.539368 -127.3048)
		(width 0.14224)
		(layer "In4.Cu")
		(net "M_L_DQS_DP<3>")
	)
	(segment
		(start 64.09055 -142.4432)
		(end 63.91275 -142.2654)
		(width 0.14224)
		(layer "In4.Cu")
		(net "M_L_DQS_DP<3>")
	)
	(segment
		(start 64.087502 -144.61236)
		(end 64.54775 -144.152112)
		(width 0.14224)
		(layer "In4.Cu")
		(net "M_L_DQS_DP<3>")
	)
	(segment
		(start 64.488568 -133.4008)
		(end 64.488568 -132.842254)
		(width 0.14224)
		(layer "In4.Cu")
		(net "M_L_DQS_DP<3>")
	)
	(segment
		(start 64.29375 -143.4592)
		(end 63.908686 -143.4592)
		(width 0.14224)
		(layer "In4.Cu")
		(net "M_L_DQS_DP<3>")
	)
	(segment
		(start 63.712852 -143.263366)
		(end 63.712852 -143.037052)
		(width 0.14224)
		(layer "In4.Cu")
		(net "M_L_DQS_DP<3>")
	)
	(segment
		(start 63.850012 -142.899892)
		(end 63.91021 -142.899892)
		(width 0.14224)
		(layer "In4.Cu")
		(net "M_L_DQS_DP<3>")
	)
	(segment
		(start 64.869822 -133.782054)
		(end 64.488568 -133.4008)
		(width 0.14224)
		(layer "In4.Cu")
		(net "M_L_DQS_DP<3>")
	)
	(segment
		(start 63.82766 -142.2654)
		(end 63.712852 -142.150592)
		(width 0.14224)
		(layer "In4.Cu")
		(net "M_L_DQS_DP<3>")
	)
	(segment
		(start 63.91021 -142.899892)
		(end 64.09055 -142.719552)
		(width 0.14224)
		(layer "In4.Cu")
		(net "M_L_DQS_DP<3>")
	)
	(segment
		(start 64.54775 -143.7132)
		(end 64.29375 -143.4592)
		(width 0.14224)
		(layer "In4.Cu")
		(net "M_L_DQS_DP<3>")
	)
	(segment
		(start 64.54775 -144.152112)
		(end 64.54775 -143.7132)
		(width 0.14224)
		(layer "In4.Cu")
		(net "M_L_DQS_DP<3>")
	)
	(segment
		(start 64.09055 -142.719552)
		(end 64.09055 -142.4432)
		(width 0.14224)
		(layer "In4.Cu")
		(net "M_L_DQS_DP<3>")
	)
	(segment
		(start 63.908686 -143.4592)
		(end 63.712852 -143.263366)
		(width 0.14224)
		(layer "In4.Cu")
		(net "M_L_DQS_DP<3>")
	)
	(segment
		(start 64.869822 -132.461)
		(end 64.869822 -127.635254)
		(width 0.14224)
		(layer "In4.Cu")
		(net "M_L_DQS_DP<3>")
	)
	(segment
		(start 64.52235 -140.976604)
		(end 64.087502 -140.541756)
		(width 0.14224)
		(layer "In4.Cu")
		(net "M_L_DQS_DP<3>")
	)
	(segment
		(start 64.539368 -126.2634)
		(end 64.212724 -125.936756)
		(width 0.14224)
		(layer "In4.Cu")
		(net "M_L_DQS_DP<3>")
	)
	(segment
		(start 64.52235 -141.4018)
		(end 64.52235 -140.976604)
		(width 0.14224)
		(layer "In4.Cu")
		(net "M_L_DQS_DP<3>")
	)
	(segment
		(start 63.712852 -143.037052)
		(end 63.850012 -142.899892)
		(width 0.14224)
		(layer "In4.Cu")
		(net "M_L_DQS_DP<3>")
	)
	(segment
		(start 64.488568 -132.842254)
		(end 64.869822 -132.461)
		(width 0.14224)
		(layer "In4.Cu")
		(net "M_L_DQS_DP<3>")
	)
	(segment
		(start 64.212724 -125.936756)
		(end 64.087502 -125.936756)
		(width 0.14224)
		(layer "In4.Cu")
		(net "M_L_DQS_DP<3>")
	)
	(segment
		(start 55.199534 -147.27174)
		(end 55.199534 -146.265646)
		(width 0.1651)
		(layer "F.Cu")
		(net "M_L_DQS_DP<2>")
	)
	(segment
		(start 54.99354 -144.61236)
		(end 54.737508 -144.61236)
		(width 0.1651)
		(layer "F.Cu")
		(net "M_L_DQS_DP<2>")
	)
	(segment
		(start 55.23738 -146.2278)
		(end 55.23738 -144.8562)
		(width 0.1651)
		(layer "F.Cu")
		(net "M_L_DQS_DP<2>")
	)
	(segment
		(start 55.199534 -146.265646)
		(end 55.23738 -146.2278)
		(width 0.1651)
		(layer "F.Cu")
		(net "M_L_DQS_DP<2>")
	)
	(segment
		(start 73.758806 -99.67214)
		(end 73.187306 -99.67214)
		(width 0.1651)
		(layer "F.Cu")
		(net "M_L_DQS_DP<2>")
	)
	(segment
		(start 55.23738 -144.8562)
		(end 54.99354 -144.61236)
		(width 0.1651)
		(layer "F.Cu")
		(net "M_L_DQS_DP<2>")
	)
	(via
		(at 54.737508 -144.61236)
		(size 0.508)
		(drill 0.254)
		(layers "F.Cu" "B.Cu")
		(net "M_L_DQS_DP<2>")
	)
	(via
		(at 73.187306 -99.67214)
		(size 0.508)
		(drill 0.254)
		(layers "F.Cu" "B.Cu")
		(net "M_L_DQS_DP<2>")
	)
	(via
		(at 54.737508 -140.541756)
		(size 0.508)
		(drill 0.254)
		(layers "F.Cu" "B.Cu")
		(net "M_L_DQS_DP<2>")
	)
	(segment
		(start 55.199534 -139.027154)
		(end 55.23738 -139.065)
		(width 0.1651)
		(layer "B.Cu")
		(net "M_L_DQS_DP<2>")
	)
	(segment
		(start 55.23738 -140.2842)
		(end 54.979824 -140.541756)
		(width 0.1651)
		(layer "B.Cu")
		(net "M_L_DQS_DP<2>")
	)
	(segment
		(start 54.979824 -140.541756)
		(end 54.737508 -140.541756)
		(width 0.1651)
		(layer "B.Cu")
		(net "M_L_DQS_DP<2>")
	)
	(segment
		(start 55.23738 -139.065)
		(end 55.23738 -140.2842)
		(width 0.1651)
		(layer "B.Cu")
		(net "M_L_DQS_DP<2>")
	)
	(segment
		(start 55.199534 -137.877296)
		(end 55.199534 -139.027154)
		(width 0.1651)
		(layer "B.Cu")
		(net "M_L_DQS_DP<2>")
	)
	(segment
		(start 60.60059 -119.67337)
		(end 60.60059 -119.985282)
		(width 0.14224)
		(layer "In4.Cu")
		(net "M_L_DQS_DP<2>")
	)
	(segment
		(start 71.980044 -101.954584)
		(end 71.979536 -101.955854)
		(width 0.0889)
		(layer "In4.Cu")
		(net "M_L_DQS_DP<2>")
	)
	(segment
		(start 54.943756 -143.4592)
		(end 55.197756 -143.7132)
		(width 0.14224)
		(layer "In4.Cu")
		(net "M_L_DQS_DP<2>")
	)
	(segment
		(start 56.407812 -123.865386)
		(end 56.407812 -128.569974)
		(width 0.14224)
		(layer "In4.Cu")
		(net "M_L_DQS_DP<2>")
	)
	(segment
		(start 61.05017 -119.22379)
		(end 60.60059 -119.67337)
		(width 0.14224)
		(layer "In4.Cu")
		(net "M_L_DQS_DP<2>")
	)
	(segment
		(start 54.362858 -141.826234)
		(end 54.362858 -142.150592)
		(width 0.14224)
		(layer "In4.Cu")
		(net "M_L_DQS_DP<2>")
	)
	(segment
		(start 55.197756 -143.7132)
		(end 55.197756 -144.152112)
		(width 0.14224)
		(layer "In4.Cu")
		(net "M_L_DQS_DP<2>")
	)
	(segment
		(start 65.702688 -109.802168)
		(end 65.702688 -114.57051)
		(width 0.14224)
		(layer "In4.Cu")
		(net "M_L_DQS_DP<2>")
	)
	(segment
		(start 62.094872 -119.417338)
		(end 61.554868 -119.417338)
		(width 0.14224)
		(layer "In4.Cu")
		(net "M_L_DQS_DP<2>")
	)
	(segment
		(start 54.362858 -142.150592)
		(end 54.477666 -142.2654)
		(width 0.14224)
		(layer "In4.Cu")
		(net "M_L_DQS_DP<2>")
	)
	(segment
		(start 71.973694 -101.966014)
		(end 71.866506 -102.156768)
		(width 0.0889)
		(layer "In4.Cu")
		(net "M_L_DQS_DP<2>")
	)
	(segment
		(start 69.344286 -104.469438)
		(end 69.344286 -106.16057)
		(width 0.14224)
		(layer "In4.Cu")
		(net "M_L_DQS_DP<2>")
	)
	(segment
		(start 69.672962 -104.085136)
		(end 69.673216 -104.140508)
		(width 0.0889)
		(layer "In4.Cu")
		(net "M_L_DQS_DP<2>")
	)
	(segment
		(start 71.981822 -101.951536)
		(end 71.980806 -101.953314)
		(width 0.0889)
		(layer "In4.Cu")
		(net "M_L_DQS_DP<2>")
	)
	(segment
		(start 58.0771 -122.339862)
		(end 57.933336 -122.339862)
		(width 0.14224)
		(layer "In4.Cu")
		(net "M_L_DQS_DP<2>")
	)
	(segment
		(start 71.866506 -102.156768)
		(end 71.10476 -102.918514)
		(width 0.0889)
		(layer "In4.Cu")
		(net "M_L_DQS_DP<2>")
	)
	(segment
		(start 55.172356 -141.4018)
		(end 54.918356 -141.6558)
		(width 0.14224)
		(layer "In4.Cu")
		(net "M_L_DQS_DP<2>")
	)
	(segment
		(start 60.93333 -120.854216)
		(end 60.325508 -121.462038)
		(width 0.14224)
		(layer "In4.Cu")
		(net "M_L_DQS_DP<2>")
	)
	(segment
		(start 54.558692 -143.4592)
		(end 54.943756 -143.4592)
		(width 0.14224)
		(layer "In4.Cu")
		(net "M_L_DQS_DP<2>")
	)
	(segment
		(start 62.637924 -117.635274)
		(end 62.637924 -118.874286)
		(width 0.14224)
		(layer "In4.Cu")
		(net "M_L_DQS_DP<2>")
	)
	(segment
		(start 57.933336 -122.339862)
		(end 56.407812 -123.865386)
		(width 0.14224)
		(layer "In4.Cu")
		(net "M_L_DQS_DP<2>")
	)
	(segment
		(start 73.534016 -100.862892)
		(end 73.490074 -100.957634)
		(width 0.0889)
		(layer "In4.Cu")
		(net "M_L_DQS_DP<2>")
	)
	(segment
		(start 55.519828 -129.457958)
		(end 55.519828 -139.75969)
		(width 0.14224)
		(layer "In4.Cu")
		(net "M_L_DQS_DP<2>")
	)
	(segment
		(start 71.984362 -101.94671)
		(end 71.98233 -101.950774)
		(width 0.0889)
		(layer "In4.Cu")
		(net "M_L_DQS_DP<2>")
	)
	(segment
		(start 71.10476 -102.918514)
		(end 70.839584 -102.918514)
		(width 0.0889)
		(layer "In4.Cu")
		(net "M_L_DQS_DP<2>")
	)
	(segment
		(start 71.980806 -101.953314)
		(end 71.980044 -101.954584)
		(width 0.0889)
		(layer "In4.Cu")
		(net "M_L_DQS_DP<2>")
	)
	(segment
		(start 54.918356 -141.6558)
		(end 54.533292 -141.6558)
		(width 0.14224)
		(layer "In4.Cu")
		(net "M_L_DQS_DP<2>")
	)
	(segment
		(start 60.60059 -119.985282)
		(end 60.93333 -120.318022)
		(width 0.14224)
		(layer "In4.Cu")
		(net "M_L_DQS_DP<2>")
	)
	(segment
		(start 54.477666 -142.2654)
		(end 54.562756 -142.2654)
		(width 0.14224)
		(layer "In4.Cu")
		(net "M_L_DQS_DP<2>")
	)
	(segment
		(start 55.172356 -140.976604)
		(end 55.172356 -141.4018)
		(width 0.14224)
		(layer "In4.Cu")
		(net "M_L_DQS_DP<2>")
	)
	(segment
		(start 54.740556 -142.4432)
		(end 54.740556 -142.719552)
		(width 0.14224)
		(layer "In4.Cu")
		(net "M_L_DQS_DP<2>")
	)
	(segment
		(start 69.673216 -104.140508)
		(end 69.657722 -104.156002)
		(width 0.0889)
		(layer "In4.Cu")
		(net "M_L_DQS_DP<2>")
	)
	(segment
		(start 60.325508 -121.462038)
		(end 59.79033 -121.462038)
		(width 0.14224)
		(layer "In4.Cu")
		(net "M_L_DQS_DP<2>")
	)
	(segment
		(start 54.362858 -143.037052)
		(end 54.362858 -143.263366)
		(width 0.14224)
		(layer "In4.Cu")
		(net "M_L_DQS_DP<2>")
	)
	(segment
		(start 59.577732 -121.24944)
		(end 59.023758 -121.24944)
		(width 0.14224)
		(layer "In4.Cu")
		(net "M_L_DQS_DP<2>")
	)
	(segment
		(start 73.490074 -100.957634)
		(end 73.29424 -101.153468)
		(width 0.0889)
		(layer "In4.Cu")
		(net "M_L_DQS_DP<2>")
	)
	(segment
		(start 59.79033 -121.462038)
		(end 59.577732 -121.24944)
		(width 0.14224)
		(layer "In4.Cu")
		(net "M_L_DQS_DP<2>")
	)
	(segment
		(start 59.023758 -121.24944)
		(end 58.40603 -121.867168)
		(width 0.14224)
		(layer "In4.Cu")
		(net "M_L_DQS_DP<2>")
	)
	(segment
		(start 58.40603 -122.010932)
		(end 58.0771 -122.339862)
		(width 0.14224)
		(layer "In4.Cu")
		(net "M_L_DQS_DP<2>")
	)
	(segment
		(start 54.533292 -141.6558)
		(end 54.362858 -141.826234)
		(width 0.14224)
		(layer "In4.Cu")
		(net "M_L_DQS_DP<2>")
	)
	(segment
		(start 71.979536 -101.955854)
		(end 71.973694 -101.966014)
		(width 0.0889)
		(layer "In4.Cu")
		(net "M_L_DQS_DP<2>")
	)
	(segment
		(start 54.500018 -142.899892)
		(end 54.362858 -143.037052)
		(width 0.14224)
		(layer "In4.Cu")
		(net "M_L_DQS_DP<2>")
	)
	(segment
		(start 54.362858 -143.263366)
		(end 54.558692 -143.4592)
		(width 0.14224)
		(layer "In4.Cu")
		(net "M_L_DQS_DP<2>")
	)
	(segment
		(start 54.560216 -142.899892)
		(end 54.500018 -142.899892)
		(width 0.14224)
		(layer "In4.Cu")
		(net "M_L_DQS_DP<2>")
	)
	(segment
		(start 54.737762 -140.541756)
		(end 54.737508 -140.541756)
		(width 0.14224)
		(layer "In4.Cu")
		(net "M_L_DQS_DP<2>")
	)
	(segment
		(start 54.740556 -142.719552)
		(end 54.560216 -142.899892)
		(width 0.14224)
		(layer "In4.Cu")
		(net "M_L_DQS_DP<2>")
	)
	(segment
		(start 54.737508 -140.541756)
		(end 55.172356 -140.976604)
		(width 0.14224)
		(layer "In4.Cu")
		(net "M_L_DQS_DP<2>")
	)
	(segment
		(start 58.40603 -121.867168)
		(end 58.40603 -122.010932)
		(width 0.14224)
		(layer "In4.Cu")
		(net "M_L_DQS_DP<2>")
	)
	(segment
		(start 61.554868 -119.417338)
		(end 61.36132 -119.22379)
		(width 0.14224)
		(layer "In4.Cu")
		(net "M_L_DQS_DP<2>")
	)
	(segment
		(start 71.98233 -101.950774)
		(end 71.981822 -101.951536)
		(width 0.0889)
		(layer "In4.Cu")
		(net "M_L_DQS_DP<2>")
	)
	(segment
		(start 61.36132 -119.22379)
		(end 61.05017 -119.22379)
		(width 0.14224)
		(layer "In4.Cu")
		(net "M_L_DQS_DP<2>")
	)
	(segment
		(start 69.344286 -106.16057)
		(end 65.702688 -109.802168)
		(width 0.14224)
		(layer "In4.Cu")
		(net "M_L_DQS_DP<2>")
	)
	(segment
		(start 72.353678 -101.748336)
		(end 72.308466 -101.748336)
		(width 0.0889)
		(layer "In4.Cu")
		(net "M_L_DQS_DP<2>")
	)
	(segment
		(start 62.637924 -118.874286)
		(end 62.094872 -119.417338)
		(width 0.14224)
		(layer "In4.Cu")
		(net "M_L_DQS_DP<2>")
	)
	(segment
		(start 60.93333 -120.318022)
		(end 60.93333 -120.854216)
		(width 0.14224)
		(layer "In4.Cu")
		(net "M_L_DQS_DP<2>")
	)
	(segment
		(start 55.197756 -144.152112)
		(end 54.737508 -144.61236)
		(width 0.14224)
		(layer "In4.Cu")
		(net "M_L_DQS_DP<2>")
	)
	(segment
		(start 54.562756 -142.2654)
		(end 54.740556 -142.4432)
		(width 0.14224)
		(layer "In4.Cu")
		(net "M_L_DQS_DP<2>")
	)
	(segment
		(start 65.702688 -114.57051)
		(end 62.637924 -117.635274)
		(width 0.14224)
		(layer "In4.Cu")
		(net "M_L_DQS_DP<2>")
	)
	(segment
		(start 70.839584 -102.918514)
		(end 69.672962 -104.085136)
		(width 0.0889)
		(layer "In4.Cu")
		(net "M_L_DQS_DP<2>")
	)
	(segment
		(start 56.407812 -128.569974)
		(end 55.519828 -129.457958)
		(width 0.14224)
		(layer "In4.Cu")
		(net "M_L_DQS_DP<2>")
	)
	(segment
		(start 69.657722 -104.156002)
		(end 69.344286 -104.469438)
		(width 0.14224)
		(layer "In4.Cu")
		(net "M_L_DQS_DP<2>")
	)
	(segment
		(start 55.519828 -139.75969)
		(end 54.737762 -140.541756)
		(width 0.14224)
		(layer "In4.Cu")
		(net "M_L_DQS_DP<2>")
	)
	(arc
		(start 72.308466 -101.748336)
		(mid 72.121172 -101.806296)
		(end 71.984362 -101.94671)
		(width 0.0889)
		(layer "In4.Cu")
		(net "M_L_DQS_DP<2>")
	)
	(arc
		(start 73.096374 -101.26345)
		(mid 72.948836 -101.331812)
		(end 72.840596 -101.453188)
		(width 0.0889)
		(layer "In4.Cu")
		(net "M_L_DQS_DP<2>")
	)
	(arc
		(start 73.187306 -99.67214)
		(mid 73.338908 -100.077153)
		(end 73.534016 -100.463096)
		(width 0.0889)
		(layer "In4.Cu")
		(net "M_L_DQS_DP<2>")
	)
	(arc
		(start 73.534016 -100.463096)
		(mid 73.587515 -100.662994)
		(end 73.534016 -100.862892)
		(width 0.0889)
		(layer "In4.Cu")
		(net "M_L_DQS_DP<2>")
	)
	(arc
		(start 72.840596 -101.453188)
		(mid 72.635037 -101.663285)
		(end 72.353678 -101.748336)
		(width 0.0889)
		(layer "In4.Cu")
		(net "M_L_DQS_DP<2>")
	)
	(arc
		(start 73.29424 -101.153468)
		(mid 73.203003 -101.222306)
		(end 73.096374 -101.26345)
		(width 0.0889)
		(layer "In4.Cu")
		(net "M_L_DQS_DP<2>")
	)
	(segment
		(start 45.84954 -146.265646)
		(end 45.887386 -146.2278)
		(width 0.1651)
		(layer "F.Cu")
		(net "M_L_DQS_DP<1>")
	)
	(segment
		(start 45.887386 -144.8562)
		(end 45.643546 -144.61236)
		(width 0.1651)
		(layer "F.Cu")
		(net "M_L_DQS_DP<1>")
	)
	(segment
		(start 45.84954 -147.27174)
		(end 45.84954 -146.265646)
		(width 0.1651)
		(layer "F.Cu")
		(net "M_L_DQS_DP<1>")
	)
	(segment
		(start 45.887386 -146.2278)
		(end 45.887386 -144.8562)
		(width 0.1651)
		(layer "F.Cu")
		(net "M_L_DQS_DP<1>")
	)
	(segment
		(start 72.041766 -89.765886)
		(end 71.470266 -89.765886)
		(width 0.1651)
		(layer "F.Cu")
		(net "M_L_DQS_DP<1>")
	)
	(segment
		(start 45.643546 -144.61236)
		(end 45.387514 -144.61236)
		(width 0.1651)
		(layer "F.Cu")
		(net "M_L_DQS_DP<1>")
	)
	(via
		(at 45.387514 -144.61236)
		(size 0.508)
		(drill 0.254)
		(layers "F.Cu" "B.Cu")
		(net "M_L_DQS_DP<1>")
	)
	(via
		(at 45.387514 -140.541756)
		(size 0.508)
		(drill 0.254)
		(layers "F.Cu" "B.Cu")
		(net "M_L_DQS_DP<1>")
	)
	(via
		(at 71.470266 -89.765886)
		(size 0.508)
		(drill 0.254)
		(layers "F.Cu" "B.Cu")
		(net "M_L_DQS_DP<1>")
	)
	(segment
		(start 45.887386 -140.2842)
		(end 45.62983 -140.541756)
		(width 0.1651)
		(layer "B.Cu")
		(net "M_L_DQS_DP<1>")
	)
	(segment
		(start 45.84954 -139.027154)
		(end 45.887386 -139.065)
		(width 0.1651)
		(layer "B.Cu")
		(net "M_L_DQS_DP<1>")
	)
	(segment
		(start 45.887386 -139.065)
		(end 45.887386 -140.2842)
		(width 0.1651)
		(layer "B.Cu")
		(net "M_L_DQS_DP<1>")
	)
	(segment
		(start 45.84954 -137.877296)
		(end 45.84954 -139.027154)
		(width 0.1651)
		(layer "B.Cu")
		(net "M_L_DQS_DP<1>")
	)
	(segment
		(start 45.62983 -140.541756)
		(end 45.387514 -140.541756)
		(width 0.1651)
		(layer "B.Cu")
		(net "M_L_DQS_DP<1>")
	)
	(segment
		(start 57.442608 -104.658414)
		(end 62.573408 -99.527614)
		(width 0.14224)
		(layer "In4.Cu")
		(net "M_L_DQS_DP<1>")
	)
	(segment
		(start 52.641754 -113.960148)
		(end 53.17744 -113.960148)
		(width 0.14224)
		(layer "In4.Cu")
		(net "M_L_DQS_DP<1>")
	)
	(segment
		(start 49.243488 -115.491514)
		(end 49.576482 -115.15852)
		(width 0.14224)
		(layer "In4.Cu")
		(net "M_L_DQS_DP<1>")
	)
	(segment
		(start 53.785262 -113.352326)
		(end 53.785262 -112.816386)
		(width 0.14224)
		(layer "In4.Cu")
		(net "M_L_DQS_DP<1>")
	)
	(segment
		(start 71.17715 -89.596976)
		(end 71.470266 -89.765886)
		(width 0.0889)
		(layer "In4.Cu")
		(net "M_L_DQS_DP<1>")
	)
	(segment
		(start 45.208698 -143.4592)
		(end 45.012864 -143.263366)
		(width 0.14224)
		(layer "In4.Cu")
		(net "M_L_DQS_DP<1>")
	)
	(segment
		(start 71.087742 -89.621106)
		(end 71.17715 -89.596976)
		(width 0.0889)
		(layer "In4.Cu")
		(net "M_L_DQS_DP<1>")
	)
	(segment
		(start 50.259488 -116.918486)
		(end 49.243488 -115.902486)
		(width 0.14224)
		(layer "In4.Cu")
		(net "M_L_DQS_DP<1>")
	)
	(segment
		(start 46.169834 -139.765786)
		(end 46.169834 -128.1811)
		(width 0.14224)
		(layer "In4.Cu")
		(net "M_L_DQS_DP<1>")
	)
	(segment
		(start 53.785262 -112.816386)
		(end 53.007514 -112.038892)
		(width 0.14224)
		(layer "In4.Cu")
		(net "M_L_DQS_DP<1>")
	)
	(segment
		(start 45.568362 -141.6558)
		(end 45.822362 -141.4018)
		(width 0.14224)
		(layer "In4.Cu")
		(net "M_L_DQS_DP<1>")
	)
	(segment
		(start 45.012864 -142.150592)
		(end 45.012864 -141.826234)
		(width 0.14224)
		(layer "In4.Cu")
		(net "M_L_DQS_DP<1>")
	)
	(segment
		(start 45.012864 -143.263366)
		(end 45.012864 -143.037052)
		(width 0.14224)
		(layer "In4.Cu")
		(net "M_L_DQS_DP<1>")
	)
	(segment
		(start 51.880262 -115.257326)
		(end 51.880262 -114.721386)
		(width 0.14224)
		(layer "In4.Cu")
		(net "M_L_DQS_DP<1>")
	)
	(segment
		(start 45.012864 -141.826234)
		(end 45.183298 -141.6558)
		(width 0.14224)
		(layer "In4.Cu")
		(net "M_L_DQS_DP<1>")
	)
	(segment
		(start 45.210222 -142.899892)
		(end 45.390562 -142.719552)
		(width 0.14224)
		(layer "In4.Cu")
		(net "M_L_DQS_DP<1>")
	)
	(segment
		(start 66.245486 -94.591378)
		(end 66.245486 -94.536006)
		(width 0.0889)
		(layer "In4.Cu")
		(net "M_L_DQS_DP<1>")
	)
	(segment
		(start 50.029618 -115.15852)
		(end 50.736246 -115.865148)
		(width 0.14224)
		(layer "In4.Cu")
		(net "M_L_DQS_DP<1>")
	)
	(segment
		(start 66.229738 -94.607126)
		(end 66.245486 -94.591378)
		(width 0.0889)
		(layer "In4.Cu")
		(net "M_L_DQS_DP<1>")
	)
	(segment
		(start 67.680078 -93.101414)
		(end 68.642992 -93.101414)
		(width 0.0889)
		(layer "In4.Cu")
		(net "M_L_DQS_DP<1>")
	)
	(segment
		(start 53.007514 -111.726726)
		(end 57.442608 -107.291632)
		(width 0.14224)
		(layer "In4.Cu")
		(net "M_L_DQS_DP<1>")
	)
	(segment
		(start 66.245486 -94.536006)
		(end 67.680078 -93.101414)
		(width 0.0889)
		(layer "In4.Cu")
		(net "M_L_DQS_DP<1>")
	)
	(segment
		(start 68.642992 -93.101414)
		(end 69.353176 -92.39123)
		(width 0.0889)
		(layer "In4.Cu")
		(net "M_L_DQS_DP<1>")
	)
	(segment
		(start 45.387514 -144.61236)
		(end 45.847762 -144.152112)
		(width 0.14224)
		(layer "In4.Cu")
		(net "M_L_DQS_DP<1>")
	)
	(segment
		(start 49.243488 -115.902486)
		(end 49.243488 -115.491514)
		(width 0.14224)
		(layer "In4.Cu")
		(net "M_L_DQS_DP<1>")
	)
	(segment
		(start 51.102514 -113.632488)
		(end 51.552348 -113.182654)
		(width 0.14224)
		(layer "In4.Cu")
		(net "M_L_DQS_DP<1>")
	)
	(segment
		(start 53.007514 -112.038892)
		(end 53.007514 -111.726726)
		(width 0.14224)
		(layer "In4.Cu")
		(net "M_L_DQS_DP<1>")
	)
	(segment
		(start 45.012864 -143.037052)
		(end 45.150024 -142.899892)
		(width 0.14224)
		(layer "In4.Cu")
		(net "M_L_DQS_DP<1>")
	)
	(segment
		(start 50.736246 -115.865148)
		(end 51.27244 -115.865148)
		(width 0.14224)
		(layer "In4.Cu")
		(net "M_L_DQS_DP<1>")
	)
	(segment
		(start 45.393864 -140.541756)
		(end 46.169834 -139.765786)
		(width 0.14224)
		(layer "In4.Cu")
		(net "M_L_DQS_DP<1>")
	)
	(segment
		(start 45.390562 -142.4432)
		(end 45.212762 -142.2654)
		(width 0.14224)
		(layer "In4.Cu")
		(net "M_L_DQS_DP<1>")
	)
	(segment
		(start 48.024288 -119.748808)
		(end 50.259488 -117.513608)
		(width 0.14224)
		(layer "In4.Cu")
		(net "M_L_DQS_DP<1>")
	)
	(segment
		(start 45.822362 -141.4018)
		(end 45.822362 -140.976604)
		(width 0.14224)
		(layer "In4.Cu")
		(net "M_L_DQS_DP<1>")
	)
	(segment
		(start 57.442608 -107.291632)
		(end 57.442608 -104.658414)
		(width 0.14224)
		(layer "In4.Cu")
		(net "M_L_DQS_DP<1>")
	)
	(segment
		(start 63.411608 -97.425256)
		(end 66.229738 -94.607126)
		(width 0.14224)
		(layer "In4.Cu")
		(net "M_L_DQS_DP<1>")
	)
	(segment
		(start 51.27244 -115.865148)
		(end 51.880262 -115.257326)
		(width 0.14224)
		(layer "In4.Cu")
		(net "M_L_DQS_DP<1>")
	)
	(segment
		(start 48.024288 -126.326646)
		(end 48.024288 -119.748808)
		(width 0.14224)
		(layer "In4.Cu")
		(net "M_L_DQS_DP<1>")
	)
	(segment
		(start 45.183298 -141.6558)
		(end 45.568362 -141.6558)
		(width 0.14224)
		(layer "In4.Cu")
		(net "M_L_DQS_DP<1>")
	)
	(segment
		(start 70.59676 -89.86139)
		(end 70.629526 -89.86139)
		(width 0.0889)
		(layer "In4.Cu")
		(net "M_L_DQS_DP<1>")
	)
	(segment
		(start 45.847762 -144.152112)
		(end 45.847762 -143.7132)
		(width 0.14224)
		(layer "In4.Cu")
		(net "M_L_DQS_DP<1>")
	)
	(segment
		(start 51.880262 -114.721386)
		(end 51.102514 -113.943892)
		(width 0.14224)
		(layer "In4.Cu")
		(net "M_L_DQS_DP<1>")
	)
	(segment
		(start 45.212762 -142.2654)
		(end 45.127672 -142.2654)
		(width 0.14224)
		(layer "In4.Cu")
		(net "M_L_DQS_DP<1>")
	)
	(segment
		(start 51.864006 -113.182654)
		(end 52.641754 -113.960148)
		(width 0.14224)
		(layer "In4.Cu")
		(net "M_L_DQS_DP<1>")
	)
	(segment
		(start 45.847762 -143.7132)
		(end 45.593762 -143.4592)
		(width 0.14224)
		(layer "In4.Cu")
		(net "M_L_DQS_DP<1>")
	)
	(segment
		(start 45.127672 -142.2654)
		(end 45.012864 -142.150592)
		(width 0.14224)
		(layer "In4.Cu")
		(net "M_L_DQS_DP<1>")
	)
	(segment
		(start 51.552348 -113.182654)
		(end 51.864006 -113.182654)
		(width 0.14224)
		(layer "In4.Cu")
		(net "M_L_DQS_DP<1>")
	)
	(segment
		(start 45.593762 -143.4592)
		(end 45.208698 -143.4592)
		(width 0.14224)
		(layer "In4.Cu")
		(net "M_L_DQS_DP<1>")
	)
	(segment
		(start 53.17744 -113.960148)
		(end 53.785262 -113.352326)
		(width 0.14224)
		(layer "In4.Cu")
		(net "M_L_DQS_DP<1>")
	)
	(segment
		(start 69.353176 -90.649044)
		(end 69.406516 -90.556588)
		(width 0.0889)
		(layer "In4.Cu")
		(net "M_L_DQS_DP<1>")
	)
	(segment
		(start 45.390562 -142.719552)
		(end 45.390562 -142.4432)
		(width 0.14224)
		(layer "In4.Cu")
		(net "M_L_DQS_DP<1>")
	)
	(segment
		(start 45.387514 -140.541756)
		(end 45.393864 -140.541756)
		(width 0.14224)
		(layer "In4.Cu")
		(net "M_L_DQS_DP<1>")
	)
	(segment
		(start 69.353176 -92.39123)
		(end 69.353176 -90.649044)
		(width 0.0889)
		(layer "In4.Cu")
		(net "M_L_DQS_DP<1>")
	)
	(segment
		(start 62.573408 -99.527614)
		(end 62.573408 -98.26371)
		(width 0.14224)
		(layer "In4.Cu")
		(net "M_L_DQS_DP<1>")
	)
	(segment
		(start 45.150024 -142.899892)
		(end 45.210222 -142.899892)
		(width 0.14224)
		(layer "In4.Cu")
		(net "M_L_DQS_DP<1>")
	)
	(segment
		(start 69.74205 -90.356436)
		(end 69.774816 -90.356436)
		(width 0.0889)
		(layer "In4.Cu")
		(net "M_L_DQS_DP<1>")
	)
	(segment
		(start 50.259488 -117.513608)
		(end 50.259488 -116.918486)
		(width 0.14224)
		(layer "In4.Cu")
		(net "M_L_DQS_DP<1>")
	)
	(segment
		(start 62.573408 -98.26371)
		(end 63.411608 -97.42551)
		(width 0.14224)
		(layer "In4.Cu")
		(net "M_L_DQS_DP<1>")
	)
	(segment
		(start 45.822362 -140.976604)
		(end 45.387514 -140.541756)
		(width 0.14224)
		(layer "In4.Cu")
		(net "M_L_DQS_DP<1>")
	)
	(segment
		(start 46.169834 -128.1811)
		(end 48.024288 -126.326646)
		(width 0.14224)
		(layer "In4.Cu")
		(net "M_L_DQS_DP<1>")
	)
	(segment
		(start 49.576482 -115.15852)
		(end 50.029618 -115.15852)
		(width 0.14224)
		(layer "In4.Cu")
		(net "M_L_DQS_DP<1>")
	)
	(segment
		(start 63.411608 -97.42551)
		(end 63.411608 -97.425256)
		(width 0.14224)
		(layer "In4.Cu")
		(net "M_L_DQS_DP<1>")
	)
	(segment
		(start 51.102514 -113.943892)
		(end 51.102514 -113.632488)
		(width 0.14224)
		(layer "In4.Cu")
		(net "M_L_DQS_DP<1>")
	)
	(arc
		(start 69.406516 -90.556588)
		(mid 69.548199 -90.412784)
		(end 69.74205 -90.356436)
		(width 0.0889)
		(layer "In4.Cu")
		(net "M_L_DQS_DP<1>")
	)
	(arc
		(start 70.265036 -90.061288)
		(mid 70.405115 -89.918552)
		(end 70.59676 -89.86139)
		(width 0.0889)
		(layer "In4.Cu")
		(net "M_L_DQS_DP<1>")
	)
	(arc
		(start 70.629526 -89.86139)
		(mid 70.886348 -89.794089)
		(end 71.087742 -89.621106)
		(width 0.0889)
		(layer "In4.Cu")
		(net "M_L_DQS_DP<1>")
	)
	(arc
		(start 69.774816 -90.356436)
		(mid 70.058033 -90.272155)
		(end 70.265036 -90.061288)
		(width 0.0889)
		(layer "In4.Cu")
		(net "M_L_DQS_DP<1>")
	)
	(segment
		(start 83.530948 -99.371404)
		(end 83.45678 -99.476814)
		(width 0.0889)
		(layer "F.Cu")
		(net "M_L_DQS_DP<17>")
	)
	(segment
		(start 84.060792 -96.700086)
		(end 84.060792 -97.03181)
		(width 0.0889)
		(layer "F.Cu")
		(net "M_L_DQS_DP<17>")
	)
	(segment
		(start 83.455764 -99.478338)
		(end 83.428332 -99.50577)
		(width 0.0889)
		(layer "F.Cu")
		(net "M_L_DQS_DP<17>")
	)
	(segment
		(start 72.673464 -122.301)
		(end 72.546464 -122.428)
		(width 0.1651)
		(layer "F.Cu")
		(net "M_L_DQS_DP<17>")
	)
	(segment
		(start 71.760334 -144.956784)
		(end 72.142096 -145.338546)
		(width 0.1651)
		(layer "F.Cu")
		(net "M_L_DQS_DP<17>")
	)
	(segment
		(start 72.673464 -113.38306)
		(end 72.673464 -121.5517)
		(width 0.1651)
		(layer "F.Cu")
		(net "M_L_DQS_DP<17>")
	)
	(segment
		(start 72.559164 -121.666)
		(end 72.559164 -121.92)
		(width 0.1651)
		(layer "F.Cu")
		(net "M_L_DQS_DP<17>")
	)
	(segment
		(start 72.1995 -142.6718)
		(end 72.1995 -143.294354)
		(width 0.1651)
		(layer "F.Cu")
		(net "M_L_DQS_DP<17>")
	)
	(segment
		(start 82.739992 -104.10317)
		(end 78.91526 -107.927902)
		(width 0.1016)
		(layer "F.Cu")
		(net "M_L_DQS_DP<17>")
	)
	(segment
		(start 72.541384 -123.94692)
		(end 72.541384 -124.20092)
		(width 0.1651)
		(layer "F.Cu")
		(net "M_L_DQS_DP<17>")
	)
	(segment
		(start 83.548982 -97.395538)
		(end 83.542632 -97.406206)
		(width 0.0889)
		(layer "F.Cu")
		(net "M_L_DQS_DP<17>")
	)
	(segment
		(start 72.15378 -125.31725)
		(end 72.145906 -125.309376)
		(width 0.1651)
		(layer "F.Cu")
		(net "M_L_DQS_DP<17>")
	)
	(segment
		(start 83.553808 -98.377502)
		(end 83.548982 -98.386138)
		(width 0.0889)
		(layer "F.Cu")
		(net "M_L_DQS_DP<17>")
	)
	(segment
		(start 72.546464 -122.428)
		(end 72.546464 -122.682)
		(width 0.1651)
		(layer "F.Cu")
		(net "M_L_DQS_DP<17>")
	)
	(segment
		(start 72.673464 -123.063)
		(end 72.546464 -123.19)
		(width 0.1651)
		(layer "F.Cu")
		(net "M_L_DQS_DP<17>")
	)
	(segment
		(start 71.763382 -143.730472)
		(end 71.6788 -143.914368)
		(width 0.1651)
		(layer "F.Cu")
		(net "M_L_DQS_DP<17>")
	)
	(segment
		(start 83.45678 -99.476814)
		(end 83.455764 -99.478338)
		(width 0.0889)
		(layer "F.Cu")
		(net "M_L_DQS_DP<17>")
	)
	(segment
		(start 72.673464 -123.571)
		(end 72.673464 -123.81484)
		(width 0.1651)
		(layer "F.Cu")
		(net "M_L_DQS_DP<17>")
	)
	(segment
		(start 72.673464 -121.5517)
		(end 72.559164 -121.666)
		(width 0.1651)
		(layer "F.Cu")
		(net "M_L_DQS_DP<17>")
	)
	(segment
		(start 72.673464 -123.81484)
		(end 72.541384 -123.94692)
		(width 0.1651)
		(layer "F.Cu")
		(net "M_L_DQS_DP<17>")
	)
	(segment
		(start 72.418194 -125.31725)
		(end 72.15378 -125.31725)
		(width 0.1651)
		(layer "F.Cu")
		(net "M_L_DQS_DP<17>")
	)
	(segment
		(start 72.559164 -121.92)
		(end 72.673464 -122.0343)
		(width 0.1651)
		(layer "F.Cu")
		(net "M_L_DQS_DP<17>")
	)
	(segment
		(start 71.6788 -143.914368)
		(end 71.6788 -144.732502)
		(width 0.1651)
		(layer "F.Cu")
		(net "M_L_DQS_DP<17>")
	)
	(segment
		(start 78.91526 -107.927902)
		(end 78.128622 -107.927902)
		(width 0.1016)
		(layer "F.Cu")
		(net "M_L_DQS_DP<17>")
	)
	(segment
		(start 84.060792 -97.03181)
		(end 83.988402 -97.1042)
		(width 0.0889)
		(layer "F.Cu")
		(net "M_L_DQS_DP<17>")
	)
	(segment
		(start 72.673464 -122.809)
		(end 72.673464 -123.063)
		(width 0.1651)
		(layer "F.Cu")
		(net "M_L_DQS_DP<17>")
	)
	(segment
		(start 83.428332 -103.163878)
		(end 82.739992 -103.852218)
		(width 0.1016)
		(layer "F.Cu")
		(net "M_L_DQS_DP<17>")
	)
	(segment
		(start 72.1995 -143.294354)
		(end 71.763382 -143.730472)
		(width 0.1651)
		(layer "F.Cu")
		(net "M_L_DQS_DP<17>")
	)
	(segment
		(start 72.546464 -123.444)
		(end 72.673464 -123.571)
		(width 0.1651)
		(layer "F.Cu")
		(net "M_L_DQS_DP<17>")
	)
	(segment
		(start 83.428332 -100.492814)
		(end 83.428332 -103.163878)
		(width 0.1016)
		(layer "F.Cu")
		(net "M_L_DQS_DP<17>")
	)
	(segment
		(start 72.541384 -124.20092)
		(end 72.673464 -124.333)
		(width 0.1651)
		(layer "F.Cu")
		(net "M_L_DQS_DP<17>")
	)
	(segment
		(start 82.739992 -103.852218)
		(end 82.739992 -104.10317)
		(width 0.1016)
		(layer "F.Cu")
		(net "M_L_DQS_DP<17>")
	)
	(segment
		(start 72.546464 -122.682)
		(end 72.673464 -122.809)
		(width 0.1651)
		(layer "F.Cu")
		(net "M_L_DQS_DP<17>")
	)
	(segment
		(start 83.548982 -98.386138)
		(end 83.542632 -98.396806)
		(width 0.0889)
		(layer "F.Cu")
		(net "M_L_DQS_DP<17>")
	)
	(segment
		(start 72.673464 -124.333)
		(end 72.673464 -125.06198)
		(width 0.1651)
		(layer "F.Cu")
		(net "M_L_DQS_DP<17>")
	)
	(segment
		(start 72.673464 -122.0343)
		(end 72.673464 -122.301)
		(width 0.1651)
		(layer "F.Cu")
		(net "M_L_DQS_DP<17>")
	)
	(segment
		(start 78.128622 -107.927902)
		(end 77.772768 -108.283756)
		(width 0.1016)
		(layer "F.Cu")
		(net "M_L_DQS_DP<17>")
	)
	(segment
		(start 77.772768 -108.283756)
		(end 72.673464 -113.38306)
		(width 0.1651)
		(layer "F.Cu")
		(net "M_L_DQS_DP<17>")
	)
	(segment
		(start 72.546464 -123.19)
		(end 72.546464 -123.444)
		(width 0.1651)
		(layer "F.Cu")
		(net "M_L_DQS_DP<17>")
	)
	(segment
		(start 71.6788 -144.732502)
		(end 71.760334 -144.956784)
		(width 0.1651)
		(layer "F.Cu")
		(net "M_L_DQS_DP<17>")
	)
	(segment
		(start 72.673464 -125.06198)
		(end 72.418194 -125.31725)
		(width 0.1651)
		(layer "F.Cu")
		(net "M_L_DQS_DP<17>")
	)
	(segment
		(start 83.428332 -99.50577)
		(end 83.428332 -100.492814)
		(width 0.0889)
		(layer "F.Cu")
		(net "M_L_DQS_DP<17>")
	)
	(via
		(at 72.142096 -139.827)
		(size 0.508)
		(drill 0.254)
		(layers "F.Cu" "B.Cu")
		(net "M_L_DQS_DP<17>")
	)
	(via
		(at 72.142096 -145.338546)
		(size 0.508)
		(drill 0.254)
		(layers "F.Cu" "B.Cu")
		(net "M_L_DQS_DP<17>")
	)
	(via
		(at 72.145906 -125.309376)
		(size 0.508)
		(drill 0.254)
		(layers "F.Cu" "B.Cu")
		(net "M_L_DQS_DP<17>")
	)
	(arc
		(start 83.548982 -97.986088)
		(mid 83.602452 -98.181151)
		(end 83.553808 -98.377502)
		(width 0.0889)
		(layer "F.Cu")
		(net "M_L_DQS_DP<17>")
	)
	(arc
		(start 83.548982 -98.976688)
		(mid 83.597591 -99.17666)
		(end 83.530948 -99.371404)
		(width 0.0889)
		(layer "F.Cu")
		(net "M_L_DQS_DP<17>")
	)
	(arc
		(start 83.988402 -97.1042)
		(mid 83.977847 -97.105628)
		(end 83.96732 -97.107248)
		(width 0.0889)
		(layer "F.Cu")
		(net "M_L_DQS_DP<17>")
	)
	(arc
		(start 83.542632 -98.396806)
		(mid 83.469834 -98.687569)
		(end 83.548982 -98.976688)
		(width 0.0889)
		(layer "F.Cu")
		(net "M_L_DQS_DP<17>")
	)
	(arc
		(start 83.542632 -97.406206)
		(mid 83.469834 -97.696969)
		(end 83.548982 -97.986088)
		(width 0.0889)
		(layer "F.Cu")
		(net "M_L_DQS_DP<17>")
	)
	(arc
		(start 83.96732 -97.107248)
		(mid 83.725559 -97.204111)
		(end 83.548982 -97.395538)
		(width 0.0889)
		(layer "F.Cu")
		(net "M_L_DQS_DP<17>")
	)
	(segment
		(start 71.753476 -140.21562)
		(end 72.142096 -139.827)
		(width 0.1651)
		(layer "B.Cu")
		(net "M_L_DQS_DP<17>")
	)
	(segment
		(start 72.1995 -142.477236)
		(end 72.1995 -141.859254)
		(width 0.1651)
		(layer "B.Cu")
		(net "M_L_DQS_DP<17>")
	)
	(segment
		(start 71.743316 -141.40307)
		(end 71.6661 -141.270736)
		(width 0.1651)
		(layer "B.Cu")
		(net "M_L_DQS_DP<17>")
	)
	(segment
		(start 71.6661 -140.375132)
		(end 71.753476 -140.21562)
		(width 0.1651)
		(layer "B.Cu")
		(net "M_L_DQS_DP<17>")
	)
	(segment
		(start 72.1995 -141.859254)
		(end 71.743316 -141.40307)
		(width 0.1651)
		(layer "B.Cu")
		(net "M_L_DQS_DP<17>")
	)
	(segment
		(start 71.6661 -141.270736)
		(end 71.6661 -140.375132)
		(width 0.1651)
		(layer "B.Cu")
		(net "M_L_DQS_DP<17>")
	)
	(segment
		(start 72.142096 -145.338546)
		(end 71.637144 -144.833594)
		(width 0.14224)
		(layer "In9.Cu")
		(net "M_L_DQS_DP<17>")
	)
	(segment
		(start 71.637144 -144.833594)
		(end 71.637144 -140.2588)
		(width 0.14224)
		(layer "In9.Cu")
		(net "M_L_DQS_DP<17>")
	)
	(segment
		(start 72.068944 -139.827)
		(end 72.142096 -139.827)
		(width 0.14224)
		(layer "In9.Cu")
		(net "M_L_DQS_DP<17>")
	)
	(segment
		(start 71.637144 -140.2588)
		(end 72.068944 -139.827)
		(width 0.14224)
		(layer "In9.Cu")
		(net "M_L_DQS_DP<17>")
	)
	(segment
		(start 72.655176 -139.321286)
		(end 72.149462 -139.827)
		(width 0.14224)
		(layer "In11.Cu")
		(net "M_L_DQS_DP<17>")
	)
	(segment
		(start 72.149462 -139.827)
		(end 72.142096 -139.827)
		(width 0.14224)
		(layer "In11.Cu")
		(net "M_L_DQS_DP<17>")
	)
	(segment
		(start 71.707248 -125.755908)
		(end 71.707248 -127.524764)
		(width 0.14224)
		(layer "In11.Cu")
		(net "M_L_DQS_DP<17>")
	)
	(segment
		(start 72.145906 -125.31725)
		(end 71.707248 -125.755908)
		(width 0.14224)
		(layer "In11.Cu")
		(net "M_L_DQS_DP<17>")
	)
	(segment
		(start 71.707248 -127.524764)
		(end 72.655176 -128.472692)
		(width 0.14224)
		(layer "In11.Cu")
		(net "M_L_DQS_DP<17>")
	)
	(segment
		(start 72.655176 -128.472692)
		(end 72.655176 -139.321286)
		(width 0.14224)
		(layer "In11.Cu")
		(net "M_L_DQS_DP<17>")
	)
	(segment
		(start 72.145906 -125.309376)
		(end 72.145906 -125.31725)
		(width 0.14224)
		(layer "In11.Cu")
		(net "M_L_DQS_DP<17>")
	)
	(segment
		(start 146.149568 -142.6718)
		(end 146.149568 -143.294354)
		(width 0.1651)
		(layer "F.Cu")
		(net "M_L_DQS_DP<16>")
	)
	(segment
		(start 120.787668 -93.052138)
		(end 121.359168 -93.052138)
		(width 0.1651)
		(layer "F.Cu")
		(net "M_L_DQS_DP<16>")
	)
	(segment
		(start 145.71345 -143.730472)
		(end 145.628868 -143.914368)
		(width 0.1651)
		(layer "F.Cu")
		(net "M_L_DQS_DP<16>")
	)
	(segment
		(start 145.628868 -144.732502)
		(end 145.710402 -144.956784)
		(width 0.1651)
		(layer "F.Cu")
		(net "M_L_DQS_DP<16>")
	)
	(segment
		(start 145.710402 -144.956784)
		(end 146.092164 -145.338546)
		(width 0.1651)
		(layer "F.Cu")
		(net "M_L_DQS_DP<16>")
	)
	(segment
		(start 145.628868 -143.914368)
		(end 145.628868 -144.732502)
		(width 0.1651)
		(layer "F.Cu")
		(net "M_L_DQS_DP<16>")
	)
	(segment
		(start 146.149568 -143.294354)
		(end 145.71345 -143.730472)
		(width 0.1651)
		(layer "F.Cu")
		(net "M_L_DQS_DP<16>")
	)
	(via
		(at 121.359168 -93.052138)
		(size 0.508)
		(drill 0.254)
		(layers "F.Cu" "B.Cu")
		(net "M_L_DQS_DP<16>")
	)
	(via
		(at 146.092164 -145.338546)
		(size 0.508)
		(drill 0.254)
		(layers "F.Cu" "B.Cu")
		(net "M_L_DQS_DP<16>")
	)
	(via
		(at 146.092164 -139.827)
		(size 0.508)
		(drill 0.254)
		(layers "F.Cu" "B.Cu")
		(net "M_L_DQS_DP<16>")
	)
	(segment
		(start 146.149568 -141.859254)
		(end 145.693384 -141.40307)
		(width 0.1651)
		(layer "B.Cu")
		(net "M_L_DQS_DP<16>")
	)
	(segment
		(start 146.149568 -142.477236)
		(end 146.149568 -141.859254)
		(width 0.1651)
		(layer "B.Cu")
		(net "M_L_DQS_DP<16>")
	)
	(segment
		(start 145.616168 -140.375132)
		(end 145.703544 -140.21562)
		(width 0.1651)
		(layer "B.Cu")
		(net "M_L_DQS_DP<16>")
	)
	(segment
		(start 145.703544 -140.21562)
		(end 146.092164 -139.827)
		(width 0.1651)
		(layer "B.Cu")
		(net "M_L_DQS_DP<16>")
	)
	(segment
		(start 145.616168 -141.270736)
		(end 145.616168 -140.375132)
		(width 0.1651)
		(layer "B.Cu")
		(net "M_L_DQS_DP<16>")
	)
	(segment
		(start 145.693384 -141.40307)
		(end 145.616168 -141.270736)
		(width 0.1651)
		(layer "B.Cu")
		(net "M_L_DQS_DP<16>")
	)
	(segment
		(start 124.401072 -106.432604)
		(end 124.401072 -106.879898)
		(width 0.0889)
		(layer "In4.Cu")
		(net "M_L_DQS_DP<16>")
	)
	(segment
		(start 146.605244 -137.24128)
		(end 146.605244 -137.535666)
		(width 0.14224)
		(layer "In4.Cu")
		(net "M_L_DQS_DP<16>")
	)
	(segment
		(start 123.058428 -105.529888)
		(end 123.091194 -105.529888)
		(width 0.0889)
		(layer "In4.Cu")
		(net "M_L_DQS_DP<16>")
	)
	(segment
		(start 146.48815 -137.124186)
		(end 146.605244 -137.24128)
		(width 0.14224)
		(layer "In4.Cu")
		(net "M_L_DQS_DP<16>")
	)
	(segment
		(start 146.605244 -137.535666)
		(end 146.447764 -137.693146)
		(width 0.14224)
		(layer "In4.Cu")
		(net "M_L_DQS_DP<16>")
	)
	(segment
		(start 121.705878 -103.158036)
		(end 121.699528 -103.168704)
		(width 0.0889)
		(layer "In4.Cu")
		(net "M_L_DQS_DP<16>")
	)
	(segment
		(start 145.587212 -140.2588)
		(end 145.587212 -144.833594)
		(width 0.14224)
		(layer "In4.Cu")
		(net "M_L_DQS_DP<16>")
	)
	(segment
		(start 146.371564 -139.827)
		(end 146.092164 -139.827)
		(width 0.14224)
		(layer "In4.Cu")
		(net "M_L_DQS_DP<16>")
	)
	(segment
		(start 121.341388 -102.558088)
		(end 121.374154 -102.558088)
		(width 0.0889)
		(layer "In4.Cu")
		(net "M_L_DQS_DP<16>")
	)
	(segment
		(start 146.605244 -139.59332)
		(end 146.371564 -139.827)
		(width 0.14224)
		(layer "In4.Cu")
		(net "M_L_DQS_DP<16>")
	)
	(segment
		(start 124.401072 -106.879898)
		(end 124.751338 -107.230164)
		(width 0.0889)
		(layer "In4.Cu")
		(net "M_L_DQS_DP<16>")
	)
	(segment
		(start 120.841008 -94.327472)
		(end 120.847358 -94.337886)
		(width 0.0889)
		(layer "In4.Cu")
		(net "M_L_DQS_DP<16>")
	)
	(segment
		(start 146.605244 -125.670056)
		(end 146.605244 -136.753092)
		(width 0.14224)
		(layer "In4.Cu")
		(net "M_L_DQS_DP<16>")
	)
	(segment
		(start 145.587212 -144.833594)
		(end 146.092164 -145.338546)
		(width 0.14224)
		(layer "In4.Cu")
		(net "M_L_DQS_DP<16>")
	)
	(segment
		(start 146.447764 -137.947146)
		(end 146.605244 -138.104626)
		(width 0.14224)
		(layer "In4.Cu")
		(net "M_L_DQS_DP<16>")
	)
	(segment
		(start 146.092164 -139.827)
		(end 146.019012 -139.827)
		(width 0.14224)
		(layer "In4.Cu")
		(net "M_L_DQS_DP<16>")
	)
	(segment
		(start 124.281438 -106.22534)
		(end 124.401072 -106.432604)
		(width 0.0889)
		(layer "In4.Cu")
		(net "M_L_DQS_DP<16>")
	)
	(segment
		(start 121.710704 -103.1494)
		(end 121.705878 -103.158036)
		(width 0.0889)
		(layer "In4.Cu")
		(net "M_L_DQS_DP<16>")
	)
	(segment
		(start 125.618748 -108.1532)
		(end 129.088388 -108.1532)
		(width 0.14224)
		(layer "In4.Cu")
		(net "M_L_DQS_DP<16>")
	)
	(segment
		(start 123.921774 -106.025188)
		(end 123.939554 -106.025188)
		(width 0.0889)
		(layer "In4.Cu")
		(net "M_L_DQS_DP<16>")
	)
	(segment
		(start 124.766578 -107.30103)
		(end 125.618748 -108.1532)
		(width 0.14224)
		(layer "In4.Cu")
		(net "M_L_DQS_DP<16>")
	)
	(segment
		(start 121.359168 -93.052138)
		(end 121.359168 -93.390212)
		(width 0.0889)
		(layer "In4.Cu")
		(net "M_L_DQS_DP<16>")
	)
	(segment
		(start 120.838468 -100.266246)
		(end 120.847358 -100.281486)
		(width 0.0889)
		(layer "In4.Cu")
		(net "M_L_DQS_DP<16>")
	)
	(segment
		(start 146.447764 -137.693146)
		(end 146.447764 -137.947146)
		(width 0.14224)
		(layer "In4.Cu")
		(net "M_L_DQS_DP<16>")
	)
	(segment
		(start 146.605244 -136.753092)
		(end 146.48815 -136.870186)
		(width 0.14224)
		(layer "In4.Cu")
		(net "M_L_DQS_DP<16>")
	)
	(segment
		(start 146.605244 -138.358626)
		(end 146.447764 -138.516106)
		(width 0.14224)
		(layer "In4.Cu")
		(net "M_L_DQS_DP<16>")
	)
	(segment
		(start 120.838468 -99.275646)
		(end 120.847358 -99.290886)
		(width 0.0889)
		(layer "In4.Cu")
		(net "M_L_DQS_DP<16>")
	)
	(segment
		(start 146.605244 -138.927586)
		(end 146.605244 -139.59332)
		(width 0.14224)
		(layer "In4.Cu")
		(net "M_L_DQS_DP<16>")
	)
	(segment
		(start 120.838468 -101.256846)
		(end 120.847358 -101.272086)
		(width 0.0889)
		(layer "In4.Cu")
		(net "M_L_DQS_DP<16>")
	)
	(segment
		(start 146.019012 -139.827)
		(end 145.587212 -140.2588)
		(width 0.14224)
		(layer "In4.Cu")
		(net "M_L_DQS_DP<16>")
	)
	(segment
		(start 124.751338 -107.230164)
		(end 124.751084 -107.285536)
		(width 0.0889)
		(layer "In4.Cu")
		(net "M_L_DQS_DP<16>")
	)
	(segment
		(start 124.751084 -107.285536)
		(end 124.766578 -107.30103)
		(width 0.0889)
		(layer "In4.Cu")
		(net "M_L_DQS_DP<16>")
	)
	(segment
		(start 122.196098 -105.034334)
		(end 122.228864 -105.034334)
		(width 0.0889)
		(layer "In4.Cu")
		(net "M_L_DQS_DP<16>")
	)
	(segment
		(start 121.359168 -93.390212)
		(end 121.294144 -93.455236)
		(width 0.0889)
		(layer "In4.Cu")
		(net "M_L_DQS_DP<16>")
	)
	(segment
		(start 129.088388 -108.1532)
		(end 146.605244 -125.670056)
		(width 0.14224)
		(layer "In4.Cu")
		(net "M_L_DQS_DP<16>")
	)
	(segment
		(start 121.710704 -104.14)
		(end 121.705878 -104.148636)
		(width 0.0889)
		(layer "In4.Cu")
		(net "M_L_DQS_DP<16>")
	)
	(segment
		(start 121.705878 -104.148636)
		(end 121.699528 -104.159304)
		(width 0.0889)
		(layer "In4.Cu")
		(net "M_L_DQS_DP<16>")
	)
	(segment
		(start 146.447764 -138.516106)
		(end 146.447764 -138.770106)
		(width 0.14224)
		(layer "In4.Cu")
		(net "M_L_DQS_DP<16>")
	)
	(segment
		(start 146.48815 -136.870186)
		(end 146.48815 -137.124186)
		(width 0.14224)
		(layer "In4.Cu")
		(net "M_L_DQS_DP<16>")
	)
	(segment
		(start 146.605244 -138.104626)
		(end 146.605244 -138.358626)
		(width 0.14224)
		(layer "In4.Cu")
		(net "M_L_DQS_DP<16>")
	)
	(segment
		(start 146.447764 -138.770106)
		(end 146.605244 -138.927586)
		(width 0.14224)
		(layer "In4.Cu")
		(net "M_L_DQS_DP<16>")
	)
	(arc
		(start 120.847358 -96.718882)
		(mid 120.768227 -97.014284)
		(end 120.847358 -97.309686)
		(width 0.0889)
		(layer "In4.Cu")
		(net "M_L_DQS_DP<16>")
	)
	(arc
		(start 120.847358 -98.700082)
		(mid 120.82204 -98.749049)
		(end 120.801384 -98.800158)
		(width 0.0889)
		(layer "In4.Cu")
		(net "M_L_DQS_DP<16>")
	)
	(arc
		(start 120.847358 -101.671882)
		(mid 120.84303 -102.255058)
		(end 121.341388 -102.558088)
		(width 0.0889)
		(layer "In4.Cu")
		(net "M_L_DQS_DP<16>")
	)
	(arc
		(start 121.374154 -102.558088)
		(mid 121.707072 -102.760079)
		(end 121.710704 -103.1494)
		(width 0.0889)
		(layer "In4.Cu")
		(net "M_L_DQS_DP<16>")
	)
	(arc
		(start 120.801384 -98.800158)
		(mid 120.769886 -99.041796)
		(end 120.838468 -99.275646)
		(width 0.0889)
		(layer "In4.Cu")
		(net "M_L_DQS_DP<16>")
	)
	(arc
		(start 120.847358 -97.709482)
		(mid 120.768227 -98.004884)
		(end 120.847358 -98.300286)
		(width 0.0889)
		(layer "In4.Cu")
		(net "M_L_DQS_DP<16>")
	)
	(arc
		(start 120.847358 -101.272086)
		(mid 120.900891 -101.471984)
		(end 120.847358 -101.671882)
		(width 0.0889)
		(layer "In4.Cu")
		(net "M_L_DQS_DP<16>")
	)
	(arc
		(start 123.422918 -105.729786)
		(mid 123.633631 -105.942865)
		(end 123.921774 -106.025188)
		(width 0.0889)
		(layer "In4.Cu")
		(net "M_L_DQS_DP<16>")
	)
	(arc
		(start 120.847358 -94.737682)
		(mid 120.768227 -95.033084)
		(end 120.847358 -95.328486)
		(width 0.0889)
		(layer "In4.Cu")
		(net "M_L_DQS_DP<16>")
	)
	(arc
		(start 120.847358 -100.281486)
		(mid 120.900891 -100.481384)
		(end 120.847358 -100.681282)
		(width 0.0889)
		(layer "In4.Cu")
		(net "M_L_DQS_DP<16>")
	)
	(arc
		(start 120.847358 -95.328486)
		(mid 120.900857 -95.528384)
		(end 120.847358 -95.728282)
		(width 0.0889)
		(layer "In4.Cu")
		(net "M_L_DQS_DP<16>")
	)
	(arc
		(start 121.699528 -104.159304)
		(mid 121.703559 -104.735486)
		(end 122.196098 -105.034334)
		(width 0.0889)
		(layer "In4.Cu")
		(net "M_L_DQS_DP<16>")
	)
	(arc
		(start 122.228864 -105.034334)
		(mid 122.422714 -105.090684)
		(end 122.564398 -105.234486)
		(width 0.0889)
		(layer "In4.Cu")
		(net "M_L_DQS_DP<16>")
	)
	(arc
		(start 120.847358 -98.300286)
		(mid 120.900857 -98.500184)
		(end 120.847358 -98.700082)
		(width 0.0889)
		(layer "In4.Cu")
		(net "M_L_DQS_DP<16>")
	)
	(arc
		(start 120.847358 -100.681282)
		(mid 120.768169 -100.967897)
		(end 120.838468 -101.256846)
		(width 0.0889)
		(layer "In4.Cu")
		(net "M_L_DQS_DP<16>")
	)
	(arc
		(start 120.847358 -96.319086)
		(mid 120.900857 -96.518984)
		(end 120.847358 -96.718882)
		(width 0.0889)
		(layer "In4.Cu")
		(net "M_L_DQS_DP<16>")
	)
	(arc
		(start 120.847358 -97.309686)
		(mid 120.900857 -97.509584)
		(end 120.847358 -97.709482)
		(width 0.0889)
		(layer "In4.Cu")
		(net "M_L_DQS_DP<16>")
	)
	(arc
		(start 120.847358 -94.337886)
		(mid 120.900857 -94.537784)
		(end 120.847358 -94.737682)
		(width 0.0889)
		(layer "In4.Cu")
		(net "M_L_DQS_DP<16>")
	)
	(arc
		(start 120.847358 -99.290886)
		(mid 120.900891 -99.490784)
		(end 120.847358 -99.690682)
		(width 0.0889)
		(layer "In4.Cu")
		(net "M_L_DQS_DP<16>")
	)
	(arc
		(start 120.847358 -95.728282)
		(mid 120.768227 -96.023684)
		(end 120.847358 -96.319086)
		(width 0.0889)
		(layer "In4.Cu")
		(net "M_L_DQS_DP<16>")
	)
	(arc
		(start 121.294144 -93.455236)
		(mid 120.834616 -93.770284)
		(end 120.841008 -94.327472)
		(width 0.0889)
		(layer "In4.Cu")
		(net "M_L_DQS_DP<16>")
	)
	(arc
		(start 123.939554 -106.025188)
		(mid 124.136989 -106.080011)
		(end 124.281438 -106.22534)
		(width 0.0889)
		(layer "In4.Cu")
		(net "M_L_DQS_DP<16>")
	)
	(arc
		(start 122.564398 -105.234486)
		(mid 122.773006 -105.446418)
		(end 123.058428 -105.529888)
		(width 0.0889)
		(layer "In4.Cu")
		(net "M_L_DQS_DP<16>")
	)
	(arc
		(start 121.705878 -103.748586)
		(mid 121.759348 -103.943649)
		(end 121.710704 -104.14)
		(width 0.0889)
		(layer "In4.Cu")
		(net "M_L_DQS_DP<16>")
	)
	(arc
		(start 123.091194 -105.529888)
		(mid 123.282836 -105.587054)
		(end 123.422918 -105.729786)
		(width 0.0889)
		(layer "In4.Cu")
		(net "M_L_DQS_DP<16>")
	)
	(arc
		(start 120.847358 -99.690682)
		(mid 120.768169 -99.977297)
		(end 120.838468 -100.266246)
		(width 0.0889)
		(layer "In4.Cu")
		(net "M_L_DQS_DP<16>")
	)
	(arc
		(start 121.699528 -103.168704)
		(mid 121.62673 -103.459467)
		(end 121.705878 -103.748586)
		(width 0.0889)
		(layer "In4.Cu")
		(net "M_L_DQS_DP<16>")
	)
	(segment
		(start 133.220968 -110.05058)
		(end 133.220968 -110.236)
		(width 0.1016)
		(layer "F.Cu")
		(net "M_L_DQS_DP<15>")
	)
	(segment
		(start 134.828788 -111.774478)
		(end 135.008366 -111.954056)
		(width 0.1651)
		(layer "F.Cu")
		(net "M_L_DQS_DP<15>")
	)
	(segment
		(start 136.799574 -142.6718)
		(end 136.799574 -143.294354)
		(width 0.1651)
		(layer "F.Cu")
		(net "M_L_DQS_DP<15>")
	)
	(segment
		(start 121.904252 -107.048554)
		(end 130.218942 -107.048554)
		(width 0.1016)
		(layer "F.Cu")
		(net "M_L_DQS_DP<15>")
	)
	(segment
		(start 137.132568 -122.130312)
		(end 137.227564 -122.225308)
		(width 0.1651)
		(layer "F.Cu")
		(net "M_L_DQS_DP<15>")
	)
	(segment
		(start 134.648956 -111.774478)
		(end 134.828788 -111.774478)
		(width 0.1651)
		(layer "F.Cu")
		(net "M_L_DQS_DP<15>")
	)
	(segment
		(start 136.086342 -113.032032)
		(end 136.086342 -113.21161)
		(width 0.1651)
		(layer "F.Cu")
		(net "M_L_DQS_DP<15>")
	)
	(segment
		(start 137.227564 -124.793502)
		(end 136.74598 -125.275086)
		(width 0.1651)
		(layer "F.Cu")
		(net "M_L_DQS_DP<15>")
	)
	(segment
		(start 136.26592 -113.391442)
		(end 136.445752 -113.391442)
		(width 0.1651)
		(layer "F.Cu")
		(net "M_L_DQS_DP<15>")
	)
	(segment
		(start 134.469378 -111.415068)
		(end 134.469378 -111.594646)
		(width 0.1651)
		(layer "F.Cu")
		(net "M_L_DQS_DP<15>")
	)
	(segment
		(start 134.2898 -111.23549)
		(end 134.469378 -111.415068)
		(width 0.1651)
		(layer "F.Cu")
		(net "M_L_DQS_DP<15>")
	)
	(segment
		(start 137.227564 -122.225308)
		(end 137.227564 -124.793502)
		(width 0.1651)
		(layer "F.Cu")
		(net "M_L_DQS_DP<15>")
	)
	(segment
		(start 130.218942 -107.048554)
		(end 133.220968 -110.05058)
		(width 0.1016)
		(layer "F.Cu")
		(net "M_L_DQS_DP<15>")
	)
	(segment
		(start 120.432068 -105.430828)
		(end 120.432068 -105.57637)
		(width 0.1016)
		(layer "F.Cu")
		(net "M_L_DQS_DP<15>")
	)
	(segment
		(start 133.750812 -110.696502)
		(end 133.93039 -110.87608)
		(width 0.1651)
		(layer "F.Cu")
		(net "M_L_DQS_DP<15>")
	)
	(segment
		(start 133.93039 -110.87608)
		(end 133.93039 -111.055658)
		(width 0.1651)
		(layer "F.Cu")
		(net "M_L_DQS_DP<15>")
	)
	(segment
		(start 120.089168 -105.087928)
		(end 120.432068 -105.430828)
		(width 0.0889)
		(layer "F.Cu")
		(net "M_L_DQS_DP<15>")
	)
	(segment
		(start 135.726932 -112.852454)
		(end 135.906764 -112.852454)
		(width 0.1651)
		(layer "F.Cu")
		(net "M_L_DQS_DP<15>")
	)
	(segment
		(start 134.469378 -111.594646)
		(end 134.648956 -111.774478)
		(width 0.1651)
		(layer "F.Cu")
		(net "M_L_DQS_DP<15>")
	)
	(segment
		(start 120.787668 -99.986338)
		(end 120.787668 -100.317808)
		(width 0.0889)
		(layer "F.Cu")
		(net "M_L_DQS_DP<15>")
	)
	(segment
		(start 133.220968 -110.236)
		(end 133.68147 -110.696502)
		(width 0.1016)
		(layer "F.Cu")
		(net "M_L_DQS_DP<15>")
	)
	(segment
		(start 135.187944 -112.313466)
		(end 135.367776 -112.313466)
		(width 0.1651)
		(layer "F.Cu")
		(net "M_L_DQS_DP<15>")
	)
	(segment
		(start 135.547354 -112.493044)
		(end 135.547354 -112.672622)
		(width 0.1651)
		(layer "F.Cu")
		(net "M_L_DQS_DP<15>")
	)
	(segment
		(start 135.008366 -112.133634)
		(end 135.187944 -112.313466)
		(width 0.1651)
		(layer "F.Cu")
		(net "M_L_DQS_DP<15>")
	)
	(segment
		(start 136.278874 -143.914368)
		(end 136.278874 -144.732502)
		(width 0.1651)
		(layer "F.Cu")
		(net "M_L_DQS_DP<15>")
	)
	(segment
		(start 135.547354 -112.672622)
		(end 135.726932 -112.852454)
		(width 0.1651)
		(layer "F.Cu")
		(net "M_L_DQS_DP<15>")
	)
	(segment
		(start 120.272556 -102.66426)
		(end 120.202452 -102.814882)
		(width 0.0889)
		(layer "F.Cu")
		(net "M_L_DQS_DP<15>")
	)
	(segment
		(start 120.089168 -103.923846)
		(end 120.089168 -105.087928)
		(width 0.0889)
		(layer "F.Cu")
		(net "M_L_DQS_DP<15>")
	)
	(segment
		(start 136.360408 -144.956784)
		(end 136.74217 -145.338546)
		(width 0.1651)
		(layer "F.Cu")
		(net "M_L_DQS_DP<15>")
	)
	(segment
		(start 120.787668 -100.317808)
		(end 120.715278 -100.390198)
		(width 0.0889)
		(layer "F.Cu")
		(net "M_L_DQS_DP<15>")
	)
	(segment
		(start 120.432068 -105.57637)
		(end 121.904252 -107.048554)
		(width 0.1016)
		(layer "F.Cu")
		(net "M_L_DQS_DP<15>")
	)
	(segment
		(start 136.799574 -143.294354)
		(end 136.363456 -143.730472)
		(width 0.1651)
		(layer "F.Cu")
		(net "M_L_DQS_DP<15>")
	)
	(segment
		(start 137.132568 -114.078258)
		(end 137.132568 -122.130312)
		(width 0.1651)
		(layer "F.Cu")
		(net "M_L_DQS_DP<15>")
	)
	(segment
		(start 135.367776 -112.313466)
		(end 135.547354 -112.493044)
		(width 0.1651)
		(layer "F.Cu")
		(net "M_L_DQS_DP<15>")
	)
	(segment
		(start 133.93039 -111.055658)
		(end 134.109968 -111.23549)
		(width 0.1651)
		(layer "F.Cu")
		(net "M_L_DQS_DP<15>")
	)
	(segment
		(start 135.906764 -112.852454)
		(end 136.086342 -113.032032)
		(width 0.1651)
		(layer "F.Cu")
		(net "M_L_DQS_DP<15>")
	)
	(segment
		(start 136.363456 -143.730472)
		(end 136.278874 -143.914368)
		(width 0.1651)
		(layer "F.Cu")
		(net "M_L_DQS_DP<15>")
	)
	(segment
		(start 134.109968 -111.23549)
		(end 134.2898 -111.23549)
		(width 0.1651)
		(layer "F.Cu")
		(net "M_L_DQS_DP<15>")
	)
	(segment
		(start 120.275858 -101.672136)
		(end 120.269508 -101.682804)
		(width 0.0889)
		(layer "F.Cu")
		(net "M_L_DQS_DP<15>")
	)
	(segment
		(start 133.68147 -110.696502)
		(end 133.750812 -110.696502)
		(width 0.1016)
		(layer "F.Cu")
		(net "M_L_DQS_DP<15>")
	)
	(segment
		(start 136.086342 -113.21161)
		(end 136.26592 -113.391442)
		(width 0.1651)
		(layer "F.Cu")
		(net "M_L_DQS_DP<15>")
	)
	(segment
		(start 120.202452 -103.810562)
		(end 120.089168 -103.923846)
		(width 0.0889)
		(layer "F.Cu")
		(net "M_L_DQS_DP<15>")
	)
	(segment
		(start 136.445752 -113.391442)
		(end 137.132568 -114.078258)
		(width 0.1651)
		(layer "F.Cu")
		(net "M_L_DQS_DP<15>")
	)
	(segment
		(start 135.008366 -111.954056)
		(end 135.008366 -112.133634)
		(width 0.1651)
		(layer "F.Cu")
		(net "M_L_DQS_DP<15>")
	)
	(segment
		(start 120.202452 -102.814882)
		(end 120.202452 -103.810562)
		(width 0.0889)
		(layer "F.Cu")
		(net "M_L_DQS_DP<15>")
	)
	(segment
		(start 136.278874 -144.732502)
		(end 136.360408 -144.956784)
		(width 0.1651)
		(layer "F.Cu")
		(net "M_L_DQS_DP<15>")
	)
	(segment
		(start 120.275858 -102.66299)
		(end 120.272556 -102.66426)
		(width 0.0889)
		(layer "F.Cu")
		(net "M_L_DQS_DP<15>")
	)
	(via
		(at 136.74217 -145.338546)
		(size 0.508)
		(drill 0.254)
		(layers "F.Cu" "B.Cu")
		(net "M_L_DQS_DP<15>")
	)
	(via
		(at 136.74598 -125.275086)
		(size 0.508)
		(drill 0.254)
		(layers "F.Cu" "B.Cu")
		(net "M_L_DQS_DP<15>")
	)
	(via
		(at 136.74217 -139.827)
		(size 0.508)
		(drill 0.254)
		(layers "F.Cu" "B.Cu")
		(net "M_L_DQS_DP<15>")
	)
	(arc
		(start 120.694196 -100.393246)
		(mid 120.25395 -100.722705)
		(end 120.275858 -101.272086)
		(width 0.0889)
		(layer "F.Cu")
		(net "M_L_DQS_DP<15>")
	)
	(arc
		(start 120.269508 -101.682804)
		(mid 120.196588 -101.973821)
		(end 120.275858 -102.263194)
		(width 0.0889)
		(layer "F.Cu")
		(net "M_L_DQS_DP<15>")
	)
	(arc
		(start 120.715278 -100.390198)
		(mid 120.704723 -100.391626)
		(end 120.694196 -100.393246)
		(width 0.0889)
		(layer "F.Cu")
		(net "M_L_DQS_DP<15>")
	)
	(arc
		(start 120.275858 -102.263194)
		(mid 120.329391 -102.463092)
		(end 120.275858 -102.66299)
		(width 0.0889)
		(layer "F.Cu")
		(net "M_L_DQS_DP<15>")
	)
	(arc
		(start 120.275858 -101.272086)
		(mid 120.329552 -101.472128)
		(end 120.275858 -101.672136)
		(width 0.0889)
		(layer "F.Cu")
		(net "M_L_DQS_DP<15>")
	)
	(segment
		(start 136.35355 -140.21562)
		(end 136.74217 -139.827)
		(width 0.1651)
		(layer "B.Cu")
		(net "M_L_DQS_DP<15>")
	)
	(segment
		(start 136.266174 -140.375132)
		(end 136.35355 -140.21562)
		(width 0.1651)
		(layer "B.Cu")
		(net "M_L_DQS_DP<15>")
	)
	(segment
		(start 136.266174 -141.270736)
		(end 136.266174 -140.375132)
		(width 0.1651)
		(layer "B.Cu")
		(net "M_L_DQS_DP<15>")
	)
	(segment
		(start 136.799574 -142.477236)
		(end 136.799574 -141.859254)
		(width 0.1651)
		(layer "B.Cu")
		(net "M_L_DQS_DP<15>")
	)
	(segment
		(start 136.34339 -141.40307)
		(end 136.266174 -141.270736)
		(width 0.1651)
		(layer "B.Cu")
		(net "M_L_DQS_DP<15>")
	)
	(segment
		(start 136.799574 -141.859254)
		(end 136.34339 -141.40307)
		(width 0.1651)
		(layer "B.Cu")
		(net "M_L_DQS_DP<15>")
	)
	(segment
		(start 137.25525 -128.658366)
		(end 137.25525 -139.363196)
		(width 0.14224)
		(layer "In4.Cu")
		(net "M_L_DQS_DP<15>")
	)
	(segment
		(start 137.25525 -139.363196)
		(end 136.791446 -139.827)
		(width 0.14224)
		(layer "In4.Cu")
		(net "M_L_DQS_DP<15>")
	)
	(segment
		(start 136.26846 -126.847092)
		(end 136.685528 -127.26416)
		(width 0.14224)
		(layer "In4.Cu")
		(net "M_L_DQS_DP<15>")
	)
	(segment
		(start 136.791446 -139.827)
		(end 136.74217 -139.827)
		(width 0.14224)
		(layer "In4.Cu")
		(net "M_L_DQS_DP<15>")
	)
	(segment
		(start 136.685528 -127.26416)
		(end 136.685528 -128.088644)
		(width 0.14224)
		(layer "In4.Cu")
		(net "M_L_DQS_DP<15>")
	)
	(segment
		(start 136.26846 -125.752606)
		(end 136.26846 -126.847092)
		(width 0.14224)
		(layer "In4.Cu")
		(net "M_L_DQS_DP<15>")
	)
	(segment
		(start 136.74598 -125.275086)
		(end 136.26846 -125.752606)
		(width 0.14224)
		(layer "In4.Cu")
		(net "M_L_DQS_DP<15>")
	)
	(segment
		(start 136.685528 -128.088644)
		(end 137.25525 -128.658366)
		(width 0.14224)
		(layer "In4.Cu")
		(net "M_L_DQS_DP<15>")
	)
	(segment
		(start 136.74217 -145.338546)
		(end 136.237218 -144.833594)
		(width 0.14224)
		(layer "In9.Cu")
		(net "M_L_DQS_DP<15>")
	)
	(segment
		(start 136.237218 -140.2588)
		(end 136.669018 -139.827)
		(width 0.14224)
		(layer "In9.Cu")
		(net "M_L_DQS_DP<15>")
	)
	(segment
		(start 136.669018 -139.827)
		(end 136.74217 -139.827)
		(width 0.14224)
		(layer "In9.Cu")
		(net "M_L_DQS_DP<15>")
	)
	(segment
		(start 136.237218 -144.833594)
		(end 136.237218 -140.2588)
		(width 0.14224)
		(layer "In9.Cu")
		(net "M_L_DQS_DP<15>")
	)
	(segment
		(start 127.010414 -144.956784)
		(end 127.392176 -145.338546)
		(width 0.1651)
		(layer "F.Cu")
		(net "M_L_DQS_DP<14>")
	)
	(segment
		(start 120.357138 -114.743992)
		(end 120.43156 -114.743992)
		(width 0.1016)
		(layer "F.Cu")
		(net "M_L_DQS_DP<14>")
	)
	(segment
		(start 126.92888 -143.914368)
		(end 126.92888 -144.732502)
		(width 0.1651)
		(layer "F.Cu")
		(net "M_L_DQS_DP<14>")
	)
	(segment
		(start 127.251968 -121.34469)
		(end 127.412242 -121.504964)
		(width 0.1651)
		(layer "F.Cu")
		(net "M_L_DQS_DP<14>")
	)
	(segment
		(start 125.829568 -119.666258)
		(end 125.829568 -119.92229)
		(width 0.1651)
		(layer "F.Cu")
		(net "M_L_DQS_DP<14>")
	)
	(segment
		(start 115.636802 -99.986338)
		(end 115.543076 -100.393246)
		(width 0.0889)
		(layer "F.Cu")
		(net "M_L_DQS_DP<14>")
	)
	(segment
		(start 115.05184 -103.091996)
		(end 115.053872 -103.099362)
		(width 0.0889)
		(layer "F.Cu")
		(net "M_L_DQS_DP<14>")
	)
	(segment
		(start 126.92888 -144.732502)
		(end 127.010414 -144.956784)
		(width 0.1651)
		(layer "F.Cu")
		(net "M_L_DQS_DP<14>")
	)
	(segment
		(start 127.44958 -142.6718)
		(end 127.44958 -143.294354)
		(width 0.1651)
		(layer "F.Cu")
		(net "M_L_DQS_DP<14>")
	)
	(segment
		(start 125.53569 -119.37238)
		(end 125.829568 -119.666258)
		(width 0.1651)
		(layer "F.Cu")
		(net "M_L_DQS_DP<14>")
	)
	(segment
		(start 127.251968 -121.088658)
		(end 127.251968 -121.34469)
		(width 0.1651)
		(layer "F.Cu")
		(net "M_L_DQS_DP<14>")
	)
	(segment
		(start 126.515368 -120.352058)
		(end 126.515368 -120.60809)
		(width 0.1651)
		(layer "F.Cu")
		(net "M_L_DQS_DP<14>")
	)
	(segment
		(start 127.869188 -121.705878)
		(end 127.869188 -125.177042)
		(width 0.1651)
		(layer "F.Cu")
		(net "M_L_DQS_DP<14>")
	)
	(segment
		(start 125.059948 -119.37238)
		(end 125.53569 -119.37238)
		(width 0.1651)
		(layer "F.Cu")
		(net "M_L_DQS_DP<14>")
	)
	(segment
		(start 126.684278 -120.777)
		(end 126.94031 -120.777)
		(width 0.1651)
		(layer "F.Cu")
		(net "M_L_DQS_DP<14>")
	)
	(segment
		(start 115.053872 -103.77805)
		(end 114.978688 -103.853234)
		(width 0.0889)
		(layer "F.Cu")
		(net "M_L_DQS_DP<14>")
	)
	(segment
		(start 126.023878 -120.1166)
		(end 126.27991 -120.1166)
		(width 0.1651)
		(layer "F.Cu")
		(net "M_L_DQS_DP<14>")
	)
	(segment
		(start 115.124992 -102.662736)
		(end 115.092734 -102.718616)
		(width 0.0889)
		(layer "F.Cu")
		(net "M_L_DQS_DP<14>")
	)
	(segment
		(start 114.978688 -103.853234)
		(end 114.978688 -105.815638)
		(width 0.0889)
		(layer "F.Cu")
		(net "M_L_DQS_DP<14>")
	)
	(segment
		(start 126.515368 -120.60809)
		(end 126.684278 -120.777)
		(width 0.1651)
		(layer "F.Cu")
		(net "M_L_DQS_DP<14>")
	)
	(segment
		(start 114.978688 -105.815638)
		(end 114.877088 -105.917238)
		(width 0.0889)
		(layer "F.Cu")
		(net "M_L_DQS_DP<14>")
	)
	(segment
		(start 127.013462 -143.730472)
		(end 126.92888 -143.914368)
		(width 0.1651)
		(layer "F.Cu")
		(net "M_L_DQS_DP<14>")
	)
	(segment
		(start 127.668274 -121.504964)
		(end 127.869188 -121.705878)
		(width 0.1651)
		(layer "F.Cu")
		(net "M_L_DQS_DP<14>")
	)
	(segment
		(start 119.123968 -113.380774)
		(end 119.123968 -113.510822)
		(width 0.1016)
		(layer "F.Cu")
		(net "M_L_DQS_DP<14>")
	)
	(segment
		(start 126.94031 -120.777)
		(end 127.251968 -121.088658)
		(width 0.1651)
		(layer "F.Cu")
		(net "M_L_DQS_DP<14>")
	)
	(segment
		(start 127.869188 -125.177042)
		(end 127.705612 -125.340618)
		(width 0.1651)
		(layer "F.Cu")
		(net "M_L_DQS_DP<14>")
	)
	(segment
		(start 127.705612 -125.340618)
		(end 127.39624 -125.340618)
		(width 0.1651)
		(layer "F.Cu")
		(net "M_L_DQS_DP<14>")
	)
	(segment
		(start 115.124992 -101.272086)
		(end 115.129818 -101.280722)
		(width 0.0889)
		(layer "F.Cu")
		(net "M_L_DQS_DP<14>")
	)
	(segment
		(start 119.123968 -113.510822)
		(end 120.357138 -114.743992)
		(width 0.1016)
		(layer "F.Cu")
		(net "M_L_DQS_DP<14>")
	)
	(segment
		(start 127.412242 -121.504964)
		(end 127.668274 -121.504964)
		(width 0.1651)
		(layer "F.Cu")
		(net "M_L_DQS_DP<14>")
	)
	(segment
		(start 127.44958 -143.294354)
		(end 127.013462 -143.730472)
		(width 0.1651)
		(layer "F.Cu")
		(net "M_L_DQS_DP<14>")
	)
	(segment
		(start 114.877088 -105.917238)
		(end 114.877088 -109.133894)
		(width 0.1016)
		(layer "F.Cu")
		(net "M_L_DQS_DP<14>")
	)
	(segment
		(start 115.124992 -102.262686)
		(end 115.129818 -102.271322)
		(width 0.0889)
		(layer "F.Cu")
		(net "M_L_DQS_DP<14>")
	)
	(segment
		(start 115.053872 -103.099362)
		(end 115.053872 -103.77805)
		(width 0.0889)
		(layer "F.Cu")
		(net "M_L_DQS_DP<14>")
	)
	(segment
		(start 126.27991 -120.1166)
		(end 126.515368 -120.352058)
		(width 0.1651)
		(layer "F.Cu")
		(net "M_L_DQS_DP<14>")
	)
	(segment
		(start 120.43156 -114.743992)
		(end 125.059948 -119.37238)
		(width 0.1651)
		(layer "F.Cu")
		(net "M_L_DQS_DP<14>")
	)
	(segment
		(start 114.877088 -109.133894)
		(end 119.123968 -113.380774)
		(width 0.1016)
		(layer "F.Cu")
		(net "M_L_DQS_DP<14>")
	)
	(segment
		(start 115.118642 -102.252018)
		(end 115.124992 -102.262686)
		(width 0.0889)
		(layer "F.Cu")
		(net "M_L_DQS_DP<14>")
	)
	(segment
		(start 125.829568 -119.92229)
		(end 126.023878 -120.1166)
		(width 0.1651)
		(layer "F.Cu")
		(net "M_L_DQS_DP<14>")
	)
	(via
		(at 127.392176 -145.338546)
		(size 0.508)
		(drill 0.254)
		(layers "F.Cu" "B.Cu")
		(net "M_L_DQS_DP<14>")
	)
	(via
		(at 127.392176 -139.827)
		(size 0.508)
		(drill 0.254)
		(layers "F.Cu" "B.Cu")
		(net "M_L_DQS_DP<14>")
	)
	(via
		(at 127.39624 -125.340618)
		(size 0.508)
		(drill 0.254)
		(layers "F.Cu" "B.Cu")
		(net "M_L_DQS_DP<14>")
	)
	(arc
		(start 115.129818 -102.271322)
		(mid 115.178573 -102.467674)
		(end 115.124992 -102.662736)
		(width 0.0889)
		(layer "F.Cu")
		(net "M_L_DQS_DP<14>")
	)
	(arc
		(start 115.543076 -100.393246)
		(mid 115.103185 -100.722839)
		(end 115.124992 -101.272086)
		(width 0.0889)
		(layer "F.Cu")
		(net "M_L_DQS_DP<14>")
	)
	(arc
		(start 115.129818 -101.280722)
		(mid 115.178573 -101.477074)
		(end 115.124992 -101.672136)
		(width 0.0889)
		(layer "F.Cu")
		(net "M_L_DQS_DP<14>")
	)
	(arc
		(start 115.124992 -101.672136)
		(mid 115.04577 -101.961254)
		(end 115.118642 -102.252018)
		(width 0.0889)
		(layer "F.Cu")
		(net "M_L_DQS_DP<14>")
	)
	(arc
		(start 115.092734 -102.718616)
		(mid 115.032995 -102.901006)
		(end 115.05184 -103.091996)
		(width 0.0889)
		(layer "F.Cu")
		(net "M_L_DQS_DP<14>")
	)
	(segment
		(start 127.44958 -142.477236)
		(end 127.44958 -141.859254)
		(width 0.1651)
		(layer "B.Cu")
		(net "M_L_DQS_DP<14>")
	)
	(segment
		(start 126.91618 -140.375132)
		(end 127.003556 -140.21562)
		(width 0.1651)
		(layer "B.Cu")
		(net "M_L_DQS_DP<14>")
	)
	(segment
		(start 127.003556 -140.21562)
		(end 127.392176 -139.827)
		(width 0.1651)
		(layer "B.Cu")
		(net "M_L_DQS_DP<14>")
	)
	(segment
		(start 126.91618 -141.270736)
		(end 126.91618 -140.375132)
		(width 0.1651)
		(layer "B.Cu")
		(net "M_L_DQS_DP<14>")
	)
	(segment
		(start 126.993396 -141.40307)
		(end 126.91618 -141.270736)
		(width 0.1651)
		(layer "B.Cu")
		(net "M_L_DQS_DP<14>")
	)
	(segment
		(start 127.44958 -141.859254)
		(end 126.993396 -141.40307)
		(width 0.1651)
		(layer "B.Cu")
		(net "M_L_DQS_DP<14>")
	)
	(segment
		(start 126.887224 -140.2588)
		(end 127.319024 -139.827)
		(width 0.14224)
		(layer "In9.Cu")
		(net "M_L_DQS_DP<14>")
	)
	(segment
		(start 126.887224 -144.833848)
		(end 126.887224 -140.2588)
		(width 0.14224)
		(layer "In9.Cu")
		(net "M_L_DQS_DP<14>")
	)
	(segment
		(start 127.392176 -145.338546)
		(end 127.391922 -145.338546)
		(width 0.14224)
		(layer "In9.Cu")
		(net "M_L_DQS_DP<14>")
	)
	(segment
		(start 127.319024 -139.827)
		(end 127.392176 -139.827)
		(width 0.14224)
		(layer "In9.Cu")
		(net "M_L_DQS_DP<14>")
	)
	(segment
		(start 127.391922 -145.338546)
		(end 126.887224 -144.833848)
		(width 0.14224)
		(layer "In9.Cu")
		(net "M_L_DQS_DP<14>")
	)
	(segment
		(start 126.958344 -125.778514)
		(end 127.39624 -125.340618)
		(width 0.14224)
		(layer "In11.Cu")
		(net "M_L_DQS_DP<14>")
	)
	(segment
		(start 127.905256 -139.363196)
		(end 127.905256 -128.288288)
		(width 0.14224)
		(layer "In11.Cu")
		(net "M_L_DQS_DP<14>")
	)
	(segment
		(start 127.392176 -139.827)
		(end 127.441452 -139.827)
		(width 0.14224)
		(layer "In11.Cu")
		(net "M_L_DQS_DP<14>")
	)
	(segment
		(start 126.958344 -126.985776)
		(end 126.958344 -125.778514)
		(width 0.14224)
		(layer "In11.Cu")
		(net "M_L_DQS_DP<14>")
	)
	(segment
		(start 127.441452 -139.827)
		(end 127.905256 -139.363196)
		(width 0.14224)
		(layer "In11.Cu")
		(net "M_L_DQS_DP<14>")
	)
	(segment
		(start 127.465328 -127.49276)
		(end 126.958344 -126.985776)
		(width 0.14224)
		(layer "In11.Cu")
		(net "M_L_DQS_DP<14>")
	)
	(segment
		(start 127.905256 -128.288288)
		(end 127.465328 -127.84836)
		(width 0.14224)
		(layer "In11.Cu")
		(net "M_L_DQS_DP<14>")
	)
	(segment
		(start 127.465328 -127.84836)
		(end 127.465328 -127.49276)
		(width 0.14224)
		(layer "In11.Cu")
		(net "M_L_DQS_DP<14>")
	)
	(segment
		(start 117.663214 -143.730726)
		(end 117.578632 -143.914368)
		(width 0.1651)
		(layer "F.Cu")
		(net "M_L_DQS_DP<13>")
	)
	(segment
		(start 118.099332 -142.6718)
		(end 118.099332 -143.294608)
		(width 0.1651)
		(layer "F.Cu")
		(net "M_L_DQS_DP<13>")
	)
	(segment
		(start 117.578632 -143.914368)
		(end 117.578632 -144.732502)
		(width 0.1651)
		(layer "F.Cu")
		(net "M_L_DQS_DP<13>")
	)
	(segment
		(start 118.099332 -143.294608)
		(end 117.663214 -143.730726)
		(width 0.1651)
		(layer "F.Cu")
		(net "M_L_DQS_DP<13>")
	)
	(segment
		(start 107.910376 -96.518984)
		(end 108.481876 -96.518984)
		(width 0.1651)
		(layer "F.Cu")
		(net "M_L_DQS_DP<13>")
	)
	(segment
		(start 117.660166 -144.956784)
		(end 118.041928 -145.338546)
		(width 0.1651)
		(layer "F.Cu")
		(net "M_L_DQS_DP<13>")
	)
	(segment
		(start 117.578632 -144.732502)
		(end 117.660166 -144.956784)
		(width 0.1651)
		(layer "F.Cu")
		(net "M_L_DQS_DP<13>")
	)
	(via
		(at 118.041928 -145.338546)
		(size 0.508)
		(drill 0.254)
		(layers "F.Cu" "B.Cu")
		(net "M_L_DQS_DP<13>")
	)
	(via
		(at 118.041928 -139.827)
		(size 0.508)
		(drill 0.254)
		(layers "F.Cu" "B.Cu")
		(net "M_L_DQS_DP<13>")
	)
	(via
		(at 108.481876 -96.518984)
		(size 0.508)
		(drill 0.254)
		(layers "F.Cu" "B.Cu")
		(net "M_L_DQS_DP<13>")
	)
	(segment
		(start 118.099332 -142.477236)
		(end 118.099332 -141.859254)
		(width 0.1651)
		(layer "B.Cu")
		(net "M_L_DQS_DP<13>")
	)
	(segment
		(start 117.653308 -140.21562)
		(end 118.041928 -139.827)
		(width 0.1651)
		(layer "B.Cu")
		(net "M_L_DQS_DP<13>")
	)
	(segment
		(start 117.643148 -141.40307)
		(end 117.565932 -141.270736)
		(width 0.1651)
		(layer "B.Cu")
		(net "M_L_DQS_DP<13>")
	)
	(segment
		(start 117.565932 -141.270736)
		(end 117.565932 -140.375132)
		(width 0.1651)
		(layer "B.Cu")
		(net "M_L_DQS_DP<13>")
	)
	(segment
		(start 117.565932 -140.375132)
		(end 117.653308 -140.21562)
		(width 0.1651)
		(layer "B.Cu")
		(net "M_L_DQS_DP<13>")
	)
	(segment
		(start 118.099332 -141.859254)
		(end 117.643148 -141.40307)
		(width 0.1651)
		(layer "B.Cu")
		(net "M_L_DQS_DP<13>")
	)
	(segment
		(start 108.02366 -99.986084)
		(end 108.02366 -102.022656)
		(width 0.0889)
		(layer "In4.Cu")
		(net "M_L_DQS_DP<13>")
	)
	(segment
		(start 118.437152 -137.945114)
		(end 118.555262 -138.063224)
		(width 0.14224)
		(layer "In4.Cu")
		(net "M_L_DQS_DP<13>")
	)
	(segment
		(start 117.53723 -140.2588)
		(end 117.53723 -144.833848)
		(width 0.14224)
		(layer "In4.Cu")
		(net "M_L_DQS_DP<13>")
	)
	(segment
		(start 118.555262 -138.317224)
		(end 118.437152 -138.435334)
		(width 0.14224)
		(layer "In4.Cu")
		(net "M_L_DQS_DP<13>")
	)
	(segment
		(start 117.990366 -128.77927)
		(end 118.555262 -129.344166)
		(width 0.14224)
		(layer "In4.Cu")
		(net "M_L_DQS_DP<13>")
	)
	(segment
		(start 107.970066 -99.786948)
		(end 107.970066 -99.786694)
		(width 0.0889)
		(layer "In4.Cu")
		(net "M_L_DQS_DP<13>")
	)
	(segment
		(start 118.555262 -137.573004)
		(end 118.437152 -137.691114)
		(width 0.14224)
		(layer "In4.Cu")
		(net "M_L_DQS_DP<13>")
	)
	(segment
		(start 108.481876 -96.518984)
		(end 108.481876 -96.85782)
		(width 0.0889)
		(layer "In4.Cu")
		(net "M_L_DQS_DP<13>")
	)
	(segment
		(start 109.136942 -106.473498)
		(end 109.136942 -116.918486)
		(width 0.14224)
		(layer "In4.Cu")
		(net "M_L_DQS_DP<13>")
	)
	(segment
		(start 118.437152 -138.689334)
		(end 118.555262 -138.807444)
		(width 0.14224)
		(layer "In4.Cu")
		(net "M_L_DQS_DP<13>")
	)
	(segment
		(start 118.437152 -136.946894)
		(end 118.437152 -137.200894)
		(width 0.14224)
		(layer "In4.Cu")
		(net "M_L_DQS_DP<13>")
	)
	(segment
		(start 108.02366 -102.022656)
		(end 109.176312 -103.175308)
		(width 0.0889)
		(layer "In4.Cu")
		(net "M_L_DQS_DP<13>")
	)
	(segment
		(start 118.555262 -138.807444)
		(end 118.555262 -139.59332)
		(width 0.14224)
		(layer "In4.Cu")
		(net "M_L_DQS_DP<13>")
	)
	(segment
		(start 118.555262 -136.828784)
		(end 118.437152 -136.946894)
		(width 0.14224)
		(layer "In4.Cu")
		(net "M_L_DQS_DP<13>")
	)
	(segment
		(start 118.555262 -137.319004)
		(end 118.555262 -137.573004)
		(width 0.14224)
		(layer "In4.Cu")
		(net "M_L_DQS_DP<13>")
	)
	(segment
		(start 108.481876 -96.85782)
		(end 108.416852 -96.922844)
		(width 0.0889)
		(layer "In4.Cu")
		(net "M_L_DQS_DP<13>")
	)
	(segment
		(start 118.555262 -139.59332)
		(end 118.321582 -139.827)
		(width 0.14224)
		(layer "In4.Cu")
		(net "M_L_DQS_DP<13>")
	)
	(segment
		(start 109.176312 -103.175308)
		(end 109.176312 -106.41203)
		(width 0.0889)
		(layer "In4.Cu")
		(net "M_L_DQS_DP<13>")
	)
	(segment
		(start 109.176312 -106.41203)
		(end 109.136942 -106.4514)
		(width 0.0889)
		(layer "In4.Cu")
		(net "M_L_DQS_DP<13>")
	)
	(segment
		(start 109.136942 -106.4514)
		(end 109.136942 -106.473498)
		(width 0.0889)
		(layer "In4.Cu")
		(net "M_L_DQS_DP<13>")
	)
	(segment
		(start 118.321582 -139.827)
		(end 118.041928 -139.827)
		(width 0.14224)
		(layer "In4.Cu")
		(net "M_L_DQS_DP<13>")
	)
	(segment
		(start 117.96903 -139.827)
		(end 117.53723 -140.2588)
		(width 0.14224)
		(layer "In4.Cu")
		(net "M_L_DQS_DP<13>")
	)
	(segment
		(start 109.136942 -116.918486)
		(end 117.990366 -125.77191)
		(width 0.14224)
		(layer "In4.Cu")
		(net "M_L_DQS_DP<13>")
	)
	(segment
		(start 117.990366 -125.77191)
		(end 117.990366 -128.77927)
		(width 0.14224)
		(layer "In4.Cu")
		(net "M_L_DQS_DP<13>")
	)
	(segment
		(start 118.555262 -129.344166)
		(end 118.555262 -136.828784)
		(width 0.14224)
		(layer "In4.Cu")
		(net "M_L_DQS_DP<13>")
	)
	(segment
		(start 118.437152 -137.691114)
		(end 118.437152 -137.945114)
		(width 0.14224)
		(layer "In4.Cu")
		(net "M_L_DQS_DP<13>")
	)
	(segment
		(start 118.437152 -138.435334)
		(end 118.437152 -138.689334)
		(width 0.14224)
		(layer "In4.Cu")
		(net "M_L_DQS_DP<13>")
	)
	(segment
		(start 118.041928 -139.827)
		(end 117.96903 -139.827)
		(width 0.14224)
		(layer "In4.Cu")
		(net "M_L_DQS_DP<13>")
	)
	(segment
		(start 117.53723 -144.833848)
		(end 118.041928 -145.338546)
		(width 0.14224)
		(layer "In4.Cu")
		(net "M_L_DQS_DP<13>")
	)
	(segment
		(start 118.437152 -137.200894)
		(end 118.555262 -137.319004)
		(width 0.14224)
		(layer "In4.Cu")
		(net "M_L_DQS_DP<13>")
	)
	(segment
		(start 118.555262 -138.063224)
		(end 118.555262 -138.317224)
		(width 0.14224)
		(layer "In4.Cu")
		(net "M_L_DQS_DP<13>")
	)
	(arc
		(start 107.970066 -99.196144)
		(mid 107.890935 -99.491546)
		(end 107.970066 -99.786948)
		(width 0.0889)
		(layer "In4.Cu")
		(net "M_L_DQS_DP<13>")
	)
	(arc
		(start 107.970066 -97.805748)
		(mid 108.023565 -98.005646)
		(end 107.970066 -98.205544)
		(width 0.0889)
		(layer "In4.Cu")
		(net "M_L_DQS_DP<13>")
	)
	(arc
		(start 107.970066 -98.796348)
		(mid 108.023565 -98.996246)
		(end 107.970066 -99.196144)
		(width 0.0889)
		(layer "In4.Cu")
		(net "M_L_DQS_DP<13>")
	)
	(arc
		(start 107.970066 -98.205544)
		(mid 107.890935 -98.500946)
		(end 107.970066 -98.796348)
		(width 0.0889)
		(layer "In4.Cu")
		(net "M_L_DQS_DP<13>")
	)
	(arc
		(start 107.970066 -99.786694)
		(mid 108.009954 -99.882872)
		(end 108.02366 -99.986084)
		(width 0.0889)
		(layer "In4.Cu")
		(net "M_L_DQS_DP<13>")
	)
	(arc
		(start 108.416852 -96.922844)
		(mid 107.954492 -97.243414)
		(end 107.970066 -97.805748)
		(width 0.0889)
		(layer "In4.Cu")
		(net "M_L_DQS_DP<13>")
	)
	(segment
		(start 72.808592 -104.787446)
		(end 72.687434 -104.787446)
		(width 0.1651)
		(layer "F.Cu")
		(net "M_L_DQS_DP<12>")
	)
	(segment
		(start 62.849506 -143.294354)
		(end 62.413388 -143.730472)
		(width 0.1651)
		(layer "F.Cu")
		(net "M_L_DQS_DP<12>")
	)
	(segment
		(start 78.909672 -98.681286)
		(end 78.909672 -99.01301)
		(width 0.0889)
		(layer "F.Cu")
		(net "M_L_DQS_DP<12>")
	)
	(segment
		(start 68.40601 -105.592626)
		(end 68.208144 -105.790492)
		(width 0.1651)
		(layer "F.Cu")
		(net "M_L_DQS_DP<12>")
	)
	(segment
		(start 73.008236 -104.787446)
		(end 72.808592 -104.787446)
		(width 0.1016)
		(layer "F.Cu")
		(net "M_L_DQS_DP<12>")
	)
	(segment
		(start 78.319122 -102.23246)
		(end 78.294992 -102.25659)
		(width 0.0889)
		(layer "F.Cu")
		(net "M_L_DQS_DP<12>")
	)
	(segment
		(start 62.647068 -121.287032)
		(end 62.647068 -122.400314)
		(width 0.1651)
		(layer "F.Cu")
		(net "M_L_DQS_DP<12>")
	)
	(segment
		(start 62.849506 -142.6718)
		(end 62.849506 -143.294354)
		(width 0.1651)
		(layer "F.Cu")
		(net "M_L_DQS_DP<12>")
	)
	(segment
		(start 74.353928 -103.441754)
		(end 73.008236 -104.787446)
		(width 0.1016)
		(layer "F.Cu")
		(net "M_L_DQS_DP<12>")
	)
	(segment
		(start 68.585588 -105.592626)
		(end 68.40601 -105.592626)
		(width 0.1651)
		(layer "F.Cu")
		(net "M_L_DQS_DP<12>")
	)
	(segment
		(start 78.391258 -101.370384)
		(end 78.390496 -101.370384)
		(width 0.0889)
		(layer "F.Cu")
		(net "M_L_DQS_DP<12>")
	)
	(segment
		(start 63.275464 -124.397008)
		(end 63.275464 -125.068076)
		(width 0.1651)
		(layer "F.Cu")
		(net "M_L_DQS_DP<12>")
	)
	(segment
		(start 78.909672 -99.01301)
		(end 78.837028 -99.085654)
		(width 0.0889)
		(layer "F.Cu")
		(net "M_L_DQS_DP<12>")
	)
	(segment
		(start 69.390514 -104.7877)
		(end 69.160136 -105.018078)
		(width 0.1651)
		(layer "F.Cu")
		(net "M_L_DQS_DP<12>")
	)
	(segment
		(start 68.782946 -105.21569)
		(end 68.782946 -105.395268)
		(width 0.1651)
		(layer "F.Cu")
		(net "M_L_DQS_DP<12>")
	)
	(segment
		(start 72.68718 -104.7877)
		(end 69.390514 -104.7877)
		(width 0.1651)
		(layer "F.Cu")
		(net "M_L_DQS_DP<12>")
	)
	(segment
		(start 62.487048 -122.560334)
		(end 62.487048 -123.608592)
		(width 0.1651)
		(layer "F.Cu")
		(net "M_L_DQS_DP<12>")
	)
	(segment
		(start 63.068454 -125.275086)
		(end 62.795912 -125.275086)
		(width 0.1651)
		(layer "F.Cu")
		(net "M_L_DQS_DP<12>")
	)
	(segment
		(start 62.487048 -111.691166)
		(end 62.487048 -121.127012)
		(width 0.1651)
		(layer "F.Cu")
		(net "M_L_DQS_DP<12>")
	)
	(segment
		(start 62.6491 -123.770644)
		(end 62.6491 -123.902216)
		(width 0.1651)
		(layer "F.Cu")
		(net "M_L_DQS_DP<12>")
	)
	(segment
		(start 72.687434 -104.787446)
		(end 72.68718 -104.7877)
		(width 0.1651)
		(layer "F.Cu")
		(net "M_L_DQS_DP<12>")
	)
	(segment
		(start 76.830174 -103.441754)
		(end 74.353928 -103.441754)
		(width 0.1016)
		(layer "F.Cu")
		(net "M_L_DQS_DP<12>")
	)
	(segment
		(start 62.6491 -123.902216)
		(end 62.828932 -124.082048)
		(width 0.1651)
		(layer "F.Cu")
		(net "M_L_DQS_DP<12>")
	)
	(segment
		(start 68.782946 -105.395268)
		(end 68.585588 -105.592626)
		(width 0.1651)
		(layer "F.Cu")
		(net "M_L_DQS_DP<12>")
	)
	(segment
		(start 78.391512 -99.95662)
		(end 78.397862 -99.967288)
		(width 0.0889)
		(layer "F.Cu")
		(net "M_L_DQS_DP<12>")
	)
	(segment
		(start 78.319122 -101.64826)
		(end 78.319122 -102.23246)
		(width 0.0889)
		(layer "F.Cu")
		(net "M_L_DQS_DP<12>")
	)
	(segment
		(start 68.208144 -105.97007)
		(end 62.487048 -111.691166)
		(width 0.1651)
		(layer "F.Cu")
		(net "M_L_DQS_DP<12>")
	)
	(segment
		(start 63.275464 -125.068076)
		(end 63.068454 -125.275086)
		(width 0.1651)
		(layer "F.Cu")
		(net "M_L_DQS_DP<12>")
	)
	(segment
		(start 62.328806 -143.914368)
		(end 62.328806 -144.732502)
		(width 0.1651)
		(layer "F.Cu")
		(net "M_L_DQS_DP<12>")
	)
	(segment
		(start 62.960504 -124.082048)
		(end 63.275464 -124.397008)
		(width 0.1651)
		(layer "F.Cu")
		(net "M_L_DQS_DP<12>")
	)
	(segment
		(start 62.413388 -143.730472)
		(end 62.328806 -143.914368)
		(width 0.1651)
		(layer "F.Cu")
		(net "M_L_DQS_DP<12>")
	)
	(segment
		(start 78.397862 -100.367084)
		(end 78.391512 -100.377752)
		(width 0.0889)
		(layer "F.Cu")
		(net "M_L_DQS_DP<12>")
	)
	(segment
		(start 62.647068 -122.400314)
		(end 62.487048 -122.560334)
		(width 0.1651)
		(layer "F.Cu")
		(net "M_L_DQS_DP<12>")
	)
	(segment
		(start 62.487048 -121.127012)
		(end 62.647068 -121.287032)
		(width 0.1651)
		(layer "F.Cu")
		(net "M_L_DQS_DP<12>")
	)
	(segment
		(start 68.980558 -105.018078)
		(end 68.782946 -105.21569)
		(width 0.1651)
		(layer "F.Cu")
		(net "M_L_DQS_DP<12>")
	)
	(segment
		(start 68.208144 -105.790492)
		(end 68.208144 -105.97007)
		(width 0.1651)
		(layer "F.Cu")
		(net "M_L_DQS_DP<12>")
	)
	(segment
		(start 78.397862 -101.357938)
		(end 78.391258 -101.370384)
		(width 0.0889)
		(layer "F.Cu")
		(net "M_L_DQS_DP<12>")
	)
	(segment
		(start 78.294992 -102.25659)
		(end 77.109828 -103.441754)
		(width 0.1016)
		(layer "F.Cu")
		(net "M_L_DQS_DP<12>")
	)
	(segment
		(start 69.160136 -105.018078)
		(end 68.980558 -105.018078)
		(width 0.1651)
		(layer "F.Cu")
		(net "M_L_DQS_DP<12>")
	)
	(segment
		(start 62.41034 -144.956784)
		(end 62.792102 -145.338546)
		(width 0.1651)
		(layer "F.Cu")
		(net "M_L_DQS_DP<12>")
	)
	(segment
		(start 77.109828 -103.441754)
		(end 76.830174 -103.441754)
		(width 0.1016)
		(layer "F.Cu")
		(net "M_L_DQS_DP<12>")
	)
	(segment
		(start 62.328806 -144.732502)
		(end 62.41034 -144.956784)
		(width 0.1651)
		(layer "F.Cu")
		(net "M_L_DQS_DP<12>")
	)
	(segment
		(start 62.828932 -124.082048)
		(end 62.960504 -124.082048)
		(width 0.1651)
		(layer "F.Cu")
		(net "M_L_DQS_DP<12>")
	)
	(segment
		(start 62.487048 -123.608592)
		(end 62.6491 -123.770644)
		(width 0.1651)
		(layer "F.Cu")
		(net "M_L_DQS_DP<12>")
	)
	(via
		(at 62.792102 -139.827)
		(size 0.508)
		(drill 0.254)
		(layers "F.Cu" "B.Cu")
		(net "M_L_DQS_DP<12>")
	)
	(via
		(at 62.792102 -145.338546)
		(size 0.508)
		(drill 0.254)
		(layers "F.Cu" "B.Cu")
		(net "M_L_DQS_DP<12>")
	)
	(via
		(at 62.795912 -125.275086)
		(size 0.508)
		(drill 0.254)
		(layers "F.Cu" "B.Cu")
		(net "M_L_DQS_DP<12>")
	)
	(arc
		(start 78.391512 -100.377752)
		(mid 78.318592 -100.668769)
		(end 78.397862 -100.958142)
		(width 0.0889)
		(layer "F.Cu")
		(net "M_L_DQS_DP<12>")
	)
	(arc
		(start 78.397862 -99.376738)
		(mid 78.31864 -99.665856)
		(end 78.391512 -99.95662)
		(width 0.0889)
		(layer "F.Cu")
		(net "M_L_DQS_DP<12>")
	)
	(arc
		(start 78.837028 -99.085654)
		(mid 78.826601 -99.087086)
		(end 78.8162 -99.088702)
		(width 0.0889)
		(layer "F.Cu")
		(net "M_L_DQS_DP<12>")
	)
	(arc
		(start 78.397862 -99.967288)
		(mid 78.451395 -100.167186)
		(end 78.397862 -100.367084)
		(width 0.0889)
		(layer "F.Cu")
		(net "M_L_DQS_DP<12>")
	)
	(arc
		(start 78.397862 -100.958142)
		(mid 78.451395 -101.15804)
		(end 78.397862 -101.357938)
		(width 0.0889)
		(layer "F.Cu")
		(net "M_L_DQS_DP<12>")
	)
	(arc
		(start 78.390496 -101.370384)
		(mid 78.337707 -101.504926)
		(end 78.319122 -101.64826)
		(width 0.0889)
		(layer "F.Cu")
		(net "M_L_DQS_DP<12>")
	)
	(arc
		(start 78.8162 -99.088702)
		(mid 78.574529 -99.185502)
		(end 78.397862 -99.376738)
		(width 0.0889)
		(layer "F.Cu")
		(net "M_L_DQS_DP<12>")
	)
	(segment
		(start 62.403482 -140.21562)
		(end 62.792102 -139.827)
		(width 0.1651)
		(layer "B.Cu")
		(net "M_L_DQS_DP<12>")
	)
	(segment
		(start 62.849506 -142.477236)
		(end 62.849506 -141.859254)
		(width 0.1651)
		(layer "B.Cu")
		(net "M_L_DQS_DP<12>")
	)
	(segment
		(start 62.849506 -141.859254)
		(end 62.393322 -141.40307)
		(width 0.1651)
		(layer "B.Cu")
		(net "M_L_DQS_DP<12>")
	)
	(segment
		(start 62.393322 -141.40307)
		(end 62.316106 -141.270736)
		(width 0.1651)
		(layer "B.Cu")
		(net "M_L_DQS_DP<12>")
	)
	(segment
		(start 62.316106 -140.375132)
		(end 62.403482 -140.21562)
		(width 0.1651)
		(layer "B.Cu")
		(net "M_L_DQS_DP<12>")
	)
	(segment
		(start 62.316106 -141.270736)
		(end 62.316106 -140.375132)
		(width 0.1651)
		(layer "B.Cu")
		(net "M_L_DQS_DP<12>")
	)
	(segment
		(start 62.71895 -139.827)
		(end 62.28715 -140.2588)
		(width 0.14224)
		(layer "In4.Cu")
		(net "M_L_DQS_DP<12>")
	)
	(segment
		(start 63.305182 -139.562586)
		(end 63.040768 -139.827)
		(width 0.14224)
		(layer "In4.Cu")
		(net "M_L_DQS_DP<12>")
	)
	(segment
		(start 63.040768 -139.827)
		(end 62.792102 -139.827)
		(width 0.14224)
		(layer "In4.Cu")
		(net "M_L_DQS_DP<12>")
	)
	(segment
		(start 62.28715 -144.833594)
		(end 62.792102 -145.338546)
		(width 0.14224)
		(layer "In4.Cu")
		(net "M_L_DQS_DP<12>")
	)
	(segment
		(start 62.795912 -125.275086)
		(end 62.353444 -125.717554)
		(width 0.14224)
		(layer "In4.Cu")
		(net "M_L_DQS_DP<12>")
	)
	(segment
		(start 63.305182 -129.003552)
		(end 63.305182 -139.562586)
		(width 0.14224)
		(layer "In4.Cu")
		(net "M_L_DQS_DP<12>")
	)
	(segment
		(start 62.792102 -139.827)
		(end 62.71895 -139.827)
		(width 0.14224)
		(layer "In4.Cu")
		(net "M_L_DQS_DP<12>")
	)
	(segment
		(start 62.353444 -126.705614)
		(end 63.305182 -129.003552)
		(width 0.14224)
		(layer "In4.Cu")
		(net "M_L_DQS_DP<12>")
	)
	(segment
		(start 62.28715 -140.2588)
		(end 62.28715 -144.833594)
		(width 0.14224)
		(layer "In4.Cu")
		(net "M_L_DQS_DP<12>")
	)
	(segment
		(start 62.353444 -125.717554)
		(end 62.353444 -126.705614)
		(width 0.14224)
		(layer "In4.Cu")
		(net "M_L_DQS_DP<12>")
	)
	(segment
		(start 53.499512 -143.294354)
		(end 53.063394 -143.730472)
		(width 0.1651)
		(layer "F.Cu")
		(net "M_L_DQS_DP<11>")
	)
	(segment
		(start 73.758806 -97.690686)
		(end 73.187306 -97.690686)
		(width 0.1651)
		(layer "F.Cu")
		(net "M_L_DQS_DP<11>")
	)
	(segment
		(start 52.978812 -143.914368)
		(end 52.978812 -144.732502)
		(width 0.1651)
		(layer "F.Cu")
		(net "M_L_DQS_DP<11>")
	)
	(segment
		(start 53.499512 -142.6718)
		(end 53.499512 -143.294354)
		(width 0.1651)
		(layer "F.Cu")
		(net "M_L_DQS_DP<11>")
	)
	(segment
		(start 53.063394 -143.730472)
		(end 52.978812 -143.914368)
		(width 0.1651)
		(layer "F.Cu")
		(net "M_L_DQS_DP<11>")
	)
	(segment
		(start 53.060346 -144.956784)
		(end 53.442108 -145.338546)
		(width 0.1651)
		(layer "F.Cu")
		(net "M_L_DQS_DP<11>")
	)
	(segment
		(start 52.978812 -144.732502)
		(end 53.060346 -144.956784)
		(width 0.1651)
		(layer "F.Cu")
		(net "M_L_DQS_DP<11>")
	)
	(via
		(at 53.442108 -139.827)
		(size 0.508)
		(drill 0.254)
		(layers "F.Cu" "B.Cu")
		(net "M_L_DQS_DP<11>")
	)
	(via
		(at 73.187306 -97.690686)
		(size 0.508)
		(drill 0.254)
		(layers "F.Cu" "B.Cu")
		(net "M_L_DQS_DP<11>")
	)
	(via
		(at 53.442108 -145.338546)
		(size 0.508)
		(drill 0.254)
		(layers "F.Cu" "B.Cu")
		(net "M_L_DQS_DP<11>")
	)
	(segment
		(start 53.499512 -142.477236)
		(end 53.499512 -141.859254)
		(width 0.1651)
		(layer "B.Cu")
		(net "M_L_DQS_DP<11>")
	)
	(segment
		(start 53.043328 -141.40307)
		(end 52.966112 -141.270736)
		(width 0.1651)
		(layer "B.Cu")
		(net "M_L_DQS_DP<11>")
	)
	(segment
		(start 52.966112 -140.375132)
		(end 53.053488 -140.21562)
		(width 0.1651)
		(layer "B.Cu")
		(net "M_L_DQS_DP<11>")
	)
	(segment
		(start 53.053488 -140.21562)
		(end 53.442108 -139.827)
		(width 0.1651)
		(layer "B.Cu")
		(net "M_L_DQS_DP<11>")
	)
	(segment
		(start 53.499512 -141.859254)
		(end 53.043328 -141.40307)
		(width 0.1651)
		(layer "B.Cu")
		(net "M_L_DQS_DP<11>")
	)
	(segment
		(start 52.966112 -141.270736)
		(end 52.966112 -140.375132)
		(width 0.1651)
		(layer "B.Cu")
		(net "M_L_DQS_DP<11>")
	)
	(segment
		(start 72.669146 -99.95662)
		(end 72.675496 -99.967288)
		(width 0.0889)
		(layer "In4.Cu")
		(net "M_L_DQS_DP<11>")
	)
	(segment
		(start 70.050406 -102.32644)
		(end 69.800724 -102.32644)
		(width 0.0889)
		(layer "In4.Cu")
		(net "M_L_DQS_DP<11>")
	)
	(segment
		(start 68.31965 -103.751634)
		(end 68.303902 -103.767382)
		(width 0.0889)
		(layer "In4.Cu")
		(net "M_L_DQS_DP<11>")
	)
	(segment
		(start 70.875652 -101.501194)
		(end 70.050406 -102.32644)
		(width 0.0889)
		(layer "In4.Cu")
		(net "M_L_DQS_DP<11>")
	)
	(segment
		(start 53.814472 -138.753342)
		(end 53.955188 -138.894058)
		(width 0.14224)
		(layer "In4.Cu")
		(net "M_L_DQS_DP<11>")
	)
	(segment
		(start 70.95871 -101.357176)
		(end 70.875652 -101.501194)
		(width 0.0889)
		(layer "In4.Cu")
		(net "M_L_DQS_DP<11>")
	)
	(segment
		(start 73.187306 -98.02876)
		(end 73.122028 -98.094038)
		(width 0.0889)
		(layer "In4.Cu")
		(net "M_L_DQS_DP<11>")
	)
	(segment
		(start 53.721508 -139.827)
		(end 53.442108 -139.827)
		(width 0.14224)
		(layer "In4.Cu")
		(net "M_L_DQS_DP<11>")
	)
	(segment
		(start 53.821584 -137.92708)
		(end 53.955188 -138.060684)
		(width 0.14224)
		(layer "In4.Cu")
		(net "M_L_DQS_DP<11>")
	)
	(segment
		(start 72.339962 -100.567236)
		(end 72.315832 -100.567236)
		(width 0.0889)
		(layer "In4.Cu")
		(net "M_L_DQS_DP<11>")
	)
	(segment
		(start 53.821584 -137.67308)
		(end 53.821584 -137.92708)
		(width 0.14224)
		(layer "In4.Cu")
		(net "M_L_DQS_DP<11>")
	)
	(segment
		(start 55.146448 -123.339606)
		(end 55.146448 -127.916686)
		(width 0.14224)
		(layer "In4.Cu")
		(net "M_L_DQS_DP<11>")
	)
	(segment
		(start 53.368956 -139.827)
		(end 52.937156 -140.2588)
		(width 0.14224)
		(layer "In4.Cu")
		(net "M_L_DQS_DP<11>")
	)
	(segment
		(start 52.937156 -140.2588)
		(end 52.937156 -144.833594)
		(width 0.14224)
		(layer "In4.Cu")
		(net "M_L_DQS_DP<11>")
	)
	(segment
		(start 67.765168 -104.306116)
		(end 67.765168 -105.950766)
		(width 0.14224)
		(layer "In4.Cu")
		(net "M_L_DQS_DP<11>")
	)
	(segment
		(start 73.187306 -97.690686)
		(end 73.187306 -98.02876)
		(width 0.0889)
		(layer "In4.Cu")
		(net "M_L_DQS_DP<11>")
	)
	(segment
		(start 71.485252 -101.062536)
		(end 71.45655 -101.062536)
		(width 0.0889)
		(layer "In4.Cu")
		(net "M_L_DQS_DP<11>")
	)
	(segment
		(start 53.955188 -129.107946)
		(end 53.955188 -137.539476)
		(width 0.14224)
		(layer "In4.Cu")
		(net "M_L_DQS_DP<11>")
	)
	(segment
		(start 64.468248 -109.247686)
		(end 64.468248 -114.017806)
		(width 0.14224)
		(layer "In4.Cu")
		(net "M_L_DQS_DP<11>")
	)
	(segment
		(start 53.955188 -137.539476)
		(end 53.821584 -137.67308)
		(width 0.14224)
		(layer "In4.Cu")
		(net "M_L_DQS_DP<11>")
	)
	(segment
		(start 72.680322 -99.368102)
		(end 72.675496 -99.376738)
		(width 0.0889)
		(layer "In4.Cu")
		(net "M_L_DQS_DP<11>")
	)
	(segment
		(start 52.937156 -144.833594)
		(end 53.442108 -145.338546)
		(width 0.14224)
		(layer "In4.Cu")
		(net "M_L_DQS_DP<11>")
	)
	(segment
		(start 53.955188 -138.358626)
		(end 53.814472 -138.499342)
		(width 0.14224)
		(layer "In4.Cu")
		(net "M_L_DQS_DP<11>")
	)
	(segment
		(start 55.146448 -127.916686)
		(end 53.955188 -129.107946)
		(width 0.14224)
		(layer "In4.Cu")
		(net "M_L_DQS_DP<11>")
	)
	(segment
		(start 53.442108 -139.827)
		(end 53.368956 -139.827)
		(width 0.14224)
		(layer "In4.Cu")
		(net "M_L_DQS_DP<11>")
	)
	(segment
		(start 53.955188 -139.59332)
		(end 53.721508 -139.827)
		(width 0.14224)
		(layer "In4.Cu")
		(net "M_L_DQS_DP<11>")
	)
	(segment
		(start 53.955188 -138.894058)
		(end 53.955188 -139.59332)
		(width 0.14224)
		(layer "In4.Cu")
		(net "M_L_DQS_DP<11>")
	)
	(segment
		(start 68.37553 -103.751634)
		(end 68.31965 -103.751634)
		(width 0.0889)
		(layer "In4.Cu")
		(net "M_L_DQS_DP<11>")
	)
	(segment
		(start 68.303902 -103.767382)
		(end 67.765168 -104.306116)
		(width 0.14224)
		(layer "In4.Cu")
		(net "M_L_DQS_DP<11>")
	)
	(segment
		(start 64.468248 -114.017806)
		(end 55.146448 -123.339606)
		(width 0.14224)
		(layer "In4.Cu")
		(net "M_L_DQS_DP<11>")
	)
	(segment
		(start 67.765168 -105.950766)
		(end 64.468248 -109.247686)
		(width 0.14224)
		(layer "In4.Cu")
		(net "M_L_DQS_DP<11>")
	)
	(segment
		(start 53.814472 -138.499342)
		(end 53.814472 -138.753342)
		(width 0.14224)
		(layer "In4.Cu")
		(net "M_L_DQS_DP<11>")
	)
	(segment
		(start 69.800724 -102.32644)
		(end 68.37553 -103.751634)
		(width 0.0889)
		(layer "In4.Cu")
		(net "M_L_DQS_DP<11>")
	)
	(segment
		(start 53.955188 -138.060684)
		(end 53.955188 -138.358626)
		(width 0.14224)
		(layer "In4.Cu")
		(net "M_L_DQS_DP<11>")
	)
	(arc
		(start 71.816976 -100.862638)
		(mid 71.676897 -101.005374)
		(end 71.485252 -101.062536)
		(width 0.0889)
		(layer "In4.Cu")
		(net "M_L_DQS_DP<11>")
	)
	(arc
		(start 71.45655 -101.062536)
		(mid 71.169114 -101.144764)
		(end 70.95871 -101.357176)
		(width 0.0889)
		(layer "In4.Cu")
		(net "M_L_DQS_DP<11>")
	)
	(arc
		(start 72.675496 -98.976688)
		(mid 72.728966 -99.171751)
		(end 72.680322 -99.368102)
		(width 0.0889)
		(layer "In4.Cu")
		(net "M_L_DQS_DP<11>")
	)
	(arc
		(start 72.315832 -100.567236)
		(mid 72.027687 -100.649555)
		(end 71.816976 -100.862638)
		(width 0.0889)
		(layer "In4.Cu")
		(net "M_L_DQS_DP<11>")
	)
	(arc
		(start 73.122028 -98.094038)
		(mid 72.660059 -98.41458)
		(end 72.675496 -98.976688)
		(width 0.0889)
		(layer "In4.Cu")
		(net "M_L_DQS_DP<11>")
	)
	(arc
		(start 72.675496 -99.967288)
		(mid 72.678079 -100.362535)
		(end 72.339962 -100.567236)
		(width 0.0889)
		(layer "In4.Cu")
		(net "M_L_DQS_DP<11>")
	)
	(arc
		(start 72.675496 -99.376738)
		(mid 72.596274 -99.665856)
		(end 72.669146 -99.95662)
		(width 0.0889)
		(layer "In4.Cu")
		(net "M_L_DQS_DP<11>")
	)
	(segment
		(start 44.149518 -142.6718)
		(end 44.149518 -143.294354)
		(width 0.1651)
		(layer "F.Cu")
		(net "M_L_DQS_DP<10>")
	)
	(segment
		(start 73.758806 -90.756486)
		(end 73.187306 -90.756486)
		(width 0.1651)
		(layer "F.Cu")
		(net "M_L_DQS_DP<10>")
	)
	(segment
		(start 43.628818 -144.732502)
		(end 43.710352 -144.956784)
		(width 0.1651)
		(layer "F.Cu")
		(net "M_L_DQS_DP<10>")
	)
	(segment
		(start 43.628818 -143.914368)
		(end 43.628818 -144.732502)
		(width 0.1651)
		(layer "F.Cu")
		(net "M_L_DQS_DP<10>")
	)
	(segment
		(start 44.149518 -143.294354)
		(end 43.7134 -143.730472)
		(width 0.1651)
		(layer "F.Cu")
		(net "M_L_DQS_DP<10>")
	)
	(segment
		(start 43.710352 -144.956784)
		(end 44.092114 -145.338546)
		(width 0.1651)
		(layer "F.Cu")
		(net "M_L_DQS_DP<10>")
	)
	(segment
		(start 43.7134 -143.730472)
		(end 43.628818 -143.914368)
		(width 0.1651)
		(layer "F.Cu")
		(net "M_L_DQS_DP<10>")
	)
	(via
		(at 44.092114 -145.338546)
		(size 0.508)
		(drill 0.254)
		(layers "F.Cu" "B.Cu")
		(net "M_L_DQS_DP<10>")
	)
	(via
		(at 73.187306 -90.756486)
		(size 0.508)
		(drill 0.254)
		(layers "F.Cu" "B.Cu")
		(net "M_L_DQS_DP<10>")
	)
	(via
		(at 44.092114 -139.827)
		(size 0.508)
		(drill 0.254)
		(layers "F.Cu" "B.Cu")
		(net "M_L_DQS_DP<10>")
	)
	(segment
		(start 44.149518 -141.859254)
		(end 43.693334 -141.40307)
		(width 0.1651)
		(layer "B.Cu")
		(net "M_L_DQS_DP<10>")
	)
	(segment
		(start 43.703494 -140.21562)
		(end 44.092114 -139.827)
		(width 0.1651)
		(layer "B.Cu")
		(net "M_L_DQS_DP<10>")
	)
	(segment
		(start 43.616118 -141.270736)
		(end 43.616118 -140.375132)
		(width 0.1651)
		(layer "B.Cu")
		(net "M_L_DQS_DP<10>")
	)
	(segment
		(start 44.149518 -142.477236)
		(end 44.149518 -141.859254)
		(width 0.1651)
		(layer "B.Cu")
		(net "M_L_DQS_DP<10>")
	)
	(segment
		(start 43.693334 -141.40307)
		(end 43.616118 -141.270736)
		(width 0.1651)
		(layer "B.Cu")
		(net "M_L_DQS_DP<10>")
	)
	(segment
		(start 43.616118 -140.375132)
		(end 43.703494 -140.21562)
		(width 0.1651)
		(layer "B.Cu")
		(net "M_L_DQS_DP<10>")
	)
	(segment
		(start 69.768212 -89.175336)
		(end 69.735446 -89.175336)
		(width 0.0889)
		(layer "In4.Cu")
		(net "M_L_DQS_DP<10>")
	)
	(segment
		(start 68.382642 -89.966546)
		(end 68.279772 -90.14587)
		(width 0.0889)
		(layer "In4.Cu")
		(net "M_L_DQS_DP<10>")
	)
	(segment
		(start 44.018962 -139.827)
		(end 43.587162 -140.2588)
		(width 0.14224)
		(layer "In4.Cu")
		(net "M_L_DQS_DP<10>")
	)
	(segment
		(start 44.605194 -129.72034)
		(end 44.605194 -139.600432)
		(width 0.14224)
		(layer "In4.Cu")
		(net "M_L_DQS_DP<10>")
	)
	(segment
		(start 68.905882 -89.67089)
		(end 68.873116 -89.67089)
		(width 0.0889)
		(layer "In4.Cu")
		(net "M_L_DQS_DP<10>")
	)
	(segment
		(start 48.331882 -117.756686)
		(end 47.753016 -117.756686)
		(width 0.14224)
		(layer "In4.Cu")
		(net "M_L_DQS_DP<10>")
	)
	(segment
		(start 61.415168 -99.061016)
		(end 56.284368 -104.191816)
		(width 0.14224)
		(layer "In4.Cu")
		(net "M_L_DQS_DP<10>")
	)
	(segment
		(start 43.587162 -144.833594)
		(end 44.092114 -145.338546)
		(width 0.14224)
		(layer "In4.Cu")
		(net "M_L_DQS_DP<10>")
	)
	(segment
		(start 44.834048 -127.688086)
		(end 44.834048 -129.491486)
		(width 0.14224)
		(layer "In4.Cu")
		(net "M_L_DQS_DP<10>")
	)
	(segment
		(start 46.789848 -125.732286)
		(end 44.834048 -127.688086)
		(width 0.14224)
		(layer "In4.Cu")
		(net "M_L_DQS_DP<10>")
	)
	(segment
		(start 68.279772 -90.14587)
		(end 68.279772 -90.493088)
		(width 0.0889)
		(layer "In4.Cu")
		(net "M_L_DQS_DP<10>")
	)
	(segment
		(start 44.834048 -129.491486)
		(end 44.605194 -129.72034)
		(width 0.14224)
		(layer "In4.Cu")
		(net "M_L_DQS_DP<10>")
	)
	(segment
		(start 73.187306 -90.756486)
		(end 72.89419 -90.587576)
		(width 0.0889)
		(layer "In4.Cu")
		(net "M_L_DQS_DP<10>")
	)
	(segment
		(start 56.284368 -104.191816)
		(end 56.284368 -106.646472)
		(width 0.14224)
		(layer "In4.Cu")
		(net "M_L_DQS_DP<10>")
	)
	(segment
		(start 68.436236 -90.649552)
		(end 68.436236 -91.921076)
		(width 0.0889)
		(layer "In4.Cu")
		(net "M_L_DQS_DP<10>")
	)
	(segment
		(start 47.753016 -117.756686)
		(end 46.789848 -118.719854)
		(width 0.14224)
		(layer "In4.Cu")
		(net "M_L_DQS_DP<10>")
	)
	(segment
		(start 48.623728 -117.083332)
		(end 48.623728 -117.46484)
		(width 0.14224)
		(layer "In4.Cu")
		(net "M_L_DQS_DP<10>")
	)
	(segment
		(start 47.658528 -116.679726)
		(end 48.220122 -116.679726)
		(width 0.14224)
		(layer "In4.Cu")
		(net "M_L_DQS_DP<10>")
	)
	(segment
		(start 68.436236 -91.921076)
		(end 68.132198 -92.225114)
		(width 0.0889)
		(layer "In4.Cu")
		(net "M_L_DQS_DP<10>")
	)
	(segment
		(start 66.918078 -92.225114)
		(end 66.531998 -92.611448)
		(width 0.0889)
		(layer "In4.Cu")
		(net "M_L_DQS_DP<10>")
	)
	(segment
		(start 72.350376 -89.67089)
		(end 72.31761 -89.67089)
		(width 0.0889)
		(layer "In4.Cu")
		(net "M_L_DQS_DP<10>")
	)
	(segment
		(start 48.220122 -116.679726)
		(end 48.623728 -117.083332)
		(width 0.14224)
		(layer "In4.Cu")
		(net "M_L_DQS_DP<10>")
	)
	(segment
		(start 47.251112 -115.679728)
		(end 47.251112 -116.27231)
		(width 0.14224)
		(layer "In4.Cu")
		(net "M_L_DQS_DP<10>")
	)
	(segment
		(start 48.623728 -117.46484)
		(end 48.331882 -117.756686)
		(width 0.14224)
		(layer "In4.Cu")
		(net "M_L_DQS_DP<10>")
	)
	(segment
		(start 66.459862 -92.627196)
		(end 61.415168 -97.67189)
		(width 0.14224)
		(layer "In4.Cu")
		(net "M_L_DQS_DP<10>")
	)
	(segment
		(start 68.132198 -92.225114)
		(end 66.918078 -92.225114)
		(width 0.0889)
		(layer "In4.Cu")
		(net "M_L_DQS_DP<10>")
	)
	(segment
		(start 44.092114 -139.827)
		(end 44.018962 -139.827)
		(width 0.14224)
		(layer "In4.Cu")
		(net "M_L_DQS_DP<10>")
	)
	(segment
		(start 70.633336 -88.68029)
		(end 70.590156 -88.68029)
		(width 0.0889)
		(layer "In4.Cu")
		(net "M_L_DQS_DP<10>")
	)
	(segment
		(start 46.789848 -118.719854)
		(end 46.789848 -125.732286)
		(width 0.14224)
		(layer "In4.Cu")
		(net "M_L_DQS_DP<10>")
	)
	(segment
		(start 68.382896 -89.966038)
		(end 68.382642 -89.966546)
		(width 0.0889)
		(layer "In4.Cu")
		(net "M_L_DQS_DP<10>")
	)
	(segment
		(start 72.89419 -90.587576)
		(end 72.870314 -90.498422)
		(width 0.0889)
		(layer "In4.Cu")
		(net "M_L_DQS_DP<10>")
	)
	(segment
		(start 68.279772 -90.493088)
		(end 68.436236 -90.649552)
		(width 0.0889)
		(layer "In4.Cu")
		(net "M_L_DQS_DP<10>")
	)
	(segment
		(start 71.488046 -89.175336)
		(end 71.45528 -89.175336)
		(width 0.0889)
		(layer "In4.Cu")
		(net "M_L_DQS_DP<10>")
	)
	(segment
		(start 61.415168 -97.67189)
		(end 61.415168 -99.061016)
		(width 0.14224)
		(layer "In4.Cu")
		(net "M_L_DQS_DP<10>")
	)
	(segment
		(start 44.378626 -139.827)
		(end 44.092114 -139.827)
		(width 0.14224)
		(layer "In4.Cu")
		(net "M_L_DQS_DP<10>")
	)
	(segment
		(start 66.531998 -92.611448)
		(end 66.47561 -92.611448)
		(width 0.0889)
		(layer "In4.Cu")
		(net "M_L_DQS_DP<10>")
	)
	(segment
		(start 56.284368 -106.646472)
		(end 47.251112 -115.679728)
		(width 0.14224)
		(layer "In4.Cu")
		(net "M_L_DQS_DP<10>")
	)
	(segment
		(start 44.605194 -139.600432)
		(end 44.378626 -139.827)
		(width 0.14224)
		(layer "In4.Cu")
		(net "M_L_DQS_DP<10>")
	)
	(segment
		(start 66.47561 -92.611448)
		(end 66.459862 -92.627196)
		(width 0.0889)
		(layer "In4.Cu")
		(net "M_L_DQS_DP<10>")
	)
	(segment
		(start 43.587162 -140.2588)
		(end 43.587162 -144.833594)
		(width 0.14224)
		(layer "In4.Cu")
		(net "M_L_DQS_DP<10>")
	)
	(segment
		(start 47.251112 -116.27231)
		(end 47.658528 -116.679726)
		(width 0.14224)
		(layer "In4.Cu")
		(net "M_L_DQS_DP<10>")
	)
	(arc
		(start 71.982076 -89.470738)
		(mid 71.773468 -89.258806)
		(end 71.488046 -89.175336)
		(width 0.0889)
		(layer "In4.Cu")
		(net "M_L_DQS_DP<10>")
	)
	(arc
		(start 71.123556 -88.975438)
		(mid 70.916552 -88.764574)
		(end 70.633336 -88.68029)
		(width 0.0889)
		(layer "In4.Cu")
		(net "M_L_DQS_DP<10>")
	)
	(arc
		(start 68.873116 -89.67089)
		(mid 68.589899 -89.755171)
		(end 68.382896 -89.966038)
		(width 0.0889)
		(layer "In4.Cu")
		(net "M_L_DQS_DP<10>")
	)
	(arc
		(start 69.241416 -89.470738)
		(mid 69.099733 -89.614542)
		(end 68.905882 -89.67089)
		(width 0.0889)
		(layer "In4.Cu")
		(net "M_L_DQS_DP<10>")
	)
	(arc
		(start 72.31761 -89.67089)
		(mid 72.12376 -89.61454)
		(end 71.982076 -89.470738)
		(width 0.0889)
		(layer "In4.Cu")
		(net "M_L_DQS_DP<10>")
	)
	(arc
		(start 71.45528 -89.175336)
		(mid 71.263638 -89.11817)
		(end 71.123556 -88.975438)
		(width 0.0889)
		(layer "In4.Cu")
		(net "M_L_DQS_DP<10>")
	)
	(arc
		(start 72.870314 -90.498422)
		(mid 72.829334 -89.947013)
		(end 72.350376 -89.67089)
		(width 0.0889)
		(layer "In4.Cu")
		(net "M_L_DQS_DP<10>")
	)
	(arc
		(start 70.590156 -88.68029)
		(mid 70.306939 -88.764571)
		(end 70.099936 -88.975438)
		(width 0.0889)
		(layer "In4.Cu")
		(net "M_L_DQS_DP<10>")
	)
	(arc
		(start 69.735446 -89.175336)
		(mid 69.450022 -89.258803)
		(end 69.241416 -89.470738)
		(width 0.0889)
		(layer "In4.Cu")
		(net "M_L_DQS_DP<10>")
	)
	(arc
		(start 70.099936 -88.975438)
		(mid 69.959857 -89.118174)
		(end 69.768212 -89.175336)
		(width 0.0889)
		(layer "In4.Cu")
		(net "M_L_DQS_DP<10>")
	)
	(segment
		(start 72.041766 -84.812886)
		(end 71.470266 -84.812886)
		(width 0.1651)
		(layer "F.Cu")
		(net "M_L_DQS_DP<0>")
	)
	(segment
		(start 36.537392 -144.8562)
		(end 36.293552 -144.61236)
		(width 0.1651)
		(layer "F.Cu")
		(net "M_L_DQS_DP<0>")
	)
	(segment
		(start 36.293552 -144.61236)
		(end 36.03752 -144.61236)
		(width 0.1651)
		(layer "F.Cu")
		(net "M_L_DQS_DP<0>")
	)
	(segment
		(start 36.499546 -147.27174)
		(end 36.499546 -146.265646)
		(width 0.1651)
		(layer "F.Cu")
		(net "M_L_DQS_DP<0>")
	)
	(segment
		(start 36.499546 -146.265646)
		(end 36.537392 -146.2278)
		(width 0.1651)
		(layer "F.Cu")
		(net "M_L_DQS_DP<0>")
	)
	(segment
		(start 36.537392 -146.2278)
		(end 36.537392 -144.8562)
		(width 0.1651)
		(layer "F.Cu")
		(net "M_L_DQS_DP<0>")
	)
	(via
		(at 36.03752 -140.541756)
		(size 0.508)
		(drill 0.254)
		(layers "F.Cu" "B.Cu")
		(net "M_L_DQS_DP<0>")
	)
	(via
		(at 71.470266 -84.812886)
		(size 0.508)
		(drill 0.254)
		(layers "F.Cu" "B.Cu")
		(net "M_L_DQS_DP<0>")
	)
	(via
		(at 36.03752 -144.61236)
		(size 0.508)
		(drill 0.254)
		(layers "F.Cu" "B.Cu")
		(net "M_L_DQS_DP<0>")
	)
	(segment
		(start 36.279836 -140.541756)
		(end 36.03752 -140.541756)
		(width 0.1651)
		(layer "B.Cu")
		(net "M_L_DQS_DP<0>")
	)
	(segment
		(start 36.537392 -139.065)
		(end 36.537392 -140.2842)
		(width 0.1651)
		(layer "B.Cu")
		(net "M_L_DQS_DP<0>")
	)
	(segment
		(start 36.499546 -137.877296)
		(end 36.499546 -139.027154)
		(width 0.1651)
		(layer "B.Cu")
		(net "M_L_DQS_DP<0>")
	)
	(segment
		(start 36.537392 -140.2842)
		(end 36.279836 -140.541756)
		(width 0.1651)
		(layer "B.Cu")
		(net "M_L_DQS_DP<0>")
	)
	(segment
		(start 36.499546 -139.027154)
		(end 36.537392 -139.065)
		(width 0.1651)
		(layer "B.Cu")
		(net "M_L_DQS_DP<0>")
	)
	(segment
		(start 66.251074 -85.89899)
		(end 67.199002 -85.89899)
		(width 0.0889)
		(layer "In4.Cu")
		(net "M_L_DQS_DP<0>")
	)
	(segment
		(start 35.860228 -142.899892)
		(end 35.80003 -142.899892)
		(width 0.14224)
		(layer "In4.Cu")
		(net "M_L_DQS_DP<0>")
	)
	(segment
		(start 36.578032 -118.188232)
		(end 36.578032 -117.311424)
		(width 0.14224)
		(layer "In4.Cu")
		(net "M_L_DQS_DP<0>")
	)
	(segment
		(start 35.66287 -141.826234)
		(end 35.66287 -142.150592)
		(width 0.14224)
		(layer "In4.Cu")
		(net "M_L_DQS_DP<0>")
	)
	(segment
		(start 36.028376 -121.360692)
		(end 35.806888 -121.139204)
		(width 0.14224)
		(layer "In4.Cu")
		(net "M_L_DQS_DP<0>")
	)
	(segment
		(start 35.806888 -120.70842)
		(end 36.028376 -120.486932)
		(width 0.14224)
		(layer "In4.Cu")
		(net "M_L_DQS_DP<0>")
	)
	(segment
		(start 35.858704 -143.4592)
		(end 36.243768 -143.4592)
		(width 0.14224)
		(layer "In4.Cu")
		(net "M_L_DQS_DP<0>")
	)
	(segment
		(start 35.685476 -123.000516)
		(end 35.91306 -122.772932)
		(width 0.14224)
		(layer "In4.Cu")
		(net "M_L_DQS_DP<0>")
	)
	(segment
		(start 64.867536 -85.849206)
		(end 64.889634 -85.849206)
		(width 0.0889)
		(layer "In4.Cu")
		(net "M_L_DQS_DP<0>")
	)
	(segment
		(start 35.777678 -142.2654)
		(end 35.862768 -142.2654)
		(width 0.14224)
		(layer "In4.Cu")
		(net "M_L_DQS_DP<0>")
	)
	(segment
		(start 35.862768 -142.2654)
		(end 36.04006 -142.442692)
		(width 0.14224)
		(layer "In4.Cu")
		(net "M_L_DQS_DP<0>")
	)
	(segment
		(start 37.330888 -118.941088)
		(end 36.578032 -118.188232)
		(width 0.14224)
		(layer "In4.Cu")
		(net "M_L_DQS_DP<0>")
	)
	(segment
		(start 36.95192 -122.772932)
		(end 37.330888 -122.393964)
		(width 0.14224)
		(layer "In4.Cu")
		(net "M_L_DQS_DP<0>")
	)
	(segment
		(start 35.926014 -125.19152)
		(end 36.992814 -125.19152)
		(width 0.14224)
		(layer "In4.Cu")
		(net "M_L_DQS_DP<0>")
	)
	(segment
		(start 68.021708 -85.403436)
		(end 68.057776 -85.403436)
		(width 0.0889)
		(layer "In4.Cu")
		(net "M_L_DQS_DP<0>")
	)
	(segment
		(start 35.705288 -127.951992)
		(end 35.705288 -125.412246)
		(width 0.14224)
		(layer "In4.Cu")
		(net "M_L_DQS_DP<0>")
	)
	(segment
		(start 37.330888 -121.738898)
		(end 36.952682 -121.360692)
		(width 0.14224)
		(layer "In4.Cu")
		(net "M_L_DQS_DP<0>")
	)
	(segment
		(start 68.87972 -84.90839)
		(end 68.912486 -84.90839)
		(width 0.0889)
		(layer "In4.Cu")
		(net "M_L_DQS_DP<0>")
	)
	(segment
		(start 36.03752 -140.541756)
		(end 36.472368 -140.976604)
		(width 0.14224)
		(layer "In4.Cu")
		(net "M_L_DQS_DP<0>")
	)
	(segment
		(start 43.09364 -109.9566)
		(end 43.939968 -109.9566)
		(width 0.14224)
		(layer "In4.Cu")
		(net "M_L_DQS_DP<0>")
	)
	(segment
		(start 39.113714 -113.936526)
		(end 43.09364 -109.9566)
		(width 0.14224)
		(layer "In4.Cu")
		(net "M_L_DQS_DP<0>")
	)
	(segment
		(start 69.961252 -84.412836)
		(end 70.50532 -84.716366)
		(width 0.0889)
		(layer "In4.Cu")
		(net "M_L_DQS_DP<0>")
	)
	(segment
		(start 35.66287 -143.037052)
		(end 35.66287 -143.263366)
		(width 0.14224)
		(layer "In4.Cu")
		(net "M_L_DQS_DP<0>")
	)
	(segment
		(start 36.04006 -142.442692)
		(end 36.04006 -142.72006)
		(width 0.14224)
		(layer "In4.Cu")
		(net "M_L_DQS_DP<0>")
	)
	(segment
		(start 70.892162 -84.721192)
		(end 71.470266 -84.812886)
		(width 0.0889)
		(layer "In4.Cu")
		(net "M_L_DQS_DP<0>")
	)
	(segment
		(start 36.243768 -143.4592)
		(end 36.497768 -143.7132)
		(width 0.14224)
		(layer "In4.Cu")
		(net "M_L_DQS_DP<0>")
	)
	(segment
		(start 35.66287 -142.150592)
		(end 35.777678 -142.2654)
		(width 0.14224)
		(layer "In4.Cu")
		(net "M_L_DQS_DP<0>")
	)
	(segment
		(start 36.497768 -144.152112)
		(end 36.03752 -144.61236)
		(width 0.14224)
		(layer "In4.Cu")
		(net "M_L_DQS_DP<0>")
	)
	(segment
		(start 35.91306 -122.772932)
		(end 36.95192 -122.772932)
		(width 0.14224)
		(layer "In4.Cu")
		(net "M_L_DQS_DP<0>")
	)
	(segment
		(start 66.16192 -85.809836)
		(end 66.251074 -85.89899)
		(width 0.0889)
		(layer "In4.Cu")
		(net "M_L_DQS_DP<0>")
	)
	(segment
		(start 35.66287 -143.263366)
		(end 35.858704 -143.4592)
		(width 0.14224)
		(layer "In4.Cu")
		(net "M_L_DQS_DP<0>")
	)
	(segment
		(start 36.028376 -120.486932)
		(end 36.95192 -120.486932)
		(width 0.14224)
		(layer "In4.Cu")
		(net "M_L_DQS_DP<0>")
	)
	(segment
		(start 37.330888 -124.02566)
		(end 36.95192 -123.646692)
		(width 0.14224)
		(layer "In4.Cu")
		(net "M_L_DQS_DP<0>")
	)
	(segment
		(start 56.367172 -93.795596)
		(end 64.313562 -85.849206)
		(width 0.14224)
		(layer "In4.Cu")
		(net "M_L_DQS_DP<0>")
	)
	(segment
		(start 36.04006 -142.72006)
		(end 35.860228 -142.899892)
		(width 0.14224)
		(layer "In4.Cu")
		(net "M_L_DQS_DP<0>")
	)
	(segment
		(start 36.95192 -120.486932)
		(end 37.330888 -120.107964)
		(width 0.14224)
		(layer "In4.Cu")
		(net "M_L_DQS_DP<0>")
	)
	(segment
		(start 37.330888 -122.393964)
		(end 37.330888 -121.738898)
		(width 0.14224)
		(layer "In4.Cu")
		(net "M_L_DQS_DP<0>")
	)
	(segment
		(start 43.939968 -109.9566)
		(end 56.367172 -97.529396)
		(width 0.14224)
		(layer "In4.Cu")
		(net "M_L_DQS_DP<0>")
	)
	(segment
		(start 36.578032 -117.311424)
		(end 39.113714 -114.775742)
		(width 0.14224)
		(layer "In4.Cu")
		(net "M_L_DQS_DP<0>")
	)
	(segment
		(start 36.03752 -140.541756)
		(end 36.046664 -140.541756)
		(width 0.14224)
		(layer "In4.Cu")
		(net "M_L_DQS_DP<0>")
	)
	(segment
		(start 35.833304 -141.6558)
		(end 35.66287 -141.826234)
		(width 0.14224)
		(layer "In4.Cu")
		(net "M_L_DQS_DP<0>")
	)
	(segment
		(start 36.81984 -129.066544)
		(end 35.705288 -127.951992)
		(width 0.14224)
		(layer "In4.Cu")
		(net "M_L_DQS_DP<0>")
	)
	(segment
		(start 36.472368 -140.976604)
		(end 36.472368 -141.4018)
		(width 0.14224)
		(layer "In4.Cu")
		(net "M_L_DQS_DP<0>")
	)
	(segment
		(start 35.899344 -123.646692)
		(end 35.685476 -123.432824)
		(width 0.14224)
		(layer "In4.Cu")
		(net "M_L_DQS_DP<0>")
	)
	(segment
		(start 56.367172 -97.529396)
		(end 56.367172 -93.795596)
		(width 0.14224)
		(layer "In4.Cu")
		(net "M_L_DQS_DP<0>")
	)
	(segment
		(start 64.889634 -85.849206)
		(end 64.929004 -85.809836)
		(width 0.0889)
		(layer "In4.Cu")
		(net "M_L_DQS_DP<0>")
	)
	(segment
		(start 70.50532 -84.716366)
		(end 70.892162 -84.721192)
		(width 0.0889)
		(layer "In4.Cu")
		(net "M_L_DQS_DP<0>")
	)
	(segment
		(start 64.929004 -85.809836)
		(end 66.16192 -85.809836)
		(width 0.0889)
		(layer "In4.Cu")
		(net "M_L_DQS_DP<0>")
	)
	(segment
		(start 36.472368 -141.4018)
		(end 36.218368 -141.6558)
		(width 0.14224)
		(layer "In4.Cu")
		(net "M_L_DQS_DP<0>")
	)
	(segment
		(start 69.74205 -84.412836)
		(end 69.961252 -84.412836)
		(width 0.0889)
		(layer "In4.Cu")
		(net "M_L_DQS_DP<0>")
	)
	(segment
		(start 36.046664 -140.541756)
		(end 36.81984 -139.76858)
		(width 0.14224)
		(layer "In4.Cu")
		(net "M_L_DQS_DP<0>")
	)
	(segment
		(start 35.80003 -142.899892)
		(end 35.66287 -143.037052)
		(width 0.14224)
		(layer "In4.Cu")
		(net "M_L_DQS_DP<0>")
	)
	(segment
		(start 35.685476 -123.432824)
		(end 35.685476 -123.000516)
		(width 0.14224)
		(layer "In4.Cu")
		(net "M_L_DQS_DP<0>")
	)
	(segment
		(start 36.95192 -123.646692)
		(end 35.899344 -123.646692)
		(width 0.14224)
		(layer "In4.Cu")
		(net "M_L_DQS_DP<0>")
	)
	(segment
		(start 35.705288 -125.412246)
		(end 35.926014 -125.19152)
		(width 0.14224)
		(layer "In4.Cu")
		(net "M_L_DQS_DP<0>")
	)
	(segment
		(start 36.952682 -121.360692)
		(end 36.028376 -121.360692)
		(width 0.14224)
		(layer "In4.Cu")
		(net "M_L_DQS_DP<0>")
	)
	(segment
		(start 36.218368 -141.6558)
		(end 35.833304 -141.6558)
		(width 0.14224)
		(layer "In4.Cu")
		(net "M_L_DQS_DP<0>")
	)
	(segment
		(start 36.992814 -125.19152)
		(end 37.330888 -124.853446)
		(width 0.14224)
		(layer "In4.Cu")
		(net "M_L_DQS_DP<0>")
	)
	(segment
		(start 35.806888 -121.139204)
		(end 35.806888 -120.70842)
		(width 0.14224)
		(layer "In4.Cu")
		(net "M_L_DQS_DP<0>")
	)
	(segment
		(start 36.81984 -139.76858)
		(end 36.81984 -129.066544)
		(width 0.14224)
		(layer "In4.Cu")
		(net "M_L_DQS_DP<0>")
	)
	(segment
		(start 37.330888 -124.853446)
		(end 37.330888 -124.02566)
		(width 0.14224)
		(layer "In4.Cu")
		(net "M_L_DQS_DP<0>")
	)
	(segment
		(start 64.313562 -85.849206)
		(end 64.867536 -85.849206)
		(width 0.14224)
		(layer "In4.Cu")
		(net "M_L_DQS_DP<0>")
	)
	(segment
		(start 39.113714 -114.775742)
		(end 39.113714 -113.936526)
		(width 0.14224)
		(layer "In4.Cu")
		(net "M_L_DQS_DP<0>")
	)
	(segment
		(start 36.497768 -143.7132)
		(end 36.497768 -144.152112)
		(width 0.14224)
		(layer "In4.Cu")
		(net "M_L_DQS_DP<0>")
	)
	(segment
		(start 37.330888 -120.107964)
		(end 37.330888 -118.941088)
		(width 0.14224)
		(layer "In4.Cu")
		(net "M_L_DQS_DP<0>")
	)
	(arc
		(start 67.199002 -85.89899)
		(mid 67.482454 -85.814709)
		(end 67.689476 -85.603588)
		(width 0.0889)
		(layer "In4.Cu")
		(net "M_L_DQS_DP<0>")
	)
	(arc
		(start 68.547996 -85.108288)
		(mid 68.688075 -84.965552)
		(end 68.87972 -84.90839)
		(width 0.0889)
		(layer "In4.Cu")
		(net "M_L_DQS_DP<0>")
	)
	(arc
		(start 67.689476 -85.603588)
		(mid 67.829744 -85.460632)
		(end 68.021708 -85.403436)
		(width 0.0889)
		(layer "In4.Cu")
		(net "M_L_DQS_DP<0>")
	)
	(arc
		(start 68.057776 -85.403436)
		(mid 68.340993 -85.319155)
		(end 68.547996 -85.108288)
		(width 0.0889)
		(layer "In4.Cu")
		(net "M_L_DQS_DP<0>")
	)
	(arc
		(start 69.406516 -84.612988)
		(mid 69.548199 -84.469184)
		(end 69.74205 -84.412836)
		(width 0.0889)
		(layer "In4.Cu")
		(net "M_L_DQS_DP<0>")
	)
	(arc
		(start 68.912486 -84.90839)
		(mid 69.19791 -84.824923)
		(end 69.406516 -84.612988)
		(width 0.0889)
		(layer "In4.Cu")
		(net "M_L_DQS_DP<0>")
	)
	(segment
		(start 35.417252 -144.602962)
		(end 35.165284 -144.85493)
		(width 0.1651)
		(layer "F.Cu")
		(net "M_L_DQS_DN<9>")
	)
	(segment
		(start 34.767774 -144.6657)
		(end 34.748724 -144.6657)
		(width 0.1651)
		(layer "F.Cu")
		(net "M_L_DQS_DN<9>")
	)
	(segment
		(start 35.165284 -144.85493)
		(end 34.957004 -144.85493)
		(width 0.1651)
		(layer "F.Cu")
		(net "M_L_DQS_DN<9>")
	)
	(segment
		(start 35.417252 -144.356328)
		(end 35.417252 -144.602962)
		(width 0.1651)
		(layer "F.Cu")
		(net "M_L_DQS_DN<9>")
	)
	(segment
		(start 35.649408 -143.331184)
		(end 35.231324 -143.749268)
		(width 0.1651)
		(layer "F.Cu")
		(net "M_L_DQS_DN<9>")
	)
	(segment
		(start 34.957004 -144.85493)
		(end 34.767774 -144.6657)
		(width 0.1651)
		(layer "F.Cu")
		(net "M_L_DQS_DN<9>")
	)
	(segment
		(start 72.900286 -85.30844)
		(end 72.328786 -85.30844)
		(width 0.1651)
		(layer "F.Cu")
		(net "M_L_DQS_DN<9>")
	)
	(segment
		(start 35.231324 -144.1704)
		(end 35.417252 -144.356328)
		(width 0.1651)
		(layer "F.Cu")
		(net "M_L_DQS_DN<9>")
	)
	(segment
		(start 35.649408 -142.6718)
		(end 35.649408 -143.331184)
		(width 0.1651)
		(layer "F.Cu")
		(net "M_L_DQS_DN<9>")
	)
	(segment
		(start 35.231324 -143.749268)
		(end 35.231324 -144.1704)
		(width 0.1651)
		(layer "F.Cu")
		(net "M_L_DQS_DN<9>")
	)
	(via
		(at 34.748724 -144.6657)
		(size 0.508)
		(drill 0.254)
		(layers "F.Cu" "B.Cu")
		(net "M_L_DQS_DN<9>")
	)
	(via
		(at 34.74212 -140.4874)
		(size 0.508)
		(drill 0.254)
		(layers "F.Cu" "B.Cu")
		(net "M_L_DQS_DN<9>")
	)
	(via
		(at 72.328786 -85.30844)
		(size 0.508)
		(drill 0.254)
		(layers "F.Cu" "B.Cu")
		(net "M_L_DQS_DN<9>")
	)
	(segment
		(start 35.383724 -140.5128)
		(end 35.16376 -140.292836)
		(width 0.1651)
		(layer "B.Cu")
		(net "M_L_DQS_DN<9>")
	)
	(segment
		(start 35.649662 -141.820392)
		(end 35.205924 -141.376654)
		(width 0.1651)
		(layer "B.Cu")
		(net "M_L_DQS_DN<9>")
	)
	(segment
		(start 35.383724 -140.843)
		(end 35.383724 -140.5128)
		(width 0.1651)
		(layer "B.Cu")
		(net "M_L_DQS_DN<9>")
	)
	(segment
		(start 35.205924 -141.0208)
		(end 35.383724 -140.843)
		(width 0.1651)
		(layer "B.Cu")
		(net "M_L_DQS_DN<9>")
	)
	(segment
		(start 35.16376 -140.292836)
		(end 34.936684 -140.292836)
		(width 0.1651)
		(layer "B.Cu")
		(net "M_L_DQS_DN<9>")
	)
	(segment
		(start 35.649408 -142.477236)
		(end 35.649662 -142.476728)
		(width 0.1651)
		(layer "B.Cu")
		(net "M_L_DQS_DN<9>")
	)
	(segment
		(start 35.205924 -141.376654)
		(end 35.205924 -141.0208)
		(width 0.1651)
		(layer "B.Cu")
		(net "M_L_DQS_DN<9>")
	)
	(segment
		(start 35.649662 -142.476728)
		(end 35.649662 -141.820392)
		(width 0.1651)
		(layer "B.Cu")
		(net "M_L_DQS_DN<9>")
	)
	(segment
		(start 34.936684 -140.292836)
		(end 34.74212 -140.4874)
		(width 0.1651)
		(layer "B.Cu")
		(net "M_L_DQS_DN<9>")
	)
	(segment
		(start 34.936176 -119.751856)
		(end 35.53079 -119.751856)
		(width 0.14224)
		(layer "In4.Cu")
		(net "M_L_DQS_DN<9>")
	)
	(segment
		(start 35.181794 -143.748506)
		(end 35.181794 -144.23263)
		(width 0.14224)
		(layer "In4.Cu")
		(net "M_L_DQS_DN<9>")
	)
	(segment
		(start 38.135814 -113.543588)
		(end 42.510202 -109.1692)
		(width 0.14224)
		(layer "In4.Cu")
		(net "M_L_DQS_DN<9>")
	)
	(segment
		(start 35.908996 -118.717822)
		(end 35.53079 -118.339616)
		(width 0.14224)
		(layer "In4.Cu")
		(net "M_L_DQS_DN<9>")
	)
	(segment
		(start 34.74212 -140.4874)
		(end 34.749486 -140.4874)
		(width 0.14224)
		(layer "In4.Cu")
		(net "M_L_DQS_DN<9>")
	)
	(segment
		(start 35.644836 -137.65276)
		(end 35.52444 -137.532364)
		(width 0.14224)
		(layer "In4.Cu")
		(net "M_L_DQS_DN<9>")
	)
	(segment
		(start 67.653154 -84.610194)
		(end 67.675252 -84.588096)
		(width 0.0889)
		(layer "In4.Cu")
		(net "M_L_DQS_DN<9>")
	)
	(segment
		(start 34.638488 -142.23492)
		(end 34.793428 -142.23492)
		(width 0.14224)
		(layer "In4.Cu")
		(net "M_L_DQS_DN<9>")
	)
	(segment
		(start 42.510202 -109.1692)
		(end 43.660314 -109.1692)
		(width 0.14224)
		(layer "In4.Cu")
		(net "M_L_DQS_DN<9>")
	)
	(segment
		(start 68.87972 -83.91779)
		(end 68.912486 -83.91779)
		(width 0.0889)
		(layer "In4.Cu")
		(net "M_L_DQS_DN<9>")
	)
	(segment
		(start 38.135814 -114.371882)
		(end 38.135814 -113.543588)
		(width 0.14224)
		(layer "In4.Cu")
		(net "M_L_DQS_DN<9>")
	)
	(segment
		(start 34.948368 -142.38986)
		(end 34.948368 -142.74292)
		(width 0.14224)
		(layer "In4.Cu")
		(net "M_L_DQS_DN<9>")
	)
	(segment
		(start 71.448676 -84.412836)
		(end 71.481442 -84.412836)
		(width 0.0889)
		(layer "In4.Cu")
		(net "M_L_DQS_DN<9>")
	)
	(segment
		(start 34.646108 -142.89786)
		(end 34.506408 -143.03756)
		(width 0.14224)
		(layer "In4.Cu")
		(net "M_L_DQS_DN<9>")
	)
	(segment
		(start 72.311006 -84.90839)
		(end 72.343772 -84.90839)
		(width 0.0889)
		(layer "In4.Cu")
		(net "M_L_DQS_DN<9>")
	)
	(segment
		(start 34.881312 -118.339616)
		(end 34.714688 -118.172992)
		(width 0.14224)
		(layer "In4.Cu")
		(net "M_L_DQS_DN<9>")
	)
	(segment
		(start 35.53079 -118.339616)
		(end 34.881312 -118.339616)
		(width 0.14224)
		(layer "In4.Cu")
		(net "M_L_DQS_DN<9>")
	)
	(segment
		(start 34.74212 -140.4874)
		(end 35.176968 -140.922248)
		(width 0.14224)
		(layer "In4.Cu")
		(net "M_L_DQS_DN<9>")
	)
	(segment
		(start 34.897568 -141.605)
		(end 34.656268 -141.605)
		(width 0.14224)
		(layer "In4.Cu")
		(net "M_L_DQS_DN<9>")
	)
	(segment
		(start 70.593966 -83.91779)
		(end 70.626732 -83.91779)
		(width 0.0889)
		(layer "In4.Cu")
		(net "M_L_DQS_DN<9>")
	)
	(segment
		(start 34.506408 -142.10284)
		(end 34.638488 -142.23492)
		(width 0.14224)
		(layer "In4.Cu")
		(net "M_L_DQS_DN<9>")
	)
	(segment
		(start 34.506408 -143.39824)
		(end 34.668968 -143.5608)
		(width 0.14224)
		(layer "In4.Cu")
		(net "M_L_DQS_DN<9>")
	)
	(segment
		(start 35.52444 -138.31824)
		(end 35.52444 -138.027156)
		(width 0.14224)
		(layer "In4.Cu")
		(net "M_L_DQS_DN<9>")
	)
	(segment
		(start 55.619142 -97.210372)
		(end 55.619142 -93.266006)
		(width 0.14224)
		(layer "In4.Cu")
		(net "M_L_DQS_DN<9>")
	)
	(segment
		(start 66.190368 -84.83092)
		(end 66.229738 -84.79155)
		(width 0.0889)
		(layer "In4.Cu")
		(net "M_L_DQS_DN<9>")
	)
	(segment
		(start 35.908996 -119.37365)
		(end 35.908996 -118.717822)
		(width 0.14224)
		(layer "In4.Cu")
		(net "M_L_DQS_DN<9>")
	)
	(segment
		(start 34.714688 -119.973344)
		(end 34.936176 -119.751856)
		(width 0.14224)
		(layer "In4.Cu")
		(net "M_L_DQS_DN<9>")
	)
	(segment
		(start 35.181794 -144.23263)
		(end 34.748724 -144.6657)
		(width 0.14224)
		(layer "In4.Cu")
		(net "M_L_DQS_DN<9>")
	)
	(segment
		(start 34.793428 -142.89786)
		(end 34.646108 -142.89786)
		(width 0.14224)
		(layer "In4.Cu")
		(net "M_L_DQS_DN<9>")
	)
	(segment
		(start 43.660314 -109.1692)
		(end 55.619142 -97.210372)
		(width 0.14224)
		(layer "In4.Cu")
		(net "M_L_DQS_DN<9>")
	)
	(segment
		(start 35.52444 -138.8872)
		(end 35.68192 -138.72972)
		(width 0.14224)
		(layer "In4.Cu")
		(net "M_L_DQS_DN<9>")
	)
	(segment
		(start 34.994088 -143.5608)
		(end 35.181794 -143.748506)
		(width 0.14224)
		(layer "In4.Cu")
		(net "M_L_DQS_DN<9>")
	)
	(segment
		(start 35.52444 -129.294382)
		(end 34.714688 -128.48463)
		(width 0.14224)
		(layer "In4.Cu")
		(net "M_L_DQS_DN<9>")
	)
	(segment
		(start 67.675252 -84.588096)
		(end 67.675252 -84.57311)
		(width 0.0889)
		(layer "In4.Cu")
		(net "M_L_DQS_DN<9>")
	)
	(segment
		(start 35.176968 -141.3256)
		(end 34.897568 -141.605)
		(width 0.14224)
		(layer "In4.Cu")
		(net "M_L_DQS_DN<9>")
	)
	(segment
		(start 64.054228 -84.83092)
		(end 66.16827 -84.83092)
		(width 0.14224)
		(layer "In4.Cu")
		(net "M_L_DQS_DN<9>")
	)
	(segment
		(start 66.733674 -84.90839)
		(end 67.304158 -84.90839)
		(width 0.0889)
		(layer "In4.Cu")
		(net "M_L_DQS_DN<9>")
	)
	(segment
		(start 35.53079 -119.751856)
		(end 35.908996 -119.37365)
		(width 0.14224)
		(layer "In4.Cu")
		(net "M_L_DQS_DN<9>")
	)
	(segment
		(start 34.714688 -118.172992)
		(end 34.714688 -117.793008)
		(width 0.14224)
		(layer "In4.Cu")
		(net "M_L_DQS_DN<9>")
	)
	(segment
		(start 34.749486 -140.4874)
		(end 35.52444 -139.712446)
		(width 0.14224)
		(layer "In4.Cu")
		(net "M_L_DQS_DN<9>")
	)
	(segment
		(start 35.176968 -140.922248)
		(end 35.176968 -141.3256)
		(width 0.14224)
		(layer "In4.Cu")
		(net "M_L_DQS_DN<9>")
	)
	(segment
		(start 67.869816 -84.412836)
		(end 68.057776 -84.412836)
		(width 0.0889)
		(layer "In4.Cu")
		(net "M_L_DQS_DN<9>")
	)
	(segment
		(start 34.506408 -143.03756)
		(end 34.506408 -143.39824)
		(width 0.14224)
		(layer "In4.Cu")
		(net "M_L_DQS_DN<9>")
	)
	(segment
		(start 35.68192 -138.47572)
		(end 35.52444 -138.31824)
		(width 0.14224)
		(layer "In4.Cu")
		(net "M_L_DQS_DN<9>")
	)
	(segment
		(start 35.644836 -137.90676)
		(end 35.644836 -137.65276)
		(width 0.14224)
		(layer "In4.Cu")
		(net "M_L_DQS_DN<9>")
	)
	(segment
		(start 34.714688 -128.48463)
		(end 34.714688 -119.973344)
		(width 0.14224)
		(layer "In4.Cu")
		(net "M_L_DQS_DN<9>")
	)
	(segment
		(start 34.656268 -141.605)
		(end 34.506408 -141.75486)
		(width 0.14224)
		(layer "In4.Cu")
		(net "M_L_DQS_DN<9>")
	)
	(segment
		(start 35.52444 -137.532364)
		(end 35.52444 -129.294382)
		(width 0.14224)
		(layer "In4.Cu")
		(net "M_L_DQS_DN<9>")
	)
	(segment
		(start 55.619142 -93.266006)
		(end 64.054228 -84.83092)
		(width 0.14224)
		(layer "In4.Cu")
		(net "M_L_DQS_DN<9>")
	)
	(segment
		(start 35.52444 -138.027156)
		(end 35.644836 -137.90676)
		(width 0.14224)
		(layer "In4.Cu")
		(net "M_L_DQS_DN<9>")
	)
	(segment
		(start 34.793428 -142.23492)
		(end 34.948368 -142.38986)
		(width 0.14224)
		(layer "In4.Cu")
		(net "M_L_DQS_DN<9>")
	)
	(segment
		(start 34.714688 -117.793008)
		(end 38.135814 -114.371882)
		(width 0.14224)
		(layer "In4.Cu")
		(net "M_L_DQS_DN<9>")
	)
	(segment
		(start 34.948368 -142.74292)
		(end 34.793428 -142.89786)
		(width 0.14224)
		(layer "In4.Cu")
		(net "M_L_DQS_DN<9>")
	)
	(segment
		(start 72.700642 -85.456014)
		(end 72.621902 -85.47735)
		(width 0.0889)
		(layer "In4.Cu")
		(net "M_L_DQS_DN<9>")
	)
	(segment
		(start 69.735192 -83.42249)
		(end 69.77126 -83.42249)
		(width 0.0889)
		(layer "In4.Cu")
		(net "M_L_DQS_DN<9>")
	)
	(segment
		(start 66.229738 -84.79155)
		(end 66.616834 -84.79155)
		(width 0.0889)
		(layer "In4.Cu")
		(net "M_L_DQS_DN<9>")
	)
	(segment
		(start 66.616834 -84.79155)
		(end 66.733674 -84.90839)
		(width 0.0889)
		(layer "In4.Cu")
		(net "M_L_DQS_DN<9>")
	)
	(segment
		(start 72.621902 -85.47735)
		(end 72.328786 -85.30844)
		(width 0.0889)
		(layer "In4.Cu")
		(net "M_L_DQS_DN<9>")
	)
	(segment
		(start 66.16827 -84.83092)
		(end 66.190368 -84.83092)
		(width 0.0889)
		(layer "In4.Cu")
		(net "M_L_DQS_DN<9>")
	)
	(segment
		(start 35.52444 -139.712446)
		(end 35.52444 -138.8872)
		(width 0.14224)
		(layer "In4.Cu")
		(net "M_L_DQS_DN<9>")
	)
	(segment
		(start 35.68192 -138.72972)
		(end 35.68192 -138.47572)
		(width 0.14224)
		(layer "In4.Cu")
		(net "M_L_DQS_DN<9>")
	)
	(segment
		(start 34.668968 -143.5608)
		(end 34.994088 -143.5608)
		(width 0.14224)
		(layer "In4.Cu")
		(net "M_L_DQS_DN<9>")
	)
	(segment
		(start 34.506408 -141.75486)
		(end 34.506408 -142.10284)
		(width 0.14224)
		(layer "In4.Cu")
		(net "M_L_DQS_DN<9>")
	)
	(arc
		(start 72.343772 -84.90839)
		(mid 72.663932 -85.089855)
		(end 72.700642 -85.456014)
		(width 0.0889)
		(layer "In4.Cu")
		(net "M_L_DQS_DN<9>")
	)
	(arc
		(start 70.099936 -83.622388)
		(mid 70.308544 -83.83432)
		(end 70.593966 -83.91779)
		(width 0.0889)
		(layer "In4.Cu")
		(net "M_L_DQS_DN<9>")
	)
	(arc
		(start 69.406516 -83.622388)
		(mid 69.54526 -83.480355)
		(end 69.735192 -83.42249)
		(width 0.0889)
		(layer "In4.Cu")
		(net "M_L_DQS_DN<9>")
	)
	(arc
		(start 71.481442 -84.412836)
		(mid 71.675292 -84.469186)
		(end 71.816976 -84.612988)
		(width 0.0889)
		(layer "In4.Cu")
		(net "M_L_DQS_DN<9>")
	)
	(arc
		(start 68.547996 -84.117688)
		(mid 68.688075 -83.974952)
		(end 68.87972 -83.91779)
		(width 0.0889)
		(layer "In4.Cu")
		(net "M_L_DQS_DN<9>")
	)
	(arc
		(start 67.304158 -84.90839)
		(mid 67.507056 -84.79253)
		(end 67.653154 -84.610194)
		(width 0.0889)
		(layer "In4.Cu")
		(net "M_L_DQS_DN<9>")
	)
	(arc
		(start 68.912486 -83.91779)
		(mid 69.19791 -83.834323)
		(end 69.406516 -83.622388)
		(width 0.0889)
		(layer "In4.Cu")
		(net "M_L_DQS_DN<9>")
	)
	(arc
		(start 68.057776 -84.412836)
		(mid 68.340993 -84.328555)
		(end 68.547996 -84.117688)
		(width 0.0889)
		(layer "In4.Cu")
		(net "M_L_DQS_DN<9>")
	)
	(arc
		(start 69.77126 -83.42249)
		(mid 69.961189 -83.48036)
		(end 70.099936 -83.622388)
		(width 0.0889)
		(layer "In4.Cu")
		(net "M_L_DQS_DN<9>")
	)
	(arc
		(start 70.626732 -83.91779)
		(mid 70.818374 -83.974956)
		(end 70.958456 -84.117688)
		(width 0.0889)
		(layer "In4.Cu")
		(net "M_L_DQS_DN<9>")
	)
	(arc
		(start 71.816976 -84.612988)
		(mid 72.025584 -84.82492)
		(end 72.311006 -84.90839)
		(width 0.0889)
		(layer "In4.Cu")
		(net "M_L_DQS_DN<9>")
	)
	(arc
		(start 70.958456 -84.117688)
		(mid 71.16546 -84.328552)
		(end 71.448676 -84.412836)
		(width 0.0889)
		(layer "In4.Cu")
		(net "M_L_DQS_DN<9>")
	)
	(arc
		(start 67.675252 -84.57311)
		(mid 67.760607 -84.478488)
		(end 67.869816 -84.412836)
		(width 0.0889)
		(layer "In4.Cu")
		(net "M_L_DQS_DN<9>")
	)
	(segment
		(start 83.349592 -104.105202)
		(end 83.349592 -104.607106)
		(width 0.1016)
		(layer "F.Cu")
		(net "M_L_DQS_DN<8>")
	)
	(segment
		(start 73.848468 -121.909586)
		(end 73.943464 -122.004582)
		(width 0.1651)
		(layer "F.Cu")
		(net "M_L_DQS_DN<8>")
	)
	(segment
		(start 75.901804 -111.679482)
		(end 75.722226 -111.85906)
		(width 0.1651)
		(layer "F.Cu")
		(net "M_L_DQS_DN<8>")
	)
	(segment
		(start 77.616812 -109.964474)
		(end 77.381862 -110.199424)
		(width 0.1651)
		(layer "F.Cu")
		(net "M_L_DQS_DN<8>")
	)
	(segment
		(start 73.943464 -125.05055)
		(end 73.684638 -125.309376)
		(width 0.1651)
		(layer "F.Cu")
		(net "M_L_DQS_DN<8>")
	)
	(segment
		(start 83.349592 -104.607106)
		(end 79.241904 -108.714794)
		(width 0.1016)
		(layer "F.Cu")
		(net "M_L_DQS_DN<8>")
	)
	(segment
		(start 73.943464 -120.596914)
		(end 73.943464 -121.503694)
		(width 0.1651)
		(layer "F.Cu")
		(net "M_L_DQS_DN<8>")
	)
	(segment
		(start 74.615802 -116.41709)
		(end 74.458322 -116.57457)
		(width 0.1651)
		(layer "F.Cu")
		(net "M_L_DQS_DN<8>")
	)
	(segment
		(start 72.667368 -145.821654)
		(end 72.667368 -145.389854)
		(width 0.1651)
		(layer "F.Cu")
		(net "M_L_DQS_DN<8>")
	)
	(segment
		(start 74.506328 -113.565432)
		(end 74.615802 -113.674906)
		(width 0.1651)
		(layer "F.Cu")
		(net "M_L_DQS_DN<8>")
	)
	(segment
		(start 76.455016 -110.932214)
		(end 76.455016 -111.12627)
		(width 0.1651)
		(layer "F.Cu")
		(net "M_L_DQS_DN<8>")
	)
	(segment
		(start 72.667368 -145.389854)
		(end 72.997822 -145.0594)
		(width 0.1651)
		(layer "F.Cu")
		(net "M_L_DQS_DN<8>")
	)
	(segment
		(start 72.997822 -145.0594)
		(end 73.22185 -145.0594)
		(width 0.1651)
		(layer "F.Cu")
		(net "M_L_DQS_DN<8>")
	)
	(segment
		(start 77.187806 -110.199424)
		(end 77.008228 -110.379002)
		(width 0.1651)
		(layer "F.Cu")
		(net "M_L_DQS_DN<8>")
	)
	(segment
		(start 73.642474 -119.723408)
		(end 73.642474 -120.295924)
		(width 0.1651)
		(layer "F.Cu")
		(net "M_L_DQS_DN<8>")
	)
	(segment
		(start 74.615802 -113.201958)
		(end 74.506328 -113.311432)
		(width 0.1651)
		(layer "F.Cu")
		(net "M_L_DQS_DN<8>")
	)
	(segment
		(start 73.943464 -122.004582)
		(end 73.943464 -122.2756)
		(width 0.1651)
		(layer "F.Cu")
		(net "M_L_DQS_DN<8>")
	)
	(segment
		(start 74.470768 -118.726966)
		(end 74.635868 -118.892066)
		(width 0.1651)
		(layer "F.Cu")
		(net "M_L_DQS_DN<8>")
	)
	(segment
		(start 74.615802 -116.16309)
		(end 74.615802 -116.41709)
		(width 0.1651)
		(layer "F.Cu")
		(net "M_L_DQS_DN<8>")
	)
	(segment
		(start 77.008228 -110.573058)
		(end 76.82865 -110.752636)
		(width 0.1651)
		(layer "F.Cu")
		(net "M_L_DQS_DN<8>")
	)
	(segment
		(start 74.458322 -115.75161)
		(end 74.458322 -116.00561)
		(width 0.1651)
		(layer "F.Cu")
		(net "M_L_DQS_DN<8>")
	)
	(segment
		(start 77.008228 -110.379002)
		(end 77.008228 -110.573058)
		(width 0.1651)
		(layer "F.Cu")
		(net "M_L_DQS_DN<8>")
	)
	(segment
		(start 84.060792 -99.67214)
		(end 84.037932 -99.695)
		(width 0.0889)
		(layer "F.Cu")
		(net "M_L_DQS_DN<8>")
	)
	(segment
		(start 74.449432 -117.408452)
		(end 74.010774 -117.408452)
		(width 0.1651)
		(layer "F.Cu")
		(net "M_L_DQS_DN<8>")
	)
	(segment
		(start 73.943464 -123.0376)
		(end 73.816464 -123.1646)
		(width 0.1651)
		(layer "F.Cu")
		(net "M_L_DQS_DN<8>")
	)
	(segment
		(start 79.241904 -108.714794)
		(end 78.866492 -108.714794)
		(width 0.1016)
		(layer "F.Cu")
		(net "M_L_DQS_DN<8>")
	)
	(segment
		(start 74.458322 -114.92865)
		(end 74.458322 -115.18265)
		(width 0.1651)
		(layer "F.Cu")
		(net "M_L_DQS_DN<8>")
	)
	(segment
		(start 74.79538 -112.785906)
		(end 74.615802 -112.965484)
		(width 0.1651)
		(layer "F.Cu")
		(net "M_L_DQS_DN<8>")
	)
	(segment
		(start 74.615802 -116.98605)
		(end 74.615802 -117.242082)
		(width 0.1651)
		(layer "F.Cu")
		(net "M_L_DQS_DN<8>")
	)
	(segment
		(start 84.037932 -99.695)
		(end 84.037932 -100.492814)
		(width 0.0889)
		(layer "F.Cu")
		(net "M_L_DQS_DN<8>")
	)
	(segment
		(start 73.816464 -123.9266)
		(end 73.816464 -124.1806)
		(width 0.1651)
		(layer "F.Cu")
		(net "M_L_DQS_DN<8>")
	)
	(segment
		(start 73.943464 -122.7836)
		(end 73.943464 -123.0376)
		(width 0.1651)
		(layer "F.Cu")
		(net "M_L_DQS_DN<8>")
	)
	(segment
		(start 74.615802 -115.34013)
		(end 74.615802 -115.59413)
		(width 0.1651)
		(layer "F.Cu")
		(net "M_L_DQS_DN<8>")
	)
	(segment
		(start 74.79538 -112.59185)
		(end 74.79538 -112.785906)
		(width 0.1651)
		(layer "F.Cu")
		(net "M_L_DQS_DN<8>")
	)
	(segment
		(start 77.9907 -109.590586)
		(end 77.79639 -109.590586)
		(width 0.1651)
		(layer "F.Cu")
		(net "M_L_DQS_DN<8>")
	)
	(segment
		(start 74.458322 -116.57457)
		(end 74.458322 -116.82857)
		(width 0.1651)
		(layer "F.Cu")
		(net "M_L_DQS_DN<8>")
	)
	(segment
		(start 75.348592 -112.232694)
		(end 75.169014 -112.412272)
		(width 0.1651)
		(layer "F.Cu")
		(net "M_L_DQS_DN<8>")
	)
	(segment
		(start 73.22185 -145.0594)
		(end 73.437496 -145.275046)
		(width 0.1651)
		(layer "F.Cu")
		(net "M_L_DQS_DN<8>")
	)
	(segment
		(start 75.722226 -111.85906)
		(end 75.52817 -111.85906)
		(width 0.1651)
		(layer "F.Cu")
		(net "M_L_DQS_DN<8>")
	)
	(segment
		(start 77.79639 -109.590586)
		(end 77.616812 -109.770164)
		(width 0.1651)
		(layer "F.Cu")
		(net "M_L_DQS_DN<8>")
	)
	(segment
		(start 73.943464 -122.2756)
		(end 73.816464 -122.4026)
		(width 0.1651)
		(layer "F.Cu")
		(net "M_L_DQS_DN<8>")
	)
	(segment
		(start 75.52817 -111.85906)
		(end 75.348592 -112.038638)
		(width 0.1651)
		(layer "F.Cu")
		(net "M_L_DQS_DN<8>")
	)
	(segment
		(start 76.634594 -110.752636)
		(end 76.455016 -110.932214)
		(width 0.1651)
		(layer "F.Cu")
		(net "M_L_DQS_DN<8>")
	)
	(segment
		(start 78.866492 -108.714794)
		(end 78.446884 -109.134402)
		(width 0.1016)
		(layer "F.Cu")
		(net "M_L_DQS_DN<8>")
	)
	(segment
		(start 74.635868 -119.222266)
		(end 74.470768 -119.387366)
		(width 0.1651)
		(layer "F.Cu")
		(net "M_L_DQS_DN<8>")
	)
	(segment
		(start 73.66 -117.759226)
		(end 73.66 -118.379748)
		(width 0.1651)
		(layer "F.Cu")
		(net "M_L_DQS_DN<8>")
	)
	(segment
		(start 76.455016 -111.12627)
		(end 76.275438 -111.305848)
		(width 0.1651)
		(layer "F.Cu")
		(net "M_L_DQS_DN<8>")
	)
	(segment
		(start 73.66 -118.379748)
		(end 74.007218 -118.726966)
		(width 0.1651)
		(layer "F.Cu")
		(net "M_L_DQS_DN<8>")
	)
	(segment
		(start 74.458322 -115.18265)
		(end 74.615802 -115.34013)
		(width 0.1651)
		(layer "F.Cu")
		(net "M_L_DQS_DN<8>")
	)
	(segment
		(start 73.816464 -124.1806)
		(end 73.943464 -124.3076)
		(width 0.1651)
		(layer "F.Cu")
		(net "M_L_DQS_DN<8>")
	)
	(segment
		(start 74.458322 -114.10569)
		(end 74.458322 -114.35969)
		(width 0.1651)
		(layer "F.Cu")
		(net "M_L_DQS_DN<8>")
	)
	(segment
		(start 73.943464 -123.7996)
		(end 73.816464 -123.9266)
		(width 0.1651)
		(layer "F.Cu")
		(net "M_L_DQS_DN<8>")
	)
	(segment
		(start 74.615802 -112.965484)
		(end 74.615802 -113.201958)
		(width 0.1651)
		(layer "F.Cu")
		(net "M_L_DQS_DN<8>")
	)
	(segment
		(start 74.974958 -112.412272)
		(end 74.79538 -112.59185)
		(width 0.1651)
		(layer "F.Cu")
		(net "M_L_DQS_DN<8>")
	)
	(segment
		(start 74.458322 -114.35969)
		(end 74.615802 -114.51717)
		(width 0.1651)
		(layer "F.Cu")
		(net "M_L_DQS_DN<8>")
	)
	(segment
		(start 73.816464 -122.6566)
		(end 73.943464 -122.7836)
		(width 0.1651)
		(layer "F.Cu")
		(net "M_L_DQS_DN<8>")
	)
	(segment
		(start 78.446884 -109.134402)
		(end 77.9907 -109.590586)
		(width 0.1651)
		(layer "F.Cu")
		(net "M_L_DQS_DN<8>")
	)
	(segment
		(start 75.348592 -112.038638)
		(end 75.348592 -112.232694)
		(width 0.1651)
		(layer "F.Cu")
		(net "M_L_DQS_DN<8>")
	)
	(segment
		(start 73.943464 -124.3076)
		(end 73.943464 -125.05055)
		(width 0.1651)
		(layer "F.Cu")
		(net "M_L_DQS_DN<8>")
	)
	(segment
		(start 74.007218 -118.726966)
		(end 74.470768 -118.726966)
		(width 0.1651)
		(layer "F.Cu")
		(net "M_L_DQS_DN<8>")
	)
	(segment
		(start 74.470768 -119.387366)
		(end 73.978516 -119.387366)
		(width 0.1651)
		(layer "F.Cu")
		(net "M_L_DQS_DN<8>")
	)
	(segment
		(start 73.978516 -119.387366)
		(end 73.642474 -119.723408)
		(width 0.1651)
		(layer "F.Cu")
		(net "M_L_DQS_DN<8>")
	)
	(segment
		(start 73.816464 -123.1646)
		(end 73.816464 -123.4186)
		(width 0.1651)
		(layer "F.Cu")
		(net "M_L_DQS_DN<8>")
	)
	(segment
		(start 76.82865 -110.752636)
		(end 76.634594 -110.752636)
		(width 0.1651)
		(layer "F.Cu")
		(net "M_L_DQS_DN<8>")
	)
	(segment
		(start 74.615802 -117.242082)
		(end 74.449432 -117.408452)
		(width 0.1651)
		(layer "F.Cu")
		(net "M_L_DQS_DN<8>")
	)
	(segment
		(start 84.037932 -100.492814)
		(end 84.037932 -103.416862)
		(width 0.1016)
		(layer "F.Cu")
		(net "M_L_DQS_DN<8>")
	)
	(segment
		(start 74.635868 -118.892066)
		(end 74.635868 -119.222266)
		(width 0.1651)
		(layer "F.Cu")
		(net "M_L_DQS_DN<8>")
	)
	(segment
		(start 74.615802 -114.51717)
		(end 74.615802 -114.77117)
		(width 0.1651)
		(layer "F.Cu")
		(net "M_L_DQS_DN<8>")
	)
	(segment
		(start 73.642474 -120.295924)
		(end 73.943464 -120.596914)
		(width 0.1651)
		(layer "F.Cu")
		(net "M_L_DQS_DN<8>")
	)
	(segment
		(start 84.037932 -103.416862)
		(end 83.349592 -104.105202)
		(width 0.1016)
		(layer "F.Cu")
		(net "M_L_DQS_DN<8>")
	)
	(segment
		(start 74.615802 -113.674906)
		(end 74.615802 -113.94821)
		(width 0.1651)
		(layer "F.Cu")
		(net "M_L_DQS_DN<8>")
	)
	(segment
		(start 73.816464 -122.4026)
		(end 73.816464 -122.6566)
		(width 0.1651)
		(layer "F.Cu")
		(net "M_L_DQS_DN<8>")
	)
	(segment
		(start 73.943464 -121.503694)
		(end 73.848468 -121.59869)
		(width 0.1651)
		(layer "F.Cu")
		(net "M_L_DQS_DN<8>")
	)
	(segment
		(start 77.381862 -110.199424)
		(end 77.187806 -110.199424)
		(width 0.1651)
		(layer "F.Cu")
		(net "M_L_DQS_DN<8>")
	)
	(segment
		(start 75.901804 -111.485426)
		(end 75.901804 -111.679482)
		(width 0.1651)
		(layer "F.Cu")
		(net "M_L_DQS_DN<8>")
	)
	(segment
		(start 75.169014 -112.412272)
		(end 74.974958 -112.412272)
		(width 0.1651)
		(layer "F.Cu")
		(net "M_L_DQS_DN<8>")
	)
	(segment
		(start 74.615802 -115.59413)
		(end 74.458322 -115.75161)
		(width 0.1651)
		(layer "F.Cu")
		(net "M_L_DQS_DN<8>")
	)
	(segment
		(start 74.615802 -114.77117)
		(end 74.458322 -114.92865)
		(width 0.1651)
		(layer "F.Cu")
		(net "M_L_DQS_DN<8>")
	)
	(segment
		(start 76.081382 -111.305848)
		(end 75.901804 -111.485426)
		(width 0.1651)
		(layer "F.Cu")
		(net "M_L_DQS_DN<8>")
	)
	(segment
		(start 74.458322 -116.82857)
		(end 74.615802 -116.98605)
		(width 0.1651)
		(layer "F.Cu")
		(net "M_L_DQS_DN<8>")
	)
	(segment
		(start 76.275438 -111.305848)
		(end 76.081382 -111.305848)
		(width 0.1651)
		(layer "F.Cu")
		(net "M_L_DQS_DN<8>")
	)
	(segment
		(start 74.458322 -116.00561)
		(end 74.615802 -116.16309)
		(width 0.1651)
		(layer "F.Cu")
		(net "M_L_DQS_DN<8>")
	)
	(segment
		(start 74.010774 -117.408452)
		(end 73.66 -117.759226)
		(width 0.1651)
		(layer "F.Cu")
		(net "M_L_DQS_DN<8>")
	)
	(segment
		(start 73.684638 -125.309376)
		(end 73.437496 -125.309376)
		(width 0.1651)
		(layer "F.Cu")
		(net "M_L_DQS_DN<8>")
	)
	(segment
		(start 73.816464 -123.4186)
		(end 73.943464 -123.5456)
		(width 0.1651)
		(layer "F.Cu")
		(net "M_L_DQS_DN<8>")
	)
	(segment
		(start 74.506328 -113.311432)
		(end 74.506328 -113.565432)
		(width 0.1651)
		(layer "F.Cu")
		(net "M_L_DQS_DN<8>")
	)
	(segment
		(start 73.943464 -123.5456)
		(end 73.943464 -123.7996)
		(width 0.1651)
		(layer "F.Cu")
		(net "M_L_DQS_DN<8>")
	)
	(segment
		(start 73.049384 -146.20367)
		(end 72.667368 -145.821654)
		(width 0.1651)
		(layer "F.Cu")
		(net "M_L_DQS_DN<8>")
	)
	(segment
		(start 77.616812 -109.770164)
		(end 77.616812 -109.964474)
		(width 0.1651)
		(layer "F.Cu")
		(net "M_L_DQS_DN<8>")
	)
	(segment
		(start 73.848468 -121.59869)
		(end 73.848468 -121.909586)
		(width 0.1651)
		(layer "F.Cu")
		(net "M_L_DQS_DN<8>")
	)
	(segment
		(start 73.049384 -147.27174)
		(end 73.049384 -146.20367)
		(width 0.1651)
		(layer "F.Cu")
		(net "M_L_DQS_DN<8>")
	)
	(segment
		(start 74.615802 -113.94821)
		(end 74.458322 -114.10569)
		(width 0.1651)
		(layer "F.Cu")
		(net "M_L_DQS_DN<8>")
	)
	(via
		(at 73.437496 -125.309376)
		(size 0.508)
		(drill 0.254)
		(layers "F.Cu" "B.Cu")
		(net "M_L_DQS_DN<8>")
	)
	(via
		(at 73.437496 -145.275046)
		(size 0.508)
		(drill 0.254)
		(layers "F.Cu" "B.Cu")
		(net "M_L_DQS_DN<8>")
	)
	(via
		(at 73.437496 -139.881356)
		(size 0.508)
		(drill 0.254)
		(layers "F.Cu" "B.Cu")
		(net "M_L_DQS_DN<8>")
	)
	(segment
		(start 73.049384 -138.78433)
		(end 72.921368 -138.912346)
		(width 0.1651)
		(layer "B.Cu")
		(net "M_L_DQS_DN<8>")
	)
	(segment
		(start 73.049384 -137.877296)
		(end 73.049384 -138.78433)
		(width 0.1651)
		(layer "B.Cu")
		(net "M_L_DQS_DN<8>")
	)
	(segment
		(start 72.667368 -139.7508)
		(end 73.022968 -140.1064)
		(width 0.1651)
		(layer "B.Cu")
		(net "M_L_DQS_DN<8>")
	)
	(segment
		(start 73.212452 -140.1064)
		(end 73.437496 -139.881356)
		(width 0.1651)
		(layer "B.Cu")
		(net "M_L_DQS_DN<8>")
	)
	(segment
		(start 72.921368 -138.912346)
		(end 72.921368 -139.166346)
		(width 0.1651)
		(layer "B.Cu")
		(net "M_L_DQS_DN<8>")
	)
	(segment
		(start 73.022968 -140.1064)
		(end 73.212452 -140.1064)
		(width 0.1651)
		(layer "B.Cu")
		(net "M_L_DQS_DN<8>")
	)
	(segment
		(start 72.921368 -139.166346)
		(end 72.667368 -139.420346)
		(width 0.1651)
		(layer "B.Cu")
		(net "M_L_DQS_DN<8>")
	)
	(segment
		(start 72.667368 -139.420346)
		(end 72.667368 -139.7508)
		(width 0.1651)
		(layer "B.Cu")
		(net "M_L_DQS_DN<8>")
	)
	(segment
		(start 73.364344 -139.881356)
		(end 73.437496 -139.881356)
		(width 0.14224)
		(layer "In9.Cu")
		(net "M_L_DQS_DN<8>")
	)
	(segment
		(start 72.793606 -143.37538)
		(end 72.793606 -141.71422)
		(width 0.14224)
		(layer "In9.Cu")
		(net "M_L_DQS_DN<8>")
	)
	(segment
		(start 73.004426 -141.5034)
		(end 73.004426 -140.241274)
		(width 0.14224)
		(layer "In9.Cu")
		(net "M_L_DQS_DN<8>")
	)
	(segment
		(start 73.004426 -144.841976)
		(end 73.004426 -143.5862)
		(width 0.14224)
		(layer "In9.Cu")
		(net "M_L_DQS_DN<8>")
	)
	(segment
		(start 72.793606 -141.71422)
		(end 73.004426 -141.5034)
		(width 0.14224)
		(layer "In9.Cu")
		(net "M_L_DQS_DN<8>")
	)
	(segment
		(start 73.437496 -145.275046)
		(end 73.004426 -144.841976)
		(width 0.14224)
		(layer "In9.Cu")
		(net "M_L_DQS_DN<8>")
	)
	(segment
		(start 73.004426 -140.241274)
		(end 73.364344 -139.881356)
		(width 0.14224)
		(layer "In9.Cu")
		(net "M_L_DQS_DN<8>")
	)
	(segment
		(start 73.004426 -143.5862)
		(end 72.793606 -143.37538)
		(width 0.14224)
		(layer "In9.Cu")
		(net "M_L_DQS_DN<8>")
	)
	(segment
		(start 72.990456 -125.756416)
		(end 72.990456 -126.916688)
		(width 0.14224)
		(layer "In11.Cu")
		(net "M_L_DQS_DN<8>")
	)
	(segment
		(start 73.950576 -138.773408)
		(end 73.950576 -139.36853)
		(width 0.14224)
		(layer "In11.Cu")
		(net "M_L_DQS_DN<8>")
	)
	(segment
		(start 73.950576 -128.092454)
		(end 73.950576 -132.1816)
		(width 0.14224)
		(layer "In11.Cu")
		(net "M_L_DQS_DN<8>")
	)
	(segment
		(start 73.43775 -139.881356)
		(end 73.437496 -139.881356)
		(width 0.14224)
		(layer "In11.Cu")
		(net "M_L_DQS_DN<8>")
	)
	(segment
		(start 73.439528 -132.692648)
		(end 73.439528 -133.46176)
		(width 0.14224)
		(layer "In11.Cu")
		(net "M_L_DQS_DN<8>")
	)
	(segment
		(start 73.437496 -125.309376)
		(end 72.990456 -125.756416)
		(width 0.14224)
		(layer "In11.Cu")
		(net "M_L_DQS_DN<8>")
	)
	(segment
		(start 73.617328 -127.759206)
		(end 73.950576 -128.092454)
		(width 0.14224)
		(layer "In11.Cu")
		(net "M_L_DQS_DN<8>")
	)
	(segment
		(start 73.708768 -137.4394)
		(end 73.708768 -138.5316)
		(width 0.14224)
		(layer "In11.Cu")
		(net "M_L_DQS_DN<8>")
	)
	(segment
		(start 73.950576 -137.197592)
		(end 73.708768 -137.4394)
		(width 0.14224)
		(layer "In11.Cu")
		(net "M_L_DQS_DN<8>")
	)
	(segment
		(start 73.439528 -133.46176)
		(end 73.950576 -133.972808)
		(width 0.14224)
		(layer "In11.Cu")
		(net "M_L_DQS_DN<8>")
	)
	(segment
		(start 72.990456 -126.916688)
		(end 73.617328 -127.54356)
		(width 0.14224)
		(layer "In11.Cu")
		(net "M_L_DQS_DN<8>")
	)
	(segment
		(start 73.950576 -139.36853)
		(end 73.43775 -139.881356)
		(width 0.14224)
		(layer "In11.Cu")
		(net "M_L_DQS_DN<8>")
	)
	(segment
		(start 73.617328 -127.54356)
		(end 73.617328 -127.759206)
		(width 0.14224)
		(layer "In11.Cu")
		(net "M_L_DQS_DN<8>")
	)
	(segment
		(start 73.950576 -133.972808)
		(end 73.950576 -137.197592)
		(width 0.14224)
		(layer "In11.Cu")
		(net "M_L_DQS_DN<8>")
	)
	(segment
		(start 73.950576 -132.1816)
		(end 73.439528 -132.692648)
		(width 0.14224)
		(layer "In11.Cu")
		(net "M_L_DQS_DN<8>")
	)
	(segment
		(start 73.708768 -138.5316)
		(end 73.950576 -138.773408)
		(width 0.14224)
		(layer "In11.Cu")
		(net "M_L_DQS_DN<8>")
	)
	(segment
		(start 120.787668 -96.023938)
		(end 121.359168 -96.023938)
		(width 0.1651)
		(layer "F.Cu")
		(net "M_L_DQS_DN<7>")
	)
	(segment
		(start 146.999452 -146.20367)
		(end 146.617436 -145.821654)
		(width 0.1651)
		(layer "F.Cu")
		(net "M_L_DQS_DN<7>")
	)
	(segment
		(start 147.171918 -145.0594)
		(end 147.387564 -145.275046)
		(width 0.1651)
		(layer "F.Cu")
		(net "M_L_DQS_DN<7>")
	)
	(segment
		(start 146.617436 -145.389854)
		(end 146.94789 -145.0594)
		(width 0.1651)
		(layer "F.Cu")
		(net "M_L_DQS_DN<7>")
	)
	(segment
		(start 146.999452 -147.27174)
		(end 146.999452 -146.20367)
		(width 0.1651)
		(layer "F.Cu")
		(net "M_L_DQS_DN<7>")
	)
	(segment
		(start 146.617436 -145.821654)
		(end 146.617436 -145.389854)
		(width 0.1651)
		(layer "F.Cu")
		(net "M_L_DQS_DN<7>")
	)
	(segment
		(start 146.94789 -145.0594)
		(end 147.171918 -145.0594)
		(width 0.1651)
		(layer "F.Cu")
		(net "M_L_DQS_DN<7>")
	)
	(via
		(at 147.387564 -139.881356)
		(size 0.508)
		(drill 0.254)
		(layers "F.Cu" "B.Cu")
		(net "M_L_DQS_DN<7>")
	)
	(via
		(at 121.359168 -96.023938)
		(size 0.508)
		(drill 0.254)
		(layers "F.Cu" "B.Cu")
		(net "M_L_DQS_DN<7>")
	)
	(via
		(at 147.387564 -145.275046)
		(size 0.508)
		(drill 0.254)
		(layers "F.Cu" "B.Cu")
		(net "M_L_DQS_DN<7>")
	)
	(segment
		(start 146.871436 -138.912346)
		(end 146.871436 -139.166346)
		(width 0.1651)
		(layer "B.Cu")
		(net "M_L_DQS_DN<7>")
	)
	(segment
		(start 147.16252 -140.1064)
		(end 147.387564 -139.881356)
		(width 0.1651)
		(layer "B.Cu")
		(net "M_L_DQS_DN<7>")
	)
	(segment
		(start 146.973036 -140.1064)
		(end 147.16252 -140.1064)
		(width 0.1651)
		(layer "B.Cu")
		(net "M_L_DQS_DN<7>")
	)
	(segment
		(start 146.999452 -138.78433)
		(end 146.871436 -138.912346)
		(width 0.1651)
		(layer "B.Cu")
		(net "M_L_DQS_DN<7>")
	)
	(segment
		(start 146.871436 -139.166346)
		(end 146.617436 -139.420346)
		(width 0.1651)
		(layer "B.Cu")
		(net "M_L_DQS_DN<7>")
	)
	(segment
		(start 146.617436 -139.420346)
		(end 146.617436 -139.7508)
		(width 0.1651)
		(layer "B.Cu")
		(net "M_L_DQS_DN<7>")
	)
	(segment
		(start 146.617436 -139.7508)
		(end 146.973036 -140.1064)
		(width 0.1651)
		(layer "B.Cu")
		(net "M_L_DQS_DN<7>")
	)
	(segment
		(start 146.999452 -137.877296)
		(end 146.999452 -138.78433)
		(width 0.1651)
		(layer "B.Cu")
		(net "M_L_DQS_DN<7>")
	)
	(segment
		(start 147.900644 -132.411978)
		(end 147.900644 -132.665978)
		(width 0.14224)
		(layer "In4.Cu")
		(net "M_L_DQS_DN<7>")
	)
	(segment
		(start 147.900644 -127.54229)
		(end 147.900644 -127.79629)
		(width 0.14224)
		(layer "In4.Cu")
		(net "M_L_DQS_DN<7>")
	)
	(segment
		(start 147.900644 -131.843018)
		(end 147.743164 -132.000498)
		(width 0.14224)
		(layer "In4.Cu")
		(net "M_L_DQS_DN<7>")
	)
	(segment
		(start 121.705878 -100.186236)
		(end 121.699528 -100.196904)
		(width 0.0889)
		(layer "In4.Cu")
		(net "M_L_DQS_DN<7>")
	)
	(segment
		(start 147.743164 -133.900418)
		(end 147.900644 -134.057898)
		(width 0.14224)
		(layer "In4.Cu")
		(net "M_L_DQS_DN<7>")
	)
	(segment
		(start 146.092672 -123.297188)
		(end 146.092672 -123.739148)
		(width 0.14224)
		(layer "In4.Cu")
		(net "M_L_DQS_DN<7>")
	)
	(segment
		(start 122.564398 -103.253286)
		(end 122.569224 -103.261922)
		(width 0.0889)
		(layer "In4.Cu")
		(net "M_L_DQS_DN<7>")
	)
	(segment
		(start 147.743164 -138.669014)
		(end 147.900644 -138.826494)
		(width 0.14224)
		(layer "In4.Cu")
		(net "M_L_DQS_DN<7>")
	)
	(segment
		(start 147.900644 -136.226804)
		(end 147.900644 -136.611614)
		(width 0.14224)
		(layer "In4.Cu")
		(net "M_L_DQS_DN<7>")
	)
	(segment
		(start 147.743164 -132.000498)
		(end 147.743164 -132.254498)
		(width 0.14224)
		(layer "In4.Cu")
		(net "M_L_DQS_DN<7>")
	)
	(segment
		(start 147.900644 -138.003534)
		(end 147.900644 -138.257534)
		(width 0.14224)
		(layer "In4.Cu")
		(net "M_L_DQS_DN<7>")
	)
	(segment
		(start 147.900644 -128.36525)
		(end 147.900644 -128.61925)
		(width 0.14224)
		(layer "In4.Cu")
		(net "M_L_DQS_DN<7>")
	)
	(segment
		(start 146.743674 -143.37538)
		(end 146.95424 -143.585946)
		(width 0.14224)
		(layer "In4.Cu")
		(net "M_L_DQS_DN<7>")
	)
	(segment
		(start 147.900644 -132.665978)
		(end 147.743164 -132.823458)
		(width 0.14224)
		(layer "In4.Cu")
		(net "M_L_DQS_DN<7>")
	)
	(segment
		(start 147.900644 -129.649728)
		(end 147.760182 -129.79019)
		(width 0.14224)
		(layer "In4.Cu")
		(net "M_L_DQS_DN<7>")
	)
	(segment
		(start 147.900644 -136.611614)
		(end 147.743164 -136.769094)
		(width 0.14224)
		(layer "In4.Cu")
		(net "M_L_DQS_DN<7>")
	)
	(segment
		(start 147.387564 -139.881356)
		(end 147.314412 -139.881356)
		(width 0.14224)
		(layer "In4.Cu")
		(net "M_L_DQS_DN<7>")
	)
	(segment
		(start 147.900644 -138.257534)
		(end 147.743164 -138.415014)
		(width 0.14224)
		(layer "In4.Cu")
		(net "M_L_DQS_DN<7>")
	)
	(segment
		(start 143.931132 -120.558052)
		(end 144.95272 -121.57964)
		(width 0.14224)
		(layer "In4.Cu")
		(net "M_L_DQS_DN<7>")
	)
	(segment
		(start 147.790408 -136.116568)
		(end 147.900644 -136.226804)
		(width 0.14224)
		(layer "In4.Cu")
		(net "M_L_DQS_DN<7>")
	)
	(segment
		(start 146.501104 -124.14758)
		(end 146.943064 -124.14758)
		(width 0.14224)
		(layer "In4.Cu")
		(net "M_L_DQS_DN<7>")
	)
	(segment
		(start 142.678658 -120.558052)
		(end 143.931132 -120.558052)
		(width 0.14224)
		(layer "In4.Cu")
		(net "M_L_DQS_DN<7>")
	)
	(segment
		(start 147.743164 -127.38481)
		(end 147.900644 -127.54229)
		(width 0.14224)
		(layer "In4.Cu")
		(net "M_L_DQS_DN<7>")
	)
	(segment
		(start 147.760182 -130.04419)
		(end 147.900644 -130.184652)
		(width 0.14224)
		(layer "In4.Cu")
		(net "M_L_DQS_DN<7>")
	)
	(segment
		(start 147.743164 -137.023094)
		(end 147.900644 -137.180574)
		(width 0.14224)
		(layer "In4.Cu")
		(net "M_L_DQS_DN<7>")
	)
	(segment
		(start 147.743164 -125.48489)
		(end 147.743164 -125.73889)
		(width 0.14224)
		(layer "In4.Cu")
		(net "M_L_DQS_DN<7>")
	)
	(segment
		(start 147.900644 -137.434574)
		(end 147.743164 -137.592054)
		(width 0.14224)
		(layer "In4.Cu")
		(net "M_L_DQS_DN<7>")
	)
	(segment
		(start 147.900644 -124.527564)
		(end 147.900644 -125.32741)
		(width 0.14224)
		(layer "In4.Cu")
		(net "M_L_DQS_DN<7>")
	)
	(segment
		(start 147.900644 -126.97333)
		(end 147.743164 -127.13081)
		(width 0.14224)
		(layer "In4.Cu")
		(net "M_L_DQS_DN<7>")
	)
	(segment
		(start 145.431256 -122.64644)
		(end 146.02206 -122.64644)
		(width 0.14224)
		(layer "In4.Cu")
		(net "M_L_DQS_DN<7>")
	)
	(segment
		(start 121.710704 -101.1682)
		(end 121.705878 -101.176836)
		(width 0.0889)
		(layer "In4.Cu")
		(net "M_L_DQS_DN<7>")
	)
	(segment
		(start 146.02206 -122.64644)
		(end 146.271996 -122.896376)
		(width 0.14224)
		(layer "In4.Cu")
		(net "M_L_DQS_DN<7>")
	)
	(segment
		(start 147.666964 -139.881356)
		(end 147.387564 -139.881356)
		(width 0.14224)
		(layer "In4.Cu")
		(net "M_L_DQS_DN<7>")
	)
	(segment
		(start 127.045466 -107.29087)
		(end 129.411476 -107.29087)
		(width 0.14224)
		(layer "In4.Cu")
		(net "M_L_DQS_DN<7>")
	)
	(segment
		(start 123.913138 -105.034334)
		(end 123.945904 -105.034334)
		(width 0.0889)
		(layer "In4.Cu")
		(net "M_L_DQS_DN<7>")
	)
	(segment
		(start 147.743164 -132.254498)
		(end 147.900644 -132.411978)
		(width 0.14224)
		(layer "In4.Cu")
		(net "M_L_DQS_DN<7>")
	)
	(segment
		(start 124.775468 -105.529888)
		(end 124.810774 -105.529888)
		(width 0.0889)
		(layer "In4.Cu")
		(net "M_L_DQS_DN<7>")
	)
	(segment
		(start 147.743164 -127.95377)
		(end 147.743164 -128.20777)
		(width 0.14224)
		(layer "In4.Cu")
		(net "M_L_DQS_DN<7>")
	)
	(segment
		(start 147.122388 -123.968256)
		(end 147.341336 -123.968256)
		(width 0.14224)
		(layer "In4.Cu")
		(net "M_L_DQS_DN<7>")
	)
	(segment
		(start 147.780248 -134.813294)
		(end 147.900644 -134.93369)
		(width 0.14224)
		(layer "In4.Cu")
		(net "M_L_DQS_DN<7>")
	)
	(segment
		(start 121.705624 -97.80524)
		(end 121.705878 -97.805494)
		(width 0.0889)
		(layer "In4.Cu")
		(net "M_L_DQS_DN<7>")
	)
	(segment
		(start 147.900644 -133.234938)
		(end 147.900644 -133.488938)
		(width 0.14224)
		(layer "In4.Cu")
		(net "M_L_DQS_DN<7>")
	)
	(segment
		(start 122.196098 -102.062534)
		(end 122.228864 -102.062534)
		(width 0.0889)
		(layer "In4.Cu")
		(net "M_L_DQS_DN<7>")
	)
	(segment
		(start 147.743164 -137.846054)
		(end 147.900644 -138.003534)
		(width 0.14224)
		(layer "In4.Cu")
		(net "M_L_DQS_DN<7>")
	)
	(segment
		(start 147.900644 -133.488938)
		(end 147.743164 -133.646418)
		(width 0.14224)
		(layer "In4.Cu")
		(net "M_L_DQS_DN<7>")
	)
	(segment
		(start 146.95424 -141.503654)
		(end 146.743674 -141.71422)
		(width 0.14224)
		(layer "In4.Cu")
		(net "M_L_DQS_DN<7>")
	)
	(segment
		(start 147.743164 -128.20777)
		(end 147.900644 -128.36525)
		(width 0.14224)
		(layer "In4.Cu")
		(net "M_L_DQS_DN<7>")
	)
	(segment
		(start 147.900644 -125.89637)
		(end 147.900644 -126.15037)
		(width 0.14224)
		(layer "In4.Cu")
		(net "M_L_DQS_DN<7>")
	)
	(segment
		(start 127.023368 -107.29087)
		(end 127.045466 -107.29087)
		(width 0.0889)
		(layer "In4.Cu")
		(net "M_L_DQS_DN<7>")
	)
	(segment
		(start 146.95424 -144.841722)
		(end 147.387564 -145.275046)
		(width 0.14224)
		(layer "In4.Cu")
		(net "M_L_DQS_DN<7>")
	)
	(segment
		(start 146.95424 -140.241528)
		(end 146.95424 -141.503654)
		(width 0.14224)
		(layer "In4.Cu")
		(net "M_L_DQS_DN<7>")
	)
	(segment
		(start 147.743164 -129.03073)
		(end 147.900644 -129.18821)
		(width 0.14224)
		(layer "In4.Cu")
		(net "M_L_DQS_DN<7>")
	)
	(segment
		(start 126.983998 -107.2515)
		(end 127.023368 -107.29087)
		(width 0.0889)
		(layer "In4.Cu")
		(net "M_L_DQS_DN<7>")
	)
	(segment
		(start 147.760182 -129.79019)
		(end 147.760182 -130.04419)
		(width 0.14224)
		(layer "In4.Cu")
		(net "M_L_DQS_DN<7>")
	)
	(segment
		(start 147.743164 -126.30785)
		(end 147.743164 -126.56185)
		(width 0.14224)
		(layer "In4.Cu")
		(net "M_L_DQS_DN<7>")
	)
	(segment
		(start 147.900644 -126.71933)
		(end 147.900644 -126.97333)
		(width 0.14224)
		(layer "In4.Cu")
		(net "M_L_DQS_DN<7>")
	)
	(segment
		(start 121.705878 -99.195636)
		(end 121.699528 -99.206304)
		(width 0.0889)
		(layer "In4.Cu")
		(net "M_L_DQS_DN<7>")
	)
	(segment
		(start 121.705878 -101.176836)
		(end 121.699528 -101.187504)
		(width 0.0889)
		(layer "In4.Cu")
		(net "M_L_DQS_DN<7>")
	)
	(segment
		(start 147.743164 -136.769094)
		(end 147.743164 -137.023094)
		(width 0.14224)
		(layer "In4.Cu")
		(net "M_L_DQS_DN<7>")
	)
	(segment
		(start 123.058428 -104.539288)
		(end 123.091194 -104.539288)
		(width 0.0889)
		(layer "In4.Cu")
		(net "M_L_DQS_DN<7>")
	)
	(segment
		(start 121.710704 -99.187)
		(end 121.705878 -99.195636)
		(width 0.0889)
		(layer "In4.Cu")
		(net "M_L_DQS_DN<7>")
	)
	(segment
		(start 147.314412 -139.881356)
		(end 146.95424 -140.241528)
		(width 0.14224)
		(layer "In4.Cu")
		(net "M_L_DQS_DN<7>")
	)
	(segment
		(start 147.743164 -125.73889)
		(end 147.900644 -125.89637)
		(width 0.14224)
		(layer "In4.Cu")
		(net "M_L_DQS_DN<7>")
	)
	(segment
		(start 147.900644 -137.180574)
		(end 147.900644 -137.434574)
		(width 0.14224)
		(layer "In4.Cu")
		(net "M_L_DQS_DN<7>")
	)
	(segment
		(start 121.705878 -97.21469)
		(end 121.705624 -97.214944)
		(width 0.0889)
		(layer "In4.Cu")
		(net "M_L_DQS_DN<7>")
	)
	(segment
		(start 146.271996 -122.896376)
		(end 146.271996 -123.117864)
		(width 0.14224)
		(layer "In4.Cu")
		(net "M_L_DQS_DN<7>")
	)
	(segment
		(start 146.092672 -123.739148)
		(end 146.501104 -124.14758)
		(width 0.14224)
		(layer "In4.Cu")
		(net "M_L_DQS_DN<7>")
	)
	(segment
		(start 147.743164 -138.415014)
		(end 147.743164 -138.669014)
		(width 0.14224)
		(layer "In4.Cu")
		(net "M_L_DQS_DN<7>")
	)
	(segment
		(start 147.900644 -135.752332)
		(end 147.790408 -135.862568)
		(width 0.14224)
		(layer "In4.Cu")
		(net "M_L_DQS_DN<7>")
	)
	(segment
		(start 147.790408 -135.862568)
		(end 147.790408 -136.116568)
		(width 0.14224)
		(layer "In4.Cu")
		(net "M_L_DQS_DN<7>")
	)
	(segment
		(start 144.95272 -122.167904)
		(end 145.431256 -122.64644)
		(width 0.14224)
		(layer "In4.Cu")
		(net "M_L_DQS_DN<7>")
	)
	(segment
		(start 147.743164 -128.77673)
		(end 147.743164 -129.03073)
		(width 0.14224)
		(layer "In4.Cu")
		(net "M_L_DQS_DN<7>")
	)
	(segment
		(start 144.95272 -121.57964)
		(end 144.95272 -122.167904)
		(width 0.14224)
		(layer "In4.Cu")
		(net "M_L_DQS_DN<7>")
	)
	(segment
		(start 147.900644 -128.61925)
		(end 147.743164 -128.77673)
		(width 0.14224)
		(layer "In4.Cu")
		(net "M_L_DQS_DN<7>")
	)
	(segment
		(start 147.900644 -138.826494)
		(end 147.900644 -139.647676)
		(width 0.14224)
		(layer "In4.Cu")
		(net "M_L_DQS_DN<7>")
	)
	(segment
		(start 147.743164 -127.13081)
		(end 147.743164 -127.38481)
		(width 0.14224)
		(layer "In4.Cu")
		(net "M_L_DQS_DN<7>")
	)
	(segment
		(start 147.900644 -126.15037)
		(end 147.743164 -126.30785)
		(width 0.14224)
		(layer "In4.Cu")
		(net "M_L_DQS_DN<7>")
	)
	(segment
		(start 147.743164 -133.646418)
		(end 147.743164 -133.900418)
		(width 0.14224)
		(layer "In4.Cu")
		(net "M_L_DQS_DN<7>")
	)
	(segment
		(start 125.100334 -105.962958)
		(end 126.388876 -107.2515)
		(width 0.0889)
		(layer "In4.Cu")
		(net "M_L_DQS_DN<7>")
	)
	(segment
		(start 147.743164 -137.592054)
		(end 147.743164 -137.846054)
		(width 0.14224)
		(layer "In4.Cu")
		(net "M_L_DQS_DN<7>")
	)
	(segment
		(start 146.943064 -124.14758)
		(end 147.122388 -123.968256)
		(width 0.14224)
		(layer "In4.Cu")
		(net "M_L_DQS_DN<7>")
	)
	(segment
		(start 147.900644 -125.32741)
		(end 147.743164 -125.48489)
		(width 0.14224)
		(layer "In4.Cu")
		(net "M_L_DQS_DN<7>")
	)
	(segment
		(start 147.900644 -134.438898)
		(end 147.780248 -134.559294)
		(width 0.14224)
		(layer "In4.Cu")
		(net "M_L_DQS_DN<7>")
	)
	(segment
		(start 147.743164 -133.077458)
		(end 147.900644 -133.234938)
		(width 0.14224)
		(layer "In4.Cu")
		(net "M_L_DQS_DN<7>")
	)
	(segment
		(start 146.743674 -141.71422)
		(end 146.743674 -143.37538)
		(width 0.14224)
		(layer "In4.Cu")
		(net "M_L_DQS_DN<7>")
	)
	(segment
		(start 146.95424 -143.585946)
		(end 146.95424 -144.841722)
		(width 0.14224)
		(layer "In4.Cu")
		(net "M_L_DQS_DN<7>")
	)
	(segment
		(start 125.100334 -105.673144)
		(end 125.100334 -105.962958)
		(width 0.0889)
		(layer "In4.Cu")
		(net "M_L_DQS_DN<7>")
	)
	(segment
		(start 121.710704 -100.1776)
		(end 121.705878 -100.186236)
		(width 0.0889)
		(layer "In4.Cu")
		(net "M_L_DQS_DN<7>")
	)
	(segment
		(start 147.900644 -139.647676)
		(end 147.666964 -139.881356)
		(width 0.14224)
		(layer "In4.Cu")
		(net "M_L_DQS_DN<7>")
	)
	(segment
		(start 147.900644 -134.057898)
		(end 147.900644 -134.438898)
		(width 0.14224)
		(layer "In4.Cu")
		(net "M_L_DQS_DN<7>")
	)
	(segment
		(start 129.411476 -107.29087)
		(end 142.678658 -120.558052)
		(width 0.14224)
		(layer "In4.Cu")
		(net "M_L_DQS_DN<7>")
	)
	(segment
		(start 147.900644 -134.93369)
		(end 147.900644 -135.752332)
		(width 0.14224)
		(layer "In4.Cu")
		(net "M_L_DQS_DN<7>")
	)
	(segment
		(start 146.271996 -123.117864)
		(end 146.092672 -123.297188)
		(width 0.14224)
		(layer "In4.Cu")
		(net "M_L_DQS_DN<7>")
	)
	(segment
		(start 147.743164 -132.823458)
		(end 147.743164 -133.077458)
		(width 0.14224)
		(layer "In4.Cu")
		(net "M_L_DQS_DN<7>")
	)
	(segment
		(start 126.388876 -107.2515)
		(end 126.983998 -107.2515)
		(width 0.0889)
		(layer "In4.Cu")
		(net "M_L_DQS_DN<7>")
	)
	(segment
		(start 147.900644 -127.79629)
		(end 147.743164 -127.95377)
		(width 0.14224)
		(layer "In4.Cu")
		(net "M_L_DQS_DN<7>")
	)
	(segment
		(start 147.780248 -134.559294)
		(end 147.780248 -134.813294)
		(width 0.14224)
		(layer "In4.Cu")
		(net "M_L_DQS_DN<7>")
	)
	(segment
		(start 122.558048 -103.242618)
		(end 122.564398 -103.253286)
		(width 0.0889)
		(layer "In4.Cu")
		(net "M_L_DQS_DN<7>")
	)
	(segment
		(start 147.341336 -123.968256)
		(end 147.900644 -124.527564)
		(width 0.14224)
		(layer "In4.Cu")
		(net "M_L_DQS_DN<7>")
	)
	(segment
		(start 147.743164 -126.56185)
		(end 147.900644 -126.71933)
		(width 0.14224)
		(layer "In4.Cu")
		(net "M_L_DQS_DN<7>")
	)
	(segment
		(start 147.900644 -130.184652)
		(end 147.900644 -131.843018)
		(width 0.14224)
		(layer "In4.Cu")
		(net "M_L_DQS_DN<7>")
	)
	(segment
		(start 147.900644 -129.18821)
		(end 147.900644 -129.649728)
		(width 0.14224)
		(layer "In4.Cu")
		(net "M_L_DQS_DN<7>")
	)
	(arc
		(start 121.705878 -98.796094)
		(mid 121.721776 -98.826473)
		(end 121.735088 -98.85807)
		(width 0.0889)
		(layer "In4.Cu")
		(net "M_L_DQS_DN<7>")
	)
	(arc
		(start 123.422918 -104.739186)
		(mid 123.629922 -104.95005)
		(end 123.913138 -105.034334)
		(width 0.0889)
		(layer "In4.Cu")
		(net "M_L_DQS_DN<7>")
	)
	(arc
		(start 121.705878 -97.805494)
		(mid 121.759377 -98.005392)
		(end 121.705878 -98.20529)
		(width 0.0889)
		(layer "In4.Cu")
		(net "M_L_DQS_DN<7>")
	)
	(arc
		(start 121.705878 -99.786186)
		(mid 121.759348 -99.981249)
		(end 121.710704 -100.1776)
		(width 0.0889)
		(layer "In4.Cu")
		(net "M_L_DQS_DN<7>")
	)
	(arc
		(start 121.705624 -97.214944)
		(mid 121.626653 -97.510092)
		(end 121.705624 -97.80524)
		(width 0.0889)
		(layer "In4.Cu")
		(net "M_L_DQS_DN<7>")
	)
	(arc
		(start 121.705878 -100.776786)
		(mid 121.759348 -100.971849)
		(end 121.710704 -101.1682)
		(width 0.0889)
		(layer "In4.Cu")
		(net "M_L_DQS_DN<7>")
	)
	(arc
		(start 122.569224 -103.261922)
		(mid 122.617979 -103.458274)
		(end 122.564398 -103.653336)
		(width 0.0889)
		(layer "In4.Cu")
		(net "M_L_DQS_DN<7>")
	)
	(arc
		(start 121.705878 -98.20529)
		(mid 121.626747 -98.500692)
		(end 121.705878 -98.796094)
		(width 0.0889)
		(layer "In4.Cu")
		(net "M_L_DQS_DN<7>")
	)
	(arc
		(start 122.228864 -102.062534)
		(mid 122.567033 -102.267332)
		(end 122.564398 -102.662736)
		(width 0.0889)
		(layer "In4.Cu")
		(net "M_L_DQS_DN<7>")
	)
	(arc
		(start 123.945904 -105.034334)
		(mid 124.139754 -105.090684)
		(end 124.281438 -105.234486)
		(width 0.0889)
		(layer "In4.Cu")
		(net "M_L_DQS_DN<7>")
	)
	(arc
		(start 121.735088 -98.85807)
		(mid 121.758315 -99.025153)
		(end 121.710704 -99.187)
		(width 0.0889)
		(layer "In4.Cu")
		(net "M_L_DQS_DN<7>")
	)
	(arc
		(start 122.564398 -102.662736)
		(mid 122.485176 -102.951854)
		(end 122.558048 -103.242618)
		(width 0.0889)
		(layer "In4.Cu")
		(net "M_L_DQS_DN<7>")
	)
	(arc
		(start 121.705878 -96.814894)
		(mid 121.759377 -97.014792)
		(end 121.705878 -97.21469)
		(width 0.0889)
		(layer "In4.Cu")
		(net "M_L_DQS_DN<7>")
	)
	(arc
		(start 121.699528 -100.196904)
		(mid 121.62673 -100.487667)
		(end 121.705878 -100.776786)
		(width 0.0889)
		(layer "In4.Cu")
		(net "M_L_DQS_DN<7>")
	)
	(arc
		(start 122.564398 -103.653336)
		(mid 122.560069 -104.236508)
		(end 123.058428 -104.539288)
		(width 0.0889)
		(layer "In4.Cu")
		(net "M_L_DQS_DN<7>")
	)
	(arc
		(start 121.359168 -96.023938)
		(mid 121.51077 -96.428951)
		(end 121.705878 -96.814894)
		(width 0.0889)
		(layer "In4.Cu")
		(net "M_L_DQS_DN<7>")
	)
	(arc
		(start 121.699528 -99.206304)
		(mid 121.62673 -99.497067)
		(end 121.705878 -99.786186)
		(width 0.0889)
		(layer "In4.Cu")
		(net "M_L_DQS_DN<7>")
	)
	(arc
		(start 124.281438 -105.234486)
		(mid 124.490046 -105.446418)
		(end 124.775468 -105.529888)
		(width 0.0889)
		(layer "In4.Cu")
		(net "M_L_DQS_DN<7>")
	)
	(arc
		(start 124.810774 -105.529888)
		(mid 124.970623 -105.571045)
		(end 125.100334 -105.673144)
		(width 0.0889)
		(layer "In4.Cu")
		(net "M_L_DQS_DN<7>")
	)
	(arc
		(start 121.699528 -101.187504)
		(mid 121.703559 -101.763686)
		(end 122.196098 -102.062534)
		(width 0.0889)
		(layer "In4.Cu")
		(net "M_L_DQS_DN<7>")
	)
	(arc
		(start 123.091194 -104.539288)
		(mid 123.282836 -104.596454)
		(end 123.422918 -104.739186)
		(width 0.0889)
		(layer "In4.Cu")
		(net "M_L_DQS_DN<7>")
	)
	(segment
		(start 137.649458 -146.20367)
		(end 137.267442 -145.821654)
		(width 0.1651)
		(layer "F.Cu")
		(net "M_L_DQS_DN<6>")
	)
	(segment
		(start 121.130568 -105.160318)
		(end 122.231404 -106.261154)
		(width 0.1016)
		(layer "F.Cu")
		(net "M_L_DQS_DN<6>")
	)
	(segment
		(start 138.229848 -121.417842)
		(end 138.503406 -121.6914)
		(width 0.1651)
		(layer "F.Cu")
		(net "M_L_DQS_DN<6>")
	)
	(segment
		(start 134.704836 -110.315756)
		(end 134.884414 -110.495588)
		(width 0.1651)
		(layer "F.Cu")
		(net "M_L_DQS_DN<6>")
	)
	(segment
		(start 135.064246 -110.495588)
		(end 135.24357 -110.675166)
		(width 0.1651)
		(layer "F.Cu")
		(net "M_L_DQS_DN<6>")
	)
	(segment
		(start 138.218164 -122.700542)
		(end 138.218164 -123.291854)
		(width 0.1651)
		(layer "F.Cu")
		(net "M_L_DQS_DN<6>")
	)
	(segment
		(start 138.298682 -125.351286)
		(end 138.03757 -125.351286)
		(width 0.1651)
		(layer "F.Cu")
		(net "M_L_DQS_DN<6>")
	)
	(segment
		(start 136.321038 -111.93272)
		(end 136.500616 -112.112552)
		(width 0.1651)
		(layer "F.Cu")
		(net "M_L_DQS_DN<6>")
	)
	(segment
		(start 138.102848 -117.094)
		(end 138.229848 -117.221)
		(width 0.1651)
		(layer "F.Cu")
		(net "M_L_DQS_DN<6>")
	)
	(segment
		(start 138.102848 -117.856)
		(end 138.229848 -117.983)
		(width 0.1651)
		(layer "F.Cu")
		(net "M_L_DQS_DN<6>")
	)
	(segment
		(start 137.03935 -112.65154)
		(end 137.219182 -112.65154)
		(width 0.1651)
		(layer "F.Cu")
		(net "M_L_DQS_DN<6>")
	)
	(segment
		(start 137.649458 -147.27174)
		(end 137.649458 -146.20367)
		(width 0.1651)
		(layer "F.Cu")
		(net "M_L_DQS_DN<6>")
	)
	(segment
		(start 138.229848 -118.745)
		(end 138.229848 -118.999)
		(width 0.1651)
		(layer "F.Cu")
		(net "M_L_DQS_DN<6>")
	)
	(segment
		(start 138.573764 -125.076204)
		(end 138.298682 -125.351286)
		(width 0.1651)
		(layer "F.Cu")
		(net "M_L_DQS_DN<6>")
	)
	(segment
		(start 136.859772 -112.29213)
		(end 136.859772 -112.471708)
		(width 0.1651)
		(layer "F.Cu")
		(net "M_L_DQS_DN<6>")
	)
	(segment
		(start 138.229848 -114.911632)
		(end 138.229848 -115.165632)
		(width 0.1651)
		(layer "F.Cu")
		(net "M_L_DQS_DN<6>")
	)
	(segment
		(start 138.102848 -117.602)
		(end 138.102848 -117.856)
		(width 0.1651)
		(layer "F.Cu")
		(net "M_L_DQS_DN<6>")
	)
	(segment
		(start 137.578084 -113.190528)
		(end 137.75817 -113.190528)
		(width 0.1651)
		(layer "F.Cu")
		(net "M_L_DQS_DN<6>")
	)
	(segment
		(start 136.141714 -111.573564)
		(end 136.321038 -111.753142)
		(width 0.1651)
		(layer "F.Cu")
		(net "M_L_DQS_DN<6>")
	)
	(segment
		(start 138.102848 -116.308632)
		(end 138.229848 -116.435632)
		(width 0.1651)
		(layer "F.Cu")
		(net "M_L_DQS_DN<6>")
	)
	(segment
		(start 138.102848 -118.364)
		(end 138.102848 -118.618)
		(width 0.1651)
		(layer "F.Cu")
		(net "M_L_DQS_DN<6>")
	)
	(segment
		(start 135.961882 -111.573564)
		(end 136.141714 -111.573564)
		(width 0.1651)
		(layer "F.Cu")
		(net "M_L_DQS_DN<6>")
	)
	(segment
		(start 138.229848 -113.66246)
		(end 138.229848 -114.403632)
		(width 0.1651)
		(layer "F.Cu")
		(net "M_L_DQS_DN<6>")
	)
	(segment
		(start 137.39876 -112.831118)
		(end 137.398506 -113.010696)
		(width 0.1651)
		(layer "F.Cu")
		(net "M_L_DQS_DN<6>")
	)
	(segment
		(start 138.554206 -122.3645)
		(end 138.218164 -122.700542)
		(width 0.1651)
		(layer "F.Cu")
		(net "M_L_DQS_DN<6>")
	)
	(segment
		(start 138.503406 -121.6914)
		(end 138.85164 -121.6914)
		(width 0.1651)
		(layer "F.Cu")
		(net "M_L_DQS_DN<6>")
	)
	(segment
		(start 138.102848 -116.84)
		(end 138.102848 -117.094)
		(width 0.1651)
		(layer "F.Cu")
		(net "M_L_DQS_DN<6>")
	)
	(segment
		(start 120.787668 -104.668828)
		(end 121.130568 -105.011728)
		(width 0.0889)
		(layer "F.Cu")
		(net "M_L_DQS_DN<6>")
	)
	(segment
		(start 138.446764 -123.9774)
		(end 138.446764 -124.2314)
		(width 0.1651)
		(layer "F.Cu")
		(net "M_L_DQS_DN<6>")
	)
	(segment
		(start 137.821924 -145.0594)
		(end 138.03757 -145.275046)
		(width 0.1651)
		(layer "F.Cu")
		(net "M_L_DQS_DN<6>")
	)
	(segment
		(start 138.102848 -115.292632)
		(end 138.102848 -115.546632)
		(width 0.1651)
		(layer "F.Cu")
		(net "M_L_DQS_DN<6>")
	)
	(segment
		(start 138.229848 -117.475)
		(end 138.102848 -117.602)
		(width 0.1651)
		(layer "F.Cu")
		(net "M_L_DQS_DN<6>")
	)
	(segment
		(start 138.85164 -122.3645)
		(end 138.554206 -122.3645)
		(width 0.1651)
		(layer "F.Cu")
		(net "M_L_DQS_DN<6>")
	)
	(segment
		(start 138.573764 -124.3584)
		(end 138.573764 -125.076204)
		(width 0.1651)
		(layer "F.Cu")
		(net "M_L_DQS_DN<6>")
	)
	(segment
		(start 138.218164 -123.291854)
		(end 138.573764 -123.647454)
		(width 0.1651)
		(layer "F.Cu")
		(net "M_L_DQS_DN<6>")
	)
	(segment
		(start 138.102848 -120.142)
		(end 138.229848 -120.269)
		(width 0.1651)
		(layer "F.Cu")
		(net "M_L_DQS_DN<6>")
	)
	(segment
		(start 138.229848 -117.983)
		(end 138.229848 -118.237)
		(width 0.1651)
		(layer "F.Cu")
		(net "M_L_DQS_DN<6>")
	)
	(segment
		(start 134.884414 -110.495588)
		(end 135.064246 -110.495588)
		(width 0.1651)
		(layer "F.Cu")
		(net "M_L_DQS_DN<6>")
	)
	(segment
		(start 138.102848 -119.126)
		(end 138.102848 -119.38)
		(width 0.1651)
		(layer "F.Cu")
		(net "M_L_DQS_DN<6>")
	)
	(segment
		(start 135.60298 -111.034576)
		(end 135.782304 -111.214154)
		(width 0.1651)
		(layer "F.Cu")
		(net "M_L_DQS_DN<6>")
	)
	(segment
		(start 138.229848 -114.403632)
		(end 138.102848 -114.530632)
		(width 0.1651)
		(layer "F.Cu")
		(net "M_L_DQS_DN<6>")
	)
	(segment
		(start 138.229848 -118.999)
		(end 138.102848 -119.126)
		(width 0.1651)
		(layer "F.Cu")
		(net "M_L_DQS_DN<6>")
	)
	(segment
		(start 133.9977 -109.713014)
		(end 134.19836 -109.713014)
		(width 0.1016)
		(layer "F.Cu")
		(net "M_L_DQS_DN<6>")
	)
	(segment
		(start 136.500616 -112.112552)
		(end 136.680448 -112.112552)
		(width 0.1651)
		(layer "F.Cu")
		(net "M_L_DQS_DN<6>")
	)
	(segment
		(start 135.24357 -110.675166)
		(end 135.24357 -110.854744)
		(width 0.1651)
		(layer "F.Cu")
		(net "M_L_DQS_DN<6>")
	)
	(segment
		(start 137.398506 -113.010696)
		(end 137.578084 -113.190528)
		(width 0.1651)
		(layer "F.Cu")
		(net "M_L_DQS_DN<6>")
	)
	(segment
		(start 134.525512 -109.9566)
		(end 134.704836 -110.136178)
		(width 0.1651)
		(layer "F.Cu")
		(net "M_L_DQS_DN<6>")
	)
	(segment
		(start 135.782304 -111.393732)
		(end 135.961882 -111.573564)
		(width 0.1651)
		(layer "F.Cu")
		(net "M_L_DQS_DN<6>")
	)
	(segment
		(start 137.267442 -145.389854)
		(end 137.597896 -145.0594)
		(width 0.1651)
		(layer "F.Cu")
		(net "M_L_DQS_DN<6>")
	)
	(segment
		(start 138.229848 -120.269)
		(end 138.229848 -120.523)
		(width 0.1651)
		(layer "F.Cu")
		(net "M_L_DQS_DN<6>")
	)
	(segment
		(start 130.54584 -106.261154)
		(end 133.9977 -109.713014)
		(width 0.1016)
		(layer "F.Cu")
		(net "M_L_DQS_DN<6>")
	)
	(segment
		(start 138.85164 -121.6914)
		(end 138.97864 -121.8184)
		(width 0.1651)
		(layer "F.Cu")
		(net "M_L_DQS_DN<6>")
	)
	(segment
		(start 138.102848 -118.618)
		(end 138.229848 -118.745)
		(width 0.1651)
		(layer "F.Cu")
		(net "M_L_DQS_DN<6>")
	)
	(segment
		(start 138.102848 -120.65)
		(end 138.102848 -120.904)
		(width 0.1651)
		(layer "F.Cu")
		(net "M_L_DQS_DN<6>")
	)
	(segment
		(start 135.782304 -111.214154)
		(end 135.782304 -111.393732)
		(width 0.1651)
		(layer "F.Cu")
		(net "M_L_DQS_DN<6>")
	)
	(segment
		(start 135.24357 -110.854744)
		(end 135.423148 -111.034576)
		(width 0.1651)
		(layer "F.Cu")
		(net "M_L_DQS_DN<6>")
	)
	(segment
		(start 136.680448 -112.112552)
		(end 136.859772 -112.29213)
		(width 0.1651)
		(layer "F.Cu")
		(net "M_L_DQS_DN<6>")
	)
	(segment
		(start 138.102848 -116.054632)
		(end 138.102848 -116.308632)
		(width 0.1651)
		(layer "F.Cu")
		(net "M_L_DQS_DN<6>")
	)
	(segment
		(start 138.102848 -115.546632)
		(end 138.229848 -115.673632)
		(width 0.1651)
		(layer "F.Cu")
		(net "M_L_DQS_DN<6>")
	)
	(segment
		(start 137.219182 -112.65154)
		(end 137.39876 -112.831118)
		(width 0.1651)
		(layer "F.Cu")
		(net "M_L_DQS_DN<6>")
	)
	(segment
		(start 136.859772 -112.471708)
		(end 137.03935 -112.65154)
		(width 0.1651)
		(layer "F.Cu")
		(net "M_L_DQS_DN<6>")
	)
	(segment
		(start 138.102848 -114.530632)
		(end 138.102848 -114.784632)
		(width 0.1651)
		(layer "F.Cu")
		(net "M_L_DQS_DN<6>")
	)
	(segment
		(start 138.229848 -115.673632)
		(end 138.229848 -115.927632)
		(width 0.1651)
		(layer "F.Cu")
		(net "M_L_DQS_DN<6>")
	)
	(segment
		(start 137.267442 -145.821654)
		(end 137.267442 -145.389854)
		(width 0.1651)
		(layer "F.Cu")
		(net "M_L_DQS_DN<6>")
	)
	(segment
		(start 138.229848 -117.221)
		(end 138.229848 -117.475)
		(width 0.1651)
		(layer "F.Cu")
		(net "M_L_DQS_DN<6>")
	)
	(segment
		(start 138.229848 -115.165632)
		(end 138.102848 -115.292632)
		(width 0.1651)
		(layer "F.Cu")
		(net "M_L_DQS_DN<6>")
	)
	(segment
		(start 121.130568 -105.011728)
		(end 121.130568 -105.160318)
		(width 0.1016)
		(layer "F.Cu")
		(net "M_L_DQS_DN<6>")
	)
	(segment
		(start 138.229848 -121.031)
		(end 138.229848 -121.417842)
		(width 0.1651)
		(layer "F.Cu")
		(net "M_L_DQS_DN<6>")
	)
	(segment
		(start 138.573764 -123.647454)
		(end 138.573764 -123.8504)
		(width 0.1651)
		(layer "F.Cu")
		(net "M_L_DQS_DN<6>")
	)
	(segment
		(start 134.704836 -110.136178)
		(end 134.704836 -110.315756)
		(width 0.1651)
		(layer "F.Cu")
		(net "M_L_DQS_DN<6>")
	)
	(segment
		(start 138.573764 -123.8504)
		(end 138.446764 -123.9774)
		(width 0.1651)
		(layer "F.Cu")
		(net "M_L_DQS_DN<6>")
	)
	(segment
		(start 134.441946 -109.9566)
		(end 134.525512 -109.9566)
		(width 0.1016)
		(layer "F.Cu")
		(net "M_L_DQS_DN<6>")
	)
	(segment
		(start 138.102848 -119.888)
		(end 138.102848 -120.142)
		(width 0.1651)
		(layer "F.Cu")
		(net "M_L_DQS_DN<6>")
	)
	(segment
		(start 138.229848 -115.927632)
		(end 138.102848 -116.054632)
		(width 0.1651)
		(layer "F.Cu")
		(net "M_L_DQS_DN<6>")
	)
	(segment
		(start 134.19836 -109.713014)
		(end 134.441946 -109.9566)
		(width 0.1016)
		(layer "F.Cu")
		(net "M_L_DQS_DN<6>")
	)
	(segment
		(start 138.102848 -120.904)
		(end 138.229848 -121.031)
		(width 0.1651)
		(layer "F.Cu")
		(net "M_L_DQS_DN<6>")
	)
	(segment
		(start 138.229848 -120.523)
		(end 138.102848 -120.65)
		(width 0.1651)
		(layer "F.Cu")
		(net "M_L_DQS_DN<6>")
	)
	(segment
		(start 138.97864 -121.8184)
		(end 138.97864 -122.2375)
		(width 0.1651)
		(layer "F.Cu")
		(net "M_L_DQS_DN<6>")
	)
	(segment
		(start 138.229848 -119.507)
		(end 138.229848 -119.761)
		(width 0.1651)
		(layer "F.Cu")
		(net "M_L_DQS_DN<6>")
	)
	(segment
		(start 138.97864 -122.2375)
		(end 138.85164 -122.3645)
		(width 0.1651)
		(layer "F.Cu")
		(net "M_L_DQS_DN<6>")
	)
	(segment
		(start 137.75817 -113.190528)
		(end 138.229848 -113.66246)
		(width 0.1651)
		(layer "F.Cu")
		(net "M_L_DQS_DN<6>")
	)
	(segment
		(start 138.229848 -116.435632)
		(end 138.229848 -116.713)
		(width 0.1651)
		(layer "F.Cu")
		(net "M_L_DQS_DN<6>")
	)
	(segment
		(start 122.231404 -106.261154)
		(end 130.54584 -106.261154)
		(width 0.1016)
		(layer "F.Cu")
		(net "M_L_DQS_DN<6>")
	)
	(segment
		(start 138.102848 -114.784632)
		(end 138.229848 -114.911632)
		(width 0.1651)
		(layer "F.Cu")
		(net "M_L_DQS_DN<6>")
	)
	(segment
		(start 138.102848 -119.38)
		(end 138.229848 -119.507)
		(width 0.1651)
		(layer "F.Cu")
		(net "M_L_DQS_DN<6>")
	)
	(segment
		(start 136.321038 -111.753142)
		(end 136.321038 -111.93272)
		(width 0.1651)
		(layer "F.Cu")
		(net "M_L_DQS_DN<6>")
	)
	(segment
		(start 138.229848 -116.713)
		(end 138.102848 -116.84)
		(width 0.1651)
		(layer "F.Cu")
		(net "M_L_DQS_DN<6>")
	)
	(segment
		(start 135.423148 -111.034576)
		(end 135.60298 -111.034576)
		(width 0.1651)
		(layer "F.Cu")
		(net "M_L_DQS_DN<6>")
	)
	(segment
		(start 138.229848 -119.761)
		(end 138.102848 -119.888)
		(width 0.1651)
		(layer "F.Cu")
		(net "M_L_DQS_DN<6>")
	)
	(segment
		(start 120.787668 -102.958138)
		(end 120.787668 -104.668828)
		(width 0.0889)
		(layer "F.Cu")
		(net "M_L_DQS_DN<6>")
	)
	(segment
		(start 137.597896 -145.0594)
		(end 137.821924 -145.0594)
		(width 0.1651)
		(layer "F.Cu")
		(net "M_L_DQS_DN<6>")
	)
	(segment
		(start 138.446764 -124.2314)
		(end 138.573764 -124.3584)
		(width 0.1651)
		(layer "F.Cu")
		(net "M_L_DQS_DN<6>")
	)
	(segment
		(start 138.229848 -118.237)
		(end 138.102848 -118.364)
		(width 0.1651)
		(layer "F.Cu")
		(net "M_L_DQS_DN<6>")
	)
	(via
		(at 138.03757 -139.881356)
		(size 0.508)
		(drill 0.254)
		(layers "F.Cu" "B.Cu")
		(net "M_L_DQS_DN<6>")
	)
	(via
		(at 138.03757 -145.275046)
		(size 0.508)
		(drill 0.254)
		(layers "F.Cu" "B.Cu")
		(net "M_L_DQS_DN<6>")
	)
	(via
		(at 138.03757 -125.351286)
		(size 0.508)
		(drill 0.254)
		(layers "F.Cu" "B.Cu")
		(net "M_L_DQS_DN<6>")
	)
	(segment
		(start 137.267442 -139.420346)
		(end 137.267442 -139.7508)
		(width 0.1651)
		(layer "B.Cu")
		(net "M_L_DQS_DN<6>")
	)
	(segment
		(start 137.267442 -139.7508)
		(end 137.623042 -140.1064)
		(width 0.1651)
		(layer "B.Cu")
		(net "M_L_DQS_DN<6>")
	)
	(segment
		(start 137.521442 -139.166346)
		(end 137.267442 -139.420346)
		(width 0.1651)
		(layer "B.Cu")
		(net "M_L_DQS_DN<6>")
	)
	(segment
		(start 137.623042 -140.1064)
		(end 137.812526 -140.1064)
		(width 0.1651)
		(layer "B.Cu")
		(net "M_L_DQS_DN<6>")
	)
	(segment
		(start 137.649458 -138.78433)
		(end 137.521442 -138.912346)
		(width 0.1651)
		(layer "B.Cu")
		(net "M_L_DQS_DN<6>")
	)
	(segment
		(start 137.521442 -138.912346)
		(end 137.521442 -139.166346)
		(width 0.1651)
		(layer "B.Cu")
		(net "M_L_DQS_DN<6>")
	)
	(segment
		(start 137.649458 -137.877296)
		(end 137.649458 -138.78433)
		(width 0.1651)
		(layer "B.Cu")
		(net "M_L_DQS_DN<6>")
	)
	(segment
		(start 137.812526 -140.1064)
		(end 138.03757 -139.881356)
		(width 0.1651)
		(layer "B.Cu")
		(net "M_L_DQS_DN<6>")
	)
	(segment
		(start 138.55065 -138.533378)
		(end 138.55065 -139.368276)
		(width 0.14224)
		(layer "In4.Cu")
		(net "M_L_DQS_DN<6>")
	)
	(segment
		(start 138.204194 -132.295646)
		(end 138.204194 -133.365494)
		(width 0.14224)
		(layer "In4.Cu")
		(net "M_L_DQS_DN<6>")
	)
	(segment
		(start 138.204194 -133.365494)
		(end 138.55065 -133.71195)
		(width 0.14224)
		(layer "In4.Cu")
		(net "M_L_DQS_DN<6>")
	)
	(segment
		(start 137.589768 -125.799088)
		(end 137.589768 -126.8984)
		(width 0.14224)
		(layer "In4.Cu")
		(net "M_L_DQS_DN<6>")
	)
	(segment
		(start 138.03757 -125.351286)
		(end 137.589768 -125.799088)
		(width 0.14224)
		(layer "In4.Cu")
		(net "M_L_DQS_DN<6>")
	)
	(segment
		(start 138.55065 -131.94919)
		(end 138.204194 -132.295646)
		(width 0.14224)
		(layer "In4.Cu")
		(net "M_L_DQS_DN<6>")
	)
	(segment
		(start 138.55065 -133.71195)
		(end 138.55065 -136.85266)
		(width 0.14224)
		(layer "In4.Cu")
		(net "M_L_DQS_DN<6>")
	)
	(segment
		(start 138.55065 -139.368276)
		(end 138.03757 -139.881356)
		(width 0.14224)
		(layer "In4.Cu")
		(net "M_L_DQS_DN<6>")
	)
	(segment
		(start 137.589768 -126.8984)
		(end 138.55065 -127.859282)
		(width 0.14224)
		(layer "In4.Cu")
		(net "M_L_DQS_DN<6>")
	)
	(segment
		(start 138.152632 -137.250678)
		(end 138.152632 -138.13536)
		(width 0.14224)
		(layer "In4.Cu")
		(net "M_L_DQS_DN<6>")
	)
	(segment
		(start 138.55065 -136.85266)
		(end 138.152632 -137.250678)
		(width 0.14224)
		(layer "In4.Cu")
		(net "M_L_DQS_DN<6>")
	)
	(segment
		(start 138.152632 -138.13536)
		(end 138.55065 -138.533378)
		(width 0.14224)
		(layer "In4.Cu")
		(net "M_L_DQS_DN<6>")
	)
	(segment
		(start 138.55065 -127.859282)
		(end 138.55065 -131.94919)
		(width 0.14224)
		(layer "In4.Cu")
		(net "M_L_DQS_DN<6>")
	)
	(segment
		(start 138.03757 -139.881356)
		(end 137.964418 -139.881356)
		(width 0.14224)
		(layer "In9.Cu")
		(net "M_L_DQS_DN<6>")
	)
	(segment
		(start 137.604246 -141.503654)
		(end 137.39368 -141.71422)
		(width 0.14224)
		(layer "In9.Cu")
		(net "M_L_DQS_DN<6>")
	)
	(segment
		(start 137.39368 -141.71422)
		(end 137.39368 -143.37538)
		(width 0.14224)
		(layer "In9.Cu")
		(net "M_L_DQS_DN<6>")
	)
	(segment
		(start 137.964418 -139.881356)
		(end 137.604246 -140.241528)
		(width 0.14224)
		(layer "In9.Cu")
		(net "M_L_DQS_DN<6>")
	)
	(segment
		(start 137.39368 -143.37538)
		(end 137.604246 -143.585946)
		(width 0.14224)
		(layer "In9.Cu")
		(net "M_L_DQS_DN<6>")
	)
	(segment
		(start 137.604246 -144.841722)
		(end 138.03757 -145.275046)
		(width 0.14224)
		(layer "In9.Cu")
		(net "M_L_DQS_DN<6>")
	)
	(segment
		(start 137.604246 -140.241528)
		(end 137.604246 -141.503654)
		(width 0.14224)
		(layer "In9.Cu")
		(net "M_L_DQS_DN<6>")
	)
	(segment
		(start 137.604246 -143.585946)
		(end 137.604246 -144.841722)
		(width 0.14224)
		(layer "In9.Cu")
		(net "M_L_DQS_DN<6>")
	)
	(segment
		(start 126.591568 -118.65229)
		(end 126.735078 -118.7958)
		(width 0.1651)
		(layer "F.Cu")
		(net "M_L_DQS_DN<5>")
	)
	(segment
		(start 128.47193 -145.0594)
		(end 128.687576 -145.275046)
		(width 0.1651)
		(layer "F.Cu")
		(net "M_L_DQS_DN<5>")
	)
	(segment
		(start 123.558554 -116.227352)
		(end 123.68403 -116.352828)
		(width 0.1651)
		(layer "F.Cu")
		(net "M_L_DQS_DN<5>")
	)
	(segment
		(start 129.614168 -123.230386)
		(end 129.182114 -123.230386)
		(width 0.1651)
		(layer "F.Cu")
		(net "M_L_DQS_DN<5>")
	)
	(segment
		(start 126.735078 -118.7958)
		(end 126.99111 -118.7958)
		(width 0.1651)
		(layer "F.Cu")
		(net "M_L_DQS_DN<5>")
	)
	(segment
		(start 122.084846 -114.933476)
		(end 122.264678 -114.933476)
		(width 0.1651)
		(layer "F.Cu")
		(net "M_L_DQS_DN<5>")
	)
	(segment
		(start 124.978414 -117.646704)
		(end 124.978414 -117.82679)
		(width 0.1651)
		(layer "F.Cu")
		(net "M_L_DQS_DN<5>")
	)
	(segment
		(start 123.378468 -116.227352)
		(end 123.558554 -116.227352)
		(width 0.1651)
		(layer "F.Cu")
		(net "M_L_DQS_DN<5>")
	)
	(segment
		(start 121.959116 -114.62766)
		(end 121.959116 -114.807746)
		(width 0.1651)
		(layer "F.Cu")
		(net "M_L_DQS_DN<5>")
	)
	(segment
		(start 121.222516 -114.070892)
		(end 121.402348 -114.070892)
		(width 0.1651)
		(layer "F.Cu")
		(net "M_L_DQS_DN<5>")
	)
	(segment
		(start 127.917448 -145.389854)
		(end 128.247902 -145.0594)
		(width 0.1651)
		(layer "F.Cu")
		(net "M_L_DQS_DN<5>")
	)
	(segment
		(start 121.096786 -113.945162)
		(end 121.222516 -114.070892)
		(width 0.1651)
		(layer "F.Cu")
		(net "M_L_DQS_DN<5>")
	)
	(segment
		(start 123.252738 -116.101622)
		(end 123.378468 -116.227352)
		(width 0.1651)
		(layer "F.Cu")
		(net "M_L_DQS_DN<5>")
	)
	(segment
		(start 124.421138 -117.089936)
		(end 124.546614 -117.215412)
		(width 0.1651)
		(layer "F.Cu")
		(net "M_L_DQS_DN<5>")
	)
	(segment
		(start 128.934718 -125.366018)
		(end 128.687576 -125.366018)
		(width 0.1651)
		(layer "F.Cu")
		(net "M_L_DQS_DN<5>")
	)
	(segment
		(start 128.81229 -120.61698)
		(end 128.81229 -120.867424)
		(width 0.1651)
		(layer "F.Cu")
		(net "M_L_DQS_DN<5>")
	)
	(segment
		(start 120.510046 -113.2586)
		(end 120.891046 -113.6396)
		(width 0.1016)
		(layer "F.Cu")
		(net "M_L_DQS_DN<5>")
	)
	(segment
		(start 127.810768 -119.615458)
		(end 127.810768 -119.87149)
		(width 0.1651)
		(layer "F.Cu")
		(net "M_L_DQS_DN<5>")
	)
	(segment
		(start 127.917448 -145.821654)
		(end 127.917448 -145.389854)
		(width 0.1651)
		(layer "F.Cu")
		(net "M_L_DQS_DN<5>")
	)
	(segment
		(start 127.344678 -119.4054)
		(end 127.60071 -119.4054)
		(width 0.1651)
		(layer "F.Cu")
		(net "M_L_DQS_DN<5>")
	)
	(segment
		(start 124.546614 -117.215412)
		(end 124.546614 -117.395498)
		(width 0.1651)
		(layer "F.Cu")
		(net "M_L_DQS_DN<5>")
	)
	(segment
		(start 128.67513 -121.184416)
		(end 128.81229 -121.321576)
		(width 0.1651)
		(layer "F.Cu")
		(net "M_L_DQS_DN<5>")
	)
	(segment
		(start 128.67513 -121.004584)
		(end 128.67513 -121.184416)
		(width 0.1651)
		(layer "F.Cu")
		(net "M_L_DQS_DN<5>")
	)
	(segment
		(start 129.741168 -122.531886)
		(end 129.741168 -123.103386)
		(width 0.1651)
		(layer "F.Cu")
		(net "M_L_DQS_DN<5>")
	)
	(segment
		(start 124.852938 -117.521228)
		(end 124.978414 -117.646704)
		(width 0.1651)
		(layer "F.Cu")
		(net "M_L_DQS_DN<5>")
	)
	(segment
		(start 128.21031 -120.015)
		(end 128.81229 -120.61698)
		(width 0.1651)
		(layer "F.Cu")
		(net "M_L_DQS_DN<5>")
	)
	(segment
		(start 122.69597 -115.364768)
		(end 122.821446 -115.490244)
		(width 0.1651)
		(layer "F.Cu")
		(net "M_L_DQS_DN<5>")
	)
	(segment
		(start 128.81229 -121.321576)
		(end 128.81229 -122.036078)
		(width 0.1651)
		(layer "F.Cu")
		(net "M_L_DQS_DN<5>")
	)
	(segment
		(start 129.614168 -122.404886)
		(end 129.741168 -122.531886)
		(width 0.1651)
		(layer "F.Cu")
		(net "M_L_DQS_DN<5>")
	)
	(segment
		(start 115.636802 -103.980234)
		(end 115.766088 -104.10952)
		(width 0.0889)
		(layer "F.Cu")
		(net "M_L_DQS_DN<5>")
	)
	(segment
		(start 128.81229 -122.036078)
		(end 129.181098 -122.404886)
		(width 0.1651)
		(layer "F.Cu")
		(net "M_L_DQS_DN<5>")
	)
	(segment
		(start 123.127262 -115.79606)
		(end 123.252738 -115.921536)
		(width 0.1651)
		(layer "F.Cu")
		(net "M_L_DQS_DN<5>")
	)
	(segment
		(start 122.390154 -115.239038)
		(end 122.515884 -115.364768)
		(width 0.1651)
		(layer "F.Cu")
		(net "M_L_DQS_DN<5>")
	)
	(segment
		(start 127.810768 -119.87149)
		(end 127.954278 -120.015)
		(width 0.1651)
		(layer "F.Cu")
		(net "M_L_DQS_DN<5>")
	)
	(segment
		(start 129.188464 -124.422154)
		(end 129.188464 -125.112272)
		(width 0.1651)
		(layer "F.Cu")
		(net "M_L_DQS_DN<5>")
	)
	(segment
		(start 122.947176 -115.79606)
		(end 123.127262 -115.79606)
		(width 0.1651)
		(layer "F.Cu")
		(net "M_L_DQS_DN<5>")
	)
	(segment
		(start 121.527824 -114.376454)
		(end 121.653554 -114.502184)
		(width 0.1651)
		(layer "F.Cu")
		(net "M_L_DQS_DN<5>")
	)
	(segment
		(start 121.83364 -114.502184)
		(end 121.959116 -114.62766)
		(width 0.1651)
		(layer "F.Cu")
		(net "M_L_DQS_DN<5>")
	)
	(segment
		(start 124.978414 -117.82679)
		(end 125.104144 -117.95252)
		(width 0.1651)
		(layer "F.Cu")
		(net "M_L_DQS_DN<5>")
	)
	(segment
		(start 123.252738 -115.921536)
		(end 123.252738 -116.101622)
		(width 0.1651)
		(layer "F.Cu")
		(net "M_L_DQS_DN<5>")
	)
	(segment
		(start 120.891046 -113.6396)
		(end 120.97131 -113.6396)
		(width 0.1016)
		(layer "F.Cu")
		(net "M_L_DQS_DN<5>")
	)
	(segment
		(start 123.989846 -116.658644)
		(end 124.115322 -116.78412)
		(width 0.1651)
		(layer "F.Cu")
		(net "M_L_DQS_DN<5>")
	)
	(segment
		(start 125.53061 -118.1989)
		(end 126.39421 -118.1989)
		(width 0.1651)
		(layer "F.Cu")
		(net "M_L_DQS_DN<5>")
	)
	(segment
		(start 123.68403 -116.532914)
		(end 123.80976 -116.658644)
		(width 0.1651)
		(layer "F.Cu")
		(net "M_L_DQS_DN<5>")
	)
	(segment
		(start 127.201168 -119.005858)
		(end 127.201168 -119.26189)
		(width 0.1651)
		(layer "F.Cu")
		(net "M_L_DQS_DN<5>")
	)
	(segment
		(start 128.299464 -147.27174)
		(end 128.299464 -146.20367)
		(width 0.1651)
		(layer "F.Cu")
		(net "M_L_DQS_DN<5>")
	)
	(segment
		(start 120.97131 -113.6396)
		(end 121.096786 -113.76533)
		(width 0.1651)
		(layer "F.Cu")
		(net "M_L_DQS_DN<5>")
	)
	(segment
		(start 124.546614 -117.395498)
		(end 124.672344 -117.521228)
		(width 0.1651)
		(layer "F.Cu")
		(net "M_L_DQS_DN<5>")
	)
	(segment
		(start 129.181098 -122.404886)
		(end 129.614168 -122.404886)
		(width 0.1651)
		(layer "F.Cu")
		(net "M_L_DQS_DN<5>")
	)
	(segment
		(start 127.60071 -119.4054)
		(end 127.810768 -119.615458)
		(width 0.1651)
		(layer "F.Cu")
		(net "M_L_DQS_DN<5>")
	)
	(segment
		(start 115.766088 -105.79989)
		(end 115.664488 -105.90149)
		(width 0.0889)
		(layer "F.Cu")
		(net "M_L_DQS_DN<5>")
	)
	(segment
		(start 124.241052 -117.089936)
		(end 124.421138 -117.089936)
		(width 0.1651)
		(layer "F.Cu")
		(net "M_L_DQS_DN<5>")
	)
	(segment
		(start 122.821446 -115.490244)
		(end 122.821446 -115.67033)
		(width 0.1651)
		(layer "F.Cu")
		(net "M_L_DQS_DN<5>")
	)
	(segment
		(start 120.116092 -113.2586)
		(end 120.510046 -113.2586)
		(width 0.1016)
		(layer "F.Cu")
		(net "M_L_DQS_DN<5>")
	)
	(segment
		(start 129.188464 -125.112272)
		(end 128.934718 -125.366018)
		(width 0.1651)
		(layer "F.Cu")
		(net "M_L_DQS_DN<5>")
	)
	(segment
		(start 129.182114 -123.230386)
		(end 128.864868 -123.547632)
		(width 0.1651)
		(layer "F.Cu")
		(net "M_L_DQS_DN<5>")
	)
	(segment
		(start 122.821446 -115.67033)
		(end 122.947176 -115.79606)
		(width 0.1651)
		(layer "F.Cu")
		(net "M_L_DQS_DN<5>")
	)
	(segment
		(start 123.68403 -116.352828)
		(end 123.68403 -116.532914)
		(width 0.1651)
		(layer "F.Cu")
		(net "M_L_DQS_DN<5>")
	)
	(segment
		(start 129.741168 -123.103386)
		(end 129.614168 -123.230386)
		(width 0.1651)
		(layer "F.Cu")
		(net "M_L_DQS_DN<5>")
	)
	(segment
		(start 115.664488 -105.90149)
		(end 115.664488 -108.806996)
		(width 0.1016)
		(layer "F.Cu")
		(net "M_L_DQS_DN<5>")
	)
	(segment
		(start 115.766088 -104.10952)
		(end 115.766088 -105.79989)
		(width 0.0889)
		(layer "F.Cu")
		(net "M_L_DQS_DN<5>")
	)
	(segment
		(start 122.515884 -115.364768)
		(end 122.69597 -115.364768)
		(width 0.1651)
		(layer "F.Cu")
		(net "M_L_DQS_DN<5>")
	)
	(segment
		(start 127.954278 -120.015)
		(end 128.21031 -120.015)
		(width 0.1651)
		(layer "F.Cu")
		(net "M_L_DQS_DN<5>")
	)
	(segment
		(start 121.096786 -113.76533)
		(end 121.096786 -113.945162)
		(width 0.1651)
		(layer "F.Cu")
		(net "M_L_DQS_DN<5>")
	)
	(segment
		(start 124.115322 -116.78412)
		(end 124.115322 -116.964206)
		(width 0.1651)
		(layer "F.Cu")
		(net "M_L_DQS_DN<5>")
	)
	(segment
		(start 128.81229 -120.867424)
		(end 128.67513 -121.004584)
		(width 0.1651)
		(layer "F.Cu")
		(net "M_L_DQS_DN<5>")
	)
	(segment
		(start 121.527824 -114.196368)
		(end 121.527824 -114.376454)
		(width 0.1651)
		(layer "F.Cu")
		(net "M_L_DQS_DN<5>")
	)
	(segment
		(start 128.864868 -123.547632)
		(end 128.864868 -124.098558)
		(width 0.1651)
		(layer "F.Cu")
		(net "M_L_DQS_DN<5>")
	)
	(segment
		(start 121.959116 -114.807746)
		(end 122.084846 -114.933476)
		(width 0.1651)
		(layer "F.Cu")
		(net "M_L_DQS_DN<5>")
	)
	(segment
		(start 115.664488 -108.806996)
		(end 120.116092 -113.2586)
		(width 0.1016)
		(layer "F.Cu")
		(net "M_L_DQS_DN<5>")
	)
	(segment
		(start 128.299464 -146.20367)
		(end 127.917448 -145.821654)
		(width 0.1651)
		(layer "F.Cu")
		(net "M_L_DQS_DN<5>")
	)
	(segment
		(start 115.636802 -102.958138)
		(end 115.636802 -103.980234)
		(width 0.0889)
		(layer "F.Cu")
		(net "M_L_DQS_DN<5>")
	)
	(segment
		(start 121.402348 -114.070892)
		(end 121.527824 -114.196368)
		(width 0.1651)
		(layer "F.Cu")
		(net "M_L_DQS_DN<5>")
	)
	(segment
		(start 125.104144 -117.95252)
		(end 125.28423 -117.95252)
		(width 0.1651)
		(layer "F.Cu")
		(net "M_L_DQS_DN<5>")
	)
	(segment
		(start 126.39421 -118.1989)
		(end 126.591568 -118.396258)
		(width 0.1651)
		(layer "F.Cu")
		(net "M_L_DQS_DN<5>")
	)
	(segment
		(start 128.247902 -145.0594)
		(end 128.47193 -145.0594)
		(width 0.1651)
		(layer "F.Cu")
		(net "M_L_DQS_DN<5>")
	)
	(segment
		(start 122.264678 -114.933476)
		(end 122.390154 -115.058952)
		(width 0.1651)
		(layer "F.Cu")
		(net "M_L_DQS_DN<5>")
	)
	(segment
		(start 126.591568 -118.396258)
		(end 126.591568 -118.65229)
		(width 0.1651)
		(layer "F.Cu")
		(net "M_L_DQS_DN<5>")
	)
	(segment
		(start 124.672344 -117.521228)
		(end 124.852938 -117.521228)
		(width 0.1651)
		(layer "F.Cu")
		(net "M_L_DQS_DN<5>")
	)
	(segment
		(start 128.864868 -124.098558)
		(end 129.188464 -124.422154)
		(width 0.1651)
		(layer "F.Cu")
		(net "M_L_DQS_DN<5>")
	)
	(segment
		(start 123.80976 -116.658644)
		(end 123.989846 -116.658644)
		(width 0.1651)
		(layer "F.Cu")
		(net "M_L_DQS_DN<5>")
	)
	(segment
		(start 122.390154 -115.058952)
		(end 122.390154 -115.239038)
		(width 0.1651)
		(layer "F.Cu")
		(net "M_L_DQS_DN<5>")
	)
	(segment
		(start 125.28423 -117.95252)
		(end 125.53061 -118.1989)
		(width 0.1651)
		(layer "F.Cu")
		(net "M_L_DQS_DN<5>")
	)
	(segment
		(start 126.99111 -118.7958)
		(end 127.201168 -119.005858)
		(width 0.1651)
		(layer "F.Cu")
		(net "M_L_DQS_DN<5>")
	)
	(segment
		(start 127.201168 -119.26189)
		(end 127.344678 -119.4054)
		(width 0.1651)
		(layer "F.Cu")
		(net "M_L_DQS_DN<5>")
	)
	(segment
		(start 124.115322 -116.964206)
		(end 124.241052 -117.089936)
		(width 0.1651)
		(layer "F.Cu")
		(net "M_L_DQS_DN<5>")
	)
	(segment
		(start 121.653554 -114.502184)
		(end 121.83364 -114.502184)
		(width 0.1651)
		(layer "F.Cu")
		(net "M_L_DQS_DN<5>")
	)
	(via
		(at 128.687576 -139.881356)
		(size 0.508)
		(drill 0.254)
		(layers "F.Cu" "B.Cu")
		(net "M_L_DQS_DN<5>")
	)
	(via
		(at 128.687576 -145.275046)
		(size 0.508)
		(drill 0.254)
		(layers "F.Cu" "B.Cu")
		(net "M_L_DQS_DN<5>")
	)
	(via
		(at 128.687576 -125.366018)
		(size 0.508)
		(drill 0.254)
		(layers "F.Cu" "B.Cu")
		(net "M_L_DQS_DN<5>")
	)
	(segment
		(start 128.171448 -138.912346)
		(end 128.171448 -139.166346)
		(width 0.1651)
		(layer "B.Cu")
		(net "M_L_DQS_DN<5>")
	)
	(segment
		(start 128.299464 -138.78433)
		(end 128.171448 -138.912346)
		(width 0.1651)
		(layer "B.Cu")
		(net "M_L_DQS_DN<5>")
	)
	(segment
		(start 128.299464 -137.877296)
		(end 128.299464 -138.78433)
		(width 0.1651)
		(layer "B.Cu")
		(net "M_L_DQS_DN<5>")
	)
	(segment
		(start 127.917448 -139.7508)
		(end 128.273048 -140.1064)
		(width 0.1651)
		(layer "B.Cu")
		(net "M_L_DQS_DN<5>")
	)
	(segment
		(start 127.917448 -139.420346)
		(end 127.917448 -139.7508)
		(width 0.1651)
		(layer "B.Cu")
		(net "M_L_DQS_DN<5>")
	)
	(segment
		(start 128.171448 -139.166346)
		(end 127.917448 -139.420346)
		(width 0.1651)
		(layer "B.Cu")
		(net "M_L_DQS_DN<5>")
	)
	(segment
		(start 128.273048 -140.1064)
		(end 128.462532 -140.1064)
		(width 0.1651)
		(layer "B.Cu")
		(net "M_L_DQS_DN<5>")
	)
	(segment
		(start 128.462532 -140.1064)
		(end 128.687576 -139.881356)
		(width 0.1651)
		(layer "B.Cu")
		(net "M_L_DQS_DN<5>")
	)
	(segment
		(start 128.254252 -144.890744)
		(end 128.638554 -145.275046)
		(width 0.14224)
		(layer "In9.Cu")
		(net "M_L_DQS_DN<5>")
	)
	(segment
		(start 128.254252 -140.27531)
		(end 128.254252 -141.503654)
		(width 0.14224)
		(layer "In9.Cu")
		(net "M_L_DQS_DN<5>")
	)
	(segment
		(start 128.638554 -145.275046)
		(end 128.687576 -145.275046)
		(width 0.14224)
		(layer "In9.Cu")
		(net "M_L_DQS_DN<5>")
	)
	(segment
		(start 128.687576 -139.881356)
		(end 128.648206 -139.881356)
		(width 0.14224)
		(layer "In9.Cu")
		(net "M_L_DQS_DN<5>")
	)
	(segment
		(start 128.043686 -143.37538)
		(end 128.254252 -143.585946)
		(width 0.14224)
		(layer "In9.Cu")
		(net "M_L_DQS_DN<5>")
	)
	(segment
		(start 128.043686 -141.71422)
		(end 128.043686 -143.37538)
		(width 0.14224)
		(layer "In9.Cu")
		(net "M_L_DQS_DN<5>")
	)
	(segment
		(start 128.648206 -139.881356)
		(end 128.254252 -140.27531)
		(width 0.14224)
		(layer "In9.Cu")
		(net "M_L_DQS_DN<5>")
	)
	(segment
		(start 128.254252 -141.503654)
		(end 128.043686 -141.71422)
		(width 0.14224)
		(layer "In9.Cu")
		(net "M_L_DQS_DN<5>")
	)
	(segment
		(start 128.254252 -143.585946)
		(end 128.254252 -144.890744)
		(width 0.14224)
		(layer "In9.Cu")
		(net "M_L_DQS_DN<5>")
	)
	(segment
		(start 128.242568 -126.873)
		(end 128.242568 -125.811026)
		(width 0.14224)
		(layer "In11.Cu")
		(net "M_L_DQS_DN<5>")
	)
	(segment
		(start 128.242568 -125.811026)
		(end 128.687576 -125.366018)
		(width 0.14224)
		(layer "In11.Cu")
		(net "M_L_DQS_DN<5>")
	)
	(segment
		(start 128.874012 -139.881356)
		(end 129.200656 -139.554712)
		(width 0.14224)
		(layer "In11.Cu")
		(net "M_L_DQS_DN<5>")
	)
	(segment
		(start 129.200656 -139.554712)
		(end 129.200656 -128.288542)
		(width 0.14224)
		(layer "In11.Cu")
		(net "M_L_DQS_DN<5>")
	)
	(segment
		(start 128.687576 -139.881356)
		(end 128.874012 -139.881356)
		(width 0.14224)
		(layer "In11.Cu")
		(net "M_L_DQS_DN<5>")
	)
	(segment
		(start 128.633728 -127.721614)
		(end 128.633728 -127.26416)
		(width 0.14224)
		(layer "In11.Cu")
		(net "M_L_DQS_DN<5>")
	)
	(segment
		(start 129.200656 -128.288542)
		(end 128.633728 -127.721614)
		(width 0.14224)
		(layer "In11.Cu")
		(net "M_L_DQS_DN<5>")
	)
	(segment
		(start 128.633728 -127.26416)
		(end 128.242568 -126.873)
		(width 0.14224)
		(layer "In11.Cu")
		(net "M_L_DQS_DN<5>")
	)
	(segment
		(start 119.121682 -145.0594)
		(end 119.337328 -145.275046)
		(width 0.1651)
		(layer "F.Cu")
		(net "M_L_DQS_DN<4>")
	)
	(segment
		(start 107.910376 -99.490784)
		(end 108.481876 -99.490784)
		(width 0.1651)
		(layer "F.Cu")
		(net "M_L_DQS_DN<4>")
	)
	(segment
		(start 118.949216 -146.20367)
		(end 118.5672 -145.821654)
		(width 0.1651)
		(layer "F.Cu")
		(net "M_L_DQS_DN<4>")
	)
	(segment
		(start 118.5672 -145.821654)
		(end 118.5672 -145.389854)
		(width 0.1651)
		(layer "F.Cu")
		(net "M_L_DQS_DN<4>")
	)
	(segment
		(start 118.949216 -147.27174)
		(end 118.949216 -146.20367)
		(width 0.1651)
		(layer "F.Cu")
		(net "M_L_DQS_DN<4>")
	)
	(segment
		(start 118.94947 -147.27174)
		(end 118.949216 -147.27174)
		(width 0.1651)
		(layer "F.Cu")
		(net "M_L_DQS_DN<4>")
	)
	(segment
		(start 118.897654 -145.0594)
		(end 119.121682 -145.0594)
		(width 0.1651)
		(layer "F.Cu")
		(net "M_L_DQS_DN<4>")
	)
	(segment
		(start 118.5672 -145.389854)
		(end 118.897654 -145.0594)
		(width 0.1651)
		(layer "F.Cu")
		(net "M_L_DQS_DN<4>")
	)
	(via
		(at 119.337328 -139.881356)
		(size 0.508)
		(drill 0.254)
		(layers "F.Cu" "B.Cu")
		(net "M_L_DQS_DN<4>")
	)
	(via
		(at 119.337328 -145.275046)
		(size 0.508)
		(drill 0.254)
		(layers "F.Cu" "B.Cu")
		(net "M_L_DQS_DN<4>")
	)
	(via
		(at 108.481876 -99.490784)
		(size 0.508)
		(drill 0.254)
		(layers "F.Cu" "B.Cu")
		(net "M_L_DQS_DN<4>")
	)
	(segment
		(start 118.9228 -140.1064)
		(end 119.112284 -140.1064)
		(width 0.1651)
		(layer "B.Cu")
		(net "M_L_DQS_DN<4>")
	)
	(segment
		(start 118.94947 -138.784076)
		(end 118.8212 -138.912346)
		(width 0.1651)
		(layer "B.Cu")
		(net "M_L_DQS_DN<4>")
	)
	(segment
		(start 119.112284 -140.1064)
		(end 119.337328 -139.881356)
		(width 0.1651)
		(layer "B.Cu")
		(net "M_L_DQS_DN<4>")
	)
	(segment
		(start 118.8212 -139.166346)
		(end 118.5672 -139.420346)
		(width 0.1651)
		(layer "B.Cu")
		(net "M_L_DQS_DN<4>")
	)
	(segment
		(start 118.94947 -137.877296)
		(end 118.94947 -138.784076)
		(width 0.1651)
		(layer "B.Cu")
		(net "M_L_DQS_DN<4>")
	)
	(segment
		(start 118.5672 -139.7508)
		(end 118.9228 -140.1064)
		(width 0.1651)
		(layer "B.Cu")
		(net "M_L_DQS_DN<4>")
	)
	(segment
		(start 118.8212 -138.912346)
		(end 118.8212 -139.166346)
		(width 0.1651)
		(layer "B.Cu")
		(net "M_L_DQS_DN<4>")
	)
	(segment
		(start 118.5672 -139.420346)
		(end 118.5672 -139.7508)
		(width 0.1651)
		(layer "B.Cu")
		(net "M_L_DQS_DN<4>")
	)
	(segment
		(start 119.761 -131.103878)
		(end 119.761 -131.357878)
		(width 0.14224)
		(layer "In4.Cu")
		(net "M_L_DQS_DN<4>")
	)
	(segment
		(start 119.901462 -137.207498)
		(end 119.901462 -137.461498)
		(width 0.14224)
		(layer "In4.Cu")
		(net "M_L_DQS_DN<4>")
	)
	(segment
		(start 119.616982 -139.881356)
		(end 119.337328 -139.881356)
		(width 0.14224)
		(layer "In4.Cu")
		(net "M_L_DQS_DN<4>")
	)
	(segment
		(start 118.837964 -127.3556)
		(end 118.837964 -128.214628)
		(width 0.14224)
		(layer "In4.Cu")
		(net "M_L_DQS_DN<4>")
	)
	(segment
		(start 119.337328 -139.881356)
		(end 119.26443 -139.881356)
		(width 0.14224)
		(layer "In4.Cu")
		(net "M_L_DQS_DN<4>")
	)
	(segment
		(start 118.738142 -125.750066)
		(end 119.118634 -126.130558)
		(width 0.14224)
		(layer "In4.Cu")
		(net "M_L_DQS_DN<4>")
	)
	(segment
		(start 108.887006 -100.38334)
		(end 109.792008 -101.288342)
		(width 0.0889)
		(layer "In4.Cu")
		(net "M_L_DQS_DN<4>")
	)
	(segment
		(start 108.828586 -100.282248)
		(end 108.887006 -100.38334)
		(width 0.0889)
		(layer "In4.Cu")
		(net "M_L_DQS_DN<4>")
	)
	(segment
		(start 119.901462 -133.455156)
		(end 119.743982 -133.612636)
		(width 0.14224)
		(layer "In4.Cu")
		(net "M_L_DQS_DN<4>")
	)
	(segment
		(start 119.743982 -133.043676)
		(end 119.901462 -133.201156)
		(width 0.14224)
		(layer "In4.Cu")
		(net "M_L_DQS_DN<4>")
	)
	(segment
		(start 119.743982 -134.582662)
		(end 119.743982 -134.836662)
		(width 0.14224)
		(layer "In4.Cu")
		(net "M_L_DQS_DN<4>")
	)
	(segment
		(start 119.743982 -131.966716)
		(end 119.743982 -132.220716)
		(width 0.14224)
		(layer "In4.Cu")
		(net "M_L_DQS_DN<4>")
	)
	(segment
		(start 119.781066 -130.29438)
		(end 119.781066 -130.54838)
		(width 0.14224)
		(layer "In4.Cu")
		(net "M_L_DQS_DN<4>")
	)
	(segment
		(start 117.5004 -124.118624)
		(end 117.723158 -124.118624)
		(width 0.14224)
		(layer "In4.Cu")
		(net "M_L_DQS_DN<4>")
	)
	(segment
		(start 118.738142 -125.133608)
		(end 118.738142 -125.750066)
		(width 0.14224)
		(layer "In4.Cu")
		(net "M_L_DQS_DN<4>")
	)
	(segment
		(start 118.904258 -143.585946)
		(end 118.904258 -144.841976)
		(width 0.14224)
		(layer "In4.Cu")
		(net "M_L_DQS_DN<4>")
	)
	(segment
		(start 118.693692 -143.37538)
		(end 118.904258 -143.585946)
		(width 0.14224)
		(layer "In4.Cu")
		(net "M_L_DQS_DN<4>")
	)
	(segment
		(start 119.743982 -134.836662)
		(end 119.901462 -134.994142)
		(width 0.14224)
		(layer "In4.Cu")
		(net "M_L_DQS_DN<4>")
	)
	(segment
		(start 119.743982 -129.65684)
		(end 119.901462 -129.81432)
		(width 0.14224)
		(layer "In4.Cu")
		(net "M_L_DQS_DN<4>")
	)
	(segment
		(start 119.901462 -132.378196)
		(end 119.901462 -132.632196)
		(width 0.14224)
		(layer "In4.Cu")
		(net "M_L_DQS_DN<4>")
	)
	(segment
		(start 119.743982 -133.612636)
		(end 119.743982 -133.866636)
		(width 0.14224)
		(layer "In4.Cu")
		(net "M_L_DQS_DN<4>")
	)
	(segment
		(start 119.901462 -131.49834)
		(end 119.901462 -131.809236)
		(width 0.14224)
		(layer "In4.Cu")
		(net "M_L_DQS_DN<4>")
	)
	(segment
		(start 119.901462 -130.173984)
		(end 119.781066 -130.29438)
		(width 0.14224)
		(layer "In4.Cu")
		(net "M_L_DQS_DN<4>")
	)
	(segment
		(start 118.837964 -128.214628)
		(end 119.205756 -128.58242)
		(width 0.14224)
		(layer "In4.Cu")
		(net "M_L_DQS_DN<4>")
	)
	(segment
		(start 117.902736 -124.521214)
		(end 118.082314 -124.700792)
		(width 0.14224)
		(layer "In4.Cu")
		(net "M_L_DQS_DN<4>")
	)
	(segment
		(start 119.64416 -127.004318)
		(end 119.189246 -127.004318)
		(width 0.14224)
		(layer "In4.Cu")
		(net "M_L_DQS_DN<4>")
	)
	(segment
		(start 119.901462 -134.425182)
		(end 119.743982 -134.582662)
		(width 0.14224)
		(layer "In4.Cu")
		(net "M_L_DQS_DN<4>")
	)
	(segment
		(start 119.901462 -135.674608)
		(end 119.743982 -135.832088)
		(width 0.14224)
		(layer "In4.Cu")
		(net "M_L_DQS_DN<4>")
	)
	(segment
		(start 119.901462 -130.963416)
		(end 119.761 -131.103878)
		(width 0.14224)
		(layer "In4.Cu")
		(net "M_L_DQS_DN<4>")
	)
	(segment
		(start 118.904258 -140.241528)
		(end 118.904258 -141.503654)
		(width 0.14224)
		(layer "In4.Cu")
		(net "M_L_DQS_DN<4>")
	)
	(segment
		(start 119.189246 -127.004318)
		(end 118.837964 -127.3556)
		(width 0.14224)
		(layer "In4.Cu")
		(net "M_L_DQS_DN<4>")
	)
	(segment
		(start 118.693692 -141.71422)
		(end 118.693692 -143.37538)
		(width 0.14224)
		(layer "In4.Cu")
		(net "M_L_DQS_DN<4>")
	)
	(segment
		(start 109.792008 -102.99319)
		(end 110.052612 -103.253794)
		(width 0.0889)
		(layer "In4.Cu")
		(net "M_L_DQS_DN<4>")
	)
	(segment
		(start 119.865648 -126.352046)
		(end 119.865648 -126.78283)
		(width 0.14224)
		(layer "In4.Cu")
		(net "M_L_DQS_DN<4>")
	)
	(segment
		(start 109.792008 -101.288342)
		(end 109.792008 -102.99319)
		(width 0.0889)
		(layer "In4.Cu")
		(net "M_L_DQS_DN<4>")
	)
	(segment
		(start 119.743982 -132.220716)
		(end 119.901462 -132.378196)
		(width 0.14224)
		(layer "In4.Cu")
		(net "M_L_DQS_DN<4>")
	)
	(segment
		(start 117.320568 -123.716034)
		(end 117.320568 -123.939046)
		(width 0.14224)
		(layer "In4.Cu")
		(net "M_L_DQS_DN<4>")
	)
	(segment
		(start 119.743982 -135.832088)
		(end 119.743982 -136.086088)
		(width 0.14224)
		(layer "In4.Cu")
		(net "M_L_DQS_DN<4>")
	)
	(segment
		(start 119.743982 -137.872978)
		(end 119.901462 -138.030458)
		(width 0.14224)
		(layer "In4.Cu")
		(net "M_L_DQS_DN<4>")
	)
	(segment
		(start 119.743982 -138.441938)
		(end 119.743982 -138.695938)
		(width 0.14224)
		(layer "In4.Cu")
		(net "M_L_DQS_DN<4>")
	)
	(segment
		(start 119.901462 -133.201156)
		(end 119.901462 -133.455156)
		(width 0.14224)
		(layer "In4.Cu")
		(net "M_L_DQS_DN<4>")
	)
	(segment
		(start 119.901462 -129.81432)
		(end 119.901462 -130.173984)
		(width 0.14224)
		(layer "In4.Cu")
		(net "M_L_DQS_DN<4>")
	)
	(segment
		(start 119.64416 -126.130558)
		(end 119.865648 -126.352046)
		(width 0.14224)
		(layer "In4.Cu")
		(net "M_L_DQS_DN<4>")
	)
	(segment
		(start 118.904258 -141.503654)
		(end 118.693692 -141.71422)
		(width 0.14224)
		(layer "In4.Cu")
		(net "M_L_DQS_DN<4>")
	)
	(segment
		(start 119.743982 -137.050018)
		(end 119.901462 -137.207498)
		(width 0.14224)
		(layer "In4.Cu")
		(net "M_L_DQS_DN<4>")
	)
	(segment
		(start 119.743982 -129.40284)
		(end 119.743982 -129.65684)
		(width 0.14224)
		(layer "In4.Cu")
		(net "M_L_DQS_DN<4>")
	)
	(segment
		(start 119.743982 -132.789676)
		(end 119.743982 -133.043676)
		(width 0.14224)
		(layer "In4.Cu")
		(net "M_L_DQS_DN<4>")
	)
	(segment
		(start 118.904258 -144.841976)
		(end 119.337328 -145.275046)
		(width 0.14224)
		(layer "In4.Cu")
		(net "M_L_DQS_DN<4>")
	)
	(segment
		(start 110.013242 -106.5403)
		(end 110.013242 -106.562398)
		(width 0.0889)
		(layer "In4.Cu")
		(net "M_L_DQS_DN<4>")
	)
	(segment
		(start 119.901462 -132.632196)
		(end 119.743982 -132.789676)
		(width 0.14224)
		(layer "In4.Cu")
		(net "M_L_DQS_DN<4>")
	)
	(segment
		(start 119.761 -131.357878)
		(end 119.901462 -131.49834)
		(width 0.14224)
		(layer "In4.Cu")
		(net "M_L_DQS_DN<4>")
	)
	(segment
		(start 119.743982 -136.796018)
		(end 119.743982 -137.050018)
		(width 0.14224)
		(layer "In4.Cu")
		(net "M_L_DQS_DN<4>")
	)
	(segment
		(start 119.901462 -136.638538)
		(end 119.743982 -136.796018)
		(width 0.14224)
		(layer "In4.Cu")
		(net "M_L_DQS_DN<4>")
	)
	(segment
		(start 119.901462 -138.030458)
		(end 119.901462 -138.284458)
		(width 0.14224)
		(layer "In4.Cu")
		(net "M_L_DQS_DN<4>")
	)
	(segment
		(start 117.723158 -124.118624)
		(end 117.902736 -124.298202)
		(width 0.14224)
		(layer "In4.Cu")
		(net "M_L_DQS_DN<4>")
	)
	(segment
		(start 119.901462 -139.596876)
		(end 119.616982 -139.881356)
		(width 0.14224)
		(layer "In4.Cu")
		(net "M_L_DQS_DN<4>")
	)
	(segment
		(start 119.743982 -137.618978)
		(end 119.743982 -137.872978)
		(width 0.14224)
		(layer "In4.Cu")
		(net "M_L_DQS_DN<4>")
	)
	(segment
		(start 119.901462 -129.24536)
		(end 119.743982 -129.40284)
		(width 0.14224)
		(layer "In4.Cu")
		(net "M_L_DQS_DN<4>")
	)
	(segment
		(start 119.118634 -126.130558)
		(end 119.64416 -126.130558)
		(width 0.14224)
		(layer "In4.Cu")
		(net "M_L_DQS_DN<4>")
	)
	(segment
		(start 119.901462 -134.994142)
		(end 119.901462 -135.674608)
		(width 0.14224)
		(layer "In4.Cu")
		(net "M_L_DQS_DN<4>")
	)
	(segment
		(start 119.901462 -138.853418)
		(end 119.901462 -139.596876)
		(width 0.14224)
		(layer "In4.Cu")
		(net "M_L_DQS_DN<4>")
	)
	(segment
		(start 119.901462 -134.024116)
		(end 119.901462 -134.425182)
		(width 0.14224)
		(layer "In4.Cu")
		(net "M_L_DQS_DN<4>")
	)
	(segment
		(start 118.082314 -124.700792)
		(end 118.305326 -124.700792)
		(width 0.14224)
		(layer "In4.Cu")
		(net "M_L_DQS_DN<4>")
	)
	(segment
		(start 119.865648 -126.78283)
		(end 119.64416 -127.004318)
		(width 0.14224)
		(layer "In4.Cu")
		(net "M_L_DQS_DN<4>")
	)
	(segment
		(start 119.901462 -128.785874)
		(end 119.901462 -129.24536)
		(width 0.14224)
		(layer "In4.Cu")
		(net "M_L_DQS_DN<4>")
	)
	(segment
		(start 119.781066 -130.54838)
		(end 119.901462 -130.668776)
		(width 0.14224)
		(layer "In4.Cu")
		(net "M_L_DQS_DN<4>")
	)
	(segment
		(start 119.743982 -138.695938)
		(end 119.901462 -138.853418)
		(width 0.14224)
		(layer "In4.Cu")
		(net "M_L_DQS_DN<4>")
	)
	(segment
		(start 117.902736 -124.298202)
		(end 117.902736 -124.521214)
		(width 0.14224)
		(layer "In4.Cu")
		(net "M_L_DQS_DN<4>")
	)
	(segment
		(start 119.26443 -139.881356)
		(end 118.904258 -140.241528)
		(width 0.14224)
		(layer "In4.Cu")
		(net "M_L_DQS_DN<4>")
	)
	(segment
		(start 119.743982 -136.086088)
		(end 119.901462 -136.243568)
		(width 0.14224)
		(layer "In4.Cu")
		(net "M_L_DQS_DN<4>")
	)
	(segment
		(start 117.320568 -123.939046)
		(end 117.5004 -124.118624)
		(width 0.14224)
		(layer "In4.Cu")
		(net "M_L_DQS_DN<4>")
	)
	(segment
		(start 110.013242 -116.408708)
		(end 117.320568 -123.716034)
		(width 0.14224)
		(layer "In4.Cu")
		(net "M_L_DQS_DN<4>")
	)
	(segment
		(start 119.901462 -131.809236)
		(end 119.743982 -131.966716)
		(width 0.14224)
		(layer "In4.Cu")
		(net "M_L_DQS_DN<4>")
	)
	(segment
		(start 110.013242 -106.562398)
		(end 110.013242 -116.408708)
		(width 0.14224)
		(layer "In4.Cu")
		(net "M_L_DQS_DN<4>")
	)
	(segment
		(start 110.052612 -106.50093)
		(end 110.013242 -106.5403)
		(width 0.0889)
		(layer "In4.Cu")
		(net "M_L_DQS_DN<4>")
	)
	(segment
		(start 110.052612 -103.253794)
		(end 110.052612 -106.50093)
		(width 0.0889)
		(layer "In4.Cu")
		(net "M_L_DQS_DN<4>")
	)
	(segment
		(start 119.901462 -136.243568)
		(end 119.901462 -136.638538)
		(width 0.14224)
		(layer "In4.Cu")
		(net "M_L_DQS_DN<4>")
	)
	(segment
		(start 119.901462 -130.668776)
		(end 119.901462 -130.963416)
		(width 0.14224)
		(layer "In4.Cu")
		(net "M_L_DQS_DN<4>")
	)
	(segment
		(start 118.305326 -124.700792)
		(end 118.738142 -125.133608)
		(width 0.14224)
		(layer "In4.Cu")
		(net "M_L_DQS_DN<4>")
	)
	(segment
		(start 119.901462 -137.461498)
		(end 119.743982 -137.618978)
		(width 0.14224)
		(layer "In4.Cu")
		(net "M_L_DQS_DN<4>")
	)
	(segment
		(start 119.205756 -128.58242)
		(end 119.698008 -128.58242)
		(width 0.14224)
		(layer "In4.Cu")
		(net "M_L_DQS_DN<4>")
	)
	(segment
		(start 119.743982 -133.866636)
		(end 119.901462 -134.024116)
		(width 0.14224)
		(layer "In4.Cu")
		(net "M_L_DQS_DN<4>")
	)
	(segment
		(start 119.901462 -138.284458)
		(end 119.743982 -138.441938)
		(width 0.14224)
		(layer "In4.Cu")
		(net "M_L_DQS_DN<4>")
	)
	(segment
		(start 119.698008 -128.58242)
		(end 119.901462 -128.785874)
		(width 0.14224)
		(layer "In4.Cu")
		(net "M_L_DQS_DN<4>")
	)
	(arc
		(start 108.481876 -99.490784)
		(mid 108.633315 -99.896116)
		(end 108.828586 -100.282248)
		(width 0.0889)
		(layer "In4.Cu")
		(net "M_L_DQS_DN<4>")
	)
	(segment
		(start 64.191388 -114.551714)
		(end 64.191388 -114.21491)
		(width 0.1651)
		(layer "F.Cu")
		(net "M_L_DQS_DN<3>")
	)
	(segment
		(start 69.376544 -106.501946)
		(end 69.556122 -106.501946)
		(width 0.1651)
		(layer "F.Cu")
		(net "M_L_DQS_DN<3>")
	)
	(segment
		(start 69.75348 -106.12501)
		(end 69.951346 -105.927144)
		(width 0.1651)
		(layer "F.Cu")
		(net "M_L_DQS_DN<3>")
	)
	(segment
		(start 66.287142 -109.591348)
		(end 66.485008 -109.393482)
		(width 0.1651)
		(layer "F.Cu")
		(net "M_L_DQS_DN<3>")
	)
	(segment
		(start 63.647828 -145.0594)
		(end 63.871856 -145.0594)
		(width 0.1651)
		(layer "F.Cu")
		(net "M_L_DQS_DN<3>")
	)
	(segment
		(start 66.485008 -109.393482)
		(end 66.664586 -109.393482)
		(width 0.1651)
		(layer "F.Cu")
		(net "M_L_DQS_DN<3>")
	)
	(segment
		(start 63.854584 -123.138184)
		(end 64.018668 -122.9741)
		(width 0.1651)
		(layer "F.Cu")
		(net "M_L_DQS_DN<3>")
	)
	(segment
		(start 63.574168 -113.7285)
		(end 63.574168 -113.4491)
		(width 0.1651)
		(layer "F.Cu")
		(net "M_L_DQS_DN<3>")
	)
	(segment
		(start 63.480188 -120.595644)
		(end 63.480188 -117.050312)
		(width 0.1651)
		(layer "F.Cu")
		(net "M_L_DQS_DN<3>")
	)
	(segment
		(start 63.574168 -113.4491)
		(end 63.447168 -113.3221)
		(width 0.1651)
		(layer "F.Cu")
		(net "M_L_DQS_DN<3>")
	)
	(segment
		(start 63.574168 -112.9157)
		(end 63.574168 -112.4839)
		(width 0.1651)
		(layer "F.Cu")
		(net "M_L_DQS_DN<3>")
	)
	(segment
		(start 67.436746 -108.441744)
		(end 67.634612 -108.243878)
		(width 0.1651)
		(layer "F.Cu")
		(net "M_L_DQS_DN<3>")
	)
	(segment
		(start 63.480188 -117.050312)
		(end 63.829438 -116.701062)
		(width 0.1651)
		(layer "F.Cu")
		(net "M_L_DQS_DN<3>")
	)
	(segment
		(start 64.018668 -122.7201)
		(end 63.878968 -122.5804)
		(width 0.1651)
		(layer "F.Cu")
		(net "M_L_DQS_DN<3>")
	)
	(segment
		(start 70.130924 -105.927144)
		(end 70.328282 -105.729786)
		(width 0.1651)
		(layer "F.Cu")
		(net "M_L_DQS_DN<3>")
	)
	(segment
		(start 65.137538 -110.740952)
		(end 65.335404 -110.543086)
		(width 0.1651)
		(layer "F.Cu")
		(net "M_L_DQS_DN<3>")
	)
	(segment
		(start 68.406518 -107.65155)
		(end 68.603876 -107.454192)
		(width 0.1651)
		(layer "F.Cu")
		(net "M_L_DQS_DN<3>")
	)
	(segment
		(start 64.018668 -121.3485)
		(end 64.018668 -121.134124)
		(width 0.1651)
		(layer "F.Cu")
		(net "M_L_DQS_DN<3>")
	)
	(segment
		(start 68.98132 -107.076748)
		(end 69.178678 -106.87939)
		(width 0.1651)
		(layer "F.Cu")
		(net "M_L_DQS_DN<3>")
	)
	(segment
		(start 64.365378 -111.69269)
		(end 64.562736 -111.495332)
		(width 0.1651)
		(layer "F.Cu")
		(net "M_L_DQS_DN<3>")
	)
	(segment
		(start 63.69939 -147.27174)
		(end 63.69939 -146.20367)
		(width 0.1651)
		(layer "F.Cu")
		(net "M_L_DQS_DN<3>")
	)
	(segment
		(start 64.416686 -116.007642)
		(end 63.829438 -116.007642)
		(width 0.1651)
		(layer "F.Cu")
		(net "M_L_DQS_DN<3>")
	)
	(segment
		(start 63.480188 -115.079272)
		(end 63.829438 -114.730022)
		(width 0.1651)
		(layer "F.Cu")
		(net "M_L_DQS_DN<3>")
	)
	(segment
		(start 72.92848 -105.729786)
		(end 74.606912 -104.051354)
		(width 0.1016)
		(layer "F.Cu")
		(net "M_L_DQS_DN<3>")
	)
	(segment
		(start 65.910206 -109.968284)
		(end 66.089784 -109.968284)
		(width 0.1651)
		(layer "F.Cu")
		(net "M_L_DQS_DN<3>")
	)
	(segment
		(start 64.334644 -125.276356)
		(end 64.570864 -125.040136)
		(width 0.1651)
		(layer "F.Cu")
		(net "M_L_DQS_DN<3>")
	)
	(segment
		(start 64.541654 -116.569744)
		(end 64.541654 -116.13261)
		(width 0.1651)
		(layer "F.Cu")
		(net "M_L_DQS_DN<3>")
	)
	(segment
		(start 63.829438 -116.007642)
		(end 63.480188 -115.658392)
		(width 0.1651)
		(layer "F.Cu")
		(net "M_L_DQS_DN<3>")
	)
	(segment
		(start 63.987934 -111.890556)
		(end 64.1858 -111.69269)
		(width 0.1651)
		(layer "F.Cu")
		(net "M_L_DQS_DN<3>")
	)
	(segment
		(start 70.328282 -105.729786)
		(end 72.808592 -105.729786)
		(width 0.1651)
		(layer "F.Cu")
		(net "M_L_DQS_DN<3>")
	)
	(segment
		(start 78.909672 -102.504494)
		(end 78.853792 -102.560374)
		(width 0.0889)
		(layer "F.Cu")
		(net "M_L_DQS_DN<3>")
	)
	(segment
		(start 65.137538 -110.92053)
		(end 65.137538 -110.740952)
		(width 0.1651)
		(layer "F.Cu")
		(net "M_L_DQS_DN<3>")
	)
	(segment
		(start 63.69939 -146.20367)
		(end 63.317374 -145.821654)
		(width 0.1651)
		(layer "F.Cu")
		(net "M_L_DQS_DN<3>")
	)
	(segment
		(start 63.88227 -114.036602)
		(end 63.574168 -113.7285)
		(width 0.1651)
		(layer "F.Cu")
		(net "M_L_DQS_DN<3>")
	)
	(segment
		(start 66.287142 -109.770926)
		(end 66.287142 -109.591348)
		(width 0.1651)
		(layer "F.Cu")
		(net "M_L_DQS_DN<3>")
	)
	(segment
		(start 69.75348 -106.304588)
		(end 69.75348 -106.12501)
		(width 0.1651)
		(layer "F.Cu")
		(net "M_L_DQS_DN<3>")
	)
	(segment
		(start 64.01308 -114.036602)
		(end 63.88227 -114.036602)
		(width 0.1651)
		(layer "F.Cu")
		(net "M_L_DQS_DN<3>")
	)
	(segment
		(start 64.94018 -111.117888)
		(end 65.137538 -110.92053)
		(width 0.1651)
		(layer "F.Cu")
		(net "M_L_DQS_DN<3>")
	)
	(segment
		(start 64.760602 -111.117888)
		(end 64.94018 -111.117888)
		(width 0.1651)
		(layer "F.Cu")
		(net "M_L_DQS_DN<3>")
	)
	(segment
		(start 64.570864 -124.364496)
		(end 64.018668 -123.8123)
		(width 0.1651)
		(layer "F.Cu")
		(net "M_L_DQS_DN<3>")
	)
	(segment
		(start 64.018668 -122.1867)
		(end 64.018668 -121.8819)
		(width 0.1651)
		(layer "F.Cu")
		(net "M_L_DQS_DN<3>")
	)
	(segment
		(start 67.81419 -108.243878)
		(end 68.029074 -108.028994)
		(width 0.1651)
		(layer "F.Cu")
		(net "M_L_DQS_DN<3>")
	)
	(segment
		(start 63.447168 -113.3221)
		(end 63.447168 -113.0427)
		(width 0.1651)
		(layer "F.Cu")
		(net "M_L_DQS_DN<3>")
	)
	(segment
		(start 67.05981 -108.81868)
		(end 67.239388 -108.81868)
		(width 0.1651)
		(layer "F.Cu")
		(net "M_L_DQS_DN<3>")
	)
	(segment
		(start 63.886588 -121.74982)
		(end 63.886588 -121.48058)
		(width 0.1651)
		(layer "F.Cu")
		(net "M_L_DQS_DN<3>")
	)
	(segment
		(start 64.541654 -116.13261)
		(end 64.416686 -116.007642)
		(width 0.1651)
		(layer "F.Cu")
		(net "M_L_DQS_DN<3>")
	)
	(segment
		(start 64.018668 -123.8123)
		(end 64.018668 -123.5329)
		(width 0.1651)
		(layer "F.Cu")
		(net "M_L_DQS_DN<3>")
	)
	(segment
		(start 63.317374 -145.821654)
		(end 63.317374 -145.389854)
		(width 0.1651)
		(layer "F.Cu")
		(net "M_L_DQS_DN<3>")
	)
	(segment
		(start 64.570864 -125.040136)
		(end 64.570864 -124.364496)
		(width 0.1651)
		(layer "F.Cu")
		(net "M_L_DQS_DN<3>")
	)
	(segment
		(start 63.878968 -122.5804)
		(end 63.878968 -122.3264)
		(width 0.1651)
		(layer "F.Cu")
		(net "M_L_DQS_DN<3>")
	)
	(segment
		(start 69.178678 -106.699812)
		(end 69.376544 -106.501946)
		(width 0.1651)
		(layer "F.Cu")
		(net "M_L_DQS_DN<3>")
	)
	(segment
		(start 63.317374 -145.389854)
		(end 63.647828 -145.0594)
		(width 0.1651)
		(layer "F.Cu")
		(net "M_L_DQS_DN<3>")
	)
	(segment
		(start 63.574168 -112.4839)
		(end 63.987934 -112.070134)
		(width 0.1651)
		(layer "F.Cu")
		(net "M_L_DQS_DN<3>")
	)
	(segment
		(start 64.410336 -116.701062)
		(end 64.541654 -116.569744)
		(width 0.1651)
		(layer "F.Cu")
		(net "M_L_DQS_DN<3>")
	)
	(segment
		(start 65.335404 -110.543086)
		(end 65.514982 -110.543086)
		(width 0.1651)
		(layer "F.Cu")
		(net "M_L_DQS_DN<3>")
	)
	(segment
		(start 68.603876 -107.274614)
		(end 68.801742 -107.076748)
		(width 0.1651)
		(layer "F.Cu")
		(net "M_L_DQS_DN<3>")
	)
	(segment
		(start 64.1858 -111.69269)
		(end 64.365378 -111.69269)
		(width 0.1651)
		(layer "F.Cu")
		(net "M_L_DQS_DN<3>")
	)
	(segment
		(start 64.018668 -121.8819)
		(end 63.886588 -121.74982)
		(width 0.1651)
		(layer "F.Cu")
		(net "M_L_DQS_DN<3>")
	)
	(segment
		(start 63.871856 -145.0594)
		(end 64.087502 -145.275046)
		(width 0.1651)
		(layer "F.Cu")
		(net "M_L_DQS_DN<3>")
	)
	(segment
		(start 67.436746 -108.621322)
		(end 67.436746 -108.441744)
		(width 0.1651)
		(layer "F.Cu")
		(net "M_L_DQS_DN<3>")
	)
	(segment
		(start 66.861944 -109.196124)
		(end 66.861944 -109.016546)
		(width 0.1651)
		(layer "F.Cu")
		(net "M_L_DQS_DN<3>")
	)
	(segment
		(start 63.480188 -115.658392)
		(end 63.480188 -115.079272)
		(width 0.1651)
		(layer "F.Cu")
		(net "M_L_DQS_DN<3>")
	)
	(segment
		(start 66.861944 -109.016546)
		(end 67.05981 -108.81868)
		(width 0.1651)
		(layer "F.Cu")
		(net "M_L_DQS_DN<3>")
	)
	(segment
		(start 69.178678 -106.87939)
		(end 69.178678 -106.699812)
		(width 0.1651)
		(layer "F.Cu")
		(net "M_L_DQS_DN<3>")
	)
	(segment
		(start 64.018668 -121.134124)
		(end 63.480188 -120.595644)
		(width 0.1651)
		(layer "F.Cu")
		(net "M_L_DQS_DN<3>")
	)
	(segment
		(start 64.087502 -125.276356)
		(end 64.334644 -125.276356)
		(width 0.1651)
		(layer "F.Cu")
		(net "M_L_DQS_DN<3>")
	)
	(segment
		(start 64.01308 -114.730022)
		(end 64.191388 -114.551714)
		(width 0.1651)
		(layer "F.Cu")
		(net "M_L_DQS_DN<3>")
	)
	(segment
		(start 63.829438 -116.701062)
		(end 64.410336 -116.701062)
		(width 0.1651)
		(layer "F.Cu")
		(net "M_L_DQS_DN<3>")
	)
	(segment
		(start 66.664586 -109.393482)
		(end 66.861944 -109.196124)
		(width 0.1651)
		(layer "F.Cu")
		(net "M_L_DQS_DN<3>")
	)
	(segment
		(start 65.71234 -110.345728)
		(end 65.71234 -110.16615)
		(width 0.1651)
		(layer "F.Cu")
		(net "M_L_DQS_DN<3>")
	)
	(segment
		(start 63.886588 -121.48058)
		(end 64.018668 -121.3485)
		(width 0.1651)
		(layer "F.Cu")
		(net "M_L_DQS_DN<3>")
	)
	(segment
		(start 72.808592 -105.729786)
		(end 72.92848 -105.729786)
		(width 0.1016)
		(layer "F.Cu")
		(net "M_L_DQS_DN<3>")
	)
	(segment
		(start 64.562736 -111.315754)
		(end 64.760602 -111.117888)
		(width 0.1651)
		(layer "F.Cu")
		(net "M_L_DQS_DN<3>")
	)
	(segment
		(start 63.854584 -123.368816)
		(end 63.854584 -123.138184)
		(width 0.1651)
		(layer "F.Cu")
		(net "M_L_DQS_DN<3>")
	)
	(segment
		(start 68.801742 -107.076748)
		(end 68.98132 -107.076748)
		(width 0.1651)
		(layer "F.Cu")
		(net "M_L_DQS_DN<3>")
	)
	(segment
		(start 74.606912 -104.051354)
		(end 76.830174 -104.051354)
		(width 0.1016)
		(layer "F.Cu")
		(net "M_L_DQS_DN<3>")
	)
	(segment
		(start 67.239388 -108.81868)
		(end 67.436746 -108.621322)
		(width 0.1651)
		(layer "F.Cu")
		(net "M_L_DQS_DN<3>")
	)
	(segment
		(start 64.018668 -123.5329)
		(end 63.854584 -123.368816)
		(width 0.1651)
		(layer "F.Cu")
		(net "M_L_DQS_DN<3>")
	)
	(segment
		(start 64.562736 -111.495332)
		(end 64.562736 -111.315754)
		(width 0.1651)
		(layer "F.Cu")
		(net "M_L_DQS_DN<3>")
	)
	(segment
		(start 65.71234 -110.16615)
		(end 65.910206 -109.968284)
		(width 0.1651)
		(layer "F.Cu")
		(net "M_L_DQS_DN<3>")
	)
	(segment
		(start 77.362812 -104.051354)
		(end 76.830174 -104.051354)
		(width 0.1016)
		(layer "F.Cu")
		(net "M_L_DQS_DN<3>")
	)
	(segment
		(start 67.634612 -108.243878)
		(end 67.81419 -108.243878)
		(width 0.1651)
		(layer "F.Cu")
		(net "M_L_DQS_DN<3>")
	)
	(segment
		(start 78.853792 -102.560374)
		(end 77.362812 -104.051354)
		(width 0.1016)
		(layer "F.Cu")
		(net "M_L_DQS_DN<3>")
	)
	(segment
		(start 65.514982 -110.543086)
		(end 65.71234 -110.345728)
		(width 0.1651)
		(layer "F.Cu")
		(net "M_L_DQS_DN<3>")
	)
	(segment
		(start 63.829438 -114.730022)
		(end 64.01308 -114.730022)
		(width 0.1651)
		(layer "F.Cu")
		(net "M_L_DQS_DN<3>")
	)
	(segment
		(start 63.878968 -122.3264)
		(end 64.018668 -122.1867)
		(width 0.1651)
		(layer "F.Cu")
		(net "M_L_DQS_DN<3>")
	)
	(segment
		(start 78.909672 -101.653086)
		(end 78.909672 -102.504494)
		(width 0.0889)
		(layer "F.Cu")
		(net "M_L_DQS_DN<3>")
	)
	(segment
		(start 63.447168 -113.0427)
		(end 63.574168 -112.9157)
		(width 0.1651)
		(layer "F.Cu")
		(net "M_L_DQS_DN<3>")
	)
	(segment
		(start 64.018668 -122.9741)
		(end 64.018668 -122.7201)
		(width 0.1651)
		(layer "F.Cu")
		(net "M_L_DQS_DN<3>")
	)
	(segment
		(start 68.029074 -107.849416)
		(end 68.22694 -107.65155)
		(width 0.1651)
		(layer "F.Cu")
		(net "M_L_DQS_DN<3>")
	)
	(segment
		(start 63.987934 -112.070134)
		(end 63.987934 -111.890556)
		(width 0.1651)
		(layer "F.Cu")
		(net "M_L_DQS_DN<3>")
	)
	(segment
		(start 68.22694 -107.65155)
		(end 68.406518 -107.65155)
		(width 0.1651)
		(layer "F.Cu")
		(net "M_L_DQS_DN<3>")
	)
	(segment
		(start 69.556122 -106.501946)
		(end 69.75348 -106.304588)
		(width 0.1651)
		(layer "F.Cu")
		(net "M_L_DQS_DN<3>")
	)
	(segment
		(start 64.191388 -114.21491)
		(end 64.01308 -114.036602)
		(width 0.1651)
		(layer "F.Cu")
		(net "M_L_DQS_DN<3>")
	)
	(segment
		(start 68.029074 -108.028994)
		(end 68.029074 -107.849416)
		(width 0.1651)
		(layer "F.Cu")
		(net "M_L_DQS_DN<3>")
	)
	(segment
		(start 66.089784 -109.968284)
		(end 66.287142 -109.770926)
		(width 0.1651)
		(layer "F.Cu")
		(net "M_L_DQS_DN<3>")
	)
	(segment
		(start 69.951346 -105.927144)
		(end 70.130924 -105.927144)
		(width 0.1651)
		(layer "F.Cu")
		(net "M_L_DQS_DN<3>")
	)
	(segment
		(start 68.603876 -107.454192)
		(end 68.603876 -107.274614)
		(width 0.1651)
		(layer "F.Cu")
		(net "M_L_DQS_DN<3>")
	)
	(via
		(at 64.087502 -139.881356)
		(size 0.508)
		(drill 0.254)
		(layers "F.Cu" "B.Cu")
		(net "M_L_DQS_DN<3>")
	)
	(via
		(at 64.087502 -125.276356)
		(size 0.508)
		(drill 0.254)
		(layers "F.Cu" "B.Cu")
		(net "M_L_DQS_DN<3>")
	)
	(via
		(at 64.087502 -145.275046)
		(size 0.508)
		(drill 0.254)
		(layers "F.Cu" "B.Cu")
		(net "M_L_DQS_DN<3>")
	)
	(segment
		(start 63.69939 -137.877296)
		(end 63.69939 -138.78433)
		(width 0.1651)
		(layer "B.Cu")
		(net "M_L_DQS_DN<3>")
	)
	(segment
		(start 63.571374 -138.912346)
		(end 63.571374 -139.166346)
		(width 0.1651)
		(layer "B.Cu")
		(net "M_L_DQS_DN<3>")
	)
	(segment
		(start 63.571374 -139.166346)
		(end 63.317374 -139.420346)
		(width 0.1651)
		(layer "B.Cu")
		(net "M_L_DQS_DN<3>")
	)
	(segment
		(start 63.862458 -140.1064)
		(end 64.087502 -139.881356)
		(width 0.1651)
		(layer "B.Cu")
		(net "M_L_DQS_DN<3>")
	)
	(segment
		(start 63.69939 -138.78433)
		(end 63.571374 -138.912346)
		(width 0.1651)
		(layer "B.Cu")
		(net "M_L_DQS_DN<3>")
	)
	(segment
		(start 63.672974 -140.1064)
		(end 63.862458 -140.1064)
		(width 0.1651)
		(layer "B.Cu")
		(net "M_L_DQS_DN<3>")
	)
	(segment
		(start 63.317374 -139.7508)
		(end 63.672974 -140.1064)
		(width 0.1651)
		(layer "B.Cu")
		(net "M_L_DQS_DN<3>")
	)
	(segment
		(start 63.317374 -139.420346)
		(end 63.317374 -139.7508)
		(width 0.1651)
		(layer "B.Cu")
		(net "M_L_DQS_DN<3>")
	)
	(segment
		(start 64.600582 -133.893814)
		(end 64.600582 -139.36853)
		(width 0.14224)
		(layer "In4.Cu")
		(net "M_L_DQS_DN<3>")
	)
	(segment
		(start 63.443612 -143.37538)
		(end 63.654432 -143.5862)
		(width 0.14224)
		(layer "In4.Cu")
		(net "M_L_DQS_DN<3>")
	)
	(segment
		(start 64.219328 -133.51256)
		(end 64.600582 -133.893814)
		(width 0.14224)
		(layer "In4.Cu")
		(net "M_L_DQS_DN<3>")
	)
	(segment
		(start 64.087502 -125.276356)
		(end 63.648844 -125.715014)
		(width 0.14224)
		(layer "In4.Cu")
		(net "M_L_DQS_DN<3>")
	)
	(segment
		(start 64.01435 -139.881356)
		(end 63.654432 -140.241274)
		(width 0.14224)
		(layer "In4.Cu")
		(net "M_L_DQS_DN<3>")
	)
	(segment
		(start 63.654432 -141.5034)
		(end 63.443612 -141.71422)
		(width 0.14224)
		(layer "In4.Cu")
		(net "M_L_DQS_DN<3>")
	)
	(segment
		(start 64.219328 -132.730494)
		(end 64.219328 -133.51256)
		(width 0.14224)
		(layer "In4.Cu")
		(net "M_L_DQS_DN<3>")
	)
	(segment
		(start 64.087502 -139.881356)
		(end 64.01435 -139.881356)
		(width 0.14224)
		(layer "In4.Cu")
		(net "M_L_DQS_DN<3>")
	)
	(segment
		(start 63.648844 -126.795276)
		(end 64.600582 -127.747014)
		(width 0.14224)
		(layer "In4.Cu")
		(net "M_L_DQS_DN<3>")
	)
	(segment
		(start 64.087756 -139.881356)
		(end 64.087502 -139.881356)
		(width 0.14224)
		(layer "In4.Cu")
		(net "M_L_DQS_DN<3>")
	)
	(segment
		(start 63.648844 -125.715014)
		(end 63.648844 -126.795276)
		(width 0.14224)
		(layer "In4.Cu")
		(net "M_L_DQS_DN<3>")
	)
	(segment
		(start 63.654432 -144.841976)
		(end 64.087502 -145.275046)
		(width 0.14224)
		(layer "In4.Cu")
		(net "M_L_DQS_DN<3>")
	)
	(segment
		(start 63.654432 -143.5862)
		(end 63.654432 -144.841976)
		(width 0.14224)
		(layer "In4.Cu")
		(net "M_L_DQS_DN<3>")
	)
	(segment
		(start 63.654432 -140.241274)
		(end 63.654432 -141.5034)
		(width 0.14224)
		(layer "In4.Cu")
		(net "M_L_DQS_DN<3>")
	)
	(segment
		(start 64.600582 -127.747014)
		(end 64.600582 -132.34924)
		(width 0.14224)
		(layer "In4.Cu")
		(net "M_L_DQS_DN<3>")
	)
	(segment
		(start 64.600582 -139.36853)
		(end 64.087756 -139.881356)
		(width 0.14224)
		(layer "In4.Cu")
		(net "M_L_DQS_DN<3>")
	)
	(segment
		(start 64.600582 -132.34924)
		(end 64.219328 -132.730494)
		(width 0.14224)
		(layer "In4.Cu")
		(net "M_L_DQS_DN<3>")
	)
	(segment
		(start 63.443612 -141.71422)
		(end 63.443612 -143.37538)
		(width 0.14224)
		(layer "In4.Cu")
		(net "M_L_DQS_DN<3>")
	)
	(segment
		(start 53.96738 -145.821654)
		(end 53.96738 -145.389854)
		(width 0.1651)
		(layer "F.Cu")
		(net "M_L_DQS_DN<2>")
	)
	(segment
		(start 54.349396 -146.20367)
		(end 53.96738 -145.821654)
		(width 0.1651)
		(layer "F.Cu")
		(net "M_L_DQS_DN<2>")
	)
	(segment
		(start 73.758806 -100.662486)
		(end 73.187306 -100.662486)
		(width 0.1651)
		(layer "F.Cu")
		(net "M_L_DQS_DN<2>")
	)
	(segment
		(start 54.297834 -145.0594)
		(end 54.521862 -145.0594)
		(width 0.1651)
		(layer "F.Cu")
		(net "M_L_DQS_DN<2>")
	)
	(segment
		(start 54.349396 -147.27174)
		(end 54.349396 -146.20367)
		(width 0.1651)
		(layer "F.Cu")
		(net "M_L_DQS_DN<2>")
	)
	(segment
		(start 54.521862 -145.0594)
		(end 54.737508 -145.275046)
		(width 0.1651)
		(layer "F.Cu")
		(net "M_L_DQS_DN<2>")
	)
	(segment
		(start 53.96738 -145.389854)
		(end 54.297834 -145.0594)
		(width 0.1651)
		(layer "F.Cu")
		(net "M_L_DQS_DN<2>")
	)
	(via
		(at 54.737508 -139.881356)
		(size 0.508)
		(drill 0.254)
		(layers "F.Cu" "B.Cu")
		(net "M_L_DQS_DN<2>")
	)
	(via
		(at 73.187306 -100.662486)
		(size 0.508)
		(drill 0.254)
		(layers "F.Cu" "B.Cu")
		(net "M_L_DQS_DN<2>")
	)
	(via
		(at 54.737508 -145.275046)
		(size 0.508)
		(drill 0.254)
		(layers "F.Cu" "B.Cu")
		(net "M_L_DQS_DN<2>")
	)
	(segment
		(start 54.349396 -137.877296)
		(end 54.349396 -138.78433)
		(width 0.1651)
		(layer "B.Cu")
		(net "M_L_DQS_DN<2>")
	)
	(segment
		(start 54.349396 -138.78433)
		(end 54.22138 -138.912346)
		(width 0.1651)
		(layer "B.Cu")
		(net "M_L_DQS_DN<2>")
	)
	(segment
		(start 54.22138 -139.166346)
		(end 53.96738 -139.420346)
		(width 0.1651)
		(layer "B.Cu")
		(net "M_L_DQS_DN<2>")
	)
	(segment
		(start 53.96738 -139.420346)
		(end 53.96738 -139.7508)
		(width 0.1651)
		(layer "B.Cu")
		(net "M_L_DQS_DN<2>")
	)
	(segment
		(start 53.96738 -139.7508)
		(end 54.32298 -140.1064)
		(width 0.1651)
		(layer "B.Cu")
		(net "M_L_DQS_DN<2>")
	)
	(segment
		(start 54.22138 -138.912346)
		(end 54.22138 -139.166346)
		(width 0.1651)
		(layer "B.Cu")
		(net "M_L_DQS_DN<2>")
	)
	(segment
		(start 54.32298 -140.1064)
		(end 54.512464 -140.1064)
		(width 0.1651)
		(layer "B.Cu")
		(net "M_L_DQS_DN<2>")
	)
	(segment
		(start 54.512464 -140.1064)
		(end 54.737508 -139.881356)
		(width 0.1651)
		(layer "B.Cu")
		(net "M_L_DQS_DN<2>")
	)
	(segment
		(start 56.138572 -125.668024)
		(end 56.138572 -125.922024)
		(width 0.14224)
		(layer "In4.Cu")
		(net "M_L_DQS_DN<2>")
	)
	(segment
		(start 55.981092 -126.079504)
		(end 55.981092 -126.333504)
		(width 0.14224)
		(layer "In4.Cu")
		(net "M_L_DQS_DN<2>")
	)
	(segment
		(start 55.145178 -136.121394)
		(end 55.250588 -136.226804)
		(width 0.14224)
		(layer "In4.Cu")
		(net "M_L_DQS_DN<2>")
	)
	(segment
		(start 69.075046 -106.04881)
		(end 65.43421 -109.689646)
		(width 0.14224)
		(layer "In4.Cu")
		(net "M_L_DQS_DN<2>")
	)
	(segment
		(start 55.981092 -126.902464)
		(end 55.981092 -127.156464)
		(width 0.14224)
		(layer "In4.Cu")
		(net "M_L_DQS_DN<2>")
	)
	(segment
		(start 55.250588 -129.680462)
		(end 55.130446 -129.800604)
		(width 0.14224)
		(layer "In4.Cu")
		(net "M_L_DQS_DN<2>")
	)
	(segment
		(start 55.139844 -134.816342)
		(end 55.250588 -134.927086)
		(width 0.14224)
		(layer "In4.Cu")
		(net "M_L_DQS_DN<2>")
	)
	(segment
		(start 54.304438 -140.241274)
		(end 54.304438 -141.5034)
		(width 0.14224)
		(layer "In4.Cu")
		(net "M_L_DQS_DN<2>")
	)
	(segment
		(start 55.017162 -139.881356)
		(end 54.737508 -139.881356)
		(width 0.14224)
		(layer "In4.Cu")
		(net "M_L_DQS_DN<2>")
	)
	(segment
		(start 55.093108 -132.234178)
		(end 55.250588 -132.391658)
		(width 0.14224)
		(layer "In4.Cu")
		(net "M_L_DQS_DN<2>")
	)
	(segment
		(start 55.981092 -127.725424)
		(end 55.981092 -127.979424)
		(width 0.14224)
		(layer "In4.Cu")
		(net "M_L_DQS_DN<2>")
	)
	(segment
		(start 72.34682 -101.557836)
		(end 72.303894 -101.557836)
		(width 0.0889)
		(layer "In4.Cu")
		(net "M_L_DQS_DN<2>")
	)
	(segment
		(start 69.48297 -103.949754)
		(end 69.467222 -103.965502)
		(width 0.0889)
		(layer "In4.Cu")
		(net "M_L_DQS_DN<2>")
	)
	(segment
		(start 55.250588 -137.5156)
		(end 55.093108 -137.67308)
		(width 0.14224)
		(layer "In4.Cu")
		(net "M_L_DQS_DN<2>")
	)
	(segment
		(start 55.130446 -130.054604)
		(end 55.250588 -130.174746)
		(width 0.14224)
		(layer "In4.Cu")
		(net "M_L_DQS_DN<2>")
	)
	(segment
		(start 55.150512 -131.14782)
		(end 55.150512 -131.40182)
		(width 0.14224)
		(layer "In4.Cu")
		(net "M_L_DQS_DN<2>")
	)
	(segment
		(start 54.304438 -141.5034)
		(end 54.093618 -141.71422)
		(width 0.14224)
		(layer "In4.Cu")
		(net "M_L_DQS_DN<2>")
	)
	(segment
		(start 54.664356 -139.881356)
		(end 54.304438 -140.241274)
		(width 0.14224)
		(layer "In4.Cu")
		(net "M_L_DQS_DN<2>")
	)
	(segment
		(start 62.368684 -117.523514)
		(end 62.368684 -118.762526)
		(width 0.14224)
		(layer "In4.Cu")
		(net "M_L_DQS_DN<2>")
	)
	(segment
		(start 55.093108 -138.49604)
		(end 55.093108 -138.75004)
		(width 0.14224)
		(layer "In4.Cu")
		(net "M_L_DQS_DN<2>")
	)
	(segment
		(start 55.250588 -134.927086)
		(end 55.250588 -135.761984)
		(width 0.14224)
		(layer "In4.Cu")
		(net "M_L_DQS_DN<2>")
	)
	(segment
		(start 61.47308 -118.95455)
		(end 60.937648 -118.95455)
		(width 0.14224)
		(layer "In4.Cu")
		(net "M_L_DQS_DN<2>")
	)
	(segment
		(start 59.689492 -120.9802)
		(end 58.911998 -120.9802)
		(width 0.14224)
		(layer "In4.Cu")
		(net "M_L_DQS_DN<2>")
	)
	(segment
		(start 69.075046 -104.357678)
		(end 69.075046 -106.04881)
		(width 0.14224)
		(layer "In4.Cu")
		(net "M_L_DQS_DN<2>")
	)
	(segment
		(start 58.911998 -120.9802)
		(end 56.138572 -123.753626)
		(width 0.14224)
		(layer "In4.Cu")
		(net "M_L_DQS_DN<2>")
	)
	(segment
		(start 54.304438 -144.841976)
		(end 54.737508 -145.275046)
		(width 0.14224)
		(layer "In4.Cu")
		(net "M_L_DQS_DN<2>")
	)
	(segment
		(start 55.093108 -137.10412)
		(end 55.250588 -137.2616)
		(width 0.14224)
		(layer "In4.Cu")
		(net "M_L_DQS_DN<2>")
	)
	(segment
		(start 55.250588 -134.037578)
		(end 55.250588 -134.451598)
		(width 0.14224)
		(layer "In4.Cu")
		(net "M_L_DQS_DN<2>")
	)
	(segment
		(start 55.145178 -135.867394)
		(end 55.145178 -136.121394)
		(width 0.14224)
		(layer "In4.Cu")
		(net "M_L_DQS_DN<2>")
	)
	(segment
		(start 55.250588 -136.226804)
		(end 55.250588 -136.69264)
		(width 0.14224)
		(layer "In4.Cu")
		(net "M_L_DQS_DN<2>")
	)
	(segment
		(start 55.250588 -134.451598)
		(end 55.139844 -134.562342)
		(width 0.14224)
		(layer "In4.Cu")
		(net "M_L_DQS_DN<2>")
	)
	(segment
		(start 70.76059 -102.728014)
		(end 69.53885 -103.949754)
		(width 0.0889)
		(layer "In4.Cu")
		(net "M_L_DQS_DN<2>")
	)
	(segment
		(start 71.025766 -102.728014)
		(end 70.76059 -102.728014)
		(width 0.0889)
		(layer "In4.Cu")
		(net "M_L_DQS_DN<2>")
	)
	(segment
		(start 65.433448 -109.689646)
		(end 65.433448 -114.45875)
		(width 0.14224)
		(layer "In4.Cu")
		(net "M_L_DQS_DN<2>")
	)
	(segment
		(start 60.33135 -119.560848)
		(end 60.33135 -120.097804)
		(width 0.14224)
		(layer "In4.Cu")
		(net "M_L_DQS_DN<2>")
	)
	(segment
		(start 69.467222 -103.965502)
		(end 69.075046 -104.357678)
		(width 0.14224)
		(layer "In4.Cu")
		(net "M_L_DQS_DN<2>")
	)
	(segment
		(start 55.250588 -130.174746)
		(end 55.250588 -131.047744)
		(width 0.14224)
		(layer "In4.Cu")
		(net "M_L_DQS_DN<2>")
	)
	(segment
		(start 60.66409 -120.741694)
		(end 60.212986 -121.192798)
		(width 0.14224)
		(layer "In4.Cu")
		(net "M_L_DQS_DN<2>")
	)
	(segment
		(start 55.250588 -138.33856)
		(end 55.093108 -138.49604)
		(width 0.14224)
		(layer "In4.Cu")
		(net "M_L_DQS_DN<2>")
	)
	(segment
		(start 55.093108 -136.85012)
		(end 55.093108 -137.10412)
		(width 0.14224)
		(layer "In4.Cu")
		(net "M_L_DQS_DN<2>")
	)
	(segment
		(start 71.81469 -101.856794)
		(end 71.813928 -101.858064)
		(width 0.0889)
		(layer "In4.Cu")
		(net "M_L_DQS_DN<2>")
	)
	(segment
		(start 54.093618 -143.37538)
		(end 54.304438 -143.5862)
		(width 0.14224)
		(layer "In4.Cu")
		(net "M_L_DQS_DN<2>")
	)
	(segment
		(start 55.250588 -139.64793)
		(end 55.017162 -139.881356)
		(width 0.14224)
		(layer "In4.Cu")
		(net "M_L_DQS_DN<2>")
	)
	(segment
		(start 56.138572 -126.744984)
		(end 55.981092 -126.902464)
		(width 0.14224)
		(layer "In4.Cu")
		(net "M_L_DQS_DN<2>")
	)
	(segment
		(start 55.093108 -138.75004)
		(end 55.250588 -138.90752)
		(width 0.14224)
		(layer "In4.Cu")
		(net "M_L_DQS_DN<2>")
	)
	(segment
		(start 55.981092 -125.256544)
		(end 55.981092 -125.510544)
		(width 0.14224)
		(layer "In4.Cu")
		(net "M_L_DQS_DN<2>")
	)
	(segment
		(start 59.90209 -121.192798)
		(end 59.689492 -120.9802)
		(width 0.14224)
		(layer "In4.Cu")
		(net "M_L_DQS_DN<2>")
	)
	(segment
		(start 55.093108 -133.057138)
		(end 55.250588 -133.214618)
		(width 0.14224)
		(layer "In4.Cu")
		(net "M_L_DQS_DN<2>")
	)
	(segment
		(start 60.937648 -118.95455)
		(end 60.33135 -119.560848)
		(width 0.14224)
		(layer "In4.Cu")
		(net "M_L_DQS_DN<2>")
	)
	(segment
		(start 71.816976 -101.852984)
		(end 71.81596 -101.854762)
		(width 0.0889)
		(layer "In4.Cu")
		(net "M_L_DQS_DN<2>")
	)
	(segment
		(start 61.666628 -119.148098)
		(end 61.47308 -118.95455)
		(width 0.14224)
		(layer "In4.Cu")
		(net "M_L_DQS_DN<2>")
	)
	(segment
		(start 56.138572 -126.490984)
		(end 56.138572 -126.744984)
		(width 0.14224)
		(layer "In4.Cu")
		(net "M_L_DQS_DN<2>")
	)
	(segment
		(start 55.250588 -131.047744)
		(end 55.150512 -131.14782)
		(width 0.14224)
		(layer "In4.Cu")
		(net "M_L_DQS_DN<2>")
	)
	(segment
		(start 55.250588 -132.391658)
		(end 55.250588 -132.645658)
		(width 0.14224)
		(layer "In4.Cu")
		(net "M_L_DQS_DN<2>")
	)
	(segment
		(start 55.441596 -129.15519)
		(end 55.250588 -129.346198)
		(width 0.14224)
		(layer "In4.Cu")
		(net "M_L_DQS_DN<2>")
	)
	(segment
		(start 55.250588 -132.645658)
		(end 55.093108 -132.803138)
		(width 0.14224)
		(layer "In4.Cu")
		(net "M_L_DQS_DN<2>")
	)
	(segment
		(start 56.138572 -125.922024)
		(end 55.981092 -126.079504)
		(width 0.14224)
		(layer "In4.Cu")
		(net "M_L_DQS_DN<2>")
	)
	(segment
		(start 55.250588 -138.08456)
		(end 55.250588 -138.33856)
		(width 0.14224)
		(layer "In4.Cu")
		(net "M_L_DQS_DN<2>")
	)
	(segment
		(start 55.250588 -129.346198)
		(end 55.250588 -129.680462)
		(width 0.14224)
		(layer "In4.Cu")
		(net "M_L_DQS_DN<2>")
	)
	(segment
		(start 60.66409 -120.430544)
		(end 60.66409 -120.741694)
		(width 0.14224)
		(layer "In4.Cu")
		(net "M_L_DQS_DN<2>")
	)
	(segment
		(start 56.138572 -127.567944)
		(end 55.981092 -127.725424)
		(width 0.14224)
		(layer "In4.Cu")
		(net "M_L_DQS_DN<2>")
	)
	(segment
		(start 55.093108 -132.803138)
		(end 55.093108 -133.057138)
		(width 0.14224)
		(layer "In4.Cu")
		(net "M_L_DQS_DN<2>")
	)
	(segment
		(start 71.813928 -101.858064)
		(end 71.712074 -102.041452)
		(width 0.0889)
		(layer "In4.Cu")
		(net "M_L_DQS_DN<2>")
	)
	(segment
		(start 54.737508 -139.881356)
		(end 54.664356 -139.881356)
		(width 0.14224)
		(layer "In4.Cu")
		(net "M_L_DQS_DN<2>")
	)
	(segment
		(start 55.150512 -131.40182)
		(end 55.250588 -131.501896)
		(width 0.14224)
		(layer "In4.Cu")
		(net "M_L_DQS_DN<2>")
	)
	(segment
		(start 71.712074 -102.041452)
		(end 71.71309 -102.040436)
		(width 0.0889)
		(layer "In4.Cu")
		(net "M_L_DQS_DN<2>")
	)
	(segment
		(start 55.250588 -135.761984)
		(end 55.145178 -135.867394)
		(width 0.14224)
		(layer "In4.Cu")
		(net "M_L_DQS_DN<2>")
	)
	(segment
		(start 55.250588 -131.501896)
		(end 55.250588 -131.822698)
		(width 0.14224)
		(layer "In4.Cu")
		(net "M_L_DQS_DN<2>")
	)
	(segment
		(start 55.981092 -127.156464)
		(end 56.138572 -127.313944)
		(width 0.14224)
		(layer "In4.Cu")
		(net "M_L_DQS_DN<2>")
	)
	(segment
		(start 65.433448 -114.45875)
		(end 62.368684 -117.523514)
		(width 0.14224)
		(layer "In4.Cu")
		(net "M_L_DQS_DN<2>")
	)
	(segment
		(start 55.981092 -127.979424)
		(end 56.138572 -128.136904)
		(width 0.14224)
		(layer "In4.Cu")
		(net "M_L_DQS_DN<2>")
	)
	(segment
		(start 55.250588 -131.822698)
		(end 55.093108 -131.980178)
		(width 0.14224)
		(layer "In4.Cu")
		(net "M_L_DQS_DN<2>")
	)
	(segment
		(start 71.81596 -101.854762)
		(end 71.81469 -101.856794)
		(width 0.0889)
		(layer "In4.Cu")
		(net "M_L_DQS_DN<2>")
	)
	(segment
		(start 65.43421 -109.689646)
		(end 65.433448 -109.689646)
		(width 0.14224)
		(layer "In4.Cu")
		(net "M_L_DQS_DN<2>")
	)
	(segment
		(start 55.250588 -133.468618)
		(end 55.093108 -133.626098)
		(width 0.14224)
		(layer "In4.Cu")
		(net "M_L_DQS_DN<2>")
	)
	(segment
		(start 56.138572 -127.313944)
		(end 56.138572 -127.567944)
		(width 0.14224)
		(layer "In4.Cu")
		(net "M_L_DQS_DN<2>")
	)
	(segment
		(start 55.621174 -128.7526)
		(end 55.441596 -128.932178)
		(width 0.14224)
		(layer "In4.Cu")
		(net "M_L_DQS_DN<2>")
	)
	(segment
		(start 60.33135 -120.097804)
		(end 60.66409 -120.430544)
		(width 0.14224)
		(layer "In4.Cu")
		(net "M_L_DQS_DN<2>")
	)
	(segment
		(start 55.250588 -133.214618)
		(end 55.250588 -133.468618)
		(width 0.14224)
		(layer "In4.Cu")
		(net "M_L_DQS_DN<2>")
	)
	(segment
		(start 55.130446 -129.800604)
		(end 55.130446 -130.054604)
		(width 0.14224)
		(layer "In4.Cu")
		(net "M_L_DQS_DN<2>")
	)
	(segment
		(start 55.093108 -137.67308)
		(end 55.093108 -137.92708)
		(width 0.14224)
		(layer "In4.Cu")
		(net "M_L_DQS_DN<2>")
	)
	(segment
		(start 56.138572 -128.136904)
		(end 56.138572 -128.458214)
		(width 0.14224)
		(layer "In4.Cu")
		(net "M_L_DQS_DN<2>")
	)
	(segment
		(start 55.250588 -136.69264)
		(end 55.093108 -136.85012)
		(width 0.14224)
		(layer "In4.Cu")
		(net "M_L_DQS_DN<2>")
	)
	(segment
		(start 55.250588 -138.90752)
		(end 55.250588 -139.64793)
		(width 0.14224)
		(layer "In4.Cu")
		(net "M_L_DQS_DN<2>")
	)
	(segment
		(start 54.304438 -143.5862)
		(end 54.304438 -144.841976)
		(width 0.14224)
		(layer "In4.Cu")
		(net "M_L_DQS_DN<2>")
	)
	(segment
		(start 69.53885 -103.949754)
		(end 69.48297 -103.949754)
		(width 0.0889)
		(layer "In4.Cu")
		(net "M_L_DQS_DN<2>")
	)
	(segment
		(start 55.844186 -128.7526)
		(end 55.621174 -128.7526)
		(width 0.14224)
		(layer "In4.Cu")
		(net "M_L_DQS_DN<2>")
	)
	(segment
		(start 62.368684 -118.762526)
		(end 61.983112 -119.148098)
		(width 0.14224)
		(layer "In4.Cu")
		(net "M_L_DQS_DN<2>")
	)
	(segment
		(start 55.093108 -131.980178)
		(end 55.093108 -132.234178)
		(width 0.14224)
		(layer "In4.Cu")
		(net "M_L_DQS_DN<2>")
	)
	(segment
		(start 55.981092 -125.510544)
		(end 56.138572 -125.668024)
		(width 0.14224)
		(layer "In4.Cu")
		(net "M_L_DQS_DN<2>")
	)
	(segment
		(start 56.138572 -125.099064)
		(end 55.981092 -125.256544)
		(width 0.14224)
		(layer "In4.Cu")
		(net "M_L_DQS_DN<2>")
	)
	(segment
		(start 54.093618 -141.71422)
		(end 54.093618 -143.37538)
		(width 0.14224)
		(layer "In4.Cu")
		(net "M_L_DQS_DN<2>")
	)
	(segment
		(start 71.71309 -102.040436)
		(end 71.025766 -102.728014)
		(width 0.0889)
		(layer "In4.Cu")
		(net "M_L_DQS_DN<2>")
	)
	(segment
		(start 56.138572 -123.753626)
		(end 56.138572 -125.099064)
		(width 0.14224)
		(layer "In4.Cu")
		(net "M_L_DQS_DN<2>")
	)
	(segment
		(start 55.093108 -133.880098)
		(end 55.250588 -134.037578)
		(width 0.14224)
		(layer "In4.Cu")
		(net "M_L_DQS_DN<2>")
	)
	(segment
		(start 61.983112 -119.148098)
		(end 61.666628 -119.148098)
		(width 0.14224)
		(layer "In4.Cu")
		(net "M_L_DQS_DN<2>")
	)
	(segment
		(start 55.093108 -137.92708)
		(end 55.250588 -138.08456)
		(width 0.14224)
		(layer "In4.Cu")
		(net "M_L_DQS_DN<2>")
	)
	(segment
		(start 55.981092 -126.333504)
		(end 56.138572 -126.490984)
		(width 0.14224)
		(layer "In4.Cu")
		(net "M_L_DQS_DN<2>")
	)
	(segment
		(start 56.138572 -128.458214)
		(end 55.844186 -128.7526)
		(width 0.14224)
		(layer "In4.Cu")
		(net "M_L_DQS_DN<2>")
	)
	(segment
		(start 55.250588 -137.2616)
		(end 55.250588 -137.5156)
		(width 0.14224)
		(layer "In4.Cu")
		(net "M_L_DQS_DN<2>")
	)
	(segment
		(start 55.441596 -128.932178)
		(end 55.441596 -129.15519)
		(width 0.14224)
		(layer "In4.Cu")
		(net "M_L_DQS_DN<2>")
	)
	(segment
		(start 60.212986 -121.192798)
		(end 59.90209 -121.192798)
		(width 0.14224)
		(layer "In4.Cu")
		(net "M_L_DQS_DN<2>")
	)
	(segment
		(start 55.093108 -133.626098)
		(end 55.093108 -133.880098)
		(width 0.14224)
		(layer "In4.Cu")
		(net "M_L_DQS_DN<2>")
	)
	(segment
		(start 55.139844 -134.562342)
		(end 55.139844 -134.816342)
		(width 0.14224)
		(layer "In4.Cu")
		(net "M_L_DQS_DN<2>")
	)
	(arc
		(start 73.05294 -101.077776)
		(mid 72.835164 -101.178711)
		(end 72.675496 -101.357938)
		(width 0.0889)
		(layer "In4.Cu")
		(net "M_L_DQS_DN<2>")
	)
	(arc
		(start 72.675496 -101.357938)
		(mid 72.536752 -101.499971)
		(end 72.34682 -101.557836)
		(width 0.0889)
		(layer "In4.Cu")
		(net "M_L_DQS_DN<2>")
	)
	(arc
		(start 73.187306 -100.662486)
		(mid 73.152877 -100.880728)
		(end 73.05294 -101.077776)
		(width 0.0889)
		(layer "In4.Cu")
		(net "M_L_DQS_DN<2>")
	)
	(arc
		(start 72.303894 -101.557836)
		(mid 72.022532 -101.642882)
		(end 71.816976 -101.852984)
		(width 0.0889)
		(layer "In4.Cu")
		(net "M_L_DQS_DN<2>")
	)
	(segment
		(start 44.600368 -145.406872)
		(end 44.94784 -145.0594)
		(width 0.1651)
		(layer "F.Cu")
		(net "M_L_DQS_DN<1>")
	)
	(segment
		(start 45.171868 -145.0594)
		(end 45.387514 -145.275046)
		(width 0.1651)
		(layer "F.Cu")
		(net "M_L_DQS_DN<1>")
	)
	(segment
		(start 71.183246 -89.27084)
		(end 70.611746 -89.27084)
		(width 0.1651)
		(layer "F.Cu")
		(net "M_L_DQS_DN<1>")
	)
	(segment
		(start 44.600368 -145.804636)
		(end 44.600368 -145.406872)
		(width 0.1651)
		(layer "F.Cu")
		(net "M_L_DQS_DN<1>")
	)
	(segment
		(start 44.94784 -145.0594)
		(end 45.171868 -145.0594)
		(width 0.1651)
		(layer "F.Cu")
		(net "M_L_DQS_DN<1>")
	)
	(segment
		(start 44.999402 -147.27174)
		(end 44.999402 -146.20367)
		(width 0.1651)
		(layer "F.Cu")
		(net "M_L_DQS_DN<1>")
	)
	(segment
		(start 44.999402 -146.20367)
		(end 44.600368 -145.804636)
		(width 0.1651)
		(layer "F.Cu")
		(net "M_L_DQS_DN<1>")
	)
	(via
		(at 45.387514 -145.275046)
		(size 0.508)
		(drill 0.254)
		(layers "F.Cu" "B.Cu")
		(net "M_L_DQS_DN<1>")
	)
	(via
		(at 45.387514 -139.881356)
		(size 0.508)
		(drill 0.254)
		(layers "F.Cu" "B.Cu")
		(net "M_L_DQS_DN<1>")
	)
	(via
		(at 70.611746 -89.27084)
		(size 0.508)
		(drill 0.254)
		(layers "F.Cu" "B.Cu")
		(net "M_L_DQS_DN<1>")
	)
	(segment
		(start 45.16247 -140.1064)
		(end 45.387514 -139.881356)
		(width 0.1651)
		(layer "B.Cu")
		(net "M_L_DQS_DN<1>")
	)
	(segment
		(start 44.999402 -138.78433)
		(end 44.871386 -138.912346)
		(width 0.1651)
		(layer "B.Cu")
		(net "M_L_DQS_DN<1>")
	)
	(segment
		(start 44.871386 -138.912346)
		(end 44.871386 -139.166346)
		(width 0.1651)
		(layer "B.Cu")
		(net "M_L_DQS_DN<1>")
	)
	(segment
		(start 44.617386 -139.420346)
		(end 44.617386 -139.7508)
		(width 0.1651)
		(layer "B.Cu")
		(net "M_L_DQS_DN<1>")
	)
	(segment
		(start 44.972986 -140.1064)
		(end 45.16247 -140.1064)
		(width 0.1651)
		(layer "B.Cu")
		(net "M_L_DQS_DN<1>")
	)
	(segment
		(start 44.871386 -139.166346)
		(end 44.617386 -139.420346)
		(width 0.1651)
		(layer "B.Cu")
		(net "M_L_DQS_DN<1>")
	)
	(segment
		(start 44.999402 -137.877296)
		(end 44.999402 -138.78433)
		(width 0.1651)
		(layer "B.Cu")
		(net "M_L_DQS_DN<1>")
	)
	(segment
		(start 44.617386 -139.7508)
		(end 44.972986 -140.1064)
		(width 0.1651)
		(layer "B.Cu")
		(net "M_L_DQS_DN<1>")
	)
	(segment
		(start 45.900594 -128.06934)
		(end 45.900594 -133.630162)
		(width 0.14224)
		(layer "In4.Cu")
		(net "M_L_DQS_DN<1>")
	)
	(segment
		(start 45.900594 -138.900916)
		(end 45.900594 -139.610592)
		(width 0.14224)
		(layer "In4.Cu")
		(net "M_L_DQS_DN<1>")
	)
	(segment
		(start 70.611746 -89.27084)
		(end 70.904862 -89.43975)
		(width 0.0889)
		(layer "In4.Cu")
		(net "M_L_DQS_DN<1>")
	)
	(segment
		(start 69.241416 -90.461338)
		(end 69.162676 -90.59799)
		(width 0.0889)
		(layer "In4.Cu")
		(net "M_L_DQS_DN<1>")
	)
	(segment
		(start 50.833274 -114.056414)
		(end 51.611022 -114.833908)
		(width 0.14224)
		(layer "In4.Cu")
		(net "M_L_DQS_DN<1>")
	)
	(segment
		(start 50.833274 -113.519966)
		(end 50.833274 -114.056414)
		(width 0.14224)
		(layer "In4.Cu")
		(net "M_L_DQS_DN<1>")
	)
	(segment
		(start 49.990248 -117.401086)
		(end 47.755048 -119.636286)
		(width 0.14224)
		(layer "In4.Cu")
		(net "M_L_DQS_DN<1>")
	)
	(segment
		(start 50.14214 -114.88928)
		(end 49.46396 -114.88928)
		(width 0.14224)
		(layer "In4.Cu")
		(net "M_L_DQS_DN<1>")
	)
	(segment
		(start 50.848768 -115.595908)
		(end 50.14214 -114.88928)
		(width 0.14224)
		(layer "In4.Cu")
		(net "M_L_DQS_DN<1>")
	)
	(segment
		(start 44.743624 -141.71422)
		(end 44.743624 -143.37538)
		(width 0.14224)
		(layer "In4.Cu")
		(net "M_L_DQS_DN<1>")
	)
	(segment
		(start 51.611022 -114.833908)
		(end 51.611022 -115.144804)
		(width 0.14224)
		(layer "In4.Cu")
		(net "M_L_DQS_DN<1>")
	)
	(segment
		(start 57.173368 -107.179872)
		(end 52.738274 -111.614966)
		(width 0.14224)
		(layer "In4.Cu")
		(net "M_L_DQS_DN<1>")
	)
	(segment
		(start 69.162676 -92.312236)
		(end 68.563998 -92.910914)
		(width 0.0889)
		(layer "In4.Cu")
		(net "M_L_DQS_DN<1>")
	)
	(segment
		(start 52.738274 -112.151414)
		(end 53.516022 -112.928908)
		(width 0.14224)
		(layer "In4.Cu")
		(net "M_L_DQS_DN<1>")
	)
	(segment
		(start 51.159918 -115.595908)
		(end 50.848768 -115.595908)
		(width 0.14224)
		(layer "In4.Cu")
		(net "M_L_DQS_DN<1>")
	)
	(segment
		(start 70.622922 -89.67089)
		(end 70.590156 -89.67089)
		(width 0.0889)
		(layer "In4.Cu")
		(net "M_L_DQS_DN<1>")
	)
	(segment
		(start 45.743114 -137.920476)
		(end 45.900594 -138.077956)
		(width 0.14224)
		(layer "In4.Cu")
		(net "M_L_DQS_DN<1>")
	)
	(segment
		(start 67.601084 -92.910914)
		(end 66.111374 -94.400624)
		(width 0.0889)
		(layer "In4.Cu")
		(net "M_L_DQS_DN<1>")
	)
	(segment
		(start 62.304168 -98.151442)
		(end 62.304168 -99.415854)
		(width 0.14224)
		(layer "In4.Cu")
		(net "M_L_DQS_DN<1>")
	)
	(segment
		(start 45.900594 -138.331956)
		(end 45.743114 -138.489436)
		(width 0.14224)
		(layer "In4.Cu")
		(net "M_L_DQS_DN<1>")
	)
	(segment
		(start 69.768212 -90.165936)
		(end 69.735446 -90.165936)
		(width 0.0889)
		(layer "In4.Cu")
		(net "M_L_DQS_DN<1>")
	)
	(segment
		(start 68.563998 -92.910914)
		(end 67.601084 -92.910914)
		(width 0.0889)
		(layer "In4.Cu")
		(net "M_L_DQS_DN<1>")
	)
	(segment
		(start 49.990248 -117.031008)
		(end 49.990248 -117.401086)
		(width 0.14224)
		(layer "In4.Cu")
		(net "M_L_DQS_DN<1>")
	)
	(segment
		(start 44.954444 -143.5862)
		(end 44.954444 -144.841976)
		(width 0.14224)
		(layer "In4.Cu")
		(net "M_L_DQS_DN<1>")
	)
	(segment
		(start 57.173368 -104.546654)
		(end 57.173368 -107.179872)
		(width 0.14224)
		(layer "In4.Cu")
		(net "M_L_DQS_DN<1>")
	)
	(segment
		(start 66.111374 -94.400624)
		(end 66.054986 -94.400624)
		(width 0.0889)
		(layer "In4.Cu")
		(net "M_L_DQS_DN<1>")
	)
	(segment
		(start 47.755048 -126.214886)
		(end 45.900594 -128.06934)
		(width 0.14224)
		(layer "In4.Cu")
		(net "M_L_DQS_DN<1>")
	)
	(segment
		(start 45.743114 -138.743436)
		(end 45.900594 -138.900916)
		(width 0.14224)
		(layer "In4.Cu")
		(net "M_L_DQS_DN<1>")
	)
	(segment
		(start 52.753514 -113.690908)
		(end 51.975766 -112.913414)
		(width 0.14224)
		(layer "In4.Cu")
		(net "M_L_DQS_DN<1>")
	)
	(segment
		(start 51.611022 -115.144804)
		(end 51.159918 -115.595908)
		(width 0.14224)
		(layer "In4.Cu")
		(net "M_L_DQS_DN<1>")
	)
	(segment
		(start 51.439826 -112.913414)
		(end 50.833274 -113.519966)
		(width 0.14224)
		(layer "In4.Cu")
		(net "M_L_DQS_DN<1>")
	)
	(segment
		(start 45.900594 -139.610592)
		(end 45.62983 -139.881356)
		(width 0.14224)
		(layer "In4.Cu")
		(net "M_L_DQS_DN<1>")
	)
	(segment
		(start 66.054986 -94.400624)
		(end 66.039238 -94.416372)
		(width 0.0889)
		(layer "In4.Cu")
		(net "M_L_DQS_DN<1>")
	)
	(segment
		(start 45.743114 -138.489436)
		(end 45.743114 -138.743436)
		(width 0.14224)
		(layer "In4.Cu")
		(net "M_L_DQS_DN<1>")
	)
	(segment
		(start 45.62983 -139.881356)
		(end 45.387514 -139.881356)
		(width 0.14224)
		(layer "In4.Cu")
		(net "M_L_DQS_DN<1>")
	)
	(segment
		(start 45.314362 -139.881356)
		(end 44.954444 -140.241274)
		(width 0.14224)
		(layer "In4.Cu")
		(net "M_L_DQS_DN<1>")
	)
	(segment
		(start 45.900594 -137.237978)
		(end 45.900594 -137.508996)
		(width 0.14224)
		(layer "In4.Cu")
		(net "M_L_DQS_DN<1>")
	)
	(segment
		(start 45.770038 -137.107422)
		(end 45.900594 -137.237978)
		(width 0.14224)
		(layer "In4.Cu")
		(net "M_L_DQS_DN<1>")
	)
	(segment
		(start 45.770038 -136.853422)
		(end 45.770038 -137.107422)
		(width 0.14224)
		(layer "In4.Cu")
		(net "M_L_DQS_DN<1>")
	)
	(segment
		(start 45.900594 -133.630162)
		(end 45.800264 -133.730492)
		(width 0.14224)
		(layer "In4.Cu")
		(net "M_L_DQS_DN<1>")
	)
	(segment
		(start 45.743114 -137.666476)
		(end 45.743114 -137.920476)
		(width 0.14224)
		(layer "In4.Cu")
		(net "M_L_DQS_DN<1>")
	)
	(segment
		(start 69.162676 -90.59799)
		(end 69.162676 -92.312236)
		(width 0.0889)
		(layer "In4.Cu")
		(net "M_L_DQS_DN<1>")
	)
	(segment
		(start 44.954444 -144.841976)
		(end 45.387514 -145.275046)
		(width 0.14224)
		(layer "In4.Cu")
		(net "M_L_DQS_DN<1>")
	)
	(segment
		(start 44.743624 -143.37538)
		(end 44.954444 -143.5862)
		(width 0.14224)
		(layer "In4.Cu")
		(net "M_L_DQS_DN<1>")
	)
	(segment
		(start 45.900594 -138.077956)
		(end 45.900594 -138.331956)
		(width 0.14224)
		(layer "In4.Cu")
		(net "M_L_DQS_DN<1>")
	)
	(segment
		(start 53.064918 -113.690908)
		(end 52.753514 -113.690908)
		(width 0.14224)
		(layer "In4.Cu")
		(net "M_L_DQS_DN<1>")
	)
	(segment
		(start 48.974248 -116.015008)
		(end 49.990248 -117.031008)
		(width 0.14224)
		(layer "In4.Cu")
		(net "M_L_DQS_DN<1>")
	)
	(segment
		(start 53.516022 -113.239804)
		(end 53.064918 -113.690908)
		(width 0.14224)
		(layer "In4.Cu")
		(net "M_L_DQS_DN<1>")
	)
	(segment
		(start 45.800264 -133.984492)
		(end 45.900594 -134.084822)
		(width 0.14224)
		(layer "In4.Cu")
		(net "M_L_DQS_DN<1>")
	)
	(segment
		(start 47.755048 -119.636286)
		(end 47.755048 -126.214886)
		(width 0.14224)
		(layer "In4.Cu")
		(net "M_L_DQS_DN<1>")
	)
	(segment
		(start 62.304168 -99.415854)
		(end 57.173368 -104.546654)
		(width 0.14224)
		(layer "In4.Cu")
		(net "M_L_DQS_DN<1>")
	)
	(segment
		(start 52.738274 -111.614966)
		(end 52.738274 -112.151414)
		(width 0.14224)
		(layer "In4.Cu")
		(net "M_L_DQS_DN<1>")
	)
	(segment
		(start 45.387514 -139.881356)
		(end 45.314362 -139.881356)
		(width 0.14224)
		(layer "In4.Cu")
		(net "M_L_DQS_DN<1>")
	)
	(segment
		(start 70.904862 -89.43975)
		(end 70.925944 -89.51849)
		(width 0.0889)
		(layer "In4.Cu")
		(net "M_L_DQS_DN<1>")
	)
	(segment
		(start 45.900594 -137.508996)
		(end 45.743114 -137.666476)
		(width 0.14224)
		(layer "In4.Cu")
		(net "M_L_DQS_DN<1>")
	)
	(segment
		(start 66.039238 -94.416372)
		(end 62.304168 -98.151442)
		(width 0.14224)
		(layer "In4.Cu")
		(net "M_L_DQS_DN<1>")
	)
	(segment
		(start 49.46396 -114.88928)
		(end 48.974248 -115.378992)
		(width 0.14224)
		(layer "In4.Cu")
		(net "M_L_DQS_DN<1>")
	)
	(segment
		(start 45.900594 -134.084822)
		(end 45.900594 -136.722866)
		(width 0.14224)
		(layer "In4.Cu")
		(net "M_L_DQS_DN<1>")
	)
	(segment
		(start 51.975766 -112.913414)
		(end 51.439826 -112.913414)
		(width 0.14224)
		(layer "In4.Cu")
		(net "M_L_DQS_DN<1>")
	)
	(segment
		(start 44.954444 -141.5034)
		(end 44.743624 -141.71422)
		(width 0.14224)
		(layer "In4.Cu")
		(net "M_L_DQS_DN<1>")
	)
	(segment
		(start 45.800264 -133.730492)
		(end 45.800264 -133.984492)
		(width 0.14224)
		(layer "In4.Cu")
		(net "M_L_DQS_DN<1>")
	)
	(segment
		(start 45.900594 -136.722866)
		(end 45.770038 -136.853422)
		(width 0.14224)
		(layer "In4.Cu")
		(net "M_L_DQS_DN<1>")
	)
	(segment
		(start 53.516022 -112.928908)
		(end 53.516022 -113.239804)
		(width 0.14224)
		(layer "In4.Cu")
		(net "M_L_DQS_DN<1>")
	)
	(segment
		(start 48.974248 -115.378992)
		(end 48.974248 -116.015008)
		(width 0.14224)
		(layer "In4.Cu")
		(net "M_L_DQS_DN<1>")
	)
	(segment
		(start 44.954444 -140.241274)
		(end 44.954444 -141.5034)
		(width 0.14224)
		(layer "In4.Cu")
		(net "M_L_DQS_DN<1>")
	)
	(arc
		(start 70.099936 -89.966038)
		(mid 69.959857 -90.108774)
		(end 69.768212 -90.165936)
		(width 0.0889)
		(layer "In4.Cu")
		(net "M_L_DQS_DN<1>")
	)
	(arc
		(start 69.735446 -90.165936)
		(mid 69.450022 -90.249403)
		(end 69.241416 -90.461338)
		(width 0.0889)
		(layer "In4.Cu")
		(net "M_L_DQS_DN<1>")
	)
	(arc
		(start 70.590156 -89.67089)
		(mid 70.306939 -89.755171)
		(end 70.099936 -89.966038)
		(width 0.0889)
		(layer "In4.Cu")
		(net "M_L_DQS_DN<1>")
	)
	(arc
		(start 70.925944 -89.51849)
		(mid 70.791382 -89.628402)
		(end 70.622922 -89.67089)
		(width 0.0889)
		(layer "In4.Cu")
		(net "M_L_DQS_DN<1>")
	)
	(segment
		(start 72.817228 -144.356328)
		(end 72.817228 -144.602962)
		(width 0.1651)
		(layer "F.Cu")
		(net "M_L_DQS_DN<17>")
	)
	(segment
		(start 84.060792 -97.690686)
		(end 84.060792 -97.358962)
		(width 0.0889)
		(layer "F.Cu")
		(net "M_L_DQS_DN<17>")
	)
	(segment
		(start 83.733132 -100.492814)
		(end 83.733132 -103.29037)
		(width 0.1016)
		(layer "F.Cu")
		(net "M_L_DQS_DN<17>")
	)
	(segment
		(start 72.817228 -144.602962)
		(end 72.56526 -144.85493)
		(width 0.1651)
		(layer "F.Cu")
		(net "M_L_DQS_DN<17>")
	)
	(segment
		(start 83.686904 -99.481386)
		(end 83.618832 -99.577906)
		(width 0.0889)
		(layer "F.Cu")
		(net "M_L_DQS_DN<17>")
	)
	(segment
		(start 83.044792 -103.97871)
		(end 83.044792 -104.355138)
		(width 0.1016)
		(layer "F.Cu")
		(net "M_L_DQS_DN<17>")
	)
	(segment
		(start 77.970126 -108.49991)
		(end 72.965564 -113.504472)
		(width 0.1651)
		(layer "F.Cu")
		(net "M_L_DQS_DN<17>")
	)
	(segment
		(start 84.060792 -97.358962)
		(end 83.997546 -97.295716)
		(width 0.0889)
		(layer "F.Cu")
		(net "M_L_DQS_DN<17>")
	)
	(segment
		(start 73.049384 -142.6718)
		(end 73.049384 -143.331184)
		(width 0.1651)
		(layer "F.Cu")
		(net "M_L_DQS_DN<17>")
	)
	(segment
		(start 73.049384 -143.331184)
		(end 72.6313 -143.749268)
		(width 0.1651)
		(layer "F.Cu")
		(net "M_L_DQS_DN<17>")
	)
	(segment
		(start 83.714082 -98.481388)
		(end 83.709256 -98.490024)
		(width 0.0889)
		(layer "F.Cu")
		(net "M_L_DQS_DN<17>")
	)
	(segment
		(start 83.733132 -99.986592)
		(end 83.733132 -100.492814)
		(width 0.0889)
		(layer "F.Cu")
		(net "M_L_DQS_DN<17>")
	)
	(segment
		(start 83.618832 -99.872292)
		(end 83.733132 -99.986592)
		(width 0.0889)
		(layer "F.Cu")
		(net "M_L_DQS_DN<17>")
	)
	(segment
		(start 83.714082 -97.490788)
		(end 83.709256 -97.499424)
		(width 0.0889)
		(layer "F.Cu")
		(net "M_L_DQS_DN<17>")
	)
	(segment
		(start 78.148434 -108.321602)
		(end 77.970126 -108.49991)
		(width 0.1016)
		(layer "F.Cu")
		(net "M_L_DQS_DN<17>")
	)
	(segment
		(start 72.965564 -125.183392)
		(end 72.17918 -125.969776)
		(width 0.1651)
		(layer "F.Cu")
		(net "M_L_DQS_DN<17>")
	)
	(segment
		(start 72.6313 -143.749268)
		(end 72.6313 -144.1704)
		(width 0.1651)
		(layer "F.Cu")
		(net "M_L_DQS_DN<17>")
	)
	(segment
		(start 72.56526 -144.85493)
		(end 72.35698 -144.85493)
		(width 0.1651)
		(layer "F.Cu")
		(net "M_L_DQS_DN<17>")
	)
	(segment
		(start 79.078328 -108.321602)
		(end 78.148434 -108.321602)
		(width 0.1016)
		(layer "F.Cu")
		(net "M_L_DQS_DN<17>")
	)
	(segment
		(start 72.35698 -144.85493)
		(end 72.16775 -144.6657)
		(width 0.1651)
		(layer "F.Cu")
		(net "M_L_DQS_DN<17>")
	)
	(segment
		(start 72.16775 -144.6657)
		(end 72.1487 -144.6657)
		(width 0.1651)
		(layer "F.Cu")
		(net "M_L_DQS_DN<17>")
	)
	(segment
		(start 83.733132 -103.29037)
		(end 83.044792 -103.97871)
		(width 0.1016)
		(layer "F.Cu")
		(net "M_L_DQS_DN<17>")
	)
	(segment
		(start 72.6313 -144.1704)
		(end 72.817228 -144.356328)
		(width 0.1651)
		(layer "F.Cu")
		(net "M_L_DQS_DN<17>")
	)
	(segment
		(start 83.044792 -104.355138)
		(end 79.078328 -108.321602)
		(width 0.1016)
		(layer "F.Cu")
		(net "M_L_DQS_DN<17>")
	)
	(segment
		(start 72.965564 -113.504472)
		(end 72.965564 -125.183392)
		(width 0.1651)
		(layer "F.Cu")
		(net "M_L_DQS_DN<17>")
	)
	(segment
		(start 72.17918 -125.969776)
		(end 72.145906 -125.969776)
		(width 0.1651)
		(layer "F.Cu")
		(net "M_L_DQS_DN<17>")
	)
	(segment
		(start 83.618832 -99.577906)
		(end 83.618832 -99.872292)
		(width 0.0889)
		(layer "F.Cu")
		(net "M_L_DQS_DN<17>")
	)
	(segment
		(start 83.720432 -98.47072)
		(end 83.714082 -98.481388)
		(width 0.0889)
		(layer "F.Cu")
		(net "M_L_DQS_DN<17>")
	)
	(via
		(at 72.142096 -140.4874)
		(size 0.508)
		(drill 0.254)
		(layers "F.Cu" "B.Cu")
		(net "M_L_DQS_DN<17>")
	)
	(via
		(at 72.1487 -144.6657)
		(size 0.508)
		(drill 0.254)
		(layers "F.Cu" "B.Cu")
		(net "M_L_DQS_DN<17>")
	)
	(via
		(at 72.145906 -125.969776)
		(size 0.508)
		(drill 0.254)
		(layers "F.Cu" "B.Cu")
		(net "M_L_DQS_DN<17>")
	)
	(arc
		(start 83.709256 -98.490024)
		(mid 83.660501 -98.686376)
		(end 83.714082 -98.881438)
		(width 0.0889)
		(layer "F.Cu")
		(net "M_L_DQS_DN<17>")
	)
	(arc
		(start 83.997546 -97.295716)
		(mid 83.833739 -97.361194)
		(end 83.714082 -97.490788)
		(width 0.0889)
		(layer "F.Cu")
		(net "M_L_DQS_DN<17>")
	)
	(arc
		(start 83.709256 -97.499424)
		(mid 83.660501 -97.695776)
		(end 83.714082 -97.890838)
		(width 0.0889)
		(layer "F.Cu")
		(net "M_L_DQS_DN<17>")
	)
	(arc
		(start 83.714082 -98.881438)
		(mid 83.788137 -99.18537)
		(end 83.686904 -99.481386)
		(width 0.0889)
		(layer "F.Cu")
		(net "M_L_DQS_DN<17>")
	)
	(arc
		(start 83.714082 -97.890838)
		(mid 83.793304 -98.179956)
		(end 83.720432 -98.47072)
		(width 0.0889)
		(layer "F.Cu")
		(net "M_L_DQS_DN<17>")
	)
	(segment
		(start 72.6059 -141.376654)
		(end 72.6059 -141.0208)
		(width 0.1651)
		(layer "B.Cu")
		(net "M_L_DQS_DN<17>")
	)
	(segment
		(start 72.563736 -140.292836)
		(end 72.33666 -140.292836)
		(width 0.1651)
		(layer "B.Cu")
		(net "M_L_DQS_DN<17>")
	)
	(segment
		(start 72.6059 -141.0208)
		(end 72.7837 -140.843)
		(width 0.1651)
		(layer "B.Cu")
		(net "M_L_DQS_DN<17>")
	)
	(segment
		(start 73.049638 -141.820392)
		(end 72.6059 -141.376654)
		(width 0.1651)
		(layer "B.Cu")
		(net "M_L_DQS_DN<17>")
	)
	(segment
		(start 73.049384 -142.477236)
		(end 73.049638 -142.476728)
		(width 0.1651)
		(layer "B.Cu")
		(net "M_L_DQS_DN<17>")
	)
	(segment
		(start 72.7837 -140.5128)
		(end 72.563736 -140.292836)
		(width 0.1651)
		(layer "B.Cu")
		(net "M_L_DQS_DN<17>")
	)
	(segment
		(start 72.7837 -140.843)
		(end 72.7837 -140.5128)
		(width 0.1651)
		(layer "B.Cu")
		(net "M_L_DQS_DN<17>")
	)
	(segment
		(start 72.33666 -140.292836)
		(end 72.142096 -140.4874)
		(width 0.1651)
		(layer "B.Cu")
		(net "M_L_DQS_DN<17>")
	)
	(segment
		(start 73.049638 -142.476728)
		(end 73.049638 -141.820392)
		(width 0.1651)
		(layer "B.Cu")
		(net "M_L_DQS_DN<17>")
	)
	(segment
		(start 72.1487 -144.6657)
		(end 72.58177 -144.23263)
		(width 0.14224)
		(layer "In9.Cu")
		(net "M_L_DQS_DN<17>")
	)
	(segment
		(start 72.068944 -143.5608)
		(end 71.906384 -143.39824)
		(width 0.14224)
		(layer "In9.Cu")
		(net "M_L_DQS_DN<17>")
	)
	(segment
		(start 72.576944 -140.922248)
		(end 72.142096 -140.4874)
		(width 0.14224)
		(layer "In9.Cu")
		(net "M_L_DQS_DN<17>")
	)
	(segment
		(start 72.193404 -142.23492)
		(end 72.038464 -142.23492)
		(width 0.14224)
		(layer "In9.Cu")
		(net "M_L_DQS_DN<17>")
	)
	(segment
		(start 72.348344 -142.38986)
		(end 72.193404 -142.23492)
		(width 0.14224)
		(layer "In9.Cu")
		(net "M_L_DQS_DN<17>")
	)
	(segment
		(start 72.056244 -141.605)
		(end 72.297544 -141.605)
		(width 0.14224)
		(layer "In9.Cu")
		(net "M_L_DQS_DN<17>")
	)
	(segment
		(start 72.58177 -144.23263)
		(end 72.58177 -143.748506)
		(width 0.14224)
		(layer "In9.Cu")
		(net "M_L_DQS_DN<17>")
	)
	(segment
		(start 72.038464 -142.23492)
		(end 71.906384 -142.10284)
		(width 0.14224)
		(layer "In9.Cu")
		(net "M_L_DQS_DN<17>")
	)
	(segment
		(start 72.193404 -142.89786)
		(end 72.348344 -142.74292)
		(width 0.14224)
		(layer "In9.Cu")
		(net "M_L_DQS_DN<17>")
	)
	(segment
		(start 71.906384 -142.10284)
		(end 71.906384 -141.75486)
		(width 0.14224)
		(layer "In9.Cu")
		(net "M_L_DQS_DN<17>")
	)
	(segment
		(start 72.348344 -142.74292)
		(end 72.348344 -142.38986)
		(width 0.14224)
		(layer "In9.Cu")
		(net "M_L_DQS_DN<17>")
	)
	(segment
		(start 71.906384 -143.39824)
		(end 71.906384 -143.03756)
		(width 0.14224)
		(layer "In9.Cu")
		(net "M_L_DQS_DN<17>")
	)
	(segment
		(start 72.297544 -141.605)
		(end 72.576944 -141.3256)
		(width 0.14224)
		(layer "In9.Cu")
		(net "M_L_DQS_DN<17>")
	)
	(segment
		(start 72.046084 -142.89786)
		(end 72.193404 -142.89786)
		(width 0.14224)
		(layer "In9.Cu")
		(net "M_L_DQS_DN<17>")
	)
	(segment
		(start 72.58177 -143.748506)
		(end 72.394064 -143.5608)
		(width 0.14224)
		(layer "In9.Cu")
		(net "M_L_DQS_DN<17>")
	)
	(segment
		(start 72.576944 -141.3256)
		(end 72.576944 -140.922248)
		(width 0.14224)
		(layer "In9.Cu")
		(net "M_L_DQS_DN<17>")
	)
	(segment
		(start 71.906384 -143.03756)
		(end 72.046084 -142.89786)
		(width 0.14224)
		(layer "In9.Cu")
		(net "M_L_DQS_DN<17>")
	)
	(segment
		(start 71.906384 -141.75486)
		(end 72.056244 -141.605)
		(width 0.14224)
		(layer "In9.Cu")
		(net "M_L_DQS_DN<17>")
	)
	(segment
		(start 72.394064 -143.5608)
		(end 72.068944 -143.5608)
		(width 0.14224)
		(layer "In9.Cu")
		(net "M_L_DQS_DN<17>")
	)
	(segment
		(start 72.594216 -128.030732)
		(end 72.924416 -128.360932)
		(width 0.14224)
		(layer "In11.Cu")
		(net "M_L_DQS_DN<17>")
	)
	(segment
		(start 72.145906 -125.969776)
		(end 72.145906 -126.00305)
		(width 0.14224)
		(layer "In11.Cu")
		(net "M_L_DQS_DN<17>")
	)
	(segment
		(start 72.149462 -140.4874)
		(end 72.142096 -140.4874)
		(width 0.14224)
		(layer "In11.Cu")
		(net "M_L_DQS_DN<17>")
	)
	(segment
		(start 72.924416 -139.712446)
		(end 72.149462 -140.4874)
		(width 0.14224)
		(layer "In11.Cu")
		(net "M_L_DQS_DN<17>")
	)
	(segment
		(start 72.145906 -126.00305)
		(end 72.594216 -126.45136)
		(width 0.14224)
		(layer "In11.Cu")
		(net "M_L_DQS_DN<17>")
	)
	(segment
		(start 72.594216 -126.45136)
		(end 72.594216 -128.030732)
		(width 0.14224)
		(layer "In11.Cu")
		(net "M_L_DQS_DN<17>")
	)
	(segment
		(start 72.924416 -128.360932)
		(end 72.924416 -139.712446)
		(width 0.14224)
		(layer "In11.Cu")
		(net "M_L_DQS_DN<17>")
	)
	(segment
		(start 146.581368 -144.1704)
		(end 146.767296 -144.356328)
		(width 0.1651)
		(layer "F.Cu")
		(net "M_L_DQS_DN<16>")
	)
	(segment
		(start 146.307048 -144.85493)
		(end 146.117818 -144.6657)
		(width 0.1651)
		(layer "F.Cu")
		(net "M_L_DQS_DN<16>")
	)
	(segment
		(start 146.999452 -143.331184)
		(end 146.581368 -143.749268)
		(width 0.1651)
		(layer "F.Cu")
		(net "M_L_DQS_DN<16>")
	)
	(segment
		(start 146.999452 -142.6718)
		(end 146.999452 -143.331184)
		(width 0.1651)
		(layer "F.Cu")
		(net "M_L_DQS_DN<16>")
	)
	(segment
		(start 146.767296 -144.602962)
		(end 146.515328 -144.85493)
		(width 0.1651)
		(layer "F.Cu")
		(net "M_L_DQS_DN<16>")
	)
	(segment
		(start 146.767296 -144.356328)
		(end 146.767296 -144.602962)
		(width 0.1651)
		(layer "F.Cu")
		(net "M_L_DQS_DN<16>")
	)
	(segment
		(start 120.787668 -94.042738)
		(end 121.359168 -94.042738)
		(width 0.1651)
		(layer "F.Cu")
		(net "M_L_DQS_DN<16>")
	)
	(segment
		(start 146.117818 -144.6657)
		(end 146.098768 -144.6657)
		(width 0.1651)
		(layer "F.Cu")
		(net "M_L_DQS_DN<16>")
	)
	(segment
		(start 146.581368 -143.749268)
		(end 146.581368 -144.1704)
		(width 0.1651)
		(layer "F.Cu")
		(net "M_L_DQS_DN<16>")
	)
	(segment
		(start 146.515328 -144.85493)
		(end 146.307048 -144.85493)
		(width 0.1651)
		(layer "F.Cu")
		(net "M_L_DQS_DN<16>")
	)
	(via
		(at 146.098768 -144.6657)
		(size 0.508)
		(drill 0.254)
		(layers "F.Cu" "B.Cu")
		(net "M_L_DQS_DN<16>")
	)
	(via
		(at 146.092164 -140.4874)
		(size 0.508)
		(drill 0.254)
		(layers "F.Cu" "B.Cu")
		(net "M_L_DQS_DN<16>")
	)
	(via
		(at 121.359168 -94.042738)
		(size 0.508)
		(drill 0.254)
		(layers "F.Cu" "B.Cu")
		(net "M_L_DQS_DN<16>")
	)
	(segment
		(start 146.999706 -142.476728)
		(end 146.999706 -141.820392)
		(width 0.1651)
		(layer "B.Cu")
		(net "M_L_DQS_DN<16>")
	)
	(segment
		(start 146.999706 -141.820392)
		(end 146.555968 -141.376654)
		(width 0.1651)
		(layer "B.Cu")
		(net "M_L_DQS_DN<16>")
	)
	(segment
		(start 146.733768 -140.5128)
		(end 146.513804 -140.292836)
		(width 0.1651)
		(layer "B.Cu")
		(net "M_L_DQS_DN<16>")
	)
	(segment
		(start 146.555968 -141.376654)
		(end 146.555968 -141.0208)
		(width 0.1651)
		(layer "B.Cu")
		(net "M_L_DQS_DN<16>")
	)
	(segment
		(start 146.513804 -140.292836)
		(end 146.286728 -140.292836)
		(width 0.1651)
		(layer "B.Cu")
		(net "M_L_DQS_DN<16>")
	)
	(segment
		(start 146.555968 -141.0208)
		(end 146.733768 -140.843)
		(width 0.1651)
		(layer "B.Cu")
		(net "M_L_DQS_DN<16>")
	)
	(segment
		(start 146.733768 -140.843)
		(end 146.733768 -140.5128)
		(width 0.1651)
		(layer "B.Cu")
		(net "M_L_DQS_DN<16>")
	)
	(segment
		(start 146.286728 -140.292836)
		(end 146.092164 -140.4874)
		(width 0.1651)
		(layer "B.Cu")
		(net "M_L_DQS_DN<16>")
	)
	(segment
		(start 146.999452 -142.477236)
		(end 146.999706 -142.476728)
		(width 0.1651)
		(layer "B.Cu")
		(net "M_L_DQS_DN<16>")
	)
	(segment
		(start 121.359168 -94.042738)
		(end 121.359168 -93.704664)
		(width 0.0889)
		(layer "In4.Cu")
		(net "M_L_DQS_DN<16>")
	)
	(segment
		(start 123.929902 -105.834688)
		(end 123.947682 -105.834688)
		(width 0.0889)
		(layer "In4.Cu")
		(net "M_L_DQS_DN<16>")
	)
	(segment
		(start 121.012712 -99.195636)
		(end 121.021602 -99.210876)
		(width 0.0889)
		(layer "In4.Cu")
		(net "M_L_DQS_DN<16>")
	)
	(segment
		(start 146.019012 -143.5608)
		(end 146.344132 -143.5608)
		(width 0.14224)
		(layer "In4.Cu")
		(net "M_L_DQS_DN<16>")
	)
	(segment
		(start 123.065032 -105.339388)
		(end 123.097798 -105.339388)
		(width 0.0889)
		(layer "In4.Cu")
		(net "M_L_DQS_DN<16>")
	)
	(segment
		(start 146.531838 -144.23263)
		(end 146.098768 -144.6657)
		(width 0.14224)
		(layer "In4.Cu")
		(net "M_L_DQS_DN<16>")
	)
	(segment
		(start 146.527012 -141.3256)
		(end 146.247612 -141.605)
		(width 0.14224)
		(layer "In4.Cu")
		(net "M_L_DQS_DN<16>")
	)
	(segment
		(start 129.200148 -107.88396)
		(end 146.874484 -125.558296)
		(width 0.14224)
		(layer "In4.Cu")
		(net "M_L_DQS_DN<16>")
	)
	(segment
		(start 145.856452 -143.39824)
		(end 146.019012 -143.5608)
		(width 0.14224)
		(layer "In4.Cu")
		(net "M_L_DQS_DN<16>")
	)
	(segment
		(start 146.247612 -141.605)
		(end 146.006312 -141.605)
		(width 0.14224)
		(layer "In4.Cu")
		(net "M_L_DQS_DN<16>")
	)
	(segment
		(start 124.885704 -107.095036)
		(end 124.941584 -107.095036)
		(width 0.0889)
		(layer "In4.Cu")
		(net "M_L_DQS_DN<16>")
	)
	(segment
		(start 121.877328 -104.233218)
		(end 121.870978 -104.243886)
		(width 0.0889)
		(layer "In4.Cu")
		(net "M_L_DQS_DN<16>")
	)
	(segment
		(start 146.006312 -141.605)
		(end 145.856452 -141.75486)
		(width 0.14224)
		(layer "In4.Cu")
		(net "M_L_DQS_DN<16>")
	)
	(segment
		(start 121.012712 -100.186236)
		(end 121.021602 -100.201476)
		(width 0.0889)
		(layer "In4.Cu")
		(net "M_L_DQS_DN<16>")
	)
	(segment
		(start 145.856452 -141.75486)
		(end 145.856452 -142.10284)
		(width 0.14224)
		(layer "In4.Cu")
		(net "M_L_DQS_DN<16>")
	)
	(segment
		(start 145.856452 -143.03756)
		(end 145.856452 -143.39824)
		(width 0.14224)
		(layer "In4.Cu")
		(net "M_L_DQS_DN<16>")
	)
	(segment
		(start 146.874484 -139.70508)
		(end 146.092164 -140.4874)
		(width 0.14224)
		(layer "In4.Cu")
		(net "M_L_DQS_DN<16>")
	)
	(segment
		(start 145.988532 -142.23492)
		(end 146.143472 -142.23492)
		(width 0.14224)
		(layer "In4.Cu")
		(net "M_L_DQS_DN<16>")
	)
	(segment
		(start 121.012712 -94.242636)
		(end 121.012458 -94.242382)
		(width 0.0889)
		(layer "In4.Cu")
		(net "M_L_DQS_DN<16>")
	)
	(segment
		(start 145.856452 -142.10284)
		(end 145.988532 -142.23492)
		(width 0.14224)
		(layer "In4.Cu")
		(net "M_L_DQS_DN<16>")
	)
	(segment
		(start 146.298412 -142.74292)
		(end 146.143472 -142.89786)
		(width 0.14224)
		(layer "In4.Cu")
		(net "M_L_DQS_DN<16>")
	)
	(segment
		(start 121.877328 -103.242618)
		(end 121.870978 -103.253286)
		(width 0.0889)
		(layer "In4.Cu")
		(net "M_L_DQS_DN<16>")
	)
	(segment
		(start 146.531838 -143.748506)
		(end 146.531838 -144.23263)
		(width 0.14224)
		(layer "In4.Cu")
		(net "M_L_DQS_DN<16>")
	)
	(segment
		(start 124.446538 -106.13009)
		(end 124.591572 -106.38155)
		(width 0.0889)
		(layer "In4.Cu")
		(net "M_L_DQS_DN<16>")
	)
	(segment
		(start 122.202702 -104.843834)
		(end 122.235468 -104.843834)
		(width 0.0889)
		(layer "In4.Cu")
		(net "M_L_DQS_DN<16>")
	)
	(segment
		(start 124.957332 -107.110784)
		(end 125.730508 -107.88396)
		(width 0.14224)
		(layer "In4.Cu")
		(net "M_L_DQS_DN<16>")
	)
	(segment
		(start 121.359168 -102.367588)
		(end 121.380758 -102.367588)
		(width 0.0889)
		(layer "In4.Cu")
		(net "M_L_DQS_DN<16>")
	)
	(segment
		(start 121.359168 -93.704664)
		(end 121.30151 -93.647006)
		(width 0.0889)
		(layer "In4.Cu")
		(net "M_L_DQS_DN<16>")
	)
	(segment
		(start 145.996152 -142.89786)
		(end 145.856452 -143.03756)
		(width 0.14224)
		(layer "In4.Cu")
		(net "M_L_DQS_DN<16>")
	)
	(segment
		(start 121.012712 -101.176836)
		(end 121.021602 -101.192076)
		(width 0.0889)
		(layer "In4.Cu")
		(net "M_L_DQS_DN<16>")
	)
	(segment
		(start 124.591572 -106.800904)
		(end 124.885704 -107.095036)
		(width 0.0889)
		(layer "In4.Cu")
		(net "M_L_DQS_DN<16>")
	)
	(segment
		(start 146.143472 -142.89786)
		(end 145.996152 -142.89786)
		(width 0.14224)
		(layer "In4.Cu")
		(net "M_L_DQS_DN<16>")
	)
	(segment
		(start 121.870978 -103.253286)
		(end 121.866152 -103.261922)
		(width 0.0889)
		(layer "In4.Cu")
		(net "M_L_DQS_DN<16>")
	)
	(segment
		(start 146.344132 -143.5608)
		(end 146.531838 -143.748506)
		(width 0.14224)
		(layer "In4.Cu")
		(net "M_L_DQS_DN<16>")
	)
	(segment
		(start 121.870978 -104.243886)
		(end 121.866152 -104.252522)
		(width 0.0889)
		(layer "In4.Cu")
		(net "M_L_DQS_DN<16>")
	)
	(segment
		(start 146.092164 -140.4874)
		(end 146.527012 -140.922248)
		(width 0.14224)
		(layer "In4.Cu")
		(net "M_L_DQS_DN<16>")
	)
	(segment
		(start 146.143472 -142.23492)
		(end 146.298412 -142.38986)
		(width 0.14224)
		(layer "In4.Cu")
		(net "M_L_DQS_DN<16>")
	)
	(segment
		(start 125.730508 -107.88396)
		(end 129.200148 -107.88396)
		(width 0.14224)
		(layer "In4.Cu")
		(net "M_L_DQS_DN<16>")
	)
	(segment
		(start 124.591572 -106.38155)
		(end 124.591572 -106.800904)
		(width 0.0889)
		(layer "In4.Cu")
		(net "M_L_DQS_DN<16>")
	)
	(segment
		(start 146.527012 -140.922248)
		(end 146.527012 -141.3256)
		(width 0.14224)
		(layer "In4.Cu")
		(net "M_L_DQS_DN<16>")
	)
	(segment
		(start 124.941584 -107.095036)
		(end 124.957332 -107.110784)
		(width 0.0889)
		(layer "In4.Cu")
		(net "M_L_DQS_DN<16>")
	)
	(segment
		(start 146.874484 -125.558296)
		(end 146.874484 -139.70508)
		(width 0.14224)
		(layer "In4.Cu")
		(net "M_L_DQS_DN<16>")
	)
	(segment
		(start 146.298412 -142.38986)
		(end 146.298412 -142.74292)
		(width 0.14224)
		(layer "In4.Cu")
		(net "M_L_DQS_DN<16>")
	)
	(arc
		(start 121.021602 -99.210876)
		(mid 121.091999 -99.499827)
		(end 121.012712 -99.78644)
		(width 0.0889)
		(layer "In4.Cu")
		(net "M_L_DQS_DN<16>")
	)
	(arc
		(start 121.012458 -94.242382)
		(mid 121.091589 -94.537784)
		(end 121.012458 -94.833186)
		(width 0.0889)
		(layer "In4.Cu")
		(net "M_L_DQS_DN<16>")
	)
	(arc
		(start 121.012458 -95.232982)
		(mid 121.091589 -95.528384)
		(end 121.012458 -95.823786)
		(width 0.0889)
		(layer "In4.Cu")
		(net "M_L_DQS_DN<16>")
	)
	(arc
		(start 121.30151 -93.647006)
		(mid 121.001195 -93.864458)
		(end 121.008394 -94.23527)
		(width 0.0889)
		(layer "In4.Cu")
		(net "M_L_DQS_DN<16>")
	)
	(arc
		(start 123.097798 -105.339388)
		(mid 123.381015 -105.423669)
		(end 123.588018 -105.634536)
		(width 0.0889)
		(layer "In4.Cu")
		(net "M_L_DQS_DN<16>")
	)
	(arc
		(start 121.866152 -103.261922)
		(mid 121.817397 -103.458274)
		(end 121.870978 -103.653336)
		(width 0.0889)
		(layer "In4.Cu")
		(net "M_L_DQS_DN<16>")
	)
	(arc
		(start 121.021602 -100.201476)
		(mid 121.091999 -100.490427)
		(end 121.012712 -100.77704)
		(width 0.0889)
		(layer "In4.Cu")
		(net "M_L_DQS_DN<16>")
	)
	(arc
		(start 121.008394 -94.23527)
		(mid 121.010534 -94.238964)
		(end 121.012712 -94.242636)
		(width 0.0889)
		(layer "In4.Cu")
		(net "M_L_DQS_DN<16>")
	)
	(arc
		(start 121.012712 -100.77704)
		(mid 120.959179 -100.976938)
		(end 121.012712 -101.176836)
		(width 0.0889)
		(layer "In4.Cu")
		(net "M_L_DQS_DN<16>")
	)
	(arc
		(start 121.866152 -104.252522)
		(mid 121.869899 -104.641778)
		(end 122.202702 -104.843834)
		(width 0.0889)
		(layer "In4.Cu")
		(net "M_L_DQS_DN<16>")
	)
	(arc
		(start 121.012458 -98.204782)
		(mid 121.091589 -98.500184)
		(end 121.012458 -98.795586)
		(width 0.0889)
		(layer "In4.Cu")
		(net "M_L_DQS_DN<16>")
	)
	(arc
		(start 121.870978 -103.653336)
		(mid 121.9502 -103.942454)
		(end 121.877328 -104.233218)
		(width 0.0889)
		(layer "In4.Cu")
		(net "M_L_DQS_DN<16>")
	)
	(arc
		(start 121.021602 -101.192076)
		(mid 121.091999 -101.481027)
		(end 121.012712 -101.76764)
		(width 0.0889)
		(layer "In4.Cu")
		(net "M_L_DQS_DN<16>")
	)
	(arc
		(start 121.012458 -96.814386)
		(mid 120.958959 -97.014284)
		(end 121.012458 -97.214182)
		(width 0.0889)
		(layer "In4.Cu")
		(net "M_L_DQS_DN<16>")
	)
	(arc
		(start 120.981724 -98.863404)
		(mid 120.960928 -99.032903)
		(end 121.012712 -99.195636)
		(width 0.0889)
		(layer "In4.Cu")
		(net "M_L_DQS_DN<16>")
	)
	(arc
		(start 123.947682 -105.834688)
		(mid 124.235827 -105.917007)
		(end 124.446538 -106.13009)
		(width 0.0889)
		(layer "In4.Cu")
		(net "M_L_DQS_DN<16>")
	)
	(arc
		(start 121.012458 -96.223582)
		(mid 121.091589 -96.518984)
		(end 121.012458 -96.814386)
		(width 0.0889)
		(layer "In4.Cu")
		(net "M_L_DQS_DN<16>")
	)
	(arc
		(start 123.588018 -105.634536)
		(mid 123.732466 -105.779867)
		(end 123.929902 -105.834688)
		(width 0.0889)
		(layer "In4.Cu")
		(net "M_L_DQS_DN<16>")
	)
	(arc
		(start 121.380758 -102.367588)
		(mid 121.873148 -102.666521)
		(end 121.877328 -103.242618)
		(width 0.0889)
		(layer "In4.Cu")
		(net "M_L_DQS_DN<16>")
	)
	(arc
		(start 121.012712 -99.78644)
		(mid 120.959179 -99.986338)
		(end 121.012712 -100.186236)
		(width 0.0889)
		(layer "In4.Cu")
		(net "M_L_DQS_DN<16>")
	)
	(arc
		(start 122.729498 -105.139236)
		(mid 122.871181 -105.28304)
		(end 123.065032 -105.339388)
		(width 0.0889)
		(layer "In4.Cu")
		(net "M_L_DQS_DN<16>")
	)
	(arc
		(start 121.012458 -97.804986)
		(mid 120.958959 -98.004884)
		(end 121.012458 -98.204782)
		(width 0.0889)
		(layer "In4.Cu")
		(net "M_L_DQS_DN<16>")
	)
	(arc
		(start 121.012458 -97.214182)
		(mid 121.091589 -97.509584)
		(end 121.012458 -97.804986)
		(width 0.0889)
		(layer "In4.Cu")
		(net "M_L_DQS_DN<16>")
	)
	(arc
		(start 121.012712 -101.76764)
		(mid 121.012795 -102.167581)
		(end 121.359168 -102.367588)
		(width 0.0889)
		(layer "In4.Cu")
		(net "M_L_DQS_DN<16>")
	)
	(arc
		(start 121.012458 -98.795586)
		(mid 120.995596 -98.828817)
		(end 120.981724 -98.863404)
		(width 0.0889)
		(layer "In4.Cu")
		(net "M_L_DQS_DN<16>")
	)
	(arc
		(start 121.012458 -95.823786)
		(mid 120.958959 -96.023684)
		(end 121.012458 -96.223582)
		(width 0.0889)
		(layer "In4.Cu")
		(net "M_L_DQS_DN<16>")
	)
	(arc
		(start 121.012458 -94.833186)
		(mid 120.958959 -95.033084)
		(end 121.012458 -95.232982)
		(width 0.0889)
		(layer "In4.Cu")
		(net "M_L_DQS_DN<16>")
	)
	(arc
		(start 122.235468 -104.843834)
		(mid 122.520892 -104.927301)
		(end 122.729498 -105.139236)
		(width 0.0889)
		(layer "In4.Cu")
		(net "M_L_DQS_DN<16>")
	)
	(segment
		(start 120.441212 -102.167436)
		(end 120.440958 -102.167944)
		(width 0.0889)
		(layer "F.Cu")
		(net "M_L_DQS_DN<15>")
	)
	(segment
		(start 137.227564 -125.20676)
		(end 137.227564 -125.479302)
		(width 0.1651)
		(layer "F.Cu")
		(net "M_L_DQS_DN<15>")
	)
	(segment
		(start 120.787668 -100.976684)
		(end 120.787668 -100.645214)
		(width 0.0889)
		(layer "F.Cu")
		(net "M_L_DQS_DN<15>")
	)
	(segment
		(start 136.957054 -144.85493)
		(end 136.767824 -144.6657)
		(width 0.1651)
		(layer "F.Cu")
		(net "M_L_DQS_DN<15>")
	)
	(segment
		(start 136.767824 -144.6657)
		(end 136.748774 -144.6657)
		(width 0.1651)
		(layer "F.Cu")
		(net "M_L_DQS_DN<15>")
	)
	(segment
		(start 120.279668 -104.9909)
		(end 120.571768 -105.283)
		(width 0.0889)
		(layer "F.Cu")
		(net "M_L_DQS_DN<15>")
	)
	(segment
		(start 120.571768 -105.283)
		(end 120.695974 -105.283)
		(width 0.1016)
		(layer "F.Cu")
		(net "M_L_DQS_DN<15>")
	)
	(segment
		(start 137.649458 -143.331184)
		(end 137.231374 -143.749268)
		(width 0.1651)
		(layer "F.Cu")
		(net "M_L_DQS_DN<15>")
	)
	(segment
		(start 133.957568 -110.49)
		(end 137.424668 -113.9571)
		(width 0.1651)
		(layer "F.Cu")
		(net "M_L_DQS_DN<15>")
	)
	(segment
		(start 120.279668 -104.013254)
		(end 120.279668 -104.9909)
		(width 0.0889)
		(layer "F.Cu")
		(net "M_L_DQS_DN<15>")
	)
	(segment
		(start 133.614668 -110.07598)
		(end 133.957568 -110.41888)
		(width 0.1016)
		(layer "F.Cu")
		(net "M_L_DQS_DN<15>")
	)
	(segment
		(start 120.695974 -105.283)
		(end 122.067828 -106.654854)
		(width 0.1016)
		(layer "F.Cu")
		(net "M_L_DQS_DN<15>")
	)
	(segment
		(start 137.519664 -124.91466)
		(end 137.227564 -125.20676)
		(width 0.1651)
		(layer "F.Cu")
		(net "M_L_DQS_DN<15>")
	)
	(segment
		(start 130.382264 -106.654854)
		(end 133.614668 -109.887258)
		(width 0.1016)
		(layer "F.Cu")
		(net "M_L_DQS_DN<15>")
	)
	(segment
		(start 137.519664 -122.10415)
		(end 137.519664 -124.91466)
		(width 0.1651)
		(layer "F.Cu")
		(net "M_L_DQS_DN<15>")
	)
	(segment
		(start 122.067828 -106.654854)
		(end 130.382264 -106.654854)
		(width 0.1016)
		(layer "F.Cu")
		(net "M_L_DQS_DN<15>")
	)
	(segment
		(start 137.424668 -122.009154)
		(end 137.519664 -122.10415)
		(width 0.1651)
		(layer "F.Cu")
		(net "M_L_DQS_DN<15>")
	)
	(segment
		(start 133.614668 -109.887258)
		(end 133.614668 -110.07598)
		(width 0.1016)
		(layer "F.Cu")
		(net "M_L_DQS_DN<15>")
	)
	(segment
		(start 137.231374 -144.1704)
		(end 137.417302 -144.356328)
		(width 0.1651)
		(layer "F.Cu")
		(net "M_L_DQS_DN<15>")
	)
	(segment
		(start 120.392952 -102.857046)
		(end 120.392952 -103.89997)
		(width 0.0889)
		(layer "F.Cu")
		(net "M_L_DQS_DN<15>")
	)
	(segment
		(start 137.227564 -125.479302)
		(end 136.74598 -125.960886)
		(width 0.1651)
		(layer "F.Cu")
		(net "M_L_DQS_DN<15>")
	)
	(segment
		(start 133.957568 -110.41888)
		(end 133.957568 -110.49)
		(width 0.1016)
		(layer "F.Cu")
		(net "M_L_DQS_DN<15>")
	)
	(segment
		(start 137.417302 -144.602962)
		(end 137.165334 -144.85493)
		(width 0.1651)
		(layer "F.Cu")
		(net "M_L_DQS_DN<15>")
	)
	(segment
		(start 137.424668 -113.9571)
		(end 137.424668 -122.009154)
		(width 0.1651)
		(layer "F.Cu")
		(net "M_L_DQS_DN<15>")
	)
	(segment
		(start 137.649458 -142.6718)
		(end 137.649458 -143.331184)
		(width 0.1651)
		(layer "F.Cu")
		(net "M_L_DQS_DN<15>")
	)
	(segment
		(start 120.787668 -100.645214)
		(end 120.724422 -100.581968)
		(width 0.0889)
		(layer "F.Cu")
		(net "M_L_DQS_DN<15>")
	)
	(segment
		(start 120.392952 -103.89997)
		(end 120.279668 -104.013254)
		(width 0.0889)
		(layer "F.Cu")
		(net "M_L_DQS_DN<15>")
	)
	(segment
		(start 137.165334 -144.85493)
		(end 136.957054 -144.85493)
		(width 0.1651)
		(layer "F.Cu")
		(net "M_L_DQS_DN<15>")
	)
	(segment
		(start 137.231374 -143.749268)
		(end 137.231374 -144.1704)
		(width 0.1651)
		(layer "F.Cu")
		(net "M_L_DQS_DN<15>")
	)
	(segment
		(start 137.417302 -144.356328)
		(end 137.417302 -144.602962)
		(width 0.1651)
		(layer "F.Cu")
		(net "M_L_DQS_DN<15>")
	)
	(segment
		(start 120.432322 -102.772972)
		(end 120.392952 -102.857046)
		(width 0.0889)
		(layer "F.Cu")
		(net "M_L_DQS_DN<15>")
	)
	(via
		(at 136.74217 -140.4874)
		(size 0.508)
		(drill 0.254)
		(layers "F.Cu" "B.Cu")
		(net "M_L_DQS_DN<15>")
	)
	(via
		(at 136.74598 -125.960886)
		(size 0.508)
		(drill 0.254)
		(layers "F.Cu" "B.Cu")
		(net "M_L_DQS_DN<15>")
	)
	(via
		(at 136.748774 -144.6657)
		(size 0.508)
		(drill 0.254)
		(layers "F.Cu" "B.Cu")
		(net "M_L_DQS_DN<15>")
	)
	(arc
		(start 120.441212 -101.76764)
		(mid 120.387679 -101.967538)
		(end 120.441212 -102.167436)
		(width 0.0889)
		(layer "F.Cu")
		(net "M_L_DQS_DN<15>")
	)
	(arc
		(start 120.441212 -101.176582)
		(mid 120.520402 -101.472128)
		(end 120.441212 -101.76764)
		(width 0.0889)
		(layer "F.Cu")
		(net "M_L_DQS_DN<15>")
	)
	(arc
		(start 120.724422 -100.581968)
		(mid 120.426557 -100.80489)
		(end 120.441212 -101.176582)
		(width 0.0889)
		(layer "F.Cu")
		(net "M_L_DQS_DN<15>")
	)
	(arc
		(start 120.440958 -102.167944)
		(mid 120.519935 -102.471629)
		(end 120.432322 -102.772972)
		(width 0.0889)
		(layer "F.Cu")
		(net "M_L_DQS_DN<15>")
	)
	(segment
		(start 137.205974 -141.0208)
		(end 137.383774 -140.843)
		(width 0.1651)
		(layer "B.Cu")
		(net "M_L_DQS_DN<15>")
	)
	(segment
		(start 137.205974 -141.376654)
		(end 137.205974 -141.0208)
		(width 0.1651)
		(layer "B.Cu")
		(net "M_L_DQS_DN<15>")
	)
	(segment
		(start 137.383774 -140.843)
		(end 137.383774 -140.5128)
		(width 0.1651)
		(layer "B.Cu")
		(net "M_L_DQS_DN<15>")
	)
	(segment
		(start 137.383774 -140.5128)
		(end 137.16381 -140.292836)
		(width 0.1651)
		(layer "B.Cu")
		(net "M_L_DQS_DN<15>")
	)
	(segment
		(start 137.649458 -142.477236)
		(end 137.649458 -141.820138)
		(width 0.1651)
		(layer "B.Cu")
		(net "M_L_DQS_DN<15>")
	)
	(segment
		(start 137.16381 -140.292836)
		(end 136.936734 -140.292836)
		(width 0.1651)
		(layer "B.Cu")
		(net "M_L_DQS_DN<15>")
	)
	(segment
		(start 136.936734 -140.292836)
		(end 136.74217 -140.4874)
		(width 0.1651)
		(layer "B.Cu")
		(net "M_L_DQS_DN<15>")
	)
	(segment
		(start 137.649458 -141.820138)
		(end 137.205974 -141.376654)
		(width 0.1651)
		(layer "B.Cu")
		(net "M_L_DQS_DN<15>")
	)
	(segment
		(start 137.52449 -139.581128)
		(end 137.25017 -139.855448)
		(width 0.14224)
		(layer "In4.Cu")
		(net "M_L_DQS_DN<15>")
	)
	(segment
		(start 137.25017 -140.015976)
		(end 136.778746 -140.4874)
		(width 0.14224)
		(layer "In4.Cu")
		(net "M_L_DQS_DN<15>")
	)
	(segment
		(start 136.74598 -125.960886)
		(end 137.183368 -126.398274)
		(width 0.14224)
		(layer "In4.Cu")
		(net "M_L_DQS_DN<15>")
	)
	(segment
		(start 136.954768 -127.1524)
		(end 136.954768 -127.976884)
		(width 0.14224)
		(layer "In4.Cu")
		(net "M_L_DQS_DN<15>")
	)
	(segment
		(start 137.183368 -126.398274)
		(end 137.183368 -126.9238)
		(width 0.14224)
		(layer "In4.Cu")
		(net "M_L_DQS_DN<15>")
	)
	(segment
		(start 137.52449 -128.546606)
		(end 137.52449 -139.581128)
		(width 0.14224)
		(layer "In4.Cu")
		(net "M_L_DQS_DN<15>")
	)
	(segment
		(start 137.25017 -139.855448)
		(end 137.25017 -140.015976)
		(width 0.14224)
		(layer "In4.Cu")
		(net "M_L_DQS_DN<15>")
	)
	(segment
		(start 136.778746 -140.4874)
		(end 136.74217 -140.4874)
		(width 0.14224)
		(layer "In4.Cu")
		(net "M_L_DQS_DN<15>")
	)
	(segment
		(start 136.954768 -127.976884)
		(end 137.52449 -128.546606)
		(width 0.14224)
		(layer "In4.Cu")
		(net "M_L_DQS_DN<15>")
	)
	(segment
		(start 137.183368 -126.9238)
		(end 136.954768 -127.1524)
		(width 0.14224)
		(layer "In4.Cu")
		(net "M_L_DQS_DN<15>")
	)
	(segment
		(start 136.897618 -141.605)
		(end 137.177018 -141.3256)
		(width 0.14224)
		(layer "In9.Cu")
		(net "M_L_DQS_DN<15>")
	)
	(segment
		(start 136.646158 -142.89786)
		(end 136.793478 -142.89786)
		(width 0.14224)
		(layer "In9.Cu")
		(net "M_L_DQS_DN<15>")
	)
	(segment
		(start 136.506458 -141.75486)
		(end 136.656318 -141.605)
		(width 0.14224)
		(layer "In9.Cu")
		(net "M_L_DQS_DN<15>")
	)
	(segment
		(start 137.181844 -144.23263)
		(end 137.181844 -143.748506)
		(width 0.14224)
		(layer "In9.Cu")
		(net "M_L_DQS_DN<15>")
	)
	(segment
		(start 136.994138 -143.5608)
		(end 136.669018 -143.5608)
		(width 0.14224)
		(layer "In9.Cu")
		(net "M_L_DQS_DN<15>")
	)
	(segment
		(start 136.506458 -142.10284)
		(end 136.506458 -141.75486)
		(width 0.14224)
		(layer "In9.Cu")
		(net "M_L_DQS_DN<15>")
	)
	(segment
		(start 136.948418 -142.74292)
		(end 136.948418 -142.38986)
		(width 0.14224)
		(layer "In9.Cu")
		(net "M_L_DQS_DN<15>")
	)
	(segment
		(start 136.506458 -143.03756)
		(end 136.646158 -142.89786)
		(width 0.14224)
		(layer "In9.Cu")
		(net "M_L_DQS_DN<15>")
	)
	(segment
		(start 136.793478 -142.23492)
		(end 136.638538 -142.23492)
		(width 0.14224)
		(layer "In9.Cu")
		(net "M_L_DQS_DN<15>")
	)
	(segment
		(start 136.638538 -142.23492)
		(end 136.506458 -142.10284)
		(width 0.14224)
		(layer "In9.Cu")
		(net "M_L_DQS_DN<15>")
	)
	(segment
		(start 136.656318 -141.605)
		(end 136.897618 -141.605)
		(width 0.14224)
		(layer "In9.Cu")
		(net "M_L_DQS_DN<15>")
	)
	(segment
		(start 137.177018 -141.3256)
		(end 137.177018 -140.922248)
		(width 0.14224)
		(layer "In9.Cu")
		(net "M_L_DQS_DN<15>")
	)
	(segment
		(start 136.506458 -143.39824)
		(end 136.506458 -143.03756)
		(width 0.14224)
		(layer "In9.Cu")
		(net "M_L_DQS_DN<15>")
	)
	(segment
		(start 136.748774 -144.6657)
		(end 137.181844 -144.23263)
		(width 0.14224)
		(layer "In9.Cu")
		(net "M_L_DQS_DN<15>")
	)
	(segment
		(start 136.948418 -142.38986)
		(end 136.793478 -142.23492)
		(width 0.14224)
		(layer "In9.Cu")
		(net "M_L_DQS_DN<15>")
	)
	(segment
		(start 137.181844 -143.748506)
		(end 136.994138 -143.5608)
		(width 0.14224)
		(layer "In9.Cu")
		(net "M_L_DQS_DN<15>")
	)
	(segment
		(start 136.793478 -142.89786)
		(end 136.948418 -142.74292)
		(width 0.14224)
		(layer "In9.Cu")
		(net "M_L_DQS_DN<15>")
	)
	(segment
		(start 136.669018 -143.5608)
		(end 136.506458 -143.39824)
		(width 0.14224)
		(layer "In9.Cu")
		(net "M_L_DQS_DN<15>")
	)
	(segment
		(start 137.177018 -140.922248)
		(end 136.74217 -140.4874)
		(width 0.14224)
		(layer "In9.Cu")
		(net "M_L_DQS_DN<15>")
	)
	(segment
		(start 115.636802 -100.976684)
		(end 115.82908 -100.784406)
		(width 0.0889)
		(layer "F.Cu")
		(net "M_L_DQS_DN<14>")
	)
	(segment
		(start 128.299464 -143.331184)
		(end 127.88138 -143.749268)
		(width 0.1651)
		(layer "F.Cu")
		(net "M_L_DQS_DN<14>")
	)
	(segment
		(start 115.270788 -105.904538)
		(end 115.270788 -108.970572)
		(width 0.1016)
		(layer "F.Cu")
		(net "M_L_DQS_DN<14>")
	)
	(segment
		(start 115.244372 -103.857044)
		(end 115.169188 -103.932228)
		(width 0.0889)
		(layer "F.Cu")
		(net "M_L_DQS_DN<14>")
	)
	(segment
		(start 128.161288 -125.2982)
		(end 127.82677 -125.632718)
		(width 0.1651)
		(layer "F.Cu")
		(net "M_L_DQS_DN<14>")
	)
	(segment
		(start 127.80137 -125.632718)
		(end 127.40767 -126.026418)
		(width 0.1651)
		(layer "F.Cu")
		(net "M_L_DQS_DN<14>")
	)
	(segment
		(start 115.82908 -100.658422)
		(end 115.752372 -100.581714)
		(width 0.0889)
		(layer "F.Cu")
		(net "M_L_DQS_DN<14>")
	)
	(segment
		(start 120.638062 -114.467894)
		(end 120.638062 -114.537236)
		(width 0.1016)
		(layer "F.Cu")
		(net "M_L_DQS_DN<14>")
	)
	(segment
		(start 127.88138 -144.1704)
		(end 128.067308 -144.356328)
		(width 0.1651)
		(layer "F.Cu")
		(net "M_L_DQS_DN<14>")
	)
	(segment
		(start 128.299464 -142.6718)
		(end 128.299464 -143.331184)
		(width 0.1651)
		(layer "F.Cu")
		(net "M_L_DQS_DN<14>")
	)
	(segment
		(start 115.290092 -102.167436)
		(end 115.296442 -102.178104)
		(width 0.0889)
		(layer "F.Cu")
		(net "M_L_DQS_DN<14>")
	)
	(segment
		(start 115.233704 -103.034846)
		(end 115.244372 -103.073454)
		(width 0.0889)
		(layer "F.Cu")
		(net "M_L_DQS_DN<14>")
	)
	(segment
		(start 127.82677 -125.632718)
		(end 127.80137 -125.632718)
		(width 0.1651)
		(layer "F.Cu")
		(net "M_L_DQS_DN<14>")
	)
	(segment
		(start 125.181106 -119.08028)
		(end 125.656848 -119.08028)
		(width 0.1651)
		(layer "F.Cu")
		(net "M_L_DQS_DN<14>")
	)
	(segment
		(start 119.504968 -113.3348)
		(end 120.638062 -114.467894)
		(width 0.1016)
		(layer "F.Cu")
		(net "M_L_DQS_DN<14>")
	)
	(segment
		(start 115.270788 -108.970572)
		(end 119.504968 -113.204752)
		(width 0.1016)
		(layer "F.Cu")
		(net "M_L_DQS_DN<14>")
	)
	(segment
		(start 128.161288 -121.58472)
		(end 128.161288 -125.2982)
		(width 0.1651)
		(layer "F.Cu")
		(net "M_L_DQS_DN<14>")
	)
	(segment
		(start 115.290092 -102.757986)
		(end 115.257834 -102.813866)
		(width 0.0889)
		(layer "F.Cu")
		(net "M_L_DQS_DN<14>")
	)
	(segment
		(start 119.504968 -113.204752)
		(end 119.504968 -113.3348)
		(width 0.1016)
		(layer "F.Cu")
		(net "M_L_DQS_DN<14>")
	)
	(segment
		(start 128.067308 -144.356328)
		(end 128.067308 -144.602962)
		(width 0.1651)
		(layer "F.Cu")
		(net "M_L_DQS_DN<14>")
	)
	(segment
		(start 127.60706 -144.85493)
		(end 127.41783 -144.6657)
		(width 0.1651)
		(layer "F.Cu")
		(net "M_L_DQS_DN<14>")
	)
	(segment
		(start 127.81534 -144.85493)
		(end 127.60706 -144.85493)
		(width 0.1651)
		(layer "F.Cu")
		(net "M_L_DQS_DN<14>")
	)
	(segment
		(start 127.88138 -143.749268)
		(end 127.88138 -144.1704)
		(width 0.1651)
		(layer "F.Cu")
		(net "M_L_DQS_DN<14>")
	)
	(segment
		(start 115.752372 -100.581714)
		(end 115.573302 -100.581714)
		(width 0.0889)
		(layer "F.Cu")
		(net "M_L_DQS_DN<14>")
	)
	(segment
		(start 115.257834 -102.813866)
		(end 115.25758 -102.81412)
		(width 0.0889)
		(layer "F.Cu")
		(net "M_L_DQS_DN<14>")
	)
	(segment
		(start 115.244372 -103.073454)
		(end 115.244372 -103.857044)
		(width 0.0889)
		(layer "F.Cu")
		(net "M_L_DQS_DN<14>")
	)
	(segment
		(start 127.41783 -144.6657)
		(end 127.39878 -144.6657)
		(width 0.1651)
		(layer "F.Cu")
		(net "M_L_DQS_DN<14>")
	)
	(segment
		(start 120.638062 -114.537236)
		(end 125.181106 -119.08028)
		(width 0.1651)
		(layer "F.Cu")
		(net "M_L_DQS_DN<14>")
	)
	(segment
		(start 127.40767 -126.026418)
		(end 127.39624 -126.026418)
		(width 0.1651)
		(layer "F.Cu")
		(net "M_L_DQS_DN<14>")
	)
	(segment
		(start 115.285266 -102.1588)
		(end 115.290092 -102.167436)
		(width 0.0889)
		(layer "F.Cu")
		(net "M_L_DQS_DN<14>")
	)
	(segment
		(start 115.169188 -105.802938)
		(end 115.270788 -105.904538)
		(width 0.0889)
		(layer "F.Cu")
		(net "M_L_DQS_DN<14>")
	)
	(segment
		(start 115.82908 -100.784406)
		(end 115.82908 -100.658422)
		(width 0.0889)
		(layer "F.Cu")
		(net "M_L_DQS_DN<14>")
	)
	(segment
		(start 115.169188 -103.932228)
		(end 115.169188 -105.802938)
		(width 0.0889)
		(layer "F.Cu")
		(net "M_L_DQS_DN<14>")
	)
	(segment
		(start 128.067308 -144.602962)
		(end 127.81534 -144.85493)
		(width 0.1651)
		(layer "F.Cu")
		(net "M_L_DQS_DN<14>")
	)
	(segment
		(start 125.656848 -119.08028)
		(end 128.161288 -121.58472)
		(width 0.1651)
		(layer "F.Cu")
		(net "M_L_DQS_DN<14>")
	)
	(via
		(at 127.392176 -140.4874)
		(size 0.508)
		(drill 0.254)
		(layers "F.Cu" "B.Cu")
		(net "M_L_DQS_DN<14>")
	)
	(via
		(at 127.39878 -144.6657)
		(size 0.508)
		(drill 0.254)
		(layers "F.Cu" "B.Cu")
		(net "M_L_DQS_DN<14>")
	)
	(via
		(at 127.39624 -126.026418)
		(size 0.508)
		(drill 0.254)
		(layers "F.Cu" "B.Cu")
		(net "M_L_DQS_DN<14>")
	)
	(arc
		(start 115.25758 -102.81412)
		(mid 115.222452 -102.921969)
		(end 115.233704 -103.034846)
		(width 0.0889)
		(layer "F.Cu")
		(net "M_L_DQS_DN<14>")
	)
	(arc
		(start 115.296442 -102.178104)
		(mid 115.36924 -102.468867)
		(end 115.290092 -102.757986)
		(width 0.0889)
		(layer "F.Cu")
		(net "M_L_DQS_DN<14>")
	)
	(arc
		(start 115.290092 -101.176582)
		(mid 115.369223 -101.471984)
		(end 115.290092 -101.767386)
		(width 0.0889)
		(layer "F.Cu")
		(net "M_L_DQS_DN<14>")
	)
	(arc
		(start 115.573302 -100.581714)
		(mid 115.275581 -100.804774)
		(end 115.290092 -101.176582)
		(width 0.0889)
		(layer "F.Cu")
		(net "M_L_DQS_DN<14>")
	)
	(arc
		(start 115.290092 -101.767386)
		(mid 115.236622 -101.962449)
		(end 115.285266 -102.1588)
		(width 0.0889)
		(layer "F.Cu")
		(net "M_L_DQS_DN<14>")
	)
	(segment
		(start 127.813816 -140.292836)
		(end 127.58674 -140.292836)
		(width 0.1651)
		(layer "B.Cu")
		(net "M_L_DQS_DN<14>")
	)
	(segment
		(start 127.85598 -141.376654)
		(end 127.85598 -141.0208)
		(width 0.1651)
		(layer "B.Cu")
		(net "M_L_DQS_DN<14>")
	)
	(segment
		(start 128.03378 -140.843)
		(end 128.03378 -140.5128)
		(width 0.1651)
		(layer "B.Cu")
		(net "M_L_DQS_DN<14>")
	)
	(segment
		(start 128.299718 -142.476728)
		(end 128.299718 -141.820392)
		(width 0.1651)
		(layer "B.Cu")
		(net "M_L_DQS_DN<14>")
	)
	(segment
		(start 128.299718 -141.820392)
		(end 127.85598 -141.376654)
		(width 0.1651)
		(layer "B.Cu")
		(net "M_L_DQS_DN<14>")
	)
	(segment
		(start 128.03378 -140.5128)
		(end 127.813816 -140.292836)
		(width 0.1651)
		(layer "B.Cu")
		(net "M_L_DQS_DN<14>")
	)
	(segment
		(start 127.85598 -141.0208)
		(end 128.03378 -140.843)
		(width 0.1651)
		(layer "B.Cu")
		(net "M_L_DQS_DN<14>")
	)
	(segment
		(start 128.299464 -142.477236)
		(end 128.299718 -142.476728)
		(width 0.1651)
		(layer "B.Cu")
		(net "M_L_DQS_DN<14>")
	)
	(segment
		(start 127.58674 -140.292836)
		(end 127.392176 -140.4874)
		(width 0.1651)
		(layer "B.Cu")
		(net "M_L_DQS_DN<14>")
	)
	(segment
		(start 127.83185 -143.748506)
		(end 127.644144 -143.5608)
		(width 0.14224)
		(layer "In9.Cu")
		(net "M_L_DQS_DN<14>")
	)
	(segment
		(start 127.547624 -141.605)
		(end 127.827024 -141.3256)
		(width 0.14224)
		(layer "In9.Cu")
		(net "M_L_DQS_DN<14>")
	)
	(segment
		(start 127.827024 -141.3256)
		(end 127.827024 -140.922248)
		(width 0.14224)
		(layer "In9.Cu")
		(net "M_L_DQS_DN<14>")
	)
	(segment
		(start 127.156464 -142.10284)
		(end 127.156464 -141.75486)
		(width 0.14224)
		(layer "In9.Cu")
		(net "M_L_DQS_DN<14>")
	)
	(segment
		(start 127.296164 -142.89786)
		(end 127.443484 -142.89786)
		(width 0.14224)
		(layer "In9.Cu")
		(net "M_L_DQS_DN<14>")
	)
	(segment
		(start 127.319024 -143.5608)
		(end 127.156464 -143.39824)
		(width 0.14224)
		(layer "In9.Cu")
		(net "M_L_DQS_DN<14>")
	)
	(segment
		(start 127.83185 -144.232376)
		(end 127.83185 -143.748506)
		(width 0.14224)
		(layer "In9.Cu")
		(net "M_L_DQS_DN<14>")
	)
	(segment
		(start 127.827024 -140.922248)
		(end 127.392176 -140.4874)
		(width 0.14224)
		(layer "In9.Cu")
		(net "M_L_DQS_DN<14>")
	)
	(segment
		(start 127.156464 -141.75486)
		(end 127.306324 -141.605)
		(width 0.14224)
		(layer "In9.Cu")
		(net "M_L_DQS_DN<14>")
	)
	(segment
		(start 127.443484 -142.23492)
		(end 127.288544 -142.23492)
		(width 0.14224)
		(layer "In9.Cu")
		(net "M_L_DQS_DN<14>")
	)
	(segment
		(start 127.39878 -144.665446)
		(end 127.83185 -144.232376)
		(width 0.14224)
		(layer "In9.Cu")
		(net "M_L_DQS_DN<14>")
	)
	(segment
		(start 127.156464 -143.03756)
		(end 127.296164 -142.89786)
		(width 0.14224)
		(layer "In9.Cu")
		(net "M_L_DQS_DN<14>")
	)
	(segment
		(start 127.306324 -141.605)
		(end 127.547624 -141.605)
		(width 0.14224)
		(layer "In9.Cu")
		(net "M_L_DQS_DN<14>")
	)
	(segment
		(start 127.644144 -143.5608)
		(end 127.319024 -143.5608)
		(width 0.14224)
		(layer "In9.Cu")
		(net "M_L_DQS_DN<14>")
	)
	(segment
		(start 127.288544 -142.23492)
		(end 127.156464 -142.10284)
		(width 0.14224)
		(layer "In9.Cu")
		(net "M_L_DQS_DN<14>")
	)
	(segment
		(start 127.156464 -143.39824)
		(end 127.156464 -143.03756)
		(width 0.14224)
		(layer "In9.Cu")
		(net "M_L_DQS_DN<14>")
	)
	(segment
		(start 127.598424 -142.38986)
		(end 127.443484 -142.23492)
		(width 0.14224)
		(layer "In9.Cu")
		(net "M_L_DQS_DN<14>")
	)
	(segment
		(start 127.39878 -144.6657)
		(end 127.39878 -144.665446)
		(width 0.14224)
		(layer "In9.Cu")
		(net "M_L_DQS_DN<14>")
	)
	(segment
		(start 127.443484 -142.89786)
		(end 127.598424 -142.74292)
		(width 0.14224)
		(layer "In9.Cu")
		(net "M_L_DQS_DN<14>")
	)
	(segment
		(start 127.598424 -142.74292)
		(end 127.598424 -142.38986)
		(width 0.14224)
		(layer "In9.Cu")
		(net "M_L_DQS_DN<14>")
	)
	(segment
		(start 127.392176 -140.4874)
		(end 127.428752 -140.4874)
		(width 0.14224)
		(layer "In11.Cu")
		(net "M_L_DQS_DN<14>")
	)
	(segment
		(start 127.836168 -127)
		(end 127.836168 -126.477776)
		(width 0.14224)
		(layer "In11.Cu")
		(net "M_L_DQS_DN<14>")
	)
	(segment
		(start 127.734568 -127.7366)
		(end 127.734568 -127.1016)
		(width 0.14224)
		(layer "In11.Cu")
		(net "M_L_DQS_DN<14>")
	)
	(segment
		(start 127.836168 -140.079984)
		(end 127.836168 -139.813284)
		(width 0.14224)
		(layer "In11.Cu")
		(net "M_L_DQS_DN<14>")
	)
	(segment
		(start 128.174496 -128.176528)
		(end 127.734568 -127.7366)
		(width 0.14224)
		(layer "In11.Cu")
		(net "M_L_DQS_DN<14>")
	)
	(segment
		(start 127.734568 -127.1016)
		(end 127.836168 -127)
		(width 0.14224)
		(layer "In11.Cu")
		(net "M_L_DQS_DN<14>")
	)
	(segment
		(start 127.836168 -126.477776)
		(end 127.39624 -126.037848)
		(width 0.14224)
		(layer "In11.Cu")
		(net "M_L_DQS_DN<14>")
	)
	(segment
		(start 127.39624 -126.037848)
		(end 127.39624 -126.026418)
		(width 0.14224)
		(layer "In11.Cu")
		(net "M_L_DQS_DN<14>")
	)
	(segment
		(start 128.174496 -139.474956)
		(end 128.174496 -128.176528)
		(width 0.14224)
		(layer "In11.Cu")
		(net "M_L_DQS_DN<14>")
	)
	(segment
		(start 127.836168 -139.813284)
		(end 128.174496 -139.474956)
		(width 0.14224)
		(layer "In11.Cu")
		(net "M_L_DQS_DN<14>")
	)
	(segment
		(start 127.428752 -140.4874)
		(end 127.836168 -140.079984)
		(width 0.14224)
		(layer "In11.Cu")
		(net "M_L_DQS_DN<14>")
	)
	(segment
		(start 118.71706 -144.356328)
		(end 118.71706 -144.602962)
		(width 0.1651)
		(layer "F.Cu")
		(net "M_L_DQS_DN<13>")
	)
	(segment
		(start 118.465092 -144.85493)
		(end 118.256812 -144.85493)
		(width 0.1651)
		(layer "F.Cu")
		(net "M_L_DQS_DN<13>")
	)
	(segment
		(start 118.94947 -142.6718)
		(end 118.94947 -143.33093)
		(width 0.1651)
		(layer "F.Cu")
		(net "M_L_DQS_DN<13>")
	)
	(segment
		(start 118.256812 -144.85493)
		(end 118.067582 -144.6657)
		(width 0.1651)
		(layer "F.Cu")
		(net "M_L_DQS_DN<13>")
	)
	(segment
		(start 118.531132 -144.1704)
		(end 118.71706 -144.356328)
		(width 0.1651)
		(layer "F.Cu")
		(net "M_L_DQS_DN<13>")
	)
	(segment
		(start 118.94947 -143.33093)
		(end 118.531132 -143.749268)
		(width 0.1651)
		(layer "F.Cu")
		(net "M_L_DQS_DN<13>")
	)
	(segment
		(start 118.067582 -144.6657)
		(end 118.048532 -144.6657)
		(width 0.1651)
		(layer "F.Cu")
		(net "M_L_DQS_DN<13>")
	)
	(segment
		(start 118.531132 -143.749268)
		(end 118.531132 -144.1704)
		(width 0.1651)
		(layer "F.Cu")
		(net "M_L_DQS_DN<13>")
	)
	(segment
		(start 107.910376 -97.509584)
		(end 108.481876 -97.509584)
		(width 0.1651)
		(layer "F.Cu")
		(net "M_L_DQS_DN<13>")
	)
	(segment
		(start 118.71706 -144.602962)
		(end 118.465092 -144.85493)
		(width 0.1651)
		(layer "F.Cu")
		(net "M_L_DQS_DN<13>")
	)
	(via
		(at 118.041928 -140.4874)
		(size 0.508)
		(drill 0.254)
		(layers "F.Cu" "B.Cu")
		(net "M_L_DQS_DN<13>")
	)
	(via
		(at 118.048532 -144.6657)
		(size 0.508)
		(drill 0.254)
		(layers "F.Cu" "B.Cu")
		(net "M_L_DQS_DN<13>")
	)
	(via
		(at 108.481876 -97.509584)
		(size 0.508)
		(drill 0.254)
		(layers "F.Cu" "B.Cu")
		(net "M_L_DQS_DN<13>")
	)
	(segment
		(start 118.463568 -140.292836)
		(end 118.236492 -140.292836)
		(width 0.1651)
		(layer "B.Cu")
		(net "M_L_DQS_DN<13>")
	)
	(segment
		(start 118.94947 -141.820392)
		(end 118.505732 -141.376654)
		(width 0.1651)
		(layer "B.Cu")
		(net "M_L_DQS_DN<13>")
	)
	(segment
		(start 118.505732 -141.0208)
		(end 118.683532 -140.843)
		(width 0.1651)
		(layer "B.Cu")
		(net "M_L_DQS_DN<13>")
	)
	(segment
		(start 118.683532 -140.5128)
		(end 118.463568 -140.292836)
		(width 0.1651)
		(layer "B.Cu")
		(net "M_L_DQS_DN<13>")
	)
	(segment
		(start 118.683532 -140.843)
		(end 118.683532 -140.5128)
		(width 0.1651)
		(layer "B.Cu")
		(net "M_L_DQS_DN<13>")
	)
	(segment
		(start 118.94947 -142.477236)
		(end 118.94947 -141.820392)
		(width 0.1651)
		(layer "B.Cu")
		(net "M_L_DQS_DN<13>")
	)
	(segment
		(start 118.236492 -140.292836)
		(end 118.041928 -140.4874)
		(width 0.1651)
		(layer "B.Cu")
		(net "M_L_DQS_DN<13>")
	)
	(segment
		(start 118.505732 -141.376654)
		(end 118.505732 -141.0208)
		(width 0.1651)
		(layer "B.Cu")
		(net "M_L_DQS_DN<13>")
	)
	(segment
		(start 109.366812 -106.41203)
		(end 109.406182 -106.4514)
		(width 0.0889)
		(layer "In4.Cu")
		(net "M_L_DQS_DN<13>")
	)
	(segment
		(start 109.406182 -106.4514)
		(end 109.406182 -106.473498)
		(width 0.0889)
		(layer "In4.Cu")
		(net "M_L_DQS_DN<13>")
	)
	(segment
		(start 118.824502 -139.70508)
		(end 118.042182 -140.4874)
		(width 0.14224)
		(layer "In4.Cu")
		(net "M_L_DQS_DN<13>")
	)
	(segment
		(start 117.80647 -141.75486)
		(end 117.80647 -142.10284)
		(width 0.14224)
		(layer "In4.Cu")
		(net "M_L_DQS_DN<13>")
	)
	(segment
		(start 109.406182 -116.806726)
		(end 118.259606 -125.66015)
		(width 0.14224)
		(layer "In4.Cu")
		(net "M_L_DQS_DN<13>")
	)
	(segment
		(start 108.21416 -101.943662)
		(end 109.366812 -103.096314)
		(width 0.0889)
		(layer "In4.Cu")
		(net "M_L_DQS_DN<13>")
	)
	(segment
		(start 118.259606 -125.66015)
		(end 118.259606 -128.66751)
		(width 0.14224)
		(layer "In4.Cu")
		(net "M_L_DQS_DN<13>")
	)
	(segment
		(start 118.254018 -142.737332)
		(end 118.09349 -142.89786)
		(width 0.14224)
		(layer "In4.Cu")
		(net "M_L_DQS_DN<13>")
	)
	(segment
		(start 117.93855 -142.23492)
		(end 118.09349 -142.23492)
		(width 0.14224)
		(layer "In4.Cu")
		(net "M_L_DQS_DN<13>")
	)
	(segment
		(start 118.47703 -141.3256)
		(end 118.19763 -141.605)
		(width 0.14224)
		(layer "In4.Cu")
		(net "M_L_DQS_DN<13>")
	)
	(segment
		(start 117.80647 -143.39824)
		(end 117.96903 -143.5608)
		(width 0.14224)
		(layer "In4.Cu")
		(net "M_L_DQS_DN<13>")
	)
	(segment
		(start 108.481876 -97.172272)
		(end 108.423964 -97.11436)
		(width 0.0889)
		(layer "In4.Cu")
		(net "M_L_DQS_DN<13>")
	)
	(segment
		(start 108.21416 -99.986084)
		(end 108.21416 -101.943662)
		(width 0.0889)
		(layer "In4.Cu")
		(net "M_L_DQS_DN<13>")
	)
	(segment
		(start 109.406182 -106.473498)
		(end 109.406182 -116.806726)
		(width 0.14224)
		(layer "In4.Cu")
		(net "M_L_DQS_DN<13>")
	)
	(segment
		(start 117.80647 -142.10284)
		(end 117.93855 -142.23492)
		(width 0.14224)
		(layer "In4.Cu")
		(net "M_L_DQS_DN<13>")
	)
	(segment
		(start 117.94617 -142.89786)
		(end 117.80647 -143.03756)
		(width 0.14224)
		(layer "In4.Cu")
		(net "M_L_DQS_DN<13>")
	)
	(segment
		(start 118.09349 -142.23492)
		(end 118.254018 -142.395448)
		(width 0.14224)
		(layer "In4.Cu")
		(net "M_L_DQS_DN<13>")
	)
	(segment
		(start 118.47703 -140.922248)
		(end 118.47703 -141.3256)
		(width 0.14224)
		(layer "In4.Cu")
		(net "M_L_DQS_DN<13>")
	)
	(segment
		(start 108.481876 -97.509584)
		(end 108.481876 -97.172272)
		(width 0.0889)
		(layer "In4.Cu")
		(net "M_L_DQS_DN<13>")
	)
	(segment
		(start 118.481856 -144.23263)
		(end 118.048786 -144.6657)
		(width 0.14224)
		(layer "In4.Cu")
		(net "M_L_DQS_DN<13>")
	)
	(segment
		(start 118.481856 -143.748506)
		(end 118.481856 -144.23263)
		(width 0.14224)
		(layer "In4.Cu")
		(net "M_L_DQS_DN<13>")
	)
	(segment
		(start 118.048786 -144.6657)
		(end 118.048532 -144.6657)
		(width 0.14224)
		(layer "In4.Cu")
		(net "M_L_DQS_DN<13>")
	)
	(segment
		(start 118.19763 -141.605)
		(end 117.95633 -141.605)
		(width 0.14224)
		(layer "In4.Cu")
		(net "M_L_DQS_DN<13>")
	)
	(segment
		(start 118.042182 -140.4874)
		(end 118.47703 -140.922248)
		(width 0.14224)
		(layer "In4.Cu")
		(net "M_L_DQS_DN<13>")
	)
	(segment
		(start 118.824502 -129.232406)
		(end 118.824502 -139.70508)
		(width 0.14224)
		(layer "In4.Cu")
		(net "M_L_DQS_DN<13>")
	)
	(segment
		(start 117.96903 -143.5608)
		(end 118.29415 -143.5608)
		(width 0.14224)
		(layer "In4.Cu")
		(net "M_L_DQS_DN<13>")
	)
	(segment
		(start 118.09349 -142.89786)
		(end 117.94617 -142.89786)
		(width 0.14224)
		(layer "In4.Cu")
		(net "M_L_DQS_DN<13>")
	)
	(segment
		(start 118.29415 -143.5608)
		(end 118.481856 -143.748506)
		(width 0.14224)
		(layer "In4.Cu")
		(net "M_L_DQS_DN<13>")
	)
	(segment
		(start 118.254018 -142.395448)
		(end 118.254018 -142.737332)
		(width 0.14224)
		(layer "In4.Cu")
		(net "M_L_DQS_DN<13>")
	)
	(segment
		(start 117.95633 -141.605)
		(end 117.80647 -141.75486)
		(width 0.14224)
		(layer "In4.Cu")
		(net "M_L_DQS_DN<13>")
	)
	(segment
		(start 118.041928 -140.4874)
		(end 118.042182 -140.4874)
		(width 0.14224)
		(layer "In4.Cu")
		(net "M_L_DQS_DN<13>")
	)
	(segment
		(start 117.80647 -143.03756)
		(end 117.80647 -143.39824)
		(width 0.14224)
		(layer "In4.Cu")
		(net "M_L_DQS_DN<13>")
	)
	(segment
		(start 109.366812 -103.096314)
		(end 109.366812 -106.41203)
		(width 0.0889)
		(layer "In4.Cu")
		(net "M_L_DQS_DN<13>")
	)
	(segment
		(start 118.259606 -128.66751)
		(end 118.824502 -129.232406)
		(width 0.14224)
		(layer "In4.Cu")
		(net "M_L_DQS_DN<13>")
	)
	(arc
		(start 108.135166 -99.691444)
		(mid 108.194012 -99.833577)
		(end 108.21416 -99.986084)
		(width 0.0889)
		(layer "In4.Cu")
		(net "M_L_DQS_DN<13>")
	)
	(arc
		(start 108.135166 -98.301048)
		(mid 108.081667 -98.500946)
		(end 108.135166 -98.700844)
		(width 0.0889)
		(layer "In4.Cu")
		(net "M_L_DQS_DN<13>")
	)
	(arc
		(start 108.423964 -97.11436)
		(mid 108.121743 -97.33581)
		(end 108.135166 -97.710244)
		(width 0.0889)
		(layer "In4.Cu")
		(net "M_L_DQS_DN<13>")
	)
	(arc
		(start 108.135166 -98.700844)
		(mid 108.214297 -98.996246)
		(end 108.135166 -99.291648)
		(width 0.0889)
		(layer "In4.Cu")
		(net "M_L_DQS_DN<13>")
	)
	(arc
		(start 108.135166 -99.291648)
		(mid 108.081667 -99.491546)
		(end 108.135166 -99.691444)
		(width 0.0889)
		(layer "In4.Cu")
		(net "M_L_DQS_DN<13>")
	)
	(arc
		(start 108.135166 -97.710244)
		(mid 108.214297 -98.005646)
		(end 108.135166 -98.301048)
		(width 0.0889)
		(layer "In4.Cu")
		(net "M_L_DQS_DN<13>")
	)
	(segment
		(start 63.281306 -144.1704)
		(end 63.467234 -144.356328)
		(width 0.1651)
		(layer "F.Cu")
		(net "M_L_DQS_DN<12>")
	)
	(segment
		(start 63.69939 -143.331184)
		(end 63.281306 -143.749268)
		(width 0.1651)
		(layer "F.Cu")
		(net "M_L_DQS_DN<12>")
	)
	(segment
		(start 78.523592 -102.459282)
		(end 78.472792 -102.510082)
		(width 0.0889)
		(layer "F.Cu")
		(net "M_L_DQS_DN<12>")
	)
	(segment
		(start 63.467234 -144.356328)
		(end 63.467234 -144.602962)
		(width 0.1651)
		(layer "F.Cu")
		(net "M_L_DQS_DN<12>")
	)
	(segment
		(start 76.830174 -103.746554)
		(end 74.48042 -103.746554)
		(width 0.1016)
		(layer "F.Cu")
		(net "M_L_DQS_DN<12>")
	)
	(segment
		(start 77.23632 -103.746554)
		(end 76.830174 -103.746554)
		(width 0.1016)
		(layer "F.Cu")
		(net "M_L_DQS_DN<12>")
	)
	(segment
		(start 73.147428 -105.079546)
		(end 72.808592 -105.079546)
		(width 0.1016)
		(layer "F.Cu")
		(net "M_L_DQS_DN<12>")
	)
	(segment
		(start 63.69939 -142.6718)
		(end 63.69939 -143.331184)
		(width 0.1651)
		(layer "F.Cu")
		(net "M_L_DQS_DN<12>")
	)
	(segment
		(start 78.566518 -99.4664)
		(end 78.563216 -99.472242)
		(width 0.0889)
		(layer "F.Cu")
		(net "M_L_DQS_DN<12>")
	)
	(segment
		(start 62.779148 -122.681492)
		(end 62.779148 -123.487434)
		(width 0.1651)
		(layer "F.Cu")
		(net "M_L_DQS_DN<12>")
	)
	(segment
		(start 62.779148 -121.005854)
		(end 62.939168 -121.165874)
		(width 0.1651)
		(layer "F.Cu")
		(net "M_L_DQS_DN<12>")
	)
	(segment
		(start 78.572106 -101.437948)
		(end 78.563216 -101.453188)
		(width 0.0889)
		(layer "F.Cu")
		(net "M_L_DQS_DN<12>")
	)
	(segment
		(start 69.511672 -105.0798)
		(end 62.779148 -111.812324)
		(width 0.1651)
		(layer "F.Cu")
		(net "M_L_DQS_DN<12>")
	)
	(segment
		(start 62.779148 -123.487434)
		(end 63.567564 -124.27585)
		(width 0.1651)
		(layer "F.Cu")
		(net "M_L_DQS_DN<12>")
	)
	(segment
		(start 63.006986 -144.85493)
		(end 62.817756 -144.6657)
		(width 0.1651)
		(layer "F.Cu")
		(net "M_L_DQS_DN<12>")
	)
	(segment
		(start 78.563216 -101.453188)
		(end 78.55839 -101.461824)
		(width 0.0889)
		(layer "F.Cu")
		(net "M_L_DQS_DN<12>")
	)
	(segment
		(start 78.523592 -101.598476)
		(end 78.523592 -102.459282)
		(width 0.0889)
		(layer "F.Cu")
		(net "M_L_DQS_DN<12>")
	)
	(segment
		(start 63.567564 -124.27585)
		(end 63.567564 -125.189234)
		(width 0.1651)
		(layer "F.Cu")
		(net "M_L_DQS_DN<12>")
	)
	(segment
		(start 62.779148 -111.812324)
		(end 62.779148 -121.005854)
		(width 0.1651)
		(layer "F.Cu")
		(net "M_L_DQS_DN<12>")
	)
	(segment
		(start 62.939168 -122.521472)
		(end 62.779148 -122.681492)
		(width 0.1651)
		(layer "F.Cu")
		(net "M_L_DQS_DN<12>")
	)
	(segment
		(start 63.281306 -143.749268)
		(end 63.281306 -144.1704)
		(width 0.1651)
		(layer "F.Cu")
		(net "M_L_DQS_DN<12>")
	)
	(segment
		(start 62.939168 -121.165874)
		(end 62.939168 -122.521472)
		(width 0.1651)
		(layer "F.Cu")
		(net "M_L_DQS_DN<12>")
	)
	(segment
		(start 78.909672 -99.340416)
		(end 78.846426 -99.27717)
		(width 0.0889)
		(layer "F.Cu")
		(net "M_L_DQS_DN<12>")
	)
	(segment
		(start 63.215266 -144.85493)
		(end 63.006986 -144.85493)
		(width 0.1651)
		(layer "F.Cu")
		(net "M_L_DQS_DN<12>")
	)
	(segment
		(start 74.48042 -103.746554)
		(end 73.147428 -105.079546)
		(width 0.1016)
		(layer "F.Cu")
		(net "M_L_DQS_DN<12>")
	)
	(segment
		(start 62.817756 -144.6657)
		(end 62.798706 -144.6657)
		(width 0.1651)
		(layer "F.Cu")
		(net "M_L_DQS_DN<12>")
	)
	(segment
		(start 63.467234 -144.602962)
		(end 63.215266 -144.85493)
		(width 0.1651)
		(layer "F.Cu")
		(net "M_L_DQS_DN<12>")
	)
	(segment
		(start 72.808592 -105.079546)
		(end 72.808338 -105.0798)
		(width 0.1651)
		(layer "F.Cu")
		(net "M_L_DQS_DN<12>")
	)
	(segment
		(start 78.472792 -102.510082)
		(end 77.23632 -103.746554)
		(width 0.1016)
		(layer "F.Cu")
		(net "M_L_DQS_DN<12>")
	)
	(segment
		(start 63.567564 -125.189234)
		(end 62.795912 -125.960886)
		(width 0.1651)
		(layer "F.Cu")
		(net "M_L_DQS_DN<12>")
	)
	(segment
		(start 78.563216 -99.872038)
		(end 78.569566 -99.882706)
		(width 0.0889)
		(layer "F.Cu")
		(net "M_L_DQS_DN<12>")
	)
	(segment
		(start 78.909672 -99.67214)
		(end 78.909672 -99.340416)
		(width 0.0889)
		(layer "F.Cu")
		(net "M_L_DQS_DN<12>")
	)
	(segment
		(start 72.808338 -105.0798)
		(end 69.511672 -105.0798)
		(width 0.1651)
		(layer "F.Cu")
		(net "M_L_DQS_DN<12>")
	)
	(via
		(at 62.792102 -140.4874)
		(size 0.508)
		(drill 0.254)
		(layers "F.Cu" "B.Cu")
		(net "M_L_DQS_DN<12>")
	)
	(via
		(at 62.798706 -144.6657)
		(size 0.508)
		(drill 0.254)
		(layers "F.Cu" "B.Cu")
		(net "M_L_DQS_DN<12>")
	)
	(via
		(at 62.795912 -125.960886)
		(size 0.508)
		(drill 0.254)
		(layers "F.Cu" "B.Cu")
		(net "M_L_DQS_DN<12>")
	)
	(arc
		(start 78.563216 -100.462588)
		(mid 78.509683 -100.662486)
		(end 78.563216 -100.862384)
		(width 0.0889)
		(layer "F.Cu")
		(net "M_L_DQS_DN<12>")
	)
	(arc
		(start 78.563216 -99.472242)
		(mid 78.509683 -99.67214)
		(end 78.563216 -99.872038)
		(width 0.0889)
		(layer "F.Cu")
		(net "M_L_DQS_DN<12>")
	)
	(arc
		(start 78.569566 -99.882706)
		(mid 78.642364 -100.173469)
		(end 78.563216 -100.462588)
		(width 0.0889)
		(layer "F.Cu")
		(net "M_L_DQS_DN<12>")
	)
	(arc
		(start 78.55839 -101.461824)
		(mid 78.532385 -101.527962)
		(end 78.523592 -101.598476)
		(width 0.0889)
		(layer "F.Cu")
		(net "M_L_DQS_DN<12>")
	)
	(arc
		(start 78.846426 -99.27717)
		(mid 78.685553 -99.340821)
		(end 78.566518 -99.4664)
		(width 0.0889)
		(layer "F.Cu")
		(net "M_L_DQS_DN<12>")
	)
	(arc
		(start 78.563216 -100.862384)
		(mid 78.642405 -101.148999)
		(end 78.572106 -101.437948)
		(width 0.0889)
		(layer "F.Cu")
		(net "M_L_DQS_DN<12>")
	)
	(segment
		(start 62.986666 -140.292836)
		(end 62.792102 -140.4874)
		(width 0.1651)
		(layer "B.Cu")
		(net "M_L_DQS_DN<12>")
	)
	(segment
		(start 63.255906 -141.0208)
		(end 63.433706 -140.843)
		(width 0.1651)
		(layer "B.Cu")
		(net "M_L_DQS_DN<12>")
	)
	(segment
		(start 63.69939 -142.477236)
		(end 63.69939 -141.820138)
		(width 0.1651)
		(layer "B.Cu")
		(net "M_L_DQS_DN<12>")
	)
	(segment
		(start 63.255906 -141.376654)
		(end 63.255906 -141.0208)
		(width 0.1651)
		(layer "B.Cu")
		(net "M_L_DQS_DN<12>")
	)
	(segment
		(start 63.213742 -140.292836)
		(end 62.986666 -140.292836)
		(width 0.1651)
		(layer "B.Cu")
		(net "M_L_DQS_DN<12>")
	)
	(segment
		(start 63.69939 -141.820138)
		(end 63.255906 -141.376654)
		(width 0.1651)
		(layer "B.Cu")
		(net "M_L_DQS_DN<12>")
	)
	(segment
		(start 63.433706 -140.5128)
		(end 63.213742 -140.292836)
		(width 0.1651)
		(layer "B.Cu")
		(net "M_L_DQS_DN<12>")
	)
	(segment
		(start 63.433706 -140.843)
		(end 63.433706 -140.5128)
		(width 0.1651)
		(layer "B.Cu")
		(net "M_L_DQS_DN<12>")
	)
	(segment
		(start 62.55639 -143.03756)
		(end 62.69609 -142.89786)
		(width 0.14224)
		(layer "In4.Cu")
		(net "M_L_DQS_DN<12>")
	)
	(segment
		(start 62.99835 -142.38986)
		(end 62.84341 -142.23492)
		(width 0.14224)
		(layer "In4.Cu")
		(net "M_L_DQS_DN<12>")
	)
	(segment
		(start 63.231776 -144.23263)
		(end 63.231776 -143.748506)
		(width 0.14224)
		(layer "In4.Cu")
		(net "M_L_DQS_DN<12>")
	)
	(segment
		(start 62.84341 -142.89786)
		(end 62.99835 -142.74292)
		(width 0.14224)
		(layer "In4.Cu")
		(net "M_L_DQS_DN<12>")
	)
	(segment
		(start 62.55639 -142.10284)
		(end 62.55639 -141.75486)
		(width 0.14224)
		(layer "In4.Cu")
		(net "M_L_DQS_DN<12>")
	)
	(segment
		(start 62.55639 -143.39824)
		(end 62.55639 -143.03756)
		(width 0.14224)
		(layer "In4.Cu")
		(net "M_L_DQS_DN<12>")
	)
	(segment
		(start 63.22695 -140.922248)
		(end 62.792102 -140.4874)
		(width 0.14224)
		(layer "In4.Cu")
		(net "M_L_DQS_DN<12>")
	)
	(segment
		(start 63.209678 -126.856744)
		(end 63.209678 -126.305564)
		(width 0.14224)
		(layer "In4.Cu")
		(net "M_L_DQS_DN<12>")
	)
	(segment
		(start 62.99835 -142.74292)
		(end 62.99835 -142.38986)
		(width 0.14224)
		(layer "In4.Cu")
		(net "M_L_DQS_DN<12>")
	)
	(segment
		(start 63.04407 -143.5608)
		(end 62.71895 -143.5608)
		(width 0.14224)
		(layer "In4.Cu")
		(net "M_L_DQS_DN<12>")
	)
	(segment
		(start 63.22695 -141.3256)
		(end 63.22695 -140.922248)
		(width 0.14224)
		(layer "In4.Cu")
		(net "M_L_DQS_DN<12>")
	)
	(segment
		(start 63.231776 -143.748506)
		(end 63.04407 -143.5608)
		(width 0.14224)
		(layer "In4.Cu")
		(net "M_L_DQS_DN<12>")
	)
	(segment
		(start 62.71895 -143.5608)
		(end 62.55639 -143.39824)
		(width 0.14224)
		(layer "In4.Cu")
		(net "M_L_DQS_DN<12>")
	)
	(segment
		(start 63.574422 -128.949958)
		(end 62.989968 -127.538988)
		(width 0.14224)
		(layer "In4.Cu")
		(net "M_L_DQS_DN<12>")
	)
	(segment
		(start 62.792102 -140.456666)
		(end 63.574422 -139.674346)
		(width 0.14224)
		(layer "In4.Cu")
		(net "M_L_DQS_DN<12>")
	)
	(segment
		(start 62.55639 -141.75486)
		(end 62.70625 -141.605)
		(width 0.14224)
		(layer "In4.Cu")
		(net "M_L_DQS_DN<12>")
	)
	(segment
		(start 62.989968 -127.538988)
		(end 62.989968 -127.076454)
		(width 0.14224)
		(layer "In4.Cu")
		(net "M_L_DQS_DN<12>")
	)
	(segment
		(start 62.865 -125.960886)
		(end 62.795912 -125.960886)
		(width 0.14224)
		(layer "In4.Cu")
		(net "M_L_DQS_DN<12>")
	)
	(segment
		(start 62.68847 -142.23492)
		(end 62.55639 -142.10284)
		(width 0.14224)
		(layer "In4.Cu")
		(net "M_L_DQS_DN<12>")
	)
	(segment
		(start 62.69609 -142.89786)
		(end 62.84341 -142.89786)
		(width 0.14224)
		(layer "In4.Cu")
		(net "M_L_DQS_DN<12>")
	)
	(segment
		(start 62.70625 -141.605)
		(end 62.94755 -141.605)
		(width 0.14224)
		(layer "In4.Cu")
		(net "M_L_DQS_DN<12>")
	)
	(segment
		(start 62.792102 -140.4874)
		(end 62.792102 -140.456666)
		(width 0.14224)
		(layer "In4.Cu")
		(net "M_L_DQS_DN<12>")
	)
	(segment
		(start 62.798706 -144.6657)
		(end 63.231776 -144.23263)
		(width 0.14224)
		(layer "In4.Cu")
		(net "M_L_DQS_DN<12>")
	)
	(segment
		(start 63.209678 -126.305564)
		(end 62.865 -125.960886)
		(width 0.14224)
		(layer "In4.Cu")
		(net "M_L_DQS_DN<12>")
	)
	(segment
		(start 62.94755 -141.605)
		(end 63.22695 -141.3256)
		(width 0.14224)
		(layer "In4.Cu")
		(net "M_L_DQS_DN<12>")
	)
	(segment
		(start 63.574422 -139.674346)
		(end 63.574422 -128.949958)
		(width 0.14224)
		(layer "In4.Cu")
		(net "M_L_DQS_DN<12>")
	)
	(segment
		(start 62.989968 -127.076454)
		(end 63.209678 -126.856744)
		(width 0.14224)
		(layer "In4.Cu")
		(net "M_L_DQS_DN<12>")
	)
	(segment
		(start 62.84341 -142.23492)
		(end 62.68847 -142.23492)
		(width 0.14224)
		(layer "In4.Cu")
		(net "M_L_DQS_DN<12>")
	)
	(segment
		(start 73.758806 -98.681286)
		(end 73.187306 -98.681286)
		(width 0.1651)
		(layer "F.Cu")
		(net "M_L_DQS_DN<11>")
	)
	(segment
		(start 54.349396 -142.6718)
		(end 54.349396 -143.331184)
		(width 0.1651)
		(layer "F.Cu")
		(net "M_L_DQS_DN<11>")
	)
	(segment
		(start 53.656992 -144.85493)
		(end 53.467762 -144.6657)
		(width 0.1651)
		(layer "F.Cu")
		(net "M_L_DQS_DN<11>")
	)
	(segment
		(start 54.11724 -144.602962)
		(end 53.865272 -144.85493)
		(width 0.1651)
		(layer "F.Cu")
		(net "M_L_DQS_DN<11>")
	)
	(segment
		(start 54.349396 -143.331184)
		(end 53.931312 -143.749268)
		(width 0.1651)
		(layer "F.Cu")
		(net "M_L_DQS_DN<11>")
	)
	(segment
		(start 53.467762 -144.6657)
		(end 53.448712 -144.6657)
		(width 0.1651)
		(layer "F.Cu")
		(net "M_L_DQS_DN<11>")
	)
	(segment
		(start 54.11724 -144.356328)
		(end 54.11724 -144.602962)
		(width 0.1651)
		(layer "F.Cu")
		(net "M_L_DQS_DN<11>")
	)
	(segment
		(start 53.865272 -144.85493)
		(end 53.656992 -144.85493)
		(width 0.1651)
		(layer "F.Cu")
		(net "M_L_DQS_DN<11>")
	)
	(segment
		(start 53.931312 -143.749268)
		(end 53.931312 -144.1704)
		(width 0.1651)
		(layer "F.Cu")
		(net "M_L_DQS_DN<11>")
	)
	(segment
		(start 53.931312 -144.1704)
		(end 54.11724 -144.356328)
		(width 0.1651)
		(layer "F.Cu")
		(net "M_L_DQS_DN<11>")
	)
	(via
		(at 73.187306 -98.681286)
		(size 0.508)
		(drill 0.254)
		(layers "F.Cu" "B.Cu")
		(net "M_L_DQS_DN<11>")
	)
	(via
		(at 53.448712 -144.6657)
		(size 0.508)
		(drill 0.254)
		(layers "F.Cu" "B.Cu")
		(net "M_L_DQS_DN<11>")
	)
	(via
		(at 53.442108 -140.4874)
		(size 0.508)
		(drill 0.254)
		(layers "F.Cu" "B.Cu")
		(net "M_L_DQS_DN<11>")
	)
	(segment
		(start 54.083712 -140.843)
		(end 54.083712 -140.5128)
		(width 0.1651)
		(layer "B.Cu")
		(net "M_L_DQS_DN<11>")
	)
	(segment
		(start 53.863748 -140.292836)
		(end 53.636672 -140.292836)
		(width 0.1651)
		(layer "B.Cu")
		(net "M_L_DQS_DN<11>")
	)
	(segment
		(start 54.34965 -142.476728)
		(end 54.34965 -141.820392)
		(width 0.1651)
		(layer "B.Cu")
		(net "M_L_DQS_DN<11>")
	)
	(segment
		(start 53.636672 -140.292836)
		(end 53.442108 -140.4874)
		(width 0.1651)
		(layer "B.Cu")
		(net "M_L_DQS_DN<11>")
	)
	(segment
		(start 54.083712 -140.5128)
		(end 53.863748 -140.292836)
		(width 0.1651)
		(layer "B.Cu")
		(net "M_L_DQS_DN<11>")
	)
	(segment
		(start 53.905912 -141.376654)
		(end 53.905912 -141.0208)
		(width 0.1651)
		(layer "B.Cu")
		(net "M_L_DQS_DN<11>")
	)
	(segment
		(start 54.34965 -141.820392)
		(end 53.905912 -141.376654)
		(width 0.1651)
		(layer "B.Cu")
		(net "M_L_DQS_DN<11>")
	)
	(segment
		(start 54.349396 -142.477236)
		(end 54.34965 -142.476728)
		(width 0.1651)
		(layer "B.Cu")
		(net "M_L_DQS_DN<11>")
	)
	(segment
		(start 53.905912 -141.0208)
		(end 54.083712 -140.843)
		(width 0.1651)
		(layer "B.Cu")
		(net "M_L_DQS_DN<11>")
	)
	(segment
		(start 72.34174 -100.75799)
		(end 72.3138 -100.75799)
		(width 0.0889)
		(layer "In4.Cu")
		(net "M_L_DQS_DN<11>")
	)
	(segment
		(start 53.368956 -143.5608)
		(end 53.694076 -143.5608)
		(width 0.14224)
		(layer "In4.Cu")
		(net "M_L_DQS_DN<11>")
	)
	(segment
		(start 53.694076 -143.5608)
		(end 53.881782 -143.748506)
		(width 0.14224)
		(layer "In4.Cu")
		(net "M_L_DQS_DN<11>")
	)
	(segment
		(start 53.206396 -143.03756)
		(end 53.206396 -143.39824)
		(width 0.14224)
		(layer "In4.Cu")
		(net "M_L_DQS_DN<11>")
	)
	(segment
		(start 53.206396 -142.10284)
		(end 53.338476 -142.23492)
		(width 0.14224)
		(layer "In4.Cu")
		(net "M_L_DQS_DN<11>")
	)
	(segment
		(start 53.206396 -141.75486)
		(end 53.206396 -142.10284)
		(width 0.14224)
		(layer "In4.Cu")
		(net "M_L_DQS_DN<11>")
	)
	(segment
		(start 73.187306 -98.343212)
		(end 73.129394 -98.2853)
		(width 0.0889)
		(layer "In4.Cu")
		(net "M_L_DQS_DN<11>")
	)
	(segment
		(start 71.12381 -101.45268)
		(end 71.028052 -101.618288)
		(width 0.0889)
		(layer "In4.Cu")
		(net "M_L_DQS_DN<11>")
	)
	(segment
		(start 55.415688 -123.451366)
		(end 55.415688 -128.028446)
		(width 0.14224)
		(layer "In4.Cu")
		(net "M_L_DQS_DN<11>")
	)
	(segment
		(start 54.224428 -129.219706)
		(end 54.224428 -139.70508)
		(width 0.14224)
		(layer "In4.Cu")
		(net "M_L_DQS_DN<11>")
	)
	(segment
		(start 68.509642 -103.887016)
		(end 68.509896 -103.942388)
		(width 0.0889)
		(layer "In4.Cu")
		(net "M_L_DQS_DN<11>")
	)
	(segment
		(start 64.737488 -114.129566)
		(end 55.415688 -123.451366)
		(width 0.14224)
		(layer "In4.Cu")
		(net "M_L_DQS_DN<11>")
	)
	(segment
		(start 53.493416 -142.89786)
		(end 53.346096 -142.89786)
		(width 0.14224)
		(layer "In4.Cu")
		(net "M_L_DQS_DN<11>")
	)
	(segment
		(start 53.338476 -142.23492)
		(end 53.493416 -142.23492)
		(width 0.14224)
		(layer "In4.Cu")
		(net "M_L_DQS_DN<11>")
	)
	(segment
		(start 53.206396 -143.39824)
		(end 53.368956 -143.5608)
		(width 0.14224)
		(layer "In4.Cu")
		(net "M_L_DQS_DN<11>")
	)
	(segment
		(start 53.356256 -141.605)
		(end 53.206396 -141.75486)
		(width 0.14224)
		(layer "In4.Cu")
		(net "M_L_DQS_DN<11>")
	)
	(segment
		(start 68.034408 -104.417876)
		(end 68.034408 -106.063288)
		(width 0.14224)
		(layer "In4.Cu")
		(net "M_L_DQS_DN<11>")
	)
	(segment
		(start 53.346096 -142.89786)
		(end 53.206396 -143.03756)
		(width 0.14224)
		(layer "In4.Cu")
		(net "M_L_DQS_DN<11>")
	)
	(segment
		(start 73.187306 -98.681286)
		(end 73.187306 -98.343212)
		(width 0.0889)
		(layer "In4.Cu")
		(net "M_L_DQS_DN<11>")
	)
	(segment
		(start 53.648356 -142.38986)
		(end 53.648356 -142.74292)
		(width 0.14224)
		(layer "In4.Cu")
		(net "M_L_DQS_DN<11>")
	)
	(segment
		(start 53.876956 -140.922248)
		(end 53.876956 -141.3256)
		(width 0.14224)
		(layer "In4.Cu")
		(net "M_L_DQS_DN<11>")
	)
	(segment
		(start 71.491856 -101.253036)
		(end 71.45909 -101.253036)
		(width 0.0889)
		(layer "In4.Cu")
		(net "M_L_DQS_DN<11>")
	)
	(segment
		(start 55.415688 -128.028446)
		(end 54.224428 -129.219706)
		(width 0.14224)
		(layer "In4.Cu")
		(net "M_L_DQS_DN<11>")
	)
	(segment
		(start 68.034408 -106.063288)
		(end 64.737488 -109.360208)
		(width 0.14224)
		(layer "In4.Cu")
		(net "M_L_DQS_DN<11>")
	)
	(segment
		(start 71.028052 -101.618288)
		(end 70.1294 -102.51694)
		(width 0.0889)
		(layer "In4.Cu")
		(net "M_L_DQS_DN<11>")
	)
	(segment
		(start 53.876956 -141.3256)
		(end 53.597556 -141.605)
		(width 0.14224)
		(layer "In4.Cu")
		(net "M_L_DQS_DN<11>")
	)
	(segment
		(start 68.509896 -103.942388)
		(end 68.494402 -103.957882)
		(width 0.0889)
		(layer "In4.Cu")
		(net "M_L_DQS_DN<11>")
	)
	(segment
		(start 53.648356 -142.74292)
		(end 53.493416 -142.89786)
		(width 0.14224)
		(layer "In4.Cu")
		(net "M_L_DQS_DN<11>")
	)
	(segment
		(start 72.840596 -99.872038)
		(end 72.846946 -99.882706)
		(width 0.0889)
		(layer "In4.Cu")
		(net "M_L_DQS_DN<11>")
	)
	(segment
		(start 69.879718 -102.51694)
		(end 68.509642 -103.887016)
		(width 0.0889)
		(layer "In4.Cu")
		(net "M_L_DQS_DN<11>")
	)
	(segment
		(start 53.597556 -141.605)
		(end 53.356256 -141.605)
		(width 0.14224)
		(layer "In4.Cu")
		(net "M_L_DQS_DN<11>")
	)
	(segment
		(start 53.442108 -140.4874)
		(end 53.876956 -140.922248)
		(width 0.14224)
		(layer "In4.Cu")
		(net "M_L_DQS_DN<11>")
	)
	(segment
		(start 53.493416 -142.23492)
		(end 53.648356 -142.38986)
		(width 0.14224)
		(layer "In4.Cu")
		(net "M_L_DQS_DN<11>")
	)
	(segment
		(start 70.1294 -102.51694)
		(end 69.879718 -102.51694)
		(width 0.0889)
		(layer "In4.Cu")
		(net "M_L_DQS_DN<11>")
	)
	(segment
		(start 53.881782 -144.23263)
		(end 53.448712 -144.6657)
		(width 0.14224)
		(layer "In4.Cu")
		(net "M_L_DQS_DN<11>")
	)
	(segment
		(start 53.881782 -143.748506)
		(end 53.881782 -144.23263)
		(width 0.14224)
		(layer "In4.Cu")
		(net "M_L_DQS_DN<11>")
	)
	(segment
		(start 54.224428 -139.70508)
		(end 53.442108 -140.4874)
		(width 0.14224)
		(layer "In4.Cu")
		(net "M_L_DQS_DN<11>")
	)
	(segment
		(start 64.737488 -109.360208)
		(end 64.737488 -114.129566)
		(width 0.14224)
		(layer "In4.Cu")
		(net "M_L_DQS_DN<11>")
	)
	(segment
		(start 68.494402 -103.957882)
		(end 68.034408 -104.417876)
		(width 0.14224)
		(layer "In4.Cu")
		(net "M_L_DQS_DN<11>")
	)
	(arc
		(start 72.846946 -99.882706)
		(mid 72.840769 -100.462638)
		(end 72.34174 -100.75799)
		(width 0.0889)
		(layer "In4.Cu")
		(net "M_L_DQS_DN<11>")
	)
	(arc
		(start 73.129394 -98.2853)
		(mid 72.827125 -98.506849)
		(end 72.840596 -98.881438)
		(width 0.0889)
		(layer "In4.Cu")
		(net "M_L_DQS_DN<11>")
	)
	(arc
		(start 71.982076 -100.957888)
		(mid 71.775072 -101.168752)
		(end 71.491856 -101.253036)
		(width 0.0889)
		(layer "In4.Cu")
		(net "M_L_DQS_DN<11>")
	)
	(arc
		(start 72.3138 -100.75799)
		(mid 72.122158 -100.815156)
		(end 71.982076 -100.957888)
		(width 0.0889)
		(layer "In4.Cu")
		(net "M_L_DQS_DN<11>")
	)
	(arc
		(start 72.840596 -99.472242)
		(mid 72.787097 -99.67214)
		(end 72.840596 -99.872038)
		(width 0.0889)
		(layer "In4.Cu")
		(net "M_L_DQS_DN<11>")
	)
	(arc
		(start 71.45909 -101.253036)
		(mid 71.265484 -101.309241)
		(end 71.12381 -101.45268)
		(width 0.0889)
		(layer "In4.Cu")
		(net "M_L_DQS_DN<11>")
	)
	(arc
		(start 72.840596 -98.881438)
		(mid 72.919727 -99.17684)
		(end 72.840596 -99.472242)
		(width 0.0889)
		(layer "In4.Cu")
		(net "M_L_DQS_DN<11>")
	)
	(segment
		(start 44.767246 -144.356328)
		(end 44.767246 -144.602962)
		(width 0.1651)
		(layer "F.Cu")
		(net "M_L_DQS_DN<10>")
	)
	(segment
		(start 44.581318 -144.1704)
		(end 44.767246 -144.356328)
		(width 0.1651)
		(layer "F.Cu")
		(net "M_L_DQS_DN<10>")
	)
	(segment
		(start 44.117768 -144.6657)
		(end 44.098718 -144.6657)
		(width 0.1651)
		(layer "F.Cu")
		(net "M_L_DQS_DN<10>")
	)
	(segment
		(start 44.306998 -144.85493)
		(end 44.117768 -144.6657)
		(width 0.1651)
		(layer "F.Cu")
		(net "M_L_DQS_DN<10>")
	)
	(segment
		(start 44.767246 -144.602962)
		(end 44.515278 -144.85493)
		(width 0.1651)
		(layer "F.Cu")
		(net "M_L_DQS_DN<10>")
	)
	(segment
		(start 44.999402 -143.331184)
		(end 44.581318 -143.749268)
		(width 0.1651)
		(layer "F.Cu")
		(net "M_L_DQS_DN<10>")
	)
	(segment
		(start 44.999402 -142.6718)
		(end 44.999402 -143.331184)
		(width 0.1651)
		(layer "F.Cu")
		(net "M_L_DQS_DN<10>")
	)
	(segment
		(start 44.515278 -144.85493)
		(end 44.306998 -144.85493)
		(width 0.1651)
		(layer "F.Cu")
		(net "M_L_DQS_DN<10>")
	)
	(segment
		(start 72.900286 -90.26144)
		(end 72.328786 -90.26144)
		(width 0.1651)
		(layer "F.Cu")
		(net "M_L_DQS_DN<10>")
	)
	(segment
		(start 44.581318 -143.749268)
		(end 44.581318 -144.1704)
		(width 0.1651)
		(layer "F.Cu")
		(net "M_L_DQS_DN<10>")
	)
	(via
		(at 44.092114 -140.4874)
		(size 0.508)
		(drill 0.254)
		(layers "F.Cu" "B.Cu")
		(net "M_L_DQS_DN<10>")
	)
	(via
		(at 72.328786 -90.26144)
		(size 0.508)
		(drill 0.254)
		(layers "F.Cu" "B.Cu")
		(net "M_L_DQS_DN<10>")
	)
	(via
		(at 44.098718 -144.6657)
		(size 0.508)
		(drill 0.254)
		(layers "F.Cu" "B.Cu")
		(net "M_L_DQS_DN<10>")
	)
	(segment
		(start 44.555918 -141.376654)
		(end 44.555918 -141.0208)
		(width 0.1651)
		(layer "B.Cu")
		(net "M_L_DQS_DN<10>")
	)
	(segment
		(start 44.733718 -140.843)
		(end 44.733718 -140.5128)
		(width 0.1651)
		(layer "B.Cu")
		(net "M_L_DQS_DN<10>")
	)
	(segment
		(start 44.286678 -140.292836)
		(end 44.092114 -140.4874)
		(width 0.1651)
		(layer "B.Cu")
		(net "M_L_DQS_DN<10>")
	)
	(segment
		(start 44.733718 -140.5128)
		(end 44.513754 -140.292836)
		(width 0.1651)
		(layer "B.Cu")
		(net "M_L_DQS_DN<10>")
	)
	(segment
		(start 44.999402 -141.820138)
		(end 44.555918 -141.376654)
		(width 0.1651)
		(layer "B.Cu")
		(net "M_L_DQS_DN<10>")
	)
	(segment
		(start 44.999402 -142.477236)
		(end 44.999402 -141.820138)
		(width 0.1651)
		(layer "B.Cu")
		(net "M_L_DQS_DN<10>")
	)
	(segment
		(start 44.555918 -141.0208)
		(end 44.733718 -140.843)
		(width 0.1651)
		(layer "B.Cu")
		(net "M_L_DQS_DN<10>")
	)
	(segment
		(start 44.513754 -140.292836)
		(end 44.286678 -140.292836)
		(width 0.1651)
		(layer "B.Cu")
		(net "M_L_DQS_DN<10>")
	)
	(segment
		(start 44.298362 -142.38986)
		(end 44.143422 -142.23492)
		(width 0.14224)
		(layer "In4.Cu")
		(net "M_L_DQS_DN<10>")
	)
	(segment
		(start 64.167258 -95.301308)
		(end 66.650616 -92.818204)
		(width 0.14224)
		(layer "In4.Cu")
		(net "M_L_DQS_DN<10>")
	)
	(segment
		(start 48.443642 -118.025926)
		(end 48.892968 -117.5766)
		(width 0.14224)
		(layer "In4.Cu")
		(net "M_L_DQS_DN<10>")
	)
	(segment
		(start 44.09948 -140.4874)
		(end 44.874434 -139.712446)
		(width 0.14224)
		(layer "In4.Cu")
		(net "M_L_DQS_DN<10>")
	)
	(segment
		(start 45.103288 -129.604008)
		(end 45.103288 -127.800608)
		(width 0.14224)
		(layer "In4.Cu")
		(net "M_L_DQS_DN<10>")
	)
	(segment
		(start 47.059088 -118.831614)
		(end 47.864776 -118.025926)
		(width 0.14224)
		(layer "In4.Cu")
		(net "M_L_DQS_DN<10>")
	)
	(segment
		(start 48.331882 -116.410486)
		(end 47.770288 -116.410486)
		(width 0.14224)
		(layer "In4.Cu")
		(net "M_L_DQS_DN<10>")
	)
	(segment
		(start 44.531788 -143.748506)
		(end 44.344082 -143.5608)
		(width 0.14224)
		(layer "In4.Cu")
		(net "M_L_DQS_DN<10>")
	)
	(segment
		(start 44.988734 -138.42873)
		(end 44.874434 -138.31443)
		(width 0.14224)
		(layer "In4.Cu")
		(net "M_L_DQS_DN<10>")
	)
	(segment
		(start 45.103288 -127.800608)
		(end 47.059088 -125.844808)
		(width 0.14224)
		(layer "In4.Cu")
		(net "M_L_DQS_DN<10>")
	)
	(segment
		(start 68.626736 -92.00007)
		(end 68.626736 -90.570558)
		(width 0.0889)
		(layer "In4.Cu")
		(net "M_L_DQS_DN<10>")
	)
	(segment
		(start 61.684408 -97.78365)
		(end 64.16675 -95.301308)
		(width 0.14224)
		(layer "In4.Cu")
		(net "M_L_DQS_DN<10>")
	)
	(segment
		(start 44.298362 -142.74292)
		(end 44.298362 -142.38986)
		(width 0.14224)
		(layer "In4.Cu")
		(net "M_L_DQS_DN<10>")
	)
	(segment
		(start 44.143422 -142.23492)
		(end 43.988482 -142.23492)
		(width 0.14224)
		(layer "In4.Cu")
		(net "M_L_DQS_DN<10>")
	)
	(segment
		(start 61.684408 -99.172776)
		(end 61.684408 -97.78365)
		(width 0.14224)
		(layer "In4.Cu")
		(net "M_L_DQS_DN<10>")
	)
	(segment
		(start 44.526962 -141.3256)
		(end 44.526962 -140.922248)
		(width 0.14224)
		(layer "In4.Cu")
		(net "M_L_DQS_DN<10>")
	)
	(segment
		(start 47.059088 -125.844808)
		(end 47.059088 -118.831614)
		(width 0.14224)
		(layer "In4.Cu")
		(net "M_L_DQS_DN<10>")
	)
	(segment
		(start 44.874434 -137.608056)
		(end 44.874434 -129.832862)
		(width 0.14224)
		(layer "In4.Cu")
		(net "M_L_DQS_DN<10>")
	)
	(segment
		(start 72.621902 -90.43035)
		(end 72.328786 -90.26144)
		(width 0.0889)
		(layer "In4.Cu")
		(net "M_L_DQS_DN<10>")
	)
	(segment
		(start 72.700642 -90.409014)
		(end 72.621902 -90.43035)
		(width 0.0889)
		(layer "In4.Cu")
		(net "M_L_DQS_DN<10>")
	)
	(segment
		(start 44.531788 -144.23263)
		(end 44.531788 -143.748506)
		(width 0.14224)
		(layer "In4.Cu")
		(net "M_L_DQS_DN<10>")
	)
	(segment
		(start 66.650616 -92.818204)
		(end 66.666364 -92.802456)
		(width 0.0889)
		(layer "In4.Cu")
		(net "M_L_DQS_DN<10>")
	)
	(segment
		(start 44.874434 -138.036808)
		(end 44.96181 -137.949432)
		(width 0.14224)
		(layer "In4.Cu")
		(net "M_L_DQS_DN<10>")
	)
	(segment
		(start 44.344082 -143.5608)
		(end 44.018962 -143.5608)
		(width 0.14224)
		(layer "In4.Cu")
		(net "M_L_DQS_DN<10>")
	)
	(segment
		(start 66.666364 -92.746576)
		(end 66.997072 -92.415614)
		(width 0.0889)
		(layer "In4.Cu")
		(net "M_L_DQS_DN<10>")
	)
	(segment
		(start 64.16675 -95.301308)
		(end 64.167258 -95.301308)
		(width 0.14224)
		(layer "In4.Cu")
		(net "M_L_DQS_DN<10>")
	)
	(segment
		(start 43.988482 -142.23492)
		(end 43.856402 -142.10284)
		(width 0.14224)
		(layer "In4.Cu")
		(net "M_L_DQS_DN<10>")
	)
	(segment
		(start 44.874434 -138.79703)
		(end 44.988734 -138.68273)
		(width 0.14224)
		(layer "In4.Cu")
		(net "M_L_DQS_DN<10>")
	)
	(segment
		(start 43.856402 -142.10284)
		(end 43.856402 -141.75486)
		(width 0.14224)
		(layer "In4.Cu")
		(net "M_L_DQS_DN<10>")
	)
	(segment
		(start 48.892968 -117.5766)
		(end 48.892968 -116.971572)
		(width 0.14224)
		(layer "In4.Cu")
		(net "M_L_DQS_DN<10>")
	)
	(segment
		(start 44.874434 -139.712446)
		(end 44.874434 -138.79703)
		(width 0.14224)
		(layer "In4.Cu")
		(net "M_L_DQS_DN<10>")
	)
	(segment
		(start 56.553608 -104.303576)
		(end 61.684408 -99.172776)
		(width 0.14224)
		(layer "In4.Cu")
		(net "M_L_DQS_DN<10>")
	)
	(segment
		(start 44.874434 -129.832862)
		(end 45.103288 -129.604008)
		(width 0.14224)
		(layer "In4.Cu")
		(net "M_L_DQS_DN<10>")
	)
	(segment
		(start 44.526962 -140.922248)
		(end 44.092114 -140.4874)
		(width 0.14224)
		(layer "In4.Cu")
		(net "M_L_DQS_DN<10>")
	)
	(segment
		(start 66.666364 -92.802456)
		(end 66.666364 -92.746576)
		(width 0.0889)
		(layer "In4.Cu")
		(net "M_L_DQS_DN<10>")
	)
	(segment
		(start 44.96181 -137.949432)
		(end 44.96181 -137.695432)
		(width 0.14224)
		(layer "In4.Cu")
		(net "M_L_DQS_DN<10>")
	)
	(segment
		(start 44.988734 -138.68273)
		(end 44.988734 -138.42873)
		(width 0.14224)
		(layer "In4.Cu")
		(net "M_L_DQS_DN<10>")
	)
	(segment
		(start 56.553608 -106.758232)
		(end 56.553608 -104.303576)
		(width 0.14224)
		(layer "In4.Cu")
		(net "M_L_DQS_DN<10>")
	)
	(segment
		(start 71.448676 -89.365836)
		(end 71.481442 -89.365836)
		(width 0.0889)
		(layer "In4.Cu")
		(net "M_L_DQS_DN<10>")
	)
	(segment
		(start 44.006262 -141.605)
		(end 44.247562 -141.605)
		(width 0.14224)
		(layer "In4.Cu")
		(net "M_L_DQS_DN<10>")
	)
	(segment
		(start 44.092114 -140.4874)
		(end 44.09948 -140.4874)
		(width 0.14224)
		(layer "In4.Cu")
		(net "M_L_DQS_DN<10>")
	)
	(segment
		(start 44.143422 -142.89786)
		(end 44.298362 -142.74292)
		(width 0.14224)
		(layer "In4.Cu")
		(net "M_L_DQS_DN<10>")
	)
	(segment
		(start 66.997072 -92.415614)
		(end 68.211192 -92.415614)
		(width 0.0889)
		(layer "In4.Cu")
		(net "M_L_DQS_DN<10>")
	)
	(segment
		(start 68.626736 -90.570558)
		(end 68.470272 -90.414094)
		(width 0.0889)
		(layer "In4.Cu")
		(net "M_L_DQS_DN<10>")
	)
	(segment
		(start 44.098718 -144.6657)
		(end 44.531788 -144.23263)
		(width 0.14224)
		(layer "In4.Cu")
		(net "M_L_DQS_DN<10>")
	)
	(segment
		(start 69.74205 -89.365836)
		(end 69.774816 -89.365836)
		(width 0.0889)
		(layer "In4.Cu")
		(net "M_L_DQS_DN<10>")
	)
	(segment
		(start 70.59676 -88.87079)
		(end 70.626732 -88.87079)
		(width 0.0889)
		(layer "In4.Cu")
		(net "M_L_DQS_DN<10>")
	)
	(segment
		(start 47.864776 -118.025926)
		(end 48.443642 -118.025926)
		(width 0.14224)
		(layer "In4.Cu")
		(net "M_L_DQS_DN<10>")
	)
	(segment
		(start 47.770288 -116.410486)
		(end 47.520352 -116.16055)
		(width 0.14224)
		(layer "In4.Cu")
		(net "M_L_DQS_DN<10>")
	)
	(segment
		(start 47.520352 -115.791488)
		(end 56.553608 -106.758232)
		(width 0.14224)
		(layer "In4.Cu")
		(net "M_L_DQS_DN<10>")
	)
	(segment
		(start 44.018962 -143.5608)
		(end 43.856402 -143.39824)
		(width 0.14224)
		(layer "In4.Cu")
		(net "M_L_DQS_DN<10>")
	)
	(segment
		(start 68.470272 -90.414094)
		(end 68.470272 -90.19667)
		(width 0.0889)
		(layer "In4.Cu")
		(net "M_L_DQS_DN<10>")
	)
	(segment
		(start 43.856402 -143.03756)
		(end 43.996102 -142.89786)
		(width 0.14224)
		(layer "In4.Cu")
		(net "M_L_DQS_DN<10>")
	)
	(segment
		(start 47.520352 -116.16055)
		(end 47.520352 -115.791488)
		(width 0.14224)
		(layer "In4.Cu")
		(net "M_L_DQS_DN<10>")
	)
	(segment
		(start 44.96181 -137.695432)
		(end 44.874434 -137.608056)
		(width 0.14224)
		(layer "In4.Cu")
		(net "M_L_DQS_DN<10>")
	)
	(segment
		(start 48.892968 -116.971572)
		(end 48.331882 -116.410486)
		(width 0.14224)
		(layer "In4.Cu")
		(net "M_L_DQS_DN<10>")
	)
	(segment
		(start 43.856402 -143.39824)
		(end 43.856402 -143.03756)
		(width 0.14224)
		(layer "In4.Cu")
		(net "M_L_DQS_DN<10>")
	)
	(segment
		(start 44.874434 -138.31443)
		(end 44.874434 -138.036808)
		(width 0.14224)
		(layer "In4.Cu")
		(net "M_L_DQS_DN<10>")
	)
	(segment
		(start 72.311006 -89.86139)
		(end 72.343772 -89.86139)
		(width 0.0889)
		(layer "In4.Cu")
		(net "M_L_DQS_DN<10>")
	)
	(segment
		(start 43.996102 -142.89786)
		(end 44.143422 -142.89786)
		(width 0.14224)
		(layer "In4.Cu")
		(net "M_L_DQS_DN<10>")
	)
	(segment
		(start 43.856402 -141.75486)
		(end 44.006262 -141.605)
		(width 0.14224)
		(layer "In4.Cu")
		(net "M_L_DQS_DN<10>")
	)
	(segment
		(start 68.470272 -90.19667)
		(end 68.547996 -90.061288)
		(width 0.0889)
		(layer "In4.Cu")
		(net "M_L_DQS_DN<10>")
	)
	(segment
		(start 68.87718 -89.86139)
		(end 68.912486 -89.86139)
		(width 0.0889)
		(layer "In4.Cu")
		(net "M_L_DQS_DN<10>")
	)
	(segment
		(start 44.247562 -141.605)
		(end 44.526962 -141.3256)
		(width 0.14224)
		(layer "In4.Cu")
		(net "M_L_DQS_DN<10>")
	)
	(segment
		(start 68.211192 -92.415614)
		(end 68.626736 -92.00007)
		(width 0.0889)
		(layer "In4.Cu")
		(net "M_L_DQS_DN<10>")
	)
	(arc
		(start 70.958456 -89.070688)
		(mid 71.16546 -89.281552)
		(end 71.448676 -89.365836)
		(width 0.0889)
		(layer "In4.Cu")
		(net "M_L_DQS_DN<10>")
	)
	(arc
		(start 69.406516 -89.565988)
		(mid 69.548199 -89.422184)
		(end 69.74205 -89.365836)
		(width 0.0889)
		(layer "In4.Cu")
		(net "M_L_DQS_DN<10>")
	)
	(arc
		(start 70.265036 -89.070688)
		(mid 70.405115 -88.927952)
		(end 70.59676 -88.87079)
		(width 0.0889)
		(layer "In4.Cu")
		(net "M_L_DQS_DN<10>")
	)
	(arc
		(start 70.626732 -88.87079)
		(mid 70.818374 -88.927956)
		(end 70.958456 -89.070688)
		(width 0.0889)
		(layer "In4.Cu")
		(net "M_L_DQS_DN<10>")
	)
	(arc
		(start 72.343772 -89.86139)
		(mid 72.663932 -90.042855)
		(end 72.700642 -90.409014)
		(width 0.0889)
		(layer "In4.Cu")
		(net "M_L_DQS_DN<10>")
	)
	(arc
		(start 68.547996 -90.061288)
		(mid 68.686989 -89.919208)
		(end 68.87718 -89.86139)
		(width 0.0889)
		(layer "In4.Cu")
		(net "M_L_DQS_DN<10>")
	)
	(arc
		(start 69.774816 -89.365836)
		(mid 70.058033 -89.281555)
		(end 70.265036 -89.070688)
		(width 0.0889)
		(layer "In4.Cu")
		(net "M_L_DQS_DN<10>")
	)
	(arc
		(start 68.912486 -89.86139)
		(mid 69.19791 -89.777923)
		(end 69.406516 -89.565988)
		(width 0.0889)
		(layer "In4.Cu")
		(net "M_L_DQS_DN<10>")
	)
	(arc
		(start 71.816976 -89.565988)
		(mid 72.025584 -89.77792)
		(end 72.311006 -89.86139)
		(width 0.0889)
		(layer "In4.Cu")
		(net "M_L_DQS_DN<10>")
	)
	(arc
		(start 71.481442 -89.365836)
		(mid 71.675292 -89.422186)
		(end 71.816976 -89.565988)
		(width 0.0889)
		(layer "In4.Cu")
		(net "M_L_DQS_DN<10>")
	)
	(segment
		(start 71.183246 -84.31784)
		(end 70.611746 -84.31784)
		(width 0.1651)
		(layer "F.Cu")
		(net "M_L_DQS_DN<0>")
	)
	(segment
		(start 35.267392 -145.821654)
		(end 35.267392 -145.389854)
		(width 0.1651)
		(layer "F.Cu")
		(net "M_L_DQS_DN<0>")
	)
	(segment
		(start 35.821874 -145.0594)
		(end 36.03752 -145.275046)
		(width 0.1651)
		(layer "F.Cu")
		(net "M_L_DQS_DN<0>")
	)
	(segment
		(start 35.597846 -145.0594)
		(end 35.821874 -145.0594)
		(width 0.1651)
		(layer "F.Cu")
		(net "M_L_DQS_DN<0>")
	)
	(segment
		(start 35.649408 -147.27174)
		(end 35.649408 -146.20367)
		(width 0.1651)
		(layer "F.Cu")
		(net "M_L_DQS_DN<0>")
	)
	(segment
		(start 35.649408 -146.20367)
		(end 35.267392 -145.821654)
		(width 0.1651)
		(layer "F.Cu")
		(net "M_L_DQS_DN<0>")
	)
	(segment
		(start 35.267392 -145.389854)
		(end 35.597846 -145.0594)
		(width 0.1651)
		(layer "F.Cu")
		(net "M_L_DQS_DN<0>")
	)
	(via
		(at 36.03752 -139.881356)
		(size 0.508)
		(drill 0.254)
		(layers "F.Cu" "B.Cu")
		(net "M_L_DQS_DN<0>")
	)
	(via
		(at 70.611746 -84.31784)
		(size 0.508)
		(drill 0.254)
		(layers "F.Cu" "B.Cu")
		(net "M_L_DQS_DN<0>")
	)
	(via
		(at 36.03752 -145.275046)
		(size 0.508)
		(drill 0.254)
		(layers "F.Cu" "B.Cu")
		(net "M_L_DQS_DN<0>")
	)
	(segment
		(start 35.649408 -138.78433)
		(end 35.521392 -138.912346)
		(width 0.1651)
		(layer "B.Cu")
		(net "M_L_DQS_DN<0>")
	)
	(segment
		(start 35.267392 -139.420346)
		(end 35.267392 -139.7508)
		(width 0.1651)
		(layer "B.Cu")
		(net "M_L_DQS_DN<0>")
	)
	(segment
		(start 35.521392 -138.912346)
		(end 35.521392 -139.166346)
		(width 0.1651)
		(layer "B.Cu")
		(net "M_L_DQS_DN<0>")
	)
	(segment
		(start 35.521392 -139.166346)
		(end 35.267392 -139.420346)
		(width 0.1651)
		(layer "B.Cu")
		(net "M_L_DQS_DN<0>")
	)
	(segment
		(start 35.622992 -140.1064)
		(end 35.812476 -140.1064)
		(width 0.1651)
		(layer "B.Cu")
		(net "M_L_DQS_DN<0>")
	)
	(segment
		(start 35.267392 -139.7508)
		(end 35.622992 -140.1064)
		(width 0.1651)
		(layer "B.Cu")
		(net "M_L_DQS_DN<0>")
	)
	(segment
		(start 35.649408 -137.877296)
		(end 35.649408 -138.78433)
		(width 0.1651)
		(layer "B.Cu")
		(net "M_L_DQS_DN<0>")
	)
	(segment
		(start 35.812476 -140.1064)
		(end 36.03752 -139.881356)
		(width 0.1651)
		(layer "B.Cu")
		(net "M_L_DQS_DN<0>")
	)
	(segment
		(start 36.5506 -134.09168)
		(end 36.39312 -133.9342)
		(width 0.14224)
		(layer "In4.Cu")
		(net "M_L_DQS_DN<0>")
	)
	(segment
		(start 36.5506 -133.26872)
		(end 36.39312 -133.11124)
		(width 0.14224)
		(layer "In4.Cu")
		(net "M_L_DQS_DN<0>")
	)
	(segment
		(start 42.98188 -109.68736)
		(end 43.828208 -109.68736)
		(width 0.14224)
		(layer "In4.Cu")
		(net "M_L_DQS_DN<0>")
	)
	(segment
		(start 37.061648 -121.85142)
		(end 36.84016 -121.629932)
		(width 0.14224)
		(layer "In4.Cu")
		(net "M_L_DQS_DN<0>")
	)
	(segment
		(start 35.915854 -121.629932)
		(end 35.537648 -121.251726)
		(width 0.14224)
		(layer "In4.Cu")
		(net "M_L_DQS_DN<0>")
	)
	(segment
		(start 38.844474 -113.824766)
		(end 42.98188 -109.68736)
		(width 0.14224)
		(layer "In4.Cu")
		(net "M_L_DQS_DN<0>")
	)
	(segment
		(start 36.881054 -124.92228)
		(end 37.061648 -124.741686)
		(width 0.14224)
		(layer "In4.Cu")
		(net "M_L_DQS_DN<0>")
	)
	(segment
		(start 38.844474 -114.663982)
		(end 38.844474 -113.824766)
		(width 0.14224)
		(layer "In4.Cu")
		(net "M_L_DQS_DN<0>")
	)
	(segment
		(start 36.301426 -128.929892)
		(end 36.078414 -128.929892)
		(width 0.14224)
		(layer "In4.Cu")
		(net "M_L_DQS_DN<0>")
	)
	(segment
		(start 36.39312 -133.11124)
		(end 36.39312 -132.85724)
		(width 0.14224)
		(layer "In4.Cu")
		(net "M_L_DQS_DN<0>")
	)
	(segment
		(start 36.39312 -133.9342)
		(end 36.39312 -133.6802)
		(width 0.14224)
		(layer "In4.Cu")
		(net "M_L_DQS_DN<0>")
	)
	(segment
		(start 56.097932 -93.683836)
		(end 64.201802 -85.579966)
		(width 0.14224)
		(layer "In4.Cu")
		(net "M_L_DQS_DN<0>")
	)
	(segment
		(start 36.5506 -134.440422)
		(end 36.5506 -134.09168)
		(width 0.14224)
		(layer "In4.Cu")
		(net "M_L_DQS_DN<0>")
	)
	(segment
		(start 36.39312 -138.5062)
		(end 36.5506 -138.34872)
		(width 0.14224)
		(layer "In4.Cu")
		(net "M_L_DQS_DN<0>")
	)
	(segment
		(start 36.4236 -135.870696)
		(end 36.5506 -135.743696)
		(width 0.14224)
		(layer "In4.Cu")
		(net "M_L_DQS_DN<0>")
	)
	(segment
		(start 36.5506 -137.27176)
		(end 36.39312 -137.11428)
		(width 0.14224)
		(layer "In4.Cu")
		(net "M_L_DQS_DN<0>")
	)
	(segment
		(start 36.5506 -129.179066)
		(end 36.301426 -128.929892)
		(width 0.14224)
		(layer "In4.Cu")
		(net "M_L_DQS_DN<0>")
	)
	(segment
		(start 36.426902 -134.81812)
		(end 36.426902 -134.56412)
		(width 0.14224)
		(layer "In4.Cu")
		(net "M_L_DQS_DN<0>")
	)
	(segment
		(start 69.735446 -84.222336)
		(end 70.057518 -84.222336)
		(width 0.0889)
		(layer "In4.Cu")
		(net "M_L_DQS_DN<0>")
	)
	(segment
		(start 35.8013 -122.503692)
		(end 36.84016 -122.503692)
		(width 0.14224)
		(layer "In4.Cu")
		(net "M_L_DQS_DN<0>")
	)
	(segment
		(start 36.84016 -121.629932)
		(end 35.915854 -121.629932)
		(width 0.14224)
		(layer "In4.Cu")
		(net "M_L_DQS_DN<0>")
	)
	(segment
		(start 35.436048 -128.064514)
		(end 35.436048 -125.300486)
		(width 0.14224)
		(layer "In4.Cu")
		(net "M_L_DQS_DN<0>")
	)
	(segment
		(start 64.929004 -85.619336)
		(end 66.240914 -85.619336)
		(width 0.0889)
		(layer "In4.Cu")
		(net "M_L_DQS_DN<0>")
	)
	(segment
		(start 36.28263 -139.881356)
		(end 36.5506 -139.613386)
		(width 0.14224)
		(layer "In4.Cu")
		(net "M_L_DQS_DN<0>")
	)
	(segment
		(start 36.39312 -138.7602)
		(end 36.39312 -138.5062)
		(width 0.14224)
		(layer "In4.Cu")
		(net "M_L_DQS_DN<0>")
	)
	(segment
		(start 35.964368 -139.881356)
		(end 35.60445 -140.241274)
		(width 0.14224)
		(layer "In4.Cu")
		(net "M_L_DQS_DN<0>")
	)
	(segment
		(start 36.5506 -134.941818)
		(end 36.426902 -134.81812)
		(width 0.14224)
		(layer "In4.Cu")
		(net "M_L_DQS_DN<0>")
	)
	(segment
		(start 64.201802 -85.579966)
		(end 64.867536 -85.579966)
		(width 0.14224)
		(layer "In4.Cu")
		(net "M_L_DQS_DN<0>")
	)
	(segment
		(start 36.84016 -122.503692)
		(end 37.061648 -122.282204)
		(width 0.14224)
		(layer "In4.Cu")
		(net "M_L_DQS_DN<0>")
	)
	(segment
		(start 56.097932 -97.417636)
		(end 56.097932 -93.683836)
		(width 0.14224)
		(layer "In4.Cu")
		(net "M_L_DQS_DN<0>")
	)
	(segment
		(start 68.873116 -84.71789)
		(end 68.905882 -84.71789)
		(width 0.0889)
		(layer "In4.Cu")
		(net "M_L_DQS_DN<0>")
	)
	(segment
		(start 35.537648 -121.251726)
		(end 35.537648 -120.595898)
		(width 0.14224)
		(layer "In4.Cu")
		(net "M_L_DQS_DN<0>")
	)
	(segment
		(start 36.03752 -139.881356)
		(end 35.964368 -139.881356)
		(width 0.14224)
		(layer "In4.Cu")
		(net "M_L_DQS_DN<0>")
	)
	(segment
		(start 36.39312 -136.86028)
		(end 36.5506 -136.7028)
		(width 0.14224)
		(layer "In4.Cu")
		(net "M_L_DQS_DN<0>")
	)
	(segment
		(start 64.867536 -85.579966)
		(end 64.889634 -85.579966)
		(width 0.0889)
		(layer "In4.Cu")
		(net "M_L_DQS_DN<0>")
	)
	(segment
		(start 43.828208 -109.68736)
		(end 56.097932 -97.417636)
		(width 0.14224)
		(layer "In4.Cu")
		(net "M_L_DQS_DN<0>")
	)
	(segment
		(start 36.5506 -138.91768)
		(end 36.39312 -138.7602)
		(width 0.14224)
		(layer "In4.Cu")
		(net "M_L_DQS_DN<0>")
	)
	(segment
		(start 35.787584 -123.915932)
		(end 35.416236 -123.544584)
		(width 0.14224)
		(layer "In4.Cu")
		(net "M_L_DQS_DN<0>")
	)
	(segment
		(start 36.84016 -123.915932)
		(end 35.787584 -123.915932)
		(width 0.14224)
		(layer "In4.Cu")
		(net "M_L_DQS_DN<0>")
	)
	(segment
		(start 35.898836 -128.527302)
		(end 35.436048 -128.064514)
		(width 0.14224)
		(layer "In4.Cu")
		(net "M_L_DQS_DN<0>")
	)
	(segment
		(start 66.330068 -85.70849)
		(end 67.192144 -85.70849)
		(width 0.0889)
		(layer "In4.Cu")
		(net "M_L_DQS_DN<0>")
	)
	(segment
		(start 35.915854 -120.217692)
		(end 36.84016 -120.217692)
		(width 0.14224)
		(layer "In4.Cu")
		(net "M_L_DQS_DN<0>")
	)
	(segment
		(start 37.061648 -119.996204)
		(end 37.061648 -119.052848)
		(width 0.14224)
		(layer "In4.Cu")
		(net "M_L_DQS_DN<0>")
	)
	(segment
		(start 35.39363 -141.71422)
		(end 35.39363 -143.37538)
		(width 0.14224)
		(layer "In4.Cu")
		(net "M_L_DQS_DN<0>")
	)
	(segment
		(start 36.5506 -131.8768)
		(end 36.5506 -129.179066)
		(width 0.14224)
		(layer "In4.Cu")
		(net "M_L_DQS_DN<0>")
	)
	(segment
		(start 70.057518 -84.222336)
		(end 70.611746 -84.31784)
		(width 0.0889)
		(layer "In4.Cu")
		(net "M_L_DQS_DN<0>")
	)
	(segment
		(start 36.39312 -137.68324)
		(end 36.5506 -137.52576)
		(width 0.14224)
		(layer "In4.Cu")
		(net "M_L_DQS_DN<0>")
	)
	(segment
		(start 36.5506 -138.34872)
		(end 36.5506 -138.09472)
		(width 0.14224)
		(layer "In4.Cu")
		(net "M_L_DQS_DN<0>")
	)
	(segment
		(start 35.436048 -125.300486)
		(end 35.814254 -124.92228)
		(width 0.14224)
		(layer "In4.Cu")
		(net "M_L_DQS_DN<0>")
	)
	(segment
		(start 36.39312 -137.11428)
		(end 36.39312 -136.86028)
		(width 0.14224)
		(layer "In4.Cu")
		(net "M_L_DQS_DN<0>")
	)
	(segment
		(start 37.061648 -122.282204)
		(end 37.061648 -121.85142)
		(width 0.14224)
		(layer "In4.Cu")
		(net "M_L_DQS_DN<0>")
	)
	(segment
		(start 36.84016 -120.217692)
		(end 37.061648 -119.996204)
		(width 0.14224)
		(layer "In4.Cu")
		(net "M_L_DQS_DN<0>")
	)
	(segment
		(start 36.39312 -132.03428)
		(end 36.5506 -131.8768)
		(width 0.14224)
		(layer "In4.Cu")
		(net "M_L_DQS_DN<0>")
	)
	(segment
		(start 35.60445 -141.5034)
		(end 35.39363 -141.71422)
		(width 0.14224)
		(layer "In4.Cu")
		(net "M_L_DQS_DN<0>")
	)
	(segment
		(start 36.39312 -132.85724)
		(end 36.5506 -132.69976)
		(width 0.14224)
		(layer "In4.Cu")
		(net "M_L_DQS_DN<0>")
	)
	(segment
		(start 36.5506 -137.52576)
		(end 36.5506 -137.27176)
		(width 0.14224)
		(layer "In4.Cu")
		(net "M_L_DQS_DN<0>")
	)
	(segment
		(start 68.018406 -85.212936)
		(end 68.051172 -85.212936)
		(width 0.0889)
		(layer "In4.Cu")
		(net "M_L_DQS_DN<0>")
	)
	(segment
		(start 36.078414 -128.929892)
		(end 35.898836 -128.750314)
		(width 0.14224)
		(layer "In4.Cu")
		(net "M_L_DQS_DN<0>")
	)
	(segment
		(start 35.39363 -143.37538)
		(end 35.60445 -143.5862)
		(width 0.14224)
		(layer "In4.Cu")
		(net "M_L_DQS_DN<0>")
	)
	(segment
		(start 36.5506 -139.613386)
		(end 36.5506 -138.91768)
		(width 0.14224)
		(layer "In4.Cu")
		(net "M_L_DQS_DN<0>")
	)
	(segment
		(start 35.60445 -140.241274)
		(end 35.60445 -141.5034)
		(width 0.14224)
		(layer "In4.Cu")
		(net "M_L_DQS_DN<0>")
	)
	(segment
		(start 36.308792 -117.199664)
		(end 38.844474 -114.663982)
		(width 0.14224)
		(layer "In4.Cu")
		(net "M_L_DQS_DN<0>")
	)
	(segment
		(start 36.4236 -136.124696)
		(end 36.4236 -135.870696)
		(width 0.14224)
		(layer "In4.Cu")
		(net "M_L_DQS_DN<0>")
	)
	(segment
		(start 37.061648 -124.13742)
		(end 36.84016 -123.915932)
		(width 0.14224)
		(layer "In4.Cu")
		(net "M_L_DQS_DN<0>")
	)
	(segment
		(start 36.5506 -132.69976)
		(end 36.5506 -132.44576)
		(width 0.14224)
		(layer "In4.Cu")
		(net "M_L_DQS_DN<0>")
	)
	(segment
		(start 36.5506 -133.52272)
		(end 36.5506 -133.26872)
		(width 0.14224)
		(layer "In4.Cu")
		(net "M_L_DQS_DN<0>")
	)
	(segment
		(start 64.889634 -85.579966)
		(end 64.929004 -85.619336)
		(width 0.0889)
		(layer "In4.Cu")
		(net "M_L_DQS_DN<0>")
	)
	(segment
		(start 37.061648 -124.741686)
		(end 37.061648 -124.13742)
		(width 0.14224)
		(layer "In4.Cu")
		(net "M_L_DQS_DN<0>")
	)
	(segment
		(start 36.426902 -134.56412)
		(end 36.5506 -134.440422)
		(width 0.14224)
		(layer "In4.Cu")
		(net "M_L_DQS_DN<0>")
	)
	(segment
		(start 36.39312 -133.6802)
		(end 36.5506 -133.52272)
		(width 0.14224)
		(layer "In4.Cu")
		(net "M_L_DQS_DN<0>")
	)
	(segment
		(start 35.416236 -123.544584)
		(end 35.416236 -122.888756)
		(width 0.14224)
		(layer "In4.Cu")
		(net "M_L_DQS_DN<0>")
	)
	(segment
		(start 36.5506 -135.743696)
		(end 36.5506 -134.941818)
		(width 0.14224)
		(layer "In4.Cu")
		(net "M_L_DQS_DN<0>")
	)
	(segment
		(start 35.898836 -128.750314)
		(end 35.898836 -128.527302)
		(width 0.14224)
		(layer "In4.Cu")
		(net "M_L_DQS_DN<0>")
	)
	(segment
		(start 35.60445 -144.841976)
		(end 36.03752 -145.275046)
		(width 0.14224)
		(layer "In4.Cu")
		(net "M_L_DQS_DN<0>")
	)
	(segment
		(start 36.39312 -137.93724)
		(end 36.39312 -137.68324)
		(width 0.14224)
		(layer "In4.Cu")
		(net "M_L_DQS_DN<0>")
	)
	(segment
		(start 66.240914 -85.619336)
		(end 66.330068 -85.70849)
		(width 0.0889)
		(layer "In4.Cu")
		(net "M_L_DQS_DN<0>")
	)
	(segment
		(start 36.5506 -136.251696)
		(end 36.4236 -136.124696)
		(width 0.14224)
		(layer "In4.Cu")
		(net "M_L_DQS_DN<0>")
	)
	(segment
		(start 35.60445 -143.5862)
		(end 35.60445 -144.841976)
		(width 0.14224)
		(layer "In4.Cu")
		(net "M_L_DQS_DN<0>")
	)
	(segment
		(start 35.416236 -122.888756)
		(end 35.8013 -122.503692)
		(width 0.14224)
		(layer "In4.Cu")
		(net "M_L_DQS_DN<0>")
	)
	(segment
		(start 36.39312 -132.28828)
		(end 36.39312 -132.03428)
		(width 0.14224)
		(layer "In4.Cu")
		(net "M_L_DQS_DN<0>")
	)
	(segment
		(start 36.5506 -136.7028)
		(end 36.5506 -136.251696)
		(width 0.14224)
		(layer "In4.Cu")
		(net "M_L_DQS_DN<0>")
	)
	(segment
		(start 37.061648 -119.052848)
		(end 36.308792 -118.299992)
		(width 0.14224)
		(layer "In4.Cu")
		(net "M_L_DQS_DN<0>")
	)
	(segment
		(start 36.308792 -118.299992)
		(end 36.308792 -117.199664)
		(width 0.14224)
		(layer "In4.Cu")
		(net "M_L_DQS_DN<0>")
	)
	(segment
		(start 36.03752 -139.881356)
		(end 36.28263 -139.881356)
		(width 0.14224)
		(layer "In4.Cu")
		(net "M_L_DQS_DN<0>")
	)
	(segment
		(start 36.5506 -132.44576)
		(end 36.39312 -132.28828)
		(width 0.14224)
		(layer "In4.Cu")
		(net "M_L_DQS_DN<0>")
	)
	(segment
		(start 35.814254 -124.92228)
		(end 36.881054 -124.92228)
		(width 0.14224)
		(layer "In4.Cu")
		(net "M_L_DQS_DN<0>")
	)
	(segment
		(start 36.5506 -138.09472)
		(end 36.39312 -137.93724)
		(width 0.14224)
		(layer "In4.Cu")
		(net "M_L_DQS_DN<0>")
	)
	(segment
		(start 35.537648 -120.595898)
		(end 35.915854 -120.217692)
		(width 0.14224)
		(layer "In4.Cu")
		(net "M_L_DQS_DN<0>")
	)
	(arc
		(start 69.241416 -84.517738)
		(mid 69.450024 -84.305806)
		(end 69.735446 -84.222336)
		(width 0.0889)
		(layer "In4.Cu")
		(net "M_L_DQS_DN<0>")
	)
	(arc
		(start 67.524376 -85.508338)
		(mid 67.732984 -85.296406)
		(end 68.018406 -85.212936)
		(width 0.0889)
		(layer "In4.Cu")
		(net "M_L_DQS_DN<0>")
	)
	(arc
		(start 68.382896 -85.013038)
		(mid 68.5899 -84.802174)
		(end 68.873116 -84.71789)
		(width 0.0889)
		(layer "In4.Cu")
		(net "M_L_DQS_DN<0>")
	)
	(arc
		(start 68.051172 -85.212936)
		(mid 68.242814 -85.15577)
		(end 68.382896 -85.013038)
		(width 0.0889)
		(layer "In4.Cu")
		(net "M_L_DQS_DN<0>")
	)
	(arc
		(start 67.192144 -85.70849)
		(mid 67.384161 -85.651382)
		(end 67.524376 -85.508338)
		(width 0.0889)
		(layer "In4.Cu")
		(net "M_L_DQS_DN<0>")
	)
	(arc
		(start 68.905882 -84.71789)
		(mid 69.099732 -84.66154)
		(end 69.241416 -84.517738)
		(width 0.0889)
		(layer "In4.Cu")
		(net "M_L_DQS_DN<0>")
	)
	(segment
		(start 72.041766 -88.775286)
		(end 71.470266 -88.775286)
		(width 0.1651)
		(layer "F.Cu")
		(net "M_L_DQ<9>")
	)
	(segment
		(start 42.449496 -142.6718)
		(end 42.449496 -143.941546)
		(width 0.1651)
		(layer "F.Cu")
		(net "M_L_DQ<9>")
	)
	(via
		(at 42.449496 -143.941546)
		(size 0.508)
		(drill 0.254)
		(layers "F.Cu" "B.Cu")
		(net "M_L_DQ<9>")
	)
	(via
		(at 71.470266 -88.775286)
		(size 0.508)
		(drill 0.254)
		(layers "F.Cu" "B.Cu")
		(net "M_L_DQ<9>")
	)
	(via
		(at 43.12158 -139.932156)
		(size 0.508)
		(drill 0.254)
		(layers "F.Cu" "B.Cu")
		(net "M_L_DQ<9>")
	)
	(segment
		(start 43.29938 -137.877296)
		(end 43.29938 -139.251182)
		(width 0.1651)
		(layer "B.Cu")
		(net "M_L_DQ<9>")
	)
	(segment
		(start 43.29938 -139.251182)
		(end 43.12158 -139.428982)
		(width 0.1651)
		(layer "B.Cu")
		(net "M_L_DQ<9>")
	)
	(segment
		(start 43.12158 -139.428982)
		(end 43.12158 -139.932156)
		(width 0.1651)
		(layer "B.Cu")
		(net "M_L_DQ<9>")
	)
	(segment
		(start 42.610786 -141.715744)
		(end 42.901362 -141.425168)
		(width 0.14224)
		(layer "In4.Cu")
		(net "M_L_DQ<9>")
	)
	(segment
		(start 43.764454 -129.10566)
		(end 44.092368 -129.10566)
		(width 0.14224)
		(layer "In4.Cu")
		(net "M_L_DQ<9>")
	)
	(segment
		(start 43.658028 -133.51129)
		(end 43.459908 -133.51129)
		(width 0.14224)
		(layer "In4.Cu")
		(net "M_L_DQ<9>")
	)
	(segment
		(start 54.596538 -107.63123)
		(end 54.596538 -106.79303)
		(width 0.14224)
		(layer "In4.Cu")
		(net "M_L_DQ<9>")
	)
	(segment
		(start 44.092368 -128.29286)
		(end 43.764454 -128.29286)
		(width 0.14224)
		(layer "In4.Cu")
		(net "M_L_DQ<9>")
	)
	(segment
		(start 46.911768 -117.628416)
		(end 47.114968 -117.425216)
		(width 0.14224)
		(layer "In4.Cu")
		(net "M_L_DQ<9>")
	)
	(segment
		(start 42.698416 -143.941546)
		(end 42.850562 -143.7894)
		(width 0.14224)
		(layer "In4.Cu")
		(net "M_L_DQ<9>")
	)
	(segment
		(start 43.459908 -133.51129)
		(end 43.304968 -133.35635)
		(width 0.14224)
		(layer "In4.Cu")
		(net "M_L_DQ<9>")
	)
	(segment
		(start 43.812968 -133.66623)
		(end 43.658028 -133.51129)
		(width 0.14224)
		(layer "In4.Cu")
		(net "M_L_DQ<9>")
	)
	(segment
		(start 43.609514 -129.2606)
		(end 43.764454 -129.10566)
		(width 0.14224)
		(layer "In4.Cu")
		(net "M_L_DQ<9>")
	)
	(segment
		(start 43.609514 -136.5758)
		(end 43.609514 -134.163054)
		(width 0.14224)
		(layer "In4.Cu")
		(net "M_L_DQ<9>")
	)
	(segment
		(start 43.099228 -139.932156)
		(end 43.12158 -139.932156)
		(width 0.14224)
		(layer "In4.Cu")
		(net "M_L_DQ<9>")
	)
	(segment
		(start 60.743338 -99.055682)
		(end 60.743338 -97.406206)
		(width 0.14224)
		(layer "In4.Cu")
		(net "M_L_DQ<9>")
	)
	(segment
		(start 43.609514 -134.163054)
		(end 43.812968 -133.9596)
		(width 0.14224)
		(layer "In4.Cu")
		(net "M_L_DQ<9>")
	)
	(segment
		(start 67.775836 -90.200226)
		(end 67.653154 -89.968832)
		(width 0.0889)
		(layer "In4.Cu")
		(net "M_L_DQ<9>")
	)
	(segment
		(start 54.836568 -106.553)
		(end 55.446168 -106.553)
		(width 0.14224)
		(layer "In4.Cu")
		(net "M_L_DQ<9>")
	)
	(segment
		(start 43.609514 -127.863854)
		(end 46.124368 -125.349)
		(width 0.14224)
		(layer "In4.Cu")
		(net "M_L_DQ<9>")
	)
	(segment
		(start 70.59676 -87.88019)
		(end 70.626732 -87.88019)
		(width 0.0889)
		(layer "In4.Cu")
		(net "M_L_DQ<9>")
	)
	(segment
		(start 42.901362 -141.425168)
		(end 42.901362 -141.020546)
		(width 0.14224)
		(layer "In4.Cu")
		(net "M_L_DQ<9>")
	)
	(segment
		(start 43.609514 -128.13792)
		(end 43.609514 -127.863854)
		(width 0.14224)
		(layer "In4.Cu")
		(net "M_L_DQ<9>")
	)
	(segment
		(start 46.124368 -116.612416)
		(end 46.124368 -116.1034)
		(width 0.14224)
		(layer "In4.Cu")
		(net "M_L_DQ<9>")
	)
	(segment
		(start 46.124368 -125.349)
		(end 46.124368 -117.831616)
		(width 0.14224)
		(layer "In4.Cu")
		(net "M_L_DQ<9>")
	)
	(segment
		(start 43.812968 -132.54355)
		(end 43.812968 -131.978654)
		(width 0.14224)
		(layer "In4.Cu")
		(net "M_L_DQ<9>")
	)
	(segment
		(start 54.723538 -105.8418)
		(end 54.596538 -105.7148)
		(width 0.14224)
		(layer "In4.Cu")
		(net "M_L_DQ<9>")
	)
	(segment
		(start 46.327568 -116.815616)
		(end 46.124368 -116.612416)
		(width 0.14224)
		(layer "In4.Cu")
		(net "M_L_DQ<9>")
	)
	(segment
		(start 43.736768 -138.7856)
		(end 43.736768 -138.342624)
		(width 0.14224)
		(layer "In4.Cu")
		(net "M_L_DQ<9>")
	)
	(segment
		(start 42.610786 -142.936976)
		(end 42.825162 -142.7226)
		(width 0.14224)
		(layer "In4.Cu")
		(net "M_L_DQ<9>")
	)
	(segment
		(start 47.114968 -117.425216)
		(end 47.114968 -117.018816)
		(width 0.14224)
		(layer "In4.Cu")
		(net "M_L_DQ<9>")
	)
	(segment
		(start 46.327568 -117.628416)
		(end 46.911768 -117.628416)
		(width 0.14224)
		(layer "In4.Cu")
		(net "M_L_DQ<9>")
	)
	(segment
		(start 67.350132 -91.183206)
		(end 67.775836 -90.757502)
		(width 0.0889)
		(layer "In4.Cu")
		(net "M_L_DQ<9>")
	)
	(segment
		(start 43.812968 -131.978654)
		(end 43.609514 -131.7752)
		(width 0.14224)
		(layer "In4.Cu")
		(net "M_L_DQ<9>")
	)
	(segment
		(start 67.775836 -90.757502)
		(end 67.775836 -90.200226)
		(width 0.0889)
		(layer "In4.Cu")
		(net "M_L_DQ<9>")
	)
	(segment
		(start 60.743338 -97.406206)
		(end 66.088768 -92.060776)
		(width 0.14224)
		(layer "In4.Cu")
		(net "M_L_DQ<9>")
	)
	(segment
		(start 42.825162 -142.2908)
		(end 42.610786 -142.076424)
		(width 0.14224)
		(layer "In4.Cu")
		(net "M_L_DQ<9>")
	)
	(segment
		(start 42.850562 -143.7894)
		(end 42.850562 -143.4846)
		(width 0.14224)
		(layer "In4.Cu")
		(net "M_L_DQ<9>")
	)
	(segment
		(start 44.219368 -128.97866)
		(end 44.219368 -128.41986)
		(width 0.14224)
		(layer "In4.Cu")
		(net "M_L_DQ<9>")
	)
	(segment
		(start 70.97522 -88.109552)
		(end 71.470266 -88.775286)
		(width 0.0889)
		(layer "In4.Cu")
		(net "M_L_DQ<9>")
	)
	(segment
		(start 55.674768 -106.0196)
		(end 55.496968 -105.8418)
		(width 0.14224)
		(layer "In4.Cu")
		(net "M_L_DQ<9>")
	)
	(segment
		(start 66.715132 -91.183206)
		(end 67.350132 -91.183206)
		(width 0.0889)
		(layer "In4.Cu")
		(net "M_L_DQ<9>")
	)
	(segment
		(start 47.114968 -117.018816)
		(end 46.911768 -116.815616)
		(width 0.14224)
		(layer "In4.Cu")
		(net "M_L_DQ<9>")
	)
	(segment
		(start 43.609514 -131.7752)
		(end 43.609514 -129.2606)
		(width 0.14224)
		(layer "In4.Cu")
		(net "M_L_DQ<9>")
	)
	(segment
		(start 66.088768 -92.060776)
		(end 66.088768 -91.80957)
		(width 0.0889)
		(layer "In4.Cu")
		(net "M_L_DQ<9>")
	)
	(segment
		(start 70.958456 -88.080088)
		(end 70.97522 -88.109552)
		(width 0.0889)
		(layer "In4.Cu")
		(net "M_L_DQ<9>")
	)
	(segment
		(start 42.850562 -143.4846)
		(end 42.610786 -143.244824)
		(width 0.14224)
		(layer "In4.Cu")
		(net "M_L_DQ<9>")
	)
	(segment
		(start 68.87972 -88.87079)
		(end 68.912486 -88.87079)
		(width 0.0889)
		(layer "In4.Cu")
		(net "M_L_DQ<9>")
	)
	(segment
		(start 42.901362 -141.020546)
		(end 42.670984 -140.790168)
		(width 0.14224)
		(layer "In4.Cu")
		(net "M_L_DQ<9>")
	)
	(segment
		(start 42.610786 -143.244824)
		(end 42.610786 -142.936976)
		(width 0.14224)
		(layer "In4.Cu")
		(net "M_L_DQ<9>")
	)
	(segment
		(start 42.825162 -142.7226)
		(end 42.825162 -142.2908)
		(width 0.14224)
		(layer "In4.Cu")
		(net "M_L_DQ<9>")
	)
	(segment
		(start 43.736768 -138.342624)
		(end 43.406568 -138.012424)
		(width 0.14224)
		(layer "In4.Cu")
		(net "M_L_DQ<9>")
	)
	(segment
		(start 43.764454 -128.29286)
		(end 43.609514 -128.13792)
		(width 0.14224)
		(layer "In4.Cu")
		(net "M_L_DQ<9>")
	)
	(segment
		(start 43.812968 -133.9596)
		(end 43.812968 -133.66623)
		(width 0.14224)
		(layer "In4.Cu")
		(net "M_L_DQ<9>")
	)
	(segment
		(start 54.596538 -105.202482)
		(end 60.743338 -99.055682)
		(width 0.14224)
		(layer "In4.Cu")
		(net "M_L_DQ<9>")
	)
	(segment
		(start 43.304968 -133.35635)
		(end 43.304968 -132.85343)
		(width 0.14224)
		(layer "In4.Cu")
		(net "M_L_DQ<9>")
	)
	(segment
		(start 46.911768 -116.815616)
		(end 46.327568 -116.815616)
		(width 0.14224)
		(layer "In4.Cu")
		(net "M_L_DQ<9>")
	)
	(segment
		(start 66.088768 -91.80957)
		(end 66.715132 -91.183206)
		(width 0.0889)
		(layer "In4.Cu")
		(net "M_L_DQ<9>")
	)
	(segment
		(start 54.596538 -105.7148)
		(end 54.596538 -105.202482)
		(width 0.14224)
		(layer "In4.Cu")
		(net "M_L_DQ<9>")
	)
	(segment
		(start 42.670984 -140.3604)
		(end 43.099228 -139.932156)
		(width 0.14224)
		(layer "In4.Cu")
		(net "M_L_DQ<9>")
	)
	(segment
		(start 55.674768 -106.3244)
		(end 55.674768 -106.0196)
		(width 0.14224)
		(layer "In4.Cu")
		(net "M_L_DQ<9>")
	)
	(segment
		(start 69.74205 -88.375236)
		(end 69.774816 -88.375236)
		(width 0.0889)
		(layer "In4.Cu")
		(net "M_L_DQ<9>")
	)
	(segment
		(start 42.670984 -140.790168)
		(end 42.670984 -140.3604)
		(width 0.14224)
		(layer "In4.Cu")
		(net "M_L_DQ<9>")
	)
	(segment
		(start 43.459908 -132.69849)
		(end 43.658028 -132.69849)
		(width 0.14224)
		(layer "In4.Cu")
		(net "M_L_DQ<9>")
	)
	(segment
		(start 43.406568 -137.606024)
		(end 43.736768 -137.275824)
		(width 0.14224)
		(layer "In4.Cu")
		(net "M_L_DQ<9>")
	)
	(segment
		(start 67.869816 -89.365836)
		(end 68.057776 -89.365836)
		(width 0.0889)
		(layer "In4.Cu")
		(net "M_L_DQ<9>")
	)
	(segment
		(start 43.12158 -139.932156)
		(end 43.12158 -139.843256)
		(width 0.14224)
		(layer "In4.Cu")
		(net "M_L_DQ<9>")
	)
	(segment
		(start 43.609514 -139.355322)
		(end 43.609514 -138.912854)
		(width 0.14224)
		(layer "In4.Cu")
		(net "M_L_DQ<9>")
	)
	(segment
		(start 43.736768 -136.703054)
		(end 43.609514 -136.5758)
		(width 0.14224)
		(layer "In4.Cu")
		(net "M_L_DQ<9>")
	)
	(segment
		(start 43.658028 -132.69849)
		(end 43.812968 -132.54355)
		(width 0.14224)
		(layer "In4.Cu")
		(net "M_L_DQ<9>")
	)
	(segment
		(start 55.446168 -106.553)
		(end 55.674768 -106.3244)
		(width 0.14224)
		(layer "In4.Cu")
		(net "M_L_DQ<9>")
	)
	(segment
		(start 42.449496 -143.941546)
		(end 42.698416 -143.941546)
		(width 0.14224)
		(layer "In4.Cu")
		(net "M_L_DQ<9>")
	)
	(segment
		(start 43.406568 -138.012424)
		(end 43.406568 -137.606024)
		(width 0.14224)
		(layer "In4.Cu")
		(net "M_L_DQ<9>")
	)
	(segment
		(start 43.736768 -137.275824)
		(end 43.736768 -136.703054)
		(width 0.14224)
		(layer "In4.Cu")
		(net "M_L_DQ<9>")
	)
	(segment
		(start 46.124368 -116.1034)
		(end 54.596538 -107.63123)
		(width 0.14224)
		(layer "In4.Cu")
		(net "M_L_DQ<9>")
	)
	(segment
		(start 46.124368 -117.831616)
		(end 46.327568 -117.628416)
		(width 0.14224)
		(layer "In4.Cu")
		(net "M_L_DQ<9>")
	)
	(segment
		(start 44.219368 -128.41986)
		(end 44.092368 -128.29286)
		(width 0.14224)
		(layer "In4.Cu")
		(net "M_L_DQ<9>")
	)
	(segment
		(start 43.304968 -132.85343)
		(end 43.459908 -132.69849)
		(width 0.14224)
		(layer "In4.Cu")
		(net "M_L_DQ<9>")
	)
	(segment
		(start 44.092368 -129.10566)
		(end 44.219368 -128.97866)
		(width 0.14224)
		(layer "In4.Cu")
		(net "M_L_DQ<9>")
	)
	(segment
		(start 42.610786 -142.076424)
		(end 42.610786 -141.715744)
		(width 0.14224)
		(layer "In4.Cu")
		(net "M_L_DQ<9>")
	)
	(segment
		(start 54.596538 -106.79303)
		(end 54.836568 -106.553)
		(width 0.14224)
		(layer "In4.Cu")
		(net "M_L_DQ<9>")
	)
	(segment
		(start 43.609514 -138.912854)
		(end 43.736768 -138.7856)
		(width 0.14224)
		(layer "In4.Cu")
		(net "M_L_DQ<9>")
	)
	(segment
		(start 55.496968 -105.8418)
		(end 54.723538 -105.8418)
		(width 0.14224)
		(layer "In4.Cu")
		(net "M_L_DQ<9>")
	)
	(segment
		(start 43.12158 -139.843256)
		(end 43.609514 -139.355322)
		(width 0.14224)
		(layer "In4.Cu")
		(net "M_L_DQ<9>")
	)
	(arc
		(start 67.653154 -89.968832)
		(mid 67.628213 -89.619399)
		(end 67.869816 -89.365836)
		(width 0.0889)
		(layer "In4.Cu")
		(net "M_L_DQ<9>")
	)
	(arc
		(start 68.547996 -89.070688)
		(mid 68.688075 -88.927952)
		(end 68.87972 -88.87079)
		(width 0.0889)
		(layer "In4.Cu")
		(net "M_L_DQ<9>")
	)
	(arc
		(start 70.626732 -87.88019)
		(mid 70.818374 -87.937356)
		(end 70.958456 -88.080088)
		(width 0.0889)
		(layer "In4.Cu")
		(net "M_L_DQ<9>")
	)
	(arc
		(start 68.057776 -89.365836)
		(mid 68.340993 -89.281555)
		(end 68.547996 -89.070688)
		(width 0.0889)
		(layer "In4.Cu")
		(net "M_L_DQ<9>")
	)
	(arc
		(start 69.406516 -88.575388)
		(mid 69.548199 -88.431584)
		(end 69.74205 -88.375236)
		(width 0.0889)
		(layer "In4.Cu")
		(net "M_L_DQ<9>")
	)
	(arc
		(start 69.774816 -88.375236)
		(mid 70.058033 -88.290955)
		(end 70.265036 -88.080088)
		(width 0.0889)
		(layer "In4.Cu")
		(net "M_L_DQ<9>")
	)
	(arc
		(start 68.912486 -88.87079)
		(mid 69.19791 -88.787323)
		(end 69.406516 -88.575388)
		(width 0.0889)
		(layer "In4.Cu")
		(net "M_L_DQ<9>")
	)
	(arc
		(start 70.265036 -88.080088)
		(mid 70.405115 -87.937352)
		(end 70.59676 -87.88019)
		(width 0.0889)
		(layer "In4.Cu")
		(net "M_L_DQ<9>")
	)
	(segment
		(start 73.758806 -89.765886)
		(end 73.187306 -89.765886)
		(width 0.1651)
		(layer "F.Cu")
		(net "M_L_DQ<8>")
	)
	(segment
		(start 43.29938 -147.277582)
		(end 43.12158 -145.415)
		(width 0.1651)
		(layer "F.Cu")
		(net "M_L_DQ<8>")
	)
	(segment
		(start 43.29938 -147.27174)
		(end 43.29938 -147.277582)
		(width 0.1651)
		(layer "F.Cu")
		(net "M_L_DQ<8>")
	)
	(via
		(at 42.449496 -141.213078)
		(size 0.508)
		(drill 0.254)
		(layers "F.Cu" "B.Cu")
		(net "M_L_DQ<8>")
	)
	(via
		(at 43.12158 -145.415)
		(size 0.508)
		(drill 0.254)
		(layers "F.Cu" "B.Cu")
		(net "M_L_DQ<8>")
	)
	(via
		(at 73.187306 -89.765886)
		(size 0.508)
		(drill 0.254)
		(layers "F.Cu" "B.Cu")
		(net "M_L_DQ<8>")
	)
	(segment
		(start 42.449496 -142.477236)
		(end 42.449496 -141.213078)
		(width 0.1651)
		(layer "B.Cu")
		(net "M_L_DQ<8>")
	)
	(segment
		(start 42.016426 -144.60601)
		(end 42.016426 -141.646148)
		(width 0.14224)
		(layer "In4.Cu")
		(net "M_L_DQ<8>")
	)
	(segment
		(start 42.085514 -140.849096)
		(end 42.085514 -140.209778)
		(width 0.14224)
		(layer "In4.Cu")
		(net "M_L_DQ<8>")
	)
	(segment
		(start 65.648586 -91.602814)
		(end 66.026792 -91.602814)
		(width 0.0889)
		(layer "In4.Cu")
		(net "M_L_DQ<8>")
	)
	(segment
		(start 42.923714 -134.484618)
		(end 42.923714 -134.137146)
		(width 0.14224)
		(layer "In4.Cu")
		(net "M_L_DQ<8>")
	)
	(segment
		(start 72.675496 -89.070688)
		(end 72.69226 -89.100152)
		(width 0.0889)
		(layer "In4.Cu")
		(net "M_L_DQ<8>")
	)
	(segment
		(start 66.026792 -91.602814)
		(end 66.636392 -90.993214)
		(width 0.0889)
		(layer "In4.Cu")
		(net "M_L_DQ<8>")
	)
	(segment
		(start 72.69226 -89.100152)
		(end 73.187306 -89.765886)
		(width 0.0889)
		(layer "In4.Cu")
		(net "M_L_DQ<8>")
	)
	(segment
		(start 42.936414 -136.258046)
		(end 42.626788 -135.94842)
		(width 0.14224)
		(layer "In4.Cu")
		(net "M_L_DQ<8>")
	)
	(segment
		(start 67.271392 -90.993214)
		(end 67.585844 -90.678762)
		(width 0.0889)
		(layer "In4.Cu")
		(net "M_L_DQ<8>")
	)
	(segment
		(start 43.12158 -145.415)
		(end 42.825416 -145.415)
		(width 0.14224)
		(layer "In4.Cu")
		(net "M_L_DQ<8>")
	)
	(segment
		(start 54.117748 -106.28122)
		(end 54.117748 -105.004108)
		(width 0.14224)
		(layer "In4.Cu")
		(net "M_L_DQ<8>")
	)
	(segment
		(start 68.873116 -88.68029)
		(end 68.905882 -88.68029)
		(width 0.0889)
		(layer "In4.Cu")
		(net "M_L_DQ<8>")
	)
	(segment
		(start 42.873168 -136.715246)
		(end 42.936414 -136.652)
		(width 0.14224)
		(layer "In4.Cu")
		(net "M_L_DQ<8>")
	)
	(segment
		(start 42.873168 -131.978146)
		(end 42.923968 -131.927346)
		(width 0.14224)
		(layer "In4.Cu")
		(net "M_L_DQ<8>")
	)
	(segment
		(start 42.085514 -140.209778)
		(end 42.936414 -139.358878)
		(width 0.14224)
		(layer "In4.Cu")
		(net "M_L_DQ<8>")
	)
	(segment
		(start 54.117748 -105.004108)
		(end 60.264548 -98.857308)
		(width 0.14224)
		(layer "In4.Cu")
		(net "M_L_DQ<8>")
	)
	(segment
		(start 42.936414 -139.358878)
		(end 42.936414 -138.975846)
		(width 0.14224)
		(layer "In4.Cu")
		(net "M_L_DQ<8>")
	)
	(segment
		(start 72.311006 -88.87079)
		(end 72.343772 -88.87079)
		(width 0.0889)
		(layer "In4.Cu")
		(net "M_L_DQ<8>")
	)
	(segment
		(start 45.713904 -117.343936)
		(end 45.713904 -117.100096)
		(width 0.14224)
		(layer "In4.Cu")
		(net "M_L_DQ<8>")
	)
	(segment
		(start 42.873168 -138.9126)
		(end 42.873168 -136.715246)
		(width 0.14224)
		(layer "In4.Cu")
		(net "M_L_DQ<8>")
	)
	(segment
		(start 42.626788 -134.781544)
		(end 42.923714 -134.484618)
		(width 0.14224)
		(layer "In4.Cu")
		(net "M_L_DQ<8>")
	)
	(segment
		(start 43.138344 -129.503424)
		(end 43.138344 -127.446024)
		(width 0.14224)
		(layer "In4.Cu")
		(net "M_L_DQ<8>")
	)
	(segment
		(start 45.489368 -114.9096)
		(end 54.117748 -106.28122)
		(width 0.14224)
		(layer "In4.Cu")
		(net "M_L_DQ<8>")
	)
	(segment
		(start 42.449496 -141.213078)
		(end 42.085514 -140.849096)
		(width 0.14224)
		(layer "In4.Cu")
		(net "M_L_DQ<8>")
	)
	(segment
		(start 45.489368 -117.568472)
		(end 45.713904 -117.343936)
		(width 0.14224)
		(layer "In4.Cu")
		(net "M_L_DQ<8>")
	)
	(segment
		(start 45.489368 -116.87556)
		(end 45.489368 -114.9096)
		(width 0.14224)
		(layer "In4.Cu")
		(net "M_L_DQ<8>")
	)
	(segment
		(start 67.833494 -89.175336)
		(end 68.051172 -89.175336)
		(width 0.0889)
		(layer "In4.Cu")
		(net "M_L_DQ<8>")
	)
	(segment
		(start 42.923714 -134.137146)
		(end 42.873168 -134.0866)
		(width 0.14224)
		(layer "In4.Cu")
		(net "M_L_DQ<8>")
	)
	(segment
		(start 71.45528 -88.184736)
		(end 71.470266 -88.184736)
		(width 0.0889)
		(layer "In4.Cu")
		(net "M_L_DQ<8>")
	)
	(segment
		(start 67.585844 -90.678762)
		(end 67.585844 -90.247978)
		(width 0.0889)
		(layer "In4.Cu")
		(net "M_L_DQ<8>")
	)
	(segment
		(start 42.873168 -134.0866)
		(end 42.873168 -131.978146)
		(width 0.14224)
		(layer "In4.Cu")
		(net "M_L_DQ<8>")
	)
	(segment
		(start 70.590156 -87.68969)
		(end 70.633336 -87.68969)
		(width 0.0889)
		(layer "In4.Cu")
		(net "M_L_DQ<8>")
	)
	(segment
		(start 60.264548 -96.986852)
		(end 65.648586 -91.602814)
		(width 0.14224)
		(layer "In4.Cu")
		(net "M_L_DQ<8>")
	)
	(segment
		(start 71.652384 -88.289892)
		(end 71.816976 -88.575388)
		(width 0.0889)
		(layer "In4.Cu")
		(net "M_L_DQ<8>")
	)
	(segment
		(start 42.923968 -131.927346)
		(end 42.923968 -131.434332)
		(width 0.14224)
		(layer "In4.Cu")
		(net "M_L_DQ<8>")
	)
	(segment
		(start 42.631614 -131.141978)
		(end 42.631614 -130.010154)
		(width 0.14224)
		(layer "In4.Cu")
		(net "M_L_DQ<8>")
	)
	(segment
		(start 67.585844 -90.247978)
		(end 67.484498 -90.058494)
		(width 0.0889)
		(layer "In4.Cu")
		(net "M_L_DQ<8>")
	)
	(segment
		(start 42.016426 -141.646148)
		(end 42.449496 -141.213078)
		(width 0.14224)
		(layer "In4.Cu")
		(net "M_L_DQ<8>")
	)
	(segment
		(start 43.138344 -127.446024)
		(end 45.489368 -125.095)
		(width 0.14224)
		(layer "In4.Cu")
		(net "M_L_DQ<8>")
	)
	(segment
		(start 42.825416 -145.415)
		(end 42.016426 -144.60601)
		(width 0.14224)
		(layer "In4.Cu")
		(net "M_L_DQ<8>")
	)
	(segment
		(start 60.264548 -98.857308)
		(end 60.264548 -96.986852)
		(width 0.14224)
		(layer "In4.Cu")
		(net "M_L_DQ<8>")
	)
	(segment
		(start 45.489368 -125.095)
		(end 45.489368 -117.568472)
		(width 0.14224)
		(layer "In4.Cu")
		(net "M_L_DQ<8>")
	)
	(segment
		(start 42.936414 -138.975846)
		(end 42.873168 -138.9126)
		(width 0.14224)
		(layer "In4.Cu")
		(net "M_L_DQ<8>")
	)
	(segment
		(start 45.713904 -117.100096)
		(end 45.489368 -116.87556)
		(width 0.14224)
		(layer "In4.Cu")
		(net "M_L_DQ<8>")
	)
	(segment
		(start 42.631614 -130.010154)
		(end 43.138344 -129.503424)
		(width 0.14224)
		(layer "In4.Cu")
		(net "M_L_DQ<8>")
	)
	(segment
		(start 42.923968 -131.434332)
		(end 42.631614 -131.141978)
		(width 0.14224)
		(layer "In4.Cu")
		(net "M_L_DQ<8>")
	)
	(segment
		(start 66.636392 -90.993214)
		(end 67.271392 -90.993214)
		(width 0.0889)
		(layer "In4.Cu")
		(net "M_L_DQ<8>")
	)
	(segment
		(start 42.626788 -135.94842)
		(end 42.626788 -134.781544)
		(width 0.14224)
		(layer "In4.Cu")
		(net "M_L_DQ<8>")
	)
	(segment
		(start 69.735446 -88.184736)
		(end 69.768212 -88.184736)
		(width 0.0889)
		(layer "In4.Cu")
		(net "M_L_DQ<8>")
	)
	(segment
		(start 42.936414 -136.652)
		(end 42.936414 -136.258046)
		(width 0.14224)
		(layer "In4.Cu")
		(net "M_L_DQ<8>")
	)
	(arc
		(start 68.905882 -88.68029)
		(mid 69.099732 -88.62394)
		(end 69.241416 -88.480138)
		(width 0.0889)
		(layer "In4.Cu")
		(net "M_L_DQ<8>")
	)
	(arc
		(start 70.099936 -87.984838)
		(mid 70.30694 -87.773974)
		(end 70.590156 -87.68969)
		(width 0.0889)
		(layer "In4.Cu")
		(net "M_L_DQ<8>")
	)
	(arc
		(start 69.768212 -88.184736)
		(mid 69.959854 -88.12757)
		(end 70.099936 -87.984838)
		(width 0.0889)
		(layer "In4.Cu")
		(net "M_L_DQ<8>")
	)
	(arc
		(start 68.051172 -89.175336)
		(mid 68.242814 -89.11817)
		(end 68.382896 -88.975438)
		(width 0.0889)
		(layer "In4.Cu")
		(net "M_L_DQ<8>")
	)
	(arc
		(start 69.241416 -88.480138)
		(mid 69.450024 -88.268206)
		(end 69.735446 -88.184736)
		(width 0.0889)
		(layer "In4.Cu")
		(net "M_L_DQ<8>")
	)
	(arc
		(start 71.123556 -87.984838)
		(mid 71.263635 -88.127574)
		(end 71.45528 -88.184736)
		(width 0.0889)
		(layer "In4.Cu")
		(net "M_L_DQ<8>")
	)
	(arc
		(start 71.816976 -88.575388)
		(mid 72.025584 -88.78732)
		(end 72.311006 -88.87079)
		(width 0.0889)
		(layer "In4.Cu")
		(net "M_L_DQ<8>")
	)
	(arc
		(start 72.343772 -88.87079)
		(mid 72.535414 -88.927956)
		(end 72.675496 -89.070688)
		(width 0.0889)
		(layer "In4.Cu")
		(net "M_L_DQ<8>")
	)
	(arc
		(start 71.470266 -88.184736)
		(mid 71.575418 -88.21291)
		(end 71.652384 -88.289892)
		(width 0.0889)
		(layer "In4.Cu")
		(net "M_L_DQ<8>")
	)
	(arc
		(start 67.484498 -90.058494)
		(mid 67.455387 -89.536426)
		(end 67.833494 -89.175336)
		(width 0.0889)
		(layer "In4.Cu")
		(net "M_L_DQ<8>")
	)
	(arc
		(start 68.382896 -88.975438)
		(mid 68.5899 -88.764574)
		(end 68.873116 -88.68029)
		(width 0.0889)
		(layer "In4.Cu")
		(net "M_L_DQ<8>")
	)
	(arc
		(start 70.633336 -87.68969)
		(mid 70.916553 -87.773971)
		(end 71.123556 -87.984838)
		(width 0.0889)
		(layer "In4.Cu")
		(net "M_L_DQ<8>")
	)
	(segment
		(start 37.34943 -142.6718)
		(end 37.34943 -143.941546)
		(width 0.1651)
		(layer "F.Cu")
		(net "M_L_DQ<7>")
	)
	(segment
		(start 71.183246 -85.30844)
		(end 70.611746 -85.30844)
		(width 0.1651)
		(layer "F.Cu")
		(net "M_L_DQ<7>")
	)
	(via
		(at 38.199314 -139.932156)
		(size 0.508)
		(drill 0.254)
		(layers "F.Cu" "B.Cu")
		(net "M_L_DQ<7>")
	)
	(via
		(at 70.611746 -85.30844)
		(size 0.508)
		(drill 0.254)
		(layers "F.Cu" "B.Cu")
		(net "M_L_DQ<7>")
	)
	(via
		(at 37.34943 -143.941546)
		(size 0.508)
		(drill 0.254)
		(layers "F.Cu" "B.Cu")
		(net "M_L_DQ<7>")
	)
	(segment
		(start 38.199568 -137.877296)
		(end 38.199314 -137.877296)
		(width 0.1651)
		(layer "B.Cu")
		(net "M_L_DQ<7>")
	)
	(segment
		(start 38.199314 -137.877296)
		(end 38.199314 -139.932156)
		(width 0.1651)
		(layer "B.Cu")
		(net "M_L_DQ<7>")
	)
	(segment
		(start 37.767768 -142.621)
		(end 37.767768 -142.3162)
		(width 0.14224)
		(layer "In4.Cu")
		(net "M_L_DQ<7>")
	)
	(segment
		(start 69.74205 -85.403436)
		(end 69.79031 -85.403436)
		(width 0.0889)
		(layer "In4.Cu")
		(net "M_L_DQ<7>")
	)
	(segment
		(start 40.292528 -117.85854)
		(end 38.799008 -117.85854)
		(width 0.14224)
		(layer "In4.Cu")
		(net "M_L_DQ<7>")
	)
	(segment
		(start 40.292528 -119.15902)
		(end 38.799008 -119.15902)
		(width 0.14224)
		(layer "In4.Cu")
		(net "M_L_DQ<7>")
	)
	(segment
		(start 37.51072 -143.151352)
		(end 37.51072 -142.878048)
		(width 0.14224)
		(layer "In4.Cu")
		(net "M_L_DQ<7>")
	)
	(segment
		(start 38.55212 -136.572752)
		(end 38.55212 -136.248394)
		(width 0.14224)
		(layer "In4.Cu")
		(net "M_L_DQ<7>")
	)
	(segment
		(start 40.292528 -122.41022)
		(end 40.434768 -122.26798)
		(width 0.14224)
		(layer "In4.Cu")
		(net "M_L_DQ<7>")
	)
	(segment
		(start 38.721284 -136.07923)
		(end 38.721284 -134.683246)
		(width 0.14224)
		(layer "In4.Cu")
		(net "M_L_DQ<7>")
	)
	(segment
		(start 37.748718 -140.790168)
		(end 37.748718 -140.3604)
		(width 0.14224)
		(layer "In4.Cu")
		(net "M_L_DQ<7>")
	)
	(segment
		(start 38.656768 -118.65102)
		(end 38.799008 -118.50878)
		(width 0.14224)
		(layer "In4.Cu")
		(net "M_L_DQ<7>")
	)
	(segment
		(start 38.50132 -131.484878)
		(end 38.78072 -131.205478)
		(width 0.14224)
		(layer "In4.Cu")
		(net "M_L_DQ<7>")
	)
	(segment
		(start 38.799008 -120.4595)
		(end 38.656768 -120.31726)
		(width 0.14224)
		(layer "In4.Cu")
		(net "M_L_DQ<7>")
	)
	(segment
		(start 38.631368 -136.652)
		(end 38.55212 -136.572752)
		(width 0.14224)
		(layer "In4.Cu")
		(net "M_L_DQ<7>")
	)
	(segment
		(start 38.55212 -129.859278)
		(end 38.55212 -129.3368)
		(width 0.14224)
		(layer "In4.Cu")
		(net "M_L_DQ<7>")
	)
	(segment
		(start 38.631368 -134.0358)
		(end 38.631368 -131.981448)
		(width 0.14224)
		(layer "In4.Cu")
		(net "M_L_DQ<7>")
	)
	(segment
		(start 57.324752 -94.51467)
		(end 64.605408 -87.234014)
		(width 0.14224)
		(layer "In4.Cu")
		(net "M_L_DQ<7>")
	)
	(segment
		(start 38.656768 -121.61774)
		(end 38.656768 -121.25198)
		(width 0.14224)
		(layer "In4.Cu")
		(net "M_L_DQ<7>")
	)
	(segment
		(start 66.92011 -86.88959)
		(end 67.195446 -86.88959)
		(width 0.0889)
		(layer "In4.Cu")
		(net "M_L_DQ<7>")
	)
	(segment
		(start 40.434768 -120.9675)
		(end 40.434768 -120.60174)
		(width 0.14224)
		(layer "In4.Cu")
		(net "M_L_DQ<7>")
	)
	(segment
		(start 37.799518 -143.763746)
		(end 37.799518 -143.44015)
		(width 0.14224)
		(layer "In4.Cu")
		(net "M_L_DQ<7>")
	)
	(segment
		(start 38.656768 -119.01678)
		(end 38.656768 -118.65102)
		(width 0.14224)
		(layer "In4.Cu")
		(net "M_L_DQ<7>")
	)
	(segment
		(start 38.55212 -129.3368)
		(end 38.656768 -129.232152)
		(width 0.14224)
		(layer "In4.Cu")
		(net "M_L_DQ<7>")
	)
	(segment
		(start 40.434768 -119.66702)
		(end 40.434768 -119.30126)
		(width 0.14224)
		(layer "In4.Cu")
		(net "M_L_DQ<7>")
	)
	(segment
		(start 38.176962 -139.932156)
		(end 38.199314 -139.932156)
		(width 0.14224)
		(layer "In4.Cu")
		(net "M_L_DQ<7>")
	)
	(segment
		(start 37.793168 -140.834618)
		(end 37.748718 -140.790168)
		(width 0.14224)
		(layer "In4.Cu")
		(net "M_L_DQ<7>")
	)
	(segment
		(start 38.799008 -121.10974)
		(end 40.292528 -121.10974)
		(width 0.14224)
		(layer "In4.Cu")
		(net "M_L_DQ<7>")
	)
	(segment
		(start 38.656768 -120.31726)
		(end 38.656768 -119.9515)
		(width 0.14224)
		(layer "In4.Cu")
		(net "M_L_DQ<7>")
	)
	(segment
		(start 37.51072 -142.878048)
		(end 37.767768 -142.621)
		(width 0.14224)
		(layer "In4.Cu")
		(net "M_L_DQ<7>")
	)
	(segment
		(start 40.292528 -121.10974)
		(end 40.434768 -120.9675)
		(width 0.14224)
		(layer "In4.Cu")
		(net "M_L_DQ<7>")
	)
	(segment
		(start 38.50132 -131.8514)
		(end 38.50132 -131.484878)
		(width 0.14224)
		(layer "In4.Cu")
		(net "M_L_DQ<7>")
	)
	(segment
		(start 37.767768 -142.3162)
		(end 37.51072 -142.059152)
		(width 0.14224)
		(layer "In4.Cu")
		(net "M_L_DQ<7>")
	)
	(segment
		(start 38.631368 -138.8618)
		(end 38.631368 -136.652)
		(width 0.14224)
		(layer "In4.Cu")
		(net "M_L_DQ<7>")
	)
	(segment
		(start 66.817494 -86.992206)
		(end 66.92011 -86.88959)
		(width 0.0889)
		(layer "In4.Cu")
		(net "M_L_DQ<7>")
	)
	(segment
		(start 69.79031 -85.403436)
		(end 70.611746 -85.30844)
		(width 0.0889)
		(layer "In4.Cu")
		(net "M_L_DQ<7>")
	)
	(segment
		(start 40.292528 -119.80926)
		(end 40.434768 -119.66702)
		(width 0.14224)
		(layer "In4.Cu")
		(net "M_L_DQ<7>")
	)
	(segment
		(start 37.793168 -141.5034)
		(end 37.793168 -140.834618)
		(width 0.14224)
		(layer "In4.Cu")
		(net "M_L_DQ<7>")
	)
	(segment
		(start 38.799008 -122.41022)
		(end 40.292528 -122.41022)
		(width 0.14224)
		(layer "In4.Cu")
		(net "M_L_DQ<7>")
	)
	(segment
		(start 38.541198 -139.590272)
		(end 38.55212 -139.590272)
		(width 0.14224)
		(layer "In4.Cu")
		(net "M_L_DQ<7>")
	)
	(segment
		(start 40.256968 -116.179346)
		(end 40.256968 -115.537234)
		(width 0.14224)
		(layer "In4.Cu")
		(net "M_L_DQ<7>")
	)
	(segment
		(start 68.87972 -85.89899)
		(end 68.912486 -85.89899)
		(width 0.0889)
		(layer "In4.Cu")
		(net "M_L_DQ<7>")
	)
	(segment
		(start 40.292528 -118.50878)
		(end 40.434768 -118.36654)
		(width 0.14224)
		(layer "In4.Cu")
		(net "M_L_DQ<7>")
	)
	(segment
		(start 38.55212 -138.941048)
		(end 38.631368 -138.8618)
		(width 0.14224)
		(layer "In4.Cu")
		(net "M_L_DQ<7>")
	)
	(segment
		(start 37.51072 -142.059152)
		(end 37.51072 -141.785848)
		(width 0.14224)
		(layer "In4.Cu")
		(net "M_L_DQ<7>")
	)
	(segment
		(start 37.51072 -141.785848)
		(end 37.793168 -141.5034)
		(width 0.14224)
		(layer "In4.Cu")
		(net "M_L_DQ<7>")
	)
	(segment
		(start 38.656768 -129.232152)
		(end 38.656768 -122.55246)
		(width 0.14224)
		(layer "In4.Cu")
		(net "M_L_DQ<7>")
	)
	(segment
		(start 38.55212 -136.248394)
		(end 38.721284 -136.07923)
		(width 0.14224)
		(layer "In4.Cu")
		(net "M_L_DQ<7>")
	)
	(segment
		(start 40.434768 -121.90222)
		(end 40.292528 -121.75998)
		(width 0.14224)
		(layer "In4.Cu")
		(net "M_L_DQ<7>")
	)
	(segment
		(start 38.631368 -131.981448)
		(end 38.50132 -131.8514)
		(width 0.14224)
		(layer "In4.Cu")
		(net "M_L_DQ<7>")
	)
	(segment
		(start 38.55212 -139.590272)
		(end 38.55212 -138.941048)
		(width 0.14224)
		(layer "In4.Cu")
		(net "M_L_DQ<7>")
	)
	(segment
		(start 37.621718 -143.941546)
		(end 37.799518 -143.763746)
		(width 0.14224)
		(layer "In4.Cu")
		(net "M_L_DQ<7>")
	)
	(segment
		(start 38.799008 -121.75998)
		(end 38.656768 -121.61774)
		(width 0.14224)
		(layer "In4.Cu")
		(net "M_L_DQ<7>")
	)
	(segment
		(start 38.721284 -134.683246)
		(end 38.57752 -134.539482)
		(width 0.14224)
		(layer "In4.Cu")
		(net "M_L_DQ<7>")
	)
	(segment
		(start 38.799008 -118.50878)
		(end 40.292528 -118.50878)
		(width 0.14224)
		(layer "In4.Cu")
		(net "M_L_DQ<7>")
	)
	(segment
		(start 37.748718 -140.3604)
		(end 38.176962 -139.932156)
		(width 0.14224)
		(layer "In4.Cu")
		(net "M_L_DQ<7>")
	)
	(segment
		(start 64.605408 -87.234014)
		(end 64.883792 -87.234014)
		(width 0.14224)
		(layer "In4.Cu")
		(net "M_L_DQ<7>")
	)
	(segment
		(start 45.125386 -110.668816)
		(end 45.125386 -110.142528)
		(width 0.14224)
		(layer "In4.Cu")
		(net "M_L_DQ<7>")
	)
	(segment
		(start 40.434768 -118.36654)
		(end 40.434768 -118.00078)
		(width 0.14224)
		(layer "In4.Cu")
		(net "M_L_DQ<7>")
	)
	(segment
		(start 40.434768 -122.26798)
		(end 40.434768 -121.90222)
		(width 0.14224)
		(layer "In4.Cu")
		(net "M_L_DQ<7>")
	)
	(segment
		(start 57.324752 -97.943162)
		(end 57.324752 -94.51467)
		(width 0.14224)
		(layer "In4.Cu")
		(net "M_L_DQ<7>")
	)
	(segment
		(start 64.883792 -87.234014)
		(end 65.1256 -86.992206)
		(width 0.0889)
		(layer "In4.Cu")
		(net "M_L_DQ<7>")
	)
	(segment
		(start 40.292528 -121.75998)
		(end 38.799008 -121.75998)
		(width 0.14224)
		(layer "In4.Cu")
		(net "M_L_DQ<7>")
	)
	(segment
		(start 68.02501 -86.394036)
		(end 68.057776 -86.394036)
		(width 0.0889)
		(layer "In4.Cu")
		(net "M_L_DQ<7>")
	)
	(segment
		(start 65.1256 -86.992206)
		(end 66.817494 -86.992206)
		(width 0.0889)
		(layer "In4.Cu")
		(net "M_L_DQ<7>")
	)
	(segment
		(start 40.292528 -120.4595)
		(end 38.799008 -120.4595)
		(width 0.14224)
		(layer "In4.Cu")
		(net "M_L_DQ<7>")
	)
	(segment
		(start 38.199314 -139.932156)
		(end 38.541198 -139.590272)
		(width 0.14224)
		(layer "In4.Cu")
		(net "M_L_DQ<7>")
	)
	(segment
		(start 40.256968 -115.537234)
		(end 40.799258 -114.994944)
		(width 0.14224)
		(layer "In4.Cu")
		(net "M_L_DQ<7>")
	)
	(segment
		(start 37.799518 -143.44015)
		(end 37.51072 -143.151352)
		(width 0.14224)
		(layer "In4.Cu")
		(net "M_L_DQ<7>")
	)
	(segment
		(start 38.78072 -130.087878)
		(end 38.55212 -129.859278)
		(width 0.14224)
		(layer "In4.Cu")
		(net "M_L_DQ<7>")
	)
	(segment
		(start 41.907968 -114.5794)
		(end 41.907968 -113.886234)
		(width 0.14224)
		(layer "In4.Cu")
		(net "M_L_DQ<7>")
	)
	(segment
		(start 38.656768 -117.7163)
		(end 38.656768 -117.137434)
		(width 0.14224)
		(layer "In4.Cu")
		(net "M_L_DQ<7>")
	)
	(segment
		(start 38.656768 -121.25198)
		(end 38.799008 -121.10974)
		(width 0.14224)
		(layer "In4.Cu")
		(net "M_L_DQ<7>")
	)
	(segment
		(start 38.799008 -119.80926)
		(end 40.292528 -119.80926)
		(width 0.14224)
		(layer "In4.Cu")
		(net "M_L_DQ<7>")
	)
	(segment
		(start 40.434768 -118.00078)
		(end 40.292528 -117.85854)
		(width 0.14224)
		(layer "In4.Cu")
		(net "M_L_DQ<7>")
	)
	(segment
		(start 38.869112 -116.92509)
		(end 39.511224 -116.92509)
		(width 0.14224)
		(layer "In4.Cu")
		(net "M_L_DQ<7>")
	)
	(segment
		(start 40.434768 -119.30126)
		(end 40.292528 -119.15902)
		(width 0.14224)
		(layer "In4.Cu")
		(net "M_L_DQ<7>")
	)
	(segment
		(start 40.799258 -114.994944)
		(end 41.492424 -114.994944)
		(width 0.14224)
		(layer "In4.Cu")
		(net "M_L_DQ<7>")
	)
	(segment
		(start 37.34943 -143.941546)
		(end 37.621718 -143.941546)
		(width 0.14224)
		(layer "In4.Cu")
		(net "M_L_DQ<7>")
	)
	(segment
		(start 38.799008 -119.15902)
		(end 38.656768 -119.01678)
		(width 0.14224)
		(layer "In4.Cu")
		(net "M_L_DQ<7>")
	)
	(segment
		(start 38.656768 -119.9515)
		(end 38.799008 -119.80926)
		(width 0.14224)
		(layer "In4.Cu")
		(net "M_L_DQ<7>")
	)
	(segment
		(start 39.511224 -116.92509)
		(end 40.256968 -116.179346)
		(width 0.14224)
		(layer "In4.Cu")
		(net "M_L_DQ<7>")
	)
	(segment
		(start 41.492424 -114.994944)
		(end 41.907968 -114.5794)
		(width 0.14224)
		(layer "In4.Cu")
		(net "M_L_DQ<7>")
	)
	(segment
		(start 45.125386 -110.142528)
		(end 57.324752 -97.943162)
		(width 0.14224)
		(layer "In4.Cu")
		(net "M_L_DQ<7>")
	)
	(segment
		(start 38.57752 -134.089648)
		(end 38.631368 -134.0358)
		(width 0.14224)
		(layer "In4.Cu")
		(net "M_L_DQ<7>")
	)
	(segment
		(start 38.78072 -131.205478)
		(end 38.78072 -130.087878)
		(width 0.14224)
		(layer "In4.Cu")
		(net "M_L_DQ<7>")
	)
	(segment
		(start 38.799008 -117.85854)
		(end 38.656768 -117.7163)
		(width 0.14224)
		(layer "In4.Cu")
		(net "M_L_DQ<7>")
	)
	(segment
		(start 38.57752 -134.539482)
		(end 38.57752 -134.089648)
		(width 0.14224)
		(layer "In4.Cu")
		(net "M_L_DQ<7>")
	)
	(segment
		(start 41.907968 -113.886234)
		(end 45.125386 -110.668816)
		(width 0.14224)
		(layer "In4.Cu")
		(net "M_L_DQ<7>")
	)
	(segment
		(start 38.656768 -117.137434)
		(end 38.869112 -116.92509)
		(width 0.14224)
		(layer "In4.Cu")
		(net "M_L_DQ<7>")
	)
	(segment
		(start 40.434768 -120.60174)
		(end 40.292528 -120.4595)
		(width 0.14224)
		(layer "In4.Cu")
		(net "M_L_DQ<7>")
	)
	(segment
		(start 38.656768 -122.55246)
		(end 38.799008 -122.41022)
		(width 0.14224)
		(layer "In4.Cu")
		(net "M_L_DQ<7>")
	)
	(arc
		(start 67.195446 -86.88959)
		(mid 67.48087 -86.806123)
		(end 67.689476 -86.594188)
		(width 0.0889)
		(layer "In4.Cu")
		(net "M_L_DQ<7>")
	)
	(arc
		(start 68.547996 -86.098888)
		(mid 68.688075 -85.956152)
		(end 68.87972 -85.89899)
		(width 0.0889)
		(layer "In4.Cu")
		(net "M_L_DQ<7>")
	)
	(arc
		(start 68.912486 -85.89899)
		(mid 69.19791 -85.815523)
		(end 69.406516 -85.603588)
		(width 0.0889)
		(layer "In4.Cu")
		(net "M_L_DQ<7>")
	)
	(arc
		(start 68.057776 -86.394036)
		(mid 68.340993 -86.309755)
		(end 68.547996 -86.098888)
		(width 0.0889)
		(layer "In4.Cu")
		(net "M_L_DQ<7>")
	)
	(arc
		(start 67.689476 -86.594188)
		(mid 67.831159 -86.450384)
		(end 68.02501 -86.394036)
		(width 0.0889)
		(layer "In4.Cu")
		(net "M_L_DQ<7>")
	)
	(arc
		(start 69.406516 -85.603588)
		(mid 69.548199 -85.459784)
		(end 69.74205 -85.403436)
		(width 0.0889)
		(layer "In4.Cu")
		(net "M_L_DQ<7>")
	)
	(segment
		(start 38.331648 -145.95348)
		(end 38.199568 -145.8214)
		(width 0.1651)
		(layer "F.Cu")
		(net "M_L_DQ<6>")
	)
	(segment
		(start 38.199568 -145.8214)
		(end 38.199568 -145.516854)
		(width 0.1651)
		(layer "F.Cu")
		(net "M_L_DQ<6>")
	)
	(segment
		(start 38.199568 -146.304)
		(end 38.331648 -146.17192)
		(width 0.1651)
		(layer "F.Cu")
		(net "M_L_DQ<6>")
	)
	(segment
		(start 38.331648 -146.17192)
		(end 38.331648 -145.95348)
		(width 0.1651)
		(layer "F.Cu")
		(net "M_L_DQ<6>")
	)
	(segment
		(start 38.199568 -147.27174)
		(end 38.199568 -146.304)
		(width 0.1651)
		(layer "F.Cu")
		(net "M_L_DQ<6>")
	)
	(segment
		(start 72.900286 -86.29904)
		(end 72.328786 -86.29904)
		(width 0.1651)
		(layer "F.Cu")
		(net "M_L_DQ<6>")
	)
	(segment
		(start 38.199568 -145.516854)
		(end 38.199314 -145.5166)
		(width 0.1651)
		(layer "F.Cu")
		(net "M_L_DQ<6>")
	)
	(via
		(at 72.328786 -86.29904)
		(size 0.508)
		(drill 0.254)
		(layers "F.Cu" "B.Cu")
		(net "M_L_DQ<6>")
	)
	(via
		(at 38.199314 -145.5166)
		(size 0.508)
		(drill 0.254)
		(layers "F.Cu" "B.Cu")
		(net "M_L_DQ<6>")
	)
	(via
		(at 37.34943 -141.213078)
		(size 0.508)
		(drill 0.254)
		(layers "F.Cu" "B.Cu")
		(net "M_L_DQ<6>")
	)
	(segment
		(start 37.34943 -142.477236)
		(end 37.34943 -141.213078)
		(width 0.1651)
		(layer "B.Cu")
		(net "M_L_DQ<6>")
	)
	(segment
		(start 68.905882 -85.70849)
		(end 68.873116 -85.70849)
		(width 0.0889)
		(layer "In4.Cu")
		(net "M_L_DQ<6>")
	)
	(segment
		(start 38.199314 -145.5166)
		(end 36.91636 -144.233646)
		(width 0.14224)
		(layer "In4.Cu")
		(net "M_L_DQ<6>")
	)
	(segment
		(start 37.773356 -136.694164)
		(end 37.773356 -138.892788)
		(width 0.14224)
		(layer "In4.Cu")
		(net "M_L_DQ<6>")
	)
	(segment
		(start 37.80663 -129.019808)
		(end 37.80663 -129.969768)
		(width 0.14224)
		(layer "In4.Cu")
		(net "M_L_DQ<6>")
	)
	(segment
		(start 41.23944 -112.758474)
		(end 40.952166 -113.045748)
		(width 0.14224)
		(layer "In4.Cu")
		(net "M_L_DQ<6>")
	)
	(segment
		(start 71.83374 -85.633052)
		(end 71.816976 -85.603588)
		(width 0.0889)
		(layer "In4.Cu")
		(net "M_L_DQ<6>")
	)
	(segment
		(start 40.377364 -113.908078)
		(end 40.089836 -113.908078)
		(width 0.14224)
		(layer "In4.Cu")
		(net "M_L_DQ<6>")
	)
	(segment
		(start 37.91712 -139.333478)
		(end 37.18052 -140.070078)
		(width 0.14224)
		(layer "In4.Cu")
		(net "M_L_DQ<6>")
	)
	(segment
		(start 37.208968 -126.1618)
		(end 37.005768 -125.9586)
		(width 0.14224)
		(layer "In4.Cu")
		(net "M_L_DQ<6>")
	)
	(segment
		(start 37.818568 -127.468376)
		(end 37.412168 -127.468376)
		(width 0.14224)
		(layer "In4.Cu")
		(net "M_L_DQ<6>")
	)
	(segment
		(start 37.71392 -130.062478)
		(end 37.71392 -131.307078)
		(width 0.14224)
		(layer "In4.Cu")
		(net "M_L_DQ<6>")
	)
	(segment
		(start 56.845962 -94.20606)
		(end 56.845962 -97.736152)
		(width 0.14224)
		(layer "In4.Cu")
		(net "M_L_DQ<6>")
	)
	(segment
		(start 39.964106 -114.644424)
		(end 39.964106 -114.931952)
		(width 0.14224)
		(layer "In4.Cu")
		(net "M_L_DQ<6>")
	)
	(segment
		(start 37.412168 -127.468376)
		(end 37.208968 -127.265176)
		(width 0.14224)
		(layer "In4.Cu")
		(net "M_L_DQ<6>")
	)
	(segment
		(start 69.768212 -85.212936)
		(end 69.735446 -85.212936)
		(width 0.0889)
		(layer "In4.Cu")
		(net "M_L_DQ<6>")
	)
	(segment
		(start 42.263314 -112.632744)
		(end 41.97604 -112.920018)
		(width 0.14224)
		(layer "In4.Cu")
		(net "M_L_DQ<6>")
	)
	(segment
		(start 41.688512 -112.920018)
		(end 41.526968 -112.758474)
		(width 0.14224)
		(layer "In4.Cu")
		(net "M_L_DQ<6>")
	)
	(segment
		(start 37.86632 -131.459478)
		(end 37.86632 -131.826)
		(width 0.14224)
		(layer "In4.Cu")
		(net "M_L_DQ<6>")
	)
	(segment
		(start 42.676572 -111.60887)
		(end 42.389044 -111.60887)
		(width 0.14224)
		(layer "In4.Cu")
		(net "M_L_DQ<6>")
	)
	(segment
		(start 68.051172 -86.203536)
		(end 68.018406 -86.203536)
		(width 0.0889)
		(layer "In4.Cu")
		(net "M_L_DQ<6>")
	)
	(segment
		(start 38.021768 -127.265176)
		(end 37.818568 -127.468376)
		(width 0.14224)
		(layer "In4.Cu")
		(net "M_L_DQ<6>")
	)
	(segment
		(start 41.11371 -113.782348)
		(end 40.826436 -114.069622)
		(width 0.14224)
		(layer "In4.Cu")
		(net "M_L_DQ<6>")
	)
	(segment
		(start 39.964106 -114.931952)
		(end 38.021768 -116.87429)
		(width 0.14224)
		(layer "In4.Cu")
		(net "M_L_DQ<6>")
	)
	(segment
		(start 43.125644 -111.770414)
		(end 42.838116 -111.770414)
		(width 0.14224)
		(layer "In4.Cu")
		(net "M_L_DQ<6>")
	)
	(segment
		(start 65.086992 -86.802214)
		(end 64.883792 -86.599014)
		(width 0.0889)
		(layer "In4.Cu")
		(net "M_L_DQ<6>")
	)
	(segment
		(start 36.599368 -125.9586)
		(end 36.396168 -126.1618)
		(width 0.14224)
		(layer "In4.Cu")
		(net "M_L_DQ<6>")
	)
	(segment
		(start 56.845962 -97.736152)
		(end 44.490386 -110.091728)
		(width 0.14224)
		(layer "In4.Cu")
		(net "M_L_DQ<6>")
	)
	(segment
		(start 37.593778 -134.759192)
		(end 37.593778 -135.932926)
		(width 0.14224)
		(layer "In4.Cu")
		(net "M_L_DQ<6>")
	)
	(segment
		(start 37.80663 -129.969768)
		(end 37.71392 -130.062478)
		(width 0.14224)
		(layer "In4.Cu")
		(net "M_L_DQ<6>")
	)
	(segment
		(start 37.91712 -139.036552)
		(end 37.91712 -139.333478)
		(width 0.14224)
		(layer "In4.Cu")
		(net "M_L_DQ<6>")
	)
	(segment
		(start 40.952166 -113.045748)
		(end 40.952166 -113.333276)
		(width 0.14224)
		(layer "In4.Cu")
		(net "M_L_DQ<6>")
	)
	(segment
		(start 39.802562 -114.48288)
		(end 39.964106 -114.644424)
		(width 0.14224)
		(layer "In4.Cu")
		(net "M_L_DQ<6>")
	)
	(segment
		(start 66.841116 -86.69909)
		(end 66.737992 -86.802214)
		(width 0.0889)
		(layer "In4.Cu")
		(net "M_L_DQ<6>")
	)
	(segment
		(start 43.538648 -110.459266)
		(end 43.251374 -110.74654)
		(width 0.14224)
		(layer "In4.Cu")
		(net "M_L_DQ<6>")
	)
	(segment
		(start 64.453008 -86.599014)
		(end 56.845962 -94.20606)
		(width 0.14224)
		(layer "In4.Cu")
		(net "M_L_DQ<6>")
	)
	(segment
		(start 44.275248 -110.62081)
		(end 43.98772 -110.62081)
		(width 0.14224)
		(layer "In4.Cu")
		(net "M_L_DQ<6>")
	)
	(segment
		(start 37.18052 -141.044168)
		(end 37.34943 -141.213078)
		(width 0.14224)
		(layer "In4.Cu")
		(net "M_L_DQ<6>")
	)
	(segment
		(start 42.10177 -112.183672)
		(end 42.263314 -112.345216)
		(width 0.14224)
		(layer "In4.Cu")
		(net "M_L_DQ<6>")
	)
	(segment
		(start 40.538908 -114.069622)
		(end 40.377364 -113.908078)
		(width 0.14224)
		(layer "In4.Cu")
		(net "M_L_DQ<6>")
	)
	(segment
		(start 40.952166 -113.333276)
		(end 41.11371 -113.49482)
		(width 0.14224)
		(layer "In4.Cu")
		(net "M_L_DQ<6>")
	)
	(segment
		(start 44.490386 -110.405672)
		(end 44.275248 -110.62081)
		(width 0.14224)
		(layer "In4.Cu")
		(net "M_L_DQ<6>")
	)
	(segment
		(start 37.91712 -136.256268)
		(end 37.91712 -136.5504)
		(width 0.14224)
		(layer "In4.Cu")
		(net "M_L_DQ<6>")
	)
	(segment
		(start 42.838116 -111.770414)
		(end 42.676572 -111.60887)
		(width 0.14224)
		(layer "In4.Cu")
		(net "M_L_DQ<6>")
	)
	(segment
		(start 41.526968 -112.758474)
		(end 41.23944 -112.758474)
		(width 0.14224)
		(layer "In4.Cu")
		(net "M_L_DQ<6>")
	)
	(segment
		(start 71.481442 -85.403436)
		(end 71.448676 -85.403436)
		(width 0.0889)
		(layer "In4.Cu")
		(net "M_L_DQ<6>")
	)
	(segment
		(start 37.86632 -134.48665)
		(end 37.593778 -134.759192)
		(width 0.14224)
		(layer "In4.Cu")
		(net "M_L_DQ<6>")
	)
	(segment
		(start 67.188842 -86.69909)
		(end 66.841116 -86.69909)
		(width 0.0889)
		(layer "In4.Cu")
		(net "M_L_DQ<6>")
	)
	(segment
		(start 42.389044 -111.60887)
		(end 42.10177 -111.896144)
		(width 0.14224)
		(layer "In4.Cu")
		(net "M_L_DQ<6>")
	)
	(segment
		(start 44.490386 -110.091728)
		(end 44.490386 -110.405672)
		(width 0.14224)
		(layer "In4.Cu")
		(net "M_L_DQ<6>")
	)
	(segment
		(start 36.396168 -127.609346)
		(end 37.80663 -129.019808)
		(width 0.14224)
		(layer "In4.Cu")
		(net "M_L_DQ<6>")
	)
	(segment
		(start 38.021768 -116.87429)
		(end 38.021768 -127.265176)
		(width 0.14224)
		(layer "In4.Cu")
		(net "M_L_DQ<6>")
	)
	(segment
		(start 36.91636 -144.233646)
		(end 36.91636 -141.646148)
		(width 0.14224)
		(layer "In4.Cu")
		(net "M_L_DQ<6>")
	)
	(segment
		(start 43.412918 -111.48314)
		(end 43.125644 -111.770414)
		(width 0.14224)
		(layer "In4.Cu")
		(net "M_L_DQ<6>")
	)
	(segment
		(start 43.826176 -110.459266)
		(end 43.538648 -110.459266)
		(width 0.14224)
		(layer "In4.Cu")
		(net "M_L_DQ<6>")
	)
	(segment
		(start 37.767768 -131.924552)
		(end 37.767768 -134.0104)
		(width 0.14224)
		(layer "In4.Cu")
		(net "M_L_DQ<6>")
	)
	(segment
		(start 37.593778 -135.932926)
		(end 37.91712 -136.256268)
		(width 0.14224)
		(layer "In4.Cu")
		(net "M_L_DQ<6>")
	)
	(segment
		(start 37.773356 -138.892788)
		(end 37.91712 -139.036552)
		(width 0.14224)
		(layer "In4.Cu")
		(net "M_L_DQ<6>")
	)
	(segment
		(start 41.11371 -113.49482)
		(end 41.11371 -113.782348)
		(width 0.14224)
		(layer "In4.Cu")
		(net "M_L_DQ<6>")
	)
	(segment
		(start 43.251374 -110.74654)
		(end 43.251374 -111.034068)
		(width 0.14224)
		(layer "In4.Cu")
		(net "M_L_DQ<6>")
	)
	(segment
		(start 66.737992 -86.802214)
		(end 65.086992 -86.802214)
		(width 0.0889)
		(layer "In4.Cu")
		(net "M_L_DQ<6>")
	)
	(segment
		(start 39.802562 -114.195352)
		(end 39.802562 -114.48288)
		(width 0.14224)
		(layer "In4.Cu")
		(net "M_L_DQ<6>")
	)
	(segment
		(start 37.18052 -140.070078)
		(end 37.18052 -141.044168)
		(width 0.14224)
		(layer "In4.Cu")
		(net "M_L_DQ<6>")
	)
	(segment
		(start 41.97604 -112.920018)
		(end 41.688512 -112.920018)
		(width 0.14224)
		(layer "In4.Cu")
		(net "M_L_DQ<6>")
	)
	(segment
		(start 43.98772 -110.62081)
		(end 43.826176 -110.459266)
		(width 0.14224)
		(layer "In4.Cu")
		(net "M_L_DQ<6>")
	)
	(segment
		(start 43.412918 -111.195612)
		(end 43.412918 -111.48314)
		(width 0.14224)
		(layer "In4.Cu")
		(net "M_L_DQ<6>")
	)
	(segment
		(start 42.10177 -111.896144)
		(end 42.10177 -112.183672)
		(width 0.14224)
		(layer "In4.Cu")
		(net "M_L_DQ<6>")
	)
	(segment
		(start 40.826436 -114.069622)
		(end 40.538908 -114.069622)
		(width 0.14224)
		(layer "In4.Cu")
		(net "M_L_DQ<6>")
	)
	(segment
		(start 37.71392 -131.307078)
		(end 37.86632 -131.459478)
		(width 0.14224)
		(layer "In4.Cu")
		(net "M_L_DQ<6>")
	)
	(segment
		(start 42.263314 -112.345216)
		(end 42.263314 -112.632744)
		(width 0.14224)
		(layer "In4.Cu")
		(net "M_L_DQ<6>")
	)
	(segment
		(start 43.251374 -111.034068)
		(end 43.412918 -111.195612)
		(width 0.14224)
		(layer "In4.Cu")
		(net "M_L_DQ<6>")
	)
	(segment
		(start 70.626732 -84.90839)
		(end 70.281292 -84.90839)
		(width 0.0889)
		(layer "In4.Cu")
		(net "M_L_DQ<6>")
	)
	(segment
		(start 72.328786 -86.29904)
		(end 71.83374 -85.633052)
		(width 0.0889)
		(layer "In4.Cu")
		(net "M_L_DQ<6>")
	)
	(segment
		(start 37.86632 -134.108952)
		(end 37.86632 -134.48665)
		(width 0.14224)
		(layer "In4.Cu")
		(net "M_L_DQ<6>")
	)
	(segment
		(start 40.089836 -113.908078)
		(end 39.802562 -114.195352)
		(width 0.14224)
		(layer "In4.Cu")
		(net "M_L_DQ<6>")
	)
	(segment
		(start 36.396168 -126.1618)
		(end 36.396168 -127.609346)
		(width 0.14224)
		(layer "In4.Cu")
		(net "M_L_DQ<6>")
	)
	(segment
		(start 37.91712 -136.5504)
		(end 37.773356 -136.694164)
		(width 0.14224)
		(layer "In4.Cu")
		(net "M_L_DQ<6>")
	)
	(segment
		(start 37.86632 -131.826)
		(end 37.767768 -131.924552)
		(width 0.14224)
		(layer "In4.Cu")
		(net "M_L_DQ<6>")
	)
	(segment
		(start 36.91636 -141.646148)
		(end 37.34943 -141.213078)
		(width 0.14224)
		(layer "In4.Cu")
		(net "M_L_DQ<6>")
	)
	(segment
		(start 64.883792 -86.599014)
		(end 64.453008 -86.599014)
		(width 0.14224)
		(layer "In4.Cu")
		(net "M_L_DQ<6>")
	)
	(segment
		(start 37.005768 -125.9586)
		(end 36.599368 -125.9586)
		(width 0.14224)
		(layer "In4.Cu")
		(net "M_L_DQ<6>")
	)
	(segment
		(start 37.767768 -134.0104)
		(end 37.86632 -134.108952)
		(width 0.14224)
		(layer "In4.Cu")
		(net "M_L_DQ<6>")
	)
	(segment
		(start 37.208968 -127.265176)
		(end 37.208968 -126.1618)
		(width 0.14224)
		(layer "In4.Cu")
		(net "M_L_DQ<6>")
	)
	(arc
		(start 71.448676 -85.403436)
		(mid 71.165459 -85.319155)
		(end 70.958456 -85.108288)
		(width 0.0889)
		(layer "In4.Cu")
		(net "M_L_DQ<6>")
	)
	(arc
		(start 68.873116 -85.70849)
		(mid 68.589899 -85.792771)
		(end 68.382896 -86.003638)
		(width 0.0889)
		(layer "In4.Cu")
		(net "M_L_DQ<6>")
	)
	(arc
		(start 68.018406 -86.203536)
		(mid 67.732982 -86.287003)
		(end 67.524376 -86.498938)
		(width 0.0889)
		(layer "In4.Cu")
		(net "M_L_DQ<6>")
	)
	(arc
		(start 69.735446 -85.212936)
		(mid 69.450022 -85.296403)
		(end 69.241416 -85.508338)
		(width 0.0889)
		(layer "In4.Cu")
		(net "M_L_DQ<6>")
	)
	(arc
		(start 70.099936 -85.013038)
		(mid 69.959857 -85.155774)
		(end 69.768212 -85.212936)
		(width 0.0889)
		(layer "In4.Cu")
		(net "M_L_DQ<6>")
	)
	(arc
		(start 69.241416 -85.508338)
		(mid 69.099733 -85.652142)
		(end 68.905882 -85.70849)
		(width 0.0889)
		(layer "In4.Cu")
		(net "M_L_DQ<6>")
	)
	(arc
		(start 68.382896 -86.003638)
		(mid 68.242817 -86.146374)
		(end 68.051172 -86.203536)
		(width 0.0889)
		(layer "In4.Cu")
		(net "M_L_DQ<6>")
	)
	(arc
		(start 70.958456 -85.108288)
		(mid 70.818377 -84.965552)
		(end 70.626732 -84.90839)
		(width 0.0889)
		(layer "In4.Cu")
		(net "M_L_DQ<6>")
	)
	(arc
		(start 71.816976 -85.603588)
		(mid 71.675293 -85.459784)
		(end 71.481442 -85.403436)
		(width 0.0889)
		(layer "In4.Cu")
		(net "M_L_DQ<6>")
	)
	(arc
		(start 67.524376 -86.498938)
		(mid 67.382693 -86.642742)
		(end 67.188842 -86.69909)
		(width 0.0889)
		(layer "In4.Cu")
		(net "M_L_DQ<6>")
	)
	(arc
		(start 70.281292 -84.90839)
		(mid 70.176591 -84.936422)
		(end 70.099936 -85.013038)
		(width 0.0889)
		(layer "In4.Cu")
		(net "M_L_DQ<6>")
	)
	(segment
		(start 122.217688 -95.528384)
		(end 121.646188 -95.528384)
		(width 0.1651)
		(layer "F.Cu")
		(net "M_L_DQ<63>")
	)
	(segment
		(start 148.699474 -142.6718)
		(end 148.699474 -143.941546)
		(width 0.1651)
		(layer "F.Cu")
		(net "M_L_DQ<63>")
	)
	(via
		(at 122.217688 -95.528384)
		(size 0.508)
		(drill 0.254)
		(layers "F.Cu" "B.Cu")
		(net "M_L_DQ<63>")
	)
	(via
		(at 148.699474 -143.941546)
		(size 0.508)
		(drill 0.254)
		(layers "F.Cu" "B.Cu")
		(net "M_L_DQ<63>")
	)
	(via
		(at 149.549358 -139.932156)
		(size 0.508)
		(drill 0.254)
		(layers "F.Cu" "B.Cu")
		(net "M_L_DQ<63>")
	)
	(segment
		(start 149.549358 -137.877296)
		(end 149.549358 -139.932156)
		(width 0.1651)
		(layer "B.Cu")
		(net "M_L_DQ<63>")
	)
	(segment
		(start 149.916642 -127.46609)
		(end 149.761702 -127.62103)
		(width 0.14224)
		(layer "In4.Cu")
		(net "M_L_DQ<63>")
	)
	(segment
		(start 150.313644 -132.421884)
		(end 150.158704 -132.576824)
		(width 0.14224)
		(layer "In4.Cu")
		(net "M_L_DQ<63>")
	)
	(segment
		(start 148.971762 -143.941546)
		(end 148.699474 -143.941546)
		(width 0.14224)
		(layer "In4.Cu")
		(net "M_L_DQ<63>")
	)
	(segment
		(start 149.149562 -143.763746)
		(end 148.971762 -143.941546)
		(width 0.14224)
		(layer "In4.Cu")
		(net "M_L_DQ<63>")
	)
	(segment
		(start 142.764002 -118.645432)
		(end 144.137888 -118.645432)
		(width 0.14224)
		(layer "In4.Cu")
		(net "M_L_DQ<63>")
	)
	(segment
		(start 148.860764 -142.878048)
		(end 148.860764 -143.151352)
		(width 0.14224)
		(layer "In4.Cu")
		(net "M_L_DQ<63>")
	)
	(segment
		(start 148.860764 -143.151352)
		(end 149.149562 -143.44015)
		(width 0.14224)
		(layer "In4.Cu")
		(net "M_L_DQ<63>")
	)
	(segment
		(start 122.729498 -100.186236)
		(end 122.735848 -100.196904)
		(width 0.0889)
		(layer "In4.Cu")
		(net "M_L_DQ<63>")
	)
	(segment
		(start 149.098762 -140.790168)
		(end 149.143212 -140.834618)
		(width 0.14224)
		(layer "In4.Cu")
		(net "M_L_DQ<63>")
	)
	(segment
		(start 130.13817 -106.0196)
		(end 142.764002 -118.645432)
		(width 0.14224)
		(layer "In4.Cu")
		(net "M_L_DQ<63>")
	)
	(segment
		(start 149.883622 -132.576824)
		(end 149.728682 -132.731764)
		(width 0.14224)
		(layer "In4.Cu")
		(net "M_L_DQ<63>")
	)
	(segment
		(start 150.158704 -133.389624)
		(end 150.313644 -133.544564)
		(width 0.14224)
		(layer "In4.Cu")
		(net "M_L_DQ<63>")
	)
	(segment
		(start 149.761702 -126.95809)
		(end 149.916642 -127.11303)
		(width 0.14224)
		(layer "In4.Cu")
		(net "M_L_DQ<63>")
	)
	(segment
		(start 149.891242 -139.590272)
		(end 149.549358 -139.932156)
		(width 0.14224)
		(layer "In4.Cu")
		(net "M_L_DQ<63>")
	)
	(segment
		(start 149.927564 -134.148068)
		(end 149.927564 -134.526782)
		(width 0.14224)
		(layer "In4.Cu")
		(net "M_L_DQ<63>")
	)
	(segment
		(start 150.071328 -134.670546)
		(end 150.071328 -136.083294)
		(width 0.14224)
		(layer "In4.Cu")
		(net "M_L_DQ<63>")
	)
	(segment
		(start 144.137888 -118.645432)
		(end 149.916642 -124.424186)
		(width 0.14224)
		(layer "In4.Cu")
		(net "M_L_DQ<63>")
	)
	(segment
		(start 149.117812 -142.3162)
		(end 149.117812 -142.621)
		(width 0.14224)
		(layer "In4.Cu")
		(net "M_L_DQ<63>")
	)
	(segment
		(start 122.724672 -100.1776)
		(end 122.729498 -100.186236)
		(width 0.0889)
		(layer "In4.Cu")
		(net "M_L_DQ<63>")
	)
	(segment
		(start 149.761702 -127.62103)
		(end 149.411436 -127.62103)
		(width 0.14224)
		(layer "In4.Cu")
		(net "M_L_DQ<63>")
	)
	(segment
		(start 125.636782 -104.843834)
		(end 125.673358 -104.843834)
		(width 0.0889)
		(layer "In4.Cu")
		(net "M_L_DQ<63>")
	)
	(segment
		(start 149.143212 -141.5034)
		(end 148.860764 -141.785848)
		(width 0.14224)
		(layer "In4.Cu")
		(net "M_L_DQ<63>")
	)
	(segment
		(start 126.977902 -105.664508)
		(end 127.332994 -106.0196)
		(width 0.14224)
		(layer "In4.Cu")
		(net "M_L_DQ<63>")
	)
	(segment
		(start 150.313644 -133.544564)
		(end 150.313644 -133.761988)
		(width 0.14224)
		(layer "In4.Cu")
		(net "M_L_DQ<63>")
	)
	(segment
		(start 149.256496 -126.80315)
		(end 149.411436 -126.95809)
		(width 0.14224)
		(layer "In4.Cu")
		(net "M_L_DQ<63>")
	)
	(segment
		(start 149.256496 -127.77597)
		(end 149.256496 -128.12903)
		(width 0.14224)
		(layer "In4.Cu")
		(net "M_L_DQ<63>")
	)
	(segment
		(start 149.549358 -139.932156)
		(end 149.527006 -139.932156)
		(width 0.14224)
		(layer "In4.Cu")
		(net "M_L_DQ<63>")
	)
	(segment
		(start 149.916642 -129.873756)
		(end 150.130764 -130.087878)
		(width 0.14224)
		(layer "In4.Cu")
		(net "M_L_DQ<63>")
	)
	(segment
		(start 123.919742 -103.853234)
		(end 123.952508 -103.853234)
		(width 0.0889)
		(layer "In4.Cu")
		(net "M_L_DQ<63>")
	)
	(segment
		(start 122.217688 -95.528384)
		(end 122.654822 -96.008444)
		(width 0.0889)
		(layer "In4.Cu")
		(net "M_L_DQ<63>")
	)
	(segment
		(start 149.761702 -126.29515)
		(end 149.411436 -126.29515)
		(width 0.14224)
		(layer "In4.Cu")
		(net "M_L_DQ<63>")
	)
	(segment
		(start 149.916642 -128.43891)
		(end 149.916642 -129.873756)
		(width 0.14224)
		(layer "In4.Cu")
		(net "M_L_DQ<63>")
	)
	(segment
		(start 149.728682 -133.234684)
		(end 149.883622 -133.389624)
		(width 0.14224)
		(layer "In4.Cu")
		(net "M_L_DQ<63>")
	)
	(segment
		(start 149.117812 -142.621)
		(end 148.860764 -142.878048)
		(width 0.14224)
		(layer "In4.Cu")
		(net "M_L_DQ<63>")
	)
	(segment
		(start 149.916642 -127.11303)
		(end 149.916642 -127.46609)
		(width 0.14224)
		(layer "In4.Cu")
		(net "M_L_DQ<63>")
	)
	(segment
		(start 149.883622 -133.389624)
		(end 150.158704 -133.389624)
		(width 0.14224)
		(layer "In4.Cu")
		(net "M_L_DQ<63>")
	)
	(segment
		(start 149.256496 -126.45009)
		(end 149.256496 -126.80315)
		(width 0.14224)
		(layer "In4.Cu")
		(net "M_L_DQ<63>")
	)
	(segment
		(start 149.902164 -139.590272)
		(end 149.891242 -139.590272)
		(width 0.14224)
		(layer "In4.Cu")
		(net "M_L_DQ<63>")
	)
	(segment
		(start 124.782072 -104.348788)
		(end 124.814838 -104.348788)
		(width 0.0889)
		(layer "In4.Cu")
		(net "M_L_DQ<63>")
	)
	(segment
		(start 150.071328 -136.083294)
		(end 149.902164 -136.252458)
		(width 0.14224)
		(layer "In4.Cu")
		(net "M_L_DQ<63>")
	)
	(segment
		(start 148.860764 -142.059152)
		(end 149.117812 -142.3162)
		(width 0.14224)
		(layer "In4.Cu")
		(net "M_L_DQ<63>")
	)
	(segment
		(start 149.411436 -128.28397)
		(end 149.761702 -128.28397)
		(width 0.14224)
		(layer "In4.Cu")
		(net "M_L_DQ<63>")
	)
	(segment
		(start 149.256496 -128.12903)
		(end 149.411436 -128.28397)
		(width 0.14224)
		(layer "In4.Cu")
		(net "M_L_DQ<63>")
	)
	(segment
		(start 148.860764 -141.785848)
		(end 148.860764 -142.059152)
		(width 0.14224)
		(layer "In4.Cu")
		(net "M_L_DQ<63>")
	)
	(segment
		(start 149.984968 -136.652)
		(end 149.984968 -138.811)
		(width 0.14224)
		(layer "In4.Cu")
		(net "M_L_DQ<63>")
	)
	(segment
		(start 150.130764 -130.087878)
		(end 150.130764 -131.205478)
		(width 0.14224)
		(layer "In4.Cu")
		(net "M_L_DQ<63>")
	)
	(segment
		(start 126.163578 -105.138982)
		(end 126.16307 -105.13949)
		(width 0.0889)
		(layer "In4.Cu")
		(net "M_L_DQ<63>")
	)
	(segment
		(start 150.130764 -131.205478)
		(end 149.851364 -131.484878)
		(width 0.14224)
		(layer "In4.Cu")
		(net "M_L_DQ<63>")
	)
	(segment
		(start 149.902164 -138.893804)
		(end 149.902164 -139.590272)
		(width 0.14224)
		(layer "In4.Cu")
		(net "M_L_DQ<63>")
	)
	(segment
		(start 149.927564 -134.526782)
		(end 150.071328 -134.670546)
		(width 0.14224)
		(layer "In4.Cu")
		(net "M_L_DQ<63>")
	)
	(segment
		(start 127.332994 -106.0196)
		(end 130.13817 -106.0196)
		(width 0.14224)
		(layer "In4.Cu")
		(net "M_L_DQ<63>")
	)
	(segment
		(start 126.299722 -105.374948)
		(end 126.58852 -105.664508)
		(width 0.0889)
		(layer "In4.Cu")
		(net "M_L_DQ<63>")
	)
	(segment
		(start 149.149562 -143.44015)
		(end 149.149562 -143.763746)
		(width 0.14224)
		(layer "In4.Cu")
		(net "M_L_DQ<63>")
	)
	(segment
		(start 149.902164 -136.252458)
		(end 149.902164 -136.569196)
		(width 0.14224)
		(layer "In4.Cu")
		(net "M_L_DQ<63>")
	)
	(segment
		(start 123.588018 -102.262686)
		(end 123.583192 -102.271322)
		(width 0.0889)
		(layer "In4.Cu")
		(net "M_L_DQ<63>")
	)
	(segment
		(start 149.916642 -124.424186)
		(end 149.916642 -126.14021)
		(width 0.14224)
		(layer "In4.Cu")
		(net "M_L_DQ<63>")
	)
	(segment
		(start 149.411436 -126.29515)
		(end 149.256496 -126.45009)
		(width 0.14224)
		(layer "In4.Cu")
		(net "M_L_DQ<63>")
	)
	(segment
		(start 149.851364 -131.484878)
		(end 149.851364 -131.746752)
		(width 0.14224)
		(layer "In4.Cu")
		(net "M_L_DQ<63>")
	)
	(segment
		(start 149.098762 -140.3604)
		(end 149.098762 -140.790168)
		(width 0.14224)
		(layer "In4.Cu")
		(net "M_L_DQ<63>")
	)
	(segment
		(start 123.594368 -102.252018)
		(end 123.588018 -102.262686)
		(width 0.0889)
		(layer "In4.Cu")
		(net "M_L_DQ<63>")
	)
	(segment
		(start 149.411436 -127.62103)
		(end 149.256496 -127.77597)
		(width 0.14224)
		(layer "In4.Cu")
		(net "M_L_DQ<63>")
	)
	(segment
		(start 149.902164 -136.569196)
		(end 149.984968 -136.652)
		(width 0.14224)
		(layer "In4.Cu")
		(net "M_L_DQ<63>")
	)
	(segment
		(start 149.527006 -139.932156)
		(end 149.098762 -140.3604)
		(width 0.14224)
		(layer "In4.Cu")
		(net "M_L_DQ<63>")
	)
	(segment
		(start 126.16307 -105.13949)
		(end 126.299722 -105.374948)
		(width 0.0889)
		(layer "In4.Cu")
		(net "M_L_DQ<63>")
	)
	(segment
		(start 123.588018 -103.253286)
		(end 123.583192 -103.261922)
		(width 0.0889)
		(layer "In4.Cu")
		(net "M_L_DQ<63>")
	)
	(segment
		(start 150.313644 -132.209032)
		(end 150.313644 -132.421884)
		(width 0.14224)
		(layer "In4.Cu")
		(net "M_L_DQ<63>")
	)
	(segment
		(start 149.984968 -138.811)
		(end 149.902164 -138.893804)
		(width 0.14224)
		(layer "In4.Cu")
		(net "M_L_DQ<63>")
	)
	(segment
		(start 149.916642 -126.14021)
		(end 149.761702 -126.29515)
		(width 0.14224)
		(layer "In4.Cu")
		(net "M_L_DQ<63>")
	)
	(segment
		(start 149.761702 -128.28397)
		(end 149.916642 -128.43891)
		(width 0.14224)
		(layer "In4.Cu")
		(net "M_L_DQ<63>")
	)
	(segment
		(start 149.143212 -140.834618)
		(end 149.143212 -141.5034)
		(width 0.14224)
		(layer "In4.Cu")
		(net "M_L_DQ<63>")
	)
	(segment
		(start 150.158704 -132.576824)
		(end 149.883622 -132.576824)
		(width 0.14224)
		(layer "In4.Cu")
		(net "M_L_DQ<63>")
	)
	(segment
		(start 123.594368 -103.242618)
		(end 123.588018 -103.253286)
		(width 0.0889)
		(layer "In4.Cu")
		(net "M_L_DQ<63>")
	)
	(segment
		(start 150.313644 -133.761988)
		(end 149.927564 -134.148068)
		(width 0.14224)
		(layer "In4.Cu")
		(net "M_L_DQ<63>")
	)
	(segment
		(start 123.065032 -101.376988)
		(end 123.097798 -101.376988)
		(width 0.0889)
		(layer "In4.Cu")
		(net "M_L_DQ<63>")
	)
	(segment
		(start 126.58852 -105.664508)
		(end 126.977902 -105.664508)
		(width 0.0889)
		(layer "In4.Cu")
		(net "M_L_DQ<63>")
	)
	(segment
		(start 149.411436 -126.95809)
		(end 149.761702 -126.95809)
		(width 0.14224)
		(layer "In4.Cu")
		(net "M_L_DQ<63>")
	)
	(segment
		(start 149.728682 -132.731764)
		(end 149.728682 -133.234684)
		(width 0.14224)
		(layer "In4.Cu")
		(net "M_L_DQ<63>")
	)
	(segment
		(start 149.851364 -131.746752)
		(end 150.313644 -132.209032)
		(width 0.14224)
		(layer "In4.Cu")
		(net "M_L_DQ<63>")
	)
	(arc
		(start 122.729498 -99.786186)
		(mid 122.676028 -99.981249)
		(end 122.724672 -100.1776)
		(width 0.0889)
		(layer "In4.Cu")
		(net "M_L_DQ<63>")
	)
	(arc
		(start 123.097798 -101.376988)
		(mid 123.590188 -101.675921)
		(end 123.594368 -102.252018)
		(width 0.0889)
		(layer "In4.Cu")
		(net "M_L_DQ<63>")
	)
	(arc
		(start 125.673358 -104.843834)
		(mid 125.956575 -104.928115)
		(end 126.163578 -105.138982)
		(width 0.0889)
		(layer "In4.Cu")
		(net "M_L_DQ<63>")
	)
	(arc
		(start 123.588018 -102.662736)
		(mid 123.66724 -102.951854)
		(end 123.594368 -103.242618)
		(width 0.0889)
		(layer "In4.Cu")
		(net "M_L_DQ<63>")
	)
	(arc
		(start 123.583192 -103.261922)
		(mid 123.586939 -103.651178)
		(end 123.919742 -103.853234)
		(width 0.0889)
		(layer "In4.Cu")
		(net "M_L_DQ<63>")
	)
	(arc
		(start 124.446538 -104.148636)
		(mid 124.588221 -104.29244)
		(end 124.782072 -104.348788)
		(width 0.0889)
		(layer "In4.Cu")
		(net "M_L_DQ<63>")
	)
	(arc
		(start 122.729498 -97.214182)
		(mid 122.808629 -97.509584)
		(end 122.729498 -97.804986)
		(width 0.0889)
		(layer "In4.Cu")
		(net "M_L_DQ<63>")
	)
	(arc
		(start 122.735848 -99.206304)
		(mid 122.808646 -99.497067)
		(end 122.729498 -99.786186)
		(width 0.0889)
		(layer "In4.Cu")
		(net "M_L_DQ<63>")
	)
	(arc
		(start 122.729498 -98.204782)
		(mid 122.808629 -98.500184)
		(end 122.729498 -98.795586)
		(width 0.0889)
		(layer "In4.Cu")
		(net "M_L_DQ<63>")
	)
	(arc
		(start 122.729498 -97.804986)
		(mid 122.675999 -98.004884)
		(end 122.729498 -98.204782)
		(width 0.0889)
		(layer "In4.Cu")
		(net "M_L_DQ<63>")
	)
	(arc
		(start 122.735848 -100.196904)
		(mid 122.808646 -100.487667)
		(end 122.729498 -100.776786)
		(width 0.0889)
		(layer "In4.Cu")
		(net "M_L_DQ<63>")
	)
	(arc
		(start 122.692922 -96.138492)
		(mid 122.708725 -96.182106)
		(end 122.729498 -96.223582)
		(width 0.0889)
		(layer "In4.Cu")
		(net "M_L_DQ<63>")
	)
	(arc
		(start 122.729498 -96.223582)
		(mid 122.808561 -96.518984)
		(end 122.729498 -96.814386)
		(width 0.0889)
		(layer "In4.Cu")
		(net "M_L_DQ<63>")
	)
	(arc
		(start 122.729498 -98.795586)
		(mid 122.675919 -99.001837)
		(end 122.735848 -99.206304)
		(width 0.0889)
		(layer "In4.Cu")
		(net "M_L_DQ<63>")
	)
	(arc
		(start 123.583192 -102.271322)
		(mid 123.534437 -102.467674)
		(end 123.588018 -102.662736)
		(width 0.0889)
		(layer "In4.Cu")
		(net "M_L_DQ<63>")
	)
	(arc
		(start 122.729498 -96.814386)
		(mid 122.675999 -97.014284)
		(end 122.729498 -97.214182)
		(width 0.0889)
		(layer "In4.Cu")
		(net "M_L_DQ<63>")
	)
	(arc
		(start 122.729498 -100.776786)
		(mid 122.72675 -101.172253)
		(end 123.065032 -101.376988)
		(width 0.0889)
		(layer "In4.Cu")
		(net "M_L_DQ<63>")
	)
	(arc
		(start 125.305058 -104.643936)
		(mid 125.445137 -104.786672)
		(end 125.636782 -104.843834)
		(width 0.0889)
		(layer "In4.Cu")
		(net "M_L_DQ<63>")
	)
	(arc
		(start 124.814838 -104.348788)
		(mid 125.098055 -104.433069)
		(end 125.305058 -104.643936)
		(width 0.0889)
		(layer "In4.Cu")
		(net "M_L_DQ<63>")
	)
	(arc
		(start 122.654822 -96.008444)
		(mid 122.672374 -96.073907)
		(end 122.692922 -96.138492)
		(width 0.0889)
		(layer "In4.Cu")
		(net "M_L_DQ<63>")
	)
	(arc
		(start 123.952508 -103.853234)
		(mid 124.237932 -103.936701)
		(end 124.446538 -104.148636)
		(width 0.0889)
		(layer "In4.Cu")
		(net "M_L_DQ<63>")
	)
	(segment
		(start 149.681692 -146.17192)
		(end 149.681692 -145.95348)
		(width 0.1651)
		(layer "F.Cu")
		(net "M_L_DQ<62>")
	)
	(segment
		(start 149.549612 -145.8214)
		(end 149.549612 -145.516854)
		(width 0.1651)
		(layer "F.Cu")
		(net "M_L_DQ<62>")
	)
	(segment
		(start 149.549612 -147.27174)
		(end 149.549612 -146.304)
		(width 0.1651)
		(layer "F.Cu")
		(net "M_L_DQ<62>")
	)
	(segment
		(start 149.549612 -146.304)
		(end 149.681692 -146.17192)
		(width 0.1651)
		(layer "F.Cu")
		(net "M_L_DQ<62>")
	)
	(segment
		(start 121.646188 -93.547184)
		(end 122.217688 -93.547184)
		(width 0.1651)
		(layer "F.Cu")
		(net "M_L_DQ<62>")
	)
	(segment
		(start 149.549612 -145.516854)
		(end 149.549358 -145.5166)
		(width 0.1651)
		(layer "F.Cu")
		(net "M_L_DQ<62>")
	)
	(segment
		(start 149.681692 -145.95348)
		(end 149.549612 -145.8214)
		(width 0.1651)
		(layer "F.Cu")
		(net "M_L_DQ<62>")
	)
	(segment
		(start 149.549358 -147.27174)
		(end 149.549612 -147.27174)
		(width 0.1651)
		(layer "F.Cu")
		(net "M_L_DQ<62>")
	)
	(via
		(at 122.217688 -93.547184)
		(size 0.508)
		(drill 0.254)
		(layers "F.Cu" "B.Cu")
		(net "M_L_DQ<62>")
	)
	(via
		(at 149.549358 -145.5166)
		(size 0.508)
		(drill 0.254)
		(layers "F.Cu" "B.Cu")
		(net "M_L_DQ<62>")
	)
	(via
		(at 148.699474 -141.213078)
		(size 0.508)
		(drill 0.254)
		(layers "F.Cu" "B.Cu")
		(net "M_L_DQ<62>")
	)
	(segment
		(start 148.699474 -142.477236)
		(end 148.699474 -141.213078)
		(width 0.1651)
		(layer "B.Cu")
		(net "M_L_DQ<62>")
	)
	(segment
		(start 149.162262 -129.96418)
		(end 149.063964 -130.062478)
		(width 0.14224)
		(layer "In4.Cu")
		(net "M_L_DQ<62>")
	)
	(segment
		(start 142.72641 -119.31904)
		(end 143.975836 -119.31904)
		(width 0.14224)
		(layer "In4.Cu")
		(net "M_L_DQ<62>")
	)
	(segment
		(start 149.216364 -131.953)
		(end 149.121368 -132.047996)
		(width 0.14224)
		(layer "In4.Cu")
		(net "M_L_DQ<62>")
	)
	(segment
		(start 124.775468 -104.539288)
		(end 124.808234 -104.539288)
		(width 0.0889)
		(layer "In4.Cu")
		(net "M_L_DQ<62>")
	)
	(segment
		(start 122.558048 -100.270818)
		(end 122.564398 -100.281486)
		(width 0.0889)
		(layer "In4.Cu")
		(net "M_L_DQ<62>")
	)
	(segment
		(start 148.266404 -141.646148)
		(end 148.266404 -144.233646)
		(width 0.14224)
		(layer "In4.Cu")
		(net "M_L_DQ<62>")
	)
	(segment
		(start 149.121368 -134.0104)
		(end 149.216364 -134.105396)
		(width 0.14224)
		(layer "In4.Cu")
		(net "M_L_DQ<62>")
	)
	(segment
		(start 148.943822 -134.768336)
		(end 148.943822 -135.932926)
		(width 0.14224)
		(layer "In4.Cu")
		(net "M_L_DQ<62>")
	)
	(segment
		(start 126.93015 -106.5149)
		(end 129.92227 -106.5149)
		(width 0.14224)
		(layer "In4.Cu")
		(net "M_L_DQ<62>")
	)
	(segment
		(start 148.798534 -128.856486)
		(end 149.162262 -129.220214)
		(width 0.14224)
		(layer "In4.Cu")
		(net "M_L_DQ<62>")
	)
	(segment
		(start 123.422918 -103.158036)
		(end 123.416568 -103.168704)
		(width 0.0889)
		(layer "In4.Cu")
		(net "M_L_DQ<62>")
	)
	(segment
		(start 149.216364 -134.495794)
		(end 148.943822 -134.768336)
		(width 0.14224)
		(layer "In4.Cu")
		(net "M_L_DQ<62>")
	)
	(segment
		(start 126.153672 -105.502964)
		(end 126.508002 -105.857294)
		(width 0.0889)
		(layer "In4.Cu")
		(net "M_L_DQ<62>")
	)
	(segment
		(start 149.063964 -130.062478)
		(end 149.063964 -131.307078)
		(width 0.14224)
		(layer "In4.Cu")
		(net "M_L_DQ<62>")
	)
	(segment
		(start 148.699474 -141.213078)
		(end 148.266404 -141.646148)
		(width 0.14224)
		(layer "In4.Cu")
		(net "M_L_DQ<62>")
	)
	(segment
		(start 129.92227 -106.5149)
		(end 142.72641 -119.31904)
		(width 0.14224)
		(layer "In4.Cu")
		(net "M_L_DQ<62>")
	)
	(segment
		(start 122.217688 -93.547184)
		(end 121.865644 -94.347538)
		(width 0.0889)
		(layer "In4.Cu")
		(net "M_L_DQ<62>")
	)
	(segment
		(start 149.121368 -132.047996)
		(end 149.121368 -134.0104)
		(width 0.14224)
		(layer "In4.Cu")
		(net "M_L_DQ<62>")
	)
	(segment
		(start 122.564398 -100.281486)
		(end 122.569224 -100.290122)
		(width 0.0889)
		(layer "In4.Cu")
		(net "M_L_DQ<62>")
	)
	(segment
		(start 123.427744 -103.1494)
		(end 123.422918 -103.158036)
		(width 0.0889)
		(layer "In4.Cu")
		(net "M_L_DQ<62>")
	)
	(segment
		(start 149.216364 -134.105396)
		(end 149.216364 -134.495794)
		(width 0.14224)
		(layer "In4.Cu")
		(net "M_L_DQ<62>")
	)
	(segment
		(start 126.508002 -106.092752)
		(end 126.93015 -106.5149)
		(width 0.14224)
		(layer "In4.Cu")
		(net "M_L_DQ<62>")
	)
	(segment
		(start 148.266404 -144.233646)
		(end 149.549358 -145.5166)
		(width 0.14224)
		(layer "In4.Cu")
		(net "M_L_DQ<62>")
	)
	(segment
		(start 149.267164 -136.256268)
		(end 149.267164 -136.4996)
		(width 0.14224)
		(layer "In4.Cu")
		(net "M_L_DQ<62>")
	)
	(segment
		(start 149.121368 -138.7348)
		(end 149.267164 -138.880596)
		(width 0.14224)
		(layer "In4.Cu")
		(net "M_L_DQ<62>")
	)
	(segment
		(start 125.630178 -105.034334)
		(end 125.662944 -105.034334)
		(width 0.0889)
		(layer "In4.Cu")
		(net "M_L_DQ<62>")
	)
	(segment
		(start 148.943822 -135.932926)
		(end 149.267164 -136.256268)
		(width 0.14224)
		(layer "In4.Cu")
		(net "M_L_DQ<62>")
	)
	(segment
		(start 148.798534 -124.141738)
		(end 148.798534 -128.856486)
		(width 0.14224)
		(layer "In4.Cu")
		(net "M_L_DQ<62>")
	)
	(segment
		(start 149.162262 -129.220214)
		(end 149.162262 -129.96418)
		(width 0.14224)
		(layer "In4.Cu")
		(net "M_L_DQ<62>")
	)
	(segment
		(start 148.530564 -141.044168)
		(end 148.699474 -141.213078)
		(width 0.14224)
		(layer "In4.Cu")
		(net "M_L_DQ<62>")
	)
	(segment
		(start 125.998478 -105.234486)
		(end 126.153672 -105.502964)
		(width 0.0889)
		(layer "In4.Cu")
		(net "M_L_DQ<62>")
	)
	(segment
		(start 123.427744 -102.1588)
		(end 123.422918 -102.167436)
		(width 0.0889)
		(layer "In4.Cu")
		(net "M_L_DQ<62>")
	)
	(segment
		(start 123.913138 -104.043734)
		(end 123.945904 -104.043734)
		(width 0.0889)
		(layer "In4.Cu")
		(net "M_L_DQ<62>")
	)
	(segment
		(start 123.422918 -102.167436)
		(end 123.416568 -102.178104)
		(width 0.0889)
		(layer "In4.Cu")
		(net "M_L_DQ<62>")
	)
	(segment
		(start 149.216364 -131.459478)
		(end 149.216364 -131.953)
		(width 0.14224)
		(layer "In4.Cu")
		(net "M_L_DQ<62>")
	)
	(segment
		(start 149.267164 -138.880596)
		(end 149.267164 -139.333478)
		(width 0.14224)
		(layer "In4.Cu")
		(net "M_L_DQ<62>")
	)
	(segment
		(start 149.121368 -136.645396)
		(end 149.121368 -138.7348)
		(width 0.14224)
		(layer "In4.Cu")
		(net "M_L_DQ<62>")
	)
	(segment
		(start 148.530564 -140.070078)
		(end 148.530564 -141.044168)
		(width 0.14224)
		(layer "In4.Cu")
		(net "M_L_DQ<62>")
	)
	(segment
		(start 149.267164 -139.333478)
		(end 148.530564 -140.070078)
		(width 0.14224)
		(layer "In4.Cu")
		(net "M_L_DQ<62>")
	)
	(segment
		(start 149.063964 -131.307078)
		(end 149.216364 -131.459478)
		(width 0.14224)
		(layer "In4.Cu")
		(net "M_L_DQ<62>")
	)
	(segment
		(start 126.508002 -105.857294)
		(end 126.508002 -106.092752)
		(width 0.0889)
		(layer "In4.Cu")
		(net "M_L_DQ<62>")
	)
	(segment
		(start 149.267164 -136.4996)
		(end 149.121368 -136.645396)
		(width 0.14224)
		(layer "In4.Cu")
		(net "M_L_DQ<62>")
	)
	(segment
		(start 123.058428 -101.567488)
		(end 123.091194 -101.567488)
		(width 0.0889)
		(layer "In4.Cu")
		(net "M_L_DQ<62>")
	)
	(segment
		(start 143.975836 -119.31904)
		(end 148.798534 -124.141738)
		(width 0.14224)
		(layer "In4.Cu")
		(net "M_L_DQ<62>")
	)
	(segment
		(start 122.564398 -99.290886)
		(end 122.569224 -99.299522)
		(width 0.0889)
		(layer "In4.Cu")
		(net "M_L_DQ<62>")
	)
	(arc
		(start 122.564398 -97.309686)
		(mid 122.617897 -97.509584)
		(end 122.564398 -97.709482)
		(width 0.0889)
		(layer "In4.Cu")
		(net "M_L_DQ<62>")
	)
	(arc
		(start 123.416568 -103.168704)
		(mid 123.420599 -103.744886)
		(end 123.913138 -104.043734)
		(width 0.0889)
		(layer "In4.Cu")
		(net "M_L_DQ<62>")
	)
	(arc
		(start 124.808234 -104.539288)
		(mid 124.999876 -104.596454)
		(end 125.139958 -104.739186)
		(width 0.0889)
		(layer "In4.Cu")
		(net "M_L_DQ<62>")
	)
	(arc
		(start 122.564398 -98.300286)
		(mid 122.617897 -98.500184)
		(end 122.564398 -98.700082)
		(width 0.0889)
		(layer "In4.Cu")
		(net "M_L_DQ<62>")
	)
	(arc
		(start 122.569224 -100.290122)
		(mid 122.617979 -100.486474)
		(end 122.564398 -100.681536)
		(width 0.0889)
		(layer "In4.Cu")
		(net "M_L_DQ<62>")
	)
	(arc
		(start 121.865644 -94.347538)
		(mid 121.817565 -94.543298)
		(end 121.870978 -94.737682)
		(width 0.0889)
		(layer "In4.Cu")
		(net "M_L_DQ<62>")
	)
	(arc
		(start 122.569224 -99.299522)
		(mid 122.617979 -99.495874)
		(end 122.564398 -99.690936)
		(width 0.0889)
		(layer "In4.Cu")
		(net "M_L_DQ<62>")
	)
	(arc
		(start 123.416568 -102.178104)
		(mid 123.34377 -102.468867)
		(end 123.422918 -102.757986)
		(width 0.0889)
		(layer "In4.Cu")
		(net "M_L_DQ<62>")
	)
	(arc
		(start 125.662944 -105.034334)
		(mid 125.856794 -105.090684)
		(end 125.998478 -105.234486)
		(width 0.0889)
		(layer "In4.Cu")
		(net "M_L_DQ<62>")
	)
	(arc
		(start 121.943368 -95.819722)
		(mid 122.159971 -96.010704)
		(end 122.404124 -96.164908)
		(width 0.0889)
		(layer "In4.Cu")
		(net "M_L_DQ<62>")
	)
	(arc
		(start 125.139958 -104.739186)
		(mid 125.346962 -104.95005)
		(end 125.630178 -105.034334)
		(width 0.0889)
		(layer "In4.Cu")
		(net "M_L_DQ<62>")
	)
	(arc
		(start 122.564398 -100.681536)
		(mid 122.560069 -101.264708)
		(end 123.058428 -101.567488)
		(width 0.0889)
		(layer "In4.Cu")
		(net "M_L_DQ<62>")
	)
	(arc
		(start 123.422918 -102.757986)
		(mid 123.476388 -102.953049)
		(end 123.427744 -103.1494)
		(width 0.0889)
		(layer "In4.Cu")
		(net "M_L_DQ<62>")
	)
	(arc
		(start 122.404124 -96.164908)
		(mid 122.495235 -96.230595)
		(end 122.564398 -96.319086)
		(width 0.0889)
		(layer "In4.Cu")
		(net "M_L_DQ<62>")
	)
	(arc
		(start 123.945904 -104.043734)
		(mid 124.139754 -104.100084)
		(end 124.281438 -104.243886)
		(width 0.0889)
		(layer "In4.Cu")
		(net "M_L_DQ<62>")
	)
	(arc
		(start 122.564398 -99.690936)
		(mid 122.485176 -99.980054)
		(end 122.558048 -100.270818)
		(width 0.0889)
		(layer "In4.Cu")
		(net "M_L_DQ<62>")
	)
	(arc
		(start 121.870978 -95.328486)
		(mid 121.821751 -95.5867)
		(end 121.943368 -95.819722)
		(width 0.0889)
		(layer "In4.Cu")
		(net "M_L_DQ<62>")
	)
	(arc
		(start 122.564398 -98.700082)
		(mid 122.485335 -98.995484)
		(end 122.564398 -99.290886)
		(width 0.0889)
		(layer "In4.Cu")
		(net "M_L_DQ<62>")
	)
	(arc
		(start 122.564398 -96.718882)
		(mid 122.485267 -97.014284)
		(end 122.564398 -97.309686)
		(width 0.0889)
		(layer "In4.Cu")
		(net "M_L_DQ<62>")
	)
	(arc
		(start 121.870978 -94.737682)
		(mid 121.950109 -95.033084)
		(end 121.870978 -95.328486)
		(width 0.0889)
		(layer "In4.Cu")
		(net "M_L_DQ<62>")
	)
	(arc
		(start 124.281438 -104.243886)
		(mid 124.490046 -104.455818)
		(end 124.775468 -104.539288)
		(width 0.0889)
		(layer "In4.Cu")
		(net "M_L_DQ<62>")
	)
	(arc
		(start 122.564398 -97.709482)
		(mid 122.485267 -98.004884)
		(end 122.564398 -98.300286)
		(width 0.0889)
		(layer "In4.Cu")
		(net "M_L_DQ<62>")
	)
	(arc
		(start 123.091194 -101.567488)
		(mid 123.424112 -101.769479)
		(end 123.427744 -102.1588)
		(width 0.0889)
		(layer "In4.Cu")
		(net "M_L_DQ<62>")
	)
	(arc
		(start 122.564398 -96.319086)
		(mid 122.617931 -96.518984)
		(end 122.564398 -96.718882)
		(width 0.0889)
		(layer "In4.Cu")
		(net "M_L_DQ<62>")
	)
	(segment
		(start 119.070882 -95.033084)
		(end 119.642382 -95.033084)
		(width 0.1651)
		(layer "F.Cu")
		(net "M_L_DQ<61>")
	)
	(segment
		(start 142.749524 -142.6718)
		(end 142.749524 -143.941546)
		(width 0.1651)
		(layer "F.Cu")
		(net "M_L_DQ<61>")
	)
	(via
		(at 119.642382 -95.033084)
		(size 0.508)
		(drill 0.254)
		(layers "F.Cu" "B.Cu")
		(net "M_L_DQ<61>")
	)
	(via
		(at 142.749524 -143.941546)
		(size 0.508)
		(drill 0.254)
		(layers "F.Cu" "B.Cu")
		(net "M_L_DQ<61>")
	)
	(via
		(at 143.577564 -139.845796)
		(size 0.508)
		(drill 0.254)
		(layers "F.Cu" "B.Cu")
		(net "M_L_DQ<61>")
	)
	(segment
		(start 143.599408 -139.823952)
		(end 143.577564 -139.845796)
		(width 0.1651)
		(layer "B.Cu")
		(net "M_L_DQ<61>")
	)
	(segment
		(start 143.599408 -137.877296)
		(end 143.599408 -139.823952)
		(width 0.1651)
		(layer "B.Cu")
		(net "M_L_DQ<61>")
	)
	(segment
		(start 140.311886 -122.473212)
		(end 140.156946 -122.318272)
		(width 0.14224)
		(layer "In4.Cu")
		(net "M_L_DQ<61>")
	)
	(segment
		(start 143.072612 -140.9192)
		(end 143.199612 -141.0462)
		(width 0.14224)
		(layer "In4.Cu")
		(net "M_L_DQ<61>")
	)
	(segment
		(start 138.831066 -122.318272)
		(end 138.831066 -121.925588)
		(width 0.14224)
		(layer "In4.Cu")
		(net "M_L_DQ<61>")
	)
	(segment
		(start 138.676126 -121.770648)
		(end 138.323066 -121.770648)
		(width 0.14224)
		(layer "In4.Cu")
		(net "M_L_DQ<61>")
	)
	(segment
		(start 125.59919 -115.067334)
		(end 122.309128 -111.777272)
		(width 0.14224)
		(layer "In4.Cu")
		(net "M_L_DQ<61>")
	)
	(segment
		(start 138.013186 -122.473212)
		(end 136.059926 -122.473212)
		(width 0.14224)
		(layer "In4.Cu")
		(net "M_L_DQ<61>")
	)
	(segment
		(start 119.295672 -101.176836)
		(end 119.290846 -101.1682)
		(width 0.0889)
		(layer "In4.Cu")
		(net "M_L_DQ<61>")
	)
	(segment
		(start 138.168126 -121.925588)
		(end 138.168126 -122.318272)
		(width 0.14224)
		(layer "In4.Cu")
		(net "M_L_DQ<61>")
	)
	(segment
		(start 143.907764 -125.309884)
		(end 141.071092 -122.473212)
		(width 0.14224)
		(layer "In4.Cu")
		(net "M_L_DQ<61>")
	)
	(segment
		(start 143.933164 -131.953)
		(end 143.933164 -131.434078)
		(width 0.14224)
		(layer "In4.Cu")
		(net "M_L_DQ<61>")
	)
	(segment
		(start 121.38406 -106.32948)
		(end 121.359168 -106.329734)
		(width 0.0889)
		(layer "In4.Cu")
		(net "M_L_DQ<61>")
	)
	(segment
		(start 143.174212 -143.789146)
		(end 143.021812 -143.941546)
		(width 0.14224)
		(layer "In4.Cu")
		(net "M_L_DQ<61>")
	)
	(segment
		(start 143.148812 -142.392654)
		(end 143.148812 -142.747746)
		(width 0.14224)
		(layer "In4.Cu")
		(net "M_L_DQ<61>")
	)
	(segment
		(start 120.149366 -105.243122)
		(end 120.154192 -105.234486)
		(width 0.0889)
		(layer "In4.Cu")
		(net "M_L_DQ<61>")
	)
	(segment
		(start 144.015968 -129.895346)
		(end 143.907764 -129.787142)
		(width 0.14224)
		(layer "In4.Cu")
		(net "M_L_DQ<61>")
	)
	(segment
		(start 119.663972 -103.358188)
		(end 119.631206 -103.358188)
		(width 0.0889)
		(layer "In4.Cu")
		(net "M_L_DQ<61>")
	)
	(segment
		(start 139.494006 -122.318272)
		(end 139.339066 -122.473212)
		(width 0.14224)
		(layer "In4.Cu")
		(net "M_L_DQ<61>")
	)
	(segment
		(start 143.072612 -140.3604)
		(end 143.072612 -140.9192)
		(width 0.14224)
		(layer "In4.Cu")
		(net "M_L_DQ<61>")
	)
	(segment
		(start 144.015968 -136.658604)
		(end 143.907764 -136.5504)
		(width 0.14224)
		(layer "In4.Cu")
		(net "M_L_DQ<61>")
	)
	(segment
		(start 128.654048 -115.067334)
		(end 125.59919 -115.067334)
		(width 0.14224)
		(layer "In4.Cu")
		(net "M_L_DQ<61>")
	)
	(segment
		(start 141.071092 -122.473212)
		(end 140.311886 -122.473212)
		(width 0.14224)
		(layer "In4.Cu")
		(net "M_L_DQ<61>")
	)
	(segment
		(start 143.174212 -143.561054)
		(end 143.174212 -143.789146)
		(width 0.14224)
		(layer "In4.Cu")
		(net "M_L_DQ<61>")
	)
	(segment
		(start 120.149366 -104.252522)
		(end 120.154192 -104.243886)
		(width 0.0889)
		(layer "In4.Cu")
		(net "M_L_DQ<61>")
	)
	(segment
		(start 122.309128 -111.777272)
		(end 122.309128 -107.47756)
		(width 0.14224)
		(layer "In4.Cu")
		(net "M_L_DQ<61>")
	)
	(segment
		(start 121.359168 -106.329734)
		(end 121.346976 -106.329734)
		(width 0.0889)
		(layer "In4.Cu")
		(net "M_L_DQ<61>")
	)
	(segment
		(start 144.060164 -135.853424)
		(end 144.060164 -134.797038)
		(width 0.14224)
		(layer "In4.Cu")
		(net "M_L_DQ<61>")
	)
	(segment
		(start 138.323066 -121.770648)
		(end 138.168126 -121.925588)
		(width 0.14224)
		(layer "In4.Cu")
		(net "M_L_DQ<61>")
	)
	(segment
		(start 143.577564 -139.845796)
		(end 143.609568 -139.845796)
		(width 0.14224)
		(layer "In4.Cu")
		(net "M_L_DQ<61>")
	)
	(segment
		(start 139.339066 -122.473212)
		(end 138.986006 -122.473212)
		(width 0.14224)
		(layer "In4.Cu")
		(net "M_L_DQ<61>")
	)
	(segment
		(start 138.986006 -122.473212)
		(end 138.831066 -122.318272)
		(width 0.14224)
		(layer "In4.Cu")
		(net "M_L_DQ<61>")
	)
	(segment
		(start 143.907764 -139.5476)
		(end 143.907764 -138.944604)
		(width 0.14224)
		(layer "In4.Cu")
		(net "M_L_DQ<61>")
	)
	(segment
		(start 143.907764 -136.005824)
		(end 144.060164 -135.853424)
		(width 0.14224)
		(layer "In4.Cu")
		(net "M_L_DQ<61>")
	)
	(segment
		(start 140.156946 -122.318272)
		(end 140.156946 -121.925588)
		(width 0.14224)
		(layer "In4.Cu")
		(net "M_L_DQ<61>")
	)
	(segment
		(start 122.046492 -107.214924)
		(end 122.046492 -106.929682)
		(width 0.0889)
		(layer "In4.Cu")
		(net "M_L_DQ<61>")
	)
	(segment
		(start 140.156946 -121.925588)
		(end 140.002006 -121.770648)
		(width 0.14224)
		(layer "In4.Cu")
		(net "M_L_DQ<61>")
	)
	(segment
		(start 143.148812 -142.747746)
		(end 142.910814 -142.985744)
		(width 0.14224)
		(layer "In4.Cu")
		(net "M_L_DQ<61>")
	)
	(segment
		(start 144.041368 -132.061204)
		(end 143.933164 -131.953)
		(width 0.14224)
		(layer "In4.Cu")
		(net "M_L_DQ<61>")
	)
	(segment
		(start 142.910814 -143.297656)
		(end 143.174212 -143.561054)
		(width 0.14224)
		(layer "In4.Cu")
		(net "M_L_DQ<61>")
	)
	(segment
		(start 143.021812 -143.941546)
		(end 142.749524 -143.941546)
		(width 0.14224)
		(layer "In4.Cu")
		(net "M_L_DQ<61>")
	)
	(segment
		(start 143.577564 -139.855448)
		(end 143.072612 -140.3604)
		(width 0.14224)
		(layer "In4.Cu")
		(net "M_L_DQ<61>")
	)
	(segment
		(start 143.933164 -131.434078)
		(end 144.015968 -131.351274)
		(width 0.14224)
		(layer "In4.Cu")
		(net "M_L_DQ<61>")
	)
	(segment
		(start 142.910814 -141.817344)
		(end 142.910814 -142.154656)
		(width 0.14224)
		(layer "In4.Cu")
		(net "M_L_DQ<61>")
	)
	(segment
		(start 142.910814 -142.985744)
		(end 142.910814 -143.297656)
		(width 0.14224)
		(layer "In4.Cu")
		(net "M_L_DQ<61>")
	)
	(segment
		(start 119.295672 -102.167436)
		(end 119.290846 -102.1588)
		(width 0.0889)
		(layer "In4.Cu")
		(net "M_L_DQ<61>")
	)
	(segment
		(start 142.910814 -142.154656)
		(end 143.148812 -142.392654)
		(width 0.14224)
		(layer "In4.Cu")
		(net "M_L_DQ<61>")
	)
	(segment
		(start 138.831066 -121.925588)
		(end 138.676126 -121.770648)
		(width 0.14224)
		(layer "In4.Cu")
		(net "M_L_DQ<61>")
	)
	(segment
		(start 143.199612 -141.0462)
		(end 143.199612 -141.528546)
		(width 0.14224)
		(layer "In4.Cu")
		(net "M_L_DQ<61>")
	)
	(segment
		(start 119.302022 -101.187504)
		(end 119.295672 -101.176836)
		(width 0.0889)
		(layer "In4.Cu")
		(net "M_L_DQ<61>")
	)
	(segment
		(start 120.518682 -105.834434)
		(end 120.485916 -105.834434)
		(width 0.0889)
		(layer "In4.Cu")
		(net "M_L_DQ<61>")
	)
	(segment
		(start 144.060164 -134.797038)
		(end 143.933164 -134.670038)
		(width 0.14224)
		(layer "In4.Cu")
		(net "M_L_DQ<61>")
	)
	(segment
		(start 139.648946 -121.770648)
		(end 139.494006 -121.925588)
		(width 0.14224)
		(layer "In4.Cu")
		(net "M_L_DQ<61>")
	)
	(segment
		(start 144.015968 -131.351274)
		(end 144.015968 -129.895346)
		(width 0.14224)
		(layer "In4.Cu")
		(net "M_L_DQ<61>")
	)
	(segment
		(start 119.302022 -100.196904)
		(end 119.295672 -100.186236)
		(width 0.0889)
		(layer "In4.Cu")
		(net "M_L_DQ<61>")
	)
	(segment
		(start 136.059926 -122.473212)
		(end 128.654048 -115.067334)
		(width 0.14224)
		(layer "In4.Cu")
		(net "M_L_DQ<61>")
	)
	(segment
		(start 138.168126 -122.318272)
		(end 138.013186 -122.473212)
		(width 0.14224)
		(layer "In4.Cu")
		(net "M_L_DQ<61>")
	)
	(segment
		(start 143.933164 -134.670038)
		(end 143.933164 -134.093204)
		(width 0.14224)
		(layer "In4.Cu")
		(net "M_L_DQ<61>")
	)
	(segment
		(start 143.199612 -141.528546)
		(end 142.910814 -141.817344)
		(width 0.14224)
		(layer "In4.Cu")
		(net "M_L_DQ<61>")
	)
	(segment
		(start 143.933164 -134.093204)
		(end 144.041368 -133.985)
		(width 0.14224)
		(layer "In4.Cu")
		(net "M_L_DQ<61>")
	)
	(segment
		(start 140.002006 -121.770648)
		(end 139.648946 -121.770648)
		(width 0.14224)
		(layer "In4.Cu")
		(net "M_L_DQ<61>")
	)
	(segment
		(start 143.609568 -139.845796)
		(end 143.907764 -139.5476)
		(width 0.14224)
		(layer "In4.Cu")
		(net "M_L_DQ<61>")
	)
	(segment
		(start 119.302022 -102.178104)
		(end 119.295672 -102.167436)
		(width 0.0889)
		(layer "In4.Cu")
		(net "M_L_DQ<61>")
	)
	(segment
		(start 143.907764 -129.787142)
		(end 143.907764 -125.309884)
		(width 0.14224)
		(layer "In4.Cu")
		(net "M_L_DQ<61>")
	)
	(segment
		(start 119.295672 -100.186236)
		(end 119.290846 -100.1776)
		(width 0.0889)
		(layer "In4.Cu")
		(net "M_L_DQ<61>")
	)
	(segment
		(start 120.154192 -105.234486)
		(end 120.160542 -105.223818)
		(width 0.0889)
		(layer "In4.Cu")
		(net "M_L_DQ<61>")
	)
	(segment
		(start 122.309128 -107.47756)
		(end 122.046492 -107.214924)
		(width 0.0889)
		(layer "In4.Cu")
		(net "M_L_DQ<61>")
	)
	(segment
		(start 139.494006 -121.925588)
		(end 139.494006 -122.318272)
		(width 0.14224)
		(layer "In4.Cu")
		(net "M_L_DQ<61>")
	)
	(segment
		(start 120.154192 -104.243886)
		(end 120.160542 -104.233218)
		(width 0.0889)
		(layer "In4.Cu")
		(net "M_L_DQ<61>")
	)
	(segment
		(start 122.046492 -106.929682)
		(end 121.871232 -106.624882)
		(width 0.0889)
		(layer "In4.Cu")
		(net "M_L_DQ<61>")
	)
	(segment
		(start 143.907764 -138.944604)
		(end 144.015968 -138.8364)
		(width 0.14224)
		(layer "In4.Cu")
		(net "M_L_DQ<61>")
	)
	(segment
		(start 143.577564 -139.845796)
		(end 143.577564 -139.855448)
		(width 0.14224)
		(layer "In4.Cu")
		(net "M_L_DQ<61>")
	)
	(segment
		(start 144.041368 -133.985)
		(end 144.041368 -132.061204)
		(width 0.14224)
		(layer "In4.Cu")
		(net "M_L_DQ<61>")
	)
	(segment
		(start 143.907764 -136.5504)
		(end 143.907764 -136.005824)
		(width 0.14224)
		(layer "In4.Cu")
		(net "M_L_DQ<61>")
	)
	(segment
		(start 119.355616 -95.679006)
		(end 119.642382 -95.033084)
		(width 0.0889)
		(layer "In4.Cu")
		(net "M_L_DQ<61>")
	)
	(segment
		(start 144.015968 -138.8364)
		(end 144.015968 -136.658604)
		(width 0.14224)
		(layer "In4.Cu")
		(net "M_L_DQ<61>")
	)
	(arc
		(start 120.160542 -105.223818)
		(mid 120.23334 -104.933055)
		(end 120.154192 -104.643936)
		(width 0.0889)
		(layer "In4.Cu")
		(net "M_L_DQ<61>")
	)
	(arc
		(start 121.871232 -106.624882)
		(mid 121.665615 -106.414541)
		(end 121.38406 -106.32948)
		(width 0.0889)
		(layer "In4.Cu")
		(net "M_L_DQ<61>")
	)
	(arc
		(start 119.295672 -99.786186)
		(mid 119.374894 -99.497068)
		(end 119.302022 -99.206304)
		(width 0.0889)
		(layer "In4.Cu")
		(net "M_L_DQ<61>")
	)
	(arc
		(start 119.295926 -97.804986)
		(mid 119.375057 -97.509584)
		(end 119.295926 -97.214182)
		(width 0.0889)
		(layer "In4.Cu")
		(net "M_L_DQ<61>")
	)
	(arc
		(start 119.295926 -98.795586)
		(mid 119.375057 -98.500184)
		(end 119.295926 -98.204782)
		(width 0.0889)
		(layer "In4.Cu")
		(net "M_L_DQ<61>")
	)
	(arc
		(start 119.290846 -100.1776)
		(mid 119.242091 -99.981248)
		(end 119.295672 -99.786186)
		(width 0.0889)
		(layer "In4.Cu")
		(net "M_L_DQ<61>")
	)
	(arc
		(start 119.290846 -101.1682)
		(mid 119.242091 -100.971848)
		(end 119.295672 -100.776786)
		(width 0.0889)
		(layer "In4.Cu")
		(net "M_L_DQ<61>")
	)
	(arc
		(start 119.295672 -100.776786)
		(mid 119.374894 -100.487668)
		(end 119.302022 -100.196904)
		(width 0.0889)
		(layer "In4.Cu")
		(net "M_L_DQ<61>")
	)
	(arc
		(start 119.631206 -103.358188)
		(mid 119.293037 -103.15339)
		(end 119.295672 -102.757986)
		(width 0.0889)
		(layer "In4.Cu")
		(net "M_L_DQ<61>")
	)
	(arc
		(start 119.295926 -96.814386)
		(mid 119.375057 -96.518984)
		(end 119.295926 -96.223582)
		(width 0.0889)
		(layer "In4.Cu")
		(net "M_L_DQ<61>")
	)
	(arc
		(start 119.295926 -98.204782)
		(mid 119.242427 -98.004884)
		(end 119.295926 -97.804986)
		(width 0.0889)
		(layer "In4.Cu")
		(net "M_L_DQ<61>")
	)
	(arc
		(start 120.154192 -104.643936)
		(mid 120.100722 -104.448873)
		(end 120.149366 -104.252522)
		(width 0.0889)
		(layer "In4.Cu")
		(net "M_L_DQ<61>")
	)
	(arc
		(start 119.290846 -102.1588)
		(mid 119.242091 -101.962448)
		(end 119.295672 -101.767386)
		(width 0.0889)
		(layer "In4.Cu")
		(net "M_L_DQ<61>")
	)
	(arc
		(start 119.295672 -102.757986)
		(mid 119.374894 -102.468868)
		(end 119.302022 -102.178104)
		(width 0.0889)
		(layer "In4.Cu")
		(net "M_L_DQ<61>")
	)
	(arc
		(start 121.012712 -106.129836)
		(mid 120.804104 -105.917904)
		(end 120.518682 -105.834434)
		(width 0.0889)
		(layer "In4.Cu")
		(net "M_L_DQ<61>")
	)
	(arc
		(start 120.160542 -104.233218)
		(mid 120.156511 -103.657036)
		(end 119.663972 -103.358188)
		(width 0.0889)
		(layer "In4.Cu")
		(net "M_L_DQ<61>")
	)
	(arc
		(start 121.346976 -106.329734)
		(mid 121.153873 -106.273215)
		(end 121.012712 -106.129836)
		(width 0.0889)
		(layer "In4.Cu")
		(net "M_L_DQ<61>")
	)
	(arc
		(start 119.302022 -99.206304)
		(mid 119.299011 -99.200822)
		(end 119.295926 -99.195382)
		(width 0.0889)
		(layer "In4.Cu")
		(net "M_L_DQ<61>")
	)
	(arc
		(start 119.295926 -95.823786)
		(mid 119.330581 -95.75338)
		(end 119.355616 -95.679006)
		(width 0.0889)
		(layer "In4.Cu")
		(net "M_L_DQ<61>")
	)
	(arc
		(start 120.485916 -105.834434)
		(mid 120.152998 -105.632443)
		(end 120.149366 -105.243122)
		(width 0.0889)
		(layer "In4.Cu")
		(net "M_L_DQ<61>")
	)
	(arc
		(start 119.295672 -101.767386)
		(mid 119.374894 -101.478268)
		(end 119.302022 -101.187504)
		(width 0.0889)
		(layer "In4.Cu")
		(net "M_L_DQ<61>")
	)
	(arc
		(start 119.295926 -97.214182)
		(mid 119.242427 -97.014284)
		(end 119.295926 -96.814386)
		(width 0.0889)
		(layer "In4.Cu")
		(net "M_L_DQ<61>")
	)
	(arc
		(start 119.295926 -96.223582)
		(mid 119.242427 -96.023684)
		(end 119.295926 -95.823786)
		(width 0.0889)
		(layer "In4.Cu")
		(net "M_L_DQ<61>")
	)
	(arc
		(start 119.295926 -99.195382)
		(mid 119.242427 -98.995484)
		(end 119.295926 -98.795586)
		(width 0.0889)
		(layer "In4.Cu")
		(net "M_L_DQ<61>")
	)
	(segment
		(start 143.599408 -145.946368)
		(end 143.501364 -145.415)
		(width 0.1651)
		(layer "F.Cu")
		(net "M_L_DQ<60>")
	)
	(segment
		(start 119.070882 -94.042738)
		(end 119.642382 -94.042738)
		(width 0.1651)
		(layer "F.Cu")
		(net "M_L_DQ<60>")
	)
	(segment
		(start 143.599408 -147.27174)
		(end 143.599408 -145.946368)
		(width 0.1651)
		(layer "F.Cu")
		(net "M_L_DQ<60>")
	)
	(via
		(at 119.642382 -94.042738)
		(size 0.508)
		(drill 0.254)
		(layers "F.Cu" "B.Cu")
		(net "M_L_DQ<60>")
	)
	(via
		(at 143.501364 -145.415)
		(size 0.508)
		(drill 0.254)
		(layers "F.Cu" "B.Cu")
		(net "M_L_DQ<60>")
	)
	(via
		(at 142.749524 -141.213078)
		(size 0.508)
		(drill 0.254)
		(layers "F.Cu" "B.Cu")
		(net "M_L_DQ<60>")
	)
	(segment
		(start 142.749524 -142.477236)
		(end 142.749524 -141.213078)
		(width 0.1651)
		(layer "B.Cu")
		(net "M_L_DQ<60>")
	)
	(segment
		(start 143.247364 -134.130796)
		(end 143.247364 -134.47395)
		(width 0.14224)
		(layer "In4.Cu")
		(net "M_L_DQ<60>")
	)
	(segment
		(start 142.434564 -140.898118)
		(end 142.749524 -141.213078)
		(width 0.14224)
		(layer "In4.Cu")
		(net "M_L_DQ<60>")
	)
	(segment
		(start 121.705878 -106.720132)
		(end 121.855992 -106.98099)
		(width 0.0889)
		(layer "In4.Cu")
		(net "M_L_DQ<60>")
	)
	(segment
		(start 119.124222 -101.261418)
		(end 119.130572 -101.272086)
		(width 0.0889)
		(layer "In4.Cu")
		(net "M_L_DQ<60>")
	)
	(segment
		(start 143.177768 -136.683496)
		(end 143.177768 -138.7602)
		(width 0.14224)
		(layer "In4.Cu")
		(net "M_L_DQ<60>")
	)
	(segment
		(start 119.130572 -102.262686)
		(end 119.135398 -102.271322)
		(width 0.0889)
		(layer "In4.Cu")
		(net "M_L_DQ<60>")
	)
	(segment
		(start 143.018764 -131.180078)
		(end 143.247364 -131.408678)
		(width 0.14224)
		(layer "In4.Cu")
		(net "M_L_DQ<60>")
	)
	(segment
		(start 143.250412 -145.415)
		(end 143.501364 -145.415)
		(width 0.14224)
		(layer "In4.Cu")
		(net "M_L_DQ<60>")
	)
	(segment
		(start 119.124222 -100.270818)
		(end 119.130572 -100.281486)
		(width 0.0889)
		(layer "In4.Cu")
		(net "M_L_DQ<60>")
	)
	(segment
		(start 142.474442 -144.337278)
		(end 142.474442 -144.63903)
		(width 0.14224)
		(layer "In4.Cu")
		(net "M_L_DQ<60>")
	)
	(segment
		(start 119.124222 -102.252018)
		(end 119.130572 -102.262686)
		(width 0.0889)
		(layer "In4.Cu")
		(net "M_L_DQ<60>")
	)
	(segment
		(start 119.989092 -104.148636)
		(end 119.982742 -104.159304)
		(width 0.0889)
		(layer "In4.Cu")
		(net "M_L_DQ<60>")
	)
	(segment
		(start 142.749524 -141.213078)
		(end 142.316454 -141.646148)
		(width 0.14224)
		(layer "In4.Cu")
		(net "M_L_DQ<60>")
	)
	(segment
		(start 142.316454 -144.17929)
		(end 142.474442 -144.337278)
		(width 0.14224)
		(layer "In4.Cu")
		(net "M_L_DQ<60>")
	)
	(segment
		(start 120.479312 -106.024934)
		(end 120.500902 -106.024934)
		(width 0.0889)
		(layer "In4.Cu")
		(net "M_L_DQ<60>")
	)
	(segment
		(start 143.247364 -131.8768)
		(end 143.177768 -131.946396)
		(width 0.14224)
		(layer "In4.Cu")
		(net "M_L_DQ<60>")
	)
	(segment
		(start 142.981172 -134.740142)
		(end 142.981172 -135.926576)
		(width 0.14224)
		(layer "In4.Cu")
		(net "M_L_DQ<60>")
	)
	(segment
		(start 143.247364 -131.408678)
		(end 143.247364 -131.8768)
		(width 0.14224)
		(layer "In4.Cu")
		(net "M_L_DQ<60>")
	)
	(segment
		(start 143.234664 -138.817096)
		(end 143.234664 -139.358878)
		(width 0.14224)
		(layer "In4.Cu")
		(net "M_L_DQ<60>")
	)
	(segment
		(start 143.177768 -138.7602)
		(end 143.234664 -138.817096)
		(width 0.14224)
		(layer "In4.Cu")
		(net "M_L_DQ<60>")
	)
	(segment
		(start 121.855992 -107.186476)
		(end 121.674128 -107.36834)
		(width 0.0889)
		(layer "In4.Cu")
		(net "M_L_DQ<60>")
	)
	(segment
		(start 121.674128 -107.36834)
		(end 121.674128 -111.819436)
		(width 0.14224)
		(layer "In4.Cu")
		(net "M_L_DQ<60>")
	)
	(segment
		(start 143.234664 -136.180068)
		(end 143.234664 -136.6266)
		(width 0.14224)
		(layer "In4.Cu")
		(net "M_L_DQ<60>")
	)
	(segment
		(start 143.272764 -125.93066)
		(end 143.272764 -129.732278)
		(width 0.14224)
		(layer "In4.Cu")
		(net "M_L_DQ<60>")
	)
	(segment
		(start 142.474442 -144.63903)
		(end 143.250412 -145.415)
		(width 0.14224)
		(layer "In4.Cu")
		(net "M_L_DQ<60>")
	)
	(segment
		(start 120.844056 -106.219244)
		(end 120.847358 -106.225086)
		(width 0.0889)
		(layer "In4.Cu")
		(net "M_L_DQ<60>")
	)
	(segment
		(start 121.674128 -111.819436)
		(end 125.400816 -115.546124)
		(width 0.14224)
		(layer "In4.Cu")
		(net "M_L_DQ<60>")
	)
	(segment
		(start 143.177768 -134.0612)
		(end 143.247364 -134.130796)
		(width 0.14224)
		(layer "In4.Cu")
		(net "M_L_DQ<60>")
	)
	(segment
		(start 119.130572 -100.281486)
		(end 119.135398 -100.290122)
		(width 0.0889)
		(layer "In4.Cu")
		(net "M_L_DQ<60>")
	)
	(segment
		(start 119.642382 -94.042738)
		(end 119.099076 -94.801436)
		(width 0.0889)
		(layer "In4.Cu")
		(net "M_L_DQ<60>")
	)
	(segment
		(start 142.316454 -141.646148)
		(end 142.316454 -144.17929)
		(width 0.14224)
		(layer "In4.Cu")
		(net "M_L_DQ<60>")
	)
	(segment
		(start 119.993918 -104.14)
		(end 119.989092 -104.148636)
		(width 0.0889)
		(layer "In4.Cu")
		(net "M_L_DQ<60>")
	)
	(segment
		(start 140.486638 -123.144534)
		(end 143.272764 -125.93066)
		(width 0.14224)
		(layer "In4.Cu")
		(net "M_L_DQ<60>")
	)
	(segment
		(start 119.989092 -105.139236)
		(end 119.982742 -105.149904)
		(width 0.0889)
		(layer "In4.Cu")
		(net "M_L_DQ<60>")
	)
	(segment
		(start 142.434564 -140.158978)
		(end 142.434564 -140.898118)
		(width 0.14224)
		(layer "In4.Cu")
		(net "M_L_DQ<60>")
	)
	(segment
		(start 121.855992 -106.98099)
		(end 121.855992 -107.186476)
		(width 0.0889)
		(layer "In4.Cu")
		(net "M_L_DQ<60>")
	)
	(segment
		(start 143.018764 -129.986278)
		(end 143.018764 -131.180078)
		(width 0.14224)
		(layer "In4.Cu")
		(net "M_L_DQ<60>")
	)
	(segment
		(start 119.993918 -105.1306)
		(end 119.989092 -105.139236)
		(width 0.0889)
		(layer "In4.Cu")
		(net "M_L_DQ<60>")
	)
	(segment
		(start 128.270508 -115.546124)
		(end 135.868918 -123.144534)
		(width 0.14224)
		(layer "In4.Cu")
		(net "M_L_DQ<60>")
	)
	(segment
		(start 125.400816 -115.546124)
		(end 128.270508 -115.546124)
		(width 0.14224)
		(layer "In4.Cu")
		(net "M_L_DQ<60>")
	)
	(segment
		(start 143.234664 -139.358878)
		(end 142.434564 -140.158978)
		(width 0.14224)
		(layer "In4.Cu")
		(net "M_L_DQ<60>")
	)
	(segment
		(start 135.868918 -123.144534)
		(end 140.486638 -123.144534)
		(width 0.14224)
		(layer "In4.Cu")
		(net "M_L_DQ<60>")
	)
	(segment
		(start 142.981172 -135.926576)
		(end 143.234664 -136.180068)
		(width 0.14224)
		(layer "In4.Cu")
		(net "M_L_DQ<60>")
	)
	(segment
		(start 143.234664 -136.6266)
		(end 143.177768 -136.683496)
		(width 0.14224)
		(layer "In4.Cu")
		(net "M_L_DQ<60>")
	)
	(segment
		(start 143.177768 -131.946396)
		(end 143.177768 -134.0612)
		(width 0.14224)
		(layer "In4.Cu")
		(net "M_L_DQ<60>")
	)
	(segment
		(start 119.130572 -101.272086)
		(end 119.135398 -101.280722)
		(width 0.0889)
		(layer "In4.Cu")
		(net "M_L_DQ<60>")
	)
	(segment
		(start 143.272764 -129.732278)
		(end 143.018764 -129.986278)
		(width 0.14224)
		(layer "In4.Cu")
		(net "M_L_DQ<60>")
	)
	(segment
		(start 119.624602 -103.548688)
		(end 119.657368 -103.548688)
		(width 0.0889)
		(layer "In4.Cu")
		(net "M_L_DQ<60>")
	)
	(segment
		(start 121.33453 -106.520488)
		(end 121.359422 -106.520234)
		(width 0.0889)
		(layer "In4.Cu")
		(net "M_L_DQ<60>")
	)
	(segment
		(start 143.247364 -134.47395)
		(end 142.981172 -134.740142)
		(width 0.14224)
		(layer "In4.Cu")
		(net "M_L_DQ<60>")
	)
	(segment
		(start 121.359422 -106.520234)
		(end 121.371614 -106.520234)
		(width 0.0889)
		(layer "In4.Cu")
		(net "M_L_DQ<60>")
	)
	(arc
		(start 119.130826 -95.328486)
		(mid 119.184325 -95.528384)
		(end 119.130826 -95.728282)
		(width 0.0889)
		(layer "In4.Cu")
		(net "M_L_DQ<60>")
	)
	(arc
		(start 119.099076 -94.801436)
		(mid 119.052848 -95.068693)
		(end 119.130826 -95.328486)
		(width 0.0889)
		(layer "In4.Cu")
		(net "M_L_DQ<60>")
	)
	(arc
		(start 119.130826 -96.718882)
		(mid 119.051695 -97.014284)
		(end 119.130826 -97.309686)
		(width 0.0889)
		(layer "In4.Cu")
		(net "M_L_DQ<60>")
	)
	(arc
		(start 119.130826 -99.290886)
		(mid 119.13319 -99.295163)
		(end 119.135398 -99.299522)
		(width 0.0889)
		(layer "In4.Cu")
		(net "M_L_DQ<60>")
	)
	(arc
		(start 119.130826 -97.709482)
		(mid 119.051695 -98.004884)
		(end 119.130826 -98.300286)
		(width 0.0889)
		(layer "In4.Cu")
		(net "M_L_DQ<60>")
	)
	(arc
		(start 119.130572 -100.681536)
		(mid 119.05135 -100.970654)
		(end 119.124222 -101.261418)
		(width 0.0889)
		(layer "In4.Cu")
		(net "M_L_DQ<60>")
	)
	(arc
		(start 119.130826 -97.309686)
		(mid 119.184325 -97.509584)
		(end 119.130826 -97.709482)
		(width 0.0889)
		(layer "In4.Cu")
		(net "M_L_DQ<60>")
	)
	(arc
		(start 119.130826 -98.700082)
		(mid 119.051695 -98.995484)
		(end 119.130826 -99.290886)
		(width 0.0889)
		(layer "In4.Cu")
		(net "M_L_DQ<60>")
	)
	(arc
		(start 119.982742 -105.149904)
		(mid 119.986773 -105.726086)
		(end 120.479312 -106.024934)
		(width 0.0889)
		(layer "In4.Cu")
		(net "M_L_DQ<60>")
	)
	(arc
		(start 119.135398 -102.271322)
		(mid 119.184153 -102.467674)
		(end 119.130572 -102.662736)
		(width 0.0889)
		(layer "In4.Cu")
		(net "M_L_DQ<60>")
	)
	(arc
		(start 119.135398 -100.290122)
		(mid 119.184153 -100.486474)
		(end 119.130572 -100.681536)
		(width 0.0889)
		(layer "In4.Cu")
		(net "M_L_DQ<60>")
	)
	(arc
		(start 119.130826 -98.300286)
		(mid 119.184325 -98.500184)
		(end 119.130826 -98.700082)
		(width 0.0889)
		(layer "In4.Cu")
		(net "M_L_DQ<60>")
	)
	(arc
		(start 119.130572 -102.662736)
		(mid 119.126243 -103.245908)
		(end 119.624602 -103.548688)
		(width 0.0889)
		(layer "In4.Cu")
		(net "M_L_DQ<60>")
	)
	(arc
		(start 119.130572 -99.690936)
		(mid 119.05135 -99.980054)
		(end 119.124222 -100.270818)
		(width 0.0889)
		(layer "In4.Cu")
		(net "M_L_DQ<60>")
	)
	(arc
		(start 119.135398 -101.280722)
		(mid 119.184153 -101.477074)
		(end 119.130572 -101.672136)
		(width 0.0889)
		(layer "In4.Cu")
		(net "M_L_DQ<60>")
	)
	(arc
		(start 120.500902 -106.024934)
		(mid 120.698063 -106.076893)
		(end 120.844056 -106.219244)
		(width 0.0889)
		(layer "In4.Cu")
		(net "M_L_DQ<60>")
	)
	(arc
		(start 119.135398 -99.299522)
		(mid 119.184153 -99.495874)
		(end 119.130572 -99.690936)
		(width 0.0889)
		(layer "In4.Cu")
		(net "M_L_DQ<60>")
	)
	(arc
		(start 119.130826 -96.319086)
		(mid 119.184325 -96.518984)
		(end 119.130826 -96.718882)
		(width 0.0889)
		(layer "In4.Cu")
		(net "M_L_DQ<60>")
	)
	(arc
		(start 119.130826 -95.728282)
		(mid 119.051695 -96.023684)
		(end 119.130826 -96.319086)
		(width 0.0889)
		(layer "In4.Cu")
		(net "M_L_DQ<60>")
	)
	(arc
		(start 119.989092 -104.739186)
		(mid 120.042562 -104.934249)
		(end 119.993918 -105.1306)
		(width 0.0889)
		(layer "In4.Cu")
		(net "M_L_DQ<60>")
	)
	(arc
		(start 120.847358 -106.225086)
		(mid 121.052975 -106.435427)
		(end 121.33453 -106.520488)
		(width 0.0889)
		(layer "In4.Cu")
		(net "M_L_DQ<60>")
	)
	(arc
		(start 119.657368 -103.548688)
		(mid 119.990286 -103.750679)
		(end 119.993918 -104.14)
		(width 0.0889)
		(layer "In4.Cu")
		(net "M_L_DQ<60>")
	)
	(arc
		(start 119.130572 -101.672136)
		(mid 119.05135 -101.961254)
		(end 119.124222 -102.252018)
		(width 0.0889)
		(layer "In4.Cu")
		(net "M_L_DQ<60>")
	)
	(arc
		(start 121.371614 -106.520234)
		(mid 121.564717 -106.576753)
		(end 121.705878 -106.720132)
		(width 0.0889)
		(layer "In4.Cu")
		(net "M_L_DQ<60>")
	)
	(arc
		(start 119.982742 -104.159304)
		(mid 119.909944 -104.450067)
		(end 119.989092 -104.739186)
		(width 0.0889)
		(layer "In4.Cu")
		(net "M_L_DQ<60>")
	)
	(segment
		(start 31.39948 -142.6718)
		(end 31.39948 -143.941546)
		(width 0.1651)
		(layer "F.Cu")
		(net "M_L_DQ<5>")
	)
	(segment
		(start 72.900286 -83.32724)
		(end 72.328786 -83.32724)
		(width 0.1651)
		(layer "F.Cu")
		(net "M_L_DQ<5>")
	)
	(via
		(at 31.39948 -143.941546)
		(size 0.508)
		(drill 0.254)
		(layers "F.Cu" "B.Cu")
		(net "M_L_DQ<5>")
	)
	(via
		(at 32.173164 -139.932156)
		(size 0.508)
		(drill 0.254)
		(layers "F.Cu" "B.Cu")
		(net "M_L_DQ<5>")
	)
	(via
		(at 72.328786 -83.32724)
		(size 0.508)
		(drill 0.254)
		(layers "F.Cu" "B.Cu")
		(net "M_L_DQ<5>")
	)
	(segment
		(start 32.249364 -139.855956)
		(end 32.173164 -139.932156)
		(width 0.1651)
		(layer "B.Cu")
		(net "M_L_DQ<5>")
	)
	(segment
		(start 32.249364 -137.877296)
		(end 32.249364 -139.855956)
		(width 0.1651)
		(layer "B.Cu")
		(net "M_L_DQ<5>")
	)
	(segment
		(start 31.722568 -140.3604)
		(end 31.722568 -140.9192)
		(width 0.14224)
		(layer "In4.Cu")
		(net "M_L_DQ<5>")
	)
	(segment
		(start 71.833486 -82.660744)
		(end 71.816976 -82.632042)
		(width 0.0889)
		(layer "In4.Cu")
		(net "M_L_DQ<5>")
	)
	(segment
		(start 31.798768 -142.747746)
		(end 31.56077 -142.985744)
		(width 0.14224)
		(layer "In4.Cu")
		(net "M_L_DQ<5>")
	)
	(segment
		(start 31.56077 -141.817344)
		(end 31.56077 -142.154656)
		(width 0.14224)
		(layer "In4.Cu")
		(net "M_L_DQ<5>")
	)
	(segment
		(start 72.328786 -83.32724)
		(end 71.833486 -82.660744)
		(width 0.0889)
		(layer "In4.Cu")
		(net "M_L_DQ<5>")
	)
	(segment
		(start 65.993772 -82.36712)
		(end 63.290958 -82.36712)
		(width 0.14224)
		(layer "In4.Cu")
		(net "M_L_DQ<5>")
	)
	(segment
		(start 32.433768 -134.415022)
		(end 32.697928 -134.679182)
		(width 0.14224)
		(layer "In4.Cu")
		(net "M_L_DQ<5>")
	)
	(segment
		(start 32.554164 -138.868404)
		(end 32.554164 -139.551156)
		(width 0.14224)
		(layer "In4.Cu")
		(net "M_L_DQ<5>")
	)
	(segment
		(start 32.697928 -135.966454)
		(end 32.554164 -136.110218)
		(width 0.14224)
		(layer "In4.Cu")
		(net "M_L_DQ<5>")
	)
	(segment
		(start 67.71132 -82.431636)
		(end 67.43065 -82.150966)
		(width 0.0889)
		(layer "In4.Cu")
		(net "M_L_DQ<5>")
	)
	(segment
		(start 35.808412 -112.959134)
		(end 35.69208 -112.842802)
		(width 0.14224)
		(layer "In4.Cu")
		(net "M_L_DQ<5>")
	)
	(segment
		(start 31.56077 -142.985744)
		(end 31.56077 -143.297656)
		(width 0.14224)
		(layer "In4.Cu")
		(net "M_L_DQ<5>")
	)
	(segment
		(start 32.681164 -131.153408)
		(end 32.433768 -131.400804)
		(width 0.14224)
		(layer "In4.Cu")
		(net "M_L_DQ<5>")
	)
	(segment
		(start 32.554164 -136.525)
		(end 32.687768 -136.658604)
		(width 0.14224)
		(layer "In4.Cu")
		(net "M_L_DQ<5>")
	)
	(segment
		(start 43.050714 -107.3404)
		(end 41.93286 -107.3404)
		(width 0.14224)
		(layer "In4.Cu")
		(net "M_L_DQ<5>")
	)
	(segment
		(start 41.93286 -107.3404)
		(end 38.001702 -111.271558)
		(width 0.14224)
		(layer "In4.Cu")
		(net "M_L_DQ<5>")
	)
	(segment
		(start 36.4109 -111.922814)
		(end 36.15182 -112.181894)
		(width 0.14224)
		(layer "In4.Cu")
		(net "M_L_DQ<5>")
	)
	(segment
		(start 37.081968 -112.191292)
		(end 36.8808 -112.191546)
		(width 0.14224)
		(layer "In4.Cu")
		(net "M_L_DQ<5>")
	)
	(segment
		(start 37.330888 -111.002826)
		(end 37.071808 -111.261906)
		(width 0.14224)
		(layer "In4.Cu")
		(net "M_L_DQ<5>")
	)
	(segment
		(start 37.072062 -111.462566)
		(end 37.340794 -111.731298)
		(width 0.14224)
		(layer "In4.Cu")
		(net "M_L_DQ<5>")
	)
	(segment
		(start 32.554164 -136.110218)
		(end 32.554164 -136.525)
		(width 0.14224)
		(layer "In4.Cu")
		(net "M_L_DQ<5>")
	)
	(segment
		(start 32.433768 -131.400804)
		(end 32.433768 -134.415022)
		(width 0.14224)
		(layer "In4.Cu")
		(net "M_L_DQ<5>")
	)
	(segment
		(start 32.697928 -134.679182)
		(end 32.697928 -135.966454)
		(width 0.14224)
		(layer "In4.Cu")
		(net "M_L_DQ<5>")
	)
	(segment
		(start 37.340794 -111.932466)
		(end 37.081968 -112.191292)
		(width 0.14224)
		(layer "In4.Cu")
		(net "M_L_DQ<5>")
	)
	(segment
		(start 68.912486 -81.93659)
		(end 68.87972 -81.93659)
		(width 0.0889)
		(layer "In4.Cu")
		(net "M_L_DQ<5>")
	)
	(segment
		(start 32.681164 -129.959608)
		(end 32.681164 -131.153408)
		(width 0.14224)
		(layer "In4.Cu")
		(net "M_L_DQ<5>")
	)
	(segment
		(start 70.626732 -81.93659)
		(end 70.593966 -81.93659)
		(width 0.0889)
		(layer "In4.Cu")
		(net "M_L_DQ<5>")
	)
	(segment
		(start 32.173164 -139.932156)
		(end 32.150812 -139.932156)
		(width 0.14224)
		(layer "In4.Cu")
		(net "M_L_DQ<5>")
	)
	(segment
		(start 31.671768 -143.941546)
		(end 31.39948 -143.941546)
		(width 0.14224)
		(layer "In4.Cu")
		(net "M_L_DQ<5>")
	)
	(segment
		(start 37.532056 -111.002826)
		(end 37.330888 -111.002826)
		(width 0.14224)
		(layer "In4.Cu")
		(net "M_L_DQ<5>")
	)
	(segment
		(start 35.490912 -112.842802)
		(end 32.503364 -115.83035)
		(width 0.14224)
		(layer "In4.Cu")
		(net "M_L_DQ<5>")
	)
	(segment
		(start 38.001702 -111.271558)
		(end 37.800788 -111.271558)
		(width 0.14224)
		(layer "In4.Cu")
		(net "M_L_DQ<5>")
	)
	(segment
		(start 31.56077 -142.154656)
		(end 31.798768 -142.392654)
		(width 0.14224)
		(layer "In4.Cu")
		(net "M_L_DQ<5>")
	)
	(segment
		(start 31.798768 -142.392654)
		(end 31.798768 -142.747746)
		(width 0.14224)
		(layer "In4.Cu")
		(net "M_L_DQ<5>")
	)
	(segment
		(start 67.43065 -82.150966)
		(end 66.209926 -82.150966)
		(width 0.0889)
		(layer "In4.Cu")
		(net "M_L_DQ<5>")
	)
	(segment
		(start 53.913532 -96.477582)
		(end 43.050714 -107.3404)
		(width 0.14224)
		(layer "In4.Cu")
		(net "M_L_DQ<5>")
	)
	(segment
		(start 63.290958 -82.36712)
		(end 53.913532 -91.744546)
		(width 0.14224)
		(layer "In4.Cu")
		(net "M_L_DQ<5>")
	)
	(segment
		(start 31.824168 -143.561054)
		(end 31.824168 -143.789146)
		(width 0.14224)
		(layer "In4.Cu")
		(net "M_L_DQ<5>")
	)
	(segment
		(start 36.15182 -112.181894)
		(end 36.152074 -112.382554)
		(width 0.14224)
		(layer "In4.Cu")
		(net "M_L_DQ<5>")
	)
	(segment
		(start 71.481442 -82.43189)
		(end 71.457312 -82.43189)
		(width 0.0889)
		(layer "In4.Cu")
		(net "M_L_DQ<5>")
	)
	(segment
		(start 32.687768 -138.7348)
		(end 32.554164 -138.868404)
		(width 0.14224)
		(layer "In4.Cu")
		(net "M_L_DQ<5>")
	)
	(segment
		(start 31.56077 -143.297656)
		(end 31.824168 -143.561054)
		(width 0.14224)
		(layer "In4.Cu")
		(net "M_L_DQ<5>")
	)
	(segment
		(start 35.69208 -112.842802)
		(end 35.490912 -112.842802)
		(width 0.14224)
		(layer "In4.Cu")
		(net "M_L_DQ<5>")
	)
	(segment
		(start 31.722568 -140.9192)
		(end 31.849568 -141.0462)
		(width 0.14224)
		(layer "In4.Cu")
		(net "M_L_DQ<5>")
	)
	(segment
		(start 31.849568 -141.0462)
		(end 31.849568 -141.528546)
		(width 0.14224)
		(layer "In4.Cu")
		(net "M_L_DQ<5>")
	)
	(segment
		(start 36.291774 -112.522254)
		(end 36.291774 -112.702086)
		(width 0.14224)
		(layer "In4.Cu")
		(net "M_L_DQ<5>")
	)
	(segment
		(start 53.913532 -91.744546)
		(end 53.913532 -96.477582)
		(width 0.14224)
		(layer "In4.Cu")
		(net "M_L_DQ<5>")
	)
	(segment
		(start 32.503364 -115.83035)
		(end 32.503364 -129.781808)
		(width 0.14224)
		(layer "In4.Cu")
		(net "M_L_DQ<5>")
	)
	(segment
		(start 36.03498 -112.95888)
		(end 35.808412 -112.959134)
		(width 0.14224)
		(layer "In4.Cu")
		(net "M_L_DQ<5>")
	)
	(segment
		(start 37.071808 -111.261906)
		(end 37.072062 -111.462566)
		(width 0.14224)
		(layer "In4.Cu")
		(net "M_L_DQ<5>")
	)
	(segment
		(start 37.340794 -111.731298)
		(end 37.340794 -111.932466)
		(width 0.14224)
		(layer "In4.Cu")
		(net "M_L_DQ<5>")
	)
	(segment
		(start 32.150812 -139.932156)
		(end 31.722568 -140.3604)
		(width 0.14224)
		(layer "In4.Cu")
		(net "M_L_DQ<5>")
	)
	(segment
		(start 32.687768 -136.658604)
		(end 32.687768 -138.7348)
		(width 0.14224)
		(layer "In4.Cu")
		(net "M_L_DQ<5>")
	)
	(segment
		(start 66.209926 -82.150966)
		(end 65.993772 -82.36712)
		(width 0.0889)
		(layer "In4.Cu")
		(net "M_L_DQ<5>")
	)
	(segment
		(start 37.800788 -111.271558)
		(end 37.532056 -111.002826)
		(width 0.14224)
		(layer "In4.Cu")
		(net "M_L_DQ<5>")
	)
	(segment
		(start 31.849568 -141.528546)
		(end 31.56077 -141.817344)
		(width 0.14224)
		(layer "In4.Cu")
		(net "M_L_DQ<5>")
	)
	(segment
		(start 36.291774 -112.702086)
		(end 36.03498 -112.95888)
		(width 0.14224)
		(layer "In4.Cu")
		(net "M_L_DQ<5>")
	)
	(segment
		(start 36.612068 -111.922814)
		(end 36.4109 -111.922814)
		(width 0.14224)
		(layer "In4.Cu")
		(net "M_L_DQ<5>")
	)
	(segment
		(start 36.152074 -112.382554)
		(end 36.291774 -112.522254)
		(width 0.14224)
		(layer "In4.Cu")
		(net "M_L_DQ<5>")
	)
	(segment
		(start 32.503364 -129.781808)
		(end 32.681164 -129.959608)
		(width 0.14224)
		(layer "In4.Cu")
		(net "M_L_DQ<5>")
	)
	(segment
		(start 68.054474 -82.431636)
		(end 67.71132 -82.431636)
		(width 0.0889)
		(layer "In4.Cu")
		(net "M_L_DQ<5>")
	)
	(segment
		(start 32.554164 -139.551156)
		(end 32.173164 -139.932156)
		(width 0.14224)
		(layer "In4.Cu")
		(net "M_L_DQ<5>")
	)
	(segment
		(start 31.824168 -143.789146)
		(end 31.671768 -143.941546)
		(width 0.14224)
		(layer "In4.Cu")
		(net "M_L_DQ<5>")
	)
	(segment
		(start 36.8808 -112.191546)
		(end 36.612068 -111.922814)
		(width 0.14224)
		(layer "In4.Cu")
		(net "M_L_DQ<5>")
	)
	(arc
		(start 68.87972 -81.93659)
		(mid 68.688078 -81.993756)
		(end 68.547996 -82.136488)
		(width 0.0889)
		(layer "In4.Cu")
		(net "M_L_DQ<5>")
	)
	(arc
		(start 70.099936 -81.641188)
		(mid 69.753226 -81.440877)
		(end 69.406516 -81.641188)
		(width 0.0889)
		(layer "In4.Cu")
		(net "M_L_DQ<5>")
	)
	(arc
		(start 70.593966 -81.93659)
		(mid 70.308542 -81.853123)
		(end 70.099936 -81.641188)
		(width 0.0889)
		(layer "In4.Cu")
		(net "M_L_DQ<5>")
	)
	(arc
		(start 71.457312 -82.43189)
		(mid 71.169167 -82.349571)
		(end 70.958456 -82.136488)
		(width 0.0889)
		(layer "In4.Cu")
		(net "M_L_DQ<5>")
	)
	(arc
		(start 70.958456 -82.136488)
		(mid 70.818377 -81.993752)
		(end 70.626732 -81.93659)
		(width 0.0889)
		(layer "In4.Cu")
		(net "M_L_DQ<5>")
	)
	(arc
		(start 71.816976 -82.632042)
		(mid 71.675293 -82.488238)
		(end 71.481442 -82.43189)
		(width 0.0889)
		(layer "In4.Cu")
		(net "M_L_DQ<5>")
	)
	(arc
		(start 69.406516 -81.641188)
		(mid 69.197908 -81.85312)
		(end 68.912486 -81.93659)
		(width 0.0889)
		(layer "In4.Cu")
		(net "M_L_DQ<5>")
	)
	(arc
		(start 68.547996 -82.136488)
		(mid 68.339577 -82.348201)
		(end 68.054474 -82.431636)
		(width 0.0889)
		(layer "In4.Cu")
		(net "M_L_DQ<5>")
	)
	(segment
		(start 122.504708 -95.033084)
		(end 123.076208 -95.033084)
		(width 0.1651)
		(layer "F.Cu")
		(net "M_L_DQ<59>")
	)
	(segment
		(start 150.399496 -142.6718)
		(end 150.399496 -143.941546)
		(width 0.1651)
		(layer "F.Cu")
		(net "M_L_DQ<59>")
	)
	(via
		(at 123.076208 -95.033084)
		(size 0.4826)
		(drill 0.254)
		(layers "F.Cu" "B.Cu")
		(net "M_L_DQ<59>")
	)
	(via
		(at 151.24938 -139.932156)
		(size 0.508)
		(drill 0.254)
		(layers "F.Cu" "B.Cu")
		(net "M_L_DQ<59>")
	)
	(via
		(at 150.399496 -143.941546)
		(size 0.508)
		(drill 0.254)
		(layers "F.Cu" "B.Cu")
		(net "M_L_DQ<59>")
	)
	(segment
		(start 151.24938 -137.877296)
		(end 151.24938 -139.932156)
		(width 0.1651)
		(layer "B.Cu")
		(net "M_L_DQ<59>")
	)
	(segment
		(start 124.441712 -102.1588)
		(end 124.446538 -102.167436)
		(width 0.0889)
		(layer "In4.Cu")
		(net "M_L_DQ<59>")
	)
	(segment
		(start 151.418544 -126.694438)
		(end 151.672544 -126.948438)
		(width 0.14224)
		(layer "In4.Cu")
		(net "M_L_DQ<59>")
	)
	(segment
		(start 150.671784 -143.941546)
		(end 150.399496 -143.941546)
		(width 0.14224)
		(layer "In4.Cu")
		(net "M_L_DQ<59>")
	)
	(segment
		(start 152.314656 -127.456438)
		(end 152.159716 -127.611378)
		(width 0.14224)
		(layer "In4.Cu")
		(net "M_L_DQ<59>")
	)
	(segment
		(start 130.389884 -104.848914)
		(end 142.803626 -117.262656)
		(width 0.14224)
		(layer "In4.Cu")
		(net "M_L_DQ<59>")
	)
	(segment
		(start 151.728424 -134.653782)
		(end 151.728424 -136.127744)
		(width 0.14224)
		(layer "In4.Cu")
		(net "M_L_DQ<59>")
	)
	(segment
		(start 123.588018 -99.290886)
		(end 123.583192 -99.299522)
		(width 0.0889)
		(layer "In4.Cu")
		(net "M_L_DQ<59>")
	)
	(segment
		(start 123.594368 -97.299018)
		(end 123.588018 -97.309686)
		(width 0.0889)
		(layer "In4.Cu")
		(net "M_L_DQ<59>")
	)
	(segment
		(start 150.560786 -143.151352)
		(end 150.849584 -143.44015)
		(width 0.14224)
		(layer "In4.Cu")
		(net "M_L_DQ<59>")
	)
	(segment
		(start 126.499112 -104.348534)
		(end 127.108712 -104.348534)
		(width 0.0889)
		(layer "In4.Cu")
		(net "M_L_DQ<59>")
	)
	(segment
		(start 151.40178 -127.752856)
		(end 151.40178 -128.105916)
		(width 0.14224)
		(layer "In4.Cu")
		(net "M_L_DQ<59>")
	)
	(segment
		(start 125.636782 -103.853234)
		(end 125.673358 -103.853234)
		(width 0.0889)
		(layer "In4.Cu")
		(net "M_L_DQ<59>")
	)
	(segment
		(start 150.817834 -142.3162)
		(end 150.817834 -142.621)
		(width 0.14224)
		(layer "In4.Cu")
		(net "M_L_DQ<59>")
	)
	(segment
		(start 150.798784 -140.790168)
		(end 150.843234 -140.834618)
		(width 0.14224)
		(layer "In4.Cu")
		(net "M_L_DQ<59>")
	)
	(segment
		(start 150.560786 -141.785848)
		(end 150.560786 -142.059152)
		(width 0.14224)
		(layer "In4.Cu")
		(net "M_L_DQ<59>")
	)
	(segment
		(start 151.715216 -128.937258)
		(end 151.49957 -129.152904)
		(width 0.14224)
		(layer "In4.Cu")
		(net "M_L_DQ<59>")
	)
	(segment
		(start 151.59355 -134.518908)
		(end 151.728424 -134.653782)
		(width 0.14224)
		(layer "In4.Cu")
		(net "M_L_DQ<59>")
	)
	(segment
		(start 151.672544 -126.948438)
		(end 152.159716 -126.948438)
		(width 0.14224)
		(layer "In4.Cu")
		(net "M_L_DQ<59>")
	)
	(segment
		(start 150.843234 -140.834618)
		(end 150.843234 -141.5034)
		(width 0.14224)
		(layer "In4.Cu")
		(net "M_L_DQ<59>")
	)
	(segment
		(start 151.49957 -129.152904)
		(end 151.49957 -129.856484)
		(width 0.14224)
		(layer "In4.Cu")
		(net "M_L_DQ<59>")
	)
	(segment
		(start 151.418544 -124.337064)
		(end 151.418544 -126.694438)
		(width 0.14224)
		(layer "In4.Cu")
		(net "M_L_DQ<59>")
	)
	(segment
		(start 127.108712 -104.348534)
		(end 127.609092 -104.848914)
		(width 0.0889)
		(layer "In4.Cu")
		(net "M_L_DQ<59>")
	)
	(segment
		(start 151.756364 -130.113278)
		(end 151.756364 -131.268978)
		(width 0.14224)
		(layer "In4.Cu")
		(net "M_L_DQ<59>")
	)
	(segment
		(start 151.59355 -131.431792)
		(end 151.59355 -134.518908)
		(width 0.14224)
		(layer "In4.Cu")
		(net "M_L_DQ<59>")
	)
	(segment
		(start 123.594368 -98.289618)
		(end 123.588018 -98.300286)
		(width 0.0889)
		(layer "In4.Cu")
		(net "M_L_DQ<59>")
	)
	(segment
		(start 123.076208 -95.033084)
		(end 123.571254 -95.699326)
		(width 0.0889)
		(layer "In4.Cu")
		(net "M_L_DQ<59>")
	)
	(segment
		(start 151.578564 -136.277604)
		(end 151.578564 -139.602972)
		(width 0.14224)
		(layer "In4.Cu")
		(net "M_L_DQ<59>")
	)
	(segment
		(start 151.578564 -139.602972)
		(end 151.24938 -139.932156)
		(width 0.14224)
		(layer "In4.Cu")
		(net "M_L_DQ<59>")
	)
	(segment
		(start 123.594368 -96.308418)
		(end 123.588018 -96.319086)
		(width 0.0889)
		(layer "In4.Cu")
		(net "M_L_DQ<59>")
	)
	(segment
		(start 150.849584 -143.763746)
		(end 150.671784 -143.941546)
		(width 0.14224)
		(layer "In4.Cu")
		(net "M_L_DQ<59>")
	)
	(segment
		(start 123.571254 -95.699326)
		(end 123.588018 -95.728536)
		(width 0.0889)
		(layer "In4.Cu")
		(net "M_L_DQ<59>")
	)
	(segment
		(start 123.588018 -97.309686)
		(end 123.583192 -97.318322)
		(width 0.0889)
		(layer "In4.Cu")
		(net "M_L_DQ<59>")
	)
	(segment
		(start 150.849584 -143.44015)
		(end 150.849584 -143.763746)
		(width 0.14224)
		(layer "In4.Cu")
		(net "M_L_DQ<59>")
	)
	(segment
		(start 150.817834 -142.621)
		(end 150.560786 -142.878048)
		(width 0.14224)
		(layer "In4.Cu")
		(net "M_L_DQ<59>")
	)
	(segment
		(start 151.570182 -128.274318)
		(end 152.159716 -128.274318)
		(width 0.14224)
		(layer "In4.Cu")
		(net "M_L_DQ<59>")
	)
	(segment
		(start 152.159716 -126.948438)
		(end 152.314656 -127.103378)
		(width 0.14224)
		(layer "In4.Cu")
		(net "M_L_DQ<59>")
	)
	(segment
		(start 151.24938 -139.932156)
		(end 150.798784 -140.382752)
		(width 0.14224)
		(layer "In4.Cu")
		(net "M_L_DQ<59>")
	)
	(segment
		(start 151.543258 -127.611378)
		(end 151.40178 -127.752856)
		(width 0.14224)
		(layer "In4.Cu")
		(net "M_L_DQ<59>")
	)
	(segment
		(start 151.49957 -129.856484)
		(end 151.756364 -130.113278)
		(width 0.14224)
		(layer "In4.Cu")
		(net "M_L_DQ<59>")
	)
	(segment
		(start 150.560786 -142.878048)
		(end 150.560786 -143.151352)
		(width 0.14224)
		(layer "In4.Cu")
		(net "M_L_DQ<59>")
	)
	(segment
		(start 152.159716 -128.274318)
		(end 152.314656 -128.429258)
		(width 0.14224)
		(layer "In4.Cu")
		(net "M_L_DQ<59>")
	)
	(segment
		(start 142.803626 -117.262656)
		(end 144.344136 -117.262656)
		(width 0.14224)
		(layer "In4.Cu")
		(net "M_L_DQ<59>")
	)
	(segment
		(start 123.916694 -100.881434)
		(end 123.956318 -100.881434)
		(width 0.0889)
		(layer "In4.Cu")
		(net "M_L_DQ<59>")
	)
	(segment
		(start 123.588018 -96.319086)
		(end 123.583192 -96.327722)
		(width 0.0889)
		(layer "In4.Cu")
		(net "M_L_DQ<59>")
	)
	(segment
		(start 123.594368 -99.280218)
		(end 123.588018 -99.290886)
		(width 0.0889)
		(layer "In4.Cu")
		(net "M_L_DQ<59>")
	)
	(segment
		(start 152.159716 -128.937258)
		(end 151.715216 -128.937258)
		(width 0.14224)
		(layer "In4.Cu")
		(net "M_L_DQ<59>")
	)
	(segment
		(start 151.40178 -128.105916)
		(end 151.570182 -128.274318)
		(width 0.14224)
		(layer "In4.Cu")
		(net "M_L_DQ<59>")
	)
	(segment
		(start 152.314656 -128.782318)
		(end 152.159716 -128.937258)
		(width 0.14224)
		(layer "In4.Cu")
		(net "M_L_DQ<59>")
	)
	(segment
		(start 144.344136 -117.262656)
		(end 151.418544 -124.337064)
		(width 0.14224)
		(layer "In4.Cu")
		(net "M_L_DQ<59>")
	)
	(segment
		(start 127.958596 -104.848914)
		(end 130.389884 -104.848914)
		(width 0.14224)
		(layer "In4.Cu")
		(net "M_L_DQ<59>")
	)
	(segment
		(start 152.159716 -127.611378)
		(end 151.543258 -127.611378)
		(width 0.14224)
		(layer "In4.Cu")
		(net "M_L_DQ<59>")
	)
	(segment
		(start 152.314656 -128.429258)
		(end 152.314656 -128.782318)
		(width 0.14224)
		(layer "In4.Cu")
		(net "M_L_DQ<59>")
	)
	(segment
		(start 152.314656 -127.103378)
		(end 152.314656 -127.456438)
		(width 0.14224)
		(layer "In4.Cu")
		(net "M_L_DQ<59>")
	)
	(segment
		(start 123.588018 -98.300286)
		(end 123.583192 -98.308922)
		(width 0.0889)
		(layer "In4.Cu")
		(net "M_L_DQ<59>")
	)
	(segment
		(start 151.756364 -131.268978)
		(end 151.59355 -131.431792)
		(width 0.14224)
		(layer "In4.Cu")
		(net "M_L_DQ<59>")
	)
	(segment
		(start 150.843234 -141.5034)
		(end 150.560786 -141.785848)
		(width 0.14224)
		(layer "In4.Cu")
		(net "M_L_DQ<59>")
	)
	(segment
		(start 150.798784 -140.382752)
		(end 150.798784 -140.790168)
		(width 0.14224)
		(layer "In4.Cu")
		(net "M_L_DQ<59>")
	)
	(segment
		(start 150.560786 -142.059152)
		(end 150.817834 -142.3162)
		(width 0.14224)
		(layer "In4.Cu")
		(net "M_L_DQ<59>")
	)
	(segment
		(start 127.609092 -104.848914)
		(end 127.958596 -104.848914)
		(width 0.0889)
		(layer "In4.Cu")
		(net "M_L_DQ<59>")
	)
	(segment
		(start 124.782072 -103.358188)
		(end 124.814838 -103.358188)
		(width 0.0889)
		(layer "In4.Cu")
		(net "M_L_DQ<59>")
	)
	(segment
		(start 151.728424 -136.127744)
		(end 151.578564 -136.277604)
		(width 0.14224)
		(layer "In4.Cu")
		(net "M_L_DQ<59>")
	)
	(segment
		(start 124.446538 -102.167436)
		(end 124.452888 -102.178104)
		(width 0.0889)
		(layer "In4.Cu")
		(net "M_L_DQ<59>")
	)
	(arc
		(start 123.583192 -97.318322)
		(mid 123.534437 -97.514674)
		(end 123.588018 -97.709736)
		(width 0.0889)
		(layer "In4.Cu")
		(net "M_L_DQ<59>")
	)
	(arc
		(start 123.583192 -96.327722)
		(mid 123.534437 -96.524074)
		(end 123.588018 -96.719136)
		(width 0.0889)
		(layer "In4.Cu")
		(net "M_L_DQ<59>")
	)
	(arc
		(start 123.583192 -99.299522)
		(mid 123.534437 -99.495874)
		(end 123.588018 -99.690936)
		(width 0.0889)
		(layer "In4.Cu")
		(net "M_L_DQ<59>")
	)
	(arc
		(start 123.588018 -97.709736)
		(mid 123.66724 -97.998854)
		(end 123.594368 -98.289618)
		(width 0.0889)
		(layer "In4.Cu")
		(net "M_L_DQ<59>")
	)
	(arc
		(start 123.588018 -96.719136)
		(mid 123.66724 -97.008254)
		(end 123.594368 -97.299018)
		(width 0.0889)
		(layer "In4.Cu")
		(net "M_L_DQ<59>")
	)
	(arc
		(start 124.814838 -103.358188)
		(mid 125.098055 -103.442469)
		(end 125.305058 -103.653336)
		(width 0.0889)
		(layer "In4.Cu")
		(net "M_L_DQ<59>")
	)
	(arc
		(start 123.588018 -95.728536)
		(mid 123.66724 -96.017654)
		(end 123.594368 -96.308418)
		(width 0.0889)
		(layer "In4.Cu")
		(net "M_L_DQ<59>")
	)
	(arc
		(start 126.163578 -104.148382)
		(mid 126.305261 -104.292186)
		(end 126.499112 -104.348534)
		(width 0.0889)
		(layer "In4.Cu")
		(net "M_L_DQ<59>")
	)
	(arc
		(start 124.452888 -102.178104)
		(mid 124.525686 -102.468867)
		(end 124.446538 -102.757986)
		(width 0.0889)
		(layer "In4.Cu")
		(net "M_L_DQ<59>")
	)
	(arc
		(start 123.588018 -99.690936)
		(mid 123.667149 -99.986338)
		(end 123.588018 -100.28174)
		(width 0.0889)
		(layer "In4.Cu")
		(net "M_L_DQ<59>")
	)
	(arc
		(start 123.583192 -98.308922)
		(mid 123.534437 -98.505274)
		(end 123.588018 -98.700336)
		(width 0.0889)
		(layer "In4.Cu")
		(net "M_L_DQ<59>")
	)
	(arc
		(start 125.673358 -103.853234)
		(mid 125.956575 -103.937515)
		(end 126.163578 -104.148382)
		(width 0.0889)
		(layer "In4.Cu")
		(net "M_L_DQ<59>")
	)
	(arc
		(start 123.588018 -100.28174)
		(mid 123.583773 -100.673985)
		(end 123.916694 -100.881434)
		(width 0.0889)
		(layer "In4.Cu")
		(net "M_L_DQ<59>")
	)
	(arc
		(start 125.305058 -103.653336)
		(mid 125.445137 -103.796072)
		(end 125.636782 -103.853234)
		(width 0.0889)
		(layer "In4.Cu")
		(net "M_L_DQ<59>")
	)
	(arc
		(start 124.446538 -102.757986)
		(mid 124.44379 -103.153453)
		(end 124.782072 -103.358188)
		(width 0.0889)
		(layer "In4.Cu")
		(net "M_L_DQ<59>")
	)
	(arc
		(start 123.588018 -98.700336)
		(mid 123.66724 -98.989454)
		(end 123.594368 -99.280218)
		(width 0.0889)
		(layer "In4.Cu")
		(net "M_L_DQ<59>")
	)
	(arc
		(start 124.446538 -101.767386)
		(mid 124.393068 -101.962449)
		(end 124.441712 -102.1588)
		(width 0.0889)
		(layer "In4.Cu")
		(net "M_L_DQ<59>")
	)
	(arc
		(start 123.956318 -100.881434)
		(mid 124.451795 -101.185877)
		(end 124.446538 -101.767386)
		(width 0.0889)
		(layer "In4.Cu")
		(net "M_L_DQ<59>")
	)
	(segment
		(start 151.24938 -146.280632)
		(end 151.380952 -146.14906)
		(width 0.1651)
		(layer "F.Cu")
		(net "M_L_DQ<58>")
	)
	(segment
		(start 151.24938 -147.27174)
		(end 151.24938 -146.280632)
		(width 0.1651)
		(layer "F.Cu")
		(net "M_L_DQ<58>")
	)
	(segment
		(start 151.380952 -145.92554)
		(end 151.24938 -145.793968)
		(width 0.1651)
		(layer "F.Cu")
		(net "M_L_DQ<58>")
	)
	(segment
		(start 122.217688 -92.556584)
		(end 121.646188 -92.556584)
		(width 0.0889)
		(layer "F.Cu")
		(net "M_L_DQ<58>")
	)
	(segment
		(start 151.24938 -145.793968)
		(end 151.24938 -145.5166)
		(width 0.1651)
		(layer "F.Cu")
		(net "M_L_DQ<58>")
	)
	(segment
		(start 151.380952 -146.14906)
		(end 151.380952 -145.92554)
		(width 0.1651)
		(layer "F.Cu")
		(net "M_L_DQ<58>")
	)
	(via
		(at 150.399496 -141.213078)
		(size 0.508)
		(drill 0.254)
		(layers "F.Cu" "B.Cu")
		(net "M_L_DQ<58>")
	)
	(via
		(at 151.24938 -145.5166)
		(size 0.508)
		(drill 0.254)
		(layers "F.Cu" "B.Cu")
		(net "M_L_DQ<58>")
	)
	(via
		(at 122.217688 -92.556584)
		(size 0.508)
		(drill 0.254)
		(layers "F.Cu" "B.Cu")
		(net "M_L_DQ<58>")
	)
	(segment
		(start 150.399496 -142.477236)
		(end 150.399496 -141.213078)
		(width 0.1651)
		(layer "B.Cu")
		(net "M_L_DQ<58>")
	)
	(segment
		(start 149.966426 -141.646148)
		(end 149.966426 -144.233646)
		(width 0.14224)
		(layer "In4.Cu")
		(net "M_L_DQ<58>")
	)
	(segment
		(start 150.689564 -135.976868)
		(end 150.886668 -136.173972)
		(width 0.14224)
		(layer "In4.Cu")
		(net "M_L_DQ<58>")
	)
	(segment
		(start 149.966426 -144.233646)
		(end 151.24938 -145.5166)
		(width 0.14224)
		(layer "In4.Cu")
		(net "M_L_DQ<58>")
	)
	(segment
		(start 122.564398 -94.737936)
		(end 122.558048 -94.748604)
		(width 0.0889)
		(layer "In4.Cu")
		(net "M_L_DQ<58>")
	)
	(segment
		(start 142.752826 -117.923056)
		(end 144.1831 -117.923056)
		(width 0.14224)
		(layer "In4.Cu")
		(net "M_L_DQ<58>")
	)
	(segment
		(start 123.422918 -97.214436)
		(end 123.416568 -97.225104)
		(width 0.0889)
		(layer "In4.Cu")
		(net "M_L_DQ<58>")
	)
	(segment
		(start 124.775468 -103.548688)
		(end 124.808234 -103.548688)
		(width 0.0889)
		(layer "In4.Cu")
		(net "M_L_DQ<58>")
	)
	(segment
		(start 150.689564 -134.72795)
		(end 150.689564 -135.976868)
		(width 0.14224)
		(layer "In4.Cu")
		(net "M_L_DQ<58>")
	)
	(segment
		(start 127.029718 -104.539034)
		(end 127.503174 -105.01249)
		(width 0.0889)
		(layer "In4.Cu")
		(net "M_L_DQ<58>")
	)
	(segment
		(start 127.503174 -105.01249)
		(end 127.503174 -105.291636)
		(width 0.0889)
		(layer "In4.Cu")
		(net "M_L_DQ<58>")
	)
	(segment
		(start 123.422918 -98.205036)
		(end 123.416568 -98.215704)
		(width 0.0889)
		(layer "In4.Cu")
		(net "M_L_DQ<58>")
	)
	(segment
		(start 150.765764 -131.332478)
		(end 150.85949 -131.426204)
		(width 0.14224)
		(layer "In4.Cu")
		(net "M_L_DQ<58>")
	)
	(segment
		(start 150.307294 -139.982448)
		(end 150.307294 -141.120876)
		(width 0.14224)
		(layer "In4.Cu")
		(net "M_L_DQ<58>")
	)
	(segment
		(start 123.422918 -99.195636)
		(end 123.416568 -99.206304)
		(width 0.0889)
		(layer "In4.Cu")
		(net "M_L_DQ<58>")
	)
	(segment
		(start 126.488698 -104.539034)
		(end 127.029718 -104.539034)
		(width 0.0889)
		(layer "In4.Cu")
		(net "M_L_DQ<58>")
	)
	(segment
		(start 123.427744 -99.187)
		(end 123.422918 -99.195636)
		(width 0.0889)
		(layer "In4.Cu")
		(net "M_L_DQ<58>")
	)
	(segment
		(start 123.427744 -97.2058)
		(end 123.422918 -97.214436)
		(width 0.0889)
		(layer "In4.Cu")
		(net "M_L_DQ<58>")
	)
	(segment
		(start 123.427744 -100.1776)
		(end 123.422918 -100.186236)
		(width 0.0889)
		(layer "In4.Cu")
		(net "M_L_DQ<58>")
	)
	(segment
		(start 144.1831 -117.923056)
		(end 150.859998 -124.599954)
		(width 0.14224)
		(layer "In4.Cu")
		(net "M_L_DQ<58>")
	)
	(segment
		(start 123.427744 -96.2152)
		(end 123.422918 -96.223836)
		(width 0.0889)
		(layer "In4.Cu")
		(net "M_L_DQ<58>")
	)
	(segment
		(start 127.697738 -105.4862)
		(end 130.31597 -105.4862)
		(width 0.14224)
		(layer "In4.Cu")
		(net "M_L_DQ<58>")
	)
	(segment
		(start 123.063254 -95.623888)
		(end 123.091194 -95.623888)
		(width 0.0889)
		(layer "In4.Cu")
		(net "M_L_DQ<58>")
	)
	(segment
		(start 123.427744 -98.1964)
		(end 123.422918 -98.205036)
		(width 0.0889)
		(layer "In4.Cu")
		(net "M_L_DQ<58>")
	)
	(segment
		(start 123.913138 -101.072188)
		(end 123.952762 -101.072188)
		(width 0.0889)
		(layer "In4.Cu")
		(net "M_L_DQ<58>")
	)
	(segment
		(start 127.503174 -105.291636)
		(end 127.697738 -105.4862)
		(width 0.14224)
		(layer "In4.Cu")
		(net "M_L_DQ<58>")
	)
	(segment
		(start 124.281438 -102.262686)
		(end 124.286264 -102.271322)
		(width 0.0889)
		(layer "In4.Cu")
		(net "M_L_DQ<58>")
	)
	(segment
		(start 150.886668 -136.173972)
		(end 150.886668 -139.403074)
		(width 0.14224)
		(layer "In4.Cu")
		(net "M_L_DQ<58>")
	)
	(segment
		(start 122.547126 -93.317568)
		(end 122.569224 -93.355922)
		(width 0.0889)
		(layer "In4.Cu")
		(net "M_L_DQ<58>")
	)
	(segment
		(start 150.859998 -124.599954)
		(end 150.859998 -129.866644)
		(width 0.14224)
		(layer "In4.Cu")
		(net "M_L_DQ<58>")
	)
	(segment
		(start 150.886668 -139.403074)
		(end 150.307294 -139.982448)
		(width 0.14224)
		(layer "In4.Cu")
		(net "M_L_DQ<58>")
	)
	(segment
		(start 122.217688 -92.556584)
		(end 122.547126 -93.317568)
		(width 0.0889)
		(layer "In4.Cu")
		(net "M_L_DQ<58>")
	)
	(segment
		(start 150.85949 -131.426204)
		(end 150.85949 -134.558024)
		(width 0.14224)
		(layer "In4.Cu")
		(net "M_L_DQ<58>")
	)
	(segment
		(start 130.31597 -105.4862)
		(end 142.752826 -117.923056)
		(width 0.14224)
		(layer "In4.Cu")
		(net "M_L_DQ<58>")
	)
	(segment
		(start 150.307294 -141.120876)
		(end 150.399496 -141.213078)
		(width 0.14224)
		(layer "In4.Cu")
		(net "M_L_DQ<58>")
	)
	(segment
		(start 124.275088 -102.252018)
		(end 124.281438 -102.262686)
		(width 0.0889)
		(layer "In4.Cu")
		(net "M_L_DQ<58>")
	)
	(segment
		(start 123.422918 -96.223836)
		(end 123.416568 -96.234504)
		(width 0.0889)
		(layer "In4.Cu")
		(net "M_L_DQ<58>")
	)
	(segment
		(start 150.399496 -141.213078)
		(end 149.966426 -141.646148)
		(width 0.14224)
		(layer "In4.Cu")
		(net "M_L_DQ<58>")
	)
	(segment
		(start 125.630178 -104.043734)
		(end 125.662944 -104.043734)
		(width 0.0889)
		(layer "In4.Cu")
		(net "M_L_DQ<58>")
	)
	(segment
		(start 150.85949 -134.558024)
		(end 150.689564 -134.72795)
		(width 0.14224)
		(layer "In4.Cu")
		(net "M_L_DQ<58>")
	)
	(segment
		(start 122.581162 -94.708472)
		(end 122.564398 -94.737936)
		(width 0.0889)
		(layer "In4.Cu")
		(net "M_L_DQ<58>")
	)
	(segment
		(start 150.765764 -129.960878)
		(end 150.765764 -131.332478)
		(width 0.14224)
		(layer "In4.Cu")
		(net "M_L_DQ<58>")
	)
	(segment
		(start 150.859998 -129.866644)
		(end 150.765764 -129.960878)
		(width 0.14224)
		(layer "In4.Cu")
		(net "M_L_DQ<58>")
	)
	(arc
		(start 122.564398 -93.747336)
		(mid 122.485267 -94.042738)
		(end 122.564398 -94.33814)
		(width 0.0889)
		(layer "In4.Cu")
		(net "M_L_DQ<58>")
	)
	(arc
		(start 123.422918 -100.186236)
		(mid 123.417664 -100.767744)
		(end 123.913138 -101.072188)
		(width 0.0889)
		(layer "In4.Cu")
		(net "M_L_DQ<58>")
	)
	(arc
		(start 125.139958 -103.748586)
		(mid 125.346962 -103.95945)
		(end 125.630178 -104.043734)
		(width 0.0889)
		(layer "In4.Cu")
		(net "M_L_DQ<58>")
	)
	(arc
		(start 122.558048 -94.748604)
		(mid 122.564225 -95.328536)
		(end 123.063254 -95.623888)
		(width 0.0889)
		(layer "In4.Cu")
		(net "M_L_DQ<58>")
	)
	(arc
		(start 125.998478 -104.243886)
		(mid 126.205482 -104.45475)
		(end 126.488698 -104.539034)
		(width 0.0889)
		(layer "In4.Cu")
		(net "M_L_DQ<58>")
	)
	(arc
		(start 123.416568 -96.234504)
		(mid 123.34377 -96.525267)
		(end 123.422918 -96.814386)
		(width 0.0889)
		(layer "In4.Cu")
		(net "M_L_DQ<58>")
	)
	(arc
		(start 122.564398 -94.33814)
		(mid 122.626245 -94.520873)
		(end 122.581162 -94.708472)
		(width 0.0889)
		(layer "In4.Cu")
		(net "M_L_DQ<58>")
	)
	(arc
		(start 124.808234 -103.548688)
		(mid 124.999876 -103.605854)
		(end 125.139958 -103.748586)
		(width 0.0889)
		(layer "In4.Cu")
		(net "M_L_DQ<58>")
	)
	(arc
		(start 124.281438 -101.672136)
		(mid 124.202216 -101.961254)
		(end 124.275088 -102.252018)
		(width 0.0889)
		(layer "In4.Cu")
		(net "M_L_DQ<58>")
	)
	(arc
		(start 124.281438 -102.662736)
		(mid 124.277109 -103.245908)
		(end 124.775468 -103.548688)
		(width 0.0889)
		(layer "In4.Cu")
		(net "M_L_DQ<58>")
	)
	(arc
		(start 123.091194 -95.623888)
		(mid 123.424112 -95.825879)
		(end 123.427744 -96.2152)
		(width 0.0889)
		(layer "In4.Cu")
		(net "M_L_DQ<58>")
	)
	(arc
		(start 125.662944 -104.043734)
		(mid 125.856794 -104.100084)
		(end 125.998478 -104.243886)
		(width 0.0889)
		(layer "In4.Cu")
		(net "M_L_DQ<58>")
	)
	(arc
		(start 123.422918 -97.804986)
		(mid 123.476388 -98.000049)
		(end 123.427744 -98.1964)
		(width 0.0889)
		(layer "In4.Cu")
		(net "M_L_DQ<58>")
	)
	(arc
		(start 123.952762 -101.072188)
		(mid 124.285731 -101.279736)
		(end 124.281438 -101.672136)
		(width 0.0889)
		(layer "In4.Cu")
		(net "M_L_DQ<58>")
	)
	(arc
		(start 123.422918 -98.795586)
		(mid 123.476388 -98.990649)
		(end 123.427744 -99.187)
		(width 0.0889)
		(layer "In4.Cu")
		(net "M_L_DQ<58>")
	)
	(arc
		(start 122.569224 -93.355922)
		(mid 122.617979 -93.552274)
		(end 122.564398 -93.747336)
		(width 0.0889)
		(layer "In4.Cu")
		(net "M_L_DQ<58>")
	)
	(arc
		(start 123.422918 -96.814386)
		(mid 123.476388 -97.009449)
		(end 123.427744 -97.2058)
		(width 0.0889)
		(layer "In4.Cu")
		(net "M_L_DQ<58>")
	)
	(arc
		(start 123.416568 -99.206304)
		(mid 123.34377 -99.497067)
		(end 123.422918 -99.786186)
		(width 0.0889)
		(layer "In4.Cu")
		(net "M_L_DQ<58>")
	)
	(arc
		(start 123.416568 -98.215704)
		(mid 123.34377 -98.506467)
		(end 123.422918 -98.795586)
		(width 0.0889)
		(layer "In4.Cu")
		(net "M_L_DQ<58>")
	)
	(arc
		(start 123.416568 -97.225104)
		(mid 123.34377 -97.515867)
		(end 123.422918 -97.804986)
		(width 0.0889)
		(layer "In4.Cu")
		(net "M_L_DQ<58>")
	)
	(arc
		(start 123.422918 -99.786186)
		(mid 123.476388 -99.981249)
		(end 123.427744 -100.1776)
		(width 0.0889)
		(layer "In4.Cu")
		(net "M_L_DQ<58>")
	)
	(arc
		(start 124.286264 -102.271322)
		(mid 124.335019 -102.467674)
		(end 124.281438 -102.662736)
		(width 0.0889)
		(layer "In4.Cu")
		(net "M_L_DQ<58>")
	)
	(segment
		(start 144.449546 -142.6718)
		(end 144.449546 -143.941546)
		(width 0.1651)
		(layer "F.Cu")
		(net "M_L_DQ<57>")
	)
	(segment
		(start 119.929402 -95.528384)
		(end 120.500902 -95.528384)
		(width 0.1651)
		(layer "F.Cu")
		(net "M_L_DQ<57>")
	)
	(via
		(at 120.500902 -95.528384)
		(size 0.508)
		(drill 0.254)
		(layers "F.Cu" "B.Cu")
		(net "M_L_DQ<57>")
	)
	(via
		(at 144.449546 -143.941546)
		(size 0.508)
		(drill 0.254)
		(layers "F.Cu" "B.Cu")
		(net "M_L_DQ<57>")
	)
	(via
		(at 145.12163 -139.932156)
		(size 0.508)
		(drill 0.254)
		(layers "F.Cu" "B.Cu")
		(net "M_L_DQ<57>")
	)
	(segment
		(start 145.12163 -139.428982)
		(end 145.12163 -139.932156)
		(width 0.1651)
		(layer "B.Cu")
		(net "M_L_DQ<57>")
	)
	(segment
		(start 145.29943 -137.877296)
		(end 145.29943 -139.251182)
		(width 0.1651)
		(layer "B.Cu")
		(net "M_L_DQ<57>")
	)
	(segment
		(start 145.29943 -139.251182)
		(end 145.12163 -139.428982)
		(width 0.1651)
		(layer "B.Cu")
		(net "M_L_DQ<57>")
	)
	(segment
		(start 144.901412 -141.425168)
		(end 144.610836 -141.715744)
		(width 0.14224)
		(layer "In4.Cu")
		(net "M_L_DQ<57>")
	)
	(segment
		(start 144.610836 -142.076424)
		(end 144.825212 -142.2908)
		(width 0.14224)
		(layer "In4.Cu")
		(net "M_L_DQ<57>")
	)
	(segment
		(start 138.347196 -119.900446)
		(end 138.347196 -119.681498)
		(width 0.14224)
		(layer "In4.Cu")
		(net "M_L_DQ<57>")
	)
	(segment
		(start 137.878312 -119.212614)
		(end 137.659364 -119.212614)
		(width 0.14224)
		(layer "In4.Cu")
		(net "M_L_DQ<57>")
	)
	(segment
		(start 123.568968 -108.458)
		(end 123.568968 -107.407456)
		(width 0.14224)
		(layer "In4.Cu")
		(net "M_L_DQ<57>")
	)
	(segment
		(start 145.609564 -139.355322)
		(end 145.609564 -138.995404)
		(width 0.14224)
		(layer "In4.Cu")
		(net "M_L_DQ<57>")
	)
	(segment
		(start 138.98372 -119.044974)
		(end 138.98372 -118.826026)
		(width 0.14224)
		(layer "In4.Cu")
		(net "M_L_DQ<57>")
	)
	(segment
		(start 145.609564 -134.042404)
		(end 145.743168 -133.9088)
		(width 0.14224)
		(layer "In4.Cu")
		(net "M_L_DQ<57>")
	)
	(segment
		(start 144.825212 -142.7226)
		(end 144.610836 -142.936976)
		(width 0.14224)
		(layer "In4.Cu")
		(net "M_L_DQ<57>")
	)
	(segment
		(start 120.518682 -102.862634)
		(end 120.485916 -102.862634)
		(width 0.0889)
		(layer "In4.Cu")
		(net "M_L_DQ<57>")
	)
	(segment
		(start 145.717768 -136.684004)
		(end 145.609564 -136.5758)
		(width 0.14224)
		(layer "In4.Cu")
		(net "M_L_DQ<57>")
	)
	(segment
		(start 145.609564 -138.995404)
		(end 145.717768 -138.8872)
		(width 0.14224)
		(layer "In4.Cu")
		(net "M_L_DQ<57>")
	)
	(segment
		(start 123.341892 -106.774488)
		(end 122.774456 -106.207052)
		(width 0.0889)
		(layer "In4.Cu")
		(net "M_L_DQ<57>")
	)
	(segment
		(start 120.149366 -102.271322)
		(end 120.154192 -102.262686)
		(width 0.0889)
		(layer "In4.Cu")
		(net "M_L_DQ<57>")
	)
	(segment
		(start 138.045952 -117.888258)
		(end 128.907794 -108.7501)
		(width 0.14224)
		(layer "In4.Cu")
		(net "M_L_DQ<57>")
	)
	(segment
		(start 144.850612 -143.4846)
		(end 144.850612 -143.7894)
		(width 0.14224)
		(layer "In4.Cu")
		(net "M_L_DQ<57>")
	)
	(segment
		(start 144.610836 -142.936976)
		(end 144.610836 -143.244824)
		(width 0.14224)
		(layer "In4.Cu")
		(net "M_L_DQ<57>")
	)
	(segment
		(start 145.743168 -132.0292)
		(end 145.609564 -131.895596)
		(width 0.14224)
		(layer "In4.Cu")
		(net "M_L_DQ<57>")
	)
	(segment
		(start 144.850612 -143.7894)
		(end 144.698466 -143.941546)
		(width 0.14224)
		(layer "In4.Cu")
		(net "M_L_DQ<57>")
	)
	(segment
		(start 145.609564 -136.5758)
		(end 145.609564 -134.042404)
		(width 0.14224)
		(layer "In4.Cu")
		(net "M_L_DQ<57>")
	)
	(segment
		(start 144.610836 -141.715744)
		(end 144.610836 -142.076424)
		(width 0.14224)
		(layer "In4.Cu")
		(net "M_L_DQ<57>")
	)
	(segment
		(start 120.154192 -102.262686)
		(end 120.160542 -102.252018)
		(width 0.0889)
		(layer "In4.Cu")
		(net "M_L_DQ<57>")
	)
	(segment
		(start 144.901412 -141.020546)
		(end 144.901412 -141.425168)
		(width 0.14224)
		(layer "In4.Cu")
		(net "M_L_DQ<57>")
	)
	(segment
		(start 139.452604 -119.513858)
		(end 138.81608 -120.150382)
		(width 0.14224)
		(layer "In4.Cu")
		(net "M_L_DQ<57>")
	)
	(segment
		(start 145.717768 -138.8872)
		(end 145.717768 -136.684004)
		(width 0.14224)
		(layer "In4.Cu")
		(net "M_L_DQ<57>")
	)
	(segment
		(start 138.98372 -118.826026)
		(end 138.733784 -118.57609)
		(width 0.14224)
		(layer "In4.Cu")
		(net "M_L_DQ<57>")
	)
	(segment
		(start 120.149366 -99.299522)
		(end 120.154446 -99.290886)
		(width 0.0889)
		(layer "In4.Cu")
		(net "M_L_DQ<57>")
	)
	(segment
		(start 120.154192 -100.281486)
		(end 120.160542 -100.270818)
		(width 0.0889)
		(layer "In4.Cu")
		(net "M_L_DQ<57>")
	)
	(segment
		(start 137.409428 -118.962678)
		(end 137.409428 -118.74373)
		(width 0.14224)
		(layer "In4.Cu")
		(net "M_L_DQ<57>")
	)
	(segment
		(start 137.409428 -118.74373)
		(end 138.045952 -118.107206)
		(width 0.14224)
		(layer "In4.Cu")
		(net "M_L_DQ<57>")
	)
	(segment
		(start 145.099278 -139.932156)
		(end 144.671034 -140.3604)
		(width 0.14224)
		(layer "In4.Cu")
		(net "M_L_DQ<57>")
	)
	(segment
		(start 145.743168 -133.9088)
		(end 145.743168 -132.0292)
		(width 0.14224)
		(layer "In4.Cu")
		(net "M_L_DQ<57>")
	)
	(segment
		(start 120.198896 -96.223328)
		(end 120.500902 -95.528384)
		(width 0.0889)
		(layer "In4.Cu")
		(net "M_L_DQ<57>")
	)
	(segment
		(start 120.154192 -101.272086)
		(end 120.160542 -101.261418)
		(width 0.0889)
		(layer "In4.Cu")
		(net "M_L_DQ<57>")
	)
	(segment
		(start 138.514836 -118.57609)
		(end 137.878312 -119.212614)
		(width 0.14224)
		(layer "In4.Cu")
		(net "M_L_DQ<57>")
	)
	(segment
		(start 122.774456 -106.207052)
		(end 122.73026 -106.130344)
		(width 0.0889)
		(layer "In4.Cu")
		(net "M_L_DQ<57>")
	)
	(segment
		(start 122.235468 -105.834434)
		(end 122.202702 -105.834434)
		(width 0.0889)
		(layer "In4.Cu")
		(net "M_L_DQ<57>")
	)
	(segment
		(start 138.597132 -120.150382)
		(end 138.347196 -119.900446)
		(width 0.14224)
		(layer "In4.Cu")
		(net "M_L_DQ<57>")
	)
	(segment
		(start 138.733784 -118.57609)
		(end 138.514836 -118.57609)
		(width 0.14224)
		(layer "In4.Cu")
		(net "M_L_DQ<57>")
	)
	(segment
		(start 121.380758 -105.339388)
		(end 121.359168 -105.339388)
		(width 0.0889)
		(layer "In4.Cu")
		(net "M_L_DQ<57>")
	)
	(segment
		(start 138.347196 -119.681498)
		(end 138.98372 -119.044974)
		(width 0.14224)
		(layer "In4.Cu")
		(net "M_L_DQ<57>")
	)
	(segment
		(start 123.861068 -108.7501)
		(end 123.568968 -108.458)
		(width 0.14224)
		(layer "In4.Cu")
		(net "M_L_DQ<57>")
	)
	(segment
		(start 120.149366 -100.290122)
		(end 120.154192 -100.281486)
		(width 0.0889)
		(layer "In4.Cu")
		(net "M_L_DQ<57>")
	)
	(segment
		(start 138.045952 -118.107206)
		(end 138.045952 -117.888258)
		(width 0.14224)
		(layer "In4.Cu")
		(net "M_L_DQ<57>")
	)
	(segment
		(start 144.698466 -143.941546)
		(end 144.449546 -143.941546)
		(width 0.14224)
		(layer "In4.Cu")
		(net "M_L_DQ<57>")
	)
	(segment
		(start 121.021602 -104.163876)
		(end 121.012712 -104.148636)
		(width 0.0889)
		(layer "In4.Cu")
		(net "M_L_DQ<57>")
	)
	(segment
		(start 144.610836 -143.244824)
		(end 144.850612 -143.4846)
		(width 0.14224)
		(layer "In4.Cu")
		(net "M_L_DQ<57>")
	)
	(segment
		(start 128.907794 -108.7501)
		(end 123.861068 -108.7501)
		(width 0.14224)
		(layer "In4.Cu")
		(net "M_L_DQ<57>")
	)
	(segment
		(start 138.81608 -120.150382)
		(end 138.597132 -120.150382)
		(width 0.14224)
		(layer "In4.Cu")
		(net "M_L_DQ<57>")
	)
	(segment
		(start 145.609564 -131.895596)
		(end 145.609564 -125.45187)
		(width 0.14224)
		(layer "In4.Cu")
		(net "M_L_DQ<57>")
	)
	(segment
		(start 144.671034 -140.790168)
		(end 144.901412 -141.020546)
		(width 0.14224)
		(layer "In4.Cu")
		(net "M_L_DQ<57>")
	)
	(segment
		(start 145.12163 -139.932156)
		(end 145.099278 -139.932156)
		(width 0.14224)
		(layer "In4.Cu")
		(net "M_L_DQ<57>")
	)
	(segment
		(start 144.671034 -140.3604)
		(end 144.671034 -140.790168)
		(width 0.14224)
		(layer "In4.Cu")
		(net "M_L_DQ<57>")
	)
	(segment
		(start 120.149366 -101.280722)
		(end 120.154192 -101.272086)
		(width 0.0889)
		(layer "In4.Cu")
		(net "M_L_DQ<57>")
	)
	(segment
		(start 145.12163 -139.843256)
		(end 145.609564 -139.355322)
		(width 0.14224)
		(layer "In4.Cu")
		(net "M_L_DQ<57>")
	)
	(segment
		(start 137.659364 -119.212614)
		(end 137.409428 -118.962678)
		(width 0.14224)
		(layer "In4.Cu")
		(net "M_L_DQ<57>")
	)
	(segment
		(start 145.609564 -125.45187)
		(end 139.671552 -119.513858)
		(width 0.14224)
		(layer "In4.Cu")
		(net "M_L_DQ<57>")
	)
	(segment
		(start 145.12163 -139.932156)
		(end 145.12163 -139.843256)
		(width 0.14224)
		(layer "In4.Cu")
		(net "M_L_DQ<57>")
	)
	(segment
		(start 139.671552 -119.513858)
		(end 139.452604 -119.513858)
		(width 0.14224)
		(layer "In4.Cu")
		(net "M_L_DQ<57>")
	)
	(segment
		(start 123.568968 -107.407456)
		(end 123.341892 -107.18038)
		(width 0.0889)
		(layer "In4.Cu")
		(net "M_L_DQ<57>")
	)
	(segment
		(start 123.341892 -107.18038)
		(end 123.341892 -106.774488)
		(width 0.0889)
		(layer "In4.Cu")
		(net "M_L_DQ<57>")
	)
	(segment
		(start 144.825212 -142.2908)
		(end 144.825212 -142.7226)
		(width 0.14224)
		(layer "In4.Cu")
		(net "M_L_DQ<57>")
	)
	(arc
		(start 121.012712 -104.148636)
		(mid 120.959179 -103.948738)
		(end 121.012712 -103.74884)
		(width 0.0889)
		(layer "In4.Cu")
		(net "M_L_DQ<57>")
	)
	(arc
		(start 120.160542 -100.270818)
		(mid 120.23334 -99.980055)
		(end 120.154192 -99.690936)
		(width 0.0889)
		(layer "In4.Cu")
		(net "M_L_DQ<57>")
	)
	(arc
		(start 120.154192 -100.681536)
		(mid 120.100722 -100.486473)
		(end 120.149366 -100.290122)
		(width 0.0889)
		(layer "In4.Cu")
		(net "M_L_DQ<57>")
	)
	(arc
		(start 120.154446 -99.290886)
		(mid 120.233577 -98.995484)
		(end 120.154446 -98.700082)
		(width 0.0889)
		(layer "In4.Cu")
		(net "M_L_DQ<57>")
	)
	(arc
		(start 120.154446 -97.709482)
		(mid 120.100947 -97.509584)
		(end 120.154446 -97.309686)
		(width 0.0889)
		(layer "In4.Cu")
		(net "M_L_DQ<57>")
	)
	(arc
		(start 120.154446 -98.300286)
		(mid 120.233577 -98.004884)
		(end 120.154446 -97.709482)
		(width 0.0889)
		(layer "In4.Cu")
		(net "M_L_DQ<57>")
	)
	(arc
		(start 121.870978 -105.634536)
		(mid 121.663974 -105.423672)
		(end 121.380758 -105.339388)
		(width 0.0889)
		(layer "In4.Cu")
		(net "M_L_DQ<57>")
	)
	(arc
		(start 121.012712 -103.74884)
		(mid 121.017237 -103.165499)
		(end 120.518682 -102.862634)
		(width 0.0889)
		(layer "In4.Cu")
		(net "M_L_DQ<57>")
	)
	(arc
		(start 122.202702 -105.834434)
		(mid 122.01106 -105.777268)
		(end 121.870978 -105.634536)
		(width 0.0889)
		(layer "In4.Cu")
		(net "M_L_DQ<57>")
	)
	(arc
		(start 121.359168 -105.339388)
		(mid 121.012742 -105.139411)
		(end 121.012712 -104.73944)
		(width 0.0889)
		(layer "In4.Cu")
		(net "M_L_DQ<57>")
	)
	(arc
		(start 122.73026 -106.130344)
		(mid 122.521353 -105.918026)
		(end 122.235468 -105.834434)
		(width 0.0889)
		(layer "In4.Cu")
		(net "M_L_DQ<57>")
	)
	(arc
		(start 120.160542 -101.261418)
		(mid 120.23334 -100.970655)
		(end 120.154192 -100.681536)
		(width 0.0889)
		(layer "In4.Cu")
		(net "M_L_DQ<57>")
	)
	(arc
		(start 121.012712 -104.73944)
		(mid 121.091901 -104.452825)
		(end 121.021602 -104.163876)
		(width 0.0889)
		(layer "In4.Cu")
		(net "M_L_DQ<57>")
	)
	(arc
		(start 120.154446 -98.700082)
		(mid 120.100947 -98.500184)
		(end 120.154446 -98.300286)
		(width 0.0889)
		(layer "In4.Cu")
		(net "M_L_DQ<57>")
	)
	(arc
		(start 120.154192 -101.672136)
		(mid 120.100722 -101.477073)
		(end 120.149366 -101.280722)
		(width 0.0889)
		(layer "In4.Cu")
		(net "M_L_DQ<57>")
	)
	(arc
		(start 120.154446 -96.718882)
		(mid 120.100947 -96.518984)
		(end 120.154446 -96.319086)
		(width 0.0889)
		(layer "In4.Cu")
		(net "M_L_DQ<57>")
	)
	(arc
		(start 120.154446 -97.309686)
		(mid 120.233577 -97.014284)
		(end 120.154446 -96.718882)
		(width 0.0889)
		(layer "In4.Cu")
		(net "M_L_DQ<57>")
	)
	(arc
		(start 120.154192 -99.690936)
		(mid 120.100722 -99.495873)
		(end 120.149366 -99.299522)
		(width 0.0889)
		(layer "In4.Cu")
		(net "M_L_DQ<57>")
	)
	(arc
		(start 120.154446 -96.319086)
		(mid 120.178814 -96.272202)
		(end 120.198896 -96.223328)
		(width 0.0889)
		(layer "In4.Cu")
		(net "M_L_DQ<57>")
	)
	(arc
		(start 120.160542 -102.252018)
		(mid 120.23334 -101.961255)
		(end 120.154192 -101.672136)
		(width 0.0889)
		(layer "In4.Cu")
		(net "M_L_DQ<57>")
	)
	(arc
		(start 120.485916 -102.862634)
		(mid 120.152998 -102.660643)
		(end 120.149366 -102.271322)
		(width 0.0889)
		(layer "In4.Cu")
		(net "M_L_DQ<57>")
	)
	(segment
		(start 145.29943 -147.27174)
		(end 145.29943 -147.277582)
		(width 0.1651)
		(layer "F.Cu")
		(net "M_L_DQ<56>")
	)
	(segment
		(start 145.29943 -147.277582)
		(end 145.12163 -145.415)
		(width 0.1651)
		(layer "F.Cu")
		(net "M_L_DQ<56>")
	)
	(segment
		(start 119.929402 -93.547184)
		(end 120.500902 -93.547184)
		(width 0.1651)
		(layer "F.Cu")
		(net "M_L_DQ<56>")
	)
	(via
		(at 120.500902 -93.547184)
		(size 0.508)
		(drill 0.254)
		(layers "F.Cu" "B.Cu")
		(net "M_L_DQ<56>")
	)
	(via
		(at 145.12163 -145.415)
		(size 0.508)
		(drill 0.254)
		(layers "F.Cu" "B.Cu")
		(net "M_L_DQ<56>")
	)
	(via
		(at 144.449546 -141.213078)
		(size 0.508)
		(drill 0.254)
		(layers "F.Cu" "B.Cu")
		(net "M_L_DQ<56>")
	)
	(segment
		(start 144.449546 -142.477236)
		(end 144.449546 -141.213078)
		(width 0.1651)
		(layer "B.Cu")
		(net "M_L_DQ<56>")
	)
	(segment
		(start 120.838468 -104.228646)
		(end 120.847358 -104.243886)
		(width 0.0889)
		(layer "In4.Cu")
		(net "M_L_DQ<56>")
	)
	(segment
		(start 144.936464 -139.358878)
		(end 144.219168 -140.076174)
		(width 0.14224)
		(layer "In4.Cu")
		(net "M_L_DQ<56>")
	)
	(segment
		(start 119.989346 -95.232982)
		(end 120.120664 -95.005398)
		(width 0.0889)
		(layer "In4.Cu")
		(net "M_L_DQ<56>")
	)
	(segment
		(start 144.016476 -144.60601)
		(end 144.825466 -145.415)
		(width 0.14224)
		(layer "In4.Cu")
		(net "M_L_DQ<56>")
	)
	(segment
		(start 122.944128 -107.46867)
		(end 122.944128 -111.26216)
		(width 0.14224)
		(layer "In4.Cu")
		(net "M_L_DQ<56>")
	)
	(segment
		(start 144.974564 -125.595888)
		(end 144.974564 -129.719578)
		(width 0.14224)
		(layer "In4.Cu")
		(net "M_L_DQ<56>")
	)
	(segment
		(start 144.825466 -145.415)
		(end 145.12163 -145.415)
		(width 0.14224)
		(layer "In4.Cu")
		(net "M_L_DQ<56>")
	)
	(segment
		(start 120.500902 -93.547184)
		(end 120.201436 -94.234762)
		(width 0.0889)
		(layer "In4.Cu")
		(net "M_L_DQ<56>")
	)
	(segment
		(start 144.61617 -135.957056)
		(end 144.936464 -136.27735)
		(width 0.14224)
		(layer "In4.Cu")
		(net "M_L_DQ<56>")
	)
	(segment
		(start 144.449546 -141.213078)
		(end 144.016476 -141.646148)
		(width 0.14224)
		(layer "In4.Cu")
		(net "M_L_DQ<56>")
	)
	(segment
		(start 144.879568 -134.0358)
		(end 144.923764 -134.079996)
		(width 0.14224)
		(layer "In4.Cu")
		(net "M_L_DQ<56>")
	)
	(segment
		(start 144.936464 -136.27735)
		(end 144.936464 -136.5758)
		(width 0.14224)
		(layer "In4.Cu")
		(net "M_L_DQ<56>")
	)
	(segment
		(start 144.016476 -141.646148)
		(end 144.016476 -144.60601)
		(width 0.14224)
		(layer "In4.Cu")
		(net "M_L_DQ<56>")
	)
	(segment
		(start 144.974564 -129.719578)
		(end 144.631664 -130.062478)
		(width 0.14224)
		(layer "In4.Cu")
		(net "M_L_DQ<56>")
	)
	(segment
		(start 134.4676 -120.025668)
		(end 140.637514 -121.258838)
		(width 0.14224)
		(layer "In4.Cu")
		(net "M_L_DQ<56>")
	)
	(segment
		(start 122.944128 -111.26216)
		(end 126.159768 -114.4778)
		(width 0.14224)
		(layer "In4.Cu")
		(net "M_L_DQ<56>")
	)
	(segment
		(start 144.923764 -131.9022)
		(end 144.879568 -131.946396)
		(width 0.14224)
		(layer "In4.Cu")
		(net "M_L_DQ<56>")
	)
	(segment
		(start 144.923764 -131.434078)
		(end 144.923764 -131.9022)
		(width 0.14224)
		(layer "In4.Cu")
		(net "M_L_DQ<56>")
	)
	(segment
		(start 144.923764 -134.079996)
		(end 144.923764 -134.478776)
		(width 0.14224)
		(layer "In4.Cu")
		(net "M_L_DQ<56>")
	)
	(segment
		(start 140.637514 -121.258838)
		(end 144.974564 -125.595888)
		(width 0.14224)
		(layer "In4.Cu")
		(net "M_L_DQ<56>")
	)
	(segment
		(start 122.62104 -106.32313)
		(end 123.151392 -106.853482)
		(width 0.0889)
		(layer "In4.Cu")
		(net "M_L_DQ<56>")
	)
	(segment
		(start 119.993918 -101.1682)
		(end 119.989092 -101.176836)
		(width 0.0889)
		(layer "In4.Cu")
		(net "M_L_DQ<56>")
	)
	(segment
		(start 144.61617 -134.78637)
		(end 144.61617 -135.957056)
		(width 0.14224)
		(layer "In4.Cu")
		(net "M_L_DQ<56>")
	)
	(segment
		(start 144.219168 -140.076174)
		(end 144.219168 -140.9827)
		(width 0.14224)
		(layer "In4.Cu")
		(net "M_L_DQ<56>")
	)
	(segment
		(start 144.936464 -136.5758)
		(end 144.879568 -136.632696)
		(width 0.14224)
		(layer "In4.Cu")
		(net "M_L_DQ<56>")
	)
	(segment
		(start 144.219168 -140.9827)
		(end 144.449546 -141.213078)
		(width 0.14224)
		(layer "In4.Cu")
		(net "M_L_DQ<56>")
	)
	(segment
		(start 126.159768 -114.4778)
		(end 128.919732 -114.4778)
		(width 0.14224)
		(layer "In4.Cu")
		(net "M_L_DQ<56>")
	)
	(segment
		(start 123.151392 -107.261406)
		(end 122.944128 -107.46867)
		(width 0.0889)
		(layer "In4.Cu")
		(net "M_L_DQ<56>")
	)
	(segment
		(start 119.989092 -100.186236)
		(end 119.982742 -100.196904)
		(width 0.0889)
		(layer "In4.Cu")
		(net "M_L_DQ<56>")
	)
	(segment
		(start 122.196098 -106.024934)
		(end 122.228864 -106.024934)
		(width 0.0889)
		(layer "In4.Cu")
		(net "M_L_DQ<56>")
	)
	(segment
		(start 144.631664 -131.141978)
		(end 144.923764 -131.434078)
		(width 0.14224)
		(layer "In4.Cu")
		(net "M_L_DQ<56>")
	)
	(segment
		(start 144.936464 -138.944096)
		(end 144.936464 -139.358878)
		(width 0.14224)
		(layer "In4.Cu")
		(net "M_L_DQ<56>")
	)
	(segment
		(start 144.879568 -136.632696)
		(end 144.879568 -138.8872)
		(width 0.14224)
		(layer "In4.Cu")
		(net "M_L_DQ<56>")
	)
	(segment
		(start 122.564398 -106.225086)
		(end 122.62104 -106.32313)
		(width 0.0889)
		(layer "In4.Cu")
		(net "M_L_DQ<56>")
	)
	(segment
		(start 144.879568 -131.946396)
		(end 144.879568 -134.0358)
		(width 0.14224)
		(layer "In4.Cu")
		(net "M_L_DQ<56>")
	)
	(segment
		(start 119.989092 -102.167436)
		(end 119.982742 -102.178104)
		(width 0.0889)
		(layer "In4.Cu")
		(net "M_L_DQ<56>")
	)
	(segment
		(start 120.479312 -103.053134)
		(end 120.500902 -103.053134)
		(width 0.0889)
		(layer "In4.Cu")
		(net "M_L_DQ<56>")
	)
	(segment
		(start 144.631664 -130.062478)
		(end 144.631664 -131.141978)
		(width 0.14224)
		(layer "In4.Cu")
		(net "M_L_DQ<56>")
	)
	(segment
		(start 119.989092 -101.176836)
		(end 119.982742 -101.187504)
		(width 0.0889)
		(layer "In4.Cu")
		(net "M_L_DQ<56>")
	)
	(segment
		(start 144.879568 -138.8872)
		(end 144.936464 -138.944096)
		(width 0.14224)
		(layer "In4.Cu")
		(net "M_L_DQ<56>")
	)
	(segment
		(start 119.993918 -102.1588)
		(end 119.989092 -102.167436)
		(width 0.0889)
		(layer "In4.Cu")
		(net "M_L_DQ<56>")
	)
	(segment
		(start 119.993918 -100.1776)
		(end 119.989092 -100.186236)
		(width 0.0889)
		(layer "In4.Cu")
		(net "M_L_DQ<56>")
	)
	(segment
		(start 128.919732 -114.4778)
		(end 134.4676 -120.025668)
		(width 0.14224)
		(layer "In4.Cu")
		(net "M_L_DQ<56>")
	)
	(segment
		(start 121.341388 -105.529888)
		(end 121.374154 -105.529888)
		(width 0.0889)
		(layer "In4.Cu")
		(net "M_L_DQ<56>")
	)
	(segment
		(start 123.151392 -106.853482)
		(end 123.151392 -107.261406)
		(width 0.0889)
		(layer "In4.Cu")
		(net "M_L_DQ<56>")
	)
	(segment
		(start 144.923764 -134.478776)
		(end 144.61617 -134.78637)
		(width 0.14224)
		(layer "In4.Cu")
		(net "M_L_DQ<56>")
	)
	(arc
		(start 119.989346 -97.214182)
		(mid 119.910215 -97.509584)
		(end 119.989346 -97.804986)
		(width 0.0889)
		(layer "In4.Cu")
		(net "M_L_DQ<56>")
	)
	(arc
		(start 120.847358 -104.643682)
		(mid 120.84303 -105.226858)
		(end 121.341388 -105.529888)
		(width 0.0889)
		(layer "In4.Cu")
		(net "M_L_DQ<56>")
	)
	(arc
		(start 120.201436 -94.234762)
		(mid 120.180425 -94.287456)
		(end 120.154446 -94.337886)
		(width 0.0889)
		(layer "In4.Cu")
		(net "M_L_DQ<56>")
	)
	(arc
		(start 120.847358 -104.243886)
		(mid 120.900891 -104.443784)
		(end 120.847358 -104.643682)
		(width 0.0889)
		(layer "In4.Cu")
		(net "M_L_DQ<56>")
	)
	(arc
		(start 120.500902 -103.053134)
		(mid 120.847328 -103.253111)
		(end 120.847358 -103.653082)
		(width 0.0889)
		(layer "In4.Cu")
		(net "M_L_DQ<56>")
	)
	(arc
		(start 119.989346 -98.795586)
		(mid 120.042845 -98.995484)
		(end 119.989346 -99.195382)
		(width 0.0889)
		(layer "In4.Cu")
		(net "M_L_DQ<56>")
	)
	(arc
		(start 119.989092 -100.776786)
		(mid 120.042562 -100.971849)
		(end 119.993918 -101.1682)
		(width 0.0889)
		(layer "In4.Cu")
		(net "M_L_DQ<56>")
	)
	(arc
		(start 122.228864 -106.024934)
		(mid 122.422714 -106.081284)
		(end 122.564398 -106.225086)
		(width 0.0889)
		(layer "In4.Cu")
		(net "M_L_DQ<56>")
	)
	(arc
		(start 119.982742 -100.196904)
		(mid 119.909944 -100.487667)
		(end 119.989092 -100.776786)
		(width 0.0889)
		(layer "In4.Cu")
		(net "M_L_DQ<56>")
	)
	(arc
		(start 120.136158 -94.701868)
		(mid 120.165023 -94.855503)
		(end 120.120664 -95.005398)
		(width 0.0889)
		(layer "In4.Cu")
		(net "M_L_DQ<56>")
	)
	(arc
		(start 119.989346 -95.823786)
		(mid 120.042845 -96.023684)
		(end 119.989346 -96.223582)
		(width 0.0889)
		(layer "In4.Cu")
		(net "M_L_DQ<56>")
	)
	(arc
		(start 120.847358 -103.653082)
		(mid 120.768169 -103.939697)
		(end 120.838468 -104.228646)
		(width 0.0889)
		(layer "In4.Cu")
		(net "M_L_DQ<56>")
	)
	(arc
		(start 119.982742 -101.187504)
		(mid 119.909944 -101.478267)
		(end 119.989092 -101.767386)
		(width 0.0889)
		(layer "In4.Cu")
		(net "M_L_DQ<56>")
	)
	(arc
		(start 119.989346 -96.814386)
		(mid 120.042845 -97.014284)
		(end 119.989346 -97.214182)
		(width 0.0889)
		(layer "In4.Cu")
		(net "M_L_DQ<56>")
	)
	(arc
		(start 119.989346 -96.223582)
		(mid 119.910215 -96.518984)
		(end 119.989346 -96.814386)
		(width 0.0889)
		(layer "In4.Cu")
		(net "M_L_DQ<56>")
	)
	(arc
		(start 119.989346 -98.204782)
		(mid 119.910215 -98.500184)
		(end 119.989346 -98.795586)
		(width 0.0889)
		(layer "In4.Cu")
		(net "M_L_DQ<56>")
	)
	(arc
		(start 119.989092 -101.767386)
		(mid 120.042562 -101.962449)
		(end 119.993918 -102.1588)
		(width 0.0889)
		(layer "In4.Cu")
		(net "M_L_DQ<56>")
	)
	(arc
		(start 119.982742 -102.178104)
		(mid 119.986773 -102.754286)
		(end 120.479312 -103.053134)
		(width 0.0889)
		(layer "In4.Cu")
		(net "M_L_DQ<56>")
	)
	(arc
		(start 119.989092 -99.786186)
		(mid 120.042562 -99.981249)
		(end 119.993918 -100.1776)
		(width 0.0889)
		(layer "In4.Cu")
		(net "M_L_DQ<56>")
	)
	(arc
		(start 121.705878 -105.729786)
		(mid 121.912882 -105.94065)
		(end 122.196098 -106.024934)
		(width 0.0889)
		(layer "In4.Cu")
		(net "M_L_DQ<56>")
	)
	(arc
		(start 119.989346 -99.195382)
		(mid 119.986099 -99.200876)
		(end 119.982742 -99.206304)
		(width 0.0889)
		(layer "In4.Cu")
		(net "M_L_DQ<56>")
	)
	(arc
		(start 119.982742 -99.206304)
		(mid 119.909944 -99.497067)
		(end 119.989092 -99.786186)
		(width 0.0889)
		(layer "In4.Cu")
		(net "M_L_DQ<56>")
	)
	(arc
		(start 121.374154 -105.529888)
		(mid 121.565796 -105.587054)
		(end 121.705878 -105.729786)
		(width 0.0889)
		(layer "In4.Cu")
		(net "M_L_DQ<56>")
	)
	(arc
		(start 119.989346 -95.232982)
		(mid 119.910215 -95.528384)
		(end 119.989346 -95.823786)
		(width 0.0889)
		(layer "In4.Cu")
		(net "M_L_DQ<56>")
	)
	(arc
		(start 120.154446 -94.337886)
		(mid 120.101453 -94.517677)
		(end 120.136158 -94.701868)
		(width 0.0889)
		(layer "In4.Cu")
		(net "M_L_DQ<56>")
	)
	(arc
		(start 119.989346 -97.804986)
		(mid 120.042845 -98.004884)
		(end 119.989346 -98.204782)
		(width 0.0889)
		(layer "In4.Cu")
		(net "M_L_DQ<56>")
	)
	(segment
		(start 140.815568 -124.21108)
		(end 140.815568 -125.182376)
		(width 0.1651)
		(layer "F.Cu")
		(net "M_L_DQ<55>")
	)
	(segment
		(start 136.421368 -109.0676)
		(end 136.707118 -109.35335)
		(width 0.1651)
		(layer "F.Cu")
		(net "M_L_DQ<55>")
	)
	(segment
		(start 137.919206 -110.997238)
		(end 138.351006 -110.997238)
		(width 0.1651)
		(layer "F.Cu")
		(net "M_L_DQ<55>")
	)
	(segment
		(start 140.08608 -120.072912)
		(end 140.74648 -120.072912)
		(width 0.1651)
		(layer "F.Cu")
		(net "M_L_DQ<55>")
	)
	(segment
		(start 122.915934 -105.080054)
		(end 131.03606 -105.080054)
		(width 0.1016)
		(layer "F.Cu")
		(net "M_L_DQ<55>")
	)
	(segment
		(start 139.302998 -111.94923)
		(end 139.876784 -112.523016)
		(width 0.1651)
		(layer "F.Cu")
		(net "M_L_DQ<55>")
	)
	(segment
		(start 140.743432 -121.059448)
		(end 140.578332 -121.224548)
		(width 0.1651)
		(layer "F.Cu")
		(net "M_L_DQ<55>")
	)
	(segment
		(start 136.707118 -109.35335)
		(end 136.707118 -109.78515)
		(width 0.1651)
		(layer "F.Cu")
		(net "M_L_DQ<55>")
	)
	(segment
		(start 136.967214 -110.045246)
		(end 137.399014 -110.045246)
		(width 0.1651)
		(layer "F.Cu")
		(net "M_L_DQ<55>")
	)
	(segment
		(start 138.611102 -111.689134)
		(end 138.871198 -111.94923)
		(width 0.1651)
		(layer "F.Cu")
		(net "M_L_DQ<55>")
	)
	(segment
		(start 140.942568 -124.08408)
		(end 140.815568 -124.21108)
		(width 0.1651)
		(layer "F.Cu")
		(net "M_L_DQ<55>")
	)
	(segment
		(start 121.646188 -103.810308)
		(end 122.915934 -105.080054)
		(width 0.1016)
		(layer "F.Cu")
		(net "M_L_DQ<55>")
	)
	(segment
		(start 137.399014 -110.045246)
		(end 137.65911 -110.305342)
		(width 0.1651)
		(layer "F.Cu")
		(net "M_L_DQ<55>")
	)
	(segment
		(start 140.937742 -121.059448)
		(end 140.743432 -121.059448)
		(width 0.1651)
		(layer "F.Cu")
		(net "M_L_DQ<55>")
	)
	(segment
		(start 139.34948 -142.6718)
		(end 139.34948 -143.941546)
		(width 0.1651)
		(layer "F.Cu")
		(net "M_L_DQ<55>")
	)
	(segment
		(start 140.74648 -120.072912)
		(end 141.135354 -120.461786)
		(width 0.1651)
		(layer "F.Cu")
		(net "M_L_DQ<55>")
	)
	(segment
		(start 141.102842 -123.956826)
		(end 140.975588 -124.08408)
		(width 0.1651)
		(layer "F.Cu")
		(net "M_L_DQ<55>")
	)
	(segment
		(start 140.975588 -124.08408)
		(end 140.942568 -124.08408)
		(width 0.1651)
		(layer "F.Cu")
		(net "M_L_DQ<55>")
	)
	(segment
		(start 140.578332 -121.224548)
		(end 140.578332 -121.717308)
		(width 0.1651)
		(layer "F.Cu")
		(net "M_L_DQ<55>")
	)
	(segment
		(start 141.135354 -120.861836)
		(end 140.937742 -121.059448)
		(width 0.1651)
		(layer "F.Cu")
		(net "M_L_DQ<55>")
	)
	(segment
		(start 141.102842 -122.047508)
		(end 141.102842 -123.956826)
		(width 0.1651)
		(layer "F.Cu")
		(net "M_L_DQ<55>")
	)
	(segment
		(start 131.03606 -105.080054)
		(end 134.261606 -108.3056)
		(width 0.1016)
		(layer "F.Cu")
		(net "M_L_DQ<55>")
	)
	(segment
		(start 121.646188 -102.462584)
		(end 121.646188 -103.810308)
		(width 0.0889)
		(layer "F.Cu")
		(net "M_L_DQ<55>")
	)
	(segment
		(start 137.65911 -110.737142)
		(end 137.919206 -110.997238)
		(width 0.1651)
		(layer "F.Cu")
		(net "M_L_DQ<55>")
	)
	(segment
		(start 140.937742 -121.882408)
		(end 141.102842 -122.047508)
		(width 0.1651)
		(layer "F.Cu")
		(net "M_L_DQ<55>")
	)
	(segment
		(start 139.876784 -119.863616)
		(end 140.08608 -120.072912)
		(width 0.1651)
		(layer "F.Cu")
		(net "M_L_DQ<55>")
	)
	(segment
		(start 137.65911 -110.305342)
		(end 137.65911 -110.737142)
		(width 0.1651)
		(layer "F.Cu")
		(net "M_L_DQ<55>")
	)
	(segment
		(start 140.743432 -121.882408)
		(end 140.937742 -121.882408)
		(width 0.1651)
		(layer "F.Cu")
		(net "M_L_DQ<55>")
	)
	(segment
		(start 134.261606 -108.3056)
		(end 135.27024 -108.3056)
		(width 0.1016)
		(layer "F.Cu")
		(net "M_L_DQ<55>")
	)
	(segment
		(start 141.135354 -120.461786)
		(end 141.135354 -120.861836)
		(width 0.1651)
		(layer "F.Cu")
		(net "M_L_DQ<55>")
	)
	(segment
		(start 138.611102 -111.257334)
		(end 138.611102 -111.689134)
		(width 0.1651)
		(layer "F.Cu")
		(net "M_L_DQ<55>")
	)
	(segment
		(start 135.443468 -108.478828)
		(end 136.03224 -109.0676)
		(width 0.1651)
		(layer "F.Cu")
		(net "M_L_DQ<55>")
	)
	(segment
		(start 138.351006 -110.997238)
		(end 138.611102 -111.257334)
		(width 0.1651)
		(layer "F.Cu")
		(net "M_L_DQ<55>")
	)
	(segment
		(start 140.688568 -125.309376)
		(end 140.046964 -125.309376)
		(width 0.1651)
		(layer "F.Cu")
		(net "M_L_DQ<55>")
	)
	(segment
		(start 140.578332 -121.717308)
		(end 140.743432 -121.882408)
		(width 0.1651)
		(layer "F.Cu")
		(net "M_L_DQ<55>")
	)
	(segment
		(start 135.27024 -108.3056)
		(end 135.443468 -108.478828)
		(width 0.1016)
		(layer "F.Cu")
		(net "M_L_DQ<55>")
	)
	(segment
		(start 138.871198 -111.94923)
		(end 139.302998 -111.94923)
		(width 0.1651)
		(layer "F.Cu")
		(net "M_L_DQ<55>")
	)
	(segment
		(start 136.03224 -109.0676)
		(end 136.421368 -109.0676)
		(width 0.1651)
		(layer "F.Cu")
		(net "M_L_DQ<55>")
	)
	(segment
		(start 136.707118 -109.78515)
		(end 136.967214 -110.045246)
		(width 0.1651)
		(layer "F.Cu")
		(net "M_L_DQ<55>")
	)
	(segment
		(start 140.815568 -125.182376)
		(end 140.688568 -125.309376)
		(width 0.1651)
		(layer "F.Cu")
		(net "M_L_DQ<55>")
	)
	(segment
		(start 139.876784 -112.523016)
		(end 139.876784 -119.863616)
		(width 0.1651)
		(layer "F.Cu")
		(net "M_L_DQ<55>")
	)
	(via
		(at 140.199364 -139.932156)
		(size 0.508)
		(drill 0.254)
		(layers "F.Cu" "B.Cu")
		(net "M_L_DQ<55>")
	)
	(via
		(at 140.046964 -125.309376)
		(size 0.508)
		(drill 0.254)
		(layers "F.Cu" "B.Cu")
		(net "M_L_DQ<55>")
	)
	(via
		(at 139.34948 -143.941546)
		(size 0.508)
		(drill 0.254)
		(layers "F.Cu" "B.Cu")
		(net "M_L_DQ<55>")
	)
	(segment
		(start 140.199364 -137.877296)
		(end 140.199364 -139.932156)
		(width 0.1651)
		(layer "B.Cu")
		(net "M_L_DQ<55>")
	)
	(segment
		(start 140.541248 -139.590272)
		(end 140.199364 -139.932156)
		(width 0.14224)
		(layer "In4.Cu")
		(net "M_L_DQ<55>")
	)
	(segment
		(start 140.55217 -136.204198)
		(end 140.55217 -136.6012)
		(width 0.14224)
		(layer "In4.Cu")
		(net "M_L_DQ<55>")
	)
	(segment
		(start 140.78077 -131.205478)
		(end 140.57757 -131.408678)
		(width 0.14224)
		(layer "In4.Cu")
		(net "M_L_DQ<55>")
	)
	(segment
		(start 140.046964 -125.309376)
		(end 140.046964 -126.911608)
		(width 0.14224)
		(layer "In4.Cu")
		(net "M_L_DQ<55>")
	)
	(segment
		(start 140.55217 -138.896598)
		(end 140.55217 -139.590272)
		(width 0.14224)
		(layer "In4.Cu")
		(net "M_L_DQ<55>")
	)
	(segment
		(start 140.55217 -129.859278)
		(end 140.78077 -130.087878)
		(width 0.14224)
		(layer "In4.Cu")
		(net "M_L_DQ<55>")
	)
	(segment
		(start 140.721334 -136.035034)
		(end 140.55217 -136.204198)
		(width 0.14224)
		(layer "In4.Cu")
		(net "M_L_DQ<55>")
	)
	(segment
		(start 140.57757 -134.568438)
		(end 140.721334 -134.712202)
		(width 0.14224)
		(layer "In4.Cu")
		(net "M_L_DQ<55>")
	)
	(segment
		(start 140.637768 -136.686798)
		(end 140.637768 -138.811)
		(width 0.14224)
		(layer "In4.Cu")
		(net "M_L_DQ<55>")
	)
	(segment
		(start 140.55217 -127.416814)
		(end 140.55217 -129.859278)
		(width 0.14224)
		(layer "In4.Cu")
		(net "M_L_DQ<55>")
	)
	(segment
		(start 140.046964 -126.911608)
		(end 140.55217 -127.416814)
		(width 0.14224)
		(layer "In4.Cu")
		(net "M_L_DQ<55>")
	)
	(segment
		(start 140.637768 -138.811)
		(end 140.55217 -138.896598)
		(width 0.14224)
		(layer "In4.Cu")
		(net "M_L_DQ<55>")
	)
	(segment
		(start 140.55217 -136.6012)
		(end 140.637768 -136.686798)
		(width 0.14224)
		(layer "In4.Cu")
		(net "M_L_DQ<55>")
	)
	(segment
		(start 140.78077 -130.087878)
		(end 140.78077 -131.205478)
		(width 0.14224)
		(layer "In4.Cu")
		(net "M_L_DQ<55>")
	)
	(segment
		(start 140.57757 -131.408678)
		(end 140.57757 -131.9276)
		(width 0.14224)
		(layer "In4.Cu")
		(net "M_L_DQ<55>")
	)
	(segment
		(start 140.612368 -134.0866)
		(end 140.57757 -134.121398)
		(width 0.14224)
		(layer "In4.Cu")
		(net "M_L_DQ<55>")
	)
	(segment
		(start 140.57757 -131.9276)
		(end 140.612368 -131.962398)
		(width 0.14224)
		(layer "In4.Cu")
		(net "M_L_DQ<55>")
	)
	(segment
		(start 140.57757 -134.121398)
		(end 140.57757 -134.568438)
		(width 0.14224)
		(layer "In4.Cu")
		(net "M_L_DQ<55>")
	)
	(segment
		(start 140.55217 -139.590272)
		(end 140.541248 -139.590272)
		(width 0.14224)
		(layer "In4.Cu")
		(net "M_L_DQ<55>")
	)
	(segment
		(start 140.721334 -134.712202)
		(end 140.721334 -136.035034)
		(width 0.14224)
		(layer "In4.Cu")
		(net "M_L_DQ<55>")
	)
	(segment
		(start 140.612368 -131.962398)
		(end 140.612368 -134.0866)
		(width 0.14224)
		(layer "In4.Cu")
		(net "M_L_DQ<55>")
	)
	(segment
		(start 139.51077 -142.059152)
		(end 139.51077 -141.785848)
		(width 0.14224)
		(layer "In9.Cu")
		(net "M_L_DQ<55>")
	)
	(segment
		(start 139.51077 -142.878048)
		(end 139.767818 -142.621)
		(width 0.14224)
		(layer "In9.Cu")
		(net "M_L_DQ<55>")
	)
	(segment
		(start 139.748768 -140.3604)
		(end 140.177012 -139.932156)
		(width 0.14224)
		(layer "In9.Cu")
		(net "M_L_DQ<55>")
	)
	(segment
		(start 139.793218 -140.834618)
		(end 139.748768 -140.790168)
		(width 0.14224)
		(layer "In9.Cu")
		(net "M_L_DQ<55>")
	)
	(segment
		(start 139.793218 -141.5034)
		(end 139.793218 -140.834618)
		(width 0.14224)
		(layer "In9.Cu")
		(net "M_L_DQ<55>")
	)
	(segment
		(start 139.799568 -143.763746)
		(end 139.799568 -143.44015)
		(width 0.14224)
		(layer "In9.Cu")
		(net "M_L_DQ<55>")
	)
	(segment
		(start 139.767818 -142.621)
		(end 139.767818 -142.3162)
		(width 0.14224)
		(layer "In9.Cu")
		(net "M_L_DQ<55>")
	)
	(segment
		(start 139.51077 -143.151352)
		(end 139.51077 -142.878048)
		(width 0.14224)
		(layer "In9.Cu")
		(net "M_L_DQ<55>")
	)
	(segment
		(start 139.799568 -143.44015)
		(end 139.51077 -143.151352)
		(width 0.14224)
		(layer "In9.Cu")
		(net "M_L_DQ<55>")
	)
	(segment
		(start 139.51077 -141.785848)
		(end 139.793218 -141.5034)
		(width 0.14224)
		(layer "In9.Cu")
		(net "M_L_DQ<55>")
	)
	(segment
		(start 139.748768 -140.790168)
		(end 139.748768 -140.3604)
		(width 0.14224)
		(layer "In9.Cu")
		(net "M_L_DQ<55>")
	)
	(segment
		(start 139.767818 -142.3162)
		(end 139.51077 -142.059152)
		(width 0.14224)
		(layer "In9.Cu")
		(net "M_L_DQ<55>")
	)
	(segment
		(start 139.34948 -143.941546)
		(end 139.621768 -143.941546)
		(width 0.14224)
		(layer "In9.Cu")
		(net "M_L_DQ<55>")
	)
	(segment
		(start 140.177012 -139.932156)
		(end 140.199364 -139.932156)
		(width 0.14224)
		(layer "In9.Cu")
		(net "M_L_DQ<55>")
	)
	(segment
		(start 139.621768 -143.941546)
		(end 139.799568 -143.763746)
		(width 0.14224)
		(layer "In9.Cu")
		(net "M_L_DQ<55>")
	)
	(segment
		(start 139.924028 -122.83694)
		(end 139.520168 -123.2408)
		(width 0.1651)
		(layer "F.Cu")
		(net "M_L_DQ<54>")
	)
	(segment
		(start 121.393712 -104.114854)
		(end 122.752612 -105.473754)
		(width 0.1016)
		(layer "F.Cu")
		(net "M_L_DQ<54>")
	)
	(segment
		(start 121.393712 -103.014272)
		(end 121.393712 -104.114854)
		(width 0.0889)
		(layer "F.Cu")
		(net "M_L_DQ<54>")
	)
	(segment
		(start 134.66826 -108.762292)
		(end 134.870952 -108.964984)
		(width 0.1016)
		(layer "F.Cu")
		(net "M_L_DQ<54>")
	)
	(segment
		(start 134.161276 -108.762292)
		(end 134.66826 -108.762292)
		(width 0.1016)
		(layer "F.Cu")
		(net "M_L_DQ<54>")
	)
	(segment
		(start 139.371578 -126.5936)
		(end 139.316968 -126.5936)
		(width 0.1651)
		(layer "F.Cu")
		(net "M_L_DQ<54>")
	)
	(segment
		(start 139.201906 -113.295938)
		(end 139.201906 -120.636538)
		(width 0.1651)
		(layer "F.Cu")
		(net "M_L_DQ<54>")
	)
	(segment
		(start 140.331698 -146.17192)
		(end 140.331698 -145.95348)
		(width 0.1651)
		(layer "F.Cu")
		(net "M_L_DQ<54>")
	)
	(segment
		(start 134.870952 -108.964984)
		(end 139.201906 -113.295938)
		(width 0.1651)
		(layer "F.Cu")
		(net "M_L_DQ<54>")
	)
	(segment
		(start 139.201906 -120.636538)
		(end 139.924028 -121.35866)
		(width 0.1651)
		(layer "F.Cu")
		(net "M_L_DQ<54>")
	)
	(segment
		(start 140.199364 -147.27174)
		(end 140.199618 -147.27174)
		(width 0.1651)
		(layer "F.Cu")
		(net "M_L_DQ<54>")
	)
	(segment
		(start 121.315988 -101.243638)
		(end 121.294652 -101.280722)
		(width 0.0889)
		(layer "F.Cu")
		(net "M_L_DQ<54>")
	)
	(segment
		(start 121.299478 -102.262686)
		(end 121.294652 -102.271322)
		(width 0.0889)
		(layer "F.Cu")
		(net "M_L_DQ<54>")
	)
	(segment
		(start 122.752612 -105.473754)
		(end 130.872738 -105.473754)
		(width 0.1016)
		(layer "F.Cu")
		(net "M_L_DQ<54>")
	)
	(segment
		(start 140.331698 -145.95348)
		(end 140.199618 -145.8214)
		(width 0.1651)
		(layer "F.Cu")
		(net "M_L_DQ<54>")
	)
	(segment
		(start 140.199618 -145.8214)
		(end 140.199618 -145.516854)
		(width 0.1651)
		(layer "F.Cu")
		(net "M_L_DQ<54>")
	)
	(segment
		(start 139.774168 -126.19101)
		(end 139.371578 -126.5936)
		(width 0.1651)
		(layer "F.Cu")
		(net "M_L_DQ<54>")
	)
	(segment
		(start 140.199618 -147.27174)
		(end 140.199618 -146.304)
		(width 0.1651)
		(layer "F.Cu")
		(net "M_L_DQ<54>")
	)
	(segment
		(start 130.872738 -105.473754)
		(end 134.161276 -108.762292)
		(width 0.1016)
		(layer "F.Cu")
		(net "M_L_DQ<54>")
	)
	(segment
		(start 139.520168 -123.2408)
		(end 139.520168 -125.4506)
		(width 0.1651)
		(layer "F.Cu")
		(net "M_L_DQ<54>")
	)
	(segment
		(start 140.199618 -146.304)
		(end 140.331698 -146.17192)
		(width 0.1651)
		(layer "F.Cu")
		(net "M_L_DQ<54>")
	)
	(segment
		(start 140.199618 -145.516854)
		(end 140.199364 -145.5166)
		(width 0.1651)
		(layer "F.Cu")
		(net "M_L_DQ<54>")
	)
	(segment
		(start 139.774168 -125.7046)
		(end 139.774168 -126.19101)
		(width 0.1651)
		(layer "F.Cu")
		(net "M_L_DQ<54>")
	)
	(segment
		(start 139.520168 -125.4506)
		(end 139.774168 -125.7046)
		(width 0.1651)
		(layer "F.Cu")
		(net "M_L_DQ<54>")
	)
	(segment
		(start 139.924028 -121.35866)
		(end 139.924028 -122.83694)
		(width 0.1651)
		(layer "F.Cu")
		(net "M_L_DQ<54>")
	)
	(segment
		(start 121.646188 -100.481638)
		(end 121.315988 -101.243638)
		(width 0.0889)
		(layer "F.Cu")
		(net "M_L_DQ<54>")
	)
	(segment
		(start 121.305828 -102.252018)
		(end 121.299478 -102.262686)
		(width 0.0889)
		(layer "F.Cu")
		(net "M_L_DQ<54>")
	)
	(via
		(at 139.34948 -141.213078)
		(size 0.508)
		(drill 0.254)
		(layers "F.Cu" "B.Cu")
		(net "M_L_DQ<54>")
	)
	(via
		(at 139.316968 -126.5936)
		(size 0.508)
		(drill 0.254)
		(layers "F.Cu" "B.Cu")
		(net "M_L_DQ<54>")
	)
	(via
		(at 140.199364 -145.5166)
		(size 0.508)
		(drill 0.254)
		(layers "F.Cu" "B.Cu")
		(net "M_L_DQ<54>")
	)
	(arc
		(start 121.299478 -101.672136)
		(mid 121.3787 -101.961254)
		(end 121.305828 -102.252018)
		(width 0.0889)
		(layer "F.Cu")
		(net "M_L_DQ<54>")
	)
	(arc
		(start 121.299478 -102.662736)
		(mid 121.369719 -102.832303)
		(end 121.393712 -103.014272)
		(width 0.0889)
		(layer "F.Cu")
		(net "M_L_DQ<54>")
	)
	(arc
		(start 121.294652 -101.280722)
		(mid 121.245897 -101.477074)
		(end 121.299478 -101.672136)
		(width 0.0889)
		(layer "F.Cu")
		(net "M_L_DQ<54>")
	)
	(arc
		(start 121.294652 -102.271322)
		(mid 121.245897 -102.467674)
		(end 121.299478 -102.662736)
		(width 0.0889)
		(layer "F.Cu")
		(net "M_L_DQ<54>")
	)
	(segment
		(start 139.34948 -142.477236)
		(end 139.34948 -141.213078)
		(width 0.1651)
		(layer "B.Cu")
		(net "M_L_DQ<54>")
	)
	(segment
		(start 139.91717 -139.333478)
		(end 139.18057 -140.070078)
		(width 0.14224)
		(layer "In4.Cu")
		(net "M_L_DQ<54>")
	)
	(segment
		(start 139.91717 -138.979402)
		(end 139.91717 -139.333478)
		(width 0.14224)
		(layer "In4.Cu")
		(net "M_L_DQ<54>")
	)
	(segment
		(start 139.86637 -134.517638)
		(end 139.593828 -134.79018)
		(width 0.14224)
		(layer "In4.Cu")
		(net "M_L_DQ<54>")
	)
	(segment
		(start 139.18057 -140.070078)
		(end 139.18057 -141.044168)
		(width 0.14224)
		(layer "In4.Cu")
		(net "M_L_DQ<54>")
	)
	(segment
		(start 139.71397 -131.307078)
		(end 139.86637 -131.459478)
		(width 0.14224)
		(layer "In4.Cu")
		(net "M_L_DQ<54>")
	)
	(segment
		(start 139.86637 -131.953)
		(end 139.774168 -132.045202)
		(width 0.14224)
		(layer "In4.Cu")
		(net "M_L_DQ<54>")
	)
	(segment
		(start 139.774168 -138.8364)
		(end 139.91717 -138.979402)
		(width 0.14224)
		(layer "In4.Cu")
		(net "M_L_DQ<54>")
	)
	(segment
		(start 139.774168 -132.045202)
		(end 139.774168 -134.0358)
		(width 0.14224)
		(layer "In4.Cu")
		(net "M_L_DQ<54>")
	)
	(segment
		(start 139.774168 -134.0358)
		(end 139.86637 -134.128002)
		(width 0.14224)
		(layer "In4.Cu")
		(net "M_L_DQ<54>")
	)
	(segment
		(start 139.850368 -136.189466)
		(end 139.850368 -136.642602)
		(width 0.14224)
		(layer "In4.Cu")
		(net "M_L_DQ<54>")
	)
	(segment
		(start 139.593828 -134.79018)
		(end 139.593828 -135.932926)
		(width 0.14224)
		(layer "In4.Cu")
		(net "M_L_DQ<54>")
	)
	(segment
		(start 139.91717 -129.859278)
		(end 139.71397 -130.062478)
		(width 0.14224)
		(layer "In4.Cu")
		(net "M_L_DQ<54>")
	)
	(segment
		(start 139.86637 -131.459478)
		(end 139.86637 -131.953)
		(width 0.14224)
		(layer "In4.Cu")
		(net "M_L_DQ<54>")
	)
	(segment
		(start 139.86637 -134.128002)
		(end 139.86637 -134.517638)
		(width 0.14224)
		(layer "In4.Cu")
		(net "M_L_DQ<54>")
	)
	(segment
		(start 139.316968 -126.5936)
		(end 139.34948 -126.626112)
		(width 0.14224)
		(layer "In4.Cu")
		(net "M_L_DQ<54>")
	)
	(segment
		(start 139.71397 -130.062478)
		(end 139.71397 -131.307078)
		(width 0.14224)
		(layer "In4.Cu")
		(net "M_L_DQ<54>")
	)
	(segment
		(start 139.850368 -136.642602)
		(end 139.774168 -136.718802)
		(width 0.14224)
		(layer "In4.Cu")
		(net "M_L_DQ<54>")
	)
	(segment
		(start 139.34948 -127.661924)
		(end 139.91717 -128.229614)
		(width 0.14224)
		(layer "In4.Cu")
		(net "M_L_DQ<54>")
	)
	(segment
		(start 139.593828 -135.932926)
		(end 139.850368 -136.189466)
		(width 0.14224)
		(layer "In4.Cu")
		(net "M_L_DQ<54>")
	)
	(segment
		(start 139.774168 -136.718802)
		(end 139.774168 -138.8364)
		(width 0.14224)
		(layer "In4.Cu")
		(net "M_L_DQ<54>")
	)
	(segment
		(start 139.91717 -128.229614)
		(end 139.91717 -129.859278)
		(width 0.14224)
		(layer "In4.Cu")
		(net "M_L_DQ<54>")
	)
	(segment
		(start 139.18057 -141.044168)
		(end 139.34948 -141.213078)
		(width 0.14224)
		(layer "In4.Cu")
		(net "M_L_DQ<54>")
	)
	(segment
		(start 139.34948 -126.626112)
		(end 139.34948 -127.661924)
		(width 0.14224)
		(layer "In4.Cu")
		(net "M_L_DQ<54>")
	)
	(segment
		(start 139.34948 -141.213078)
		(end 138.91641 -141.646148)
		(width 0.14224)
		(layer "In9.Cu")
		(net "M_L_DQ<54>")
	)
	(segment
		(start 138.91641 -144.233646)
		(end 140.199364 -145.5166)
		(width 0.14224)
		(layer "In9.Cu")
		(net "M_L_DQ<54>")
	)
	(segment
		(start 138.91641 -141.646148)
		(end 138.91641 -144.233646)
		(width 0.14224)
		(layer "In9.Cu")
		(net "M_L_DQ<54>")
	)
	(segment
		(start 118.654068 -105.6259)
		(end 118.844568 -105.8164)
		(width 0.0889)
		(layer "F.Cu")
		(net "M_L_DQ<53>")
	)
	(segment
		(start 130.325368 -113.8174)
		(end 130.706368 -114.1984)
		(width 0.1651)
		(layer "F.Cu")
		(net "M_L_DQ<53>")
	)
	(segment
		(start 133.373368 -118.4148)
		(end 134.530846 -119.572278)
		(width 0.1651)
		(layer "F.Cu")
		(net "M_L_DQ<53>")
	)
	(segment
		(start 118.383812 -103.764334)
		(end 118.654068 -104.03459)
		(width 0.0889)
		(layer "F.Cu")
		(net "M_L_DQ<53>")
	)
	(segment
		(start 134.530846 -119.572278)
		(end 134.530846 -123.890278)
		(width 0.1651)
		(layer "F.Cu")
		(net "M_L_DQ<53>")
	)
	(segment
		(start 134.649464 -124.008896)
		(end 134.649464 -124.871226)
		(width 0.1651)
		(layer "F.Cu")
		(net "M_L_DQ<53>")
	)
	(segment
		(start 133.39953 -142.6718)
		(end 133.39953 -143.941546)
		(width 0.1651)
		(layer "F.Cu")
		(net "M_L_DQ<53>")
	)
	(segment
		(start 130.98526 -114.1984)
		(end 131.671568 -113.512092)
		(width 0.1651)
		(layer "F.Cu")
		(net "M_L_DQ<53>")
	)
	(segment
		(start 131.461256 -114.674396)
		(end 131.461256 -114.953288)
		(width 0.1651)
		(layer "F.Cu")
		(net "M_L_DQ<53>")
	)
	(segment
		(start 118.383812 -103.34498)
		(end 118.383812 -103.764334)
		(width 0.0889)
		(layer "F.Cu")
		(net "M_L_DQ<53>")
	)
	(segment
		(start 118.724172 -101.76764)
		(end 118.719346 -101.776276)
		(width 0.0889)
		(layer "F.Cu")
		(net "M_L_DQ<53>")
	)
	(segment
		(start 131.671568 -113.512092)
		(end 131.95046 -113.512092)
		(width 0.1651)
		(layer "F.Cu")
		(net "M_L_DQ<53>")
	)
	(segment
		(start 134.649464 -124.871226)
		(end 134.160514 -125.360176)
		(width 0.1651)
		(layer "F.Cu")
		(net "M_L_DQ<53>")
	)
	(segment
		(start 129.728976 -108.229654)
		(end 131.620768 -110.121446)
		(width 0.1016)
		(layer "F.Cu")
		(net "M_L_DQ<53>")
	)
	(segment
		(start 130.325368 -113.2078)
		(end 130.325368 -113.8174)
		(width 0.1651)
		(layer "F.Cu")
		(net "M_L_DQ<53>")
	)
	(segment
		(start 131.620768 -111.1631)
		(end 131.620768 -111.9124)
		(width 0.1651)
		(layer "F.Cu")
		(net "M_L_DQ<53>")
	)
	(segment
		(start 118.844568 -105.8164)
		(end 119.00027 -105.8164)
		(width 0.0889)
		(layer "F.Cu")
		(net "M_L_DQ<53>")
	)
	(segment
		(start 131.461256 -114.953288)
		(end 133.373368 -116.8654)
		(width 0.1651)
		(layer "F.Cu")
		(net "M_L_DQ<53>")
	)
	(segment
		(start 132.147564 -113.988088)
		(end 131.461256 -114.674396)
		(width 0.1651)
		(layer "F.Cu")
		(net "M_L_DQ<53>")
	)
	(segment
		(start 118.654068 -104.03459)
		(end 118.654068 -105.6259)
		(width 0.0889)
		(layer "F.Cu")
		(net "M_L_DQ<53>")
	)
	(segment
		(start 118.722648 -102.765098)
		(end 118.383812 -103.34498)
		(width 0.0889)
		(layer "F.Cu")
		(net "M_L_DQ<53>")
	)
	(segment
		(start 131.620768 -110.121446)
		(end 131.620768 -111.1631)
		(width 0.1016)
		(layer "F.Cu")
		(net "M_L_DQ<53>")
	)
	(segment
		(start 121.413524 -108.229654)
		(end 129.728976 -108.229654)
		(width 0.1016)
		(layer "F.Cu")
		(net "M_L_DQ<53>")
	)
	(segment
		(start 131.620768 -111.9124)
		(end 130.325368 -113.2078)
		(width 0.1651)
		(layer "F.Cu")
		(net "M_L_DQ<53>")
	)
	(segment
		(start 133.373368 -116.8654)
		(end 133.373368 -118.4148)
		(width 0.1651)
		(layer "F.Cu")
		(net "M_L_DQ<53>")
	)
	(segment
		(start 134.530846 -123.890278)
		(end 134.649464 -124.008896)
		(width 0.1651)
		(layer "F.Cu")
		(net "M_L_DQ<53>")
	)
	(segment
		(start 119.00027 -105.8164)
		(end 121.413524 -108.229654)
		(width 0.1016)
		(layer "F.Cu")
		(net "M_L_DQ<53>")
	)
	(segment
		(start 130.706368 -114.1984)
		(end 130.98526 -114.1984)
		(width 0.1651)
		(layer "F.Cu")
		(net "M_L_DQ<53>")
	)
	(segment
		(start 131.95046 -113.512092)
		(end 132.147564 -113.709196)
		(width 0.1651)
		(layer "F.Cu")
		(net "M_L_DQ<53>")
	)
	(segment
		(start 132.147564 -113.709196)
		(end 132.147564 -113.988088)
		(width 0.1651)
		(layer "F.Cu")
		(net "M_L_DQ<53>")
	)
	(via
		(at 134.173214 -139.932156)
		(size 0.508)
		(drill 0.254)
		(layers "F.Cu" "B.Cu")
		(net "M_L_DQ<53>")
	)
	(via
		(at 134.160514 -125.360176)
		(size 0.508)
		(drill 0.254)
		(layers "F.Cu" "B.Cu")
		(net "M_L_DQ<53>")
	)
	(via
		(at 133.39953 -143.941546)
		(size 0.508)
		(drill 0.254)
		(layers "F.Cu" "B.Cu")
		(net "M_L_DQ<53>")
	)
	(arc
		(start 118.719346 -101.776276)
		(mid 118.670591 -101.972628)
		(end 118.724172 -102.16769)
		(width 0.0889)
		(layer "F.Cu")
		(net "M_L_DQ<53>")
	)
	(arc
		(start 119.070882 -100.976684)
		(mid 118.916625 -101.380534)
		(end 118.724172 -101.76764)
		(width 0.0889)
		(layer "F.Cu")
		(net "M_L_DQ<53>")
	)
	(arc
		(start 118.724172 -102.16769)
		(mid 118.803909 -102.466605)
		(end 118.722648 -102.765098)
		(width 0.0889)
		(layer "F.Cu")
		(net "M_L_DQ<53>")
	)
	(segment
		(start 134.249414 -137.877296)
		(end 134.249414 -139.855956)
		(width 0.1651)
		(layer "B.Cu")
		(net "M_L_DQ<53>")
	)
	(segment
		(start 134.249414 -139.855956)
		(end 134.173214 -139.932156)
		(width 0.1651)
		(layer "B.Cu")
		(net "M_L_DQ<53>")
	)
	(segment
		(start 134.668768 -131.962398)
		(end 134.668768 -134.0104)
		(width 0.14224)
		(layer "In4.Cu")
		(net "M_L_DQ<53>")
	)
	(segment
		(start 134.71017 -134.797038)
		(end 134.71017 -135.853424)
		(width 0.14224)
		(layer "In4.Cu")
		(net "M_L_DQ<53>")
	)
	(segment
		(start 134.668768 -134.0104)
		(end 134.58317 -134.095998)
		(width 0.14224)
		(layer "In4.Cu")
		(net "M_L_DQ<53>")
	)
	(segment
		(start 134.58317 -134.095998)
		(end 134.58317 -134.670038)
		(width 0.14224)
		(layer "In4.Cu")
		(net "M_L_DQ<53>")
	)
	(segment
		(start 134.55777 -139.5476)
		(end 134.173214 -139.932156)
		(width 0.14224)
		(layer "In4.Cu")
		(net "M_L_DQ<53>")
	)
	(segment
		(start 134.55777 -138.896598)
		(end 134.55777 -139.5476)
		(width 0.14224)
		(layer "In4.Cu")
		(net "M_L_DQ<53>")
	)
	(segment
		(start 134.58317 -131.434078)
		(end 134.58317 -131.8768)
		(width 0.14224)
		(layer "In4.Cu")
		(net "M_L_DQ<53>")
	)
	(segment
		(start 134.58317 -134.670038)
		(end 134.71017 -134.797038)
		(width 0.14224)
		(layer "In4.Cu")
		(net "M_L_DQ<53>")
	)
	(segment
		(start 134.64667 -129.994914)
		(end 134.64667 -131.370578)
		(width 0.14224)
		(layer "In4.Cu")
		(net "M_L_DQ<53>")
	)
	(segment
		(start 134.668768 -138.7856)
		(end 134.55777 -138.896598)
		(width 0.14224)
		(layer "In4.Cu")
		(net "M_L_DQ<53>")
	)
	(segment
		(start 134.55777 -136.005824)
		(end 134.55777 -136.525)
		(width 0.14224)
		(layer "In4.Cu")
		(net "M_L_DQ<53>")
	)
	(segment
		(start 134.64667 -131.370578)
		(end 134.58317 -131.434078)
		(width 0.14224)
		(layer "In4.Cu")
		(net "M_L_DQ<53>")
	)
	(segment
		(start 134.668768 -136.635998)
		(end 134.668768 -138.7856)
		(width 0.14224)
		(layer "In4.Cu")
		(net "M_L_DQ<53>")
	)
	(segment
		(start 134.71017 -135.853424)
		(end 134.55777 -136.005824)
		(width 0.14224)
		(layer "In4.Cu")
		(net "M_L_DQ<53>")
	)
	(segment
		(start 134.55777 -136.525)
		(end 134.668768 -136.635998)
		(width 0.14224)
		(layer "In4.Cu")
		(net "M_L_DQ<53>")
	)
	(segment
		(start 134.160514 -125.360176)
		(end 134.160514 -128.136904)
		(width 0.14224)
		(layer "In4.Cu")
		(net "M_L_DQ<53>")
	)
	(segment
		(start 134.58317 -131.8768)
		(end 134.668768 -131.962398)
		(width 0.14224)
		(layer "In4.Cu")
		(net "M_L_DQ<53>")
	)
	(segment
		(start 134.55777 -128.53416)
		(end 134.55777 -129.906014)
		(width 0.14224)
		(layer "In4.Cu")
		(net "M_L_DQ<53>")
	)
	(segment
		(start 134.160514 -128.136904)
		(end 134.55777 -128.53416)
		(width 0.14224)
		(layer "In4.Cu")
		(net "M_L_DQ<53>")
	)
	(segment
		(start 134.55777 -129.906014)
		(end 134.64667 -129.994914)
		(width 0.14224)
		(layer "In4.Cu")
		(net "M_L_DQ<53>")
	)
	(segment
		(start 133.56082 -141.817344)
		(end 133.849618 -141.528546)
		(width 0.14224)
		(layer "In9.Cu")
		(net "M_L_DQ<53>")
	)
	(segment
		(start 133.722618 -140.9192)
		(end 133.722618 -140.3604)
		(width 0.14224)
		(layer "In9.Cu")
		(net "M_L_DQ<53>")
	)
	(segment
		(start 133.824218 -143.561054)
		(end 133.56082 -143.297656)
		(width 0.14224)
		(layer "In9.Cu")
		(net "M_L_DQ<53>")
	)
	(segment
		(start 133.849618 -141.0462)
		(end 133.722618 -140.9192)
		(width 0.14224)
		(layer "In9.Cu")
		(net "M_L_DQ<53>")
	)
	(segment
		(start 133.722618 -140.3604)
		(end 134.150862 -139.932156)
		(width 0.14224)
		(layer "In9.Cu")
		(net "M_L_DQ<53>")
	)
	(segment
		(start 133.849618 -141.528546)
		(end 133.849618 -141.0462)
		(width 0.14224)
		(layer "In9.Cu")
		(net "M_L_DQ<53>")
	)
	(segment
		(start 133.798818 -142.747746)
		(end 133.798818 -142.392654)
		(width 0.14224)
		(layer "In9.Cu")
		(net "M_L_DQ<53>")
	)
	(segment
		(start 133.39953 -143.941546)
		(end 133.671818 -143.941546)
		(width 0.14224)
		(layer "In9.Cu")
		(net "M_L_DQ<53>")
	)
	(segment
		(start 133.56082 -143.297656)
		(end 133.56082 -142.985744)
		(width 0.14224)
		(layer "In9.Cu")
		(net "M_L_DQ<53>")
	)
	(segment
		(start 133.671818 -143.941546)
		(end 133.824218 -143.789146)
		(width 0.14224)
		(layer "In9.Cu")
		(net "M_L_DQ<53>")
	)
	(segment
		(start 134.150862 -139.932156)
		(end 134.173214 -139.932156)
		(width 0.14224)
		(layer "In9.Cu")
		(net "M_L_DQ<53>")
	)
	(segment
		(start 133.56082 -142.154656)
		(end 133.56082 -141.817344)
		(width 0.14224)
		(layer "In9.Cu")
		(net "M_L_DQ<53>")
	)
	(segment
		(start 133.824218 -143.789146)
		(end 133.824218 -143.561054)
		(width 0.14224)
		(layer "In9.Cu")
		(net "M_L_DQ<53>")
	)
	(segment
		(start 133.56082 -142.985744)
		(end 133.798818 -142.747746)
		(width 0.14224)
		(layer "In9.Cu")
		(net "M_L_DQ<53>")
	)
	(segment
		(start 133.798818 -142.392654)
		(end 133.56082 -142.154656)
		(width 0.14224)
		(layer "In9.Cu")
		(net "M_L_DQ<53>")
	)
	(segment
		(start 132.687568 -117.094)
		(end 132.687568 -118.744746)
		(width 0.1651)
		(layer "F.Cu")
		(net "M_L_DQ<52>")
	)
	(segment
		(start 130.960368 -111.3028)
		(end 130.960368 -111.6076)
		(width 0.1651)
		(layer "F.Cu")
		(net "M_L_DQ<52>")
	)
	(segment
		(start 129.512568 -113.919)
		(end 132.687568 -117.094)
		(width 0.1651)
		(layer "F.Cu")
		(net "M_L_DQ<52>")
	)
	(segment
		(start 118.666768 -106.03992)
		(end 121.250202 -108.623354)
		(width 0.1016)
		(layer "F.Cu")
		(net "M_L_DQ<52>")
	)
	(segment
		(start 121.250202 -108.623354)
		(end 129.565654 -108.623354)
		(width 0.1016)
		(layer "F.Cu")
		(net "M_L_DQ<52>")
	)
	(segment
		(start 133.703568 -126.13386)
		(end 133.24713 -126.590298)
		(width 0.1651)
		(layer "F.Cu")
		(net "M_L_DQ<52>")
	)
	(segment
		(start 118.463568 -104.139746)
		(end 118.463568 -105.7148)
		(width 0.0889)
		(layer "F.Cu")
		(net "M_L_DQ<52>")
	)
	(segment
		(start 118.463568 -105.7148)
		(end 118.666768 -105.918)
		(width 0.0889)
		(layer "F.Cu")
		(net "M_L_DQ<52>")
	)
	(segment
		(start 118.184168 -103.308912)
		(end 118.184168 -103.860346)
		(width 0.0889)
		(layer "F.Cu")
		(net "M_L_DQ<52>")
	)
	(segment
		(start 134.249414 -145.946368)
		(end 134.15137 -145.415)
		(width 0.1651)
		(layer "F.Cu")
		(net "M_L_DQ<52>")
	)
	(segment
		(start 118.184168 -103.860346)
		(end 118.463568 -104.139746)
		(width 0.0889)
		(layer "F.Cu")
		(net "M_L_DQ<52>")
	)
	(segment
		(start 132.687568 -118.744746)
		(end 133.805168 -119.862346)
		(width 0.1651)
		(layer "F.Cu")
		(net "M_L_DQ<52>")
	)
	(segment
		(start 134.249414 -147.27174)
		(end 134.249414 -145.946368)
		(width 0.1651)
		(layer "F.Cu")
		(net "M_L_DQ<52>")
	)
	(segment
		(start 118.558056 -102.667816)
		(end 118.184168 -103.308912)
		(width 0.0889)
		(layer "F.Cu")
		(net "M_L_DQ<52>")
	)
	(segment
		(start 133.805168 -124.333)
		(end 133.703568 -124.4346)
		(width 0.1651)
		(layer "F.Cu")
		(net "M_L_DQ<52>")
	)
	(segment
		(start 129.512568 -113.0554)
		(end 129.512568 -113.919)
		(width 0.1651)
		(layer "F.Cu")
		(net "M_L_DQ<52>")
	)
	(segment
		(start 129.565654 -108.623354)
		(end 130.960368 -110.018068)
		(width 0.1016)
		(layer "F.Cu")
		(net "M_L_DQ<52>")
	)
	(segment
		(start 118.666768 -105.918)
		(end 118.666768 -106.03992)
		(width 0.0889)
		(layer "F.Cu")
		(net "M_L_DQ<52>")
	)
	(segment
		(start 133.805168 -119.862346)
		(end 133.805168 -124.333)
		(width 0.1651)
		(layer "F.Cu")
		(net "M_L_DQ<52>")
	)
	(segment
		(start 130.960368 -111.6076)
		(end 129.512568 -113.0554)
		(width 0.1651)
		(layer "F.Cu")
		(net "M_L_DQ<52>")
	)
	(segment
		(start 133.703568 -124.4346)
		(end 133.703568 -126.13386)
		(width 0.1651)
		(layer "F.Cu")
		(net "M_L_DQ<52>")
	)
	(segment
		(start 130.960368 -110.018068)
		(end 130.960368 -111.3028)
		(width 0.1016)
		(layer "F.Cu")
		(net "M_L_DQ<52>")
	)
	(via
		(at 133.39953 -141.213078)
		(size 0.508)
		(drill 0.254)
		(layers "F.Cu" "B.Cu")
		(net "M_L_DQ<52>")
	)
	(via
		(at 133.24713 -126.590298)
		(size 0.508)
		(drill 0.254)
		(layers "F.Cu" "B.Cu")
		(net "M_L_DQ<52>")
	)
	(via
		(at 134.15137 -145.415)
		(size 0.508)
		(drill 0.254)
		(layers "F.Cu" "B.Cu")
		(net "M_L_DQ<52>")
	)
	(arc
		(start 119.059706 -100.576634)
		(mid 118.865856 -100.632984)
		(end 118.724172 -100.776786)
		(width 0.0889)
		(layer "F.Cu")
		(net "M_L_DQ<52>")
	)
	(arc
		(start 118.671594 -101.002084)
		(mid 118.654038 -101.343612)
		(end 118.559072 -101.672136)
		(width 0.0889)
		(layer "F.Cu")
		(net "M_L_DQ<52>")
	)
	(arc
		(start 119.929402 -100.481638)
		(mid 119.496475 -100.546721)
		(end 119.059706 -100.576634)
		(width 0.0889)
		(layer "F.Cu")
		(net "M_L_DQ<52>")
	)
	(arc
		(start 118.724172 -100.776786)
		(mid 118.703222 -100.818625)
		(end 118.687342 -100.862638)
		(width 0.0889)
		(layer "F.Cu")
		(net "M_L_DQ<52>")
	)
	(arc
		(start 118.559072 -101.672136)
		(mid 118.479941 -101.967538)
		(end 118.559072 -102.26294)
		(width 0.0889)
		(layer "F.Cu")
		(net "M_L_DQ<52>")
	)
	(arc
		(start 118.687342 -100.862638)
		(mid 118.673286 -100.931665)
		(end 118.671594 -101.002084)
		(width 0.0889)
		(layer "F.Cu")
		(net "M_L_DQ<52>")
	)
	(arc
		(start 118.559072 -102.26294)
		(mid 118.61305 -102.46553)
		(end 118.558056 -102.667816)
		(width 0.0889)
		(layer "F.Cu")
		(net "M_L_DQ<52>")
	)
	(segment
		(start 133.39953 -142.477236)
		(end 133.39953 -141.213078)
		(width 0.1651)
		(layer "B.Cu")
		(net "M_L_DQ<52>")
	)
	(segment
		(start 133.88467 -139.042902)
		(end 133.88467 -139.358878)
		(width 0.14224)
		(layer "In4.Cu")
		(net "M_L_DQ<52>")
	)
	(segment
		(start 133.631178 -134.74319)
		(end 133.631178 -135.926576)
		(width 0.14224)
		(layer "In4.Cu")
		(net "M_L_DQ<52>")
	)
	(segment
		(start 133.24713 -126.590298)
		(end 133.347968 -126.691136)
		(width 0.14224)
		(layer "In4.Cu")
		(net "M_L_DQ<52>")
	)
	(segment
		(start 133.66877 -129.986278)
		(end 133.66877 -131.192778)
		(width 0.14224)
		(layer "In4.Cu")
		(net "M_L_DQ<52>")
	)
	(segment
		(start 133.830568 -132.019802)
		(end 133.830568 -134.0612)
		(width 0.14224)
		(layer "In4.Cu")
		(net "M_L_DQ<52>")
	)
	(segment
		(start 133.88467 -139.358878)
		(end 133.373368 -139.87018)
		(width 0.1016)
		(layer "In4.Cu")
		(net "M_L_DQ<52>")
	)
	(segment
		(start 133.89737 -134.128002)
		(end 133.89737 -134.476998)
		(width 0.14224)
		(layer "In4.Cu")
		(net "M_L_DQ<52>")
	)
	(segment
		(start 133.347968 -126.691136)
		(end 133.347968 -128.518412)
		(width 0.14224)
		(layer "In4.Cu")
		(net "M_L_DQ<52>")
	)
	(segment
		(start 133.88467 -136.6012)
		(end 133.830568 -136.655302)
		(width 0.14224)
		(layer "In4.Cu")
		(net "M_L_DQ<52>")
	)
	(segment
		(start 133.89737 -131.953)
		(end 133.830568 -132.019802)
		(width 0.14224)
		(layer "In4.Cu")
		(net "M_L_DQ<52>")
	)
	(segment
		(start 133.88467 -136.180068)
		(end 133.88467 -136.6012)
		(width 0.14224)
		(layer "In4.Cu")
		(net "M_L_DQ<52>")
	)
	(segment
		(start 133.66877 -131.192778)
		(end 133.89737 -131.421378)
		(width 0.14224)
		(layer "In4.Cu")
		(net "M_L_DQ<52>")
	)
	(segment
		(start 133.89737 -131.421378)
		(end 133.89737 -131.953)
		(width 0.14224)
		(layer "In4.Cu")
		(net "M_L_DQ<52>")
	)
	(segment
		(start 133.830568 -138.9888)
		(end 133.88467 -139.042902)
		(width 0.14224)
		(layer "In4.Cu")
		(net "M_L_DQ<52>")
	)
	(segment
		(start 133.830568 -136.655302)
		(end 133.830568 -138.9888)
		(width 0.14224)
		(layer "In4.Cu")
		(net "M_L_DQ<52>")
	)
	(segment
		(start 133.830568 -134.0612)
		(end 133.89737 -134.128002)
		(width 0.14224)
		(layer "In4.Cu")
		(net "M_L_DQ<52>")
	)
	(segment
		(start 133.347968 -128.518412)
		(end 133.92277 -129.093214)
		(width 0.14224)
		(layer "In4.Cu")
		(net "M_L_DQ<52>")
	)
	(segment
		(start 133.373368 -141.186916)
		(end 133.39953 -141.213078)
		(width 0.1016)
		(layer "In4.Cu")
		(net "M_L_DQ<52>")
	)
	(segment
		(start 133.373368 -139.87018)
		(end 133.373368 -141.186916)
		(width 0.1016)
		(layer "In4.Cu")
		(net "M_L_DQ<52>")
	)
	(segment
		(start 133.92277 -129.732278)
		(end 133.66877 -129.986278)
		(width 0.14224)
		(layer "In4.Cu")
		(net "M_L_DQ<52>")
	)
	(segment
		(start 133.89737 -134.476998)
		(end 133.631178 -134.74319)
		(width 0.14224)
		(layer "In4.Cu")
		(net "M_L_DQ<52>")
	)
	(segment
		(start 133.631178 -135.926576)
		(end 133.88467 -136.180068)
		(width 0.14224)
		(layer "In4.Cu")
		(net "M_L_DQ<52>")
	)
	(segment
		(start 133.92277 -129.093214)
		(end 133.92277 -129.732278)
		(width 0.14224)
		(layer "In4.Cu")
		(net "M_L_DQ<52>")
	)
	(segment
		(start 132.96646 -144.17929)
		(end 133.124448 -144.337278)
		(width 0.14224)
		(layer "In9.Cu")
		(net "M_L_DQ<52>")
	)
	(segment
		(start 133.124448 -144.63903)
		(end 133.900418 -145.415)
		(width 0.14224)
		(layer "In9.Cu")
		(net "M_L_DQ<52>")
	)
	(segment
		(start 132.96646 -141.646148)
		(end 132.96646 -144.17929)
		(width 0.14224)
		(layer "In9.Cu")
		(net "M_L_DQ<52>")
	)
	(segment
		(start 133.124448 -144.337278)
		(end 133.124448 -144.63903)
		(width 0.14224)
		(layer "In9.Cu")
		(net "M_L_DQ<52>")
	)
	(segment
		(start 133.900418 -145.415)
		(end 134.15137 -145.415)
		(width 0.14224)
		(layer "In9.Cu")
		(net "M_L_DQ<52>")
	)
	(segment
		(start 133.39953 -141.213078)
		(end 132.96646 -141.646148)
		(width 0.14224)
		(layer "In9.Cu")
		(net "M_L_DQ<52>")
	)
	(segment
		(start 134.58825 -107.5182)
		(end 136.599168 -107.5182)
		(width 0.1016)
		(layer "F.Cu")
		(net "M_L_DQ<51>")
	)
	(segment
		(start 141.049502 -142.6718)
		(end 141.049502 -143.941546)
		(width 0.1651)
		(layer "F.Cu")
		(net "M_L_DQ<51>")
	)
	(segment
		(start 137.513568 -107.6706)
		(end 141.22654 -111.383572)
		(width 0.1651)
		(layer "F.Cu")
		(net "M_L_DQ<51>")
	)
	(segment
		(start 122.153172 -102.1588)
		(end 122.157998 -102.167436)
		(width 0.0889)
		(layer "F.Cu")
		(net "M_L_DQ<51>")
	)
	(segment
		(start 122.157998 -102.167436)
		(end 122.164348 -102.178104)
		(width 0.0889)
		(layer "F.Cu")
		(net "M_L_DQ<51>")
	)
	(segment
		(start 122.109992 -102.829614)
		(end 122.109992 -103.159814)
		(width 0.0889)
		(layer "F.Cu")
		(net "M_L_DQ<51>")
	)
	(segment
		(start 131.362704 -104.292654)
		(end 134.58825 -107.5182)
		(width 0.1016)
		(layer "F.Cu")
		(net "M_L_DQ<51>")
	)
	(segment
		(start 142.452598 -119.793258)
		(end 142.452598 -124.223272)
		(width 0.1651)
		(layer "F.Cu")
		(net "M_L_DQ<51>")
	)
	(segment
		(start 122.504708 -101.967538)
		(end 122.504708 -101.635814)
		(width 0.0889)
		(layer "F.Cu")
		(net "M_L_DQ<51>")
	)
	(segment
		(start 122.504708 -101.635814)
		(end 122.441208 -101.572314)
		(width 0.0889)
		(layer "F.Cu")
		(net "M_L_DQ<51>")
	)
	(segment
		(start 142.412466 -126.020576)
		(end 141.899386 -126.020576)
		(width 0.1651)
		(layer "F.Cu")
		(net "M_L_DQ<51>")
	)
	(segment
		(start 136.599168 -107.5182)
		(end 136.751568 -107.6706)
		(width 0.1016)
		(layer "F.Cu")
		(net "M_L_DQ<51>")
	)
	(segment
		(start 122.157998 -102.781608)
		(end 122.109992 -102.829614)
		(width 0.0889)
		(layer "F.Cu")
		(net "M_L_DQ<51>")
	)
	(segment
		(start 141.22654 -111.383572)
		(end 141.22654 -118.5672)
		(width 0.1651)
		(layer "F.Cu")
		(net "M_L_DQ<51>")
	)
	(segment
		(start 142.886684 -124.657358)
		(end 142.886684 -125.546358)
		(width 0.1651)
		(layer "F.Cu")
		(net "M_L_DQ<51>")
	)
	(segment
		(start 142.886684 -125.546358)
		(end 142.412466 -126.020576)
		(width 0.1651)
		(layer "F.Cu")
		(net "M_L_DQ<51>")
	)
	(segment
		(start 122.109992 -103.159814)
		(end 123.242832 -104.292654)
		(width 0.1016)
		(layer "F.Cu")
		(net "M_L_DQ<51>")
	)
	(segment
		(start 142.452598 -124.223272)
		(end 142.886684 -124.657358)
		(width 0.1651)
		(layer "F.Cu")
		(net "M_L_DQ<51>")
	)
	(segment
		(start 136.751568 -107.6706)
		(end 137.513568 -107.6706)
		(width 0.1651)
		(layer "F.Cu")
		(net "M_L_DQ<51>")
	)
	(segment
		(start 141.22654 -118.5672)
		(end 142.452598 -119.793258)
		(width 0.1651)
		(layer "F.Cu")
		(net "M_L_DQ<51>")
	)
	(segment
		(start 122.157998 -102.757986)
		(end 122.157998 -102.781608)
		(width 0.0889)
		(layer "F.Cu")
		(net "M_L_DQ<51>")
	)
	(segment
		(start 123.242832 -104.292654)
		(end 131.362704 -104.292654)
		(width 0.1016)
		(layer "F.Cu")
		(net "M_L_DQ<51>")
	)
	(via
		(at 141.899386 -126.020576)
		(size 0.508)
		(drill 0.254)
		(layers "F.Cu" "B.Cu")
		(net "M_L_DQ<51>")
	)
	(via
		(at 141.049502 -143.941546)
		(size 0.508)
		(drill 0.254)
		(layers "F.Cu" "B.Cu")
		(net "M_L_DQ<51>")
	)
	(via
		(at 141.899386 -139.932156)
		(size 0.508)
		(drill 0.254)
		(layers "F.Cu" "B.Cu")
		(net "M_L_DQ<51>")
	)
	(arc
		(start 122.441208 -101.572314)
		(mid 122.145423 -101.791048)
		(end 122.153172 -102.1588)
		(width 0.0889)
		(layer "F.Cu")
		(net "M_L_DQ<51>")
	)
	(arc
		(start 122.164348 -102.178104)
		(mid 122.237146 -102.468867)
		(end 122.157998 -102.757986)
		(width 0.0889)
		(layer "F.Cu")
		(net "M_L_DQ<51>")
	)
	(segment
		(start 141.899386 -137.877296)
		(end 141.899386 -139.932156)
		(width 0.1651)
		(layer "B.Cu")
		(net "M_L_DQ<51>")
	)
	(segment
		(start 142.25397 -129.960878)
		(end 142.40637 -130.113278)
		(width 0.14224)
		(layer "In4.Cu")
		(net "M_L_DQ<51>")
	)
	(segment
		(start 142.314168 -138.6586)
		(end 142.22857 -138.744198)
		(width 0.14224)
		(layer "In4.Cu")
		(net "M_L_DQ<51>")
	)
	(segment
		(start 142.339568 -134.0104)
		(end 142.26667 -134.083298)
		(width 0.14224)
		(layer "In4.Cu")
		(net "M_L_DQ<51>")
	)
	(segment
		(start 142.339568 -132.102098)
		(end 142.339568 -134.0104)
		(width 0.14224)
		(layer "In4.Cu")
		(net "M_L_DQ<51>")
	)
	(segment
		(start 142.48257 -135.975852)
		(end 142.22857 -136.229852)
		(width 0.14224)
		(layer "In4.Cu")
		(net "M_L_DQ<51>")
	)
	(segment
		(start 142.26667 -134.083298)
		(end 142.26667 -134.581138)
		(width 0.14224)
		(layer "In4.Cu")
		(net "M_L_DQ<51>")
	)
	(segment
		(start 142.26667 -131.408678)
		(end 142.26667 -132.0292)
		(width 0.14224)
		(layer "In4.Cu")
		(net "M_L_DQ<51>")
	)
	(segment
		(start 142.22857 -136.5504)
		(end 142.314168 -136.635998)
		(width 0.14224)
		(layer "In4.Cu")
		(net "M_L_DQ<51>")
	)
	(segment
		(start 142.22857 -139.61618)
		(end 141.899386 -139.945364)
		(width 0.14224)
		(layer "In4.Cu")
		(net "M_L_DQ<51>")
	)
	(segment
		(start 142.25397 -126.37516)
		(end 142.25397 -129.960878)
		(width 0.14224)
		(layer "In4.Cu")
		(net "M_L_DQ<51>")
	)
	(segment
		(start 142.40637 -130.113278)
		(end 142.40637 -131.268978)
		(width 0.14224)
		(layer "In4.Cu")
		(net "M_L_DQ<51>")
	)
	(segment
		(start 141.899386 -126.020576)
		(end 142.25397 -126.37516)
		(width 0.14224)
		(layer "In4.Cu")
		(net "M_L_DQ<51>")
	)
	(segment
		(start 141.899386 -139.945364)
		(end 141.899386 -139.932156)
		(width 0.14224)
		(layer "In4.Cu")
		(net "M_L_DQ<51>")
	)
	(segment
		(start 142.22857 -138.744198)
		(end 142.22857 -139.61618)
		(width 0.14224)
		(layer "In4.Cu")
		(net "M_L_DQ<51>")
	)
	(segment
		(start 142.26667 -132.0292)
		(end 142.339568 -132.102098)
		(width 0.14224)
		(layer "In4.Cu")
		(net "M_L_DQ<51>")
	)
	(segment
		(start 142.48257 -134.797038)
		(end 142.48257 -135.975852)
		(width 0.14224)
		(layer "In4.Cu")
		(net "M_L_DQ<51>")
	)
	(segment
		(start 142.40637 -131.268978)
		(end 142.26667 -131.408678)
		(width 0.14224)
		(layer "In4.Cu")
		(net "M_L_DQ<51>")
	)
	(segment
		(start 142.22857 -136.229852)
		(end 142.22857 -136.5504)
		(width 0.14224)
		(layer "In4.Cu")
		(net "M_L_DQ<51>")
	)
	(segment
		(start 142.314168 -136.635998)
		(end 142.314168 -138.6586)
		(width 0.14224)
		(layer "In4.Cu")
		(net "M_L_DQ<51>")
	)
	(segment
		(start 142.26667 -134.581138)
		(end 142.48257 -134.797038)
		(width 0.14224)
		(layer "In4.Cu")
		(net "M_L_DQ<51>")
	)
	(segment
		(start 141.210792 -141.785848)
		(end 141.49324 -141.5034)
		(width 0.14224)
		(layer "In9.Cu")
		(net "M_L_DQ<51>")
	)
	(segment
		(start 141.210792 -142.878048)
		(end 141.46784 -142.621)
		(width 0.14224)
		(layer "In9.Cu")
		(net "M_L_DQ<51>")
	)
	(segment
		(start 141.32179 -143.941546)
		(end 141.49959 -143.763746)
		(width 0.14224)
		(layer "In9.Cu")
		(net "M_L_DQ<51>")
	)
	(segment
		(start 141.49324 -140.834618)
		(end 141.44879 -140.790168)
		(width 0.14224)
		(layer "In9.Cu")
		(net "M_L_DQ<51>")
	)
	(segment
		(start 141.44879 -140.3604)
		(end 141.877034 -139.932156)
		(width 0.14224)
		(layer "In9.Cu")
		(net "M_L_DQ<51>")
	)
	(segment
		(start 141.44879 -140.790168)
		(end 141.44879 -140.3604)
		(width 0.14224)
		(layer "In9.Cu")
		(net "M_L_DQ<51>")
	)
	(segment
		(start 141.210792 -142.059152)
		(end 141.210792 -141.785848)
		(width 0.14224)
		(layer "In9.Cu")
		(net "M_L_DQ<51>")
	)
	(segment
		(start 141.049502 -143.941546)
		(end 141.32179 -143.941546)
		(width 0.14224)
		(layer "In9.Cu")
		(net "M_L_DQ<51>")
	)
	(segment
		(start 141.49959 -143.44015)
		(end 141.210792 -143.151352)
		(width 0.14224)
		(layer "In9.Cu")
		(net "M_L_DQ<51>")
	)
	(segment
		(start 141.49959 -143.763746)
		(end 141.49959 -143.44015)
		(width 0.14224)
		(layer "In9.Cu")
		(net "M_L_DQ<51>")
	)
	(segment
		(start 141.877034 -139.932156)
		(end 141.899386 -139.932156)
		(width 0.14224)
		(layer "In9.Cu")
		(net "M_L_DQ<51>")
	)
	(segment
		(start 141.46784 -142.621)
		(end 141.46784 -142.3162)
		(width 0.14224)
		(layer "In9.Cu")
		(net "M_L_DQ<51>")
	)
	(segment
		(start 141.210792 -143.151352)
		(end 141.210792 -142.878048)
		(width 0.14224)
		(layer "In9.Cu")
		(net "M_L_DQ<51>")
	)
	(segment
		(start 141.46784 -142.3162)
		(end 141.210792 -142.059152)
		(width 0.14224)
		(layer "In9.Cu")
		(net "M_L_DQ<51>")
	)
	(segment
		(start 141.49324 -141.5034)
		(end 141.49324 -140.834618)
		(width 0.14224)
		(layer "In9.Cu")
		(net "M_L_DQ<51>")
	)
	(segment
		(start 122.432064 -101.381052)
		(end 122.504708 -101.308408)
		(width 0.0889)
		(layer "F.Cu")
		(net "M_L_DQ<50>")
	)
	(segment
		(start 140.551662 -112.131094)
		(end 136.789668 -108.3691)
		(width 0.1651)
		(layer "F.Cu")
		(net "M_L_DQ<50>")
	)
	(segment
		(start 123.079256 -104.686354)
		(end 121.906792 -103.51389)
		(width 0.1016)
		(layer "F.Cu")
		(net "M_L_DQ<50>")
	)
	(segment
		(start 136.789668 -108.3691)
		(end 136.484868 -108.3691)
		(width 0.1651)
		(layer "F.Cu")
		(net "M_L_DQ<50>")
	)
	(segment
		(start 141.425168 -126.138432)
		(end 141.425168 -125.076204)
		(width 0.1651)
		(layer "F.Cu")
		(net "M_L_DQ<50>")
	)
	(segment
		(start 136.484868 -108.3691)
		(end 136.027668 -107.9119)
		(width 0.1016)
		(layer "F.Cu")
		(net "M_L_DQ<50>")
	)
	(segment
		(start 122.504708 -101.308408)
		(end 122.504708 -100.976684)
		(width 0.0889)
		(layer "F.Cu")
		(net "M_L_DQ<50>")
	)
	(segment
		(start 141.77772 -124.723652)
		(end 141.77772 -120.138952)
		(width 0.1651)
		(layer "F.Cu")
		(net "M_L_DQ<50>")
	)
	(segment
		(start 131.199382 -104.686354)
		(end 123.079256 -104.686354)
		(width 0.1016)
		(layer "F.Cu")
		(net "M_L_DQ<50>")
	)
	(segment
		(start 142.030958 -145.92554)
		(end 141.899386 -145.793968)
		(width 0.1651)
		(layer "F.Cu")
		(net "M_L_DQ<50>")
	)
	(segment
		(start 134.424928 -107.9119)
		(end 131.199382 -104.686354)
		(width 0.1016)
		(layer "F.Cu")
		(net "M_L_DQ<50>")
	)
	(segment
		(start 140.551662 -118.912894)
		(end 140.551662 -112.131094)
		(width 0.1651)
		(layer "F.Cu")
		(net "M_L_DQ<50>")
	)
	(segment
		(start 140.917168 -126.615698)
		(end 140.947902 -126.615698)
		(width 0.1651)
		(layer "F.Cu")
		(net "M_L_DQ<50>")
	)
	(segment
		(start 121.906792 -102.748842)
		(end 121.992898 -102.662736)
		(width 0.0889)
		(layer "F.Cu")
		(net "M_L_DQ<50>")
	)
	(segment
		(start 141.899386 -146.280632)
		(end 142.030958 -146.14906)
		(width 0.1651)
		(layer "F.Cu")
		(net "M_L_DQ<50>")
	)
	(segment
		(start 141.899386 -145.793968)
		(end 141.899386 -145.5166)
		(width 0.1651)
		(layer "F.Cu")
		(net "M_L_DQ<50>")
	)
	(segment
		(start 141.425168 -125.076204)
		(end 141.77772 -124.723652)
		(width 0.1651)
		(layer "F.Cu")
		(net "M_L_DQ<50>")
	)
	(segment
		(start 142.030958 -146.14906)
		(end 142.030958 -145.92554)
		(width 0.1651)
		(layer "F.Cu")
		(net "M_L_DQ<50>")
	)
	(segment
		(start 140.947902 -126.615698)
		(end 141.425168 -126.138432)
		(width 0.1651)
		(layer "F.Cu")
		(net "M_L_DQ<50>")
	)
	(segment
		(start 141.899386 -147.27174)
		(end 141.899386 -146.280632)
		(width 0.1651)
		(layer "F.Cu")
		(net "M_L_DQ<50>")
	)
	(segment
		(start 121.906792 -103.51389)
		(end 121.906792 -102.748842)
		(width 0.0889)
		(layer "F.Cu")
		(net "M_L_DQ<50>")
	)
	(segment
		(start 136.027668 -107.9119)
		(end 134.424928 -107.9119)
		(width 0.1016)
		(layer "F.Cu")
		(net "M_L_DQ<50>")
	)
	(segment
		(start 121.997724 -102.271322)
		(end 121.992898 -102.262686)
		(width 0.0889)
		(layer "F.Cu")
		(net "M_L_DQ<50>")
	)
	(segment
		(start 141.77772 -120.138952)
		(end 140.551662 -118.912894)
		(width 0.1651)
		(layer "F.Cu")
		(net "M_L_DQ<50>")
	)
	(segment
		(start 121.992898 -102.262686)
		(end 121.986548 -102.252018)
		(width 0.0889)
		(layer "F.Cu")
		(net "M_L_DQ<50>")
	)
	(via
		(at 141.899386 -145.5166)
		(size 0.508)
		(drill 0.254)
		(layers "F.Cu" "B.Cu")
		(net "M_L_DQ<50>")
	)
	(via
		(at 141.049502 -141.213078)
		(size 0.508)
		(drill 0.254)
		(layers "F.Cu" "B.Cu")
		(net "M_L_DQ<50>")
	)
	(via
		(at 140.917168 -126.615698)
		(size 0.508)
		(drill 0.254)
		(layers "F.Cu" "B.Cu")
		(net "M_L_DQ<50>")
	)
	(arc
		(start 121.986548 -102.252018)
		(mid 121.978422 -101.698389)
		(end 122.432064 -101.381052)
		(width 0.0889)
		(layer "F.Cu")
		(net "M_L_DQ<50>")
	)
	(arc
		(start 121.992898 -102.662736)
		(mid 122.046368 -102.467673)
		(end 121.997724 -102.271322)
		(width 0.0889)
		(layer "F.Cu")
		(net "M_L_DQ<50>")
	)
	(segment
		(start 141.049502 -142.477236)
		(end 141.049502 -141.213078)
		(width 0.1651)
		(layer "B.Cu")
		(net "M_L_DQ<50>")
	)
	(segment
		(start 140.917168 -126.615698)
		(end 140.947902 -126.615698)
		(width 0.14224)
		(layer "In4.Cu")
		(net "M_L_DQ<50>")
	)
	(segment
		(start 141.56817 -136.205468)
		(end 141.56817 -136.559544)
		(width 0.14224)
		(layer "In4.Cu")
		(net "M_L_DQ<50>")
	)
	(segment
		(start 141.56817 -138.852402)
		(end 141.56817 -139.371578)
		(width 0.14224)
		(layer "In4.Cu")
		(net "M_L_DQ<50>")
	)
	(segment
		(start 140.70457 -140.235178)
		(end 140.70457 -140.868146)
		(width 0.14224)
		(layer "In4.Cu")
		(net "M_L_DQ<50>")
	)
	(segment
		(start 141.475206 -134.035038)
		(end 141.61897 -134.178802)
		(width 0.14224)
		(layer "In4.Cu")
		(net "M_L_DQ<50>")
	)
	(segment
		(start 141.41577 -129.960878)
		(end 141.41577 -131.332478)
		(width 0.14224)
		(layer "In4.Cu")
		(net "M_L_DQ<50>")
	)
	(segment
		(start 141.61897 -134.178802)
		(end 141.61897 -134.492238)
		(width 0.14224)
		(layer "In4.Cu")
		(net "M_L_DQ<50>")
	)
	(segment
		(start 141.61897 -131.535678)
		(end 141.61897 -131.953)
		(width 0.14224)
		(layer "In4.Cu")
		(net "M_L_DQ<50>")
	)
	(segment
		(start 141.475968 -138.7602)
		(end 141.56817 -138.852402)
		(width 0.14224)
		(layer "In4.Cu")
		(net "M_L_DQ<50>")
	)
	(segment
		(start 140.947902 -126.615698)
		(end 141.54277 -127.210566)
		(width 0.14224)
		(layer "In4.Cu")
		(net "M_L_DQ<50>")
	)
	(segment
		(start 141.54277 -129.833878)
		(end 141.41577 -129.960878)
		(width 0.14224)
		(layer "In4.Cu")
		(net "M_L_DQ<50>")
	)
	(segment
		(start 141.61897 -134.492238)
		(end 141.33957 -134.771638)
		(width 0.14224)
		(layer "In4.Cu")
		(net "M_L_DQ<50>")
	)
	(segment
		(start 141.56817 -139.371578)
		(end 140.70457 -140.235178)
		(width 0.14224)
		(layer "In4.Cu")
		(net "M_L_DQ<50>")
	)
	(segment
		(start 141.33957 -135.976868)
		(end 141.56817 -136.205468)
		(width 0.14224)
		(layer "In4.Cu")
		(net "M_L_DQ<50>")
	)
	(segment
		(start 141.475968 -136.651746)
		(end 141.475968 -138.7602)
		(width 0.14224)
		(layer "In4.Cu")
		(net "M_L_DQ<50>")
	)
	(segment
		(start 141.475206 -132.096764)
		(end 141.475206 -134.035038)
		(width 0.14224)
		(layer "In4.Cu")
		(net "M_L_DQ<50>")
	)
	(segment
		(start 141.41577 -131.332478)
		(end 141.61897 -131.535678)
		(width 0.14224)
		(layer "In4.Cu")
		(net "M_L_DQ<50>")
	)
	(segment
		(start 140.70457 -140.868146)
		(end 141.049502 -141.213078)
		(width 0.14224)
		(layer "In4.Cu")
		(net "M_L_DQ<50>")
	)
	(segment
		(start 141.56817 -136.559544)
		(end 141.475968 -136.651746)
		(width 0.14224)
		(layer "In4.Cu")
		(net "M_L_DQ<50>")
	)
	(segment
		(start 141.54277 -127.210566)
		(end 141.54277 -129.833878)
		(width 0.14224)
		(layer "In4.Cu")
		(net "M_L_DQ<50>")
	)
	(segment
		(start 141.33957 -134.771638)
		(end 141.33957 -135.976868)
		(width 0.14224)
		(layer "In4.Cu")
		(net "M_L_DQ<50>")
	)
	(segment
		(start 141.61897 -131.953)
		(end 141.475206 -132.096764)
		(width 0.14224)
		(layer "In4.Cu")
		(net "M_L_DQ<50>")
	)
	(segment
		(start 140.616432 -141.646148)
		(end 140.616432 -144.233646)
		(width 0.14224)
		(layer "In9.Cu")
		(net "M_L_DQ<50>")
	)
	(segment
		(start 141.049502 -141.213078)
		(end 140.616432 -141.646148)
		(width 0.14224)
		(layer "In9.Cu")
		(net "M_L_DQ<50>")
	)
	(segment
		(start 140.616432 -144.233646)
		(end 141.899386 -145.5166)
		(width 0.14224)
		(layer "In9.Cu")
		(net "M_L_DQ<50>")
	)
	(segment
		(start 32.249364 -145.946368)
		(end 32.15132 -145.415)
		(width 0.1651)
		(layer "F.Cu")
		(net "M_L_DQ<4>")
	)
	(segment
		(start 32.249364 -147.27174)
		(end 32.249364 -145.946368)
		(width 0.1651)
		(layer "F.Cu")
		(net "M_L_DQ<4>")
	)
	(segment
		(start 73.758806 -83.822286)
		(end 73.187306 -83.822286)
		(width 0.1651)
		(layer "F.Cu")
		(net "M_L_DQ<4>")
	)
	(via
		(at 31.39948 -141.213078)
		(size 0.508)
		(drill 0.254)
		(layers "F.Cu" "B.Cu")
		(net "M_L_DQ<4>")
	)
	(via
		(at 73.187306 -83.822286)
		(size 0.508)
		(drill 0.254)
		(layers "F.Cu" "B.Cu")
		(net "M_L_DQ<4>")
	)
	(via
		(at 32.15132 -145.415)
		(size 0.508)
		(drill 0.254)
		(layers "F.Cu" "B.Cu")
		(net "M_L_DQ<4>")
	)
	(segment
		(start 31.39948 -142.477236)
		(end 31.39948 -141.213078)
		(width 0.1651)
		(layer "B.Cu")
		(net "M_L_DQ<4>")
	)
	(segment
		(start 72.857106 -83.060286)
		(end 72.840596 -83.031838)
		(width 0.0889)
		(layer "In4.Cu")
		(net "M_L_DQ<4>")
	)
	(segment
		(start 31.690564 -131.09702)
		(end 31.85668 -131.498086)
		(width 0.14224)
		(layer "In4.Cu")
		(net "M_L_DQ<4>")
	)
	(segment
		(start 72.350376 -82.73669)
		(end 72.31761 -82.73669)
		(width 0.0889)
		(layer "In4.Cu")
		(net "M_L_DQ<4>")
	)
	(segment
		(start 31.627064 -139.829032)
		(end 31.290514 -140.165582)
		(width 0.14224)
		(layer "In4.Cu")
		(net "M_L_DQ<4>")
	)
	(segment
		(start 69.771006 -81.250536)
		(end 69.735446 -81.250536)
		(width 0.0889)
		(layer "In4.Cu")
		(net "M_L_DQ<4>")
	)
	(segment
		(start 67.790314 -82.241136)
		(end 67.510152 -81.960974)
		(width 0.0889)
		(layer "In4.Cu")
		(net "M_L_DQ<4>")
	)
	(segment
		(start 31.947612 -115.714526)
		(end 31.947612 -129.645918)
		(width 0.14224)
		(layer "In4.Cu")
		(net "M_L_DQ<4>")
	)
	(segment
		(start 31.665164 -135.86206)
		(end 31.876746 -136.373108)
		(width 0.14224)
		(layer "In4.Cu")
		(net "M_L_DQ<4>")
	)
	(segment
		(start 66.222626 -81.960974)
		(end 65.993772 -81.73212)
		(width 0.0889)
		(layer "In4.Cu")
		(net "M_L_DQ<4>")
	)
	(segment
		(start 31.876746 -139.226036)
		(end 31.627064 -139.829032)
		(width 0.14224)
		(layer "In4.Cu")
		(net "M_L_DQ<4>")
	)
	(segment
		(start 53.434742 -91.325192)
		(end 53.434742 -95.200978)
		(width 0.14224)
		(layer "In4.Cu")
		(net "M_L_DQ<4>")
	)
	(segment
		(start 40.804338 -106.8578)
		(end 31.947612 -115.714526)
		(width 0.14224)
		(layer "In4.Cu")
		(net "M_L_DQ<4>")
	)
	(segment
		(start 31.665164 -134.860284)
		(end 31.665164 -135.86206)
		(width 0.14224)
		(layer "In4.Cu")
		(net "M_L_DQ<4>")
	)
	(segment
		(start 31.876746 -136.373108)
		(end 31.876746 -139.226036)
		(width 0.14224)
		(layer "In4.Cu")
		(net "M_L_DQ<4>")
	)
	(segment
		(start 68.905882 -81.74609)
		(end 68.873116 -81.74609)
		(width 0.0889)
		(layer "In4.Cu")
		(net "M_L_DQ<4>")
	)
	(segment
		(start 31.690564 -130.266694)
		(end 31.690564 -131.09702)
		(width 0.14224)
		(layer "In4.Cu")
		(net "M_L_DQ<4>")
	)
	(segment
		(start 31.290514 -141.104112)
		(end 31.39948 -141.213078)
		(width 0.14224)
		(layer "In4.Cu")
		(net "M_L_DQ<4>")
	)
	(segment
		(start 73.187306 -83.822286)
		(end 72.857106 -83.060286)
		(width 0.0889)
		(layer "In4.Cu")
		(net "M_L_DQ<4>")
	)
	(segment
		(start 31.39948 -141.213078)
		(end 30.96641 -141.646148)
		(width 0.14224)
		(layer "In4.Cu")
		(net "M_L_DQ<4>")
	)
	(segment
		(start 31.886398 -129.794)
		(end 31.844234 -129.8956)
		(width 0.14224)
		(layer "In4.Cu")
		(net "M_L_DQ<4>")
	)
	(segment
		(start 53.189124 -95.794068)
		(end 52.696364 -96.98355)
		(width 0.14224)
		(layer "In4.Cu")
		(net "M_L_DQ<4>")
	)
	(segment
		(start 31.844234 -129.8956)
		(end 31.690564 -130.266694)
		(width 0.14224)
		(layer "In4.Cu")
		(net "M_L_DQ<4>")
	)
	(segment
		(start 65.993772 -81.73212)
		(end 63.027814 -81.73212)
		(width 0.14224)
		(layer "In4.Cu")
		(net "M_L_DQ<4>")
	)
	(segment
		(start 44.248832 -105.431082)
		(end 40.804338 -106.8578)
		(width 0.14224)
		(layer "In4.Cu")
		(net "M_L_DQ<4>")
	)
	(segment
		(start 70.633336 -81.74609)
		(end 70.60057 -81.74609)
		(width 0.0889)
		(layer "In4.Cu")
		(net "M_L_DQ<4>")
	)
	(segment
		(start 52.696364 -96.98355)
		(end 44.248832 -105.431082)
		(width 0.14224)
		(layer "In4.Cu")
		(net "M_L_DQ<4>")
	)
	(segment
		(start 30.96641 -144.23009)
		(end 32.15132 -145.415)
		(width 0.14224)
		(layer "In4.Cu")
		(net "M_L_DQ<4>")
	)
	(segment
		(start 53.434742 -95.200978)
		(end 53.189124 -95.794068)
		(width 0.14224)
		(layer "In4.Cu")
		(net "M_L_DQ<4>")
	)
	(segment
		(start 71.48322 -82.241136)
		(end 71.45528 -82.241136)
		(width 0.0889)
		(layer "In4.Cu")
		(net "M_L_DQ<4>")
	)
	(segment
		(start 67.510152 -81.960974)
		(end 66.222626 -81.960974)
		(width 0.0889)
		(layer "In4.Cu")
		(net "M_L_DQ<4>")
	)
	(segment
		(start 31.85668 -134.397496)
		(end 31.665164 -134.860284)
		(width 0.14224)
		(layer "In4.Cu")
		(net "M_L_DQ<4>")
	)
	(segment
		(start 31.85668 -131.498086)
		(end 31.85668 -134.397496)
		(width 0.14224)
		(layer "In4.Cu")
		(net "M_L_DQ<4>")
	)
	(segment
		(start 31.290514 -140.165582)
		(end 31.290514 -141.104112)
		(width 0.14224)
		(layer "In4.Cu")
		(net "M_L_DQ<4>")
	)
	(segment
		(start 63.027814 -81.73212)
		(end 53.434742 -91.325192)
		(width 0.14224)
		(layer "In4.Cu")
		(net "M_L_DQ<4>")
	)
	(segment
		(start 31.947612 -129.645918)
		(end 31.886398 -129.794)
		(width 0.14224)
		(layer "In4.Cu")
		(net "M_L_DQ<4>")
	)
	(segment
		(start 30.96641 -141.646148)
		(end 30.96641 -144.23009)
		(width 0.14224)
		(layer "In4.Cu")
		(net "M_L_DQ<4>")
	)
	(segment
		(start 68.051172 -82.241136)
		(end 67.790314 -82.241136)
		(width 0.0889)
		(layer "In4.Cu")
		(net "M_L_DQ<4>")
	)
	(arc
		(start 69.241416 -81.545938)
		(mid 69.099733 -81.689742)
		(end 68.905882 -81.74609)
		(width 0.0889)
		(layer "In4.Cu")
		(net "M_L_DQ<4>")
	)
	(arc
		(start 68.382896 -82.041238)
		(mid 68.242817 -82.183974)
		(end 68.051172 -82.241136)
		(width 0.0889)
		(layer "In4.Cu")
		(net "M_L_DQ<4>")
	)
	(arc
		(start 71.45528 -82.241136)
		(mid 71.263638 -82.18397)
		(end 71.123556 -82.041238)
		(width 0.0889)
		(layer "In4.Cu")
		(net "M_L_DQ<4>")
	)
	(arc
		(start 68.873116 -81.74609)
		(mid 68.589899 -81.830371)
		(end 68.382896 -82.041238)
		(width 0.0889)
		(layer "In4.Cu")
		(net "M_L_DQ<4>")
	)
	(arc
		(start 70.265036 -81.545938)
		(mid 70.056428 -81.334006)
		(end 69.771006 -81.250536)
		(width 0.0889)
		(layer "In4.Cu")
		(net "M_L_DQ<4>")
	)
	(arc
		(start 71.123556 -82.041238)
		(mid 70.916552 -81.830374)
		(end 70.633336 -81.74609)
		(width 0.0889)
		(layer "In4.Cu")
		(net "M_L_DQ<4>")
	)
	(arc
		(start 69.735446 -81.250536)
		(mid 69.450022 -81.334003)
		(end 69.241416 -81.545938)
		(width 0.0889)
		(layer "In4.Cu")
		(net "M_L_DQ<4>")
	)
	(arc
		(start 72.840596 -83.031838)
		(mid 72.633592 -82.820974)
		(end 72.350376 -82.73669)
		(width 0.0889)
		(layer "In4.Cu")
		(net "M_L_DQ<4>")
	)
	(arc
		(start 70.60057 -81.74609)
		(mid 70.40672 -81.68974)
		(end 70.265036 -81.545938)
		(width 0.0889)
		(layer "In4.Cu")
		(net "M_L_DQ<4>")
	)
	(arc
		(start 72.31761 -82.73669)
		(mid 72.12376 -82.68034)
		(end 71.982076 -82.536538)
		(width 0.0889)
		(layer "In4.Cu")
		(net "M_L_DQ<4>")
	)
	(arc
		(start 71.982076 -82.536538)
		(mid 71.771363 -82.323459)
		(end 71.48322 -82.241136)
		(width 0.0889)
		(layer "In4.Cu")
		(net "M_L_DQ<4>")
	)
	(segment
		(start 130.05562 -107.442254)
		(end 132.789168 -110.175802)
		(width 0.1016)
		(layer "F.Cu")
		(net "M_L_DQ<49>")
	)
	(segment
		(start 135.075168 -117.6401)
		(end 135.240268 -117.8052)
		(width 0.1651)
		(layer "F.Cu")
		(net "M_L_DQ<49>")
	)
	(segment
		(start 135.583168 -117.8052)
		(end 135.748268 -117.6401)
		(width 0.1651)
		(layer "F.Cu")
		(net "M_L_DQ<49>")
	)
	(segment
		(start 119.929402 -102.462584)
		(end 119.929402 -103.448612)
		(width 0.0889)
		(layer "F.Cu")
		(net "M_L_DQ<49>")
	)
	(segment
		(start 136.262364 -125.195076)
		(end 136.135364 -125.322076)
		(width 0.1651)
		(layer "F.Cu")
		(net "M_L_DQ<49>")
	)
	(segment
		(start 136.256268 -115.8494)
		(end 136.421368 -116.0145)
		(width 0.1651)
		(layer "F.Cu")
		(net "M_L_DQ<49>")
	)
	(segment
		(start 119.466868 -105.2957)
		(end 119.657368 -105.4862)
		(width 0.0889)
		(layer "F.Cu")
		(net "M_L_DQ<49>")
	)
	(segment
		(start 135.748268 -116.0145)
		(end 135.913368 -115.8494)
		(width 0.1651)
		(layer "F.Cu")
		(net "M_L_DQ<49>")
	)
	(segment
		(start 135.748268 -117.6401)
		(end 135.748268 -116.0145)
		(width 0.1651)
		(layer "F.Cu")
		(net "M_L_DQ<49>")
	)
	(segment
		(start 119.466868 -103.911146)
		(end 119.466868 -105.2957)
		(width 0.0889)
		(layer "F.Cu")
		(net "M_L_DQ<49>")
	)
	(segment
		(start 135.913368 -115.8494)
		(end 136.256268 -115.8494)
		(width 0.1651)
		(layer "F.Cu")
		(net "M_L_DQ<49>")
	)
	(segment
		(start 119.657368 -105.4862)
		(end 119.784622 -105.4862)
		(width 0.0889)
		(layer "F.Cu")
		(net "M_L_DQ<49>")
	)
	(segment
		(start 119.784622 -105.4862)
		(end 121.740676 -107.442254)
		(width 0.1016)
		(layer "F.Cu")
		(net "M_L_DQ<49>")
	)
	(segment
		(start 132.789168 -110.175802)
		(end 132.789168 -110.9218)
		(width 0.1016)
		(layer "F.Cu")
		(net "M_L_DQ<49>")
	)
	(segment
		(start 136.421368 -124.1806)
		(end 136.262364 -124.339604)
		(width 0.1651)
		(layer "F.Cu")
		(net "M_L_DQ<49>")
	)
	(segment
		(start 135.240268 -117.8052)
		(end 135.583168 -117.8052)
		(width 0.1651)
		(layer "F.Cu")
		(net "M_L_DQ<49>")
	)
	(segment
		(start 136.135364 -125.322076)
		(end 135.771636 -125.322076)
		(width 0.1651)
		(layer "F.Cu")
		(net "M_L_DQ<49>")
	)
	(segment
		(start 136.262364 -124.339604)
		(end 136.262364 -125.195076)
		(width 0.1651)
		(layer "F.Cu")
		(net "M_L_DQ<49>")
	)
	(segment
		(start 135.075168 -113.2078)
		(end 135.075168 -117.6401)
		(width 0.1651)
		(layer "F.Cu")
		(net "M_L_DQ<49>")
	)
	(segment
		(start 119.929402 -103.448612)
		(end 119.466868 -103.911146)
		(width 0.0889)
		(layer "F.Cu")
		(net "M_L_DQ<49>")
	)
	(segment
		(start 135.099552 -142.6718)
		(end 135.099552 -143.941546)
		(width 0.1651)
		(layer "F.Cu")
		(net "M_L_DQ<49>")
	)
	(segment
		(start 121.740676 -107.442254)
		(end 130.05562 -107.442254)
		(width 0.1016)
		(layer "F.Cu")
		(net "M_L_DQ<49>")
	)
	(segment
		(start 132.789168 -110.9218)
		(end 135.075168 -113.2078)
		(width 0.1651)
		(layer "F.Cu")
		(net "M_L_DQ<49>")
	)
	(segment
		(start 136.421368 -116.0145)
		(end 136.421368 -124.1806)
		(width 0.1651)
		(layer "F.Cu")
		(net "M_L_DQ<49>")
	)
	(via
		(at 135.099552 -143.941546)
		(size 0.508)
		(drill 0.254)
		(layers "F.Cu" "B.Cu")
		(net "M_L_DQ<49>")
	)
	(via
		(at 135.771636 -125.322076)
		(size 0.508)
		(drill 0.254)
		(layers "F.Cu" "B.Cu")
		(net "M_L_DQ<49>")
	)
	(via
		(at 135.771636 -139.932156)
		(size 0.508)
		(drill 0.254)
		(layers "F.Cu" "B.Cu")
		(net "M_L_DQ<49>")
	)
	(segment
		(start 135.949436 -137.877296)
		(end 135.949436 -139.251182)
		(width 0.1651)
		(layer "B.Cu")
		(net "M_L_DQ<49>")
	)
	(segment
		(start 135.949436 -139.251182)
		(end 135.771636 -139.428982)
		(width 0.1651)
		(layer "B.Cu")
		(net "M_L_DQ<49>")
	)
	(segment
		(start 135.771636 -139.428982)
		(end 135.771636 -139.932156)
		(width 0.1651)
		(layer "B.Cu")
		(net "M_L_DQ<49>")
	)
	(segment
		(start 136.370568 -131.927854)
		(end 136.370568 -134.1374)
		(width 0.14224)
		(layer "In4.Cu")
		(net "M_L_DQ<49>")
	)
	(segment
		(start 136.25957 -134.248398)
		(end 136.25957 -136.5758)
		(width 0.14224)
		(layer "In4.Cu")
		(net "M_L_DQ<49>")
	)
	(segment
		(start 136.25957 -138.896598)
		(end 136.25957 -139.355322)
		(width 0.14224)
		(layer "In4.Cu")
		(net "M_L_DQ<49>")
	)
	(segment
		(start 136.370568 -136.686798)
		(end 136.370568 -138.7856)
		(width 0.14224)
		(layer "In4.Cu")
		(net "M_L_DQ<49>")
	)
	(segment
		(start 135.576564 -128.257808)
		(end 136.25957 -128.940814)
		(width 0.14224)
		(layer "In4.Cu")
		(net "M_L_DQ<49>")
	)
	(segment
		(start 135.771636 -125.322076)
		(end 135.576564 -125.517148)
		(width 0.14224)
		(layer "In4.Cu")
		(net "M_L_DQ<49>")
	)
	(segment
		(start 136.370568 -138.7856)
		(end 136.25957 -138.896598)
		(width 0.14224)
		(layer "In4.Cu")
		(net "M_L_DQ<49>")
	)
	(segment
		(start 136.25957 -131.816856)
		(end 136.370568 -131.927854)
		(width 0.14224)
		(layer "In4.Cu")
		(net "M_L_DQ<49>")
	)
	(segment
		(start 136.370568 -134.1374)
		(end 136.25957 -134.248398)
		(width 0.14224)
		(layer "In4.Cu")
		(net "M_L_DQ<49>")
	)
	(segment
		(start 136.25957 -128.940814)
		(end 136.25957 -131.816856)
		(width 0.14224)
		(layer "In4.Cu")
		(net "M_L_DQ<49>")
	)
	(segment
		(start 136.25957 -139.355322)
		(end 135.771636 -139.843256)
		(width 0.14224)
		(layer "In4.Cu")
		(net "M_L_DQ<49>")
	)
	(segment
		(start 135.771636 -139.843256)
		(end 135.771636 -139.932156)
		(width 0.14224)
		(layer "In4.Cu")
		(net "M_L_DQ<49>")
	)
	(segment
		(start 136.25957 -136.5758)
		(end 136.370568 -136.686798)
		(width 0.14224)
		(layer "In4.Cu")
		(net "M_L_DQ<49>")
	)
	(segment
		(start 135.576564 -125.517148)
		(end 135.576564 -128.257808)
		(width 0.14224)
		(layer "In4.Cu")
		(net "M_L_DQ<49>")
	)
	(segment
		(start 135.500618 -143.4846)
		(end 135.260842 -143.244824)
		(width 0.14224)
		(layer "In9.Cu")
		(net "M_L_DQ<49>")
	)
	(segment
		(start 135.348472 -143.941546)
		(end 135.500618 -143.7894)
		(width 0.14224)
		(layer "In9.Cu")
		(net "M_L_DQ<49>")
	)
	(segment
		(start 135.551418 -141.020546)
		(end 135.32104 -140.790168)
		(width 0.14224)
		(layer "In9.Cu")
		(net "M_L_DQ<49>")
	)
	(segment
		(start 135.260842 -142.076424)
		(end 135.260842 -141.715744)
		(width 0.14224)
		(layer "In9.Cu")
		(net "M_L_DQ<49>")
	)
	(segment
		(start 135.551418 -141.425168)
		(end 135.551418 -141.020546)
		(width 0.14224)
		(layer "In9.Cu")
		(net "M_L_DQ<49>")
	)
	(segment
		(start 135.32104 -140.790168)
		(end 135.32104 -140.3604)
		(width 0.14224)
		(layer "In9.Cu")
		(net "M_L_DQ<49>")
	)
	(segment
		(start 135.32104 -140.3604)
		(end 135.749284 -139.932156)
		(width 0.14224)
		(layer "In9.Cu")
		(net "M_L_DQ<49>")
	)
	(segment
		(start 135.500618 -143.7894)
		(end 135.500618 -143.4846)
		(width 0.14224)
		(layer "In9.Cu")
		(net "M_L_DQ<49>")
	)
	(segment
		(start 135.475218 -142.7226)
		(end 135.475218 -142.2908)
		(width 0.14224)
		(layer "In9.Cu")
		(net "M_L_DQ<49>")
	)
	(segment
		(start 135.475218 -142.2908)
		(end 135.260842 -142.076424)
		(width 0.14224)
		(layer "In9.Cu")
		(net "M_L_DQ<49>")
	)
	(segment
		(start 135.260842 -142.936976)
		(end 135.475218 -142.7226)
		(width 0.14224)
		(layer "In9.Cu")
		(net "M_L_DQ<49>")
	)
	(segment
		(start 135.099552 -143.941546)
		(end 135.348472 -143.941546)
		(width 0.14224)
		(layer "In9.Cu")
		(net "M_L_DQ<49>")
	)
	(segment
		(start 135.749284 -139.932156)
		(end 135.771636 -139.932156)
		(width 0.14224)
		(layer "In9.Cu")
		(net "M_L_DQ<49>")
	)
	(segment
		(start 135.260842 -141.715744)
		(end 135.551418 -141.425168)
		(width 0.14224)
		(layer "In9.Cu")
		(net "M_L_DQ<49>")
	)
	(segment
		(start 135.260842 -143.244824)
		(end 135.260842 -142.936976)
		(width 0.14224)
		(layer "In9.Cu")
		(net "M_L_DQ<49>")
	)
	(segment
		(start 129.892298 -107.835954)
		(end 132.281168 -110.224824)
		(width 0.1016)
		(layer "F.Cu")
		(net "M_L_DQ<48>")
	)
	(segment
		(start 135.297164 -126.418086)
		(end 135.124952 -126.590298)
		(width 0.1651)
		(layer "F.Cu")
		(net "M_L_DQ<48>")
	)
	(segment
		(start 133.779768 -113.585752)
		(end 132.558536 -114.806476)
		(width 0.1651)
		(layer "F.Cu")
		(net "M_L_DQ<48>")
	)
	(segment
		(start 133.034532 -115.282472)
		(end 133.733794 -114.583464)
		(width 0.1651)
		(layer "F.Cu")
		(net "M_L_DQ<48>")
	)
	(segment
		(start 133.733794 -114.583464)
		(end 134.012178 -114.583464)
		(width 0.1651)
		(layer "F.Cu")
		(net "M_L_DQ<48>")
	)
	(segment
		(start 135.735568 -119.7864)
		(end 135.735568 -123.241054)
		(width 0.1651)
		(layer "F.Cu")
		(net "M_L_DQ<48>")
	)
	(segment
		(start 135.124952 -126.590298)
		(end 134.821168 -126.590298)
		(width 0.1651)
		(layer "F.Cu")
		(net "M_L_DQ<48>")
	)
	(segment
		(start 119.51081 -103.524304)
		(end 119.276368 -103.758746)
		(width 0.0889)
		(layer "F.Cu")
		(net "M_L_DQ<48>")
	)
	(segment
		(start 135.949436 -147.27174)
		(end 135.949436 -147.277582)
		(width 0.1651)
		(layer "F.Cu")
		(net "M_L_DQ<48>")
	)
	(segment
		(start 134.012178 -114.583464)
		(end 134.109968 -114.681254)
		(width 0.1651)
		(layer "F.Cu")
		(net "M_L_DQ<48>")
	)
	(segment
		(start 119.276368 -103.758746)
		(end 119.276368 -105.392728)
		(width 0.0889)
		(layer "F.Cu")
		(net "M_L_DQ<48>")
	)
	(segment
		(start 119.276368 -105.392728)
		(end 119.479568 -105.595928)
		(width 0.0889)
		(layer "F.Cu")
		(net "M_L_DQ<48>")
	)
	(segment
		(start 121.577354 -107.835954)
		(end 129.892298 -107.835954)
		(width 0.1016)
		(layer "F.Cu")
		(net "M_L_DQ<48>")
	)
	(segment
		(start 134.109968 -114.681254)
		(end 134.109968 -118.1608)
		(width 0.1651)
		(layer "F.Cu")
		(net "M_L_DQ<48>")
	)
	(segment
		(start 135.735568 -123.241054)
		(end 135.297164 -123.679458)
		(width 0.1651)
		(layer "F.Cu")
		(net "M_L_DQ<48>")
	)
	(segment
		(start 135.297164 -123.679458)
		(end 135.297164 -126.418086)
		(width 0.1651)
		(layer "F.Cu")
		(net "M_L_DQ<48>")
	)
	(segment
		(start 132.756148 -115.282472)
		(end 133.034532 -115.282472)
		(width 0.1651)
		(layer "F.Cu")
		(net "M_L_DQ<48>")
	)
	(segment
		(start 119.479568 -105.595928)
		(end 119.479568 -105.738168)
		(width 0.0889)
		(layer "F.Cu")
		(net "M_L_DQ<48>")
	)
	(segment
		(start 119.070882 -101.967538)
		(end 119.51081 -102.407466)
		(width 0.0889)
		(layer "F.Cu")
		(net "M_L_DQ<48>")
	)
	(segment
		(start 119.51081 -102.407466)
		(end 119.51081 -103.524304)
		(width 0.0889)
		(layer "F.Cu")
		(net "M_L_DQ<48>")
	)
	(segment
		(start 132.281168 -110.224824)
		(end 132.281168 -111.252254)
		(width 0.1016)
		(layer "F.Cu")
		(net "M_L_DQ<48>")
	)
	(segment
		(start 132.558536 -114.806476)
		(end 132.558536 -115.08486)
		(width 0.1651)
		(layer "F.Cu")
		(net "M_L_DQ<48>")
	)
	(segment
		(start 133.779768 -113.131854)
		(end 133.779768 -113.585752)
		(width 0.1651)
		(layer "F.Cu")
		(net "M_L_DQ<48>")
	)
	(segment
		(start 132.281168 -111.252254)
		(end 132.281168 -111.633254)
		(width 0.1651)
		(layer "F.Cu")
		(net "M_L_DQ<48>")
	)
	(segment
		(start 119.479568 -105.738168)
		(end 121.577354 -107.835954)
		(width 0.1016)
		(layer "F.Cu")
		(net "M_L_DQ<48>")
	)
	(segment
		(start 135.949436 -147.277582)
		(end 135.771636 -145.415)
		(width 0.1651)
		(layer "F.Cu")
		(net "M_L_DQ<48>")
	)
	(segment
		(start 132.558536 -115.08486)
		(end 132.756148 -115.282472)
		(width 0.1651)
		(layer "F.Cu")
		(net "M_L_DQ<48>")
	)
	(segment
		(start 134.109968 -118.1608)
		(end 135.735568 -119.7864)
		(width 0.1651)
		(layer "F.Cu")
		(net "M_L_DQ<48>")
	)
	(segment
		(start 132.281168 -111.633254)
		(end 133.779768 -113.131854)
		(width 0.1651)
		(layer "F.Cu")
		(net "M_L_DQ<48>")
	)
	(via
		(at 135.771636 -145.415)
		(size 0.508)
		(drill 0.254)
		(layers "F.Cu" "B.Cu")
		(net "M_L_DQ<48>")
	)
	(via
		(at 135.099552 -141.213078)
		(size 0.508)
		(drill 0.254)
		(layers "F.Cu" "B.Cu")
		(net "M_L_DQ<48>")
	)
	(via
		(at 134.821168 -126.590298)
		(size 0.508)
		(drill 0.254)
		(layers "F.Cu" "B.Cu")
		(net "M_L_DQ<48>")
	)
	(segment
		(start 135.099552 -142.477236)
		(end 135.099552 -141.213078)
		(width 0.1651)
		(layer "B.Cu")
		(net "M_L_DQ<48>")
	)
	(segment
		(start 135.62457 -129.719578)
		(end 135.28167 -130.062478)
		(width 0.14224)
		(layer "In4.Cu")
		(net "M_L_DQ<48>")
	)
	(segment
		(start 135.099552 -126.868682)
		(end 135.099552 -128.67894)
		(width 0.14224)
		(layer "In4.Cu")
		(net "M_L_DQ<48>")
	)
	(segment
		(start 135.28167 -130.062478)
		(end 135.28167 -131.141978)
		(width 0.14224)
		(layer "In4.Cu")
		(net "M_L_DQ<48>")
	)
	(segment
		(start 134.73557 -140.849096)
		(end 135.099552 -141.213078)
		(width 0.14224)
		(layer "In4.Cu")
		(net "M_L_DQ<48>")
	)
	(segment
		(start 134.73557 -140.209778)
		(end 134.73557 -140.849096)
		(width 0.14224)
		(layer "In4.Cu")
		(net "M_L_DQ<48>")
	)
	(segment
		(start 135.532368 -134.0104)
		(end 135.57377 -134.051802)
		(width 0.14224)
		(layer "In4.Cu")
		(net "M_L_DQ<48>")
	)
	(segment
		(start 135.57377 -134.484618)
		(end 135.29437 -134.764018)
		(width 0.14224)
		(layer "In4.Cu")
		(net "M_L_DQ<48>")
	)
	(segment
		(start 135.29437 -135.956802)
		(end 135.58647 -136.248902)
		(width 0.14224)
		(layer "In4.Cu")
		(net "M_L_DQ<48>")
	)
	(segment
		(start 135.532368 -136.680702)
		(end 135.532368 -138.9634)
		(width 0.14224)
		(layer "In4.Cu")
		(net "M_L_DQ<48>")
	)
	(segment
		(start 135.532368 -138.9634)
		(end 135.58647 -139.017502)
		(width 0.14224)
		(layer "In4.Cu")
		(net "M_L_DQ<48>")
	)
	(segment
		(start 135.58647 -139.017502)
		(end 135.58647 -139.358878)
		(width 0.14224)
		(layer "In4.Cu")
		(net "M_L_DQ<48>")
	)
	(segment
		(start 135.57377 -131.9784)
		(end 135.532368 -132.019802)
		(width 0.14224)
		(layer "In4.Cu")
		(net "M_L_DQ<48>")
	)
	(segment
		(start 135.58647 -136.248902)
		(end 135.58647 -136.6266)
		(width 0.14224)
		(layer "In4.Cu")
		(net "M_L_DQ<48>")
	)
	(segment
		(start 135.28167 -131.141978)
		(end 135.57377 -131.434078)
		(width 0.14224)
		(layer "In4.Cu")
		(net "M_L_DQ<48>")
	)
	(segment
		(start 135.58647 -136.6266)
		(end 135.532368 -136.680702)
		(width 0.14224)
		(layer "In4.Cu")
		(net "M_L_DQ<48>")
	)
	(segment
		(start 135.532368 -132.019802)
		(end 135.532368 -134.0104)
		(width 0.14224)
		(layer "In4.Cu")
		(net "M_L_DQ<48>")
	)
	(segment
		(start 135.58647 -139.358878)
		(end 134.73557 -140.209778)
		(width 0.14224)
		(layer "In4.Cu")
		(net "M_L_DQ<48>")
	)
	(segment
		(start 135.57377 -131.434078)
		(end 135.57377 -131.9784)
		(width 0.14224)
		(layer "In4.Cu")
		(net "M_L_DQ<48>")
	)
	(segment
		(start 135.62457 -129.203958)
		(end 135.62457 -129.719578)
		(width 0.14224)
		(layer "In4.Cu")
		(net "M_L_DQ<48>")
	)
	(segment
		(start 135.29437 -134.764018)
		(end 135.29437 -135.956802)
		(width 0.14224)
		(layer "In4.Cu")
		(net "M_L_DQ<48>")
	)
	(segment
		(start 135.57377 -134.051802)
		(end 135.57377 -134.484618)
		(width 0.14224)
		(layer "In4.Cu")
		(net "M_L_DQ<48>")
	)
	(segment
		(start 134.821168 -126.590298)
		(end 135.099552 -126.868682)
		(width 0.14224)
		(layer "In4.Cu")
		(net "M_L_DQ<48>")
	)
	(segment
		(start 135.099552 -128.67894)
		(end 135.62457 -129.203958)
		(width 0.14224)
		(layer "In4.Cu")
		(net "M_L_DQ<48>")
	)
	(segment
		(start 135.771636 -145.415)
		(end 135.475472 -145.415)
		(width 0.14224)
		(layer "In9.Cu")
		(net "M_L_DQ<48>")
	)
	(segment
		(start 134.666482 -141.646148)
		(end 135.099552 -141.213078)
		(width 0.14224)
		(layer "In9.Cu")
		(net "M_L_DQ<48>")
	)
	(segment
		(start 135.475472 -145.415)
		(end 134.666482 -144.60601)
		(width 0.14224)
		(layer "In9.Cu")
		(net "M_L_DQ<48>")
	)
	(segment
		(start 134.666482 -144.60601)
		(end 134.666482 -141.646148)
		(width 0.14224)
		(layer "In9.Cu")
		(net "M_L_DQ<48>")
	)
	(segment
		(start 126.442216 -115.622832)
		(end 126.913132 -115.622832)
		(width 0.1651)
		(layer "F.Cu")
		(net "M_L_DQ<47>")
	)
	(segment
		(start 131.214368 -123.9012)
		(end 131.214368 -124.944378)
		(width 0.1651)
		(layer "F.Cu")
		(net "M_L_DQ<47>")
	)
	(segment
		(start 125.976126 -116.351558)
		(end 126.155958 -116.351558)
		(width 0.1651)
		(layer "F.Cu")
		(net "M_L_DQ<47>")
	)
	(segment
		(start 122.806968 -113.1824)
		(end 125.976126 -116.351558)
		(width 0.1651)
		(layer "F.Cu")
		(net "M_L_DQ<47>")
	)
	(segment
		(start 129.999486 -142.6718)
		(end 129.999486 -143.941546)
		(width 0.1651)
		(layer "F.Cu")
		(net "M_L_DQ<47>")
	)
	(segment
		(start 116.495322 -103.695754)
		(end 116.73713 -103.937562)
		(width 0.0889)
		(layer "F.Cu")
		(net "M_L_DQ<47>")
	)
	(segment
		(start 127.529844 -117.023134)
		(end 127.897636 -117.023134)
		(width 0.1651)
		(layer "F.Cu")
		(net "M_L_DQ<47>")
	)
	(segment
		(start 122.171968 -112.340644)
		(end 122.171968 -112.5474)
		(width 0.1016)
		(layer "F.Cu")
		(net "M_L_DQ<47>")
	)
	(segment
		(start 121.769124 -111.9378)
		(end 122.171968 -112.340644)
		(width 0.1016)
		(layer "F.Cu")
		(net "M_L_DQ<47>")
	)
	(segment
		(start 126.913132 -115.622832)
		(end 127.049276 -115.758976)
		(width 0.1651)
		(layer "F.Cu")
		(net "M_L_DQ<47>")
	)
	(segment
		(start 128.373632 -117.49913)
		(end 128.373632 -117.73281)
		(width 0.1651)
		(layer "F.Cu")
		(net "M_L_DQ<47>")
	)
	(segment
		(start 122.171968 -112.5474)
		(end 122.806968 -113.1824)
		(width 0.1016)
		(layer "F.Cu")
		(net "M_L_DQ<47>")
	)
	(segment
		(start 128.845056 -116.813584)
		(end 128.845056 -117.027706)
		(width 0.1651)
		(layer "F.Cu")
		(net "M_L_DQ<47>")
	)
	(segment
		(start 128.60274 -116.571268)
		(end 128.845056 -116.813584)
		(width 0.1651)
		(layer "F.Cu")
		(net "M_L_DQ<47>")
	)
	(segment
		(start 128.845056 -117.027706)
		(end 128.373632 -117.49913)
		(width 0.1651)
		(layer "F.Cu")
		(net "M_L_DQ<47>")
	)
	(segment
		(start 120.466612 -111.9378)
		(end 121.769124 -111.9378)
		(width 0.1016)
		(layer "F.Cu")
		(net "M_L_DQ<47>")
	)
	(segment
		(start 126.306326 -116.20119)
		(end 126.306326 -115.758722)
		(width 0.1651)
		(layer "F.Cu")
		(net "M_L_DQ<47>")
	)
	(segment
		(start 116.495322 -102.462584)
		(end 116.495322 -103.695754)
		(width 0.0889)
		(layer "F.Cu")
		(net "M_L_DQ<47>")
	)
	(segment
		(start 116.845588 -105.883964)
		(end 116.845588 -108.316776)
		(width 0.1016)
		(layer "F.Cu")
		(net "M_L_DQ<47>")
	)
	(segment
		(start 116.73713 -103.937562)
		(end 116.73713 -105.775506)
		(width 0.0889)
		(layer "F.Cu")
		(net "M_L_DQ<47>")
	)
	(segment
		(start 116.845588 -108.316776)
		(end 120.466612 -111.9378)
		(width 0.1016)
		(layer "F.Cu")
		(net "M_L_DQ<47>")
	)
	(segment
		(start 131.214368 -124.944378)
		(end 130.74777 -125.410976)
		(width 0.1651)
		(layer "F.Cu")
		(net "M_L_DQ<47>")
	)
	(segment
		(start 127.897636 -117.023134)
		(end 128.349502 -116.571268)
		(width 0.1651)
		(layer "F.Cu")
		(net "M_L_DQ<47>")
	)
	(segment
		(start 116.73713 -105.775506)
		(end 116.845588 -105.883964)
		(width 0.0889)
		(layer "F.Cu")
		(net "M_L_DQ<47>")
	)
	(segment
		(start 128.349502 -116.571268)
		(end 128.60274 -116.571268)
		(width 0.1651)
		(layer "F.Cu")
		(net "M_L_DQ<47>")
	)
	(segment
		(start 126.306326 -115.758722)
		(end 126.442216 -115.622832)
		(width 0.1651)
		(layer "F.Cu")
		(net "M_L_DQ<47>")
	)
	(segment
		(start 126.155958 -116.351558)
		(end 126.306326 -116.20119)
		(width 0.1651)
		(layer "F.Cu")
		(net "M_L_DQ<47>")
	)
	(segment
		(start 128.373632 -117.73281)
		(end 131.648454 -121.007632)
		(width 0.1651)
		(layer "F.Cu")
		(net "M_L_DQ<47>")
	)
	(segment
		(start 131.648454 -121.007632)
		(end 131.648454 -123.467114)
		(width 0.1651)
		(layer "F.Cu")
		(net "M_L_DQ<47>")
	)
	(segment
		(start 127.049276 -115.758976)
		(end 127.049276 -116.542566)
		(width 0.1651)
		(layer "F.Cu")
		(net "M_L_DQ<47>")
	)
	(segment
		(start 131.648454 -123.467114)
		(end 131.214368 -123.9012)
		(width 0.1651)
		(layer "F.Cu")
		(net "M_L_DQ<47>")
	)
	(segment
		(start 127.049276 -116.542566)
		(end 127.529844 -117.023134)
		(width 0.1651)
		(layer "F.Cu")
		(net "M_L_DQ<47>")
	)
	(via
		(at 130.74777 -125.410976)
		(size 0.508)
		(drill 0.254)
		(layers "F.Cu" "B.Cu")
		(net "M_L_DQ<47>")
	)
	(via
		(at 129.999486 -143.941546)
		(size 0.508)
		(drill 0.254)
		(layers "F.Cu" "B.Cu")
		(net "M_L_DQ<47>")
	)
	(via
		(at 130.84937 -139.932156)
		(size 0.508)
		(drill 0.254)
		(layers "F.Cu" "B.Cu")
		(net "M_L_DQ<47>")
	)
	(segment
		(start 130.84937 -137.877296)
		(end 130.84937 -139.932156)
		(width 0.1651)
		(layer "B.Cu")
		(net "M_L_DQ<47>")
	)
	(segment
		(start 130.160776 -141.785848)
		(end 130.443224 -141.5034)
		(width 0.14224)
		(layer "In9.Cu")
		(net "M_L_DQ<47>")
	)
	(segment
		(start 130.398774 -140.790168)
		(end 130.398774 -140.3604)
		(width 0.14224)
		(layer "In9.Cu")
		(net "M_L_DQ<47>")
	)
	(segment
		(start 130.827018 -139.932156)
		(end 130.84937 -139.932156)
		(width 0.14224)
		(layer "In9.Cu")
		(net "M_L_DQ<47>")
	)
	(segment
		(start 130.160776 -142.059152)
		(end 130.160776 -141.785848)
		(width 0.14224)
		(layer "In9.Cu")
		(net "M_L_DQ<47>")
	)
	(segment
		(start 130.449574 -143.44015)
		(end 130.160776 -143.151352)
		(width 0.14224)
		(layer "In9.Cu")
		(net "M_L_DQ<47>")
	)
	(segment
		(start 130.271774 -143.941546)
		(end 130.449574 -143.763746)
		(width 0.14224)
		(layer "In9.Cu")
		(net "M_L_DQ<47>")
	)
	(segment
		(start 130.160776 -142.878048)
		(end 130.417824 -142.621)
		(width 0.14224)
		(layer "In9.Cu")
		(net "M_L_DQ<47>")
	)
	(segment
		(start 129.999486 -143.941546)
		(end 130.271774 -143.941546)
		(width 0.14224)
		(layer "In9.Cu")
		(net "M_L_DQ<47>")
	)
	(segment
		(start 130.160776 -143.151352)
		(end 130.160776 -142.878048)
		(width 0.14224)
		(layer "In9.Cu")
		(net "M_L_DQ<47>")
	)
	(segment
		(start 130.417824 -142.3162)
		(end 130.160776 -142.059152)
		(width 0.14224)
		(layer "In9.Cu")
		(net "M_L_DQ<47>")
	)
	(segment
		(start 130.417824 -142.621)
		(end 130.417824 -142.3162)
		(width 0.14224)
		(layer "In9.Cu")
		(net "M_L_DQ<47>")
	)
	(segment
		(start 130.398774 -140.3604)
		(end 130.827018 -139.932156)
		(width 0.14224)
		(layer "In9.Cu")
		(net "M_L_DQ<47>")
	)
	(segment
		(start 130.443224 -141.5034)
		(end 130.443224 -140.834618)
		(width 0.14224)
		(layer "In9.Cu")
		(net "M_L_DQ<47>")
	)
	(segment
		(start 130.449574 -143.763746)
		(end 130.449574 -143.44015)
		(width 0.14224)
		(layer "In9.Cu")
		(net "M_L_DQ<47>")
	)
	(segment
		(start 130.443224 -140.834618)
		(end 130.398774 -140.790168)
		(width 0.14224)
		(layer "In9.Cu")
		(net "M_L_DQ<47>")
	)
	(segment
		(start 131.290568 -134.0358)
		(end 131.290568 -132.015992)
		(width 0.14224)
		(layer "In11.Cu")
		(net "M_L_DQ<47>")
	)
	(segment
		(start 131.227576 -134.098792)
		(end 131.290568 -134.0358)
		(width 0.14224)
		(layer "In11.Cu")
		(net "M_L_DQ<47>")
	)
	(segment
		(start 131.202176 -138.797792)
		(end 131.265168 -138.7348)
		(width 0.14224)
		(layer "In11.Cu")
		(net "M_L_DQ<47>")
	)
	(segment
		(start 131.430776 -130.087878)
		(end 131.202176 -129.859278)
		(width 0.14224)
		(layer "In11.Cu")
		(net "M_L_DQ<47>")
	)
	(segment
		(start 131.202176 -139.590272)
		(end 131.202176 -138.797792)
		(width 0.14224)
		(layer "In11.Cu")
		(net "M_L_DQ<47>")
	)
	(segment
		(start 130.775964 -128.92278)
		(end 130.775964 -125.43917)
		(width 0.14224)
		(layer "In11.Cu")
		(net "M_L_DQ<47>")
	)
	(segment
		(start 131.37134 -134.712202)
		(end 131.227576 -134.568438)
		(width 0.14224)
		(layer "In11.Cu")
		(net "M_L_DQ<47>")
	)
	(segment
		(start 131.227576 -134.568438)
		(end 131.227576 -134.098792)
		(width 0.14224)
		(layer "In11.Cu")
		(net "M_L_DQ<47>")
	)
	(segment
		(start 131.202176 -129.348992)
		(end 130.775964 -128.92278)
		(width 0.14224)
		(layer "In11.Cu")
		(net "M_L_DQ<47>")
	)
	(segment
		(start 131.202176 -129.859278)
		(end 131.202176 -129.348992)
		(width 0.14224)
		(layer "In11.Cu")
		(net "M_L_DQ<47>")
	)
	(segment
		(start 131.202176 -136.6012)
		(end 131.202176 -136.206738)
		(width 0.14224)
		(layer "In11.Cu")
		(net "M_L_DQ<47>")
	)
	(segment
		(start 131.191254 -139.590272)
		(end 131.202176 -139.590272)
		(width 0.14224)
		(layer "In11.Cu")
		(net "M_L_DQ<47>")
	)
	(segment
		(start 131.202176 -136.206738)
		(end 131.37134 -136.037574)
		(width 0.14224)
		(layer "In11.Cu")
		(net "M_L_DQ<47>")
	)
	(segment
		(start 130.775964 -125.43917)
		(end 130.74777 -125.410976)
		(width 0.14224)
		(layer "In11.Cu")
		(net "M_L_DQ<47>")
	)
	(segment
		(start 130.84937 -139.932156)
		(end 131.191254 -139.590272)
		(width 0.14224)
		(layer "In11.Cu")
		(net "M_L_DQ<47>")
	)
	(segment
		(start 131.151376 -131.484878)
		(end 131.430776 -131.205478)
		(width 0.14224)
		(layer "In11.Cu")
		(net "M_L_DQ<47>")
	)
	(segment
		(start 131.290568 -132.015992)
		(end 131.151376 -131.8768)
		(width 0.14224)
		(layer "In11.Cu")
		(net "M_L_DQ<47>")
	)
	(segment
		(start 131.151376 -131.8768)
		(end 131.151376 -131.484878)
		(width 0.14224)
		(layer "In11.Cu")
		(net "M_L_DQ<47>")
	)
	(segment
		(start 131.265168 -138.7348)
		(end 131.265168 -136.664192)
		(width 0.14224)
		(layer "In11.Cu")
		(net "M_L_DQ<47>")
	)
	(segment
		(start 131.430776 -131.205478)
		(end 131.430776 -130.087878)
		(width 0.14224)
		(layer "In11.Cu")
		(net "M_L_DQ<47>")
	)
	(segment
		(start 131.37134 -136.037574)
		(end 131.37134 -134.712202)
		(width 0.14224)
		(layer "In11.Cu")
		(net "M_L_DQ<47>")
	)
	(segment
		(start 131.265168 -136.664192)
		(end 131.202176 -136.6012)
		(width 0.14224)
		(layer "In11.Cu")
		(net "M_L_DQ<47>")
	)
	(segment
		(start 130.198368 -125.5014)
		(end 130.426968 -125.73)
		(width 0.1651)
		(layer "F.Cu")
		(net "M_L_DQ<46>")
	)
	(segment
		(start 130.84937 -147.27174)
		(end 130.849624 -147.27174)
		(width 0.1651)
		(layer "F.Cu")
		(net "M_L_DQ<46>")
	)
	(segment
		(start 126.858014 -117.258592)
		(end 129.976118 -120.376696)
		(width 0.1651)
		(layer "F.Cu")
		(net "M_L_DQ<46>")
	)
	(segment
		(start 130.981704 -146.17192)
		(end 130.981704 -145.95348)
		(width 0.1651)
		(layer "F.Cu")
		(net "M_L_DQ<46>")
	)
	(segment
		(start 130.973576 -121.374154)
		(end 130.973576 -123.227592)
		(width 0.1651)
		(layer "F.Cu")
		(net "M_L_DQ<46>")
	)
	(segment
		(start 120.30329 -112.3315)
		(end 121.473722 -112.3315)
		(width 0.1016)
		(layer "F.Cu")
		(net "M_L_DQ<46>")
	)
	(segment
		(start 130.426968 -125.73)
		(end 130.426968 -126.188216)
		(width 0.1651)
		(layer "F.Cu")
		(net "M_L_DQ<46>")
	)
	(segment
		(start 116.304822 -103.774748)
		(end 116.54663 -104.016556)
		(width 0.0889)
		(layer "F.Cu")
		(net "M_L_DQ<46>")
	)
	(segment
		(start 129.975864 -120.624092)
		(end 129.842514 -120.757442)
		(width 0.1651)
		(layer "F.Cu")
		(net "M_L_DQ<46>")
	)
	(segment
		(start 130.426968 -126.188216)
		(end 129.999486 -126.615698)
		(width 0.1651)
		(layer "F.Cu")
		(net "M_L_DQ<46>")
	)
	(segment
		(start 125.96876 -117.258592)
		(end 126.858014 -117.258592)
		(width 0.1651)
		(layer "F.Cu")
		(net "M_L_DQ<46>")
	)
	(segment
		(start 116.148612 -102.26294)
		(end 116.143786 -102.271576)
		(width 0.0889)
		(layer "F.Cu")
		(net "M_L_DQ<46>")
	)
	(segment
		(start 130.849624 -146.304)
		(end 130.981704 -146.17192)
		(width 0.1651)
		(layer "F.Cu")
		(net "M_L_DQ<46>")
	)
	(segment
		(start 130.32613 -121.24055)
		(end 130.459226 -121.107454)
		(width 0.1651)
		(layer "F.Cu")
		(net "M_L_DQ<46>")
	)
	(segment
		(start 130.849624 -147.27174)
		(end 130.849624 -146.304)
		(width 0.1651)
		(layer "F.Cu")
		(net "M_L_DQ<46>")
	)
	(segment
		(start 130.198368 -124.0028)
		(end 130.198368 -125.5014)
		(width 0.1651)
		(layer "F.Cu")
		(net "M_L_DQ<46>")
	)
	(segment
		(start 129.842514 -120.757442)
		(end 129.842514 -121.004838)
		(width 0.1651)
		(layer "F.Cu")
		(net "M_L_DQ<46>")
	)
	(segment
		(start 130.078226 -121.24055)
		(end 130.32613 -121.24055)
		(width 0.1651)
		(layer "F.Cu")
		(net "M_L_DQ<46>")
	)
	(segment
		(start 129.842514 -121.004838)
		(end 130.078226 -121.24055)
		(width 0.1651)
		(layer "F.Cu")
		(net "M_L_DQ<46>")
	)
	(segment
		(start 130.849624 -145.516854)
		(end 130.84937 -145.5166)
		(width 0.1651)
		(layer "F.Cu")
		(net "M_L_DQ<46>")
	)
	(segment
		(start 130.973576 -123.227592)
		(end 130.198368 -124.0028)
		(width 0.1651)
		(layer "F.Cu")
		(net "M_L_DQ<46>")
	)
	(segment
		(start 116.495322 -100.481638)
		(end 116.165376 -101.243638)
		(width 0.0889)
		(layer "F.Cu")
		(net "M_L_DQ<46>")
	)
	(segment
		(start 121.981468 -113.2713)
		(end 125.96876 -117.258592)
		(width 0.1651)
		(layer "F.Cu")
		(net "M_L_DQ<46>")
	)
	(segment
		(start 116.54663 -104.016556)
		(end 116.54663 -105.789222)
		(width 0.0889)
		(layer "F.Cu")
		(net "M_L_DQ<46>")
	)
	(segment
		(start 121.740168 -113.03)
		(end 121.981468 -113.2713)
		(width 0.1016)
		(layer "F.Cu")
		(net "M_L_DQ<46>")
	)
	(segment
		(start 116.54663 -105.789222)
		(end 116.451888 -105.883964)
		(width 0.0889)
		(layer "F.Cu")
		(net "M_L_DQ<46>")
	)
	(segment
		(start 121.473722 -112.3315)
		(end 121.740168 -112.597946)
		(width 0.1016)
		(layer "F.Cu")
		(net "M_L_DQ<46>")
	)
	(segment
		(start 130.981704 -145.95348)
		(end 130.849624 -145.8214)
		(width 0.1651)
		(layer "F.Cu")
		(net "M_L_DQ<46>")
	)
	(segment
		(start 116.148612 -101.67239)
		(end 116.154962 -101.683058)
		(width 0.0889)
		(layer "F.Cu")
		(net "M_L_DQ<46>")
	)
	(segment
		(start 116.451888 -105.883964)
		(end 116.451888 -108.480098)
		(width 0.1016)
		(layer "F.Cu")
		(net "M_L_DQ<46>")
	)
	(segment
		(start 129.976118 -120.376696)
		(end 129.975864 -120.624092)
		(width 0.1651)
		(layer "F.Cu")
		(net "M_L_DQ<46>")
	)
	(segment
		(start 116.232432 -102.97541)
		(end 116.304822 -103.0478)
		(width 0.0889)
		(layer "F.Cu")
		(net "M_L_DQ<46>")
	)
	(segment
		(start 121.740168 -112.597946)
		(end 121.740168 -113.03)
		(width 0.1016)
		(layer "F.Cu")
		(net "M_L_DQ<46>")
	)
	(segment
		(start 130.849624 -145.8214)
		(end 130.849624 -145.516854)
		(width 0.1651)
		(layer "F.Cu")
		(net "M_L_DQ<46>")
	)
	(segment
		(start 116.304822 -103.0478)
		(end 116.304822 -103.774748)
		(width 0.0889)
		(layer "F.Cu")
		(net "M_L_DQ<46>")
	)
	(segment
		(start 130.706876 -121.107454)
		(end 130.973576 -121.374154)
		(width 0.1651)
		(layer "F.Cu")
		(net "M_L_DQ<46>")
	)
	(segment
		(start 116.165376 -101.243638)
		(end 116.148612 -101.272594)
		(width 0.0889)
		(layer "F.Cu")
		(net "M_L_DQ<46>")
	)
	(segment
		(start 116.451888 -108.480098)
		(end 120.30329 -112.3315)
		(width 0.1016)
		(layer "F.Cu")
		(net "M_L_DQ<46>")
	)
	(segment
		(start 130.459226 -121.107454)
		(end 130.706876 -121.107454)
		(width 0.1651)
		(layer "F.Cu")
		(net "M_L_DQ<46>")
	)
	(via
		(at 130.84937 -145.5166)
		(size 0.508)
		(drill 0.254)
		(layers "F.Cu" "B.Cu")
		(net "M_L_DQ<46>")
	)
	(via
		(at 129.999486 -126.615698)
		(size 0.508)
		(drill 0.254)
		(layers "F.Cu" "B.Cu")
		(net "M_L_DQ<46>")
	)
	(via
		(at 129.999486 -141.213078)
		(size 0.508)
		(drill 0.254)
		(layers "F.Cu" "B.Cu")
		(net "M_L_DQ<46>")
	)
	(arc
		(start 116.143786 -102.271576)
		(mid 116.095031 -102.467928)
		(end 116.148612 -102.66299)
		(width 0.0889)
		(layer "F.Cu")
		(net "M_L_DQ<46>")
	)
	(arc
		(start 116.148612 -101.272594)
		(mid 116.095113 -101.472492)
		(end 116.148612 -101.67239)
		(width 0.0889)
		(layer "F.Cu")
		(net "M_L_DQ<46>")
	)
	(arc
		(start 116.154962 -101.683058)
		(mid 116.22776 -101.973821)
		(end 116.148612 -102.26294)
		(width 0.0889)
		(layer "F.Cu")
		(net "M_L_DQ<46>")
	)
	(arc
		(start 116.148612 -102.66299)
		(mid 116.211069 -102.813683)
		(end 116.232432 -102.97541)
		(width 0.0889)
		(layer "F.Cu")
		(net "M_L_DQ<46>")
	)
	(segment
		(start 129.999486 -142.477236)
		(end 129.999486 -141.213078)
		(width 0.1651)
		(layer "B.Cu")
		(net "M_L_DQ<46>")
	)
	(segment
		(start 129.566416 -141.646148)
		(end 129.566416 -144.233646)
		(width 0.14224)
		(layer "In9.Cu")
		(net "M_L_DQ<46>")
	)
	(segment
		(start 129.999486 -141.213078)
		(end 129.566416 -141.646148)
		(width 0.14224)
		(layer "In9.Cu")
		(net "M_L_DQ<46>")
	)
	(segment
		(start 129.566416 -144.233646)
		(end 130.84937 -145.5166)
		(width 0.14224)
		(layer "In9.Cu")
		(net "M_L_DQ<46>")
	)
	(segment
		(start 130.426968 -134.0612)
		(end 130.516376 -134.150608)
		(width 0.14224)
		(layer "In11.Cu")
		(net "M_L_DQ<46>")
	)
	(segment
		(start 130.243834 -134.79018)
		(end 130.243834 -135.932926)
		(width 0.14224)
		(layer "In11.Cu")
		(net "M_L_DQ<46>")
	)
	(segment
		(start 130.567176 -129.426208)
		(end 130.567176 -129.859278)
		(width 0.14224)
		(layer "In11.Cu")
		(net "M_L_DQ<46>")
	)
	(segment
		(start 130.426968 -136.690608)
		(end 130.426968 -138.8364)
		(width 0.14224)
		(layer "In11.Cu")
		(net "M_L_DQ<46>")
	)
	(segment
		(start 130.567176 -136.5504)
		(end 130.426968 -136.690608)
		(width 0.14224)
		(layer "In11.Cu")
		(net "M_L_DQ<46>")
	)
	(segment
		(start 130.567176 -129.859278)
		(end 130.363976 -130.062478)
		(width 0.14224)
		(layer "In11.Cu")
		(net "M_L_DQ<46>")
	)
	(segment
		(start 130.243834 -135.932926)
		(end 130.567176 -136.256268)
		(width 0.14224)
		(layer "In11.Cu")
		(net "M_L_DQ<46>")
	)
	(segment
		(start 130.115564 -128.974596)
		(end 130.567176 -129.426208)
		(width 0.14224)
		(layer "In11.Cu")
		(net "M_L_DQ<46>")
	)
	(segment
		(start 130.516376 -131.459478)
		(end 130.516376 -131.953)
		(width 0.14224)
		(layer "In11.Cu")
		(net "M_L_DQ<46>")
	)
	(segment
		(start 130.363976 -130.062478)
		(end 130.363976 -131.307078)
		(width 0.14224)
		(layer "In11.Cu")
		(net "M_L_DQ<46>")
	)
	(segment
		(start 130.567176 -136.256268)
		(end 130.567176 -136.5504)
		(width 0.14224)
		(layer "In11.Cu")
		(net "M_L_DQ<46>")
	)
	(segment
		(start 130.426968 -138.8364)
		(end 130.567176 -138.976608)
		(width 0.14224)
		(layer "In11.Cu")
		(net "M_L_DQ<46>")
	)
	(segment
		(start 130.115564 -126.731776)
		(end 130.115564 -128.974596)
		(width 0.14224)
		(layer "In11.Cu")
		(net "M_L_DQ<46>")
	)
	(segment
		(start 130.567176 -138.976608)
		(end 130.567176 -139.333478)
		(width 0.14224)
		(layer "In11.Cu")
		(net "M_L_DQ<46>")
	)
	(segment
		(start 130.426968 -132.042408)
		(end 130.426968 -134.0612)
		(width 0.14224)
		(layer "In11.Cu")
		(net "M_L_DQ<46>")
	)
	(segment
		(start 129.830576 -140.070078)
		(end 129.830576 -141.044168)
		(width 0.14224)
		(layer "In11.Cu")
		(net "M_L_DQ<46>")
	)
	(segment
		(start 130.516376 -134.517638)
		(end 130.243834 -134.79018)
		(width 0.14224)
		(layer "In11.Cu")
		(net "M_L_DQ<46>")
	)
	(segment
		(start 130.363976 -131.307078)
		(end 130.516376 -131.459478)
		(width 0.14224)
		(layer "In11.Cu")
		(net "M_L_DQ<46>")
	)
	(segment
		(start 129.999486 -126.615698)
		(end 130.115564 -126.731776)
		(width 0.14224)
		(layer "In11.Cu")
		(net "M_L_DQ<46>")
	)
	(segment
		(start 129.830576 -141.044168)
		(end 129.999486 -141.213078)
		(width 0.14224)
		(layer "In11.Cu")
		(net "M_L_DQ<46>")
	)
	(segment
		(start 130.516376 -131.953)
		(end 130.426968 -132.042408)
		(width 0.14224)
		(layer "In11.Cu")
		(net "M_L_DQ<46>")
	)
	(segment
		(start 130.516376 -134.150608)
		(end 130.516376 -134.517638)
		(width 0.14224)
		(layer "In11.Cu")
		(net "M_L_DQ<46>")
	)
	(segment
		(start 130.567176 -139.333478)
		(end 129.830576 -140.070078)
		(width 0.14224)
		(layer "In11.Cu")
		(net "M_L_DQ<46>")
	)
	(segment
		(start 113.594388 -105.77322)
		(end 113.695988 -105.87482)
		(width 0.0889)
		(layer "F.Cu")
		(net "M_L_DQ<45>")
	)
	(segment
		(start 121.137426 -119.310658)
		(end 121.137426 -120.06453)
		(width 0.1651)
		(layer "F.Cu")
		(net "M_L_DQ<45>")
	)
	(segment
		(start 118.0592 -116.790216)
		(end 118.221252 -116.628164)
		(width 0.1651)
		(layer "F.Cu")
		(net "M_L_DQ<45>")
	)
	(segment
		(start 122.123708 -121.050812)
		(end 122.366024 -121.293128)
		(width 0.1651)
		(layer "F.Cu")
		(net "M_L_DQ<45>")
	)
	(segment
		(start 113.695988 -109.62386)
		(end 117.091968 -113.01984)
		(width 0.1016)
		(layer "F.Cu")
		(net "M_L_DQ<45>")
	)
	(segment
		(start 113.573052 -101.76764)
		(end 113.568226 -101.776276)
		(width 0.0889)
		(layer "F.Cu")
		(net "M_L_DQ<45>")
	)
	(segment
		(start 113.571528 -102.765098)
		(end 113.157254 -103.474012)
		(width 0.0889)
		(layer "F.Cu")
		(net "M_L_DQ<45>")
	)
	(segment
		(start 123.108212 -121.916444)
		(end 123.404376 -122.212608)
		(width 0.1651)
		(layer "F.Cu")
		(net "M_L_DQ<45>")
	)
	(segment
		(start 123.25223 -121.592594)
		(end 123.108212 -121.736612)
		(width 0.1651)
		(layer "F.Cu")
		(net "M_L_DQ<45>")
	)
	(segment
		(start 117.091968 -114.3762)
		(end 117.193568 -114.4778)
		(width 0.1651)
		(layer "F.Cu")
		(net "M_L_DQ<45>")
	)
	(segment
		(start 122.300238 -120.640602)
		(end 122.123708 -120.817132)
		(width 0.1651)
		(layer "F.Cu")
		(net "M_L_DQ<45>")
	)
	(segment
		(start 125.229874 -123.103894)
		(end 124.82322 -123.510548)
		(width 0.1651)
		(layer "F.Cu")
		(net "M_L_DQ<45>")
	)
	(segment
		(start 121.414032 -120.341136)
		(end 121.647712 -120.341136)
		(width 0.1651)
		(layer "F.Cu")
		(net "M_L_DQ<45>")
	)
	(segment
		(start 122.123708 -120.817132)
		(end 122.123708 -121.050812)
		(width 0.1651)
		(layer "F.Cu")
		(net "M_L_DQ<45>")
	)
	(segment
		(start 117.583204 -116.5479)
		(end 117.82552 -116.790216)
		(width 0.1651)
		(layer "F.Cu")
		(net "M_L_DQ<45>")
	)
	(segment
		(start 117.193568 -114.4778)
		(end 117.193568 -115.3668)
		(width 0.1651)
		(layer "F.Cu")
		(net "M_L_DQ<45>")
	)
	(segment
		(start 119.173244 -117.580156)
		(end 119.406924 -117.580156)
		(width 0.1651)
		(layer "F.Cu")
		(net "M_L_DQ<45>")
	)
	(segment
		(start 113.695988 -105.87482)
		(end 113.695988 -109.62386)
		(width 0.1016)
		(layer "F.Cu")
		(net "M_L_DQ<45>")
	)
	(segment
		(start 121.137426 -120.06453)
		(end 121.414032 -120.341136)
		(width 0.1651)
		(layer "F.Cu")
		(net "M_L_DQ<45>")
	)
	(segment
		(start 118.697248 -116.87048)
		(end 118.697248 -117.10416)
		(width 0.1651)
		(layer "F.Cu")
		(net "M_L_DQ<45>")
	)
	(segment
		(start 118.454932 -116.628164)
		(end 118.697248 -116.87048)
		(width 0.1651)
		(layer "F.Cu")
		(net "M_L_DQ<45>")
	)
	(segment
		(start 118.535196 -117.266212)
		(end 118.535196 -117.499892)
		(width 0.1651)
		(layer "F.Cu")
		(net "M_L_DQ<45>")
	)
	(segment
		(start 117.583204 -116.31422)
		(end 117.583204 -116.5479)
		(width 0.1651)
		(layer "F.Cu")
		(net "M_L_DQ<45>")
	)
	(segment
		(start 122.300238 -120.406922)
		(end 122.300238 -120.640602)
		(width 0.1651)
		(layer "F.Cu")
		(net "M_L_DQ<45>")
	)
	(segment
		(start 117.745256 -116.152168)
		(end 117.583204 -116.31422)
		(width 0.1651)
		(layer "F.Cu")
		(net "M_L_DQ<45>")
	)
	(segment
		(start 117.745256 -115.918488)
		(end 117.745256 -116.152168)
		(width 0.1651)
		(layer "F.Cu")
		(net "M_L_DQ<45>")
	)
	(segment
		(start 117.82552 -116.790216)
		(end 118.0592 -116.790216)
		(width 0.1651)
		(layer "F.Cu")
		(net "M_L_DQ<45>")
	)
	(segment
		(start 123.009914 -121.116598)
		(end 123.25223 -121.358914)
		(width 0.1651)
		(layer "F.Cu")
		(net "M_L_DQ<45>")
	)
	(segment
		(start 123.404376 -122.212608)
		(end 123.584208 -122.212608)
		(width 0.1651)
		(layer "F.Cu")
		(net "M_L_DQ<45>")
	)
	(segment
		(start 118.221252 -116.628164)
		(end 118.454932 -116.628164)
		(width 0.1651)
		(layer "F.Cu")
		(net "M_L_DQ<45>")
	)
	(segment
		(start 118.535196 -117.499892)
		(end 118.777512 -117.742208)
		(width 0.1651)
		(layer "F.Cu")
		(net "M_L_DQ<45>")
	)
	(segment
		(start 117.091968 -113.01984)
		(end 117.091968 -114.3762)
		(width 0.1016)
		(layer "F.Cu")
		(net "M_L_DQ<45>")
	)
	(segment
		(start 124.049536 -142.6718)
		(end 124.049536 -143.941546)
		(width 0.1651)
		(layer "F.Cu")
		(net "M_L_DQ<45>")
	)
	(segment
		(start 124.156216 -121.6406)
		(end 124.584968 -121.6406)
		(width 0.1651)
		(layer "F.Cu")
		(net "M_L_DQ<45>")
	)
	(segment
		(start 122.057922 -120.164606)
		(end 122.300238 -120.406922)
		(width 0.1651)
		(layer "F.Cu")
		(net "M_L_DQ<45>")
	)
	(segment
		(start 113.157254 -103.474012)
		(end 113.157254 -103.761286)
		(width 0.0889)
		(layer "F.Cu")
		(net "M_L_DQ<45>")
	)
	(segment
		(start 118.777512 -117.742208)
		(end 119.011192 -117.742208)
		(width 0.1651)
		(layer "F.Cu")
		(net "M_L_DQ<45>")
	)
	(segment
		(start 113.157254 -103.761286)
		(end 113.594388 -104.19842)
		(width 0.0889)
		(layer "F.Cu")
		(net "M_L_DQ<45>")
	)
	(segment
		(start 119.011192 -117.742208)
		(end 119.173244 -117.580156)
		(width 0.1651)
		(layer "F.Cu")
		(net "M_L_DQ<45>")
	)
	(segment
		(start 123.25223 -121.358914)
		(end 123.25223 -121.592594)
		(width 0.1651)
		(layer "F.Cu")
		(net "M_L_DQ<45>")
	)
	(segment
		(start 113.594388 -104.19842)
		(end 113.594388 -105.77322)
		(width 0.0889)
		(layer "F.Cu")
		(net "M_L_DQ<45>")
	)
	(segment
		(start 122.776234 -121.116598)
		(end 123.009914 -121.116598)
		(width 0.1651)
		(layer "F.Cu")
		(net "M_L_DQ<45>")
	)
	(segment
		(start 122.599704 -121.293128)
		(end 122.776234 -121.116598)
		(width 0.1651)
		(layer "F.Cu")
		(net "M_L_DQ<45>")
	)
	(segment
		(start 118.697248 -117.10416)
		(end 118.535196 -117.266212)
		(width 0.1651)
		(layer "F.Cu")
		(net "M_L_DQ<45>")
	)
	(segment
		(start 119.406924 -117.580156)
		(end 121.137426 -119.310658)
		(width 0.1651)
		(layer "F.Cu")
		(net "M_L_DQ<45>")
	)
	(segment
		(start 125.229874 -122.285506)
		(end 125.229874 -123.103894)
		(width 0.1651)
		(layer "F.Cu")
		(net "M_L_DQ<45>")
	)
	(segment
		(start 117.193568 -115.3668)
		(end 117.745256 -115.918488)
		(width 0.1651)
		(layer "F.Cu")
		(net "M_L_DQ<45>")
	)
	(segment
		(start 122.366024 -121.293128)
		(end 122.599704 -121.293128)
		(width 0.1651)
		(layer "F.Cu")
		(net "M_L_DQ<45>")
	)
	(segment
		(start 121.647712 -120.341136)
		(end 121.824242 -120.164606)
		(width 0.1651)
		(layer "F.Cu")
		(net "M_L_DQ<45>")
	)
	(segment
		(start 123.108212 -121.736612)
		(end 123.108212 -121.916444)
		(width 0.1651)
		(layer "F.Cu")
		(net "M_L_DQ<45>")
	)
	(segment
		(start 124.82322 -123.510548)
		(end 124.82322 -124.750576)
		(width 0.1651)
		(layer "F.Cu")
		(net "M_L_DQ<45>")
	)
	(segment
		(start 124.584968 -121.6406)
		(end 125.229874 -122.285506)
		(width 0.1651)
		(layer "F.Cu")
		(net "M_L_DQ<45>")
	)
	(segment
		(start 123.584208 -122.212608)
		(end 124.156216 -121.6406)
		(width 0.1651)
		(layer "F.Cu")
		(net "M_L_DQ<45>")
	)
	(segment
		(start 121.824242 -120.164606)
		(end 122.057922 -120.164606)
		(width 0.1651)
		(layer "F.Cu")
		(net "M_L_DQ<45>")
	)
	(via
		(at 124.049536 -143.941546)
		(size 0.508)
		(drill 0.254)
		(layers "F.Cu" "B.Cu")
		(net "M_L_DQ<45>")
	)
	(via
		(at 124.82322 -124.750576)
		(size 0.508)
		(drill 0.254)
		(layers "F.Cu" "B.Cu")
		(net "M_L_DQ<45>")
	)
	(via
		(at 124.82322 -139.932156)
		(size 0.508)
		(drill 0.254)
		(layers "F.Cu" "B.Cu")
		(net "M_L_DQ<45>")
	)
	(arc
		(start 113.573052 -102.16769)
		(mid 113.652789 -102.466605)
		(end 113.571528 -102.765098)
		(width 0.0889)
		(layer "F.Cu")
		(net "M_L_DQ<45>")
	)
	(arc
		(start 113.919762 -100.976684)
		(mid 113.765505 -101.380534)
		(end 113.573052 -101.76764)
		(width 0.0889)
		(layer "F.Cu")
		(net "M_L_DQ<45>")
	)
	(arc
		(start 113.568226 -101.776276)
		(mid 113.519471 -101.972628)
		(end 113.573052 -102.16769)
		(width 0.0889)
		(layer "F.Cu")
		(net "M_L_DQ<45>")
	)
	(segment
		(start 124.89942 -139.855956)
		(end 124.82322 -139.932156)
		(width 0.1651)
		(layer "B.Cu")
		(net "M_L_DQ<45>")
	)
	(segment
		(start 124.89942 -137.877296)
		(end 124.89942 -139.855956)
		(width 0.1651)
		(layer "B.Cu")
		(net "M_L_DQ<45>")
	)
	(segment
		(start 124.474224 -143.789146)
		(end 124.474224 -143.561054)
		(width 0.14224)
		(layer "In9.Cu")
		(net "M_L_DQ<45>")
	)
	(segment
		(start 124.321824 -143.941546)
		(end 124.474224 -143.789146)
		(width 0.14224)
		(layer "In9.Cu")
		(net "M_L_DQ<45>")
	)
	(segment
		(start 124.372624 -140.9192)
		(end 124.372624 -140.3604)
		(width 0.14224)
		(layer "In9.Cu")
		(net "M_L_DQ<45>")
	)
	(segment
		(start 124.800868 -139.932156)
		(end 124.82322 -139.932156)
		(width 0.14224)
		(layer "In9.Cu")
		(net "M_L_DQ<45>")
	)
	(segment
		(start 124.448824 -142.747746)
		(end 124.448824 -142.392654)
		(width 0.14224)
		(layer "In9.Cu")
		(net "M_L_DQ<45>")
	)
	(segment
		(start 124.499624 -141.0462)
		(end 124.372624 -140.9192)
		(width 0.14224)
		(layer "In9.Cu")
		(net "M_L_DQ<45>")
	)
	(segment
		(start 124.210826 -142.985744)
		(end 124.448824 -142.747746)
		(width 0.14224)
		(layer "In9.Cu")
		(net "M_L_DQ<45>")
	)
	(segment
		(start 124.049536 -143.941546)
		(end 124.321824 -143.941546)
		(width 0.14224)
		(layer "In9.Cu")
		(net "M_L_DQ<45>")
	)
	(segment
		(start 124.372624 -140.3604)
		(end 124.800868 -139.932156)
		(width 0.14224)
		(layer "In9.Cu")
		(net "M_L_DQ<45>")
	)
	(segment
		(start 124.499624 -141.528546)
		(end 124.499624 -141.0462)
		(width 0.14224)
		(layer "In9.Cu")
		(net "M_L_DQ<45>")
	)
	(segment
		(start 124.448824 -142.392654)
		(end 124.210826 -142.154656)
		(width 0.14224)
		(layer "In9.Cu")
		(net "M_L_DQ<45>")
	)
	(segment
		(start 124.210826 -143.297656)
		(end 124.210826 -142.985744)
		(width 0.14224)
		(layer "In9.Cu")
		(net "M_L_DQ<45>")
	)
	(segment
		(start 124.210826 -141.817344)
		(end 124.499624 -141.528546)
		(width 0.14224)
		(layer "In9.Cu")
		(net "M_L_DQ<45>")
	)
	(segment
		(start 124.474224 -143.561054)
		(end 124.210826 -143.297656)
		(width 0.14224)
		(layer "In9.Cu")
		(net "M_L_DQ<45>")
	)
	(segment
		(start 124.210826 -142.154656)
		(end 124.210826 -141.817344)
		(width 0.14224)
		(layer "In9.Cu")
		(net "M_L_DQ<45>")
	)
	(segment
		(start 125.360176 -134.797038)
		(end 125.233176 -134.670038)
		(width 0.14224)
		(layer "In11.Cu")
		(net "M_L_DQ<45>")
	)
	(segment
		(start 125.233176 -134.670038)
		(end 125.233176 -134.149592)
		(width 0.14224)
		(layer "In11.Cu")
		(net "M_L_DQ<45>")
	)
	(segment
		(start 125.289564 -125.21692)
		(end 124.82322 -124.750576)
		(width 0.14224)
		(layer "In11.Cu")
		(net "M_L_DQ<45>")
	)
	(segment
		(start 125.207776 -138.823192)
		(end 125.321568 -138.7094)
		(width 0.14224)
		(layer "In11.Cu")
		(net "M_L_DQ<45>")
	)
	(segment
		(start 125.207776 -136.005824)
		(end 125.360176 -135.853424)
		(width 0.14224)
		(layer "In11.Cu")
		(net "M_L_DQ<45>")
	)
	(segment
		(start 125.321568 -131.939792)
		(end 125.233176 -131.8514)
		(width 0.14224)
		(layer "In11.Cu")
		(net "M_L_DQ<45>")
	)
	(segment
		(start 125.296676 -129.795778)
		(end 125.207776 -129.706878)
		(width 0.14224)
		(layer "In11.Cu")
		(net "M_L_DQ<45>")
	)
	(segment
		(start 125.233176 -131.434078)
		(end 125.296676 -131.370578)
		(width 0.14224)
		(layer "In11.Cu")
		(net "M_L_DQ<45>")
	)
	(segment
		(start 125.321568 -134.0612)
		(end 125.321568 -131.939792)
		(width 0.14224)
		(layer "In11.Cu")
		(net "M_L_DQ<45>")
	)
	(segment
		(start 125.360176 -135.853424)
		(end 125.360176 -134.797038)
		(width 0.14224)
		(layer "In11.Cu")
		(net "M_L_DQ<45>")
	)
	(segment
		(start 125.289564 -125.558804)
		(end 125.289564 -125.21692)
		(width 0.14224)
		(layer "In11.Cu")
		(net "M_L_DQ<45>")
	)
	(segment
		(start 125.207776 -129.706878)
		(end 125.207776 -126.90602)
		(width 0.14224)
		(layer "In11.Cu")
		(net "M_L_DQ<45>")
	)
	(segment
		(start 125.296676 -131.370578)
		(end 125.296676 -129.795778)
		(width 0.14224)
		(layer "In11.Cu")
		(net "M_L_DQ<45>")
	)
	(segment
		(start 125.063758 -126.762002)
		(end 125.063758 -125.78461)
		(width 0.14224)
		(layer "In11.Cu")
		(net "M_L_DQ<45>")
	)
	(segment
		(start 125.063758 -125.78461)
		(end 125.289564 -125.558804)
		(width 0.14224)
		(layer "In11.Cu")
		(net "M_L_DQ<45>")
	)
	(segment
		(start 125.321568 -138.7094)
		(end 125.321568 -136.664192)
		(width 0.14224)
		(layer "In11.Cu")
		(net "M_L_DQ<45>")
	)
	(segment
		(start 125.207776 -136.5504)
		(end 125.207776 -136.005824)
		(width 0.14224)
		(layer "In11.Cu")
		(net "M_L_DQ<45>")
	)
	(segment
		(start 125.233176 -131.8514)
		(end 125.233176 -131.434078)
		(width 0.14224)
		(layer "In11.Cu")
		(net "M_L_DQ<45>")
	)
	(segment
		(start 125.207776 -126.90602)
		(end 125.063758 -126.762002)
		(width 0.14224)
		(layer "In11.Cu")
		(net "M_L_DQ<45>")
	)
	(segment
		(start 125.321568 -136.664192)
		(end 125.207776 -136.5504)
		(width 0.14224)
		(layer "In11.Cu")
		(net "M_L_DQ<45>")
	)
	(segment
		(start 125.207776 -139.5476)
		(end 125.207776 -138.823192)
		(width 0.14224)
		(layer "In11.Cu")
		(net "M_L_DQ<45>")
	)
	(segment
		(start 124.82322 -139.932156)
		(end 125.207776 -139.5476)
		(width 0.14224)
		(layer "In11.Cu")
		(net "M_L_DQ<45>")
	)
	(segment
		(start 125.233176 -134.149592)
		(end 125.321568 -134.0612)
		(width 0.14224)
		(layer "In11.Cu")
		(net "M_L_DQ<45>")
	)
	(segment
		(start 113.403888 -104.287574)
		(end 113.403888 -105.77068)
		(width 0.0889)
		(layer "F.Cu")
		(net "M_L_DQ<44>")
	)
	(segment
		(start 120.493536 -119.846344)
		(end 120.34647 -119.99341)
		(width 0.1651)
		(layer "F.Cu")
		(net "M_L_DQ<44>")
	)
	(segment
		(start 120.34647 -119.99341)
		(end 120.34647 -120.22709)
		(width 0.1651)
		(layer "F.Cu")
		(net "M_L_DQ<44>")
	)
	(segment
		(start 119.065548 -118.418356)
		(end 119.299228 -118.418356)
		(width 0.1651)
		(layer "F.Cu")
		(net "M_L_DQ<44>")
	)
	(segment
		(start 124.89942 -145.946368)
		(end 124.801376 -145.415)
		(width 0.1651)
		(layer "F.Cu")
		(net "M_L_DQ<44>")
	)
	(segment
		(start 120.25122 -119.370348)
		(end 120.493536 -119.612664)
		(width 0.1651)
		(layer "F.Cu")
		(net "M_L_DQ<44>")
	)
	(segment
		(start 119.860568 -119.52732)
		(end 120.01754 -119.370348)
		(width 0.1651)
		(layer "F.Cu")
		(net "M_L_DQ<44>")
	)
	(segment
		(start 118.684802 -118.565422)
		(end 118.918482 -118.565422)
		(width 0.1651)
		(layer "F.Cu")
		(net "M_L_DQ<44>")
	)
	(segment
		(start 120.34647 -120.22709)
		(end 123.08078 -122.9614)
		(width 0.1651)
		(layer "F.Cu")
		(net "M_L_DQ<44>")
	)
	(segment
		(start 124.356368 -125.603)
		(end 124.508768 -125.7554)
		(width 0.1651)
		(layer "F.Cu")
		(net "M_L_DQ<44>")
	)
	(segment
		(start 119.384572 -119.051324)
		(end 119.384572 -119.285004)
		(width 0.1651)
		(layer "F.Cu")
		(net "M_L_DQ<44>")
	)
	(segment
		(start 124.89942 -147.27174)
		(end 124.89942 -145.946368)
		(width 0.1651)
		(layer "F.Cu")
		(net "M_L_DQ<44>")
	)
	(segment
		(start 113.410746 -102.662228)
		(end 112.966754 -103.423212)
		(width 0.0889)
		(layer "F.Cu")
		(net "M_L_DQ<44>")
	)
	(segment
		(start 119.626888 -119.52732)
		(end 119.860568 -119.52732)
		(width 0.1651)
		(layer "F.Cu")
		(net "M_L_DQ<44>")
	)
	(segment
		(start 124.508768 -126.156466)
		(end 124.049536 -126.615698)
		(width 0.1651)
		(layer "F.Cu")
		(net "M_L_DQ<44>")
	)
	(segment
		(start 116.431568 -116.312188)
		(end 118.684802 -118.565422)
		(width 0.1651)
		(layer "F.Cu")
		(net "M_L_DQ<44>")
	)
	(segment
		(start 120.01754 -119.370348)
		(end 120.25122 -119.370348)
		(width 0.1651)
		(layer "F.Cu")
		(net "M_L_DQ<44>")
	)
	(segment
		(start 116.431568 -114.6556)
		(end 116.431568 -116.312188)
		(width 0.1651)
		(layer "F.Cu")
		(net "M_L_DQ<44>")
	)
	(segment
		(start 116.634768 -114.4524)
		(end 116.431568 -114.6556)
		(width 0.1016)
		(layer "F.Cu")
		(net "M_L_DQ<44>")
	)
	(segment
		(start 124.178568 -124.9934)
		(end 124.356368 -125.1712)
		(width 0.1651)
		(layer "F.Cu")
		(net "M_L_DQ<44>")
	)
	(segment
		(start 119.541544 -118.894352)
		(end 119.384572 -119.051324)
		(width 0.1651)
		(layer "F.Cu")
		(net "M_L_DQ<44>")
	)
	(segment
		(start 113.302288 -105.87228)
		(end 113.302288 -109.787182)
		(width 0.1016)
		(layer "F.Cu")
		(net "M_L_DQ<44>")
	)
	(segment
		(start 112.966754 -103.423212)
		(end 112.966754 -103.85044)
		(width 0.0889)
		(layer "F.Cu")
		(net "M_L_DQ<44>")
	)
	(segment
		(start 124.178568 -123.1646)
		(end 124.178568 -124.9934)
		(width 0.1651)
		(layer "F.Cu")
		(net "M_L_DQ<44>")
	)
	(segment
		(start 116.634768 -113.119662)
		(end 116.634768 -114.4524)
		(width 0.1016)
		(layer "F.Cu")
		(net "M_L_DQ<44>")
	)
	(segment
		(start 118.918482 -118.565422)
		(end 119.065548 -118.418356)
		(width 0.1651)
		(layer "F.Cu")
		(net "M_L_DQ<44>")
	)
	(segment
		(start 119.299228 -118.418356)
		(end 119.541544 -118.660672)
		(width 0.1651)
		(layer "F.Cu")
		(net "M_L_DQ<44>")
	)
	(segment
		(start 112.966754 -103.85044)
		(end 113.403888 -104.287574)
		(width 0.0889)
		(layer "F.Cu")
		(net "M_L_DQ<44>")
	)
	(segment
		(start 120.493536 -119.612664)
		(end 120.493536 -119.846344)
		(width 0.1651)
		(layer "F.Cu")
		(net "M_L_DQ<44>")
	)
	(segment
		(start 113.302288 -109.787182)
		(end 116.634768 -113.119662)
		(width 0.1016)
		(layer "F.Cu")
		(net "M_L_DQ<44>")
	)
	(segment
		(start 113.403888 -105.77068)
		(end 113.302288 -105.87228)
		(width 0.0889)
		(layer "F.Cu")
		(net "M_L_DQ<44>")
	)
	(segment
		(start 124.356368 -125.1712)
		(end 124.356368 -125.603)
		(width 0.1651)
		(layer "F.Cu")
		(net "M_L_DQ<44>")
	)
	(segment
		(start 123.975368 -122.9614)
		(end 124.178568 -123.1646)
		(width 0.1651)
		(layer "F.Cu")
		(net "M_L_DQ<44>")
	)
	(segment
		(start 124.508768 -125.7554)
		(end 124.508768 -126.156466)
		(width 0.1651)
		(layer "F.Cu")
		(net "M_L_DQ<44>")
	)
	(segment
		(start 119.541544 -118.660672)
		(end 119.541544 -118.894352)
		(width 0.1651)
		(layer "F.Cu")
		(net "M_L_DQ<44>")
	)
	(segment
		(start 119.384572 -119.285004)
		(end 119.626888 -119.52732)
		(width 0.1651)
		(layer "F.Cu")
		(net "M_L_DQ<44>")
	)
	(segment
		(start 123.08078 -122.9614)
		(end 123.975368 -122.9614)
		(width 0.1651)
		(layer "F.Cu")
		(net "M_L_DQ<44>")
	)
	(via
		(at 124.049536 -126.615698)
		(size 0.508)
		(drill 0.254)
		(layers "F.Cu" "B.Cu")
		(net "M_L_DQ<44>")
	)
	(via
		(at 124.049536 -141.213078)
		(size 0.508)
		(drill 0.254)
		(layers "F.Cu" "B.Cu")
		(net "M_L_DQ<44>")
	)
	(via
		(at 124.801376 -145.415)
		(size 0.508)
		(drill 0.254)
		(layers "F.Cu" "B.Cu")
		(net "M_L_DQ<44>")
	)
	(arc
		(start 113.520474 -101.002084)
		(mid 113.502918 -101.343612)
		(end 113.407952 -101.672136)
		(width 0.0889)
		(layer "F.Cu")
		(net "M_L_DQ<44>")
	)
	(arc
		(start 113.407952 -102.26294)
		(mid 113.462107 -102.462225)
		(end 113.410746 -102.662228)
		(width 0.0889)
		(layer "F.Cu")
		(net "M_L_DQ<44>")
	)
	(arc
		(start 113.908586 -100.576634)
		(mid 113.714736 -100.632984)
		(end 113.573052 -100.776786)
		(width 0.0889)
		(layer "F.Cu")
		(net "M_L_DQ<44>")
	)
	(arc
		(start 113.573052 -100.776786)
		(mid 113.552102 -100.818625)
		(end 113.536222 -100.862638)
		(width 0.0889)
		(layer "F.Cu")
		(net "M_L_DQ<44>")
	)
	(arc
		(start 113.536222 -100.862638)
		(mid 113.522166 -100.931665)
		(end 113.520474 -101.002084)
		(width 0.0889)
		(layer "F.Cu")
		(net "M_L_DQ<44>")
	)
	(arc
		(start 113.407952 -101.672136)
		(mid 113.328821 -101.967538)
		(end 113.407952 -102.26294)
		(width 0.0889)
		(layer "F.Cu")
		(net "M_L_DQ<44>")
	)
	(arc
		(start 114.778282 -100.481638)
		(mid 114.345355 -100.546721)
		(end 113.908586 -100.576634)
		(width 0.0889)
		(layer "F.Cu")
		(net "M_L_DQ<44>")
	)
	(segment
		(start 124.049536 -142.477236)
		(end 124.049536 -141.213078)
		(width 0.1651)
		(layer "B.Cu")
		(net "M_L_DQ<44>")
	)
	(segment
		(start 123.774454 -144.337278)
		(end 123.774454 -144.63903)
		(width 0.14224)
		(layer "In9.Cu")
		(net "M_L_DQ<44>")
	)
	(segment
		(start 123.616466 -144.17929)
		(end 123.774454 -144.337278)
		(width 0.14224)
		(layer "In9.Cu")
		(net "M_L_DQ<44>")
	)
	(segment
		(start 123.774454 -144.63903)
		(end 124.550424 -145.415)
		(width 0.14224)
		(layer "In9.Cu")
		(net "M_L_DQ<44>")
	)
	(segment
		(start 124.049536 -141.213078)
		(end 123.616466 -141.646148)
		(width 0.14224)
		(layer "In9.Cu")
		(net "M_L_DQ<44>")
	)
	(segment
		(start 123.616466 -141.646148)
		(end 123.616466 -144.17929)
		(width 0.14224)
		(layer "In9.Cu")
		(net "M_L_DQ<44>")
	)
	(segment
		(start 124.550424 -145.415)
		(end 124.801376 -145.415)
		(width 0.14224)
		(layer "In9.Cu")
		(net "M_L_DQ<44>")
	)
	(segment
		(start 124.318776 -129.986278)
		(end 124.318776 -131.180078)
		(width 0.14224)
		(layer "In11.Cu")
		(net "M_L_DQ<44>")
	)
	(segment
		(start 124.547376 -131.9784)
		(end 124.483368 -132.042408)
		(width 0.14224)
		(layer "In11.Cu")
		(net "M_L_DQ<44>")
	)
	(segment
		(start 124.572776 -129.732278)
		(end 124.318776 -129.986278)
		(width 0.14224)
		(layer "In11.Cu")
		(net "M_L_DQ<44>")
	)
	(segment
		(start 124.534676 -139.493244)
		(end 124.04852 -139.9794)
		(width 0.14224)
		(layer "In11.Cu")
		(net "M_L_DQ<44>")
	)
	(segment
		(start 124.534676 -138.836908)
		(end 124.534676 -139.493244)
		(width 0.14224)
		(layer "In11.Cu")
		(net "M_L_DQ<44>")
	)
	(segment
		(start 124.281184 -135.926576)
		(end 124.534676 -136.180068)
		(width 0.14224)
		(layer "In11.Cu")
		(net "M_L_DQ<44>")
	)
	(segment
		(start 124.483368 -129.209546)
		(end 124.572776 -129.298954)
		(width 0.14224)
		(layer "In11.Cu")
		(net "M_L_DQ<44>")
	)
	(segment
		(start 124.281184 -134.746238)
		(end 124.281184 -135.926576)
		(width 0.14224)
		(layer "In11.Cu")
		(net "M_L_DQ<44>")
	)
	(segment
		(start 124.483368 -138.7856)
		(end 124.534676 -138.836908)
		(width 0.14224)
		(layer "In11.Cu")
		(net "M_L_DQ<44>")
	)
	(segment
		(start 124.483368 -134.112)
		(end 124.547376 -134.176008)
		(width 0.14224)
		(layer "In11.Cu")
		(net "M_L_DQ<44>")
	)
	(segment
		(start 124.547376 -131.408678)
		(end 124.547376 -131.9784)
		(width 0.14224)
		(layer "In11.Cu")
		(net "M_L_DQ<44>")
	)
	(segment
		(start 124.483368 -132.042408)
		(end 124.483368 -134.112)
		(width 0.14224)
		(layer "In11.Cu")
		(net "M_L_DQ<44>")
	)
	(segment
		(start 124.04852 -141.212062)
		(end 124.049536 -141.213078)
		(width 0.1016)
		(layer "In11.Cu")
		(net "M_L_DQ<44>")
	)
	(segment
		(start 124.547376 -134.480046)
		(end 124.281184 -134.746238)
		(width 0.14224)
		(layer "In11.Cu")
		(net "M_L_DQ<44>")
	)
	(segment
		(start 124.534676 -136.6012)
		(end 124.483368 -136.652508)
		(width 0.14224)
		(layer "In11.Cu")
		(net "M_L_DQ<44>")
	)
	(segment
		(start 124.534676 -136.180068)
		(end 124.534676 -136.6012)
		(width 0.14224)
		(layer "In11.Cu")
		(net "M_L_DQ<44>")
	)
	(segment
		(start 124.049536 -126.615698)
		(end 124.483368 -127.04953)
		(width 0.14224)
		(layer "In11.Cu")
		(net "M_L_DQ<44>")
	)
	(segment
		(start 124.04852 -139.9794)
		(end 124.04852 -141.212062)
		(width 0.1016)
		(layer "In11.Cu")
		(net "M_L_DQ<44>")
	)
	(segment
		(start 124.483368 -136.652508)
		(end 124.483368 -138.7856)
		(width 0.14224)
		(layer "In11.Cu")
		(net "M_L_DQ<44>")
	)
	(segment
		(start 124.572776 -129.298954)
		(end 124.572776 -129.732278)
		(width 0.14224)
		(layer "In11.Cu")
		(net "M_L_DQ<44>")
	)
	(segment
		(start 124.547376 -134.176008)
		(end 124.547376 -134.480046)
		(width 0.14224)
		(layer "In11.Cu")
		(net "M_L_DQ<44>")
	)
	(segment
		(start 124.483368 -127.04953)
		(end 124.483368 -129.209546)
		(width 0.14224)
		(layer "In11.Cu")
		(net "M_L_DQ<44>")
	)
	(segment
		(start 124.318776 -131.180078)
		(end 124.547376 -131.408678)
		(width 0.14224)
		(layer "In11.Cu")
		(net "M_L_DQ<44>")
	)
	(segment
		(start 127.485902 -114.327432)
		(end 128.438402 -115.279932)
		(width 0.1651)
		(layer "F.Cu")
		(net "M_L_DQ<43>")
	)
	(segment
		(start 130.174238 -117.675152)
		(end 132.941568 -120.442482)
		(width 0.1651)
		(layer "F.Cu")
		(net "M_L_DQ<43>")
	)
	(segment
		(start 130.174238 -115.984528)
		(end 130.174238 -116.370862)
		(width 0.1651)
		(layer "F.Cu")
		(net "M_L_DQ<43>")
	)
	(segment
		(start 116.974112 -103.27894)
		(end 117.531388 -103.836216)
		(width 0.0889)
		(layer "F.Cu")
		(net "M_L_DQ<43>")
	)
	(segment
		(start 132.814568 -124.968)
		(end 132.346192 -125.436376)
		(width 0.1651)
		(layer "F.Cu")
		(net "M_L_DQ<43>")
	)
	(segment
		(start 116.974112 -102.88143)
		(end 116.974112 -103.27894)
		(width 0.0889)
		(layer "F.Cu")
		(net "M_L_DQ<43>")
	)
	(segment
		(start 120.793256 -111.1504)
		(end 122.095768 -111.1504)
		(width 0.1016)
		(layer "F.Cu")
		(net "M_L_DQ<43>")
	)
	(segment
		(start 130.899154 -117.209062)
		(end 130.339338 -117.209062)
		(width 0.1651)
		(layer "F.Cu")
		(net "M_L_DQ<43>")
	)
	(segment
		(start 131.064254 -117.043962)
		(end 130.899154 -117.209062)
		(width 0.1651)
		(layer "F.Cu")
		(net "M_L_DQ<43>")
	)
	(segment
		(start 128.438402 -115.279932)
		(end 129.469642 -115.279932)
		(width 0.1651)
		(layer "F.Cu")
		(net "M_L_DQ<43>")
	)
	(segment
		(start 123.848368 -112.1918)
		(end 125.984 -114.327432)
		(width 0.1651)
		(layer "F.Cu")
		(net "M_L_DQ<43>")
	)
	(segment
		(start 123.137168 -112.1918)
		(end 123.848368 -112.1918)
		(width 0.1016)
		(layer "F.Cu")
		(net "M_L_DQ<43>")
	)
	(segment
		(start 132.814568 -124.1552)
		(end 132.814568 -124.968)
		(width 0.1651)
		(layer "F.Cu")
		(net "M_L_DQ<43>")
	)
	(segment
		(start 130.174238 -117.374162)
		(end 130.174238 -117.675152)
		(width 0.1651)
		(layer "F.Cu")
		(net "M_L_DQ<43>")
	)
	(segment
		(start 117.353842 -101.967538)
		(end 117.04066 -102.690168)
		(width 0.0889)
		(layer "F.Cu")
		(net "M_L_DQ<43>")
	)
	(segment
		(start 130.339338 -116.535962)
		(end 130.899154 -116.535962)
		(width 0.1651)
		(layer "F.Cu")
		(net "M_L_DQ<43>")
	)
	(segment
		(start 131.064254 -116.701062)
		(end 131.064254 -117.043962)
		(width 0.1651)
		(layer "F.Cu")
		(net "M_L_DQ<43>")
	)
	(segment
		(start 130.339338 -117.209062)
		(end 130.174238 -117.374162)
		(width 0.1651)
		(layer "F.Cu")
		(net "M_L_DQ<43>")
	)
	(segment
		(start 129.469642 -115.279932)
		(end 130.174238 -115.984528)
		(width 0.1651)
		(layer "F.Cu")
		(net "M_L_DQ<43>")
	)
	(segment
		(start 132.941568 -120.442482)
		(end 132.941568 -124.0282)
		(width 0.1651)
		(layer "F.Cu")
		(net "M_L_DQ<43>")
	)
	(segment
		(start 130.899154 -116.535962)
		(end 131.064254 -116.701062)
		(width 0.1651)
		(layer "F.Cu")
		(net "M_L_DQ<43>")
	)
	(segment
		(start 117.632988 -107.990132)
		(end 120.793256 -111.1504)
		(width 0.1016)
		(layer "F.Cu")
		(net "M_L_DQ<43>")
	)
	(segment
		(start 130.174238 -116.370862)
		(end 130.339338 -116.535962)
		(width 0.1651)
		(layer "F.Cu")
		(net "M_L_DQ<43>")
	)
	(segment
		(start 117.632988 -105.87228)
		(end 117.632988 -107.990132)
		(width 0.1016)
		(layer "F.Cu")
		(net "M_L_DQ<43>")
	)
	(segment
		(start 117.531388 -103.836216)
		(end 117.531388 -105.77068)
		(width 0.0889)
		(layer "F.Cu")
		(net "M_L_DQ<43>")
	)
	(segment
		(start 131.699508 -142.6718)
		(end 131.699508 -143.941546)
		(width 0.1651)
		(layer "F.Cu")
		(net "M_L_DQ<43>")
	)
	(segment
		(start 117.531388 -105.77068)
		(end 117.632988 -105.87228)
		(width 0.0889)
		(layer "F.Cu")
		(net "M_L_DQ<43>")
	)
	(segment
		(start 122.095768 -111.1504)
		(end 123.137168 -112.1918)
		(width 0.1016)
		(layer "F.Cu")
		(net "M_L_DQ<43>")
	)
	(segment
		(start 132.941568 -124.0282)
		(end 132.814568 -124.1552)
		(width 0.1651)
		(layer "F.Cu")
		(net "M_L_DQ<43>")
	)
	(segment
		(start 125.984 -114.327432)
		(end 127.485902 -114.327432)
		(width 0.1651)
		(layer "F.Cu")
		(net "M_L_DQ<43>")
	)
	(via
		(at 131.699508 -143.941546)
		(size 0.508)
		(drill 0.254)
		(layers "F.Cu" "B.Cu")
		(net "M_L_DQ<43>")
	)
	(via
		(at 132.346192 -125.436376)
		(size 0.508)
		(drill 0.254)
		(layers "F.Cu" "B.Cu")
		(net "M_L_DQ<43>")
	)
	(via
		(at 132.549392 -139.932156)
		(size 0.508)
		(drill 0.254)
		(layers "F.Cu" "B.Cu")
		(net "M_L_DQ<43>")
	)
	(arc
		(start 117.007132 -102.757986)
		(mid 116.982473 -102.817532)
		(end 116.974112 -102.88143)
		(width 0.0889)
		(layer "F.Cu")
		(net "M_L_DQ<43>")
	)
	(arc
		(start 117.04066 -102.690168)
		(mid 117.024974 -102.724609)
		(end 117.007132 -102.757986)
		(width 0.0889)
		(layer "F.Cu")
		(net "M_L_DQ<43>")
	)
	(segment
		(start 132.549392 -137.877296)
		(end 132.549392 -139.932156)
		(width 0.1651)
		(layer "B.Cu")
		(net "M_L_DQ<43>")
	)
	(segment
		(start 131.860798 -141.785848)
		(end 132.143246 -141.5034)
		(width 0.14224)
		(layer "In9.Cu")
		(net "M_L_DQ<43>")
	)
	(segment
		(start 132.149596 -143.44015)
		(end 131.860798 -143.151352)
		(width 0.14224)
		(layer "In9.Cu")
		(net "M_L_DQ<43>")
	)
	(segment
		(start 131.971796 -143.941546)
		(end 132.149596 -143.763746)
		(width 0.14224)
		(layer "In9.Cu")
		(net "M_L_DQ<43>")
	)
	(segment
		(start 132.143246 -141.5034)
		(end 132.143246 -140.834618)
		(width 0.14224)
		(layer "In9.Cu")
		(net "M_L_DQ<43>")
	)
	(segment
		(start 131.860798 -142.059152)
		(end 131.860798 -141.785848)
		(width 0.14224)
		(layer "In9.Cu")
		(net "M_L_DQ<43>")
	)
	(segment
		(start 132.098796 -140.3604)
		(end 132.52704 -139.932156)
		(width 0.14224)
		(layer "In9.Cu")
		(net "M_L_DQ<43>")
	)
	(segment
		(start 132.117846 -142.621)
		(end 132.117846 -142.3162)
		(width 0.14224)
		(layer "In9.Cu")
		(net "M_L_DQ<43>")
	)
	(segment
		(start 131.699508 -143.941546)
		(end 131.971796 -143.941546)
		(width 0.14224)
		(layer "In9.Cu")
		(net "M_L_DQ<43>")
	)
	(segment
		(start 131.860798 -142.878048)
		(end 132.117846 -142.621)
		(width 0.14224)
		(layer "In9.Cu")
		(net "M_L_DQ<43>")
	)
	(segment
		(start 131.860798 -143.151352)
		(end 131.860798 -142.878048)
		(width 0.14224)
		(layer "In9.Cu")
		(net "M_L_DQ<43>")
	)
	(segment
		(start 132.098796 -140.790168)
		(end 132.098796 -140.3604)
		(width 0.14224)
		(layer "In9.Cu")
		(net "M_L_DQ<43>")
	)
	(segment
		(start 132.143246 -140.834618)
		(end 132.098796 -140.790168)
		(width 0.14224)
		(layer "In9.Cu")
		(net "M_L_DQ<43>")
	)
	(segment
		(start 132.149596 -143.763746)
		(end 132.149596 -143.44015)
		(width 0.14224)
		(layer "In9.Cu")
		(net "M_L_DQ<43>")
	)
	(segment
		(start 132.52704 -139.932156)
		(end 132.549392 -139.932156)
		(width 0.14224)
		(layer "In9.Cu")
		(net "M_L_DQ<43>")
	)
	(segment
		(start 132.117846 -142.3162)
		(end 131.860798 -142.059152)
		(width 0.14224)
		(layer "In9.Cu")
		(net "M_L_DQ<43>")
	)
	(segment
		(start 132.916676 -131.9022)
		(end 132.966968 -131.952492)
		(width 0.14224)
		(layer "In11.Cu")
		(net "M_L_DQ<43>")
	)
	(segment
		(start 132.966968 -136.638792)
		(end 132.966968 -138.6586)
		(width 0.14224)
		(layer "In11.Cu")
		(net "M_L_DQ<43>")
	)
	(segment
		(start 132.903976 -129.374392)
		(end 132.903976 -129.960878)
		(width 0.14224)
		(layer "In11.Cu")
		(net "M_L_DQ<43>")
	)
	(segment
		(start 132.966968 -138.6586)
		(end 132.878576 -138.746992)
		(width 0.14224)
		(layer "In11.Cu")
		(net "M_L_DQ<43>")
	)
	(segment
		(start 133.132576 -135.978392)
		(end 132.878576 -136.232392)
		(width 0.14224)
		(layer "In11.Cu")
		(net "M_L_DQ<43>")
	)
	(segment
		(start 132.878576 -136.232392)
		(end 132.878576 -136.5504)
		(width 0.14224)
		(layer "In11.Cu")
		(net "M_L_DQ<43>")
	)
	(segment
		(start 132.903976 -129.960878)
		(end 133.056376 -130.113278)
		(width 0.14224)
		(layer "In11.Cu")
		(net "M_L_DQ<43>")
	)
	(segment
		(start 132.346192 -127.369824)
		(end 132.992368 -128.016)
		(width 0.14224)
		(layer "In11.Cu")
		(net "M_L_DQ<43>")
	)
	(segment
		(start 132.966968 -134.0612)
		(end 132.916676 -134.111492)
		(width 0.14224)
		(layer "In11.Cu")
		(net "M_L_DQ<43>")
	)
	(segment
		(start 132.878576 -138.746992)
		(end 132.878576 -139.61618)
		(width 0.14224)
		(layer "In11.Cu")
		(net "M_L_DQ<43>")
	)
	(segment
		(start 132.549392 -139.945364)
		(end 132.549392 -139.932156)
		(width 0.14224)
		(layer "In11.Cu")
		(net "M_L_DQ<43>")
	)
	(segment
		(start 133.132576 -134.797038)
		(end 133.132576 -135.978392)
		(width 0.14224)
		(layer "In11.Cu")
		(net "M_L_DQ<43>")
	)
	(segment
		(start 132.992368 -129.286)
		(end 132.903976 -129.374392)
		(width 0.14224)
		(layer "In11.Cu")
		(net "M_L_DQ<43>")
	)
	(segment
		(start 132.346192 -125.436376)
		(end 132.346192 -127.369824)
		(width 0.14224)
		(layer "In11.Cu")
		(net "M_L_DQ<43>")
	)
	(segment
		(start 132.878576 -139.61618)
		(end 132.549392 -139.945364)
		(width 0.14224)
		(layer "In11.Cu")
		(net "M_L_DQ<43>")
	)
	(segment
		(start 133.056376 -131.268978)
		(end 132.916676 -131.408678)
		(width 0.14224)
		(layer "In11.Cu")
		(net "M_L_DQ<43>")
	)
	(segment
		(start 132.916676 -134.111492)
		(end 132.916676 -134.581138)
		(width 0.14224)
		(layer "In11.Cu")
		(net "M_L_DQ<43>")
	)
	(segment
		(start 132.966968 -131.952492)
		(end 132.966968 -134.0612)
		(width 0.14224)
		(layer "In11.Cu")
		(net "M_L_DQ<43>")
	)
	(segment
		(start 133.056376 -130.113278)
		(end 133.056376 -131.268978)
		(width 0.14224)
		(layer "In11.Cu")
		(net "M_L_DQ<43>")
	)
	(segment
		(start 132.916676 -134.581138)
		(end 133.132576 -134.797038)
		(width 0.14224)
		(layer "In11.Cu")
		(net "M_L_DQ<43>")
	)
	(segment
		(start 132.878576 -136.5504)
		(end 132.966968 -136.638792)
		(width 0.14224)
		(layer "In11.Cu")
		(net "M_L_DQ<43>")
	)
	(segment
		(start 132.916676 -131.408678)
		(end 132.916676 -131.9022)
		(width 0.14224)
		(layer "In11.Cu")
		(net "M_L_DQ<43>")
	)
	(segment
		(start 132.992368 -128.016)
		(end 132.992368 -129.286)
		(width 0.14224)
		(layer "In11.Cu")
		(net "M_L_DQ<43>")
	)
	(segment
		(start 116.783612 -103.357934)
		(end 117.340888 -103.91521)
		(width 0.0889)
		(layer "F.Cu")
		(net "M_L_DQ<42>")
	)
	(segment
		(start 132.680964 -145.92554)
		(end 132.549392 -145.793968)
		(width 0.1651)
		(layer "F.Cu")
		(net "M_L_DQ<42>")
	)
	(segment
		(start 117.239288 -108.153454)
		(end 120.629934 -111.5441)
		(width 0.1016)
		(layer "F.Cu")
		(net "M_L_DQ<42>")
	)
	(segment
		(start 116.783612 -102.880668)
		(end 116.783612 -103.357934)
		(width 0.0889)
		(layer "F.Cu")
		(net "M_L_DQ<42>")
	)
	(segment
		(start 132.680964 -146.14906)
		(end 132.680964 -145.92554)
		(width 0.1651)
		(layer "F.Cu")
		(net "M_L_DQ<42>")
	)
	(segment
		(start 120.629934 -111.5441)
		(end 121.932446 -111.5441)
		(width 0.1016)
		(layer "F.Cu")
		(net "M_L_DQ<42>")
	)
	(segment
		(start 116.835682 -102.252018)
		(end 116.842032 -102.262686)
		(width 0.0889)
		(layer "F.Cu")
		(net "M_L_DQ<42>")
	)
	(segment
		(start 132.549392 -146.280632)
		(end 132.680964 -146.14906)
		(width 0.1651)
		(layer "F.Cu")
		(net "M_L_DQ<42>")
	)
	(segment
		(start 121.932446 -111.5441)
		(end 123.037346 -112.649)
		(width 0.1016)
		(layer "F.Cu")
		(net "M_L_DQ<42>")
	)
	(segment
		(start 131.874768 -125.603)
		(end 132.001768 -125.73)
		(width 0.1651)
		(layer "F.Cu")
		(net "M_L_DQ<42>")
	)
	(segment
		(start 131.874768 -124.1552)
		(end 131.874768 -125.603)
		(width 0.1651)
		(layer "F.Cu")
		(net "M_L_DQ<42>")
	)
	(segment
		(start 128.16332 -115.92052)
		(end 128.86817 -115.92052)
		(width 0.1651)
		(layer "F.Cu")
		(net "M_L_DQ<42>")
	)
	(segment
		(start 117.239288 -105.87228)
		(end 117.239288 -108.153454)
		(width 0.1016)
		(layer "F.Cu")
		(net "M_L_DQ<42>")
	)
	(segment
		(start 132.549392 -145.793968)
		(end 132.549392 -145.5166)
		(width 0.1651)
		(layer "F.Cu")
		(net "M_L_DQ<42>")
	)
	(segment
		(start 132.549392 -147.27174)
		(end 132.549392 -146.280632)
		(width 0.1651)
		(layer "F.Cu")
		(net "M_L_DQ<42>")
	)
	(segment
		(start 132.001768 -125.73)
		(end 132.001768 -126.161038)
		(width 0.1651)
		(layer "F.Cu")
		(net "M_L_DQ<42>")
	)
	(segment
		(start 123.391168 -112.649)
		(end 125.725174 -114.983006)
		(width 0.1651)
		(layer "F.Cu")
		(net "M_L_DQ<42>")
	)
	(segment
		(start 117.340888 -103.91521)
		(end 117.340888 -105.77068)
		(width 0.0889)
		(layer "F.Cu")
		(net "M_L_DQ<42>")
	)
	(segment
		(start 127.225806 -114.983006)
		(end 128.16332 -115.92052)
		(width 0.1651)
		(layer "F.Cu")
		(net "M_L_DQ<42>")
	)
	(segment
		(start 129.520696 -116.573046)
		(end 129.520696 -117.93093)
		(width 0.1651)
		(layer "F.Cu")
		(net "M_L_DQ<42>")
	)
	(segment
		(start 128.86817 -115.92052)
		(end 129.520696 -116.573046)
		(width 0.1651)
		(layer "F.Cu")
		(net "M_L_DQ<42>")
	)
	(segment
		(start 125.725174 -114.983006)
		(end 127.225806 -114.983006)
		(width 0.1651)
		(layer "F.Cu")
		(net "M_L_DQ<42>")
	)
	(segment
		(start 132.291328 -120.701562)
		(end 132.291328 -123.73864)
		(width 0.1651)
		(layer "F.Cu")
		(net "M_L_DQ<42>")
	)
	(segment
		(start 117.353842 -100.976684)
		(end 116.824506 -101.704394)
		(width 0.0889)
		(layer "F.Cu")
		(net "M_L_DQ<42>")
	)
	(segment
		(start 123.037346 -112.649)
		(end 123.391168 -112.649)
		(width 0.1016)
		(layer "F.Cu")
		(net "M_L_DQ<42>")
	)
	(segment
		(start 117.340888 -105.77068)
		(end 117.239288 -105.87228)
		(width 0.0889)
		(layer "F.Cu")
		(net "M_L_DQ<42>")
	)
	(segment
		(start 116.842032 -102.262686)
		(end 116.846858 -102.271322)
		(width 0.0889)
		(layer "F.Cu")
		(net "M_L_DQ<42>")
	)
	(segment
		(start 132.291328 -123.73864)
		(end 131.874768 -124.1552)
		(width 0.1651)
		(layer "F.Cu")
		(net "M_L_DQ<42>")
	)
	(segment
		(start 132.001768 -126.161038)
		(end 131.547108 -126.615698)
		(width 0.1651)
		(layer "F.Cu")
		(net "M_L_DQ<42>")
	)
	(segment
		(start 129.520696 -117.93093)
		(end 132.291328 -120.701562)
		(width 0.1651)
		(layer "F.Cu")
		(net "M_L_DQ<42>")
	)
	(via
		(at 132.549392 -145.5166)
		(size 0.508)
		(drill 0.254)
		(layers "F.Cu" "B.Cu")
		(net "M_L_DQ<42>")
	)
	(via
		(at 131.699508 -141.213078)
		(size 0.508)
		(drill 0.254)
		(layers "F.Cu" "B.Cu")
		(net "M_L_DQ<42>")
	)
	(via
		(at 131.547108 -126.615698)
		(size 0.508)
		(drill 0.254)
		(layers "F.Cu" "B.Cu")
		(net "M_L_DQ<42>")
	)
	(arc
		(start 116.824506 -101.704394)
		(mid 116.762829 -101.979581)
		(end 116.835682 -102.252018)
		(width 0.0889)
		(layer "F.Cu")
		(net "M_L_DQ<42>")
	)
	(arc
		(start 116.846858 -102.271322)
		(mid 116.895613 -102.467674)
		(end 116.842032 -102.662736)
		(width 0.0889)
		(layer "F.Cu")
		(net "M_L_DQ<42>")
	)
	(arc
		(start 116.842032 -102.662736)
		(mid 116.798487 -102.767858)
		(end 116.783612 -102.880668)
		(width 0.0889)
		(layer "F.Cu")
		(net "M_L_DQ<42>")
	)
	(segment
		(start 131.699508 -142.477236)
		(end 131.699508 -141.213078)
		(width 0.1651)
		(layer "B.Cu")
		(net "M_L_DQ<42>")
	)
	(segment
		(start 131.699508 -141.213078)
		(end 131.266438 -141.646148)
		(width 0.14224)
		(layer "In9.Cu")
		(net "M_L_DQ<42>")
	)
	(segment
		(start 131.266438 -141.646148)
		(end 131.266438 -144.233646)
		(width 0.14224)
		(layer "In9.Cu")
		(net "M_L_DQ<42>")
	)
	(segment
		(start 131.266438 -144.233646)
		(end 132.549392 -145.5166)
		(width 0.14224)
		(layer "In9.Cu")
		(net "M_L_DQ<42>")
	)
	(segment
		(start 132.192776 -129.833878)
		(end 132.065776 -129.960878)
		(width 0.14224)
		(layer "In11.Cu")
		(net "M_L_DQ<42>")
	)
	(segment
		(start 131.547108 -128.679194)
		(end 132.192776 -129.324862)
		(width 0.14224)
		(layer "In11.Cu")
		(net "M_L_DQ<42>")
	)
	(segment
		(start 132.268976 -131.535678)
		(end 132.268976 -131.8768)
		(width 0.14224)
		(layer "In11.Cu")
		(net "M_L_DQ<42>")
	)
	(segment
		(start 132.128768 -136.665208)
		(end 132.128768 -138.7348)
		(width 0.14224)
		(layer "In11.Cu")
		(net "M_L_DQ<42>")
	)
	(segment
		(start 132.065776 -129.960878)
		(end 132.065776 -131.332478)
		(width 0.14224)
		(layer "In11.Cu")
		(net "M_L_DQ<42>")
	)
	(segment
		(start 132.128768 -132.017008)
		(end 132.128768 -134.0612)
		(width 0.14224)
		(layer "In11.Cu")
		(net "M_L_DQ<42>")
	)
	(segment
		(start 131.989576 -134.771638)
		(end 131.989576 -135.976868)
		(width 0.14224)
		(layer "In11.Cu")
		(net "M_L_DQ<42>")
	)
	(segment
		(start 131.354576 -140.235178)
		(end 131.354576 -140.868146)
		(width 0.14224)
		(layer "In11.Cu")
		(net "M_L_DQ<42>")
	)
	(segment
		(start 132.218176 -136.5758)
		(end 132.128768 -136.665208)
		(width 0.14224)
		(layer "In11.Cu")
		(net "M_L_DQ<42>")
	)
	(segment
		(start 132.268976 -134.492238)
		(end 131.989576 -134.771638)
		(width 0.14224)
		(layer "In11.Cu")
		(net "M_L_DQ<42>")
	)
	(segment
		(start 132.128768 -138.7348)
		(end 132.218176 -138.824208)
		(width 0.14224)
		(layer "In11.Cu")
		(net "M_L_DQ<42>")
	)
	(segment
		(start 132.065776 -131.332478)
		(end 132.268976 -131.535678)
		(width 0.14224)
		(layer "In11.Cu")
		(net "M_L_DQ<42>")
	)
	(segment
		(start 132.128768 -134.0612)
		(end 132.268976 -134.201408)
		(width 0.14224)
		(layer "In11.Cu")
		(net "M_L_DQ<42>")
	)
	(segment
		(start 132.218176 -138.824208)
		(end 132.218176 -139.371578)
		(width 0.14224)
		(layer "In11.Cu")
		(net "M_L_DQ<42>")
	)
	(segment
		(start 132.218176 -139.371578)
		(end 131.354576 -140.235178)
		(width 0.14224)
		(layer "In11.Cu")
		(net "M_L_DQ<42>")
	)
	(segment
		(start 132.192776 -129.324862)
		(end 132.192776 -129.833878)
		(width 0.14224)
		(layer "In11.Cu")
		(net "M_L_DQ<42>")
	)
	(segment
		(start 132.268976 -131.8768)
		(end 132.128768 -132.017008)
		(width 0.14224)
		(layer "In11.Cu")
		(net "M_L_DQ<42>")
	)
	(segment
		(start 131.354576 -140.868146)
		(end 131.699508 -141.213078)
		(width 0.14224)
		(layer "In11.Cu")
		(net "M_L_DQ<42>")
	)
	(segment
		(start 132.218176 -136.205468)
		(end 132.218176 -136.5758)
		(width 0.14224)
		(layer "In11.Cu")
		(net "M_L_DQ<42>")
	)
	(segment
		(start 131.547108 -126.615698)
		(end 131.547108 -128.679194)
		(width 0.14224)
		(layer "In11.Cu")
		(net "M_L_DQ<42>")
	)
	(segment
		(start 131.989576 -135.976868)
		(end 132.218176 -136.205468)
		(width 0.14224)
		(layer "In11.Cu")
		(net "M_L_DQ<42>")
	)
	(segment
		(start 132.268976 -134.201408)
		(end 132.268976 -134.492238)
		(width 0.14224)
		(layer "In11.Cu")
		(net "M_L_DQ<42>")
	)
	(segment
		(start 126.870968 -122.019568)
		(end 126.870968 -123.165616)
		(width 0.1651)
		(layer "F.Cu")
		(net "M_L_DQ<41>")
	)
	(segment
		(start 121.580656 -116.805456)
		(end 121.77776 -117.00256)
		(width 0.1651)
		(layer "F.Cu")
		(net "M_L_DQ<41>")
	)
	(segment
		(start 123.681744 -118.906544)
		(end 123.681744 -119.185436)
		(width 0.1651)
		(layer "F.Cu")
		(net "M_L_DQ<41>")
	)
	(segment
		(start 126.599442 -124.687076)
		(end 126.421642 -124.687076)
		(width 0.1651)
		(layer "F.Cu")
		(net "M_L_DQ<41>")
	)
	(segment
		(start 121.77776 -117.281452)
		(end 121.547636 -117.511576)
		(width 0.1651)
		(layer "F.Cu")
		(net "M_L_DQ<41>")
	)
	(segment
		(start 124.865384 -120.013984)
		(end 126.870968 -122.019568)
		(width 0.1651)
		(layer "F.Cu")
		(net "M_L_DQ<41>")
	)
	(segment
		(start 127.080518 -124.206)
		(end 126.599442 -124.687076)
		(width 0.1651)
		(layer "F.Cu")
		(net "M_L_DQ<41>")
	)
	(segment
		(start 121.07164 -117.03558)
		(end 121.301764 -116.805456)
		(width 0.1651)
		(layer "F.Cu")
		(net "M_L_DQ<41>")
	)
	(segment
		(start 124.15774 -119.661432)
		(end 124.436632 -119.661432)
		(width 0.1651)
		(layer "F.Cu")
		(net "M_L_DQ<41>")
	)
	(segment
		(start 114.431572 -102.662736)
		(end 114.578384 -102.917498)
		(width 0.0889)
		(layer "F.Cu")
		(net "M_L_DQ<41>")
	)
	(segment
		(start 118.412768 -113.226596)
		(end 118.412768 -113.8174)
		(width 0.1016)
		(layer "F.Cu")
		(net "M_L_DQ<41>")
	)
	(segment
		(start 118.717568 -114.1222)
		(end 118.717568 -114.935)
		(width 0.1651)
		(layer "F.Cu")
		(net "M_L_DQ<41>")
	)
	(segment
		(start 114.578384 -103.542084)
		(end 114.381788 -103.73868)
		(width 0.0889)
		(layer "F.Cu")
		(net "M_L_DQ<41>")
	)
	(segment
		(start 122.729752 -117.954552)
		(end 122.729752 -118.233444)
		(width 0.1651)
		(layer "F.Cu")
		(net "M_L_DQ<41>")
	)
	(segment
		(start 122.499628 -118.74246)
		(end 122.696732 -118.939564)
		(width 0.1651)
		(layer "F.Cu")
		(net "M_L_DQ<41>")
	)
	(segment
		(start 123.45162 -119.41556)
		(end 123.45162 -119.694452)
		(width 0.1651)
		(layer "F.Cu")
		(net "M_L_DQ<41>")
	)
	(segment
		(start 120.792748 -117.03558)
		(end 121.07164 -117.03558)
		(width 0.1651)
		(layer "F.Cu")
		(net "M_L_DQ<41>")
	)
	(segment
		(start 122.023632 -117.987572)
		(end 122.253756 -117.757448)
		(width 0.1651)
		(layer "F.Cu")
		(net "M_L_DQ<41>")
	)
	(segment
		(start 121.547636 -117.511576)
		(end 121.547636 -117.790468)
		(width 0.1651)
		(layer "F.Cu")
		(net "M_L_DQ<41>")
	)
	(segment
		(start 123.45162 -119.694452)
		(end 123.648724 -119.891556)
		(width 0.1651)
		(layer "F.Cu")
		(net "M_L_DQ<41>")
	)
	(segment
		(start 118.717568 -114.935)
		(end 119.327168 -115.5446)
		(width 0.1651)
		(layer "F.Cu")
		(net "M_L_DQ<41>")
	)
	(segment
		(start 124.436632 -119.661432)
		(end 124.789184 -120.013984)
		(width 0.1651)
		(layer "F.Cu")
		(net "M_L_DQ<41>")
	)
	(segment
		(start 114.381788 -103.73868)
		(end 114.381788 -105.782364)
		(width 0.0889)
		(layer "F.Cu")
		(net "M_L_DQ<41>")
	)
	(segment
		(start 123.681744 -119.185436)
		(end 123.45162 -119.41556)
		(width 0.1651)
		(layer "F.Cu")
		(net "M_L_DQ<41>")
	)
	(segment
		(start 124.789184 -120.013984)
		(end 124.865384 -120.013984)
		(width 0.1651)
		(layer "F.Cu")
		(net "M_L_DQ<41>")
	)
	(segment
		(start 121.301764 -116.805456)
		(end 121.580656 -116.805456)
		(width 0.1651)
		(layer "F.Cu")
		(net "M_L_DQ<41>")
	)
	(segment
		(start 122.499628 -118.463568)
		(end 122.499628 -118.74246)
		(width 0.1651)
		(layer "F.Cu")
		(net "M_L_DQ<41>")
	)
	(segment
		(start 122.253756 -117.757448)
		(end 122.532648 -117.757448)
		(width 0.1651)
		(layer "F.Cu")
		(net "M_L_DQ<41>")
	)
	(segment
		(start 120.825768 -116.32946)
		(end 120.595644 -116.559584)
		(width 0.1651)
		(layer "F.Cu")
		(net "M_L_DQ<41>")
	)
	(segment
		(start 125.749558 -142.6718)
		(end 125.749558 -143.941546)
		(width 0.1651)
		(layer "F.Cu")
		(net "M_L_DQ<41>")
	)
	(segment
		(start 114.491008 -102.296976)
		(end 114.40414 -102.320344)
		(width 0.0889)
		(layer "F.Cu")
		(net "M_L_DQ<41>")
	)
	(segment
		(start 123.648724 -119.891556)
		(end 123.927616 -119.891556)
		(width 0.1651)
		(layer "F.Cu")
		(net "M_L_DQ<41>")
	)
	(segment
		(start 123.927616 -119.891556)
		(end 124.15774 -119.661432)
		(width 0.1651)
		(layer "F.Cu")
		(net "M_L_DQ<41>")
	)
	(segment
		(start 121.77776 -117.00256)
		(end 121.77776 -117.281452)
		(width 0.1651)
		(layer "F.Cu")
		(net "M_L_DQ<41>")
	)
	(segment
		(start 122.729752 -118.233444)
		(end 122.499628 -118.463568)
		(width 0.1651)
		(layer "F.Cu")
		(net "M_L_DQ<41>")
	)
	(segment
		(start 122.532648 -117.757448)
		(end 122.729752 -117.954552)
		(width 0.1651)
		(layer "F.Cu")
		(net "M_L_DQ<41>")
	)
	(segment
		(start 120.595644 -116.838476)
		(end 120.792748 -117.03558)
		(width 0.1651)
		(layer "F.Cu")
		(net "M_L_DQ<41>")
	)
	(segment
		(start 126.870968 -123.165616)
		(end 127.080518 -123.375166)
		(width 0.1651)
		(layer "F.Cu")
		(net "M_L_DQ<41>")
	)
	(segment
		(start 114.778282 -102.462584)
		(end 114.491008 -102.296976)
		(width 0.0889)
		(layer "F.Cu")
		(net "M_L_DQ<41>")
	)
	(segment
		(start 120.3198 -115.5446)
		(end 120.825768 -116.050568)
		(width 0.1651)
		(layer "F.Cu")
		(net "M_L_DQ<41>")
	)
	(segment
		(start 120.595644 -116.559584)
		(end 120.595644 -116.838476)
		(width 0.1651)
		(layer "F.Cu")
		(net "M_L_DQ<41>")
	)
	(segment
		(start 114.381788 -105.782364)
		(end 114.483388 -105.883964)
		(width 0.0889)
		(layer "F.Cu")
		(net "M_L_DQ<41>")
	)
	(segment
		(start 122.696732 -118.939564)
		(end 122.975624 -118.939564)
		(width 0.1651)
		(layer "F.Cu")
		(net "M_L_DQ<41>")
	)
	(segment
		(start 114.578384 -102.917498)
		(end 114.578384 -103.542084)
		(width 0.0889)
		(layer "F.Cu")
		(net "M_L_DQ<41>")
	)
	(segment
		(start 119.327168 -115.5446)
		(end 120.3198 -115.5446)
		(width 0.1651)
		(layer "F.Cu")
		(net "M_L_DQ<41>")
	)
	(segment
		(start 114.483388 -105.883964)
		(end 114.483388 -109.297216)
		(width 0.1016)
		(layer "F.Cu")
		(net "M_L_DQ<41>")
	)
	(segment
		(start 123.205748 -118.70944)
		(end 123.48464 -118.70944)
		(width 0.1651)
		(layer "F.Cu")
		(net "M_L_DQ<41>")
	)
	(segment
		(start 127.080518 -123.375166)
		(end 127.080518 -124.206)
		(width 0.1651)
		(layer "F.Cu")
		(net "M_L_DQ<41>")
	)
	(segment
		(start 121.547636 -117.790468)
		(end 121.74474 -117.987572)
		(width 0.1651)
		(layer "F.Cu")
		(net "M_L_DQ<41>")
	)
	(segment
		(start 123.48464 -118.70944)
		(end 123.681744 -118.906544)
		(width 0.1651)
		(layer "F.Cu")
		(net "M_L_DQ<41>")
	)
	(segment
		(start 122.975624 -118.939564)
		(end 123.205748 -118.70944)
		(width 0.1651)
		(layer "F.Cu")
		(net "M_L_DQ<41>")
	)
	(segment
		(start 118.412768 -113.8174)
		(end 118.717568 -114.1222)
		(width 0.1651)
		(layer "F.Cu")
		(net "M_L_DQ<41>")
	)
	(segment
		(start 114.483388 -109.297216)
		(end 118.412768 -113.226596)
		(width 0.1016)
		(layer "F.Cu")
		(net "M_L_DQ<41>")
	)
	(segment
		(start 120.825768 -116.050568)
		(end 120.825768 -116.32946)
		(width 0.1651)
		(layer "F.Cu")
		(net "M_L_DQ<41>")
	)
	(segment
		(start 121.74474 -117.987572)
		(end 122.023632 -117.987572)
		(width 0.1651)
		(layer "F.Cu")
		(net "M_L_DQ<41>")
	)
	(via
		(at 126.421642 -124.687076)
		(size 0.508)
		(drill 0.254)
		(layers "F.Cu" "B.Cu")
		(net "M_L_DQ<41>")
	)
	(via
		(at 126.421642 -139.932156)
		(size 0.508)
		(drill 0.254)
		(layers "F.Cu" "B.Cu")
		(net "M_L_DQ<41>")
	)
	(via
		(at 125.749558 -143.941546)
		(size 0.508)
		(drill 0.254)
		(layers "F.Cu" "B.Cu")
		(net "M_L_DQ<41>")
	)
	(arc
		(start 114.40414 -102.320344)
		(mid 114.379298 -102.494622)
		(end 114.431572 -102.662736)
		(width 0.0889)
		(layer "F.Cu")
		(net "M_L_DQ<41>")
	)
	(segment
		(start 126.599442 -137.877296)
		(end 126.599442 -139.251182)
		(width 0.1651)
		(layer "B.Cu")
		(net "M_L_DQ<41>")
	)
	(segment
		(start 126.421642 -139.428982)
		(end 126.421642 -139.932156)
		(width 0.1651)
		(layer "B.Cu")
		(net "M_L_DQ<41>")
	)
	(segment
		(start 126.599442 -139.251182)
		(end 126.421642 -139.428982)
		(width 0.1651)
		(layer "B.Cu")
		(net "M_L_DQ<41>")
	)
	(segment
		(start 126.150624 -143.7894)
		(end 126.150624 -143.4846)
		(width 0.14224)
		(layer "In9.Cu")
		(net "M_L_DQ<41>")
	)
	(segment
		(start 125.910848 -142.936976)
		(end 126.125224 -142.7226)
		(width 0.14224)
		(layer "In9.Cu")
		(net "M_L_DQ<41>")
	)
	(segment
		(start 126.150624 -143.4846)
		(end 125.910848 -143.244824)
		(width 0.14224)
		(layer "In9.Cu")
		(net "M_L_DQ<41>")
	)
	(segment
		(start 126.39929 -139.932156)
		(end 126.421642 -139.932156)
		(width 0.14224)
		(layer "In9.Cu")
		(net "M_L_DQ<41>")
	)
	(segment
		(start 126.201424 -141.020546)
		(end 125.971046 -140.790168)
		(width 0.14224)
		(layer "In9.Cu")
		(net "M_L_DQ<41>")
	)
	(segment
		(start 126.125224 -142.7226)
		(end 126.125224 -142.2908)
		(width 0.14224)
		(layer "In9.Cu")
		(net "M_L_DQ<41>")
	)
	(segment
		(start 125.971046 -140.3604)
		(end 126.39929 -139.932156)
		(width 0.14224)
		(layer "In9.Cu")
		(net "M_L_DQ<41>")
	)
	(segment
		(start 125.910848 -141.715744)
		(end 126.201424 -141.425168)
		(width 0.14224)
		(layer "In9.Cu")
		(net "M_L_DQ<41>")
	)
	(segment
		(start 125.749558 -143.941546)
		(end 125.998478 -143.941546)
		(width 0.14224)
		(layer "In9.Cu")
		(net "M_L_DQ<41>")
	)
	(segment
		(start 126.125224 -142.2908)
		(end 125.910848 -142.076424)
		(width 0.14224)
		(layer "In9.Cu")
		(net "M_L_DQ<41>")
	)
	(segment
		(start 126.201424 -141.425168)
		(end 126.201424 -141.020546)
		(width 0.14224)
		(layer "In9.Cu")
		(net "M_L_DQ<41>")
	)
	(segment
		(start 125.971046 -140.790168)
		(end 125.971046 -140.3604)
		(width 0.14224)
		(layer "In9.Cu")
		(net "M_L_DQ<41>")
	)
	(segment
		(start 125.998478 -143.941546)
		(end 126.150624 -143.7894)
		(width 0.14224)
		(layer "In9.Cu")
		(net "M_L_DQ<41>")
	)
	(segment
		(start 125.910848 -143.244824)
		(end 125.910848 -142.936976)
		(width 0.14224)
		(layer "In9.Cu")
		(net "M_L_DQ<41>")
	)
	(segment
		(start 125.910848 -142.076424)
		(end 125.910848 -141.715744)
		(width 0.14224)
		(layer "In9.Cu")
		(net "M_L_DQ<41>")
	)
	(segment
		(start 126.909576 -136.5758)
		(end 126.909576 -134.200392)
		(width 0.14224)
		(layer "In11.Cu")
		(net "M_L_DQ<41>")
	)
	(segment
		(start 126.909576 -139.355322)
		(end 126.909576 -138.823192)
		(width 0.14224)
		(layer "In11.Cu")
		(net "M_L_DQ<41>")
	)
	(segment
		(start 126.909576 -131.7244)
		(end 126.909576 -128.60782)
		(width 0.14224)
		(layer "In11.Cu")
		(net "M_L_DQ<41>")
	)
	(segment
		(start 127.023368 -138.7094)
		(end 127.023368 -136.689592)
		(width 0.14224)
		(layer "In11.Cu")
		(net "M_L_DQ<41>")
	)
	(segment
		(start 126.909576 -134.200392)
		(end 127.023368 -134.0866)
		(width 0.14224)
		(layer "In11.Cu")
		(net "M_L_DQ<41>")
	)
	(segment
		(start 125.924564 -125.469396)
		(end 125.924564 -125.184154)
		(width 0.14224)
		(layer "In11.Cu")
		(net "M_L_DQ<41>")
	)
	(segment
		(start 126.909576 -138.823192)
		(end 127.023368 -138.7094)
		(width 0.14224)
		(layer "In11.Cu")
		(net "M_L_DQ<41>")
	)
	(segment
		(start 126.421642 -139.843256)
		(end 126.909576 -139.355322)
		(width 0.14224)
		(layer "In11.Cu")
		(net "M_L_DQ<41>")
	)
	(segment
		(start 127.023368 -136.689592)
		(end 126.909576 -136.5758)
		(width 0.14224)
		(layer "In11.Cu")
		(net "M_L_DQ<41>")
	)
	(segment
		(start 126.254764 -127.953008)
		(end 126.254764 -125.799596)
		(width 0.14224)
		(layer "In11.Cu")
		(net "M_L_DQ<41>")
	)
	(segment
		(start 125.924564 -125.184154)
		(end 126.421642 -124.687076)
		(width 0.14224)
		(layer "In11.Cu")
		(net "M_L_DQ<41>")
	)
	(segment
		(start 127.023368 -134.0866)
		(end 127.023368 -131.838192)
		(width 0.14224)
		(layer "In11.Cu")
		(net "M_L_DQ<41>")
	)
	(segment
		(start 126.421642 -139.932156)
		(end 126.421642 -139.843256)
		(width 0.14224)
		(layer "In11.Cu")
		(net "M_L_DQ<41>")
	)
	(segment
		(start 126.254764 -125.799596)
		(end 125.924564 -125.469396)
		(width 0.14224)
		(layer "In11.Cu")
		(net "M_L_DQ<41>")
	)
	(segment
		(start 126.909576 -128.60782)
		(end 126.254764 -127.953008)
		(width 0.14224)
		(layer "In11.Cu")
		(net "M_L_DQ<41>")
	)
	(segment
		(start 127.023368 -131.838192)
		(end 126.909576 -131.7244)
		(width 0.14224)
		(layer "In11.Cu")
		(net "M_L_DQ<41>")
	)
	(segment
		(start 126.257558 -126.86919)
		(end 126.004066 -126.615698)
		(width 0.1651)
		(layer "F.Cu")
		(net "M_L_DQ<40>")
	)
	(segment
		(start 114.089688 -105.883964)
		(end 114.089688 -109.460538)
		(width 0.1016)
		(layer "F.Cu")
		(net "M_L_DQ<40>")
	)
	(segment
		(start 114.387884 -102.968552)
		(end 114.387884 -103.46309)
		(width 0.0889)
		(layer "F.Cu")
		(net "M_L_DQ<40>")
	)
	(segment
		(start 117.752368 -114.0714)
		(end 117.955568 -114.2746)
		(width 0.1651)
		(layer "F.Cu")
		(net "M_L_DQ<40>")
	)
	(segment
		(start 114.191288 -105.782364)
		(end 114.089688 -105.883964)
		(width 0.0889)
		(layer "F.Cu")
		(net "M_L_DQ<40>")
	)
	(segment
		(start 125.473968 -125.0696)
		(end 125.270768 -125.2728)
		(width 0.1651)
		(layer "F.Cu")
		(net "M_L_DQ<40>")
	)
	(segment
		(start 125.016768 -127.254)
		(end 125.194568 -127.4318)
		(width 0.1651)
		(layer "F.Cu")
		(net "M_L_DQ<40>")
	)
	(segment
		(start 125.194568 -127.4318)
		(end 126.083568 -127.4318)
		(width 0.1651)
		(layer "F.Cu")
		(net "M_L_DQ<40>")
	)
	(segment
		(start 114.387884 -103.46309)
		(end 114.191288 -103.659686)
		(width 0.0889)
		(layer "F.Cu")
		(net "M_L_DQ<40>")
	)
	(segment
		(start 126.599442 -147.27174)
		(end 126.599442 -147.277582)
		(width 0.1651)
		(layer "F.Cu")
		(net "M_L_DQ<40>")
	)
	(segment
		(start 114.191288 -103.659686)
		(end 114.191288 -105.782364)
		(width 0.0889)
		(layer "F.Cu")
		(net "M_L_DQ<40>")
	)
	(segment
		(start 126.083568 -123.317)
		(end 125.473968 -123.9266)
		(width 0.1651)
		(layer "F.Cu")
		(net "M_L_DQ<40>")
	)
	(segment
		(start 123.62688 -120.8278)
		(end 124.737368 -120.8278)
		(width 0.1651)
		(layer "F.Cu")
		(net "M_L_DQ<40>")
	)
	(segment
		(start 125.270768 -125.603)
		(end 125.016768 -125.857)
		(width 0.1651)
		(layer "F.Cu")
		(net "M_L_DQ<40>")
	)
	(segment
		(start 124.737368 -120.8278)
		(end 126.083568 -122.174)
		(width 0.1651)
		(layer "F.Cu")
		(net "M_L_DQ<40>")
	)
	(segment
		(start 114.089688 -109.460538)
		(end 117.752368 -113.123218)
		(width 0.1016)
		(layer "F.Cu")
		(net "M_L_DQ<40>")
	)
	(segment
		(start 126.004066 -126.615698)
		(end 125.673358 -126.615698)
		(width 0.1651)
		(layer "F.Cu")
		(net "M_L_DQ<40>")
	)
	(segment
		(start 113.919762 -101.967538)
		(end 114.207036 -102.133146)
		(width 0.0889)
		(layer "F.Cu")
		(net "M_L_DQ<40>")
	)
	(segment
		(start 117.752368 -113.123218)
		(end 117.752368 -114.0714)
		(width 0.1016)
		(layer "F.Cu")
		(net "M_L_DQ<40>")
	)
	(segment
		(start 114.207036 -102.133146)
		(end 114.233706 -102.232714)
		(width 0.0889)
		(layer "F.Cu")
		(net "M_L_DQ<40>")
	)
	(segment
		(start 117.955568 -114.2746)
		(end 117.955568 -115.156488)
		(width 0.1651)
		(layer "F.Cu")
		(net "M_L_DQ<40>")
	)
	(segment
		(start 114.266472 -102.757986)
		(end 114.387884 -102.968552)
		(width 0.0889)
		(layer "F.Cu")
		(net "M_L_DQ<40>")
	)
	(segment
		(start 126.257558 -127.25781)
		(end 126.257558 -126.86919)
		(width 0.1651)
		(layer "F.Cu")
		(net "M_L_DQ<40>")
	)
	(segment
		(start 117.955568 -115.156488)
		(end 123.62688 -120.8278)
		(width 0.1651)
		(layer "F.Cu")
		(net "M_L_DQ<40>")
	)
	(segment
		(start 125.473968 -123.9266)
		(end 125.473968 -125.0696)
		(width 0.1651)
		(layer "F.Cu")
		(net "M_L_DQ<40>")
	)
	(segment
		(start 126.599442 -147.277582)
		(end 126.421642 -145.415)
		(width 0.1651)
		(layer "F.Cu")
		(net "M_L_DQ<40>")
	)
	(segment
		(start 125.270768 -125.2728)
		(end 125.270768 -125.603)
		(width 0.1651)
		(layer "F.Cu")
		(net "M_L_DQ<40>")
	)
	(segment
		(start 126.083568 -127.4318)
		(end 126.257558 -127.25781)
		(width 0.1651)
		(layer "F.Cu")
		(net "M_L_DQ<40>")
	)
	(segment
		(start 126.083568 -122.174)
		(end 126.083568 -123.317)
		(width 0.1651)
		(layer "F.Cu")
		(net "M_L_DQ<40>")
	)
	(segment
		(start 125.016768 -125.857)
		(end 125.016768 -127.254)
		(width 0.1651)
		(layer "F.Cu")
		(net "M_L_DQ<40>")
	)
	(via
		(at 125.749558 -141.213078)
		(size 0.508)
		(drill 0.254)
		(layers "F.Cu" "B.Cu")
		(net "M_L_DQ<40>")
	)
	(via
		(at 125.673358 -126.615698)
		(size 0.508)
		(drill 0.254)
		(layers "F.Cu" "B.Cu")
		(net "M_L_DQ<40>")
	)
	(via
		(at 126.421642 -145.415)
		(size 0.508)
		(drill 0.254)
		(layers "F.Cu" "B.Cu")
		(net "M_L_DQ<40>")
	)
	(arc
		(start 114.233706 -102.232714)
		(mid 114.188428 -102.499189)
		(end 114.266472 -102.757986)
		(width 0.0889)
		(layer "F.Cu")
		(net "M_L_DQ<40>")
	)
	(segment
		(start 125.749558 -142.477236)
		(end 125.749558 -141.213078)
		(width 0.1651)
		(layer "B.Cu")
		(net "M_L_DQ<40>")
	)
	(segment
		(start 125.316488 -141.646148)
		(end 125.749558 -141.213078)
		(width 0.14224)
		(layer "In9.Cu")
		(net "M_L_DQ<40>")
	)
	(segment
		(start 126.421642 -145.415)
		(end 126.125478 -145.415)
		(width 0.14224)
		(layer "In9.Cu")
		(net "M_L_DQ<40>")
	)
	(segment
		(start 126.125478 -145.415)
		(end 125.316488 -144.60601)
		(width 0.14224)
		(layer "In9.Cu")
		(net "M_L_DQ<40>")
	)
	(segment
		(start 125.316488 -144.60601)
		(end 125.316488 -141.646148)
		(width 0.14224)
		(layer "In9.Cu")
		(net "M_L_DQ<40>")
	)
	(segment
		(start 126.274576 -128.870964)
		(end 126.274576 -129.719578)
		(width 0.14224)
		(layer "In11.Cu")
		(net "M_L_DQ<40>")
	)
	(segment
		(start 125.385576 -140.849096)
		(end 125.749558 -141.213078)
		(width 0.14224)
		(layer "In11.Cu")
		(net "M_L_DQ<40>")
	)
	(segment
		(start 125.931676 -130.062478)
		(end 125.931676 -131.141978)
		(width 0.14224)
		(layer "In11.Cu")
		(net "M_L_DQ<40>")
	)
	(segment
		(start 126.185168 -131.966208)
		(end 126.185168 -134.0866)
		(width 0.14224)
		(layer "In11.Cu")
		(net "M_L_DQ<40>")
	)
	(segment
		(start 126.274576 -129.719578)
		(end 125.931676 -130.062478)
		(width 0.14224)
		(layer "In11.Cu")
		(net "M_L_DQ<40>")
	)
	(segment
		(start 125.944376 -135.979662)
		(end 126.236476 -136.271762)
		(width 0.14224)
		(layer "In11.Cu")
		(net "M_L_DQ<40>")
	)
	(segment
		(start 125.673358 -128.269746)
		(end 126.274576 -128.870964)
		(width 0.14224)
		(layer "In11.Cu")
		(net "M_L_DQ<40>")
	)
	(segment
		(start 125.931676 -131.141978)
		(end 126.223776 -131.434078)
		(width 0.14224)
		(layer "In11.Cu")
		(net "M_L_DQ<40>")
	)
	(segment
		(start 126.185168 -136.601708)
		(end 126.185168 -138.7602)
		(width 0.14224)
		(layer "In11.Cu")
		(net "M_L_DQ<40>")
	)
	(segment
		(start 126.223776 -131.9276)
		(end 126.185168 -131.966208)
		(width 0.14224)
		(layer "In11.Cu")
		(net "M_L_DQ<40>")
	)
	(segment
		(start 125.385576 -140.209778)
		(end 125.385576 -140.849096)
		(width 0.14224)
		(layer "In11.Cu")
		(net "M_L_DQ<40>")
	)
	(segment
		(start 126.185168 -138.7602)
		(end 126.236476 -138.811508)
		(width 0.14224)
		(layer "In11.Cu")
		(net "M_L_DQ<40>")
	)
	(segment
		(start 126.236476 -138.811508)
		(end 126.236476 -139.358878)
		(width 0.14224)
		(layer "In11.Cu")
		(net "M_L_DQ<40>")
	)
	(segment
		(start 126.223776 -134.125208)
		(end 126.223776 -134.479538)
		(width 0.14224)
		(layer "In11.Cu")
		(net "M_L_DQ<40>")
	)
	(segment
		(start 126.236476 -139.358878)
		(end 125.385576 -140.209778)
		(width 0.14224)
		(layer "In11.Cu")
		(net "M_L_DQ<40>")
	)
	(segment
		(start 126.236476 -136.271762)
		(end 126.236476 -136.5504)
		(width 0.14224)
		(layer "In11.Cu")
		(net "M_L_DQ<40>")
	)
	(segment
		(start 125.673358 -126.615698)
		(end 125.673358 -128.269746)
		(width 0.14224)
		(layer "In11.Cu")
		(net "M_L_DQ<40>")
	)
	(segment
		(start 126.223776 -134.479538)
		(end 125.944376 -134.758938)
		(width 0.14224)
		(layer "In11.Cu")
		(net "M_L_DQ<40>")
	)
	(segment
		(start 126.185168 -134.0866)
		(end 126.223776 -134.125208)
		(width 0.14224)
		(layer "In11.Cu")
		(net "M_L_DQ<40>")
	)
	(segment
		(start 125.944376 -134.758938)
		(end 125.944376 -135.979662)
		(width 0.14224)
		(layer "In11.Cu")
		(net "M_L_DQ<40>")
	)
	(segment
		(start 126.236476 -136.5504)
		(end 126.185168 -136.601708)
		(width 0.14224)
		(layer "In11.Cu")
		(net "M_L_DQ<40>")
	)
	(segment
		(start 126.223776 -131.434078)
		(end 126.223776 -131.9276)
		(width 0.14224)
		(layer "In11.Cu")
		(net "M_L_DQ<40>")
	)
	(segment
		(start 71.183246 -86.29904)
		(end 70.611746 -86.29904)
		(width 0.1651)
		(layer "F.Cu")
		(net "M_L_DQ<3>")
	)
	(segment
		(start 39.049452 -142.6718)
		(end 39.049452 -143.941546)
		(width 0.1651)
		(layer "F.Cu")
		(net "M_L_DQ<3>")
	)
	(via
		(at 39.049452 -143.941546)
		(size 0.508)
		(drill 0.254)
		(layers "F.Cu" "B.Cu")
		(net "M_L_DQ<3>")
	)
	(via
		(at 39.899336 -139.932156)
		(size 0.508)
		(drill 0.254)
		(layers "F.Cu" "B.Cu")
		(net "M_L_DQ<3>")
	)
	(via
		(at 70.611746 -86.29904)
		(size 0.508)
		(drill 0.254)
		(layers "F.Cu" "B.Cu")
		(net "M_L_DQ<3>")
	)
	(segment
		(start 39.899336 -137.877296)
		(end 39.899336 -139.932156)
		(width 0.1651)
		(layer "B.Cu")
		(net "M_L_DQ<3>")
	)
	(segment
		(start 40.510968 -130.048254)
		(end 40.510968 -131.089146)
		(width 0.14224)
		(layer "In4.Cu")
		(net "M_L_DQ<3>")
	)
	(segment
		(start 40.333168 -134.0358)
		(end 40.171116 -134.197852)
		(width 0.14224)
		(layer "In4.Cu")
		(net "M_L_DQ<3>")
	)
	(segment
		(start 64.463168 -88.595454)
		(end 64.463168 -88.730582)
		(width 0.0889)
		(layer "In4.Cu")
		(net "M_L_DQ<3>")
	)
	(segment
		(start 42.365168 -118.9228)
		(end 42.161968 -118.7196)
		(width 0.14224)
		(layer "In4.Cu")
		(net "M_L_DQ<3>")
	)
	(segment
		(start 47.469552 -110.13567)
		(end 47.250604 -110.13567)
		(width 0.14224)
		(layer "In4.Cu")
		(net "M_L_DQ<3>")
	)
	(segment
		(start 49.090326 -107.595924)
		(end 48.734472 -107.951778)
		(width 0.14224)
		(layer "In4.Cu")
		(net "M_L_DQ<3>")
	)
	(segment
		(start 46.403768 -110.282482)
		(end 46.403768 -111.186722)
		(width 0.14224)
		(layer "In4.Cu")
		(net "M_L_DQ<3>")
	)
	(segment
		(start 48.97501 -108.630212)
		(end 48.619156 -108.986066)
		(width 0.14224)
		(layer "In4.Cu")
		(net "M_L_DQ<3>")
	)
	(segment
		(start 39.899336 -139.945364)
		(end 39.899336 -139.932156)
		(width 0.14224)
		(layer "In4.Cu")
		(net "M_L_DQ<3>")
	)
	(segment
		(start 41.552368 -118.9228)
		(end 41.552368 -125.613922)
		(width 0.14224)
		(layer "In4.Cu")
		(net "M_L_DQ<3>")
	)
	(segment
		(start 64.289432 -88.904318)
		(end 58.282332 -94.911418)
		(width 0.14224)
		(layer "In4.Cu")
		(net "M_L_DQ<3>")
	)
	(segment
		(start 50.124614 -107.26166)
		(end 50.124614 -107.480608)
		(width 0.14224)
		(layer "In4.Cu")
		(net "M_L_DQ<3>")
	)
	(segment
		(start 39.49319 -141.5034)
		(end 39.49319 -140.834618)
		(width 0.14224)
		(layer "In4.Cu")
		(net "M_L_DQ<3>")
	)
	(segment
		(start 40.134032 -136.393936)
		(end 40.134032 -136.732264)
		(width 0.14224)
		(layer "In4.Cu")
		(net "M_L_DQ<3>")
	)
	(segment
		(start 50.124614 -107.480608)
		(end 49.76876 -107.836462)
		(width 0.14224)
		(layer "In4.Cu")
		(net "M_L_DQ<3>")
	)
	(segment
		(start 39.49954 -143.44015)
		(end 39.210742 -143.151352)
		(width 0.14224)
		(layer "In4.Cu")
		(net "M_L_DQ<3>")
	)
	(segment
		(start 39.49954 -143.763746)
		(end 39.49954 -143.44015)
		(width 0.14224)
		(layer "In4.Cu")
		(net "M_L_DQ<3>")
	)
	(segment
		(start 42.365168 -123.9266)
		(end 42.365168 -118.9228)
		(width 0.14224)
		(layer "In4.Cu")
		(net "M_L_DQ<3>")
	)
	(segment
		(start 48.734472 -108.170726)
		(end 48.97501 -108.411264)
		(width 0.14224)
		(layer "In4.Cu")
		(net "M_L_DQ<3>")
	)
	(segment
		(start 48.15967 -108.745528)
		(end 47.940722 -108.745528)
		(width 0.14224)
		(layer "In4.Cu")
		(net "M_L_DQ<3>")
	)
	(segment
		(start 42.161968 -118.7196)
		(end 41.755568 -118.7196)
		(width 0.14224)
		(layer "In4.Cu")
		(net "M_L_DQ<3>")
	)
	(segment
		(start 41.755568 -118.7196)
		(end 41.552368 -118.9228)
		(width 0.14224)
		(layer "In4.Cu")
		(net "M_L_DQ<3>")
	)
	(segment
		(start 49.884076 -107.021122)
		(end 50.124614 -107.26166)
		(width 0.14224)
		(layer "In4.Cu")
		(net "M_L_DQ<3>")
	)
	(segment
		(start 66.334132 -88.338406)
		(end 64.720216 -88.338406)
		(width 0.0889)
		(layer "In4.Cu")
		(net "M_L_DQ<3>")
	)
	(segment
		(start 46.791118 -109.895132)
		(end 46.403768 -110.282482)
		(width 0.14224)
		(layer "In4.Cu")
		(net "M_L_DQ<3>")
	)
	(segment
		(start 39.210742 -142.059152)
		(end 39.210742 -141.785848)
		(width 0.14224)
		(layer "In4.Cu")
		(net "M_L_DQ<3>")
	)
	(segment
		(start 40.180768 -131.419346)
		(end 40.180768 -132.0038)
		(width 0.14224)
		(layer "In4.Cu")
		(net "M_L_DQ<3>")
	)
	(segment
		(start 49.884076 -106.802174)
		(end 49.884076 -107.021122)
		(width 0.14224)
		(layer "In4.Cu")
		(net "M_L_DQ<3>")
	)
	(segment
		(start 40.282368 -126.883922)
		(end 40.282368 -129.819654)
		(width 0.14224)
		(layer "In4.Cu")
		(net "M_L_DQ<3>")
	)
	(segment
		(start 64.720216 -88.338406)
		(end 64.463168 -88.595454)
		(width 0.0889)
		(layer "In4.Cu")
		(net "M_L_DQ<3>")
	)
	(segment
		(start 39.210742 -141.785848)
		(end 39.49319 -141.5034)
		(width 0.14224)
		(layer "In4.Cu")
		(net "M_L_DQ<3>")
	)
	(segment
		(start 39.210742 -142.878048)
		(end 39.46779 -142.621)
		(width 0.14224)
		(layer "In4.Cu")
		(net "M_L_DQ<3>")
	)
	(segment
		(start 39.46779 -142.3162)
		(end 39.210742 -142.059152)
		(width 0.14224)
		(layer "In4.Cu")
		(net "M_L_DQ<3>")
	)
	(segment
		(start 48.619156 -108.986066)
		(end 48.400208 -108.986066)
		(width 0.14224)
		(layer "In4.Cu")
		(net "M_L_DQ<3>")
	)
	(segment
		(start 41.552368 -125.613922)
		(end 40.282368 -126.883922)
		(width 0.14224)
		(layer "In4.Cu")
		(net "M_L_DQ<3>")
	)
	(segment
		(start 39.210742 -143.151352)
		(end 39.210742 -142.878048)
		(width 0.14224)
		(layer "In4.Cu")
		(net "M_L_DQ<3>")
	)
	(segment
		(start 47.250604 -110.13567)
		(end 47.010066 -109.895132)
		(width 0.14224)
		(layer "In4.Cu")
		(net "M_L_DQ<3>")
	)
	(segment
		(start 40.206168 -138.8872)
		(end 40.206168 -139.638532)
		(width 0.14224)
		(layer "In4.Cu")
		(net "M_L_DQ<3>")
	)
	(segment
		(start 40.171116 -134.197852)
		(end 40.171116 -134.485634)
		(width 0.14224)
		(layer "In4.Cu")
		(net "M_L_DQ<3>")
	)
	(segment
		(start 40.282368 -129.819654)
		(end 40.510968 -130.048254)
		(width 0.14224)
		(layer "In4.Cu")
		(net "M_L_DQ<3>")
	)
	(segment
		(start 40.333168 -138.7602)
		(end 40.206168 -138.8872)
		(width 0.14224)
		(layer "In4.Cu")
		(net "M_L_DQ<3>")
	)
	(segment
		(start 39.049452 -143.941546)
		(end 39.32174 -143.941546)
		(width 0.14224)
		(layer "In4.Cu")
		(net "M_L_DQ<3>")
	)
	(segment
		(start 40.134032 -136.732264)
		(end 40.333168 -136.9314)
		(width 0.14224)
		(layer "In4.Cu")
		(net "M_L_DQ<3>")
	)
	(segment
		(start 39.49319 -140.834618)
		(end 39.44874 -140.790168)
		(width 0.14224)
		(layer "In4.Cu")
		(net "M_L_DQ<3>")
	)
	(segment
		(start 43.177968 -114.412522)
		(end 43.177968 -123.9266)
		(width 0.14224)
		(layer "In4.Cu")
		(net "M_L_DQ<3>")
	)
	(segment
		(start 40.206168 -139.638532)
		(end 39.899336 -139.945364)
		(width 0.14224)
		(layer "In4.Cu")
		(net "M_L_DQ<3>")
	)
	(segment
		(start 69.79031 -86.394036)
		(end 69.74205 -86.394036)
		(width 0.0889)
		(layer "In4.Cu")
		(net "M_L_DQ<3>")
	)
	(segment
		(start 40.510968 -131.089146)
		(end 40.180768 -131.419346)
		(width 0.14224)
		(layer "In4.Cu")
		(net "M_L_DQ<3>")
	)
	(segment
		(start 58.282332 -94.911418)
		(end 58.282332 -98.403918)
		(width 0.14224)
		(layer "In4.Cu")
		(net "M_L_DQ<3>")
	)
	(segment
		(start 39.876984 -139.932156)
		(end 39.899336 -139.932156)
		(width 0.14224)
		(layer "In4.Cu")
		(net "M_L_DQ<3>")
	)
	(segment
		(start 47.584868 -109.32033)
		(end 47.825406 -109.560868)
		(width 0.14224)
		(layer "In4.Cu")
		(net "M_L_DQ<3>")
	)
	(segment
		(start 47.940722 -108.745528)
		(end 47.584868 -109.101382)
		(width 0.14224)
		(layer "In4.Cu")
		(net "M_L_DQ<3>")
	)
	(segment
		(start 47.825406 -109.779816)
		(end 47.469552 -110.13567)
		(width 0.14224)
		(layer "In4.Cu")
		(net "M_L_DQ<3>")
	)
	(segment
		(start 49.549812 -107.836462)
		(end 49.309274 -107.595924)
		(width 0.14224)
		(layer "In4.Cu")
		(net "M_L_DQ<3>")
	)
	(segment
		(start 39.44874 -140.3604)
		(end 39.876984 -139.932156)
		(width 0.14224)
		(layer "In4.Cu")
		(net "M_L_DQ<3>")
	)
	(segment
		(start 39.44874 -140.790168)
		(end 39.44874 -140.3604)
		(width 0.14224)
		(layer "In4.Cu")
		(net "M_L_DQ<3>")
	)
	(segment
		(start 40.333168 -132.1562)
		(end 40.333168 -134.0358)
		(width 0.14224)
		(layer "In4.Cu")
		(net "M_L_DQ<3>")
	)
	(segment
		(start 40.180768 -132.0038)
		(end 40.333168 -132.1562)
		(width 0.14224)
		(layer "In4.Cu")
		(net "M_L_DQ<3>")
	)
	(segment
		(start 66.792348 -87.88019)
		(end 66.334132 -88.338406)
		(width 0.0889)
		(layer "In4.Cu")
		(net "M_L_DQ<3>")
	)
	(segment
		(start 47.584868 -109.101382)
		(end 47.584868 -109.32033)
		(width 0.14224)
		(layer "In4.Cu")
		(net "M_L_DQ<3>")
	)
	(segment
		(start 58.282332 -98.403918)
		(end 49.884076 -106.802174)
		(width 0.14224)
		(layer "In4.Cu")
		(net "M_L_DQ<3>")
	)
	(segment
		(start 47.010066 -109.895132)
		(end 46.791118 -109.895132)
		(width 0.14224)
		(layer "In4.Cu")
		(net "M_L_DQ<3>")
	)
	(segment
		(start 46.403768 -111.186722)
		(end 43.177968 -114.412522)
		(width 0.14224)
		(layer "In4.Cu")
		(net "M_L_DQ<3>")
	)
	(segment
		(start 42.568368 -124.1298)
		(end 42.365168 -123.9266)
		(width 0.14224)
		(layer "In4.Cu")
		(net "M_L_DQ<3>")
	)
	(segment
		(start 40.48252 -136.045448)
		(end 40.134032 -136.393936)
		(width 0.14224)
		(layer "In4.Cu")
		(net "M_L_DQ<3>")
	)
	(segment
		(start 48.400208 -108.986066)
		(end 48.15967 -108.745528)
		(width 0.14224)
		(layer "In4.Cu")
		(net "M_L_DQ<3>")
	)
	(segment
		(start 40.333168 -136.9314)
		(end 40.333168 -138.7602)
		(width 0.14224)
		(layer "In4.Cu")
		(net "M_L_DQ<3>")
	)
	(segment
		(start 49.76876 -107.836462)
		(end 49.549812 -107.836462)
		(width 0.14224)
		(layer "In4.Cu")
		(net "M_L_DQ<3>")
	)
	(segment
		(start 47.825406 -109.560868)
		(end 47.825406 -109.779816)
		(width 0.14224)
		(layer "In4.Cu")
		(net "M_L_DQ<3>")
	)
	(segment
		(start 40.171116 -134.485634)
		(end 40.48252 -134.797038)
		(width 0.14224)
		(layer "In4.Cu")
		(net "M_L_DQ<3>")
	)
	(segment
		(start 68.912486 -86.88959)
		(end 68.87972 -86.88959)
		(width 0.0889)
		(layer "In4.Cu")
		(net "M_L_DQ<3>")
	)
	(segment
		(start 40.48252 -134.797038)
		(end 40.48252 -136.045448)
		(width 0.14224)
		(layer "In4.Cu")
		(net "M_L_DQ<3>")
	)
	(segment
		(start 48.734472 -107.951778)
		(end 48.734472 -108.170726)
		(width 0.14224)
		(layer "In4.Cu")
		(net "M_L_DQ<3>")
	)
	(segment
		(start 68.057776 -87.384636)
		(end 68.02501 -87.384636)
		(width 0.0889)
		(layer "In4.Cu")
		(net "M_L_DQ<3>")
	)
	(segment
		(start 43.177968 -123.9266)
		(end 42.974768 -124.1298)
		(width 0.14224)
		(layer "In4.Cu")
		(net "M_L_DQ<3>")
	)
	(segment
		(start 70.611746 -86.29904)
		(end 69.79031 -86.394036)
		(width 0.0889)
		(layer "In4.Cu")
		(net "M_L_DQ<3>")
	)
	(segment
		(start 39.46779 -142.621)
		(end 39.46779 -142.3162)
		(width 0.14224)
		(layer "In4.Cu")
		(net "M_L_DQ<3>")
	)
	(segment
		(start 64.463168 -88.730582)
		(end 64.289432 -88.904318)
		(width 0.0889)
		(layer "In4.Cu")
		(net "M_L_DQ<3>")
	)
	(segment
		(start 42.974768 -124.1298)
		(end 42.568368 -124.1298)
		(width 0.14224)
		(layer "In4.Cu")
		(net "M_L_DQ<3>")
	)
	(segment
		(start 49.309274 -107.595924)
		(end 49.090326 -107.595924)
		(width 0.14224)
		(layer "In4.Cu")
		(net "M_L_DQ<3>")
	)
	(segment
		(start 48.97501 -108.411264)
		(end 48.97501 -108.630212)
		(width 0.14224)
		(layer "In4.Cu")
		(net "M_L_DQ<3>")
	)
	(segment
		(start 67.191382 -87.88019)
		(end 66.792348 -87.88019)
		(width 0.0889)
		(layer "In4.Cu")
		(net "M_L_DQ<3>")
	)
	(segment
		(start 39.32174 -143.941546)
		(end 39.49954 -143.763746)
		(width 0.14224)
		(layer "In4.Cu")
		(net "M_L_DQ<3>")
	)
	(arc
		(start 68.547996 -87.089488)
		(mid 68.340992 -87.300352)
		(end 68.057776 -87.384636)
		(width 0.0889)
		(layer "In4.Cu")
		(net "M_L_DQ<3>")
	)
	(arc
		(start 69.406516 -86.594188)
		(mid 69.197908 -86.80612)
		(end 68.912486 -86.88959)
		(width 0.0889)
		(layer "In4.Cu")
		(net "M_L_DQ<3>")
	)
	(arc
		(start 68.02501 -87.384636)
		(mid 67.83116 -87.440986)
		(end 67.689476 -87.584788)
		(width 0.0889)
		(layer "In4.Cu")
		(net "M_L_DQ<3>")
	)
	(arc
		(start 67.689476 -87.584788)
		(mid 67.479123 -87.79776)
		(end 67.191382 -87.88019)
		(width 0.0889)
		(layer "In4.Cu")
		(net "M_L_DQ<3>")
	)
	(arc
		(start 68.87972 -86.88959)
		(mid 68.688078 -86.946756)
		(end 68.547996 -87.089488)
		(width 0.0889)
		(layer "In4.Cu")
		(net "M_L_DQ<3>")
	)
	(arc
		(start 69.74205 -86.394036)
		(mid 69.5482 -86.450386)
		(end 69.406516 -86.594188)
		(width 0.0889)
		(layer "In4.Cu")
		(net "M_L_DQ<3>")
	)
	(segment
		(start 108.768896 -98.995738)
		(end 109.340396 -98.995738)
		(width 0.1651)
		(layer "F.Cu")
		(net "M_L_DQ<39>")
	)
	(segment
		(start 120.649492 -142.6718)
		(end 120.649492 -143.941546)
		(width 0.1651)
		(layer "F.Cu")
		(net "M_L_DQ<39>")
	)
	(via
		(at 120.649492 -143.941546)
		(size 0.508)
		(drill 0.254)
		(layers "F.Cu" "B.Cu")
		(net "M_L_DQ<39>")
	)
	(via
		(at 121.499376 -139.932156)
		(size 0.508)
		(drill 0.254)
		(layers "F.Cu" "B.Cu")
		(net "M_L_DQ<39>")
	)
	(via
		(at 109.340396 -98.995738)
		(size 0.508)
		(drill 0.254)
		(layers "F.Cu" "B.Cu")
		(net "M_L_DQ<39>")
	)
	(segment
		(start 121.499376 -137.877296)
		(end 121.499376 -139.932156)
		(width 0.1651)
		(layer "B.Cu")
		(net "M_L_DQ<39>")
	)
	(segment
		(start 114.175286 -117.784118)
		(end 114.175286 -118.003066)
		(width 0.14224)
		(layer "In4.Cu")
		(net "M_L_DQ<39>")
	)
	(segment
		(start 110.710726 -100.186236)
		(end 110.74908 -100.258372)
		(width 0.0889)
		(layer "In4.Cu")
		(net "M_L_DQ<39>")
	)
	(segment
		(start 120.92178 -143.941546)
		(end 120.649492 -143.941546)
		(width 0.14224)
		(layer "In4.Cu")
		(net "M_L_DQ<39>")
	)
	(segment
		(start 113.600484 -117.428264)
		(end 113.819432 -117.428264)
		(width 0.14224)
		(layer "In4.Cu")
		(net "M_L_DQ<39>")
	)
	(segment
		(start 116.11864 -119.727472)
		(end 116.474494 -120.083326)
		(width 0.14224)
		(layer "In4.Cu")
		(net "M_L_DQ<39>")
	)
	(segment
		(start 117.624098 -121.451878)
		(end 117.462046 -121.61393)
		(width 0.14224)
		(layer "In4.Cu")
		(net "M_L_DQ<39>")
	)
	(segment
		(start 122.021346 -134.676134)
		(end 122.021346 -136.015222)
		(width 0.14224)
		(layer "In4.Cu")
		(net "M_L_DQ<39>")
	)
	(segment
		(start 117.268244 -120.877076)
		(end 117.624098 -121.23293)
		(width 0.14224)
		(layer "In4.Cu")
		(net "M_L_DQ<39>")
	)
	(segment
		(start 115.899692 -119.727472)
		(end 116.11864 -119.727472)
		(width 0.14224)
		(layer "In4.Cu")
		(net "M_L_DQ<39>")
	)
	(segment
		(start 117.624098 -121.23293)
		(end 117.624098 -121.451878)
		(width 0.14224)
		(layer "In4.Cu")
		(net "M_L_DQ<39>")
	)
	(segment
		(start 121.714768 -132.9436)
		(end 121.714768 -133.3754)
		(width 0.14224)
		(layer "In4.Cu")
		(net "M_L_DQ<39>")
	)
	(segment
		(start 117.049296 -120.877076)
		(end 117.268244 -120.877076)
		(width 0.14224)
		(layer "In4.Cu")
		(net "M_L_DQ<39>")
	)
	(segment
		(start 109.412532 -99.362514)
		(end 109.499146 -99.417124)
		(width 0.0889)
		(layer "In4.Cu")
		(net "M_L_DQ<39>")
	)
	(segment
		(start 122.146568 -131.064)
		(end 121.765568 -131.445)
		(width 0.14224)
		(layer "In4.Cu")
		(net "M_L_DQ<39>")
	)
	(segment
		(start 121.748804 -137.456164)
		(end 121.748804 -138.057636)
		(width 0.14224)
		(layer "In4.Cu")
		(net "M_L_DQ<39>")
	)
	(segment
		(start 122.019568 -138.7856)
		(end 121.852182 -138.952986)
		(width 0.14224)
		(layer "In4.Cu")
		(net "M_L_DQ<39>")
	)
	(segment
		(start 122.021346 -136.015222)
		(end 121.852182 -136.184386)
		(width 0.14224)
		(layer "In4.Cu")
		(net "M_L_DQ<39>")
	)
	(segment
		(start 113.219484 -117.590316)
		(end 113.438432 -117.590316)
		(width 0.14224)
		(layer "In4.Cu")
		(net "M_L_DQ<39>")
	)
	(segment
		(start 120.810782 -143.151352)
		(end 121.09958 -143.44015)
		(width 0.14224)
		(layer "In4.Cu")
		(net "M_L_DQ<39>")
	)
	(segment
		(start 121.09958 -143.763746)
		(end 120.92178 -143.941546)
		(width 0.14224)
		(layer "In4.Cu")
		(net "M_L_DQ<39>")
	)
	(segment
		(start 114.969036 -118.577868)
		(end 115.32489 -118.933722)
		(width 0.14224)
		(layer "In4.Cu")
		(net "M_L_DQ<39>")
	)
	(segment
		(start 116.668296 -121.039128)
		(end 116.887244 -121.039128)
		(width 0.14224)
		(layer "In4.Cu")
		(net "M_L_DQ<39>")
	)
	(segment
		(start 120.810782 -142.878048)
		(end 120.810782 -143.151352)
		(width 0.14224)
		(layer "In4.Cu")
		(net "M_L_DQ<39>")
	)
	(segment
		(start 121.852182 -136.58596)
		(end 122.019568 -136.753346)
		(width 0.14224)
		(layer "In4.Cu")
		(net "M_L_DQ<39>")
	)
	(segment
		(start 111.298482 -103.342694)
		(end 111.298482 -104.24414)
		(width 0.0889)
		(layer "In4.Cu")
		(net "M_L_DQ<39>")
	)
	(segment
		(start 121.852182 -136.184386)
		(end 121.852182 -136.58596)
		(width 0.14224)
		(layer "In4.Cu")
		(net "M_L_DQ<39>")
	)
	(segment
		(start 116.312442 -120.464326)
		(end 116.312442 -120.683274)
		(width 0.14224)
		(layer "In4.Cu")
		(net "M_L_DQ<39>")
	)
	(segment
		(start 114.013234 -118.384066)
		(end 114.369088 -118.73992)
		(width 0.14224)
		(layer "In4.Cu")
		(net "M_L_DQ<39>")
	)
	(segment
		(start 115.32489 -118.933722)
		(end 115.32489 -119.15267)
		(width 0.14224)
		(layer "In4.Cu")
		(net "M_L_DQ<39>")
	)
	(segment
		(start 122.019568 -138.3284)
		(end 122.019568 -138.7856)
		(width 0.14224)
		(layer "In4.Cu")
		(net "M_L_DQ<39>")
	)
	(segment
		(start 121.477024 -139.932156)
		(end 121.04878 -140.3604)
		(width 0.14224)
		(layer "In4.Cu")
		(net "M_L_DQ<39>")
	)
	(segment
		(start 121.852182 -139.590272)
		(end 121.84126 -139.590272)
		(width 0.14224)
		(layer "In4.Cu")
		(net "M_L_DQ<39>")
	)
	(segment
		(start 121.790968 -126.1618)
		(end 121.790968 -129.798064)
		(width 0.14224)
		(layer "In4.Cu")
		(net "M_L_DQ<39>")
	)
	(segment
		(start 110.74908 -102.793292)
		(end 111.298482 -103.342694)
		(width 0.0889)
		(layer "In4.Cu")
		(net "M_L_DQ<39>")
	)
	(segment
		(start 109.340396 -98.995738)
		(end 109.340396 -99.290378)
		(width 0.0889)
		(layer "In4.Cu")
		(net "M_L_DQ<39>")
	)
	(segment
		(start 114.750088 -118.577868)
		(end 114.969036 -118.577868)
		(width 0.14224)
		(layer "In4.Cu")
		(net "M_L_DQ<39>")
	)
	(segment
		(start 113.438432 -117.590316)
		(end 113.600484 -117.428264)
		(width 0.14224)
		(layer "In4.Cu")
		(net "M_L_DQ<39>")
	)
	(segment
		(start 121.04878 -140.790168)
		(end 121.09323 -140.834618)
		(width 0.14224)
		(layer "In4.Cu")
		(net "M_L_DQ<39>")
	)
	(segment
		(start 115.73764 -119.889524)
		(end 115.899692 -119.727472)
		(width 0.14224)
		(layer "In4.Cu")
		(net "M_L_DQ<39>")
	)
	(segment
		(start 114.013234 -118.165118)
		(end 114.013234 -118.384066)
		(width 0.14224)
		(layer "In4.Cu")
		(net "M_L_DQ<39>")
	)
	(segment
		(start 122.019568 -137.1854)
		(end 121.748804 -137.456164)
		(width 0.14224)
		(layer "In4.Cu")
		(net "M_L_DQ<39>")
	)
	(segment
		(start 115.162838 -119.314722)
		(end 115.162838 -119.53367)
		(width 0.14224)
		(layer "In4.Cu")
		(net "M_L_DQ<39>")
	)
	(segment
		(start 121.765568 -131.917186)
		(end 122.019568 -132.171186)
		(width 0.14224)
		(layer "In4.Cu")
		(net "M_L_DQ<39>")
	)
	(segment
		(start 120.810782 -141.785848)
		(end 120.810782 -142.059152)
		(width 0.14224)
		(layer "In4.Cu")
		(net "M_L_DQ<39>")
	)
	(segment
		(start 121.06783 -142.621)
		(end 120.810782 -142.878048)
		(width 0.14224)
		(layer "In4.Cu")
		(net "M_L_DQ<39>")
	)
	(segment
		(start 110.74908 -100.258372)
		(end 110.74908 -102.793292)
		(width 0.0889)
		(layer "In4.Cu")
		(net "M_L_DQ<39>")
	)
	(segment
		(start 116.312442 -120.683274)
		(end 116.668296 -121.039128)
		(width 0.14224)
		(layer "In4.Cu")
		(net "M_L_DQ<39>")
	)
	(segment
		(start 115.162838 -119.53367)
		(end 115.518692 -119.889524)
		(width 0.14224)
		(layer "In4.Cu")
		(net "M_L_DQ<39>")
	)
	(segment
		(start 121.852182 -138.952986)
		(end 121.852182 -139.590272)
		(width 0.14224)
		(layer "In4.Cu")
		(net "M_L_DQ<39>")
	)
	(segment
		(start 116.474494 -120.302274)
		(end 116.312442 -120.464326)
		(width 0.14224)
		(layer "In4.Cu")
		(net "M_L_DQ<39>")
	)
	(segment
		(start 115.518692 -119.889524)
		(end 115.73764 -119.889524)
		(width 0.14224)
		(layer "In4.Cu")
		(net "M_L_DQ<39>")
	)
	(segment
		(start 121.790968 -129.798064)
		(end 122.146568 -130.153664)
		(width 0.14224)
		(layer "In4.Cu")
		(net "M_L_DQ<39>")
	)
	(segment
		(start 121.06783 -142.3162)
		(end 121.06783 -142.621)
		(width 0.14224)
		(layer "In4.Cu")
		(net "M_L_DQ<39>")
	)
	(segment
		(start 111.584232 -115.955064)
		(end 113.219484 -117.590316)
		(width 0.14224)
		(layer "In4.Cu")
		(net "M_L_DQ<39>")
	)
	(segment
		(start 113.819432 -117.428264)
		(end 114.175286 -117.784118)
		(width 0.14224)
		(layer "In4.Cu")
		(net "M_L_DQ<39>")
	)
	(segment
		(start 111.584232 -104.52989)
		(end 111.584232 -115.955064)
		(width 0.14224)
		(layer "In4.Cu")
		(net "M_L_DQ<39>")
	)
	(segment
		(start 122.019568 -136.753346)
		(end 122.019568 -137.1854)
		(width 0.14224)
		(layer "In4.Cu")
		(net "M_L_DQ<39>")
	)
	(segment
		(start 121.09323 -140.834618)
		(end 121.09323 -141.5034)
		(width 0.14224)
		(layer "In4.Cu")
		(net "M_L_DQ<39>")
	)
	(segment
		(start 117.462046 -121.832878)
		(end 121.790968 -126.1618)
		(width 0.14224)
		(layer "In4.Cu")
		(net "M_L_DQ<39>")
	)
	(segment
		(start 121.877582 -134.53237)
		(end 122.021346 -134.676134)
		(width 0.14224)
		(layer "In4.Cu")
		(net "M_L_DQ<39>")
	)
	(segment
		(start 121.09323 -141.5034)
		(end 120.810782 -141.785848)
		(width 0.14224)
		(layer "In4.Cu")
		(net "M_L_DQ<39>")
	)
	(segment
		(start 116.887244 -121.039128)
		(end 117.049296 -120.877076)
		(width 0.14224)
		(layer "In4.Cu")
		(net "M_L_DQ<39>")
	)
	(segment
		(start 114.175286 -118.003066)
		(end 114.013234 -118.165118)
		(width 0.14224)
		(layer "In4.Cu")
		(net "M_L_DQ<39>")
	)
	(segment
		(start 114.369088 -118.73992)
		(end 114.588036 -118.73992)
		(width 0.14224)
		(layer "In4.Cu")
		(net "M_L_DQ<39>")
	)
	(segment
		(start 117.462046 -121.61393)
		(end 117.462046 -121.832878)
		(width 0.14224)
		(layer "In4.Cu")
		(net "M_L_DQ<39>")
	)
	(segment
		(start 116.474494 -120.083326)
		(end 116.474494 -120.302274)
		(width 0.14224)
		(layer "In4.Cu")
		(net "M_L_DQ<39>")
	)
	(segment
		(start 121.994168 -133.985)
		(end 121.877582 -134.101586)
		(width 0.14224)
		(layer "In4.Cu")
		(net "M_L_DQ<39>")
	)
	(segment
		(start 111.298482 -104.24414)
		(end 111.584232 -104.52989)
		(width 0.0889)
		(layer "In4.Cu")
		(net "M_L_DQ<39>")
	)
	(segment
		(start 109.340396 -99.290378)
		(end 109.412532 -99.362514)
		(width 0.0889)
		(layer "In4.Cu")
		(net "M_L_DQ<39>")
	)
	(segment
		(start 121.84126 -139.590272)
		(end 121.499376 -139.932156)
		(width 0.14224)
		(layer "In4.Cu")
		(net "M_L_DQ<39>")
	)
	(segment
		(start 115.32489 -119.15267)
		(end 115.162838 -119.314722)
		(width 0.14224)
		(layer "In4.Cu")
		(net "M_L_DQ<39>")
	)
	(segment
		(start 121.499376 -139.932156)
		(end 121.477024 -139.932156)
		(width 0.14224)
		(layer "In4.Cu")
		(net "M_L_DQ<39>")
	)
	(segment
		(start 110.18393 -99.890834)
		(end 110.216696 -99.890834)
		(width 0.0889)
		(layer "In4.Cu")
		(net "M_L_DQ<39>")
	)
	(segment
		(start 121.994168 -133.6548)
		(end 121.994168 -133.985)
		(width 0.14224)
		(layer "In4.Cu")
		(net "M_L_DQ<39>")
	)
	(segment
		(start 121.04878 -140.3604)
		(end 121.04878 -140.790168)
		(width 0.14224)
		(layer "In4.Cu")
		(net "M_L_DQ<39>")
	)
	(segment
		(start 121.714768 -133.3754)
		(end 121.994168 -133.6548)
		(width 0.14224)
		(layer "In4.Cu")
		(net "M_L_DQ<39>")
	)
	(segment
		(start 121.877582 -134.101586)
		(end 121.877582 -134.53237)
		(width 0.14224)
		(layer "In4.Cu")
		(net "M_L_DQ<39>")
	)
	(segment
		(start 122.019568 -132.171186)
		(end 122.019568 -132.6388)
		(width 0.14224)
		(layer "In4.Cu")
		(net "M_L_DQ<39>")
	)
	(segment
		(start 121.748804 -138.057636)
		(end 122.019568 -138.3284)
		(width 0.14224)
		(layer "In4.Cu")
		(net "M_L_DQ<39>")
	)
	(segment
		(start 120.810782 -142.059152)
		(end 121.06783 -142.3162)
		(width 0.14224)
		(layer "In4.Cu")
		(net "M_L_DQ<39>")
	)
	(segment
		(start 114.588036 -118.73992)
		(end 114.750088 -118.577868)
		(width 0.14224)
		(layer "In4.Cu")
		(net "M_L_DQ<39>")
	)
	(segment
		(start 121.765568 -131.445)
		(end 121.765568 -131.917186)
		(width 0.14224)
		(layer "In4.Cu")
		(net "M_L_DQ<39>")
	)
	(segment
		(start 121.09958 -143.44015)
		(end 121.09958 -143.763746)
		(width 0.14224)
		(layer "In4.Cu")
		(net "M_L_DQ<39>")
	)
	(segment
		(start 122.146568 -130.153664)
		(end 122.146568 -131.064)
		(width 0.14224)
		(layer "In4.Cu")
		(net "M_L_DQ<39>")
	)
	(segment
		(start 122.019568 -132.6388)
		(end 121.714768 -132.9436)
		(width 0.14224)
		(layer "In4.Cu")
		(net "M_L_DQ<39>")
	)
	(arc
		(start 109.852206 -99.690936)
		(mid 109.992285 -99.833672)
		(end 110.18393 -99.890834)
		(width 0.0889)
		(layer "In4.Cu")
		(net "M_L_DQ<39>")
	)
	(arc
		(start 110.216696 -99.890834)
		(mid 110.50212 -99.974301)
		(end 110.710726 -100.186236)
		(width 0.0889)
		(layer "In4.Cu")
		(net "M_L_DQ<39>")
	)
	(arc
		(start 109.499146 -99.417124)
		(mid 109.702601 -99.519309)
		(end 109.852206 -99.690936)
		(width 0.0889)
		(layer "In4.Cu")
		(net "M_L_DQ<39>")
	)
	(segment
		(start 121.49963 -146.304)
		(end 121.63171 -146.17192)
		(width 0.1651)
		(layer "F.Cu")
		(net "M_L_DQ<38>")
	)
	(segment
		(start 121.49963 -145.8214)
		(end 121.49963 -145.516854)
		(width 0.1651)
		(layer "F.Cu")
		(net "M_L_DQ<38>")
	)
	(segment
		(start 121.49963 -145.516854)
		(end 121.499376 -145.5166)
		(width 0.1651)
		(layer "F.Cu")
		(net "M_L_DQ<38>")
	)
	(segment
		(start 121.49963 -147.27174)
		(end 121.49963 -146.304)
		(width 0.1651)
		(layer "F.Cu")
		(net "M_L_DQ<38>")
	)
	(segment
		(start 108.768896 -97.014538)
		(end 109.340396 -97.014538)
		(width 0.1651)
		(layer "F.Cu")
		(net "M_L_DQ<38>")
	)
	(segment
		(start 121.499376 -147.27174)
		(end 121.49963 -147.27174)
		(width 0.1651)
		(layer "F.Cu")
		(net "M_L_DQ<38>")
	)
	(segment
		(start 121.63171 -146.17192)
		(end 121.63171 -145.95348)
		(width 0.1651)
		(layer "F.Cu")
		(net "M_L_DQ<38>")
	)
	(segment
		(start 121.63171 -145.95348)
		(end 121.49963 -145.8214)
		(width 0.1651)
		(layer "F.Cu")
		(net "M_L_DQ<38>")
	)
	(via
		(at 109.340396 -97.014538)
		(size 0.508)
		(drill 0.254)
		(layers "F.Cu" "B.Cu")
		(net "M_L_DQ<38>")
	)
	(via
		(at 120.649492 -141.213078)
		(size 0.508)
		(drill 0.254)
		(layers "F.Cu" "B.Cu")
		(net "M_L_DQ<38>")
	)
	(via
		(at 121.499376 -145.5166)
		(size 0.508)
		(drill 0.254)
		(layers "F.Cu" "B.Cu")
		(net "M_L_DQ<38>")
	)
	(segment
		(start 120.649492 -142.477236)
		(end 120.649492 -141.213078)
		(width 0.1651)
		(layer "B.Cu")
		(net "M_L_DQ<38>")
	)
	(segment
		(start 121.155968 -126.228856)
		(end 121.155968 -129.794)
		(width 0.14224)
		(layer "In4.Cu")
		(net "M_L_DQ<38>")
	)
	(segment
		(start 121.217182 -136.332468)
		(end 121.217182 -136.5758)
		(width 0.14224)
		(layer "In4.Cu")
		(net "M_L_DQ<38>")
	)
	(segment
		(start 110.559088 -100.307394)
		(end 110.559088 -102.872032)
		(width 0.0889)
		(layer "In4.Cu")
		(net "M_L_DQ<38>")
	)
	(segment
		(start 120.216422 -141.646148)
		(end 120.216422 -144.233646)
		(width 0.14224)
		(layer "In4.Cu")
		(net "M_L_DQ<38>")
	)
	(segment
		(start 121.073418 -138.80465)
		(end 121.217182 -138.948414)
		(width 0.14224)
		(layer "In4.Cu")
		(net "M_L_DQ<38>")
	)
	(segment
		(start 108.98886 -98.1964)
		(end 108.993686 -98.205036)
		(width 0.0889)
		(layer "In4.Cu")
		(net "M_L_DQ<38>")
	)
	(segment
		(start 120.901968 -131.0894)
		(end 121.257568 -131.445)
		(width 0.14224)
		(layer "In4.Cu")
		(net "M_L_DQ<38>")
	)
	(segment
		(start 120.480582 -141.044168)
		(end 120.649492 -141.213078)
		(width 0.14224)
		(layer "In4.Cu")
		(net "M_L_DQ<38>")
	)
	(segment
		(start 121.202704 -134.184136)
		(end 121.202704 -134.471664)
		(width 0.14224)
		(layer "In4.Cu")
		(net "M_L_DQ<38>")
	)
	(segment
		(start 121.202704 -134.471664)
		(end 120.800368 -134.874)
		(width 0.14224)
		(layer "In4.Cu")
		(net "M_L_DQ<38>")
	)
	(segment
		(start 121.217182 -138.948414)
		(end 121.217182 -139.400534)
		(width 0.14224)
		(layer "In4.Cu")
		(net "M_L_DQ<38>")
	)
	(segment
		(start 109.01045 -97.776284)
		(end 108.993686 -97.804986)
		(width 0.0889)
		(layer "In4.Cu")
		(net "M_L_DQ<38>")
	)
	(segment
		(start 121.079768 -134.0612)
		(end 121.202704 -134.184136)
		(width 0.14224)
		(layer "In4.Cu")
		(net "M_L_DQ<38>")
	)
	(segment
		(start 121.217182 -139.400534)
		(end 120.480582 -140.137134)
		(width 0.14224)
		(layer "In4.Cu")
		(net "M_L_DQ<38>")
	)
	(segment
		(start 110.54207 -100.275644)
		(end 110.559088 -100.307394)
		(width 0.0889)
		(layer "In4.Cu")
		(net "M_L_DQ<38>")
	)
	(segment
		(start 110.949232 -104.399588)
		(end 110.949232 -116.02212)
		(width 0.14224)
		(layer "In4.Cu")
		(net "M_L_DQ<38>")
	)
	(segment
		(start 121.257568 -131.445)
		(end 121.257568 -131.861814)
		(width 0.14224)
		(layer "In4.Cu")
		(net "M_L_DQ<38>")
	)
	(segment
		(start 121.217182 -136.5758)
		(end 121.073418 -136.719564)
		(width 0.14224)
		(layer "In4.Cu")
		(net "M_L_DQ<38>")
	)
	(segment
		(start 120.649492 -141.213078)
		(end 120.216422 -141.646148)
		(width 0.14224)
		(layer "In4.Cu")
		(net "M_L_DQ<38>")
	)
	(segment
		(start 108.993686 -98.205036)
		(end 109.000036 -98.215704)
		(width 0.0889)
		(layer "In4.Cu")
		(net "M_L_DQ<38>")
	)
	(segment
		(start 120.800368 -135.915654)
		(end 121.217182 -136.332468)
		(width 0.14224)
		(layer "In4.Cu")
		(net "M_L_DQ<38>")
	)
	(segment
		(start 121.257568 -131.861814)
		(end 121.079768 -132.039614)
		(width 0.14224)
		(layer "In4.Cu")
		(net "M_L_DQ<38>")
	)
	(segment
		(start 110.177326 -100.081334)
		(end 110.198916 -100.081334)
		(width 0.0889)
		(layer "In4.Cu")
		(net "M_L_DQ<38>")
	)
	(segment
		(start 120.800368 -134.874)
		(end 120.800368 -135.915654)
		(width 0.14224)
		(layer "In4.Cu")
		(net "M_L_DQ<38>")
	)
	(segment
		(start 120.901968 -130.048)
		(end 120.901968 -131.0894)
		(width 0.14224)
		(layer "In4.Cu")
		(net "M_L_DQ<38>")
	)
	(segment
		(start 121.155968 -129.794)
		(end 120.901968 -130.048)
		(width 0.14224)
		(layer "In4.Cu")
		(net "M_L_DQ<38>")
	)
	(segment
		(start 120.216422 -144.233646)
		(end 121.499376 -145.5166)
		(width 0.14224)
		(layer "In4.Cu")
		(net "M_L_DQ<38>")
	)
	(segment
		(start 121.073418 -136.719564)
		(end 121.073418 -138.80465)
		(width 0.14224)
		(layer "In4.Cu")
		(net "M_L_DQ<38>")
	)
	(segment
		(start 111.10849 -104.24033)
		(end 110.949232 -104.399588)
		(width 0.0889)
		(layer "In4.Cu")
		(net "M_L_DQ<38>")
	)
	(segment
		(start 121.079768 -132.039614)
		(end 121.079768 -134.0612)
		(width 0.14224)
		(layer "In4.Cu")
		(net "M_L_DQ<38>")
	)
	(segment
		(start 111.10849 -103.421434)
		(end 111.10849 -104.24033)
		(width 0.0889)
		(layer "In4.Cu")
		(net "M_L_DQ<38>")
	)
	(segment
		(start 109.077252 -99.297236)
		(end 109.287564 -99.507548)
		(width 0.0889)
		(layer "In4.Cu")
		(net "M_L_DQ<38>")
	)
	(segment
		(start 110.949232 -116.02212)
		(end 121.155968 -126.228856)
		(width 0.14224)
		(layer "In4.Cu")
		(net "M_L_DQ<38>")
	)
	(segment
		(start 109.340396 -97.014538)
		(end 109.01045 -97.776284)
		(width 0.0889)
		(layer "In4.Cu")
		(net "M_L_DQ<38>")
	)
	(segment
		(start 110.559088 -102.872032)
		(end 111.10849 -103.421434)
		(width 0.0889)
		(layer "In4.Cu")
		(net "M_L_DQ<38>")
	)
	(segment
		(start 120.480582 -140.137134)
		(end 120.480582 -141.044168)
		(width 0.14224)
		(layer "In4.Cu")
		(net "M_L_DQ<38>")
	)
	(arc
		(start 109.447076 -99.600512)
		(mid 109.585354 -99.669734)
		(end 109.687106 -99.786186)
		(width 0.0889)
		(layer "In4.Cu")
		(net "M_L_DQ<38>")
	)
	(arc
		(start 108.993686 -98.795586)
		(mid 108.945487 -99.061428)
		(end 109.077252 -99.297236)
		(width 0.0889)
		(layer "In4.Cu")
		(net "M_L_DQ<38>")
	)
	(arc
		(start 108.993686 -97.804986)
		(mid 108.940216 -98.000049)
		(end 108.98886 -98.1964)
		(width 0.0889)
		(layer "In4.Cu")
		(net "M_L_DQ<38>")
	)
	(arc
		(start 110.198916 -100.081334)
		(mid 110.396077 -100.133293)
		(end 110.54207 -100.275644)
		(width 0.0889)
		(layer "In4.Cu")
		(net "M_L_DQ<38>")
	)
	(arc
		(start 109.287564 -99.507548)
		(mid 109.361281 -99.564398)
		(end 109.447076 -99.600512)
		(width 0.0889)
		(layer "In4.Cu")
		(net "M_L_DQ<38>")
	)
	(arc
		(start 109.687106 -99.786186)
		(mid 109.89411 -99.99705)
		(end 110.177326 -100.081334)
		(width 0.0889)
		(layer "In4.Cu")
		(net "M_L_DQ<38>")
	)
	(arc
		(start 109.000036 -98.215704)
		(mid 109.072834 -98.506467)
		(end 108.993686 -98.795586)
		(width 0.0889)
		(layer "In4.Cu")
		(net "M_L_DQ<38>")
	)
	(segment
		(start 114.699542 -142.6718)
		(end 114.699542 -143.941546)
		(width 0.1651)
		(layer "F.Cu")
		(net "M_L_DQ<37>")
	)
	(segment
		(start 107.051856 -97.014538)
		(end 107.623356 -97.014538)
		(width 0.1651)
		(layer "F.Cu")
		(net "M_L_DQ<37>")
	)
	(via
		(at 107.623356 -97.014538)
		(size 0.508)
		(drill 0.254)
		(layers "F.Cu" "B.Cu")
		(net "M_L_DQ<37>")
	)
	(via
		(at 115.473226 -139.932156)
		(size 0.508)
		(drill 0.254)
		(layers "F.Cu" "B.Cu")
		(net "M_L_DQ<37>")
	)
	(via
		(at 114.699542 -143.941546)
		(size 0.508)
		(drill 0.254)
		(layers "F.Cu" "B.Cu")
		(net "M_L_DQ<37>")
	)
	(segment
		(start 115.549426 -137.877296)
		(end 115.549426 -139.855956)
		(width 0.1651)
		(layer "B.Cu")
		(net "M_L_DQ<37>")
	)
	(segment
		(start 115.549426 -139.855956)
		(end 115.473226 -139.932156)
		(width 0.1651)
		(layer "B.Cu")
		(net "M_L_DQ<37>")
	)
	(segment
		(start 114.860832 -143.297656)
		(end 115.12423 -143.561054)
		(width 0.14224)
		(layer "In4.Cu")
		(net "M_L_DQ<37>")
	)
	(segment
		(start 115.974368 -131.942586)
		(end 115.974368 -133.9342)
		(width 0.14224)
		(layer "In4.Cu")
		(net "M_L_DQ<37>")
	)
	(segment
		(start 115.857782 -138.927586)
		(end 115.857782 -139.5476)
		(width 0.14224)
		(layer "In4.Cu")
		(net "M_L_DQ<37>")
	)
	(segment
		(start 115.450874 -139.932156)
		(end 115.02263 -140.3604)
		(width 0.14224)
		(layer "In4.Cu")
		(net "M_L_DQ<37>")
	)
	(segment
		(start 115.974368 -138.811)
		(end 115.857782 -138.927586)
		(width 0.14224)
		(layer "In4.Cu")
		(net "M_L_DQ<37>")
	)
	(segment
		(start 107.286044 -97.014538)
		(end 107.223306 -97.077276)
		(width 0.0889)
		(layer "In4.Cu")
		(net "M_L_DQ<37>")
	)
	(segment
		(start 110.559596 -122.341386)
		(end 110.837472 -122.619262)
		(width 0.14224)
		(layer "In4.Cu")
		(net "M_L_DQ<37>")
	)
	(segment
		(start 115.473226 -139.932156)
		(end 115.450874 -139.932156)
		(width 0.14224)
		(layer "In4.Cu")
		(net "M_L_DQ<37>")
	)
	(segment
		(start 107.223306 -97.077276)
		(end 107.223306 -98.000312)
		(width 0.0889)
		(layer "In4.Cu")
		(net "M_L_DQ<37>")
	)
	(segment
		(start 115.12423 -143.561054)
		(end 115.12423 -143.789146)
		(width 0.14224)
		(layer "In4.Cu")
		(net "M_L_DQ<37>")
	)
	(segment
		(start 115.857782 -139.5476)
		(end 115.473226 -139.932156)
		(width 0.14224)
		(layer "In4.Cu")
		(net "M_L_DQ<37>")
	)
	(segment
		(start 115.883182 -131.8514)
		(end 115.974368 -131.942586)
		(width 0.14224)
		(layer "In4.Cu")
		(net "M_L_DQ<37>")
	)
	(segment
		(start 115.857782 -136.005824)
		(end 115.857782 -136.5504)
		(width 0.14224)
		(layer "In4.Cu")
		(net "M_L_DQ<37>")
	)
	(segment
		(start 114.860832 -141.817344)
		(end 114.860832 -142.154656)
		(width 0.14224)
		(layer "In4.Cu")
		(net "M_L_DQ<37>")
	)
	(segment
		(start 106.499406 -102.667816)
		(end 106.906314 -103.074724)
		(width 0.0889)
		(layer "In4.Cu")
		(net "M_L_DQ<37>")
	)
	(segment
		(start 106.49966 -98.723958)
		(end 106.49966 -99.052126)
		(width 0.0889)
		(layer "In4.Cu")
		(net "M_L_DQ<37>")
	)
	(segment
		(start 115.857782 -136.5504)
		(end 115.974368 -136.666986)
		(width 0.14224)
		(layer "In4.Cu")
		(net "M_L_DQ<37>")
	)
	(segment
		(start 115.946682 -129.994914)
		(end 115.946682 -131.370578)
		(width 0.14224)
		(layer "In4.Cu")
		(net "M_L_DQ<37>")
	)
	(segment
		(start 114.860832 -142.985744)
		(end 114.860832 -143.297656)
		(width 0.14224)
		(layer "In4.Cu")
		(net "M_L_DQ<37>")
	)
	(segment
		(start 106.499406 -99.05238)
		(end 106.499406 -102.667816)
		(width 0.0889)
		(layer "In4.Cu")
		(net "M_L_DQ<37>")
	)
	(segment
		(start 106.906314 -103.074724)
		(end 106.906314 -105.985056)
		(width 0.0889)
		(layer "In4.Cu")
		(net "M_L_DQ<37>")
	)
	(segment
		(start 110.837472 -122.619262)
		(end 111.125 -122.619262)
		(width 0.14224)
		(layer "In4.Cu")
		(net "M_L_DQ<37>")
	)
	(segment
		(start 107.113832 -106.192574)
		(end 107.113832 -118.895622)
		(width 0.14224)
		(layer "In4.Cu")
		(net "M_L_DQ<37>")
	)
	(segment
		(start 107.223306 -98.000312)
		(end 106.49966 -98.723958)
		(width 0.0889)
		(layer "In4.Cu")
		(net "M_L_DQ<37>")
	)
	(segment
		(start 116.010182 -135.853424)
		(end 115.857782 -136.005824)
		(width 0.14224)
		(layer "In4.Cu")
		(net "M_L_DQ<37>")
	)
	(segment
		(start 116.010182 -134.797038)
		(end 116.010182 -135.853424)
		(width 0.14224)
		(layer "In4.Cu")
		(net "M_L_DQ<37>")
	)
	(segment
		(start 110.607094 -121.169684)
		(end 110.868968 -121.431558)
		(width 0.14224)
		(layer "In4.Cu")
		(net "M_L_DQ<37>")
	)
	(segment
		(start 115.09883 -142.392654)
		(end 115.09883 -142.747746)
		(width 0.14224)
		(layer "In4.Cu")
		(net "M_L_DQ<37>")
	)
	(segment
		(start 115.883182 -131.434078)
		(end 115.883182 -131.8514)
		(width 0.14224)
		(layer "In4.Cu")
		(net "M_L_DQ<37>")
	)
	(segment
		(start 106.49966 -99.052126)
		(end 106.499406 -99.05238)
		(width 0.0889)
		(layer "In4.Cu")
		(net "M_L_DQ<37>")
	)
	(segment
		(start 110.294166 -121.169684)
		(end 110.607094 -121.169684)
		(width 0.14224)
		(layer "In4.Cu")
		(net "M_L_DQ<37>")
	)
	(segment
		(start 111.476536 -122.267726)
		(end 111.730282 -122.267726)
		(width 0.14224)
		(layer "In4.Cu")
		(net "M_L_DQ<37>")
	)
	(segment
		(start 115.694968 -126.232412)
		(end 115.694968 -129.7432)
		(width 0.14224)
		(layer "In4.Cu")
		(net "M_L_DQ<37>")
	)
	(segment
		(start 115.694968 -129.7432)
		(end 115.946682 -129.994914)
		(width 0.14224)
		(layer "In4.Cu")
		(net "M_L_DQ<37>")
	)
	(segment
		(start 110.559596 -122.053858)
		(end 110.559596 -122.341386)
		(width 0.14224)
		(layer "In4.Cu")
		(net "M_L_DQ<37>")
	)
	(segment
		(start 115.12423 -143.789146)
		(end 114.97183 -143.941546)
		(width 0.14224)
		(layer "In4.Cu")
		(net "M_L_DQ<37>")
	)
	(segment
		(start 114.860832 -142.154656)
		(end 115.09883 -142.392654)
		(width 0.14224)
		(layer "In4.Cu")
		(net "M_L_DQ<37>")
	)
	(segment
		(start 115.974368 -133.9342)
		(end 115.883182 -134.025386)
		(width 0.14224)
		(layer "In4.Cu")
		(net "M_L_DQ<37>")
	)
	(segment
		(start 115.14963 -141.0462)
		(end 115.14963 -141.528546)
		(width 0.14224)
		(layer "In4.Cu")
		(net "M_L_DQ<37>")
	)
	(segment
		(start 109.697266 -121.479056)
		(end 109.984794 -121.479056)
		(width 0.14224)
		(layer "In4.Cu")
		(net "M_L_DQ<37>")
	)
	(segment
		(start 109.984794 -121.479056)
		(end 110.294166 -121.169684)
		(width 0.14224)
		(layer "In4.Cu")
		(net "M_L_DQ<37>")
	)
	(segment
		(start 110.868968 -121.431558)
		(end 110.868968 -121.744486)
		(width 0.14224)
		(layer "In4.Cu")
		(net "M_L_DQ<37>")
	)
	(segment
		(start 115.974368 -136.666986)
		(end 115.974368 -138.811)
		(width 0.14224)
		(layer "In4.Cu")
		(net "M_L_DQ<37>")
	)
	(segment
		(start 111.730282 -122.267726)
		(end 115.694968 -126.232412)
		(width 0.14224)
		(layer "In4.Cu")
		(net "M_L_DQ<37>")
	)
	(segment
		(start 107.113832 -118.895622)
		(end 109.697266 -121.479056)
		(width 0.14224)
		(layer "In4.Cu")
		(net "M_L_DQ<37>")
	)
	(segment
		(start 115.883182 -134.025386)
		(end 115.883182 -134.670038)
		(width 0.14224)
		(layer "In4.Cu")
		(net "M_L_DQ<37>")
	)
	(segment
		(start 115.14963 -141.528546)
		(end 114.860832 -141.817344)
		(width 0.14224)
		(layer "In4.Cu")
		(net "M_L_DQ<37>")
	)
	(segment
		(start 111.125 -122.619262)
		(end 111.476536 -122.267726)
		(width 0.14224)
		(layer "In4.Cu")
		(net "M_L_DQ<37>")
	)
	(segment
		(start 115.883182 -134.670038)
		(end 116.010182 -134.797038)
		(width 0.14224)
		(layer "In4.Cu")
		(net "M_L_DQ<37>")
	)
	(segment
		(start 107.623356 -97.014538)
		(end 107.286044 -97.014538)
		(width 0.0889)
		(layer "In4.Cu")
		(net "M_L_DQ<37>")
	)
	(segment
		(start 106.906314 -105.985056)
		(end 107.113832 -106.192574)
		(width 0.0889)
		(layer "In4.Cu")
		(net "M_L_DQ<37>")
	)
	(segment
		(start 115.09883 -142.747746)
		(end 114.860832 -142.985744)
		(width 0.14224)
		(layer "In4.Cu")
		(net "M_L_DQ<37>")
	)
	(segment
		(start 114.97183 -143.941546)
		(end 114.699542 -143.941546)
		(width 0.14224)
		(layer "In4.Cu")
		(net "M_L_DQ<37>")
	)
	(segment
		(start 115.02263 -140.3604)
		(end 115.02263 -140.9192)
		(width 0.14224)
		(layer "In4.Cu")
		(net "M_L_DQ<37>")
	)
	(segment
		(start 115.02263 -140.9192)
		(end 115.14963 -141.0462)
		(width 0.14224)
		(layer "In4.Cu")
		(net "M_L_DQ<37>")
	)
	(segment
		(start 110.868968 -121.744486)
		(end 110.559596 -122.053858)
		(width 0.14224)
		(layer "In4.Cu")
		(net "M_L_DQ<37>")
	)
	(segment
		(start 115.946682 -131.370578)
		(end 115.883182 -131.434078)
		(width 0.14224)
		(layer "In4.Cu")
		(net "M_L_DQ<37>")
	)
	(segment
		(start 107.051856 -96.023938)
		(end 107.623356 -96.023938)
		(width 0.1651)
		(layer "F.Cu")
		(net "M_L_DQ<36>")
	)
	(segment
		(start 115.549426 -147.27174)
		(end 115.549426 -145.946368)
		(width 0.1651)
		(layer "F.Cu")
		(net "M_L_DQ<36>")
	)
	(segment
		(start 115.549426 -145.946368)
		(end 115.451382 -145.415)
		(width 0.1651)
		(layer "F.Cu")
		(net "M_L_DQ<36>")
	)
	(via
		(at 114.699542 -141.213078)
		(size 0.508)
		(drill 0.254)
		(layers "F.Cu" "B.Cu")
		(net "M_L_DQ<36>")
	)
	(via
		(at 115.451382 -145.415)
		(size 0.508)
		(drill 0.254)
		(layers "F.Cu" "B.Cu")
		(net "M_L_DQ<36>")
	)
	(via
		(at 107.623356 -96.023938)
		(size 0.508)
		(drill 0.254)
		(layers "F.Cu" "B.Cu")
		(net "M_L_DQ<36>")
	)
	(segment
		(start 114.699542 -142.477236)
		(end 114.699542 -141.213078)
		(width 0.1651)
		(layer "B.Cu")
		(net "M_L_DQ<36>")
	)
	(segment
		(start 114.42446 -144.63903)
		(end 115.20043 -145.415)
		(width 0.14224)
		(layer "In4.Cu")
		(net "M_L_DQ<36>")
	)
	(segment
		(start 115.184682 -139.358878)
		(end 114.561874 -139.981686)
		(width 0.14224)
		(layer "In4.Cu")
		(net "M_L_DQ<36>")
	)
	(segment
		(start 115.156996 -129.798064)
		(end 114.968782 -129.986278)
		(width 0.14224)
		(layer "In4.Cu")
		(net "M_L_DQ<36>")
	)
	(segment
		(start 114.986308 -134.66826)
		(end 114.986308 -135.981694)
		(width 0.14224)
		(layer "In4.Cu")
		(net "M_L_DQ<36>")
	)
	(segment
		(start 114.968782 -131.192778)
		(end 115.197382 -131.421378)
		(width 0.14224)
		(layer "In4.Cu")
		(net "M_L_DQ<36>")
	)
	(segment
		(start 115.197382 -131.421378)
		(end 115.197382 -134.457186)
		(width 0.14224)
		(layer "In4.Cu")
		(net "M_L_DQ<36>")
	)
	(segment
		(start 107.033314 -97.921572)
		(end 106.308906 -98.64598)
		(width 0.0889)
		(layer "In4.Cu")
		(net "M_L_DQ<36>")
	)
	(segment
		(start 115.20043 -145.415)
		(end 115.451382 -145.415)
		(width 0.14224)
		(layer "In4.Cu")
		(net "M_L_DQ<36>")
	)
	(segment
		(start 107.623356 -96.023938)
		(end 107.172252 -96.023938)
		(width 0.0889)
		(layer "In4.Cu")
		(net "M_L_DQ<36>")
	)
	(segment
		(start 106.715814 -105.894886)
		(end 106.478832 -106.131868)
		(width 0.0889)
		(layer "In4.Cu")
		(net "M_L_DQ<36>")
	)
	(segment
		(start 115.156996 -127.814832)
		(end 115.156996 -129.798064)
		(width 0.14224)
		(layer "In4.Cu")
		(net "M_L_DQ<36>")
	)
	(segment
		(start 114.968782 -129.986278)
		(end 114.968782 -131.192778)
		(width 0.14224)
		(layer "In4.Cu")
		(net "M_L_DQ<36>")
	)
	(segment
		(start 114.42446 -144.337278)
		(end 114.42446 -144.63903)
		(width 0.14224)
		(layer "In4.Cu")
		(net "M_L_DQ<36>")
	)
	(segment
		(start 114.699542 -141.213078)
		(end 114.266472 -141.646148)
		(width 0.14224)
		(layer "In4.Cu")
		(net "M_L_DQ<36>")
	)
	(segment
		(start 114.561874 -141.07541)
		(end 114.699542 -141.213078)
		(width 0.14224)
		(layer "In4.Cu")
		(net "M_L_DQ<36>")
	)
	(segment
		(start 114.266472 -141.646148)
		(end 114.266472 -144.17929)
		(width 0.14224)
		(layer "In4.Cu")
		(net "M_L_DQ<36>")
	)
	(segment
		(start 106.478832 -119.136668)
		(end 115.156996 -127.814832)
		(width 0.14224)
		(layer "In4.Cu")
		(net "M_L_DQ<36>")
	)
	(segment
		(start 106.308906 -98.64598)
		(end 106.308906 -102.746048)
		(width 0.0889)
		(layer "In4.Cu")
		(net "M_L_DQ<36>")
	)
	(segment
		(start 107.033314 -96.162876)
		(end 107.033314 -97.921572)
		(width 0.0889)
		(layer "In4.Cu")
		(net "M_L_DQ<36>")
	)
	(segment
		(start 107.172252 -96.023938)
		(end 107.033314 -96.162876)
		(width 0.0889)
		(layer "In4.Cu")
		(net "M_L_DQ<36>")
	)
	(segment
		(start 114.266472 -144.17929)
		(end 114.42446 -144.337278)
		(width 0.14224)
		(layer "In4.Cu")
		(net "M_L_DQ<36>")
	)
	(segment
		(start 115.197382 -134.457186)
		(end 114.986308 -134.66826)
		(width 0.14224)
		(layer "In4.Cu")
		(net "M_L_DQ<36>")
	)
	(segment
		(start 106.308906 -102.746048)
		(end 106.715814 -103.152956)
		(width 0.0889)
		(layer "In4.Cu")
		(net "M_L_DQ<36>")
	)
	(segment
		(start 114.561874 -139.981686)
		(end 114.561874 -141.07541)
		(width 0.14224)
		(layer "In4.Cu")
		(net "M_L_DQ<36>")
	)
	(segment
		(start 106.478832 -106.131868)
		(end 106.478832 -119.136668)
		(width 0.14224)
		(layer "In4.Cu")
		(net "M_L_DQ<36>")
	)
	(segment
		(start 114.986308 -135.981694)
		(end 115.184682 -136.180068)
		(width 0.14224)
		(layer "In4.Cu")
		(net "M_L_DQ<36>")
	)
	(segment
		(start 106.715814 -103.152956)
		(end 106.715814 -105.894886)
		(width 0.0889)
		(layer "In4.Cu")
		(net "M_L_DQ<36>")
	)
	(segment
		(start 115.184682 -136.180068)
		(end 115.184682 -139.358878)
		(width 0.14224)
		(layer "In4.Cu")
		(net "M_L_DQ<36>")
	)
	(segment
		(start 109.627416 -98.500184)
		(end 110.198916 -98.500184)
		(width 0.1651)
		(layer "F.Cu")
		(net "M_L_DQ<35>")
	)
	(segment
		(start 122.349514 -142.6718)
		(end 122.349514 -143.941546)
		(width 0.1651)
		(layer "F.Cu")
		(net "M_L_DQ<35>")
	)
	(via
		(at 110.198916 -98.500184)
		(size 0.508)
		(drill 0.254)
		(layers "F.Cu" "B.Cu")
		(net "M_L_DQ<35>")
	)
	(via
		(at 122.349514 -143.941546)
		(size 0.508)
		(drill 0.254)
		(layers "F.Cu" "B.Cu")
		(net "M_L_DQ<35>")
	)
	(via
		(at 123.199398 -139.932156)
		(size 0.508)
		(drill 0.254)
		(layers "F.Cu" "B.Cu")
		(net "M_L_DQ<35>")
	)
	(segment
		(start 123.199398 -137.877296)
		(end 123.199398 -139.932156)
		(width 0.1651)
		(layer "B.Cu")
		(net "M_L_DQ<35>")
	)
	(segment
		(start 121.99112 -124.831856)
		(end 122.170952 -124.831856)
		(width 0.14224)
		(layer "In4.Cu")
		(net "M_L_DQ<35>")
	)
	(segment
		(start 122.799602 -143.44015)
		(end 122.799602 -143.763746)
		(width 0.14224)
		(layer "In4.Cu")
		(net "M_L_DQ<35>")
	)
	(segment
		(start 122.621802 -143.941546)
		(end 122.349514 -143.941546)
		(width 0.14224)
		(layer "In4.Cu")
		(net "M_L_DQ<35>")
	)
	(segment
		(start 111.575342 -100.270818)
		(end 111.515652 -100.372926)
		(width 0.0889)
		(layer "In4.Cu")
		(net "M_L_DQ<35>")
	)
	(segment
		(start 123.619768 -132.080254)
		(end 123.619768 -134.0866)
		(width 0.14224)
		(layer "In4.Cu")
		(net "M_L_DQ<35>")
	)
	(segment
		(start 112.598454 -103.55834)
		(end 112.598454 -103.800656)
		(width 0.0889)
		(layer "In4.Cu")
		(net "M_L_DQ<35>")
	)
	(segment
		(start 122.510804 -142.059152)
		(end 122.767852 -142.3162)
		(width 0.14224)
		(layer "In4.Cu")
		(net "M_L_DQ<35>")
	)
	(segment
		(start 123.706382 -129.956814)
		(end 123.706382 -131.268978)
		(width 0.14224)
		(layer "In4.Cu")
		(net "M_L_DQ<35>")
	)
	(segment
		(start 123.619768 -134.0866)
		(end 123.566682 -134.139686)
		(width 0.14224)
		(layer "In4.Cu")
		(net "M_L_DQ<35>")
	)
	(segment
		(start 122.510804 -142.878048)
		(end 122.510804 -143.151352)
		(width 0.14224)
		(layer "In4.Cu")
		(net "M_L_DQ<35>")
	)
	(segment
		(start 122.793252 -141.5034)
		(end 122.510804 -141.785848)
		(width 0.14224)
		(layer "In4.Cu")
		(net "M_L_DQ<35>")
	)
	(segment
		(start 123.553982 -129.804414)
		(end 123.706382 -129.956814)
		(width 0.14224)
		(layer "In4.Cu")
		(net "M_L_DQ<35>")
	)
	(segment
		(start 122.170952 -124.831856)
		(end 122.389138 -124.61367)
		(width 0.14224)
		(layer "In4.Cu")
		(net "M_L_DQ<35>")
	)
	(segment
		(start 120.982486 -122.98807)
		(end 120.982486 -123.207018)
		(width 0.14224)
		(layer "In4.Cu")
		(net "M_L_DQ<35>")
	)
	(segment
		(start 120.73255 -122.738134)
		(end 120.982486 -122.98807)
		(width 0.14224)
		(layer "In4.Cu")
		(net "M_L_DQ<35>")
	)
	(segment
		(start 123.199398 -139.945364)
		(end 123.199398 -139.932156)
		(width 0.14224)
		(layer "In4.Cu")
		(net "M_L_DQ<35>")
	)
	(segment
		(start 112.598454 -103.800656)
		(end 112.856772 -104.058974)
		(width 0.0889)
		(layer "In4.Cu")
		(net "M_L_DQ<35>")
	)
	(segment
		(start 123.177046 -139.932156)
		(end 122.748802 -140.3604)
		(width 0.14224)
		(layer "In4.Cu")
		(net "M_L_DQ<35>")
	)
	(segment
		(start 119.793766 -122.73915)
		(end 120.043702 -122.989086)
		(width 0.14224)
		(layer "In4.Cu")
		(net "M_L_DQ<35>")
	)
	(segment
		(start 123.528582 -136.53516)
		(end 123.619768 -136.626346)
		(width 0.14224)
		(layer "In4.Cu")
		(net "M_L_DQ<35>")
	)
	(segment
		(start 123.467368 -131.507992)
		(end 123.467368 -131.927854)
		(width 0.14224)
		(layer "In4.Cu")
		(net "M_L_DQ<35>")
	)
	(segment
		(start 123.619768 -138.7856)
		(end 123.528582 -138.876786)
		(width 0.14224)
		(layer "In4.Cu")
		(net "M_L_DQ<35>")
	)
	(segment
		(start 120.26265 -122.989086)
		(end 120.513602 -122.738134)
		(width 0.14224)
		(layer "In4.Cu")
		(net "M_L_DQ<35>")
	)
	(segment
		(start 123.782582 -135.955532)
		(end 123.528582 -136.209532)
		(width 0.14224)
		(layer "In4.Cu")
		(net "M_L_DQ<35>")
	)
	(segment
		(start 123.566682 -134.139686)
		(end 123.566682 -134.523226)
		(width 0.14224)
		(layer "In4.Cu")
		(net "M_L_DQ<35>")
	)
	(segment
		(start 110.499652 -98.982276)
		(end 110.46079 -98.959416)
		(width 0.0889)
		(layer "In4.Cu")
		(net "M_L_DQ<35>")
	)
	(segment
		(start 123.528582 -136.209532)
		(end 123.528582 -136.53516)
		(width 0.14224)
		(layer "In4.Cu")
		(net "M_L_DQ<35>")
	)
	(segment
		(start 121.702068 -124.362972)
		(end 121.702068 -124.542804)
		(width 0.14224)
		(layer "In4.Cu")
		(net "M_L_DQ<35>")
	)
	(segment
		(start 120.044718 -122.26925)
		(end 119.793766 -122.520202)
		(width 0.14224)
		(layer "In4.Cu")
		(net "M_L_DQ<35>")
	)
	(segment
		(start 120.98147 -123.926854)
		(end 121.200418 -123.926854)
		(width 0.14224)
		(layer "In4.Cu")
		(net "M_L_DQ<35>")
	)
	(segment
		(start 122.767852 -142.621)
		(end 122.510804 -142.878048)
		(width 0.14224)
		(layer "In4.Cu")
		(net "M_L_DQ<35>")
	)
	(segment
		(start 120.043702 -122.989086)
		(end 120.26265 -122.989086)
		(width 0.14224)
		(layer "In4.Cu")
		(net "M_L_DQ<35>")
	)
	(segment
		(start 120.513602 -122.738134)
		(end 120.73255 -122.738134)
		(width 0.14224)
		(layer "In4.Cu")
		(net "M_L_DQ<35>")
	)
	(segment
		(start 123.706382 -131.268978)
		(end 123.467368 -131.507992)
		(width 0.14224)
		(layer "In4.Cu")
		(net "M_L_DQ<35>")
	)
	(segment
		(start 123.553982 -127.823214)
		(end 123.553982 -129.804414)
		(width 0.14224)
		(layer "In4.Cu")
		(net "M_L_DQ<35>")
	)
	(segment
		(start 122.748802 -140.3604)
		(end 122.748802 -140.790168)
		(width 0.14224)
		(layer "In4.Cu")
		(net "M_L_DQ<35>")
	)
	(segment
		(start 123.566682 -134.523226)
		(end 123.782582 -134.739126)
		(width 0.14224)
		(layer "In4.Cu")
		(net "M_L_DQ<35>")
	)
	(segment
		(start 122.748802 -140.790168)
		(end 122.793252 -140.834618)
		(width 0.14224)
		(layer "In4.Cu")
		(net "M_L_DQ<35>")
	)
	(segment
		(start 120.044718 -122.050302)
		(end 120.044718 -122.26925)
		(width 0.14224)
		(layer "In4.Cu")
		(net "M_L_DQ<35>")
	)
	(segment
		(start 120.731534 -123.676918)
		(end 120.98147 -123.926854)
		(width 0.14224)
		(layer "In4.Cu")
		(net "M_L_DQ<35>")
	)
	(segment
		(start 112.856772 -114.862356)
		(end 120.044718 -122.050302)
		(width 0.14224)
		(layer "In4.Cu")
		(net "M_L_DQ<35>")
	)
	(segment
		(start 111.515652 -102.475538)
		(end 112.598454 -103.55834)
		(width 0.0889)
		(layer "In4.Cu")
		(net "M_L_DQ<35>")
	)
	(segment
		(start 120.731534 -123.45797)
		(end 120.731534 -123.676918)
		(width 0.14224)
		(layer "In4.Cu")
		(net "M_L_DQ<35>")
	)
	(segment
		(start 122.389138 -124.61367)
		(end 122.608086 -124.61367)
		(width 0.14224)
		(layer "In4.Cu")
		(net "M_L_DQ<35>")
	)
	(segment
		(start 122.510804 -141.785848)
		(end 122.510804 -142.059152)
		(width 0.14224)
		(layer "In4.Cu")
		(net "M_L_DQ<35>")
	)
	(segment
		(start 121.702068 -124.542804)
		(end 121.99112 -124.831856)
		(width 0.14224)
		(layer "In4.Cu")
		(net "M_L_DQ<35>")
	)
	(segment
		(start 121.920254 -124.144786)
		(end 121.702068 -124.362972)
		(width 0.14224)
		(layer "In4.Cu")
		(net "M_L_DQ<35>")
	)
	(segment
		(start 110.710726 -99.195636)
		(end 110.714028 -99.201478)
		(width 0.0889)
		(layer "In4.Cu")
		(net "M_L_DQ<35>")
	)
	(segment
		(start 123.467368 -131.927854)
		(end 123.619768 -132.080254)
		(width 0.14224)
		(layer "In4.Cu")
		(net "M_L_DQ<35>")
	)
	(segment
		(start 123.528582 -138.876786)
		(end 123.528582 -139.61618)
		(width 0.14224)
		(layer "In4.Cu")
		(net "M_L_DQ<35>")
	)
	(segment
		(start 111.057182 -99.395788)
		(end 111.078772 -99.395788)
		(width 0.0889)
		(layer "In4.Cu")
		(net "M_L_DQ<35>")
	)
	(segment
		(start 121.920254 -123.925838)
		(end 121.920254 -124.144786)
		(width 0.14224)
		(layer "In4.Cu")
		(net "M_L_DQ<35>")
	)
	(segment
		(start 122.793252 -140.834618)
		(end 122.793252 -141.5034)
		(width 0.14224)
		(layer "In4.Cu")
		(net "M_L_DQ<35>")
	)
	(segment
		(start 121.45137 -123.675902)
		(end 121.670318 -123.675902)
		(width 0.14224)
		(layer "In4.Cu")
		(net "M_L_DQ<35>")
	)
	(segment
		(start 122.767852 -142.3162)
		(end 122.767852 -142.621)
		(width 0.14224)
		(layer "In4.Cu")
		(net "M_L_DQ<35>")
	)
	(segment
		(start 120.982486 -123.207018)
		(end 120.731534 -123.45797)
		(width 0.14224)
		(layer "In4.Cu")
		(net "M_L_DQ<35>")
	)
	(segment
		(start 111.515652 -100.372926)
		(end 111.515652 -102.475538)
		(width 0.0889)
		(layer "In4.Cu")
		(net "M_L_DQ<35>")
	)
	(segment
		(start 123.528582 -139.61618)
		(end 123.199398 -139.945364)
		(width 0.14224)
		(layer "In4.Cu")
		(net "M_L_DQ<35>")
	)
	(segment
		(start 123.619768 -136.626346)
		(end 123.619768 -138.7856)
		(width 0.14224)
		(layer "In4.Cu")
		(net "M_L_DQ<35>")
	)
	(segment
		(start 123.111768 -127.381)
		(end 123.553982 -127.823214)
		(width 0.14224)
		(layer "In4.Cu")
		(net "M_L_DQ<35>")
	)
	(segment
		(start 122.799602 -143.763746)
		(end 122.621802 -143.941546)
		(width 0.14224)
		(layer "In4.Cu")
		(net "M_L_DQ<35>")
	)
	(segment
		(start 123.199398 -139.932156)
		(end 123.177046 -139.932156)
		(width 0.14224)
		(layer "In4.Cu")
		(net "M_L_DQ<35>")
	)
	(segment
		(start 121.670318 -123.675902)
		(end 121.920254 -123.925838)
		(width 0.14224)
		(layer "In4.Cu")
		(net "M_L_DQ<35>")
	)
	(segment
		(start 122.510804 -143.151352)
		(end 122.799602 -143.44015)
		(width 0.14224)
		(layer "In4.Cu")
		(net "M_L_DQ<35>")
	)
	(segment
		(start 112.856772 -104.058974)
		(end 112.856772 -114.862356)
		(width 0.14224)
		(layer "In4.Cu")
		(net "M_L_DQ<35>")
	)
	(segment
		(start 123.111768 -125.117352)
		(end 123.111768 -127.381)
		(width 0.14224)
		(layer "In4.Cu")
		(net "M_L_DQ<35>")
	)
	(segment
		(start 123.782582 -134.739126)
		(end 123.782582 -135.955532)
		(width 0.14224)
		(layer "In4.Cu")
		(net "M_L_DQ<35>")
	)
	(segment
		(start 122.608086 -124.61367)
		(end 123.111768 -125.117352)
		(width 0.14224)
		(layer "In4.Cu")
		(net "M_L_DQ<35>")
	)
	(segment
		(start 121.200418 -123.926854)
		(end 121.45137 -123.675902)
		(width 0.14224)
		(layer "In4.Cu")
		(net "M_L_DQ<35>")
	)
	(segment
		(start 119.793766 -122.520202)
		(end 119.793766 -122.73915)
		(width 0.14224)
		(layer "In4.Cu")
		(net "M_L_DQ<35>")
	)
	(arc
		(start 110.46079 -98.959416)
		(mid 110.268916 -98.764534)
		(end 110.198916 -98.500184)
		(width 0.0889)
		(layer "In4.Cu")
		(net "M_L_DQ<35>")
	)
	(arc
		(start 111.078772 -99.395788)
		(mid 111.571162 -99.694721)
		(end 111.575342 -100.270818)
		(width 0.0889)
		(layer "In4.Cu")
		(net "M_L_DQ<35>")
	)
	(arc
		(start 110.714028 -99.201478)
		(mid 110.859994 -99.343877)
		(end 111.057182 -99.395788)
		(width 0.0889)
		(layer "In4.Cu")
		(net "M_L_DQ<35>")
	)
	(arc
		(start 110.499652 -98.982276)
		(mid 110.61895 -99.07534)
		(end 110.710726 -99.195636)
		(width 0.0889)
		(layer "In4.Cu")
		(net "M_L_DQ<35>")
	)
	(segment
		(start 109.627416 -97.509584)
		(end 110.198916 -97.509584)
		(width 0.1651)
		(layer "F.Cu")
		(net "M_L_DQ<34>")
	)
	(segment
		(start 123.199398 -147.27174)
		(end 123.199398 -146.280632)
		(width 0.1651)
		(layer "F.Cu")
		(net "M_L_DQ<34>")
	)
	(segment
		(start 123.199398 -145.793968)
		(end 123.199398 -145.5166)
		(width 0.1651)
		(layer "F.Cu")
		(net "M_L_DQ<34>")
	)
	(segment
		(start 123.199398 -146.280632)
		(end 123.33097 -146.14906)
		(width 0.1651)
		(layer "F.Cu")
		(net "M_L_DQ<34>")
	)
	(segment
		(start 123.33097 -146.14906)
		(end 123.33097 -145.92554)
		(width 0.1651)
		(layer "F.Cu")
		(net "M_L_DQ<34>")
	)
	(segment
		(start 123.33097 -145.92554)
		(end 123.199398 -145.793968)
		(width 0.1651)
		(layer "F.Cu")
		(net "M_L_DQ<34>")
	)
	(via
		(at 122.349514 -141.213078)
		(size 0.508)
		(drill 0.254)
		(layers "F.Cu" "B.Cu")
		(net "M_L_DQ<34>")
	)
	(via
		(at 110.198916 -97.509584)
		(size 0.508)
		(drill 0.254)
		(layers "F.Cu" "B.Cu")
		(net "M_L_DQ<34>")
	)
	(via
		(at 123.199398 -145.5166)
		(size 0.508)
		(drill 0.254)
		(layers "F.Cu" "B.Cu")
		(net "M_L_DQ<34>")
	)
	(segment
		(start 122.349514 -142.477236)
		(end 122.349514 -141.213078)
		(width 0.1651)
		(layer "B.Cu")
		(net "M_L_DQ<34>")
	)
	(segment
		(start 122.732038 -131.348734)
		(end 122.83313 -131.449826)
		(width 0.14224)
		(layer "In4.Cu")
		(net "M_L_DQ<34>")
	)
	(segment
		(start 122.732038 -129.91973)
		(end 122.732038 -131.348734)
		(width 0.14224)
		(layer "In4.Cu")
		(net "M_L_DQ<34>")
	)
	(segment
		(start 118.23192 -121.135648)
		(end 118.23192 -121.866152)
		(width 0.14224)
		(layer "In4.Cu")
		(net "M_L_DQ<34>")
	)
	(segment
		(start 122.78614 -129.865628)
		(end 122.732038 -129.91973)
		(width 0.14224)
		(layer "In4.Cu")
		(net "M_L_DQ<34>")
	)
	(segment
		(start 111.039402 -99.586288)
		(end 111.072168 -99.586288)
		(width 0.0889)
		(layer "In4.Cu")
		(net "M_L_DQ<34>")
	)
	(segment
		(start 112.408462 -103.848154)
		(end 112.221772 -104.034844)
		(width 0.0889)
		(layer "In4.Cu")
		(net "M_L_DQ<34>")
	)
	(segment
		(start 122.004582 -140.868146)
		(end 122.349514 -141.213078)
		(width 0.14224)
		(layer "In4.Cu")
		(net "M_L_DQ<34>")
	)
	(segment
		(start 122.83313 -131.449826)
		(end 122.83313 -134.51713)
		(width 0.14224)
		(layer "In4.Cu")
		(net "M_L_DQ<34>")
	)
	(segment
		(start 122.83313 -134.51713)
		(end 122.639582 -134.710678)
		(width 0.14224)
		(layer "In4.Cu")
		(net "M_L_DQ<34>")
	)
	(segment
		(start 122.78614 -129.188972)
		(end 122.78614 -129.865628)
		(width 0.14224)
		(layer "In4.Cu")
		(net "M_L_DQ<34>")
	)
	(segment
		(start 121.916444 -144.233646)
		(end 123.199398 -145.5166)
		(width 0.14224)
		(layer "In4.Cu")
		(net "M_L_DQ<34>")
	)
	(segment
		(start 110.54207 -99.285044)
		(end 110.545372 -99.290886)
		(width 0.0889)
		(layer "In4.Cu")
		(net "M_L_DQ<34>")
	)
	(segment
		(start 110.048294 -98.871024)
		(end 110.254796 -99.077526)
		(width 0.0889)
		(layer "In4.Cu")
		(net "M_L_DQ<34>")
	)
	(segment
		(start 111.325152 -100.721414)
		(end 111.32566 -100.721922)
		(width 0.0889)
		(layer "In4.Cu")
		(net "M_L_DQ<34>")
	)
	(segment
		(start 111.41075 -100.17379)
		(end 111.325152 -100.321872)
		(width 0.0889)
		(layer "In4.Cu")
		(net "M_L_DQ<34>")
	)
	(segment
		(start 118.23192 -121.866152)
		(end 122.476768 -126.111)
		(width 0.14224)
		(layer "In4.Cu")
		(net "M_L_DQ<34>")
	)
	(segment
		(start 111.325152 -100.321872)
		(end 111.325152 -100.721414)
		(width 0.0889)
		(layer "In4.Cu")
		(net "M_L_DQ<34>")
	)
	(segment
		(start 122.349514 -141.213078)
		(end 121.916444 -141.646148)
		(width 0.14224)
		(layer "In4.Cu")
		(net "M_L_DQ<34>")
	)
	(segment
		(start 122.799602 -136.136888)
		(end 122.799602 -139.440158)
		(width 0.14224)
		(layer "In4.Cu")
		(net "M_L_DQ<34>")
	)
	(segment
		(start 110.198916 -97.509584)
		(end 110.154466 -97.509584)
		(width 0.0889)
		(layer "In4.Cu")
		(net "M_L_DQ<34>")
	)
	(segment
		(start 122.004582 -140.235178)
		(end 122.004582 -140.868146)
		(width 0.14224)
		(layer "In4.Cu")
		(net "M_L_DQ<34>")
	)
	(segment
		(start 122.639582 -135.976868)
		(end 122.799602 -136.136888)
		(width 0.14224)
		(layer "In4.Cu")
		(net "M_L_DQ<34>")
	)
	(segment
		(start 122.639582 -134.710678)
		(end 122.639582 -135.976868)
		(width 0.14224)
		(layer "In4.Cu")
		(net "M_L_DQ<34>")
	)
	(segment
		(start 122.476768 -128.8796)
		(end 122.78614 -129.188972)
		(width 0.14224)
		(layer "In4.Cu")
		(net "M_L_DQ<34>")
	)
	(segment
		(start 112.408462 -103.63708)
		(end 112.408462 -103.848154)
		(width 0.0889)
		(layer "In4.Cu")
		(net "M_L_DQ<34>")
	)
	(segment
		(start 121.916444 -141.646148)
		(end 121.916444 -144.233646)
		(width 0.14224)
		(layer "In4.Cu")
		(net "M_L_DQ<34>")
	)
	(segment
		(start 112.221772 -115.1255)
		(end 118.23192 -121.135648)
		(width 0.14224)
		(layer "In4.Cu")
		(net "M_L_DQ<34>")
	)
	(segment
		(start 112.221772 -104.034844)
		(end 112.221772 -104.247696)
		(width 0.0889)
		(layer "In4.Cu")
		(net "M_L_DQ<34>")
	)
	(segment
		(start 111.32566 -100.721922)
		(end 111.32566 -102.554278)
		(width 0.0889)
		(layer "In4.Cu")
		(net "M_L_DQ<34>")
	)
	(segment
		(start 122.799602 -139.440158)
		(end 122.004582 -140.235178)
		(width 0.14224)
		(layer "In4.Cu")
		(net "M_L_DQ<34>")
	)
	(segment
		(start 122.476768 -126.111)
		(end 122.476768 -128.8796)
		(width 0.14224)
		(layer "In4.Cu")
		(net "M_L_DQ<34>")
	)
	(segment
		(start 112.221772 -104.247696)
		(end 112.221772 -115.1255)
		(width 0.14224)
		(layer "In4.Cu")
		(net "M_L_DQ<34>")
	)
	(segment
		(start 111.32566 -102.554278)
		(end 112.408462 -103.63708)
		(width 0.0889)
		(layer "In4.Cu")
		(net "M_L_DQ<34>")
	)
	(arc
		(start 109.858556 -98.289618)
		(mid 109.84146 -98.32044)
		(end 109.82706 -98.35261)
		(width 0.0889)
		(layer "In4.Cu")
		(net "M_L_DQ<34>")
	)
	(arc
		(start 110.254796 -99.077526)
		(mid 110.27603 -99.093785)
		(end 110.30077 -99.103942)
		(width 0.0889)
		(layer "In4.Cu")
		(net "M_L_DQ<34>")
	)
	(arc
		(start 109.82706 -98.35261)
		(mid 109.83083 -98.657413)
		(end 110.048294 -98.871024)
		(width 0.0889)
		(layer "In4.Cu")
		(net "M_L_DQ<34>")
	)
	(arc
		(start 111.072168 -99.586288)
		(mid 111.404012 -99.786405)
		(end 111.41075 -100.17379)
		(width 0.0889)
		(layer "In4.Cu")
		(net "M_L_DQ<34>")
	)
	(arc
		(start 110.154466 -97.509584)
		(mid 109.948624 -97.612676)
		(end 109.907832 -97.839276)
		(width 0.0889)
		(layer "In4.Cu")
		(net "M_L_DQ<34>")
	)
	(arc
		(start 110.30077 -99.103942)
		(mid 110.439151 -99.170874)
		(end 110.54207 -99.285044)
		(width 0.0889)
		(layer "In4.Cu")
		(net "M_L_DQ<34>")
	)
	(arc
		(start 109.907832 -97.839276)
		(mid 109.928281 -98.069381)
		(end 109.858556 -98.289618)
		(width 0.0889)
		(layer "In4.Cu")
		(net "M_L_DQ<34>")
	)
	(arc
		(start 110.545372 -99.290886)
		(mid 110.75398 -99.502818)
		(end 111.039402 -99.586288)
		(width 0.0889)
		(layer "In4.Cu")
		(net "M_L_DQ<34>")
	)
	(segment
		(start 107.051856 -99.986338)
		(end 107.623356 -99.986338)
		(width 0.1651)
		(layer "F.Cu")
		(net "M_L_DQ<33>")
	)
	(segment
		(start 116.399564 -142.6718)
		(end 116.399564 -143.941546)
		(width 0.1651)
		(layer "F.Cu")
		(net "M_L_DQ<33>")
	)
	(via
		(at 116.399564 -143.941546)
		(size 0.508)
		(drill 0.254)
		(layers "F.Cu" "B.Cu")
		(net "M_L_DQ<33>")
	)
	(via
		(at 117.071648 -139.932156)
		(size 0.508)
		(drill 0.254)
		(layers "F.Cu" "B.Cu")
		(net "M_L_DQ<33>")
	)
	(via
		(at 107.623356 -99.986338)
		(size 0.508)
		(drill 0.254)
		(layers "F.Cu" "B.Cu")
		(net "M_L_DQ<33>")
	)
	(segment
		(start 117.071648 -139.428982)
		(end 117.071648 -139.932156)
		(width 0.1651)
		(layer "B.Cu")
		(net "M_L_DQ<33>")
	)
	(segment
		(start 117.249448 -137.877296)
		(end 117.249448 -139.251182)
		(width 0.1651)
		(layer "B.Cu")
		(net "M_L_DQ<33>")
	)
	(segment
		(start 117.249448 -139.251182)
		(end 117.071648 -139.428982)
		(width 0.1651)
		(layer "B.Cu")
		(net "M_L_DQ<33>")
	)
	(segment
		(start 116.80063 -143.4846)
		(end 116.80063 -143.7894)
		(width 0.14224)
		(layer "In4.Cu")
		(net "M_L_DQ<33>")
	)
	(segment
		(start 108.168186 -106.088688)
		(end 108.383832 -106.304334)
		(width 0.0889)
		(layer "In4.Cu")
		(net "M_L_DQ<33>")
	)
	(segment
		(start 116.80063 -143.7894)
		(end 116.648484 -143.941546)
		(width 0.14224)
		(layer "In4.Cu")
		(net "M_L_DQ<33>")
	)
	(segment
		(start 117.255544 -127.216154)
		(end 117.397784 -127.358394)
		(width 0.14224)
		(layer "In4.Cu")
		(net "M_L_DQ<33>")
	)
	(segment
		(start 116.947188 -128.60274)
		(end 117.180868 -128.60274)
		(width 0.14224)
		(layer "In4.Cu")
		(net "M_L_DQ<33>")
	)
	(segment
		(start 116.77523 -142.7226)
		(end 116.560854 -142.936976)
		(width 0.14224)
		(layer "In4.Cu")
		(net "M_L_DQ<33>")
	)
	(segment
		(start 117.162072 -132.746496)
		(end 117.162072 -133.099556)
		(width 0.14224)
		(layer "In4.Cu")
		(net "M_L_DQ<33>")
	)
	(segment
		(start 116.560854 -142.076424)
		(end 116.77523 -142.2908)
		(width 0.14224)
		(layer "In4.Cu")
		(net "M_L_DQ<33>")
	)
	(segment
		(start 117.397784 -127.358394)
		(end 117.404134 -127.358394)
		(width 0.14224)
		(layer "In4.Cu")
		(net "M_L_DQ<33>")
	)
	(segment
		(start 107.223306 -100.06838)
		(end 107.223306 -102.368604)
		(width 0.0889)
		(layer "In4.Cu")
		(net "M_L_DQ<33>")
	)
	(segment
		(start 117.99062 -138.252454)
		(end 117.99062 -138.547348)
		(width 0.14224)
		(layer "In4.Cu")
		(net "M_L_DQ<33>")
	)
	(segment
		(start 117.559582 -139.355322)
		(end 117.071648 -139.843256)
		(width 0.14224)
		(layer "In4.Cu")
		(net "M_L_DQ<33>")
	)
	(segment
		(start 107.623356 -99.986338)
		(end 107.305348 -99.986338)
		(width 0.0889)
		(layer "In4.Cu")
		(net "M_L_DQ<33>")
	)
	(segment
		(start 117.99062 -137.279634)
		(end 117.83568 -137.434574)
		(width 0.14224)
		(layer "In4.Cu")
		(net "M_L_DQ<33>")
	)
	(segment
		(start 116.560854 -143.244824)
		(end 116.80063 -143.4846)
		(width 0.14224)
		(layer "In4.Cu")
		(net "M_L_DQ<33>")
	)
	(segment
		(start 117.094762 -137.942574)
		(end 117.249702 -138.097514)
		(width 0.14224)
		(layer "In4.Cu")
		(net "M_L_DQ<33>")
	)
	(segment
		(start 116.85143 -141.425168)
		(end 116.560854 -141.715744)
		(width 0.14224)
		(layer "In4.Cu")
		(net "M_L_DQ<33>")
	)
	(segment
		(start 117.249702 -138.097514)
		(end 117.83568 -138.097514)
		(width 0.14224)
		(layer "In4.Cu")
		(net "M_L_DQ<33>")
	)
	(segment
		(start 116.621052 -140.3604)
		(end 116.621052 -140.790168)
		(width 0.14224)
		(layer "In4.Cu")
		(net "M_L_DQ<33>")
	)
	(segment
		(start 117.323362 -128.745234)
		(end 117.323362 -129.009394)
		(width 0.14224)
		(layer "In4.Cu")
		(net "M_L_DQ<33>")
	)
	(segment
		(start 117.9703 -132.17017)
		(end 117.9703 -132.443474)
		(width 0.14224)
		(layer "In4.Cu")
		(net "M_L_DQ<33>")
	)
	(segment
		(start 117.249702 -137.434574)
		(end 117.094762 -137.589514)
		(width 0.14224)
		(layer "In4.Cu")
		(net "M_L_DQ<33>")
	)
	(segment
		(start 117.071648 -139.932156)
		(end 117.049296 -139.932156)
		(width 0.14224)
		(layer "In4.Cu")
		(net "M_L_DQ<33>")
	)
	(segment
		(start 117.559074 -127.513334)
		(end 117.559074 -127.866394)
		(width 0.14224)
		(layer "In4.Cu")
		(net "M_L_DQ<33>")
	)
	(segment
		(start 117.180868 -128.60274)
		(end 117.323362 -128.745234)
		(width 0.14224)
		(layer "In4.Cu")
		(net "M_L_DQ<33>")
	)
	(segment
		(start 117.255544 -125.978666)
		(end 117.255544 -127.216154)
		(width 0.14224)
		(layer "In4.Cu")
		(net "M_L_DQ<33>")
	)
	(segment
		(start 117.404134 -127.358394)
		(end 117.559074 -127.513334)
		(width 0.14224)
		(layer "In4.Cu")
		(net "M_L_DQ<33>")
	)
	(segment
		(start 107.305348 -99.986338)
		(end 107.223306 -100.06838)
		(width 0.0889)
		(layer "In4.Cu")
		(net "M_L_DQ<33>")
	)
	(segment
		(start 117.32387 -133.261354)
		(end 117.81536 -133.261354)
		(width 0.14224)
		(layer "In4.Cu")
		(net "M_L_DQ<33>")
	)
	(segment
		(start 117.559582 -134.130034)
		(end 117.559582 -136.58596)
		(width 0.14224)
		(layer "In4.Cu")
		(net "M_L_DQ<33>")
	)
	(segment
		(start 117.9703 -132.443474)
		(end 117.81536 -132.598414)
		(width 0.14224)
		(layer "In4.Cu")
		(net "M_L_DQ<33>")
	)
	(segment
		(start 107.223306 -102.368604)
		(end 108.168186 -103.313484)
		(width 0.0889)
		(layer "In4.Cu")
		(net "M_L_DQ<33>")
	)
	(segment
		(start 117.9703 -133.416294)
		(end 117.9703 -133.719316)
		(width 0.14224)
		(layer "In4.Cu")
		(net "M_L_DQ<33>")
	)
	(segment
		(start 117.559582 -129.245614)
		(end 117.559582 -131.759452)
		(width 0.14224)
		(layer "In4.Cu")
		(net "M_L_DQ<33>")
	)
	(segment
		(start 117.99062 -138.547348)
		(end 117.559582 -138.978386)
		(width 0.14224)
		(layer "In4.Cu")
		(net "M_L_DQ<33>")
	)
	(segment
		(start 116.959888 -128.021334)
		(end 116.804948 -128.176274)
		(width 0.14224)
		(layer "In4.Cu")
		(net "M_L_DQ<33>")
	)
	(segment
		(start 117.094762 -137.589514)
		(end 117.094762 -137.942574)
		(width 0.14224)
		(layer "In4.Cu")
		(net "M_L_DQ<33>")
	)
	(segment
		(start 108.383832 -117.106954)
		(end 117.255544 -125.978666)
		(width 0.14224)
		(layer "In4.Cu")
		(net "M_L_DQ<33>")
	)
	(segment
		(start 117.81536 -133.261354)
		(end 117.9703 -133.416294)
		(width 0.14224)
		(layer "In4.Cu")
		(net "M_L_DQ<33>")
	)
	(segment
		(start 117.559582 -136.58596)
		(end 117.99062 -137.016998)
		(width 0.14224)
		(layer "In4.Cu")
		(net "M_L_DQ<33>")
	)
	(segment
		(start 117.559074 -127.866394)
		(end 117.404134 -128.021334)
		(width 0.14224)
		(layer "In4.Cu")
		(net "M_L_DQ<33>")
	)
	(segment
		(start 117.559582 -131.759452)
		(end 117.9703 -132.17017)
		(width 0.14224)
		(layer "In4.Cu")
		(net "M_L_DQ<33>")
	)
	(segment
		(start 116.804948 -128.176274)
		(end 116.804948 -128.4605)
		(width 0.14224)
		(layer "In4.Cu")
		(net "M_L_DQ<33>")
	)
	(segment
		(start 108.168186 -103.313484)
		(end 108.168186 -106.088688)
		(width 0.0889)
		(layer "In4.Cu")
		(net "M_L_DQ<33>")
	)
	(segment
		(start 116.648484 -143.941546)
		(end 116.399564 -143.941546)
		(width 0.14224)
		(layer "In4.Cu")
		(net "M_L_DQ<33>")
	)
	(segment
		(start 116.85143 -141.020546)
		(end 116.85143 -141.425168)
		(width 0.14224)
		(layer "In4.Cu")
		(net "M_L_DQ<33>")
	)
	(segment
		(start 117.071648 -139.843256)
		(end 117.071648 -139.932156)
		(width 0.14224)
		(layer "In4.Cu")
		(net "M_L_DQ<33>")
	)
	(segment
		(start 108.383832 -106.304334)
		(end 108.383832 -117.106954)
		(width 0.14224)
		(layer "In4.Cu")
		(net "M_L_DQ<33>")
	)
	(segment
		(start 116.804948 -128.4605)
		(end 116.947188 -128.60274)
		(width 0.14224)
		(layer "In4.Cu")
		(net "M_L_DQ<33>")
	)
	(segment
		(start 116.621052 -140.790168)
		(end 116.85143 -141.020546)
		(width 0.14224)
		(layer "In4.Cu")
		(net "M_L_DQ<33>")
	)
	(segment
		(start 117.9703 -133.719316)
		(end 117.559582 -134.130034)
		(width 0.14224)
		(layer "In4.Cu")
		(net "M_L_DQ<33>")
	)
	(segment
		(start 117.310154 -132.598414)
		(end 117.162072 -132.746496)
		(width 0.14224)
		(layer "In4.Cu")
		(net "M_L_DQ<33>")
	)
	(segment
		(start 117.404134 -128.021334)
		(end 116.959888 -128.021334)
		(width 0.14224)
		(layer "In4.Cu")
		(net "M_L_DQ<33>")
	)
	(segment
		(start 117.049296 -139.932156)
		(end 116.621052 -140.3604)
		(width 0.14224)
		(layer "In4.Cu")
		(net "M_L_DQ<33>")
	)
	(segment
		(start 116.560854 -142.936976)
		(end 116.560854 -143.244824)
		(width 0.14224)
		(layer "In4.Cu")
		(net "M_L_DQ<33>")
	)
	(segment
		(start 117.99062 -137.016998)
		(end 117.99062 -137.279634)
		(width 0.14224)
		(layer "In4.Cu")
		(net "M_L_DQ<33>")
	)
	(segment
		(start 117.559582 -138.978386)
		(end 117.559582 -139.355322)
		(width 0.14224)
		(layer "In4.Cu")
		(net "M_L_DQ<33>")
	)
	(segment
		(start 117.83568 -138.097514)
		(end 117.99062 -138.252454)
		(width 0.14224)
		(layer "In4.Cu")
		(net "M_L_DQ<33>")
	)
	(segment
		(start 117.323362 -129.009394)
		(end 117.559582 -129.245614)
		(width 0.14224)
		(layer "In4.Cu")
		(net "M_L_DQ<33>")
	)
	(segment
		(start 117.83568 -137.434574)
		(end 117.249702 -137.434574)
		(width 0.14224)
		(layer "In4.Cu")
		(net "M_L_DQ<33>")
	)
	(segment
		(start 116.560854 -141.715744)
		(end 116.560854 -142.076424)
		(width 0.14224)
		(layer "In4.Cu")
		(net "M_L_DQ<33>")
	)
	(segment
		(start 117.162072 -133.099556)
		(end 117.32387 -133.261354)
		(width 0.14224)
		(layer "In4.Cu")
		(net "M_L_DQ<33>")
	)
	(segment
		(start 116.77523 -142.2908)
		(end 116.77523 -142.7226)
		(width 0.14224)
		(layer "In4.Cu")
		(net "M_L_DQ<33>")
	)
	(segment
		(start 117.81536 -132.598414)
		(end 117.310154 -132.598414)
		(width 0.14224)
		(layer "In4.Cu")
		(net "M_L_DQ<33>")
	)
	(segment
		(start 107.051856 -98.995738)
		(end 107.623356 -98.995738)
		(width 0.1651)
		(layer "F.Cu")
		(net "M_L_DQ<32>")
	)
	(segment
		(start 117.249448 -147.27174)
		(end 117.249448 -147.277582)
		(width 0.1651)
		(layer "F.Cu")
		(net "M_L_DQ<32>")
	)
	(segment
		(start 117.249448 -147.277582)
		(end 117.071648 -145.415)
		(width 0.1651)
		(layer "F.Cu")
		(net "M_L_DQ<32>")
	)
	(via
		(at 116.399564 -141.213078)
		(size 0.508)
		(drill 0.254)
		(layers "F.Cu" "B.Cu")
		(net "M_L_DQ<32>")
	)
	(via
		(at 107.623356 -98.995738)
		(size 0.508)
		(drill 0.254)
		(layers "F.Cu" "B.Cu")
		(net "M_L_DQ<32>")
	)
	(via
		(at 117.071648 -145.415)
		(size 0.508)
		(drill 0.254)
		(layers "F.Cu" "B.Cu")
		(net "M_L_DQ<32>")
	)
	(segment
		(start 116.399564 -142.477236)
		(end 116.399564 -141.213078)
		(width 0.1651)
		(layer "B.Cu")
		(net "M_L_DQ<32>")
	)
	(segment
		(start 116.259356 -128.783588)
		(end 116.924582 -129.448814)
		(width 0.14224)
		(layer "In4.Cu")
		(net "M_L_DQ<32>")
	)
	(segment
		(start 116.594382 -134.761986)
		(end 116.594382 -135.976614)
		(width 0.14224)
		(layer "In4.Cu")
		(net "M_L_DQ<32>")
	)
	(segment
		(start 107.137708 -98.995738)
		(end 107.032806 -99.10064)
		(width 0.0889)
		(layer "In4.Cu")
		(net "M_L_DQ<32>")
	)
	(segment
		(start 116.873782 -131.434078)
		(end 116.873782 -131.826)
		(width 0.14224)
		(layer "In4.Cu")
		(net "M_L_DQ<32>")
	)
	(segment
		(start 107.032806 -99.10064)
		(end 107.032806 -102.446836)
		(width 0.0889)
		(layer "In4.Cu")
		(net "M_L_DQ<32>")
	)
	(segment
		(start 115.966494 -141.646148)
		(end 115.966494 -144.60601)
		(width 0.14224)
		(layer "In4.Cu")
		(net "M_L_DQ<32>")
	)
	(segment
		(start 110.471458 -120.094502)
		(end 116.259356 -125.8824)
		(width 0.14224)
		(layer "In4.Cu")
		(net "M_L_DQ<32>")
	)
	(segment
		(start 116.535708 -138.58494)
		(end 116.886482 -138.935714)
		(width 0.14224)
		(layer "In4.Cu")
		(net "M_L_DQ<32>")
	)
	(segment
		(start 116.535708 -137.002774)
		(end 116.535708 -138.58494)
		(width 0.14224)
		(layer "In4.Cu")
		(net "M_L_DQ<32>")
	)
	(segment
		(start 109.31271 -119.816372)
		(end 109.31271 -120.103392)
		(width 0.14224)
		(layer "In4.Cu")
		(net "M_L_DQ<32>")
	)
	(segment
		(start 116.775484 -145.415)
		(end 117.071648 -145.415)
		(width 0.14224)
		(layer "In4.Cu")
		(net "M_L_DQ<32>")
	)
	(segment
		(start 108.237274 -118.5926)
		(end 108.237274 -118.873016)
		(width 0.14224)
		(layer "In4.Cu")
		(net "M_L_DQ<32>")
	)
	(segment
		(start 116.609622 -132.09016)
		(end 116.609622 -133.807454)
		(width 0.14224)
		(layer "In4.Cu")
		(net "M_L_DQ<32>")
	)
	(segment
		(start 115.966494 -144.60601)
		(end 116.775484 -145.415)
		(width 0.14224)
		(layer "In4.Cu")
		(net "M_L_DQ<32>")
	)
	(segment
		(start 116.581682 -131.141978)
		(end 116.873782 -131.434078)
		(width 0.14224)
		(layer "In4.Cu")
		(net "M_L_DQ<32>")
	)
	(segment
		(start 109.887766 -120.391174)
		(end 110.184438 -120.094502)
		(width 0.14224)
		(layer "In4.Cu")
		(net "M_L_DQ<32>")
	)
	(segment
		(start 109.321854 -118.944898)
		(end 109.609636 -119.23268)
		(width 0.14224)
		(layer "In4.Cu")
		(net "M_L_DQ<32>")
	)
	(segment
		(start 116.886482 -136.652)
		(end 116.535708 -137.002774)
		(width 0.14224)
		(layer "In4.Cu")
		(net "M_L_DQ<32>")
	)
	(segment
		(start 109.31271 -120.103392)
		(end 109.600492 -120.391174)
		(width 0.14224)
		(layer "In4.Cu")
		(net "M_L_DQ<32>")
	)
	(segment
		(start 108.818934 -119.160798)
		(end 109.034834 -118.944898)
		(width 0.14224)
		(layer "In4.Cu")
		(net "M_L_DQ<32>")
	)
	(segment
		(start 116.259356 -125.8824)
		(end 116.259356 -128.783588)
		(width 0.14224)
		(layer "In4.Cu")
		(net "M_L_DQ<32>")
	)
	(segment
		(start 116.886482 -139.358878)
		(end 116.035582 -140.209778)
		(width 0.14224)
		(layer "In4.Cu")
		(net "M_L_DQ<32>")
	)
	(segment
		(start 116.609622 -133.807454)
		(end 116.873782 -134.071614)
		(width 0.14224)
		(layer "In4.Cu")
		(net "M_L_DQ<32>")
	)
	(segment
		(start 116.873782 -134.071614)
		(end 116.873782 -134.482586)
		(width 0.14224)
		(layer "In4.Cu")
		(net "M_L_DQ<32>")
	)
	(segment
		(start 116.873782 -131.826)
		(end 116.609622 -132.09016)
		(width 0.14224)
		(layer "In4.Cu")
		(net "M_L_DQ<32>")
	)
	(segment
		(start 107.748832 -117.371876)
		(end 108.460032 -118.083076)
		(width 0.14224)
		(layer "In4.Cu")
		(net "M_L_DQ<32>")
	)
	(segment
		(start 109.600492 -120.391174)
		(end 109.887766 -120.391174)
		(width 0.14224)
		(layer "In4.Cu")
		(net "M_L_DQ<32>")
	)
	(segment
		(start 116.886482 -138.935714)
		(end 116.886482 -139.358878)
		(width 0.14224)
		(layer "In4.Cu")
		(net "M_L_DQ<32>")
	)
	(segment
		(start 116.035582 -140.849096)
		(end 116.399564 -141.213078)
		(width 0.14224)
		(layer "In4.Cu")
		(net "M_L_DQ<32>")
	)
	(segment
		(start 109.609636 -119.23268)
		(end 109.609636 -119.519446)
		(width 0.14224)
		(layer "In4.Cu")
		(net "M_L_DQ<32>")
	)
	(segment
		(start 108.460032 -118.083076)
		(end 108.460032 -118.369842)
		(width 0.14224)
		(layer "In4.Cu")
		(net "M_L_DQ<32>")
	)
	(segment
		(start 108.460032 -118.369842)
		(end 108.237274 -118.5926)
		(width 0.14224)
		(layer "In4.Cu")
		(net "M_L_DQ<32>")
	)
	(segment
		(start 116.035582 -140.209778)
		(end 116.035582 -140.849096)
		(width 0.14224)
		(layer "In4.Cu")
		(net "M_L_DQ<32>")
	)
	(segment
		(start 116.924582 -129.448814)
		(end 116.924582 -129.719578)
		(width 0.14224)
		(layer "In4.Cu")
		(net "M_L_DQ<32>")
	)
	(segment
		(start 107.748832 -106.301794)
		(end 107.748832 -117.371876)
		(width 0.14224)
		(layer "In4.Cu")
		(net "M_L_DQ<32>")
	)
	(segment
		(start 116.873782 -134.482586)
		(end 116.594382 -134.761986)
		(width 0.14224)
		(layer "In4.Cu")
		(net "M_L_DQ<32>")
	)
	(segment
		(start 116.594382 -135.976614)
		(end 116.886482 -136.268714)
		(width 0.14224)
		(layer "In4.Cu")
		(net "M_L_DQ<32>")
	)
	(segment
		(start 108.237274 -118.873016)
		(end 108.525056 -119.160798)
		(width 0.14224)
		(layer "In4.Cu")
		(net "M_L_DQ<32>")
	)
	(segment
		(start 107.978194 -106.072432)
		(end 107.748832 -106.301794)
		(width 0.0889)
		(layer "In4.Cu")
		(net "M_L_DQ<32>")
	)
	(segment
		(start 109.609636 -119.519446)
		(end 109.31271 -119.816372)
		(width 0.14224)
		(layer "In4.Cu")
		(net "M_L_DQ<32>")
	)
	(segment
		(start 110.184438 -120.094502)
		(end 110.471458 -120.094502)
		(width 0.14224)
		(layer "In4.Cu")
		(net "M_L_DQ<32>")
	)
	(segment
		(start 107.978194 -103.392224)
		(end 107.978194 -106.072432)
		(width 0.0889)
		(layer "In4.Cu")
		(net "M_L_DQ<32>")
	)
	(segment
		(start 116.399564 -141.213078)
		(end 115.966494 -141.646148)
		(width 0.14224)
		(layer "In4.Cu")
		(net "M_L_DQ<32>")
	)
	(segment
		(start 109.034834 -118.944898)
		(end 109.321854 -118.944898)
		(width 0.14224)
		(layer "In4.Cu")
		(net "M_L_DQ<32>")
	)
	(segment
		(start 107.032806 -102.446836)
		(end 107.978194 -103.392224)
		(width 0.0889)
		(layer "In4.Cu")
		(net "M_L_DQ<32>")
	)
	(segment
		(start 108.525056 -119.160798)
		(end 108.818934 -119.160798)
		(width 0.14224)
		(layer "In4.Cu")
		(net "M_L_DQ<32>")
	)
	(segment
		(start 116.886482 -136.268714)
		(end 116.886482 -136.652)
		(width 0.14224)
		(layer "In4.Cu")
		(net "M_L_DQ<32>")
	)
	(segment
		(start 116.924582 -129.719578)
		(end 116.581682 -130.062478)
		(width 0.14224)
		(layer "In4.Cu")
		(net "M_L_DQ<32>")
	)
	(segment
		(start 116.581682 -130.062478)
		(end 116.581682 -131.141978)
		(width 0.14224)
		(layer "In4.Cu")
		(net "M_L_DQ<32>")
	)
	(segment
		(start 107.623356 -98.995738)
		(end 107.137708 -98.995738)
		(width 0.0889)
		(layer "In4.Cu")
		(net "M_L_DQ<32>")
	)
	(segment
		(start 66.239898 -122.004328)
		(end 66.239898 -121.671588)
		(width 0.1651)
		(layer "F.Cu")
		(net "M_L_DQ<31>")
	)
	(segment
		(start 65.247774 -120.123204)
		(end 65.06591 -119.94134)
		(width 0.1651)
		(layer "F.Cu")
		(net "M_L_DQ<31>")
	)
	(segment
		(start 66.239898 -118.909592)
		(end 66.08699 -118.756684)
		(width 0.1651)
		(layer "F.Cu")
		(net "M_L_DQ<31>")
	)
	(segment
		(start 66.051176 -120.123204)
		(end 65.247774 -120.123204)
		(width 0.1651)
		(layer "F.Cu")
		(net "M_L_DQ<31>")
	)
	(segment
		(start 66.077338 -119.439944)
		(end 66.239898 -119.277384)
		(width 0.1651)
		(layer "F.Cu")
		(net "M_L_DQ<31>")
	)
	(segment
		(start 65.656968 -122.348244)
		(end 65.832228 -122.172984)
		(width 0.1651)
		(layer "F.Cu")
		(net "M_L_DQ<31>")
	)
	(segment
		(start 66.077084 -120.806464)
		(end 66.23939 -120.644158)
		(width 0.1651)
		(layer "F.Cu")
		(net "M_L_DQ<31>")
	)
	(segment
		(start 72.637396 -107.314746)
		(end 74.986388 -104.965754)
		(width 0.1016)
		(layer "F.Cu")
		(net "M_L_DQ<31>")
	)
	(segment
		(start 65.656968 -122.680984)
		(end 65.656968 -122.348244)
		(width 0.1651)
		(layer "F.Cu")
		(net "M_L_DQ<31>")
	)
	(segment
		(start 66.249296 -125.410976)
		(end 66.596768 -125.410976)
		(width 0.1651)
		(layer "F.Cu")
		(net "M_L_DQ<31>")
	)
	(segment
		(start 79.691992 -103.01605)
		(end 77.742288 -104.965754)
		(width 0.1016)
		(layer "F.Cu")
		(net "M_L_DQ<31>")
	)
	(segment
		(start 66.18859 -112.206532)
		(end 71.080376 -107.314746)
		(width 0.1651)
		(layer "F.Cu")
		(net "M_L_DQ<31>")
	)
	(segment
		(start 74.986388 -104.965754)
		(end 76.830174 -104.965754)
		(width 0.1016)
		(layer "F.Cu")
		(net "M_L_DQ<31>")
	)
	(segment
		(start 66.058034 -121.489724)
		(end 65.832228 -121.489724)
		(width 0.1651)
		(layer "F.Cu")
		(net "M_L_DQ<31>")
	)
	(segment
		(start 65.254124 -118.756684)
		(end 65.085214 -118.587774)
		(width 0.1651)
		(layer "F.Cu")
		(net "M_L_DQ<31>")
	)
	(segment
		(start 66.392044 -115.414298)
		(end 66.18859 -115.210844)
		(width 0.1651)
		(layer "F.Cu")
		(net "M_L_DQ<31>")
	)
	(segment
		(start 65.234566 -119.439944)
		(end 66.077338 -119.439944)
		(width 0.1651)
		(layer "F.Cu")
		(net "M_L_DQ<31>")
	)
	(segment
		(start 65.06591 -119.6086)
		(end 65.234566 -119.439944)
		(width 0.1651)
		(layer "F.Cu")
		(net "M_L_DQ<31>")
	)
	(segment
		(start 66.00444 -113.445036)
		(end 66.00444 -113.249456)
		(width 0.1651)
		(layer "F.Cu")
		(net "M_L_DQ<31>")
	)
	(segment
		(start 65.266824 -118.073424)
		(end 66.01333 -118.073424)
		(width 0.1651)
		(layer "F.Cu")
		(net "M_L_DQ<31>")
	)
	(segment
		(start 66.392044 -115.686332)
		(end 66.392044 -115.414298)
		(width 0.1651)
		(layer "F.Cu")
		(net "M_L_DQ<31>")
	)
	(segment
		(start 66.18859 -113.629186)
		(end 66.00444 -113.445036)
		(width 0.1651)
		(layer "F.Cu")
		(net "M_L_DQ<31>")
	)
	(segment
		(start 65.656968 -120.981724)
		(end 65.832228 -120.806464)
		(width 0.1651)
		(layer "F.Cu")
		(net "M_L_DQ<31>")
	)
	(segment
		(start 65.832228 -122.856244)
		(end 65.656968 -122.680984)
		(width 0.1651)
		(layer "F.Cu")
		(net "M_L_DQ<31>")
	)
	(segment
		(start 66.071242 -122.172984)
		(end 66.239898 -122.004328)
		(width 0.1651)
		(layer "F.Cu")
		(net "M_L_DQ<31>")
	)
	(segment
		(start 66.23939 -120.644158)
		(end 66.23939 -120.311418)
		(width 0.1651)
		(layer "F.Cu")
		(net "M_L_DQ<31>")
	)
	(segment
		(start 66.00444 -113.249456)
		(end 66.18859 -113.065306)
		(width 0.1651)
		(layer "F.Cu")
		(net "M_L_DQ<31>")
	)
	(segment
		(start 79.768192 -101.15804)
		(end 79.768192 -102.93985)
		(width 0.0889)
		(layer "F.Cu")
		(net "M_L_DQ<31>")
	)
	(segment
		(start 77.742288 -104.965754)
		(end 76.830174 -104.965754)
		(width 0.1016)
		(layer "F.Cu")
		(net "M_L_DQ<31>")
	)
	(segment
		(start 66.23939 -120.311418)
		(end 66.051176 -120.123204)
		(width 0.1651)
		(layer "F.Cu")
		(net "M_L_DQ<31>")
	)
	(segment
		(start 66.723768 -125.283976)
		(end 66.723768 -124.2822)
		(width 0.1651)
		(layer "F.Cu")
		(net "M_L_DQ<31>")
	)
	(segment
		(start 65.06591 -119.94134)
		(end 65.06591 -119.6086)
		(width 0.1651)
		(layer "F.Cu")
		(net "M_L_DQ<31>")
	)
	(segment
		(start 66.18859 -123.031504)
		(end 66.01333 -122.856244)
		(width 0.1651)
		(layer "F.Cu")
		(net "M_L_DQ<31>")
	)
	(segment
		(start 66.01333 -122.856244)
		(end 65.832228 -122.856244)
		(width 0.1651)
		(layer "F.Cu")
		(net "M_L_DQ<31>")
	)
	(segment
		(start 66.18859 -117.898164)
		(end 66.18859 -115.889786)
		(width 0.1651)
		(layer "F.Cu")
		(net "M_L_DQ<31>")
	)
	(segment
		(start 66.18859 -123.747022)
		(end 66.18859 -123.031504)
		(width 0.1651)
		(layer "F.Cu")
		(net "M_L_DQ<31>")
	)
	(segment
		(start 66.723768 -124.2822)
		(end 66.18859 -123.747022)
		(width 0.1651)
		(layer "F.Cu")
		(net "M_L_DQ<31>")
	)
	(segment
		(start 66.18859 -115.889786)
		(end 66.392044 -115.686332)
		(width 0.1651)
		(layer "F.Cu")
		(net "M_L_DQ<31>")
	)
	(segment
		(start 65.656968 -121.314464)
		(end 65.656968 -120.981724)
		(width 0.1651)
		(layer "F.Cu")
		(net "M_L_DQ<31>")
	)
	(segment
		(start 66.596768 -125.410976)
		(end 66.723768 -125.283976)
		(width 0.1651)
		(layer "F.Cu")
		(net "M_L_DQ<31>")
	)
	(segment
		(start 79.768192 -102.93985)
		(end 79.691992 -103.01605)
		(width 0.0889)
		(layer "F.Cu")
		(net "M_L_DQ<31>")
	)
	(segment
		(start 65.832228 -122.172984)
		(end 66.071242 -122.172984)
		(width 0.1651)
		(layer "F.Cu")
		(net "M_L_DQ<31>")
	)
	(segment
		(start 66.01333 -118.073424)
		(end 66.18859 -117.898164)
		(width 0.1651)
		(layer "F.Cu")
		(net "M_L_DQ<31>")
	)
	(segment
		(start 66.18859 -115.210844)
		(end 66.18859 -113.629186)
		(width 0.1651)
		(layer "F.Cu")
		(net "M_L_DQ<31>")
	)
	(segment
		(start 65.832228 -121.489724)
		(end 65.656968 -121.314464)
		(width 0.1651)
		(layer "F.Cu")
		(net "M_L_DQ<31>")
	)
	(segment
		(start 66.08699 -118.756684)
		(end 65.254124 -118.756684)
		(width 0.1651)
		(layer "F.Cu")
		(net "M_L_DQ<31>")
	)
	(segment
		(start 72.427592 -107.314746)
		(end 72.637396 -107.314746)
		(width 0.1016)
		(layer "F.Cu")
		(net "M_L_DQ<31>")
	)
	(segment
		(start 65.085214 -118.255034)
		(end 65.266824 -118.073424)
		(width 0.1651)
		(layer "F.Cu")
		(net "M_L_DQ<31>")
	)
	(segment
		(start 65.832228 -120.806464)
		(end 66.077084 -120.806464)
		(width 0.1651)
		(layer "F.Cu")
		(net "M_L_DQ<31>")
	)
	(segment
		(start 65.399412 -142.6718)
		(end 65.399412 -143.941546)
		(width 0.1651)
		(layer "F.Cu")
		(net "M_L_DQ<31>")
	)
	(segment
		(start 71.080376 -107.314746)
		(end 72.427592 -107.314746)
		(width 0.1651)
		(layer "F.Cu")
		(net "M_L_DQ<31>")
	)
	(segment
		(start 66.239898 -119.277384)
		(end 66.239898 -118.909592)
		(width 0.1651)
		(layer "F.Cu")
		(net "M_L_DQ<31>")
	)
	(segment
		(start 65.085214 -118.587774)
		(end 65.085214 -118.255034)
		(width 0.1651)
		(layer "F.Cu")
		(net "M_L_DQ<31>")
	)
	(segment
		(start 66.239898 -121.671588)
		(end 66.058034 -121.489724)
		(width 0.1651)
		(layer "F.Cu")
		(net "M_L_DQ<31>")
	)
	(segment
		(start 66.18859 -113.065306)
		(end 66.18859 -112.206532)
		(width 0.1651)
		(layer "F.Cu")
		(net "M_L_DQ<31>")
	)
	(via
		(at 66.249296 -125.410976)
		(size 0.508)
		(drill 0.254)
		(layers "F.Cu" "B.Cu")
		(net "M_L_DQ<31>")
	)
	(via
		(at 66.249296 -139.932156)
		(size 0.508)
		(drill 0.254)
		(layers "F.Cu" "B.Cu")
		(net "M_L_DQ<31>")
	)
	(via
		(at 65.399412 -143.941546)
		(size 0.508)
		(drill 0.254)
		(layers "F.Cu" "B.Cu")
		(net "M_L_DQ<31>")
	)
	(segment
		(start 66.24955 -137.877296)
		(end 66.249296 -137.877296)
		(width 0.1651)
		(layer "B.Cu")
		(net "M_L_DQ<31>")
	)
	(segment
		(start 66.249296 -137.877296)
		(end 66.249296 -139.932156)
		(width 0.1651)
		(layer "B.Cu")
		(net "M_L_DQ<31>")
	)
	(segment
		(start 66.551302 -131.9022)
		(end 66.551302 -131.484878)
		(width 0.14224)
		(layer "In4.Cu")
		(net "M_L_DQ<31>")
	)
	(segment
		(start 65.7987 -140.3604)
		(end 66.226944 -139.932156)
		(width 0.14224)
		(layer "In4.Cu")
		(net "M_L_DQ<31>")
	)
	(segment
		(start 66.876168 -138.3538)
		(end 66.545968 -138.0236)
		(width 0.14224)
		(layer "In4.Cu")
		(net "M_L_DQ<31>")
	)
	(segment
		(start 65.69329 -125.211078)
		(end 66.049398 -125.211078)
		(width 0.14224)
		(layer "In4.Cu")
		(net "M_L_DQ<31>")
	)
	(segment
		(start 65.399412 -143.941546)
		(end 65.6717 -143.941546)
		(width 0.14224)
		(layer "In4.Cu")
		(net "M_L_DQ<31>")
	)
	(segment
		(start 66.602102 -127.61468)
		(end 65.834768 -126.847346)
		(width 0.14224)
		(layer "In4.Cu")
		(net "M_L_DQ<31>")
	)
	(segment
		(start 66.602102 -139.590272)
		(end 66.602102 -138.983466)
		(width 0.14224)
		(layer "In4.Cu")
		(net "M_L_DQ<31>")
	)
	(segment
		(start 66.545968 -137.6934)
		(end 66.876168 -137.3632)
		(width 0.14224)
		(layer "In4.Cu")
		(net "M_L_DQ<31>")
	)
	(segment
		(start 65.84315 -141.5034)
		(end 65.84315 -140.834618)
		(width 0.14224)
		(layer "In4.Cu")
		(net "M_L_DQ<31>")
	)
	(segment
		(start 66.602102 -129.859278)
		(end 66.602102 -127.61468)
		(width 0.14224)
		(layer "In4.Cu")
		(net "M_L_DQ<31>")
	)
	(segment
		(start 66.771266 -136.020302)
		(end 66.771266 -134.712202)
		(width 0.14224)
		(layer "In4.Cu")
		(net "M_L_DQ<31>")
	)
	(segment
		(start 66.551302 -131.484878)
		(end 66.830702 -131.205478)
		(width 0.14224)
		(layer "In4.Cu")
		(net "M_L_DQ<31>")
	)
	(segment
		(start 65.592452 -125.513084)
		(end 65.592452 -125.311916)
		(width 0.14224)
		(layer "In4.Cu")
		(net "M_L_DQ<31>")
	)
	(segment
		(start 66.830702 -131.205478)
		(end 66.830702 -130.087878)
		(width 0.14224)
		(layer "In4.Cu")
		(net "M_L_DQ<31>")
	)
	(segment
		(start 65.6717 -143.941546)
		(end 65.8495 -143.763746)
		(width 0.14224)
		(layer "In4.Cu")
		(net "M_L_DQ<31>")
	)
	(segment
		(start 65.8495 -143.763746)
		(end 65.8495 -143.44015)
		(width 0.14224)
		(layer "In4.Cu")
		(net "M_L_DQ<31>")
	)
	(segment
		(start 65.7987 -140.790168)
		(end 65.7987 -140.3604)
		(width 0.14224)
		(layer "In4.Cu")
		(net "M_L_DQ<31>")
	)
	(segment
		(start 66.771266 -134.712202)
		(end 66.627502 -134.568438)
		(width 0.14224)
		(layer "In4.Cu")
		(net "M_L_DQ<31>")
	)
	(segment
		(start 65.560702 -143.151352)
		(end 65.560702 -142.878048)
		(width 0.14224)
		(layer "In4.Cu")
		(net "M_L_DQ<31>")
	)
	(segment
		(start 66.226944 -139.932156)
		(end 66.249296 -139.932156)
		(width 0.14224)
		(layer "In4.Cu")
		(net "M_L_DQ<31>")
	)
	(segment
		(start 66.876168 -137.3632)
		(end 66.876168 -136.849866)
		(width 0.14224)
		(layer "In4.Cu")
		(net "M_L_DQ<31>")
	)
	(segment
		(start 66.249296 -139.932156)
		(end 66.59118 -139.590272)
		(width 0.14224)
		(layer "In4.Cu")
		(net "M_L_DQ<31>")
	)
	(segment
		(start 66.876168 -136.849866)
		(end 66.602102 -136.5758)
		(width 0.14224)
		(layer "In4.Cu")
		(net "M_L_DQ<31>")
	)
	(segment
		(start 65.81775 -142.621)
		(end 65.81775 -142.3162)
		(width 0.14224)
		(layer "In4.Cu")
		(net "M_L_DQ<31>")
	)
	(segment
		(start 65.560702 -141.785848)
		(end 65.84315 -141.5034)
		(width 0.14224)
		(layer "In4.Cu")
		(net "M_L_DQ<31>")
	)
	(segment
		(start 66.830702 -130.087878)
		(end 66.602102 -129.859278)
		(width 0.14224)
		(layer "In4.Cu")
		(net "M_L_DQ<31>")
	)
	(segment
		(start 66.627502 -134.157466)
		(end 66.825368 -133.9596)
		(width 0.14224)
		(layer "In4.Cu")
		(net "M_L_DQ<31>")
	)
	(segment
		(start 65.84315 -140.834618)
		(end 65.7987 -140.790168)
		(width 0.14224)
		(layer "In4.Cu")
		(net "M_L_DQ<31>")
	)
	(segment
		(start 66.627502 -134.568438)
		(end 66.627502 -134.157466)
		(width 0.14224)
		(layer "In4.Cu")
		(net "M_L_DQ<31>")
	)
	(segment
		(start 66.825368 -133.5532)
		(end 66.596768 -133.3246)
		(width 0.14224)
		(layer "In4.Cu")
		(net "M_L_DQ<31>")
	)
	(segment
		(start 65.560702 -142.878048)
		(end 65.81775 -142.621)
		(width 0.14224)
		(layer "In4.Cu")
		(net "M_L_DQ<31>")
	)
	(segment
		(start 66.596768 -132.9182)
		(end 66.825368 -132.6896)
		(width 0.14224)
		(layer "In4.Cu")
		(net "M_L_DQ<31>")
	)
	(segment
		(start 65.592452 -125.311916)
		(end 65.69329 -125.211078)
		(width 0.14224)
		(layer "In4.Cu")
		(net "M_L_DQ<31>")
	)
	(segment
		(start 66.596768 -133.3246)
		(end 66.596768 -132.9182)
		(width 0.14224)
		(layer "In4.Cu")
		(net "M_L_DQ<31>")
	)
	(segment
		(start 66.59118 -139.590272)
		(end 66.602102 -139.590272)
		(width 0.14224)
		(layer "In4.Cu")
		(net "M_L_DQ<31>")
	)
	(segment
		(start 66.602102 -136.5758)
		(end 66.602102 -136.189466)
		(width 0.14224)
		(layer "In4.Cu")
		(net "M_L_DQ<31>")
	)
	(segment
		(start 65.834768 -125.7554)
		(end 65.592452 -125.513084)
		(width 0.14224)
		(layer "In4.Cu")
		(net "M_L_DQ<31>")
	)
	(segment
		(start 65.81775 -142.3162)
		(end 65.560702 -142.059152)
		(width 0.14224)
		(layer "In4.Cu")
		(net "M_L_DQ<31>")
	)
	(segment
		(start 66.545968 -138.0236)
		(end 66.545968 -137.6934)
		(width 0.14224)
		(layer "In4.Cu")
		(net "M_L_DQ<31>")
	)
	(segment
		(start 65.834768 -126.847346)
		(end 65.834768 -125.7554)
		(width 0.14224)
		(layer "In4.Cu")
		(net "M_L_DQ<31>")
	)
	(segment
		(start 66.602102 -138.983466)
		(end 66.876168 -138.7094)
		(width 0.14224)
		(layer "In4.Cu")
		(net "M_L_DQ<31>")
	)
	(segment
		(start 66.825368 -133.9596)
		(end 66.825368 -133.5532)
		(width 0.14224)
		(layer "In4.Cu")
		(net "M_L_DQ<31>")
	)
	(segment
		(start 66.876168 -138.7094)
		(end 66.876168 -138.3538)
		(width 0.14224)
		(layer "In4.Cu")
		(net "M_L_DQ<31>")
	)
	(segment
		(start 66.602102 -136.189466)
		(end 66.771266 -136.020302)
		(width 0.14224)
		(layer "In4.Cu")
		(net "M_L_DQ<31>")
	)
	(segment
		(start 65.560702 -142.059152)
		(end 65.560702 -141.785848)
		(width 0.14224)
		(layer "In4.Cu")
		(net "M_L_DQ<31>")
	)
	(segment
		(start 66.825368 -132.6896)
		(end 66.825368 -132.176266)
		(width 0.14224)
		(layer "In4.Cu")
		(net "M_L_DQ<31>")
	)
	(segment
		(start 65.8495 -143.44015)
		(end 65.560702 -143.151352)
		(width 0.14224)
		(layer "In4.Cu")
		(net "M_L_DQ<31>")
	)
	(segment
		(start 66.049398 -125.211078)
		(end 66.249296 -125.410976)
		(width 0.14224)
		(layer "In4.Cu")
		(net "M_L_DQ<31>")
	)
	(segment
		(start 66.825368 -132.176266)
		(end 66.551302 -131.9022)
		(width 0.14224)
		(layer "In4.Cu")
		(net "M_L_DQ<31>")
	)
	(segment
		(start 65.513712 -114.671348)
		(end 65.513712 -113.864644)
		(width 0.1651)
		(layer "F.Cu")
		(net "M_L_DQ<30>")
	)
	(segment
		(start 64.81445 -113.510822)
		(end 64.81445 -113.178082)
		(width 0.1651)
		(layer "F.Cu")
		(net "M_L_DQ<30>")
	)
	(segment
		(start 65.386712 -115.481608)
		(end 65.21577 -115.481608)
		(width 0.1651)
		(layer "F.Cu")
		(net "M_L_DQ<30>")
	)
	(segment
		(start 65.338452 -113.689384)
		(end 64.993012 -113.689384)
		(width 0.1651)
		(layer "F.Cu")
		(net "M_L_DQ<30>")
	)
	(segment
		(start 72.705214 -106.667046)
		(end 72.853804 -106.667046)
		(width 0.1016)
		(layer "F.Cu")
		(net "M_L_DQ<30>")
	)
	(segment
		(start 65.513712 -113.864644)
		(end 65.338452 -113.689384)
		(width 0.1651)
		(layer "F.Cu")
		(net "M_L_DQ<30>")
	)
	(segment
		(start 64.41313 -118.020846)
		(end 65.03543 -117.398546)
		(width 0.1651)
		(layer "F.Cu")
		(net "M_L_DQ<30>")
	)
	(segment
		(start 65.783968 -125.6538)
		(end 65.783968 -124.2568)
		(width 0.1651)
		(layer "F.Cu")
		(net "M_L_DQ<30>")
	)
	(segment
		(start 64.996568 -123.4694)
		(end 64.996568 -120.788938)
		(width 0.1651)
		(layer "F.Cu")
		(net "M_L_DQ<30>")
	)
	(segment
		(start 65.338452 -113.006124)
		(end 65.540128 -112.804448)
		(width 0.1651)
		(layer "F.Cu")
		(net "M_L_DQ<30>")
	)
	(segment
		(start 66.24955 -145.516854)
		(end 66.249296 -145.5166)
		(width 0.1651)
		(layer "F.Cu")
		(net "M_L_DQ<30>")
	)
	(segment
		(start 66.24955 -147.27174)
		(end 66.24955 -146.304)
		(width 0.1651)
		(layer "F.Cu")
		(net "M_L_DQ<30>")
	)
	(segment
		(start 79.768192 -99.17684)
		(end 79.4385 -99.938078)
		(width 0.0889)
		(layer "F.Cu")
		(net "M_L_DQ<30>")
	)
	(segment
		(start 65.386712 -114.798348)
		(end 65.513712 -114.671348)
		(width 0.1651)
		(layer "F.Cu")
		(net "M_L_DQ<30>")
	)
	(segment
		(start 66.38163 -145.95348)
		(end 66.24955 -145.8214)
		(width 0.1651)
		(layer "F.Cu")
		(net "M_L_DQ<30>")
	)
	(segment
		(start 65.399412 -126.615698)
		(end 65.885568 -126.129542)
		(width 0.1651)
		(layer "F.Cu")
		(net "M_L_DQ<30>")
	)
	(segment
		(start 72.853804 -106.667046)
		(end 74.859896 -104.660954)
		(width 0.1016)
		(layer "F.Cu")
		(net "M_L_DQ<30>")
	)
	(segment
		(start 70.813168 -106.667046)
		(end 72.705214 -106.667046)
		(width 0.1651)
		(layer "F.Cu")
		(net "M_L_DQ<30>")
	)
	(segment
		(start 65.075816 -114.925348)
		(end 65.202816 -114.798348)
		(width 0.1651)
		(layer "F.Cu")
		(net "M_L_DQ<30>")
	)
	(segment
		(start 65.03543 -117.398546)
		(end 65.336166 -117.398546)
		(width 0.1651)
		(layer "F.Cu")
		(net "M_L_DQ<30>")
	)
	(segment
		(start 65.885568 -126.129542)
		(end 65.885568 -125.7554)
		(width 0.1651)
		(layer "F.Cu")
		(net "M_L_DQ<30>")
	)
	(segment
		(start 64.41313 -120.2055)
		(end 64.41313 -118.020846)
		(width 0.1651)
		(layer "F.Cu")
		(net "M_L_DQ<30>")
	)
	(segment
		(start 65.885568 -125.7554)
		(end 65.783968 -125.6538)
		(width 0.1651)
		(layer "F.Cu")
		(net "M_L_DQ<30>")
	)
	(segment
		(start 77.615796 -104.660954)
		(end 76.830174 -104.660954)
		(width 0.1016)
		(layer "F.Cu")
		(net "M_L_DQ<30>")
	)
	(segment
		(start 65.546732 -115.641628)
		(end 65.386712 -115.481608)
		(width 0.1651)
		(layer "F.Cu")
		(net "M_L_DQ<30>")
	)
	(segment
		(start 79.524352 -101.746812)
		(end 79.524352 -102.752398)
		(width 0.0889)
		(layer "F.Cu")
		(net "M_L_DQ<30>")
	)
	(segment
		(start 65.546732 -117.18798)
		(end 65.546732 -115.641628)
		(width 0.1651)
		(layer "F.Cu")
		(net "M_L_DQ<30>")
	)
	(segment
		(start 74.859896 -104.660954)
		(end 76.830174 -104.660954)
		(width 0.1016)
		(layer "F.Cu")
		(net "M_L_DQ<30>")
	)
	(segment
		(start 64.993012 -113.689384)
		(end 64.81445 -113.510822)
		(width 0.1651)
		(layer "F.Cu")
		(net "M_L_DQ<30>")
	)
	(segment
		(start 64.986408 -113.006124)
		(end 65.338452 -113.006124)
		(width 0.1651)
		(layer "F.Cu")
		(net "M_L_DQ<30>")
	)
	(segment
		(start 66.24955 -146.304)
		(end 66.38163 -146.17192)
		(width 0.1651)
		(layer "F.Cu")
		(net "M_L_DQ<30>")
	)
	(segment
		(start 79.524352 -102.752398)
		(end 79.417164 -102.859586)
		(width 0.0889)
		(layer "F.Cu")
		(net "M_L_DQ<30>")
	)
	(segment
		(start 64.81445 -113.178082)
		(end 64.986408 -113.006124)
		(width 0.1651)
		(layer "F.Cu")
		(net "M_L_DQ<30>")
	)
	(segment
		(start 65.540128 -111.940086)
		(end 70.813168 -106.667046)
		(width 0.1651)
		(layer "F.Cu")
		(net "M_L_DQ<30>")
	)
	(segment
		(start 65.336166 -117.398546)
		(end 65.546732 -117.18798)
		(width 0.1651)
		(layer "F.Cu")
		(net "M_L_DQ<30>")
	)
	(segment
		(start 79.4385 -99.938078)
		(end 79.421482 -99.967288)
		(width 0.0889)
		(layer "F.Cu")
		(net "M_L_DQ<30>")
	)
	(segment
		(start 64.996568 -120.788938)
		(end 64.41313 -120.2055)
		(width 0.1651)
		(layer "F.Cu")
		(net "M_L_DQ<30>")
	)
	(segment
		(start 65.21577 -115.481608)
		(end 65.075816 -115.341654)
		(width 0.1651)
		(layer "F.Cu")
		(net "M_L_DQ<30>")
	)
	(segment
		(start 65.783968 -124.2568)
		(end 64.996568 -123.4694)
		(width 0.1651)
		(layer "F.Cu")
		(net "M_L_DQ<30>")
	)
	(segment
		(start 65.202816 -114.798348)
		(end 65.386712 -114.798348)
		(width 0.1651)
		(layer "F.Cu")
		(net "M_L_DQ<30>")
	)
	(segment
		(start 79.417164 -102.859586)
		(end 77.615796 -104.660954)
		(width 0.1016)
		(layer "F.Cu")
		(net "M_L_DQ<30>")
	)
	(segment
		(start 65.075816 -115.341654)
		(end 65.075816 -114.925348)
		(width 0.1651)
		(layer "F.Cu")
		(net "M_L_DQ<30>")
	)
	(segment
		(start 66.24955 -145.8214)
		(end 66.24955 -145.516854)
		(width 0.1651)
		(layer "F.Cu")
		(net "M_L_DQ<30>")
	)
	(segment
		(start 79.421482 -101.357938)
		(end 79.430372 -101.373178)
		(width 0.0889)
		(layer "F.Cu")
		(net "M_L_DQ<30>")
	)
	(segment
		(start 66.38163 -146.17192)
		(end 66.38163 -145.95348)
		(width 0.1651)
		(layer "F.Cu")
		(net "M_L_DQ<30>")
	)
	(segment
		(start 79.416656 -101.349302)
		(end 79.421482 -101.357938)
		(width 0.0889)
		(layer "F.Cu")
		(net "M_L_DQ<30>")
	)
	(segment
		(start 65.540128 -112.804448)
		(end 65.540128 -111.940086)
		(width 0.1651)
		(layer "F.Cu")
		(net "M_L_DQ<30>")
	)
	(via
		(at 65.399412 -141.213078)
		(size 0.508)
		(drill 0.254)
		(layers "F.Cu" "B.Cu")
		(net "M_L_DQ<30>")
	)
	(via
		(at 66.249296 -145.5166)
		(size 0.508)
		(drill 0.254)
		(layers "F.Cu" "B.Cu")
		(net "M_L_DQ<30>")
	)
	(via
		(at 65.399412 -126.615698)
		(size 0.508)
		(drill 0.254)
		(layers "F.Cu" "B.Cu")
		(net "M_L_DQ<30>")
	)
	(arc
		(start 79.421482 -99.967288)
		(mid 79.367983 -100.167186)
		(end 79.421482 -100.367084)
		(width 0.0889)
		(layer "F.Cu")
		(net "M_L_DQ<30>")
	)
	(arc
		(start 79.421482 -100.367084)
		(mid 79.500613 -100.662486)
		(end 79.421482 -100.957888)
		(width 0.0889)
		(layer "F.Cu")
		(net "M_L_DQ<30>")
	)
	(arc
		(start 79.421482 -100.957888)
		(mid 79.368012 -101.152951)
		(end 79.416656 -101.349302)
		(width 0.0889)
		(layer "F.Cu")
		(net "M_L_DQ<30>")
	)
	(arc
		(start 79.430372 -101.373178)
		(mid 79.500521 -101.554172)
		(end 79.524352 -101.746812)
		(width 0.0889)
		(layer "F.Cu")
		(net "M_L_DQ<30>")
	)
	(segment
		(start 65.399412 -142.477236)
		(end 65.399412 -141.213078)
		(width 0.1651)
		(layer "B.Cu")
		(net "M_L_DQ<30>")
	)
	(segment
		(start 65.763902 -131.307078)
		(end 65.763902 -130.062478)
		(width 0.14224)
		(layer "In4.Cu")
		(net "M_L_DQ<30>")
	)
	(segment
		(start 65.916302 -134.517638)
		(end 65.916302 -134.066534)
		(width 0.14224)
		(layer "In4.Cu")
		(net "M_L_DQ<30>")
	)
	(segment
		(start 65.916302 -134.066534)
		(end 65.834768 -133.985)
		(width 0.14224)
		(layer "In4.Cu")
		(net "M_L_DQ<30>")
	)
	(segment
		(start 66.249296 -145.5166)
		(end 64.966342 -144.233646)
		(width 0.14224)
		(layer "In4.Cu")
		(net "M_L_DQ<30>")
	)
	(segment
		(start 65.230502 -141.044168)
		(end 65.230502 -140.070078)
		(width 0.14224)
		(layer "In4.Cu")
		(net "M_L_DQ<30>")
	)
	(segment
		(start 65.967102 -136.256268)
		(end 65.64376 -135.932926)
		(width 0.14224)
		(layer "In4.Cu")
		(net "M_L_DQ<30>")
	)
	(segment
		(start 65.967102 -139.333478)
		(end 65.967102 -138.867134)
		(width 0.14224)
		(layer "In4.Cu")
		(net "M_L_DQ<30>")
	)
	(segment
		(start 65.64376 -135.932926)
		(end 65.64376 -134.79018)
		(width 0.14224)
		(layer "In4.Cu")
		(net "M_L_DQ<30>")
	)
	(segment
		(start 64.966342 -141.646148)
		(end 65.399412 -141.213078)
		(width 0.14224)
		(layer "In4.Cu")
		(net "M_L_DQ<30>")
	)
	(segment
		(start 65.64376 -134.79018)
		(end 65.916302 -134.517638)
		(width 0.14224)
		(layer "In4.Cu")
		(net "M_L_DQ<30>")
	)
	(segment
		(start 65.834768 -138.7348)
		(end 65.834768 -136.682734)
		(width 0.14224)
		(layer "In4.Cu")
		(net "M_L_DQ<30>")
	)
	(segment
		(start 65.834768 -136.682734)
		(end 65.967102 -136.5504)
		(width 0.14224)
		(layer "In4.Cu")
		(net "M_L_DQ<30>")
	)
	(segment
		(start 65.834768 -131.958334)
		(end 65.916302 -131.8768)
		(width 0.14224)
		(layer "In4.Cu")
		(net "M_L_DQ<30>")
	)
	(segment
		(start 65.916302 -131.459478)
		(end 65.763902 -131.307078)
		(width 0.14224)
		(layer "In4.Cu")
		(net "M_L_DQ<30>")
	)
	(segment
		(start 65.230502 -140.070078)
		(end 65.967102 -139.333478)
		(width 0.14224)
		(layer "In4.Cu")
		(net "M_L_DQ<30>")
	)
	(segment
		(start 65.967102 -136.5504)
		(end 65.967102 -136.256268)
		(width 0.14224)
		(layer "In4.Cu")
		(net "M_L_DQ<30>")
	)
	(segment
		(start 65.834768 -133.985)
		(end 65.834768 -131.958334)
		(width 0.14224)
		(layer "In4.Cu")
		(net "M_L_DQ<30>")
	)
	(segment
		(start 65.399412 -141.213078)
		(end 65.230502 -141.044168)
		(width 0.14224)
		(layer "In4.Cu")
		(net "M_L_DQ<30>")
	)
	(segment
		(start 65.399412 -127.199898)
		(end 65.399412 -126.615698)
		(width 0.14224)
		(layer "In4.Cu")
		(net "M_L_DQ<30>")
	)
	(segment
		(start 65.967102 -129.859278)
		(end 65.967102 -127.767588)
		(width 0.14224)
		(layer "In4.Cu")
		(net "M_L_DQ<30>")
	)
	(segment
		(start 65.763902 -130.062478)
		(end 65.967102 -129.859278)
		(width 0.14224)
		(layer "In4.Cu")
		(net "M_L_DQ<30>")
	)
	(segment
		(start 65.916302 -131.8768)
		(end 65.916302 -131.459478)
		(width 0.14224)
		(layer "In4.Cu")
		(net "M_L_DQ<30>")
	)
	(segment
		(start 64.966342 -144.233646)
		(end 64.966342 -141.646148)
		(width 0.14224)
		(layer "In4.Cu")
		(net "M_L_DQ<30>")
	)
	(segment
		(start 65.967102 -127.767588)
		(end 65.399412 -127.199898)
		(width 0.14224)
		(layer "In4.Cu")
		(net "M_L_DQ<30>")
	)
	(segment
		(start 65.967102 -138.867134)
		(end 65.834768 -138.7348)
		(width 0.14224)
		(layer "In4.Cu")
		(net "M_L_DQ<30>")
	)
	(segment
		(start 39.899336 -145.793968)
		(end 39.899336 -145.5166)
		(width 0.1651)
		(layer "F.Cu")
		(net "M_L_DQ<2>")
	)
	(segment
		(start 72.041766 -86.794086)
		(end 71.470266 -86.794086)
		(width 0.1651)
		(layer "F.Cu")
		(net "M_L_DQ<2>")
	)
	(segment
		(start 39.899336 -146.280632)
		(end 40.030908 -146.14906)
		(width 0.1651)
		(layer "F.Cu")
		(net "M_L_DQ<2>")
	)
	(segment
		(start 40.030908 -146.14906)
		(end 40.030908 -145.92554)
		(width 0.1651)
		(layer "F.Cu")
		(net "M_L_DQ<2>")
	)
	(segment
		(start 40.030908 -145.92554)
		(end 39.899336 -145.793968)
		(width 0.1651)
		(layer "F.Cu")
		(net "M_L_DQ<2>")
	)
	(segment
		(start 39.899336 -147.27174)
		(end 39.899336 -146.280632)
		(width 0.1651)
		(layer "F.Cu")
		(net "M_L_DQ<2>")
	)
	(via
		(at 39.049452 -141.213078)
		(size 0.508)
		(drill 0.254)
		(layers "F.Cu" "B.Cu")
		(net "M_L_DQ<2>")
	)
	(via
		(at 71.470266 -86.794086)
		(size 0.508)
		(drill 0.254)
		(layers "F.Cu" "B.Cu")
		(net "M_L_DQ<2>")
	)
	(via
		(at 39.899336 -145.5166)
		(size 0.508)
		(drill 0.254)
		(layers "F.Cu" "B.Cu")
		(net "M_L_DQ<2>")
	)
	(segment
		(start 39.049452 -142.477236)
		(end 39.049452 -141.213078)
		(width 0.1651)
		(layer "B.Cu")
		(net "M_L_DQ<2>")
	)
	(segment
		(start 45.760386 -110.218728)
		(end 57.803542 -98.175572)
		(width 0.14224)
		(layer "In4.Cu")
		(net "M_L_DQ<2>")
	)
	(segment
		(start 45.760386 -110.93196)
		(end 45.760386 -110.218728)
		(width 0.14224)
		(layer "In4.Cu")
		(net "M_L_DQ<2>")
	)
	(segment
		(start 68.873116 -86.69909)
		(end 68.905882 -86.69909)
		(width 0.0889)
		(layer "In4.Cu")
		(net "M_L_DQ<2>")
	)
	(segment
		(start 40.917368 -115.8494)
		(end 41.120568 -115.6462)
		(width 0.14224)
		(layer "In4.Cu")
		(net "M_L_DQ<2>")
	)
	(segment
		(start 66.255392 -88.148414)
		(end 66.714116 -87.68969)
		(width 0.0889)
		(layer "In4.Cu")
		(net "M_L_DQ<2>")
	)
	(segment
		(start 39.291768 -123.2662)
		(end 39.494968 -123.063)
		(width 0.14224)
		(layer "In4.Cu")
		(net "M_L_DQ<2>")
	)
	(segment
		(start 39.494968 -123.063)
		(end 39.901368 -123.063)
		(width 0.14224)
		(layer "In4.Cu")
		(net "M_L_DQ<2>")
	)
	(segment
		(start 39.56812 -139.036552)
		(end 39.469568 -138.938)
		(width 0.14224)
		(layer "In4.Cu")
		(net "M_L_DQ<2>")
	)
	(segment
		(start 42.542968 -117.8814)
		(end 42.542968 -114.149378)
		(width 0.14224)
		(layer "In4.Cu")
		(net "M_L_DQ<2>")
	)
	(segment
		(start 68.018406 -87.194136)
		(end 68.051172 -87.194136)
		(width 0.0889)
		(layer "In4.Cu")
		(net "M_L_DQ<2>")
	)
	(segment
		(start 39.33952 -134.701026)
		(end 39.61892 -134.421626)
		(width 0.14224)
		(layer "In4.Cu")
		(net "M_L_DQ<2>")
	)
	(segment
		(start 39.41572 -131.332478)
		(end 39.41572 -129.960878)
		(width 0.14224)
		(layer "In4.Cu")
		(net "M_L_DQ<2>")
	)
	(segment
		(start 41.933368 -118.0846)
		(end 42.339768 -118.0846)
		(width 0.14224)
		(layer "In4.Cu")
		(net "M_L_DQ<2>")
	)
	(segment
		(start 39.56812 -136.601708)
		(end 39.56812 -136.205468)
		(width 0.14224)
		(layer "In4.Cu")
		(net "M_L_DQ<2>")
	)
	(segment
		(start 66.714116 -87.68969)
		(end 67.188842 -87.68969)
		(width 0.0889)
		(layer "In4.Cu")
		(net "M_L_DQ<2>")
	)
	(segment
		(start 39.291768 -128.933448)
		(end 39.291768 -123.2662)
		(width 0.14224)
		(layer "In4.Cu")
		(net "M_L_DQ<2>")
	)
	(segment
		(start 39.475156 -133.939788)
		(end 39.475156 -131.969764)
		(width 0.14224)
		(layer "In4.Cu")
		(net "M_L_DQ<2>")
	)
	(segment
		(start 39.54272 -129.1844)
		(end 39.291768 -128.933448)
		(width 0.14224)
		(layer "In4.Cu")
		(net "M_L_DQ<2>")
	)
	(segment
		(start 39.61892 -134.421626)
		(end 39.61892 -134.083552)
		(width 0.14224)
		(layer "In4.Cu")
		(net "M_L_DQ<2>")
	)
	(segment
		(start 39.56812 -136.205468)
		(end 39.33952 -135.976868)
		(width 0.14224)
		(layer "In4.Cu")
		(net "M_L_DQ<2>")
	)
	(segment
		(start 40.917368 -125.3236)
		(end 40.917368 -115.8494)
		(width 0.14224)
		(layer "In4.Cu")
		(net "M_L_DQ<2>")
	)
	(segment
		(start 39.61892 -131.826)
		(end 39.61892 -131.535678)
		(width 0.14224)
		(layer "In4.Cu")
		(net "M_L_DQ<2>")
	)
	(segment
		(start 40.714168 -125.5268)
		(end 40.917368 -125.3236)
		(width 0.14224)
		(layer "In4.Cu")
		(net "M_L_DQ<2>")
	)
	(segment
		(start 57.803542 -94.71279)
		(end 64.098932 -88.4174)
		(width 0.14224)
		(layer "In4.Cu")
		(net "M_L_DQ<2>")
	)
	(segment
		(start 64.615568 -88.148414)
		(end 66.255392 -88.148414)
		(width 0.0889)
		(layer "In4.Cu")
		(net "M_L_DQ<2>")
	)
	(segment
		(start 39.469568 -136.70026)
		(end 39.56812 -136.601708)
		(width 0.14224)
		(layer "In4.Cu")
		(net "M_L_DQ<2>")
	)
	(segment
		(start 42.339768 -118.0846)
		(end 42.542968 -117.8814)
		(width 0.14224)
		(layer "In4.Cu")
		(net "M_L_DQ<2>")
	)
	(segment
		(start 57.803542 -98.175572)
		(end 57.803542 -94.71279)
		(width 0.14224)
		(layer "In4.Cu")
		(net "M_L_DQ<2>")
	)
	(segment
		(start 40.104568 -125.3236)
		(end 40.307768 -125.5268)
		(width 0.14224)
		(layer "In4.Cu")
		(net "M_L_DQ<2>")
	)
	(segment
		(start 42.542968 -114.149378)
		(end 45.760386 -110.93196)
		(width 0.14224)
		(layer "In4.Cu")
		(net "M_L_DQ<2>")
	)
	(segment
		(start 40.307768 -125.5268)
		(end 40.714168 -125.5268)
		(width 0.14224)
		(layer "In4.Cu")
		(net "M_L_DQ<2>")
	)
	(segment
		(start 39.049452 -141.213078)
		(end 38.70452 -140.868146)
		(width 0.14224)
		(layer "In4.Cu")
		(net "M_L_DQ<2>")
	)
	(segment
		(start 71.123556 -86.003638)
		(end 71.14032 -86.03234)
		(width 0.0889)
		(layer "In4.Cu")
		(net "M_L_DQ<2>")
	)
	(segment
		(start 38.616382 -141.646148)
		(end 38.616382 -144.233646)
		(width 0.14224)
		(layer "In4.Cu")
		(net "M_L_DQ<2>")
	)
	(segment
		(start 64.346582 -88.4174)
		(end 64.615568 -88.148414)
		(width 0.0889)
		(layer "In4.Cu")
		(net "M_L_DQ<2>")
	)
	(segment
		(start 41.730168 -117.8814)
		(end 41.933368 -118.0846)
		(width 0.14224)
		(layer "In4.Cu")
		(net "M_L_DQ<2>")
	)
	(segment
		(start 64.098932 -88.4174)
		(end 64.346582 -88.4174)
		(width 0.0889)
		(layer "In4.Cu")
		(net "M_L_DQ<2>")
	)
	(segment
		(start 71.14032 -86.03234)
		(end 71.470266 -86.794086)
		(width 0.0889)
		(layer "In4.Cu")
		(net "M_L_DQ<2>")
	)
	(segment
		(start 41.120568 -115.6462)
		(end 41.526968 -115.6462)
		(width 0.14224)
		(layer "In4.Cu")
		(net "M_L_DQ<2>")
	)
	(segment
		(start 38.616382 -144.233646)
		(end 39.899336 -145.5166)
		(width 0.14224)
		(layer "In4.Cu")
		(net "M_L_DQ<2>")
	)
	(segment
		(start 39.56812 -139.371578)
		(end 39.56812 -139.036552)
		(width 0.14224)
		(layer "In4.Cu")
		(net "M_L_DQ<2>")
	)
	(segment
		(start 41.730168 -115.8494)
		(end 41.730168 -117.8814)
		(width 0.14224)
		(layer "In4.Cu")
		(net "M_L_DQ<2>")
	)
	(segment
		(start 40.104568 -123.2662)
		(end 40.104568 -125.3236)
		(width 0.14224)
		(layer "In4.Cu")
		(net "M_L_DQ<2>")
	)
	(segment
		(start 41.526968 -115.6462)
		(end 41.730168 -115.8494)
		(width 0.14224)
		(layer "In4.Cu")
		(net "M_L_DQ<2>")
	)
	(segment
		(start 38.70452 -140.235178)
		(end 39.56812 -139.371578)
		(width 0.14224)
		(layer "In4.Cu")
		(net "M_L_DQ<2>")
	)
	(segment
		(start 39.61892 -131.535678)
		(end 39.41572 -131.332478)
		(width 0.14224)
		(layer "In4.Cu")
		(net "M_L_DQ<2>")
	)
	(segment
		(start 39.33952 -135.976868)
		(end 39.33952 -134.701026)
		(width 0.14224)
		(layer "In4.Cu")
		(net "M_L_DQ<2>")
	)
	(segment
		(start 39.475156 -131.969764)
		(end 39.61892 -131.826)
		(width 0.14224)
		(layer "In4.Cu")
		(net "M_L_DQ<2>")
	)
	(segment
		(start 69.735446 -86.203536)
		(end 69.768212 -86.203536)
		(width 0.0889)
		(layer "In4.Cu")
		(net "M_L_DQ<2>")
	)
	(segment
		(start 39.901368 -123.063)
		(end 40.104568 -123.2662)
		(width 0.14224)
		(layer "In4.Cu")
		(net "M_L_DQ<2>")
	)
	(segment
		(start 39.049452 -141.213078)
		(end 38.616382 -141.646148)
		(width 0.14224)
		(layer "In4.Cu")
		(net "M_L_DQ<2>")
	)
	(segment
		(start 70.590156 -85.70849)
		(end 70.633336 -85.70849)
		(width 0.0889)
		(layer "In4.Cu")
		(net "M_L_DQ<2>")
	)
	(segment
		(start 39.41572 -129.960878)
		(end 39.54272 -129.833878)
		(width 0.14224)
		(layer "In4.Cu")
		(net "M_L_DQ<2>")
	)
	(segment
		(start 38.70452 -140.868146)
		(end 38.70452 -140.235178)
		(width 0.14224)
		(layer "In4.Cu")
		(net "M_L_DQ<2>")
	)
	(segment
		(start 39.61892 -134.083552)
		(end 39.475156 -133.939788)
		(width 0.14224)
		(layer "In4.Cu")
		(net "M_L_DQ<2>")
	)
	(segment
		(start 39.469568 -138.938)
		(end 39.469568 -136.70026)
		(width 0.14224)
		(layer "In4.Cu")
		(net "M_L_DQ<2>")
	)
	(segment
		(start 39.54272 -129.833878)
		(end 39.54272 -129.1844)
		(width 0.14224)
		(layer "In4.Cu")
		(net "M_L_DQ<2>")
	)
	(arc
		(start 68.382896 -86.994238)
		(mid 68.5899 -86.783374)
		(end 68.873116 -86.69909)
		(width 0.0889)
		(layer "In4.Cu")
		(net "M_L_DQ<2>")
	)
	(arc
		(start 69.768212 -86.203536)
		(mid 69.959854 -86.14637)
		(end 70.099936 -86.003638)
		(width 0.0889)
		(layer "In4.Cu")
		(net "M_L_DQ<2>")
	)
	(arc
		(start 70.633336 -85.70849)
		(mid 70.916553 -85.792771)
		(end 71.123556 -86.003638)
		(width 0.0889)
		(layer "In4.Cu")
		(net "M_L_DQ<2>")
	)
	(arc
		(start 67.524376 -87.489538)
		(mid 67.732984 -87.277606)
		(end 68.018406 -87.194136)
		(width 0.0889)
		(layer "In4.Cu")
		(net "M_L_DQ<2>")
	)
	(arc
		(start 69.241416 -86.498938)
		(mid 69.450024 -86.287006)
		(end 69.735446 -86.203536)
		(width 0.0889)
		(layer "In4.Cu")
		(net "M_L_DQ<2>")
	)
	(arc
		(start 67.188842 -87.68969)
		(mid 67.382692 -87.63334)
		(end 67.524376 -87.489538)
		(width 0.0889)
		(layer "In4.Cu")
		(net "M_L_DQ<2>")
	)
	(arc
		(start 68.051172 -87.194136)
		(mid 68.242814 -87.13697)
		(end 68.382896 -86.994238)
		(width 0.0889)
		(layer "In4.Cu")
		(net "M_L_DQ<2>")
	)
	(arc
		(start 70.099936 -86.003638)
		(mid 70.30694 -85.792774)
		(end 70.590156 -85.70849)
		(width 0.0889)
		(layer "In4.Cu")
		(net "M_L_DQ<2>")
	)
	(arc
		(start 68.905882 -86.69909)
		(mid 69.099732 -86.64274)
		(end 69.241416 -86.498938)
		(width 0.0889)
		(layer "In4.Cu")
		(net "M_L_DQ<2>")
	)
	(segment
		(start 59.459368 -115.5446)
		(end 59.459368 -115.951)
		(width 0.1651)
		(layer "F.Cu")
		(net "M_L_DQ<29>")
	)
	(segment
		(start 72.969628 -103.530146)
		(end 72.171052 -103.530146)
		(width 0.1016)
		(layer "F.Cu")
		(net "M_L_DQ<29>")
	)
	(segment
		(start 59.941968 -115.062)
		(end 59.459368 -115.5446)
		(width 0.1651)
		(layer "F.Cu")
		(net "M_L_DQ<29>")
	)
	(segment
		(start 59.459368 -113.8936)
		(end 59.941968 -114.3762)
		(width 0.1651)
		(layer "F.Cu")
		(net "M_L_DQ<29>")
	)
	(segment
		(start 59.459368 -119.5578)
		(end 59.987434 -120.085866)
		(width 0.1651)
		(layer "F.Cu")
		(net "M_L_DQ<29>")
	)
	(segment
		(start 59.891168 -122.072654)
		(end 59.459368 -122.504454)
		(width 0.1651)
		(layer "F.Cu")
		(net "M_L_DQ<29>")
	)
	(segment
		(start 76.326492 -102.224586)
		(end 76.023724 -102.527354)
		(width 0.1016)
		(layer "F.Cu")
		(net "M_L_DQ<29>")
	)
	(segment
		(start 76.830174 -101.482398)
		(end 76.644754 -101.812598)
		(width 0.0889)
		(layer "F.Cu")
		(net "M_L_DQ<29>")
	)
	(segment
		(start 59.941968 -114.3762)
		(end 59.941968 -115.062)
		(width 0.1651)
		(layer "F.Cu")
		(net "M_L_DQ<29>")
	)
	(segment
		(start 59.459368 -121.3104)
		(end 59.891168 -121.7422)
		(width 0.1651)
		(layer "F.Cu")
		(net "M_L_DQ<29>")
	)
	(segment
		(start 59.459368 -113.312194)
		(end 59.459368 -113.8936)
		(width 0.1651)
		(layer "F.Cu")
		(net "M_L_DQ<29>")
	)
	(segment
		(start 59.459368 -119.1768)
		(end 59.459368 -119.5578)
		(width 0.1651)
		(layer "F.Cu")
		(net "M_L_DQ<29>")
	)
	(segment
		(start 72.171052 -103.530146)
		(end 71.485252 -102.844346)
		(width 0.1016)
		(layer "F.Cu")
		(net "M_L_DQ<29>")
	)
	(segment
		(start 59.987434 -120.085866)
		(end 59.987434 -120.375934)
		(width 0.1651)
		(layer "F.Cu")
		(net "M_L_DQ<29>")
	)
	(segment
		(start 59.459368 -117.7798)
		(end 59.987434 -118.307866)
		(width 0.1651)
		(layer "F.Cu")
		(net "M_L_DQ<29>")
	)
	(segment
		(start 59.459368 -117.3734)
		(end 59.459368 -117.7798)
		(width 0.1651)
		(layer "F.Cu")
		(net "M_L_DQ<29>")
	)
	(segment
		(start 76.326492 -102.13086)
		(end 76.326492 -102.224586)
		(width 0.0889)
		(layer "F.Cu")
		(net "M_L_DQ<29>")
	)
	(segment
		(start 73.97242 -102.527354)
		(end 72.969628 -103.530146)
		(width 0.1016)
		(layer "F.Cu")
		(net "M_L_DQ<29>")
	)
	(segment
		(start 59.449462 -142.6718)
		(end 59.449462 -143.941546)
		(width 0.1651)
		(layer "F.Cu")
		(net "M_L_DQ<29>")
	)
	(segment
		(start 59.459368 -115.951)
		(end 59.987434 -116.479066)
		(width 0.1651)
		(layer "F.Cu")
		(net "M_L_DQ<29>")
	)
	(segment
		(start 76.852526 -101.44252)
		(end 76.830174 -101.482398)
		(width 0.0889)
		(layer "F.Cu")
		(net "M_L_DQ<29>")
	)
	(segment
		(start 76.644754 -101.812598)
		(end 76.326492 -102.13086)
		(width 0.0889)
		(layer "F.Cu")
		(net "M_L_DQ<29>")
	)
	(segment
		(start 60.830206 -110.002574)
		(end 59.459368 -113.312194)
		(width 0.1651)
		(layer "F.Cu")
		(net "M_L_DQ<29>")
	)
	(segment
		(start 59.987434 -118.648734)
		(end 59.459368 -119.1768)
		(width 0.1651)
		(layer "F.Cu")
		(net "M_L_DQ<29>")
	)
	(segment
		(start 71.485252 -102.844346)
		(end 71.164196 -102.844346)
		(width 0.1016)
		(layer "F.Cu")
		(net "M_L_DQ<29>")
	)
	(segment
		(start 67.988434 -102.844346)
		(end 60.830206 -110.002574)
		(width 0.1651)
		(layer "F.Cu")
		(net "M_L_DQ<29>")
	)
	(segment
		(start 59.814968 -124.3076)
		(end 60.170568 -124.6632)
		(width 0.1651)
		(layer "F.Cu")
		(net "M_L_DQ<29>")
	)
	(segment
		(start 59.987434 -116.479066)
		(end 59.987434 -116.845334)
		(width 0.1651)
		(layer "F.Cu")
		(net "M_L_DQ<29>")
	)
	(segment
		(start 59.459368 -122.504454)
		(end 59.459368 -122.936254)
		(width 0.1651)
		(layer "F.Cu")
		(net "M_L_DQ<29>")
	)
	(segment
		(start 59.459368 -120.904)
		(end 59.459368 -121.3104)
		(width 0.1651)
		(layer "F.Cu")
		(net "M_L_DQ<29>")
	)
	(segment
		(start 76.023724 -102.527354)
		(end 73.97242 -102.527354)
		(width 0.1016)
		(layer "F.Cu")
		(net "M_L_DQ<29>")
	)
	(segment
		(start 59.987434 -118.307866)
		(end 59.987434 -118.648734)
		(width 0.1651)
		(layer "F.Cu")
		(net "M_L_DQ<29>")
	)
	(segment
		(start 59.987434 -116.845334)
		(end 59.459368 -117.3734)
		(width 0.1651)
		(layer "F.Cu")
		(net "M_L_DQ<29>")
	)
	(segment
		(start 77.192886 -99.67214)
		(end 76.903326 -100.327206)
		(width 0.0889)
		(layer "F.Cu")
		(net "M_L_DQ<29>")
	)
	(segment
		(start 59.891168 -121.7422)
		(end 59.891168 -122.072654)
		(width 0.1651)
		(layer "F.Cu")
		(net "M_L_DQ<29>")
	)
	(segment
		(start 59.814968 -123.291854)
		(end 59.814968 -124.3076)
		(width 0.1651)
		(layer "F.Cu")
		(net "M_L_DQ<29>")
	)
	(segment
		(start 71.164196 -102.844346)
		(end 67.988434 -102.844346)
		(width 0.1651)
		(layer "F.Cu")
		(net "M_L_DQ<29>")
	)
	(segment
		(start 59.459368 -122.936254)
		(end 59.814968 -123.291854)
		(width 0.1651)
		(layer "F.Cu")
		(net "M_L_DQ<29>")
	)
	(segment
		(start 76.846176 -100.462588)
		(end 76.84135 -100.471224)
		(width 0.0889)
		(layer "F.Cu")
		(net "M_L_DQ<29>")
	)
	(segment
		(start 59.987434 -120.375934)
		(end 59.459368 -120.904)
		(width 0.1651)
		(layer "F.Cu")
		(net "M_L_DQ<29>")
	)
	(via
		(at 59.449462 -143.941546)
		(size 0.508)
		(drill 0.254)
		(layers "F.Cu" "B.Cu")
		(net "M_L_DQ<29>")
	)
	(via
		(at 60.170568 -124.6632)
		(size 0.508)
		(drill 0.254)
		(layers "F.Cu" "B.Cu")
		(net "M_L_DQ<29>")
	)
	(via
		(at 60.223146 -139.932156)
		(size 0.508)
		(drill 0.254)
		(layers "F.Cu" "B.Cu")
		(net "M_L_DQ<29>")
	)
	(arc
		(start 76.903326 -100.327206)
		(mid 76.87899 -100.396688)
		(end 76.846176 -100.462588)
		(width 0.0889)
		(layer "F.Cu")
		(net "M_L_DQ<29>")
	)
	(arc
		(start 76.846176 -100.862638)
		(mid 76.925398 -101.151756)
		(end 76.852526 -101.44252)
		(width 0.0889)
		(layer "F.Cu")
		(net "M_L_DQ<29>")
	)
	(arc
		(start 76.84135 -100.471224)
		(mid 76.792595 -100.667576)
		(end 76.846176 -100.862638)
		(width 0.0889)
		(layer "F.Cu")
		(net "M_L_DQ<29>")
	)
	(segment
		(start 60.299346 -139.855956)
		(end 60.223146 -139.932156)
		(width 0.1651)
		(layer "B.Cu")
		(net "M_L_DQ<29>")
	)
	(segment
		(start 60.299346 -137.877296)
		(end 60.299346 -139.855956)
		(width 0.1651)
		(layer "B.Cu")
		(net "M_L_DQ<29>")
	)
	(segment
		(start 59.89955 -141.528546)
		(end 59.89955 -141.0462)
		(width 0.14224)
		(layer "In4.Cu")
		(net "M_L_DQ<29>")
	)
	(segment
		(start 60.607702 -125.100334)
		(end 60.170568 -124.6632)
		(width 0.14224)
		(layer "In4.Cu")
		(net "M_L_DQ<29>")
	)
	(segment
		(start 60.633102 -134.132066)
		(end 60.729368 -134.0358)
		(width 0.14224)
		(layer "In4.Cu")
		(net "M_L_DQ<29>")
	)
	(segment
		(start 59.77255 -140.9192)
		(end 59.77255 -140.3604)
		(width 0.14224)
		(layer "In4.Cu")
		(net "M_L_DQ<29>")
	)
	(segment
		(start 59.610752 -143.297656)
		(end 59.610752 -142.985744)
		(width 0.14224)
		(layer "In4.Cu")
		(net "M_L_DQ<29>")
	)
	(segment
		(start 60.633102 -131.434078)
		(end 60.696602 -131.370578)
		(width 0.14224)
		(layer "In4.Cu")
		(net "M_L_DQ<29>")
	)
	(segment
		(start 60.607702 -125.49632)
		(end 60.607702 -125.100334)
		(width 0.14224)
		(layer "In4.Cu")
		(net "M_L_DQ<29>")
	)
	(segment
		(start 60.607702 -127.9652)
		(end 60.195968 -127.553466)
		(width 0.14224)
		(layer "In4.Cu")
		(net "M_L_DQ<29>")
	)
	(segment
		(start 59.610752 -142.985744)
		(end 59.84875 -142.747746)
		(width 0.14224)
		(layer "In4.Cu")
		(net "M_L_DQ<29>")
	)
	(segment
		(start 60.607702 -136.005824)
		(end 60.760102 -135.853424)
		(width 0.14224)
		(layer "In4.Cu")
		(net "M_L_DQ<29>")
	)
	(segment
		(start 60.633102 -131.8768)
		(end 60.633102 -131.434078)
		(width 0.14224)
		(layer "In4.Cu")
		(net "M_L_DQ<29>")
	)
	(segment
		(start 60.696602 -131.370578)
		(end 60.696602 -129.795778)
		(width 0.14224)
		(layer "In4.Cu")
		(net "M_L_DQ<29>")
	)
	(segment
		(start 60.195968 -125.908054)
		(end 60.607702 -125.49632)
		(width 0.14224)
		(layer "In4.Cu")
		(net "M_L_DQ<29>")
	)
	(segment
		(start 59.72175 -143.941546)
		(end 59.87415 -143.789146)
		(width 0.14224)
		(layer "In4.Cu")
		(net "M_L_DQ<29>")
	)
	(segment
		(start 60.607702 -136.4996)
		(end 60.607702 -136.005824)
		(width 0.14224)
		(layer "In4.Cu")
		(net "M_L_DQ<29>")
	)
	(segment
		(start 59.610752 -141.817344)
		(end 59.89955 -141.528546)
		(width 0.14224)
		(layer "In4.Cu")
		(net "M_L_DQ<29>")
	)
	(segment
		(start 59.84875 -142.392654)
		(end 59.610752 -142.154656)
		(width 0.14224)
		(layer "In4.Cu")
		(net "M_L_DQ<29>")
	)
	(segment
		(start 60.729368 -136.621266)
		(end 60.607702 -136.4996)
		(width 0.14224)
		(layer "In4.Cu")
		(net "M_L_DQ<29>")
	)
	(segment
		(start 60.633102 -134.670038)
		(end 60.633102 -134.132066)
		(width 0.14224)
		(layer "In4.Cu")
		(net "M_L_DQ<29>")
	)
	(segment
		(start 60.729368 -134.0358)
		(end 60.729368 -131.973066)
		(width 0.14224)
		(layer "In4.Cu")
		(net "M_L_DQ<29>")
	)
	(segment
		(start 60.729368 -138.7856)
		(end 60.729368 -136.621266)
		(width 0.14224)
		(layer "In4.Cu")
		(net "M_L_DQ<29>")
	)
	(segment
		(start 59.84875 -142.747746)
		(end 59.84875 -142.392654)
		(width 0.14224)
		(layer "In4.Cu")
		(net "M_L_DQ<29>")
	)
	(segment
		(start 60.696602 -129.795778)
		(end 60.607702 -129.706878)
		(width 0.14224)
		(layer "In4.Cu")
		(net "M_L_DQ<29>")
	)
	(segment
		(start 59.87415 -143.789146)
		(end 59.87415 -143.561054)
		(width 0.14224)
		(layer "In4.Cu")
		(net "M_L_DQ<29>")
	)
	(segment
		(start 60.607702 -139.5476)
		(end 60.607702 -138.907266)
		(width 0.14224)
		(layer "In4.Cu")
		(net "M_L_DQ<29>")
	)
	(segment
		(start 59.87415 -143.561054)
		(end 59.610752 -143.297656)
		(width 0.14224)
		(layer "In4.Cu")
		(net "M_L_DQ<29>")
	)
	(segment
		(start 60.223146 -139.932156)
		(end 60.607702 -139.5476)
		(width 0.14224)
		(layer "In4.Cu")
		(net "M_L_DQ<29>")
	)
	(segment
		(start 59.610752 -142.154656)
		(end 59.610752 -141.817344)
		(width 0.14224)
		(layer "In4.Cu")
		(net "M_L_DQ<29>")
	)
	(segment
		(start 59.89955 -141.0462)
		(end 59.77255 -140.9192)
		(width 0.14224)
		(layer "In4.Cu")
		(net "M_L_DQ<29>")
	)
	(segment
		(start 60.607702 -138.907266)
		(end 60.729368 -138.7856)
		(width 0.14224)
		(layer "In4.Cu")
		(net "M_L_DQ<29>")
	)
	(segment
		(start 60.729368 -131.973066)
		(end 60.633102 -131.8768)
		(width 0.14224)
		(layer "In4.Cu")
		(net "M_L_DQ<29>")
	)
	(segment
		(start 59.449462 -143.941546)
		(end 59.72175 -143.941546)
		(width 0.14224)
		(layer "In4.Cu")
		(net "M_L_DQ<29>")
	)
	(segment
		(start 60.760102 -135.853424)
		(end 60.760102 -134.797038)
		(width 0.14224)
		(layer "In4.Cu")
		(net "M_L_DQ<29>")
	)
	(segment
		(start 60.760102 -134.797038)
		(end 60.633102 -134.670038)
		(width 0.14224)
		(layer "In4.Cu")
		(net "M_L_DQ<29>")
	)
	(segment
		(start 60.195968 -127.553466)
		(end 60.195968 -125.908054)
		(width 0.14224)
		(layer "In4.Cu")
		(net "M_L_DQ<29>")
	)
	(segment
		(start 60.200794 -139.932156)
		(end 60.223146 -139.932156)
		(width 0.14224)
		(layer "In4.Cu")
		(net "M_L_DQ<29>")
	)
	(segment
		(start 59.77255 -140.3604)
		(end 60.200794 -139.932156)
		(width 0.14224)
		(layer "In4.Cu")
		(net "M_L_DQ<29>")
	)
	(segment
		(start 60.607702 -129.706878)
		(end 60.607702 -127.9652)
		(width 0.14224)
		(layer "In4.Cu")
		(net "M_L_DQ<29>")
	)
	(segment
		(start 60.403486 -109.307376)
		(end 58.798968 -113.180622)
		(width 0.1651)
		(layer "F.Cu")
		(net "M_L_DQ<28>")
	)
	(segment
		(start 59.154568 -126.619)
		(end 59.256168 -126.619)
		(width 0.1651)
		(layer "F.Cu")
		(net "M_L_DQ<28>")
	)
	(segment
		(start 73.840848 -102.209854)
		(end 72.838056 -103.212646)
		(width 0.127)
		(layer "F.Cu")
		(net "M_L_DQ<28>")
	)
	(segment
		(start 72.302624 -103.212646)
		(end 71.286624 -102.196646)
		(width 0.127)
		(layer "F.Cu")
		(net "M_L_DQ<28>")
	)
	(segment
		(start 72.838056 -103.212646)
		(end 72.302624 -103.212646)
		(width 0.127)
		(layer "F.Cu")
		(net "M_L_DQ<28>")
	)
	(segment
		(start 76.674726 -99.95662)
		(end 76.681076 -99.967288)
		(width 0.0889)
		(layer "F.Cu")
		(net "M_L_DQ<28>")
	)
	(segment
		(start 76.490322 -101.69779)
		(end 76.183998 -102.004114)
		(width 0.0889)
		(layer "F.Cu")
		(net "M_L_DQ<28>")
	)
	(segment
		(start 76.685902 -101.349302)
		(end 76.490322 -101.69779)
		(width 0.0889)
		(layer "F.Cu")
		(net "M_L_DQ<28>")
	)
	(segment
		(start 60.299346 -147.27174)
		(end 60.299346 -145.946368)
		(width 0.1651)
		(layer "F.Cu")
		(net "M_L_DQ<28>")
	)
	(segment
		(start 58.798968 -113.180622)
		(end 58.798968 -126.2634)
		(width 0.1651)
		(layer "F.Cu")
		(net "M_L_DQ<28>")
	)
	(segment
		(start 58.798968 -126.2634)
		(end 59.154568 -126.619)
		(width 0.1651)
		(layer "F.Cu")
		(net "M_L_DQ<28>")
	)
	(segment
		(start 76.183998 -102.004114)
		(end 76.097892 -102.004114)
		(width 0.0889)
		(layer "F.Cu")
		(net "M_L_DQ<28>")
	)
	(segment
		(start 78.051406 -99.17684)
		(end 77.20838 -99.081336)
		(width 0.0889)
		(layer "F.Cu")
		(net "M_L_DQ<28>")
	)
	(segment
		(start 67.514216 -102.196646)
		(end 60.403486 -109.307376)
		(width 0.1651)
		(layer "F.Cu")
		(net "M_L_DQ<28>")
	)
	(segment
		(start 75.892152 -102.209854)
		(end 73.840848 -102.209854)
		(width 0.127)
		(layer "F.Cu")
		(net "M_L_DQ<28>")
	)
	(segment
		(start 76.097892 -102.004114)
		(end 75.892152 -102.209854)
		(width 0.127)
		(layer "F.Cu")
		(net "M_L_DQ<28>")
	)
	(segment
		(start 71.286624 -102.196646)
		(end 67.514216 -102.196646)
		(width 0.1651)
		(layer "F.Cu")
		(net "M_L_DQ<28>")
	)
	(segment
		(start 60.299346 -145.946368)
		(end 60.201302 -145.415)
		(width 0.1651)
		(layer "F.Cu")
		(net "M_L_DQ<28>")
	)
	(via
		(at 59.449462 -141.213078)
		(size 0.508)
		(drill 0.254)
		(layers "F.Cu" "B.Cu")
		(net "M_L_DQ<28>")
	)
	(via
		(at 60.201302 -145.415)
		(size 0.508)
		(drill 0.254)
		(layers "F.Cu" "B.Cu")
		(net "M_L_DQ<28>")
	)
	(via
		(at 59.256168 -126.619)
		(size 0.508)
		(drill 0.254)
		(layers "F.Cu" "B.Cu")
		(net "M_L_DQ<28>")
	)
	(arc
		(start 76.681076 -99.967288)
		(mid 76.734575 -100.167186)
		(end 76.681076 -100.367084)
		(width 0.0889)
		(layer "F.Cu")
		(net "M_L_DQ<28>")
	)
	(arc
		(start 76.681076 -100.367084)
		(mid 76.601945 -100.662486)
		(end 76.681076 -100.957888)
		(width 0.0889)
		(layer "F.Cu")
		(net "M_L_DQ<28>")
	)
	(arc
		(start 77.20838 -99.081336)
		(mid 76.688256 -99.364508)
		(end 76.674726 -99.95662)
		(width 0.0889)
		(layer "F.Cu")
		(net "M_L_DQ<28>")
	)
	(arc
		(start 76.681076 -100.957888)
		(mid 76.734546 -101.152951)
		(end 76.685902 -101.349302)
		(width 0.0889)
		(layer "F.Cu")
		(net "M_L_DQ<28>")
	)
	(segment
		(start 59.449462 -142.477236)
		(end 59.449462 -141.213078)
		(width 0.1651)
		(layer "B.Cu")
		(net "M_L_DQ<28>")
	)
	(segment
		(start 59.972702 -129.732278)
		(end 59.972702 -128.122934)
		(width 0.14224)
		(layer "In4.Cu")
		(net "M_L_DQ<28>")
	)
	(segment
		(start 59.016392 -141.646148)
		(end 59.449462 -141.213078)
		(width 0.14224)
		(layer "In4.Cu")
		(net "M_L_DQ<28>")
	)
	(segment
		(start 59.972702 -128.122934)
		(end 59.256168 -127.4064)
		(width 0.14224)
		(layer "In4.Cu")
		(net "M_L_DQ<28>")
	)
	(segment
		(start 59.910726 -134.498842)
		(end 59.910726 -131.372102)
		(width 0.14224)
		(layer "In4.Cu")
		(net "M_L_DQ<28>")
	)
	(segment
		(start 59.17438 -144.63903)
		(end 59.17438 -144.337278)
		(width 0.14224)
		(layer "In4.Cu")
		(net "M_L_DQ<28>")
	)
	(segment
		(start 59.321446 -139.972034)
		(end 59.916822 -139.376658)
		(width 0.14224)
		(layer "In4.Cu")
		(net "M_L_DQ<28>")
	)
	(segment
		(start 59.718702 -129.986278)
		(end 59.972702 -129.732278)
		(width 0.14224)
		(layer "In4.Cu")
		(net "M_L_DQ<28>")
	)
	(segment
		(start 59.321446 -141.085062)
		(end 59.321446 -139.972034)
		(width 0.14224)
		(layer "In4.Cu")
		(net "M_L_DQ<28>")
	)
	(segment
		(start 59.712098 -135.957564)
		(end 59.712098 -134.69747)
		(width 0.14224)
		(layer "In4.Cu")
		(net "M_L_DQ<28>")
	)
	(segment
		(start 59.449462 -141.213078)
		(end 59.321446 -141.085062)
		(width 0.14224)
		(layer "In4.Cu")
		(net "M_L_DQ<28>")
	)
	(segment
		(start 59.712098 -134.69747)
		(end 59.910726 -134.498842)
		(width 0.14224)
		(layer "In4.Cu")
		(net "M_L_DQ<28>")
	)
	(segment
		(start 59.916822 -139.376658)
		(end 59.916822 -136.162288)
		(width 0.14224)
		(layer "In4.Cu")
		(net "M_L_DQ<28>")
	)
	(segment
		(start 59.256168 -127.4064)
		(end 59.256168 -126.619)
		(width 0.14224)
		(layer "In4.Cu")
		(net "M_L_DQ<28>")
	)
	(segment
		(start 60.201302 -145.415)
		(end 59.95035 -145.415)
		(width 0.14224)
		(layer "In4.Cu")
		(net "M_L_DQ<28>")
	)
	(segment
		(start 59.17438 -144.337278)
		(end 59.016392 -144.17929)
		(width 0.14224)
		(layer "In4.Cu")
		(net "M_L_DQ<28>")
	)
	(segment
		(start 59.016392 -144.17929)
		(end 59.016392 -141.646148)
		(width 0.14224)
		(layer "In4.Cu")
		(net "M_L_DQ<28>")
	)
	(segment
		(start 59.718702 -131.180078)
		(end 59.718702 -129.986278)
		(width 0.14224)
		(layer "In4.Cu")
		(net "M_L_DQ<28>")
	)
	(segment
		(start 59.95035 -145.415)
		(end 59.17438 -144.63903)
		(width 0.14224)
		(layer "In4.Cu")
		(net "M_L_DQ<28>")
	)
	(segment
		(start 59.910726 -131.372102)
		(end 59.718702 -131.180078)
		(width 0.14224)
		(layer "In4.Cu")
		(net "M_L_DQ<28>")
	)
	(segment
		(start 59.916822 -136.162288)
		(end 59.712098 -135.957564)
		(width 0.14224)
		(layer "In4.Cu")
		(net "M_L_DQ<28>")
	)
	(segment
		(start 67.663568 -122.525536)
		(end 67.536568 -122.398536)
		(width 0.1651)
		(layer "F.Cu")
		(net "M_L_DQ<27>")
	)
	(segment
		(start 68.450968 -121.356374)
		(end 68.285868 -121.191274)
		(width 0.1651)
		(layer "F.Cu")
		(net "M_L_DQ<27>")
	)
	(segment
		(start 67.793108 -112.513872)
		(end 68.285868 -112.513872)
		(width 0.1651)
		(layer "F.Cu")
		(net "M_L_DQ<27>")
	)
	(segment
		(start 68.450968 -124.0409)
		(end 68.323968 -123.9139)
		(width 0.1651)
		(layer "F.Cu")
		(net "M_L_DQ<27>")
	)
	(segment
		(start 67.628008 -112.678972)
		(end 67.793108 -112.513872)
		(width 0.1651)
		(layer "F.Cu")
		(net "M_L_DQ<27>")
	)
	(segment
		(start 67.701668 -119.171974)
		(end 68.285868 -119.171974)
		(width 0.1651)
		(layer "F.Cu")
		(net "M_L_DQ<27>")
	)
	(segment
		(start 67.966336 -125.455426)
		(end 68.03771 -125.5268)
		(width 0.1651)
		(layer "F.Cu")
		(net "M_L_DQ<27>")
	)
	(segment
		(start 68.285868 -121.191274)
		(end 67.701668 -121.191274)
		(width 0.1651)
		(layer "F.Cu")
		(net "M_L_DQ<27>")
	)
	(segment
		(start 72.097392 -108.610146)
		(end 72.22236 -108.610146)
		(width 0.127)
		(layer "F.Cu")
		(net "M_L_DQ<27>")
	)
	(segment
		(start 80.268064 -101.446584)
		(end 80.164432 -101.632004)
		(width 0.0889)
		(layer "F.Cu")
		(net "M_L_DQ<27>")
	)
	(segment
		(start 68.273168 -122.525536)
		(end 67.663568 -122.525536)
		(width 0.1651)
		(layer "F.Cu")
		(net "M_L_DQ<27>")
	)
	(segment
		(start 68.450968 -118.663974)
		(end 68.285868 -118.498874)
		(width 0.1651)
		(layer "F.Cu")
		(net "M_L_DQ<27>")
	)
	(segment
		(start 67.701668 -119.845074)
		(end 67.536568 -119.679974)
		(width 0.1651)
		(layer "F.Cu")
		(net "M_L_DQ<27>")
	)
	(segment
		(start 68.450968 -113.352072)
		(end 68.285868 -113.186972)
		(width 0.1651)
		(layer "F.Cu")
		(net "M_L_DQ<27>")
	)
	(segment
		(start 68.285868 -120.518174)
		(end 68.450968 -120.353074)
		(width 0.1651)
		(layer "F.Cu")
		(net "M_L_DQ<27>")
	)
	(segment
		(start 67.701668 -121.191274)
		(end 67.536568 -121.026174)
		(width 0.1651)
		(layer "F.Cu")
		(net "M_L_DQ<27>")
	)
	(segment
		(start 80.164432 -103.423974)
		(end 80.136492 -103.451914)
		(width 0.0889)
		(layer "F.Cu")
		(net "M_L_DQ<27>")
	)
	(segment
		(start 68.450968 -121.699274)
		(end 68.450968 -121.356374)
		(width 0.1651)
		(layer "F.Cu")
		(net "M_L_DQ<27>")
	)
	(segment
		(start 68.03771 -125.5268)
		(end 68.323968 -125.5268)
		(width 0.1651)
		(layer "F.Cu")
		(net "M_L_DQ<27>")
	)
	(segment
		(start 67.701668 -120.518174)
		(end 68.285868 -120.518174)
		(width 0.1651)
		(layer "F.Cu")
		(net "M_L_DQ<27>")
	)
	(segment
		(start 68.450968 -112.348772)
		(end 68.450968 -111.8489)
		(width 0.1651)
		(layer "F.Cu")
		(net "M_L_DQ<27>")
	)
	(segment
		(start 67.701668 -118.498874)
		(end 67.536568 -118.333774)
		(width 0.1651)
		(layer "F.Cu")
		(net "M_L_DQ<27>")
	)
	(segment
		(start 68.144644 -123.9139)
		(end 67.942968 -123.712224)
		(width 0.1651)
		(layer "F.Cu")
		(net "M_L_DQ<27>")
	)
	(segment
		(start 68.298568 -116.4336)
		(end 68.298568 -116.0272)
		(width 0.1651)
		(layer "F.Cu")
		(net "M_L_DQ<27>")
	)
	(segment
		(start 67.536568 -120.683274)
		(end 67.701668 -120.518174)
		(width 0.1651)
		(layer "F.Cu")
		(net "M_L_DQ<27>")
	)
	(segment
		(start 68.247514 -117.8306)
		(end 68.450968 -117.627146)
		(width 0.1651)
		(layer "F.Cu")
		(net "M_L_DQ<27>")
	)
	(segment
		(start 68.273168 -114.868706)
		(end 68.273168 -114.223546)
		(width 0.1651)
		(layer "F.Cu")
		(net "M_L_DQ<27>")
	)
	(segment
		(start 80.164432 -101.632004)
		(end 80.164432 -103.423974)
		(width 0.0889)
		(layer "F.Cu")
		(net "M_L_DQ<27>")
	)
	(segment
		(start 68.450968 -120.353074)
		(end 68.450968 -120.010174)
		(width 0.1651)
		(layer "F.Cu")
		(net "M_L_DQ<27>")
	)
	(segment
		(start 67.536568 -122.398536)
		(end 67.536568 -122.029474)
		(width 0.1651)
		(layer "F.Cu")
		(net "M_L_DQ<27>")
	)
	(segment
		(start 68.450968 -123.033536)
		(end 68.450968 -122.703336)
		(width 0.1651)
		(layer "F.Cu")
		(net "M_L_DQ<27>")
	)
	(segment
		(start 68.450968 -114.045746)
		(end 68.450968 -113.352072)
		(width 0.1651)
		(layer "F.Cu")
		(net "M_L_DQ<27>")
	)
	(segment
		(start 68.323968 -125.5268)
		(end 68.450968 -125.3998)
		(width 0.1651)
		(layer "F.Cu")
		(net "M_L_DQ<27>")
	)
	(segment
		(start 68.112386 -123.185936)
		(end 68.298568 -123.185936)
		(width 0.1651)
		(layer "F.Cu")
		(net "M_L_DQ<27>")
	)
	(segment
		(start 68.273168 -114.223546)
		(end 68.450968 -114.045746)
		(width 0.1651)
		(layer "F.Cu")
		(net "M_L_DQ<27>")
	)
	(segment
		(start 68.285868 -119.171974)
		(end 68.450968 -119.006874)
		(width 0.1651)
		(layer "F.Cu")
		(net "M_L_DQ<27>")
	)
	(segment
		(start 68.450968 -122.703336)
		(end 68.273168 -122.525536)
		(width 0.1651)
		(layer "F.Cu")
		(net "M_L_DQ<27>")
	)
	(segment
		(start 68.298568 -116.0272)
		(end 68.450968 -115.8748)
		(width 0.1651)
		(layer "F.Cu")
		(net "M_L_DQ<27>")
	)
	(segment
		(start 67.536568 -121.026174)
		(end 67.536568 -120.683274)
		(width 0.1651)
		(layer "F.Cu")
		(net "M_L_DQ<27>")
	)
	(segment
		(start 68.450968 -117.627146)
		(end 68.450968 -116.586)
		(width 0.1651)
		(layer "F.Cu")
		(net "M_L_DQ<27>")
	)
	(segment
		(start 68.285868 -121.864374)
		(end 68.450968 -121.699274)
		(width 0.1651)
		(layer "F.Cu")
		(net "M_L_DQ<27>")
	)
	(segment
		(start 67.536568 -117.9576)
		(end 67.663568 -117.8306)
		(width 0.1651)
		(layer "F.Cu")
		(net "M_L_DQ<27>")
	)
	(segment
		(start 68.450968 -115.046506)
		(end 68.273168 -114.868706)
		(width 0.1651)
		(layer "F.Cu")
		(net "M_L_DQ<27>")
	)
	(segment
		(start 67.793108 -113.186972)
		(end 67.628008 -113.021872)
		(width 0.1651)
		(layer "F.Cu")
		(net "M_L_DQ<27>")
	)
	(segment
		(start 68.285868 -112.513872)
		(end 68.450968 -112.348772)
		(width 0.1651)
		(layer "F.Cu")
		(net "M_L_DQ<27>")
	)
	(segment
		(start 71.689722 -108.610146)
		(end 72.097392 -108.610146)
		(width 0.1651)
		(layer "F.Cu")
		(net "M_L_DQ<27>")
	)
	(segment
		(start 68.450968 -120.010174)
		(end 68.285868 -119.845074)
		(width 0.1651)
		(layer "F.Cu")
		(net "M_L_DQ<27>")
	)
	(segment
		(start 68.285868 -119.845074)
		(end 67.701668 -119.845074)
		(width 0.1651)
		(layer "F.Cu")
		(net "M_L_DQ<27>")
	)
	(segment
		(start 67.536568 -122.029474)
		(end 67.701668 -121.864374)
		(width 0.1651)
		(layer "F.Cu")
		(net "M_L_DQ<27>")
	)
	(segment
		(start 68.298568 -123.185936)
		(end 68.450968 -123.033536)
		(width 0.1651)
		(layer "F.Cu")
		(net "M_L_DQ<27>")
	)
	(segment
		(start 68.450968 -111.8489)
		(end 71.689722 -108.610146)
		(width 0.1651)
		(layer "F.Cu")
		(net "M_L_DQ<27>")
	)
	(segment
		(start 67.663568 -117.8306)
		(end 68.247514 -117.8306)
		(width 0.1651)
		(layer "F.Cu")
		(net "M_L_DQ<27>")
	)
	(segment
		(start 68.285868 -113.186972)
		(end 67.793108 -113.186972)
		(width 0.1651)
		(layer "F.Cu")
		(net "M_L_DQ<27>")
	)
	(segment
		(start 80.333342 -101.336856)
		(end 80.268064 -101.446584)
		(width 0.0889)
		(layer "F.Cu")
		(net "M_L_DQ<27>")
	)
	(segment
		(start 67.536568 -119.337074)
		(end 67.701668 -119.171974)
		(width 0.1651)
		(layer "F.Cu")
		(net "M_L_DQ<27>")
	)
	(segment
		(start 68.323968 -123.9139)
		(end 68.144644 -123.9139)
		(width 0.1651)
		(layer "F.Cu")
		(net "M_L_DQ<27>")
	)
	(segment
		(start 68.450968 -115.8748)
		(end 68.450968 -115.046506)
		(width 0.1651)
		(layer "F.Cu")
		(net "M_L_DQ<27>")
	)
	(segment
		(start 67.099434 -142.6718)
		(end 67.099434 -143.941546)
		(width 0.1651)
		(layer "F.Cu")
		(net "M_L_DQ<27>")
	)
	(segment
		(start 68.450968 -119.006874)
		(end 68.450968 -118.663974)
		(width 0.1651)
		(layer "F.Cu")
		(net "M_L_DQ<27>")
	)
	(segment
		(start 68.450968 -125.3998)
		(end 68.450968 -124.0409)
		(width 0.1651)
		(layer "F.Cu")
		(net "M_L_DQ<27>")
	)
	(segment
		(start 67.628008 -113.021872)
		(end 67.628008 -112.678972)
		(width 0.1651)
		(layer "F.Cu")
		(net "M_L_DQ<27>")
	)
	(segment
		(start 72.22236 -108.610146)
		(end 75.244452 -105.588054)
		(width 0.127)
		(layer "F.Cu")
		(net "M_L_DQ<27>")
	)
	(segment
		(start 68.285868 -118.498874)
		(end 67.701668 -118.498874)
		(width 0.1651)
		(layer "F.Cu")
		(net "M_L_DQ<27>")
	)
	(segment
		(start 68.450968 -116.586)
		(end 68.298568 -116.4336)
		(width 0.1651)
		(layer "F.Cu")
		(net "M_L_DQ<27>")
	)
	(segment
		(start 67.701668 -121.864374)
		(end 68.285868 -121.864374)
		(width 0.1651)
		(layer "F.Cu")
		(net "M_L_DQ<27>")
	)
	(segment
		(start 67.536568 -118.333774)
		(end 67.536568 -117.9576)
		(width 0.1651)
		(layer "F.Cu")
		(net "M_L_DQ<27>")
	)
	(segment
		(start 67.536568 -119.679974)
		(end 67.536568 -119.337074)
		(width 0.1651)
		(layer "F.Cu")
		(net "M_L_DQ<27>")
	)
	(segment
		(start 78.000352 -105.588054)
		(end 75.244452 -105.588054)
		(width 0.127)
		(layer "F.Cu")
		(net "M_L_DQ<27>")
	)
	(segment
		(start 67.942968 -123.355354)
		(end 68.112386 -123.185936)
		(width 0.1651)
		(layer "F.Cu")
		(net "M_L_DQ<27>")
	)
	(segment
		(start 80.136492 -103.451914)
		(end 78.000352 -105.588054)
		(width 0.127)
		(layer "F.Cu")
		(net "M_L_DQ<27>")
	)
	(segment
		(start 67.942968 -123.712224)
		(end 67.942968 -123.355354)
		(width 0.1651)
		(layer "F.Cu")
		(net "M_L_DQ<27>")
	)
	(segment
		(start 80.626712 -100.662486)
		(end 80.338676 -101.326696)
		(width 0.0889)
		(layer "F.Cu")
		(net "M_L_DQ<27>")
	)
	(via
		(at 67.966336 -125.455426)
		(size 0.508)
		(drill 0.254)
		(layers "F.Cu" "B.Cu")
		(net "M_L_DQ<27>")
	)
	(via
		(at 67.949318 -139.932156)
		(size 0.508)
		(drill 0.254)
		(layers "F.Cu" "B.Cu")
		(net "M_L_DQ<27>")
	)
	(via
		(at 67.099434 -143.941546)
		(size 0.508)
		(drill 0.254)
		(layers "F.Cu" "B.Cu")
		(net "M_L_DQ<27>")
	)
	(arc
		(start 80.338676 -101.326696)
		(mid 80.336172 -101.331862)
		(end 80.333342 -101.336856)
		(width 0.0889)
		(layer "F.Cu")
		(net "M_L_DQ<27>")
	)
	(segment
		(start 67.949318 -137.877296)
		(end 67.949318 -139.932156)
		(width 0.1651)
		(layer "B.Cu")
		(net "M_L_DQ<27>")
	)
	(segment
		(start 67.949572 -137.877296)
		(end 67.949318 -137.877296)
		(width 0.1651)
		(layer "B.Cu")
		(net "M_L_DQ<27>")
	)
	(segment
		(start 67.993768 -137.362946)
		(end 68.273168 -137.642346)
		(width 0.14224)
		(layer "In4.Cu")
		(net "M_L_DQ<27>")
	)
	(segment
		(start 67.498722 -140.3604)
		(end 67.498722 -140.790168)
		(width 0.14224)
		(layer "In4.Cu")
		(net "M_L_DQ<27>")
	)
	(segment
		(start 68.273168 -137.922)
		(end 68.045584 -138.149584)
		(width 0.14224)
		(layer "In4.Cu")
		(net "M_L_DQ<27>")
	)
	(segment
		(start 67.260724 -142.878048)
		(end 67.260724 -143.151352)
		(width 0.14224)
		(layer "In4.Cu")
		(net "M_L_DQ<27>")
	)
	(segment
		(start 68.278502 -136.72312)
		(end 67.993768 -137.007854)
		(width 0.14224)
		(layer "In4.Cu")
		(net "M_L_DQ<27>")
	)
	(segment
		(start 67.260724 -142.059152)
		(end 67.517772 -142.3162)
		(width 0.14224)
		(layer "In4.Cu")
		(net "M_L_DQ<27>")
	)
	(segment
		(start 67.543172 -140.834618)
		(end 67.543172 -141.5034)
		(width 0.14224)
		(layer "In4.Cu")
		(net "M_L_DQ<27>")
	)
	(segment
		(start 67.549522 -143.44015)
		(end 67.549522 -143.763746)
		(width 0.14224)
		(layer "In4.Cu")
		(net "M_L_DQ<27>")
	)
	(segment
		(start 68.273168 -138.7602)
		(end 68.273168 -139.621514)
		(width 0.14224)
		(layer "In4.Cu")
		(net "M_L_DQ<27>")
	)
	(segment
		(start 68.273168 -139.621514)
		(end 67.949318 -139.945364)
		(width 0.14224)
		(layer "In4.Cu")
		(net "M_L_DQ<27>")
	)
	(segment
		(start 68.273168 -137.642346)
		(end 68.273168 -137.922)
		(width 0.14224)
		(layer "In4.Cu")
		(net "M_L_DQ<27>")
	)
	(segment
		(start 67.966336 -125.455426)
		(end 68.303902 -125.792992)
		(width 0.14224)
		(layer "In4.Cu")
		(net "M_L_DQ<27>")
	)
	(segment
		(start 67.517772 -142.621)
		(end 67.260724 -142.878048)
		(width 0.14224)
		(layer "In4.Cu")
		(net "M_L_DQ<27>")
	)
	(segment
		(start 68.532502 -136.011412)
		(end 68.278502 -136.265412)
		(width 0.14224)
		(layer "In4.Cu")
		(net "M_L_DQ<27>")
	)
	(segment
		(start 68.278502 -136.265412)
		(end 68.278502 -136.72312)
		(width 0.14224)
		(layer "In4.Cu")
		(net "M_L_DQ<27>")
	)
	(segment
		(start 67.926966 -139.932156)
		(end 67.498722 -140.3604)
		(width 0.14224)
		(layer "In4.Cu")
		(net "M_L_DQ<27>")
	)
	(segment
		(start 68.045584 -138.532616)
		(end 68.273168 -138.7602)
		(width 0.14224)
		(layer "In4.Cu")
		(net "M_L_DQ<27>")
	)
	(segment
		(start 68.316602 -134.119366)
		(end 68.316602 -134.581138)
		(width 0.14224)
		(layer "In4.Cu")
		(net "M_L_DQ<27>")
	)
	(segment
		(start 68.303902 -129.960878)
		(end 68.456302 -130.113278)
		(width 0.14224)
		(layer "In4.Cu")
		(net "M_L_DQ<27>")
	)
	(segment
		(start 68.374768 -131.934966)
		(end 68.374768 -134.0612)
		(width 0.14224)
		(layer "In4.Cu")
		(net "M_L_DQ<27>")
	)
	(segment
		(start 68.456302 -130.113278)
		(end 68.456302 -131.268978)
		(width 0.14224)
		(layer "In4.Cu")
		(net "M_L_DQ<27>")
	)
	(segment
		(start 68.045584 -138.149584)
		(end 68.045584 -138.532616)
		(width 0.14224)
		(layer "In4.Cu")
		(net "M_L_DQ<27>")
	)
	(segment
		(start 67.260724 -141.785848)
		(end 67.260724 -142.059152)
		(width 0.14224)
		(layer "In4.Cu")
		(net "M_L_DQ<27>")
	)
	(segment
		(start 68.532502 -134.797038)
		(end 68.532502 -136.011412)
		(width 0.14224)
		(layer "In4.Cu")
		(net "M_L_DQ<27>")
	)
	(segment
		(start 68.316602 -131.8768)
		(end 68.374768 -131.934966)
		(width 0.14224)
		(layer "In4.Cu")
		(net "M_L_DQ<27>")
	)
	(segment
		(start 67.949318 -139.932156)
		(end 67.926966 -139.932156)
		(width 0.14224)
		(layer "In4.Cu")
		(net "M_L_DQ<27>")
	)
	(segment
		(start 67.260724 -143.151352)
		(end 67.549522 -143.44015)
		(width 0.14224)
		(layer "In4.Cu")
		(net "M_L_DQ<27>")
	)
	(segment
		(start 68.316602 -134.581138)
		(end 68.532502 -134.797038)
		(width 0.14224)
		(layer "In4.Cu")
		(net "M_L_DQ<27>")
	)
	(segment
		(start 67.993768 -137.007854)
		(end 67.993768 -137.362946)
		(width 0.14224)
		(layer "In4.Cu")
		(net "M_L_DQ<27>")
	)
	(segment
		(start 67.549522 -143.763746)
		(end 67.371722 -143.941546)
		(width 0.14224)
		(layer "In4.Cu")
		(net "M_L_DQ<27>")
	)
	(segment
		(start 67.371722 -143.941546)
		(end 67.099434 -143.941546)
		(width 0.14224)
		(layer "In4.Cu")
		(net "M_L_DQ<27>")
	)
	(segment
		(start 68.374768 -134.0612)
		(end 68.316602 -134.119366)
		(width 0.14224)
		(layer "In4.Cu")
		(net "M_L_DQ<27>")
	)
	(segment
		(start 68.316602 -131.408678)
		(end 68.316602 -131.8768)
		(width 0.14224)
		(layer "In4.Cu")
		(net "M_L_DQ<27>")
	)
	(segment
		(start 67.498722 -140.790168)
		(end 67.543172 -140.834618)
		(width 0.14224)
		(layer "In4.Cu")
		(net "M_L_DQ<27>")
	)
	(segment
		(start 68.303902 -125.792992)
		(end 68.303902 -129.960878)
		(width 0.14224)
		(layer "In4.Cu")
		(net "M_L_DQ<27>")
	)
	(segment
		(start 67.517772 -142.3162)
		(end 67.517772 -142.621)
		(width 0.14224)
		(layer "In4.Cu")
		(net "M_L_DQ<27>")
	)
	(segment
		(start 67.949318 -139.945364)
		(end 67.949318 -139.932156)
		(width 0.14224)
		(layer "In4.Cu")
		(net "M_L_DQ<27>")
	)
	(segment
		(start 68.456302 -131.268978)
		(end 68.316602 -131.408678)
		(width 0.14224)
		(layer "In4.Cu")
		(net "M_L_DQ<27>")
	)
	(segment
		(start 67.543172 -141.5034)
		(end 67.260724 -141.785848)
		(width 0.14224)
		(layer "In4.Cu")
		(net "M_L_DQ<27>")
	)
	(segment
		(start 79.973932 -101.621082)
		(end 79.973932 -103.165402)
		(width 0.0889)
		(layer "F.Cu")
		(net "M_L_DQ<26>")
	)
	(segment
		(start 67.447668 -114.554762)
		(end 67.092068 -114.554762)
		(width 0.1651)
		(layer "F.Cu")
		(net "M_L_DQ<26>")
	)
	(segment
		(start 79.973932 -103.165402)
		(end 79.937356 -103.201978)
		(width 0.0889)
		(layer "F.Cu")
		(net "M_L_DQ<26>")
	)
	(segment
		(start 67.092068 -116.535962)
		(end 67.549268 -116.535962)
		(width 0.1651)
		(layer "F.Cu")
		(net "M_L_DQ<26>")
	)
	(segment
		(start 80.117188 -101.30409)
		(end 80.094074 -101.345492)
		(width 0.0889)
		(layer "F.Cu")
		(net "M_L_DQ<26>")
	)
	(segment
		(start 76.830174 -105.270554)
		(end 75.11288 -105.270554)
		(width 0.1016)
		(layer "F.Cu")
		(net "M_L_DQ<26>")
	)
	(segment
		(start 67.331336 -126.8476)
		(end 67.099434 -126.615698)
		(width 0.1651)
		(layer "F.Cu")
		(net "M_L_DQ<26>")
	)
	(segment
		(start 66.885058 -123.52909)
		(end 67.384168 -124.0282)
		(width 0.1651)
		(layer "F.Cu")
		(net "M_L_DQ<26>")
	)
	(segment
		(start 67.949572 -147.27174)
		(end 67.949318 -147.27174)
		(width 0.1651)
		(layer "F.Cu")
		(net "M_L_DQ<26>")
	)
	(segment
		(start 66.917062 -113.693956)
		(end 67.117468 -113.894362)
		(width 0.1651)
		(layer "F.Cu")
		(net "M_L_DQ<26>")
	)
	(segment
		(start 67.447668 -113.894362)
		(end 67.612768 -114.059462)
		(width 0.1651)
		(layer "F.Cu")
		(net "M_L_DQ<26>")
	)
	(segment
		(start 67.549268 -117.196362)
		(end 67.092068 -117.196362)
		(width 0.1651)
		(layer "F.Cu")
		(net "M_L_DQ<26>")
	)
	(segment
		(start 67.714368 -116.701062)
		(end 67.714368 -117.031262)
		(width 0.1651)
		(layer "F.Cu")
		(net "M_L_DQ<26>")
	)
	(segment
		(start 67.949318 -145.793968)
		(end 67.949318 -145.5166)
		(width 0.1651)
		(layer "F.Cu")
		(net "M_L_DQ<26>")
	)
	(segment
		(start 67.612768 -114.389662)
		(end 67.447668 -114.554762)
		(width 0.1651)
		(layer "F.Cu")
		(net "M_L_DQ<26>")
	)
	(segment
		(start 67.917568 -126.619)
		(end 67.688968 -126.8476)
		(width 0.1651)
		(layer "F.Cu")
		(net "M_L_DQ<26>")
	)
	(segment
		(start 67.688968 -126.8476)
		(end 67.331336 -126.8476)
		(width 0.1651)
		(layer "F.Cu")
		(net "M_L_DQ<26>")
	)
	(segment
		(start 77.86878 -105.270554)
		(end 76.830174 -105.270554)
		(width 0.1016)
		(layer "F.Cu")
		(net "M_L_DQ<26>")
	)
	(segment
		(start 67.949318 -147.27174)
		(end 67.949318 -146.280632)
		(width 0.1651)
		(layer "F.Cu")
		(net "M_L_DQ<26>")
	)
	(segment
		(start 67.485768 -125.6792)
		(end 67.917568 -126.111)
		(width 0.1651)
		(layer "F.Cu")
		(net "M_L_DQ<26>")
	)
	(segment
		(start 67.384168 -124.0282)
		(end 67.384168 -125.1458)
		(width 0.1651)
		(layer "F.Cu")
		(net "M_L_DQ<26>")
	)
	(segment
		(start 72.275192 -107.962446)
		(end 71.397876 -107.962446)
		(width 0.1651)
		(layer "F.Cu")
		(net "M_L_DQ<26>")
	)
	(segment
		(start 67.092068 -114.554762)
		(end 66.926968 -114.719862)
		(width 0.1651)
		(layer "F.Cu")
		(net "M_L_DQ<26>")
	)
	(segment
		(start 71.397876 -107.962446)
		(end 66.917062 -112.44326)
		(width 0.1651)
		(layer "F.Cu")
		(net "M_L_DQ<26>")
	)
	(segment
		(start 72.420988 -107.962446)
		(end 72.275192 -107.962446)
		(width 0.1016)
		(layer "F.Cu")
		(net "M_L_DQ<26>")
	)
	(segment
		(start 67.612768 -114.059462)
		(end 67.612768 -114.389662)
		(width 0.1651)
		(layer "F.Cu")
		(net "M_L_DQ<26>")
	)
	(segment
		(start 68.08089 -145.92554)
		(end 67.949318 -145.793968)
		(width 0.1651)
		(layer "F.Cu")
		(net "M_L_DQ<26>")
	)
	(segment
		(start 67.549268 -115.215162)
		(end 67.714368 -115.380262)
		(width 0.1651)
		(layer "F.Cu")
		(net "M_L_DQ<26>")
	)
	(segment
		(start 75.11288 -105.270554)
		(end 72.420988 -107.962446)
		(width 0.1016)
		(layer "F.Cu")
		(net "M_L_DQ<26>")
	)
	(segment
		(start 67.092068 -115.875562)
		(end 66.926968 -116.040662)
		(width 0.1651)
		(layer "F.Cu")
		(net "M_L_DQ<26>")
	)
	(segment
		(start 66.917062 -112.44326)
		(end 66.917062 -113.693956)
		(width 0.1651)
		(layer "F.Cu")
		(net "M_L_DQ<26>")
	)
	(segment
		(start 67.092068 -117.196362)
		(end 66.885058 -117.403372)
		(width 0.1651)
		(layer "F.Cu")
		(net "M_L_DQ<26>")
	)
	(segment
		(start 66.885058 -117.403372)
		(end 66.885058 -123.52909)
		(width 0.1651)
		(layer "F.Cu")
		(net "M_L_DQ<26>")
	)
	(segment
		(start 67.092068 -115.215162)
		(end 67.549268 -115.215162)
		(width 0.1651)
		(layer "F.Cu")
		(net "M_L_DQ<26>")
	)
	(segment
		(start 67.384168 -125.1458)
		(end 67.485768 -125.2474)
		(width 0.1651)
		(layer "F.Cu")
		(net "M_L_DQ<26>")
	)
	(segment
		(start 67.917568 -126.111)
		(end 67.917568 -126.619)
		(width 0.1651)
		(layer "F.Cu")
		(net "M_L_DQ<26>")
	)
	(segment
		(start 80.626712 -99.67214)
		(end 80.162146 -100.297234)
		(width 0.0889)
		(layer "F.Cu")
		(net "M_L_DQ<26>")
	)
	(segment
		(start 66.926968 -114.719862)
		(end 66.926968 -115.050062)
		(width 0.1651)
		(layer "F.Cu")
		(net "M_L_DQ<26>")
	)
	(segment
		(start 67.714368 -117.031262)
		(end 67.549268 -117.196362)
		(width 0.1651)
		(layer "F.Cu")
		(net "M_L_DQ<26>")
	)
	(segment
		(start 66.926968 -116.370862)
		(end 67.092068 -116.535962)
		(width 0.1651)
		(layer "F.Cu")
		(net "M_L_DQ<26>")
	)
	(segment
		(start 66.926968 -115.050062)
		(end 67.092068 -115.215162)
		(width 0.1651)
		(layer "F.Cu")
		(net "M_L_DQ<26>")
	)
	(segment
		(start 79.937356 -103.201978)
		(end 77.86878 -105.270554)
		(width 0.1016)
		(layer "F.Cu")
		(net "M_L_DQ<26>")
	)
	(segment
		(start 67.714368 -115.710462)
		(end 67.549268 -115.875562)
		(width 0.1651)
		(layer "F.Cu")
		(net "M_L_DQ<26>")
	)
	(segment
		(start 67.485768 -125.2474)
		(end 67.485768 -125.6792)
		(width 0.1651)
		(layer "F.Cu")
		(net "M_L_DQ<26>")
	)
	(segment
		(start 66.926968 -116.040662)
		(end 66.926968 -116.370862)
		(width 0.1651)
		(layer "F.Cu")
		(net "M_L_DQ<26>")
	)
	(segment
		(start 67.549268 -115.875562)
		(end 67.092068 -115.875562)
		(width 0.1651)
		(layer "F.Cu")
		(net "M_L_DQ<26>")
	)
	(segment
		(start 68.08089 -146.14906)
		(end 68.08089 -145.92554)
		(width 0.1651)
		(layer "F.Cu")
		(net "M_L_DQ<26>")
	)
	(segment
		(start 67.549268 -116.535962)
		(end 67.714368 -116.701062)
		(width 0.1651)
		(layer "F.Cu")
		(net "M_L_DQ<26>")
	)
	(segment
		(start 67.949318 -146.280632)
		(end 68.08089 -146.14906)
		(width 0.1651)
		(layer "F.Cu")
		(net "M_L_DQ<26>")
	)
	(segment
		(start 67.714368 -115.380262)
		(end 67.714368 -115.710462)
		(width 0.1651)
		(layer "F.Cu")
		(net "M_L_DQ<26>")
	)
	(segment
		(start 67.117468 -113.894362)
		(end 67.447668 -113.894362)
		(width 0.1651)
		(layer "F.Cu")
		(net "M_L_DQ<26>")
	)
	(segment
		(start 80.094074 -101.345492)
		(end 80.011524 -101.484176)
		(width 0.0889)
		(layer "F.Cu")
		(net "M_L_DQ<26>")
	)
	(via
		(at 67.099434 -141.213078)
		(size 0.508)
		(drill 0.254)
		(layers "F.Cu" "B.Cu")
		(net "M_L_DQ<26>")
	)
	(via
		(at 67.099434 -126.615698)
		(size 0.508)
		(drill 0.254)
		(layers "F.Cu" "B.Cu")
		(net "M_L_DQ<26>")
	)
	(via
		(at 67.949318 -145.5166)
		(size 0.508)
		(drill 0.254)
		(layers "F.Cu" "B.Cu")
		(net "M_L_DQ<26>")
	)
	(arc
		(start 80.011524 -101.484176)
		(mid 79.983462 -101.550088)
		(end 79.973932 -101.621082)
		(width 0.0889)
		(layer "F.Cu")
		(net "M_L_DQ<26>")
	)
	(arc
		(start 80.162146 -100.297234)
		(mid 80.037261 -100.620322)
		(end 80.114902 -100.957888)
		(width 0.0889)
		(layer "F.Cu")
		(net "M_L_DQ<26>")
	)
	(arc
		(start 80.114902 -100.957888)
		(mid 80.161733 -101.130673)
		(end 80.117188 -101.30409)
		(width 0.0889)
		(layer "F.Cu")
		(net "M_L_DQ<26>")
	)
	(segment
		(start 67.099434 -142.477236)
		(end 67.099434 -141.213078)
		(width 0.1651)
		(layer "B.Cu")
		(net "M_L_DQ<26>")
	)
	(segment
		(start 67.536568 -134.0612)
		(end 67.536568 -132.009134)
		(width 0.14224)
		(layer "In4.Cu")
		(net "M_L_DQ<26>")
	)
	(segment
		(start 67.465702 -129.960878)
		(end 67.592702 -129.833878)
		(width 0.14224)
		(layer "In4.Cu")
		(net "M_L_DQ<26>")
	)
	(segment
		(start 67.389502 -134.771638)
		(end 67.668902 -134.492238)
		(width 0.14224)
		(layer "In4.Cu")
		(net "M_L_DQ<26>")
	)
	(segment
		(start 67.536568 -138.8872)
		(end 67.536568 -136.631934)
		(width 0.14224)
		(layer "In4.Cu")
		(net "M_L_DQ<26>")
	)
	(segment
		(start 66.754502 -140.868146)
		(end 66.754502 -140.235178)
		(width 0.14224)
		(layer "In4.Cu")
		(net "M_L_DQ<26>")
	)
	(segment
		(start 67.465702 -131.332478)
		(end 67.465702 -129.960878)
		(width 0.14224)
		(layer "In4.Cu")
		(net "M_L_DQ<26>")
	)
	(segment
		(start 67.618102 -136.5504)
		(end 67.618102 -136.205468)
		(width 0.14224)
		(layer "In4.Cu")
		(net "M_L_DQ<26>")
	)
	(segment
		(start 67.592702 -127.108966)
		(end 67.099434 -126.615698)
		(width 0.14224)
		(layer "In4.Cu")
		(net "M_L_DQ<26>")
	)
	(segment
		(start 67.592702 -129.833878)
		(end 67.592702 -127.108966)
		(width 0.14224)
		(layer "In4.Cu")
		(net "M_L_DQ<26>")
	)
	(segment
		(start 67.668902 -134.492238)
		(end 67.668902 -134.193534)
		(width 0.14224)
		(layer "In4.Cu")
		(net "M_L_DQ<26>")
	)
	(segment
		(start 67.618102 -138.968734)
		(end 67.536568 -138.8872)
		(width 0.14224)
		(layer "In4.Cu")
		(net "M_L_DQ<26>")
	)
	(segment
		(start 67.663568 -131.882134)
		(end 67.663568 -131.530344)
		(width 0.14224)
		(layer "In4.Cu")
		(net "M_L_DQ<26>")
	)
	(segment
		(start 66.666364 -144.233646)
		(end 66.666364 -141.646148)
		(width 0.14224)
		(layer "In4.Cu")
		(net "M_L_DQ<26>")
	)
	(segment
		(start 66.754502 -140.235178)
		(end 67.618102 -139.371578)
		(width 0.14224)
		(layer "In4.Cu")
		(net "M_L_DQ<26>")
	)
	(segment
		(start 67.099434 -141.213078)
		(end 66.754502 -140.868146)
		(width 0.14224)
		(layer "In4.Cu")
		(net "M_L_DQ<26>")
	)
	(segment
		(start 66.666364 -141.646148)
		(end 67.099434 -141.213078)
		(width 0.14224)
		(layer "In4.Cu")
		(net "M_L_DQ<26>")
	)
	(segment
		(start 67.668902 -134.193534)
		(end 67.536568 -134.0612)
		(width 0.14224)
		(layer "In4.Cu")
		(net "M_L_DQ<26>")
	)
	(segment
		(start 67.536568 -136.631934)
		(end 67.618102 -136.5504)
		(width 0.14224)
		(layer "In4.Cu")
		(net "M_L_DQ<26>")
	)
	(segment
		(start 67.536568 -132.009134)
		(end 67.663568 -131.882134)
		(width 0.14224)
		(layer "In4.Cu")
		(net "M_L_DQ<26>")
	)
	(segment
		(start 67.949318 -145.5166)
		(end 66.666364 -144.233646)
		(width 0.14224)
		(layer "In4.Cu")
		(net "M_L_DQ<26>")
	)
	(segment
		(start 67.389502 -135.976868)
		(end 67.389502 -134.771638)
		(width 0.14224)
		(layer "In4.Cu")
		(net "M_L_DQ<26>")
	)
	(segment
		(start 67.618102 -139.371578)
		(end 67.618102 -138.968734)
		(width 0.14224)
		(layer "In4.Cu")
		(net "M_L_DQ<26>")
	)
	(segment
		(start 67.618102 -136.205468)
		(end 67.389502 -135.976868)
		(width 0.14224)
		(layer "In4.Cu")
		(net "M_L_DQ<26>")
	)
	(segment
		(start 67.663568 -131.530344)
		(end 67.465702 -131.332478)
		(width 0.14224)
		(layer "In4.Cu")
		(net "M_L_DQ<26>")
	)
	(segment
		(start 61.676026 -121.505472)
		(end 61.841126 -121.340372)
		(width 0.1651)
		(layer "F.Cu")
		(net "M_L_DQ<25>")
	)
	(segment
		(start 62.329568 -125.759464)
		(end 62.329568 -124.914152)
		(width 0.1651)
		(layer "F.Cu")
		(net "M_L_DQ<25>")
	)
	(segment
		(start 61.834522 -122.318272)
		(end 61.682122 -122.165872)
		(width 0.1651)
		(layer "F.Cu")
		(net "M_L_DQ<25>")
	)
	(segment
		(start 61.796168 -112.054132)
		(end 61.796168 -111.127286)
		(width 0.1651)
		(layer "F.Cu")
		(net "M_L_DQ<25>")
	)
	(segment
		(start 61.796168 -115.632992)
		(end 61.796168 -113.057432)
		(width 0.1651)
		(layer "F.Cu")
		(net "M_L_DQ<25>")
	)
	(segment
		(start 74.225404 -103.136954)
		(end 76.830174 -103.136954)
		(width 0.1016)
		(layer "F.Cu")
		(net "M_L_DQ<25>")
	)
	(segment
		(start 61.26861 -122.000772)
		(end 61.26861 -121.670572)
		(width 0.1651)
		(layer "F.Cu")
		(net "M_L_DQ<25>")
	)
	(segment
		(start 61.796168 -116.252244)
		(end 61.614304 -116.07038)
		(width 0.1651)
		(layer "F.Cu")
		(net "M_L_DQ<25>")
	)
	(segment
		(start 61.268864 -119.028972)
		(end 61.433964 -118.863872)
		(width 0.1651)
		(layer "F.Cu")
		(net "M_L_DQ<25>")
	)
	(segment
		(start 61.614304 -116.07038)
		(end 61.614304 -115.814856)
		(width 0.1651)
		(layer "F.Cu")
		(net "M_L_DQ<25>")
	)
	(segment
		(start 61.831728 -123.621292)
		(end 61.704728 -123.494292)
		(width 0.1651)
		(layer "F.Cu")
		(net "M_L_DQ<25>")
	)
	(segment
		(start 77.996034 -102.124256)
		(end 76.983336 -103.136954)
		(width 0.1016)
		(layer "F.Cu")
		(net "M_L_DQ<25>")
	)
	(segment
		(start 61.462412 -124.787152)
		(end 61.310012 -124.634752)
		(width 0.1651)
		(layer "F.Cu")
		(net "M_L_DQ<25>")
	)
	(segment
		(start 61.268864 -119.359172)
		(end 61.268864 -119.028972)
		(width 0.1651)
		(layer "F.Cu")
		(net "M_L_DQ<25>")
	)
	(segment
		(start 61.268356 -112.384332)
		(end 61.433456 -112.219232)
		(width 0.1651)
		(layer "F.Cu")
		(net "M_L_DQ<25>")
	)
	(segment
		(start 61.43371 -121.505472)
		(end 61.676026 -121.505472)
		(width 0.1651)
		(layer "F.Cu")
		(net "M_L_DQ<25>")
	)
	(segment
		(start 61.268356 -112.727232)
		(end 61.268356 -112.384332)
		(width 0.1651)
		(layer "F.Cu")
		(net "M_L_DQ<25>")
	)
	(segment
		(start 73.222612 -104.139746)
		(end 74.225404 -103.136954)
		(width 0.1016)
		(layer "F.Cu")
		(net "M_L_DQ<25>")
	)
	(segment
		(start 61.682122 -122.165872)
		(end 61.43371 -122.165872)
		(width 0.1651)
		(layer "F.Cu")
		(net "M_L_DQ<25>")
	)
	(segment
		(start 61.149484 -142.6718)
		(end 61.149484 -143.941546)
		(width 0.1651)
		(layer "F.Cu")
		(net "M_L_DQ<25>")
	)
	(segment
		(start 61.614304 -115.814856)
		(end 61.796168 -115.632992)
		(width 0.1651)
		(layer "F.Cu")
		(net "M_L_DQ<25>")
	)
	(segment
		(start 61.796168 -113.057432)
		(end 61.631068 -112.892332)
		(width 0.1651)
		(layer "F.Cu")
		(net "M_L_DQ<25>")
	)
	(segment
		(start 61.841126 -121.340372)
		(end 61.841126 -121.010172)
		(width 0.1651)
		(layer "F.Cu")
		(net "M_L_DQ<25>")
	)
	(segment
		(start 61.268864 -120.679972)
		(end 61.268864 -120.349772)
		(width 0.1651)
		(layer "F.Cu")
		(net "M_L_DQ<25>")
	)
	(segment
		(start 61.440568 -123.494292)
		(end 61.288168 -123.341892)
		(width 0.1651)
		(layer "F.Cu")
		(net "M_L_DQ<25>")
	)
	(segment
		(start 61.288168 -123.341892)
		(end 61.288168 -122.971814)
		(width 0.1651)
		(layer "F.Cu")
		(net "M_L_DQ<25>")
	)
	(segment
		(start 61.43371 -122.165872)
		(end 61.26861 -122.000772)
		(width 0.1651)
		(layer "F.Cu")
		(net "M_L_DQ<25>")
	)
	(segment
		(start 61.821568 -125.906276)
		(end 62.182756 -125.906276)
		(width 0.1651)
		(layer "F.Cu")
		(net "M_L_DQ<25>")
	)
	(segment
		(start 68.783708 -104.139746)
		(end 71.43369 -104.139746)
		(width 0.1651)
		(layer "F.Cu")
		(net "M_L_DQ<25>")
	)
	(segment
		(start 61.437012 -124.139452)
		(end 61.669168 -124.139452)
		(width 0.1651)
		(layer "F.Cu")
		(net "M_L_DQ<25>")
	)
	(segment
		(start 61.433456 -112.219232)
		(end 61.631068 -112.219232)
		(width 0.1651)
		(layer "F.Cu")
		(net "M_L_DQ<25>")
	)
	(segment
		(start 61.631068 -118.863872)
		(end 61.796168 -118.698772)
		(width 0.1651)
		(layer "F.Cu")
		(net "M_L_DQ<25>")
	)
	(segment
		(start 61.831728 -123.976892)
		(end 61.831728 -123.621292)
		(width 0.1651)
		(layer "F.Cu")
		(net "M_L_DQ<25>")
	)
	(segment
		(start 61.288168 -122.971814)
		(end 61.43371 -122.826272)
		(width 0.1651)
		(layer "F.Cu")
		(net "M_L_DQ<25>")
	)
	(segment
		(start 61.433964 -119.524272)
		(end 61.268864 -119.359172)
		(width 0.1651)
		(layer "F.Cu")
		(net "M_L_DQ<25>")
	)
	(segment
		(start 61.433964 -120.184672)
		(end 61.675772 -120.184672)
		(width 0.1651)
		(layer "F.Cu")
		(net "M_L_DQ<25>")
	)
	(segment
		(start 62.202568 -124.787152)
		(end 61.462412 -124.787152)
		(width 0.1651)
		(layer "F.Cu")
		(net "M_L_DQ<25>")
	)
	(segment
		(start 78.051406 -102.068884)
		(end 77.996034 -102.124256)
		(width 0.0889)
		(layer "F.Cu")
		(net "M_L_DQ<25>")
	)
	(segment
		(start 61.704728 -123.494292)
		(end 61.440568 -123.494292)
		(width 0.1651)
		(layer "F.Cu")
		(net "M_L_DQ<25>")
	)
	(segment
		(start 61.433964 -118.863872)
		(end 61.631068 -118.863872)
		(width 0.1651)
		(layer "F.Cu")
		(net "M_L_DQ<25>")
	)
	(segment
		(start 61.675772 -120.184672)
		(end 61.840872 -120.019572)
		(width 0.1651)
		(layer "F.Cu")
		(net "M_L_DQ<25>")
	)
	(segment
		(start 61.841126 -121.010172)
		(end 61.676026 -120.845072)
		(width 0.1651)
		(layer "F.Cu")
		(net "M_L_DQ<25>")
	)
	(segment
		(start 61.310012 -124.634752)
		(end 61.310012 -124.266452)
		(width 0.1651)
		(layer "F.Cu")
		(net "M_L_DQ<25>")
	)
	(segment
		(start 61.268864 -120.349772)
		(end 61.433964 -120.184672)
		(width 0.1651)
		(layer "F.Cu")
		(net "M_L_DQ<25>")
	)
	(segment
		(start 61.669168 -124.139452)
		(end 61.831728 -123.976892)
		(width 0.1651)
		(layer "F.Cu")
		(net "M_L_DQ<25>")
	)
	(segment
		(start 61.796168 -111.127286)
		(end 68.783708 -104.139746)
		(width 0.1651)
		(layer "F.Cu")
		(net "M_L_DQ<25>")
	)
	(segment
		(start 62.182756 -125.906276)
		(end 62.329568 -125.759464)
		(width 0.1651)
		(layer "F.Cu")
		(net "M_L_DQ<25>")
	)
	(segment
		(start 76.983336 -103.136954)
		(end 76.830174 -103.136954)
		(width 0.1016)
		(layer "F.Cu")
		(net "M_L_DQ<25>")
	)
	(segment
		(start 71.43369 -104.139746)
		(end 73.222612 -104.139746)
		(width 0.1016)
		(layer "F.Cu")
		(net "M_L_DQ<25>")
	)
	(segment
		(start 61.796168 -118.698772)
		(end 61.796168 -116.252244)
		(width 0.1651)
		(layer "F.Cu")
		(net "M_L_DQ<25>")
	)
	(segment
		(start 61.834522 -122.648472)
		(end 61.834522 -122.318272)
		(width 0.1651)
		(layer "F.Cu")
		(net "M_L_DQ<25>")
	)
	(segment
		(start 62.329568 -124.914152)
		(end 62.202568 -124.787152)
		(width 0.1651)
		(layer "F.Cu")
		(net "M_L_DQ<25>")
	)
	(segment
		(start 61.43371 -122.826272)
		(end 61.656722 -122.826272)
		(width 0.1651)
		(layer "F.Cu")
		(net "M_L_DQ<25>")
	)
	(segment
		(start 61.631068 -112.892332)
		(end 61.433456 -112.892332)
		(width 0.1651)
		(layer "F.Cu")
		(net "M_L_DQ<25>")
	)
	(segment
		(start 61.26861 -121.670572)
		(end 61.43371 -121.505472)
		(width 0.1651)
		(layer "F.Cu")
		(net "M_L_DQ<25>")
	)
	(segment
		(start 61.433456 -112.892332)
		(end 61.268356 -112.727232)
		(width 0.1651)
		(layer "F.Cu")
		(net "M_L_DQ<25>")
	)
	(segment
		(start 61.676026 -120.845072)
		(end 61.433964 -120.845072)
		(width 0.1651)
		(layer "F.Cu")
		(net "M_L_DQ<25>")
	)
	(segment
		(start 61.840872 -119.689372)
		(end 61.675772 -119.524272)
		(width 0.1651)
		(layer "F.Cu")
		(net "M_L_DQ<25>")
	)
	(segment
		(start 61.840872 -120.019572)
		(end 61.840872 -119.689372)
		(width 0.1651)
		(layer "F.Cu")
		(net "M_L_DQ<25>")
	)
	(segment
		(start 61.310012 -124.266452)
		(end 61.437012 -124.139452)
		(width 0.1651)
		(layer "F.Cu")
		(net "M_L_DQ<25>")
	)
	(segment
		(start 61.656722 -122.826272)
		(end 61.834522 -122.648472)
		(width 0.1651)
		(layer "F.Cu")
		(net "M_L_DQ<25>")
	)
	(segment
		(start 61.433964 -120.845072)
		(end 61.268864 -120.679972)
		(width 0.1651)
		(layer "F.Cu")
		(net "M_L_DQ<25>")
	)
	(segment
		(start 61.675772 -119.524272)
		(end 61.433964 -119.524272)
		(width 0.1651)
		(layer "F.Cu")
		(net "M_L_DQ<25>")
	)
	(segment
		(start 61.631068 -112.219232)
		(end 61.796168 -112.054132)
		(width 0.1651)
		(layer "F.Cu")
		(net "M_L_DQ<25>")
	)
	(segment
		(start 78.051406 -101.15804)
		(end 78.051406 -102.068884)
		(width 0.0889)
		(layer "F.Cu")
		(net "M_L_DQ<25>")
	)
	(via
		(at 61.821568 -125.906276)
		(size 0.508)
		(drill 0.254)
		(layers "F.Cu" "B.Cu")
		(net "M_L_DQ<25>")
	)
	(via
		(at 61.821568 -139.932156)
		(size 0.508)
		(drill 0.254)
		(layers "F.Cu" "B.Cu")
		(net "M_L_DQ<25>")
	)
	(via
		(at 61.149484 -143.941546)
		(size 0.508)
		(drill 0.254)
		(layers "F.Cu" "B.Cu")
		(net "M_L_DQ<25>")
	)
	(segment
		(start 61.999368 -137.877296)
		(end 61.999368 -139.251182)
		(width 0.1651)
		(layer "B.Cu")
		(net "M_L_DQ<25>")
	)
	(segment
		(start 61.821568 -139.428982)
		(end 61.821568 -139.932156)
		(width 0.1651)
		(layer "B.Cu")
		(net "M_L_DQ<25>")
	)
	(segment
		(start 61.999368 -139.251182)
		(end 61.821568 -139.428982)
		(width 0.1651)
		(layer "B.Cu")
		(net "M_L_DQ<25>")
	)
	(segment
		(start 62.309502 -128.523746)
		(end 61.821568 -128.035812)
		(width 0.14224)
		(layer "In4.Cu")
		(net "M_L_DQ<25>")
	)
	(segment
		(start 61.310774 -142.936976)
		(end 61.52515 -142.7226)
		(width 0.14224)
		(layer "In4.Cu")
		(net "M_L_DQ<25>")
	)
	(segment
		(start 61.55055 -143.4846)
		(end 61.310774 -143.244824)
		(width 0.14224)
		(layer "In4.Cu")
		(net "M_L_DQ<25>")
	)
	(segment
		(start 61.310774 -143.244824)
		(end 61.310774 -142.936976)
		(width 0.14224)
		(layer "In4.Cu")
		(net "M_L_DQ<25>")
	)
	(segment
		(start 61.60135 -141.425168)
		(end 61.60135 -141.020546)
		(width 0.14224)
		(layer "In4.Cu")
		(net "M_L_DQ<25>")
	)
	(segment
		(start 62.431168 -136.697466)
		(end 62.309502 -136.5758)
		(width 0.14224)
		(layer "In4.Cu")
		(net "M_L_DQ<25>")
	)
	(segment
		(start 61.370972 -140.3604)
		(end 61.799216 -139.932156)
		(width 0.14224)
		(layer "In4.Cu")
		(net "M_L_DQ<25>")
	)
	(segment
		(start 61.821568 -139.843256)
		(end 62.309502 -139.355322)
		(width 0.14224)
		(layer "In4.Cu")
		(net "M_L_DQ<25>")
	)
	(segment
		(start 62.309502 -134.563866)
		(end 62.431168 -134.4422)
		(width 0.14224)
		(layer "In4.Cu")
		(net "M_L_DQ<25>")
	)
	(segment
		(start 61.799216 -139.932156)
		(end 61.821568 -139.932156)
		(width 0.14224)
		(layer "In4.Cu")
		(net "M_L_DQ<25>")
	)
	(segment
		(start 61.310774 -142.076424)
		(end 61.310774 -141.715744)
		(width 0.14224)
		(layer "In4.Cu")
		(net "M_L_DQ<25>")
	)
	(segment
		(start 62.309502 -136.5758)
		(end 62.309502 -134.563866)
		(width 0.14224)
		(layer "In4.Cu")
		(net "M_L_DQ<25>")
	)
	(segment
		(start 62.431168 -138.811)
		(end 62.431168 -136.697466)
		(width 0.14224)
		(layer "In4.Cu")
		(net "M_L_DQ<25>")
	)
	(segment
		(start 61.398404 -143.941546)
		(end 61.55055 -143.7894)
		(width 0.14224)
		(layer "In4.Cu")
		(net "M_L_DQ<25>")
	)
	(segment
		(start 61.52515 -142.2908)
		(end 61.310774 -142.076424)
		(width 0.14224)
		(layer "In4.Cu")
		(net "M_L_DQ<25>")
	)
	(segment
		(start 61.821568 -139.932156)
		(end 61.821568 -139.843256)
		(width 0.14224)
		(layer "In4.Cu")
		(net "M_L_DQ<25>")
	)
	(segment
		(start 61.149484 -143.941546)
		(end 61.398404 -143.941546)
		(width 0.14224)
		(layer "In4.Cu")
		(net "M_L_DQ<25>")
	)
	(segment
		(start 62.309502 -139.355322)
		(end 62.309502 -138.932666)
		(width 0.14224)
		(layer "In4.Cu")
		(net "M_L_DQ<25>")
	)
	(segment
		(start 61.55055 -143.7894)
		(end 61.55055 -143.4846)
		(width 0.14224)
		(layer "In4.Cu")
		(net "M_L_DQ<25>")
	)
	(segment
		(start 62.431168 -131.978146)
		(end 62.309502 -131.85648)
		(width 0.14224)
		(layer "In4.Cu")
		(net "M_L_DQ<25>")
	)
	(segment
		(start 61.370972 -140.790168)
		(end 61.370972 -140.3604)
		(width 0.14224)
		(layer "In4.Cu")
		(net "M_L_DQ<25>")
	)
	(segment
		(start 62.431168 -134.4422)
		(end 62.431168 -131.978146)
		(width 0.14224)
		(layer "In4.Cu")
		(net "M_L_DQ<25>")
	)
	(segment
		(start 62.309502 -138.932666)
		(end 62.431168 -138.811)
		(width 0.14224)
		(layer "In4.Cu")
		(net "M_L_DQ<25>")
	)
	(segment
		(start 61.60135 -141.020546)
		(end 61.370972 -140.790168)
		(width 0.14224)
		(layer "In4.Cu")
		(net "M_L_DQ<25>")
	)
	(segment
		(start 61.52515 -142.7226)
		(end 61.52515 -142.2908)
		(width 0.14224)
		(layer "In4.Cu")
		(net "M_L_DQ<25>")
	)
	(segment
		(start 61.821568 -128.035812)
		(end 61.821568 -125.906276)
		(width 0.14224)
		(layer "In4.Cu")
		(net "M_L_DQ<25>")
	)
	(segment
		(start 61.310774 -141.715744)
		(end 61.60135 -141.425168)
		(width 0.14224)
		(layer "In4.Cu")
		(net "M_L_DQ<25>")
	)
	(segment
		(start 62.309502 -131.85648)
		(end 62.309502 -128.523746)
		(width 0.14224)
		(layer "In4.Cu")
		(net "M_L_DQ<25>")
	)
	(segment
		(start 60.792868 -117.590062)
		(end 60.977272 -117.590062)
		(width 0.1651)
		(layer "F.Cu")
		(net "M_L_DQ<24>")
	)
	(segment
		(start 60.792868 -118.250462)
		(end 60.627768 -118.415562)
		(width 0.1651)
		(layer "F.Cu")
		(net "M_L_DQ<24>")
	)
	(segment
		(start 60.627768 -112.186466)
		(end 60.627768 -113.462562)
		(width 0.1651)
		(layer "F.Cu")
		(net "M_L_DQ<24>")
	)
	(segment
		(start 61.084968 -114.122962)
		(end 60.919868 -114.288062)
		(width 0.1651)
		(layer "F.Cu")
		(net "M_L_DQ<24>")
	)
	(segment
		(start 77.632814 -101.102414)
		(end 77.632814 -102.056184)
		(width 0.0889)
		(layer "F.Cu")
		(net "M_L_DQ<24>")
	)
	(segment
		(start 60.627768 -113.462562)
		(end 60.792868 -113.627662)
		(width 0.1651)
		(layer "F.Cu")
		(net "M_L_DQ<24>")
	)
	(segment
		(start 68.526152 -103.492046)
		(end 61.190886 -110.827312)
		(width 0.1651)
		(layer "F.Cu")
		(net "M_L_DQ<24>")
	)
	(segment
		(start 60.792868 -116.929662)
		(end 60.627768 -117.094762)
		(width 0.1651)
		(layer "F.Cu")
		(net "M_L_DQ<24>")
	)
	(segment
		(start 60.627768 -115.773962)
		(end 60.627768 -116.104162)
		(width 0.1651)
		(layer "F.Cu")
		(net "M_L_DQ<24>")
	)
	(segment
		(start 77.589888 -102.09911)
		(end 76.856844 -102.832154)
		(width 0.1016)
		(layer "F.Cu")
		(net "M_L_DQ<24>")
	)
	(segment
		(start 61.084968 -116.434362)
		(end 61.084968 -116.764562)
		(width 0.1651)
		(layer "F.Cu")
		(net "M_L_DQ<24>")
	)
	(segment
		(start 61.084968 -113.792762)
		(end 61.084968 -114.122962)
		(width 0.1651)
		(layer "F.Cu")
		(net "M_L_DQ<24>")
	)
	(segment
		(start 77.192886 -100.662486)
		(end 77.632814 -101.102414)
		(width 0.0889)
		(layer "F.Cu")
		(net "M_L_DQ<24>")
	)
	(segment
		(start 60.919868 -116.929662)
		(end 60.792868 -116.929662)
		(width 0.1651)
		(layer "F.Cu")
		(net "M_L_DQ<24>")
	)
	(segment
		(start 60.792868 -113.627662)
		(end 60.919868 -113.627662)
		(width 0.1651)
		(layer "F.Cu")
		(net "M_L_DQ<24>")
	)
	(segment
		(start 77.632814 -102.056184)
		(end 77.589888 -102.09911)
		(width 0.0889)
		(layer "F.Cu")
		(net "M_L_DQ<24>")
	)
	(segment
		(start 60.99048 -118.250462)
		(end 60.792868 -118.250462)
		(width 0.1651)
		(layer "F.Cu")
		(net "M_L_DQ<24>")
	)
	(segment
		(start 60.977272 -117.590062)
		(end 61.148976 -117.761766)
		(width 0.1651)
		(layer "F.Cu")
		(net "M_L_DQ<24>")
	)
	(segment
		(start 60.792868 -114.288062)
		(end 60.627768 -114.453162)
		(width 0.1651)
		(layer "F.Cu")
		(net "M_L_DQ<24>")
	)
	(segment
		(start 60.792868 -116.269262)
		(end 60.919868 -116.269262)
		(width 0.1651)
		(layer "F.Cu")
		(net "M_L_DQ<24>")
	)
	(segment
		(start 61.084968 -115.443762)
		(end 60.919868 -115.608862)
		(width 0.1651)
		(layer "F.Cu")
		(net "M_L_DQ<24>")
	)
	(segment
		(start 61.999368 -147.27174)
		(end 61.999368 -147.277582)
		(width 0.1651)
		(layer "F.Cu")
		(net "M_L_DQ<24>")
	)
	(segment
		(start 61.084968 -116.764562)
		(end 60.919868 -116.929662)
		(width 0.1651)
		(layer "F.Cu")
		(net "M_L_DQ<24>")
	)
	(segment
		(start 76.856844 -102.832154)
		(end 74.098912 -102.832154)
		(width 0.1016)
		(layer "F.Cu")
		(net "M_L_DQ<24>")
	)
	(segment
		(start 60.627768 -117.424962)
		(end 60.792868 -117.590062)
		(width 0.1651)
		(layer "F.Cu")
		(net "M_L_DQ<24>")
	)
	(segment
		(start 60.919868 -116.269262)
		(end 61.084968 -116.434362)
		(width 0.1651)
		(layer "F.Cu")
		(net "M_L_DQ<24>")
	)
	(segment
		(start 60.627768 -117.094762)
		(end 60.627768 -117.424962)
		(width 0.1651)
		(layer "F.Cu")
		(net "M_L_DQ<24>")
	)
	(segment
		(start 60.919868 -113.627662)
		(end 61.084968 -113.792762)
		(width 0.1651)
		(layer "F.Cu")
		(net "M_L_DQ<24>")
	)
	(segment
		(start 60.919868 -115.608862)
		(end 60.792868 -115.608862)
		(width 0.1651)
		(layer "F.Cu")
		(net "M_L_DQ<24>")
	)
	(segment
		(start 74.098912 -102.832154)
		(end 73.09612 -103.834946)
		(width 0.1016)
		(layer "F.Cu")
		(net "M_L_DQ<24>")
	)
	(segment
		(start 71.70166 -103.492046)
		(end 71.43369 -103.492046)
		(width 0.1016)
		(layer "F.Cu")
		(net "M_L_DQ<24>")
	)
	(segment
		(start 61.148976 -117.761766)
		(end 61.148976 -118.091966)
		(width 0.1651)
		(layer "F.Cu")
		(net "M_L_DQ<24>")
	)
	(segment
		(start 60.919868 -114.288062)
		(end 60.792868 -114.288062)
		(width 0.1651)
		(layer "F.Cu")
		(net "M_L_DQ<24>")
	)
	(segment
		(start 61.999368 -147.277582)
		(end 61.821568 -145.415)
		(width 0.1651)
		(layer "F.Cu")
		(net "M_L_DQ<24>")
	)
	(segment
		(start 73.09612 -103.834946)
		(end 72.04456 -103.834946)
		(width 0.1016)
		(layer "F.Cu")
		(net "M_L_DQ<24>")
	)
	(segment
		(start 61.084968 -115.113562)
		(end 61.084968 -115.443762)
		(width 0.1651)
		(layer "F.Cu")
		(net "M_L_DQ<24>")
	)
	(segment
		(start 60.627768 -125.73)
		(end 60.856368 -125.9586)
		(width 0.1651)
		(layer "F.Cu")
		(net "M_L_DQ<24>")
	)
	(segment
		(start 60.627768 -118.415562)
		(end 60.627768 -125.73)
		(width 0.1651)
		(layer "F.Cu")
		(net "M_L_DQ<24>")
	)
	(segment
		(start 61.148976 -118.091966)
		(end 60.99048 -118.250462)
		(width 0.1651)
		(layer "F.Cu")
		(net "M_L_DQ<24>")
	)
	(segment
		(start 60.792868 -114.948462)
		(end 60.919868 -114.948462)
		(width 0.1651)
		(layer "F.Cu")
		(net "M_L_DQ<24>")
	)
	(segment
		(start 60.627768 -116.104162)
		(end 60.792868 -116.269262)
		(width 0.1651)
		(layer "F.Cu")
		(net "M_L_DQ<24>")
	)
	(segment
		(start 60.792868 -115.608862)
		(end 60.627768 -115.773962)
		(width 0.1651)
		(layer "F.Cu")
		(net "M_L_DQ<24>")
	)
	(segment
		(start 72.04456 -103.834946)
		(end 71.70166 -103.492046)
		(width 0.1016)
		(layer "F.Cu")
		(net "M_L_DQ<24>")
	)
	(segment
		(start 71.43369 -103.492046)
		(end 68.526152 -103.492046)
		(width 0.1651)
		(layer "F.Cu")
		(net "M_L_DQ<24>")
	)
	(segment
		(start 60.627768 -114.453162)
		(end 60.627768 -114.783362)
		(width 0.1651)
		(layer "F.Cu")
		(net "M_L_DQ<24>")
	)
	(segment
		(start 60.627768 -114.783362)
		(end 60.792868 -114.948462)
		(width 0.1651)
		(layer "F.Cu")
		(net "M_L_DQ<24>")
	)
	(segment
		(start 60.919868 -114.948462)
		(end 61.084968 -115.113562)
		(width 0.1651)
		(layer "F.Cu")
		(net "M_L_DQ<24>")
	)
	(segment
		(start 61.190886 -110.827312)
		(end 60.627768 -112.186466)
		(width 0.1651)
		(layer "F.Cu")
		(net "M_L_DQ<24>")
	)
	(via
		(at 61.821568 -145.415)
		(size 0.508)
		(drill 0.254)
		(layers "F.Cu" "B.Cu")
		(net "M_L_DQ<24>")
	)
	(via
		(at 61.149484 -141.213078)
		(size 0.508)
		(drill 0.254)
		(layers "F.Cu" "B.Cu")
		(net "M_L_DQ<24>")
	)
	(via
		(at 60.856368 -125.9586)
		(size 0.508)
		(drill 0.254)
		(layers "F.Cu" "B.Cu")
		(net "M_L_DQ<24>")
	)
	(segment
		(start 61.149484 -142.477236)
		(end 61.149484 -141.213078)
		(width 0.1651)
		(layer "B.Cu")
		(net "M_L_DQ<24>")
	)
	(segment
		(start 61.636402 -138.956034)
		(end 61.567568 -138.8872)
		(width 0.14224)
		(layer "In4.Cu")
		(net "M_L_DQ<24>")
	)
	(segment
		(start 61.821568 -145.415)
		(end 61.525404 -145.415)
		(width 0.14224)
		(layer "In4.Cu")
		(net "M_L_DQ<24>")
	)
	(segment
		(start 61.288168 -126.3904)
		(end 60.856368 -125.9586)
		(width 0.14224)
		(layer "In4.Cu")
		(net "M_L_DQ<24>")
	)
	(segment
		(start 60.716414 -141.646148)
		(end 61.149484 -141.213078)
		(width 0.14224)
		(layer "In4.Cu")
		(net "M_L_DQ<24>")
	)
	(segment
		(start 61.567568 -134.0866)
		(end 61.567568 -131.907534)
		(width 0.14224)
		(layer "In4.Cu")
		(net "M_L_DQ<24>")
	)
	(segment
		(start 61.636402 -136.263634)
		(end 61.344302 -135.971534)
		(width 0.14224)
		(layer "In4.Cu")
		(net "M_L_DQ<24>")
	)
	(segment
		(start 60.785502 -140.849096)
		(end 60.785502 -140.209778)
		(width 0.14224)
		(layer "In4.Cu")
		(net "M_L_DQ<24>")
	)
	(segment
		(start 61.636402 -136.6012)
		(end 61.636402 -136.263634)
		(width 0.14224)
		(layer "In4.Cu")
		(net "M_L_DQ<24>")
	)
	(segment
		(start 60.716414 -144.60601)
		(end 60.716414 -141.646148)
		(width 0.14224)
		(layer "In4.Cu")
		(net "M_L_DQ<24>")
	)
	(segment
		(start 61.567568 -131.907534)
		(end 61.623702 -131.8514)
		(width 0.14224)
		(layer "In4.Cu")
		(net "M_L_DQ<24>")
	)
	(segment
		(start 61.623702 -134.142734)
		(end 61.567568 -134.0866)
		(width 0.14224)
		(layer "In4.Cu")
		(net "M_L_DQ<24>")
	)
	(segment
		(start 60.785502 -140.209778)
		(end 61.636402 -139.358878)
		(width 0.14224)
		(layer "In4.Cu")
		(net "M_L_DQ<24>")
	)
	(segment
		(start 61.344302 -134.764018)
		(end 61.623702 -134.484618)
		(width 0.14224)
		(layer "In4.Cu")
		(net "M_L_DQ<24>")
	)
	(segment
		(start 61.674502 -129.158492)
		(end 61.288168 -128.772158)
		(width 0.14224)
		(layer "In4.Cu")
		(net "M_L_DQ<24>")
	)
	(segment
		(start 61.623702 -134.484618)
		(end 61.623702 -134.142734)
		(width 0.14224)
		(layer "In4.Cu")
		(net "M_L_DQ<24>")
	)
	(segment
		(start 61.331602 -131.141978)
		(end 61.331602 -130.062478)
		(width 0.14224)
		(layer "In4.Cu")
		(net "M_L_DQ<24>")
	)
	(segment
		(start 61.567568 -138.8872)
		(end 61.567568 -136.670034)
		(width 0.14224)
		(layer "In4.Cu")
		(net "M_L_DQ<24>")
	)
	(segment
		(start 61.674502 -129.719578)
		(end 61.674502 -129.158492)
		(width 0.14224)
		(layer "In4.Cu")
		(net "M_L_DQ<24>")
	)
	(segment
		(start 61.623702 -131.8514)
		(end 61.623702 -131.434078)
		(width 0.14224)
		(layer "In4.Cu")
		(net "M_L_DQ<24>")
	)
	(segment
		(start 61.567568 -136.670034)
		(end 61.636402 -136.6012)
		(width 0.14224)
		(layer "In4.Cu")
		(net "M_L_DQ<24>")
	)
	(segment
		(start 61.525404 -145.415)
		(end 60.716414 -144.60601)
		(width 0.14224)
		(layer "In4.Cu")
		(net "M_L_DQ<24>")
	)
	(segment
		(start 61.288168 -128.772158)
		(end 61.288168 -126.3904)
		(width 0.14224)
		(layer "In4.Cu")
		(net "M_L_DQ<24>")
	)
	(segment
		(start 61.331602 -130.062478)
		(end 61.674502 -129.719578)
		(width 0.14224)
		(layer "In4.Cu")
		(net "M_L_DQ<24>")
	)
	(segment
		(start 61.344302 -135.971534)
		(end 61.344302 -134.764018)
		(width 0.14224)
		(layer "In4.Cu")
		(net "M_L_DQ<24>")
	)
	(segment
		(start 61.636402 -139.358878)
		(end 61.636402 -138.956034)
		(width 0.14224)
		(layer "In4.Cu")
		(net "M_L_DQ<24>")
	)
	(segment
		(start 61.149484 -141.213078)
		(end 60.785502 -140.849096)
		(width 0.14224)
		(layer "In4.Cu")
		(net "M_L_DQ<24>")
	)
	(segment
		(start 61.623702 -131.434078)
		(end 61.331602 -131.141978)
		(width 0.14224)
		(layer "In4.Cu")
		(net "M_L_DQ<24>")
	)
	(segment
		(start 74.617326 -100.167186)
		(end 74.045826 -100.167186)
		(width 0.1651)
		(layer "F.Cu")
		(net "M_L_DQ<23>")
	)
	(segment
		(start 56.049418 -142.6718)
		(end 56.049418 -143.941546)
		(width 0.1651)
		(layer "F.Cu")
		(net "M_L_DQ<23>")
	)
	(via
		(at 56.899302 -139.932156)
		(size 0.508)
		(drill 0.254)
		(layers "F.Cu" "B.Cu")
		(net "M_L_DQ<23>")
	)
	(via
		(at 74.045826 -100.167186)
		(size 0.508)
		(drill 0.254)
		(layers "F.Cu" "B.Cu")
		(net "M_L_DQ<23>")
	)
	(via
		(at 56.049418 -143.941546)
		(size 0.508)
		(drill 0.254)
		(layers "F.Cu" "B.Cu")
		(net "M_L_DQ<23>")
	)
	(segment
		(start 56.899556 -137.877296)
		(end 56.899302 -137.877296)
		(width 0.1651)
		(layer "B.Cu")
		(net "M_L_DQ<23>")
	)
	(segment
		(start 56.899302 -137.877296)
		(end 56.899302 -139.932156)
		(width 0.1651)
		(layer "B.Cu")
		(net "M_L_DQ<23>")
	)
	(segment
		(start 57.252108 -136.167114)
		(end 57.252108 -136.57834)
		(width 0.14224)
		(layer "In4.Cu")
		(net "M_L_DQ<23>")
	)
	(segment
		(start 56.499506 -143.763746)
		(end 56.321706 -143.941546)
		(width 0.14224)
		(layer "In4.Cu")
		(net "M_L_DQ<23>")
	)
	(segment
		(start 65.566798 -117.412008)
		(end 65.816734 -117.661944)
		(width 0.14224)
		(layer "In4.Cu")
		(net "M_L_DQ<23>")
	)
	(segment
		(start 64.027558 -118.513352)
		(end 64.246506 -118.513352)
		(width 0.14224)
		(layer "In4.Cu")
		(net "M_L_DQ<23>")
	)
	(segment
		(start 56.210708 -142.878048)
		(end 56.210708 -143.151352)
		(width 0.14224)
		(layer "In4.Cu")
		(net "M_L_DQ<23>")
	)
	(segment
		(start 56.467756 -142.621)
		(end 56.210708 -142.878048)
		(width 0.14224)
		(layer "In4.Cu")
		(net "M_L_DQ<23>")
	)
	(segment
		(start 74.546968 -101.471222)
		(end 74.498962 -101.557074)
		(width 0.0889)
		(layer "In4.Cu")
		(net "M_L_DQ<23>")
	)
	(segment
		(start 57.480708 -130.087878)
		(end 57.480708 -131.188206)
		(width 0.14224)
		(layer "In4.Cu")
		(net "M_L_DQ<23>")
	)
	(segment
		(start 56.493156 -140.834618)
		(end 56.493156 -141.5034)
		(width 0.14224)
		(layer "In4.Cu")
		(net "M_L_DQ<23>")
	)
	(segment
		(start 57.252108 -129.33426)
		(end 57.252108 -129.859278)
		(width 0.14224)
		(layer "In4.Cu")
		(net "M_L_DQ<23>")
	)
	(segment
		(start 56.493156 -141.5034)
		(end 56.210708 -141.785848)
		(width 0.14224)
		(layer "In4.Cu")
		(net "M_L_DQ<23>")
	)
	(segment
		(start 72.861424 -102.435914)
		(end 71.870062 -103.427276)
		(width 0.0889)
		(layer "In4.Cu")
		(net "M_L_DQ<23>")
	)
	(segment
		(start 56.210708 -141.785848)
		(end 56.210708 -142.059152)
		(width 0.14224)
		(layer "In4.Cu")
		(net "M_L_DQ<23>")
	)
	(segment
		(start 56.448706 -140.3604)
		(end 56.448706 -140.790168)
		(width 0.14224)
		(layer "In4.Cu")
		(net "M_L_DQ<23>")
	)
	(segment
		(start 71.870062 -105.487216)
		(end 67.003168 -110.35411)
		(width 0.14224)
		(layer "In4.Cu")
		(net "M_L_DQ<23>")
	)
	(segment
		(start 56.499506 -143.44015)
		(end 56.499506 -143.763746)
		(width 0.14224)
		(layer "In4.Cu")
		(net "M_L_DQ<23>")
	)
	(segment
		(start 57.325768 -138.8364)
		(end 57.252108 -138.91006)
		(width 0.14224)
		(layer "In4.Cu")
		(net "M_L_DQ<23>")
	)
	(segment
		(start 60.91682 -122.780806)
		(end 59.53252 -122.780806)
		(width 0.14224)
		(layer "In4.Cu")
		(net "M_L_DQ<23>")
	)
	(segment
		(start 57.325768 -136.652)
		(end 57.325768 -138.8364)
		(width 0.14224)
		(layer "In4.Cu")
		(net "M_L_DQ<23>")
	)
	(segment
		(start 56.467756 -142.3162)
		(end 56.467756 -142.621)
		(width 0.14224)
		(layer "In4.Cu")
		(net "M_L_DQ<23>")
	)
	(segment
		(start 56.321706 -143.941546)
		(end 56.049418 -143.941546)
		(width 0.14224)
		(layer "In4.Cu")
		(net "M_L_DQ<23>")
	)
	(segment
		(start 57.681368 -128.905)
		(end 57.252108 -129.33426)
		(width 0.14224)
		(layer "In4.Cu")
		(net "M_L_DQ<23>")
	)
	(segment
		(start 71.870062 -104.088184)
		(end 71.870062 -105.487216)
		(width 0.14224)
		(layer "In4.Cu")
		(net "M_L_DQ<23>")
	)
	(segment
		(start 67.003168 -114.818922)
		(end 63.777622 -118.044468)
		(width 0.14224)
		(layer "In4.Cu")
		(net "M_L_DQ<23>")
	)
	(segment
		(start 57.252108 -129.859278)
		(end 57.480708 -130.087878)
		(width 0.14224)
		(layer "In4.Cu")
		(net "M_L_DQ<23>")
	)
	(segment
		(start 57.201308 -131.953)
		(end 57.325768 -132.07746)
		(width 0.14224)
		(layer "In4.Cu")
		(net "M_L_DQ<23>")
	)
	(segment
		(start 56.87695 -139.932156)
		(end 56.448706 -140.3604)
		(width 0.14224)
		(layer "In4.Cu")
		(net "M_L_DQ<23>")
	)
	(segment
		(start 71.870062 -103.427276)
		(end 71.870062 -104.088184)
		(width 0.0889)
		(layer "In4.Cu")
		(net "M_L_DQ<23>")
	)
	(segment
		(start 63.777622 -118.263416)
		(end 64.027558 -118.513352)
		(width 0.14224)
		(layer "In4.Cu")
		(net "M_L_DQ<23>")
	)
	(segment
		(start 57.201308 -131.467606)
		(end 57.201308 -131.953)
		(width 0.14224)
		(layer "In4.Cu")
		(net "M_L_DQ<23>")
	)
	(segment
		(start 67.003168 -110.35411)
		(end 67.003168 -114.818922)
		(width 0.14224)
		(layer "In4.Cu")
		(net "M_L_DQ<23>")
	)
	(segment
		(start 73.620122 -102.435914)
		(end 72.861424 -102.435914)
		(width 0.0889)
		(layer "In4.Cu")
		(net "M_L_DQ<23>")
	)
	(segment
		(start 74.563986 -101.44252)
		(end 74.546968 -101.471222)
		(width 0.0889)
		(layer "In4.Cu")
		(net "M_L_DQ<23>")
	)
	(segment
		(start 57.421272 -135.99795)
		(end 57.252108 -136.167114)
		(width 0.14224)
		(layer "In4.Cu")
		(net "M_L_DQ<23>")
	)
	(segment
		(start 56.899302 -139.932156)
		(end 56.87695 -139.932156)
		(width 0.14224)
		(layer "In4.Cu")
		(net "M_L_DQ<23>")
	)
	(segment
		(start 56.210708 -142.059152)
		(end 56.467756 -142.3162)
		(width 0.14224)
		(layer "In4.Cu")
		(net "M_L_DQ<23>")
	)
	(segment
		(start 74.540872 -100.833428)
		(end 74.557636 -100.862638)
		(width 0.0889)
		(layer "In4.Cu")
		(net "M_L_DQ<23>")
	)
	(segment
		(start 63.777622 -118.044468)
		(end 63.777622 -118.263416)
		(width 0.14224)
		(layer "In4.Cu")
		(net "M_L_DQ<23>")
	)
	(segment
		(start 56.448706 -140.790168)
		(end 56.493156 -140.834618)
		(width 0.14224)
		(layer "In4.Cu")
		(net "M_L_DQ<23>")
	)
	(segment
		(start 65.816734 -117.880892)
		(end 60.91682 -122.780806)
		(width 0.14224)
		(layer "In4.Cu")
		(net "M_L_DQ<23>")
	)
	(segment
		(start 57.252108 -139.590272)
		(end 57.241186 -139.590272)
		(width 0.14224)
		(layer "In4.Cu")
		(net "M_L_DQ<23>")
	)
	(segment
		(start 57.277508 -134.568438)
		(end 57.421272 -134.712202)
		(width 0.14224)
		(layer "In4.Cu")
		(net "M_L_DQ<23>")
	)
	(segment
		(start 57.480708 -131.188206)
		(end 57.201308 -131.467606)
		(width 0.14224)
		(layer "In4.Cu")
		(net "M_L_DQ<23>")
	)
	(segment
		(start 64.246506 -118.513352)
		(end 65.34785 -117.412008)
		(width 0.14224)
		(layer "In4.Cu")
		(net "M_L_DQ<23>")
	)
	(segment
		(start 57.325768 -132.07746)
		(end 57.325768 -134.0866)
		(width 0.14224)
		(layer "In4.Cu")
		(net "M_L_DQ<23>")
	)
	(segment
		(start 57.241186 -139.590272)
		(end 56.899302 -139.932156)
		(width 0.14224)
		(layer "In4.Cu")
		(net "M_L_DQ<23>")
	)
	(segment
		(start 57.252108 -138.91006)
		(end 57.252108 -139.590272)
		(width 0.14224)
		(layer "In4.Cu")
		(net "M_L_DQ<23>")
	)
	(segment
		(start 65.816734 -117.661944)
		(end 65.816734 -117.880892)
		(width 0.14224)
		(layer "In4.Cu")
		(net "M_L_DQ<23>")
	)
	(segment
		(start 57.252108 -136.57834)
		(end 57.325768 -136.652)
		(width 0.14224)
		(layer "In4.Cu")
		(net "M_L_DQ<23>")
	)
	(segment
		(start 57.681368 -124.631958)
		(end 57.681368 -128.905)
		(width 0.14224)
		(layer "In4.Cu")
		(net "M_L_DQ<23>")
	)
	(segment
		(start 65.34785 -117.412008)
		(end 65.566798 -117.412008)
		(width 0.14224)
		(layer "In4.Cu")
		(net "M_L_DQ<23>")
	)
	(segment
		(start 56.210708 -143.151352)
		(end 56.499506 -143.44015)
		(width 0.14224)
		(layer "In4.Cu")
		(net "M_L_DQ<23>")
	)
	(segment
		(start 57.325768 -134.0866)
		(end 57.277508 -134.13486)
		(width 0.14224)
		(layer "In4.Cu")
		(net "M_L_DQ<23>")
	)
	(segment
		(start 57.277508 -134.13486)
		(end 57.277508 -134.568438)
		(width 0.14224)
		(layer "In4.Cu")
		(net "M_L_DQ<23>")
	)
	(segment
		(start 74.498962 -101.557074)
		(end 73.620122 -102.435914)
		(width 0.0889)
		(layer "In4.Cu")
		(net "M_L_DQ<23>")
	)
	(segment
		(start 57.421272 -134.712202)
		(end 57.421272 -135.99795)
		(width 0.14224)
		(layer "In4.Cu")
		(net "M_L_DQ<23>")
	)
	(segment
		(start 59.53252 -122.780806)
		(end 57.681368 -124.631958)
		(width 0.14224)
		(layer "In4.Cu")
		(net "M_L_DQ<23>")
	)
	(arc
		(start 74.365612 -100.589334)
		(mid 74.459443 -100.706928)
		(end 74.540872 -100.833428)
		(width 0.0889)
		(layer "In4.Cu")
		(net "M_L_DQ<23>")
	)
	(arc
		(start 74.045826 -100.167186)
		(mid 74.197702 -100.384333)
		(end 74.365612 -100.589334)
		(width 0.0889)
		(layer "In4.Cu")
		(net "M_L_DQ<23>")
	)
	(arc
		(start 74.557636 -100.862638)
		(mid 74.636858 -101.151756)
		(end 74.563986 -101.44252)
		(width 0.0889)
		(layer "In4.Cu")
		(net "M_L_DQ<23>")
	)
	(segment
		(start 56.899556 -147.27174)
		(end 56.899556 -146.304)
		(width 0.1651)
		(layer "F.Cu")
		(net "M_L_DQ<22>")
	)
	(segment
		(start 56.899556 -145.8214)
		(end 56.899556 -145.516854)
		(width 0.1651)
		(layer "F.Cu")
		(net "M_L_DQ<22>")
	)
	(segment
		(start 56.899556 -146.304)
		(end 57.031636 -146.17192)
		(width 0.1651)
		(layer "F.Cu")
		(net "M_L_DQ<22>")
	)
	(segment
		(start 74.617326 -98.18624)
		(end 74.045826 -98.18624)
		(width 0.1651)
		(layer "F.Cu")
		(net "M_L_DQ<22>")
	)
	(segment
		(start 57.031636 -145.95348)
		(end 56.899556 -145.8214)
		(width 0.1651)
		(layer "F.Cu")
		(net "M_L_DQ<22>")
	)
	(segment
		(start 57.031636 -146.17192)
		(end 57.031636 -145.95348)
		(width 0.1651)
		(layer "F.Cu")
		(net "M_L_DQ<22>")
	)
	(segment
		(start 56.899556 -145.516854)
		(end 56.899302 -145.5166)
		(width 0.1651)
		(layer "F.Cu")
		(net "M_L_DQ<22>")
	)
	(via
		(at 56.899302 -145.5166)
		(size 0.508)
		(drill 0.254)
		(layers "F.Cu" "B.Cu")
		(net "M_L_DQ<22>")
	)
	(via
		(at 56.049418 -141.214094)
		(size 0.508)
		(drill 0.254)
		(layers "F.Cu" "B.Cu")
		(net "M_L_DQ<22>")
	)
	(via
		(at 74.045826 -98.18624)
		(size 0.508)
		(drill 0.254)
		(layers "F.Cu" "B.Cu")
		(net "M_L_DQ<22>")
	)
	(segment
		(start 56.049418 -142.477236)
		(end 56.049418 -141.214094)
		(width 0.1651)
		(layer "B.Cu")
		(net "M_L_DQ<22>")
	)
	(segment
		(start 56.617108 -139.04214)
		(end 56.617108 -139.333478)
		(width 0.14224)
		(layer "In4.Cu")
		(net "M_L_DQ<22>")
	)
	(segment
		(start 66.368168 -110.077504)
		(end 66.368168 -114.68608)
		(width 0.14224)
		(layer "In4.Cu")
		(net "M_L_DQ<22>")
	)
	(segment
		(start 56.462168 -136.70534)
		(end 56.462168 -138.8872)
		(width 0.14224)
		(layer "In4.Cu")
		(net "M_L_DQ<22>")
	)
	(segment
		(start 55.880508 -141.044168)
		(end 56.049418 -141.213078)
		(width 0.14224)
		(layer "In4.Cu")
		(net "M_L_DQ<22>")
	)
	(segment
		(start 56.462168 -132.08254)
		(end 56.462168 -134.0612)
		(width 0.14224)
		(layer "In4.Cu")
		(net "M_L_DQ<22>")
	)
	(segment
		(start 57.046368 -128.752854)
		(end 56.617108 -129.182114)
		(width 0.14224)
		(layer "In4.Cu")
		(net "M_L_DQ<22>")
	)
	(segment
		(start 56.293766 -135.932926)
		(end 56.617108 -136.256268)
		(width 0.14224)
		(layer "In4.Cu")
		(net "M_L_DQ<22>")
	)
	(segment
		(start 71.68007 -103.620316)
		(end 71.617332 -103.683054)
		(width 0.0889)
		(layer "In4.Cu")
		(net "M_L_DQ<22>")
	)
	(segment
		(start 71.68007 -103.348536)
		(end 71.68007 -103.620316)
		(width 0.0889)
		(layer "In4.Cu")
		(net "M_L_DQ<22>")
	)
	(segment
		(start 74.045826 -98.18624)
		(end 73.71588 -98.947986)
		(width 0.0889)
		(layer "In4.Cu")
		(net "M_L_DQ<22>")
	)
	(segment
		(start 73.69429 -99.368102)
		(end 73.699116 -99.376738)
		(width 0.0889)
		(layer "In4.Cu")
		(net "M_L_DQ<22>")
	)
	(segment
		(start 63.257684 -117.796564)
		(end 63.257684 -119.538242)
		(width 0.14224)
		(layer "In4.Cu")
		(net "M_L_DQ<22>")
	)
	(segment
		(start 56.899302 -145.5166)
		(end 55.616348 -144.233646)
		(width 0.14224)
		(layer "In4.Cu")
		(net "M_L_DQ<22>")
	)
	(segment
		(start 56.617108 -129.182114)
		(end 56.617108 -129.859278)
		(width 0.14224)
		(layer "In4.Cu")
		(net "M_L_DQ<22>")
	)
	(segment
		(start 60.65012 -122.145806)
		(end 59.20232 -122.145806)
		(width 0.14224)
		(layer "In4.Cu")
		(net "M_L_DQ<22>")
	)
	(segment
		(start 56.566308 -131.9784)
		(end 56.462168 -132.08254)
		(width 0.14224)
		(layer "In4.Cu")
		(net "M_L_DQ<22>")
	)
	(segment
		(start 55.616348 -141.646148)
		(end 56.049418 -141.213078)
		(width 0.14224)
		(layer "In4.Cu")
		(net "M_L_DQ<22>")
	)
	(segment
		(start 56.566308 -134.16534)
		(end 56.566308 -134.517638)
		(width 0.14224)
		(layer "In4.Cu")
		(net "M_L_DQ<22>")
	)
	(segment
		(start 56.617108 -129.859278)
		(end 56.413908 -130.062478)
		(width 0.14224)
		(layer "In4.Cu")
		(net "M_L_DQ<22>")
	)
	(segment
		(start 71.373492 -103.683054)
		(end 71.168768 -103.887778)
		(width 0.14224)
		(layer "In4.Cu")
		(net "M_L_DQ<22>")
	)
	(segment
		(start 56.413908 -131.307078)
		(end 56.566308 -131.459478)
		(width 0.14224)
		(layer "In4.Cu")
		(net "M_L_DQ<22>")
	)
	(segment
		(start 73.705466 -99.95662)
		(end 73.699116 -99.967288)
		(width 0.0889)
		(layer "In4.Cu")
		(net "M_L_DQ<22>")
	)
	(segment
		(start 73.71588 -98.947986)
		(end 73.699116 -98.976688)
		(width 0.0889)
		(layer "In4.Cu")
		(net "M_L_DQ<22>")
	)
	(segment
		(start 56.566308 -134.517638)
		(end 56.293766 -134.79018)
		(width 0.14224)
		(layer "In4.Cu")
		(net "M_L_DQ<22>")
	)
	(segment
		(start 56.462168 -134.0612)
		(end 56.566308 -134.16534)
		(width 0.14224)
		(layer "In4.Cu")
		(net "M_L_DQ<22>")
	)
	(segment
		(start 63.257684 -119.538242)
		(end 60.65012 -122.145806)
		(width 0.14224)
		(layer "In4.Cu")
		(net "M_L_DQ<22>")
	)
	(segment
		(start 56.293766 -134.79018)
		(end 56.293766 -135.932926)
		(width 0.14224)
		(layer "In4.Cu")
		(net "M_L_DQ<22>")
	)
	(segment
		(start 56.566308 -131.459478)
		(end 56.566308 -131.9784)
		(width 0.14224)
		(layer "In4.Cu")
		(net "M_L_DQ<22>")
	)
	(segment
		(start 71.168768 -105.276904)
		(end 66.368168 -110.077504)
		(width 0.14224)
		(layer "In4.Cu")
		(net "M_L_DQ<22>")
	)
	(segment
		(start 73.541128 -102.245922)
		(end 72.782684 -102.245922)
		(width 0.0889)
		(layer "In4.Cu")
		(net "M_L_DQ<22>")
	)
	(segment
		(start 56.617108 -136.5504)
		(end 56.462168 -136.70534)
		(width 0.14224)
		(layer "In4.Cu")
		(net "M_L_DQ<22>")
	)
	(segment
		(start 56.617108 -136.256268)
		(end 56.617108 -136.5504)
		(width 0.14224)
		(layer "In4.Cu")
		(net "M_L_DQ<22>")
	)
	(segment
		(start 56.413908 -130.062478)
		(end 56.413908 -131.307078)
		(width 0.14224)
		(layer "In4.Cu")
		(net "M_L_DQ<22>")
	)
	(segment
		(start 71.617332 -103.683054)
		(end 71.373492 -103.683054)
		(width 0.0889)
		(layer "In4.Cu")
		(net "M_L_DQ<22>")
	)
	(segment
		(start 55.880508 -140.070078)
		(end 55.880508 -141.044168)
		(width 0.14224)
		(layer "In4.Cu")
		(net "M_L_DQ<22>")
	)
	(segment
		(start 55.616348 -144.233646)
		(end 55.616348 -141.646148)
		(width 0.14224)
		(layer "In4.Cu")
		(net "M_L_DQ<22>")
	)
	(segment
		(start 56.617108 -139.333478)
		(end 55.880508 -140.070078)
		(width 0.14224)
		(layer "In4.Cu")
		(net "M_L_DQ<22>")
	)
	(segment
		(start 71.168768 -103.887778)
		(end 71.168768 -105.276904)
		(width 0.14224)
		(layer "In4.Cu")
		(net "M_L_DQ<22>")
	)
	(segment
		(start 72.782684 -102.245922)
		(end 71.68007 -103.348536)
		(width 0.0889)
		(layer "In4.Cu")
		(net "M_L_DQ<22>")
	)
	(segment
		(start 56.049418 -141.213078)
		(end 56.049418 -141.214094)
		(width 0.14224)
		(layer "In4.Cu")
		(net "M_L_DQ<22>")
	)
	(segment
		(start 57.046368 -124.301758)
		(end 57.046368 -128.752854)
		(width 0.14224)
		(layer "In4.Cu")
		(net "M_L_DQ<22>")
	)
	(segment
		(start 56.462168 -138.8872)
		(end 56.617108 -139.04214)
		(width 0.14224)
		(layer "In4.Cu")
		(net "M_L_DQ<22>")
	)
	(segment
		(start 74.397362 -101.349302)
		(end 74.346054 -101.440996)
		(width 0.0889)
		(layer "In4.Cu")
		(net "M_L_DQ<22>")
	)
	(segment
		(start 74.346054 -101.440996)
		(end 73.541128 -102.245922)
		(width 0.0889)
		(layer "In4.Cu")
		(net "M_L_DQ<22>")
	)
	(segment
		(start 59.20232 -122.145806)
		(end 57.046368 -124.301758)
		(width 0.14224)
		(layer "In4.Cu")
		(net "M_L_DQ<22>")
	)
	(segment
		(start 66.368168 -114.68608)
		(end 63.257684 -117.796564)
		(width 0.14224)
		(layer "In4.Cu")
		(net "M_L_DQ<22>")
	)
	(arc
		(start 73.699116 -99.967288)
		(mid 73.668105 -100.299452)
		(end 73.899522 -100.539804)
		(width 0.0889)
		(layer "In4.Cu")
		(net "M_L_DQ<22>")
	)
	(arc
		(start 73.699116 -98.976688)
		(mid 73.645646 -99.171751)
		(end 73.69429 -99.368102)
		(width 0.0889)
		(layer "In4.Cu")
		(net "M_L_DQ<22>")
	)
	(arc
		(start 73.899522 -100.539804)
		(mid 74.180734 -100.707917)
		(end 74.392536 -100.957888)
		(width 0.0889)
		(layer "In4.Cu")
		(net "M_L_DQ<22>")
	)
	(arc
		(start 74.392536 -100.957888)
		(mid 74.446006 -101.152951)
		(end 74.397362 -101.349302)
		(width 0.0889)
		(layer "In4.Cu")
		(net "M_L_DQ<22>")
	)
	(arc
		(start 73.699116 -99.376738)
		(mid 73.778338 -99.665856)
		(end 73.705466 -99.95662)
		(width 0.0889)
		(layer "In4.Cu")
		(net "M_L_DQ<22>")
	)
	(segment
		(start 50.099468 -142.6718)
		(end 50.099468 -143.941546)
		(width 0.1651)
		(layer "F.Cu")
		(net "M_L_DQ<21>")
	)
	(segment
		(start 72.041766 -99.67214)
		(end 71.470266 -99.67214)
		(width 0.1651)
		(layer "F.Cu")
		(net "M_L_DQ<21>")
	)
	(via
		(at 71.470266 -99.67214)
		(size 0.508)
		(drill 0.254)
		(layers "F.Cu" "B.Cu")
		(net "M_L_DQ<21>")
	)
	(via
		(at 50.099468 -143.941546)
		(size 0.508)
		(drill 0.254)
		(layers "F.Cu" "B.Cu")
		(net "M_L_DQ<21>")
	)
	(via
		(at 50.873152 -139.932156)
		(size 0.508)
		(drill 0.254)
		(layers "F.Cu" "B.Cu")
		(net "M_L_DQ<21>")
	)
	(segment
		(start 50.949352 -137.877296)
		(end 50.949352 -139.855956)
		(width 0.1651)
		(layer "B.Cu")
		(net "M_L_DQ<21>")
	)
	(segment
		(start 50.949352 -139.855956)
		(end 50.873152 -139.932156)
		(width 0.1651)
		(layer "B.Cu")
		(net "M_L_DQ<21>")
	)
	(segment
		(start 51.051968 -139.75334)
		(end 50.873152 -139.932156)
		(width 0.14224)
		(layer "In4.Cu")
		(net "M_L_DQ<21>")
	)
	(segment
		(start 52.829968 -127.6096)
		(end 51.229768 -129.2098)
		(width 0.14224)
		(layer "In4.Cu")
		(net "M_L_DQ<21>")
	)
	(segment
		(start 64.74587 -104.65308)
		(end 65.149984 -104.65308)
		(width 0.14224)
		(layer "In4.Cu")
		(net "M_L_DQ<21>")
	)
	(segment
		(start 63.8175 -107.131866)
		(end 63.706502 -107.021122)
		(width 0.14224)
		(layer "In4.Cu")
		(net "M_L_DQ<21>")
	)
	(segment
		(start 51.382168 -138.7602)
		(end 51.051968 -139.0904)
		(width 0.14224)
		(layer "In4.Cu")
		(net "M_L_DQ<21>")
	)
	(segment
		(start 68.90766 -100.75799)
		(end 67.708018 -100.75799)
		(width 0.0889)
		(layer "In4.Cu")
		(net "M_L_DQ<21>")
	)
	(segment
		(start 51.229768 -129.742946)
		(end 51.483768 -129.996946)
		(width 0.14224)
		(layer "In4.Cu")
		(net "M_L_DQ<21>")
	)
	(segment
		(start 67.111372 -101.679248)
		(end 64.59093 -104.19969)
		(width 0.14224)
		(layer "In4.Cu")
		(net "M_L_DQ<21>")
	)
	(segment
		(start 64.392302 -106.557064)
		(end 64.392302 -106.776012)
		(width 0.14224)
		(layer "In4.Cu")
		(net "M_L_DQ<21>")
	)
	(segment
		(start 51.382168 -134.0104)
		(end 51.283108 -134.10946)
		(width 0.14224)
		(layer "In4.Cu")
		(net "M_L_DQ<21>")
	)
	(segment
		(start 50.873152 -139.932156)
		(end 50.8508 -139.932156)
		(width 0.14224)
		(layer "In4.Cu")
		(net "M_L_DQ<21>")
	)
	(segment
		(start 63.242698 -107.925616)
		(end 62.532768 -108.635546)
		(width 0.14224)
		(layer "In4.Cu")
		(net "M_L_DQ<21>")
	)
	(segment
		(start 65.149984 -105.31602)
		(end 64.74587 -105.31602)
		(width 0.14224)
		(layer "In4.Cu")
		(net "M_L_DQ<21>")
	)
	(segment
		(start 63.1317 -107.376976)
		(end 63.1317 -107.59567)
		(width 0.14224)
		(layer "In4.Cu")
		(net "M_L_DQ<21>")
	)
	(segment
		(start 65.304924 -104.80802)
		(end 65.304924 -105.16108)
		(width 0.14224)
		(layer "In4.Cu")
		(net "M_L_DQ<21>")
	)
	(segment
		(start 50.524156 -143.789146)
		(end 50.371756 -143.941546)
		(width 0.14224)
		(layer "In4.Cu")
		(net "M_L_DQ<21>")
	)
	(segment
		(start 51.410108 -134.797038)
		(end 51.410108 -135.853424)
		(width 0.14224)
		(layer "In4.Cu")
		(net "M_L_DQ<21>")
	)
	(segment
		(start 51.229768 -129.2098)
		(end 51.229768 -129.742946)
		(width 0.14224)
		(layer "In4.Cu")
		(net "M_L_DQ<21>")
	)
	(segment
		(start 51.205638 -131.367276)
		(end 51.205638 -131.79933)
		(width 0.14224)
		(layer "In4.Cu")
		(net "M_L_DQ<21>")
	)
	(segment
		(start 50.524156 -143.561054)
		(end 50.524156 -143.789146)
		(width 0.14224)
		(layer "In4.Cu")
		(net "M_L_DQ<21>")
	)
	(segment
		(start 64.59093 -105.916984)
		(end 64.28105 -106.226864)
		(width 0.14224)
		(layer "In4.Cu")
		(net "M_L_DQ<21>")
	)
	(segment
		(start 64.28105 -106.445812)
		(end 64.392302 -106.557064)
		(width 0.14224)
		(layer "In4.Cu")
		(net "M_L_DQ<21>")
	)
	(segment
		(start 50.260758 -142.154656)
		(end 50.498756 -142.392654)
		(width 0.14224)
		(layer "In4.Cu")
		(net "M_L_DQ<21>")
	)
	(segment
		(start 65.149984 -104.65308)
		(end 65.304924 -104.80802)
		(width 0.14224)
		(layer "In4.Cu")
		(net "M_L_DQ<21>")
	)
	(segment
		(start 50.549556 -141.0462)
		(end 50.549556 -141.528546)
		(width 0.14224)
		(layer "In4.Cu")
		(net "M_L_DQ<21>")
	)
	(segment
		(start 69.771006 -100.26269)
		(end 69.735192 -100.26269)
		(width 0.0889)
		(layer "In4.Cu")
		(net "M_L_DQ<21>")
	)
	(segment
		(start 50.549556 -141.528546)
		(end 50.260758 -141.817344)
		(width 0.14224)
		(layer "In4.Cu")
		(net "M_L_DQ<21>")
	)
	(segment
		(start 51.483768 -129.996946)
		(end 51.483768 -131.089146)
		(width 0.14224)
		(layer "In4.Cu")
		(net "M_L_DQ<21>")
	)
	(segment
		(start 51.410108 -135.853424)
		(end 51.257708 -136.005824)
		(width 0.14224)
		(layer "In4.Cu")
		(net "M_L_DQ<21>")
	)
	(segment
		(start 64.59093 -104.49814)
		(end 64.74587 -104.65308)
		(width 0.14224)
		(layer "In4.Cu")
		(net "M_L_DQ<21>")
	)
	(segment
		(start 50.8508 -139.932156)
		(end 50.422556 -140.3604)
		(width 0.14224)
		(layer "In4.Cu")
		(net "M_L_DQ<21>")
	)
	(segment
		(start 64.59093 -104.19969)
		(end 64.59093 -104.49814)
		(width 0.14224)
		(layer "In4.Cu")
		(net "M_L_DQ<21>")
	)
	(segment
		(start 63.1317 -107.59567)
		(end 63.242698 -107.706668)
		(width 0.14224)
		(layer "In4.Cu")
		(net "M_L_DQ<21>")
	)
	(segment
		(start 50.260758 -141.817344)
		(end 50.260758 -142.154656)
		(width 0.14224)
		(layer "In4.Cu")
		(net "M_L_DQ<21>")
	)
	(segment
		(start 50.422556 -140.9192)
		(end 50.549556 -141.0462)
		(width 0.14224)
		(layer "In4.Cu")
		(net "M_L_DQ<21>")
	)
	(segment
		(start 63.242698 -107.706668)
		(end 63.242698 -107.925616)
		(width 0.14224)
		(layer "In4.Cu")
		(net "M_L_DQ<21>")
	)
	(segment
		(start 63.487554 -107.021122)
		(end 63.1317 -107.376976)
		(width 0.14224)
		(layer "In4.Cu")
		(net "M_L_DQ<21>")
	)
	(segment
		(start 50.260758 -143.297656)
		(end 50.524156 -143.561054)
		(width 0.14224)
		(layer "In4.Cu")
		(net "M_L_DQ<21>")
	)
	(segment
		(start 50.260758 -142.985744)
		(end 50.260758 -143.297656)
		(width 0.14224)
		(layer "In4.Cu")
		(net "M_L_DQ<21>")
	)
	(segment
		(start 51.205638 -131.79933)
		(end 51.382168 -131.97586)
		(width 0.14224)
		(layer "In4.Cu")
		(net "M_L_DQ<21>")
	)
	(segment
		(start 63.706502 -107.021122)
		(end 63.487554 -107.021122)
		(width 0.14224)
		(layer "In4.Cu")
		(net "M_L_DQ<21>")
	)
	(segment
		(start 51.051968 -139.0904)
		(end 51.051968 -139.75334)
		(width 0.14224)
		(layer "In4.Cu")
		(net "M_L_DQ<21>")
	)
	(segment
		(start 64.28105 -106.226864)
		(end 64.28105 -106.445812)
		(width 0.14224)
		(layer "In4.Cu")
		(net "M_L_DQ<21>")
	)
	(segment
		(start 51.382168 -136.64946)
		(end 51.382168 -138.7602)
		(width 0.14224)
		(layer "In4.Cu")
		(net "M_L_DQ<21>")
	)
	(segment
		(start 51.483768 -131.089146)
		(end 51.205638 -131.367276)
		(width 0.14224)
		(layer "In4.Cu")
		(net "M_L_DQ<21>")
	)
	(segment
		(start 62.532768 -108.635546)
		(end 62.532768 -113.174526)
		(width 0.14224)
		(layer "In4.Cu")
		(net "M_L_DQ<21>")
	)
	(segment
		(start 50.422556 -140.3604)
		(end 50.422556 -140.9192)
		(width 0.14224)
		(layer "In4.Cu")
		(net "M_L_DQ<21>")
	)
	(segment
		(start 51.283108 -134.670038)
		(end 51.410108 -134.797038)
		(width 0.14224)
		(layer "In4.Cu")
		(net "M_L_DQ<21>")
	)
	(segment
		(start 50.498756 -142.392654)
		(end 50.498756 -142.747746)
		(width 0.14224)
		(layer "In4.Cu")
		(net "M_L_DQ<21>")
	)
	(segment
		(start 64.036448 -107.131866)
		(end 63.8175 -107.131866)
		(width 0.14224)
		(layer "In4.Cu")
		(net "M_L_DQ<21>")
	)
	(segment
		(start 51.257708 -136.005824)
		(end 51.257708 -136.525)
		(width 0.14224)
		(layer "In4.Cu")
		(net "M_L_DQ<21>")
	)
	(segment
		(start 62.532768 -113.174526)
		(end 52.829968 -122.877326)
		(width 0.14224)
		(layer "In4.Cu")
		(net "M_L_DQ<21>")
	)
	(segment
		(start 67.708018 -100.75799)
		(end 67.111372 -101.354636)
		(width 0.0889)
		(layer "In4.Cu")
		(net "M_L_DQ<21>")
	)
	(segment
		(start 52.829968 -122.877326)
		(end 52.829968 -127.6096)
		(width 0.14224)
		(layer "In4.Cu")
		(net "M_L_DQ<21>")
	)
	(segment
		(start 50.498756 -142.747746)
		(end 50.260758 -142.985744)
		(width 0.14224)
		(layer "In4.Cu")
		(net "M_L_DQ<21>")
	)
	(segment
		(start 51.382168 -131.97586)
		(end 51.382168 -134.0104)
		(width 0.14224)
		(layer "In4.Cu")
		(net "M_L_DQ<21>")
	)
	(segment
		(start 51.283108 -134.10946)
		(end 51.283108 -134.670038)
		(width 0.14224)
		(layer "In4.Cu")
		(net "M_L_DQ<21>")
	)
	(segment
		(start 64.392302 -106.776012)
		(end 64.036448 -107.131866)
		(width 0.14224)
		(layer "In4.Cu")
		(net "M_L_DQ<21>")
	)
	(segment
		(start 64.74587 -105.31602)
		(end 64.59093 -105.47096)
		(width 0.14224)
		(layer "In4.Cu")
		(net "M_L_DQ<21>")
	)
	(segment
		(start 64.59093 -105.47096)
		(end 64.59093 -105.916984)
		(width 0.14224)
		(layer "In4.Cu")
		(net "M_L_DQ<21>")
	)
	(segment
		(start 71.470266 -99.67214)
		(end 70.648322 -99.76739)
		(width 0.0889)
		(layer "In4.Cu")
		(net "M_L_DQ<21>")
	)
	(segment
		(start 50.371756 -143.941546)
		(end 50.099468 -143.941546)
		(width 0.14224)
		(layer "In4.Cu")
		(net "M_L_DQ<21>")
	)
	(segment
		(start 51.257708 -136.525)
		(end 51.382168 -136.64946)
		(width 0.14224)
		(layer "In4.Cu")
		(net "M_L_DQ<21>")
	)
	(segment
		(start 67.111372 -101.354636)
		(end 67.111372 -101.679248)
		(width 0.0889)
		(layer "In4.Cu")
		(net "M_L_DQ<21>")
	)
	(segment
		(start 70.648322 -99.76739)
		(end 70.593712 -99.76739)
		(width 0.0889)
		(layer "In4.Cu")
		(net "M_L_DQ<21>")
	)
	(segment
		(start 65.304924 -105.16108)
		(end 65.149984 -105.31602)
		(width 0.14224)
		(layer "In4.Cu")
		(net "M_L_DQ<21>")
	)
	(arc
		(start 70.265036 -99.967288)
		(mid 70.056428 -100.17922)
		(end 69.771006 -100.26269)
		(width 0.0889)
		(layer "In4.Cu")
		(net "M_L_DQ<21>")
	)
	(arc
		(start 69.735192 -100.26269)
		(mid 69.545263 -100.32056)
		(end 69.406516 -100.462588)
		(width 0.0889)
		(layer "In4.Cu")
		(net "M_L_DQ<21>")
	)
	(arc
		(start 69.406516 -100.462588)
		(mid 69.195803 -100.675667)
		(end 68.90766 -100.75799)
		(width 0.0889)
		(layer "In4.Cu")
		(net "M_L_DQ<21>")
	)
	(arc
		(start 70.593712 -99.76739)
		(mid 70.403783 -99.82526)
		(end 70.265036 -99.967288)
		(width 0.0889)
		(layer "In4.Cu")
		(net "M_L_DQ<21>")
	)
	(segment
		(start 50.949352 -147.27174)
		(end 50.949352 -145.946368)
		(width 0.1651)
		(layer "F.Cu")
		(net "M_L_DQ<20>")
	)
	(segment
		(start 50.949352 -145.946368)
		(end 50.851308 -145.415)
		(width 0.1651)
		(layer "F.Cu")
		(net "M_L_DQ<20>")
	)
	(segment
		(start 72.041766 -98.681286)
		(end 71.470266 -98.681286)
		(width 0.1651)
		(layer "F.Cu")
		(net "M_L_DQ<20>")
	)
	(via
		(at 50.851308 -145.415)
		(size 0.508)
		(drill 0.254)
		(layers "F.Cu" "B.Cu")
		(net "M_L_DQ<20>")
	)
	(via
		(at 71.470266 -98.681286)
		(size 0.508)
		(drill 0.254)
		(layers "F.Cu" "B.Cu")
		(net "M_L_DQ<20>")
	)
	(via
		(at 50.099468 -141.213078)
		(size 0.508)
		(drill 0.254)
		(layers "F.Cu" "B.Cu")
		(net "M_L_DQ<20>")
	)
	(segment
		(start 50.099468 -142.477236)
		(end 50.099468 -141.213078)
		(width 0.1651)
		(layer "B.Cu")
		(net "M_L_DQ<20>")
	)
	(segment
		(start 49.824386 -144.337278)
		(end 49.824386 -144.63903)
		(width 0.14224)
		(layer "In4.Cu")
		(net "M_L_DQ<20>")
	)
	(segment
		(start 50.38598 -131.205478)
		(end 50.597308 -131.416806)
		(width 0.14224)
		(layer "In4.Cu")
		(net "M_L_DQ<20>")
	)
	(segment
		(start 50.584608 -139.304014)
		(end 49.961546 -139.927076)
		(width 0.14224)
		(layer "In4.Cu")
		(net "M_L_DQ<20>")
	)
	(segment
		(start 50.584608 -136.180068)
		(end 50.584608 -139.304014)
		(width 0.14224)
		(layer "In4.Cu")
		(net "M_L_DQ<20>")
	)
	(segment
		(start 68.905882 -100.567236)
		(end 67.62877 -100.567236)
		(width 0.0889)
		(layer "In4.Cu")
		(net "M_L_DQ<20>")
	)
	(segment
		(start 69.77126 -100.071936)
		(end 69.731636 -100.071936)
		(width 0.0889)
		(layer "In4.Cu")
		(net "M_L_DQ<20>")
	)
	(segment
		(start 49.666398 -144.17929)
		(end 49.824386 -144.337278)
		(width 0.14224)
		(layer "In4.Cu")
		(net "M_L_DQ<20>")
	)
	(segment
		(start 67.62877 -100.567236)
		(end 66.94043 -101.255576)
		(width 0.0889)
		(layer "In4.Cu")
		(net "M_L_DQ<20>")
	)
	(segment
		(start 61.897768 -112.911382)
		(end 52.194968 -122.614182)
		(width 0.14224)
		(layer "In4.Cu")
		(net "M_L_DQ<20>")
	)
	(segment
		(start 50.588164 -129.089404)
		(end 50.588164 -129.766822)
		(width 0.14224)
		(layer "In4.Cu")
		(net "M_L_DQ<20>")
	)
	(segment
		(start 50.597308 -131.416806)
		(end 50.597308 -134.490206)
		(width 0.14224)
		(layer "In4.Cu")
		(net "M_L_DQ<20>")
	)
	(segment
		(start 63.929768 -103.962708)
		(end 63.929768 -105.892346)
		(width 0.14224)
		(layer "In4.Cu")
		(net "M_L_DQ<20>")
	)
	(segment
		(start 50.600356 -145.415)
		(end 50.851308 -145.415)
		(width 0.14224)
		(layer "In4.Cu")
		(net "M_L_DQ<20>")
	)
	(segment
		(start 52.194968 -122.614182)
		(end 52.194968 -127.4826)
		(width 0.14224)
		(layer "In4.Cu")
		(net "M_L_DQ<20>")
	)
	(segment
		(start 66.6369 -101.255576)
		(end 63.929768 -103.962708)
		(width 0.14224)
		(layer "In4.Cu")
		(net "M_L_DQ<20>")
	)
	(segment
		(start 50.331116 -135.926576)
		(end 50.584608 -136.180068)
		(width 0.14224)
		(layer "In4.Cu")
		(net "M_L_DQ<20>")
	)
	(segment
		(start 70.974966 -99.348036)
		(end 70.958456 -99.376738)
		(width 0.0889)
		(layer "In4.Cu")
		(net "M_L_DQ<20>")
	)
	(segment
		(start 52.194968 -127.4826)
		(end 50.588164 -129.089404)
		(width 0.14224)
		(layer "In4.Cu")
		(net "M_L_DQ<20>")
	)
	(segment
		(start 50.38598 -129.969006)
		(end 50.38598 -131.205478)
		(width 0.14224)
		(layer "In4.Cu")
		(net "M_L_DQ<20>")
	)
	(segment
		(start 71.470266 -98.681286)
		(end 70.974966 -99.348036)
		(width 0.0889)
		(layer "In4.Cu")
		(net "M_L_DQ<20>")
	)
	(segment
		(start 50.099468 -141.213078)
		(end 49.666398 -141.646148)
		(width 0.14224)
		(layer "In4.Cu")
		(net "M_L_DQ<20>")
	)
	(segment
		(start 49.961546 -141.075156)
		(end 50.099468 -141.213078)
		(width 0.14224)
		(layer "In4.Cu")
		(net "M_L_DQ<20>")
	)
	(segment
		(start 63.929768 -105.892346)
		(end 61.897768 -107.924346)
		(width 0.14224)
		(layer "In4.Cu")
		(net "M_L_DQ<20>")
	)
	(segment
		(start 49.824386 -144.63903)
		(end 50.600356 -145.415)
		(width 0.14224)
		(layer "In4.Cu")
		(net "M_L_DQ<20>")
	)
	(segment
		(start 50.588164 -129.766822)
		(end 50.38598 -129.969006)
		(width 0.14224)
		(layer "In4.Cu")
		(net "M_L_DQ<20>")
	)
	(segment
		(start 66.94043 -101.255576)
		(end 66.6369 -101.255576)
		(width 0.0889)
		(layer "In4.Cu")
		(net "M_L_DQ<20>")
	)
	(segment
		(start 49.666398 -141.646148)
		(end 49.666398 -144.17929)
		(width 0.14224)
		(layer "In4.Cu")
		(net "M_L_DQ<20>")
	)
	(segment
		(start 61.897768 -107.924346)
		(end 61.897768 -112.911382)
		(width 0.14224)
		(layer "In4.Cu")
		(net "M_L_DQ<20>")
	)
	(segment
		(start 50.597308 -134.490206)
		(end 50.331116 -134.756398)
		(width 0.14224)
		(layer "In4.Cu")
		(net "M_L_DQ<20>")
	)
	(segment
		(start 50.331116 -134.756398)
		(end 50.331116 -135.926576)
		(width 0.14224)
		(layer "In4.Cu")
		(net "M_L_DQ<20>")
	)
	(segment
		(start 49.961546 -139.927076)
		(end 49.961546 -141.075156)
		(width 0.14224)
		(layer "In4.Cu")
		(net "M_L_DQ<20>")
	)
	(segment
		(start 70.62978 -99.576636)
		(end 70.593966 -99.576636)
		(width 0.0889)
		(layer "In4.Cu")
		(net "M_L_DQ<20>")
	)
	(arc
		(start 69.731636 -100.071936)
		(mid 69.448419 -100.156217)
		(end 69.241416 -100.367084)
		(width 0.0889)
		(layer "In4.Cu")
		(net "M_L_DQ<20>")
	)
	(arc
		(start 70.099936 -99.872038)
		(mid 69.961192 -100.014071)
		(end 69.77126 -100.071936)
		(width 0.0889)
		(layer "In4.Cu")
		(net "M_L_DQ<20>")
	)
	(arc
		(start 69.241416 -100.367084)
		(mid 69.099733 -100.510888)
		(end 68.905882 -100.567236)
		(width 0.0889)
		(layer "In4.Cu")
		(net "M_L_DQ<20>")
	)
	(arc
		(start 70.593966 -99.576636)
		(mid 70.308542 -99.660103)
		(end 70.099936 -99.872038)
		(width 0.0889)
		(layer "In4.Cu")
		(net "M_L_DQ<20>")
	)
	(arc
		(start 70.958456 -99.376738)
		(mid 70.819712 -99.518771)
		(end 70.62978 -99.576636)
		(width 0.0889)
		(layer "In4.Cu")
		(net "M_L_DQ<20>")
	)
	(segment
		(start 72.041766 -83.822286)
		(end 71.470266 -83.822286)
		(width 0.1651)
		(layer "F.Cu")
		(net "M_L_DQ<1>")
	)
	(segment
		(start 33.099502 -142.6718)
		(end 33.099502 -143.941546)
		(width 0.1651)
		(layer "F.Cu")
		(net "M_L_DQ<1>")
	)
	(via
		(at 71.470266 -83.822286)
		(size 0.508)
		(drill 0.254)
		(layers "F.Cu" "B.Cu")
		(net "M_L_DQ<1>")
	)
	(via
		(at 33.771586 -139.932156)
		(size 0.508)
		(drill 0.254)
		(layers "F.Cu" "B.Cu")
		(net "M_L_DQ<1>")
	)
	(via
		(at 33.099502 -143.941546)
		(size 0.508)
		(drill 0.254)
		(layers "F.Cu" "B.Cu")
		(net "M_L_DQ<1>")
	)
	(segment
		(start 33.949386 -137.877296)
		(end 33.949386 -139.251182)
		(width 0.1651)
		(layer "B.Cu")
		(net "M_L_DQ<1>")
	)
	(segment
		(start 33.949386 -139.251182)
		(end 33.771586 -139.428982)
		(width 0.1651)
		(layer "B.Cu")
		(net "M_L_DQ<1>")
	)
	(segment
		(start 33.771586 -139.428982)
		(end 33.771586 -139.932156)
		(width 0.1651)
		(layer "B.Cu")
		(net "M_L_DQ<1>")
	)
	(segment
		(start 43.380914 -108.3818)
		(end 54.871112 -96.891602)
		(width 0.14224)
		(layer "In4.Cu")
		(net "M_L_DQ<1>")
	)
	(segment
		(start 33.771586 -139.932156)
		(end 33.771586 -139.843256)
		(width 0.14224)
		(layer "In4.Cu")
		(net "M_L_DQ<1>")
	)
	(segment
		(start 54.871112 -96.891602)
		(end 54.871112 -92.583254)
		(width 0.14224)
		(layer "In4.Cu")
		(net "M_L_DQ<1>")
	)
	(segment
		(start 35.25774 -116.17452)
		(end 35.257994 -115.973352)
		(width 0.14224)
		(layer "In4.Cu")
		(net "M_L_DQ<1>")
	)
	(segment
		(start 66.257932 -83.563206)
		(end 66.893948 -82.92719)
		(width 0.0889)
		(layer "In4.Cu")
		(net "M_L_DQ<1>")
	)
	(segment
		(start 34.539428 -133.385052)
		(end 34.087308 -133.385052)
		(width 0.14224)
		(layer "In4.Cu")
		(net "M_L_DQ<1>")
	)
	(segment
		(start 54.871112 -92.583254)
		(end 63.664846 -83.78952)
		(width 0.14224)
		(layer "In4.Cu")
		(net "M_L_DQ<1>")
	)
	(segment
		(start 34.608262 -115.32362)
		(end 34.608262 -115.122452)
		(width 0.14224)
		(layer "In4.Cu")
		(net "M_L_DQ<1>")
	)
	(segment
		(start 70.958456 -83.127342)
		(end 70.974966 -83.156298)
		(width 0.0889)
		(layer "In4.Cu")
		(net "M_L_DQ<1>")
	)
	(segment
		(start 33.475168 -142.2908)
		(end 33.475168 -142.7226)
		(width 0.14224)
		(layer "In4.Cu")
		(net "M_L_DQ<1>")
	)
	(segment
		(start 33.551368 -141.425168)
		(end 33.260792 -141.715744)
		(width 0.14224)
		(layer "In4.Cu")
		(net "M_L_DQ<1>")
	)
	(segment
		(start 34.148014 -115.783614)
		(end 34.797746 -116.433346)
		(width 0.14224)
		(layer "In4.Cu")
		(net "M_L_DQ<1>")
	)
	(segment
		(start 70.974966 -83.156298)
		(end 71.470266 -83.822286)
		(width 0.0889)
		(layer "In4.Cu")
		(net "M_L_DQ<1>")
	)
	(segment
		(start 33.260792 -141.715744)
		(end 33.260792 -142.076424)
		(width 0.14224)
		(layer "In4.Cu")
		(net "M_L_DQ<1>")
	)
	(segment
		(start 33.749234 -139.932156)
		(end 33.32099 -140.3604)
		(width 0.14224)
		(layer "In4.Cu")
		(net "M_L_DQ<1>")
	)
	(segment
		(start 70.590156 -82.92719)
		(end 70.622922 -82.92719)
		(width 0.0889)
		(layer "In4.Cu")
		(net "M_L_DQ<1>")
	)
	(segment
		(start 34.389568 -136.709404)
		(end 34.255964 -136.5758)
		(width 0.14224)
		(layer "In4.Cu")
		(net "M_L_DQ<1>")
	)
	(segment
		(start 33.32099 -140.790168)
		(end 33.551368 -141.020546)
		(width 0.14224)
		(layer "In4.Cu")
		(net "M_L_DQ<1>")
	)
	(segment
		(start 34.036508 -132.572252)
		(end 34.539428 -132.572252)
		(width 0.14224)
		(layer "In4.Cu")
		(net "M_L_DQ<1>")
	)
	(segment
		(start 34.255964 -138.893804)
		(end 34.389568 -138.7602)
		(width 0.14224)
		(layer "In4.Cu")
		(net "M_L_DQ<1>")
	)
	(segment
		(start 35.068002 -114.863626)
		(end 35.717734 -115.513358)
		(width 0.14224)
		(layer "In4.Cu")
		(net "M_L_DQ<1>")
	)
	(segment
		(start 34.539428 -132.572252)
		(end 34.694368 -132.417312)
		(width 0.14224)
		(layer "In4.Cu")
		(net "M_L_DQ<1>")
	)
	(segment
		(start 33.906968 -132.701792)
		(end 34.036508 -132.572252)
		(width 0.14224)
		(layer "In4.Cu")
		(net "M_L_DQ<1>")
	)
	(segment
		(start 66.065146 -83.563206)
		(end 66.257932 -83.563206)
		(width 0.0889)
		(layer "In4.Cu")
		(net "M_L_DQ<1>")
	)
	(segment
		(start 34.087308 -133.385052)
		(end 33.906968 -133.204712)
		(width 0.14224)
		(layer "In4.Cu")
		(net "M_L_DQ<1>")
	)
	(segment
		(start 34.797746 -116.433346)
		(end 34.998914 -116.433346)
		(width 0.14224)
		(layer "In4.Cu")
		(net "M_L_DQ<1>")
	)
	(segment
		(start 68.88353 -82.92719)
		(end 68.916296 -82.92719)
		(width 0.0889)
		(layer "In4.Cu")
		(net "M_L_DQ<1>")
	)
	(segment
		(start 34.694368 -132.417312)
		(end 34.694368 -132.1816)
		(width 0.14224)
		(layer "In4.Cu")
		(net "M_L_DQ<1>")
	)
	(segment
		(start 33.551368 -141.020546)
		(end 33.551368 -141.425168)
		(width 0.14224)
		(layer "In4.Cu")
		(net "M_L_DQ<1>")
	)
	(segment
		(start 33.779968 -128.853184)
		(end 33.779968 -115.950746)
		(width 0.14224)
		(layer "In4.Cu")
		(net "M_L_DQ<1>")
	)
	(segment
		(start 34.608262 -115.122452)
		(end 34.867342 -114.863372)
		(width 0.14224)
		(layer "In4.Cu")
		(net "M_L_DQ<1>")
	)
	(segment
		(start 34.389568 -138.7602)
		(end 34.389568 -136.709404)
		(width 0.14224)
		(layer "In4.Cu")
		(net "M_L_DQ<1>")
	)
	(segment
		(start 36.167568 -115.264692)
		(end 36.167568 -114.452146)
		(width 0.14224)
		(layer "In4.Cu")
		(net "M_L_DQ<1>")
	)
	(segment
		(start 34.255964 -139.358878)
		(end 34.255964 -138.893804)
		(width 0.14224)
		(layer "In4.Cu")
		(net "M_L_DQ<1>")
	)
	(segment
		(start 33.260792 -142.936976)
		(end 33.260792 -143.244824)
		(width 0.14224)
		(layer "In4.Cu")
		(net "M_L_DQ<1>")
	)
	(segment
		(start 33.771586 -139.932156)
		(end 33.749234 -139.932156)
		(width 0.14224)
		(layer "In4.Cu")
		(net "M_L_DQ<1>")
	)
	(segment
		(start 33.260792 -143.244824)
		(end 33.500568 -143.4846)
		(width 0.14224)
		(layer "In4.Cu")
		(net "M_L_DQ<1>")
	)
	(segment
		(start 67.298316 -82.92719)
		(end 67.375786 -83.00466)
		(width 0.0889)
		(layer "In4.Cu")
		(net "M_L_DQ<1>")
	)
	(segment
		(start 65.838832 -83.78952)
		(end 66.065146 -83.563206)
		(width 0.0889)
		(layer "In4.Cu")
		(net "M_L_DQ<1>")
	)
	(segment
		(start 63.664846 -83.78952)
		(end 65.838832 -83.78952)
		(width 0.14224)
		(layer "In4.Cu")
		(net "M_L_DQ<1>")
	)
	(segment
		(start 33.500568 -143.7894)
		(end 33.348422 -143.941546)
		(width 0.14224)
		(layer "In4.Cu")
		(net "M_L_DQ<1>")
	)
	(segment
		(start 66.893948 -82.92719)
		(end 67.298316 -82.92719)
		(width 0.0889)
		(layer "In4.Cu")
		(net "M_L_DQ<1>")
	)
	(segment
		(start 33.947354 -115.78336)
		(end 34.148014 -115.783614)
		(width 0.14224)
		(layer "In4.Cu")
		(net "M_L_DQ<1>")
	)
	(segment
		(start 33.475168 -142.7226)
		(end 33.260792 -142.936976)
		(width 0.14224)
		(layer "In4.Cu")
		(net "M_L_DQ<1>")
	)
	(segment
		(start 36.167568 -114.452146)
		(end 42.237914 -108.3818)
		(width 0.14224)
		(layer "In4.Cu")
		(net "M_L_DQ<1>")
	)
	(segment
		(start 34.255964 -136.5758)
		(end 34.255964 -134.271004)
		(width 0.14224)
		(layer "In4.Cu")
		(net "M_L_DQ<1>")
	)
	(segment
		(start 34.867342 -114.863372)
		(end 35.068002 -114.863626)
		(width 0.14224)
		(layer "In4.Cu")
		(net "M_L_DQ<1>")
	)
	(segment
		(start 34.694368 -132.1816)
		(end 34.255964 -131.743196)
		(width 0.14224)
		(layer "In4.Cu")
		(net "M_L_DQ<1>")
	)
	(segment
		(start 35.717734 -115.513358)
		(end 35.918902 -115.513358)
		(width 0.14224)
		(layer "In4.Cu")
		(net "M_L_DQ<1>")
	)
	(segment
		(start 34.694368 -133.539992)
		(end 34.539428 -133.385052)
		(width 0.14224)
		(layer "In4.Cu")
		(net "M_L_DQ<1>")
	)
	(segment
		(start 42.237914 -108.3818)
		(end 43.380914 -108.3818)
		(width 0.14224)
		(layer "In4.Cu")
		(net "M_L_DQ<1>")
	)
	(segment
		(start 34.255964 -131.743196)
		(end 34.255964 -129.32918)
		(width 0.14224)
		(layer "In4.Cu")
		(net "M_L_DQ<1>")
	)
	(segment
		(start 67.833494 -83.42249)
		(end 68.057776 -83.42249)
		(width 0.0889)
		(layer "In4.Cu")
		(net "M_L_DQ<1>")
	)
	(segment
		(start 33.500568 -143.4846)
		(end 33.500568 -143.7894)
		(width 0.14224)
		(layer "In4.Cu")
		(net "M_L_DQ<1>")
	)
	(segment
		(start 34.998914 -116.433346)
		(end 35.25774 -116.17452)
		(width 0.14224)
		(layer "In4.Cu")
		(net "M_L_DQ<1>")
	)
	(segment
		(start 35.918902 -115.513358)
		(end 36.167568 -115.264692)
		(width 0.14224)
		(layer "In4.Cu")
		(net "M_L_DQ<1>")
	)
	(segment
		(start 67.375786 -83.00466)
		(end 67.484498 -83.124294)
		(width 0.0889)
		(layer "In4.Cu")
		(net "M_L_DQ<1>")
	)
	(segment
		(start 33.32099 -140.3604)
		(end 33.32099 -140.790168)
		(width 0.14224)
		(layer "In4.Cu")
		(net "M_L_DQ<1>")
	)
	(segment
		(start 34.255964 -129.32918)
		(end 33.779968 -128.853184)
		(width 0.14224)
		(layer "In4.Cu")
		(net "M_L_DQ<1>")
	)
	(segment
		(start 34.694368 -133.8326)
		(end 34.694368 -133.539992)
		(width 0.14224)
		(layer "In4.Cu")
		(net "M_L_DQ<1>")
	)
	(segment
		(start 33.348422 -143.941546)
		(end 33.099502 -143.941546)
		(width 0.14224)
		(layer "In4.Cu")
		(net "M_L_DQ<1>")
	)
	(segment
		(start 33.260792 -142.076424)
		(end 33.475168 -142.2908)
		(width 0.14224)
		(layer "In4.Cu")
		(net "M_L_DQ<1>")
	)
	(segment
		(start 33.906968 -133.204712)
		(end 33.906968 -132.701792)
		(width 0.14224)
		(layer "In4.Cu")
		(net "M_L_DQ<1>")
	)
	(segment
		(start 33.779968 -115.950746)
		(end 33.947354 -115.78336)
		(width 0.14224)
		(layer "In4.Cu")
		(net "M_L_DQ<1>")
	)
	(segment
		(start 33.771586 -139.843256)
		(end 34.255964 -139.358878)
		(width 0.14224)
		(layer "In4.Cu")
		(net "M_L_DQ<1>")
	)
	(segment
		(start 34.255964 -134.271004)
		(end 34.694368 -133.8326)
		(width 0.14224)
		(layer "In4.Cu")
		(net "M_L_DQ<1>")
	)
	(segment
		(start 35.257994 -115.973352)
		(end 34.608262 -115.32362)
		(width 0.14224)
		(layer "In4.Cu")
		(net "M_L_DQ<1>")
	)
	(arc
		(start 70.099936 -82.632042)
		(mid 70.30694 -82.842906)
		(end 70.590156 -82.92719)
		(width 0.0889)
		(layer "In4.Cu")
		(net "M_L_DQ<1>")
	)
	(arc
		(start 69.406516 -82.632042)
		(mid 69.753226 -82.431731)
		(end 70.099936 -82.632042)
		(width 0.0889)
		(layer "In4.Cu")
		(net "M_L_DQ<1>")
	)
	(arc
		(start 68.916296 -82.92719)
		(mid 69.199513 -82.842909)
		(end 69.406516 -82.632042)
		(width 0.0889)
		(layer "In4.Cu")
		(net "M_L_DQ<1>")
	)
	(arc
		(start 67.484498 -83.124294)
		(mid 67.630598 -83.306628)
		(end 67.833494 -83.42249)
		(width 0.0889)
		(layer "In4.Cu")
		(net "M_L_DQ<1>")
	)
	(arc
		(start 68.547996 -83.127342)
		(mid 68.689679 -82.983538)
		(end 68.88353 -82.92719)
		(width 0.0889)
		(layer "In4.Cu")
		(net "M_L_DQ<1>")
	)
	(arc
		(start 68.057776 -83.42249)
		(mid 68.340993 -83.338209)
		(end 68.547996 -83.127342)
		(width 0.0889)
		(layer "In4.Cu")
		(net "M_L_DQ<1>")
	)
	(arc
		(start 70.622922 -82.92719)
		(mid 70.816772 -82.98354)
		(end 70.958456 -83.127342)
		(width 0.0889)
		(layer "In4.Cu")
		(net "M_L_DQ<1>")
	)
	(segment
		(start 75.475846 -99.67214)
		(end 74.904346 -99.67214)
		(width 0.1651)
		(layer "F.Cu")
		(net "M_L_DQ<19>")
	)
	(segment
		(start 57.74944 -142.6718)
		(end 57.74944 -143.941546)
		(width 0.1651)
		(layer "F.Cu")
		(net "M_L_DQ<19>")
	)
	(via
		(at 58.599324 -139.932156)
		(size 0.508)
		(drill 0.254)
		(layers "F.Cu" "B.Cu")
		(net "M_L_DQ<19>")
	)
	(via
		(at 74.904346 -99.67214)
		(size 0.508)
		(drill 0.254)
		(layers "F.Cu" "B.Cu")
		(net "M_L_DQ<19>")
	)
	(via
		(at 57.74944 -143.941546)
		(size 0.508)
		(drill 0.254)
		(layers "F.Cu" "B.Cu")
		(net "M_L_DQ<19>")
	)
	(segment
		(start 58.599324 -137.877296)
		(end 58.599324 -139.932156)
		(width 0.1651)
		(layer "B.Cu")
		(net "M_L_DQ<19>")
	)
	(segment
		(start 58.599578 -137.877296)
		(end 58.599324 -137.877296)
		(width 0.1651)
		(layer "B.Cu")
		(net "M_L_DQ<19>")
	)
	(segment
		(start 58.928508 -136.52754)
		(end 59.027568 -136.6266)
		(width 0.14224)
		(layer "In4.Cu")
		(net "M_L_DQ<19>")
	)
	(segment
		(start 66.947288 -116.314982)
		(end 66.947288 -118.309898)
		(width 0.14224)
		(layer "In4.Cu")
		(net "M_L_DQ<19>")
	)
	(segment
		(start 62.557152 -123.760738)
		(end 62.136274 -123.33986)
		(width 0.14224)
		(layer "In4.Cu")
		(net "M_L_DQ<19>")
	)
	(segment
		(start 58.021728 -143.941546)
		(end 57.74944 -143.941546)
		(width 0.14224)
		(layer "In4.Cu")
		(net "M_L_DQ<19>")
	)
	(segment
		(start 58.199528 -143.763746)
		(end 58.021728 -143.941546)
		(width 0.14224)
		(layer "In4.Cu")
		(net "M_L_DQ<19>")
	)
	(segment
		(start 58.148728 -140.790168)
		(end 58.193178 -140.834618)
		(width 0.14224)
		(layer "In4.Cu")
		(net "M_L_DQ<19>")
	)
	(segment
		(start 58.199528 -143.44015)
		(end 58.199528 -143.763746)
		(width 0.14224)
		(layer "In4.Cu")
		(net "M_L_DQ<19>")
	)
	(segment
		(start 59.106308 -130.113278)
		(end 59.106308 -131.268978)
		(width 0.14224)
		(layer "In4.Cu")
		(net "M_L_DQ<19>")
	)
	(segment
		(start 62.136274 -123.33986)
		(end 61.917326 -123.33986)
		(width 0.14224)
		(layer "In4.Cu")
		(net "M_L_DQ<19>")
	)
	(segment
		(start 75.576176 -102.540562)
		(end 74.973942 -103.142796)
		(width 0.0889)
		(layer "In4.Cu")
		(net "M_L_DQ<19>")
	)
	(segment
		(start 58.576972 -139.932156)
		(end 58.148728 -140.3604)
		(width 0.14224)
		(layer "In4.Cu")
		(net "M_L_DQ<19>")
	)
	(segment
		(start 61.917326 -123.33986)
		(end 61.178186 -124.079)
		(width 0.14224)
		(layer "In4.Cu")
		(net "M_L_DQ<19>")
	)
	(segment
		(start 59.916568 -124.079)
		(end 58.798968 -125.1966)
		(width 0.14224)
		(layer "In4.Cu")
		(net "M_L_DQ<19>")
	)
	(segment
		(start 75.41133 -101.349302)
		(end 75.576176 -101.64445)
		(width 0.0889)
		(layer "In4.Cu")
		(net "M_L_DQ<19>")
	)
	(segment
		(start 58.966608 -131.408678)
		(end 58.966608 -131.9022)
		(width 0.14224)
		(layer "In4.Cu")
		(net "M_L_DQ<19>")
	)
	(segment
		(start 59.027568 -138.7856)
		(end 58.928508 -138.88466)
		(width 0.14224)
		(layer "In4.Cu")
		(net "M_L_DQ<19>")
	)
	(segment
		(start 68.273168 -110.880398)
		(end 68.273168 -117.520466)
		(width 0.14224)
		(layer "In4.Cu")
		(net "M_L_DQ<19>")
	)
	(segment
		(start 74.973942 -103.142796)
		(end 74.973942 -103.445564)
		(width 0.0889)
		(layer "In4.Cu")
		(net "M_L_DQ<19>")
	)
	(segment
		(start 57.91073 -142.059152)
		(end 58.167778 -142.3162)
		(width 0.14224)
		(layer "In4.Cu")
		(net "M_L_DQ<19>")
	)
	(segment
		(start 59.182508 -135.98906)
		(end 58.928508 -136.24306)
		(width 0.14224)
		(layer "In4.Cu")
		(net "M_L_DQ<19>")
	)
	(segment
		(start 58.966608 -134.581138)
		(end 59.182508 -134.797038)
		(width 0.14224)
		(layer "In4.Cu")
		(net "M_L_DQ<19>")
	)
	(segment
		(start 67.610228 -117.520466)
		(end 67.610228 -116.314982)
		(width 0.14224)
		(layer "In4.Cu")
		(net "M_L_DQ<19>")
	)
	(segment
		(start 61.178186 -124.079)
		(end 59.916568 -124.079)
		(width 0.14224)
		(layer "In4.Cu")
		(net "M_L_DQ<19>")
	)
	(segment
		(start 63.026036 -123.291854)
		(end 63.026036 -123.510802)
		(width 0.14224)
		(layer "In4.Cu")
		(net "M_L_DQ<19>")
	)
	(segment
		(start 67.102228 -116.160042)
		(end 66.947288 -116.314982)
		(width 0.14224)
		(layer "In4.Cu")
		(net "M_L_DQ<19>")
	)
	(segment
		(start 63.026036 -123.510802)
		(end 62.7761 -123.760738)
		(width 0.14224)
		(layer "In4.Cu")
		(net "M_L_DQ<19>")
	)
	(segment
		(start 58.167778 -142.3162)
		(end 58.167778 -142.621)
		(width 0.14224)
		(layer "In4.Cu")
		(net "M_L_DQ<19>")
	)
	(segment
		(start 58.928508 -136.24306)
		(end 58.928508 -136.52754)
		(width 0.14224)
		(layer "In4.Cu")
		(net "M_L_DQ<19>")
	)
	(segment
		(start 62.7761 -123.760738)
		(end 62.557152 -123.760738)
		(width 0.14224)
		(layer "In4.Cu")
		(net "M_L_DQ<19>")
	)
	(segment
		(start 58.798968 -125.1966)
		(end 58.798968 -129.805938)
		(width 0.14224)
		(layer "In4.Cu")
		(net "M_L_DQ<19>")
	)
	(segment
		(start 58.966608 -131.9022)
		(end 59.027568 -131.96316)
		(width 0.14224)
		(layer "In4.Cu")
		(net "M_L_DQ<19>")
	)
	(segment
		(start 58.966608 -134.07136)
		(end 58.966608 -134.581138)
		(width 0.14224)
		(layer "In4.Cu")
		(net "M_L_DQ<19>")
	)
	(segment
		(start 75.576176 -101.64445)
		(end 75.576176 -102.540562)
		(width 0.0889)
		(layer "In4.Cu")
		(net "M_L_DQ<19>")
	)
	(segment
		(start 59.182508 -134.797038)
		(end 59.182508 -135.98906)
		(width 0.14224)
		(layer "In4.Cu")
		(net "M_L_DQ<19>")
	)
	(segment
		(start 58.798968 -129.805938)
		(end 59.106308 -130.113278)
		(width 0.14224)
		(layer "In4.Cu")
		(net "M_L_DQ<19>")
	)
	(segment
		(start 62.605158 -122.652028)
		(end 62.605158 -122.870976)
		(width 0.14224)
		(layer "In4.Cu")
		(net "M_L_DQ<19>")
	)
	(segment
		(start 57.91073 -141.785848)
		(end 57.91073 -142.059152)
		(width 0.14224)
		(layer "In4.Cu")
		(net "M_L_DQ<19>")
	)
	(segment
		(start 75.399646 -100.338128)
		(end 75.416156 -100.367084)
		(width 0.0889)
		(layer "In4.Cu")
		(net "M_L_DQ<19>")
	)
	(segment
		(start 58.599324 -139.945364)
		(end 58.599324 -139.932156)
		(width 0.14224)
		(layer "In4.Cu")
		(net "M_L_DQ<19>")
	)
	(segment
		(start 58.928508 -139.61618)
		(end 58.599324 -139.945364)
		(width 0.14224)
		(layer "In4.Cu")
		(net "M_L_DQ<19>")
	)
	(segment
		(start 58.148728 -140.3604)
		(end 58.148728 -140.790168)
		(width 0.14224)
		(layer "In4.Cu")
		(net "M_L_DQ<19>")
	)
	(segment
		(start 59.027568 -134.0104)
		(end 58.966608 -134.07136)
		(width 0.14224)
		(layer "In4.Cu")
		(net "M_L_DQ<19>")
	)
	(segment
		(start 74.973942 -103.445564)
		(end 74.973942 -104.179624)
		(width 0.14224)
		(layer "In4.Cu")
		(net "M_L_DQ<19>")
	)
	(segment
		(start 68.118228 -117.675406)
		(end 67.765168 -117.675406)
		(width 0.14224)
		(layer "In4.Cu")
		(net "M_L_DQ<19>")
	)
	(segment
		(start 57.91073 -143.151352)
		(end 58.199528 -143.44015)
		(width 0.14224)
		(layer "In4.Cu")
		(net "M_L_DQ<19>")
	)
	(segment
		(start 58.599324 -139.932156)
		(end 58.576972 -139.932156)
		(width 0.14224)
		(layer "In4.Cu")
		(net "M_L_DQ<19>")
	)
	(segment
		(start 67.455288 -116.160042)
		(end 67.102228 -116.160042)
		(width 0.14224)
		(layer "In4.Cu")
		(net "M_L_DQ<19>")
	)
	(segment
		(start 62.605158 -122.870976)
		(end 63.026036 -123.291854)
		(width 0.14224)
		(layer "In4.Cu")
		(net "M_L_DQ<19>")
	)
	(segment
		(start 59.027568 -131.96316)
		(end 59.027568 -134.0104)
		(width 0.14224)
		(layer "In4.Cu")
		(net "M_L_DQ<19>")
	)
	(segment
		(start 59.106308 -131.268978)
		(end 58.966608 -131.408678)
		(width 0.14224)
		(layer "In4.Cu")
		(net "M_L_DQ<19>")
	)
	(segment
		(start 74.904346 -99.67214)
		(end 75.399646 -100.338128)
		(width 0.0889)
		(layer "In4.Cu")
		(net "M_L_DQ<19>")
	)
	(segment
		(start 67.765168 -117.675406)
		(end 67.610228 -117.520466)
		(width 0.14224)
		(layer "In4.Cu")
		(net "M_L_DQ<19>")
	)
	(segment
		(start 58.193178 -141.5034)
		(end 57.91073 -141.785848)
		(width 0.14224)
		(layer "In4.Cu")
		(net "M_L_DQ<19>")
	)
	(segment
		(start 67.610228 -116.314982)
		(end 67.455288 -116.160042)
		(width 0.14224)
		(layer "In4.Cu")
		(net "M_L_DQ<19>")
	)
	(segment
		(start 66.947288 -118.309898)
		(end 62.605158 -122.652028)
		(width 0.14224)
		(layer "In4.Cu")
		(net "M_L_DQ<19>")
	)
	(segment
		(start 57.91073 -142.878048)
		(end 57.91073 -143.151352)
		(width 0.14224)
		(layer "In4.Cu")
		(net "M_L_DQ<19>")
	)
	(segment
		(start 59.027568 -136.6266)
		(end 59.027568 -138.7856)
		(width 0.14224)
		(layer "In4.Cu")
		(net "M_L_DQ<19>")
	)
	(segment
		(start 58.193178 -140.834618)
		(end 58.193178 -141.5034)
		(width 0.14224)
		(layer "In4.Cu")
		(net "M_L_DQ<19>")
	)
	(segment
		(start 58.167778 -142.621)
		(end 57.91073 -142.878048)
		(width 0.14224)
		(layer "In4.Cu")
		(net "M_L_DQ<19>")
	)
	(segment
		(start 68.273168 -117.520466)
		(end 68.118228 -117.675406)
		(width 0.14224)
		(layer "In4.Cu")
		(net "M_L_DQ<19>")
	)
	(segment
		(start 58.928508 -138.88466)
		(end 58.928508 -139.61618)
		(width 0.14224)
		(layer "In4.Cu")
		(net "M_L_DQ<19>")
	)
	(segment
		(start 74.973942 -104.179624)
		(end 68.273168 -110.880398)
		(width 0.14224)
		(layer "In4.Cu")
		(net "M_L_DQ<19>")
	)
	(arc
		(start 75.416156 -100.367084)
		(mid 75.495287 -100.662486)
		(end 75.416156 -100.957888)
		(width 0.0889)
		(layer "In4.Cu")
		(net "M_L_DQ<19>")
	)
	(arc
		(start 75.416156 -100.957888)
		(mid 75.362686 -101.152951)
		(end 75.41133 -101.349302)
		(width 0.0889)
		(layer "In4.Cu")
		(net "M_L_DQ<19>")
	)
	(segment
		(start 58.599324 -147.27174)
		(end 58.599324 -146.280632)
		(width 0.1651)
		(layer "F.Cu")
		(net "M_L_DQ<18>")
	)
	(segment
		(start 75.475846 -98.681286)
		(end 74.904346 -98.681286)
		(width 0.1651)
		(layer "F.Cu")
		(net "M_L_DQ<18>")
	)
	(segment
		(start 58.730896 -145.92554)
		(end 58.599324 -145.793968)
		(width 0.1651)
		(layer "F.Cu")
		(net "M_L_DQ<18>")
	)
	(segment
		(start 58.599324 -145.793968)
		(end 58.599324 -145.5166)
		(width 0.1651)
		(layer "F.Cu")
		(net "M_L_DQ<18>")
	)
	(segment
		(start 58.599324 -146.280632)
		(end 58.730896 -146.14906)
		(width 0.1651)
		(layer "F.Cu")
		(net "M_L_DQ<18>")
	)
	(segment
		(start 58.599578 -147.27174)
		(end 58.599324 -147.27174)
		(width 0.1651)
		(layer "F.Cu")
		(net "M_L_DQ<18>")
	)
	(segment
		(start 58.730896 -146.14906)
		(end 58.730896 -145.92554)
		(width 0.1651)
		(layer "F.Cu")
		(net "M_L_DQ<18>")
	)
	(via
		(at 58.599324 -145.5166)
		(size 0.508)
		(drill 0.254)
		(layers "F.Cu" "B.Cu")
		(net "M_L_DQ<18>")
	)
	(via
		(at 74.904346 -98.681286)
		(size 0.508)
		(drill 0.254)
		(layers "F.Cu" "B.Cu")
		(net "M_L_DQ<18>")
	)
	(via
		(at 57.74944 -141.213078)
		(size 0.508)
		(drill 0.254)
		(layers "F.Cu" "B.Cu")
		(net "M_L_DQ<18>")
	)
	(segment
		(start 57.74944 -142.477236)
		(end 57.74944 -141.213078)
		(width 0.1651)
		(layer "B.Cu")
		(net "M_L_DQ<18>")
	)
	(segment
		(start 75.244706 -101.44252)
		(end 75.26147 -101.470968)
		(width 0.0889)
		(layer "In4.Cu")
		(net "M_L_DQ<18>")
	)
	(segment
		(start 74.409046 -99.348036)
		(end 74.392536 -99.376738)
		(width 0.0889)
		(layer "In4.Cu")
		(net "M_L_DQ<18>")
	)
	(segment
		(start 73.962768 -103.605838)
		(end 73.962768 -104.292654)
		(width 0.14224)
		(layer "In4.Cu")
		(net "M_L_DQ<18>")
	)
	(segment
		(start 58.318908 -131.523486)
		(end 58.318908 -131.9276)
		(width 0.14224)
		(layer "In4.Cu")
		(net "M_L_DQ<18>")
	)
	(segment
		(start 58.28411 -134.181342)
		(end 58.28411 -134.469124)
		(width 0.14224)
		(layer "In4.Cu")
		(net "M_L_DQ<18>")
	)
	(segment
		(start 75.26147 -101.470968)
		(end 75.386184 -101.69398)
		(width 0.0889)
		(layer "In4.Cu")
		(net "M_L_DQ<18>")
	)
	(segment
		(start 58.175144 -132.071364)
		(end 58.175144 -134.072376)
		(width 0.14224)
		(layer "In4.Cu")
		(net "M_L_DQ<18>")
	)
	(segment
		(start 58.268108 -136.5504)
		(end 58.189368 -136.62914)
		(width 0.14224)
		(layer "In4.Cu")
		(net "M_L_DQ<18>")
	)
	(segment
		(start 66.355976 -118.06555)
		(end 61.00572 -123.415806)
		(width 0.14224)
		(layer "In4.Cu")
		(net "M_L_DQ<18>")
	)
	(segment
		(start 58.268108 -138.96594)
		(end 58.268108 -139.371578)
		(width 0.14224)
		(layer "In4.Cu")
		(net "M_L_DQ<18>")
	)
	(segment
		(start 58.189368 -136.62914)
		(end 58.189368 -138.8872)
		(width 0.14224)
		(layer "In4.Cu")
		(net "M_L_DQ<18>")
	)
	(segment
		(start 74.886566 -100.26269)
		(end 74.92238 -100.26269)
		(width 0.0889)
		(layer "In4.Cu")
		(net "M_L_DQ<18>")
	)
	(segment
		(start 58.039508 -134.713726)
		(end 58.039508 -135.976868)
		(width 0.14224)
		(layer "In4.Cu")
		(net "M_L_DQ<18>")
	)
	(segment
		(start 74.904346 -98.681286)
		(end 74.409046 -99.348036)
		(width 0.0889)
		(layer "In4.Cu")
		(net "M_L_DQ<18>")
	)
	(segment
		(start 58.316368 -124.962158)
		(end 58.316368 -129.760218)
		(width 0.14224)
		(layer "In4.Cu")
		(net "M_L_DQ<18>")
	)
	(segment
		(start 58.318908 -131.9276)
		(end 58.175144 -132.071364)
		(width 0.14224)
		(layer "In4.Cu")
		(net "M_L_DQ<18>")
	)
	(segment
		(start 57.74944 -141.213078)
		(end 57.31637 -141.646148)
		(width 0.14224)
		(layer "In4.Cu")
		(net "M_L_DQ<18>")
	)
	(segment
		(start 58.039508 -135.976868)
		(end 58.268108 -136.205468)
		(width 0.14224)
		(layer "In4.Cu")
		(net "M_L_DQ<18>")
	)
	(segment
		(start 57.31637 -141.646148)
		(end 57.31637 -144.233646)
		(width 0.14224)
		(layer "In4.Cu")
		(net "M_L_DQ<18>")
	)
	(segment
		(start 58.28411 -134.469124)
		(end 58.039508 -134.713726)
		(width 0.14224)
		(layer "In4.Cu")
		(net "M_L_DQ<18>")
	)
	(segment
		(start 74.601578 -102.967028)
		(end 73.962768 -103.605838)
		(width 0.14224)
		(layer "In4.Cu")
		(net "M_L_DQ<18>")
	)
	(segment
		(start 73.962768 -104.292654)
		(end 67.638168 -110.617254)
		(width 0.14224)
		(layer "In4.Cu")
		(net "M_L_DQ<18>")
	)
	(segment
		(start 67.638168 -110.617254)
		(end 67.638168 -114.925094)
		(width 0.14224)
		(layer "In4.Cu")
		(net "M_L_DQ<18>")
	)
	(segment
		(start 57.31637 -144.233646)
		(end 58.599324 -145.5166)
		(width 0.14224)
		(layer "In4.Cu")
		(net "M_L_DQ<18>")
	)
	(segment
		(start 59.86272 -123.415806)
		(end 58.316368 -124.962158)
		(width 0.14224)
		(layer "In4.Cu")
		(net "M_L_DQ<18>")
	)
	(segment
		(start 57.404508 -140.235178)
		(end 57.404508 -140.868146)
		(width 0.14224)
		(layer "In4.Cu")
		(net "M_L_DQ<18>")
	)
	(segment
		(start 58.115708 -129.960878)
		(end 58.115708 -131.320286)
		(width 0.14224)
		(layer "In4.Cu")
		(net "M_L_DQ<18>")
	)
	(segment
		(start 58.268108 -136.205468)
		(end 58.268108 -136.5504)
		(width 0.14224)
		(layer "In4.Cu")
		(net "M_L_DQ<18>")
	)
	(segment
		(start 61.00572 -123.415806)
		(end 59.86272 -123.415806)
		(width 0.14224)
		(layer "In4.Cu")
		(net "M_L_DQ<18>")
	)
	(segment
		(start 75.386184 -101.69398)
		(end 75.386184 -102.461822)
		(width 0.0889)
		(layer "In4.Cu")
		(net "M_L_DQ<18>")
	)
	(segment
		(start 58.268108 -139.371578)
		(end 57.404508 -140.235178)
		(width 0.14224)
		(layer "In4.Cu")
		(net "M_L_DQ<18>")
	)
	(segment
		(start 74.880978 -102.967028)
		(end 74.601578 -102.967028)
		(width 0.0889)
		(layer "In4.Cu")
		(net "M_L_DQ<18>")
	)
	(segment
		(start 58.175144 -134.072376)
		(end 58.28411 -134.181342)
		(width 0.14224)
		(layer "In4.Cu")
		(net "M_L_DQ<18>")
	)
	(segment
		(start 58.115708 -131.320286)
		(end 58.318908 -131.523486)
		(width 0.14224)
		(layer "In4.Cu")
		(net "M_L_DQ<18>")
	)
	(segment
		(start 58.316368 -129.760218)
		(end 58.115708 -129.960878)
		(width 0.14224)
		(layer "In4.Cu")
		(net "M_L_DQ<18>")
	)
	(segment
		(start 58.189368 -138.8872)
		(end 58.268108 -138.96594)
		(width 0.14224)
		(layer "In4.Cu")
		(net "M_L_DQ<18>")
	)
	(segment
		(start 66.355976 -116.207286)
		(end 66.355976 -118.06555)
		(width 0.14224)
		(layer "In4.Cu")
		(net "M_L_DQ<18>")
	)
	(segment
		(start 57.404508 -140.868146)
		(end 57.74944 -141.213078)
		(width 0.14224)
		(layer "In4.Cu")
		(net "M_L_DQ<18>")
	)
	(segment
		(start 67.638168 -114.925094)
		(end 66.355976 -116.207286)
		(width 0.14224)
		(layer "In4.Cu")
		(net "M_L_DQ<18>")
	)
	(segment
		(start 75.386184 -102.461822)
		(end 74.880978 -102.967028)
		(width 0.0889)
		(layer "In4.Cu")
		(net "M_L_DQ<18>")
	)
	(arc
		(start 74.392536 -99.376738)
		(mid 74.388207 -99.95991)
		(end 74.886566 -100.26269)
		(width 0.0889)
		(layer "In4.Cu")
		(net "M_L_DQ<18>")
	)
	(arc
		(start 74.92238 -100.26269)
		(mid 75.255349 -100.470238)
		(end 75.251056 -100.862638)
		(width 0.0889)
		(layer "In4.Cu")
		(net "M_L_DQ<18>")
	)
	(arc
		(start 75.251056 -100.862638)
		(mid 75.171834 -101.151756)
		(end 75.244706 -101.44252)
		(width 0.0889)
		(layer "In4.Cu")
		(net "M_L_DQ<18>")
	)
	(segment
		(start 72.900286 -100.167186)
		(end 72.328786 -100.167186)
		(width 0.1651)
		(layer "F.Cu")
		(net "M_L_DQ<17>")
	)
	(segment
		(start 51.79949 -142.6718)
		(end 51.79949 -143.941546)
		(width 0.1651)
		(layer "F.Cu")
		(net "M_L_DQ<17>")
	)
	(via
		(at 52.471574 -139.932156)
		(size 0.508)
		(drill 0.254)
		(layers "F.Cu" "B.Cu")
		(net "M_L_DQ<17>")
	)
	(via
		(at 51.79949 -143.941546)
		(size 0.508)
		(drill 0.254)
		(layers "F.Cu" "B.Cu")
		(net "M_L_DQ<17>")
	)
	(via
		(at 72.328786 -100.167186)
		(size 0.508)
		(drill 0.254)
		(layers "F.Cu" "B.Cu")
		(net "M_L_DQ<17>")
	)
	(segment
		(start 52.471574 -139.428982)
		(end 52.471574 -139.932156)
		(width 0.1651)
		(layer "B.Cu")
		(net "M_L_DQ<17>")
	)
	(segment
		(start 52.649374 -139.251182)
		(end 52.471574 -139.428982)
		(width 0.1651)
		(layer "B.Cu")
		(net "M_L_DQ<17>")
	)
	(segment
		(start 52.649374 -137.877296)
		(end 52.649374 -139.251182)
		(width 0.1651)
		(layer "B.Cu")
		(net "M_L_DQ<17>")
	)
	(segment
		(start 52.730908 -137.397998)
		(end 52.575968 -137.552938)
		(width 0.14224)
		(layer "In4.Cu")
		(net "M_L_DQ<17>")
	)
	(segment
		(start 52.730908 -138.210798)
		(end 53.005228 -138.210798)
		(width 0.14224)
		(layer "In4.Cu")
		(net "M_L_DQ<17>")
	)
	(segment
		(start 52.175156 -142.7226)
		(end 51.96078 -142.936976)
		(width 0.14224)
		(layer "In4.Cu")
		(net "M_L_DQ<17>")
	)
	(segment
		(start 53.337968 -132.1816)
		(end 53.337968 -132.45211)
		(width 0.14224)
		(layer "In4.Cu")
		(net "M_L_DQ<17>")
	)
	(segment
		(start 52.575968 -137.552938)
		(end 52.575968 -138.055858)
		(width 0.14224)
		(layer "In4.Cu")
		(net "M_L_DQ<17>")
	)
	(segment
		(start 52.652168 -133.26491)
		(end 52.807108 -133.41985)
		(width 0.14224)
		(layer "In4.Cu")
		(net "M_L_DQ<17>")
	)
	(segment
		(start 63.802768 -108.966254)
		(end 63.802768 -113.700814)
		(width 0.14224)
		(layer "In4.Cu")
		(net "M_L_DQ<17>")
	)
	(segment
		(start 53.005228 -138.210798)
		(end 53.160168 -138.365738)
		(width 0.14224)
		(layer "In4.Cu")
		(net "M_L_DQ<17>")
	)
	(segment
		(start 52.807108 -132.60705)
		(end 52.652168 -132.76199)
		(width 0.14224)
		(layer "In4.Cu")
		(net "M_L_DQ<17>")
	)
	(segment
		(start 53.160168 -138.7094)
		(end 52.959508 -138.91006)
		(width 0.14224)
		(layer "In4.Cu")
		(net "M_L_DQ<17>")
	)
	(segment
		(start 69.774816 -101.253036)
		(end 69.742558 -101.253036)
		(width 0.0889)
		(layer "In4.Cu")
		(net "M_L_DQ<17>")
	)
	(segment
		(start 67.002406 -105.766616)
		(end 63.802768 -108.966254)
		(width 0.14224)
		(layer "In4.Cu")
		(net "M_L_DQ<17>")
	)
	(segment
		(start 53.183028 -132.60705)
		(end 52.807108 -132.60705)
		(width 0.14224)
		(layer "In4.Cu")
		(net "M_L_DQ<17>")
	)
	(segment
		(start 69.406008 -101.452934)
		(end 69.349112 -101.551486)
		(width 0.0889)
		(layer "In4.Cu")
		(net "M_L_DQ<17>")
	)
	(segment
		(start 69.349112 -101.551486)
		(end 68.261992 -102.638606)
		(width 0.0889)
		(layer "In4.Cu")
		(net "M_L_DQ<17>")
	)
	(segment
		(start 72.328786 -100.167186)
		(end 71.506334 -100.26269)
		(width 0.0889)
		(layer "In4.Cu")
		(net "M_L_DQ<17>")
	)
	(segment
		(start 51.96078 -142.936976)
		(end 51.96078 -143.244824)
		(width 0.14224)
		(layer "In4.Cu")
		(net "M_L_DQ<17>")
	)
	(segment
		(start 52.020978 -140.790168)
		(end 52.251356 -141.020546)
		(width 0.14224)
		(layer "In4.Cu")
		(net "M_L_DQ<17>")
	)
	(segment
		(start 54.099968 -123.403614)
		(end 54.099968 -124.104654)
		(width 0.14224)
		(layer "In4.Cu")
		(net "M_L_DQ<17>")
	)
	(segment
		(start 52.959508 -129.23266)
		(end 52.959508 -131.80314)
		(width 0.14224)
		(layer "In4.Cu")
		(net "M_L_DQ<17>")
	)
	(segment
		(start 51.96078 -141.715744)
		(end 51.96078 -142.076424)
		(width 0.14224)
		(layer "In4.Cu")
		(net "M_L_DQ<17>")
	)
	(segment
		(start 54.480968 -124.485654)
		(end 54.480968 -124.663454)
		(width 0.14224)
		(layer "In4.Cu")
		(net "M_L_DQ<17>")
	)
	(segment
		(start 54.480968 -125.755654)
		(end 54.480968 -126.045214)
		(width 0.14224)
		(layer "In4.Cu")
		(net "M_L_DQ<17>")
	)
	(segment
		(start 52.251356 -141.020546)
		(end 52.251356 -141.425168)
		(width 0.14224)
		(layer "In4.Cu")
		(net "M_L_DQ<17>")
	)
	(segment
		(start 66.490596 -105.27538)
		(end 66.847466 -105.27538)
		(width 0.14224)
		(layer "In4.Cu")
		(net "M_L_DQ<17>")
	)
	(segment
		(start 53.160168 -136.8044)
		(end 53.160168 -137.243058)
		(width 0.14224)
		(layer "In4.Cu")
		(net "M_L_DQ<17>")
	)
	(segment
		(start 53.005228 -137.397998)
		(end 52.730908 -137.397998)
		(width 0.14224)
		(layer "In4.Cu")
		(net "M_L_DQ<17>")
	)
	(segment
		(start 53.337968 -132.45211)
		(end 53.183028 -132.60705)
		(width 0.14224)
		(layer "In4.Cu")
		(net "M_L_DQ<17>")
	)
	(segment
		(start 52.959508 -139.444222)
		(end 52.471574 -139.932156)
		(width 0.14224)
		(layer "In4.Cu")
		(net "M_L_DQ<17>")
	)
	(segment
		(start 52.959508 -134.26186)
		(end 52.959508 -136.60374)
		(width 0.14224)
		(layer "In4.Cu")
		(net "M_L_DQ<17>")
	)
	(segment
		(start 54.099968 -126.858014)
		(end 54.480968 -127.239014)
		(width 0.14224)
		(layer "In4.Cu")
		(net "M_L_DQ<17>")
	)
	(segment
		(start 53.183028 -133.41985)
		(end 53.337968 -133.57479)
		(width 0.14224)
		(layer "In4.Cu")
		(net "M_L_DQ<17>")
	)
	(segment
		(start 66.975482 -104.143302)
		(end 66.975482 -104.4575)
		(width 0.14224)
		(layer "In4.Cu")
		(net "M_L_DQ<17>")
	)
	(segment
		(start 52.04841 -143.941546)
		(end 51.79949 -143.941546)
		(width 0.14224)
		(layer "In4.Cu")
		(net "M_L_DQ<17>")
	)
	(segment
		(start 54.099968 -125.044454)
		(end 54.099968 -125.374654)
		(width 0.14224)
		(layer "In4.Cu")
		(net "M_L_DQ<17>")
	)
	(segment
		(start 52.959508 -131.80314)
		(end 53.337968 -132.1816)
		(width 0.14224)
		(layer "In4.Cu")
		(net "M_L_DQ<17>")
	)
	(segment
		(start 52.652168 -132.76199)
		(end 52.652168 -133.26491)
		(width 0.14224)
		(layer "In4.Cu")
		(net "M_L_DQ<17>")
	)
	(segment
		(start 66.975482 -104.4575)
		(end 66.820542 -104.61244)
		(width 0.14224)
		(layer "In4.Cu")
		(net "M_L_DQ<17>")
	)
	(segment
		(start 52.959508 -136.60374)
		(end 53.160168 -136.8044)
		(width 0.14224)
		(layer "In4.Cu")
		(net "M_L_DQ<17>")
	)
	(segment
		(start 54.480968 -127.7112)
		(end 52.959508 -129.23266)
		(width 0.14224)
		(layer "In4.Cu")
		(net "M_L_DQ<17>")
	)
	(segment
		(start 66.820542 -104.61244)
		(end 66.490596 -104.61244)
		(width 0.14224)
		(layer "In4.Cu")
		(net "M_L_DQ<17>")
	)
	(segment
		(start 52.449222 -139.932156)
		(end 52.020978 -140.3604)
		(width 0.14224)
		(layer "In4.Cu")
		(net "M_L_DQ<17>")
	)
	(segment
		(start 66.847466 -105.27538)
		(end 67.002406 -105.43032)
		(width 0.14224)
		(layer "In4.Cu")
		(net "M_L_DQ<17>")
	)
	(segment
		(start 54.480968 -126.045214)
		(end 54.099968 -126.426214)
		(width 0.14224)
		(layer "In4.Cu")
		(net "M_L_DQ<17>")
	)
	(segment
		(start 52.020978 -140.3604)
		(end 52.020978 -140.790168)
		(width 0.14224)
		(layer "In4.Cu")
		(net "M_L_DQ<17>")
	)
	(segment
		(start 68.261992 -102.638606)
		(end 68.261992 -102.856792)
		(width 0.0889)
		(layer "In4.Cu")
		(net "M_L_DQ<17>")
	)
	(segment
		(start 69.74205 -101.252528)
		(end 69.738748 -101.252528)
		(width 0.0889)
		(layer "In4.Cu")
		(net "M_L_DQ<17>")
	)
	(segment
		(start 54.099968 -126.426214)
		(end 54.099968 -126.858014)
		(width 0.14224)
		(layer "In4.Cu")
		(net "M_L_DQ<17>")
	)
	(segment
		(start 66.490596 -104.61244)
		(end 66.335656 -104.76738)
		(width 0.14224)
		(layer "In4.Cu")
		(net "M_L_DQ<17>")
	)
	(segment
		(start 70.6247 -100.75799)
		(end 70.59676 -100.75799)
		(width 0.0889)
		(layer "In4.Cu")
		(net "M_L_DQ<17>")
	)
	(segment
		(start 52.959508 -138.91006)
		(end 52.959508 -139.444222)
		(width 0.14224)
		(layer "In4.Cu")
		(net "M_L_DQ<17>")
	)
	(segment
		(start 52.200556 -143.4846)
		(end 52.200556 -143.7894)
		(width 0.14224)
		(layer "In4.Cu")
		(net "M_L_DQ<17>")
	)
	(segment
		(start 54.099968 -125.374654)
		(end 54.480968 -125.755654)
		(width 0.14224)
		(layer "In4.Cu")
		(net "M_L_DQ<17>")
	)
	(segment
		(start 53.337968 -133.57479)
		(end 53.337968 -133.8834)
		(width 0.14224)
		(layer "In4.Cu")
		(net "M_L_DQ<17>")
	)
	(segment
		(start 69.742558 -101.253036)
		(end 69.74205 -101.252528)
		(width 0.0889)
		(layer "In4.Cu")
		(net "M_L_DQ<17>")
	)
	(segment
		(start 53.160168 -138.365738)
		(end 53.160168 -138.7094)
		(width 0.14224)
		(layer "In4.Cu")
		(net "M_L_DQ<17>")
	)
	(segment
		(start 67.002406 -105.43032)
		(end 67.002406 -105.766616)
		(width 0.14224)
		(layer "In4.Cu")
		(net "M_L_DQ<17>")
	)
	(segment
		(start 63.802768 -113.700814)
		(end 54.099968 -123.403614)
		(width 0.14224)
		(layer "In4.Cu")
		(net "M_L_DQ<17>")
	)
	(segment
		(start 71.506334 -100.26269)
		(end 71.452232 -100.26269)
		(width 0.0889)
		(layer "In4.Cu")
		(net "M_L_DQ<17>")
	)
	(segment
		(start 54.480968 -127.239014)
		(end 54.480968 -127.7112)
		(width 0.14224)
		(layer "In4.Cu")
		(net "M_L_DQ<17>")
	)
	(segment
		(start 52.471574 -139.932156)
		(end 52.449222 -139.932156)
		(width 0.14224)
		(layer "In4.Cu")
		(net "M_L_DQ<17>")
	)
	(segment
		(start 51.96078 -142.076424)
		(end 52.175156 -142.2908)
		(width 0.14224)
		(layer "In4.Cu")
		(net "M_L_DQ<17>")
	)
	(segment
		(start 54.099968 -124.104654)
		(end 54.480968 -124.485654)
		(width 0.14224)
		(layer "In4.Cu")
		(net "M_L_DQ<17>")
	)
	(segment
		(start 52.175156 -142.2908)
		(end 52.175156 -142.7226)
		(width 0.14224)
		(layer "In4.Cu")
		(net "M_L_DQ<17>")
	)
	(segment
		(start 52.251356 -141.425168)
		(end 51.96078 -141.715744)
		(width 0.14224)
		(layer "In4.Cu")
		(net "M_L_DQ<17>")
	)
	(segment
		(start 66.335656 -105.12044)
		(end 66.490596 -105.27538)
		(width 0.14224)
		(layer "In4.Cu")
		(net "M_L_DQ<17>")
	)
	(segment
		(start 52.807108 -133.41985)
		(end 53.183028 -133.41985)
		(width 0.14224)
		(layer "In4.Cu")
		(net "M_L_DQ<17>")
	)
	(segment
		(start 52.575968 -138.055858)
		(end 52.730908 -138.210798)
		(width 0.14224)
		(layer "In4.Cu")
		(net "M_L_DQ<17>")
	)
	(segment
		(start 54.480968 -124.663454)
		(end 54.099968 -125.044454)
		(width 0.14224)
		(layer "In4.Cu")
		(net "M_L_DQ<17>")
	)
	(segment
		(start 51.96078 -143.244824)
		(end 52.200556 -143.4846)
		(width 0.14224)
		(layer "In4.Cu")
		(net "M_L_DQ<17>")
	)
	(segment
		(start 52.200556 -143.7894)
		(end 52.04841 -143.941546)
		(width 0.14224)
		(layer "In4.Cu")
		(net "M_L_DQ<17>")
	)
	(segment
		(start 53.337968 -133.8834)
		(end 52.959508 -134.26186)
		(width 0.14224)
		(layer "In4.Cu")
		(net "M_L_DQ<17>")
	)
	(segment
		(start 53.160168 -137.243058)
		(end 53.005228 -137.397998)
		(width 0.14224)
		(layer "In4.Cu")
		(net "M_L_DQ<17>")
	)
	(segment
		(start 68.261992 -102.856792)
		(end 66.975482 -104.143302)
		(width 0.14224)
		(layer "In4.Cu")
		(net "M_L_DQ<17>")
	)
	(segment
		(start 66.335656 -104.76738)
		(end 66.335656 -105.12044)
		(width 0.14224)
		(layer "In4.Cu")
		(net "M_L_DQ<17>")
	)
	(arc
		(start 71.452232 -100.26269)
		(mid 71.262303 -100.32056)
		(end 71.123556 -100.462588)
		(width 0.0889)
		(layer "In4.Cu")
		(net "M_L_DQ<17>")
	)
	(arc
		(start 69.738748 -101.252528)
		(mid 69.546462 -101.309713)
		(end 69.406008 -101.452934)
		(width 0.0889)
		(layer "In4.Cu")
		(net "M_L_DQ<17>")
	)
	(arc
		(start 70.265036 -100.957888)
		(mid 70.058032 -101.168752)
		(end 69.774816 -101.253036)
		(width 0.0889)
		(layer "In4.Cu")
		(net "M_L_DQ<17>")
	)
	(arc
		(start 70.59676 -100.75799)
		(mid 70.405118 -100.815156)
		(end 70.265036 -100.957888)
		(width 0.0889)
		(layer "In4.Cu")
		(net "M_L_DQ<17>")
	)
	(arc
		(start 71.123556 -100.462588)
		(mid 70.912843 -100.675667)
		(end 70.6247 -100.75799)
		(width 0.0889)
		(layer "In4.Cu")
		(net "M_L_DQ<17>")
	)
	(segment
		(start 52.649374 -147.27174)
		(end 52.649374 -147.277582)
		(width 0.1651)
		(layer "F.Cu")
		(net "M_L_DQ<16>")
	)
	(segment
		(start 52.649374 -147.277582)
		(end 52.471574 -145.415)
		(width 0.1651)
		(layer "F.Cu")
		(net "M_L_DQ<16>")
	)
	(segment
		(start 72.900286 -98.18624)
		(end 72.328786 -98.18624)
		(width 0.1651)
		(layer "F.Cu")
		(net "M_L_DQ<16>")
	)
	(via
		(at 51.79949 -141.213078)
		(size 0.508)
		(drill 0.254)
		(layers "F.Cu" "B.Cu")
		(net "M_L_DQ<16>")
	)
	(via
		(at 72.328786 -98.18624)
		(size 0.508)
		(drill 0.254)
		(layers "F.Cu" "B.Cu")
		(net "M_L_DQ<16>")
	)
	(via
		(at 52.471574 -145.415)
		(size 0.508)
		(drill 0.254)
		(layers "F.Cu" "B.Cu")
		(net "M_L_DQ<16>")
	)
	(segment
		(start 51.79949 -142.477236)
		(end 51.79949 -141.213078)
		(width 0.1651)
		(layer "B.Cu")
		(net "M_L_DQ<16>")
	)
	(segment
		(start 69.768212 -101.062536)
		(end 69.735446 -101.062536)
		(width 0.0889)
		(layer "In4.Cu")
		(net "M_L_DQ<16>")
	)
	(segment
		(start 51.598068 -140.047218)
		(end 51.598068 -141.011656)
		(width 0.14224)
		(layer "In4.Cu")
		(net "M_L_DQ<16>")
	)
	(segment
		(start 52.273708 -134.484618)
		(end 51.981608 -134.776718)
		(width 0.14224)
		(layer "In4.Cu")
		(net "M_L_DQ<16>")
	)
	(segment
		(start 51.981608 -135.979916)
		(end 52.285138 -136.283446)
		(width 0.14224)
		(layer "In4.Cu")
		(net "M_L_DQ<16>")
	)
	(segment
		(start 63.167768 -108.686854)
		(end 63.167768 -113.43767)
		(width 0.14224)
		(layer "In4.Cu")
		(net "M_L_DQ<16>")
	)
	(segment
		(start 63.167768 -113.43767)
		(end 53.464968 -123.14047)
		(width 0.14224)
		(layer "In4.Cu")
		(net "M_L_DQ<16>")
	)
	(segment
		(start 65.790064 -104.430576)
		(end 65.790064 -106.064558)
		(width 0.14224)
		(layer "In4.Cu")
		(net "M_L_DQ<16>")
	)
	(segment
		(start 51.598068 -141.011656)
		(end 51.79949 -141.213078)
		(width 0.14224)
		(layer "In4.Cu")
		(net "M_L_DQ<16>")
	)
	(segment
		(start 52.265072 -131.46405)
		(end 52.265072 -131.961636)
		(width 0.14224)
		(layer "In4.Cu")
		(net "M_L_DQ<16>")
	)
	(segment
		(start 51.940968 -130.103118)
		(end 51.940968 -131.139946)
		(width 0.14224)
		(layer "In4.Cu")
		(net "M_L_DQ<16>")
	)
	(segment
		(start 52.143914 -133.984746)
		(end 52.273708 -134.11454)
		(width 0.14224)
		(layer "In4.Cu")
		(net "M_L_DQ<16>")
	)
	(segment
		(start 51.36642 -144.60601)
		(end 52.17541 -145.415)
		(width 0.14224)
		(layer "In4.Cu")
		(net "M_L_DQ<16>")
	)
	(segment
		(start 52.23129 -138.694922)
		(end 52.23129 -139.413996)
		(width 0.14224)
		(layer "In4.Cu")
		(net "M_L_DQ<16>")
	)
	(segment
		(start 70.622922 -100.567236)
		(end 70.598792 -100.567236)
		(width 0.0889)
		(layer "In4.Cu")
		(net "M_L_DQ<16>")
	)
	(segment
		(start 52.09667 -138.560302)
		(end 52.23129 -138.694922)
		(width 0.14224)
		(layer "In4.Cu")
		(net "M_L_DQ<16>")
	)
	(segment
		(start 52.09667 -136.790938)
		(end 52.09667 -138.560302)
		(width 0.14224)
		(layer "In4.Cu")
		(net "M_L_DQ<16>")
	)
	(segment
		(start 52.265072 -131.961636)
		(end 52.143914 -132.082794)
		(width 0.14224)
		(layer "In4.Cu")
		(net "M_L_DQ<16>")
	)
	(segment
		(start 51.940968 -131.139946)
		(end 52.265072 -131.46405)
		(width 0.14224)
		(layer "In4.Cu")
		(net "M_L_DQ<16>")
	)
	(segment
		(start 51.981608 -134.776718)
		(end 51.981608 -135.979916)
		(width 0.14224)
		(layer "In4.Cu")
		(net "M_L_DQ<16>")
	)
	(segment
		(start 51.79949 -141.213078)
		(end 51.36642 -141.646148)
		(width 0.14224)
		(layer "In4.Cu")
		(net "M_L_DQ<16>")
	)
	(segment
		(start 52.273708 -134.11454)
		(end 52.273708 -134.484618)
		(width 0.14224)
		(layer "In4.Cu")
		(net "M_L_DQ<16>")
	)
	(segment
		(start 71.83374 -98.851974)
		(end 71.816976 -98.881438)
		(width 0.0889)
		(layer "In4.Cu")
		(net "M_L_DQ<16>")
	)
	(segment
		(start 52.319936 -129.034032)
		(end 52.319936 -129.72415)
		(width 0.14224)
		(layer "In4.Cu")
		(net "M_L_DQ<16>")
	)
	(segment
		(start 52.285138 -136.60247)
		(end 52.09667 -136.790938)
		(width 0.14224)
		(layer "In4.Cu")
		(net "M_L_DQ<16>")
	)
	(segment
		(start 52.23129 -139.413996)
		(end 51.598068 -140.047218)
		(width 0.14224)
		(layer "In4.Cu")
		(net "M_L_DQ<16>")
	)
	(segment
		(start 51.36642 -141.646148)
		(end 51.36642 -144.60601)
		(width 0.14224)
		(layer "In4.Cu")
		(net "M_L_DQ<16>")
	)
	(segment
		(start 67.79895 -102.42169)
		(end 65.790064 -104.430576)
		(width 0.14224)
		(layer "In4.Cu")
		(net "M_L_DQ<16>")
	)
	(segment
		(start 53.464968 -127.889)
		(end 52.319936 -129.034032)
		(width 0.14224)
		(layer "In4.Cu")
		(net "M_L_DQ<16>")
	)
	(segment
		(start 69.241416 -101.357938)
		(end 69.196966 -101.4349)
		(width 0.0889)
		(layer "In4.Cu")
		(net "M_L_DQ<16>")
	)
	(segment
		(start 71.4883 -100.071936)
		(end 71.448676 -100.071936)
		(width 0.0889)
		(layer "In4.Cu")
		(net "M_L_DQ<16>")
	)
	(segment
		(start 65.790064 -106.064558)
		(end 63.167768 -108.686854)
		(width 0.14224)
		(layer "In4.Cu")
		(net "M_L_DQ<16>")
	)
	(segment
		(start 52.17541 -145.415)
		(end 52.471574 -145.415)
		(width 0.14224)
		(layer "In4.Cu")
		(net "M_L_DQ<16>")
	)
	(segment
		(start 69.196966 -101.4349)
		(end 68.210176 -102.42169)
		(width 0.0889)
		(layer "In4.Cu")
		(net "M_L_DQ<16>")
	)
	(segment
		(start 52.319936 -129.72415)
		(end 51.940968 -130.103118)
		(width 0.14224)
		(layer "In4.Cu")
		(net "M_L_DQ<16>")
	)
	(segment
		(start 72.328786 -98.18624)
		(end 71.83374 -98.851974)
		(width 0.0889)
		(layer "In4.Cu")
		(net "M_L_DQ<16>")
	)
	(segment
		(start 68.210176 -102.42169)
		(end 67.79895 -102.42169)
		(width 0.0889)
		(layer "In4.Cu")
		(net "M_L_DQ<16>")
	)
	(segment
		(start 52.143914 -132.082794)
		(end 52.143914 -133.984746)
		(width 0.14224)
		(layer "In4.Cu")
		(net "M_L_DQ<16>")
	)
	(segment
		(start 52.285138 -136.283446)
		(end 52.285138 -136.60247)
		(width 0.14224)
		(layer "In4.Cu")
		(net "M_L_DQ<16>")
	)
	(segment
		(start 53.464968 -123.14047)
		(end 53.464968 -127.889)
		(width 0.14224)
		(layer "In4.Cu")
		(net "M_L_DQ<16>")
	)
	(arc
		(start 70.598792 -100.567236)
		(mid 70.310647 -100.649555)
		(end 70.099936 -100.862638)
		(width 0.0889)
		(layer "In4.Cu")
		(net "M_L_DQ<16>")
	)
	(arc
		(start 70.958456 -100.367084)
		(mid 70.816773 -100.510888)
		(end 70.622922 -100.567236)
		(width 0.0889)
		(layer "In4.Cu")
		(net "M_L_DQ<16>")
	)
	(arc
		(start 71.816976 -99.472242)
		(mid 71.821221 -99.864487)
		(end 71.4883 -100.071936)
		(width 0.0889)
		(layer "In4.Cu")
		(net "M_L_DQ<16>")
	)
	(arc
		(start 69.735446 -101.062536)
		(mid 69.450022 -101.146003)
		(end 69.241416 -101.357938)
		(width 0.0889)
		(layer "In4.Cu")
		(net "M_L_DQ<16>")
	)
	(arc
		(start 71.448676 -100.071936)
		(mid 71.165459 -100.156217)
		(end 70.958456 -100.367084)
		(width 0.0889)
		(layer "In4.Cu")
		(net "M_L_DQ<16>")
	)
	(arc
		(start 70.099936 -100.862638)
		(mid 69.959857 -101.005374)
		(end 69.768212 -101.062536)
		(width 0.0889)
		(layer "In4.Cu")
		(net "M_L_DQ<16>")
	)
	(arc
		(start 71.816976 -98.881438)
		(mid 71.737845 -99.17684)
		(end 71.816976 -99.472242)
		(width 0.0889)
		(layer "In4.Cu")
		(net "M_L_DQ<16>")
	)
	(segment
		(start 46.699424 -142.6718)
		(end 46.699424 -143.941546)
		(width 0.1651)
		(layer "F.Cu")
		(net "M_L_DQ<15>")
	)
	(segment
		(start 71.183246 -91.25204)
		(end 70.611746 -91.25204)
		(width 0.1651)
		(layer "F.Cu")
		(net "M_L_DQ<15>")
	)
	(via
		(at 47.549308 -139.932156)
		(size 0.508)
		(drill 0.254)
		(layers "F.Cu" "B.Cu")
		(net "M_L_DQ<15>")
	)
	(via
		(at 46.699424 -143.941546)
		(size 0.508)
		(drill 0.254)
		(layers "F.Cu" "B.Cu")
		(net "M_L_DQ<15>")
	)
	(via
		(at 70.611746 -91.25204)
		(size 0.508)
		(drill 0.254)
		(layers "F.Cu" "B.Cu")
		(net "M_L_DQ<15>")
	)
	(segment
		(start 47.549562 -137.877296)
		(end 47.549308 -137.877296)
		(width 0.1651)
		(layer "B.Cu")
		(net "M_L_DQ<15>")
	)
	(segment
		(start 47.549308 -137.877296)
		(end 47.549308 -139.932156)
		(width 0.1651)
		(layer "B.Cu")
		(net "M_L_DQ<15>")
	)
	(segment
		(start 51.686968 -117.357144)
		(end 51.686968 -117.644672)
		(width 0.14224)
		(layer "In4.Cu")
		(net "M_L_DQ<15>")
	)
	(segment
		(start 47.902114 -136.220454)
		(end 47.902114 -136.575546)
		(width 0.14224)
		(layer "In4.Cu")
		(net "M_L_DQ<15>")
	)
	(segment
		(start 47.978568 -138.785346)
		(end 47.902114 -138.8618)
		(width 0.14224)
		(layer "In4.Cu")
		(net "M_L_DQ<15>")
	)
	(segment
		(start 48.130714 -130.087878)
		(end 48.130714 -131.140454)
		(width 0.14224)
		(layer "In4.Cu")
		(net "M_L_DQ<15>")
	)
	(segment
		(start 46.860714 -143.151352)
		(end 47.149512 -143.44015)
		(width 0.14224)
		(layer "In4.Cu")
		(net "M_L_DQ<15>")
	)
	(segment
		(start 49.324768 -127.032512)
		(end 47.902114 -128.455166)
		(width 0.14224)
		(layer "In4.Cu")
		(net "M_L_DQ<15>")
	)
	(segment
		(start 47.149512 -143.763746)
		(end 46.971712 -143.941546)
		(width 0.14224)
		(layer "In4.Cu")
		(net "M_L_DQ<15>")
	)
	(segment
		(start 57.794906 -109.693964)
		(end 58.466228 -109.693964)
		(width 0.14224)
		(layer "In4.Cu")
		(net "M_L_DQ<15>")
	)
	(segment
		(start 48.130714 -131.140454)
		(end 47.851314 -131.419854)
		(width 0.14224)
		(layer "In4.Cu")
		(net "M_L_DQ<15>")
	)
	(segment
		(start 70.26021 -92.433902)
		(end 70.265036 -92.442538)
		(width 0.0889)
		(layer "In4.Cu")
		(net "M_L_DQ<15>")
	)
	(segment
		(start 50.584608 -120.758712)
		(end 50.36566 -120.758712)
		(width 0.14224)
		(layer "In4.Cu")
		(net "M_L_DQ<15>")
	)
	(segment
		(start 51.515772 -119.827548)
		(end 50.584608 -120.758712)
		(width 0.14224)
		(layer "In4.Cu")
		(net "M_L_DQ<15>")
	)
	(segment
		(start 52.26177 -117.931946)
		(end 54.243478 -115.950238)
		(width 0.14224)
		(layer "In4.Cu")
		(net "M_L_DQ<15>")
	)
	(segment
		(start 49.790858 -121.552462)
		(end 49.324768 -122.018552)
		(width 0.14224)
		(layer "In4.Cu")
		(net "M_L_DQ<15>")
	)
	(segment
		(start 57.639966 -109.539024)
		(end 57.794906 -109.693964)
		(width 0.14224)
		(layer "In4.Cu")
		(net "M_L_DQ<15>")
	)
	(segment
		(start 58.466228 -109.693964)
		(end 58.621168 -109.848904)
		(width 0.14224)
		(layer "In4.Cu")
		(net "M_L_DQ<15>")
	)
	(segment
		(start 47.891192 -139.590272)
		(end 47.549308 -139.932156)
		(width 0.14224)
		(layer "In4.Cu")
		(net "M_L_DQ<15>")
	)
	(segment
		(start 47.978568 -132.080254)
		(end 47.978568 -134.112)
		(width 0.14224)
		(layer "In4.Cu")
		(net "M_L_DQ<15>")
	)
	(segment
		(start 51.482498 -118.64467)
		(end 51.126644 -119.000524)
		(width 0.14224)
		(layer "In4.Cu")
		(net "M_L_DQ<15>")
	)
	(segment
		(start 65.798192 -96.595946)
		(end 65.798192 -96.892872)
		(width 0.0889)
		(layer "In4.Cu")
		(net "M_L_DQ<15>")
	)
	(segment
		(start 47.902114 -136.575546)
		(end 47.978568 -136.652)
		(width 0.14224)
		(layer "In4.Cu")
		(net "M_L_DQ<15>")
	)
	(segment
		(start 58.466228 -109.031024)
		(end 57.794906 -109.031024)
		(width 0.14224)
		(layer "In4.Cu")
		(net "M_L_DQ<15>")
	)
	(segment
		(start 58.621168 -109.848904)
		(end 58.621168 -110.422944)
		(width 0.14224)
		(layer "In4.Cu")
		(net "M_L_DQ<15>")
	)
	(segment
		(start 70.39229 -91.822016)
		(end 70.265036 -92.042488)
		(width 0.0889)
		(layer "In4.Cu")
		(net "M_L_DQ<15>")
	)
	(segment
		(start 46.860714 -142.878048)
		(end 46.860714 -143.151352)
		(width 0.14224)
		(layer "In4.Cu")
		(net "M_L_DQ<15>")
	)
	(segment
		(start 58.621168 -108.876084)
		(end 58.466228 -109.031024)
		(width 0.14224)
		(layer "In4.Cu")
		(net "M_L_DQ<15>")
	)
	(segment
		(start 51.701446 -118.64467)
		(end 51.482498 -118.64467)
		(width 0.14224)
		(layer "In4.Cu")
		(net "M_L_DQ<15>")
	)
	(segment
		(start 48.071278 -134.686802)
		(end 48.071278 -136.05129)
		(width 0.14224)
		(layer "In4.Cu")
		(net "M_L_DQ<15>")
	)
	(segment
		(start 51.686968 -117.644672)
		(end 51.974242 -117.931946)
		(width 0.14224)
		(layer "In4.Cu")
		(net "M_L_DQ<15>")
	)
	(segment
		(start 47.851314 -131.419854)
		(end 47.851314 -131.953)
		(width 0.14224)
		(layer "In4.Cu")
		(net "M_L_DQ<15>")
	)
	(segment
		(start 47.549308 -139.932156)
		(end 47.526956 -139.932156)
		(width 0.14224)
		(layer "In4.Cu")
		(net "M_L_DQ<15>")
	)
	(segment
		(start 46.971712 -143.941546)
		(end 46.699424 -143.941546)
		(width 0.14224)
		(layer "In4.Cu")
		(net "M_L_DQ<15>")
	)
	(segment
		(start 69.574918 -93.32849)
		(end 69.299582 -93.603826)
		(width 0.0889)
		(layer "In4.Cu")
		(net "M_L_DQ<15>")
	)
	(segment
		(start 69.299582 -93.603826)
		(end 69.298566 -93.603826)
		(width 0.0889)
		(layer "In4.Cu")
		(net "M_L_DQ<15>")
	)
	(segment
		(start 47.143162 -140.834618)
		(end 47.143162 -141.5034)
		(width 0.14224)
		(layer "In4.Cu")
		(net "M_L_DQ<15>")
	)
	(segment
		(start 49.324768 -122.018552)
		(end 49.324768 -127.032512)
		(width 0.14224)
		(layer "In4.Cu")
		(net "M_L_DQ<15>")
	)
	(segment
		(start 69.298566 -93.603826)
		(end 68.188586 -94.713806)
		(width 0.0889)
		(layer "In4.Cu")
		(net "M_L_DQ<15>")
	)
	(segment
		(start 52.309522 -119.033798)
		(end 52.090574 -119.033798)
		(width 0.14224)
		(layer "In4.Cu")
		(net "M_L_DQ<15>")
	)
	(segment
		(start 49.22393 -120.766586)
		(end 49.790858 -121.333514)
		(width 0.14224)
		(layer "In4.Cu")
		(net "M_L_DQ<15>")
	)
	(segment
		(start 54.243478 -115.950238)
		(end 54.531006 -115.950238)
		(width 0.14224)
		(layer "In4.Cu")
		(net "M_L_DQ<15>")
	)
	(segment
		(start 47.098712 -140.3604)
		(end 47.098712 -140.790168)
		(width 0.14224)
		(layer "In4.Cu")
		(net "M_L_DQ<15>")
	)
	(segment
		(start 50.36566 -120.758712)
		(end 49.798732 -120.191784)
		(width 0.14224)
		(layer "In4.Cu")
		(net "M_L_DQ<15>")
	)
	(segment
		(start 51.974242 -117.931946)
		(end 52.26177 -117.931946)
		(width 0.14224)
		(layer "In4.Cu")
		(net "M_L_DQ<15>")
	)
	(segment
		(start 47.978568 -134.112)
		(end 47.927514 -134.163054)
		(width 0.14224)
		(layer "In4.Cu")
		(net "M_L_DQ<15>")
	)
	(segment
		(start 46.860714 -142.059152)
		(end 47.117762 -142.3162)
		(width 0.14224)
		(layer "In4.Cu")
		(net "M_L_DQ<15>")
	)
	(segment
		(start 58.621168 -104.893364)
		(end 58.621168 -108.876084)
		(width 0.14224)
		(layer "In4.Cu")
		(net "M_L_DQ<15>")
	)
	(segment
		(start 51.126644 -119.000524)
		(end 51.126644 -119.219472)
		(width 0.14224)
		(layer "In4.Cu")
		(net "M_L_DQ<15>")
	)
	(segment
		(start 58.621168 -110.422944)
		(end 51.686968 -117.357144)
		(width 0.14224)
		(layer "In4.Cu")
		(net "M_L_DQ<15>")
	)
	(segment
		(start 51.126644 -119.219472)
		(end 51.515772 -119.6086)
		(width 0.14224)
		(layer "In4.Cu")
		(net "M_L_DQ<15>")
	)
	(segment
		(start 47.526956 -139.932156)
		(end 47.098712 -140.3604)
		(width 0.14224)
		(layer "In4.Cu")
		(net "M_L_DQ<15>")
	)
	(segment
		(start 52.090574 -119.033798)
		(end 51.701446 -118.64467)
		(width 0.14224)
		(layer "In4.Cu")
		(net "M_L_DQ<15>")
	)
	(segment
		(start 49.798732 -120.191784)
		(end 49.579784 -120.191784)
		(width 0.14224)
		(layer "In4.Cu")
		(net "M_L_DQ<15>")
	)
	(segment
		(start 65.798192 -96.892872)
		(end 63.621158 -99.069906)
		(width 0.14224)
		(layer "In4.Cu")
		(net "M_L_DQ<15>")
	)
	(segment
		(start 70.265036 -92.442538)
		(end 70.271386 -92.453206)
		(width 0.0889)
		(layer "In4.Cu")
		(net "M_L_DQ<15>")
	)
	(segment
		(start 46.860714 -141.785848)
		(end 46.860714 -142.059152)
		(width 0.14224)
		(layer "In4.Cu")
		(net "M_L_DQ<15>")
	)
	(segment
		(start 51.515772 -119.6086)
		(end 51.515772 -119.827548)
		(width 0.14224)
		(layer "In4.Cu")
		(net "M_L_DQ<15>")
	)
	(segment
		(start 49.790858 -121.333514)
		(end 49.790858 -121.552462)
		(width 0.14224)
		(layer "In4.Cu")
		(net "M_L_DQ<15>")
	)
	(segment
		(start 54.531006 -115.950238)
		(end 54.81828 -116.237512)
		(width 0.14224)
		(layer "In4.Cu")
		(net "M_L_DQ<15>")
	)
	(segment
		(start 54.81828 -116.237512)
		(end 54.81828 -116.52504)
		(width 0.14224)
		(layer "In4.Cu")
		(net "M_L_DQ<15>")
	)
	(segment
		(start 57.639966 -109.185964)
		(end 57.639966 -109.539024)
		(width 0.14224)
		(layer "In4.Cu")
		(net "M_L_DQ<15>")
	)
	(segment
		(start 47.149512 -143.44015)
		(end 47.149512 -143.763746)
		(width 0.14224)
		(layer "In4.Cu")
		(net "M_L_DQ<15>")
	)
	(segment
		(start 47.902114 -128.455166)
		(end 47.902114 -129.859278)
		(width 0.14224)
		(layer "In4.Cu")
		(net "M_L_DQ<15>")
	)
	(segment
		(start 48.071278 -136.05129)
		(end 47.902114 -136.220454)
		(width 0.14224)
		(layer "In4.Cu")
		(net "M_L_DQ<15>")
	)
	(segment
		(start 63.621158 -99.069906)
		(end 63.621158 -99.893374)
		(width 0.14224)
		(layer "In4.Cu")
		(net "M_L_DQ<15>")
	)
	(segment
		(start 47.117762 -142.3162)
		(end 47.117762 -142.621)
		(width 0.14224)
		(layer "In4.Cu")
		(net "M_L_DQ<15>")
	)
	(segment
		(start 68.188586 -94.713806)
		(end 67.680332 -94.713806)
		(width 0.0889)
		(layer "In4.Cu")
		(net "M_L_DQ<15>")
	)
	(segment
		(start 49.22393 -120.547638)
		(end 49.22393 -120.766586)
		(width 0.14224)
		(layer "In4.Cu")
		(net "M_L_DQ<15>")
	)
	(segment
		(start 47.927514 -134.163054)
		(end 47.927514 -134.543038)
		(width 0.14224)
		(layer "In4.Cu")
		(net "M_L_DQ<15>")
	)
	(segment
		(start 49.579784 -120.191784)
		(end 49.22393 -120.547638)
		(width 0.14224)
		(layer "In4.Cu")
		(net "M_L_DQ<15>")
	)
	(segment
		(start 47.927514 -134.543038)
		(end 48.071278 -134.686802)
		(width 0.14224)
		(layer "In4.Cu")
		(net "M_L_DQ<15>")
	)
	(segment
		(start 57.794906 -109.031024)
		(end 57.639966 -109.185964)
		(width 0.14224)
		(layer "In4.Cu")
		(net "M_L_DQ<15>")
	)
	(segment
		(start 47.098712 -140.790168)
		(end 47.143162 -140.834618)
		(width 0.14224)
		(layer "In4.Cu")
		(net "M_L_DQ<15>")
	)
	(segment
		(start 47.902114 -129.859278)
		(end 48.130714 -130.087878)
		(width 0.14224)
		(layer "In4.Cu")
		(net "M_L_DQ<15>")
	)
	(segment
		(start 63.621158 -99.893374)
		(end 58.621168 -104.893364)
		(width 0.14224)
		(layer "In4.Cu")
		(net "M_L_DQ<15>")
	)
	(segment
		(start 47.851314 -131.953)
		(end 47.978568 -132.080254)
		(width 0.14224)
		(layer "In4.Cu")
		(net "M_L_DQ<15>")
	)
	(segment
		(start 47.117762 -142.621)
		(end 46.860714 -142.878048)
		(width 0.14224)
		(layer "In4.Cu")
		(net "M_L_DQ<15>")
	)
	(segment
		(start 67.680332 -94.713806)
		(end 65.798192 -96.595946)
		(width 0.0889)
		(layer "In4.Cu")
		(net "M_L_DQ<15>")
	)
	(segment
		(start 69.76618 -93.32849)
		(end 69.574918 -93.32849)
		(width 0.0889)
		(layer "In4.Cu")
		(net "M_L_DQ<15>")
	)
	(segment
		(start 47.902114 -138.8618)
		(end 47.902114 -139.590272)
		(width 0.14224)
		(layer "In4.Cu")
		(net "M_L_DQ<15>")
	)
	(segment
		(start 47.902114 -139.590272)
		(end 47.891192 -139.590272)
		(width 0.14224)
		(layer "In4.Cu")
		(net "M_L_DQ<15>")
	)
	(segment
		(start 47.978568 -136.652)
		(end 47.978568 -138.785346)
		(width 0.14224)
		(layer "In4.Cu")
		(net "M_L_DQ<15>")
	)
	(segment
		(start 47.143162 -141.5034)
		(end 46.860714 -141.785848)
		(width 0.14224)
		(layer "In4.Cu")
		(net "M_L_DQ<15>")
	)
	(segment
		(start 54.81828 -116.52504)
		(end 52.309522 -119.033798)
		(width 0.14224)
		(layer "In4.Cu")
		(net "M_L_DQ<15>")
	)
	(arc
		(start 70.611746 -91.25204)
		(mid 70.52427 -91.545594)
		(end 70.39229 -91.822016)
		(width 0.0889)
		(layer "In4.Cu")
		(net "M_L_DQ<15>")
	)
	(arc
		(start 70.271386 -92.453206)
		(mid 70.265209 -93.033138)
		(end 69.76618 -93.32849)
		(width 0.0889)
		(layer "In4.Cu")
		(net "M_L_DQ<15>")
	)
	(arc
		(start 70.265036 -92.042488)
		(mid 70.211566 -92.237551)
		(end 70.26021 -92.433902)
		(width 0.0889)
		(layer "In4.Cu")
		(net "M_L_DQ<15>")
	)
	(segment
		(start 47.549562 -147.27174)
		(end 47.549562 -146.304)
		(width 0.1651)
		(layer "F.Cu")
		(net "M_L_DQ<14>")
	)
	(segment
		(start 71.183246 -90.26144)
		(end 70.611746 -90.26144)
		(width 0.1651)
		(layer "F.Cu")
		(net "M_L_DQ<14>")
	)
	(segment
		(start 47.549562 -146.304)
		(end 47.681642 -146.17192)
		(width 0.1651)
		(layer "F.Cu")
		(net "M_L_DQ<14>")
	)
	(segment
		(start 47.681642 -146.17192)
		(end 47.681642 -145.95348)
		(width 0.1651)
		(layer "F.Cu")
		(net "M_L_DQ<14>")
	)
	(segment
		(start 47.681642 -145.95348)
		(end 47.549562 -145.8214)
		(width 0.1651)
		(layer "F.Cu")
		(net "M_L_DQ<14>")
	)
	(segment
		(start 47.549562 -145.8214)
		(end 47.549562 -145.516854)
		(width 0.1651)
		(layer "F.Cu")
		(net "M_L_DQ<14>")
	)
	(segment
		(start 47.549562 -145.516854)
		(end 47.549308 -145.5166)
		(width 0.1651)
		(layer "F.Cu")
		(net "M_L_DQ<14>")
	)
	(via
		(at 47.549308 -145.5166)
		(size 0.508)
		(drill 0.254)
		(layers "F.Cu" "B.Cu")
		(net "M_L_DQ<14>")
	)
	(via
		(at 46.699424 -141.213078)
		(size 0.508)
		(drill 0.254)
		(layers "F.Cu" "B.Cu")
		(net "M_L_DQ<14>")
	)
	(via
		(at 70.611746 -90.26144)
		(size 0.508)
		(drill 0.254)
		(layers "F.Cu" "B.Cu")
		(net "M_L_DQ<14>")
	)
	(segment
		(start 46.699424 -142.477236)
		(end 46.699424 -141.213078)
		(width 0.1651)
		(layer "B.Cu")
		(net "M_L_DQ<14>")
	)
	(segment
		(start 47.216314 -134.137146)
		(end 47.216314 -134.492238)
		(width 0.14224)
		(layer "In4.Cu")
		(net "M_L_DQ<14>")
	)
	(segment
		(start 54.255416 -112.307878)
		(end 54.517544 -112.307878)
		(width 0.14224)
		(layer "In4.Cu")
		(net "M_L_DQ<14>")
	)
	(segment
		(start 70.22719 -91.726766)
		(end 70.099936 -91.947238)
		(width 0.0889)
		(layer "In4.Cu")
		(net "M_L_DQ<14>")
	)
	(segment
		(start 46.530514 -140.070078)
		(end 46.530514 -141.044168)
		(width 0.14224)
		(layer "In4.Cu")
		(net "M_L_DQ<14>")
	)
	(segment
		(start 50.017172 -119.593868)
		(end 49.699672 -119.276368)
		(width 0.14224)
		(layer "In4.Cu")
		(net "M_L_DQ<14>")
	)
	(segment
		(start 57.210452 -110.935516)
		(end 51.051968 -117.094)
		(width 0.14224)
		(layer "In4.Cu")
		(net "M_L_DQ<14>")
	)
	(segment
		(start 48.689768 -120.024144)
		(end 48.689768 -126.769368)
		(width 0.14224)
		(layer "In4.Cu")
		(net "M_L_DQ<14>")
	)
	(segment
		(start 46.266354 -144.233646)
		(end 47.549308 -145.5166)
		(width 0.14224)
		(layer "In4.Cu")
		(net "M_L_DQ<14>")
	)
	(segment
		(start 47.267114 -139.333478)
		(end 46.530514 -140.070078)
		(width 0.14224)
		(layer "In4.Cu")
		(net "M_L_DQ<14>")
	)
	(segment
		(start 50.591974 -119.019066)
		(end 50.591974 -119.306594)
		(width 0.14224)
		(layer "In4.Cu")
		(net "M_L_DQ<14>")
	)
	(segment
		(start 70.099936 -92.537788)
		(end 70.104762 -92.546424)
		(width 0.0889)
		(layer "In4.Cu")
		(net "M_L_DQ<14>")
	)
	(segment
		(start 47.191168 -129.935224)
		(end 46.962568 -130.163824)
		(width 0.14224)
		(layer "In4.Cu")
		(net "M_L_DQ<14>")
	)
	(segment
		(start 48.689768 -126.769368)
		(end 47.191168 -128.267968)
		(width 0.14224)
		(layer "In4.Cu")
		(net "M_L_DQ<14>")
	)
	(segment
		(start 70.611746 -90.26144)
		(end 70.2818 -91.023186)
		(width 0.0889)
		(layer "In4.Cu")
		(net "M_L_DQ<14>")
	)
	(segment
		(start 46.962568 -130.163824)
		(end 46.962568 -131.205732)
		(width 0.14224)
		(layer "In4.Cu")
		(net "M_L_DQ<14>")
	)
	(segment
		(start 47.267114 -136.525)
		(end 47.114968 -136.677146)
		(width 0.14224)
		(layer "In4.Cu")
		(net "M_L_DQ<14>")
	)
	(segment
		(start 69.495924 -93.137736)
		(end 68.109846 -94.523814)
		(width 0.0889)
		(layer "In4.Cu")
		(net "M_L_DQ<14>")
	)
	(segment
		(start 50.3047 -119.593868)
		(end 50.017172 -119.593868)
		(width 0.14224)
		(layer "In4.Cu")
		(net "M_L_DQ<14>")
	)
	(segment
		(start 67.601592 -94.523814)
		(end 65.696592 -96.428814)
		(width 0.0889)
		(layer "In4.Cu")
		(net "M_L_DQ<14>")
	)
	(segment
		(start 46.962568 -131.205732)
		(end 47.216314 -131.459478)
		(width 0.14224)
		(layer "In4.Cu")
		(net "M_L_DQ<14>")
	)
	(segment
		(start 63.142368 -99.695)
		(end 57.935368 -104.902)
		(width 0.14224)
		(layer "In4.Cu")
		(net "M_L_DQ<14>")
	)
	(segment
		(start 63.142368 -98.650552)
		(end 63.142368 -99.695)
		(width 0.14224)
		(layer "In4.Cu")
		(net "M_L_DQ<14>")
	)
	(segment
		(start 47.114968 -138.811)
		(end 47.267114 -138.963146)
		(width 0.14224)
		(layer "In4.Cu")
		(net "M_L_DQ<14>")
	)
	(segment
		(start 65.364106 -96.428814)
		(end 63.142368 -98.650552)
		(width 0.14224)
		(layer "In4.Cu")
		(net "M_L_DQ<14>")
	)
	(segment
		(start 47.267114 -138.963146)
		(end 47.267114 -139.333478)
		(width 0.14224)
		(layer "In4.Cu")
		(net "M_L_DQ<14>")
	)
	(segment
		(start 57.210452 -110.477046)
		(end 57.210452 -110.935516)
		(width 0.14224)
		(layer "In4.Cu")
		(net "M_L_DQ<14>")
	)
	(segment
		(start 47.114968 -131.978146)
		(end 47.114968 -134.0358)
		(width 0.14224)
		(layer "In4.Cu")
		(net "M_L_DQ<14>")
	)
	(segment
		(start 47.216314 -134.492238)
		(end 46.943772 -134.76478)
		(width 0.14224)
		(layer "In4.Cu")
		(net "M_L_DQ<14>")
	)
	(segment
		(start 47.191168 -128.267968)
		(end 47.191168 -129.935224)
		(width 0.14224)
		(layer "In4.Cu")
		(net "M_L_DQ<14>")
	)
	(segment
		(start 49.699672 -119.276368)
		(end 49.437544 -119.276368)
		(width 0.14224)
		(layer "In4.Cu")
		(net "M_L_DQ<14>")
	)
	(segment
		(start 56.923178 -110.189772)
		(end 57.210452 -110.477046)
		(width 0.14224)
		(layer "In4.Cu")
		(net "M_L_DQ<14>")
	)
	(segment
		(start 46.530514 -141.044168)
		(end 46.699424 -141.213078)
		(width 0.14224)
		(layer "In4.Cu")
		(net "M_L_DQ<14>")
	)
	(segment
		(start 47.114968 -134.0358)
		(end 47.216314 -134.137146)
		(width 0.14224)
		(layer "In4.Cu")
		(net "M_L_DQ<14>")
	)
	(segment
		(start 56.63565 -110.189772)
		(end 56.923178 -110.189772)
		(width 0.14224)
		(layer "In4.Cu")
		(net "M_L_DQ<14>")
	)
	(segment
		(start 69.768212 -93.137736)
		(end 69.495924 -93.137736)
		(width 0.0889)
		(layer "In4.Cu")
		(net "M_L_DQ<14>")
	)
	(segment
		(start 53.968142 -111.707676)
		(end 53.968142 -112.020604)
		(width 0.14224)
		(layer "In4.Cu")
		(net "M_L_DQ<14>")
	)
	(segment
		(start 47.114968 -136.677146)
		(end 47.114968 -138.811)
		(width 0.14224)
		(layer "In4.Cu")
		(net "M_L_DQ<14>")
	)
	(segment
		(start 46.699424 -141.213078)
		(end 46.266354 -141.646148)
		(width 0.14224)
		(layer "In4.Cu")
		(net "M_L_DQ<14>")
	)
	(segment
		(start 53.968142 -112.020604)
		(end 54.255416 -112.307878)
		(width 0.14224)
		(layer "In4.Cu")
		(net "M_L_DQ<14>")
	)
	(segment
		(start 46.266354 -141.646148)
		(end 46.266354 -144.233646)
		(width 0.14224)
		(layer "In4.Cu")
		(net "M_L_DQ<14>")
	)
	(segment
		(start 54.517544 -112.307878)
		(end 56.63565 -110.189772)
		(width 0.14224)
		(layer "In4.Cu")
		(net "M_L_DQ<14>")
	)
	(segment
		(start 65.696592 -96.428814)
		(end 65.364106 -96.428814)
		(width 0.0889)
		(layer "In4.Cu")
		(net "M_L_DQ<14>")
	)
	(segment
		(start 47.216314 -131.8768)
		(end 47.114968 -131.978146)
		(width 0.14224)
		(layer "In4.Cu")
		(net "M_L_DQ<14>")
	)
	(segment
		(start 68.109846 -94.523814)
		(end 67.601592 -94.523814)
		(width 0.0889)
		(layer "In4.Cu")
		(net "M_L_DQ<14>")
	)
	(segment
		(start 46.943772 -134.76478)
		(end 46.943772 -135.932926)
		(width 0.14224)
		(layer "In4.Cu")
		(net "M_L_DQ<14>")
	)
	(segment
		(start 70.093586 -92.52712)
		(end 70.099936 -92.537788)
		(width 0.0889)
		(layer "In4.Cu")
		(net "M_L_DQ<14>")
	)
	(segment
		(start 70.2818 -91.023186)
		(end 70.265036 -91.051888)
		(width 0.0889)
		(layer "In4.Cu")
		(net "M_L_DQ<14>")
	)
	(segment
		(start 47.216314 -131.459478)
		(end 47.216314 -131.8768)
		(width 0.14224)
		(layer "In4.Cu")
		(net "M_L_DQ<14>")
	)
	(segment
		(start 51.051968 -117.094)
		(end 51.051968 -117.661944)
		(width 0.14224)
		(layer "In4.Cu")
		(net "M_L_DQ<14>")
	)
	(segment
		(start 50.274474 -118.439438)
		(end 50.274474 -118.701566)
		(width 0.14224)
		(layer "In4.Cu")
		(net "M_L_DQ<14>")
	)
	(segment
		(start 46.943772 -135.932926)
		(end 47.267114 -136.256268)
		(width 0.14224)
		(layer "In4.Cu")
		(net "M_L_DQ<14>")
	)
	(segment
		(start 57.935368 -104.902)
		(end 57.935368 -107.74045)
		(width 0.14224)
		(layer "In4.Cu")
		(net "M_L_DQ<14>")
	)
	(segment
		(start 50.274474 -118.701566)
		(end 50.591974 -119.019066)
		(width 0.14224)
		(layer "In4.Cu")
		(net "M_L_DQ<14>")
	)
	(segment
		(start 57.935368 -107.74045)
		(end 53.968142 -111.707676)
		(width 0.14224)
		(layer "In4.Cu")
		(net "M_L_DQ<14>")
	)
	(segment
		(start 51.051968 -117.661944)
		(end 50.274474 -118.439438)
		(width 0.14224)
		(layer "In4.Cu")
		(net "M_L_DQ<14>")
	)
	(segment
		(start 50.591974 -119.306594)
		(end 50.3047 -119.593868)
		(width 0.14224)
		(layer "In4.Cu")
		(net "M_L_DQ<14>")
	)
	(segment
		(start 47.267114 -136.256268)
		(end 47.267114 -136.525)
		(width 0.14224)
		(layer "In4.Cu")
		(net "M_L_DQ<14>")
	)
	(segment
		(start 49.437544 -119.276368)
		(end 48.689768 -120.024144)
		(width 0.14224)
		(layer "In4.Cu")
		(net "M_L_DQ<14>")
	)
	(arc
		(start 70.2437 -91.40952)
		(mid 70.27224 -91.570051)
		(end 70.22719 -91.726766)
		(width 0.0889)
		(layer "In4.Cu")
		(net "M_L_DQ<14>")
	)
	(arc
		(start 70.099936 -91.947238)
		(mid 70.020714 -92.236356)
		(end 70.093586 -92.52712)
		(width 0.0889)
		(layer "In4.Cu")
		(net "M_L_DQ<14>")
	)
	(arc
		(start 70.265036 -91.051888)
		(mid 70.212122 -91.228185)
		(end 70.2437 -91.40952)
		(width 0.0889)
		(layer "In4.Cu")
		(net "M_L_DQ<14>")
	)
	(arc
		(start 70.104762 -92.546424)
		(mid 70.101015 -92.93568)
		(end 69.768212 -93.137736)
		(width 0.0889)
		(layer "In4.Cu")
		(net "M_L_DQ<14>")
	)
	(segment
		(start 72.900286 -88.28024)
		(end 72.328786 -88.28024)
		(width 0.1651)
		(layer "F.Cu")
		(net "M_L_DQ<13>")
	)
	(segment
		(start 40.749474 -142.6718)
		(end 40.749474 -143.941546)
		(width 0.1651)
		(layer "F.Cu")
		(net "M_L_DQ<13>")
	)
	(via
		(at 72.328786 -88.28024)
		(size 0.508)
		(drill 0.254)
		(layers "F.Cu" "B.Cu")
		(net "M_L_DQ<13>")
	)
	(via
		(at 40.749474 -143.941546)
		(size 0.508)
		(drill 0.254)
		(layers "F.Cu" "B.Cu")
		(net "M_L_DQ<13>")
	)
	(via
		(at 41.523158 -139.932156)
		(size 0.508)
		(drill 0.254)
		(layers "F.Cu" "B.Cu")
		(net "M_L_DQ<13>")
	)
	(segment
		(start 41.599358 -137.877296)
		(end 41.599358 -139.855956)
		(width 0.1651)
		(layer "B.Cu")
		(net "M_L_DQ<13>")
	)
	(segment
		(start 41.599358 -139.855956)
		(end 41.523158 -139.932156)
		(width 0.1651)
		(layer "B.Cu")
		(net "M_L_DQ<13>")
	)
	(segment
		(start 40.910764 -142.985744)
		(end 40.910764 -143.297656)
		(width 0.14224)
		(layer "In4.Cu")
		(net "M_L_DQ<13>")
	)
	(segment
		(start 65.264792 -91.088464)
		(end 65.264792 -90.804746)
		(width 0.0889)
		(layer "In4.Cu")
		(net "M_L_DQ<13>")
	)
	(segment
		(start 41.832022 -134.568946)
		(end 41.832022 -133.531102)
		(width 0.14224)
		(layer "In4.Cu")
		(net "M_L_DQ<13>")
	)
	(segment
		(start 42.43832 -133.221222)
		(end 42.43832 -132.868162)
		(width 0.14224)
		(layer "In4.Cu")
		(net "M_L_DQ<13>")
	)
	(segment
		(start 44.854368 -114.8588)
		(end 53.638958 -106.07421)
		(width 0.14224)
		(layer "In4.Cu")
		(net "M_L_DQ<13>")
	)
	(segment
		(start 41.907714 -138.938254)
		(end 42.288968 -138.557)
		(width 0.14224)
		(layer "In4.Cu")
		(net "M_L_DQ<13>")
	)
	(segment
		(start 59.785758 -96.567498)
		(end 65.264792 -91.088464)
		(width 0.14224)
		(layer "In4.Cu")
		(net "M_L_DQ<13>")
	)
	(segment
		(start 41.523158 -139.932156)
		(end 41.907714 -139.5476)
		(width 0.14224)
		(layer "In4.Cu")
		(net "M_L_DQ<13>")
	)
	(segment
		(start 42.062908 -128.88341)
		(end 42.44467 -128.88341)
		(width 0.14224)
		(layer "In4.Cu")
		(net "M_L_DQ<13>")
	)
	(segment
		(start 42.43832 -132.868162)
		(end 42.28338 -132.713222)
		(width 0.14224)
		(layer "In4.Cu")
		(net "M_L_DQ<13>")
	)
	(segment
		(start 41.174162 -143.789146)
		(end 41.021762 -143.941546)
		(width 0.14224)
		(layer "In4.Cu")
		(net "M_L_DQ<13>")
	)
	(segment
		(start 42.060114 -135.853424)
		(end 42.060114 -134.797038)
		(width 0.14224)
		(layer "In4.Cu")
		(net "M_L_DQ<13>")
	)
	(segment
		(start 41.523158 -139.932156)
		(end 41.500806 -139.932156)
		(width 0.14224)
		(layer "In4.Cu")
		(net "M_L_DQ<13>")
	)
	(segment
		(start 42.28338 -132.713222)
		(end 41.986962 -132.713222)
		(width 0.14224)
		(layer "In4.Cu")
		(net "M_L_DQ<13>")
	)
	(segment
		(start 44.854368 -124.7394)
		(end 44.854368 -114.8588)
		(width 0.14224)
		(layer "In4.Cu")
		(net "M_L_DQ<13>")
	)
	(segment
		(start 41.907968 -129.8194)
		(end 41.907968 -129.03835)
		(width 0.14224)
		(layer "In4.Cu")
		(net "M_L_DQ<13>")
	)
	(segment
		(start 41.832022 -133.531102)
		(end 41.986962 -133.376162)
		(width 0.14224)
		(layer "In4.Cu")
		(net "M_L_DQ<13>")
	)
	(segment
		(start 40.910764 -143.297656)
		(end 41.174162 -143.561054)
		(width 0.14224)
		(layer "In4.Cu")
		(net "M_L_DQ<13>")
	)
	(segment
		(start 70.59676 -86.88959)
		(end 70.626732 -86.88959)
		(width 0.0889)
		(layer "In4.Cu")
		(net "M_L_DQ<13>")
	)
	(segment
		(start 41.021762 -143.941546)
		(end 40.749474 -143.941546)
		(width 0.14224)
		(layer "In4.Cu")
		(net "M_L_DQ<13>")
	)
	(segment
		(start 65.264792 -90.804746)
		(end 66.546984 -89.522554)
		(width 0.0889)
		(layer "In4.Cu")
		(net "M_L_DQ<13>")
	)
	(segment
		(start 41.907968 -128.06553)
		(end 41.907968 -127.6858)
		(width 0.14224)
		(layer "In4.Cu")
		(net "M_L_DQ<13>")
	)
	(segment
		(start 41.174162 -143.561054)
		(end 41.174162 -143.789146)
		(width 0.14224)
		(layer "In4.Cu")
		(net "M_L_DQ<13>")
	)
	(segment
		(start 41.984168 -131.383024)
		(end 41.984168 -129.8956)
		(width 0.14224)
		(layer "In4.Cu")
		(net "M_L_DQ<13>")
	)
	(segment
		(start 42.44467 -128.88341)
		(end 42.59961 -128.72847)
		(width 0.14224)
		(layer "In4.Cu")
		(net "M_L_DQ<13>")
	)
	(segment
		(start 41.986962 -133.376162)
		(end 42.28338 -133.376162)
		(width 0.14224)
		(layer "In4.Cu")
		(net "M_L_DQ<13>")
	)
	(segment
		(start 53.638958 -104.805734)
		(end 59.785758 -98.658934)
		(width 0.14224)
		(layer "In4.Cu")
		(net "M_L_DQ<13>")
	)
	(segment
		(start 59.785758 -98.658934)
		(end 59.785758 -96.567498)
		(width 0.14224)
		(layer "In4.Cu")
		(net "M_L_DQ<13>")
	)
	(segment
		(start 41.148762 -142.392654)
		(end 41.148762 -142.747746)
		(width 0.14224)
		(layer "In4.Cu")
		(net "M_L_DQ<13>")
	)
	(segment
		(start 41.984168 -129.8956)
		(end 41.907968 -129.8194)
		(width 0.14224)
		(layer "In4.Cu")
		(net "M_L_DQ<13>")
	)
	(segment
		(start 40.910764 -141.817344)
		(end 40.910764 -142.154656)
		(width 0.14224)
		(layer "In4.Cu")
		(net "M_L_DQ<13>")
	)
	(segment
		(start 71.448676 -87.384636)
		(end 71.481442 -87.384636)
		(width 0.0889)
		(layer "In4.Cu")
		(net "M_L_DQ<13>")
	)
	(segment
		(start 41.500806 -139.932156)
		(end 41.072562 -140.3604)
		(width 0.14224)
		(layer "In4.Cu")
		(net "M_L_DQ<13>")
	)
	(segment
		(start 66.546984 -89.522554)
		(end 66.546984 -89.17686)
		(width 0.0889)
		(layer "In4.Cu")
		(net "M_L_DQ<13>")
	)
	(segment
		(start 41.986962 -132.713222)
		(end 41.832022 -132.558282)
		(width 0.14224)
		(layer "In4.Cu")
		(net "M_L_DQ<13>")
	)
	(segment
		(start 41.072562 -140.9192)
		(end 41.199562 -141.0462)
		(width 0.14224)
		(layer "In4.Cu")
		(net "M_L_DQ<13>")
	)
	(segment
		(start 42.59961 -128.37541)
		(end 42.44467 -128.22047)
		(width 0.14224)
		(layer "In4.Cu")
		(net "M_L_DQ<13>")
	)
	(segment
		(start 42.288968 -138.557)
		(end 42.288968 -136.906254)
		(width 0.14224)
		(layer "In4.Cu")
		(net "M_L_DQ<13>")
	)
	(segment
		(start 41.148762 -142.747746)
		(end 40.910764 -142.985744)
		(width 0.14224)
		(layer "In4.Cu")
		(net "M_L_DQ<13>")
	)
	(segment
		(start 71.939912 -87.734394)
		(end 72.328786 -88.28024)
		(width 0.0889)
		(layer "In4.Cu")
		(net "M_L_DQ<13>")
	)
	(segment
		(start 40.910764 -142.154656)
		(end 41.148762 -142.392654)
		(width 0.14224)
		(layer "In4.Cu")
		(net "M_L_DQ<13>")
	)
	(segment
		(start 42.062908 -128.22047)
		(end 41.907968 -128.06553)
		(width 0.14224)
		(layer "In4.Cu")
		(net "M_L_DQ<13>")
	)
	(segment
		(start 68.87972 -87.88019)
		(end 68.912486 -87.88019)
		(width 0.0889)
		(layer "In4.Cu")
		(net "M_L_DQ<13>")
	)
	(segment
		(start 41.907714 -136.525)
		(end 41.907714 -136.005824)
		(width 0.14224)
		(layer "In4.Cu")
		(net "M_L_DQ<13>")
	)
	(segment
		(start 42.28338 -133.376162)
		(end 42.43832 -133.221222)
		(width 0.14224)
		(layer "In4.Cu")
		(net "M_L_DQ<13>")
	)
	(segment
		(start 68.02501 -88.375236)
		(end 68.057776 -88.375236)
		(width 0.0889)
		(layer "In4.Cu")
		(net "M_L_DQ<13>")
	)
	(segment
		(start 66.853054 -88.87079)
		(end 67.195446 -88.87079)
		(width 0.0889)
		(layer "In4.Cu")
		(net "M_L_DQ<13>")
	)
	(segment
		(start 41.907714 -139.5476)
		(end 41.907714 -138.938254)
		(width 0.14224)
		(layer "In4.Cu")
		(net "M_L_DQ<13>")
	)
	(segment
		(start 41.907968 -127.6858)
		(end 44.854368 -124.7394)
		(width 0.14224)
		(layer "In4.Cu")
		(net "M_L_DQ<13>")
	)
	(segment
		(start 41.199562 -141.528546)
		(end 40.910764 -141.817344)
		(width 0.14224)
		(layer "In4.Cu")
		(net "M_L_DQ<13>")
	)
	(segment
		(start 41.907714 -136.005824)
		(end 42.060114 -135.853424)
		(width 0.14224)
		(layer "In4.Cu")
		(net "M_L_DQ<13>")
	)
	(segment
		(start 41.832022 -132.558282)
		(end 41.832022 -131.53517)
		(width 0.14224)
		(layer "In4.Cu")
		(net "M_L_DQ<13>")
	)
	(segment
		(start 42.44467 -128.22047)
		(end 42.062908 -128.22047)
		(width 0.14224)
		(layer "In4.Cu")
		(net "M_L_DQ<13>")
	)
	(segment
		(start 42.060114 -134.797038)
		(end 41.832022 -134.568946)
		(width 0.14224)
		(layer "In4.Cu")
		(net "M_L_DQ<13>")
	)
	(segment
		(start 41.907968 -129.03835)
		(end 42.062908 -128.88341)
		(width 0.14224)
		(layer "In4.Cu")
		(net "M_L_DQ<13>")
	)
	(segment
		(start 42.288968 -136.906254)
		(end 41.907714 -136.525)
		(width 0.14224)
		(layer "In4.Cu")
		(net "M_L_DQ<13>")
	)
	(segment
		(start 42.59961 -128.72847)
		(end 42.59961 -128.37541)
		(width 0.14224)
		(layer "In4.Cu")
		(net "M_L_DQ<13>")
	)
	(segment
		(start 41.072562 -140.3604)
		(end 41.072562 -140.9192)
		(width 0.14224)
		(layer "In4.Cu")
		(net "M_L_DQ<13>")
	)
	(segment
		(start 53.638958 -106.07421)
		(end 53.638958 -104.805734)
		(width 0.14224)
		(layer "In4.Cu")
		(net "M_L_DQ<13>")
	)
	(segment
		(start 66.546984 -89.17686)
		(end 66.853054 -88.87079)
		(width 0.0889)
		(layer "In4.Cu")
		(net "M_L_DQ<13>")
	)
	(segment
		(start 41.199562 -141.0462)
		(end 41.199562 -141.528546)
		(width 0.14224)
		(layer "In4.Cu")
		(net "M_L_DQ<13>")
	)
	(segment
		(start 41.832022 -131.53517)
		(end 41.984168 -131.383024)
		(width 0.14224)
		(layer "In4.Cu")
		(net "M_L_DQ<13>")
	)
	(segment
		(start 69.74205 -87.384636)
		(end 69.774816 -87.384636)
		(width 0.0889)
		(layer "In4.Cu")
		(net "M_L_DQ<13>")
	)
	(arc
		(start 71.816976 -87.584788)
		(mid 71.872263 -87.664672)
		(end 71.939912 -87.734394)
		(width 0.0889)
		(layer "In4.Cu")
		(net "M_L_DQ<13>")
	)
	(arc
		(start 67.689476 -88.575388)
		(mid 67.831159 -88.431584)
		(end 68.02501 -88.375236)
		(width 0.0889)
		(layer "In4.Cu")
		(net "M_L_DQ<13>")
	)
	(arc
		(start 68.547996 -88.080088)
		(mid 68.688075 -87.937352)
		(end 68.87972 -87.88019)
		(width 0.0889)
		(layer "In4.Cu")
		(net "M_L_DQ<13>")
	)
	(arc
		(start 69.406516 -87.584788)
		(mid 69.548199 -87.440984)
		(end 69.74205 -87.384636)
		(width 0.0889)
		(layer "In4.Cu")
		(net "M_L_DQ<13>")
	)
	(arc
		(start 70.958456 -87.089488)
		(mid 71.16546 -87.300352)
		(end 71.448676 -87.384636)
		(width 0.0889)
		(layer "In4.Cu")
		(net "M_L_DQ<13>")
	)
	(arc
		(start 67.195446 -88.87079)
		(mid 67.48087 -88.787323)
		(end 67.689476 -88.575388)
		(width 0.0889)
		(layer "In4.Cu")
		(net "M_L_DQ<13>")
	)
	(arc
		(start 70.265036 -87.089488)
		(mid 70.405115 -86.946752)
		(end 70.59676 -86.88959)
		(width 0.0889)
		(layer "In4.Cu")
		(net "M_L_DQ<13>")
	)
	(arc
		(start 70.626732 -86.88959)
		(mid 70.818374 -86.946756)
		(end 70.958456 -87.089488)
		(width 0.0889)
		(layer "In4.Cu")
		(net "M_L_DQ<13>")
	)
	(arc
		(start 68.057776 -88.375236)
		(mid 68.340993 -88.290955)
		(end 68.547996 -88.080088)
		(width 0.0889)
		(layer "In4.Cu")
		(net "M_L_DQ<13>")
	)
	(arc
		(start 71.481442 -87.384636)
		(mid 71.675292 -87.440986)
		(end 71.816976 -87.584788)
		(width 0.0889)
		(layer "In4.Cu")
		(net "M_L_DQ<13>")
	)
	(arc
		(start 68.912486 -87.88019)
		(mid 69.19791 -87.796723)
		(end 69.406516 -87.584788)
		(width 0.0889)
		(layer "In4.Cu")
		(net "M_L_DQ<13>")
	)
	(arc
		(start 69.774816 -87.384636)
		(mid 70.058033 -87.300355)
		(end 70.265036 -87.089488)
		(width 0.0889)
		(layer "In4.Cu")
		(net "M_L_DQ<13>")
	)
	(segment
		(start 41.599358 -145.946368)
		(end 41.501314 -145.415)
		(width 0.1651)
		(layer "F.Cu")
		(net "M_L_DQ<12>")
	)
	(segment
		(start 41.599358 -147.27174)
		(end 41.599358 -145.946368)
		(width 0.1651)
		(layer "F.Cu")
		(net "M_L_DQ<12>")
	)
	(segment
		(start 73.758806 -88.775286)
		(end 73.187306 -88.775286)
		(width 0.1651)
		(layer "F.Cu")
		(net "M_L_DQ<12>")
	)
	(via
		(at 40.749474 -141.213078)
		(size 0.508)
		(drill 0.254)
		(layers "F.Cu" "B.Cu")
		(net "M_L_DQ<12>")
	)
	(via
		(at 41.501314 -145.415)
		(size 0.508)
		(drill 0.254)
		(layers "F.Cu" "B.Cu")
		(net "M_L_DQ<12>")
	)
	(via
		(at 73.187306 -88.775286)
		(size 0.508)
		(drill 0.254)
		(layers "F.Cu" "B.Cu")
		(net "M_L_DQ<12>")
	)
	(segment
		(start 40.749474 -142.477236)
		(end 40.749474 -141.213078)
		(width 0.1651)
		(layer "B.Cu")
		(net "M_L_DQ<12>")
	)
	(segment
		(start 41.057068 -136.002522)
		(end 41.057068 -134.6581)
		(width 0.14224)
		(layer "In4.Cu")
		(net "M_L_DQ<12>")
	)
	(segment
		(start 40.316404 -141.646148)
		(end 40.749474 -141.213078)
		(width 0.14224)
		(layer "In4.Cu")
		(net "M_L_DQ<12>")
	)
	(segment
		(start 68.018406 -88.184736)
		(end 68.051172 -88.184736)
		(width 0.0889)
		(layer "In4.Cu")
		(net "M_L_DQ<12>")
	)
	(segment
		(start 72.840596 -87.984838)
		(end 73.187306 -88.775286)
		(width 0.0889)
		(layer "In4.Cu")
		(net "M_L_DQ<12>")
	)
	(segment
		(start 41.501314 -145.415)
		(end 41.250362 -145.415)
		(width 0.14224)
		(layer "In4.Cu")
		(net "M_L_DQ<12>")
	)
	(segment
		(start 53.160168 -104.60736)
		(end 59.306968 -98.46056)
		(width 0.14224)
		(layer "In4.Cu")
		(net "M_L_DQ<12>")
	)
	(segment
		(start 41.299892 -127.303276)
		(end 44.193968 -124.4092)
		(width 0.14224)
		(layer "In4.Cu")
		(net "M_L_DQ<12>")
	)
	(segment
		(start 44.193968 -114.8334)
		(end 53.160168 -105.8672)
		(width 0.14224)
		(layer "In4.Cu")
		(net "M_L_DQ<12>")
	)
	(segment
		(start 68.873116 -87.68969)
		(end 68.905882 -87.68969)
		(width 0.0889)
		(layer "In4.Cu")
		(net "M_L_DQ<12>")
	)
	(segment
		(start 40.316404 -144.17929)
		(end 40.316404 -141.646148)
		(width 0.14224)
		(layer "In4.Cu")
		(net "M_L_DQ<12>")
	)
	(segment
		(start 64.116712 -91.3384)
		(end 64.842898 -90.612214)
		(width 0.14224)
		(layer "In4.Cu")
		(net "M_L_DQ<12>")
	)
	(segment
		(start 66.774822 -88.68029)
		(end 67.188842 -88.68029)
		(width 0.0889)
		(layer "In4.Cu")
		(net "M_L_DQ<12>")
	)
	(segment
		(start 41.234614 -139.358878)
		(end 41.234614 -136.180068)
		(width 0.14224)
		(layer "In4.Cu")
		(net "M_L_DQ<12>")
	)
	(segment
		(start 66.356992 -89.443814)
		(end 66.356992 -89.09812)
		(width 0.0889)
		(layer "In4.Cu")
		(net "M_L_DQ<12>")
	)
	(segment
		(start 41.250362 -145.415)
		(end 40.474392 -144.63903)
		(width 0.14224)
		(layer "In4.Cu")
		(net "M_L_DQ<12>")
	)
	(segment
		(start 41.063926 -129.941066)
		(end 41.299892 -129.7051)
		(width 0.14224)
		(layer "In4.Cu")
		(net "M_L_DQ<12>")
	)
	(segment
		(start 41.299892 -129.7051)
		(end 41.299892 -127.303276)
		(width 0.14224)
		(layer "In4.Cu")
		(net "M_L_DQ<12>")
	)
	(segment
		(start 40.474392 -144.337278)
		(end 40.316404 -144.17929)
		(width 0.14224)
		(layer "In4.Cu")
		(net "M_L_DQ<12>")
	)
	(segment
		(start 66.356992 -89.09812)
		(end 66.774822 -88.68029)
		(width 0.0889)
		(layer "In4.Cu")
		(net "M_L_DQ<12>")
	)
	(segment
		(start 70.590156 -86.69909)
		(end 70.633336 -86.69909)
		(width 0.0889)
		(layer "In4.Cu")
		(net "M_L_DQ<12>")
	)
	(segment
		(start 41.234614 -136.180068)
		(end 41.057068 -136.002522)
		(width 0.14224)
		(layer "In4.Cu")
		(net "M_L_DQ<12>")
	)
	(segment
		(start 71.45528 -87.194136)
		(end 71.488046 -87.194136)
		(width 0.0889)
		(layer "In4.Cu")
		(net "M_L_DQ<12>")
	)
	(segment
		(start 40.474392 -144.63903)
		(end 40.474392 -144.337278)
		(width 0.14224)
		(layer "In4.Cu")
		(net "M_L_DQ<12>")
	)
	(segment
		(start 53.160168 -105.8672)
		(end 53.160168 -104.60736)
		(width 0.14224)
		(layer "In4.Cu")
		(net "M_L_DQ<12>")
	)
	(segment
		(start 72.31761 -87.68969)
		(end 72.350376 -87.68969)
		(width 0.0889)
		(layer "In4.Cu")
		(net "M_L_DQ<12>")
	)
	(segment
		(start 44.193968 -124.4092)
		(end 44.193968 -114.8334)
		(width 0.14224)
		(layer "In4.Cu")
		(net "M_L_DQ<12>")
	)
	(segment
		(start 69.735446 -87.194136)
		(end 69.768212 -87.194136)
		(width 0.0889)
		(layer "In4.Cu")
		(net "M_L_DQ<12>")
	)
	(segment
		(start 41.057068 -134.6581)
		(end 41.247314 -134.467854)
		(width 0.14224)
		(layer "In4.Cu")
		(net "M_L_DQ<12>")
	)
	(segment
		(start 65.188592 -90.612214)
		(end 66.356992 -89.443814)
		(width 0.0889)
		(layer "In4.Cu")
		(net "M_L_DQ<12>")
	)
	(segment
		(start 64.842898 -90.612214)
		(end 65.188592 -90.612214)
		(width 0.0889)
		(layer "In4.Cu")
		(net "M_L_DQ<12>")
	)
	(segment
		(start 63.904368 -91.3384)
		(end 64.116712 -91.3384)
		(width 0.14224)
		(layer "In4.Cu")
		(net "M_L_DQ<12>")
	)
	(segment
		(start 40.652954 -139.940538)
		(end 41.234614 -139.358878)
		(width 0.14224)
		(layer "In4.Cu")
		(net "M_L_DQ<12>")
	)
	(segment
		(start 41.247314 -134.467854)
		(end 41.247314 -131.432554)
		(width 0.14224)
		(layer "In4.Cu")
		(net "M_L_DQ<12>")
	)
	(segment
		(start 59.306968 -98.46056)
		(end 59.306968 -95.9358)
		(width 0.14224)
		(layer "In4.Cu")
		(net "M_L_DQ<12>")
	)
	(segment
		(start 59.306968 -95.9358)
		(end 63.904368 -91.3384)
		(width 0.14224)
		(layer "In4.Cu")
		(net "M_L_DQ<12>")
	)
	(segment
		(start 40.749474 -141.213078)
		(end 40.652954 -141.116558)
		(width 0.14224)
		(layer "In4.Cu")
		(net "M_L_DQ<12>")
	)
	(segment
		(start 40.652954 -141.116558)
		(end 40.652954 -139.940538)
		(width 0.14224)
		(layer "In4.Cu")
		(net "M_L_DQ<12>")
	)
	(segment
		(start 41.247314 -131.432554)
		(end 41.063926 -131.249166)
		(width 0.14224)
		(layer "In4.Cu")
		(net "M_L_DQ<12>")
	)
	(segment
		(start 41.063926 -131.249166)
		(end 41.063926 -129.941066)
		(width 0.14224)
		(layer "In4.Cu")
		(net "M_L_DQ<12>")
	)
	(arc
		(start 67.188842 -88.68029)
		(mid 67.382692 -88.62394)
		(end 67.524376 -88.480138)
		(width 0.0889)
		(layer "In4.Cu")
		(net "M_L_DQ<12>")
	)
	(arc
		(start 70.099936 -86.994238)
		(mid 70.30694 -86.783374)
		(end 70.590156 -86.69909)
		(width 0.0889)
		(layer "In4.Cu")
		(net "M_L_DQ<12>")
	)
	(arc
		(start 68.382896 -87.984838)
		(mid 68.5899 -87.773974)
		(end 68.873116 -87.68969)
		(width 0.0889)
		(layer "In4.Cu")
		(net "M_L_DQ<12>")
	)
	(arc
		(start 68.905882 -87.68969)
		(mid 69.099732 -87.63334)
		(end 69.241416 -87.489538)
		(width 0.0889)
		(layer "In4.Cu")
		(net "M_L_DQ<12>")
	)
	(arc
		(start 67.524376 -88.480138)
		(mid 67.732984 -88.268206)
		(end 68.018406 -88.184736)
		(width 0.0889)
		(layer "In4.Cu")
		(net "M_L_DQ<12>")
	)
	(arc
		(start 70.633336 -86.69909)
		(mid 70.916553 -86.783371)
		(end 71.123556 -86.994238)
		(width 0.0889)
		(layer "In4.Cu")
		(net "M_L_DQ<12>")
	)
	(arc
		(start 71.982076 -87.489538)
		(mid 72.123759 -87.633342)
		(end 72.31761 -87.68969)
		(width 0.0889)
		(layer "In4.Cu")
		(net "M_L_DQ<12>")
	)
	(arc
		(start 71.488046 -87.194136)
		(mid 71.77347 -87.277603)
		(end 71.982076 -87.489538)
		(width 0.0889)
		(layer "In4.Cu")
		(net "M_L_DQ<12>")
	)
	(arc
		(start 72.350376 -87.68969)
		(mid 72.633593 -87.773971)
		(end 72.840596 -87.984838)
		(width 0.0889)
		(layer "In4.Cu")
		(net "M_L_DQ<12>")
	)
	(arc
		(start 71.123556 -86.994238)
		(mid 71.263635 -87.136974)
		(end 71.45528 -87.194136)
		(width 0.0889)
		(layer "In4.Cu")
		(net "M_L_DQ<12>")
	)
	(arc
		(start 68.051172 -88.184736)
		(mid 68.242814 -88.12757)
		(end 68.382896 -87.984838)
		(width 0.0889)
		(layer "In4.Cu")
		(net "M_L_DQ<12>")
	)
	(arc
		(start 69.768212 -87.194136)
		(mid 69.959854 -87.13697)
		(end 70.099936 -86.994238)
		(width 0.0889)
		(layer "In4.Cu")
		(net "M_L_DQ<12>")
	)
	(arc
		(start 69.241416 -87.489538)
		(mid 69.450024 -87.277606)
		(end 69.735446 -87.194136)
		(width 0.0889)
		(layer "In4.Cu")
		(net "M_L_DQ<12>")
	)
	(segment
		(start 48.399446 -142.6718)
		(end 48.399446 -143.941546)
		(width 0.1651)
		(layer "F.Cu")
		(net "M_L_DQ<11>")
	)
	(segment
		(start 72.041766 -91.747086)
		(end 71.470266 -91.747086)
		(width 0.1651)
		(layer "F.Cu")
		(net "M_L_DQ<11>")
	)
	(via
		(at 49.24933 -139.932156)
		(size 0.508)
		(drill 0.254)
		(layers "F.Cu" "B.Cu")
		(net "M_L_DQ<11>")
	)
	(via
		(at 71.470266 -91.747086)
		(size 0.508)
		(drill 0.254)
		(layers "F.Cu" "B.Cu")
		(net "M_L_DQ<11>")
	)
	(via
		(at 48.399446 -143.941546)
		(size 0.508)
		(drill 0.254)
		(layers "F.Cu" "B.Cu")
		(net "M_L_DQ<11>")
	)
	(segment
		(start 49.24933 -137.877296)
		(end 49.24933 -139.932156)
		(width 0.1651)
		(layer "B.Cu")
		(net "M_L_DQ<11>")
	)
	(segment
		(start 49.249584 -137.877296)
		(end 49.24933 -137.877296)
		(width 0.1651)
		(layer "B.Cu")
		(net "M_L_DQ<11>")
	)
	(segment
		(start 49.578768 -128.5748)
		(end 49.578768 -129.935732)
		(width 0.14224)
		(layer "In4.Cu")
		(net "M_L_DQ<11>")
	)
	(segment
		(start 66.368168 -98.8822)
		(end 60.881768 -104.3686)
		(width 0.14224)
		(layer "In4.Cu")
		(net "M_L_DQ<11>")
	)
	(segment
		(start 48.817784 -142.621)
		(end 48.560736 -142.878048)
		(width 0.14224)
		(layer "In4.Cu")
		(net "M_L_DQ<11>")
	)
	(segment
		(start 50.931826 -126.600204)
		(end 51.069748 -126.738126)
		(width 0.14224)
		(layer "In4.Cu")
		(net "M_L_DQ<11>")
	)
	(segment
		(start 51.178968 -123.620022)
		(end 51.178968 -124.026422)
		(width 0.14224)
		(layer "In4.Cu")
		(net "M_L_DQ<11>")
	)
	(segment
		(start 49.832514 -134.758938)
		(end 49.832514 -135.966708)
		(width 0.14224)
		(layer "In4.Cu")
		(net "M_L_DQ<11>")
	)
	(segment
		(start 49.680368 -131.965954)
		(end 49.680368 -134.0612)
		(width 0.14224)
		(layer "In4.Cu")
		(net "M_L_DQ<11>")
	)
	(segment
		(start 60.881768 -105.842308)
		(end 60.881768 -106.195368)
		(width 0.14224)
		(layer "In4.Cu")
		(net "M_L_DQ<11>")
	)
	(segment
		(start 58.692796 -113.510314)
		(end 60.385452 -111.817658)
		(width 0.14224)
		(layer "In4.Cu")
		(net "M_L_DQ<11>")
	)
	(segment
		(start 60.960254 -112.39246)
		(end 51.178968 -122.173746)
		(width 0.14224)
		(layer "In4.Cu")
		(net "M_L_DQ<11>")
	)
	(segment
		(start 49.616614 -131.305554)
		(end 49.616614 -131.9022)
		(width 0.14224)
		(layer "In4.Cu")
		(net "M_L_DQ<11>")
	)
	(segment
		(start 49.756314 -131.165854)
		(end 49.616614 -131.305554)
		(width 0.14224)
		(layer "In4.Cu")
		(net "M_L_DQ<11>")
	)
	(segment
		(start 48.560736 -141.785848)
		(end 48.560736 -142.059152)
		(width 0.14224)
		(layer "In4.Cu")
		(net "M_L_DQ<11>")
	)
	(segment
		(start 70.6247 -94.81439)
		(end 70.59676 -94.81439)
		(width 0.0889)
		(layer "In4.Cu")
		(net "M_L_DQ<11>")
	)
	(segment
		(start 51.178968 -124.026422)
		(end 50.975768 -124.229622)
		(width 0.14224)
		(layer "In4.Cu")
		(net "M_L_DQ<11>")
	)
	(segment
		(start 49.616614 -131.9022)
		(end 49.680368 -131.965954)
		(width 0.14224)
		(layer "In4.Cu")
		(net "M_L_DQ<11>")
	)
	(segment
		(start 60.960254 -112.104932)
		(end 60.960254 -112.39246)
		(width 0.14224)
		(layer "In4.Cu")
		(net "M_L_DQ<11>")
	)
	(segment
		(start 50.45329 -123.220226)
		(end 50.649886 -123.416822)
		(width 0.14224)
		(layer "In4.Cu")
		(net "M_L_DQ<11>")
	)
	(segment
		(start 50.473356 -124.432822)
		(end 50.473356 -124.839222)
		(width 0.14224)
		(layer "In4.Cu")
		(net "M_L_DQ<11>")
	)
	(segment
		(start 50.473356 -124.839222)
		(end 50.676556 -125.042422)
		(width 0.14224)
		(layer "In4.Cu")
		(net "M_L_DQ<11>")
	)
	(segment
		(start 59.930284 -106.505248)
		(end 59.930284 -106.858308)
		(width 0.14224)
		(layer "In4.Cu")
		(net "M_L_DQ<11>")
	)
	(segment
		(start 48.798734 -140.790168)
		(end 48.843184 -140.834618)
		(width 0.14224)
		(layer "In4.Cu")
		(net "M_L_DQ<11>")
	)
	(segment
		(start 50.975768 -125.855222)
		(end 50.53203 -125.855222)
		(width 0.14224)
		(layer "In4.Cu")
		(net "M_L_DQ<11>")
	)
	(segment
		(start 48.560736 -142.878048)
		(end 48.560736 -143.151352)
		(width 0.14224)
		(layer "In4.Cu")
		(net "M_L_DQ<11>")
	)
	(segment
		(start 49.24933 -139.932156)
		(end 49.226978 -139.932156)
		(width 0.14224)
		(layer "In4.Cu")
		(net "M_L_DQ<11>")
	)
	(segment
		(start 71.123556 -93.928438)
		(end 71.129906 -93.939106)
		(width 0.0889)
		(layer "In4.Cu")
		(net "M_L_DQ<11>")
	)
	(segment
		(start 50.975768 -125.042422)
		(end 51.178968 -125.245622)
		(width 0.14224)
		(layer "In4.Cu")
		(net "M_L_DQ<11>")
	)
	(segment
		(start 49.680368 -134.0612)
		(end 49.616614 -134.124954)
		(width 0.14224)
		(layer "In4.Cu")
		(net "M_L_DQ<11>")
	)
	(segment
		(start 49.756314 -130.113278)
		(end 49.756314 -131.165854)
		(width 0.14224)
		(layer "In4.Cu")
		(net "M_L_DQ<11>")
	)
	(segment
		(start 48.849534 -143.44015)
		(end 48.849534 -143.763746)
		(width 0.14224)
		(layer "In4.Cu")
		(net "M_L_DQ<11>")
	)
	(segment
		(start 60.085224 -105.687368)
		(end 60.726828 -105.687368)
		(width 0.14224)
		(layer "In4.Cu")
		(net "M_L_DQ<11>")
	)
	(segment
		(start 48.817784 -142.3162)
		(end 48.817784 -142.621)
		(width 0.14224)
		(layer "In4.Cu")
		(net "M_L_DQ<11>")
	)
	(segment
		(start 51.069748 -127.08382)
		(end 49.578768 -128.5748)
		(width 0.14224)
		(layer "In4.Cu")
		(net "M_L_DQ<11>")
	)
	(segment
		(start 50.649886 -123.416822)
		(end 50.975768 -123.416822)
		(width 0.14224)
		(layer "In4.Cu")
		(net "M_L_DQ<11>")
	)
	(segment
		(start 60.881768 -106.195368)
		(end 60.726828 -106.350308)
		(width 0.14224)
		(layer "In4.Cu")
		(net "M_L_DQ<11>")
	)
	(segment
		(start 60.085224 -106.350308)
		(end 59.930284 -106.505248)
		(width 0.14224)
		(layer "In4.Cu")
		(net "M_L_DQ<11>")
	)
	(segment
		(start 59.930284 -105.532428)
		(end 60.085224 -105.687368)
		(width 0.14224)
		(layer "In4.Cu")
		(net "M_L_DQ<11>")
	)
	(segment
		(start 50.676556 -125.042422)
		(end 50.975768 -125.042422)
		(width 0.14224)
		(layer "In4.Cu")
		(net "M_L_DQ<11>")
	)
	(segment
		(start 59.930284 -106.858308)
		(end 60.085224 -107.013248)
		(width 0.14224)
		(layer "In4.Cu")
		(net "M_L_DQ<11>")
	)
	(segment
		(start 49.578514 -139.61618)
		(end 49.24933 -139.945364)
		(width 0.14224)
		(layer "In4.Cu")
		(net "M_L_DQ<11>")
	)
	(segment
		(start 48.843184 -140.834618)
		(end 48.843184 -141.5034)
		(width 0.14224)
		(layer "In4.Cu")
		(net "M_L_DQ<11>")
	)
	(segment
		(start 60.881768 -107.168188)
		(end 60.881768 -110.171738)
		(width 0.14224)
		(layer "In4.Cu")
		(net "M_L_DQ<11>")
	)
	(segment
		(start 60.085224 -107.013248)
		(end 60.726828 -107.013248)
		(width 0.14224)
		(layer "In4.Cu")
		(net "M_L_DQ<11>")
	)
	(segment
		(start 51.178968 -122.400822)
		(end 50.975768 -122.604022)
		(width 0.14224)
		(layer "In4.Cu")
		(net "M_L_DQ<11>")
	)
	(segment
		(start 50.551588 -126.600204)
		(end 50.931826 -126.600204)
		(width 0.14224)
		(layer "In4.Cu")
		(net "M_L_DQ<11>")
	)
	(segment
		(start 49.616614 -134.543038)
		(end 49.832514 -134.758938)
		(width 0.14224)
		(layer "In4.Cu")
		(net "M_L_DQ<11>")
	)
	(segment
		(start 60.085224 -105.024428)
		(end 59.930284 -105.179368)
		(width 0.14224)
		(layer "In4.Cu")
		(net "M_L_DQ<11>")
	)
	(segment
		(start 48.849534 -143.763746)
		(end 48.671734 -143.941546)
		(width 0.14224)
		(layer "In4.Cu")
		(net "M_L_DQ<11>")
	)
	(segment
		(start 50.45329 -122.813826)
		(end 50.45329 -123.220226)
		(width 0.14224)
		(layer "In4.Cu")
		(net "M_L_DQ<11>")
	)
	(segment
		(start 58.117994 -113.22304)
		(end 58.405268 -113.510314)
		(width 0.14224)
		(layer "In4.Cu")
		(net "M_L_DQ<11>")
	)
	(segment
		(start 49.578514 -138.887454)
		(end 49.578514 -139.61618)
		(width 0.14224)
		(layer "In4.Cu")
		(net "M_L_DQ<11>")
	)
	(segment
		(start 51.069748 -126.738126)
		(end 51.069748 -127.08382)
		(width 0.14224)
		(layer "In4.Cu")
		(net "M_L_DQ<11>")
	)
	(segment
		(start 67.299332 -97.193608)
		(end 66.368168 -98.124772)
		(width 0.14224)
		(layer "In4.Cu")
		(net "M_L_DQ<11>")
	)
	(segment
		(start 66.368168 -98.124772)
		(end 66.368168 -98.8822)
		(width 0.14224)
		(layer "In4.Cu")
		(net "M_L_DQ<11>")
	)
	(segment
		(start 59.930284 -105.179368)
		(end 59.930284 -105.532428)
		(width 0.14224)
		(layer "In4.Cu")
		(net "M_L_DQ<11>")
	)
	(segment
		(start 49.578514 -136.525)
		(end 49.680368 -136.626854)
		(width 0.14224)
		(layer "In4.Cu")
		(net "M_L_DQ<11>")
	)
	(segment
		(start 60.881768 -104.3686)
		(end 60.881768 -104.869488)
		(width 0.14224)
		(layer "In4.Cu")
		(net "M_L_DQ<11>")
	)
	(segment
		(start 48.843184 -141.5034)
		(end 48.560736 -141.785848)
		(width 0.14224)
		(layer "In4.Cu")
		(net "M_L_DQ<11>")
	)
	(segment
		(start 48.798734 -140.3604)
		(end 48.798734 -140.790168)
		(width 0.14224)
		(layer "In4.Cu")
		(net "M_L_DQ<11>")
	)
	(segment
		(start 50.53203 -125.855222)
		(end 50.372518 -126.014734)
		(width 0.14224)
		(layer "In4.Cu")
		(net "M_L_DQ<11>")
	)
	(segment
		(start 50.372518 -126.421134)
		(end 50.551588 -126.600204)
		(width 0.14224)
		(layer "In4.Cu")
		(net "M_L_DQ<11>")
	)
	(segment
		(start 60.726828 -107.013248)
		(end 60.881768 -107.168188)
		(width 0.14224)
		(layer "In4.Cu")
		(net "M_L_DQ<11>")
	)
	(segment
		(start 48.671734 -143.941546)
		(end 48.399446 -143.941546)
		(width 0.14224)
		(layer "In4.Cu")
		(net "M_L_DQ<11>")
	)
	(segment
		(start 50.975768 -123.416822)
		(end 51.178968 -123.620022)
		(width 0.14224)
		(layer "In4.Cu")
		(net "M_L_DQ<11>")
	)
	(segment
		(start 60.881768 -110.171738)
		(end 58.117994 -112.935512)
		(width 0.14224)
		(layer "In4.Cu")
		(net "M_L_DQ<11>")
	)
	(segment
		(start 60.726828 -105.024428)
		(end 60.085224 -105.024428)
		(width 0.14224)
		(layer "In4.Cu")
		(net "M_L_DQ<11>")
	)
	(segment
		(start 49.226978 -139.932156)
		(end 48.798734 -140.3604)
		(width 0.14224)
		(layer "In4.Cu")
		(net "M_L_DQ<11>")
	)
	(segment
		(start 50.975768 -124.229622)
		(end 50.676556 -124.229622)
		(width 0.14224)
		(layer "In4.Cu")
		(net "M_L_DQ<11>")
	)
	(segment
		(start 49.578514 -136.220708)
		(end 49.578514 -136.525)
		(width 0.14224)
		(layer "In4.Cu")
		(net "M_L_DQ<11>")
	)
	(segment
		(start 50.663094 -122.604022)
		(end 50.45329 -122.813826)
		(width 0.14224)
		(layer "In4.Cu")
		(net "M_L_DQ<11>")
	)
	(segment
		(start 67.299332 -96.771206)
		(end 67.299332 -97.193608)
		(width 0.0889)
		(layer "In4.Cu")
		(net "M_L_DQ<11>")
	)
	(segment
		(start 58.405268 -113.510314)
		(end 58.692796 -113.510314)
		(width 0.14224)
		(layer "In4.Cu")
		(net "M_L_DQ<11>")
	)
	(segment
		(start 68.761102 -95.309436)
		(end 67.299332 -96.771206)
		(width 0.0889)
		(layer "In4.Cu")
		(net "M_L_DQ<11>")
	)
	(segment
		(start 49.680368 -136.626854)
		(end 49.680368 -138.7856)
		(width 0.14224)
		(layer "In4.Cu")
		(net "M_L_DQ<11>")
	)
	(segment
		(start 60.726828 -106.350308)
		(end 60.085224 -106.350308)
		(width 0.14224)
		(layer "In4.Cu")
		(net "M_L_DQ<11>")
	)
	(segment
		(start 69.774816 -95.309436)
		(end 68.761102 -95.309436)
		(width 0.0889)
		(layer "In4.Cu")
		(net "M_L_DQ<11>")
	)
	(segment
		(start 51.178968 -125.245622)
		(end 51.178968 -125.652022)
		(width 0.14224)
		(layer "In4.Cu")
		(net "M_L_DQ<11>")
	)
	(segment
		(start 71.470266 -91.747086)
		(end 71.140828 -92.50807)
		(width 0.0889)
		(layer "In4.Cu")
		(net "M_L_DQ<11>")
	)
	(segment
		(start 50.372518 -126.014734)
		(end 50.372518 -126.421134)
		(width 0.14224)
		(layer "In4.Cu")
		(net "M_L_DQ<11>")
	)
	(segment
		(start 51.178968 -125.652022)
		(end 50.975768 -125.855222)
		(width 0.14224)
		(layer "In4.Cu")
		(net "M_L_DQ<11>")
	)
	(segment
		(start 50.676556 -124.229622)
		(end 50.473356 -124.432822)
		(width 0.14224)
		(layer "In4.Cu")
		(net "M_L_DQ<11>")
	)
	(segment
		(start 71.140828 -92.50807)
		(end 71.11873 -92.546424)
		(width 0.0889)
		(layer "In4.Cu")
		(net "M_L_DQ<11>")
	)
	(segment
		(start 50.975768 -122.604022)
		(end 50.663094 -122.604022)
		(width 0.14224)
		(layer "In4.Cu")
		(net "M_L_DQ<11>")
	)
	(segment
		(start 51.178968 -122.173746)
		(end 51.178968 -122.400822)
		(width 0.14224)
		(layer "In4.Cu")
		(net "M_L_DQ<11>")
	)
	(segment
		(start 58.117994 -112.935512)
		(end 58.117994 -113.22304)
		(width 0.14224)
		(layer "In4.Cu")
		(net "M_L_DQ<11>")
	)
	(segment
		(start 48.560736 -143.151352)
		(end 48.849534 -143.44015)
		(width 0.14224)
		(layer "In4.Cu")
		(net "M_L_DQ<11>")
	)
	(segment
		(start 49.832514 -135.966708)
		(end 49.578514 -136.220708)
		(width 0.14224)
		(layer "In4.Cu")
		(net "M_L_DQ<11>")
	)
	(segment
		(start 60.385452 -111.817658)
		(end 60.67298 -111.817658)
		(width 0.14224)
		(layer "In4.Cu")
		(net "M_L_DQ<11>")
	)
	(segment
		(start 60.67298 -111.817658)
		(end 60.960254 -112.104932)
		(width 0.14224)
		(layer "In4.Cu")
		(net "M_L_DQ<11>")
	)
	(segment
		(start 48.560736 -142.059152)
		(end 48.817784 -142.3162)
		(width 0.14224)
		(layer "In4.Cu")
		(net "M_L_DQ<11>")
	)
	(segment
		(start 60.881768 -104.869488)
		(end 60.726828 -105.024428)
		(width 0.14224)
		(layer "In4.Cu")
		(net "M_L_DQ<11>")
	)
	(segment
		(start 49.24933 -139.945364)
		(end 49.24933 -139.932156)
		(width 0.14224)
		(layer "In4.Cu")
		(net "M_L_DQ<11>")
	)
	(segment
		(start 49.578768 -129.935732)
		(end 49.756314 -130.113278)
		(width 0.14224)
		(layer "In4.Cu")
		(net "M_L_DQ<11>")
	)
	(segment
		(start 49.680368 -138.7856)
		(end 49.578514 -138.887454)
		(width 0.14224)
		(layer "In4.Cu")
		(net "M_L_DQ<11>")
	)
	(segment
		(start 49.616614 -134.124954)
		(end 49.616614 -134.543038)
		(width 0.14224)
		(layer "In4.Cu")
		(net "M_L_DQ<11>")
	)
	(segment
		(start 60.726828 -105.687368)
		(end 60.881768 -105.842308)
		(width 0.14224)
		(layer "In4.Cu")
		(net "M_L_DQ<11>")
	)
	(arc
		(start 71.129906 -93.939106)
		(mid 71.123729 -94.519038)
		(end 70.6247 -94.81439)
		(width 0.0889)
		(layer "In4.Cu")
		(net "M_L_DQ<11>")
	)
	(arc
		(start 71.123556 -93.528642)
		(mid 71.070057 -93.72854)
		(end 71.123556 -93.928438)
		(width 0.0889)
		(layer "In4.Cu")
		(net "M_L_DQ<11>")
	)
	(arc
		(start 70.59676 -94.81439)
		(mid 70.405118 -94.871556)
		(end 70.265036 -95.014288)
		(width 0.0889)
		(layer "In4.Cu")
		(net "M_L_DQ<11>")
	)
	(arc
		(start 71.123556 -92.937838)
		(mid 71.202687 -93.23324)
		(end 71.123556 -93.528642)
		(width 0.0889)
		(layer "In4.Cu")
		(net "M_L_DQ<11>")
	)
	(arc
		(start 70.265036 -95.014288)
		(mid 70.058032 -95.225152)
		(end 69.774816 -95.309436)
		(width 0.0889)
		(layer "In4.Cu")
		(net "M_L_DQ<11>")
	)
	(arc
		(start 71.11873 -92.546424)
		(mid 71.069975 -92.742776)
		(end 71.123556 -92.937838)
		(width 0.0889)
		(layer "In4.Cu")
		(net "M_L_DQ<11>")
	)
	(segment
		(start 72.900286 -91.25204)
		(end 72.328786 -91.25204)
		(width 0.1651)
		(layer "F.Cu")
		(net "M_L_DQ<10>")
	)
	(segment
		(start 49.24933 -146.280632)
		(end 49.380902 -146.14906)
		(width 0.1651)
		(layer "F.Cu")
		(net "M_L_DQ<10>")
	)
	(segment
		(start 49.380902 -146.14906)
		(end 49.380902 -145.92554)
		(width 0.1651)
		(layer "F.Cu")
		(net "M_L_DQ<10>")
	)
	(segment
		(start 49.380902 -145.92554)
		(end 49.24933 -145.793968)
		(width 0.1651)
		(layer "F.Cu")
		(net "M_L_DQ<10>")
	)
	(segment
		(start 49.249584 -147.27174)
		(end 49.24933 -147.27174)
		(width 0.1651)
		(layer "F.Cu")
		(net "M_L_DQ<10>")
	)
	(segment
		(start 49.24933 -147.27174)
		(end 49.24933 -146.280632)
		(width 0.1651)
		(layer "F.Cu")
		(net "M_L_DQ<10>")
	)
	(segment
		(start 49.24933 -145.793968)
		(end 49.24933 -145.5166)
		(width 0.1651)
		(layer "F.Cu")
		(net "M_L_DQ<10>")
	)
	(via
		(at 49.24933 -145.5166)
		(size 0.508)
		(drill 0.254)
		(layers "F.Cu" "B.Cu")
		(net "M_L_DQ<10>")
	)
	(via
		(at 48.399446 -141.213078)
		(size 0.508)
		(drill 0.254)
		(layers "F.Cu" "B.Cu")
		(net "M_L_DQ<10>")
	)
	(via
		(at 72.328786 -91.25204)
		(size 0.508)
		(drill 0.254)
		(layers "F.Cu" "B.Cu")
		(net "M_L_DQ<10>")
	)
	(segment
		(start 48.399446 -142.477236)
		(end 48.399446 -141.213078)
		(width 0.1651)
		(layer "B.Cu")
		(net "M_L_DQ<10>")
	)
	(segment
		(start 59.303666 -109.35716)
		(end 59.99099 -109.35716)
		(width 0.14224)
		(layer "In4.Cu")
		(net "M_L_DQ<10>")
	)
	(segment
		(start 60.14593 -108.53928)
		(end 59.99099 -108.69422)
		(width 0.14224)
		(layer "In4.Cu")
		(net "M_L_DQ<10>")
	)
	(segment
		(start 48.943768 -129.782824)
		(end 48.588168 -130.138424)
		(width 0.14224)
		(layer "In4.Cu")
		(net "M_L_DQ<10>")
	)
	(segment
		(start 55.041038 -115.239038)
		(end 55.041038 -115.41887)
		(width 0.14224)
		(layer "In4.Cu")
		(net "M_L_DQ<10>")
	)
	(segment
		(start 70.958456 -92.442538)
		(end 70.952106 -92.453206)
		(width 0.0889)
		(layer "In4.Cu")
		(net "M_L_DQ<10>")
	)
	(segment
		(start 60.14593 -110.134146)
		(end 55.041038 -115.239038)
		(width 0.14224)
		(layer "In4.Cu")
		(net "M_L_DQ<10>")
	)
	(segment
		(start 47.966376 -141.646148)
		(end 47.966376 -144.233646)
		(width 0.14224)
		(layer "In4.Cu")
		(net "M_L_DQ<10>")
	)
	(segment
		(start 55.21325 -115.591082)
		(end 55.500778 -115.591082)
		(width 0.14224)
		(layer "In4.Cu")
		(net "M_L_DQ<10>")
	)
	(segment
		(start 48.918114 -136.5758)
		(end 48.816768 -136.677146)
		(width 0.14224)
		(layer "In4.Cu")
		(net "M_L_DQ<10>")
	)
	(segment
		(start 48.968914 -134.213346)
		(end 48.968914 -134.454138)
		(width 0.14224)
		(layer "In4.Cu")
		(net "M_L_DQ<10>")
	)
	(segment
		(start 59.303666 -108.69422)
		(end 59.148726 -108.84916)
		(width 0.14224)
		(layer "In4.Cu")
		(net "M_L_DQ<10>")
	)
	(segment
		(start 48.968914 -134.454138)
		(end 48.689514 -134.733538)
		(width 0.14224)
		(layer "In4.Cu")
		(net "M_L_DQ<10>")
	)
	(segment
		(start 65.733168 -97.85604)
		(end 65.733168 -98.458528)
		(width 0.14224)
		(layer "In4.Cu")
		(net "M_L_DQ<10>")
	)
	(segment
		(start 48.943768 -128.311656)
		(end 48.943768 -129.782824)
		(width 0.14224)
		(layer "In4.Cu")
		(net "M_L_DQ<10>")
	)
	(segment
		(start 49.070768 -131.5212)
		(end 49.070768 -131.851146)
		(width 0.14224)
		(layer "In4.Cu")
		(net "M_L_DQ<10>")
	)
	(segment
		(start 57.507378 -113.87201)
		(end 57.794652 -114.159284)
		(width 0.14224)
		(layer "In4.Cu")
		(net "M_L_DQ<10>")
	)
	(segment
		(start 60.14593 -107.936538)
		(end 60.14593 -108.53928)
		(width 0.14224)
		(layer "In4.Cu")
		(net "M_L_DQ<10>")
	)
	(segment
		(start 71.45909 -91.347036)
		(end 71.50735 -91.347036)
		(width 0.0889)
		(layer "In4.Cu")
		(net "M_L_DQ<10>")
	)
	(segment
		(start 67.060064 -96.741742)
		(end 66.847466 -96.741742)
		(width 0.0889)
		(layer "In4.Cu")
		(net "M_L_DQ<10>")
	)
	(segment
		(start 70.963282 -92.433902)
		(end 70.958456 -92.442538)
		(width 0.0889)
		(layer "In4.Cu")
		(net "M_L_DQ<10>")
	)
	(segment
		(start 57.794652 -114.446812)
		(end 49.959768 -122.281696)
		(width 0.14224)
		(layer "In4.Cu")
		(net "M_L_DQ<10>")
	)
	(segment
		(start 57.794652 -114.159284)
		(end 57.794652 -114.446812)
		(width 0.14224)
		(layer "In4.Cu")
		(net "M_L_DQ<10>")
	)
	(segment
		(start 59.310524 -107.101132)
		(end 60.14593 -107.936538)
		(width 0.14224)
		(layer "In4.Cu")
		(net "M_L_DQ<10>")
	)
	(segment
		(start 59.148726 -109.20222)
		(end 59.303666 -109.35716)
		(width 0.14224)
		(layer "In4.Cu")
		(net "M_L_DQ<10>")
	)
	(segment
		(start 59.99099 -109.35716)
		(end 60.14593 -109.5121)
		(width 0.14224)
		(layer "In4.Cu")
		(net "M_L_DQ<10>")
	)
	(segment
		(start 59.310524 -104.881172)
		(end 59.310524 -107.101132)
		(width 0.14224)
		(layer "In4.Cu")
		(net "M_L_DQ<10>")
	)
	(segment
		(start 48.588168 -131.0386)
		(end 49.070768 -131.5212)
		(width 0.14224)
		(layer "In4.Cu")
		(net "M_L_DQ<10>")
	)
	(segment
		(start 48.399446 -141.213078)
		(end 47.966376 -141.646148)
		(width 0.14224)
		(layer "In4.Cu")
		(net "M_L_DQ<10>")
	)
	(segment
		(start 70.952106 -94.01302)
		(end 70.958456 -94.023688)
		(width 0.0889)
		(layer "In4.Cu")
		(net "M_L_DQ<10>")
	)
	(segment
		(start 48.824896 -134.069328)
		(end 48.968914 -134.213346)
		(width 0.14224)
		(layer "In4.Cu")
		(net "M_L_DQ<10>")
	)
	(segment
		(start 49.070768 -131.851146)
		(end 48.824896 -132.097018)
		(width 0.14224)
		(layer "In4.Cu")
		(net "M_L_DQ<10>")
	)
	(segment
		(start 59.148726 -108.84916)
		(end 59.148726 -109.20222)
		(width 0.14224)
		(layer "In4.Cu")
		(net "M_L_DQ<10>")
	)
	(segment
		(start 70.958456 -91.8337)
		(end 71.123556 -91.547188)
		(width 0.0889)
		(layer "In4.Cu")
		(net "M_L_DQ<10>")
	)
	(segment
		(start 48.689514 -135.976868)
		(end 48.918114 -136.205468)
		(width 0.14224)
		(layer "In4.Cu")
		(net "M_L_DQ<10>")
	)
	(segment
		(start 68.68287 -95.118936)
		(end 67.060064 -96.741742)
		(width 0.0889)
		(layer "In4.Cu")
		(net "M_L_DQ<10>")
	)
	(segment
		(start 48.918114 -138.963146)
		(end 48.918114 -139.371578)
		(width 0.14224)
		(layer "In4.Cu")
		(net "M_L_DQ<10>")
	)
	(segment
		(start 48.689514 -134.733538)
		(end 48.689514 -135.976868)
		(width 0.14224)
		(layer "In4.Cu")
		(net "M_L_DQ<10>")
	)
	(segment
		(start 48.918114 -136.205468)
		(end 48.918114 -136.5758)
		(width 0.14224)
		(layer "In4.Cu")
		(net "M_L_DQ<10>")
	)
	(segment
		(start 49.959768 -122.281696)
		(end 49.959768 -127.295656)
		(width 0.14224)
		(layer "In4.Cu")
		(net "M_L_DQ<10>")
	)
	(segment
		(start 48.816768 -136.677146)
		(end 48.816768 -138.8618)
		(width 0.14224)
		(layer "In4.Cu")
		(net "M_L_DQ<10>")
	)
	(segment
		(start 59.99099 -108.69422)
		(end 59.303666 -108.69422)
		(width 0.14224)
		(layer "In4.Cu")
		(net "M_L_DQ<10>")
	)
	(segment
		(start 60.14593 -109.5121)
		(end 60.14593 -110.134146)
		(width 0.14224)
		(layer "In4.Cu")
		(net "M_L_DQ<10>")
	)
	(segment
		(start 57.21985 -113.87201)
		(end 57.507378 -113.87201)
		(width 0.14224)
		(layer "In4.Cu")
		(net "M_L_DQ<10>")
	)
	(segment
		(start 71.50735 -91.347036)
		(end 72.328786 -91.25204)
		(width 0.0889)
		(layer "In4.Cu")
		(net "M_L_DQ<10>")
	)
	(segment
		(start 70.963282 -93.424502)
		(end 70.958456 -93.433138)
		(width 0.0889)
		(layer "In4.Cu")
		(net "M_L_DQ<10>")
	)
	(segment
		(start 55.500778 -115.591082)
		(end 57.21985 -113.87201)
		(width 0.14224)
		(layer "In4.Cu")
		(net "M_L_DQ<10>")
	)
	(segment
		(start 55.041038 -115.41887)
		(end 55.21325 -115.591082)
		(width 0.14224)
		(layer "In4.Cu")
		(net "M_L_DQ<10>")
	)
	(segment
		(start 47.966376 -144.233646)
		(end 49.24933 -145.5166)
		(width 0.14224)
		(layer "In4.Cu")
		(net "M_L_DQ<10>")
	)
	(segment
		(start 48.054514 -140.868146)
		(end 48.399446 -141.213078)
		(width 0.14224)
		(layer "In4.Cu")
		(net "M_L_DQ<10>")
	)
	(segment
		(start 48.918114 -139.371578)
		(end 48.054514 -140.235178)
		(width 0.14224)
		(layer "In4.Cu")
		(net "M_L_DQ<10>")
	)
	(segment
		(start 48.588168 -130.138424)
		(end 48.588168 -131.0386)
		(width 0.14224)
		(layer "In4.Cu")
		(net "M_L_DQ<10>")
	)
	(segment
		(start 66.847466 -96.741742)
		(end 65.733168 -97.85604)
		(width 0.14224)
		(layer "In4.Cu")
		(net "M_L_DQ<10>")
	)
	(segment
		(start 69.768212 -95.118936)
		(end 68.68287 -95.118936)
		(width 0.0889)
		(layer "In4.Cu")
		(net "M_L_DQ<10>")
	)
	(segment
		(start 48.816768 -138.8618)
		(end 48.918114 -138.963146)
		(width 0.14224)
		(layer "In4.Cu")
		(net "M_L_DQ<10>")
	)
	(segment
		(start 65.733168 -98.458528)
		(end 59.310524 -104.881172)
		(width 0.14224)
		(layer "In4.Cu")
		(net "M_L_DQ<10>")
	)
	(segment
		(start 48.054514 -140.235178)
		(end 48.054514 -140.868146)
		(width 0.14224)
		(layer "In4.Cu")
		(net "M_L_DQ<10>")
	)
	(segment
		(start 70.622922 -94.623636)
		(end 70.598792 -94.623636)
		(width 0.0889)
		(layer "In4.Cu")
		(net "M_L_DQ<10>")
	)
	(segment
		(start 48.824896 -132.097018)
		(end 48.824896 -134.069328)
		(width 0.14224)
		(layer "In4.Cu")
		(net "M_L_DQ<10>")
	)
	(segment
		(start 49.959768 -127.295656)
		(end 48.943768 -128.311656)
		(width 0.14224)
		(layer "In4.Cu")
		(net "M_L_DQ<10>")
	)
	(arc
		(start 70.958456 -94.023688)
		(mid 70.961039 -94.418935)
		(end 70.622922 -94.623636)
		(width 0.0889)
		(layer "In4.Cu")
		(net "M_L_DQ<10>")
	)
	(arc
		(start 70.958456 -91.8337)
		(mid 70.930488 -91.938094)
		(end 70.958456 -92.042488)
		(width 0.0889)
		(layer "In4.Cu")
		(net "M_L_DQ<10>")
	)
	(arc
		(start 70.958456 -93.033088)
		(mid 71.011926 -93.228151)
		(end 70.963282 -93.424502)
		(width 0.0889)
		(layer "In4.Cu")
		(net "M_L_DQ<10>")
	)
	(arc
		(start 70.958456 -92.042488)
		(mid 71.011926 -92.237551)
		(end 70.963282 -92.433902)
		(width 0.0889)
		(layer "In4.Cu")
		(net "M_L_DQ<10>")
	)
	(arc
		(start 70.598792 -94.623636)
		(mid 70.310647 -94.705955)
		(end 70.099936 -94.919038)
		(width 0.0889)
		(layer "In4.Cu")
		(net "M_L_DQ<10>")
	)
	(arc
		(start 70.952106 -92.453206)
		(mid 70.879308 -92.743969)
		(end 70.958456 -93.033088)
		(width 0.0889)
		(layer "In4.Cu")
		(net "M_L_DQ<10>")
	)
	(arc
		(start 70.099936 -94.919038)
		(mid 69.959857 -95.061774)
		(end 69.768212 -95.118936)
		(width 0.0889)
		(layer "In4.Cu")
		(net "M_L_DQ<10>")
	)
	(arc
		(start 71.123556 -91.547188)
		(mid 71.265239 -91.403384)
		(end 71.45909 -91.347036)
		(width 0.0889)
		(layer "In4.Cu")
		(net "M_L_DQ<10>")
	)
	(arc
		(start 70.958456 -93.433138)
		(mid 70.879234 -93.722256)
		(end 70.952106 -94.01302)
		(width 0.0889)
		(layer "In4.Cu")
		(net "M_L_DQ<10>")
	)
	(segment
		(start 33.949386 -147.277582)
		(end 33.771586 -145.415)
		(width 0.1651)
		(layer "F.Cu")
		(net "M_L_DQ<0>")
	)
	(segment
		(start 33.949386 -147.27174)
		(end 33.949386 -147.277582)
		(width 0.1651)
		(layer "F.Cu")
		(net "M_L_DQ<0>")
	)
	(segment
		(start 73.758806 -84.812886)
		(end 73.187306 -84.812886)
		(width 0.1651)
		(layer "F.Cu")
		(net "M_L_DQ<0>")
	)
	(via
		(at 33.771586 -145.415)
		(size 0.508)
		(drill 0.254)
		(layers "F.Cu" "B.Cu")
		(net "M_L_DQ<0>")
	)
	(via
		(at 33.099502 -141.213078)
		(size 0.508)
		(drill 0.254)
		(layers "F.Cu" "B.Cu")
		(net "M_L_DQ<0>")
	)
	(via
		(at 73.187306 -84.812886)
		(size 0.508)
		(drill 0.254)
		(layers "F.Cu" "B.Cu")
		(net "M_L_DQ<0>")
	)
	(segment
		(start 33.099502 -142.477236)
		(end 33.099502 -141.213078)
		(width 0.1651)
		(layer "B.Cu")
		(net "M_L_DQ<0>")
	)
	(segment
		(start 33.525968 -138.8872)
		(end 33.525968 -136.670796)
		(width 0.14224)
		(layer "In4.Cu")
		(net "M_L_DQ<0>")
	)
	(segment
		(start 33.570164 -138.931396)
		(end 33.525968 -138.8872)
		(width 0.14224)
		(layer "In4.Cu")
		(net "M_L_DQ<0>")
	)
	(segment
		(start 33.290764 -135.98525)
		(end 33.290764 -134.767574)
		(width 0.14224)
		(layer "In4.Cu")
		(net "M_L_DQ<0>")
	)
	(segment
		(start 66.179192 -83.373214)
		(end 66.815208 -82.737198)
		(width 0.0889)
		(layer "In4.Cu")
		(net "M_L_DQ<0>")
	)
	(segment
		(start 33.620964 -134.181596)
		(end 33.322768 -133.8834)
		(width 0.14224)
		(layer "In4.Cu")
		(net "M_L_DQ<0>")
	)
	(segment
		(start 67.8688 -83.231736)
		(end 68.05422 -83.231736)
		(width 0.0889)
		(layer "In4.Cu")
		(net "M_L_DQ<0>")
	)
	(segment
		(start 63.401702 -83.15452)
		(end 65.808352 -83.15452)
		(width 0.14224)
		(layer "In4.Cu")
		(net "M_L_DQ<0>")
	)
	(segment
		(start 33.620964 -131.953)
		(end 33.620964 -131.514596)
		(width 0.14224)
		(layer "In4.Cu")
		(net "M_L_DQ<0>")
	)
	(segment
		(start 54.392322 -92.1639)
		(end 63.401702 -83.15452)
		(width 0.14224)
		(layer "In4.Cu")
		(net "M_L_DQ<0>")
	)
	(segment
		(start 33.322768 -132.251196)
		(end 33.620964 -131.953)
		(width 0.14224)
		(layer "In4.Cu")
		(net "M_L_DQ<0>")
	)
	(segment
		(start 66.815208 -82.737198)
		(end 67.379596 -82.737198)
		(width 0.0889)
		(layer "In4.Cu")
		(net "M_L_DQ<0>")
	)
	(segment
		(start 32.8549 -140.951712)
		(end 32.8549 -140.055092)
		(width 0.14224)
		(layer "In4.Cu")
		(net "M_L_DQ<0>")
	)
	(segment
		(start 33.138364 -128.97485)
		(end 33.138364 -115.90655)
		(width 0.14224)
		(layer "In4.Cu")
		(net "M_L_DQ<0>")
	)
	(segment
		(start 32.8549 -140.055092)
		(end 33.570164 -139.339828)
		(width 0.14224)
		(layer "In4.Cu")
		(net "M_L_DQ<0>")
	)
	(segment
		(start 72.31761 -83.72729)
		(end 72.350376 -83.72729)
		(width 0.0889)
		(layer "In4.Cu")
		(net "M_L_DQ<0>")
	)
	(segment
		(start 33.099502 -141.213078)
		(end 32.666432 -141.646148)
		(width 0.14224)
		(layer "In4.Cu")
		(net "M_L_DQ<0>")
	)
	(segment
		(start 70.60057 -82.73669)
		(end 70.633336 -82.73669)
		(width 0.0889)
		(layer "In4.Cu")
		(net "M_L_DQ<0>")
	)
	(segment
		(start 32.666432 -141.646148)
		(end 32.666432 -144.60601)
		(width 0.14224)
		(layer "In4.Cu")
		(net "M_L_DQ<0>")
	)
	(segment
		(start 33.290764 -131.184396)
		(end 33.290764 -130.035808)
		(width 0.14224)
		(layer "In4.Cu")
		(net "M_L_DQ<0>")
	)
	(segment
		(start 36.522914 -113.4364)
		(end 42.110914 -107.8484)
		(width 0.14224)
		(layer "In4.Cu")
		(net "M_L_DQ<0>")
	)
	(segment
		(start 65.808352 -83.15452)
		(end 66.027046 -83.373214)
		(width 0.0889)
		(layer "In4.Cu")
		(net "M_L_DQ<0>")
	)
	(segment
		(start 33.290764 -130.035808)
		(end 33.518602 -129.80797)
		(width 0.14224)
		(layer "In4.Cu")
		(net "M_L_DQ<0>")
	)
	(segment
		(start 33.570164 -136.26465)
		(end 33.290764 -135.98525)
		(width 0.14224)
		(layer "In4.Cu")
		(net "M_L_DQ<0>")
	)
	(segment
		(start 33.290764 -134.767574)
		(end 33.620964 -134.437374)
		(width 0.14224)
		(layer "In4.Cu")
		(net "M_L_DQ<0>")
	)
	(segment
		(start 33.525968 -136.670796)
		(end 33.570164 -136.6266)
		(width 0.14224)
		(layer "In4.Cu")
		(net "M_L_DQ<0>")
	)
	(segment
		(start 68.873116 -82.73669)
		(end 68.905882 -82.73669)
		(width 0.0889)
		(layer "In4.Cu")
		(net "M_L_DQ<0>")
	)
	(segment
		(start 33.099502 -141.213078)
		(end 33.099502 -141.196314)
		(width 0.14224)
		(layer "In4.Cu")
		(net "M_L_DQ<0>")
	)
	(segment
		(start 67.544188 -82.90179)
		(end 67.766946 -83.158076)
		(width 0.0889)
		(layer "In4.Cu")
		(net "M_L_DQ<0>")
	)
	(segment
		(start 54.392322 -96.684592)
		(end 54.392322 -92.1639)
		(width 0.14224)
		(layer "In4.Cu")
		(net "M_L_DQ<0>")
	)
	(segment
		(start 35.608514 -113.4364)
		(end 36.522914 -113.4364)
		(width 0.14224)
		(layer "In4.Cu")
		(net "M_L_DQ<0>")
	)
	(segment
		(start 33.518602 -129.355088)
		(end 33.138364 -128.97485)
		(width 0.14224)
		(layer "In4.Cu")
		(net "M_L_DQ<0>")
	)
	(segment
		(start 66.027046 -83.373214)
		(end 66.179192 -83.373214)
		(width 0.0889)
		(layer "In4.Cu")
		(net "M_L_DQ<0>")
	)
	(segment
		(start 42.110914 -107.8484)
		(end 43.228514 -107.8484)
		(width 0.14224)
		(layer "In4.Cu")
		(net "M_L_DQ<0>")
	)
	(segment
		(start 33.518602 -129.80797)
		(end 33.518602 -129.355088)
		(width 0.14224)
		(layer "In4.Cu")
		(net "M_L_DQ<0>")
	)
	(segment
		(start 32.666432 -144.60601)
		(end 33.475422 -145.415)
		(width 0.14224)
		(layer "In4.Cu")
		(net "M_L_DQ<0>")
	)
	(segment
		(start 33.620964 -131.514596)
		(end 33.290764 -131.184396)
		(width 0.14224)
		(layer "In4.Cu")
		(net "M_L_DQ<0>")
	)
	(segment
		(start 33.570164 -139.339828)
		(end 33.570164 -138.931396)
		(width 0.14224)
		(layer "In4.Cu")
		(net "M_L_DQ<0>")
	)
	(segment
		(start 33.620964 -134.437374)
		(end 33.620964 -134.181596)
		(width 0.14224)
		(layer "In4.Cu")
		(net "M_L_DQ<0>")
	)
	(segment
		(start 33.475422 -145.415)
		(end 33.771586 -145.415)
		(width 0.14224)
		(layer "In4.Cu")
		(net "M_L_DQ<0>")
	)
	(segment
		(start 33.099502 -141.196314)
		(end 32.8549 -140.951712)
		(width 0.14224)
		(layer "In4.Cu")
		(net "M_L_DQ<0>")
	)
	(segment
		(start 33.138364 -115.90655)
		(end 35.608514 -113.4364)
		(width 0.14224)
		(layer "In4.Cu")
		(net "M_L_DQ<0>")
	)
	(segment
		(start 33.570164 -136.6266)
		(end 33.570164 -136.26465)
		(width 0.14224)
		(layer "In4.Cu")
		(net "M_L_DQ<0>")
	)
	(segment
		(start 43.228514 -107.8484)
		(end 54.392322 -96.684592)
		(width 0.14224)
		(layer "In4.Cu")
		(net "M_L_DQ<0>")
	)
	(segment
		(start 67.379596 -82.737198)
		(end 67.544188 -82.90179)
		(width 0.0889)
		(layer "In4.Cu")
		(net "M_L_DQ<0>")
	)
	(segment
		(start 33.322768 -133.8834)
		(end 33.322768 -132.251196)
		(width 0.14224)
		(layer "In4.Cu")
		(net "M_L_DQ<0>")
	)
	(segment
		(start 71.452232 -83.231736)
		(end 71.488046 -83.231736)
		(width 0.0889)
		(layer "In4.Cu")
		(net "M_L_DQ<0>")
	)
	(segment
		(start 72.840596 -84.022438)
		(end 72.85736 -84.05114)
		(width 0.0889)
		(layer "In4.Cu")
		(net "M_L_DQ<0>")
	)
	(segment
		(start 72.85736 -84.05114)
		(end 73.187306 -84.812886)
		(width 0.0889)
		(layer "In4.Cu")
		(net "M_L_DQ<0>")
	)
	(arc
		(start 68.05422 -83.231736)
		(mid 68.244149 -83.173866)
		(end 68.382896 -83.031838)
		(width 0.0889)
		(layer "In4.Cu")
		(net "M_L_DQ<0>")
	)
	(arc
		(start 69.241416 -82.536538)
		(mid 69.753226 -82.240999)
		(end 70.265036 -82.536538)
		(width 0.0889)
		(layer "In4.Cu")
		(net "M_L_DQ<0>")
	)
	(arc
		(start 68.382896 -83.031838)
		(mid 68.5899 -82.820974)
		(end 68.873116 -82.73669)
		(width 0.0889)
		(layer "In4.Cu")
		(net "M_L_DQ<0>")
	)
	(arc
		(start 68.905882 -82.73669)
		(mid 69.099732 -82.68034)
		(end 69.241416 -82.536538)
		(width 0.0889)
		(layer "In4.Cu")
		(net "M_L_DQ<0>")
	)
	(arc
		(start 67.766946 -83.158076)
		(mid 67.813647 -83.200743)
		(end 67.8688 -83.231736)
		(width 0.0889)
		(layer "In4.Cu")
		(net "M_L_DQ<0>")
	)
	(arc
		(start 72.350376 -83.72729)
		(mid 72.633593 -83.811571)
		(end 72.840596 -84.022438)
		(width 0.0889)
		(layer "In4.Cu")
		(net "M_L_DQ<0>")
	)
	(arc
		(start 70.265036 -82.536538)
		(mid 70.406719 -82.680342)
		(end 70.60057 -82.73669)
		(width 0.0889)
		(layer "In4.Cu")
		(net "M_L_DQ<0>")
	)
	(arc
		(start 70.633336 -82.73669)
		(mid 70.916553 -82.820971)
		(end 71.123556 -83.031838)
		(width 0.0889)
		(layer "In4.Cu")
		(net "M_L_DQ<0>")
	)
	(arc
		(start 71.982076 -83.527138)
		(mid 72.123759 -83.670942)
		(end 72.31761 -83.72729)
		(width 0.0889)
		(layer "In4.Cu")
		(net "M_L_DQ<0>")
	)
	(arc
		(start 71.488046 -83.231736)
		(mid 71.77347 -83.315203)
		(end 71.982076 -83.527138)
		(width 0.0889)
		(layer "In4.Cu")
		(net "M_L_DQ<0>")
	)
	(arc
		(start 71.123556 -83.031838)
		(mid 71.2623 -83.173871)
		(end 71.452232 -83.231736)
		(width 0.0889)
		(layer "In4.Cu")
		(net "M_L_DQ<0>")
	)
	(segment
		(start 102.089204 -95.21444)
		(end 101.517704 -95.21444)
		(width 0.1016)
		(layer "F.Cu")
		(net "M_L_CS_N<7>")
	)
	(via
		(at 112.99952 -139.172188)
		(size 0.4572)
		(drill 0.2032)
		(layers "F.Cu" "B.Cu")
		(net "M_L_CS_N<7>")
	)
	(via
		(at 101.517704 -95.21444)
		(size 0.508)
		(drill 0.254)
		(layers "F.Cu" "B.Cu")
		(net "M_L_CS_N<7>")
	)
	(segment
		(start 112.99952 -137.877296)
		(end 112.99952 -139.172188)
		(width 0.1651)
		(layer "B.Cu")
		(net "M_L_CS_N<7>")
	)
	(segment
		(start 112.58296 -131.966208)
		(end 112.58296 -134.759192)
		(width 0.14224)
		(layer "In4.Cu")
		(net "M_L_CS_N<7>")
	)
	(segment
		(start 112.606582 -131.942586)
		(end 112.58296 -131.966208)
		(width 0.14224)
		(layer "In4.Cu")
		(net "M_L_CS_N<7>")
	)
	(segment
		(start 112.58296 -134.759192)
		(end 112.588802 -134.765034)
		(width 0.14224)
		(layer "In4.Cu")
		(net "M_L_CS_N<7>")
	)
	(segment
		(start 112.606582 -129.956814)
		(end 112.606582 -130.520186)
		(width 0.14224)
		(layer "In4.Cu")
		(net "M_L_CS_N<7>")
	)
	(segment
		(start 112.54232 -130.584448)
		(end 112.54232 -131.238752)
		(width 0.14224)
		(layer "In4.Cu")
		(net "M_L_CS_N<7>")
	)
	(segment
		(start 112.418368 -128.090168)
		(end 112.418368 -129.7686)
		(width 0.14224)
		(layer "In4.Cu")
		(net "M_L_CS_N<7>")
	)
	(segment
		(start 101.517704 -95.21444)
		(end 102.456488 -95.21444)
		(width 0.0889)
		(layer "In4.Cu")
		(net "M_L_CS_N<7>")
	)
	(segment
		(start 104.696768 -120.368568)
		(end 112.418368 -128.090168)
		(width 0.14224)
		(layer "In4.Cu")
		(net "M_L_CS_N<7>")
	)
	(segment
		(start 103.756968 -100.9396)
		(end 104.696768 -101.8794)
		(width 0.0889)
		(layer "In4.Cu")
		(net "M_L_CS_N<7>")
	)
	(segment
		(start 112.606582 -131.303014)
		(end 112.606582 -131.942586)
		(width 0.14224)
		(layer "In4.Cu")
		(net "M_L_CS_N<7>")
	)
	(segment
		(start 112.99952 -138.528552)
		(end 112.99952 -139.172188)
		(width 0.14224)
		(layer "In4.Cu")
		(net "M_L_CS_N<7>")
	)
	(segment
		(start 103.756968 -97.65284)
		(end 103.756968 -100.9396)
		(width 0.0889)
		(layer "In4.Cu")
		(net "M_L_CS_N<7>")
	)
	(segment
		(start 112.588802 -134.765034)
		(end 112.588802 -138.117834)
		(width 0.14224)
		(layer "In4.Cu")
		(net "M_L_CS_N<7>")
	)
	(segment
		(start 112.54232 -131.238752)
		(end 112.606582 -131.303014)
		(width 0.14224)
		(layer "In4.Cu")
		(net "M_L_CS_N<7>")
	)
	(segment
		(start 104.696768 -103.1494)
		(end 104.696768 -120.368568)
		(width 0.14224)
		(layer "In4.Cu")
		(net "M_L_CS_N<7>")
	)
	(segment
		(start 112.588802 -138.117834)
		(end 112.99952 -138.528552)
		(width 0.14224)
		(layer "In4.Cu")
		(net "M_L_CS_N<7>")
	)
	(segment
		(start 102.994968 -96.89084)
		(end 103.756968 -97.65284)
		(width 0.0889)
		(layer "In4.Cu")
		(net "M_L_CS_N<7>")
	)
	(segment
		(start 112.418368 -129.7686)
		(end 112.606582 -129.956814)
		(width 0.14224)
		(layer "In4.Cu")
		(net "M_L_CS_N<7>")
	)
	(segment
		(start 112.606582 -130.520186)
		(end 112.54232 -130.584448)
		(width 0.14224)
		(layer "In4.Cu")
		(net "M_L_CS_N<7>")
	)
	(segment
		(start 104.696768 -101.8794)
		(end 104.696768 -103.1494)
		(width 0.0889)
		(layer "In4.Cu")
		(net "M_L_CS_N<7>")
	)
	(segment
		(start 102.994968 -95.75292)
		(end 102.994968 -96.89084)
		(width 0.0889)
		(layer "In4.Cu")
		(net "M_L_CS_N<7>")
	)
	(segment
		(start 102.456488 -95.21444)
		(end 102.994968 -95.75292)
		(width 0.0889)
		(layer "In4.Cu")
		(net "M_L_CS_N<7>")
	)
	(segment
		(start 102.947724 -96.700086)
		(end 102.376224 -96.700086)
		(width 0.1016)
		(layer "F.Cu")
		(net "M_L_CS_N<6>")
	)
	(via
		(at 102.376224 -96.700086)
		(size 0.508)
		(drill 0.254)
		(layers "F.Cu" "B.Cu")
		(net "M_L_CS_N<6>")
	)
	(via
		(at 112.99952 -141.188186)
		(size 0.4572)
		(drill 0.2032)
		(layers "F.Cu" "B.Cu")
		(net "M_L_CS_N<6>")
	)
	(segment
		(start 112.99952 -142.477236)
		(end 112.99952 -141.188186)
		(width 0.1651)
		(layer "B.Cu")
		(net "M_L_CS_N<6>")
	)
	(segment
		(start 103.477568 -97.80143)
		(end 103.477568 -101.1936)
		(width 0.0889)
		(layer "In4.Cu")
		(net "M_L_CS_N<6>")
	)
	(segment
		(start 111.70793 -134.797038)
		(end 111.70793 -137.998962)
		(width 0.14224)
		(layer "In4.Cu")
		(net "M_L_CS_N<6>")
	)
	(segment
		(start 111.854488 -129.77368)
		(end 111.575342 -130.052826)
		(width 0.14224)
		(layer "In4.Cu")
		(net "M_L_CS_N<6>")
	)
	(segment
		(start 103.477568 -101.1936)
		(end 104.315768 -102.0318)
		(width 0.0889)
		(layer "In4.Cu")
		(net "M_L_CS_N<6>")
	)
	(segment
		(start 112.99952 -140.503656)
		(end 112.99952 -141.188186)
		(width 0.14224)
		(layer "In4.Cu")
		(net "M_L_CS_N<6>")
	)
	(segment
		(start 111.575342 -130.398774)
		(end 111.834168 -130.6576)
		(width 0.14224)
		(layer "In4.Cu")
		(net "M_L_CS_N<6>")
	)
	(segment
		(start 111.70793 -137.998962)
		(end 112.588802 -138.879834)
		(width 0.14224)
		(layer "In4.Cu")
		(net "M_L_CS_N<6>")
	)
	(segment
		(start 111.71174 -131.237228)
		(end 111.71174 -134.793228)
		(width 0.14224)
		(layer "In4.Cu")
		(net "M_L_CS_N<6>")
	)
	(segment
		(start 111.834168 -130.6576)
		(end 111.834168 -131.1148)
		(width 0.14224)
		(layer "In4.Cu")
		(net "M_L_CS_N<6>")
	)
	(segment
		(start 111.71174 -134.793228)
		(end 111.70793 -134.797038)
		(width 0.14224)
		(layer "In4.Cu")
		(net "M_L_CS_N<6>")
	)
	(segment
		(start 111.854488 -129.260346)
		(end 111.854488 -129.77368)
		(width 0.14224)
		(layer "In4.Cu")
		(net "M_L_CS_N<6>")
	)
	(segment
		(start 111.834168 -131.1148)
		(end 111.71174 -131.237228)
		(width 0.14224)
		(layer "In4.Cu")
		(net "M_L_CS_N<6>")
	)
	(segment
		(start 112.588802 -140.092938)
		(end 112.99952 -140.503656)
		(width 0.14224)
		(layer "In4.Cu")
		(net "M_L_CS_N<6>")
	)
	(segment
		(start 107.244388 -123.733306)
		(end 107.244388 -124.650246)
		(width 0.14224)
		(layer "In4.Cu")
		(net "M_L_CS_N<6>")
	)
	(segment
		(start 102.376224 -96.700086)
		(end 103.477568 -97.80143)
		(width 0.0889)
		(layer "In4.Cu")
		(net "M_L_CS_N<6>")
	)
	(segment
		(start 104.188768 -102.83571)
		(end 104.188768 -103.07447)
		(width 0.0889)
		(layer "In4.Cu")
		(net "M_L_CS_N<6>")
	)
	(segment
		(start 104.188768 -120.677686)
		(end 107.244388 -123.733306)
		(width 0.14224)
		(layer "In4.Cu")
		(net "M_L_CS_N<6>")
	)
	(segment
		(start 111.575342 -130.052826)
		(end 111.575342 -130.398774)
		(width 0.14224)
		(layer "In4.Cu")
		(net "M_L_CS_N<6>")
	)
	(segment
		(start 107.244388 -124.650246)
		(end 111.854488 -129.260346)
		(width 0.14224)
		(layer "In4.Cu")
		(net "M_L_CS_N<6>")
	)
	(segment
		(start 112.588802 -138.879834)
		(end 112.588802 -140.092938)
		(width 0.14224)
		(layer "In4.Cu")
		(net "M_L_CS_N<6>")
	)
	(segment
		(start 104.188768 -103.07447)
		(end 104.188768 -120.677686)
		(width 0.14224)
		(layer "In4.Cu")
		(net "M_L_CS_N<6>")
	)
	(segment
		(start 104.315768 -102.70871)
		(end 104.188768 -102.83571)
		(width 0.0889)
		(layer "In4.Cu")
		(net "M_L_CS_N<6>")
	)
	(segment
		(start 104.315768 -102.0318)
		(end 104.315768 -102.70871)
		(width 0.0889)
		(layer "In4.Cu")
		(net "M_L_CS_N<6>")
	)
	(segment
		(start 99.513898 -94.718886)
		(end 98.942398 -94.718886)
		(width 0.1016)
		(layer "F.Cu")
		(net "M_L_CS_N<5>")
	)
	(via
		(at 109.599476 -141.183868)
		(size 0.4572)
		(drill 0.2032)
		(layers "F.Cu" "B.Cu")
		(net "M_L_CS_N<5>")
	)
	(via
		(at 98.942398 -94.718886)
		(size 0.508)
		(drill 0.254)
		(layers "F.Cu" "B.Cu")
		(net "M_L_CS_N<5>")
	)
	(segment
		(start 109.599476 -142.477236)
		(end 109.599476 -141.183868)
		(width 0.1651)
		(layer "B.Cu")
		(net "M_L_CS_N<5>")
	)
	(segment
		(start 108.334556 -132.647436)
		(end 108.334556 -134.734554)
		(width 0.14224)
		(layer "In4.Cu")
		(net "M_L_CS_N<5>")
	)
	(segment
		(start 108.430568 -129.7559)
		(end 108.181648 -130.00482)
		(width 0.14224)
		(layer "In4.Cu")
		(net "M_L_CS_N<5>")
	)
	(segment
		(start 99.437952 -95.385636)
		(end 99.45751 -95.42018)
		(width 0.0889)
		(layer "In4.Cu")
		(net "M_L_CS_N<5>")
	)
	(segment
		(start 105.212388 -124.434092)
		(end 105.212388 -125.49251)
		(width 0.14224)
		(layer "In4.Cu")
		(net "M_L_CS_N<5>")
	)
	(segment
		(start 102.156768 -103.3018)
		(end 102.156768 -103.552498)
		(width 0.0889)
		(layer "In4.Cu")
		(net "M_L_CS_N<5>")
	)
	(segment
		(start 108.13288 -132.44576)
		(end 108.334556 -132.647436)
		(width 0.14224)
		(layer "In4.Cu")
		(net "M_L_CS_N<5>")
	)
	(segment
		(start 101.115368 -100.1014)
		(end 101.115368 -101.6508)
		(width 0.0889)
		(layer "In4.Cu")
		(net "M_L_CS_N<5>")
	)
	(segment
		(start 100.312474 -97.490788)
		(end 100.307648 -97.499424)
		(width 0.0889)
		(layer "In4.Cu")
		(net "M_L_CS_N<5>")
	)
	(segment
		(start 108.461048 -134.861046)
		(end 108.461048 -135.800338)
		(width 0.14224)
		(layer "In4.Cu")
		(net "M_L_CS_N<5>")
	)
	(segment
		(start 108.181648 -130.00482)
		(end 108.181648 -130.32486)
		(width 0.14224)
		(layer "In4.Cu")
		(net "M_L_CS_N<5>")
	)
	(segment
		(start 108.334556 -134.734554)
		(end 108.461048 -134.861046)
		(width 0.14224)
		(layer "In4.Cu")
		(net "M_L_CS_N<5>")
	)
	(segment
		(start 105.212388 -125.49251)
		(end 108.430568 -128.71069)
		(width 0.14224)
		(layer "In4.Cu")
		(net "M_L_CS_N<5>")
	)
	(segment
		(start 109.163104 -140.067284)
		(end 109.599476 -140.503656)
		(width 0.14224)
		(layer "In4.Cu")
		(net "M_L_CS_N<5>")
	)
	(segment
		(start 102.156768 -121.378472)
		(end 105.212388 -124.434092)
		(width 0.14224)
		(layer "In4.Cu")
		(net "M_L_CS_N<5>")
	)
	(segment
		(start 100.312474 -96.500188)
		(end 100.307648 -96.508824)
		(width 0.0889)
		(layer "In4.Cu")
		(net "M_L_CS_N<5>")
	)
	(segment
		(start 102.156768 -103.552498)
		(end 102.156768 -121.378472)
		(width 0.14224)
		(layer "In4.Cu")
		(net "M_L_CS_N<5>")
	)
	(segment
		(start 98.942398 -94.718886)
		(end 99.437952 -95.385636)
		(width 0.0889)
		(layer "In4.Cu")
		(net "M_L_CS_N<5>")
	)
	(segment
		(start 108.545122 -130.688334)
		(end 108.545122 -131.101846)
		(width 0.14224)
		(layer "In4.Cu")
		(net "M_L_CS_N<5>")
	)
	(segment
		(start 108.181648 -130.32486)
		(end 108.545122 -130.688334)
		(width 0.14224)
		(layer "In4.Cu")
		(net "M_L_CS_N<5>")
	)
	(segment
		(start 100.556568 -99.178364)
		(end 100.556568 -99.5426)
		(width 0.0889)
		(layer "In4.Cu")
		(net "M_L_CS_N<5>")
	)
	(segment
		(start 109.163104 -138.984736)
		(end 109.163104 -140.067284)
		(width 0.14224)
		(layer "In4.Cu")
		(net "M_L_CS_N<5>")
	)
	(segment
		(start 101.648768 -102.7938)
		(end 102.156768 -103.3018)
		(width 0.0889)
		(layer "In4.Cu")
		(net "M_L_CS_N<5>")
	)
	(segment
		(start 108.334556 -138.156188)
		(end 109.163104 -138.984736)
		(width 0.14224)
		(layer "In4.Cu")
		(net "M_L_CS_N<5>")
	)
	(segment
		(start 108.545122 -131.101846)
		(end 108.13288 -131.514088)
		(width 0.14224)
		(layer "In4.Cu")
		(net "M_L_CS_N<5>")
	)
	(segment
		(start 100.556568 -99.5426)
		(end 101.115368 -100.1014)
		(width 0.0889)
		(layer "In4.Cu")
		(net "M_L_CS_N<5>")
	)
	(segment
		(start 108.334556 -135.92683)
		(end 108.334556 -138.156188)
		(width 0.14224)
		(layer "In4.Cu")
		(net "M_L_CS_N<5>")
	)
	(segment
		(start 100.318824 -98.47072)
		(end 100.312474 -98.481388)
		(width 0.0889)
		(layer "In4.Cu")
		(net "M_L_CS_N<5>")
	)
	(segment
		(start 100.318824 -97.48012)
		(end 100.312474 -97.490788)
		(width 0.0889)
		(layer "In4.Cu")
		(net "M_L_CS_N<5>")
	)
	(segment
		(start 99.800664 -95.61449)
		(end 99.822254 -95.61449)
		(width 0.0889)
		(layer "In4.Cu")
		(net "M_L_CS_N<5>")
	)
	(segment
		(start 108.430568 -128.71069)
		(end 108.430568 -129.7559)
		(width 0.14224)
		(layer "In4.Cu")
		(net "M_L_CS_N<5>")
	)
	(segment
		(start 100.318824 -96.48952)
		(end 100.312474 -96.500188)
		(width 0.0889)
		(layer "In4.Cu")
		(net "M_L_CS_N<5>")
	)
	(segment
		(start 101.115368 -101.6508)
		(end 101.648768 -102.1842)
		(width 0.0889)
		(layer "In4.Cu")
		(net "M_L_CS_N<5>")
	)
	(segment
		(start 100.312474 -98.481388)
		(end 100.307648 -98.490024)
		(width 0.0889)
		(layer "In4.Cu")
		(net "M_L_CS_N<5>")
	)
	(segment
		(start 108.13288 -131.514088)
		(end 108.13288 -132.44576)
		(width 0.14224)
		(layer "In4.Cu")
		(net "M_L_CS_N<5>")
	)
	(segment
		(start 109.599476 -140.503656)
		(end 109.599476 -141.183868)
		(width 0.14224)
		(layer "In4.Cu")
		(net "M_L_CS_N<5>")
	)
	(segment
		(start 108.461048 -135.800338)
		(end 108.334556 -135.92683)
		(width 0.14224)
		(layer "In4.Cu")
		(net "M_L_CS_N<5>")
	)
	(segment
		(start 101.648768 -102.1842)
		(end 101.648768 -102.7938)
		(width 0.0889)
		(layer "In4.Cu")
		(net "M_L_CS_N<5>")
	)
	(segment
		(start 100.548694 -99.17049)
		(end 100.556568 -99.178364)
		(width 0.0889)
		(layer "In4.Cu")
		(net "M_L_CS_N<5>")
	)
	(arc
		(start 100.307648 -96.508824)
		(mid 100.258893 -96.705176)
		(end 100.312474 -96.900238)
		(width 0.0889)
		(layer "In4.Cu")
		(net "M_L_CS_N<5>")
	)
	(arc
		(start 100.312474 -96.900238)
		(mid 100.391696 -97.189356)
		(end 100.318824 -97.48012)
		(width 0.0889)
		(layer "In4.Cu")
		(net "M_L_CS_N<5>")
	)
	(arc
		(start 100.307648 -97.499424)
		(mid 100.258893 -97.695776)
		(end 100.312474 -97.890838)
		(width 0.0889)
		(layer "In4.Cu")
		(net "M_L_CS_N<5>")
	)
	(arc
		(start 100.307648 -98.490024)
		(mid 100.258893 -98.686376)
		(end 100.312474 -98.881438)
		(width 0.0889)
		(layer "In4.Cu")
		(net "M_L_CS_N<5>")
	)
	(arc
		(start 100.312474 -98.881438)
		(mid 100.418827 -99.035571)
		(end 100.548694 -99.17049)
		(width 0.0889)
		(layer "In4.Cu")
		(net "M_L_CS_N<5>")
	)
	(arc
		(start 99.822254 -95.61449)
		(mid 100.314644 -95.913423)
		(end 100.318824 -96.48952)
		(width 0.0889)
		(layer "In4.Cu")
		(net "M_L_CS_N<5>")
	)
	(arc
		(start 100.312474 -97.890838)
		(mid 100.391696 -98.179956)
		(end 100.318824 -98.47072)
		(width 0.0889)
		(layer "In4.Cu")
		(net "M_L_CS_N<5>")
	)
	(arc
		(start 99.45751 -95.42018)
		(mid 99.603476 -95.562579)
		(end 99.800664 -95.61449)
		(width 0.0889)
		(layer "In4.Cu")
		(net "M_L_CS_N<5>")
	)
	(segment
		(start 98.655378 -98.18624)
		(end 98.083878 -98.18624)
		(width 0.1016)
		(layer "F.Cu")
		(net "M_L_CS_N<4>")
	)
	(via
		(at 98.083878 -98.18624)
		(size 0.508)
		(drill 0.254)
		(layers "F.Cu" "B.Cu")
		(net "M_L_CS_N<4>")
	)
	(via
		(at 105.349802 -141.187678)
		(size 0.4572)
		(drill 0.2032)
		(layers "F.Cu" "B.Cu")
		(net "M_L_CS_N<4>")
	)
	(segment
		(start 105.349548 -141.187932)
		(end 105.349802 -141.187678)
		(width 0.1651)
		(layer "B.Cu")
		(net "M_L_CS_N<4>")
	)
	(segment
		(start 105.349548 -142.477236)
		(end 105.349548 -141.187932)
		(width 0.1651)
		(layer "B.Cu")
		(net "M_L_CS_N<4>")
	)
	(segment
		(start 104.083866 -133.912102)
		(end 104.188768 -133.8072)
		(width 0.14224)
		(layer "In4.Cu")
		(net "M_L_CS_N<4>")
	)
	(segment
		(start 98.083878 -98.87331)
		(end 98.083878 -98.18624)
		(width 0.0889)
		(layer "In4.Cu")
		(net "M_L_CS_N<4>")
	)
	(segment
		(start 104.018334 -128.315212)
		(end 103.539544 -128.315212)
		(width 0.14224)
		(layer "In4.Cu")
		(net "M_L_CS_N<4>")
	)
	(segment
		(start 104.087422 -136.092946)
		(end 104.137968 -136.0424)
		(width 0.14224)
		(layer "In4.Cu")
		(net "M_L_CS_N<4>")
	)
	(segment
		(start 101.09327 -123.523502)
		(end 100.805996 -123.236228)
		(width 0.14224)
		(layer "In4.Cu")
		(net "M_L_CS_N<4>")
	)
	(segment
		(start 98.461068 -99.2505)
		(end 98.083878 -98.87331)
		(width 0.0889)
		(layer "In4.Cu")
		(net "M_L_CS_N<4>")
	)
	(segment
		(start 104.087422 -138.074654)
		(end 104.087422 -136.092946)
		(width 0.14224)
		(layer "In4.Cu")
		(net "M_L_CS_N<4>")
	)
	(segment
		(start 101.09327 -123.81103)
		(end 101.09327 -123.523502)
		(width 0.14224)
		(layer "In4.Cu")
		(net "M_L_CS_N<4>")
	)
	(segment
		(start 104.083866 -134.743698)
		(end 104.083866 -133.912102)
		(width 0.14224)
		(layer "In4.Cu")
		(net "M_L_CS_N<4>")
	)
	(segment
		(start 100.084636 -123.67006)
		(end 99.797108 -123.67006)
		(width 0.14224)
		(layer "In4.Cu")
		(net "M_L_CS_N<4>")
	)
	(segment
		(start 99.797108 -123.67006)
		(end 99.616768 -123.48972)
		(width 0.14224)
		(layer "In4.Cu")
		(net "M_L_CS_N<4>")
	)
	(segment
		(start 104.9274 -138.914632)
		(end 104.087422 -138.074654)
		(width 0.14224)
		(layer "In4.Cu")
		(net "M_L_CS_N<4>")
	)
	(segment
		(start 103.236522 -127.663194)
		(end 103.369618 -127.530098)
		(width 0.14224)
		(layer "In4.Cu")
		(net "M_L_CS_N<4>")
	)
	(segment
		(start 99.083368 -102.5398)
		(end 99.083368 -102.2096)
		(width 0.0889)
		(layer "In4.Cu")
		(net "M_L_CS_N<4>")
	)
	(segment
		(start 103.369618 -127.530098)
		(end 103.369618 -127.24257)
		(width 0.14224)
		(layer "In4.Cu")
		(net "M_L_CS_N<4>")
	)
	(segment
		(start 98.461068 -101.5873)
		(end 98.461068 -99.2505)
		(width 0.0889)
		(layer "In4.Cu")
		(net "M_L_CS_N<4>")
	)
	(segment
		(start 103.369618 -127.24257)
		(end 100.659438 -124.53239)
		(width 0.14224)
		(layer "In4.Cu")
		(net "M_L_CS_N<4>")
	)
	(segment
		(start 100.805996 -123.236228)
		(end 100.518468 -123.236228)
		(width 0.14224)
		(layer "In4.Cu")
		(net "M_L_CS_N<4>")
	)
	(segment
		(start 104.033574 -129.387854)
		(end 104.342946 -129.078482)
		(width 0.14224)
		(layer "In4.Cu")
		(net "M_L_CS_N<4>")
	)
	(segment
		(start 103.236522 -128.01219)
		(end 103.236522 -127.663194)
		(width 0.14224)
		(layer "In4.Cu")
		(net "M_L_CS_N<4>")
	)
	(segment
		(start 104.137968 -130.4798)
		(end 104.137968 -129.921)
		(width 0.14224)
		(layer "In4.Cu")
		(net "M_L_CS_N<4>")
	)
	(segment
		(start 100.659438 -124.244862)
		(end 101.09327 -123.81103)
		(width 0.14224)
		(layer "In4.Cu")
		(net "M_L_CS_N<4>")
	)
	(segment
		(start 104.188768 -131.3942)
		(end 104.010968 -131.2164)
		(width 0.14224)
		(layer "In4.Cu")
		(net "M_L_CS_N<4>")
	)
	(segment
		(start 105.349802 -141.187678)
		(end 104.9274 -140.765276)
		(width 0.14224)
		(layer "In4.Cu")
		(net "M_L_CS_N<4>")
	)
	(segment
		(start 104.010968 -131.2164)
		(end 104.010968 -130.6068)
		(width 0.14224)
		(layer "In4.Cu")
		(net "M_L_CS_N<4>")
	)
	(segment
		(start 104.137968 -136.0424)
		(end 104.137968 -134.7978)
		(width 0.14224)
		(layer "In4.Cu")
		(net "M_L_CS_N<4>")
	)
	(segment
		(start 103.539544 -128.315212)
		(end 103.236522 -128.01219)
		(width 0.14224)
		(layer "In4.Cu")
		(net "M_L_CS_N<4>")
	)
	(segment
		(start 104.342946 -129.078482)
		(end 104.342946 -128.639824)
		(width 0.14224)
		(layer "In4.Cu")
		(net "M_L_CS_N<4>")
	)
	(segment
		(start 99.616768 -123.48972)
		(end 99.616768 -103.279448)
		(width 0.14224)
		(layer "In4.Cu")
		(net "M_L_CS_N<4>")
	)
	(segment
		(start 104.9274 -140.765276)
		(end 104.9274 -138.914632)
		(width 0.14224)
		(layer "In4.Cu")
		(net "M_L_CS_N<4>")
	)
	(segment
		(start 99.083368 -102.2096)
		(end 98.461068 -101.5873)
		(width 0.0889)
		(layer "In4.Cu")
		(net "M_L_CS_N<4>")
	)
	(segment
		(start 104.342946 -128.639824)
		(end 104.018334 -128.315212)
		(width 0.14224)
		(layer "In4.Cu")
		(net "M_L_CS_N<4>")
	)
	(segment
		(start 104.188768 -133.8072)
		(end 104.188768 -131.3942)
		(width 0.14224)
		(layer "In4.Cu")
		(net "M_L_CS_N<4>")
	)
	(segment
		(start 100.518468 -123.236228)
		(end 100.084636 -123.67006)
		(width 0.14224)
		(layer "In4.Cu")
		(net "M_L_CS_N<4>")
	)
	(segment
		(start 99.616768 -103.279448)
		(end 99.616768 -103.0732)
		(width 0.0889)
		(layer "In4.Cu")
		(net "M_L_CS_N<4>")
	)
	(segment
		(start 104.137968 -129.921)
		(end 104.033574 -129.816606)
		(width 0.14224)
		(layer "In4.Cu")
		(net "M_L_CS_N<4>")
	)
	(segment
		(start 104.010968 -130.6068)
		(end 104.137968 -130.4798)
		(width 0.14224)
		(layer "In4.Cu")
		(net "M_L_CS_N<4>")
	)
	(segment
		(start 104.033574 -129.816606)
		(end 104.033574 -129.387854)
		(width 0.14224)
		(layer "In4.Cu")
		(net "M_L_CS_N<4>")
	)
	(segment
		(start 100.659438 -124.53239)
		(end 100.659438 -124.244862)
		(width 0.14224)
		(layer "In4.Cu")
		(net "M_L_CS_N<4>")
	)
	(segment
		(start 99.616768 -103.0732)
		(end 99.083368 -102.5398)
		(width 0.0889)
		(layer "In4.Cu")
		(net "M_L_CS_N<4>")
	)
	(segment
		(start 104.137968 -134.7978)
		(end 104.083866 -134.743698)
		(width 0.14224)
		(layer "In4.Cu")
		(net "M_L_CS_N<4>")
	)
	(segment
		(start 112.99952 -147.27174)
		(end 112.99952 -145.988786)
		(width 0.1651)
		(layer "F.Cu")
		(net "M_L_CS_N<3>")
	)
	(segment
		(start 101.230684 -93.72854)
		(end 100.659184 -93.72854)
		(width 0.1016)
		(layer "F.Cu")
		(net "M_L_CS_N<3>")
	)
	(segment
		(start 112.99952 -145.988786)
		(end 113.000028 -145.988278)
		(width 0.1651)
		(layer "F.Cu")
		(net "M_L_CS_N<3>")
	)
	(via
		(at 113.000028 -145.988278)
		(size 0.4572)
		(drill 0.2032)
		(layers "F.Cu" "B.Cu")
		(net "M_L_CS_N<3>")
	)
	(via
		(at 100.659184 -93.72854)
		(size 0.508)
		(drill 0.254)
		(layers "F.Cu" "B.Cu")
		(net "M_L_CS_N<3>")
	)
	(segment
		(start 105.204768 -120.20042)
		(end 113.486438 -128.48209)
		(width 0.14224)
		(layer "In4.Cu")
		(net "M_L_CS_N<3>")
	)
	(segment
		(start 113.535968 -136.9568)
		(end 113.535968 -139.319)
		(width 0.14224)
		(layer "In4.Cu")
		(net "M_L_CS_N<3>")
	)
	(segment
		(start 113.231168 -140.0048)
		(end 113.485168 -140.2588)
		(width 0.14224)
		(layer "In4.Cu")
		(net "M_L_CS_N<3>")
	)
	(segment
		(start 113.612168 -141.6812)
		(end 113.612168 -144.0942)
		(width 0.14224)
		(layer "In4.Cu")
		(net "M_L_CS_N<3>")
	)
	(segment
		(start 113.42878 -134.719568)
		(end 113.42878 -136.849612)
		(width 0.14224)
		(layer "In4.Cu")
		(net "M_L_CS_N<3>")
	)
	(segment
		(start 105.204768 -103.333804)
		(end 105.204768 -120.20042)
		(width 0.14224)
		(layer "In4.Cu")
		(net "M_L_CS_N<3>")
	)
	(segment
		(start 105.052368 -101.6762)
		(end 105.052368 -102.944168)
		(width 0.0889)
		(layer "In4.Cu")
		(net "M_L_CS_N<3>")
	)
	(segment
		(start 103.604568 -96.974152)
		(end 104.010968 -97.380552)
		(width 0.0889)
		(layer "In4.Cu")
		(net "M_L_CS_N<3>")
	)
	(segment
		(start 113.256568 -130.4544)
		(end 113.486438 -130.68427)
		(width 0.14224)
		(layer "In4.Cu")
		(net "M_L_CS_N<3>")
	)
	(segment
		(start 103.604568 -95.0468)
		(end 103.604568 -96.974152)
		(width 0.0889)
		(layer "In4.Cu")
		(net "M_L_CS_N<3>")
	)
	(segment
		(start 113.485168 -141.5542)
		(end 113.612168 -141.6812)
		(width 0.14224)
		(layer "In4.Cu")
		(net "M_L_CS_N<3>")
	)
	(segment
		(start 101.702108 -93.72854)
		(end 102.207568 -94.234)
		(width 0.0889)
		(layer "In4.Cu")
		(net "M_L_CS_N<3>")
	)
	(segment
		(start 102.207568 -94.234)
		(end 102.791768 -94.234)
		(width 0.0889)
		(layer "In4.Cu")
		(net "M_L_CS_N<3>")
	)
	(segment
		(start 113.612168 -144.0942)
		(end 112.99952 -144.706848)
		(width 0.14224)
		(layer "In4.Cu")
		(net "M_L_CS_N<3>")
	)
	(segment
		(start 100.659184 -93.72854)
		(end 101.702108 -93.72854)
		(width 0.0889)
		(layer "In4.Cu")
		(net "M_L_CS_N<3>")
	)
	(segment
		(start 105.204768 -103.096568)
		(end 105.204768 -103.333804)
		(width 0.0889)
		(layer "In4.Cu")
		(net "M_L_CS_N<3>")
	)
	(segment
		(start 112.99952 -144.706848)
		(end 112.99952 -145.98777)
		(width 0.14224)
		(layer "In4.Cu")
		(net "M_L_CS_N<3>")
	)
	(segment
		(start 105.052368 -102.944168)
		(end 105.204768 -103.096568)
		(width 0.0889)
		(layer "In4.Cu")
		(net "M_L_CS_N<3>")
	)
	(segment
		(start 113.486438 -132.0165)
		(end 113.40719 -132.095748)
		(width 0.14224)
		(layer "In4.Cu")
		(net "M_L_CS_N<3>")
	)
	(segment
		(start 112.99952 -145.98777)
		(end 113.000028 -145.988278)
		(width 0.14224)
		(layer "In4.Cu")
		(net "M_L_CS_N<3>")
	)
	(segment
		(start 113.231168 -139.6238)
		(end 113.231168 -140.0048)
		(width 0.14224)
		(layer "In4.Cu")
		(net "M_L_CS_N<3>")
	)
	(segment
		(start 113.486438 -129.76733)
		(end 113.256568 -129.9972)
		(width 0.14224)
		(layer "In4.Cu")
		(net "M_L_CS_N<3>")
	)
	(segment
		(start 113.256568 -129.9972)
		(end 113.256568 -130.4544)
		(width 0.14224)
		(layer "In4.Cu")
		(net "M_L_CS_N<3>")
	)
	(segment
		(start 113.486438 -130.68427)
		(end 113.486438 -132.0165)
		(width 0.14224)
		(layer "In4.Cu")
		(net "M_L_CS_N<3>")
	)
	(segment
		(start 113.486438 -128.48209)
		(end 113.486438 -129.76733)
		(width 0.14224)
		(layer "In4.Cu")
		(net "M_L_CS_N<3>")
	)
	(segment
		(start 113.40719 -134.697978)
		(end 113.42878 -134.719568)
		(width 0.14224)
		(layer "In4.Cu")
		(net "M_L_CS_N<3>")
	)
	(segment
		(start 104.010968 -97.380552)
		(end 104.010968 -100.6348)
		(width 0.0889)
		(layer "In4.Cu")
		(net "M_L_CS_N<3>")
	)
	(segment
		(start 113.40719 -132.095748)
		(end 113.40719 -134.697978)
		(width 0.14224)
		(layer "In4.Cu")
		(net "M_L_CS_N<3>")
	)
	(segment
		(start 113.535968 -139.319)
		(end 113.231168 -139.6238)
		(width 0.14224)
		(layer "In4.Cu")
		(net "M_L_CS_N<3>")
	)
	(segment
		(start 113.485168 -140.2588)
		(end 113.485168 -141.5542)
		(width 0.14224)
		(layer "In4.Cu")
		(net "M_L_CS_N<3>")
	)
	(segment
		(start 113.42878 -136.849612)
		(end 113.535968 -136.9568)
		(width 0.14224)
		(layer "In4.Cu")
		(net "M_L_CS_N<3>")
	)
	(segment
		(start 104.010968 -100.6348)
		(end 105.052368 -101.6762)
		(width 0.0889)
		(layer "In4.Cu")
		(net "M_L_CS_N<3>")
	)
	(segment
		(start 102.791768 -94.234)
		(end 103.604568 -95.0468)
		(width 0.0889)
		(layer "In4.Cu")
		(net "M_L_CS_N<3>")
	)
	(segment
		(start 112.99952 -142.6718)
		(end 112.99952 -143.972788)
		(width 0.1651)
		(layer "F.Cu")
		(net "M_L_CS_N<2>")
	)
	(segment
		(start 102.089204 -96.20504)
		(end 101.517704 -96.20504)
		(width 0.1016)
		(layer "F.Cu")
		(net "M_L_CS_N<2>")
	)
	(via
		(at 112.99952 -143.972788)
		(size 0.4572)
		(drill 0.2032)
		(layers "F.Cu" "B.Cu")
		(net "M_L_CS_N<2>")
	)
	(via
		(at 101.517704 -96.20504)
		(size 0.508)
		(drill 0.254)
		(layers "F.Cu" "B.Cu")
		(net "M_L_CS_N<2>")
	)
	(segment
		(start 112.99952 -143.972788)
		(end 112.545368 -143.518636)
		(width 0.14224)
		(layer "In4.Cu")
		(net "M_L_CS_N<2>")
	)
	(segment
		(start 103.807768 -102.543864)
		(end 103.807768 -102.0572)
		(width 0.0889)
		(layer "In4.Cu")
		(net "M_L_CS_N<2>")
	)
	(segment
		(start 103.680768 -120.859804)
		(end 103.680768 -102.960932)
		(width 0.14224)
		(layer "In4.Cu")
		(net "M_L_CS_N<2>")
	)
	(segment
		(start 110.875826 -131.996942)
		(end 110.919768 -131.953)
		(width 0.14224)
		(layer "In4.Cu")
		(net "M_L_CS_N<2>")
	)
	(segment
		(start 111.71174 -140.060172)
		(end 111.71174 -138.891772)
		(width 0.14224)
		(layer "In4.Cu")
		(net "M_L_CS_N<2>")
	)
	(segment
		(start 110.818168 -131.191)
		(end 110.818168 -130.6576)
		(width 0.14224)
		(layer "In4.Cu")
		(net "M_L_CS_N<2>")
	)
	(segment
		(start 110.919768 -129.9718)
		(end 110.827312 -129.879344)
		(width 0.14224)
		(layer "In4.Cu")
		(net "M_L_CS_N<2>")
	)
	(segment
		(start 101.826568 -96.7994)
		(end 101.826568 -96.513904)
		(width 0.0889)
		(layer "In4.Cu")
		(net "M_L_CS_N<2>")
	)
	(segment
		(start 101.826568 -96.513904)
		(end 101.517704 -96.20504)
		(width 0.0889)
		(layer "In4.Cu")
		(net "M_L_CS_N<2>")
	)
	(segment
		(start 110.818168 -130.6576)
		(end 110.919768 -130.556)
		(width 0.14224)
		(layer "In4.Cu")
		(net "M_L_CS_N<2>")
	)
	(segment
		(start 112.545368 -141.5796)
		(end 112.584992 -141.539976)
		(width 0.14224)
		(layer "In4.Cu")
		(net "M_L_CS_N<2>")
	)
	(segment
		(start 110.86465 -135.360918)
		(end 110.875826 -135.349742)
		(width 0.14224)
		(layer "In4.Cu")
		(net "M_L_CS_N<2>")
	)
	(segment
		(start 112.584992 -141.539976)
		(end 112.584992 -140.933424)
		(width 0.14224)
		(layer "In4.Cu")
		(net "M_L_CS_N<2>")
	)
	(segment
		(start 110.86465 -138.044682)
		(end 110.86465 -135.360918)
		(width 0.14224)
		(layer "In4.Cu")
		(net "M_L_CS_N<2>")
	)
	(segment
		(start 103.680768 -102.960932)
		(end 103.680768 -102.670864)
		(width 0.0889)
		(layer "In4.Cu")
		(net "M_L_CS_N<2>")
	)
	(segment
		(start 110.919768 -131.2926)
		(end 110.818168 -131.191)
		(width 0.14224)
		(layer "In4.Cu")
		(net "M_L_CS_N<2>")
	)
	(segment
		(start 110.919768 -131.953)
		(end 110.919768 -131.2926)
		(width 0.14224)
		(layer "In4.Cu")
		(net "M_L_CS_N<2>")
	)
	(segment
		(start 111.71174 -138.891772)
		(end 110.86465 -138.044682)
		(width 0.14224)
		(layer "In4.Cu")
		(net "M_L_CS_N<2>")
	)
	(segment
		(start 110.827312 -129.879344)
		(end 110.827312 -128.951736)
		(width 0.14224)
		(layer "In4.Cu")
		(net "M_L_CS_N<2>")
	)
	(segment
		(start 110.827312 -128.951736)
		(end 106.736388 -124.860812)
		(width 0.14224)
		(layer "In4.Cu")
		(net "M_L_CS_N<2>")
	)
	(segment
		(start 112.584992 -140.933424)
		(end 111.71174 -140.060172)
		(width 0.14224)
		(layer "In4.Cu")
		(net "M_L_CS_N<2>")
	)
	(segment
		(start 103.121968 -101.3714)
		(end 103.121968 -98.0948)
		(width 0.0889)
		(layer "In4.Cu")
		(net "M_L_CS_N<2>")
	)
	(segment
		(start 110.875826 -135.349742)
		(end 110.875826 -131.996942)
		(width 0.14224)
		(layer "In4.Cu")
		(net "M_L_CS_N<2>")
	)
	(segment
		(start 103.680768 -102.670864)
		(end 103.807768 -102.543864)
		(width 0.0889)
		(layer "In4.Cu")
		(net "M_L_CS_N<2>")
	)
	(segment
		(start 110.919768 -130.556)
		(end 110.919768 -129.9718)
		(width 0.14224)
		(layer "In4.Cu")
		(net "M_L_CS_N<2>")
	)
	(segment
		(start 112.545368 -143.518636)
		(end 112.545368 -141.5796)
		(width 0.14224)
		(layer "In4.Cu")
		(net "M_L_CS_N<2>")
	)
	(segment
		(start 103.121968 -98.0948)
		(end 101.826568 -96.7994)
		(width 0.0889)
		(layer "In4.Cu")
		(net "M_L_CS_N<2>")
	)
	(segment
		(start 103.807768 -102.0572)
		(end 103.121968 -101.3714)
		(width 0.0889)
		(layer "In4.Cu")
		(net "M_L_CS_N<2>")
	)
	(segment
		(start 106.736388 -123.915424)
		(end 103.680768 -120.859804)
		(width 0.14224)
		(layer "In4.Cu")
		(net "M_L_CS_N<2>")
	)
	(segment
		(start 106.736388 -124.860812)
		(end 106.736388 -123.915424)
		(width 0.14224)
		(layer "In4.Cu")
		(net "M_L_CS_N<2>")
	)
	(segment
		(start 109.599476 -142.6718)
		(end 109.599476 -143.968978)
		(width 0.1651)
		(layer "F.Cu")
		(net "M_L_CS_N<1>")
	)
	(segment
		(start 98.655378 -95.21444)
		(end 98.083878 -95.21444)
		(width 0.1016)
		(layer "F.Cu")
		(net "M_L_CS_N<1>")
	)
	(via
		(at 109.599476 -143.968978)
		(size 0.508)
		(drill 0.254)
		(layers "F.Cu" "B.Cu")
		(net "M_L_CS_N<1>")
	)
	(via
		(at 98.083878 -95.21444)
		(size 0.508)
		(drill 0.254)
		(layers "F.Cu" "B.Cu")
		(net "M_L_CS_N<1>")
	)
	(segment
		(start 100.147374 -97.395538)
		(end 100.141024 -97.406206)
		(width 0.0889)
		(layer "In4.Cu")
		(net "M_L_CS_N<1>")
	)
	(segment
		(start 101.648768 -103.3272)
		(end 101.648768 -103.53421)
		(width 0.0889)
		(layer "In4.Cu")
		(net "M_L_CS_N<1>")
	)
	(segment
		(start 98.083878 -95.21444)
		(end 98.413824 -95.976186)
		(width 0.0889)
		(layer "In4.Cu")
		(net "M_L_CS_N<1>")
	)
	(segment
		(start 107.592368 -130.4798)
		(end 107.414568 -130.6576)
		(width 0.14224)
		(layer "In4.Cu")
		(net "M_L_CS_N<1>")
	)
	(segment
		(start 108.338112 -138.896344)
		(end 108.338112 -139.436856)
		(width 0.14224)
		(layer "In4.Cu")
		(net "M_L_CS_N<1>")
	)
	(segment
		(start 107.414568 -131.1402)
		(end 107.541568 -131.2672)
		(width 0.14224)
		(layer "In4.Cu")
		(net "M_L_CS_N<1>")
	)
	(segment
		(start 108.227368 -139.5476)
		(end 108.227368 -140.015976)
		(width 0.14224)
		(layer "In4.Cu")
		(net "M_L_CS_N<1>")
	)
	(segment
		(start 107.414568 -130.6576)
		(end 107.414568 -131.1402)
		(width 0.14224)
		(layer "In4.Cu")
		(net "M_L_CS_N<1>")
	)
	(segment
		(start 101.648768 -103.53421)
		(end 101.648768 -121.532904)
		(width 0.14224)
		(layer "In4.Cu")
		(net "M_L_CS_N<1>")
	)
	(segment
		(start 109.187234 -143.556736)
		(end 109.599476 -143.968978)
		(width 0.14224)
		(layer "In4.Cu")
		(net "M_L_CS_N<1>")
	)
	(segment
		(start 107.566968 -135.93826)
		(end 107.461304 -136.043924)
		(width 0.14224)
		(layer "In4.Cu")
		(net "M_L_CS_N<1>")
	)
	(segment
		(start 107.461304 -138.019536)
		(end 108.338112 -138.896344)
		(width 0.14224)
		(layer "In4.Cu")
		(net "M_L_CS_N<1>")
	)
	(segment
		(start 108.227368 -140.015976)
		(end 109.187234 -140.975842)
		(width 0.14224)
		(layer "In4.Cu")
		(net "M_L_CS_N<1>")
	)
	(segment
		(start 100.1522 -97.386902)
		(end 100.147374 -97.395538)
		(width 0.0889)
		(layer "In4.Cu")
		(net "M_L_CS_N<1>")
	)
	(segment
		(start 107.352338 -128.351026)
		(end 107.352338 -129.85877)
		(width 0.14224)
		(layer "In4.Cu")
		(net "M_L_CS_N<1>")
	)
	(segment
		(start 108.338112 -139.436856)
		(end 108.227368 -139.5476)
		(width 0.14224)
		(layer "In4.Cu")
		(net "M_L_CS_N<1>")
	)
	(segment
		(start 107.461304 -136.043924)
		(end 107.461304 -138.019536)
		(width 0.14224)
		(layer "In4.Cu")
		(net "M_L_CS_N<1>")
	)
	(segment
		(start 98.413824 -95.976186)
		(end 98.430588 -96.004888)
		(width 0.0889)
		(layer "In4.Cu")
		(net "M_L_CS_N<1>")
	)
	(segment
		(start 107.465368 -131.9784)
		(end 107.465368 -134.7216)
		(width 0.14224)
		(layer "In4.Cu")
		(net "M_L_CS_N<1>")
	)
	(segment
		(start 100.200968 -99.176586)
		(end 100.200968 -99.695)
		(width 0.0889)
		(layer "In4.Cu")
		(net "M_L_CS_N<1>")
	)
	(segment
		(start 100.147374 -98.386138)
		(end 100.141024 -98.396806)
		(width 0.0889)
		(layer "In4.Cu")
		(net "M_L_CS_N<1>")
	)
	(segment
		(start 100.200968 -99.695)
		(end 100.810568 -100.3046)
		(width 0.0889)
		(layer "In4.Cu")
		(net "M_L_CS_N<1>")
	)
	(segment
		(start 100.1522 -98.377502)
		(end 100.147374 -98.386138)
		(width 0.0889)
		(layer "In4.Cu")
		(net "M_L_CS_N<1>")
	)
	(segment
		(start 104.704388 -125.703076)
		(end 107.352338 -128.351026)
		(width 0.14224)
		(layer "In4.Cu")
		(net "M_L_CS_N<1>")
	)
	(segment
		(start 107.566968 -134.8232)
		(end 107.566968 -135.93826)
		(width 0.14224)
		(layer "In4.Cu")
		(net "M_L_CS_N<1>")
	)
	(segment
		(start 107.352338 -129.85877)
		(end 107.592368 -130.0988)
		(width 0.14224)
		(layer "In4.Cu")
		(net "M_L_CS_N<1>")
	)
	(segment
		(start 101.648768 -121.532904)
		(end 104.704388 -124.588524)
		(width 0.14224)
		(layer "In4.Cu")
		(net "M_L_CS_N<1>")
	)
	(segment
		(start 99.782884 -96.79559)
		(end 99.81565 -96.79559)
		(width 0.0889)
		(layer "In4.Cu")
		(net "M_L_CS_N<1>")
	)
	(segment
		(start 100.810568 -100.3046)
		(end 100.810568 -102.489)
		(width 0.0889)
		(layer "In4.Cu")
		(net "M_L_CS_N<1>")
	)
	(segment
		(start 107.541568 -131.9022)
		(end 107.465368 -131.9784)
		(width 0.14224)
		(layer "In4.Cu")
		(net "M_L_CS_N<1>")
	)
	(segment
		(start 98.920808 -96.300036)
		(end 98.942398 -96.300036)
		(width 0.0889)
		(layer "In4.Cu")
		(net "M_L_CS_N<1>")
	)
	(segment
		(start 107.592368 -130.0988)
		(end 107.592368 -130.4798)
		(width 0.14224)
		(layer "In4.Cu")
		(net "M_L_CS_N<1>")
	)
	(segment
		(start 100.810568 -102.489)
		(end 101.648768 -103.3272)
		(width 0.0889)
		(layer "In4.Cu")
		(net "M_L_CS_N<1>")
	)
	(segment
		(start 109.187234 -140.975842)
		(end 109.187234 -143.556736)
		(width 0.14224)
		(layer "In4.Cu")
		(net "M_L_CS_N<1>")
	)
	(segment
		(start 99.285552 -96.494346)
		(end 99.288854 -96.500188)
		(width 0.0889)
		(layer "In4.Cu")
		(net "M_L_CS_N<1>")
	)
	(segment
		(start 107.465368 -134.7216)
		(end 107.566968 -134.8232)
		(width 0.14224)
		(layer "In4.Cu")
		(net "M_L_CS_N<1>")
	)
	(segment
		(start 107.541568 -131.2672)
		(end 107.541568 -131.9022)
		(width 0.14224)
		(layer "In4.Cu")
		(net "M_L_CS_N<1>")
	)
	(segment
		(start 104.704388 -124.588524)
		(end 104.704388 -125.703076)
		(width 0.14224)
		(layer "In4.Cu")
		(net "M_L_CS_N<1>")
	)
	(arc
		(start 99.288854 -96.500188)
		(mid 99.497462 -96.71212)
		(end 99.782884 -96.79559)
		(width 0.0889)
		(layer "In4.Cu")
		(net "M_L_CS_N<1>")
	)
	(arc
		(start 100.147374 -98.976688)
		(mid 100.187317 -99.073111)
		(end 100.200968 -99.176586)
		(width 0.0889)
		(layer "In4.Cu")
		(net "M_L_CS_N<1>")
	)
	(arc
		(start 100.141024 -97.406206)
		(mid 100.068226 -97.696969)
		(end 100.147374 -97.986088)
		(width 0.0889)
		(layer "In4.Cu")
		(net "M_L_CS_N<1>")
	)
	(arc
		(start 98.942398 -96.300036)
		(mid 99.139559 -96.351995)
		(end 99.285552 -96.494346)
		(width 0.0889)
		(layer "In4.Cu")
		(net "M_L_CS_N<1>")
	)
	(arc
		(start 100.147374 -97.986088)
		(mid 100.200844 -98.181151)
		(end 100.1522 -98.377502)
		(width 0.0889)
		(layer "In4.Cu")
		(net "M_L_CS_N<1>")
	)
	(arc
		(start 100.141024 -98.396806)
		(mid 100.068226 -98.687569)
		(end 100.147374 -98.976688)
		(width 0.0889)
		(layer "In4.Cu")
		(net "M_L_CS_N<1>")
	)
	(arc
		(start 98.430588 -96.004888)
		(mid 98.637592 -96.215752)
		(end 98.920808 -96.300036)
		(width 0.0889)
		(layer "In4.Cu")
		(net "M_L_CS_N<1>")
	)
	(arc
		(start 99.81565 -96.79559)
		(mid 100.148568 -96.997581)
		(end 100.1522 -97.386902)
		(width 0.0889)
		(layer "In4.Cu")
		(net "M_L_CS_N<1>")
	)
	(segment
		(start 105.349548 -143.972534)
		(end 105.349802 -143.972788)
		(width 0.1651)
		(layer "F.Cu")
		(net "M_L_CS_N<0>")
	)
	(segment
		(start 105.349548 -142.6718)
		(end 105.349548 -143.972534)
		(width 0.1651)
		(layer "F.Cu")
		(net "M_L_CS_N<0>")
	)
	(segment
		(start 97.796858 -97.690686)
		(end 97.225358 -97.690686)
		(width 0.1016)
		(layer "F.Cu")
		(net "M_L_CS_N<0>")
	)
	(via
		(at 105.349802 -143.972788)
		(size 0.4572)
		(drill 0.2032)
		(layers "F.Cu" "B.Cu")
		(net "M_L_CS_N<0>")
	)
	(via
		(at 97.225358 -97.690686)
		(size 0.508)
		(drill 0.254)
		(layers "F.Cu" "B.Cu")
		(net "M_L_CS_N<0>")
	)
	(segment
		(start 103.274368 -131.191)
		(end 103.274368 -130.6322)
		(width 0.14224)
		(layer "In4.Cu")
		(net "M_L_CS_N<0>")
	)
	(segment
		(start 103.274368 -130.6322)
		(end 103.172768 -130.5306)
		(width 0.14224)
		(layer "In4.Cu")
		(net "M_L_CS_N<0>")
	)
	(segment
		(start 103.59263 -132.27685)
		(end 103.179118 -132.27685)
		(width 0.14224)
		(layer "In4.Cu")
		(net "M_L_CS_N<0>")
	)
	(segment
		(start 104.112568 -140.699236)
		(end 104.112568 -139.4968)
		(width 0.14224)
		(layer "In4.Cu")
		(net "M_L_CS_N<0>")
	)
	(segment
		(start 103.74757 -132.43179)
		(end 103.59263 -132.27685)
		(width 0.14224)
		(layer "In4.Cu")
		(net "M_L_CS_N<0>")
	)
	(segment
		(start 99.108768 -103.26116)
		(end 99.108768 -103.064564)
		(width 0.0889)
		(layer "In4.Cu")
		(net "M_L_CS_N<0>")
	)
	(segment
		(start 97.660968 -98.126296)
		(end 97.225358 -97.690686)
		(width 0.0889)
		(layer "In4.Cu")
		(net "M_L_CS_N<0>")
	)
	(segment
		(start 103.212646 -133.859524)
		(end 102.905306 -133.552184)
		(width 0.14224)
		(layer "In4.Cu")
		(net "M_L_CS_N<0>")
	)
	(segment
		(start 103.214424 -136.668256)
		(end 103.214424 -136.109456)
		(width 0.14224)
		(layer "In4.Cu")
		(net "M_L_CS_N<0>")
	)
	(segment
		(start 103.11003 -134.885938)
		(end 103.212646 -134.783322)
		(width 0.14224)
		(layer "In4.Cu")
		(net "M_L_CS_N<0>")
	)
	(segment
		(start 103.179118 -132.27685)
		(end 103.024178 -132.12191)
		(width 0.14224)
		(layer "In4.Cu")
		(net "M_L_CS_N<0>")
	)
	(segment
		(start 105.349802 -142.14856)
		(end 104.921812 -141.72057)
		(width 0.14224)
		(layer "In4.Cu")
		(net "M_L_CS_N<0>")
	)
	(segment
		(start 102.081076 -128.150112)
		(end 102.436168 -127.79502)
		(width 0.14224)
		(layer "In4.Cu")
		(net "M_L_CS_N<0>")
	)
	(segment
		(start 104.083866 -139.468098)
		(end 104.083866 -138.833098)
		(width 0.14224)
		(layer "In4.Cu")
		(net "M_L_CS_N<0>")
	)
	(segment
		(start 102.081076 -128.43764)
		(end 102.081076 -128.150112)
		(width 0.14224)
		(layer "In4.Cu")
		(net "M_L_CS_N<0>")
	)
	(segment
		(start 102.436168 -127.028194)
		(end 101.444044 -126.03607)
		(width 0.14224)
		(layer "In4.Cu")
		(net "M_L_CS_N<0>")
	)
	(segment
		(start 103.59263 -132.93979)
		(end 103.74757 -132.78485)
		(width 0.14224)
		(layer "In4.Cu")
		(net "M_L_CS_N<0>")
	)
	(segment
		(start 104.390444 -141.72057)
		(end 104.059482 -141.389608)
		(width 0.14224)
		(layer "In4.Cu")
		(net "M_L_CS_N<0>")
	)
	(segment
		(start 105.349802 -143.972788)
		(end 105.349802 -142.14856)
		(width 0.14224)
		(layer "In4.Cu")
		(net "M_L_CS_N<0>")
	)
	(segment
		(start 98.067368 -99.441)
		(end 97.660968 -99.0346)
		(width 0.0889)
		(layer "In4.Cu")
		(net "M_L_CS_N<0>")
	)
	(segment
		(start 99.108768 -123.70054)
		(end 99.108768 -103.26116)
		(width 0.14224)
		(layer "In4.Cu")
		(net "M_L_CS_N<0>")
	)
	(segment
		(start 103.024178 -131.44119)
		(end 103.274368 -131.191)
		(width 0.14224)
		(layer "In4.Cu")
		(net "M_L_CS_N<0>")
	)
	(segment
		(start 103.74757 -132.78485)
		(end 103.74757 -132.43179)
		(width 0.14224)
		(layer "In4.Cu")
		(net "M_L_CS_N<0>")
	)
	(segment
		(start 103.172768 -129.9464)
		(end 103.502968 -129.6162)
		(width 0.14224)
		(layer "In4.Cu")
		(net "M_L_CS_N<0>")
	)
	(segment
		(start 102.905306 -133.144006)
		(end 103.109522 -132.93979)
		(width 0.14224)
		(layer "In4.Cu")
		(net "M_L_CS_N<0>")
	)
	(segment
		(start 103.214424 -136.109456)
		(end 103.11003 -136.005062)
		(width 0.14224)
		(layer "In4.Cu")
		(net "M_L_CS_N<0>")
	)
	(segment
		(start 102.905306 -133.552184)
		(end 102.905306 -133.144006)
		(width 0.14224)
		(layer "In4.Cu")
		(net "M_L_CS_N<0>")
	)
	(segment
		(start 102.436168 -127.79502)
		(end 102.436168 -127.028194)
		(width 0.14224)
		(layer "In4.Cu")
		(net "M_L_CS_N<0>")
	)
	(segment
		(start 103.172768 -130.5306)
		(end 103.172768 -129.9464)
		(width 0.14224)
		(layer "In4.Cu")
		(net "M_L_CS_N<0>")
	)
	(segment
		(start 104.112568 -139.4968)
		(end 104.083866 -139.468098)
		(width 0.14224)
		(layer "In4.Cu")
		(net "M_L_CS_N<0>")
	)
	(segment
		(start 103.375968 -138.1252)
		(end 103.375968 -136.8298)
		(width 0.14224)
		(layer "In4.Cu")
		(net "M_L_CS_N<0>")
	)
	(segment
		(start 103.212646 -134.783322)
		(end 103.212646 -133.859524)
		(width 0.14224)
		(layer "In4.Cu")
		(net "M_L_CS_N<0>")
	)
	(segment
		(start 104.059482 -141.389608)
		(end 104.059482 -140.752322)
		(width 0.14224)
		(layer "In4.Cu")
		(net "M_L_CS_N<0>")
	)
	(segment
		(start 98.803968 -102.759764)
		(end 98.803968 -102.489)
		(width 0.0889)
		(layer "In4.Cu")
		(net "M_L_CS_N<0>")
	)
	(segment
		(start 103.502968 -129.6162)
		(end 103.502968 -129.105152)
		(width 0.14224)
		(layer "In4.Cu")
		(net "M_L_CS_N<0>")
	)
	(segment
		(start 103.024178 -132.12191)
		(end 103.024178 -131.44119)
		(width 0.14224)
		(layer "In4.Cu")
		(net "M_L_CS_N<0>")
	)
	(segment
		(start 101.444298 -126.03607)
		(end 99.108768 -123.70054)
		(width 0.14224)
		(layer "In4.Cu")
		(net "M_L_CS_N<0>")
	)
	(segment
		(start 103.109522 -132.93979)
		(end 103.59263 -132.93979)
		(width 0.14224)
		(layer "In4.Cu")
		(net "M_L_CS_N<0>")
	)
	(segment
		(start 98.067368 -101.7524)
		(end 98.067368 -99.441)
		(width 0.0889)
		(layer "In4.Cu")
		(net "M_L_CS_N<0>")
	)
	(segment
		(start 103.201216 -128.8034)
		(end 102.446836 -128.8034)
		(width 0.14224)
		(layer "In4.Cu")
		(net "M_L_CS_N<0>")
	)
	(segment
		(start 98.803968 -102.489)
		(end 98.067368 -101.7524)
		(width 0.0889)
		(layer "In4.Cu")
		(net "M_L_CS_N<0>")
	)
	(segment
		(start 103.11003 -136.005062)
		(end 103.11003 -134.885938)
		(width 0.14224)
		(layer "In4.Cu")
		(net "M_L_CS_N<0>")
	)
	(segment
		(start 103.375968 -136.8298)
		(end 103.214424 -136.668256)
		(width 0.14224)
		(layer "In4.Cu")
		(net "M_L_CS_N<0>")
	)
	(segment
		(start 99.108768 -103.064564)
		(end 98.803968 -102.759764)
		(width 0.0889)
		(layer "In4.Cu")
		(net "M_L_CS_N<0>")
	)
	(segment
		(start 103.502968 -129.105152)
		(end 103.201216 -128.8034)
		(width 0.14224)
		(layer "In4.Cu")
		(net "M_L_CS_N<0>")
	)
	(segment
		(start 104.921812 -141.72057)
		(end 104.390444 -141.72057)
		(width 0.14224)
		(layer "In4.Cu")
		(net "M_L_CS_N<0>")
	)
	(segment
		(start 104.059482 -140.752322)
		(end 104.112568 -140.699236)
		(width 0.14224)
		(layer "In4.Cu")
		(net "M_L_CS_N<0>")
	)
	(segment
		(start 97.660968 -99.0346)
		(end 97.660968 -98.126296)
		(width 0.0889)
		(layer "In4.Cu")
		(net "M_L_CS_N<0>")
	)
	(segment
		(start 102.446836 -128.8034)
		(end 102.081076 -128.43764)
		(width 0.14224)
		(layer "In4.Cu")
		(net "M_L_CS_N<0>")
	)
	(segment
		(start 104.083866 -138.833098)
		(end 103.375968 -138.1252)
		(width 0.14224)
		(layer "In4.Cu")
		(net "M_L_CS_N<0>")
	)
	(segment
		(start 101.444044 -126.03607)
		(end 101.444298 -126.03607)
		(width 0.14224)
		(layer "In4.Cu")
		(net "M_L_CS_N<0>")
	)
	(segment
		(start 93.504258 -96.20504)
		(end 92.932758 -96.20504)
		(width 0.1016)
		(layer "F.Cu")
		(net "M_L_CLK_DP<3>")
	)
	(via
		(at 91.825572 -139.170156)
		(size 0.508)
		(drill 0.254)
		(layers "F.Cu" "B.Cu")
		(net "M_L_CLK_DP<3>")
	)
	(via
		(at 92.932758 -96.20504)
		(size 0.508)
		(drill 0.254)
		(layers "F.Cu" "B.Cu")
		(net "M_L_CLK_DP<3>")
	)
	(segment
		(start 91.749372 -137.877296)
		(end 91.749372 -139.093956)
		(width 0.1651)
		(layer "B.Cu")
		(net "M_L_CLK_DP<3>")
	)
	(segment
		(start 91.749372 -139.093956)
		(end 91.825572 -139.170156)
		(width 0.1651)
		(layer "B.Cu")
		(net "M_L_CLK_DP<3>")
	)
	(segment
		(start 94.277688 -139.34948)
		(end 94.277688 -138.16584)
		(width 0.14224)
		(layer "In4.Cu")
		(net "M_L_CLK_DP<3>")
	)
	(segment
		(start 91.951048 -139.934696)
		(end 92.351352 -140.335)
		(width 0.14224)
		(layer "In4.Cu")
		(net "M_L_CLK_DP<3>")
	)
	(segment
		(start 93.927168 -103.941118)
		(end 93.927168 -103.479346)
		(width 0.0889)
		(layer "In4.Cu")
		(net "M_L_CLK_DP<3>")
	)
	(segment
		(start 92.581222 -131.87553)
		(end 92.787978 -131.668774)
		(width 0.14224)
		(layer "In4.Cu")
		(net "M_L_CLK_DP<3>")
	)
	(segment
		(start 93.292168 -140.335)
		(end 94.277688 -139.34948)
		(width 0.14224)
		(layer "In4.Cu")
		(net "M_L_CLK_DP<3>")
	)
	(segment
		(start 93.97238 -104.015794)
		(end 93.97238 -103.98633)
		(width 0.0889)
		(layer "In4.Cu")
		(net "M_L_CLK_DP<3>")
	)
	(segment
		(start 94.277688 -133.045962)
		(end 93.899736 -132.66801)
		(width 0.14224)
		(layer "In4.Cu")
		(net "M_L_CLK_DP<3>")
	)
	(segment
		(start 92.581222 -132.48894)
		(end 92.581222 -131.87553)
		(width 0.14224)
		(layer "In4.Cu")
		(net "M_L_CLK_DP<3>")
	)
	(segment
		(start 92.695014 -137.19048)
		(end 93.965268 -137.19048)
		(width 0.14224)
		(layer "In4.Cu")
		(net "M_L_CLK_DP<3>")
	)
	(segment
		(start 92.676726 -137.85342)
		(end 92.53093 -137.707624)
		(width 0.14224)
		(layer "In4.Cu")
		(net "M_L_CLK_DP<3>")
	)
	(segment
		(start 92.58554 -97.394268)
		(end 92.581222 -97.386902)
		(width 0.0889)
		(layer "In4.Cu")
		(net "M_L_CLK_DP<3>")
	)
	(segment
		(start 91.825572 -139.170156)
		(end 91.951048 -139.295632)
		(width 0.14224)
		(layer "In4.Cu")
		(net "M_L_CLK_DP<3>")
	)
	(segment
		(start 92.760038 -96.37776)
		(end 92.932758 -96.20504)
		(width 0.0889)
		(layer "In4.Cu")
		(net "M_L_CLK_DP<3>")
	)
	(segment
		(start 92.693744 -100.112576)
		(end 92.693744 -97.71507)
		(width 0.0889)
		(layer "In4.Cu")
		(net "M_L_CLK_DP<3>")
	)
	(segment
		(start 94.277688 -138.16584)
		(end 93.965268 -137.85342)
		(width 0.14224)
		(layer "In4.Cu")
		(net "M_L_CLK_DP<3>")
	)
	(segment
		(start 94.277688 -136.87806)
		(end 94.277688 -133.045962)
		(width 0.14224)
		(layer "In4.Cu")
		(net "M_L_CLK_DP<3>")
	)
	(segment
		(start 92.760292 -132.66801)
		(end 92.581222 -132.48894)
		(width 0.14224)
		(layer "In4.Cu")
		(net "M_L_CLK_DP<3>")
	)
	(segment
		(start 93.899736 -132.66801)
		(end 92.760292 -132.66801)
		(width 0.14224)
		(layer "In4.Cu")
		(net "M_L_CLK_DP<3>")
	)
	(segment
		(start 93.927168 -103.479346)
		(end 93.088968 -102.641146)
		(width 0.0889)
		(layer "In4.Cu")
		(net "M_L_CLK_DP<3>")
	)
	(segment
		(start 93.088968 -100.5078)
		(end 92.693744 -100.112576)
		(width 0.0889)
		(layer "In4.Cu")
		(net "M_L_CLK_DP<3>")
	)
	(segment
		(start 93.088968 -102.641146)
		(end 93.088968 -100.5078)
		(width 0.0889)
		(layer "In4.Cu")
		(net "M_L_CLK_DP<3>")
	)
	(segment
		(start 92.787978 -131.668774)
		(end 93.470222 -131.668774)
		(width 0.14224)
		(layer "In4.Cu")
		(net "M_L_CLK_DP<3>")
	)
	(segment
		(start 91.951048 -139.295632)
		(end 91.951048 -139.934696)
		(width 0.14224)
		(layer "In4.Cu")
		(net "M_L_CLK_DP<3>")
	)
	(segment
		(start 93.470222 -131.668774)
		(end 93.97238 -131.166616)
		(width 0.14224)
		(layer "In4.Cu")
		(net "M_L_CLK_DP<3>")
	)
	(segment
		(start 92.53093 -137.707624)
		(end 92.53093 -137.354564)
		(width 0.14224)
		(layer "In4.Cu")
		(net "M_L_CLK_DP<3>")
	)
	(segment
		(start 93.965268 -137.19048)
		(end 94.277688 -136.87806)
		(width 0.14224)
		(layer "In4.Cu")
		(net "M_L_CLK_DP<3>")
	)
	(segment
		(start 93.97238 -131.166616)
		(end 93.97238 -104.015794)
		(width 0.14224)
		(layer "In4.Cu")
		(net "M_L_CLK_DP<3>")
	)
	(segment
		(start 93.965268 -137.85342)
		(end 92.676726 -137.85342)
		(width 0.14224)
		(layer "In4.Cu")
		(net "M_L_CLK_DP<3>")
	)
	(segment
		(start 93.97238 -103.98633)
		(end 93.927168 -103.941118)
		(width 0.0889)
		(layer "In4.Cu")
		(net "M_L_CLK_DP<3>")
	)
	(segment
		(start 92.351352 -140.335)
		(end 93.292168 -140.335)
		(width 0.14224)
		(layer "In4.Cu")
		(net "M_L_CLK_DP<3>")
	)
	(segment
		(start 92.53093 -137.354564)
		(end 92.695014 -137.19048)
		(width 0.14224)
		(layer "In4.Cu")
		(net "M_L_CLK_DP<3>")
	)
	(arc
		(start 92.581222 -97.386902)
		(mid 92.575462 -97.376068)
		(end 92.570046 -97.365058)
		(width 0.0889)
		(layer "In4.Cu")
		(net "M_L_CLK_DP<3>")
	)
	(arc
		(start 92.662756 -96.646492)
		(mid 92.681502 -96.501307)
		(end 92.760038 -96.37776)
		(width 0.0889)
		(layer "In4.Cu")
		(net "M_L_CLK_DP<3>")
	)
	(arc
		(start 92.570046 -97.365058)
		(mid 92.532805 -97.178315)
		(end 92.586048 -96.995488)
		(width 0.0889)
		(layer "In4.Cu")
		(net "M_L_CLK_DP<3>")
	)
	(arc
		(start 92.693744 -97.71507)
		(mid 92.655643 -97.549271)
		(end 92.58554 -97.394268)
		(width 0.0889)
		(layer "In4.Cu")
		(net "M_L_CLK_DP<3>")
	)
	(arc
		(start 92.586048 -96.995488)
		(mid 92.651406 -96.826926)
		(end 92.662756 -96.646492)
		(width 0.0889)
		(layer "In4.Cu")
		(net "M_L_CLK_DP<3>")
	)
	(segment
		(start 91.749372 -147.27174)
		(end 91.749372 -145.984468)
		(width 0.1651)
		(layer "F.Cu")
		(net "M_L_CLK_DP<1>")
	)
	(segment
		(start 96.079818 -96.700086)
		(end 95.508318 -96.700086)
		(width 0.1016)
		(layer "F.Cu")
		(net "M_L_CLK_DP<1>")
	)
	(via
		(at 95.508318 -96.700086)
		(size 0.508)
		(drill 0.254)
		(layers "F.Cu" "B.Cu")
		(net "M_L_CLK_DP<1>")
	)
	(via
		(at 91.749372 -145.984468)
		(size 0.508)
		(drill 0.254)
		(layers "F.Cu" "B.Cu")
		(net "M_L_CLK_DP<1>")
	)
	(segment
		(start 95.167958 -97.48012)
		(end 95.161608 -97.490788)
		(width 0.0889)
		(layer "In4.Cu")
		(net "M_L_CLK_DP<1>")
	)
	(segment
		(start 96.949768 -141.677136)
		(end 96.949768 -144.798288)
		(width 0.14224)
		(layer "In4.Cu")
		(net "M_L_CLK_DP<1>")
	)
	(segment
		(start 94.483936 -147.26412)
		(end 92.546678 -147.26412)
		(width 0.14224)
		(layer "In4.Cu")
		(net "M_L_CLK_DP<1>")
	)
	(segment
		(start 95.107252 -99.569778)
		(end 95.107252 -101.95179)
		(width 0.0889)
		(layer "In4.Cu")
		(net "M_L_CLK_DP<1>")
	)
	(segment
		(start 96.949768 -144.798288)
		(end 94.483936 -147.26412)
		(width 0.14224)
		(layer "In4.Cu")
		(net "M_L_CLK_DP<1>")
	)
	(segment
		(start 96.416622 -103.26116)
		(end 96.416622 -103.899462)
		(width 0.0889)
		(layer "In4.Cu")
		(net "M_L_CLK_DP<1>")
	)
	(segment
		(start 95.215202 -96.531176)
		(end 95.136462 -96.552512)
		(width 0.0889)
		(layer "In4.Cu")
		(net "M_L_CLK_DP<1>")
	)
	(segment
		(start 95.167958 -99.461066)
		(end 95.107252 -99.569778)
		(width 0.0889)
		(layer "In4.Cu")
		(net "M_L_CLK_DP<1>")
	)
	(segment
		(start 92.546678 -147.26412)
		(end 92.060776 -146.778218)
		(width 0.14224)
		(layer "In4.Cu")
		(net "M_L_CLK_DP<1>")
	)
	(segment
		(start 96.450404 -126.785878)
		(end 97.250504 -127.585978)
		(width 0.14224)
		(layer "In4.Cu")
		(net "M_L_CLK_DP<1>")
	)
	(segment
		(start 95.508318 -96.700086)
		(end 95.215202 -96.531176)
		(width 0.0889)
		(layer "In4.Cu")
		(net "M_L_CLK_DP<1>")
	)
	(segment
		(start 92.060776 -146.295872)
		(end 91.749372 -145.984468)
		(width 0.14224)
		(layer "In4.Cu")
		(net "M_L_CLK_DP<1>")
	)
	(segment
		(start 95.167958 -98.47072)
		(end 95.161608 -98.481388)
		(width 0.0889)
		(layer "In4.Cu")
		(net "M_L_CLK_DP<1>")
	)
	(segment
		(start 97.250504 -127.585978)
		(end 97.250504 -141.3764)
		(width 0.14224)
		(layer "In4.Cu")
		(net "M_L_CLK_DP<1>")
	)
	(segment
		(start 97.250504 -141.3764)
		(end 96.949768 -141.677136)
		(width 0.14224)
		(layer "In4.Cu")
		(net "M_L_CLK_DP<1>")
	)
	(segment
		(start 95.107252 -101.95179)
		(end 96.416622 -103.26116)
		(width 0.0889)
		(layer "In4.Cu")
		(net "M_L_CLK_DP<1>")
	)
	(segment
		(start 96.450404 -103.933244)
		(end 96.450404 -126.785878)
		(width 0.14224)
		(layer "In4.Cu")
		(net "M_L_CLK_DP<1>")
	)
	(segment
		(start 92.060776 -146.778218)
		(end 92.060776 -146.295872)
		(width 0.14224)
		(layer "In4.Cu")
		(net "M_L_CLK_DP<1>")
	)
	(segment
		(start 96.416622 -103.899462)
		(end 96.450404 -103.933244)
		(width 0.0889)
		(layer "In4.Cu")
		(net "M_L_CLK_DP<1>")
	)
	(segment
		(start 95.161608 -98.481388)
		(end 95.156782 -98.490024)
		(width 0.0889)
		(layer "In4.Cu")
		(net "M_L_CLK_DP<1>")
	)
	(segment
		(start 95.161608 -97.490788)
		(end 95.156782 -97.499424)
		(width 0.0889)
		(layer "In4.Cu")
		(net "M_L_CLK_DP<1>")
	)
	(arc
		(start 95.156782 -98.490024)
		(mid 95.108027 -98.686376)
		(end 95.161608 -98.881438)
		(width 0.0889)
		(layer "In4.Cu")
		(net "M_L_CLK_DP<1>")
	)
	(arc
		(start 95.239078 -99.129596)
		(mid 95.227806 -99.300545)
		(end 95.167958 -99.461066)
		(width 0.0889)
		(layer "In4.Cu")
		(net "M_L_CLK_DP<1>")
	)
	(arc
		(start 95.161608 -96.900238)
		(mid 95.24083 -97.189356)
		(end 95.167958 -97.48012)
		(width 0.0889)
		(layer "In4.Cu")
		(net "M_L_CLK_DP<1>")
	)
	(arc
		(start 95.161608 -98.881438)
		(mid 95.214166 -99.001203)
		(end 95.239078 -99.129596)
		(width 0.0889)
		(layer "In4.Cu")
		(net "M_L_CLK_DP<1>")
	)
	(arc
		(start 95.161608 -97.890838)
		(mid 95.24083 -98.179956)
		(end 95.167958 -98.47072)
		(width 0.0889)
		(layer "In4.Cu")
		(net "M_L_CLK_DP<1>")
	)
	(arc
		(start 95.136462 -96.552512)
		(mid 95.11526 -96.625588)
		(end 95.108268 -96.701356)
		(width 0.0889)
		(layer "In4.Cu")
		(net "M_L_CLK_DP<1>")
	)
	(arc
		(start 95.108268 -96.701356)
		(mid 95.12193 -96.804286)
		(end 95.161608 -96.900238)
		(width 0.0889)
		(layer "In4.Cu")
		(net "M_L_CLK_DP<1>")
	)
	(arc
		(start 95.156782 -97.499424)
		(mid 95.108027 -97.695776)
		(end 95.161608 -97.890838)
		(width 0.0889)
		(layer "In4.Cu")
		(net "M_L_CLK_DP<1>")
	)
	(segment
		(start 93.504258 -95.21444)
		(end 92.932758 -95.21444)
		(width 0.1016)
		(layer "F.Cu")
		(net "M_L_CLK_DP<2>")
	)
	(via
		(at 92.932758 -95.21444)
		(size 0.508)
		(drill 0.254)
		(layers "F.Cu" "B.Cu")
		(net "M_L_CLK_DP<2>")
	)
	(via
		(at 91.77528 -141.183868)
		(size 0.508)
		(drill 0.254)
		(layers "F.Cu" "B.Cu")
		(net "M_L_CLK_DP<2>")
	)
	(segment
		(start 91.749372 -141.209776)
		(end 91.77528 -141.183868)
		(width 0.1651)
		(layer "B.Cu")
		(net "M_L_CLK_DP<2>")
	)
	(segment
		(start 91.749372 -142.477236)
		(end 91.749372 -141.209776)
		(width 0.1651)
		(layer "B.Cu")
		(net "M_L_CLK_DP<2>")
	)
	(segment
		(start 92.921582 -95.61449)
		(end 92.954348 -95.61449)
		(width 0.0889)
		(layer "In4.Cu")
		(net "M_L_CLK_DP<2>")
	)
	(segment
		(start 93.368368 -98.065336)
		(end 93.368368 -99.865434)
		(width 0.0889)
		(layer "In4.Cu")
		(net "M_L_CLK_DP<2>")
	)
	(segment
		(start 95.248984 -141.419072)
		(end 94.280736 -142.38732)
		(width 0.14224)
		(layer "In4.Cu")
		(net "M_L_CLK_DP<2>")
	)
	(segment
		(start 94.811088 -103.973884)
		(end 94.811088 -104.004364)
		(width 0.0889)
		(layer "In4.Cu")
		(net "M_L_CLK_DP<2>")
	)
	(segment
		(start 94.765368 -103.4288)
		(end 94.765368 -103.928164)
		(width 0.0889)
		(layer "In4.Cu")
		(net "M_L_CLK_DP<2>")
	)
	(segment
		(start 93.450918 -96.48952)
		(end 93.444568 -96.500188)
		(width 0.0889)
		(layer "In4.Cu")
		(net "M_L_CLK_DP<2>")
	)
	(segment
		(start 94.811088 -132.023866)
		(end 95.248984 -132.461762)
		(width 0.14224)
		(layer "In4.Cu")
		(net "M_L_CLK_DP<2>")
	)
	(segment
		(start 94.765368 -103.928164)
		(end 94.811088 -103.973884)
		(width 0.0889)
		(layer "In4.Cu")
		(net "M_L_CLK_DP<2>")
	)
	(segment
		(start 91.77528 -141.209776)
		(end 91.77528 -141.183868)
		(width 0.14224)
		(layer "In4.Cu")
		(net "M_L_CLK_DP<2>")
	)
	(segment
		(start 93.450918 -97.48012)
		(end 93.444568 -97.490788)
		(width 0.0889)
		(layer "In4.Cu")
		(net "M_L_CLK_DP<2>")
	)
	(segment
		(start 93.723968 -102.3874)
		(end 94.765368 -103.4288)
		(width 0.0889)
		(layer "In4.Cu")
		(net "M_L_CLK_DP<2>")
	)
	(segment
		(start 92.639642 -95.045276)
		(end 92.560902 -95.066612)
		(width 0.0889)
		(layer "In4.Cu")
		(net "M_L_CLK_DP<2>")
	)
	(segment
		(start 95.248984 -132.461762)
		(end 95.248984 -141.419072)
		(width 0.14224)
		(layer "In4.Cu")
		(net "M_L_CLK_DP<2>")
	)
	(segment
		(start 92.457778 -142.38732)
		(end 92.00769 -141.937232)
		(width 0.14224)
		(layer "In4.Cu")
		(net "M_L_CLK_DP<2>")
	)
	(segment
		(start 92.00769 -141.937232)
		(end 92.00769 -141.442186)
		(width 0.14224)
		(layer "In4.Cu")
		(net "M_L_CLK_DP<2>")
	)
	(segment
		(start 93.723968 -100.221034)
		(end 93.723968 -102.3874)
		(width 0.0889)
		(layer "In4.Cu")
		(net "M_L_CLK_DP<2>")
	)
	(segment
		(start 92.00769 -141.442186)
		(end 91.77528 -141.209776)
		(width 0.14224)
		(layer "In4.Cu")
		(net "M_L_CLK_DP<2>")
	)
	(segment
		(start 94.280736 -142.38732)
		(end 92.457778 -142.38732)
		(width 0.14224)
		(layer "In4.Cu")
		(net "M_L_CLK_DP<2>")
	)
	(segment
		(start 93.368368 -99.865434)
		(end 93.723968 -100.221034)
		(width 0.0889)
		(layer "In4.Cu")
		(net "M_L_CLK_DP<2>")
	)
	(segment
		(start 94.811088 -104.004364)
		(end 94.811088 -132.023866)
		(width 0.14224)
		(layer "In4.Cu")
		(net "M_L_CLK_DP<2>")
	)
	(segment
		(start 93.444568 -96.500188)
		(end 93.439742 -96.508824)
		(width 0.0889)
		(layer "In4.Cu")
		(net "M_L_CLK_DP<2>")
	)
	(segment
		(start 92.932758 -95.21444)
		(end 92.639642 -95.045276)
		(width 0.0889)
		(layer "In4.Cu")
		(net "M_L_CLK_DP<2>")
	)
	(segment
		(start 93.358462 -98.015806)
		(end 93.368368 -98.065336)
		(width 0.0889)
		(layer "In4.Cu")
		(net "M_L_CLK_DP<2>")
	)
	(arc
		(start 93.439742 -96.508824)
		(mid 93.390987 -96.705176)
		(end 93.444568 -96.900238)
		(width 0.0889)
		(layer "In4.Cu")
		(net "M_L_CLK_DP<2>")
	)
	(arc
		(start 92.560902 -95.066612)
		(mid 92.546437 -95.109997)
		(end 92.537026 -95.15475)
		(width 0.0889)
		(layer "In4.Cu")
		(net "M_L_CLK_DP<2>")
	)
	(arc
		(start 92.537026 -95.15475)
		(mid 92.625782 -95.471213)
		(end 92.921582 -95.61449)
		(width 0.0889)
		(layer "In4.Cu")
		(net "M_L_CLK_DP<2>")
	)
	(arc
		(start 93.444568 -96.900238)
		(mid 93.52379 -97.189356)
		(end 93.450918 -97.48012)
		(width 0.0889)
		(layer "In4.Cu")
		(net "M_L_CLK_DP<2>")
	)
	(arc
		(start 92.954348 -95.61449)
		(mid 93.446738 -95.913423)
		(end 93.450918 -96.48952)
		(width 0.0889)
		(layer "In4.Cu")
		(net "M_L_CLK_DP<2>")
	)
	(arc
		(start 93.444568 -97.490788)
		(mid 93.353754 -97.745465)
		(end 93.358462 -98.015806)
		(width 0.0889)
		(layer "In4.Cu")
		(net "M_L_CLK_DP<2>")
	)
	(segment
		(start 91.749372 -142.6718)
		(end 91.749372 -143.970756)
		(width 0.1651)
		(layer "F.Cu")
		(net "M_L_CLK_DP<0>")
	)
	(segment
		(start 94.649798 -95.21444)
		(end 95.221298 -95.21444)
		(width 0.1016)
		(layer "F.Cu")
		(net "M_L_CLK_DP<0>")
	)
	(via
		(at 91.749372 -143.970756)
		(size 0.508)
		(drill 0.254)
		(layers "F.Cu" "B.Cu")
		(net "M_L_CLK_DP<0>")
	)
	(via
		(at 94.649798 -95.21444)
		(size 0.508)
		(drill 0.254)
		(layers "F.Cu" "B.Cu")
		(net "M_L_CLK_DP<0>")
	)
	(segment
		(start 94.356936 -145.20672)
		(end 92.396564 -145.20672)
		(width 0.14224)
		(layer "In4.Cu")
		(net "M_L_CLK_DP<0>")
	)
	(segment
		(start 96.362266 -129.485644)
		(end 95.999554 -129.848356)
		(width 0.14224)
		(layer "In4.Cu")
		(net "M_L_CLK_DP<0>")
	)
	(segment
		(start 92.017342 -144.827498)
		(end 92.017342 -144.238726)
		(width 0.14224)
		(layer "In4.Cu")
		(net "M_L_CLK_DP<0>")
	)
	(segment
		(start 96.436688 -139.7254)
		(end 96.213168 -139.94892)
		(width 0.14224)
		(layer "In4.Cu")
		(net "M_L_CLK_DP<0>")
	)
	(segment
		(start 94.298262 -98.377502)
		(end 94.303088 -98.386138)
		(width 0.0889)
		(layer "In4.Cu")
		(net "M_L_CLK_DP<0>")
	)
	(segment
		(start 95.581216 -103.988108)
		(end 95.581216 -128.150366)
		(width 0.14224)
		(layer "In4.Cu")
		(net "M_L_CLK_DP<0>")
	)
	(segment
		(start 96.213168 -139.94892)
		(end 96.213168 -143.350488)
		(width 0.14224)
		(layer "In4.Cu")
		(net "M_L_CLK_DP<0>")
	)
	(segment
		(start 95.641668 -129.975356)
		(end 95.641668 -130.384296)
		(width 0.14224)
		(layer "In4.Cu")
		(net "M_L_CLK_DP<0>")
	)
	(segment
		(start 95.535496 -103.942388)
		(end 95.581216 -103.988108)
		(width 0.0889)
		(layer "In4.Cu")
		(net "M_L_CLK_DP<0>")
	)
	(segment
		(start 94.303088 -98.386138)
		(end 94.309438 -98.396806)
		(width 0.0889)
		(layer "In4.Cu")
		(net "M_L_CLK_DP<0>")
	)
	(segment
		(start 94.303088 -95.414338)
		(end 94.309438 -95.425006)
		(width 0.0889)
		(layer "In4.Cu")
		(net "M_L_CLK_DP<0>")
	)
	(segment
		(start 96.436688 -130.961892)
		(end 96.436688 -139.7254)
		(width 0.14224)
		(layer "In4.Cu")
		(net "M_L_CLK_DP<0>")
	)
	(segment
		(start 94.384368 -99.514914)
		(end 94.384368 -102.117906)
		(width 0.0889)
		(layer "In4.Cu")
		(net "M_L_CLK_DP<0>")
	)
	(segment
		(start 95.641668 -130.384296)
		(end 95.768668 -130.511296)
		(width 0.14224)
		(layer "In4.Cu")
		(net "M_L_CLK_DP<0>")
	)
	(segment
		(start 95.581216 -128.150366)
		(end 96.362266 -128.931416)
		(width 0.14224)
		(layer "In4.Cu")
		(net "M_L_CLK_DP<0>")
	)
	(segment
		(start 94.356682 -95.045276)
		(end 94.277942 -95.066612)
		(width 0.0889)
		(layer "In4.Cu")
		(net "M_L_CLK_DP<0>")
	)
	(segment
		(start 92.396564 -145.20672)
		(end 92.017342 -144.827498)
		(width 0.14224)
		(layer "In4.Cu")
		(net "M_L_CLK_DP<0>")
	)
	(segment
		(start 95.768668 -129.848356)
		(end 95.641668 -129.975356)
		(width 0.14224)
		(layer "In4.Cu")
		(net "M_L_CLK_DP<0>")
	)
	(segment
		(start 95.986092 -130.511296)
		(end 96.436688 -130.961892)
		(width 0.14224)
		(layer "In4.Cu")
		(net "M_L_CLK_DP<0>")
	)
	(segment
		(start 94.303088 -97.395538)
		(end 94.309438 -97.406206)
		(width 0.0889)
		(layer "In4.Cu")
		(net "M_L_CLK_DP<0>")
	)
	(segment
		(start 94.303088 -96.404938)
		(end 94.309438 -96.415606)
		(width 0.0889)
		(layer "In4.Cu")
		(net "M_L_CLK_DP<0>")
	)
	(segment
		(start 94.649798 -95.21444)
		(end 94.356682 -95.045276)
		(width 0.0889)
		(layer "In4.Cu")
		(net "M_L_CLK_DP<0>")
	)
	(segment
		(start 94.298262 -95.405702)
		(end 94.303088 -95.414338)
		(width 0.0889)
		(layer "In4.Cu")
		(net "M_L_CLK_DP<0>")
	)
	(segment
		(start 94.384368 -102.117906)
		(end 95.535496 -103.269034)
		(width 0.0889)
		(layer "In4.Cu")
		(net "M_L_CLK_DP<0>")
	)
	(segment
		(start 94.329504 -99.42322)
		(end 94.384368 -99.514914)
		(width 0.0889)
		(layer "In4.Cu")
		(net "M_L_CLK_DP<0>")
	)
	(segment
		(start 94.298262 -97.386902)
		(end 94.303088 -97.395538)
		(width 0.0889)
		(layer "In4.Cu")
		(net "M_L_CLK_DP<0>")
	)
	(segment
		(start 94.298008 -99.367594)
		(end 94.329504 -99.42322)
		(width 0.0889)
		(layer "In4.Cu")
		(net "M_L_CLK_DP<0>")
	)
	(segment
		(start 95.999554 -129.848356)
		(end 95.768668 -129.848356)
		(width 0.14224)
		(layer "In4.Cu")
		(net "M_L_CLK_DP<0>")
	)
	(segment
		(start 95.535496 -103.269034)
		(end 95.535496 -103.942388)
		(width 0.0889)
		(layer "In4.Cu")
		(net "M_L_CLK_DP<0>")
	)
	(segment
		(start 96.362266 -128.931416)
		(end 96.362266 -129.485644)
		(width 0.14224)
		(layer "In4.Cu")
		(net "M_L_CLK_DP<0>")
	)
	(segment
		(start 92.017342 -144.238726)
		(end 91.749372 -143.970756)
		(width 0.14224)
		(layer "In4.Cu")
		(net "M_L_CLK_DP<0>")
	)
	(segment
		(start 95.768668 -130.511296)
		(end 95.986092 -130.511296)
		(width 0.14224)
		(layer "In4.Cu")
		(net "M_L_CLK_DP<0>")
	)
	(segment
		(start 96.213168 -143.350488)
		(end 94.356936 -145.20672)
		(width 0.14224)
		(layer "In4.Cu")
		(net "M_L_CLK_DP<0>")
	)
	(segment
		(start 94.298262 -96.396302)
		(end 94.303088 -96.404938)
		(width 0.0889)
		(layer "In4.Cu")
		(net "M_L_CLK_DP<0>")
	)
	(arc
		(start 94.309438 -96.415606)
		(mid 94.382236 -96.706369)
		(end 94.303088 -96.995488)
		(width 0.0889)
		(layer "In4.Cu")
		(net "M_L_CLK_DP<0>")
	)
	(arc
		(start 94.277942 -95.066612)
		(mid 94.261767 -95.116695)
		(end 94.252288 -95.168466)
		(width 0.0889)
		(layer "In4.Cu")
		(net "M_L_CLK_DP<0>")
	)
	(arc
		(start 94.303088 -98.976688)
		(mid 94.249622 -99.171467)
		(end 94.298008 -99.367594)
		(width 0.0889)
		(layer "In4.Cu")
		(net "M_L_CLK_DP<0>")
	)
	(arc
		(start 94.309438 -98.396806)
		(mid 94.382236 -98.687569)
		(end 94.303088 -98.976688)
		(width 0.0889)
		(layer "In4.Cu")
		(net "M_L_CLK_DP<0>")
	)
	(arc
		(start 94.309438 -97.406206)
		(mid 94.382236 -97.696969)
		(end 94.303088 -97.986088)
		(width 0.0889)
		(layer "In4.Cu")
		(net "M_L_CLK_DP<0>")
	)
	(arc
		(start 94.303088 -97.986088)
		(mid 94.249618 -98.181151)
		(end 94.298262 -98.377502)
		(width 0.0889)
		(layer "In4.Cu")
		(net "M_L_CLK_DP<0>")
	)
	(arc
		(start 94.252288 -95.168466)
		(mid 94.256956 -95.290633)
		(end 94.298262 -95.405702)
		(width 0.0889)
		(layer "In4.Cu")
		(net "M_L_CLK_DP<0>")
	)
	(arc
		(start 94.309438 -95.425006)
		(mid 94.382236 -95.715769)
		(end 94.303088 -96.004888)
		(width 0.0889)
		(layer "In4.Cu")
		(net "M_L_CLK_DP<0>")
	)
	(arc
		(start 94.303088 -96.004888)
		(mid 94.249618 -96.199951)
		(end 94.298262 -96.396302)
		(width 0.0889)
		(layer "In4.Cu")
		(net "M_L_CLK_DP<0>")
	)
	(arc
		(start 94.303088 -96.995488)
		(mid 94.249618 -97.190551)
		(end 94.298262 -97.386902)
		(width 0.0889)
		(layer "In4.Cu")
		(net "M_L_CLK_DP<0>")
	)
	(segment
		(start 92.645738 -96.700086)
		(end 92.074238 -96.700086)
		(width 0.1016)
		(layer "F.Cu")
		(net "M_L_CLK_DN<3>")
	)
	(via
		(at 92.074238 -96.700086)
		(size 0.508)
		(drill 0.254)
		(layers "F.Cu" "B.Cu")
		(net "M_L_CLK_DN<3>")
	)
	(via
		(at 92.52331 -139.170156)
		(size 0.508)
		(drill 0.254)
		(layers "F.Cu" "B.Cu")
		(net "M_L_CLK_DN<3>")
	)
	(segment
		(start 92.59951 -139.093956)
		(end 92.52331 -139.170156)
		(width 0.1651)
		(layer "B.Cu")
		(net "M_L_CLK_DN<3>")
	)
	(segment
		(start 92.59951 -137.877296)
		(end 92.59951 -139.093956)
		(width 0.1651)
		(layer "B.Cu")
		(net "M_L_CLK_DN<3>")
	)
	(segment
		(start 93.449902 -133.04393)
		(end 93.556582 -132.93725)
		(width 0.14224)
		(layer "In4.Cu")
		(net "M_L_CLK_DN<3>")
	)
	(segment
		(start 93.894656 -134.693152)
		(end 93.894656 -135.157972)
		(width 0.14224)
		(layer "In4.Cu")
		(net "M_L_CLK_DN<3>")
	)
	(segment
		(start 94.008448 -133.157722)
		(end 94.008448 -133.48716)
		(width 0.14224)
		(layer "In4.Cu")
		(net "M_L_CLK_DN<3>")
	)
	(segment
		(start 93.589348 -130.476244)
		(end 93.70314 -130.590036)
		(width 0.14224)
		(layer "In4.Cu")
		(net "M_L_CLK_DN<3>")
	)
	(segment
		(start 93.589348 -129.31902)
		(end 93.70314 -129.432812)
		(width 0.14224)
		(layer "In4.Cu")
		(net "M_L_CLK_DN<3>")
	)
	(segment
		(start 93.358462 -131.399534)
		(end 92.676218 -131.399534)
		(width 0.14224)
		(layer "In4.Cu")
		(net "M_L_CLK_DN<3>")
	)
	(segment
		(start 93.70314 -127.583184)
		(end 93.589348 -127.696976)
		(width 0.14224)
		(layer "In4.Cu")
		(net "M_L_CLK_DN<3>")
	)
	(segment
		(start 92.414598 -97.48012)
		(end 92.420948 -97.490788)
		(width 0.0889)
		(layer "In4.Cu")
		(net "M_L_CLK_DN<3>")
	)
	(segment
		(start 92.985082 -133.04393)
		(end 93.449902 -133.04393)
		(width 0.14224)
		(layer "In4.Cu")
		(net "M_L_CLK_DN<3>")
	)
	(segment
		(start 93.894656 -135.850376)
		(end 93.894656 -136.315196)
		(width 0.14224)
		(layer "In4.Cu")
		(net "M_L_CLK_DN<3>")
	)
	(segment
		(start 93.585538 -136.92124)
		(end 93.472 -136.807702)
		(width 0.14224)
		(layer "In4.Cu")
		(net "M_L_CLK_DN<3>")
	)
	(segment
		(start 93.70314 -129.432812)
		(end 93.70314 -129.897632)
		(width 0.14224)
		(layer "In4.Cu")
		(net "M_L_CLK_DN<3>")
	)
	(segment
		(start 92.26169 -137.242804)
		(end 92.26169 -137.819384)
		(width 0.14224)
		(layer "In4.Cu")
		(net "M_L_CLK_DN<3>")
	)
	(segment
		(start 92.898468 -102.72014)
		(end 93.736668 -103.55834)
		(width 0.0889)
		(layer "In4.Cu")
		(net "M_L_CLK_DN<3>")
	)
	(segment
		(start 92.220288 -139.822936)
		(end 92.220288 -139.473178)
		(width 0.14224)
		(layer "In4.Cu")
		(net "M_L_CLK_DN<3>")
	)
	(segment
		(start 92.879672 -138.12266)
		(end 92.992956 -138.235944)
		(width 0.14224)
		(layer "In4.Cu")
		(net "M_L_CLK_DN<3>")
	)
	(segment
		(start 93.556582 -132.93725)
		(end 93.787976 -132.93725)
		(width 0.14224)
		(layer "In4.Cu")
		(net "M_L_CLK_DN<3>")
	)
	(segment
		(start 93.894656 -135.157972)
		(end 94.008448 -135.271764)
		(width 0.14224)
		(layer "In4.Cu")
		(net "M_L_CLK_DN<3>")
	)
	(segment
		(start 93.57106 -138.12266)
		(end 93.853508 -138.12266)
		(width 0.14224)
		(layer "In4.Cu")
		(net "M_L_CLK_DN<3>")
	)
	(segment
		(start 94.008448 -133.48716)
		(end 93.89491 -133.600698)
		(width 0.14224)
		(layer "In4.Cu")
		(net "M_L_CLK_DN<3>")
	)
	(segment
		(start 93.853508 -136.92124)
		(end 93.585538 -136.92124)
		(width 0.14224)
		(layer "In4.Cu")
		(net "M_L_CLK_DN<3>")
	)
	(segment
		(start 93.853508 -138.12266)
		(end 94.008448 -138.2776)
		(width 0.14224)
		(layer "In4.Cu")
		(net "M_L_CLK_DN<3>")
	)
	(segment
		(start 92.311982 -132.6007)
		(end 92.648532 -132.93725)
		(width 0.14224)
		(layer "In4.Cu")
		(net "M_L_CLK_DN<3>")
	)
	(segment
		(start 92.583254 -136.92124)
		(end 92.26169 -137.242804)
		(width 0.14224)
		(layer "In4.Cu")
		(net "M_L_CLK_DN<3>")
	)
	(segment
		(start 93.70314 -128.740408)
		(end 93.589348 -128.8542)
		(width 0.14224)
		(layer "In4.Cu")
		(net "M_L_CLK_DN<3>")
	)
	(segment
		(start 93.70314 -130.590036)
		(end 93.70314 -131.054856)
		(width 0.14224)
		(layer "In4.Cu")
		(net "M_L_CLK_DN<3>")
	)
	(segment
		(start 92.893642 -136.92124)
		(end 92.583254 -136.92124)
		(width 0.14224)
		(layer "In4.Cu")
		(net "M_L_CLK_DN<3>")
	)
	(segment
		(start 93.70314 -131.054856)
		(end 93.358462 -131.399534)
		(width 0.14224)
		(layer "In4.Cu")
		(net "M_L_CLK_DN<3>")
	)
	(segment
		(start 94.008448 -135.271764)
		(end 94.008448 -135.736584)
		(width 0.14224)
		(layer "In4.Cu")
		(net "M_L_CLK_DN<3>")
	)
	(segment
		(start 93.472 -136.807702)
		(end 93.00718 -136.807702)
		(width 0.14224)
		(layer "In4.Cu")
		(net "M_L_CLK_DN<3>")
	)
	(segment
		(start 92.074238 -96.700086)
		(end 92.367354 -96.531176)
		(width 0.0889)
		(layer "In4.Cu")
		(net "M_L_CLK_DN<3>")
	)
	(segment
		(start 93.736668 -103.961184)
		(end 93.70314 -103.994712)
		(width 0.0889)
		(layer "In4.Cu")
		(net "M_L_CLK_DN<3>")
	)
	(segment
		(start 93.70314 -129.897632)
		(end 93.589348 -130.011424)
		(width 0.14224)
		(layer "In4.Cu")
		(net "M_L_CLK_DN<3>")
	)
	(segment
		(start 94.008448 -139.23772)
		(end 93.180408 -140.06576)
		(width 0.14224)
		(layer "In4.Cu")
		(net "M_L_CLK_DN<3>")
	)
	(segment
		(start 93.00718 -136.807702)
		(end 92.893642 -136.92124)
		(width 0.14224)
		(layer "In4.Cu")
		(net "M_L_CLK_DN<3>")
	)
	(segment
		(start 93.589348 -128.8542)
		(end 93.589348 -129.31902)
		(width 0.14224)
		(layer "In4.Cu")
		(net "M_L_CLK_DN<3>")
	)
	(segment
		(start 93.736668 -103.55834)
		(end 93.736668 -103.961184)
		(width 0.0889)
		(layer "In4.Cu")
		(net "M_L_CLK_DN<3>")
	)
	(segment
		(start 92.311982 -131.76377)
		(end 92.311982 -132.6007)
		(width 0.14224)
		(layer "In4.Cu")
		(net "M_L_CLK_DN<3>")
	)
	(segment
		(start 93.180408 -140.06576)
		(end 92.463112 -140.06576)
		(width 0.14224)
		(layer "In4.Cu")
		(net "M_L_CLK_DN<3>")
	)
	(segment
		(start 92.992956 -138.235944)
		(end 93.457776 -138.235944)
		(width 0.14224)
		(layer "In4.Cu")
		(net "M_L_CLK_DN<3>")
	)
	(segment
		(start 92.26169 -137.819384)
		(end 92.564966 -138.12266)
		(width 0.14224)
		(layer "In4.Cu")
		(net "M_L_CLK_DN<3>")
	)
	(segment
		(start 92.676218 -131.399534)
		(end 92.311982 -131.76377)
		(width 0.14224)
		(layer "In4.Cu")
		(net "M_L_CLK_DN<3>")
	)
	(segment
		(start 93.589348 -130.011424)
		(end 93.589348 -130.476244)
		(width 0.14224)
		(layer "In4.Cu")
		(net "M_L_CLK_DN<3>")
	)
	(segment
		(start 94.008448 -134.179056)
		(end 94.008448 -134.57936)
		(width 0.14224)
		(layer "In4.Cu")
		(net "M_L_CLK_DN<3>")
	)
	(segment
		(start 94.008448 -135.736584)
		(end 93.894656 -135.850376)
		(width 0.14224)
		(layer "In4.Cu")
		(net "M_L_CLK_DN<3>")
	)
	(segment
		(start 93.70314 -104.005888)
		(end 93.70314 -127.583184)
		(width 0.14224)
		(layer "In4.Cu")
		(net "M_L_CLK_DN<3>")
	)
	(segment
		(start 92.503244 -97.728024)
		(end 92.503244 -100.19157)
		(width 0.0889)
		(layer "In4.Cu")
		(net "M_L_CLK_DN<3>")
	)
	(segment
		(start 92.503244 -100.19157)
		(end 92.898468 -100.586794)
		(width 0.0889)
		(layer "In4.Cu")
		(net "M_L_CLK_DN<3>")
	)
	(segment
		(start 94.008448 -136.428988)
		(end 94.008448 -136.7663)
		(width 0.14224)
		(layer "In4.Cu")
		(net "M_L_CLK_DN<3>")
	)
	(segment
		(start 93.589348 -128.161796)
		(end 93.70314 -128.275588)
		(width 0.14224)
		(layer "In4.Cu")
		(net "M_L_CLK_DN<3>")
	)
	(segment
		(start 92.648532 -132.93725)
		(end 92.878402 -132.93725)
		(width 0.14224)
		(layer "In4.Cu")
		(net "M_L_CLK_DN<3>")
	)
	(segment
		(start 93.787976 -132.93725)
		(end 94.008448 -133.157722)
		(width 0.14224)
		(layer "In4.Cu")
		(net "M_L_CLK_DN<3>")
	)
	(segment
		(start 94.008448 -136.7663)
		(end 93.853508 -136.92124)
		(width 0.14224)
		(layer "In4.Cu")
		(net "M_L_CLK_DN<3>")
	)
	(segment
		(start 92.878402 -132.93725)
		(end 92.985082 -133.04393)
		(width 0.14224)
		(layer "In4.Cu")
		(net "M_L_CLK_DN<3>")
	)
	(segment
		(start 92.367354 -96.531176)
		(end 92.446094 -96.552512)
		(width 0.0889)
		(layer "In4.Cu")
		(net "M_L_CLK_DN<3>")
	)
	(segment
		(start 92.564966 -138.12266)
		(end 92.879672 -138.12266)
		(width 0.14224)
		(layer "In4.Cu")
		(net "M_L_CLK_DN<3>")
	)
	(segment
		(start 93.89491 -134.065518)
		(end 94.008448 -134.179056)
		(width 0.14224)
		(layer "In4.Cu")
		(net "M_L_CLK_DN<3>")
	)
	(segment
		(start 94.008448 -138.2776)
		(end 94.008448 -139.23772)
		(width 0.14224)
		(layer "In4.Cu")
		(net "M_L_CLK_DN<3>")
	)
	(segment
		(start 93.70314 -103.994712)
		(end 93.70314 -104.005888)
		(width 0.0889)
		(layer "In4.Cu")
		(net "M_L_CLK_DN<3>")
	)
	(segment
		(start 93.89491 -133.600698)
		(end 93.89491 -134.065518)
		(width 0.14224)
		(layer "In4.Cu")
		(net "M_L_CLK_DN<3>")
	)
	(segment
		(start 92.898468 -100.586794)
		(end 92.898468 -102.72014)
		(width 0.0889)
		(layer "In4.Cu")
		(net "M_L_CLK_DN<3>")
	)
	(segment
		(start 93.589348 -127.696976)
		(end 93.589348 -128.161796)
		(width 0.14224)
		(layer "In4.Cu")
		(net "M_L_CLK_DN<3>")
	)
	(segment
		(start 93.70314 -128.275588)
		(end 93.70314 -128.740408)
		(width 0.14224)
		(layer "In4.Cu")
		(net "M_L_CLK_DN<3>")
	)
	(segment
		(start 92.220288 -139.473178)
		(end 92.52331 -139.170156)
		(width 0.14224)
		(layer "In4.Cu")
		(net "M_L_CLK_DN<3>")
	)
	(segment
		(start 92.463112 -140.06576)
		(end 92.220288 -139.822936)
		(width 0.14224)
		(layer "In4.Cu")
		(net "M_L_CLK_DN<3>")
	)
	(segment
		(start 93.894656 -136.315196)
		(end 94.008448 -136.428988)
		(width 0.14224)
		(layer "In4.Cu")
		(net "M_L_CLK_DN<3>")
	)
	(segment
		(start 94.008448 -134.57936)
		(end 93.894656 -134.693152)
		(width 0.14224)
		(layer "In4.Cu")
		(net "M_L_CLK_DN<3>")
	)
	(segment
		(start 93.457776 -138.235944)
		(end 93.57106 -138.12266)
		(width 0.14224)
		(layer "In4.Cu")
		(net "M_L_CLK_DN<3>")
	)
	(arc
		(start 92.420948 -96.900238)
		(mid 92.342252 -97.170106)
		(end 92.397072 -97.44583)
		(width 0.0889)
		(layer "In4.Cu")
		(net "M_L_CLK_DN<3>")
	)
	(arc
		(start 92.472764 -96.663764)
		(mid 92.465166 -96.786015)
		(end 92.420948 -96.900238)
		(width 0.0889)
		(layer "In4.Cu")
		(net "M_L_CLK_DN<3>")
	)
	(arc
		(start 92.420948 -97.490788)
		(mid 92.473362 -97.605498)
		(end 92.503244 -97.728024)
		(width 0.0889)
		(layer "In4.Cu")
		(net "M_L_CLK_DN<3>")
	)
	(arc
		(start 92.397072 -97.44583)
		(mid 92.405557 -97.463117)
		(end 92.414598 -97.48012)
		(width 0.0889)
		(layer "In4.Cu")
		(net "M_L_CLK_DN<3>")
	)
	(arc
		(start 92.446094 -96.552512)
		(mid 92.46343 -96.60718)
		(end 92.472764 -96.663764)
		(width 0.0889)
		(layer "In4.Cu")
		(net "M_L_CLK_DN<3>")
	)
	(segment
		(start 94.649798 -96.20504)
		(end 95.221298 -96.20504)
		(width 0.1016)
		(layer "F.Cu")
		(net "M_L_CLK_DN<1>")
	)
	(segment
		(start 92.59951 -147.27174)
		(end 92.59951 -145.984468)
		(width 0.1651)
		(layer "F.Cu")
		(net "M_L_CLK_DN<1>")
	)
	(via
		(at 94.649798 -96.20504)
		(size 0.508)
		(drill 0.254)
		(layers "F.Cu" "B.Cu")
		(net "M_L_CLK_DN<1>")
	)
	(via
		(at 92.59951 -145.984468)
		(size 0.508)
		(drill 0.254)
		(layers "F.Cu" "B.Cu")
		(net "M_L_CLK_DN<1>")
	)
	(segment
		(start 95.02902 -146.176492)
		(end 94.70009 -146.505422)
		(width 0.14224)
		(layer "In4.Cu")
		(net "M_L_CLK_DN<1>")
	)
	(segment
		(start 95.00108 -99.368864)
		(end 94.916752 -99.520248)
		(width 0.0889)
		(layer "In4.Cu")
		(net "M_L_CLK_DN<1>")
	)
	(segment
		(start 96.181164 -126.432818)
		(end 96.181164 -126.897638)
		(width 0.14224)
		(layer "In4.Cu")
		(net "M_L_CLK_DN<1>")
	)
	(segment
		(start 96.981264 -127.697738)
		(end 96.981264 -128.171702)
		(width 0.14224)
		(layer "In4.Cu")
		(net "M_L_CLK_DN<1>")
	)
	(segment
		(start 94.996508 -97.395538)
		(end 94.990158 -97.406206)
		(width 0.0889)
		(layer "In4.Cu")
		(net "M_L_CLK_DN<1>")
	)
	(segment
		(start 96.181164 -123.425966)
		(end 96.067372 -123.539758)
		(width 0.14224)
		(layer "In4.Cu")
		(net "M_L_CLK_DN<1>")
	)
	(segment
		(start 96.067372 -125.854206)
		(end 96.067372 -126.319026)
		(width 0.14224)
		(layer "In4.Cu")
		(net "M_L_CLK_DN<1>")
	)
	(segment
		(start 96.680528 -144.685766)
		(end 96.00819 -145.358104)
		(width 0.14224)
		(layer "In4.Cu")
		(net "M_L_CLK_DN<1>")
	)
	(segment
		(start 95.518478 -145.687034)
		(end 95.518478 -145.847816)
		(width 0.14224)
		(layer "In4.Cu")
		(net "M_L_CLK_DN<1>")
	)
	(segment
		(start 93.123258 -146.99488)
		(end 92.658438 -146.99488)
		(width 0.14224)
		(layer "In4.Cu")
		(net "M_L_CLK_DN<1>")
	)
	(segment
		(start 96.680528 -141.565376)
		(end 96.680528 -143.637508)
		(width 0.14224)
		(layer "In4.Cu")
		(net "M_L_CLK_DN<1>")
	)
	(segment
		(start 96.181164 -126.897638)
		(end 96.981264 -127.697738)
		(width 0.14224)
		(layer "In4.Cu")
		(net "M_L_CLK_DN<1>")
	)
	(segment
		(start 96.181164 -125.740414)
		(end 96.067372 -125.854206)
		(width 0.14224)
		(layer "In4.Cu")
		(net "M_L_CLK_DN<1>")
	)
	(segment
		(start 95.189802 -146.176492)
		(end 95.02902 -146.176492)
		(width 0.14224)
		(layer "In4.Cu")
		(net "M_L_CLK_DN<1>")
	)
	(segment
		(start 94.996508 -98.976688)
		(end 94.996762 -98.976942)
		(width 0.0889)
		(layer "In4.Cu")
		(net "M_L_CLK_DN<1>")
	)
	(segment
		(start 96.981264 -128.171702)
		(end 96.876616 -128.27635)
		(width 0.14224)
		(layer "In4.Cu")
		(net "M_L_CLK_DN<1>")
	)
	(segment
		(start 95.001334 -97.386902)
		(end 94.996508 -97.395538)
		(width 0.0889)
		(layer "In4.Cu")
		(net "M_L_CLK_DN<1>")
	)
	(segment
		(start 94.649798 -96.20504)
		(end 94.754954 -96.31045)
		(width 0.0889)
		(layer "In4.Cu")
		(net "M_L_CLK_DN<1>")
	)
	(segment
		(start 96.876616 -140.244068)
		(end 96.876616 -140.708888)
		(width 0.14224)
		(layer "In4.Cu")
		(net "M_L_CLK_DN<1>")
	)
	(segment
		(start 92.330016 -146.666458)
		(end 92.330016 -146.253962)
		(width 0.14224)
		(layer "In4.Cu")
		(net "M_L_CLK_DN<1>")
	)
	(segment
		(start 94.371414 -146.99488)
		(end 93.815662 -146.99488)
		(width 0.14224)
		(layer "In4.Cu")
		(net "M_L_CLK_DN<1>")
	)
	(segment
		(start 95.001334 -98.377502)
		(end 94.996508 -98.386138)
		(width 0.0889)
		(layer "In4.Cu")
		(net "M_L_CLK_DN<1>")
	)
	(segment
		(start 96.181164 -103.941626)
		(end 96.181164 -103.963724)
		(width 0.0889)
		(layer "In4.Cu")
		(net "M_L_CLK_DN<1>")
	)
	(segment
		(start 96.876616 -140.708888)
		(end 96.981264 -140.813536)
		(width 0.14224)
		(layer "In4.Cu")
		(net "M_L_CLK_DN<1>")
	)
	(segment
		(start 96.885506 -130.029712)
		(end 96.885506 -130.494532)
		(width 0.14224)
		(layer "In4.Cu")
		(net "M_L_CLK_DN<1>")
	)
	(segment
		(start 96.981264 -140.13942)
		(end 96.876616 -140.244068)
		(width 0.14224)
		(layer "In4.Cu")
		(net "M_L_CLK_DN<1>")
	)
	(segment
		(start 96.680528 -144.266412)
		(end 96.680528 -144.685766)
		(width 0.14224)
		(layer "In4.Cu")
		(net "M_L_CLK_DN<1>")
	)
	(segment
		(start 94.916752 -102.030784)
		(end 96.226122 -103.340154)
		(width 0.0889)
		(layer "In4.Cu")
		(net "M_L_CLK_DN<1>")
	)
	(segment
		(start 96.876616 -128.74117)
		(end 96.981264 -128.845818)
		(width 0.14224)
		(layer "In4.Cu")
		(net "M_L_CLK_DN<1>")
	)
	(segment
		(start 95.518478 -145.847816)
		(end 95.189802 -146.176492)
		(width 0.14224)
		(layer "In4.Cu")
		(net "M_L_CLK_DN<1>")
	)
	(segment
		(start 93.815662 -146.99488)
		(end 93.70187 -146.881088)
		(width 0.14224)
		(layer "In4.Cu")
		(net "M_L_CLK_DN<1>")
	)
	(segment
		(start 96.067372 -123.539758)
		(end 96.067372 -124.004578)
		(width 0.14224)
		(layer "In4.Cu")
		(net "M_L_CLK_DN<1>")
	)
	(segment
		(start 92.658438 -146.99488)
		(end 92.330016 -146.666458)
		(width 0.14224)
		(layer "In4.Cu")
		(net "M_L_CLK_DN<1>")
	)
	(segment
		(start 96.981264 -130.59029)
		(end 96.981264 -140.13942)
		(width 0.14224)
		(layer "In4.Cu")
		(net "M_L_CLK_DN<1>")
	)
	(segment
		(start 95.847408 -145.358104)
		(end 95.518478 -145.687034)
		(width 0.14224)
		(layer "In4.Cu")
		(net "M_L_CLK_DN<1>")
	)
	(segment
		(start 94.916752 -99.520248)
		(end 94.916752 -102.030784)
		(width 0.0889)
		(layer "In4.Cu")
		(net "M_L_CLK_DN<1>")
	)
	(segment
		(start 96.876616 -128.27635)
		(end 96.876616 -128.74117)
		(width 0.14224)
		(layer "In4.Cu")
		(net "M_L_CLK_DN<1>")
	)
	(segment
		(start 96.181164 -125.275594)
		(end 96.181164 -125.740414)
		(width 0.14224)
		(layer "In4.Cu")
		(net "M_L_CLK_DN<1>")
	)
	(segment
		(start 96.226122 -103.340154)
		(end 96.226122 -103.896668)
		(width 0.0889)
		(layer "In4.Cu")
		(net "M_L_CLK_DN<1>")
	)
	(segment
		(start 96.181164 -103.963724)
		(end 96.181164 -123.425966)
		(width 0.14224)
		(layer "In4.Cu")
		(net "M_L_CLK_DN<1>")
	)
	(segment
		(start 96.067372 -125.161802)
		(end 96.181164 -125.275594)
		(width 0.14224)
		(layer "In4.Cu")
		(net "M_L_CLK_DN<1>")
	)
	(segment
		(start 96.598486 -144.18437)
		(end 96.680528 -144.266412)
		(width 0.14224)
		(layer "In4.Cu")
		(net "M_L_CLK_DN<1>")
	)
	(segment
		(start 94.70009 -146.505422)
		(end 94.70009 -146.666204)
		(width 0.14224)
		(layer "In4.Cu")
		(net "M_L_CLK_DN<1>")
	)
	(segment
		(start 92.330016 -146.253962)
		(end 92.59951 -145.984468)
		(width 0.14224)
		(layer "In4.Cu")
		(net "M_L_CLK_DN<1>")
	)
	(segment
		(start 96.067372 -124.696982)
		(end 96.067372 -125.161802)
		(width 0.14224)
		(layer "In4.Cu")
		(net "M_L_CLK_DN<1>")
	)
	(segment
		(start 94.70009 -146.666204)
		(end 94.371414 -146.99488)
		(width 0.14224)
		(layer "In4.Cu")
		(net "M_L_CLK_DN<1>")
	)
	(segment
		(start 96.981264 -128.845818)
		(end 96.981264 -129.933954)
		(width 0.14224)
		(layer "In4.Cu")
		(net "M_L_CLK_DN<1>")
	)
	(segment
		(start 96.067372 -124.004578)
		(end 96.181164 -124.11837)
		(width 0.14224)
		(layer "In4.Cu")
		(net "M_L_CLK_DN<1>")
	)
	(segment
		(start 96.226122 -103.896668)
		(end 96.181164 -103.941626)
		(width 0.0889)
		(layer "In4.Cu")
		(net "M_L_CLK_DN<1>")
	)
	(segment
		(start 93.70187 -146.881088)
		(end 93.23705 -146.881088)
		(width 0.14224)
		(layer "In4.Cu")
		(net "M_L_CLK_DN<1>")
	)
	(segment
		(start 96.885506 -130.494532)
		(end 96.981264 -130.59029)
		(width 0.14224)
		(layer "In4.Cu")
		(net "M_L_CLK_DN<1>")
	)
	(segment
		(start 96.680528 -143.637508)
		(end 96.598486 -143.71955)
		(width 0.14224)
		(layer "In4.Cu")
		(net "M_L_CLK_DN<1>")
	)
	(segment
		(start 96.981264 -140.813536)
		(end 96.981264 -141.26464)
		(width 0.14224)
		(layer "In4.Cu")
		(net "M_L_CLK_DN<1>")
	)
	(segment
		(start 96.981264 -129.933954)
		(end 96.885506 -130.029712)
		(width 0.14224)
		(layer "In4.Cu")
		(net "M_L_CLK_DN<1>")
	)
	(segment
		(start 94.996508 -98.386138)
		(end 94.990158 -98.396806)
		(width 0.0889)
		(layer "In4.Cu")
		(net "M_L_CLK_DN<1>")
	)
	(segment
		(start 96.067372 -126.319026)
		(end 96.181164 -126.432818)
		(width 0.14224)
		(layer "In4.Cu")
		(net "M_L_CLK_DN<1>")
	)
	(segment
		(start 96.181164 -124.11837)
		(end 96.181164 -124.58319)
		(width 0.14224)
		(layer "In4.Cu")
		(net "M_L_CLK_DN<1>")
	)
	(segment
		(start 96.00819 -145.358104)
		(end 95.847408 -145.358104)
		(width 0.14224)
		(layer "In4.Cu")
		(net "M_L_CLK_DN<1>")
	)
	(segment
		(start 96.181164 -124.58319)
		(end 96.067372 -124.696982)
		(width 0.14224)
		(layer "In4.Cu")
		(net "M_L_CLK_DN<1>")
	)
	(segment
		(start 96.981264 -141.26464)
		(end 96.680528 -141.565376)
		(width 0.14224)
		(layer "In4.Cu")
		(net "M_L_CLK_DN<1>")
	)
	(segment
		(start 96.598486 -143.71955)
		(end 96.598486 -144.18437)
		(width 0.14224)
		(layer "In4.Cu")
		(net "M_L_CLK_DN<1>")
	)
	(segment
		(start 93.23705 -146.881088)
		(end 93.123258 -146.99488)
		(width 0.14224)
		(layer "In4.Cu")
		(net "M_L_CLK_DN<1>")
	)
	(arc
		(start 95.048832 -99.144836)
		(mid 95.041309 -99.260334)
		(end 95.00108 -99.368864)
		(width 0.0889)
		(layer "In4.Cu")
		(net "M_L_CLK_DN<1>")
	)
	(arc
		(start 94.996508 -96.995488)
		(mid 95.049978 -97.190551)
		(end 95.001334 -97.386902)
		(width 0.0889)
		(layer "In4.Cu")
		(net "M_L_CLK_DN<1>")
	)
	(arc
		(start 94.754954 -96.31045)
		(mid 94.87503 -96.490017)
		(end 94.91726 -96.701864)
		(width 0.0889)
		(layer "In4.Cu")
		(net "M_L_CLK_DN<1>")
	)
	(arc
		(start 94.996762 -98.976942)
		(mid 95.03213 -99.057995)
		(end 95.048832 -99.144836)
		(width 0.0889)
		(layer "In4.Cu")
		(net "M_L_CLK_DN<1>")
	)
	(arc
		(start 94.996508 -97.986088)
		(mid 95.049978 -98.181151)
		(end 95.001334 -98.377502)
		(width 0.0889)
		(layer "In4.Cu")
		(net "M_L_CLK_DN<1>")
	)
	(arc
		(start 94.990158 -98.396806)
		(mid 94.91736 -98.687569)
		(end 94.996508 -98.976688)
		(width 0.0889)
		(layer "In4.Cu")
		(net "M_L_CLK_DN<1>")
	)
	(arc
		(start 94.91726 -96.701864)
		(mid 94.937679 -96.853859)
		(end 94.996508 -96.995488)
		(width 0.0889)
		(layer "In4.Cu")
		(net "M_L_CLK_DN<1>")
	)
	(arc
		(start 94.990158 -97.406206)
		(mid 94.91736 -97.696969)
		(end 94.996508 -97.986088)
		(width 0.0889)
		(layer "In4.Cu")
		(net "M_L_CLK_DN<1>")
	)
	(segment
		(start 92.645738 -94.718886)
		(end 92.074238 -94.718886)
		(width 0.1016)
		(layer "F.Cu")
		(net "M_L_CLK_DN<2>")
	)
	(via
		(at 92.074238 -94.718886)
		(size 0.508)
		(drill 0.254)
		(layers "F.Cu" "B.Cu")
		(net "M_L_CLK_DN<2>")
	)
	(via
		(at 92.59951 -141.183868)
		(size 0.508)
		(drill 0.254)
		(layers "F.Cu" "B.Cu")
		(net "M_L_CLK_DN<2>")
	)
	(segment
		(start 92.59951 -142.477236)
		(end 92.59951 -141.183868)
		(width 0.1651)
		(layer "B.Cu")
		(net "M_L_CLK_DN<2>")
	)
	(segment
		(start 93.284294 -96.396302)
		(end 93.279468 -96.404938)
		(width 0.0889)
		(layer "In4.Cu")
		(net "M_L_CLK_DN<2>")
	)
	(segment
		(start 93.177868 -99.944428)
		(end 93.533468 -100.300028)
		(width 0.0889)
		(layer "In4.Cu")
		(net "M_L_CLK_DN<2>")
	)
	(segment
		(start 94.865952 -137.256266)
		(end 94.979744 -137.370058)
		(width 0.14224)
		(layer "In4.Cu")
		(net "M_L_CLK_DN<2>")
	)
	(segment
		(start 94.979744 -138.527282)
		(end 94.979744 -138.992102)
		(width 0.14224)
		(layer "In4.Cu")
		(net "M_L_CLK_DN<2>")
	)
	(segment
		(start 92.074238 -94.718886)
		(end 92.283026 -94.92742)
		(width 0.0889)
		(layer "In4.Cu")
		(net "M_L_CLK_DN<2>")
	)
	(segment
		(start 94.771464 -141.51483)
		(end 94.641162 -141.515084)
		(width 0.14224)
		(layer "In4.Cu")
		(net "M_L_CLK_DN<2>")
	)
	(segment
		(start 94.979744 -137.370058)
		(end 94.979744 -137.834878)
		(width 0.14224)
		(layer "In4.Cu")
		(net "M_L_CLK_DN<2>")
	)
	(segment
		(start 94.865952 -136.099042)
		(end 94.979744 -136.212834)
		(width 0.14224)
		(layer "In4.Cu")
		(net "M_L_CLK_DN<2>")
	)
	(segment
		(start 93.684598 -142.004796)
		(end 93.219778 -142.004796)
		(width 0.14224)
		(layer "In4.Cu")
		(net "M_L_CLK_DN<2>")
	)
	(segment
		(start 94.979744 -140.149326)
		(end 94.865952 -140.263118)
		(width 0.14224)
		(layer "In4.Cu")
		(net "M_L_CLK_DN<2>")
	)
	(segment
		(start 93.533468 -100.300028)
		(end 93.533468 -102.466394)
		(width 0.0889)
		(layer "In4.Cu")
		(net "M_L_CLK_DN<2>")
	)
	(segment
		(start 92.27693 -141.825472)
		(end 92.27693 -141.506448)
		(width 0.14224)
		(layer "In4.Cu")
		(net "M_L_CLK_DN<2>")
	)
	(segment
		(start 94.541848 -104.004364)
		(end 94.541848 -132.135626)
		(width 0.14224)
		(layer "In4.Cu")
		(net "M_L_CLK_DN<2>")
	)
	(segment
		(start 94.354142 -141.932152)
		(end 94.168214 -142.11808)
		(width 0.14224)
		(layer "In4.Cu")
		(net "M_L_CLK_DN<2>")
	)
	(segment
		(start 94.168214 -142.11808)
		(end 93.797882 -142.11808)
		(width 0.14224)
		(layer "In4.Cu")
		(net "M_L_CLK_DN<2>")
	)
	(segment
		(start 94.865952 -135.634222)
		(end 94.865952 -136.099042)
		(width 0.14224)
		(layer "In4.Cu")
		(net "M_L_CLK_DN<2>")
	)
	(segment
		(start 92.27693 -141.506448)
		(end 92.59951 -141.183868)
		(width 0.14224)
		(layer "In4.Cu")
		(net "M_L_CLK_DN<2>")
	)
	(segment
		(start 93.533468 -102.466394)
		(end 94.574868 -103.507794)
		(width 0.0889)
		(layer "In4.Cu")
		(net "M_L_CLK_DN<2>")
	)
	(segment
		(start 94.865952 -139.105894)
		(end 94.865952 -139.570714)
		(width 0.14224)
		(layer "In4.Cu")
		(net "M_L_CLK_DN<2>")
	)
	(segment
		(start 94.979744 -133.898386)
		(end 94.979744 -134.363206)
		(width 0.14224)
		(layer "In4.Cu")
		(net "M_L_CLK_DN<2>")
	)
	(segment
		(start 93.797882 -142.11808)
		(end 93.684598 -142.004796)
		(width 0.14224)
		(layer "In4.Cu")
		(net "M_L_CLK_DN<2>")
	)
	(segment
		(start 94.865952 -139.570714)
		(end 94.979744 -139.684506)
		(width 0.14224)
		(layer "In4.Cu")
		(net "M_L_CLK_DN<2>")
	)
	(segment
		(start 94.541848 -103.982266)
		(end 94.541848 -104.004364)
		(width 0.0889)
		(layer "In4.Cu")
		(net "M_L_CLK_DN<2>")
	)
	(segment
		(start 94.574868 -103.507794)
		(end 94.574868 -103.949246)
		(width 0.0889)
		(layer "In4.Cu")
		(net "M_L_CLK_DN<2>")
	)
	(segment
		(start 94.979744 -133.205982)
		(end 94.865952 -133.319774)
		(width 0.14224)
		(layer "In4.Cu")
		(net "M_L_CLK_DN<2>")
	)
	(segment
		(start 94.979744 -139.684506)
		(end 94.979744 -140.149326)
		(width 0.14224)
		(layer "In4.Cu")
		(net "M_L_CLK_DN<2>")
	)
	(segment
		(start 93.106494 -142.11808)
		(end 92.569538 -142.11808)
		(width 0.14224)
		(layer "In4.Cu")
		(net "M_L_CLK_DN<2>")
	)
	(segment
		(start 94.865952 -136.791446)
		(end 94.865952 -137.256266)
		(width 0.14224)
		(layer "In4.Cu")
		(net "M_L_CLK_DN<2>")
	)
	(segment
		(start 94.979744 -132.573522)
		(end 94.979744 -133.205982)
		(width 0.14224)
		(layer "In4.Cu")
		(net "M_L_CLK_DN<2>")
	)
	(segment
		(start 94.865952 -134.476998)
		(end 94.865952 -134.941818)
		(width 0.14224)
		(layer "In4.Cu")
		(net "M_L_CLK_DN<2>")
	)
	(segment
		(start 93.284294 -97.386902)
		(end 93.279468 -97.395538)
		(width 0.0889)
		(layer "In4.Cu")
		(net "M_L_CLK_DN<2>")
	)
	(segment
		(start 94.865952 -137.94867)
		(end 94.865952 -138.41349)
		(width 0.14224)
		(layer "In4.Cu")
		(net "M_L_CLK_DN<2>")
	)
	(segment
		(start 94.541848 -132.135626)
		(end 94.979744 -132.573522)
		(width 0.14224)
		(layer "In4.Cu")
		(net "M_L_CLK_DN<2>")
	)
	(segment
		(start 94.865952 -133.784594)
		(end 94.979744 -133.898386)
		(width 0.14224)
		(layer "In4.Cu")
		(net "M_L_CLK_DN<2>")
	)
	(segment
		(start 93.177868 -98.08464)
		(end 93.177868 -99.944428)
		(width 0.0889)
		(layer "In4.Cu")
		(net "M_L_CLK_DN<2>")
	)
	(segment
		(start 94.979744 -138.992102)
		(end 94.865952 -139.105894)
		(width 0.14224)
		(layer "In4.Cu")
		(net "M_L_CLK_DN<2>")
	)
	(segment
		(start 93.279468 -96.404938)
		(end 93.273118 -96.415606)
		(width 0.0889)
		(layer "In4.Cu")
		(net "M_L_CLK_DN<2>")
	)
	(segment
		(start 94.979744 -135.52043)
		(end 94.865952 -135.634222)
		(width 0.14224)
		(layer "In4.Cu")
		(net "M_L_CLK_DN<2>")
	)
	(segment
		(start 92.569538 -142.11808)
		(end 92.27693 -141.825472)
		(width 0.14224)
		(layer "In4.Cu")
		(net "M_L_CLK_DN<2>")
	)
	(segment
		(start 94.979744 -135.05561)
		(end 94.979744 -135.52043)
		(width 0.14224)
		(layer "In4.Cu")
		(net "M_L_CLK_DN<2>")
	)
	(segment
		(start 94.641162 -141.515084)
		(end 94.354142 -141.802104)
		(width 0.14224)
		(layer "In4.Cu")
		(net "M_L_CLK_DN<2>")
	)
	(segment
		(start 94.979744 -137.834878)
		(end 94.865952 -137.94867)
		(width 0.14224)
		(layer "In4.Cu")
		(net "M_L_CLK_DN<2>")
	)
	(segment
		(start 94.865952 -140.263118)
		(end 94.865952 -140.727938)
		(width 0.14224)
		(layer "In4.Cu")
		(net "M_L_CLK_DN<2>")
	)
	(segment
		(start 94.865952 -140.727938)
		(end 94.979744 -140.84173)
		(width 0.14224)
		(layer "In4.Cu")
		(net "M_L_CLK_DN<2>")
	)
	(segment
		(start 94.865952 -133.319774)
		(end 94.865952 -133.784594)
		(width 0.14224)
		(layer "In4.Cu")
		(net "M_L_CLK_DN<2>")
	)
	(segment
		(start 94.354142 -141.802104)
		(end 94.354142 -141.932152)
		(width 0.14224)
		(layer "In4.Cu")
		(net "M_L_CLK_DN<2>")
	)
	(segment
		(start 94.865952 -134.941818)
		(end 94.979744 -135.05561)
		(width 0.14224)
		(layer "In4.Cu")
		(net "M_L_CLK_DN<2>")
	)
	(segment
		(start 93.171518 -98.053398)
		(end 93.177868 -98.08464)
		(width 0.0889)
		(layer "In4.Cu")
		(net "M_L_CLK_DN<2>")
	)
	(segment
		(start 94.979744 -136.212834)
		(end 94.979744 -136.677654)
		(width 0.14224)
		(layer "In4.Cu")
		(net "M_L_CLK_DN<2>")
	)
	(segment
		(start 94.979744 -140.84173)
		(end 94.979744 -141.30655)
		(width 0.14224)
		(layer "In4.Cu")
		(net "M_L_CLK_DN<2>")
	)
	(segment
		(start 92.914978 -95.80499)
		(end 92.947744 -95.80499)
		(width 0.0889)
		(layer "In4.Cu")
		(net "M_L_CLK_DN<2>")
	)
	(segment
		(start 94.979744 -136.677654)
		(end 94.865952 -136.791446)
		(width 0.14224)
		(layer "In4.Cu")
		(net "M_L_CLK_DN<2>")
	)
	(segment
		(start 94.574868 -103.949246)
		(end 94.541848 -103.982266)
		(width 0.0889)
		(layer "In4.Cu")
		(net "M_L_CLK_DN<2>")
	)
	(segment
		(start 94.979744 -134.363206)
		(end 94.865952 -134.476998)
		(width 0.14224)
		(layer "In4.Cu")
		(net "M_L_CLK_DN<2>")
	)
	(segment
		(start 94.979744 -141.30655)
		(end 94.771464 -141.51483)
		(width 0.14224)
		(layer "In4.Cu")
		(net "M_L_CLK_DN<2>")
	)
	(segment
		(start 93.219778 -142.004796)
		(end 93.106494 -142.11808)
		(width 0.14224)
		(layer "In4.Cu")
		(net "M_L_CLK_DN<2>")
	)
	(segment
		(start 94.865952 -138.41349)
		(end 94.979744 -138.527282)
		(width 0.14224)
		(layer "In4.Cu")
		(net "M_L_CLK_DN<2>")
	)
	(arc
		(start 93.273118 -96.415606)
		(mid 93.20032 -96.706369)
		(end 93.279468 -96.995488)
		(width 0.0889)
		(layer "In4.Cu")
		(net "M_L_CLK_DN<2>")
	)
	(arc
		(start 93.279468 -97.395538)
		(mid 93.165657 -97.714643)
		(end 93.171518 -98.053398)
		(width 0.0889)
		(layer "In4.Cu")
		(net "M_L_CLK_DN<2>")
	)
	(arc
		(start 92.947744 -95.80499)
		(mid 93.280662 -96.006981)
		(end 93.284294 -96.396302)
		(width 0.0889)
		(layer "In4.Cu")
		(net "M_L_CLK_DN<2>")
	)
	(arc
		(start 92.348304 -95.126302)
		(mid 92.478992 -95.593102)
		(end 92.914978 -95.80499)
		(width 0.0889)
		(layer "In4.Cu")
		(net "M_L_CLK_DN<2>")
	)
	(arc
		(start 93.279468 -96.995488)
		(mid 93.332938 -97.190551)
		(end 93.284294 -97.386902)
		(width 0.0889)
		(layer "In4.Cu")
		(net "M_L_CLK_DN<2>")
	)
	(arc
		(start 92.283026 -94.92742)
		(mid 92.339339 -95.01909)
		(end 92.348304 -95.126302)
		(width 0.0889)
		(layer "In4.Cu")
		(net "M_L_CLK_DN<2>")
	)
	(segment
		(start 94.362778 -94.718886)
		(end 93.791278 -94.718886)
		(width 0.1016)
		(layer "F.Cu")
		(net "M_L_CLK_DN<0>")
	)
	(segment
		(start 92.59951 -142.6718)
		(end 92.59951 -143.970756)
		(width 0.1651)
		(layer "F.Cu")
		(net "M_L_CLK_DN<0>")
	)
	(via
		(at 92.59951 -143.970756)
		(size 0.508)
		(drill 0.254)
		(layers "F.Cu" "B.Cu")
		(net "M_L_CLK_DN<0>")
	)
	(via
		(at 93.791278 -94.718886)
		(size 0.508)
		(drill 0.254)
		(layers "F.Cu" "B.Cu")
		(net "M_L_CLK_DN<0>")
	)
	(segment
		(start 94.164658 -99.519232)
		(end 94.132146 -99.46132)
		(width 0.0889)
		(layer "In4.Cu")
		(net "M_L_CLK_DN<0>")
	)
	(segment
		(start 95.830136 -141.038072)
		(end 95.943928 -140.92428)
		(width 0.14224)
		(layer "In4.Cu")
		(net "M_L_CLK_DN<0>")
	)
	(segment
		(start 96.167448 -132.276088)
		(end 96.167448 -131.073652)
		(width 0.14224)
		(layer "In4.Cu")
		(net "M_L_CLK_DN<0>")
	)
	(segment
		(start 94.193868 -102.1969)
		(end 94.193868 -99.567746)
		(width 0.0889)
		(layer "In4.Cu")
		(net "M_L_CLK_DN<0>")
	)
	(segment
		(start 94.245176 -144.93748)
		(end 94.445582 -144.737074)
		(width 0.14224)
		(layer "In4.Cu")
		(net "M_L_CLK_DN<0>")
	)
	(segment
		(start 94.137988 -97.490788)
		(end 94.131638 -97.48012)
		(width 0.0889)
		(layer "In4.Cu")
		(net "M_L_CLK_DN<0>")
	)
	(segment
		(start 94.137988 -98.481388)
		(end 94.131638 -98.47072)
		(width 0.0889)
		(layer "In4.Cu")
		(net "M_L_CLK_DN<0>")
	)
	(segment
		(start 95.582994 -143.44015)
		(end 95.742506 -143.44015)
		(width 0.14224)
		(layer "In4.Cu")
		(net "M_L_CLK_DN<0>")
	)
	(segment
		(start 96.053656 -132.8547)
		(end 96.053656 -132.38988)
		(width 0.14224)
		(layer "In4.Cu")
		(net "M_L_CLK_DN<0>")
	)
	(segment
		(start 95.943928 -141.616684)
		(end 95.830136 -141.502892)
		(width 0.14224)
		(layer "In4.Cu")
		(net "M_L_CLK_DN<0>")
	)
	(segment
		(start 95.943928 -140.92428)
		(end 95.943928 -139.83716)
		(width 0.14224)
		(layer "In4.Cu")
		(net "M_L_CLK_DN<0>")
	)
	(segment
		(start 92.286582 -144.283684)
		(end 92.286582 -144.715738)
		(width 0.14224)
		(layer "In4.Cu")
		(net "M_L_CLK_DN<0>")
	)
	(segment
		(start 94.142814 -97.499424)
		(end 94.137988 -97.490788)
		(width 0.0889)
		(layer "In4.Cu")
		(net "M_L_CLK_DN<0>")
	)
	(segment
		(start 94.193868 -99.567746)
		(end 94.164658 -99.519232)
		(width 0.0889)
		(layer "In4.Cu")
		(net "M_L_CLK_DN<0>")
	)
	(segment
		(start 96.053656 -132.38988)
		(end 96.167448 -132.276088)
		(width 0.14224)
		(layer "In4.Cu")
		(net "M_L_CLK_DN<0>")
	)
	(segment
		(start 96.093026 -129.043176)
		(end 95.311976 -128.262126)
		(width 0.14224)
		(layer "In4.Cu")
		(net "M_L_CLK_DN<0>")
	)
	(segment
		(start 94.774258 -144.25422)
		(end 94.928436 -144.25422)
		(width 0.14224)
		(layer "In4.Cu")
		(net "M_L_CLK_DN<0>")
	)
	(segment
		(start 93.720412 -144.93748)
		(end 94.245176 -144.93748)
		(width 0.14224)
		(layer "In4.Cu")
		(net "M_L_CLK_DN<0>")
	)
	(segment
		(start 95.830136 -141.502892)
		(end 95.830136 -141.038072)
		(width 0.14224)
		(layer "In4.Cu")
		(net "M_L_CLK_DN<0>")
	)
	(segment
		(start 95.943928 -142.773908)
		(end 95.830136 -142.660116)
		(width 0.14224)
		(layer "In4.Cu")
		(net "M_L_CLK_DN<0>")
	)
	(segment
		(start 95.887794 -129.579116)
		(end 96.093026 -129.373884)
		(width 0.14224)
		(layer "In4.Cu")
		(net "M_L_CLK_DN<0>")
	)
	(segment
		(start 93.028516 -144.93748)
		(end 93.142054 -144.823942)
		(width 0.14224)
		(layer "In4.Cu")
		(net "M_L_CLK_DN<0>")
	)
	(segment
		(start 93.979238 -94.906846)
		(end 93.791278 -94.718886)
		(width 0.0889)
		(layer "In4.Cu")
		(net "M_L_CLK_DN<0>")
	)
	(segment
		(start 92.286582 -144.715738)
		(end 92.508324 -144.93748)
		(width 0.14224)
		(layer "In4.Cu")
		(net "M_L_CLK_DN<0>")
	)
	(segment
		(start 93.142054 -144.823942)
		(end 93.606874 -144.823942)
		(width 0.14224)
		(layer "In4.Cu")
		(net "M_L_CLK_DN<0>")
	)
	(segment
		(start 94.142814 -98.490024)
		(end 94.137988 -98.481388)
		(width 0.0889)
		(layer "In4.Cu")
		(net "M_L_CLK_DN<0>")
	)
	(segment
		(start 95.372428 -130.496056)
		(end 95.372428 -129.863596)
		(width 0.14224)
		(layer "In4.Cu")
		(net "M_L_CLK_DN<0>")
	)
	(segment
		(start 95.656908 -129.579116)
		(end 95.887794 -129.579116)
		(width 0.14224)
		(layer "In4.Cu")
		(net "M_L_CLK_DN<0>")
	)
	(segment
		(start 96.053656 -133.547104)
		(end 96.167448 -133.433312)
		(width 0.14224)
		(layer "In4.Cu")
		(net "M_L_CLK_DN<0>")
	)
	(segment
		(start 94.928436 -144.25422)
		(end 95.254318 -143.928338)
		(width 0.14224)
		(layer "In4.Cu")
		(net "M_L_CLK_DN<0>")
	)
	(segment
		(start 96.053656 -134.011924)
		(end 96.053656 -133.547104)
		(width 0.14224)
		(layer "In4.Cu")
		(net "M_L_CLK_DN<0>")
	)
	(segment
		(start 95.943928 -143.238728)
		(end 95.943928 -142.773908)
		(width 0.14224)
		(layer "In4.Cu")
		(net "M_L_CLK_DN<0>")
	)
	(segment
		(start 96.167448 -139.61364)
		(end 96.167448 -136.440164)
		(width 0.14224)
		(layer "In4.Cu")
		(net "M_L_CLK_DN<0>")
	)
	(segment
		(start 96.167448 -135.74776)
		(end 96.167448 -135.28294)
		(width 0.14224)
		(layer "In4.Cu")
		(net "M_L_CLK_DN<0>")
	)
	(segment
		(start 96.167448 -133.433312)
		(end 96.167448 -132.968492)
		(width 0.14224)
		(layer "In4.Cu")
		(net "M_L_CLK_DN<0>")
	)
	(segment
		(start 96.053656 -134.704328)
		(end 96.167448 -134.590536)
		(width 0.14224)
		(layer "In4.Cu")
		(net "M_L_CLK_DN<0>")
	)
	(segment
		(start 95.943928 -139.83716)
		(end 96.167448 -139.61364)
		(width 0.14224)
		(layer "In4.Cu")
		(net "M_L_CLK_DN<0>")
	)
	(segment
		(start 95.311976 -103.988108)
		(end 95.311976 -103.976932)
		(width 0.0889)
		(layer "In4.Cu")
		(net "M_L_CLK_DN<0>")
	)
	(segment
		(start 92.59951 -143.970756)
		(end 92.286582 -144.283684)
		(width 0.14224)
		(layer "In4.Cu")
		(net "M_L_CLK_DN<0>")
	)
	(segment
		(start 95.742506 -143.44015)
		(end 95.943928 -143.238728)
		(width 0.14224)
		(layer "In4.Cu")
		(net "M_L_CLK_DN<0>")
	)
	(segment
		(start 95.311976 -128.262126)
		(end 95.311976 -103.988108)
		(width 0.14224)
		(layer "In4.Cu")
		(net "M_L_CLK_DN<0>")
	)
	(segment
		(start 95.830136 -142.195296)
		(end 95.943928 -142.081504)
		(width 0.14224)
		(layer "In4.Cu")
		(net "M_L_CLK_DN<0>")
	)
	(segment
		(start 95.830136 -142.660116)
		(end 95.830136 -142.195296)
		(width 0.14224)
		(layer "In4.Cu")
		(net "M_L_CLK_DN<0>")
	)
	(segment
		(start 96.053656 -136.326372)
		(end 96.053656 -135.861552)
		(width 0.14224)
		(layer "In4.Cu")
		(net "M_L_CLK_DN<0>")
	)
	(segment
		(start 95.372428 -129.863596)
		(end 95.656908 -129.579116)
		(width 0.14224)
		(layer "In4.Cu")
		(net "M_L_CLK_DN<0>")
	)
	(segment
		(start 94.445582 -144.582896)
		(end 94.774258 -144.25422)
		(width 0.14224)
		(layer "In4.Cu")
		(net "M_L_CLK_DN<0>")
	)
	(segment
		(start 93.606874 -144.823942)
		(end 93.720412 -144.93748)
		(width 0.14224)
		(layer "In4.Cu")
		(net "M_L_CLK_DN<0>")
	)
	(segment
		(start 95.311976 -103.976932)
		(end 95.344996 -103.943912)
		(width 0.0889)
		(layer "In4.Cu")
		(net "M_L_CLK_DN<0>")
	)
	(segment
		(start 96.167448 -134.590536)
		(end 96.167448 -134.125716)
		(width 0.14224)
		(layer "In4.Cu")
		(net "M_L_CLK_DN<0>")
	)
	(segment
		(start 95.344996 -103.943912)
		(end 95.344996 -103.348028)
		(width 0.0889)
		(layer "In4.Cu")
		(net "M_L_CLK_DN<0>")
	)
	(segment
		(start 96.167448 -134.125716)
		(end 96.053656 -134.011924)
		(width 0.14224)
		(layer "In4.Cu")
		(net "M_L_CLK_DN<0>")
	)
	(segment
		(start 95.656908 -130.780536)
		(end 95.372428 -130.496056)
		(width 0.14224)
		(layer "In4.Cu")
		(net "M_L_CLK_DN<0>")
	)
	(segment
		(start 96.053656 -135.861552)
		(end 96.167448 -135.74776)
		(width 0.14224)
		(layer "In4.Cu")
		(net "M_L_CLK_DN<0>")
	)
	(segment
		(start 94.142814 -96.508824)
		(end 94.137988 -96.500188)
		(width 0.0889)
		(layer "In4.Cu")
		(net "M_L_CLK_DN<0>")
	)
	(segment
		(start 96.167448 -132.968492)
		(end 96.053656 -132.8547)
		(width 0.14224)
		(layer "In4.Cu")
		(net "M_L_CLK_DN<0>")
	)
	(segment
		(start 96.167448 -131.073652)
		(end 95.874332 -130.780536)
		(width 0.14224)
		(layer "In4.Cu")
		(net "M_L_CLK_DN<0>")
	)
	(segment
		(start 92.508324 -144.93748)
		(end 93.028516 -144.93748)
		(width 0.14224)
		(layer "In4.Cu")
		(net "M_L_CLK_DN<0>")
	)
	(segment
		(start 94.137988 -96.500188)
		(end 94.131638 -96.48952)
		(width 0.0889)
		(layer "In4.Cu")
		(net "M_L_CLK_DN<0>")
	)
	(segment
		(start 95.254318 -143.768826)
		(end 95.582994 -143.44015)
		(width 0.14224)
		(layer "In4.Cu")
		(net "M_L_CLK_DN<0>")
	)
	(segment
		(start 94.132146 -99.46132)
		(end 94.131638 -99.460558)
		(width 0.0889)
		(layer "In4.Cu")
		(net "M_L_CLK_DN<0>")
	)
	(segment
		(start 95.874332 -130.780536)
		(end 95.656908 -130.780536)
		(width 0.14224)
		(layer "In4.Cu")
		(net "M_L_CLK_DN<0>")
	)
	(segment
		(start 95.344996 -103.348028)
		(end 94.193868 -102.1969)
		(width 0.0889)
		(layer "In4.Cu")
		(net "M_L_CLK_DN<0>")
	)
	(segment
		(start 96.167448 -135.28294)
		(end 96.053656 -135.169148)
		(width 0.14224)
		(layer "In4.Cu")
		(net "M_L_CLK_DN<0>")
	)
	(segment
		(start 95.943928 -142.081504)
		(end 95.943928 -141.616684)
		(width 0.14224)
		(layer "In4.Cu")
		(net "M_L_CLK_DN<0>")
	)
	(segment
		(start 94.137988 -95.509588)
		(end 94.131638 -95.49892)
		(width 0.0889)
		(layer "In4.Cu")
		(net "M_L_CLK_DN<0>")
	)
	(segment
		(start 94.142814 -95.518224)
		(end 94.137988 -95.509588)
		(width 0.0889)
		(layer "In4.Cu")
		(net "M_L_CLK_DN<0>")
	)
	(segment
		(start 96.167448 -136.440164)
		(end 96.053656 -136.326372)
		(width 0.14224)
		(layer "In4.Cu")
		(net "M_L_CLK_DN<0>")
	)
	(segment
		(start 95.254318 -143.928338)
		(end 95.254318 -143.768826)
		(width 0.14224)
		(layer "In4.Cu")
		(net "M_L_CLK_DN<0>")
	)
	(segment
		(start 96.053656 -135.169148)
		(end 96.053656 -134.704328)
		(width 0.14224)
		(layer "In4.Cu")
		(net "M_L_CLK_DN<0>")
	)
	(segment
		(start 94.445582 -144.737074)
		(end 94.445582 -144.582896)
		(width 0.14224)
		(layer "In4.Cu")
		(net "M_L_CLK_DN<0>")
	)
	(segment
		(start 96.093026 -129.373884)
		(end 96.093026 -129.043176)
		(width 0.14224)
		(layer "In4.Cu")
		(net "M_L_CLK_DN<0>")
	)
	(arc
		(start 94.131638 -96.48952)
		(mid 94.05884 -96.198757)
		(end 94.137988 -95.909638)
		(width 0.0889)
		(layer "In4.Cu")
		(net "M_L_CLK_DN<0>")
	)
	(arc
		(start 94.137988 -95.909638)
		(mid 94.191458 -95.714575)
		(end 94.142814 -95.518224)
		(width 0.0889)
		(layer "In4.Cu")
		(net "M_L_CLK_DN<0>")
	)
	(arc
		(start 94.06255 -95.146368)
		(mid 94.048295 -95.017086)
		(end 93.979238 -94.906846)
		(width 0.0889)
		(layer "In4.Cu")
		(net "M_L_CLK_DN<0>")
	)
	(arc
		(start 94.131638 -97.48012)
		(mid 94.05884 -97.189357)
		(end 94.137988 -96.900238)
		(width 0.0889)
		(layer "In4.Cu")
		(net "M_L_CLK_DN<0>")
	)
	(arc
		(start 94.137988 -96.900238)
		(mid 94.191458 -96.705175)
		(end 94.142814 -96.508824)
		(width 0.0889)
		(layer "In4.Cu")
		(net "M_L_CLK_DN<0>")
	)
	(arc
		(start 94.137988 -97.890838)
		(mid 94.191458 -97.695775)
		(end 94.142814 -97.499424)
		(width 0.0889)
		(layer "In4.Cu")
		(net "M_L_CLK_DN<0>")
	)
	(arc
		(start 94.131638 -95.49892)
		(mid 94.069669 -95.328021)
		(end 94.06255 -95.146368)
		(width 0.0889)
		(layer "In4.Cu")
		(net "M_L_CLK_DN<0>")
	)
	(arc
		(start 94.131638 -98.47072)
		(mid 94.05884 -98.179957)
		(end 94.137988 -97.890838)
		(width 0.0889)
		(layer "In4.Cu")
		(net "M_L_CLK_DN<0>")
	)
	(arc
		(start 94.131638 -99.460558)
		(mid 94.058961 -99.170159)
		(end 94.137988 -98.881438)
		(width 0.0889)
		(layer "In4.Cu")
		(net "M_L_CLK_DN<0>")
	)
	(arc
		(start 94.137988 -98.881438)
		(mid 94.191458 -98.686375)
		(end 94.142814 -98.490024)
		(width 0.0889)
		(layer "In4.Cu")
		(net "M_L_CLK_DN<0>")
	)
	(segment
		(start 86.636352 -96.20504)
		(end 86.064852 -96.20504)
		(width 0.1016)
		(layer "F.Cu")
		(net "M_L_CKE<3>")
	)
	(via
		(at 86.064852 -96.20504)
		(size 0.508)
		(drill 0.254)
		(layers "F.Cu" "B.Cu")
		(net "M_L_CKE<3>")
	)
	(via
		(at 78.999334 -139.170156)
		(size 0.4572)
		(drill 0.2032)
		(layers "F.Cu" "B.Cu")
		(net "M_L_CKE<3>")
	)
	(segment
		(start 78.999334 -137.877296)
		(end 78.999334 -139.170156)
		(width 0.1651)
		(layer "B.Cu")
		(net "M_L_CKE<3>")
	)
	(segment
		(start 85.665056 -98.351848)
		(end 85.665056 -98.114104)
		(width 0.0889)
		(layer "In4.Cu")
		(net "M_L_CKE<3>")
	)
	(segment
		(start 85.718142 -96.995488)
		(end 85.734906 -96.966786)
		(width 0.0889)
		(layer "In4.Cu")
		(net "M_L_CKE<3>")
	)
	(segment
		(start 85.734906 -96.966786)
		(end 86.064852 -96.20504)
		(width 0.0889)
		(layer "In4.Cu")
		(net "M_L_CKE<3>")
	)
	(segment
		(start 85.718142 -97.395538)
		(end 85.713316 -97.386902)
		(width 0.0889)
		(layer "In4.Cu")
		(net "M_L_CKE<3>")
	)
	(segment
		(start 79.207868 -131.5085)
		(end 79.499968 -131.2164)
		(width 0.14224)
		(layer "In4.Cu")
		(net "M_L_CKE<3>")
	)
	(segment
		(start 85.734398 -97.946718)
		(end 85.743034 -97.938082)
		(width 0.0889)
		(layer "In4.Cu")
		(net "M_L_CKE<3>")
	)
	(segment
		(start 78.999334 -138.524488)
		(end 79.409036 -138.114786)
		(width 0.14224)
		(layer "In4.Cu")
		(net "M_L_CKE<3>")
	)
	(segment
		(start 79.435706 -135.979662)
		(end 79.435706 -134.098538)
		(width 0.14224)
		(layer "In4.Cu")
		(net "M_L_CKE<3>")
	)
	(segment
		(start 79.499968 -130.6068)
		(end 79.347568 -130.4544)
		(width 0.14224)
		(layer "In4.Cu")
		(net "M_L_CKE<3>")
	)
	(segment
		(start 78.999334 -139.170156)
		(end 78.999334 -138.524488)
		(width 0.14224)
		(layer "In4.Cu")
		(net "M_L_CKE<3>")
	)
	(segment
		(start 79.409036 -136.006332)
		(end 79.435706 -135.979662)
		(width 0.14224)
		(layer "In4.Cu")
		(net "M_L_CKE<3>")
	)
	(segment
		(start 86.041484 -120.280684)
		(end 86.041484 -101.715316)
		(width 0.14224)
		(layer "In4.Cu")
		(net "M_L_CKE<3>")
	)
	(segment
		(start 79.347568 -130.4544)
		(end 79.347568 -130.048)
		(width 0.14224)
		(layer "In4.Cu")
		(net "M_L_CKE<3>")
	)
	(segment
		(start 86.041484 -101.715316)
		(end 86.041484 -98.728276)
		(width 0.0889)
		(layer "In4.Cu")
		(net "M_L_CKE<3>")
	)
	(segment
		(start 79.207868 -133.8707)
		(end 79.207868 -131.5085)
		(width 0.14224)
		(layer "In4.Cu")
		(net "M_L_CKE<3>")
	)
	(segment
		(start 79.626968 -126.6952)
		(end 86.041484 -120.280684)
		(width 0.14224)
		(layer "In4.Cu")
		(net "M_L_CKE<3>")
	)
	(segment
		(start 79.626968 -129.7686)
		(end 79.626968 -126.6952)
		(width 0.14224)
		(layer "In4.Cu")
		(net "M_L_CKE<3>")
	)
	(segment
		(start 79.409036 -138.114786)
		(end 79.409036 -136.006332)
		(width 0.14224)
		(layer "In4.Cu")
		(net "M_L_CKE<3>")
	)
	(segment
		(start 79.347568 -130.048)
		(end 79.626968 -129.7686)
		(width 0.14224)
		(layer "In4.Cu")
		(net "M_L_CKE<3>")
	)
	(segment
		(start 79.499968 -131.2164)
		(end 79.499968 -130.6068)
		(width 0.14224)
		(layer "In4.Cu")
		(net "M_L_CKE<3>")
	)
	(segment
		(start 79.435706 -134.098538)
		(end 79.207868 -133.8707)
		(width 0.14224)
		(layer "In4.Cu")
		(net "M_L_CKE<3>")
	)
	(segment
		(start 86.041484 -98.728276)
		(end 85.665056 -98.351848)
		(width 0.0889)
		(layer "In4.Cu")
		(net "M_L_CKE<3>")
	)
	(segment
		(start 85.724492 -97.406206)
		(end 85.718142 -97.395538)
		(width 0.0889)
		(layer "In4.Cu")
		(net "M_L_CKE<3>")
	)
	(arc
		(start 85.713316 -97.386902)
		(mid 85.664561 -97.19055)
		(end 85.718142 -96.995488)
		(width 0.0889)
		(layer "In4.Cu")
		(net "M_L_CKE<3>")
	)
	(arc
		(start 85.743034 -97.938082)
		(mid 85.79706 -97.669927)
		(end 85.724492 -97.406206)
		(width 0.0889)
		(layer "In4.Cu")
		(net "M_L_CKE<3>")
	)
	(arc
		(start 85.665056 -98.114104)
		(mid 85.683076 -98.023512)
		(end 85.734398 -97.946718)
		(width 0.0889)
		(layer "In4.Cu")
		(net "M_L_CKE<3>")
	)
	(segment
		(start 86.636352 -94.223586)
		(end 86.064852 -94.223586)
		(width 0.1016)
		(layer "F.Cu")
		(net "M_L_CKE<2>")
	)
	(via
		(at 86.064852 -94.223586)
		(size 0.508)
		(drill 0.254)
		(layers "F.Cu" "B.Cu")
		(net "M_L_CKE<2>")
	)
	(via
		(at 79.849472 -141.187678)
		(size 0.4572)
		(drill 0.2032)
		(layers "F.Cu" "B.Cu")
		(net "M_L_CKE<2>")
	)
	(segment
		(start 79.849472 -142.477236)
		(end 79.849472 -141.187678)
		(width 0.1651)
		(layer "B.Cu")
		(net "M_L_CKE<2>")
	)
	(segment
		(start 81.049368 -133.985)
		(end 81.049368 -131.318)
		(width 0.14224)
		(layer "In4.Cu")
		(net "M_L_CKE<2>")
	)
	(segment
		(start 81.136998 -134.07263)
		(end 81.049368 -133.985)
		(width 0.14224)
		(layer "In4.Cu")
		(net "M_L_CKE<2>")
	)
	(segment
		(start 80.160368 -140.876782)
		(end 80.160368 -140.2334)
		(width 0.14224)
		(layer "In4.Cu")
		(net "M_L_CKE<2>")
	)
	(segment
		(start 81.176368 -131.191)
		(end 81.176368 -130.6068)
		(width 0.14224)
		(layer "In4.Cu")
		(net "M_L_CKE<2>")
	)
	(segment
		(start 81.176368 -130.6068)
		(end 81.074768 -130.5052)
		(width 0.14224)
		(layer "In4.Cu")
		(net "M_L_CKE<2>")
	)
	(segment
		(start 86.576662 -94.919038)
		(end 86.559898 -94.889828)
		(width 0.0889)
		(layer "In4.Cu")
		(net "M_L_CKE<2>")
	)
	(segment
		(start 87.057484 -101.562916)
		(end 86.434168 -100.9396)
		(width 0.0889)
		(layer "In4.Cu")
		(net "M_L_CKE<2>")
	)
	(segment
		(start 81.114646 -138.034522)
		(end 81.114646 -134.783322)
		(width 0.14224)
		(layer "In4.Cu")
		(net "M_L_CKE<2>")
	)
	(segment
		(start 86.576662 -96.500188)
		(end 86.583012 -96.48952)
		(width 0.0889)
		(layer "In4.Cu")
		(net "M_L_CKE<2>")
	)
	(segment
		(start 86.576662 -95.509588)
		(end 86.583012 -95.49892)
		(width 0.0889)
		(layer "In4.Cu")
		(net "M_L_CKE<2>")
	)
	(segment
		(start 86.571836 -96.508824)
		(end 86.576662 -96.500188)
		(width 0.0889)
		(layer "In4.Cu")
		(net "M_L_CKE<2>")
	)
	(segment
		(start 80.338168 -139.6238)
		(end 80.289908 -139.57554)
		(width 0.14224)
		(layer "In4.Cu")
		(net "M_L_CKE<2>")
	)
	(segment
		(start 86.576662 -97.490788)
		(end 86.583012 -97.48012)
		(width 0.0889)
		(layer "In4.Cu")
		(net "M_L_CKE<2>")
	)
	(segment
		(start 81.049368 -131.318)
		(end 81.176368 -131.191)
		(width 0.14224)
		(layer "In4.Cu")
		(net "M_L_CKE<2>")
	)
	(segment
		(start 80.338168 -140.0556)
		(end 80.338168 -139.6238)
		(width 0.14224)
		(layer "In4.Cu")
		(net "M_L_CKE<2>")
	)
	(segment
		(start 80.160368 -140.2334)
		(end 80.338168 -140.0556)
		(width 0.14224)
		(layer "In4.Cu")
		(net "M_L_CKE<2>")
	)
	(segment
		(start 80.289908 -138.85926)
		(end 81.114646 -138.034522)
		(width 0.14224)
		(layer "In4.Cu")
		(net "M_L_CKE<2>")
	)
	(segment
		(start 86.559898 -94.889828)
		(end 86.064852 -94.223586)
		(width 0.0889)
		(layer "In4.Cu")
		(net "M_L_CKE<2>")
	)
	(segment
		(start 86.571836 -98.490024)
		(end 86.576662 -98.481388)
		(width 0.0889)
		(layer "In4.Cu")
		(net "M_L_CKE<2>")
	)
	(segment
		(start 81.074768 -130.5052)
		(end 81.074768 -129.9972)
		(width 0.14224)
		(layer "In4.Cu")
		(net "M_L_CKE<2>")
	)
	(segment
		(start 86.434168 -100.9396)
		(end 86.434168 -98.887534)
		(width 0.0889)
		(layer "In4.Cu")
		(net "M_L_CKE<2>")
	)
	(segment
		(start 86.571836 -97.499424)
		(end 86.576662 -97.490788)
		(width 0.0889)
		(layer "In4.Cu")
		(net "M_L_CKE<2>")
	)
	(segment
		(start 86.434168 -98.887534)
		(end 86.525862 -98.63328)
		(width 0.0889)
		(layer "In4.Cu")
		(net "M_L_CKE<2>")
	)
	(segment
		(start 81.252568 -129.8194)
		(end 81.252568 -126.5682)
		(width 0.14224)
		(layer "In4.Cu")
		(net "M_L_CKE<2>")
	)
	(segment
		(start 86.576662 -98.481388)
		(end 86.583012 -98.47072)
		(width 0.0889)
		(layer "In4.Cu")
		(net "M_L_CKE<2>")
	)
	(segment
		(start 86.571836 -95.518224)
		(end 86.576662 -95.509588)
		(width 0.0889)
		(layer "In4.Cu")
		(net "M_L_CKE<2>")
	)
	(segment
		(start 80.289908 -139.57554)
		(end 80.289908 -138.85926)
		(width 0.14224)
		(layer "In4.Cu")
		(net "M_L_CKE<2>")
	)
	(segment
		(start 87.057484 -101.800152)
		(end 87.057484 -101.562916)
		(width 0.0889)
		(layer "In4.Cu")
		(net "M_L_CKE<2>")
	)
	(segment
		(start 81.074768 -129.9972)
		(end 81.252568 -129.8194)
		(width 0.14224)
		(layer "In4.Cu")
		(net "M_L_CKE<2>")
	)
	(segment
		(start 81.136998 -134.76097)
		(end 81.136998 -134.07263)
		(width 0.14224)
		(layer "In4.Cu")
		(net "M_L_CKE<2>")
	)
	(segment
		(start 81.114646 -134.783322)
		(end 81.136998 -134.76097)
		(width 0.14224)
		(layer "In4.Cu")
		(net "M_L_CKE<2>")
	)
	(segment
		(start 87.057484 -120.763284)
		(end 87.057484 -101.800152)
		(width 0.14224)
		(layer "In4.Cu")
		(net "M_L_CKE<2>")
	)
	(segment
		(start 79.849472 -141.187678)
		(end 80.160368 -140.876782)
		(width 0.14224)
		(layer "In4.Cu")
		(net "M_L_CKE<2>")
	)
	(segment
		(start 81.252568 -126.5682)
		(end 87.057484 -120.763284)
		(width 0.14224)
		(layer "In4.Cu")
		(net "M_L_CKE<2>")
	)
	(arc
		(start 86.583012 -98.47072)
		(mid 86.65581 -98.179957)
		(end 86.576662 -97.890838)
		(width 0.0889)
		(layer "In4.Cu")
		(net "M_L_CKE<2>")
	)
	(arc
		(start 86.576662 -95.909638)
		(mid 86.523192 -95.714575)
		(end 86.571836 -95.518224)
		(width 0.0889)
		(layer "In4.Cu")
		(net "M_L_CKE<2>")
	)
	(arc
		(start 86.525862 -98.63328)
		(mid 86.542052 -98.55947)
		(end 86.571836 -98.490024)
		(width 0.0889)
		(layer "In4.Cu")
		(net "M_L_CKE<2>")
	)
	(arc
		(start 86.583012 -95.49892)
		(mid 86.65581 -95.208157)
		(end 86.576662 -94.919038)
		(width 0.0889)
		(layer "In4.Cu")
		(net "M_L_CKE<2>")
	)
	(arc
		(start 86.576662 -96.900238)
		(mid 86.523192 -96.705175)
		(end 86.571836 -96.508824)
		(width 0.0889)
		(layer "In4.Cu")
		(net "M_L_CKE<2>")
	)
	(arc
		(start 86.583012 -97.48012)
		(mid 86.65581 -97.189357)
		(end 86.576662 -96.900238)
		(width 0.0889)
		(layer "In4.Cu")
		(net "M_L_CKE<2>")
	)
	(arc
		(start 86.576662 -97.890838)
		(mid 86.523192 -97.695775)
		(end 86.571836 -97.499424)
		(width 0.0889)
		(layer "In4.Cu")
		(net "M_L_CKE<2>")
	)
	(arc
		(start 86.583012 -96.48952)
		(mid 86.65581 -96.198757)
		(end 86.576662 -95.909638)
		(width 0.0889)
		(layer "In4.Cu")
		(net "M_L_CKE<2>")
	)
	(segment
		(start 78.999334 -145.988278)
		(end 78.999334 -147.27174)
		(width 0.1651)
		(layer "F.Cu")
		(net "M_L_CKE<1>")
	)
	(segment
		(start 86.636352 -95.21444)
		(end 86.064852 -95.21444)
		(width 0.1016)
		(layer "F.Cu")
		(net "M_L_CKE<1>")
	)
	(via
		(at 86.064852 -95.21444)
		(size 0.508)
		(drill 0.254)
		(layers "F.Cu" "B.Cu")
		(net "M_L_CKE<1>")
	)
	(via
		(at 78.999334 -145.988278)
		(size 0.4572)
		(drill 0.2032)
		(layers "F.Cu" "B.Cu")
		(net "M_L_CKE<1>")
	)
	(segment
		(start 80.263746 -134.084822)
		(end 80.263746 -136.094978)
		(width 0.14224)
		(layer "In4.Cu")
		(net "M_L_CKE<1>")
	)
	(segment
		(start 80.286098 -136.11733)
		(end 80.286098 -138.02487)
		(width 0.14224)
		(layer "In4.Cu")
		(net "M_L_CKE<1>")
	)
	(segment
		(start 80.338168 -129.9972)
		(end 80.338168 -130.5052)
		(width 0.14224)
		(layer "In4.Cu")
		(net "M_L_CKE<1>")
	)
	(segment
		(start 78.999334 -144.671034)
		(end 78.999334 -145.988278)
		(width 0.14224)
		(layer "In4.Cu")
		(net "M_L_CKE<1>")
	)
	(segment
		(start 80.211168 -131.191)
		(end 80.312768 -131.2926)
		(width 0.14224)
		(layer "In4.Cu")
		(net "M_L_CKE<1>")
	)
	(segment
		(start 80.211168 -126.873)
		(end 80.211168 -129.8702)
		(width 0.14224)
		(layer "In4.Cu")
		(net "M_L_CKE<1>")
	)
	(segment
		(start 80.211168 -129.8702)
		(end 80.338168 -129.9972)
		(width 0.14224)
		(layer "In4.Cu")
		(net "M_L_CKE<1>")
	)
	(segment
		(start 79.439008 -144.23136)
		(end 78.999334 -144.671034)
		(width 0.14224)
		(layer "In4.Cu")
		(net "M_L_CKE<1>")
	)
	(segment
		(start 86.411562 -98.386138)
		(end 86.405212 -98.396806)
		(width 0.0889)
		(layer "In4.Cu")
		(net "M_L_CKE<1>")
	)
	(segment
		(start 80.263746 -136.094978)
		(end 80.286098 -136.11733)
		(width 0.14224)
		(layer "In4.Cu")
		(net "M_L_CKE<1>")
	)
	(segment
		(start 86.411562 -96.404938)
		(end 86.405212 -96.415606)
		(width 0.0889)
		(layer "In4.Cu")
		(net "M_L_CKE<1>")
	)
	(segment
		(start 86.416388 -97.386902)
		(end 86.411562 -97.395538)
		(width 0.0889)
		(layer "In4.Cu")
		(net "M_L_CKE<1>")
	)
	(segment
		(start 80.211168 -130.6322)
		(end 80.211168 -131.191)
		(width 0.14224)
		(layer "In4.Cu")
		(net "M_L_CKE<1>")
	)
	(segment
		(start 79.412846 -138.898122)
		(end 79.412846 -140.146278)
		(width 0.14224)
		(layer "In4.Cu")
		(net "M_L_CKE<1>")
	)
	(segment
		(start 80.312768 -131.2926)
		(end 80.312768 -134.0358)
		(width 0.14224)
		(layer "In4.Cu")
		(net "M_L_CKE<1>")
	)
	(segment
		(start 80.286098 -138.02487)
		(end 79.412846 -138.898122)
		(width 0.14224)
		(layer "In4.Cu")
		(net "M_L_CKE<1>")
	)
	(segment
		(start 86.549484 -101.854762)
		(end 86.549484 -120.534684)
		(width 0.14224)
		(layer "In4.Cu")
		(net "M_L_CKE<1>")
	)
	(segment
		(start 79.412846 -140.146278)
		(end 79.439008 -140.17244)
		(width 0.14224)
		(layer "In4.Cu")
		(net "M_L_CKE<1>")
	)
	(segment
		(start 80.312768 -134.0358)
		(end 80.263746 -134.084822)
		(width 0.14224)
		(layer "In4.Cu")
		(net "M_L_CKE<1>")
	)
	(segment
		(start 86.243668 -101.240844)
		(end 86.549484 -101.54666)
		(width 0.0889)
		(layer "In4.Cu")
		(net "M_L_CKE<1>")
	)
	(segment
		(start 86.411562 -97.395538)
		(end 86.405212 -97.406206)
		(width 0.0889)
		(layer "In4.Cu")
		(net "M_L_CKE<1>")
	)
	(segment
		(start 86.394798 -95.976186)
		(end 86.411562 -96.004888)
		(width 0.0889)
		(layer "In4.Cu")
		(net "M_L_CKE<1>")
	)
	(segment
		(start 86.064852 -95.21444)
		(end 86.394798 -95.976186)
		(width 0.0889)
		(layer "In4.Cu")
		(net "M_L_CKE<1>")
	)
	(segment
		(start 80.338168 -130.5052)
		(end 80.211168 -130.6322)
		(width 0.14224)
		(layer "In4.Cu")
		(net "M_L_CKE<1>")
	)
	(segment
		(start 86.367874 -98.479356)
		(end 86.271608 -98.58756)
		(width 0.0889)
		(layer "In4.Cu")
		(net "M_L_CKE<1>")
	)
	(segment
		(start 79.439008 -140.17244)
		(end 79.439008 -144.23136)
		(width 0.14224)
		(layer "In4.Cu")
		(net "M_L_CKE<1>")
	)
	(segment
		(start 86.549484 -120.534684)
		(end 80.211168 -126.873)
		(width 0.14224)
		(layer "In4.Cu")
		(net "M_L_CKE<1>")
	)
	(segment
		(start 86.416388 -96.396302)
		(end 86.411562 -96.404938)
		(width 0.0889)
		(layer "In4.Cu")
		(net "M_L_CKE<1>")
	)
	(segment
		(start 86.549484 -101.54666)
		(end 86.549484 -101.854762)
		(width 0.0889)
		(layer "In4.Cu")
		(net "M_L_CKE<1>")
	)
	(segment
		(start 86.416388 -98.377502)
		(end 86.411562 -98.386138)
		(width 0.0889)
		(layer "In4.Cu")
		(net "M_L_CKE<1>")
	)
	(segment
		(start 86.271608 -98.58756)
		(end 86.243668 -98.6155)
		(width 0.0889)
		(layer "In4.Cu")
		(net "M_L_CKE<1>")
	)
	(segment
		(start 86.243668 -98.6155)
		(end 86.243668 -101.240844)
		(width 0.0889)
		(layer "In4.Cu")
		(net "M_L_CKE<1>")
	)
	(arc
		(start 86.405212 -98.396806)
		(mid 86.38495 -98.437361)
		(end 86.367874 -98.479356)
		(width 0.0889)
		(layer "In4.Cu")
		(net "M_L_CKE<1>")
	)
	(arc
		(start 86.405212 -96.415606)
		(mid 86.332414 -96.706369)
		(end 86.411562 -96.995488)
		(width 0.0889)
		(layer "In4.Cu")
		(net "M_L_CKE<1>")
	)
	(arc
		(start 86.405212 -97.406206)
		(mid 86.332414 -97.696969)
		(end 86.411562 -97.986088)
		(width 0.0889)
		(layer "In4.Cu")
		(net "M_L_CKE<1>")
	)
	(arc
		(start 86.411562 -97.986088)
		(mid 86.465032 -98.181151)
		(end 86.416388 -98.377502)
		(width 0.0889)
		(layer "In4.Cu")
		(net "M_L_CKE<1>")
	)
	(arc
		(start 86.411562 -96.995488)
		(mid 86.465032 -97.190551)
		(end 86.416388 -97.386902)
		(width 0.0889)
		(layer "In4.Cu")
		(net "M_L_CKE<1>")
	)
	(arc
		(start 86.411562 -96.004888)
		(mid 86.465032 -96.199951)
		(end 86.416388 -96.396302)
		(width 0.0889)
		(layer "In4.Cu")
		(net "M_L_CKE<1>")
	)
	(segment
		(start 79.849472 -142.6718)
		(end 79.849472 -143.970756)
		(width 0.1651)
		(layer "F.Cu")
		(net "M_L_CKE<0>")
	)
	(segment
		(start 87.494872 -94.718886)
		(end 86.923372 -94.718886)
		(width 0.1016)
		(layer "F.Cu")
		(net "M_L_CKE<0>")
	)
	(via
		(at 86.923372 -94.718886)
		(size 0.508)
		(drill 0.254)
		(layers "F.Cu" "B.Cu")
		(net "M_L_CKE<0>")
	)
	(via
		(at 79.849472 -143.970756)
		(size 0.4572)
		(drill 0.2032)
		(layers "F.Cu" "B.Cu")
		(net "M_L_CKE<0>")
	)
	(segment
		(start 87.270082 -96.500188)
		(end 87.263732 -96.48952)
		(width 0.0889)
		(layer "In4.Cu")
		(net "M_L_CKE<0>")
	)
	(segment
		(start 81.114646 -139.583922)
		(end 81.114646 -138.735054)
		(width 0.14224)
		(layer "In4.Cu")
		(net "M_L_CKE<0>")
	)
	(segment
		(start 81.989168 -131.953)
		(end 82.039968 -131.9022)
		(width 0.14224)
		(layer "In4.Cu")
		(net "M_L_CKE<0>")
	)
	(segment
		(start 81.912968 -126.6952)
		(end 87.57666 -121.031508)
		(width 0.14224)
		(layer "In4.Cu")
		(net "M_L_CKE<0>")
	)
	(segment
		(start 87.57666 -100.821998)
		(end 87.57666 -100.478336)
		(width 0.0889)
		(layer "In4.Cu")
		(net "M_L_CKE<0>")
	)
	(segment
		(start 82.039968 -131.2926)
		(end 81.887568 -131.1402)
		(width 0.14224)
		(layer "In4.Cu")
		(net "M_L_CKE<0>")
	)
	(segment
		(start 82.014568 -130.5306)
		(end 82.014568 -129.9464)
		(width 0.14224)
		(layer "In4.Cu")
		(net "M_L_CKE<0>")
	)
	(segment
		(start 87.3379 -99.590606)
		(end 87.224616 -99.394518)
		(width 0.0889)
		(layer "In4.Cu")
		(net "M_L_CKE<0>")
	)
	(segment
		(start 81.987898 -136.14273)
		(end 82.099658 -136.03097)
		(width 0.14224)
		(layer "In4.Cu")
		(net "M_L_CKE<0>")
	)
	(segment
		(start 81.987898 -136.67867)
		(end 81.987898 -136.14273)
		(width 0.14224)
		(layer "In4.Cu")
		(net "M_L_CKE<0>")
	)
	(segment
		(start 87.57666 -121.031508)
		(end 87.57666 -100.821998)
		(width 0.14224)
		(layer "In4.Cu")
		(net "M_L_CKE<0>")
	)
	(segment
		(start 87.274908 -98.490024)
		(end 87.270082 -98.481388)
		(width 0.0889)
		(layer "In4.Cu")
		(net "M_L_CKE<0>")
	)
	(segment
		(start 81.023968 -139.6746)
		(end 81.114646 -139.583922)
		(width 0.14224)
		(layer "In4.Cu")
		(net "M_L_CKE<0>")
	)
	(segment
		(start 87.3379 -100.239576)
		(end 87.3379 -99.590606)
		(width 0.0889)
		(layer "In4.Cu")
		(net "M_L_CKE<0>")
	)
	(segment
		(start 87.57666 -100.478336)
		(end 87.3379 -100.239576)
		(width 0.0889)
		(layer "In4.Cu")
		(net "M_L_CKE<0>")
	)
	(segment
		(start 81.114646 -138.735054)
		(end 81.811368 -138.038332)
		(width 0.14224)
		(layer "In4.Cu")
		(net "M_L_CKE<0>")
	)
	(segment
		(start 81.887568 -130.6576)
		(end 82.014568 -130.5306)
		(width 0.14224)
		(layer "In4.Cu")
		(net "M_L_CKE<0>")
	)
	(segment
		(start 81.989168 -134.7978)
		(end 81.989168 -131.953)
		(width 0.14224)
		(layer "In4.Cu")
		(net "M_L_CKE<0>")
	)
	(segment
		(start 82.099658 -134.90829)
		(end 81.989168 -134.7978)
		(width 0.14224)
		(layer "In4.Cu")
		(net "M_L_CKE<0>")
	)
	(segment
		(start 81.912968 -129.8448)
		(end 81.912968 -126.6952)
		(width 0.14224)
		(layer "In4.Cu")
		(net "M_L_CKE<0>")
	)
	(segment
		(start 87.25281 -95.47987)
		(end 86.923372 -94.718886)
		(width 0.0889)
		(layer "In4.Cu")
		(net "M_L_CKE<0>")
	)
	(segment
		(start 87.274908 -97.499424)
		(end 87.270082 -97.490788)
		(width 0.0889)
		(layer "In4.Cu")
		(net "M_L_CKE<0>")
	)
	(segment
		(start 81.811368 -138.038332)
		(end 81.811368 -136.8552)
		(width 0.14224)
		(layer "In4.Cu")
		(net "M_L_CKE<0>")
	)
	(segment
		(start 82.039968 -131.9022)
		(end 82.039968 -131.2926)
		(width 0.14224)
		(layer "In4.Cu")
		(net "M_L_CKE<0>")
	)
	(segment
		(start 87.274908 -96.508824)
		(end 87.270082 -96.500188)
		(width 0.0889)
		(layer "In4.Cu")
		(net "M_L_CKE<0>")
	)
	(segment
		(start 87.270082 -97.490788)
		(end 87.263732 -97.48012)
		(width 0.0889)
		(layer "In4.Cu")
		(net "M_L_CKE<0>")
	)
	(segment
		(start 81.887568 -131.1402)
		(end 81.887568 -130.6576)
		(width 0.14224)
		(layer "In4.Cu")
		(net "M_L_CKE<0>")
	)
	(segment
		(start 87.270082 -98.481388)
		(end 87.263732 -98.47072)
		(width 0.0889)
		(layer "In4.Cu")
		(net "M_L_CKE<0>")
	)
	(segment
		(start 82.099658 -136.03097)
		(end 82.099658 -134.90829)
		(width 0.14224)
		(layer "In4.Cu")
		(net "M_L_CKE<0>")
	)
	(segment
		(start 81.811368 -136.8552)
		(end 81.987898 -136.67867)
		(width 0.14224)
		(layer "In4.Cu")
		(net "M_L_CKE<0>")
	)
	(segment
		(start 79.849472 -143.41856)
		(end 81.140554 -142.127478)
		(width 0.14224)
		(layer "In4.Cu")
		(net "M_L_CKE<0>")
	)
	(segment
		(start 82.014568 -129.9464)
		(end 81.912968 -129.8448)
		(width 0.14224)
		(layer "In4.Cu")
		(net "M_L_CKE<0>")
	)
	(segment
		(start 79.849472 -143.970756)
		(end 79.849472 -143.41856)
		(width 0.14224)
		(layer "In4.Cu")
		(net "M_L_CKE<0>")
	)
	(segment
		(start 81.140554 -142.127478)
		(end 81.140554 -140.477494)
		(width 0.14224)
		(layer "In4.Cu")
		(net "M_L_CKE<0>")
	)
	(segment
		(start 81.140554 -140.477494)
		(end 81.023968 -140.360908)
		(width 0.14224)
		(layer "In4.Cu")
		(net "M_L_CKE<0>")
	)
	(segment
		(start 81.023968 -140.360908)
		(end 81.023968 -139.6746)
		(width 0.14224)
		(layer "In4.Cu")
		(net "M_L_CKE<0>")
	)
	(segment
		(start 87.274908 -95.518224)
		(end 87.25281 -95.47987)
		(width 0.0889)
		(layer "In4.Cu")
		(net "M_L_CKE<0>")
	)
	(arc
		(start 87.228172 -99.382834)
		(mid 87.193055 -99.127441)
		(end 87.270082 -98.881438)
		(width 0.0889)
		(layer "In4.Cu")
		(net "M_L_CKE<0>")
	)
	(arc
		(start 87.270082 -97.890838)
		(mid 87.323552 -97.695775)
		(end 87.274908 -97.499424)
		(width 0.0889)
		(layer "In4.Cu")
		(net "M_L_CKE<0>")
	)
	(arc
		(start 87.270082 -96.900238)
		(mid 87.323552 -96.705175)
		(end 87.274908 -96.508824)
		(width 0.0889)
		(layer "In4.Cu")
		(net "M_L_CKE<0>")
	)
	(arc
		(start 87.270082 -98.881438)
		(mid 87.323552 -98.686375)
		(end 87.274908 -98.490024)
		(width 0.0889)
		(layer "In4.Cu")
		(net "M_L_CKE<0>")
	)
	(arc
		(start 87.263732 -97.48012)
		(mid 87.190934 -97.189357)
		(end 87.270082 -96.900238)
		(width 0.0889)
		(layer "In4.Cu")
		(net "M_L_CKE<0>")
	)
	(arc
		(start 87.263732 -98.47072)
		(mid 87.190934 -98.179957)
		(end 87.270082 -97.890838)
		(width 0.0889)
		(layer "In4.Cu")
		(net "M_L_CKE<0>")
	)
	(arc
		(start 87.263732 -96.48952)
		(mid 87.190934 -96.198757)
		(end 87.270082 -95.909638)
		(width 0.0889)
		(layer "In4.Cu")
		(net "M_L_CKE<0>")
	)
	(arc
		(start 87.224616 -99.394518)
		(mid 87.226365 -99.388667)
		(end 87.228172 -99.382834)
		(width 0.0889)
		(layer "In4.Cu")
		(net "M_L_CKE<0>")
	)
	(arc
		(start 87.270082 -95.909638)
		(mid 87.323552 -95.714575)
		(end 87.274908 -95.518224)
		(width 0.0889)
		(layer "In4.Cu")
		(net "M_L_CKE<0>")
	)
	(segment
		(start 111.299498 -147.27174)
		(end 111.299498 -145.988786)
		(width 0.10795)
		(layer "F.Cu")
		(net "M_L_C<2>")
	)
	(segment
		(start 111.299498 -145.988786)
		(end 111.300006 -145.988278)
		(width 0.10795)
		(layer "F.Cu")
		(net "M_L_C<2>")
	)
	(segment
		(start 101.230684 -96.700086)
		(end 100.659184 -96.700086)
		(width 0.1016)
		(layer "F.Cu")
		(net "M_L_C<2>")
	)
	(via
		(at 111.300006 -145.988278)
		(size 0.4572)
		(drill 0.2032)
		(layers "F.Cu" "B.Cu")
		(net "M_L_C<2>")
	)
	(via
		(at 111.300006 -139.172188)
		(size 0.4572)
		(drill 0.2032)
		(layers "F.Cu" "B.Cu")
		(net "M_L_C<2>")
	)
	(via
		(at 100.659184 -96.700086)
		(size 0.508)
		(drill 0.254)
		(layers "F.Cu" "B.Cu")
		(net "M_L_C<2>")
	)
	(segment
		(start 111.299498 -137.877296)
		(end 111.299498 -139.17168)
		(width 0.1651)
		(layer "B.Cu")
		(net "M_L_C<2>")
	)
	(segment
		(start 111.299498 -139.17168)
		(end 111.300006 -139.172188)
		(width 0.1651)
		(layer "B.Cu")
		(net "M_L_C<2>")
	)
	(segment
		(start 110.890812 -144.24914)
		(end 111.299498 -144.657826)
		(width 0.14224)
		(layer "In11.Cu")
		(net "M_L_C<2>")
	)
	(segment
		(start 110.081568 -129.7686)
		(end 109.972856 -129.877312)
		(width 0.14224)
		(layer "In11.Cu")
		(net "M_L_C<2>")
	)
	(segment
		(start 101.115368 -98.5266)
		(end 101.115368 -99.4664)
		(width 0.0889)
		(layer "In11.Cu")
		(net "M_L_C<2>")
	)
	(segment
		(start 110.081568 -127.42418)
		(end 110.081568 -129.7686)
		(width 0.14224)
		(layer "In11.Cu")
		(net "M_L_C<2>")
	)
	(segment
		(start 109.674152 -135.692896)
		(end 110.039912 -136.058656)
		(width 0.14224)
		(layer "In11.Cu")
		(net "M_L_C<2>")
	)
	(segment
		(start 110.081314 -130.631946)
		(end 110.081314 -131.089654)
		(width 0.14224)
		(layer "In11.Cu")
		(net "M_L_C<2>")
	)
	(segment
		(start 102.791768 -102.4636)
		(end 103.147368 -102.8192)
		(width 0.14224)
		(layer "In11.Cu")
		(net "M_L_C<2>")
	)
	(segment
		(start 109.972856 -129.877312)
		(end 109.972856 -130.523488)
		(width 0.14224)
		(layer "In11.Cu")
		(net "M_L_C<2>")
	)
	(segment
		(start 101.115368 -100.0506)
		(end 102.283768 -101.219)
		(width 0.14224)
		(layer "In11.Cu")
		(net "M_L_C<2>")
	)
	(segment
		(start 110.890812 -140.918184)
		(end 110.890812 -142.36065)
		(width 0.14224)
		(layer "In11.Cu")
		(net "M_L_C<2>")
	)
	(segment
		(start 111.299498 -144.657826)
		(end 111.299498 -145.98777)
		(width 0.14224)
		(layer "In11.Cu")
		(net "M_L_C<2>")
	)
	(segment
		(start 109.069124 -126.411482)
		(end 109.069124 -126.411736)
		(width 0.14224)
		(layer "In11.Cu")
		(net "M_L_C<2>")
	)
	(segment
		(start 103.147368 -102.8192)
		(end 103.147368 -120.489726)
		(width 0.14224)
		(layer "In11.Cu")
		(net "M_L_C<2>")
	)
	(segment
		(start 110.081314 -131.089654)
		(end 109.990128 -131.18084)
		(width 0.14224)
		(layer "In11.Cu")
		(net "M_L_C<2>")
	)
	(segment
		(start 100.312474 -97.89033)
		(end 100.368862 -97.98812)
		(width 0.0889)
		(layer "In11.Cu")
		(net "M_L_C<2>")
	)
	(segment
		(start 110.036356 -131.882388)
		(end 110.036356 -134.690612)
		(width 0.14224)
		(layer "In11.Cu")
		(net "M_L_C<2>")
	)
	(segment
		(start 100.659184 -96.700086)
		(end 100.328984 -97.462086)
		(width 0.0889)
		(layer "In11.Cu")
		(net "M_L_C<2>")
	)
	(segment
		(start 111.300006 -138.727688)
		(end 111.300006 -139.172188)
		(width 0.14224)
		(layer "In11.Cu")
		(net "M_L_C<2>")
	)
	(segment
		(start 101.115368 -99.4664)
		(end 101.115368 -100.0506)
		(width 0.14224)
		(layer "In11.Cu")
		(net "M_L_C<2>")
	)
	(segment
		(start 110.039912 -136.058656)
		(end 110.039912 -137.467594)
		(width 0.14224)
		(layer "In11.Cu")
		(net "M_L_C<2>")
	)
	(segment
		(start 103.147368 -120.489726)
		(end 109.069124 -126.411482)
		(width 0.14224)
		(layer "In11.Cu")
		(net "M_L_C<2>")
	)
	(segment
		(start 100.328984 -97.462086)
		(end 100.312474 -97.490534)
		(width 0.0889)
		(layer "In11.Cu")
		(net "M_L_C<2>")
	)
	(segment
		(start 102.791768 -101.4984)
		(end 102.791768 -102.4636)
		(width 0.14224)
		(layer "In11.Cu")
		(net "M_L_C<2>")
	)
	(segment
		(start 109.972856 -130.523488)
		(end 110.081314 -130.631946)
		(width 0.14224)
		(layer "In11.Cu")
		(net "M_L_C<2>")
	)
	(segment
		(start 109.674152 -135.052816)
		(end 109.674152 -135.692896)
		(width 0.14224)
		(layer "In11.Cu")
		(net "M_L_C<2>")
	)
	(segment
		(start 102.512368 -101.219)
		(end 102.791768 -101.4984)
		(width 0.14224)
		(layer "In11.Cu")
		(net "M_L_C<2>")
	)
	(segment
		(start 111.300006 -139.172188)
		(end 111.299498 -139.172696)
		(width 0.14224)
		(layer "In11.Cu")
		(net "M_L_C<2>")
	)
	(segment
		(start 109.069124 -126.411736)
		(end 110.081568 -127.42418)
		(width 0.14224)
		(layer "In11.Cu")
		(net "M_L_C<2>")
	)
	(segment
		(start 111.299498 -139.172696)
		(end 111.299498 -140.509498)
		(width 0.14224)
		(layer "In11.Cu")
		(net "M_L_C<2>")
	)
	(segment
		(start 110.039912 -137.467594)
		(end 111.300006 -138.727688)
		(width 0.14224)
		(layer "In11.Cu")
		(net "M_L_C<2>")
	)
	(segment
		(start 109.990128 -131.83616)
		(end 110.036356 -131.882388)
		(width 0.14224)
		(layer "In11.Cu")
		(net "M_L_C<2>")
	)
	(segment
		(start 109.990128 -131.18084)
		(end 109.990128 -131.83616)
		(width 0.14224)
		(layer "In11.Cu")
		(net "M_L_C<2>")
	)
	(segment
		(start 102.283768 -101.219)
		(end 102.512368 -101.219)
		(width 0.14224)
		(layer "In11.Cu")
		(net "M_L_C<2>")
	)
	(segment
		(start 111.299498 -145.98777)
		(end 111.300006 -145.988278)
		(width 0.14224)
		(layer "In11.Cu")
		(net "M_L_C<2>")
	)
	(segment
		(start 110.890812 -143.680942)
		(end 110.890812 -144.24914)
		(width 0.14224)
		(layer "In11.Cu")
		(net "M_L_C<2>")
	)
	(segment
		(start 111.104934 -143.46682)
		(end 110.890812 -143.680942)
		(width 0.14224)
		(layer "In11.Cu")
		(net "M_L_C<2>")
	)
	(segment
		(start 110.890812 -142.36065)
		(end 111.104934 -142.574772)
		(width 0.14224)
		(layer "In11.Cu")
		(net "M_L_C<2>")
	)
	(segment
		(start 111.299498 -140.509498)
		(end 110.890812 -140.918184)
		(width 0.14224)
		(layer "In11.Cu")
		(net "M_L_C<2>")
	)
	(segment
		(start 110.036356 -134.690612)
		(end 109.674152 -135.052816)
		(width 0.14224)
		(layer "In11.Cu")
		(net "M_L_C<2>")
	)
	(segment
		(start 111.104934 -142.574772)
		(end 111.104934 -143.46682)
		(width 0.14224)
		(layer "In11.Cu")
		(net "M_L_C<2>")
	)
	(arc
		(start 100.368862 -97.98812)
		(mid 100.576972 -98.19641)
		(end 100.861368 -98.2726)
		(width 0.0889)
		(layer "In11.Cu")
		(net "M_L_C<2>")
	)
	(arc
		(start 100.312474 -97.490534)
		(mid 100.258975 -97.690432)
		(end 100.312474 -97.89033)
		(width 0.0889)
		(layer "In11.Cu")
		(net "M_L_C<2>")
	)
	(arc
		(start 100.861368 -98.2726)
		(mid 101.040973 -98.346995)
		(end 101.115368 -98.5266)
		(width 0.0889)
		(layer "In11.Cu")
		(net "M_L_C<2>")
	)
	(segment
		(start 89.211912 -94.718886)
		(end 88.640412 -94.718886)
		(width 0.1016)
		(layer "F.Cu")
		(net "M_L_BG<1>")
	)
	(segment
		(start 82.399378 -145.988278)
		(end 82.399378 -147.27174)
		(width 0.1651)
		(layer "F.Cu")
		(net "M_L_BG<1>")
	)
	(via
		(at 82.399378 -145.988278)
		(size 0.4572)
		(drill 0.2032)
		(layers "F.Cu" "B.Cu")
		(net "M_L_BG<1>")
	)
	(via
		(at 88.640412 -94.718886)
		(size 0.508)
		(drill 0.254)
		(layers "F.Cu" "B.Cu")
		(net "M_L_BG<1>")
	)
	(via
		(at 82.399378 -139.170156)
		(size 0.4572)
		(drill 0.2032)
		(layers "F.Cu" "B.Cu")
		(net "M_L_BG<1>")
	)
	(segment
		(start 82.399378 -139.170156)
		(end 82.399378 -137.877296)
		(width 0.1651)
		(layer "B.Cu")
		(net "M_L_BG<1>")
	)
	(segment
		(start 86.281768 -129.8194)
		(end 86.180168 -129.921)
		(width 0.14224)
		(layer "In11.Cu")
		(net "M_L_BG<1>")
	)
	(segment
		(start 89.641172 -100.858574)
		(end 89.641172 -103.023924)
		(width 0.0889)
		(layer "In11.Cu")
		(net "M_L_BG<1>")
	)
	(segment
		(start 89.802716 -103.586534)
		(end 89.802716 -123.377452)
		(width 0.14224)
		(layer "In11.Cu")
		(net "M_L_BG<1>")
	)
	(segment
		(start 82.812636 -144.286732)
		(end 82.399378 -144.69999)
		(width 0.14224)
		(layer "In11.Cu")
		(net "M_L_BG<1>")
	)
	(segment
		(start 84.587334 -136.9822)
		(end 82.399378 -139.170156)
		(width 0.14224)
		(layer "In11.Cu")
		(net "M_L_BG<1>")
	)
	(segment
		(start 83.01863 -143.137128)
		(end 82.812636 -143.343122)
		(width 0.14224)
		(layer "In11.Cu")
		(net "M_L_BG<1>")
	)
	(segment
		(start 86.103968 -131.7498)
		(end 86.238334 -131.884166)
		(width 0.14224)
		(layer "In11.Cu")
		(net "M_L_BG<1>")
	)
	(segment
		(start 85.372702 -136.589262)
		(end 84.979764 -136.9822)
		(width 0.14224)
		(layer "In11.Cu")
		(net "M_L_BG<1>")
	)
	(segment
		(start 89.056972 -100.274374)
		(end 89.641172 -100.858574)
		(width 0.0889)
		(layer "In11.Cu")
		(net "M_L_BG<1>")
	)
	(segment
		(start 83.01863 -141.841982)
		(end 83.01863 -143.137128)
		(width 0.14224)
		(layer "In11.Cu")
		(net "M_L_BG<1>")
	)
	(segment
		(start 85.372702 -135.996934)
		(end 85.372702 -136.589262)
		(width 0.14224)
		(layer "In11.Cu")
		(net "M_L_BG<1>")
	)
	(segment
		(start 86.967568 -128.3462)
		(end 86.281768 -129.032)
		(width 0.14224)
		(layer "In11.Cu")
		(net "M_L_BG<1>")
	)
	(segment
		(start 86.103968 -131.3942)
		(end 86.103968 -131.7498)
		(width 0.14224)
		(layer "In11.Cu")
		(net "M_L_BG<1>")
	)
	(segment
		(start 88.977978 -98.466148)
		(end 88.986868 -98.481388)
		(width 0.0889)
		(layer "In11.Cu")
		(net "M_L_BG<1>")
	)
	(segment
		(start 86.238334 -131.884166)
		(end 86.238334 -134.587234)
		(width 0.14224)
		(layer "In11.Cu")
		(net "M_L_BG<1>")
	)
	(segment
		(start 86.180168 -129.921)
		(end 86.180168 -130.5306)
		(width 0.14224)
		(layer "In11.Cu")
		(net "M_L_BG<1>")
	)
	(segment
		(start 88.640412 -94.718886)
		(end 88.66505 -94.743524)
		(width 0.0889)
		(layer "In11.Cu")
		(net "M_L_BG<1>")
	)
	(segment
		(start 86.332568 -131.1656)
		(end 86.103968 -131.3942)
		(width 0.14224)
		(layer "In11.Cu")
		(net "M_L_BG<1>")
	)
	(segment
		(start 82.399378 -139.170156)
		(end 82.399378 -140.341096)
		(width 0.14224)
		(layer "In11.Cu")
		(net "M_L_BG<1>")
	)
	(segment
		(start 82.399378 -140.341096)
		(end 82.812636 -140.754354)
		(width 0.14224)
		(layer "In11.Cu")
		(net "M_L_BG<1>")
	)
	(segment
		(start 85.633814 -135.735822)
		(end 85.372702 -135.996934)
		(width 0.14224)
		(layer "In11.Cu")
		(net "M_L_BG<1>")
	)
	(segment
		(start 88.977978 -95.494348)
		(end 88.986868 -95.509588)
		(width 0.0889)
		(layer "In11.Cu")
		(net "M_L_BG<1>")
	)
	(segment
		(start 89.802716 -123.377452)
		(end 86.967568 -126.2126)
		(width 0.14224)
		(layer "In11.Cu")
		(net "M_L_BG<1>")
	)
	(segment
		(start 82.812636 -143.343122)
		(end 82.812636 -144.286732)
		(width 0.14224)
		(layer "In11.Cu")
		(net "M_L_BG<1>")
	)
	(segment
		(start 82.812636 -141.635988)
		(end 83.01863 -141.841982)
		(width 0.14224)
		(layer "In11.Cu")
		(net "M_L_BG<1>")
	)
	(segment
		(start 82.812636 -140.754354)
		(end 82.812636 -141.635988)
		(width 0.14224)
		(layer "In11.Cu")
		(net "M_L_BG<1>")
	)
	(segment
		(start 88.977978 -97.475548)
		(end 88.986868 -97.490788)
		(width 0.0889)
		(layer "In11.Cu")
		(net "M_L_BG<1>")
	)
	(segment
		(start 84.979764 -136.9822)
		(end 84.587334 -136.9822)
		(width 0.14224)
		(layer "In11.Cu")
		(net "M_L_BG<1>")
	)
	(segment
		(start 86.180168 -130.5306)
		(end 86.332568 -130.683)
		(width 0.14224)
		(layer "In11.Cu")
		(net "M_L_BG<1>")
	)
	(segment
		(start 86.967568 -126.2126)
		(end 86.967568 -128.3462)
		(width 0.14224)
		(layer "In11.Cu")
		(net "M_L_BG<1>")
	)
	(segment
		(start 89.056972 -98.95332)
		(end 89.056972 -100.274374)
		(width 0.0889)
		(layer "In11.Cu")
		(net "M_L_BG<1>")
	)
	(segment
		(start 86.281768 -129.032)
		(end 86.281768 -129.8194)
		(width 0.14224)
		(layer "In11.Cu")
		(net "M_L_BG<1>")
	)
	(segment
		(start 86.238334 -134.587234)
		(end 85.633814 -135.191754)
		(width 0.14224)
		(layer "In11.Cu")
		(net "M_L_BG<1>")
	)
	(segment
		(start 88.977978 -96.484948)
		(end 88.986868 -96.500188)
		(width 0.0889)
		(layer "In11.Cu")
		(net "M_L_BG<1>")
	)
	(segment
		(start 86.332568 -130.683)
		(end 86.332568 -131.1656)
		(width 0.14224)
		(layer "In11.Cu")
		(net "M_L_BG<1>")
	)
	(segment
		(start 89.802716 -103.185468)
		(end 89.802716 -103.586534)
		(width 0.0889)
		(layer "In11.Cu")
		(net "M_L_BG<1>")
	)
	(segment
		(start 89.641172 -103.023924)
		(end 89.802716 -103.185468)
		(width 0.0889)
		(layer "In11.Cu")
		(net "M_L_BG<1>")
	)
	(segment
		(start 85.633814 -135.191754)
		(end 85.633814 -135.735822)
		(width 0.14224)
		(layer "In11.Cu")
		(net "M_L_BG<1>")
	)
	(segment
		(start 82.399378 -144.69999)
		(end 82.399378 -145.988278)
		(width 0.14224)
		(layer "In11.Cu")
		(net "M_L_BG<1>")
	)
	(arc
		(start 88.986868 -95.909384)
		(mid 88.907679 -96.195999)
		(end 88.977978 -96.484948)
		(width 0.0889)
		(layer "In11.Cu")
		(net "M_L_BG<1>")
	)
	(arc
		(start 88.93937 -95.405702)
		(mid 88.956868 -95.450811)
		(end 88.977978 -95.494348)
		(width 0.0889)
		(layer "In11.Cu")
		(net "M_L_BG<1>")
	)
	(arc
		(start 88.986868 -95.509588)
		(mid 89.040401 -95.709486)
		(end 88.986868 -95.909384)
		(width 0.0889)
		(layer "In11.Cu")
		(net "M_L_BG<1>")
	)
	(arc
		(start 88.986868 -97.890584)
		(mid 88.907679 -98.177199)
		(end 88.977978 -98.466148)
		(width 0.0889)
		(layer "In11.Cu")
		(net "M_L_BG<1>")
	)
	(arc
		(start 88.986868 -96.899984)
		(mid 88.907679 -97.186599)
		(end 88.977978 -97.475548)
		(width 0.0889)
		(layer "In11.Cu")
		(net "M_L_BG<1>")
	)
	(arc
		(start 88.986868 -96.500188)
		(mid 89.040401 -96.700086)
		(end 88.986868 -96.899984)
		(width 0.0889)
		(layer "In11.Cu")
		(net "M_L_BG<1>")
	)
	(arc
		(start 88.986868 -98.481388)
		(mid 89.067379 -98.710603)
		(end 89.056972 -98.95332)
		(width 0.0889)
		(layer "In11.Cu")
		(net "M_L_BG<1>")
	)
	(arc
		(start 88.66505 -94.743524)
		(mid 88.868049 -95.047334)
		(end 88.93937 -95.405702)
		(width 0.0889)
		(layer "In11.Cu")
		(net "M_L_BG<1>")
	)
	(arc
		(start 88.986868 -97.490788)
		(mid 89.040401 -97.690686)
		(end 88.986868 -97.890584)
		(width 0.0889)
		(layer "In11.Cu")
		(net "M_L_BG<1>")
	)
	(segment
		(start 88.353392 -93.23324)
		(end 87.781892 -93.23324)
		(width 0.1016)
		(layer "F.Cu")
		(net "M_L_BG<0>")
	)
	(segment
		(start 82.399378 -142.6718)
		(end 82.399378 -143.970756)
		(width 0.1651)
		(layer "F.Cu")
		(net "M_L_BG<0>")
	)
	(via
		(at 82.399378 -143.970756)
		(size 0.4572)
		(drill 0.2032)
		(layers "F.Cu" "B.Cu")
		(net "M_L_BG<0>")
	)
	(via
		(at 82.399378 -141.187678)
		(size 0.4572)
		(drill 0.2032)
		(layers "F.Cu" "B.Cu")
		(net "M_L_BG<0>")
	)
	(via
		(at 87.781892 -93.23324)
		(size 0.508)
		(drill 0.254)
		(layers "F.Cu" "B.Cu")
		(net "M_L_BG<0>")
	)
	(segment
		(start 82.399378 -142.477236)
		(end 82.399378 -141.187678)
		(width 0.1651)
		(layer "B.Cu")
		(net "M_L_BG<0>")
	)
	(segment
		(start 82.674968 -140.72362)
		(end 82.399378 -140.99921)
		(width 0.14224)
		(layer "In4.Cu")
		(net "M_L_BG<0>")
	)
	(segment
		(start 88.133428 -97.386902)
		(end 88.128602 -97.395538)
		(width 0.0889)
		(layer "In4.Cu")
		(net "M_L_BG<0>")
	)
	(segment
		(start 82.399378 -140.99921)
		(end 82.399378 -141.187678)
		(width 0.14224)
		(layer "In4.Cu")
		(net "M_L_BG<0>")
	)
	(segment
		(start 83.689444 -131.878324)
		(end 83.689444 -134.718552)
		(width 0.14224)
		(layer "In4.Cu")
		(net "M_L_BG<0>")
	)
	(segment
		(start 83.689444 -134.718552)
		(end 83.663282 -134.744714)
		(width 0.14224)
		(layer "In4.Cu")
		(net "M_L_BG<0>")
	)
	(segment
		(start 83.741768 -130.5814)
		(end 83.589368 -130.7338)
		(width 0.14224)
		(layer "In4.Cu")
		(net "M_L_BG<0>")
	)
	(segment
		(start 84.300568 -126.864872)
		(end 84.300568 -128.721104)
		(width 0.14224)
		(layer "In4.Cu")
		(net "M_L_BG<0>")
	)
	(segment
		(start 83.663282 -138.051286)
		(end 82.827368 -138.8872)
		(width 0.14224)
		(layer "In4.Cu")
		(net "M_L_BG<0>")
	)
	(segment
		(start 88.128602 -99.376738)
		(end 88.008968 -99.584256)
		(width 0.0889)
		(layer "In4.Cu")
		(net "M_L_BG<0>")
	)
	(segment
		(start 88.181688 -94.222062)
		(end 88.181688 -97.178368)
		(width 0.0889)
		(layer "In4.Cu")
		(net "M_L_BG<0>")
	)
	(segment
		(start 88.111584 -93.994478)
		(end 88.128602 -94.023688)
		(width 0.0889)
		(layer "In4.Cu")
		(net "M_L_BG<0>")
	)
	(segment
		(start 83.589368 -130.7338)
		(end 83.589368 -131.1656)
		(width 0.14224)
		(layer "In4.Cu")
		(net "M_L_BG<0>")
	)
	(segment
		(start 87.781892 -93.23324)
		(end 88.111584 -93.994478)
		(width 0.0889)
		(layer "In4.Cu")
		(net "M_L_BG<0>")
	)
	(segment
		(start 88.008968 -99.9998)
		(end 88.59266 -100.583492)
		(width 0.0889)
		(layer "In4.Cu")
		(net "M_L_BG<0>")
	)
	(segment
		(start 88.128602 -97.395538)
		(end 88.122252 -97.406206)
		(width 0.0889)
		(layer "In4.Cu")
		(net "M_L_BG<0>")
	)
	(segment
		(start 88.59266 -122.57278)
		(end 84.300568 -126.864872)
		(width 0.14224)
		(layer "In4.Cu")
		(net "M_L_BG<0>")
	)
	(segment
		(start 88.133428 -98.377502)
		(end 88.128602 -98.386138)
		(width 0.0889)
		(layer "In4.Cu")
		(net "M_L_BG<0>")
	)
	(segment
		(start 82.827368 -138.8872)
		(end 82.827368 -139.4206)
		(width 0.14224)
		(layer "In4.Cu")
		(net "M_L_BG<0>")
	)
	(segment
		(start 83.741768 -129.921)
		(end 83.741768 -130.5814)
		(width 0.14224)
		(layer "In4.Cu")
		(net "M_L_BG<0>")
	)
	(segment
		(start 83.589368 -129.7686)
		(end 83.741768 -129.921)
		(width 0.14224)
		(layer "In4.Cu")
		(net "M_L_BG<0>")
	)
	(segment
		(start 88.008968 -99.584256)
		(end 88.008968 -99.9998)
		(width 0.0889)
		(layer "In4.Cu")
		(net "M_L_BG<0>")
	)
	(segment
		(start 88.59266 -100.93071)
		(end 88.59266 -122.57278)
		(width 0.14224)
		(layer "In4.Cu")
		(net "M_L_BG<0>")
	)
	(segment
		(start 82.399378 -141.187678)
		(end 82.399378 -143.970756)
		(width 0.14224)
		(layer "In4.Cu")
		(net "M_L_BG<0>")
	)
	(segment
		(start 83.589368 -131.1656)
		(end 83.767168 -131.3434)
		(width 0.14224)
		(layer "In4.Cu")
		(net "M_L_BG<0>")
	)
	(segment
		(start 83.589368 -129.432304)
		(end 83.589368 -129.7686)
		(width 0.14224)
		(layer "In4.Cu")
		(net "M_L_BG<0>")
	)
	(segment
		(start 83.767168 -131.8006)
		(end 83.689444 -131.878324)
		(width 0.14224)
		(layer "In4.Cu")
		(net "M_L_BG<0>")
	)
	(segment
		(start 82.827368 -139.4206)
		(end 82.674968 -139.573)
		(width 0.14224)
		(layer "In4.Cu")
		(net "M_L_BG<0>")
	)
	(segment
		(start 83.663282 -134.744714)
		(end 83.663282 -138.051286)
		(width 0.14224)
		(layer "In4.Cu")
		(net "M_L_BG<0>")
	)
	(segment
		(start 83.767168 -131.3434)
		(end 83.767168 -131.8006)
		(width 0.14224)
		(layer "In4.Cu")
		(net "M_L_BG<0>")
	)
	(segment
		(start 88.59266 -100.583492)
		(end 88.59266 -100.93071)
		(width 0.0889)
		(layer "In4.Cu")
		(net "M_L_BG<0>")
	)
	(segment
		(start 84.300568 -128.721104)
		(end 83.589368 -129.432304)
		(width 0.14224)
		(layer "In4.Cu")
		(net "M_L_BG<0>")
	)
	(segment
		(start 82.674968 -139.573)
		(end 82.674968 -140.72362)
		(width 0.14224)
		(layer "In4.Cu")
		(net "M_L_BG<0>")
	)
	(arc
		(start 88.181688 -97.178368)
		(mid 88.171745 -97.285916)
		(end 88.133428 -97.386902)
		(width 0.0889)
		(layer "In4.Cu")
		(net "M_L_BG<0>")
	)
	(arc
		(start 88.122252 -97.406206)
		(mid 88.049454 -97.696969)
		(end 88.128602 -97.986088)
		(width 0.0889)
		(layer "In4.Cu")
		(net "M_L_BG<0>")
	)
	(arc
		(start 88.128602 -98.976942)
		(mid 88.182101 -99.17684)
		(end 88.128602 -99.376738)
		(width 0.0889)
		(layer "In4.Cu")
		(net "M_L_BG<0>")
	)
	(arc
		(start 88.128602 -97.986088)
		(mid 88.182072 -98.181151)
		(end 88.133428 -98.377502)
		(width 0.0889)
		(layer "In4.Cu")
		(net "M_L_BG<0>")
	)
	(arc
		(start 88.128602 -98.386138)
		(mid 88.049471 -98.68154)
		(end 88.128602 -98.976942)
		(width 0.0889)
		(layer "In4.Cu")
		(net "M_L_BG<0>")
	)
	(arc
		(start 88.128602 -94.023688)
		(mid 88.168205 -94.119382)
		(end 88.181688 -94.222062)
		(width 0.0889)
		(layer "In4.Cu")
		(net "M_L_BG<0>")
	)
	(segment
		(start 94.362778 -97.690686)
		(end 93.791278 -97.690686)
		(width 0.1016)
		(layer "F.Cu")
		(net "M_L_BA<1>")
	)
	(segment
		(start 101.949504 -147.27174)
		(end 101.949504 -145.988532)
		(width 0.1651)
		(layer "F.Cu")
		(net "M_L_BA<1>")
	)
	(segment
		(start 101.949504 -145.988532)
		(end 101.949758 -145.988278)
		(width 0.1651)
		(layer "F.Cu")
		(net "M_L_BA<1>")
	)
	(via
		(at 101.949504 -139.172188)
		(size 0.4572)
		(drill 0.2032)
		(layers "F.Cu" "B.Cu")
		(net "M_L_BA<1>")
	)
	(via
		(at 101.949758 -145.988278)
		(size 0.4572)
		(drill 0.2032)
		(layers "F.Cu" "B.Cu")
		(net "M_L_BA<1>")
	)
	(via
		(at 93.791278 -97.690686)
		(size 0.508)
		(drill 0.254)
		(layers "F.Cu" "B.Cu")
		(net "M_L_BA<1>")
	)
	(segment
		(start 101.949504 -137.877296)
		(end 101.949504 -139.172188)
		(width 0.1651)
		(layer "B.Cu")
		(net "M_L_BA<1>")
	)
	(segment
		(start 99.119436 -137.603738)
		(end 99.420426 -137.904728)
		(width 0.14224)
		(layer "In11.Cu")
		(net "M_L_BA<1>")
	)
	(segment
		(start 94.120716 -98.45167)
		(end 94.142814 -98.490024)
		(width 0.0889)
		(layer "In11.Cu")
		(net "M_L_BA<1>")
	)
	(segment
		(start 96.949768 -135.9408)
		(end 98.612706 -137.603738)
		(width 0.14224)
		(layer "In11.Cu")
		(net "M_L_BA<1>")
	)
	(segment
		(start 96.492568 -102.108)
		(end 96.492568 -102.784148)
		(width 0.0889)
		(layer "In11.Cu")
		(net "M_L_BA<1>")
	)
	(segment
		(start 96.000316 -125.796548)
		(end 96.949768 -126.746)
		(width 0.14224)
		(layer "In11.Cu")
		(net "M_L_BA<1>")
	)
	(segment
		(start 101.949504 -139.861036)
		(end 101.512624 -140.297916)
		(width 0.14224)
		(layer "In11.Cu")
		(net "M_L_BA<1>")
	)
	(segment
		(start 101.949758 -144.84604)
		(end 101.949758 -145.988278)
		(width 0.14224)
		(layer "In11.Cu")
		(net "M_L_BA<1>")
	)
	(segment
		(start 98.612706 -137.603738)
		(end 99.119436 -137.603738)
		(width 0.14224)
		(layer "In11.Cu")
		(net "M_L_BA<1>")
	)
	(segment
		(start 101.389434 -138.612118)
		(end 101.949504 -139.172188)
		(width 0.14224)
		(layer "In11.Cu")
		(net "M_L_BA<1>")
	)
	(segment
		(start 99.704906 -138.612118)
		(end 101.389434 -138.612118)
		(width 0.14224)
		(layer "In11.Cu")
		(net "M_L_BA<1>")
	)
	(segment
		(start 94.206568 -99.822)
		(end 96.492568 -102.108)
		(width 0.0889)
		(layer "In11.Cu")
		(net "M_L_BA<1>")
	)
	(segment
		(start 101.512624 -140.297916)
		(end 101.512624 -142.556484)
		(width 0.14224)
		(layer "In11.Cu")
		(net "M_L_BA<1>")
	)
	(segment
		(start 101.512624 -142.556484)
		(end 101.53523 -142.57909)
		(width 0.14224)
		(layer "In11.Cu")
		(net "M_L_BA<1>")
	)
	(segment
		(start 101.53523 -142.57909)
		(end 101.53523 -144.431512)
		(width 0.14224)
		(layer "In11.Cu")
		(net "M_L_BA<1>")
	)
	(segment
		(start 96.949768 -126.746)
		(end 96.949768 -135.9408)
		(width 0.14224)
		(layer "In11.Cu")
		(net "M_L_BA<1>")
	)
	(segment
		(start 101.949504 -139.172188)
		(end 101.949504 -139.861036)
		(width 0.14224)
		(layer "In11.Cu")
		(net "M_L_BA<1>")
	)
	(segment
		(start 93.791278 -97.690686)
		(end 94.120716 -98.45167)
		(width 0.0889)
		(layer "In11.Cu")
		(net "M_L_BA<1>")
	)
	(segment
		(start 94.206568 -99.7458)
		(end 94.206568 -99.822)
		(width 0.0889)
		(layer "In11.Cu")
		(net "M_L_BA<1>")
	)
	(segment
		(start 96.000316 -103.2764)
		(end 96.000316 -104.353614)
		(width 0.0889)
		(layer "In11.Cu")
		(net "M_L_BA<1>")
	)
	(segment
		(start 99.420426 -138.327638)
		(end 99.704906 -138.612118)
		(width 0.14224)
		(layer "In11.Cu")
		(net "M_L_BA<1>")
	)
	(segment
		(start 96.000316 -104.353614)
		(end 96.000316 -125.796548)
		(width 0.14224)
		(layer "In11.Cu")
		(net "M_L_BA<1>")
	)
	(segment
		(start 99.420426 -137.904728)
		(end 99.420426 -138.327638)
		(width 0.14224)
		(layer "In11.Cu")
		(net "M_L_BA<1>")
	)
	(segment
		(start 96.492568 -102.784148)
		(end 96.000316 -103.2764)
		(width 0.0889)
		(layer "In11.Cu")
		(net "M_L_BA<1>")
	)
	(segment
		(start 101.53523 -144.431512)
		(end 101.949758 -144.84604)
		(width 0.14224)
		(layer "In11.Cu")
		(net "M_L_BA<1>")
	)
	(arc
		(start 94.137988 -99.472242)
		(mid 94.191415 -99.604225)
		(end 94.206568 -99.7458)
		(width 0.0889)
		(layer "In11.Cu")
		(net "M_L_BA<1>")
	)
	(arc
		(start 94.137988 -98.881438)
		(mid 94.058857 -99.17684)
		(end 94.137988 -99.472242)
		(width 0.0889)
		(layer "In11.Cu")
		(net "M_L_BA<1>")
	)
	(arc
		(start 94.142814 -98.490024)
		(mid 94.191569 -98.686376)
		(end 94.137988 -98.881438)
		(width 0.0889)
		(layer "In11.Cu")
		(net "M_L_BA<1>")
	)
	(segment
		(start 96.079818 -94.718886)
		(end 95.508318 -94.718886)
		(width 0.1016)
		(layer "F.Cu")
		(net "M_L_BA<0>")
	)
	(segment
		(start 102.799388 -143.972534)
		(end 102.799642 -143.972788)
		(width 0.1651)
		(layer "F.Cu")
		(net "M_L_BA<0>")
	)
	(segment
		(start 102.799388 -142.6718)
		(end 102.799388 -143.972534)
		(width 0.1651)
		(layer "F.Cu")
		(net "M_L_BA<0>")
	)
	(via
		(at 102.799642 -141.187678)
		(size 0.4572)
		(drill 0.2032)
		(layers "F.Cu" "B.Cu")
		(net "M_L_BA<0>")
	)
	(via
		(at 95.508318 -94.718886)
		(size 0.508)
		(drill 0.254)
		(layers "F.Cu" "B.Cu")
		(net "M_L_BA<0>")
	)
	(via
		(at 102.799642 -143.972788)
		(size 0.4572)
		(drill 0.2032)
		(layers "F.Cu" "B.Cu")
		(net "M_L_BA<0>")
	)
	(segment
		(start 102.799388 -142.477236)
		(end 102.799388 -141.187932)
		(width 0.1651)
		(layer "B.Cu")
		(net "M_L_BA<0>")
	)
	(segment
		(start 102.799388 -141.187932)
		(end 102.799642 -141.187678)
		(width 0.1651)
		(layer "B.Cu")
		(net "M_L_BA<0>")
	)
	(segment
		(start 98.092768 -124.12218)
		(end 98.092768 -103.311198)
		(width 0.14224)
		(layer "In4.Cu")
		(net "M_L_BA<0>")
	)
	(segment
		(start 100.99548 -127.024892)
		(end 98.092768 -124.12218)
		(width 0.14224)
		(layer "In4.Cu")
		(net "M_L_BA<0>")
	)
	(segment
		(start 96.707198 -97.406206)
		(end 96.713548 -97.395538)
		(width 0.0889)
		(layer "In4.Cu")
		(net "M_L_BA<0>")
	)
	(segment
		(start 101.470968 -131.9022)
		(end 101.470968 -131.2926)
		(width 0.14224)
		(layer "In4.Cu")
		(net "M_L_BA<0>")
	)
	(segment
		(start 96.381824 -95.80499)
		(end 96.349058 -95.80499)
		(width 0.0889)
		(layer "In4.Cu")
		(net "M_L_BA<0>")
	)
	(segment
		(start 101.470968 -130.4798)
		(end 101.470968 -129.9718)
		(width 0.14224)
		(layer "In4.Cu")
		(net "M_L_BA<0>")
	)
	(segment
		(start 101.534976 -137.839196)
		(end 101.534976 -131.966208)
		(width 0.14224)
		(layer "In4.Cu")
		(net "M_L_BA<0>")
	)
	(segment
		(start 97.991168 -102.642416)
		(end 96.797368 -101.448616)
		(width 0.0889)
		(layer "In4.Cu")
		(net "M_L_BA<0>")
	)
	(segment
		(start 101.597968 -129.391664)
		(end 100.99548 -128.789176)
		(width 0.14224)
		(layer "In4.Cu")
		(net "M_L_BA<0>")
	)
	(segment
		(start 96.713548 -98.386138)
		(end 96.718374 -98.377502)
		(width 0.0889)
		(layer "In4.Cu")
		(net "M_L_BA<0>")
	)
	(segment
		(start 101.724968 -131.0386)
		(end 101.724968 -130.7338)
		(width 0.14224)
		(layer "In4.Cu")
		(net "M_L_BA<0>")
	)
	(segment
		(start 102.799642 -141.187678)
		(end 102.799642 -143.972788)
		(width 0.14224)
		(layer "In4.Cu")
		(net "M_L_BA<0>")
	)
	(segment
		(start 102.37851 -138.68273)
		(end 101.534976 -137.839196)
		(width 0.14224)
		(layer "In4.Cu")
		(net "M_L_BA<0>")
	)
	(segment
		(start 100.99548 -128.789176)
		(end 100.99548 -127.024892)
		(width 0.14224)
		(layer "In4.Cu")
		(net "M_L_BA<0>")
	)
	(segment
		(start 101.470968 -129.9718)
		(end 101.597968 -129.8448)
		(width 0.14224)
		(layer "In4.Cu")
		(net "M_L_BA<0>")
	)
	(segment
		(start 96.707198 -96.415606)
		(end 96.713548 -96.404938)
		(width 0.0889)
		(layer "In4.Cu")
		(net "M_L_BA<0>")
	)
	(segment
		(start 96.713548 -97.395538)
		(end 96.718374 -97.386902)
		(width 0.0889)
		(layer "In4.Cu")
		(net "M_L_BA<0>")
	)
	(segment
		(start 97.991168 -103.020368)
		(end 97.991168 -102.642416)
		(width 0.0889)
		(layer "In4.Cu")
		(net "M_L_BA<0>")
	)
	(segment
		(start 101.597968 -129.8448)
		(end 101.597968 -129.391664)
		(width 0.14224)
		(layer "In4.Cu")
		(net "M_L_BA<0>")
	)
	(segment
		(start 96.707198 -98.396806)
		(end 96.713548 -98.386138)
		(width 0.0889)
		(layer "In4.Cu")
		(net "M_L_BA<0>")
	)
	(segment
		(start 95.855028 -95.509588)
		(end 95.837756 -95.47987)
		(width 0.0889)
		(layer "In4.Cu")
		(net "M_L_BA<0>")
	)
	(segment
		(start 101.534976 -131.966208)
		(end 101.470968 -131.9022)
		(width 0.14224)
		(layer "In4.Cu")
		(net "M_L_BA<0>")
	)
	(segment
		(start 98.092768 -103.121968)
		(end 97.991168 -103.020368)
		(width 0.0889)
		(layer "In4.Cu")
		(net "M_L_BA<0>")
	)
	(segment
		(start 102.799642 -141.187678)
		(end 102.799642 -140.82903)
		(width 0.14224)
		(layer "In4.Cu")
		(net "M_L_BA<0>")
	)
	(segment
		(start 98.092768 -103.311198)
		(end 98.092768 -103.121968)
		(width 0.0889)
		(layer "In4.Cu")
		(net "M_L_BA<0>")
	)
	(segment
		(start 95.837756 -95.47987)
		(end 95.508318 -94.718886)
		(width 0.0889)
		(layer "In4.Cu")
		(net "M_L_BA<0>")
	)
	(segment
		(start 101.724968 -130.7338)
		(end 101.470968 -130.4798)
		(width 0.14224)
		(layer "In4.Cu")
		(net "M_L_BA<0>")
	)
	(segment
		(start 96.797368 -101.448616)
		(end 96.797368 -99.314)
		(width 0.0889)
		(layer "In4.Cu")
		(net "M_L_BA<0>")
	)
	(segment
		(start 101.470968 -131.2926)
		(end 101.724968 -131.0386)
		(width 0.14224)
		(layer "In4.Cu")
		(net "M_L_BA<0>")
	)
	(segment
		(start 96.713548 -96.404938)
		(end 96.718374 -96.396302)
		(width 0.0889)
		(layer "In4.Cu")
		(net "M_L_BA<0>")
	)
	(segment
		(start 102.799642 -140.82903)
		(end 102.37851 -140.407898)
		(width 0.14224)
		(layer "In4.Cu")
		(net "M_L_BA<0>")
	)
	(segment
		(start 102.37851 -140.407898)
		(end 102.37851 -138.68273)
		(width 0.14224)
		(layer "In4.Cu")
		(net "M_L_BA<0>")
	)
	(arc
		(start 96.349058 -95.80499)
		(mid 96.063634 -95.721523)
		(end 95.855028 -95.509588)
		(width 0.0889)
		(layer "In4.Cu")
		(net "M_L_BA<0>")
	)
	(arc
		(start 96.797368 -99.314)
		(mid 96.779265 -99.139425)
		(end 96.713548 -98.976688)
		(width 0.0889)
		(layer "In4.Cu")
		(net "M_L_BA<0>")
	)
	(arc
		(start 96.713548 -97.986088)
		(mid 96.634326 -97.69697)
		(end 96.707198 -97.406206)
		(width 0.0889)
		(layer "In4.Cu")
		(net "M_L_BA<0>")
	)
	(arc
		(start 96.718374 -98.377502)
		(mid 96.767129 -98.18115)
		(end 96.713548 -97.986088)
		(width 0.0889)
		(layer "In4.Cu")
		(net "M_L_BA<0>")
	)
	(arc
		(start 96.718374 -96.396302)
		(mid 96.714627 -96.007046)
		(end 96.381824 -95.80499)
		(width 0.0889)
		(layer "In4.Cu")
		(net "M_L_BA<0>")
	)
	(arc
		(start 96.713548 -96.995488)
		(mid 96.634326 -96.70637)
		(end 96.707198 -96.415606)
		(width 0.0889)
		(layer "In4.Cu")
		(net "M_L_BA<0>")
	)
	(arc
		(start 96.713548 -98.976688)
		(mid 96.634326 -98.68757)
		(end 96.707198 -98.396806)
		(width 0.0889)
		(layer "In4.Cu")
		(net "M_L_BA<0>")
	)
	(arc
		(start 96.718374 -97.386902)
		(mid 96.767129 -97.19055)
		(end 96.713548 -96.995488)
		(width 0.0889)
		(layer "In4.Cu")
		(net "M_L_BA<0>")
	)
	(segment
		(start 83.249516 -145.988278)
		(end 83.249516 -147.27174)
		(width 0.1651)
		(layer "F.Cu")
		(net "M_L_ALERT_N")
	)
	(segment
		(start 89.211912 -96.700086)
		(end 88.640412 -96.700086)
		(width 0.1651)
		(layer "F.Cu")
		(net "M_L_ALERT_N")
	)
	(via
		(at 88.640412 -96.700086)
		(size 0.508)
		(drill 0.254)
		(layers "F.Cu" "B.Cu")
		(net "M_L_ALERT_N")
	)
	(via
		(at 83.249516 -139.170156)
		(size 0.4572)
		(drill 0.2032)
		(layers "F.Cu" "B.Cu")
		(net "M_L_ALERT_N")
	)
	(via
		(at 83.249516 -145.988278)
		(size 0.4572)
		(drill 0.2032)
		(layers "F.Cu" "B.Cu")
		(net "M_L_ALERT_N")
	)
	(segment
		(start 83.249516 -139.170156)
		(end 83.249516 -137.877296)
		(width 0.1651)
		(layer "B.Cu")
		(net "M_L_ALERT_N")
	)
	(segment
		(start 88.640412 -96.700086)
		(end 88.310974 -97.46107)
		(width 0.0889)
		(layer "In4.Cu")
		(net "M_L_ALERT_N")
	)
	(segment
		(start 84.540344 -137.879328)
		(end 83.249516 -139.170156)
		(width 0.14224)
		(layer "In4.Cu")
		(net "M_L_ALERT_N")
	)
	(segment
		(start 89.10066 -103.38181)
		(end 89.10066 -122.668792)
		(width 0.14224)
		(layer "In4.Cu")
		(net "M_L_ALERT_N")
	)
	(segment
		(start 83.685634 -140.761466)
		(end 83.685634 -144.886934)
		(width 0.14224)
		(layer "In4.Cu")
		(net "M_L_ALERT_N")
	)
	(segment
		(start 83.249516 -139.170156)
		(end 83.249516 -140.325348)
		(width 0.14224)
		(layer "In4.Cu")
		(net "M_L_ALERT_N")
	)
	(segment
		(start 84.478368 -130.556)
		(end 84.579968 -130.6576)
		(width 0.14224)
		(layer "In4.Cu")
		(net "M_L_ALERT_N")
	)
	(segment
		(start 88.236552 -99.571302)
		(end 88.236552 -99.90074)
		(width 0.0889)
		(layer "In4.Cu")
		(net "M_L_ALERT_N")
	)
	(segment
		(start 83.249516 -140.325348)
		(end 83.685634 -140.761466)
		(width 0.14224)
		(layer "In4.Cu")
		(net "M_L_ALERT_N")
	)
	(segment
		(start 88.293702 -99.472242)
		(end 88.236552 -99.571302)
		(width 0.0889)
		(layer "In4.Cu")
		(net "M_L_ALERT_N")
	)
	(segment
		(start 84.808568 -129.6162)
		(end 84.478368 -129.9464)
		(width 0.14224)
		(layer "In4.Cu")
		(net "M_L_ALERT_N")
	)
	(segment
		(start 89.10066 -103.149908)
		(end 89.10066 -103.38181)
		(width 0.0889)
		(layer "In4.Cu")
		(net "M_L_ALERT_N")
	)
	(segment
		(start 84.579968 -130.6576)
		(end 84.579968 -131.191)
		(width 0.14224)
		(layer "In4.Cu")
		(net "M_L_ALERT_N")
	)
	(segment
		(start 88.236552 -99.90074)
		(end 89.634568 -101.298756)
		(width 0.0889)
		(layer "In4.Cu")
		(net "M_L_ALERT_N")
	)
	(segment
		(start 84.452968 -131.8768)
		(end 84.529168 -131.953)
		(width 0.14224)
		(layer "In4.Cu")
		(net "M_L_ALERT_N")
	)
	(segment
		(start 88.310974 -97.46107)
		(end 88.288876 -97.499424)
		(width 0.0889)
		(layer "In4.Cu")
		(net "M_L_ALERT_N")
	)
	(segment
		(start 84.540344 -136.155176)
		(end 84.540344 -137.879328)
		(width 0.14224)
		(layer "In4.Cu")
		(net "M_L_ALERT_N")
	)
	(segment
		(start 89.10066 -122.668792)
		(end 84.808568 -126.960884)
		(width 0.14224)
		(layer "In4.Cu")
		(net "M_L_ALERT_N")
	)
	(segment
		(start 84.452968 -131.318)
		(end 84.452968 -131.8768)
		(width 0.14224)
		(layer "In4.Cu")
		(net "M_L_ALERT_N")
	)
	(segment
		(start 84.579968 -131.191)
		(end 84.452968 -131.318)
		(width 0.14224)
		(layer "In4.Cu")
		(net "M_L_ALERT_N")
	)
	(segment
		(start 89.634568 -101.298756)
		(end 89.634568 -102.616)
		(width 0.0889)
		(layer "In4.Cu")
		(net "M_L_ALERT_N")
	)
	(segment
		(start 84.450936 -136.065768)
		(end 84.540344 -136.155176)
		(width 0.14224)
		(layer "In4.Cu")
		(net "M_L_ALERT_N")
	)
	(segment
		(start 84.450936 -134.799832)
		(end 84.450936 -136.065768)
		(width 0.14224)
		(layer "In4.Cu")
		(net "M_L_ALERT_N")
	)
	(segment
		(start 89.634568 -102.616)
		(end 89.10066 -103.149908)
		(width 0.0889)
		(layer "In4.Cu")
		(net "M_L_ALERT_N")
	)
	(segment
		(start 84.478368 -129.9464)
		(end 84.478368 -130.556)
		(width 0.14224)
		(layer "In4.Cu")
		(net "M_L_ALERT_N")
	)
	(segment
		(start 84.808568 -126.960884)
		(end 84.808568 -129.6162)
		(width 0.14224)
		(layer "In4.Cu")
		(net "M_L_ALERT_N")
	)
	(segment
		(start 83.249516 -145.323052)
		(end 83.249516 -145.988278)
		(width 0.14224)
		(layer "In4.Cu")
		(net "M_L_ALERT_N")
	)
	(segment
		(start 84.529168 -131.953)
		(end 84.529168 -134.7216)
		(width 0.14224)
		(layer "In4.Cu")
		(net "M_L_ALERT_N")
	)
	(segment
		(start 84.529168 -134.7216)
		(end 84.450936 -134.799832)
		(width 0.14224)
		(layer "In4.Cu")
		(net "M_L_ALERT_N")
	)
	(segment
		(start 83.685634 -144.886934)
		(end 83.249516 -145.323052)
		(width 0.14224)
		(layer "In4.Cu")
		(net "M_L_ALERT_N")
	)
	(arc
		(start 88.293702 -97.890838)
		(mid 88.372833 -98.18624)
		(end 88.293702 -98.481642)
		(width 0.0889)
		(layer "In4.Cu")
		(net "M_L_ALERT_N")
	)
	(arc
		(start 88.293702 -98.881438)
		(mid 88.372833 -99.17684)
		(end 88.293702 -99.472242)
		(width 0.0889)
		(layer "In4.Cu")
		(net "M_L_ALERT_N")
	)
	(arc
		(start 88.293702 -98.481642)
		(mid 88.240203 -98.68154)
		(end 88.293702 -98.881438)
		(width 0.0889)
		(layer "In4.Cu")
		(net "M_L_ALERT_N")
	)
	(arc
		(start 88.288876 -97.499424)
		(mid 88.240121 -97.695776)
		(end 88.293702 -97.890838)
		(width 0.0889)
		(layer "In4.Cu")
		(net "M_L_ALERT_N")
	)
	(segment
		(start 81.549494 -142.6718)
		(end 81.549494 -143.970756)
		(width 0.1651)
		(layer "F.Cu")
		(net "M_L_ACT_N")
	)
	(segment
		(start 88.353392 -96.20504)
		(end 87.781892 -96.20504)
		(width 0.1651)
		(layer "F.Cu")
		(net "M_L_ACT_N")
	)
	(via
		(at 81.549494 -141.187678)
		(size 0.4572)
		(drill 0.2032)
		(layers "F.Cu" "B.Cu")
		(net "M_L_ACT_N")
	)
	(via
		(at 87.781892 -96.20504)
		(size 0.508)
		(drill 0.254)
		(layers "F.Cu" "B.Cu")
		(net "M_L_ACT_N")
	)
	(via
		(at 81.549494 -143.970756)
		(size 0.4572)
		(drill 0.2032)
		(layers "F.Cu" "B.Cu")
		(net "M_L_ACT_N")
	)
	(segment
		(start 81.549494 -142.477236)
		(end 81.549494 -141.187678)
		(width 0.1651)
		(layer "B.Cu")
		(net "M_L_ACT_N")
	)
	(segment
		(start 85.104986 -125.226826)
		(end 85.104986 -125.445774)
		(width 0.14224)
		(layer "In4.Cu")
		(net "M_L_ACT_N")
	)
	(segment
		(start 82.903568 -129.7686)
		(end 82.751168 -129.921)
		(width 0.14224)
		(layer "In4.Cu")
		(net "M_L_ACT_N")
	)
	(segment
		(start 87.621364 -99.70008)
		(end 87.621872 -99.700588)
		(width 0.0889)
		(layer "In4.Cu")
		(net "M_L_ACT_N")
	)
	(segment
		(start 84.3661 -125.425708)
		(end 84.133182 -125.425708)
		(width 0.14224)
		(layer "In4.Cu")
		(net "M_L_ACT_N")
	)
	(segment
		(start 85.57387 -124.757942)
		(end 85.301074 -124.485146)
		(width 0.14224)
		(layer "In4.Cu")
		(net "M_L_ACT_N")
	)
	(segment
		(start 85.082126 -124.485146)
		(end 84.83219 -124.735082)
		(width 0.14224)
		(layer "In4.Cu")
		(net "M_L_ACT_N")
	)
	(segment
		(start 87.430356 -99.368102)
		(end 87.434928 -99.376992)
		(width 0.0889)
		(layer "In4.Cu")
		(net "M_L_ACT_N")
	)
	(segment
		(start 85.792818 -124.757942)
		(end 85.57387 -124.757942)
		(width 0.14224)
		(layer "In4.Cu")
		(net "M_L_ACT_N")
	)
	(segment
		(start 87.451946 -96.966786)
		(end 87.435182 -96.995488)
		(width 0.0889)
		(layer "In4.Cu")
		(net "M_L_ACT_N")
	)
	(segment
		(start 87.434928 -99.376992)
		(end 87.435182 -99.376738)
		(width 0.0889)
		(layer "In4.Cu")
		(net "M_L_ACT_N")
	)
	(segment
		(start 83.883246 -125.880622)
		(end 84.167218 -126.164594)
		(width 0.14224)
		(layer "In4.Cu")
		(net "M_L_ACT_N")
	)
	(segment
		(start 82.776568 -132.306568)
		(end 82.816446 -132.346446)
		(width 0.14224)
		(layer "In4.Cu")
		(net "M_L_ACT_N")
	)
	(segment
		(start 82.827368 -138.0236)
		(end 81.987644 -138.863324)
		(width 0.14224)
		(layer "In4.Cu")
		(net "M_L_ACT_N")
	)
	(segment
		(start 87.781892 -96.20504)
		(end 87.451946 -96.966786)
		(width 0.0889)
		(layer "In4.Cu")
		(net "M_L_ACT_N")
	)
	(segment
		(start 85.104986 -125.445774)
		(end 84.85505 -125.69571)
		(width 0.14224)
		(layer "In4.Cu")
		(net "M_L_ACT_N")
	)
	(segment
		(start 84.636102 -125.69571)
		(end 84.3661 -125.425708)
		(width 0.14224)
		(layer "In4.Cu")
		(net "M_L_ACT_N")
	)
	(segment
		(start 85.842602 -123.853194)
		(end 85.842602 -124.088906)
		(width 0.14224)
		(layer "In4.Cu")
		(net "M_L_ACT_N")
	)
	(segment
		(start 84.83219 -124.95403)
		(end 85.104986 -125.226826)
		(width 0.14224)
		(layer "In4.Cu")
		(net "M_L_ACT_N")
	)
	(segment
		(start 81.549494 -141.187678)
		(end 81.549494 -143.970756)
		(width 0.14224)
		(layer "In4.Cu")
		(net "M_L_ACT_N")
	)
	(segment
		(start 84.133182 -125.425708)
		(end 83.883246 -125.675644)
		(width 0.14224)
		(layer "In4.Cu")
		(net "M_L_ACT_N")
	)
	(segment
		(start 87.430356 -97.386902)
		(end 87.435182 -97.395538)
		(width 0.0889)
		(layer "In4.Cu")
		(net "M_L_ACT_N")
	)
	(segment
		(start 82.816446 -135.371078)
		(end 82.827368 -135.382)
		(width 0.14224)
		(layer "In4.Cu")
		(net "M_L_ACT_N")
	)
	(segment
		(start 83.741768 -126.808992)
		(end 83.741768 -128.561084)
		(width 0.14224)
		(layer "In4.Cu")
		(net "M_L_ACT_N")
	)
	(segment
		(start 86.092538 -123.603258)
		(end 85.842602 -123.853194)
		(width 0.14224)
		(layer "In4.Cu")
		(net "M_L_ACT_N")
	)
	(segment
		(start 87.435182 -98.386138)
		(end 87.441532 -98.396806)
		(width 0.0889)
		(layer "In4.Cu")
		(net "M_L_ACT_N")
	)
	(segment
		(start 82.776568 -131.2926)
		(end 82.776568 -132.306568)
		(width 0.14224)
		(layer "In4.Cu")
		(net "M_L_ACT_N")
	)
	(segment
		(start 84.83219 -124.735082)
		(end 84.83219 -124.95403)
		(width 0.14224)
		(layer "In4.Cu")
		(net "M_L_ACT_N")
	)
	(segment
		(start 82.827368 -135.382)
		(end 82.827368 -138.0236)
		(width 0.14224)
		(layer "In4.Cu")
		(net "M_L_ACT_N")
	)
	(segment
		(start 83.883246 -125.675644)
		(end 83.883246 -125.880622)
		(width 0.14224)
		(layer "In4.Cu")
		(net "M_L_ACT_N")
	)
	(segment
		(start 87.430356 -98.377502)
		(end 87.435182 -98.386138)
		(width 0.0889)
		(layer "In4.Cu")
		(net "M_L_ACT_N")
	)
	(segment
		(start 88.08466 -122.4661)
		(end 86.730586 -123.820174)
		(width 0.14224)
		(layer "In4.Cu")
		(net "M_L_ACT_N")
	)
	(segment
		(start 88.08466 -100.867972)
		(end 88.08466 -122.4661)
		(width 0.14224)
		(layer "In4.Cu")
		(net "M_L_ACT_N")
	)
	(segment
		(start 84.167218 -126.383542)
		(end 83.741768 -126.808992)
		(width 0.14224)
		(layer "In4.Cu")
		(net "M_L_ACT_N")
	)
	(segment
		(start 82.903568 -129.399284)
		(end 82.903568 -129.7686)
		(width 0.14224)
		(layer "In4.Cu")
		(net "M_L_ACT_N")
	)
	(segment
		(start 86.294722 -123.603258)
		(end 86.092538 -123.603258)
		(width 0.14224)
		(layer "In4.Cu")
		(net "M_L_ACT_N")
	)
	(segment
		(start 82.751168 -130.5052)
		(end 82.903568 -130.6576)
		(width 0.14224)
		(layer "In4.Cu")
		(net "M_L_ACT_N")
	)
	(segment
		(start 82.040222 -139.573254)
		(end 82.040222 -140.69695)
		(width 0.14224)
		(layer "In4.Cu")
		(net "M_L_ACT_N")
	)
	(segment
		(start 88.08466 -100.507292)
		(end 88.08466 -100.867972)
		(width 0.0889)
		(layer "In4.Cu")
		(net "M_L_ACT_N")
	)
	(segment
		(start 87.434928 -99.377246)
		(end 87.621364 -99.70008)
		(width 0.0889)
		(layer "In4.Cu")
		(net "M_L_ACT_N")
	)
	(segment
		(start 81.987644 -138.863324)
		(end 81.987644 -139.520676)
		(width 0.14224)
		(layer "In4.Cu")
		(net "M_L_ACT_N")
	)
	(segment
		(start 82.903568 -130.6576)
		(end 82.903568 -131.1656)
		(width 0.14224)
		(layer "In4.Cu")
		(net "M_L_ACT_N")
	)
	(segment
		(start 87.621872 -100.044504)
		(end 88.08466 -100.507292)
		(width 0.0889)
		(layer "In4.Cu")
		(net "M_L_ACT_N")
	)
	(segment
		(start 87.435182 -97.395538)
		(end 87.441532 -97.406206)
		(width 0.0889)
		(layer "In4.Cu")
		(net "M_L_ACT_N")
	)
	(segment
		(start 82.903568 -131.1656)
		(end 82.776568 -131.2926)
		(width 0.14224)
		(layer "In4.Cu")
		(net "M_L_ACT_N")
	)
	(segment
		(start 86.511638 -123.820174)
		(end 86.294722 -123.603258)
		(width 0.14224)
		(layer "In4.Cu")
		(net "M_L_ACT_N")
	)
	(segment
		(start 82.751168 -129.921)
		(end 82.751168 -130.5052)
		(width 0.14224)
		(layer "In4.Cu")
		(net "M_L_ACT_N")
	)
	(segment
		(start 82.816446 -132.346446)
		(end 82.816446 -135.371078)
		(width 0.14224)
		(layer "In4.Cu")
		(net "M_L_ACT_N")
	)
	(segment
		(start 82.040222 -140.69695)
		(end 81.549494 -141.187678)
		(width 0.14224)
		(layer "In4.Cu")
		(net "M_L_ACT_N")
	)
	(segment
		(start 86.042754 -124.508006)
		(end 85.792818 -124.757942)
		(width 0.14224)
		(layer "In4.Cu")
		(net "M_L_ACT_N")
	)
	(segment
		(start 84.85505 -125.69571)
		(end 84.636102 -125.69571)
		(width 0.14224)
		(layer "In4.Cu")
		(net "M_L_ACT_N")
	)
	(segment
		(start 86.042754 -124.289058)
		(end 86.042754 -124.508006)
		(width 0.14224)
		(layer "In4.Cu")
		(net "M_L_ACT_N")
	)
	(segment
		(start 85.301074 -124.485146)
		(end 85.082126 -124.485146)
		(width 0.14224)
		(layer "In4.Cu")
		(net "M_L_ACT_N")
	)
	(segment
		(start 81.987644 -139.520676)
		(end 82.040222 -139.573254)
		(width 0.14224)
		(layer "In4.Cu")
		(net "M_L_ACT_N")
	)
	(segment
		(start 87.621872 -99.700588)
		(end 87.621872 -100.044504)
		(width 0.0889)
		(layer "In4.Cu")
		(net "M_L_ACT_N")
	)
	(segment
		(start 84.167218 -126.164594)
		(end 84.167218 -126.383542)
		(width 0.14224)
		(layer "In4.Cu")
		(net "M_L_ACT_N")
	)
	(segment
		(start 86.730586 -123.820174)
		(end 86.511638 -123.820174)
		(width 0.14224)
		(layer "In4.Cu")
		(net "M_L_ACT_N")
	)
	(segment
		(start 85.842602 -124.088906)
		(end 86.042754 -124.289058)
		(width 0.14224)
		(layer "In4.Cu")
		(net "M_L_ACT_N")
	)
	(segment
		(start 83.741768 -128.561084)
		(end 82.903568 -129.399284)
		(width 0.14224)
		(layer "In4.Cu")
		(net "M_L_ACT_N")
	)
	(arc
		(start 87.435182 -98.976688)
		(mid 87.381712 -99.171751)
		(end 87.430356 -99.368102)
		(width 0.0889)
		(layer "In4.Cu")
		(net "M_L_ACT_N")
	)
	(arc
		(start 87.435182 -96.995488)
		(mid 87.381712 -97.190551)
		(end 87.430356 -97.386902)
		(width 0.0889)
		(layer "In4.Cu")
		(net "M_L_ACT_N")
	)
	(arc
		(start 87.441532 -98.396806)
		(mid 87.51433 -98.687569)
		(end 87.435182 -98.976688)
		(width 0.0889)
		(layer "In4.Cu")
		(net "M_L_ACT_N")
	)
	(arc
		(start 87.441532 -97.406206)
		(mid 87.51433 -97.696969)
		(end 87.435182 -97.986088)
		(width 0.0889)
		(layer "In4.Cu")
		(net "M_L_ACT_N")
	)
	(arc
		(start 87.435182 -97.986088)
		(mid 87.381712 -98.181151)
		(end 87.430356 -98.377502)
		(width 0.0889)
		(layer "In4.Cu")
		(net "M_L_ACT_N")
	)
	(arc
		(start 87.435182 -99.376738)
		(mid 87.435055 -99.376992)
		(end 87.434928 -99.377246)
		(width 0.0889)
		(layer "In4.Cu")
		(net "M_L_ACT_N")
	)
	(segment
		(start 96.079818 -100.662486)
		(end 96.38665 -101.37013)
		(width 0.0889)
		(layer "F.Cu")
		(net "M_K_PAR")
	)
	(segment
		(start 100.249482 -136.435084)
		(end 100.22713 -136.412732)
		(width 0.1651)
		(layer "F.Cu")
		(net "M_K_PAR")
	)
	(segment
		(start 100.249228 -129.936748)
		(end 100.249228 -130.249168)
		(width 0.1651)
		(layer "F.Cu")
		(net "M_K_PAR")
	)
	(segment
		(start 98.80854 -128.49606)
		(end 100.249228 -129.936748)
		(width 0.1651)
		(layer "F.Cu")
		(net "M_K_PAR")
	)
	(segment
		(start 97.476818 -104.28859)
		(end 97.476818 -126.446534)
		(width 0.1651)
		(layer "F.Cu")
		(net "M_K_PAR")
	)
	(segment
		(start 96.480122 -102.6414)
		(end 97.476818 -103.638096)
		(width 0.0889)
		(layer "F.Cu")
		(net "M_K_PAR")
	)
	(segment
		(start 98.80854 -127.778256)
		(end 98.80854 -128.49606)
		(width 0.1651)
		(layer "F.Cu")
		(net "M_K_PAR")
	)
	(segment
		(start 100.249482 -137.67054)
		(end 100.249482 -136.435084)
		(width 0.1651)
		(layer "F.Cu")
		(net "M_K_PAR")
	)
	(segment
		(start 96.420178 -101.44252)
		(end 96.426528 -101.453188)
		(width 0.0889)
		(layer "F.Cu")
		(net "M_K_PAR")
	)
	(segment
		(start 96.480122 -101.654356)
		(end 96.480122 -102.6414)
		(width 0.0889)
		(layer "F.Cu")
		(net "M_K_PAR")
	)
	(segment
		(start 96.426528 -101.453188)
		(end 96.431354 -101.461824)
		(width 0.0889)
		(layer "F.Cu")
		(net "M_K_PAR")
	)
	(segment
		(start 97.476818 -103.638096)
		(end 97.476818 -104.28859)
		(width 0.0889)
		(layer "F.Cu")
		(net "M_K_PAR")
	)
	(segment
		(start 97.476818 -126.446534)
		(end 98.80854 -127.778256)
		(width 0.1651)
		(layer "F.Cu")
		(net "M_K_PAR")
	)
	(via
		(at 100.249228 -130.249168)
		(size 0.508)
		(drill 0.254)
		(layers "F.Cu" "B.Cu")
		(net "M_K_PAR")
	)
	(via
		(at 100.22713 -136.412732)
		(size 0.508)
		(drill 0.254)
		(layers "F.Cu" "B.Cu")
		(net "M_K_PAR")
	)
	(arc
		(start 96.38665 -101.37013)
		(mid 96.402192 -101.406891)
		(end 96.420178 -101.44252)
		(width 0.0889)
		(layer "F.Cu")
		(net "M_K_PAR")
	)
	(arc
		(start 96.431354 -101.461824)
		(mid 96.467875 -101.555017)
		(end 96.480122 -101.654356)
		(width 0.0889)
		(layer "F.Cu")
		(net "M_K_PAR")
	)
	(segment
		(start 100.249482 -128.276096)
		(end 100.249482 -130.248914)
		(width 0.1651)
		(layer "B.Cu")
		(net "M_K_PAR")
	)
	(segment
		(start 100.249482 -130.248914)
		(end 100.249228 -130.249168)
		(width 0.1651)
		(layer "B.Cu")
		(net "M_K_PAR")
	)
	(segment
		(start 100.661978 -131.309618)
		(end 100.661978 -134.540752)
		(width 0.14224)
		(layer "In9.Cu")
		(net "M_K_PAR")
	)
	(segment
		(start 100.249228 -130.896868)
		(end 100.661978 -131.309618)
		(width 0.14224)
		(layer "In9.Cu")
		(net "M_K_PAR")
	)
	(segment
		(start 100.226876 -136.412478)
		(end 100.22713 -136.412732)
		(width 0.14224)
		(layer "In9.Cu")
		(net "M_K_PAR")
	)
	(segment
		(start 100.249228 -130.249168)
		(end 100.249228 -130.896868)
		(width 0.14224)
		(layer "In9.Cu")
		(net "M_K_PAR")
	)
	(segment
		(start 100.757482 -134.636256)
		(end 100.757482 -135.269732)
		(width 0.14224)
		(layer "In9.Cu")
		(net "M_K_PAR")
	)
	(segment
		(start 100.226876 -135.800338)
		(end 100.226876 -136.412478)
		(width 0.14224)
		(layer "In9.Cu")
		(net "M_K_PAR")
	)
	(segment
		(start 100.661978 -134.540752)
		(end 100.757482 -134.636256)
		(width 0.14224)
		(layer "In9.Cu")
		(net "M_K_PAR")
	)
	(segment
		(start 100.757482 -135.269732)
		(end 100.226876 -135.800338)
		(width 0.14224)
		(layer "In9.Cu")
		(net "M_K_PAR")
	)
	(segment
		(start 103.643938 -106.239564)
		(end 103.643938 -121.42597)
		(width 0.1651)
		(layer "F.Cu")
		(net "M_K_ODT<3>")
	)
	(segment
		(start 111.282988 -129.06502)
		(end 111.586518 -129.19075)
		(width 0.1651)
		(layer "F.Cu")
		(net "M_K_ODT<3>")
	)
	(segment
		(start 103.643938 -121.42597)
		(end 111.282988 -129.06502)
		(width 0.1651)
		(layer "F.Cu")
		(net "M_K_ODT<3>")
	)
	(segment
		(start 100.823268 -102.501446)
		(end 103.643938 -105.322116)
		(width 0.0889)
		(layer "F.Cu")
		(net "M_K_ODT<3>")
	)
	(segment
		(start 100.372164 -99.17684)
		(end 100.631244 -99.774502)
		(width 0.0889)
		(layer "F.Cu")
		(net "M_K_ODT<3>")
	)
	(segment
		(start 100.823268 -100.69957)
		(end 100.823268 -102.501446)
		(width 0.0889)
		(layer "F.Cu")
		(net "M_K_ODT<3>")
	)
	(segment
		(start 111.757968 -129.3622)
		(end 111.757968 -129.795524)
		(width 0.1651)
		(layer "F.Cu")
		(net "M_K_ODT<3>")
	)
	(segment
		(start 103.643938 -105.322116)
		(end 103.643938 -106.239564)
		(width 0.0889)
		(layer "F.Cu")
		(net "M_K_ODT<3>")
	)
	(segment
		(start 111.586518 -129.19075)
		(end 111.757968 -129.3622)
		(width 0.1651)
		(layer "F.Cu")
		(net "M_K_ODT<3>")
	)
	(segment
		(start 111.757968 -129.795524)
		(end 111.299498 -130.902456)
		(width 0.1651)
		(layer "F.Cu")
		(net "M_K_ODT<3>")
	)
	(via
		(at 111.299498 -130.902456)
		(size 0.508)
		(drill 0.254)
		(layers "F.Cu" "B.Cu")
		(net "M_K_ODT<3>")
	)
	(arc
		(start 100.631244 -99.774502)
		(mid 100.774752 -100.227178)
		(end 100.823268 -100.69957)
		(width 0.0889)
		(layer "F.Cu")
		(net "M_K_ODT<3>")
	)
	(segment
		(start 111.299498 -132.876036)
		(end 111.299498 -130.902456)
		(width 0.1651)
		(layer "B.Cu")
		(net "M_K_ODT<3>")
	)
	(segment
		(start 98.507804 -100.541836)
		(end 98.600768 -100.6348)
		(width 0.0889)
		(layer "F.Cu")
		(net "M_K_ODT<2>")
	)
	(segment
		(start 98.803968 -100.6348)
		(end 99.089972 -100.920804)
		(width 0.0889)
		(layer "F.Cu")
		(net "M_K_ODT<2>")
	)
	(segment
		(start 98.655378 -99.360736)
		(end 98.259392 -99.756722)
		(width 0.0889)
		(layer "F.Cu")
		(net "M_K_ODT<2>")
	)
	(segment
		(start 99.388168 -102.7684)
		(end 99.632262 -102.7684)
		(width 0.0889)
		(layer "F.Cu")
		(net "M_K_ODT<2>")
	)
	(segment
		(start 98.280728 -100.322634)
		(end 98.49993 -100.541836)
		(width 0.0889)
		(layer "F.Cu")
		(net "M_K_ODT<2>")
	)
	(segment
		(start 101.627178 -104.763316)
		(end 101.627178 -105.540302)
		(width 0.0889)
		(layer "F.Cu")
		(net "M_K_ODT<2>")
	)
	(segment
		(start 108.354368 -129.362454)
		(end 108.354368 -130.022854)
		(width 0.1651)
		(layer "F.Cu")
		(net "M_K_ODT<2>")
	)
	(segment
		(start 98.655378 -99.17684)
		(end 98.655378 -99.360736)
		(width 0.0889)
		(layer "F.Cu")
		(net "M_K_ODT<2>")
	)
	(segment
		(start 101.627178 -105.540302)
		(end 101.627178 -122.635264)
		(width 0.1651)
		(layer "F.Cu")
		(net "M_K_ODT<2>")
	)
	(segment
		(start 98.49993 -100.541836)
		(end 98.507804 -100.541836)
		(width 0.0889)
		(layer "F.Cu")
		(net "M_K_ODT<2>")
	)
	(segment
		(start 98.259392 -100.293424)
		(end 98.280728 -100.31476)
		(width 0.0889)
		(layer "F.Cu")
		(net "M_K_ODT<2>")
	)
	(segment
		(start 104.789224 -125.79731)
		(end 104.789224 -126.299722)
		(width 0.1651)
		(layer "F.Cu")
		(net "M_K_ODT<2>")
	)
	(segment
		(start 105.65511 -127.165608)
		(end 106.157522 -127.165608)
		(width 0.1651)
		(layer "F.Cu")
		(net "M_K_ODT<2>")
	)
	(segment
		(start 101.627178 -122.635264)
		(end 104.789224 -125.79731)
		(width 0.1651)
		(layer "F.Cu")
		(net "M_K_ODT<2>")
	)
	(segment
		(start 99.089972 -102.470204)
		(end 99.388168 -102.7684)
		(width 0.0889)
		(layer "F.Cu")
		(net "M_K_ODT<2>")
	)
	(segment
		(start 108.201968 -130.175254)
		(end 108.201968 -130.599942)
		(width 0.1651)
		(layer "F.Cu")
		(net "M_K_ODT<2>")
	)
	(segment
		(start 99.089972 -100.920804)
		(end 99.089972 -102.470204)
		(width 0.0889)
		(layer "F.Cu")
		(net "M_K_ODT<2>")
	)
	(segment
		(start 99.632262 -102.7684)
		(end 101.627178 -104.763316)
		(width 0.0889)
		(layer "F.Cu")
		(net "M_K_ODT<2>")
	)
	(segment
		(start 106.157522 -127.165608)
		(end 108.354368 -129.362454)
		(width 0.1651)
		(layer "F.Cu")
		(net "M_K_ODT<2>")
	)
	(segment
		(start 104.789224 -126.299722)
		(end 105.65511 -127.165608)
		(width 0.1651)
		(layer "F.Cu")
		(net "M_K_ODT<2>")
	)
	(segment
		(start 108.201968 -130.599942)
		(end 107.899454 -130.902456)
		(width 0.1651)
		(layer "F.Cu")
		(net "M_K_ODT<2>")
	)
	(segment
		(start 98.600768 -100.6348)
		(end 98.803968 -100.6348)
		(width 0.0889)
		(layer "F.Cu")
		(net "M_K_ODT<2>")
	)
	(segment
		(start 98.259392 -99.756722)
		(end 98.259392 -100.293424)
		(width 0.0889)
		(layer "F.Cu")
		(net "M_K_ODT<2>")
	)
	(segment
		(start 98.280728 -100.31476)
		(end 98.280728 -100.322634)
		(width 0.0889)
		(layer "F.Cu")
		(net "M_K_ODT<2>")
	)
	(segment
		(start 108.354368 -130.022854)
		(end 108.201968 -130.175254)
		(width 0.1651)
		(layer "F.Cu")
		(net "M_K_ODT<2>")
	)
	(via
		(at 107.899454 -130.902456)
		(size 0.508)
		(drill 0.254)
		(layers "F.Cu" "B.Cu")
		(net "M_K_ODT<2>")
	)
	(segment
		(start 107.899454 -132.876036)
		(end 107.899454 -130.902456)
		(width 0.1651)
		(layer "B.Cu")
		(net "M_K_ODT<2>")
	)
	(segment
		(start 110.970568 -129.921)
		(end 110.843568 -129.794)
		(width 0.1651)
		(layer "F.Cu")
		(net "M_K_ODT<1>")
	)
	(segment
		(start 100.521262 -102.52964)
		(end 100.521262 -101.541834)
		(width 0.0889)
		(layer "F.Cu")
		(net "M_K_ODT<1>")
	)
	(segment
		(start 110.776258 -131.04749)
		(end 110.776258 -130.640074)
		(width 0.1651)
		(layer "F.Cu")
		(net "M_K_ODT<1>")
	)
	(segment
		(start 100.521262 -101.541834)
		(end 100.372164 -101.15804)
		(width 0.0889)
		(layer "F.Cu")
		(net "M_K_ODT<1>")
	)
	(segment
		(start 106.591354 -125.135386)
		(end 103.139748 -121.68378)
		(width 0.1651)
		(layer "F.Cu")
		(net "M_K_ODT<1>")
	)
	(segment
		(start 103.139748 -106.09326)
		(end 103.139748 -105.148126)
		(width 0.0889)
		(layer "F.Cu")
		(net "M_K_ODT<1>")
	)
	(segment
		(start 110.970568 -130.445764)
		(end 110.970568 -129.921)
		(width 0.1651)
		(layer "F.Cu")
		(net "M_K_ODT<1>")
	)
	(segment
		(start 111.299498 -133.0706)
		(end 111.299498 -131.57073)
		(width 0.1651)
		(layer "F.Cu")
		(net "M_K_ODT<1>")
	)
	(segment
		(start 110.776258 -130.640074)
		(end 110.970568 -130.445764)
		(width 0.1651)
		(layer "F.Cu")
		(net "M_K_ODT<1>")
	)
	(segment
		(start 110.843568 -129.3876)
		(end 106.591354 -125.135386)
		(width 0.1651)
		(layer "F.Cu")
		(net "M_K_ODT<1>")
	)
	(segment
		(start 110.843568 -129.794)
		(end 110.843568 -129.3876)
		(width 0.1651)
		(layer "F.Cu")
		(net "M_K_ODT<1>")
	)
	(segment
		(start 103.139748 -121.68378)
		(end 103.139748 -106.09326)
		(width 0.1651)
		(layer "F.Cu")
		(net "M_K_ODT<1>")
	)
	(segment
		(start 103.139748 -105.148126)
		(end 100.521262 -102.52964)
		(width 0.0889)
		(layer "F.Cu")
		(net "M_K_ODT<1>")
	)
	(segment
		(start 111.299498 -131.57073)
		(end 110.776258 -131.04749)
		(width 0.1651)
		(layer "F.Cu")
		(net "M_K_ODT<1>")
	)
	(via
		(at 106.591354 -125.135386)
		(size 0.508)
		(drill 0.254)
		(layers "F.Cu" "B.Cu")
		(net "M_K_ODT<1>")
	)
	(segment
		(start 98.768916 -102.428548)
		(end 98.768916 -101.271578)
		(width 0.0889)
		(layer "F.Cu")
		(net "M_K_ODT<0>")
	)
	(segment
		(start 104.008682 -125.792738)
		(end 103.340154 -125.12421)
		(width 0.1651)
		(layer "F.Cu")
		(net "M_K_ODT<0>")
	)
	(segment
		(start 107.899454 -133.0706)
		(end 107.899454 -133.076442)
		(width 0.1651)
		(layer "F.Cu")
		(net "M_K_ODT<0>")
	)
	(segment
		(start 107.770168 -132.947156)
		(end 107.770168 -131.5974)
		(width 0.1651)
		(layer "F.Cu")
		(net "M_K_ODT<0>")
	)
	(segment
		(start 107.363768 -129.921)
		(end 107.363768 -129.3622)
		(width 0.1651)
		(layer "F.Cu")
		(net "M_K_ODT<0>")
	)
	(segment
		(start 103.340154 -125.12421)
		(end 101.122988 -122.907044)
		(width 0.1651)
		(layer "F.Cu")
		(net "M_K_ODT<0>")
	)
	(segment
		(start 107.262168 -131.0894)
		(end 107.262168 -130.7338)
		(width 0.1651)
		(layer "F.Cu")
		(net "M_K_ODT<0>")
	)
	(segment
		(start 104.008682 -127.096266)
		(end 104.008682 -125.792738)
		(width 0.1651)
		(layer "F.Cu")
		(net "M_K_ODT<0>")
	)
	(segment
		(start 101.122988 -105.333292)
		(end 101.225858 -105.230422)
		(width 0.0889)
		(layer "F.Cu")
		(net "M_K_ODT<0>")
	)
	(segment
		(start 107.770168 -131.5974)
		(end 107.262168 -131.0894)
		(width 0.1651)
		(layer "F.Cu")
		(net "M_K_ODT<0>")
	)
	(segment
		(start 107.516168 -130.0734)
		(end 107.363768 -129.921)
		(width 0.1651)
		(layer "F.Cu")
		(net "M_K_ODT<0>")
	)
	(segment
		(start 101.225858 -104.88549)
		(end 98.768916 -102.428548)
		(width 0.0889)
		(layer "F.Cu")
		(net "M_K_ODT<0>")
	)
	(segment
		(start 107.516168 -130.4798)
		(end 107.516168 -130.0734)
		(width 0.1651)
		(layer "F.Cu")
		(net "M_K_ODT<0>")
	)
	(segment
		(start 98.768916 -101.271578)
		(end 98.655378 -101.15804)
		(width 0.0889)
		(layer "F.Cu")
		(net "M_K_ODT<0>")
	)
	(segment
		(start 107.899454 -133.076442)
		(end 107.770168 -132.947156)
		(width 0.1651)
		(layer "F.Cu")
		(net "M_K_ODT<0>")
	)
	(segment
		(start 104.898952 -127.986536)
		(end 104.008682 -127.096266)
		(width 0.1651)
		(layer "F.Cu")
		(net "M_K_ODT<0>")
	)
	(segment
		(start 107.262168 -130.7338)
		(end 107.516168 -130.4798)
		(width 0.1651)
		(layer "F.Cu")
		(net "M_K_ODT<0>")
	)
	(segment
		(start 107.363768 -129.3622)
		(end 105.988104 -127.986536)
		(width 0.1651)
		(layer "F.Cu")
		(net "M_K_ODT<0>")
	)
	(segment
		(start 105.988104 -127.986536)
		(end 104.898952 -127.986536)
		(width 0.1651)
		(layer "F.Cu")
		(net "M_K_ODT<0>")
	)
	(segment
		(start 101.122988 -122.907044)
		(end 101.122988 -105.333292)
		(width 0.1651)
		(layer "F.Cu")
		(net "M_K_ODT<0>")
	)
	(segment
		(start 101.225858 -105.230422)
		(end 101.225858 -104.88549)
		(width 0.0889)
		(layer "F.Cu")
		(net "M_K_ODT<0>")
	)
	(via
		(at 103.340154 -125.12421)
		(size 0.508)
		(drill 0.254)
		(layers "F.Cu" "B.Cu")
		(net "M_K_ODT<0>")
	)
	(segment
		(start 84.949538 -133.0706)
		(end 84.949538 -134.369302)
		(width 0.1651)
		(layer "F.Cu")
		(net "M_K_MA<9>")
	)
	(segment
		(start 89.211912 -102.302056)
		(end 89.202768 -102.3112)
		(width 0.1651)
		(layer "F.Cu")
		(net "M_K_MA<9>")
	)
	(segment
		(start 84.949538 -134.369302)
		(end 84.949284 -134.369556)
		(width 0.1651)
		(layer "F.Cu")
		(net "M_K_MA<9>")
	)
	(segment
		(start 89.211912 -101.653086)
		(end 89.211912 -102.302056)
		(width 0.1651)
		(layer "F.Cu")
		(net "M_K_MA<9>")
	)
	(via
		(at 84.949284 -134.369556)
		(size 0.4572)
		(drill 0.2032)
		(layers "F.Cu" "B.Cu")
		(net "M_K_MA<9>")
	)
	(via
		(at 84.949538 -131.611878)
		(size 0.508)
		(drill 0.254)
		(layers "F.Cu" "B.Cu")
		(net "M_K_MA<9>")
	)
	(via
		(at 89.202768 -102.3112)
		(size 0.508)
		(drill 0.254)
		(layers "F.Cu" "B.Cu")
		(net "M_K_MA<9>")
	)
	(segment
		(start 84.949538 -132.876036)
		(end 84.949538 -131.611878)
		(width 0.1651)
		(layer "B.Cu")
		(net "M_K_MA<9>")
	)
	(segment
		(start 89.177368 -122.52833)
		(end 89.177368 -122.923554)
		(width 0.14224)
		(layer "In11.Cu")
		(net "M_K_MA<9>")
	)
	(segment
		(start 87.646002 -122.55119)
		(end 87.358728 -122.838464)
		(width 0.14224)
		(layer "In11.Cu")
		(net "M_K_MA<9>")
	)
	(segment
		(start 86.541102 -123.723908)
		(end 86.253828 -124.011182)
		(width 0.14224)
		(layer "In11.Cu")
		(net "M_K_MA<9>")
	)
	(segment
		(start 89.177368 -122.923554)
		(end 88.91524 -123.185682)
		(width 0.14224)
		(layer "In11.Cu")
		(net "M_K_MA<9>")
	)
	(segment
		(start 86.985602 -125.022102)
		(end 86.985602 -125.345698)
		(width 0.14224)
		(layer "In11.Cu")
		(net "M_K_MA<9>")
	)
	(segment
		(start 85.633814 -125.969522)
		(end 86.368128 -126.703836)
		(width 0.14224)
		(layer "In11.Cu")
		(net "M_K_MA<9>")
	)
	(segment
		(start 85.418168 -130.5306)
		(end 85.291168 -130.6576)
		(width 0.14224)
		(layer "In11.Cu")
		(net "M_K_MA<9>")
	)
	(segment
		(start 87.358728 -123.09602)
		(end 88.169242 -123.906534)
		(width 0.14224)
		(layer "In11.Cu")
		(net "M_K_MA<9>")
	)
	(segment
		(start 86.837012 -123.723908)
		(end 86.541102 -123.723908)
		(width 0.14224)
		(layer "In11.Cu")
		(net "M_K_MA<9>")
	)
	(segment
		(start 86.253828 -124.011182)
		(end 86.253828 -124.290328)
		(width 0.14224)
		(layer "In11.Cu")
		(net "M_K_MA<9>")
	)
	(segment
		(start 85.265768 -129.413)
		(end 85.265768 -129.794)
		(width 0.14224)
		(layer "In11.Cu")
		(net "M_K_MA<9>")
	)
	(segment
		(start 86.253828 -124.290328)
		(end 86.985602 -125.022102)
		(width 0.14224)
		(layer "In11.Cu")
		(net "M_K_MA<9>")
	)
	(segment
		(start 85.418168 -129.9464)
		(end 85.418168 -130.5306)
		(width 0.14224)
		(layer "In11.Cu")
		(net "M_K_MA<9>")
	)
	(segment
		(start 87.963502 -122.55119)
		(end 87.646002 -122.55119)
		(width 0.14224)
		(layer "In11.Cu")
		(net "M_K_MA<9>")
	)
	(segment
		(start 85.291168 -131.270248)
		(end 84.949538 -131.611878)
		(width 0.14224)
		(layer "In11.Cu")
		(net "M_K_MA<9>")
	)
	(segment
		(start 84.949538 -134.369302)
		(end 84.949284 -134.369556)
		(width 0.14224)
		(layer "In11.Cu")
		(net "M_K_MA<9>")
	)
	(segment
		(start 88.597994 -123.185682)
		(end 87.963502 -122.55119)
		(width 0.14224)
		(layer "In11.Cu")
		(net "M_K_MA<9>")
	)
	(segment
		(start 86.418928 -125.632972)
		(end 86.131654 -125.345698)
		(width 0.14224)
		(layer "In11.Cu")
		(net "M_K_MA<9>")
	)
	(segment
		(start 88.169242 -123.906534)
		(end 88.169242 -124.156724)
		(width 0.14224)
		(layer "In11.Cu")
		(net "M_K_MA<9>")
	)
	(segment
		(start 85.633814 -125.64237)
		(end 85.633814 -125.969522)
		(width 0.14224)
		(layer "In11.Cu")
		(net "M_K_MA<9>")
	)
	(segment
		(start 88.169242 -124.156724)
		(end 87.881968 -124.443998)
		(width 0.14224)
		(layer "In11.Cu")
		(net "M_K_MA<9>")
	)
	(segment
		(start 88.914986 -122.265948)
		(end 89.177368 -122.52833)
		(width 0.14224)
		(layer "In11.Cu")
		(net "M_K_MA<9>")
	)
	(segment
		(start 85.265768 -129.794)
		(end 85.418168 -129.9464)
		(width 0.14224)
		(layer "In11.Cu")
		(net "M_K_MA<9>")
	)
	(segment
		(start 87.881968 -124.443998)
		(end 87.557102 -124.443998)
		(width 0.14224)
		(layer "In11.Cu")
		(net "M_K_MA<9>")
	)
	(segment
		(start 87.557102 -124.443998)
		(end 86.837012 -123.723908)
		(width 0.14224)
		(layer "In11.Cu")
		(net "M_K_MA<9>")
	)
	(segment
		(start 87.358728 -122.838464)
		(end 87.358728 -123.09602)
		(width 0.14224)
		(layer "In11.Cu")
		(net "M_K_MA<9>")
	)
	(segment
		(start 86.368128 -126.703836)
		(end 86.368128 -128.31064)
		(width 0.14224)
		(layer "In11.Cu")
		(net "M_K_MA<9>")
	)
	(segment
		(start 89.177368 -102.3366)
		(end 89.177368 -121.5263)
		(width 0.14224)
		(layer "In11.Cu")
		(net "M_K_MA<9>")
	)
	(segment
		(start 86.698328 -125.632972)
		(end 86.418928 -125.632972)
		(width 0.14224)
		(layer "In11.Cu")
		(net "M_K_MA<9>")
	)
	(segment
		(start 88.91524 -123.185682)
		(end 88.597994 -123.185682)
		(width 0.14224)
		(layer "In11.Cu")
		(net "M_K_MA<9>")
	)
	(segment
		(start 88.914986 -121.788682)
		(end 88.914986 -122.265948)
		(width 0.14224)
		(layer "In11.Cu")
		(net "M_K_MA<9>")
	)
	(segment
		(start 89.202768 -102.3112)
		(end 89.177368 -102.3366)
		(width 0.14224)
		(layer "In11.Cu")
		(net "M_K_MA<9>")
	)
	(segment
		(start 86.368128 -128.31064)
		(end 85.265768 -129.413)
		(width 0.14224)
		(layer "In11.Cu")
		(net "M_K_MA<9>")
	)
	(segment
		(start 86.985602 -125.345698)
		(end 86.698328 -125.632972)
		(width 0.14224)
		(layer "In11.Cu")
		(net "M_K_MA<9>")
	)
	(segment
		(start 84.949538 -131.611878)
		(end 84.949538 -134.369302)
		(width 0.14224)
		(layer "In11.Cu")
		(net "M_K_MA<9>")
	)
	(segment
		(start 89.177368 -121.5263)
		(end 88.914986 -121.788682)
		(width 0.14224)
		(layer "In11.Cu")
		(net "M_K_MA<9>")
	)
	(segment
		(start 85.291168 -130.6576)
		(end 85.291168 -131.270248)
		(width 0.14224)
		(layer "In11.Cu")
		(net "M_K_MA<9>")
	)
	(segment
		(start 86.131654 -125.345698)
		(end 85.930486 -125.345698)
		(width 0.14224)
		(layer "In11.Cu")
		(net "M_K_MA<9>")
	)
	(segment
		(start 85.930486 -125.345698)
		(end 85.633814 -125.64237)
		(width 0.14224)
		(layer "In11.Cu")
		(net "M_K_MA<9>")
	)
	(segment
		(start 86.408768 -126.0856)
		(end 86.408768 -129.667)
		(width 0.1651)
		(layer "F.Cu")
		(net "M_K_MA<8>")
	)
	(segment
		(start 86.408768 -129.667)
		(end 86.180168 -129.8956)
		(width 0.1651)
		(layer "F.Cu")
		(net "M_K_MA<8>")
	)
	(segment
		(start 90.388186 -103.54691)
		(end 90.388186 -103.828596)
		(width 0.0889)
		(layer "F.Cu")
		(net "M_K_MA<8>")
	)
	(segment
		(start 90.388186 -115.409218)
		(end 86.619334 -119.17807)
		(width 0.1651)
		(layer "F.Cu")
		(net "M_K_MA<8>")
	)
	(segment
		(start 89.80297 -102.961694)
		(end 90.388186 -103.54691)
		(width 0.0889)
		(layer "F.Cu")
		(net "M_K_MA<8>")
	)
	(segment
		(start 86.619334 -119.17807)
		(end 86.619334 -125.875034)
		(width 0.1651)
		(layer "F.Cu")
		(net "M_K_MA<8>")
	)
	(segment
		(start 86.180168 -129.8956)
		(end 86.180168 -130.474466)
		(width 0.1651)
		(layer "F.Cu")
		(net "M_K_MA<8>")
	)
	(segment
		(start 86.180168 -130.474466)
		(end 86.64956 -130.943858)
		(width 0.1651)
		(layer "F.Cu")
		(net "M_K_MA<8>")
	)
	(segment
		(start 90.388186 -103.828596)
		(end 90.388186 -115.409218)
		(width 0.1651)
		(layer "F.Cu")
		(net "M_K_MA<8>")
	)
	(segment
		(start 86.619334 -125.875034)
		(end 86.408768 -126.0856)
		(width 0.1651)
		(layer "F.Cu")
		(net "M_K_MA<8>")
	)
	(segment
		(start 86.64956 -130.943858)
		(end 86.64956 -131.611878)
		(width 0.1651)
		(layer "F.Cu")
		(net "M_K_MA<8>")
	)
	(segment
		(start 89.80297 -101.654356)
		(end 89.80297 -102.961694)
		(width 0.0889)
		(layer "F.Cu")
		(net "M_K_MA<8>")
	)
	(segment
		(start 86.64956 -133.0706)
		(end 86.64956 -134.371588)
		(width 0.1651)
		(layer "F.Cu")
		(net "M_K_MA<8>")
	)
	(via
		(at 86.64956 -134.371588)
		(size 0.4572)
		(drill 0.2032)
		(layers "F.Cu" "B.Cu")
		(net "M_K_MA<8>")
	)
	(via
		(at 86.64956 -131.611878)
		(size 0.508)
		(drill 0.254)
		(layers "F.Cu" "B.Cu")
		(net "M_K_MA<8>")
	)
	(arc
		(start 90.928698 -99.67214)
		(mid 90.653353 -100.005294)
		(end 90.416888 -100.367084)
		(width 0.0889)
		(layer "F.Cu")
		(net "M_K_MA<8>")
	)
	(arc
		(start 89.723722 -100.958142)
		(mid 89.675974 -101.164039)
		(end 89.730072 -101.368352)
		(width 0.0889)
		(layer "F.Cu")
		(net "M_K_MA<8>")
	)
	(arc
		(start 90.416888 -100.367084)
		(mid 90.329909 -100.471664)
		(end 90.212926 -100.541074)
		(width 0.0889)
		(layer "F.Cu")
		(net "M_K_MA<8>")
	)
	(arc
		(start 89.730072 -101.368352)
		(mid 89.784688 -101.506727)
		(end 89.80297 -101.654356)
		(width 0.0889)
		(layer "F.Cu")
		(net "M_K_MA<8>")
	)
	(arc
		(start 90.212926 -100.541074)
		(mid 89.932393 -100.707464)
		(end 89.723722 -100.958142)
		(width 0.0889)
		(layer "F.Cu")
		(net "M_K_MA<8>")
	)
	(segment
		(start 86.64956 -132.876036)
		(end 86.64956 -131.611878)
		(width 0.1651)
		(layer "B.Cu")
		(net "M_K_MA<8>")
	)
	(segment
		(start 85.538818 -133.771894)
		(end 86.049866 -133.771894)
		(width 0.14224)
		(layer "In9.Cu")
		(net "M_K_MA<8>")
	)
	(segment
		(start 85.559646 -131.479798)
		(end 85.406992 -131.632452)
		(width 0.14224)
		(layer "In9.Cu")
		(net "M_K_MA<8>")
	)
	(segment
		(start 84.943696 -132.214874)
		(end 84.943696 -132.46354)
		(width 0.14224)
		(layer "In9.Cu")
		(net "M_K_MA<8>")
	)
	(segment
		(start 86.156546 -132.649214)
		(end 86.311486 -132.804154)
		(width 0.14224)
		(layer "In9.Cu")
		(net "M_K_MA<8>")
	)
	(segment
		(start 85.968332 -131.94157)
		(end 85.968332 -131.637024)
		(width 0.14224)
		(layer "In9.Cu")
		(net "M_K_MA<8>")
	)
	(segment
		(start 86.64956 -131.611878)
		(end 86.64956 -131.926584)
		(width 0.14224)
		(layer "In9.Cu")
		(net "M_K_MA<8>")
	)
	(segment
		(start 86.049866 -133.771894)
		(end 86.64956 -134.371588)
		(width 0.14224)
		(layer "In9.Cu")
		(net "M_K_MA<8>")
	)
	(segment
		(start 85.511894 -133.210554)
		(end 85.370416 -133.352032)
		(width 0.14224)
		(layer "In9.Cu")
		(net "M_K_MA<8>")
	)
	(segment
		(start 86.114636 -132.087874)
		(end 85.968332 -131.94157)
		(width 0.14224)
		(layer "In9.Cu")
		(net "M_K_MA<8>")
	)
	(segment
		(start 86.64956 -131.926584)
		(end 86.48827 -132.087874)
		(width 0.14224)
		(layer "In9.Cu")
		(net "M_K_MA<8>")
	)
	(segment
		(start 86.311486 -132.804154)
		(end 86.311486 -133.055614)
		(width 0.14224)
		(layer "In9.Cu")
		(net "M_K_MA<8>")
	)
	(segment
		(start 84.943696 -132.46354)
		(end 85.12937 -132.649214)
		(width 0.14224)
		(layer "In9.Cu")
		(net "M_K_MA<8>")
	)
	(segment
		(start 85.968332 -131.637024)
		(end 85.811106 -131.479798)
		(width 0.14224)
		(layer "In9.Cu")
		(net "M_K_MA<8>")
	)
	(segment
		(start 85.070696 -132.087874)
		(end 84.943696 -132.214874)
		(width 0.14224)
		(layer "In9.Cu")
		(net "M_K_MA<8>")
	)
	(segment
		(start 86.48827 -132.087874)
		(end 86.114636 -132.087874)
		(width 0.14224)
		(layer "In9.Cu")
		(net "M_K_MA<8>")
	)
	(segment
		(start 85.406992 -131.94157)
		(end 85.260688 -132.087874)
		(width 0.14224)
		(layer "In9.Cu")
		(net "M_K_MA<8>")
	)
	(segment
		(start 85.406992 -131.632452)
		(end 85.406992 -131.94157)
		(width 0.14224)
		(layer "In9.Cu")
		(net "M_K_MA<8>")
	)
	(segment
		(start 85.12937 -132.649214)
		(end 86.156546 -132.649214)
		(width 0.14224)
		(layer "In9.Cu")
		(net "M_K_MA<8>")
	)
	(segment
		(start 86.311486 -133.055614)
		(end 86.156546 -133.210554)
		(width 0.14224)
		(layer "In9.Cu")
		(net "M_K_MA<8>")
	)
	(segment
		(start 86.156546 -133.210554)
		(end 85.511894 -133.210554)
		(width 0.14224)
		(layer "In9.Cu")
		(net "M_K_MA<8>")
	)
	(segment
		(start 85.811106 -131.479798)
		(end 85.559646 -131.479798)
		(width 0.14224)
		(layer "In9.Cu")
		(net "M_K_MA<8>")
	)
	(segment
		(start 85.370416 -133.352032)
		(end 85.370416 -133.603492)
		(width 0.14224)
		(layer "In9.Cu")
		(net "M_K_MA<8>")
	)
	(segment
		(start 85.260688 -132.087874)
		(end 85.070696 -132.087874)
		(width 0.14224)
		(layer "In9.Cu")
		(net "M_K_MA<8>")
	)
	(segment
		(start 85.370416 -133.603492)
		(end 85.538818 -133.771894)
		(width 0.14224)
		(layer "In9.Cu")
		(net "M_K_MA<8>")
	)
	(segment
		(start 89.856056 -115.197128)
		(end 85.964014 -119.08917)
		(width 0.1651)
		(layer "F.Cu")
		(net "M_K_MA<7>")
	)
	(segment
		(start 85.944202 -122.473466)
		(end 85.640418 -122.473466)
		(width 0.1651)
		(layer "F.Cu")
		(net "M_K_MA<7>")
	)
	(segment
		(start 89.611962 -103.260906)
		(end 89.856056 -103.505)
		(width 0.0889)
		(layer "F.Cu")
		(net "M_K_MA<7>")
	)
	(segment
		(start 86.101682 -125.51156)
		(end 85.799422 -125.81382)
		(width 0.1651)
		(layer "F.Cu")
		(net "M_K_MA<7>")
	)
	(segment
		(start 86.109302 -120.600216)
		(end 86.109302 -120.943116)
		(width 0.1651)
		(layer "F.Cu")
		(net "M_K_MA<7>")
	)
	(segment
		(start 85.702902 -123.819666)
		(end 85.537802 -123.984766)
		(width 0.1651)
		(layer "F.Cu")
		(net "M_K_MA<7>")
	)
	(segment
		(start 86.109302 -121.946416)
		(end 86.109302 -122.308366)
		(width 0.1651)
		(layer "F.Cu")
		(net "M_K_MA<7>")
	)
	(segment
		(start 89.856056 -103.726488)
		(end 89.856056 -115.197128)
		(width 0.1651)
		(layer "F.Cu")
		(net "M_K_MA<7>")
	)
	(segment
		(start 85.475064 -122.63882)
		(end 85.475064 -122.981466)
		(width 0.1651)
		(layer "F.Cu")
		(net "M_K_MA<7>")
	)
	(segment
		(start 85.702902 -124.492766)
		(end 85.846158 -124.492766)
		(width 0.1651)
		(layer "F.Cu")
		(net "M_K_MA<7>")
	)
	(segment
		(start 89.549478 -101.437948)
		(end 89.558368 -101.453188)
		(width 0.0889)
		(layer "F.Cu")
		(net "M_K_MA<7>")
	)
	(segment
		(start 85.964014 -119.08917)
		(end 85.964014 -120.454928)
		(width 0.1651)
		(layer "F.Cu")
		(net "M_K_MA<7>")
	)
	(segment
		(start 85.964014 -120.454928)
		(end 86.109302 -120.600216)
		(width 0.1651)
		(layer "F.Cu")
		(net "M_K_MA<7>")
	)
	(segment
		(start 86.101682 -124.74829)
		(end 86.101682 -125.51156)
		(width 0.1651)
		(layer "F.Cu")
		(net "M_K_MA<7>")
	)
	(segment
		(start 89.856056 -103.505)
		(end 89.856056 -103.726488)
		(width 0.0889)
		(layer "F.Cu")
		(net "M_K_MA<7>")
	)
	(segment
		(start 86.109302 -122.308366)
		(end 85.944202 -122.473466)
		(width 0.1651)
		(layer "F.Cu")
		(net "M_K_MA<7>")
	)
	(segment
		(start 85.944202 -123.819666)
		(end 85.702902 -123.819666)
		(width 0.1651)
		(layer "F.Cu")
		(net "M_K_MA<7>")
	)
	(segment
		(start 86.109302 -123.654566)
		(end 85.944202 -123.819666)
		(width 0.1651)
		(layer "F.Cu")
		(net "M_K_MA<7>")
	)
	(segment
		(start 85.944202 -121.781316)
		(end 86.109302 -121.946416)
		(width 0.1651)
		(layer "F.Cu")
		(net "M_K_MA<7>")
	)
	(segment
		(start 89.730072 -99.95662)
		(end 89.723722 -99.967288)
		(width 0.0889)
		(layer "F.Cu")
		(net "M_K_MA<7>")
	)
	(segment
		(start 85.640418 -122.473466)
		(end 85.475064 -122.63882)
		(width 0.1651)
		(layer "F.Cu")
		(net "M_K_MA<7>")
	)
	(segment
		(start 85.944202 -121.108216)
		(end 85.760052 -121.108216)
		(width 0.1651)
		(layer "F.Cu")
		(net "M_K_MA<7>")
	)
	(segment
		(start 85.799422 -136.387078)
		(end 85.799422 -137.67054)
		(width 0.1651)
		(layer "F.Cu")
		(net "M_K_MA<7>")
	)
	(segment
		(start 85.944202 -123.146566)
		(end 86.109302 -123.311666)
		(width 0.1651)
		(layer "F.Cu")
		(net "M_K_MA<7>")
	)
	(segment
		(start 85.475064 -122.981466)
		(end 85.640164 -123.146566)
		(width 0.1651)
		(layer "F.Cu")
		(net "M_K_MA<7>")
	)
	(segment
		(start 86.109302 -120.943116)
		(end 85.944202 -121.108216)
		(width 0.1651)
		(layer "F.Cu")
		(net "M_K_MA<7>")
	)
	(segment
		(start 85.537802 -123.984766)
		(end 85.537802 -124.327666)
		(width 0.1651)
		(layer "F.Cu")
		(net "M_K_MA<7>")
	)
	(segment
		(start 85.537802 -124.327666)
		(end 85.702902 -124.492766)
		(width 0.1651)
		(layer "F.Cu")
		(net "M_K_MA<7>")
	)
	(segment
		(start 89.611962 -101.658166)
		(end 89.611962 -103.260906)
		(width 0.0889)
		(layer "F.Cu")
		(net "M_K_MA<7>")
	)
	(segment
		(start 85.846158 -124.492766)
		(end 86.101682 -124.74829)
		(width 0.1651)
		(layer "F.Cu")
		(net "M_K_MA<7>")
	)
	(segment
		(start 85.640164 -123.146566)
		(end 85.944202 -123.146566)
		(width 0.1651)
		(layer "F.Cu")
		(net "M_K_MA<7>")
	)
	(segment
		(start 86.109302 -123.311666)
		(end 86.109302 -123.654566)
		(width 0.1651)
		(layer "F.Cu")
		(net "M_K_MA<7>")
	)
	(segment
		(start 85.760052 -121.781316)
		(end 85.944202 -121.781316)
		(width 0.1651)
		(layer "F.Cu")
		(net "M_K_MA<7>")
	)
	(segment
		(start 85.799422 -125.81382)
		(end 85.799422 -129.539746)
		(width 0.1651)
		(layer "F.Cu")
		(net "M_K_MA<7>")
	)
	(segment
		(start 85.594952 -121.616216)
		(end 85.760052 -121.781316)
		(width 0.1651)
		(layer "F.Cu")
		(net "M_K_MA<7>")
	)
	(segment
		(start 85.760052 -121.108216)
		(end 85.594952 -121.273316)
		(width 0.1651)
		(layer "F.Cu")
		(net "M_K_MA<7>")
	)
	(segment
		(start 85.594952 -121.273316)
		(end 85.594952 -121.616216)
		(width 0.1651)
		(layer "F.Cu")
		(net "M_K_MA<7>")
	)
	(via
		(at 85.799422 -129.539746)
		(size 0.508)
		(drill 0.254)
		(layers "F.Cu" "B.Cu")
		(net "M_K_MA<7>")
	)
	(via
		(at 85.799422 -136.387078)
		(size 0.4572)
		(drill 0.2032)
		(layers "F.Cu" "B.Cu")
		(net "M_K_MA<7>")
	)
	(arc
		(start 89.558368 -101.453188)
		(mid 89.598998 -101.552063)
		(end 89.611962 -101.658166)
		(width 0.0889)
		(layer "F.Cu")
		(net "M_K_MA<7>")
	)
	(arc
		(start 90.070178 -99.17684)
		(mid 89.924654 -99.577429)
		(end 89.730072 -99.95662)
		(width 0.0889)
		(layer "F.Cu")
		(net "M_K_MA<7>")
	)
	(arc
		(start 89.723722 -99.967288)
		(mid 89.676065 -100.098876)
		(end 89.676732 -100.238814)
		(width 0.0889)
		(layer "F.Cu")
		(net "M_K_MA<7>")
	)
	(arc
		(start 89.558368 -100.862384)
		(mid 89.479179 -101.148999)
		(end 89.549478 -101.437948)
		(width 0.0889)
		(layer "F.Cu")
		(net "M_K_MA<7>")
	)
	(arc
		(start 89.676732 -100.238814)
		(mid 89.675557 -100.561617)
		(end 89.558368 -100.862384)
		(width 0.0889)
		(layer "F.Cu")
		(net "M_K_MA<7>")
	)
	(segment
		(start 85.799422 -128.276096)
		(end 85.799422 -129.539746)
		(width 0.1651)
		(layer "B.Cu")
		(net "M_K_MA<7>")
	)
	(segment
		(start 84.48675 -131.437126)
		(end 84.48675 -133.308598)
		(width 0.14224)
		(layer "In9.Cu")
		(net "M_K_MA<7>")
	)
	(segment
		(start 85.799422 -129.539746)
		(end 85.799422 -130.124454)
		(width 0.14224)
		(layer "In9.Cu")
		(net "M_K_MA<7>")
	)
	(segment
		(start 85.35797 -135.945626)
		(end 85.799422 -136.387078)
		(width 0.14224)
		(layer "In9.Cu")
		(net "M_K_MA<7>")
	)
	(segment
		(start 85.799422 -130.124454)
		(end 84.48675 -131.437126)
		(width 0.14224)
		(layer "In9.Cu")
		(net "M_K_MA<7>")
	)
	(segment
		(start 84.48675 -133.308598)
		(end 85.35797 -134.179818)
		(width 0.14224)
		(layer "In9.Cu")
		(net "M_K_MA<7>")
	)
	(segment
		(start 85.35797 -134.179818)
		(end 85.35797 -135.945626)
		(width 0.14224)
		(layer "In9.Cu")
		(net "M_K_MA<7>")
	)
	(segment
		(start 86.925404 -126.891796)
		(end 87.136224 -127.102616)
		(width 0.1651)
		(layer "F.Cu")
		(net "M_K_MA<6>")
	)
	(segment
		(start 87.136224 -128.448816)
		(end 87.136224 -128.989836)
		(width 0.1651)
		(layer "F.Cu")
		(net "M_K_MA<6>")
	)
	(segment
		(start 87.136224 -128.989836)
		(end 86.958424 -129.167636)
		(width 0.1651)
		(layer "F.Cu")
		(net "M_K_MA<6>")
	)
	(segment
		(start 86.958424 -129.759456)
		(end 87.616538 -130.41757)
		(width 0.1651)
		(layer "F.Cu")
		(net "M_K_MA<6>")
	)
	(segment
		(start 87.136224 -127.536194)
		(end 86.896702 -127.775716)
		(width 0.1651)
		(layer "F.Cu")
		(net "M_K_MA<6>")
	)
	(segment
		(start 87.616538 -130.785362)
		(end 87.499444 -130.902456)
		(width 0.1651)
		(layer "F.Cu")
		(net "M_K_MA<6>")
	)
	(segment
		(start 90.920316 -103.879904)
		(end 90.920316 -115.709446)
		(width 0.1651)
		(layer "F.Cu")
		(net "M_K_MA<6>")
	)
	(segment
		(start 86.958424 -129.167636)
		(end 86.958424 -129.759456)
		(width 0.1651)
		(layer "F.Cu")
		(net "M_K_MA<6>")
	)
	(segment
		(start 87.136224 -126.189994)
		(end 86.925404 -126.400814)
		(width 0.1651)
		(layer "F.Cu")
		(net "M_K_MA<6>")
	)
	(segment
		(start 86.896702 -127.775716)
		(end 86.896702 -128.209294)
		(width 0.1651)
		(layer "F.Cu")
		(net "M_K_MA<6>")
	)
	(segment
		(start 90.070178 -102.797864)
		(end 90.920316 -103.648002)
		(width 0.0889)
		(layer "F.Cu")
		(net "M_K_MA<6>")
	)
	(segment
		(start 86.925404 -126.400814)
		(end 86.925404 -126.891796)
		(width 0.1651)
		(layer "F.Cu")
		(net "M_K_MA<6>")
	)
	(segment
		(start 90.920316 -115.709446)
		(end 87.136224 -119.493538)
		(width 0.1651)
		(layer "F.Cu")
		(net "M_K_MA<6>")
	)
	(segment
		(start 87.136224 -127.102616)
		(end 87.136224 -127.536194)
		(width 0.1651)
		(layer "F.Cu")
		(net "M_K_MA<6>")
	)
	(segment
		(start 90.920316 -103.648002)
		(end 90.920316 -103.879904)
		(width 0.0889)
		(layer "F.Cu")
		(net "M_K_MA<6>")
	)
	(segment
		(start 86.896702 -128.209294)
		(end 87.136224 -128.448816)
		(width 0.1651)
		(layer "F.Cu")
		(net "M_K_MA<6>")
	)
	(segment
		(start 87.499444 -133.0706)
		(end 87.499444 -134.371588)
		(width 0.1651)
		(layer "F.Cu")
		(net "M_K_MA<6>")
	)
	(segment
		(start 87.616538 -130.41757)
		(end 87.616538 -130.785362)
		(width 0.1651)
		(layer "F.Cu")
		(net "M_K_MA<6>")
	)
	(segment
		(start 90.070178 -101.15804)
		(end 90.070178 -102.797864)
		(width 0.0889)
		(layer "F.Cu")
		(net "M_K_MA<6>")
	)
	(segment
		(start 87.136224 -119.493538)
		(end 87.136224 -126.189994)
		(width 0.1651)
		(layer "F.Cu")
		(net "M_K_MA<6>")
	)
	(via
		(at 87.499444 -130.902456)
		(size 0.508)
		(drill 0.254)
		(layers "F.Cu" "B.Cu")
		(net "M_K_MA<6>")
	)
	(via
		(at 87.499444 -134.371588)
		(size 0.4572)
		(drill 0.2032)
		(layers "F.Cu" "B.Cu")
		(net "M_K_MA<6>")
	)
	(segment
		(start 87.499444 -132.876036)
		(end 87.499444 -130.902456)
		(width 0.1651)
		(layer "B.Cu")
		(net "M_K_MA<6>")
	)
	(segment
		(start 88.612726 -132.298694)
		(end 88.457786 -132.143754)
		(width 0.14224)
		(layer "In9.Cu")
		(net "M_K_MA<6>")
	)
	(segment
		(start 88.597232 -133.417564)
		(end 88.446102 -133.266434)
		(width 0.14224)
		(layer "In9.Cu")
		(net "M_K_MA<6>")
	)
	(segment
		(start 87.499444 -131.988814)
		(end 87.499444 -131.741418)
		(width 0.14224)
		(layer "In9.Cu")
		(net "M_K_MA<6>")
	)
	(segment
		(start 88.612726 -132.550154)
		(end 88.612726 -132.298694)
		(width 0.14224)
		(layer "In9.Cu")
		(net "M_K_MA<6>")
	)
	(segment
		(start 87.812626 -131.215638)
		(end 87.499444 -130.902456)
		(width 0.14224)
		(layer "In9.Cu")
		(net "M_K_MA<6>")
	)
	(segment
		(start 88.446102 -133.266434)
		(end 87.37219 -133.266434)
		(width 0.14224)
		(layer "In9.Cu")
		(net "M_K_MA<6>")
	)
	(segment
		(start 87.20582 -133.100064)
		(end 87.20582 -132.848604)
		(width 0.14224)
		(layer "In9.Cu")
		(net "M_K_MA<6>")
	)
	(segment
		(start 87.812626 -131.428236)
		(end 87.812626 -131.215638)
		(width 0.14224)
		(layer "In9.Cu")
		(net "M_K_MA<6>")
	)
	(segment
		(start 87.654384 -132.143754)
		(end 87.499444 -131.988814)
		(width 0.14224)
		(layer "In9.Cu")
		(net "M_K_MA<6>")
	)
	(segment
		(start 87.627968 -133.827774)
		(end 88.438482 -133.827774)
		(width 0.14224)
		(layer "In9.Cu")
		(net "M_K_MA<6>")
	)
	(segment
		(start 88.438482 -133.827774)
		(end 88.597232 -133.669024)
		(width 0.14224)
		(layer "In9.Cu")
		(net "M_K_MA<6>")
	)
	(segment
		(start 87.499444 -133.956298)
		(end 87.627968 -133.827774)
		(width 0.14224)
		(layer "In9.Cu")
		(net "M_K_MA<6>")
	)
	(segment
		(start 87.37219 -133.266434)
		(end 87.20582 -133.100064)
		(width 0.14224)
		(layer "In9.Cu")
		(net "M_K_MA<6>")
	)
	(segment
		(start 87.499444 -131.741418)
		(end 87.812626 -131.428236)
		(width 0.14224)
		(layer "In9.Cu")
		(net "M_K_MA<6>")
	)
	(segment
		(start 87.20582 -132.848604)
		(end 87.34933 -132.705094)
		(width 0.14224)
		(layer "In9.Cu")
		(net "M_K_MA<6>")
	)
	(segment
		(start 88.597232 -133.669024)
		(end 88.597232 -133.417564)
		(width 0.14224)
		(layer "In9.Cu")
		(net "M_K_MA<6>")
	)
	(segment
		(start 87.499444 -134.371588)
		(end 87.499444 -133.956298)
		(width 0.14224)
		(layer "In9.Cu")
		(net "M_K_MA<6>")
	)
	(segment
		(start 87.34933 -132.705094)
		(end 88.457786 -132.705094)
		(width 0.14224)
		(layer "In9.Cu")
		(net "M_K_MA<6>")
	)
	(segment
		(start 88.457786 -132.705094)
		(end 88.612726 -132.550154)
		(width 0.14224)
		(layer "In9.Cu")
		(net "M_K_MA<6>")
	)
	(segment
		(start 88.457786 -132.143754)
		(end 87.654384 -132.143754)
		(width 0.14224)
		(layer "In9.Cu")
		(net "M_K_MA<6>")
	)
	(segment
		(start 91.452446 -103.824278)
		(end 91.452446 -104.029764)
		(width 0.0889)
		(layer "F.Cu")
		(net "M_K_MA<5>")
	)
	(segment
		(start 91.787218 -99.17684)
		(end 91.285568 -99.8474)
		(width 0.0889)
		(layer "F.Cu")
		(net "M_K_MA<5>")
	)
	(segment
		(start 90.528394 -100.6602)
		(end 90.450162 -101.271324)
		(width 0.0889)
		(layer "F.Cu")
		(net "M_K_MA<5>")
	)
	(segment
		(start 91.056968 -100.076)
		(end 90.714068 -100.324666)
		(width 0.0889)
		(layer "F.Cu")
		(net "M_K_MA<5>")
	)
	(segment
		(start 87.662004 -119.728996)
		(end 87.662004 -129.406396)
		(width 0.1651)
		(layer "F.Cu")
		(net "M_K_MA<5>")
	)
	(segment
		(start 90.345768 -101.4222)
		(end 90.320368 -101.4984)
		(width 0.0889)
		(layer "F.Cu")
		(net "M_K_MA<5>")
	)
	(segment
		(start 90.320368 -102.6922)
		(end 91.452446 -103.824278)
		(width 0.0889)
		(layer "F.Cu")
		(net "M_K_MA<5>")
	)
	(segment
		(start 87.499444 -136.387078)
		(end 87.499444 -137.67054)
		(width 0.1651)
		(layer "F.Cu")
		(net "M_K_MA<5>")
	)
	(segment
		(start 87.662004 -129.406396)
		(end 87.499444 -129.568956)
		(width 0.1651)
		(layer "F.Cu")
		(net "M_K_MA<5>")
	)
	(segment
		(start 91.452446 -115.938554)
		(end 87.662004 -119.728996)
		(width 0.1651)
		(layer "F.Cu")
		(net "M_K_MA<5>")
	)
	(segment
		(start 91.285568 -99.8474)
		(end 91.056968 -100.076)
		(width 0.0889)
		(layer "F.Cu")
		(net "M_K_MA<5>")
	)
	(segment
		(start 91.452446 -104.029764)
		(end 91.452446 -115.938554)
		(width 0.1651)
		(layer "F.Cu")
		(net "M_K_MA<5>")
	)
	(segment
		(start 90.320368 -101.4984)
		(end 90.320368 -102.6922)
		(width 0.0889)
		(layer "F.Cu")
		(net "M_K_MA<5>")
	)
	(via
		(at 87.499444 -129.568956)
		(size 0.508)
		(drill 0.254)
		(layers "F.Cu" "B.Cu")
		(net "M_K_MA<5>")
	)
	(via
		(at 87.499444 -136.387078)
		(size 0.4572)
		(drill 0.2032)
		(layers "F.Cu" "B.Cu")
		(net "M_K_MA<5>")
	)
	(arc
		(start 90.450162 -101.271324)
		(mid 90.402191 -101.349686)
		(end 90.345768 -101.4222)
		(width 0.0889)
		(layer "F.Cu")
		(net "M_K_MA<5>")
	)
	(arc
		(start 90.714068 -100.324666)
		(mid 90.578471 -100.46876)
		(end 90.528394 -100.6602)
		(width 0.0889)
		(layer "F.Cu")
		(net "M_K_MA<5>")
	)
	(segment
		(start 87.499444 -128.276096)
		(end 87.499444 -129.568956)
		(width 0.1651)
		(layer "B.Cu")
		(net "M_K_MA<5>")
	)
	(segment
		(start 87.499444 -135.177276)
		(end 87.070946 -134.748778)
		(width 0.14224)
		(layer "In9.Cu")
		(net "M_K_MA<5>")
	)
	(segment
		(start 87.018368 -131.2164)
		(end 87.018368 -130.730244)
		(width 0.14224)
		(layer "In9.Cu")
		(net "M_K_MA<5>")
	)
	(segment
		(start 86.789768 -133.7437)
		(end 86.789768 -132.543296)
		(width 0.14224)
		(layer "In9.Cu")
		(net "M_K_MA<5>")
	)
	(segment
		(start 87.499444 -136.387078)
		(end 87.499444 -135.177276)
		(width 0.14224)
		(layer "In9.Cu")
		(net "M_K_MA<5>")
	)
	(segment
		(start 87.089996 -132.243068)
		(end 87.089996 -131.288028)
		(width 0.14224)
		(layer "In9.Cu")
		(net "M_K_MA<5>")
	)
	(segment
		(start 86.789768 -132.543296)
		(end 87.089996 -132.243068)
		(width 0.14224)
		(layer "In9.Cu")
		(net "M_K_MA<5>")
	)
	(segment
		(start 87.070946 -134.748778)
		(end 87.070946 -134.024878)
		(width 0.14224)
		(layer "In9.Cu")
		(net "M_K_MA<5>")
	)
	(segment
		(start 87.089996 -131.288028)
		(end 87.018368 -131.2164)
		(width 0.14224)
		(layer "In9.Cu")
		(net "M_K_MA<5>")
	)
	(segment
		(start 87.018368 -130.730244)
		(end 87.499444 -129.568956)
		(width 0.14224)
		(layer "In9.Cu")
		(net "M_K_MA<5>")
	)
	(segment
		(start 87.070946 -134.024878)
		(end 86.789768 -133.7437)
		(width 0.14224)
		(layer "In9.Cu")
		(net "M_K_MA<5>")
	)
	(segment
		(start 90.59926 -101.42347)
		(end 90.581988 -101.453188)
		(width 0.0889)
		(layer "F.Cu")
		(net "M_K_MA<4>")
	)
	(segment
		(start 90.928698 -100.662486)
		(end 90.59926 -101.42347)
		(width 0.0889)
		(layer "F.Cu")
		(net "M_K_MA<4>")
	)
	(segment
		(start 91.984576 -103.950008)
		(end 91.984576 -104.142286)
		(width 0.0889)
		(layer "F.Cu")
		(net "M_K_MA<4>")
	)
	(segment
		(start 88.349582 -136.387078)
		(end 88.349582 -137.67054)
		(width 0.1651)
		(layer "F.Cu")
		(net "M_K_MA<4>")
	)
	(segment
		(start 91.984576 -104.142286)
		(end 91.984576 -116.159026)
		(width 0.1651)
		(layer "F.Cu")
		(net "M_K_MA<4>")
	)
	(segment
		(start 88.208866 -119.934736)
		(end 88.208866 -130.108452)
		(width 0.1651)
		(layer "F.Cu")
		(net "M_K_MA<4>")
	)
	(segment
		(start 88.208866 -130.108452)
		(end 88.349582 -130.249168)
		(width 0.1651)
		(layer "F.Cu")
		(net "M_K_MA<4>")
	)
	(segment
		(start 90.527886 -101.652324)
		(end 90.527886 -102.493318)
		(width 0.0889)
		(layer "F.Cu")
		(net "M_K_MA<4>")
	)
	(segment
		(start 90.527886 -102.493318)
		(end 91.984576 -103.950008)
		(width 0.0889)
		(layer "F.Cu")
		(net "M_K_MA<4>")
	)
	(segment
		(start 91.984576 -116.159026)
		(end 88.208866 -119.934736)
		(width 0.1651)
		(layer "F.Cu")
		(net "M_K_MA<4>")
	)
	(via
		(at 88.349582 -130.249168)
		(size 0.508)
		(drill 0.254)
		(layers "F.Cu" "B.Cu")
		(net "M_K_MA<4>")
	)
	(via
		(at 88.349582 -136.387078)
		(size 0.4572)
		(drill 0.2032)
		(layers "F.Cu" "B.Cu")
		(net "M_K_MA<4>")
	)
	(arc
		(start 90.581988 -101.453188)
		(mid 90.541885 -101.549206)
		(end 90.527886 -101.652324)
		(width 0.0889)
		(layer "F.Cu")
		(net "M_K_MA<4>")
	)
	(segment
		(start 88.349582 -128.276096)
		(end 88.349582 -130.249168)
		(width 0.1651)
		(layer "B.Cu")
		(net "M_K_MA<4>")
	)
	(segment
		(start 88.720168 -130.619754)
		(end 88.720168 -131.1148)
		(width 0.14224)
		(layer "In9.Cu")
		(net "M_K_MA<4>")
	)
	(segment
		(start 89.033604 -131.428236)
		(end 89.033604 -133.940042)
		(width 0.14224)
		(layer "In9.Cu")
		(net "M_K_MA<4>")
	)
	(segment
		(start 89.033604 -133.940042)
		(end 88.783668 -134.189978)
		(width 0.14224)
		(layer "In9.Cu")
		(net "M_K_MA<4>")
	)
	(segment
		(start 88.720168 -131.1148)
		(end 89.033604 -131.428236)
		(width 0.14224)
		(layer "In9.Cu")
		(net "M_K_MA<4>")
	)
	(segment
		(start 88.349582 -130.249168)
		(end 88.720168 -130.619754)
		(width 0.14224)
		(layer "In9.Cu")
		(net "M_K_MA<4>")
	)
	(segment
		(start 88.349582 -135.752586)
		(end 88.349582 -136.387078)
		(width 0.14224)
		(layer "In9.Cu")
		(net "M_K_MA<4>")
	)
	(segment
		(start 88.783668 -135.3185)
		(end 88.349582 -135.752586)
		(width 0.14224)
		(layer "In9.Cu")
		(net "M_K_MA<4>")
	)
	(segment
		(start 88.783668 -134.189978)
		(end 88.783668 -135.3185)
		(width 0.14224)
		(layer "In9.Cu")
		(net "M_K_MA<4>")
	)
	(segment
		(start 91.269058 -101.44252)
		(end 91.275408 -101.453188)
		(width 0.0889)
		(layer "F.Cu")
		(net "M_K_MA<3>")
	)
	(segment
		(start 88.713056 -120.159526)
		(end 88.713056 -129.209038)
		(width 0.1651)
		(layer "F.Cu")
		(net "M_K_MA<3>")
	)
	(segment
		(start 92.645738 -99.67214)
		(end 92.133928 -100.367084)
		(width 0.0889)
		(layer "F.Cu")
		(net "M_K_MA<3>")
	)
	(segment
		(start 91.329002 -101.653848)
		(end 91.329002 -102.761034)
		(width 0.0889)
		(layer "F.Cu")
		(net "M_K_MA<3>")
	)
	(segment
		(start 88.652858 -129.269236)
		(end 88.652858 -129.86385)
		(width 0.1651)
		(layer "F.Cu")
		(net "M_K_MA<3>")
	)
	(segment
		(start 88.911684 -130.122676)
		(end 88.911684 -130.614674)
		(width 0.1651)
		(layer "F.Cu")
		(net "M_K_MA<3>")
	)
	(segment
		(start 88.911684 -130.614674)
		(end 89.199466 -130.902456)
		(width 0.1651)
		(layer "F.Cu")
		(net "M_K_MA<3>")
	)
	(segment
		(start 92.516706 -116.355876)
		(end 88.713056 -120.159526)
		(width 0.1651)
		(layer "F.Cu")
		(net "M_K_MA<3>")
	)
	(segment
		(start 88.713056 -129.209038)
		(end 88.652858 -129.269236)
		(width 0.1651)
		(layer "F.Cu")
		(net "M_K_MA<3>")
	)
	(segment
		(start 92.516706 -104.176322)
		(end 92.516706 -116.355876)
		(width 0.1651)
		(layer "F.Cu")
		(net "M_K_MA<3>")
	)
	(segment
		(start 91.275408 -101.453188)
		(end 91.280234 -101.461824)
		(width 0.0889)
		(layer "F.Cu")
		(net "M_K_MA<3>")
	)
	(segment
		(start 92.516706 -103.948738)
		(end 92.516706 -104.176322)
		(width 0.0889)
		(layer "F.Cu")
		(net "M_K_MA<3>")
	)
	(segment
		(start 89.199466 -133.0706)
		(end 89.199466 -134.371588)
		(width 0.1651)
		(layer "F.Cu")
		(net "M_K_MA<3>")
	)
	(segment
		(start 91.798394 -100.567236)
		(end 91.774264 -100.567236)
		(width 0.0889)
		(layer "F.Cu")
		(net "M_K_MA<3>")
	)
	(segment
		(start 91.329002 -102.761034)
		(end 92.516706 -103.948738)
		(width 0.0889)
		(layer "F.Cu")
		(net "M_K_MA<3>")
	)
	(segment
		(start 88.652858 -129.86385)
		(end 88.911684 -130.122676)
		(width 0.1651)
		(layer "F.Cu")
		(net "M_K_MA<3>")
	)
	(via
		(at 89.199466 -134.371588)
		(size 0.4572)
		(drill 0.2032)
		(layers "F.Cu" "B.Cu")
		(net "M_K_MA<3>")
	)
	(via
		(at 89.199466 -130.902456)
		(size 0.508)
		(drill 0.254)
		(layers "F.Cu" "B.Cu")
		(net "M_K_MA<3>")
	)
	(arc
		(start 91.774264 -100.567236)
		(mid 91.275383 -100.862673)
		(end 91.269058 -101.44252)
		(width 0.0889)
		(layer "F.Cu")
		(net "M_K_MA<3>")
	)
	(arc
		(start 91.280234 -101.461824)
		(mid 91.316693 -101.55477)
		(end 91.329002 -101.653848)
		(width 0.0889)
		(layer "F.Cu")
		(net "M_K_MA<3>")
	)
	(arc
		(start 92.133928 -100.367084)
		(mid 91.992245 -100.510888)
		(end 91.798394 -100.567236)
		(width 0.0889)
		(layer "F.Cu")
		(net "M_K_MA<3>")
	)
	(segment
		(start 89.199466 -132.876036)
		(end 89.199466 -130.902456)
		(width 0.1651)
		(layer "B.Cu")
		(net "M_K_MA<3>")
	)
	(segment
		(start 89.199466 -130.902456)
		(end 89.46388 -131.16687)
		(width 0.14224)
		(layer "In9.Cu")
		(net "M_K_MA<3>")
	)
	(segment
		(start 89.46388 -131.16687)
		(end 89.46388 -134.107174)
		(width 0.14224)
		(layer "In9.Cu")
		(net "M_K_MA<3>")
	)
	(segment
		(start 89.46388 -134.107174)
		(end 89.199466 -134.371588)
		(width 0.14224)
		(layer "In9.Cu")
		(net "M_K_MA<3>")
	)
	(segment
		(start 93.580966 -104.123998)
		(end 93.580966 -104.336596)
		(width 0.0889)
		(layer "F.Cu")
		(net "M_K_MA<2>")
	)
	(segment
		(start 89.849706 -123.005342)
		(end 89.849706 -123.929902)
		(width 0.1651)
		(layer "F.Cu")
		(net "M_K_MA<2>")
	)
	(segment
		(start 91.787218 -101.15804)
		(end 91.787218 -102.33025)
		(width 0.0889)
		(layer "F.Cu")
		(net "M_K_MA<2>")
	)
	(segment
		(start 90.04935 -136.412732)
		(end 90.049604 -136.412478)
		(width 0.1651)
		(layer "F.Cu")
		(net "M_K_MA<2>")
	)
	(segment
		(start 90.04935 -137.67054)
		(end 90.04935 -136.412732)
		(width 0.1651)
		(layer "F.Cu")
		(net "M_K_MA<2>")
	)
	(segment
		(start 89.849706 -123.929902)
		(end 90.168476 -124.248672)
		(width 0.1651)
		(layer "F.Cu")
		(net "M_K_MA<2>")
	)
	(segment
		(start 89.849706 -126.670054)
		(end 90.121232 -126.94158)
		(width 0.1651)
		(layer "F.Cu")
		(net "M_K_MA<2>")
	)
	(segment
		(start 90.121232 -128.59131)
		(end 89.993978 -128.718564)
		(width 0.1651)
		(layer "F.Cu")
		(net "M_K_MA<2>")
	)
	(segment
		(start 89.993978 -128.718564)
		(end 89.993978 -130.249168)
		(width 0.1651)
		(layer "F.Cu")
		(net "M_K_MA<2>")
	)
	(segment
		(start 89.849706 -125.613922)
		(end 89.849706 -126.670054)
		(width 0.1651)
		(layer "F.Cu")
		(net "M_K_MA<2>")
	)
	(segment
		(start 90.121232 -126.94158)
		(end 90.121232 -128.59131)
		(width 0.1651)
		(layer "F.Cu")
		(net "M_K_MA<2>")
	)
	(segment
		(start 91.787218 -102.33025)
		(end 93.580966 -104.123998)
		(width 0.0889)
		(layer "F.Cu")
		(net "M_K_MA<2>")
	)
	(segment
		(start 93.580966 -104.336596)
		(end 93.580966 -116.838476)
		(width 0.1651)
		(layer "F.Cu")
		(net "M_K_MA<2>")
	)
	(segment
		(start 90.168476 -125.295152)
		(end 89.849706 -125.613922)
		(width 0.1651)
		(layer "F.Cu")
		(net "M_K_MA<2>")
	)
	(segment
		(start 90.168476 -124.248672)
		(end 90.168476 -125.295152)
		(width 0.1651)
		(layer "F.Cu")
		(net "M_K_MA<2>")
	)
	(segment
		(start 93.580966 -116.838476)
		(end 90.264742 -120.1547)
		(width 0.1651)
		(layer "F.Cu")
		(net "M_K_MA<2>")
	)
	(segment
		(start 90.264742 -120.1547)
		(end 90.264742 -122.590306)
		(width 0.1651)
		(layer "F.Cu")
		(net "M_K_MA<2>")
	)
	(segment
		(start 90.049604 -136.412478)
		(end 90.049604 -136.387078)
		(width 0.1651)
		(layer "F.Cu")
		(net "M_K_MA<2>")
	)
	(segment
		(start 90.264742 -122.590306)
		(end 89.849706 -123.005342)
		(width 0.1651)
		(layer "F.Cu")
		(net "M_K_MA<2>")
	)
	(via
		(at 89.993978 -130.249168)
		(size 0.508)
		(drill 0.254)
		(layers "F.Cu" "B.Cu")
		(net "M_K_MA<2>")
	)
	(via
		(at 90.049604 -136.387078)
		(size 0.4572)
		(drill 0.2032)
		(layers "F.Cu" "B.Cu")
		(net "M_K_MA<2>")
	)
	(segment
		(start 90.04935 -128.276096)
		(end 90.04935 -130.193796)
		(width 0.1651)
		(layer "B.Cu")
		(net "M_K_MA<2>")
	)
	(segment
		(start 90.04935 -130.193796)
		(end 89.993978 -130.249168)
		(width 0.1651)
		(layer "B.Cu")
		(net "M_K_MA<2>")
	)
	(segment
		(start 90.717116 -130.91668)
		(end 90.049604 -130.249168)
		(width 0.14224)
		(layer "In9.Cu")
		(net "M_K_MA<2>")
	)
	(segment
		(start 90.464132 -134.077964)
		(end 90.717116 -133.82498)
		(width 0.14224)
		(layer "In9.Cu")
		(net "M_K_MA<2>")
	)
	(segment
		(start 90.464132 -134.763764)
		(end 90.464132 -134.077964)
		(width 0.14224)
		(layer "In9.Cu")
		(net "M_K_MA<2>")
	)
	(segment
		(start 90.049604 -130.249168)
		(end 89.993978 -130.249168)
		(width 0.14224)
		(layer "In9.Cu")
		(net "M_K_MA<2>")
	)
	(segment
		(start 90.04935 -135.178546)
		(end 90.464132 -134.763764)
		(width 0.14224)
		(layer "In9.Cu")
		(net "M_K_MA<2>")
	)
	(segment
		(start 90.717116 -133.82498)
		(end 90.717116 -130.91668)
		(width 0.14224)
		(layer "In9.Cu")
		(net "M_K_MA<2>")
	)
	(segment
		(start 90.04935 -136.386824)
		(end 90.04935 -135.178546)
		(width 0.14224)
		(layer "In9.Cu")
		(net "M_K_MA<2>")
	)
	(segment
		(start 90.049604 -136.387078)
		(end 90.04935 -136.386824)
		(width 0.14224)
		(layer "In9.Cu")
		(net "M_K_MA<2>")
	)
	(segment
		(start 89.685368 -127.297688)
		(end 89.685368 -127.88011)
		(width 0.1651)
		(layer "F.Cu")
		(net "M_K_MA<1>")
	)
	(segment
		(start 89.464388 -130.04038)
		(end 89.464388 -130.468116)
		(width 0.1651)
		(layer "F.Cu")
		(net "M_K_MA<1>")
	)
	(segment
		(start 89.706196 -131.26847)
		(end 90.049604 -131.611878)
		(width 0.1651)
		(layer "F.Cu")
		(net "M_K_MA<1>")
	)
	(segment
		(start 89.706196 -130.709924)
		(end 89.706196 -131.26847)
		(width 0.1651)
		(layer "F.Cu")
		(net "M_K_MA<1>")
	)
	(segment
		(start 91.564968 -101.714808)
		(end 91.564968 -102.5398)
		(width 0.0889)
		(layer "F.Cu")
		(net "M_K_MA<1>")
	)
	(segment
		(start 92.645738 -100.662486)
		(end 91.86037 -100.753672)
		(width 0.0889)
		(layer "F.Cu")
		(net "M_K_MA<1>")
	)
	(segment
		(start 89.464388 -130.468116)
		(end 89.706196 -130.709924)
		(width 0.1651)
		(layer "F.Cu")
		(net "M_K_MA<1>")
	)
	(segment
		(start 89.33053 -128.234948)
		(end 89.33053 -128.87071)
		(width 0.1651)
		(layer "F.Cu")
		(net "M_K_MA<1>")
	)
	(segment
		(start 89.33053 -128.87071)
		(end 89.574878 -129.115058)
		(width 0.1651)
		(layer "F.Cu")
		(net "M_K_MA<1>")
	)
	(segment
		(start 90.04935 -133.0706)
		(end 90.04935 -134.371588)
		(width 0.1651)
		(layer "F.Cu")
		(net "M_K_MA<1>")
	)
	(segment
		(start 89.574878 -129.92989)
		(end 89.464388 -130.04038)
		(width 0.1651)
		(layer "F.Cu")
		(net "M_K_MA<1>")
	)
	(segment
		(start 91.800172 -100.75799)
		(end 91.772232 -100.75799)
		(width 0.0889)
		(layer "F.Cu")
		(net "M_K_MA<1>")
	)
	(segment
		(start 89.685368 -127.88011)
		(end 89.33053 -128.234948)
		(width 0.1651)
		(layer "F.Cu")
		(net "M_K_MA<1>")
	)
	(segment
		(start 93.048836 -104.023668)
		(end 93.048836 -104.271826)
		(width 0.0889)
		(layer "F.Cu")
		(net "M_K_MA<1>")
	)
	(segment
		(start 89.574878 -129.115058)
		(end 89.574878 -129.92989)
		(width 0.1651)
		(layer "F.Cu")
		(net "M_K_MA<1>")
	)
	(segment
		(start 89.32291 -126.93523)
		(end 89.685368 -127.297688)
		(width 0.1651)
		(layer "F.Cu")
		(net "M_K_MA<1>")
	)
	(segment
		(start 89.32291 -120.295162)
		(end 89.32291 -126.93523)
		(width 0.1651)
		(layer "F.Cu")
		(net "M_K_MA<1>")
	)
	(segment
		(start 91.564968 -102.5398)
		(end 93.048836 -104.023668)
		(width 0.0889)
		(layer "F.Cu")
		(net "M_K_MA<1>")
	)
	(segment
		(start 93.048836 -116.569236)
		(end 89.32291 -120.295162)
		(width 0.1651)
		(layer "F.Cu")
		(net "M_K_MA<1>")
	)
	(segment
		(start 93.048836 -104.271826)
		(end 93.048836 -116.569236)
		(width 0.1651)
		(layer "F.Cu")
		(net "M_K_MA<1>")
	)
	(via
		(at 90.049604 -131.611878)
		(size 0.508)
		(drill 0.254)
		(layers "F.Cu" "B.Cu")
		(net "M_K_MA<1>")
	)
	(via
		(at 90.04935 -134.371588)
		(size 0.4572)
		(drill 0.2032)
		(layers "F.Cu" "B.Cu")
		(net "M_K_MA<1>")
	)
	(arc
		(start 91.435682 -101.349302)
		(mid 91.531719 -101.520953)
		(end 91.564968 -101.714808)
		(width 0.0889)
		(layer "F.Cu")
		(net "M_K_MA<1>")
	)
	(arc
		(start 91.772232 -100.75799)
		(mid 91.439314 -100.959981)
		(end 91.435682 -101.349302)
		(width 0.0889)
		(layer "F.Cu")
		(net "M_K_MA<1>")
	)
	(arc
		(start 91.86037 -100.753672)
		(mid 91.830326 -100.756603)
		(end 91.800172 -100.75799)
		(width 0.0889)
		(layer "F.Cu")
		(net "M_K_MA<1>")
	)
	(segment
		(start 90.04935 -132.876036)
		(end 90.04935 -131.612132)
		(width 0.1651)
		(layer "B.Cu")
		(net "M_K_MA<1>")
	)
	(segment
		(start 90.04935 -131.612132)
		(end 90.049604 -131.611878)
		(width 0.1651)
		(layer "B.Cu")
		(net "M_K_MA<1>")
	)
	(segment
		(start 90.08491 -132.565648)
		(end 90.08491 -133.511036)
		(width 0.14224)
		(layer "In9.Cu")
		(net "M_K_MA<1>")
	)
	(segment
		(start 89.95156 -133.644386)
		(end 89.95156 -134.273798)
		(width 0.14224)
		(layer "In9.Cu")
		(net "M_K_MA<1>")
	)
	(segment
		(start 89.901776 -132.382514)
		(end 90.08491 -132.565648)
		(width 0.14224)
		(layer "In9.Cu")
		(net "M_K_MA<1>")
	)
	(segment
		(start 90.049604 -131.611878)
		(end 89.901776 -131.759706)
		(width 0.14224)
		(layer "In9.Cu")
		(net "M_K_MA<1>")
	)
	(segment
		(start 89.901776 -131.759706)
		(end 89.901776 -132.382514)
		(width 0.14224)
		(layer "In9.Cu")
		(net "M_K_MA<1>")
	)
	(segment
		(start 89.95156 -134.273798)
		(end 90.04935 -134.371588)
		(width 0.14224)
		(layer "In9.Cu")
		(net "M_K_MA<1>")
	)
	(segment
		(start 90.08491 -133.511036)
		(end 89.95156 -133.644386)
		(width 0.14224)
		(layer "In9.Cu")
		(net "M_K_MA<1>")
	)
	(segment
		(start 110.44936 -137.67054)
		(end 110.44936 -136.387586)
		(width 0.1651)
		(layer "F.Cu")
		(net "M_K_MA<17>")
	)
	(segment
		(start 110.44936 -136.387586)
		(end 110.449868 -136.387078)
		(width 0.1651)
		(layer "F.Cu")
		(net "M_K_MA<17>")
	)
	(segment
		(start 102.089204 -99.17684)
		(end 101.517704 -99.17684)
		(width 0.1651)
		(layer "F.Cu")
		(net "M_K_MA<17>")
	)
	(via
		(at 110.44936 -130.249168)
		(size 0.508)
		(drill 0.254)
		(layers "F.Cu" "B.Cu")
		(net "M_K_MA<17>")
	)
	(via
		(at 110.449868 -136.387078)
		(size 0.4572)
		(drill 0.2032)
		(layers "F.Cu" "B.Cu")
		(net "M_K_MA<17>")
	)
	(via
		(at 101.517704 -99.17684)
		(size 0.508)
		(drill 0.254)
		(layers "F.Cu" "B.Cu")
		(net "M_K_MA<17>")
	)
	(segment
		(start 110.44936 -128.276096)
		(end 110.44936 -130.249168)
		(width 0.1651)
		(layer "B.Cu")
		(net "M_K_MA<17>")
	)
	(segment
		(start 106.120184 -122.174508)
		(end 106.300524 -122.174254)
		(width 0.14224)
		(layer "In11.Cu")
		(net "M_K_MA<17>")
	)
	(segment
		(start 110.44936 -130.249168)
		(end 110.44936 -130.441192)
		(width 0.14224)
		(layer "In11.Cu")
		(net "M_K_MA<17>")
	)
	(segment
		(start 109.780324 -125.8824)
		(end 110.29569 -125.8824)
		(width 0.14224)
		(layer "In11.Cu")
		(net "M_K_MA<17>")
	)
	(segment
		(start 111.216186 -131.836414)
		(end 111.061754 -131.990846)
		(width 0.14224)
		(layer "In11.Cu")
		(net "M_K_MA<17>")
	)
	(segment
		(start 106.928666 -122.875802)
		(end 107.376722 -123.323858)
		(width 0.14224)
		(layer "In11.Cu")
		(net "M_K_MA<17>")
	)
	(segment
		(start 111.037878 -132.634228)
		(end 111.18596 -132.78231)
		(width 0.14224)
		(layer "In11.Cu")
		(net "M_K_MA<17>")
	)
	(segment
		(start 111.020352 -128.309624)
		(end 110.818168 -128.511808)
		(width 0.14224)
		(layer "In11.Cu")
		(net "M_K_MA<17>")
	)
	(segment
		(start 104.629458 -120.216168)
		(end 104.629458 -120.683782)
		(width 0.14224)
		(layer "In11.Cu")
		(net "M_K_MA<17>")
	)
	(segment
		(start 104.97058 -121.024904)
		(end 105.15092 -121.02465)
		(width 0.14224)
		(layer "In11.Cu")
		(net "M_K_MA<17>")
	)
	(segment
		(start 110.818168 -129.88036)
		(end 110.44936 -130.249168)
		(width 0.14224)
		(layer "In11.Cu")
		(net "M_K_MA<17>")
	)
	(segment
		(start 110.818168 -128.511808)
		(end 110.818168 -129.88036)
		(width 0.14224)
		(layer "In11.Cu")
		(net "M_K_MA<17>")
	)
	(segment
		(start 104.629458 -120.683782)
		(end 104.97058 -121.024904)
		(width 0.14224)
		(layer "In11.Cu")
		(net "M_K_MA<17>")
	)
	(segment
		(start 105.779062 -121.833386)
		(end 106.120184 -122.174508)
		(width 0.14224)
		(layer "In11.Cu")
		(net "M_K_MA<17>")
	)
	(segment
		(start 101.953568 -99.612704)
		(end 101.953568 -100.0506)
		(width 0.0889)
		(layer "In11.Cu")
		(net "M_K_MA<17>")
	)
	(segment
		(start 111.216186 -131.566158)
		(end 111.216186 -131.836414)
		(width 0.14224)
		(layer "In11.Cu")
		(net "M_K_MA<17>")
	)
	(segment
		(start 108.07827 -123.66498)
		(end 108.07827 -124.132594)
		(width 0.14224)
		(layer "In11.Cu")
		(net "M_K_MA<17>")
	)
	(segment
		(start 110.785148 -132.634228)
		(end 111.037878 -132.634228)
		(width 0.14224)
		(layer "In11.Cu")
		(net "M_K_MA<17>")
	)
	(segment
		(start 111.020352 -126.607062)
		(end 111.020352 -128.309624)
		(width 0.14224)
		(layer "In11.Cu")
		(net "M_K_MA<17>")
	)
	(segment
		(start 110.612428 -133.81609)
		(end 110.86465 -134.068312)
		(width 0.14224)
		(layer "In11.Cu")
		(net "M_K_MA<17>")
	)
	(segment
		(start 106.300524 -122.174254)
		(end 106.587544 -122.174254)
		(width 0.14224)
		(layer "In11.Cu")
		(net "M_K_MA<17>")
	)
	(segment
		(start 102.537768 -100.1522)
		(end 103.985568 -101.6)
		(width 0.0889)
		(layer "In11.Cu")
		(net "M_K_MA<17>")
	)
	(segment
		(start 110.623096 -132.472176)
		(end 110.785148 -132.634228)
		(width 0.14224)
		(layer "In11.Cu")
		(net "M_K_MA<17>")
	)
	(segment
		(start 111.061754 -131.990846)
		(end 110.77956 -131.990846)
		(width 0.14224)
		(layer "In11.Cu")
		(net "M_K_MA<17>")
	)
	(segment
		(start 110.29569 -125.8824)
		(end 111.020352 -126.607062)
		(width 0.14224)
		(layer "In11.Cu")
		(net "M_K_MA<17>")
	)
	(segment
		(start 110.662466 -131.012438)
		(end 111.216186 -131.566158)
		(width 0.14224)
		(layer "In11.Cu")
		(net "M_K_MA<17>")
	)
	(segment
		(start 110.86465 -135.972296)
		(end 110.449868 -136.387078)
		(width 0.14224)
		(layer "In11.Cu")
		(net "M_K_MA<17>")
	)
	(segment
		(start 110.77956 -131.990846)
		(end 110.623096 -132.14731)
		(width 0.14224)
		(layer "In11.Cu")
		(net "M_K_MA<17>")
	)
	(segment
		(start 111.024162 -133.195568)
		(end 110.767368 -133.195568)
		(width 0.14224)
		(layer "In11.Cu")
		(net "M_K_MA<17>")
	)
	(segment
		(start 108.07827 -124.132594)
		(end 108.419392 -124.473716)
		(width 0.14224)
		(layer "In11.Cu")
		(net "M_K_MA<17>")
	)
	(segment
		(start 105.43794 -121.02465)
		(end 105.779062 -121.365772)
		(width 0.14224)
		(layer "In11.Cu")
		(net "M_K_MA<17>")
	)
	(segment
		(start 105.779062 -121.365772)
		(end 105.779062 -121.833386)
		(width 0.14224)
		(layer "In11.Cu")
		(net "M_K_MA<17>")
	)
	(segment
		(start 102.055168 -100.1522)
		(end 102.537768 -100.1522)
		(width 0.0889)
		(layer "In11.Cu")
		(net "M_K_MA<17>")
	)
	(segment
		(start 108.419392 -124.473716)
		(end 108.599732 -124.473462)
		(width 0.14224)
		(layer "In11.Cu")
		(net "M_K_MA<17>")
	)
	(segment
		(start 103.985568 -101.994462)
		(end 103.985568 -119.572278)
		(width 0.14224)
		(layer "In11.Cu")
		(net "M_K_MA<17>")
	)
	(segment
		(start 103.985568 -119.572278)
		(end 104.629458 -120.216168)
		(width 0.14224)
		(layer "In11.Cu")
		(net "M_K_MA<17>")
	)
	(segment
		(start 110.623096 -132.14731)
		(end 110.623096 -132.472176)
		(width 0.14224)
		(layer "In11.Cu")
		(net "M_K_MA<17>")
	)
	(segment
		(start 106.928666 -122.515376)
		(end 106.928666 -122.875802)
		(width 0.14224)
		(layer "In11.Cu")
		(net "M_K_MA<17>")
	)
	(segment
		(start 110.86465 -134.068312)
		(end 110.86465 -135.972296)
		(width 0.14224)
		(layer "In11.Cu")
		(net "M_K_MA<17>")
	)
	(segment
		(start 109.227874 -124.814584)
		(end 109.227874 -125.32995)
		(width 0.14224)
		(layer "In11.Cu")
		(net "M_K_MA<17>")
	)
	(segment
		(start 108.886752 -124.473462)
		(end 109.227874 -124.814584)
		(width 0.14224)
		(layer "In11.Cu")
		(net "M_K_MA<17>")
	)
	(segment
		(start 107.376722 -123.323858)
		(end 107.737148 -123.323858)
		(width 0.14224)
		(layer "In11.Cu")
		(net "M_K_MA<17>")
	)
	(segment
		(start 111.18596 -132.78231)
		(end 111.18596 -133.03377)
		(width 0.14224)
		(layer "In11.Cu")
		(net "M_K_MA<17>")
	)
	(segment
		(start 105.15092 -121.02465)
		(end 105.43794 -121.02465)
		(width 0.14224)
		(layer "In11.Cu")
		(net "M_K_MA<17>")
	)
	(segment
		(start 109.227874 -125.32995)
		(end 109.780324 -125.8824)
		(width 0.14224)
		(layer "In11.Cu")
		(net "M_K_MA<17>")
	)
	(segment
		(start 101.517704 -99.17684)
		(end 101.953568 -99.612704)
		(width 0.0889)
		(layer "In11.Cu")
		(net "M_K_MA<17>")
	)
	(segment
		(start 108.599732 -124.473462)
		(end 108.886752 -124.473462)
		(width 0.14224)
		(layer "In11.Cu")
		(net "M_K_MA<17>")
	)
	(segment
		(start 107.737148 -123.323858)
		(end 108.07827 -123.66498)
		(width 0.14224)
		(layer "In11.Cu")
		(net "M_K_MA<17>")
	)
	(segment
		(start 103.985568 -101.6)
		(end 103.985568 -101.994462)
		(width 0.0889)
		(layer "In11.Cu")
		(net "M_K_MA<17>")
	)
	(segment
		(start 110.662466 -130.654298)
		(end 110.662466 -131.012438)
		(width 0.14224)
		(layer "In11.Cu")
		(net "M_K_MA<17>")
	)
	(segment
		(start 110.767368 -133.195568)
		(end 110.612428 -133.350508)
		(width 0.14224)
		(layer "In11.Cu")
		(net "M_K_MA<17>")
	)
	(segment
		(start 101.953568 -100.0506)
		(end 102.055168 -100.1522)
		(width 0.0889)
		(layer "In11.Cu")
		(net "M_K_MA<17>")
	)
	(segment
		(start 110.612428 -133.350508)
		(end 110.612428 -133.81609)
		(width 0.14224)
		(layer "In11.Cu")
		(net "M_K_MA<17>")
	)
	(segment
		(start 111.18596 -133.03377)
		(end 111.024162 -133.195568)
		(width 0.14224)
		(layer "In11.Cu")
		(net "M_K_MA<17>")
	)
	(segment
		(start 106.587544 -122.174254)
		(end 106.928666 -122.515376)
		(width 0.14224)
		(layer "In11.Cu")
		(net "M_K_MA<17>")
	)
	(segment
		(start 110.44936 -130.441192)
		(end 110.662466 -130.654298)
		(width 0.14224)
		(layer "In11.Cu")
		(net "M_K_MA<17>")
	)
	(segment
		(start 97.206054 -101.653594)
		(end 97.206054 -102.161086)
		(width 0.0889)
		(layer "F.Cu")
		(net "M_K_MA<16>")
	)
	(segment
		(start 97.278698 -99.95662)
		(end 97.285048 -99.967288)
		(width 0.0889)
		(layer "F.Cu")
		(net "M_K_MA<16>")
	)
	(segment
		(start 96.938338 -99.17684)
		(end 97.278698 -99.95662)
		(width 0.0889)
		(layer "F.Cu")
		(net "M_K_MA<16>")
	)
	(segment
		(start 97.289874 -101.349302)
		(end 97.285048 -101.357938)
		(width 0.0889)
		(layer "F.Cu")
		(net "M_K_MA<16>")
	)
	(segment
		(start 97.206054 -102.161086)
		(end 99.077018 -104.03205)
		(width 0.0889)
		(layer "F.Cu")
		(net "M_K_MA<16>")
	)
	(segment
		(start 99.077018 -104.03205)
		(end 99.077018 -104.375458)
		(width 0.0889)
		(layer "F.Cu")
		(net "M_K_MA<16>")
	)
	(segment
		(start 103.649526 -133.0706)
		(end 103.649526 -134.367778)
		(width 0.1651)
		(layer "F.Cu")
		(net "M_K_MA<16>")
	)
	(segment
		(start 100.227384 -126.844044)
		(end 100.227384 -127.009652)
		(width 0.1651)
		(layer "F.Cu")
		(net "M_K_MA<16>")
	)
	(segment
		(start 102.334568 -129.116836)
		(end 102.334568 -129.7686)
		(width 0.1651)
		(layer "F.Cu")
		(net "M_K_MA<16>")
	)
	(segment
		(start 103.649272 -131.083304)
		(end 103.649272 -131.611878)
		(width 0.1651)
		(layer "F.Cu")
		(net "M_K_MA<16>")
	)
	(segment
		(start 99.077018 -125.693678)
		(end 100.227384 -126.844044)
		(width 0.1651)
		(layer "F.Cu")
		(net "M_K_MA<16>")
	)
	(segment
		(start 99.077018 -104.375458)
		(end 99.077018 -125.693678)
		(width 0.1651)
		(layer "F.Cu")
		(net "M_K_MA<16>")
	)
	(segment
		(start 100.227384 -127.009652)
		(end 102.334568 -129.116836)
		(width 0.1651)
		(layer "F.Cu")
		(net "M_K_MA<16>")
	)
	(segment
		(start 102.334568 -129.7686)
		(end 103.649272 -131.083304)
		(width 0.1651)
		(layer "F.Cu")
		(net "M_K_MA<16>")
	)
	(via
		(at 103.649526 -134.367778)
		(size 0.508)
		(drill 0.254)
		(layers "F.Cu" "B.Cu")
		(net "M_K_MA<16>")
	)
	(via
		(at 103.649272 -131.611878)
		(size 0.508)
		(drill 0.254)
		(layers "F.Cu" "B.Cu")
		(net "M_K_MA<16>")
	)
	(arc
		(start 97.285048 -99.967288)
		(mid 97.338547 -100.167186)
		(end 97.285048 -100.367084)
		(width 0.0889)
		(layer "F.Cu")
		(net "M_K_MA<16>")
	)
	(arc
		(start 97.285048 -101.357938)
		(mid 97.226071 -101.500562)
		(end 97.206054 -101.653594)
		(width 0.0889)
		(layer "F.Cu")
		(net "M_K_MA<16>")
	)
	(arc
		(start 97.285048 -100.367084)
		(mid 97.205917 -100.662486)
		(end 97.285048 -100.957888)
		(width 0.0889)
		(layer "F.Cu")
		(net "M_K_MA<16>")
	)
	(arc
		(start 97.285048 -100.957888)
		(mid 97.338518 -101.152951)
		(end 97.289874 -101.349302)
		(width 0.0889)
		(layer "F.Cu")
		(net "M_K_MA<16>")
	)
	(segment
		(start 103.649526 -131.612132)
		(end 103.649272 -131.611878)
		(width 0.1651)
		(layer "B.Cu")
		(net "M_K_MA<16>")
	)
	(segment
		(start 103.649526 -132.876036)
		(end 103.649526 -131.612132)
		(width 0.1651)
		(layer "B.Cu")
		(net "M_K_MA<16>")
	)
	(segment
		(start 104.24414 -132.112766)
		(end 103.804212 -132.112766)
		(width 0.14224)
		(layer "In9.Cu")
		(net "M_K_MA<16>")
	)
	(segment
		(start 104.39908 -132.267706)
		(end 104.24414 -132.112766)
		(width 0.14224)
		(layer "In9.Cu")
		(net "M_K_MA<16>")
	)
	(segment
		(start 103.896922 -133.235446)
		(end 103.738172 -133.076696)
		(width 0.14224)
		(layer "In9.Cu")
		(net "M_K_MA<16>")
	)
	(segment
		(start 103.649272 -134.367524)
		(end 103.649272 -133.951726)
		(width 0.14224)
		(layer "In9.Cu")
		(net "M_K_MA<16>")
	)
	(segment
		(start 103.738172 -133.076696)
		(end 103.738172 -132.825236)
		(width 0.14224)
		(layer "In9.Cu")
		(net "M_K_MA<16>")
	)
	(segment
		(start 103.649272 -133.951726)
		(end 103.804212 -133.796786)
		(width 0.14224)
		(layer "In9.Cu")
		(net "M_K_MA<16>")
	)
	(segment
		(start 103.649272 -131.957826)
		(end 103.649272 -131.611878)
		(width 0.14224)
		(layer "In9.Cu")
		(net "M_K_MA<16>")
	)
	(segment
		(start 105.048304 -133.382512)
		(end 104.901238 -133.235446)
		(width 0.14224)
		(layer "In9.Cu")
		(net "M_K_MA<16>")
	)
	(segment
		(start 103.804212 -133.796786)
		(end 104.88549 -133.796786)
		(width 0.14224)
		(layer "In9.Cu")
		(net "M_K_MA<16>")
	)
	(segment
		(start 103.649526 -134.367778)
		(end 103.649272 -134.367524)
		(width 0.14224)
		(layer "In9.Cu")
		(net "M_K_MA<16>")
	)
	(segment
		(start 104.24414 -132.674106)
		(end 104.39908 -132.519166)
		(width 0.14224)
		(layer "In9.Cu")
		(net "M_K_MA<16>")
	)
	(segment
		(start 105.048304 -133.633972)
		(end 105.048304 -133.382512)
		(width 0.14224)
		(layer "In9.Cu")
		(net "M_K_MA<16>")
	)
	(segment
		(start 103.738172 -132.825236)
		(end 103.889302 -132.674106)
		(width 0.14224)
		(layer "In9.Cu")
		(net "M_K_MA<16>")
	)
	(segment
		(start 104.901238 -133.235446)
		(end 103.896922 -133.235446)
		(width 0.14224)
		(layer "In9.Cu")
		(net "M_K_MA<16>")
	)
	(segment
		(start 104.39908 -132.519166)
		(end 104.39908 -132.267706)
		(width 0.14224)
		(layer "In9.Cu")
		(net "M_K_MA<16>")
	)
	(segment
		(start 104.88549 -133.796786)
		(end 105.048304 -133.633972)
		(width 0.14224)
		(layer "In9.Cu")
		(net "M_K_MA<16>")
	)
	(segment
		(start 103.804212 -132.112766)
		(end 103.649272 -131.957826)
		(width 0.14224)
		(layer "In9.Cu")
		(net "M_K_MA<16>")
	)
	(segment
		(start 103.889302 -132.674106)
		(end 104.24414 -132.674106)
		(width 0.14224)
		(layer "In9.Cu")
		(net "M_K_MA<16>")
	)
	(segment
		(start 107.04957 -133.0706)
		(end 107.04957 -134.371334)
		(width 0.1651)
		(layer "F.Cu")
		(net "M_K_MA<15>")
	)
	(segment
		(start 99.513898 -97.690686)
		(end 98.942398 -97.690686)
		(width 0.1651)
		(layer "F.Cu")
		(net "M_K_MA<15>")
	)
	(segment
		(start 107.04957 -134.371334)
		(end 107.049824 -134.371588)
		(width 0.1651)
		(layer "F.Cu")
		(net "M_K_MA<15>")
	)
	(via
		(at 107.049316 -131.611878)
		(size 0.508)
		(drill 0.254)
		(layers "F.Cu" "B.Cu")
		(net "M_K_MA<15>")
	)
	(via
		(at 98.942398 -97.690686)
		(size 0.508)
		(drill 0.254)
		(layers "F.Cu" "B.Cu")
		(net "M_K_MA<15>")
	)
	(via
		(at 107.049824 -134.371588)
		(size 0.4572)
		(drill 0.2032)
		(layers "F.Cu" "B.Cu")
		(net "M_K_MA<15>")
	)
	(segment
		(start 107.04957 -131.612132)
		(end 107.049316 -131.611878)
		(width 0.1651)
		(layer "B.Cu")
		(net "M_K_MA<15>")
	)
	(segment
		(start 107.04957 -132.876036)
		(end 107.04957 -131.612132)
		(width 0.1651)
		(layer "B.Cu")
		(net "M_K_MA<15>")
	)
	(segment
		(start 107.049316 -131.611878)
		(end 106.830622 -131.611878)
		(width 0.14224)
		(layer "In11.Cu")
		(net "M_K_MA<15>")
	)
	(segment
		(start 107.049316 -130.997452)
		(end 107.049316 -131.611878)
		(width 0.14224)
		(layer "In11.Cu")
		(net "M_K_MA<15>")
	)
	(segment
		(start 107.493816 -130.552952)
		(end 107.049316 -130.997452)
		(width 0.14224)
		(layer "In11.Cu")
		(net "M_K_MA<15>")
	)
	(segment
		(start 107.003088 -133.25475)
		(end 106.710988 -133.25475)
		(width 0.14224)
		(layer "In11.Cu")
		(net "M_K_MA<15>")
	)
	(segment
		(start 100.150168 -102.6414)
		(end 101.305868 -103.7971)
		(width 0.14224)
		(layer "In11.Cu")
		(net "M_K_MA<15>")
	)
	(segment
		(start 106.619548 -132.189982)
		(end 106.871516 -132.44195)
		(width 0.14224)
		(layer "In11.Cu")
		(net "M_K_MA<15>")
	)
	(segment
		(start 106.830622 -131.611878)
		(end 106.619548 -131.822952)
		(width 0.14224)
		(layer "In11.Cu")
		(net "M_K_MA<15>")
	)
	(segment
		(start 101.305868 -103.7971)
		(end 101.305868 -121.262902)
		(width 0.14224)
		(layer "In11.Cu")
		(net "M_K_MA<15>")
	)
	(segment
		(start 98.942398 -98.10877)
		(end 98.524568 -98.5266)
		(width 0.0889)
		(layer "In11.Cu")
		(net "M_K_MA<15>")
	)
	(segment
		(start 107.626912 -133.571996)
		(end 107.320334 -133.571996)
		(width 0.14224)
		(layer "In11.Cu")
		(net "M_K_MA<15>")
	)
	(segment
		(start 101.305868 -121.262902)
		(end 106.849164 -126.806198)
		(width 0.14224)
		(layer "In11.Cu")
		(net "M_K_MA<15>")
	)
	(segment
		(start 107.320334 -133.571996)
		(end 107.003088 -133.25475)
		(width 0.14224)
		(layer "In11.Cu")
		(net "M_K_MA<15>")
	)
	(segment
		(start 98.524568 -98.5266)
		(end 98.524568 -98.8314)
		(width 0.0889)
		(layer "In11.Cu")
		(net "M_K_MA<15>")
	)
	(segment
		(start 106.619548 -131.822952)
		(end 106.619548 -132.189982)
		(width 0.14224)
		(layer "In11.Cu")
		(net "M_K_MA<15>")
	)
	(segment
		(start 106.849164 -126.806198)
		(end 106.849164 -129.380996)
		(width 0.14224)
		(layer "In11.Cu")
		(net "M_K_MA<15>")
	)
	(segment
		(start 100.150168 -101.432868)
		(end 100.150168 -102.6414)
		(width 0.14224)
		(layer "In11.Cu")
		(net "M_K_MA<15>")
	)
	(segment
		(start 107.876594 -132.78993)
		(end 107.876594 -133.322314)
		(width 0.14224)
		(layer "In11.Cu")
		(net "M_K_MA<15>")
	)
	(segment
		(start 107.528614 -132.44195)
		(end 107.876594 -132.78993)
		(width 0.14224)
		(layer "In11.Cu")
		(net "M_K_MA<15>")
	)
	(segment
		(start 99.718368 -101.001068)
		(end 100.150168 -101.432868)
		(width 0.14224)
		(layer "In11.Cu")
		(net "M_K_MA<15>")
	)
	(segment
		(start 106.710988 -133.25475)
		(end 106.434128 -133.53161)
		(width 0.14224)
		(layer "In11.Cu")
		(net "M_K_MA<15>")
	)
	(segment
		(start 99.718368 -100.0252)
		(end 99.718368 -101.001068)
		(width 0.14224)
		(layer "In11.Cu")
		(net "M_K_MA<15>")
	)
	(segment
		(start 106.434128 -133.755892)
		(end 107.049824 -134.371588)
		(width 0.14224)
		(layer "In11.Cu")
		(net "M_K_MA<15>")
	)
	(segment
		(start 106.849164 -129.380996)
		(end 107.493816 -130.025648)
		(width 0.14224)
		(layer "In11.Cu")
		(net "M_K_MA<15>")
	)
	(segment
		(start 98.942398 -97.690686)
		(end 98.942398 -98.10877)
		(width 0.0889)
		(layer "In11.Cu")
		(net "M_K_MA<15>")
	)
	(segment
		(start 107.876594 -133.322314)
		(end 107.626912 -133.571996)
		(width 0.14224)
		(layer "In11.Cu")
		(net "M_K_MA<15>")
	)
	(segment
		(start 107.493816 -130.025648)
		(end 107.493816 -130.552952)
		(width 0.14224)
		(layer "In11.Cu")
		(net "M_K_MA<15>")
	)
	(segment
		(start 98.524568 -98.8314)
		(end 99.718368 -100.0252)
		(width 0.0889)
		(layer "In11.Cu")
		(net "M_K_MA<15>")
	)
	(segment
		(start 106.871516 -132.44195)
		(end 107.528614 -132.44195)
		(width 0.14224)
		(layer "In11.Cu")
		(net "M_K_MA<15>")
	)
	(segment
		(start 106.434128 -133.53161)
		(end 106.434128 -133.755892)
		(width 0.14224)
		(layer "In11.Cu")
		(net "M_K_MA<15>")
	)
	(segment
		(start 99.67468 -125.139704)
		(end 100.173536 -125.63856)
		(width 0.1651)
		(layer "F.Cu")
		(net "M_K_MA<14>")
	)
	(segment
		(start 101.604064 -127.463296)
		(end 104.389936 -130.249168)
		(width 0.1651)
		(layer "F.Cu")
		(net "M_K_MA<14>")
	)
	(segment
		(start 100.173536 -125.63856)
		(end 100.52304 -125.63856)
		(width 0.1651)
		(layer "F.Cu")
		(net "M_K_MA<14>")
	)
	(segment
		(start 99.610418 -104.210866)
		(end 99.610418 -104.610662)
		(width 0.0889)
		(layer "F.Cu")
		(net "M_K_MA<14>")
	)
	(segment
		(start 99.67468 -124.762514)
		(end 99.67468 -125.139704)
		(width 0.1651)
		(layer "F.Cu")
		(net "M_K_MA<14>")
	)
	(segment
		(start 101.081078 -126.196598)
		(end 101.081078 -126.535942)
		(width 0.1651)
		(layer "F.Cu")
		(net "M_K_MA<14>")
	)
	(segment
		(start 97.47504 -102.075488)
		(end 99.610418 -104.210866)
		(width 0.0889)
		(layer "F.Cu")
		(net "M_K_MA<14>")
	)
	(segment
		(start 105.349548 -137.67054)
		(end 105.349548 -136.387332)
		(width 0.1651)
		(layer "F.Cu")
		(net "M_K_MA<14>")
	)
	(segment
		(start 97.796858 -100.662486)
		(end 97.796858 -101.10216)
		(width 0.0889)
		(layer "F.Cu")
		(net "M_K_MA<14>")
	)
	(segment
		(start 97.396808 -101.652832)
		(end 97.47504 -102.075488)
		(width 0.0889)
		(layer "F.Cu")
		(net "M_K_MA<14>")
	)
	(segment
		(start 99.610418 -123.80468)
		(end 99.960938 -124.1552)
		(width 0.1651)
		(layer "F.Cu")
		(net "M_K_MA<14>")
	)
	(segment
		(start 101.081078 -126.535942)
		(end 100.870766 -126.746254)
		(width 0.1651)
		(layer "F.Cu")
		(net "M_K_MA<14>")
	)
	(segment
		(start 100.870766 -126.746254)
		(end 100.870766 -126.979934)
		(width 0.1651)
		(layer "F.Cu")
		(net "M_K_MA<14>")
	)
	(segment
		(start 99.960938 -124.476256)
		(end 99.67468 -124.762514)
		(width 0.1651)
		(layer "F.Cu")
		(net "M_K_MA<14>")
	)
	(segment
		(start 104.389936 -130.249168)
		(end 105.349294 -130.249168)
		(width 0.1651)
		(layer "F.Cu")
		(net "M_K_MA<14>")
	)
	(segment
		(start 100.870766 -126.979934)
		(end 101.354128 -127.463296)
		(width 0.1651)
		(layer "F.Cu")
		(net "M_K_MA<14>")
	)
	(segment
		(start 105.349548 -136.387332)
		(end 105.349802 -136.387078)
		(width 0.1651)
		(layer "F.Cu")
		(net "M_K_MA<14>")
	)
	(segment
		(start 99.960938 -124.1552)
		(end 99.960938 -124.476256)
		(width 0.1651)
		(layer "F.Cu")
		(net "M_K_MA<14>")
	)
	(segment
		(start 97.456498 -101.44252)
		(end 97.450148 -101.453188)
		(width 0.0889)
		(layer "F.Cu")
		(net "M_K_MA<14>")
	)
	(segment
		(start 99.610418 -104.610662)
		(end 99.610418 -123.80468)
		(width 0.1651)
		(layer "F.Cu")
		(net "M_K_MA<14>")
	)
	(segment
		(start 101.354128 -127.463296)
		(end 101.604064 -127.463296)
		(width 0.1651)
		(layer "F.Cu")
		(net "M_K_MA<14>")
	)
	(segment
		(start 97.796858 -101.10216)
		(end 97.456498 -101.44252)
		(width 0.0889)
		(layer "F.Cu")
		(net "M_K_MA<14>")
	)
	(segment
		(start 100.52304 -125.63856)
		(end 101.081078 -126.196598)
		(width 0.1651)
		(layer "F.Cu")
		(net "M_K_MA<14>")
	)
	(via
		(at 105.349802 -136.387078)
		(size 0.4572)
		(drill 0.2032)
		(layers "F.Cu" "B.Cu")
		(net "M_K_MA<14>")
	)
	(via
		(at 105.349294 -130.249168)
		(size 0.508)
		(drill 0.254)
		(layers "F.Cu" "B.Cu")
		(net "M_K_MA<14>")
	)
	(arc
		(start 97.450148 -101.453188)
		(mid 97.410349 -101.549504)
		(end 97.396808 -101.652832)
		(width 0.0889)
		(layer "F.Cu")
		(net "M_K_MA<14>")
	)
	(segment
		(start 105.349294 -130.249168)
		(end 105.349294 -128.276096)
		(width 0.1651)
		(layer "B.Cu")
		(net "M_K_MA<14>")
	)
	(segment
		(start 105.349294 -128.276096)
		(end 105.349548 -128.276096)
		(width 0.1651)
		(layer "B.Cu")
		(net "M_K_MA<14>")
	)
	(segment
		(start 105.349294 -130.894582)
		(end 105.349294 -130.249168)
		(width 0.14224)
		(layer "In9.Cu")
		(net "M_K_MA<14>")
	)
	(segment
		(start 104.874568 -131.369308)
		(end 105.349294 -130.894582)
		(width 0.14224)
		(layer "In9.Cu")
		(net "M_K_MA<14>")
	)
	(segment
		(start 105.760266 -135.368538)
		(end 105.760266 -132.736844)
		(width 0.14224)
		(layer "In9.Cu")
		(net "M_K_MA<14>")
	)
	(segment
		(start 105.760266 -132.736844)
		(end 104.874568 -131.851146)
		(width 0.14224)
		(layer "In9.Cu")
		(net "M_K_MA<14>")
	)
	(segment
		(start 105.349802 -135.779002)
		(end 105.760266 -135.368538)
		(width 0.14224)
		(layer "In9.Cu")
		(net "M_K_MA<14>")
	)
	(segment
		(start 105.349802 -136.387078)
		(end 105.349802 -135.779002)
		(width 0.14224)
		(layer "In9.Cu")
		(net "M_K_MA<14>")
	)
	(segment
		(start 104.874568 -131.851146)
		(end 104.874568 -131.369308)
		(width 0.14224)
		(layer "In9.Cu")
		(net "M_K_MA<14>")
	)
	(segment
		(start 108.749338 -136.387586)
		(end 108.749846 -136.387078)
		(width 0.1651)
		(layer "F.Cu")
		(net "M_K_MA<13>")
	)
	(segment
		(start 100.372164 -98.18624)
		(end 99.800664 -98.18624)
		(width 0.1651)
		(layer "F.Cu")
		(net "M_K_MA<13>")
	)
	(segment
		(start 108.749338 -137.67054)
		(end 108.749338 -136.387586)
		(width 0.1651)
		(layer "F.Cu")
		(net "M_K_MA<13>")
	)
	(via
		(at 99.800664 -98.18624)
		(size 0.508)
		(drill 0.254)
		(layers "F.Cu" "B.Cu")
		(net "M_K_MA<13>")
	)
	(via
		(at 108.749338 -130.249168)
		(size 0.508)
		(drill 0.254)
		(layers "F.Cu" "B.Cu")
		(net "M_K_MA<13>")
	)
	(via
		(at 108.749846 -136.387078)
		(size 0.4572)
		(drill 0.2032)
		(layers "F.Cu" "B.Cu")
		(net "M_K_MA<13>")
	)
	(segment
		(start 108.749338 -128.276096)
		(end 108.749338 -130.249168)
		(width 0.1651)
		(layer "B.Cu")
		(net "M_K_MA<13>")
	)
	(segment
		(start 108.379768 -131.21894)
		(end 108.252768 -131.34594)
		(width 0.14224)
		(layer "In11.Cu")
		(net "M_K_MA<13>")
	)
	(segment
		(start 99.388168 -99.3648)
		(end 99.972368 -99.949)
		(width 0.0889)
		(layer "In11.Cu")
		(net "M_K_MA<13>")
	)
	(segment
		(start 107.404408 -128.202944)
		(end 107.404408 -128.668272)
		(width 0.14224)
		(layer "In11.Cu")
		(net "M_K_MA<13>")
	)
	(segment
		(start 100.632768 -102.387654)
		(end 101.813868 -103.568754)
		(width 0.14224)
		(layer "In11.Cu")
		(net "M_K_MA<13>")
	)
	(segment
		(start 108.252768 -131.34594)
		(end 108.252768 -131.826)
		(width 0.14224)
		(layer "In11.Cu")
		(net "M_K_MA<13>")
	)
	(segment
		(start 108.341922 -131.915154)
		(end 108.341922 -135.979154)
		(width 0.14224)
		(layer "In11.Cu")
		(net "M_K_MA<13>")
	)
	(segment
		(start 108.749338 -129.57683)
		(end 108.749338 -130.249168)
		(width 0.14224)
		(layer "In11.Cu")
		(net "M_K_MA<13>")
	)
	(segment
		(start 99.972368 -99.949)
		(end 99.972368 -100.6348)
		(width 0.14224)
		(layer "In11.Cu")
		(net "M_K_MA<13>")
	)
	(segment
		(start 108.188506 -127.426974)
		(end 108.188506 -127.854202)
		(width 0.14224)
		(layer "In11.Cu")
		(net "M_K_MA<13>")
	)
	(segment
		(start 108.014516 -128.842008)
		(end 108.749338 -129.57683)
		(width 0.14224)
		(layer "In11.Cu")
		(net "M_K_MA<13>")
	)
	(segment
		(start 99.972368 -100.6348)
		(end 100.632768 -101.2952)
		(width 0.14224)
		(layer "In11.Cu")
		(net "M_K_MA<13>")
	)
	(segment
		(start 99.388168 -98.598736)
		(end 99.388168 -99.3648)
		(width 0.0889)
		(layer "In11.Cu")
		(net "M_K_MA<13>")
	)
	(segment
		(start 107.578144 -128.029208)
		(end 107.404408 -128.202944)
		(width 0.14224)
		(layer "In11.Cu")
		(net "M_K_MA<13>")
	)
	(segment
		(start 99.800664 -98.18624)
		(end 99.388168 -98.598736)
		(width 0.0889)
		(layer "In11.Cu")
		(net "M_K_MA<13>")
	)
	(segment
		(start 108.252768 -131.826)
		(end 108.341922 -131.915154)
		(width 0.14224)
		(layer "In11.Cu")
		(net "M_K_MA<13>")
	)
	(segment
		(start 107.578144 -128.842008)
		(end 108.014516 -128.842008)
		(width 0.14224)
		(layer "In11.Cu")
		(net "M_K_MA<13>")
	)
	(segment
		(start 108.0135 -128.029208)
		(end 107.578144 -128.029208)
		(width 0.14224)
		(layer "In11.Cu")
		(net "M_K_MA<13>")
	)
	(segment
		(start 100.632768 -101.2952)
		(end 100.632768 -102.387654)
		(width 0.14224)
		(layer "In11.Cu")
		(net "M_K_MA<13>")
	)
	(segment
		(start 108.188506 -127.854202)
		(end 108.0135 -128.029208)
		(width 0.14224)
		(layer "In11.Cu")
		(net "M_K_MA<13>")
	)
	(segment
		(start 108.341922 -135.979154)
		(end 108.749846 -136.387078)
		(width 0.14224)
		(layer "In11.Cu")
		(net "M_K_MA<13>")
	)
	(segment
		(start 101.813868 -103.568754)
		(end 101.813868 -121.052336)
		(width 0.14224)
		(layer "In11.Cu")
		(net "M_K_MA<13>")
	)
	(segment
		(start 108.749338 -130.249168)
		(end 108.379768 -130.618738)
		(width 0.14224)
		(layer "In11.Cu")
		(net "M_K_MA<13>")
	)
	(segment
		(start 108.379768 -130.618738)
		(end 108.379768 -131.21894)
		(width 0.14224)
		(layer "In11.Cu")
		(net "M_K_MA<13>")
	)
	(segment
		(start 107.404408 -128.668272)
		(end 107.578144 -128.842008)
		(width 0.14224)
		(layer "In11.Cu")
		(net "M_K_MA<13>")
	)
	(segment
		(start 101.813868 -121.052336)
		(end 108.188506 -127.426974)
		(width 0.14224)
		(layer "In11.Cu")
		(net "M_K_MA<13>")
	)
	(segment
		(start 84.0994 -133.0706)
		(end 84.0994 -134.369556)
		(width 0.1651)
		(layer "F.Cu")
		(net "M_K_MA<12>")
	)
	(segment
		(start 87.494872 -96.700086)
		(end 86.923372 -96.700086)
		(width 0.1651)
		(layer "F.Cu")
		(net "M_K_MA<12>")
	)
	(via
		(at 84.0994 -130.902456)
		(size 0.508)
		(drill 0.254)
		(layers "F.Cu" "B.Cu")
		(net "M_K_MA<12>")
	)
	(via
		(at 86.923372 -96.700086)
		(size 0.508)
		(drill 0.254)
		(layers "F.Cu" "B.Cu")
		(net "M_K_MA<12>")
	)
	(via
		(at 84.0994 -134.369556)
		(size 0.4572)
		(drill 0.2032)
		(layers "F.Cu" "B.Cu")
		(net "M_K_MA<12>")
	)
	(segment
		(start 84.0994 -132.876036)
		(end 84.0994 -130.902456)
		(width 0.1651)
		(layer "B.Cu")
		(net "M_K_MA<12>")
	)
	(segment
		(start 87.973916 -100.575872)
		(end 87.973916 -120.934988)
		(width 0.14224)
		(layer "In11.Cu")
		(net "M_K_MA<12>")
	)
	(segment
		(start 87.25281 -97.46107)
		(end 87.270082 -97.490788)
		(width 0.0889)
		(layer "In11.Cu")
		(net "M_K_MA<12>")
	)
	(segment
		(start 88.008206 -99.631754)
		(end 87.973916 -99.831398)
		(width 0.0889)
		(layer "In11.Cu")
		(net "M_K_MA<12>")
	)
	(segment
		(start 83.614768 -129.8448)
		(end 84.0994 -130.329432)
		(width 0.14224)
		(layer "In11.Cu")
		(net "M_K_MA<12>")
	)
	(segment
		(start 87.764112 -97.78619)
		(end 87.796878 -97.78619)
		(width 0.0889)
		(layer "In11.Cu")
		(net "M_K_MA<12>")
	)
	(segment
		(start 86.923372 -96.700086)
		(end 87.25281 -97.46107)
		(width 0.0889)
		(layer "In11.Cu")
		(net "M_K_MA<12>")
	)
	(segment
		(start 88.128602 -98.386138)
		(end 88.122252 -98.396806)
		(width 0.0889)
		(layer "In11.Cu")
		(net "M_K_MA<12>")
	)
	(segment
		(start 84.554568 -128.4732)
		(end 83.614768 -129.413)
		(width 0.14224)
		(layer "In11.Cu")
		(net "M_K_MA<12>")
	)
	(segment
		(start 87.973916 -120.934988)
		(end 84.554568 -124.354336)
		(width 0.14224)
		(layer "In11.Cu")
		(net "M_K_MA<12>")
	)
	(segment
		(start 88.133428 -99.368102)
		(end 88.128602 -99.376738)
		(width 0.0889)
		(layer "In11.Cu")
		(net "M_K_MA<12>")
	)
	(segment
		(start 88.133428 -98.377502)
		(end 88.128602 -98.386138)
		(width 0.0889)
		(layer "In11.Cu")
		(net "M_K_MA<12>")
	)
	(segment
		(start 84.0994 -130.329432)
		(end 84.0994 -130.902456)
		(width 0.14224)
		(layer "In11.Cu")
		(net "M_K_MA<12>")
	)
	(segment
		(start 83.614768 -129.413)
		(end 83.614768 -129.8448)
		(width 0.14224)
		(layer "In11.Cu")
		(net "M_K_MA<12>")
	)
	(segment
		(start 84.007198 -134.277354)
		(end 84.0994 -134.369556)
		(width 0.14224)
		(layer "In11.Cu")
		(net "M_K_MA<12>")
	)
	(segment
		(start 84.554568 -124.354336)
		(end 84.554568 -128.4732)
		(width 0.14224)
		(layer "In11.Cu")
		(net "M_K_MA<12>")
	)
	(segment
		(start 84.0994 -130.902456)
		(end 84.007198 -130.994658)
		(width 0.14224)
		(layer "In11.Cu")
		(net "M_K_MA<12>")
	)
	(segment
		(start 84.007198 -130.994658)
		(end 84.007198 -134.277354)
		(width 0.14224)
		(layer "In11.Cu")
		(net "M_K_MA<12>")
	)
	(segment
		(start 87.973916 -99.831398)
		(end 87.973916 -100.575872)
		(width 0.0889)
		(layer "In11.Cu")
		(net "M_K_MA<12>")
	)
	(arc
		(start 88.128602 -98.976688)
		(mid 88.182072 -99.171751)
		(end 88.133428 -99.368102)
		(width 0.0889)
		(layer "In11.Cu")
		(net "M_K_MA<12>")
	)
	(arc
		(start 87.796878 -97.78619)
		(mid 88.129796 -97.988181)
		(end 88.133428 -98.377502)
		(width 0.0889)
		(layer "In11.Cu")
		(net "M_K_MA<12>")
	)
	(arc
		(start 87.270082 -97.490788)
		(mid 87.47869 -97.70272)
		(end 87.764112 -97.78619)
		(width 0.0889)
		(layer "In11.Cu")
		(net "M_K_MA<12>")
	)
	(arc
		(start 88.128602 -99.376738)
		(mid 88.064036 -99.502184)
		(end 88.008206 -99.631754)
		(width 0.0889)
		(layer "In11.Cu")
		(net "M_K_MA<12>")
	)
	(arc
		(start 88.122252 -98.396806)
		(mid 88.049454 -98.687569)
		(end 88.128602 -98.976688)
		(width 0.0889)
		(layer "In11.Cu")
		(net "M_K_MA<12>")
	)
	(segment
		(start 89.211912 -99.67214)
		(end 88.640412 -98.681286)
		(width 0.1651)
		(layer "F.Cu")
		(net "M_K_MA<11>")
	)
	(segment
		(start 84.949538 -136.387078)
		(end 84.949538 -137.67054)
		(width 0.1651)
		(layer "F.Cu")
		(net "M_K_MA<11>")
	)
	(via
		(at 84.949538 -130.249168)
		(size 0.508)
		(drill 0.254)
		(layers "F.Cu" "B.Cu")
		(net "M_K_MA<11>")
	)
	(via
		(at 88.640412 -98.681286)
		(size 0.508)
		(drill 0.254)
		(layers "F.Cu" "B.Cu")
		(net "M_K_MA<11>")
	)
	(via
		(at 84.949538 -136.387078)
		(size 0.4572)
		(drill 0.2032)
		(layers "F.Cu" "B.Cu")
		(net "M_K_MA<11>")
	)
	(segment
		(start 84.949538 -128.276096)
		(end 84.949538 -130.249168)
		(width 0.1651)
		(layer "B.Cu")
		(net "M_K_MA<11>")
	)
	(segment
		(start 84.949538 -130.249168)
		(end 84.706968 -130.491738)
		(width 0.14224)
		(layer "In11.Cu")
		(net "M_K_MA<11>")
	)
	(segment
		(start 88.640412 -98.681286)
		(end 88.640412 -98.871786)
		(width 0.0889)
		(layer "In11.Cu")
		(net "M_K_MA<11>")
	)
	(segment
		(start 84.46516 -135.9027)
		(end 84.949538 -136.387078)
		(width 0.14224)
		(layer "In11.Cu")
		(net "M_K_MA<11>")
	)
	(segment
		(start 84.732368 -129.3622)
		(end 84.732368 -130.031998)
		(width 0.14224)
		(layer "In11.Cu")
		(net "M_K_MA<11>")
	)
	(segment
		(start 88.240616 -99.670362)
		(end 88.240616 -99.988116)
		(width 0.0889)
		(layer "In11.Cu")
		(net "M_K_MA<11>")
	)
	(segment
		(start 85.062568 -129.032)
		(end 84.732368 -129.3622)
		(width 0.14224)
		(layer "In11.Cu")
		(net "M_K_MA<11>")
	)
	(segment
		(start 83.59521 -135.095996)
		(end 83.59521 -135.347456)
		(width 0.14224)
		(layer "In11.Cu")
		(net "M_K_MA<11>")
	)
	(segment
		(start 85.062568 -124.536708)
		(end 85.062568 -129.032)
		(width 0.14224)
		(layer "In11.Cu")
		(net "M_K_MA<11>")
	)
	(segment
		(start 88.481916 -100.229416)
		(end 88.481916 -100.585778)
		(width 0.0889)
		(layer "In11.Cu")
		(net "M_K_MA<11>")
	)
	(segment
		(start 88.640412 -98.871786)
		(end 88.37168 -99.140518)
		(width 0.0889)
		(layer "In11.Cu")
		(net "M_K_MA<11>")
	)
	(segment
		(start 84.529168 -131.9276)
		(end 84.529168 -134.722108)
		(width 0.14224)
		(layer "In11.Cu")
		(net "M_K_MA<11>")
	)
	(segment
		(start 88.481916 -100.585778)
		(end 88.481916 -101.031548)
		(width 0.14224)
		(layer "In11.Cu")
		(net "M_K_MA<11>")
	)
	(segment
		(start 88.481916 -121.11736)
		(end 85.062568 -124.536708)
		(width 0.14224)
		(layer "In11.Cu")
		(net "M_K_MA<11>")
	)
	(segment
		(start 83.75015 -134.941056)
		(end 83.59521 -135.095996)
		(width 0.14224)
		(layer "In11.Cu")
		(net "M_K_MA<11>")
	)
	(segment
		(start 83.75015 -135.502396)
		(end 84.262468 -135.502396)
		(width 0.14224)
		(layer "In11.Cu")
		(net "M_K_MA<11>")
	)
	(segment
		(start 84.732368 -130.031998)
		(end 84.949538 -130.249168)
		(width 0.14224)
		(layer "In11.Cu")
		(net "M_K_MA<11>")
	)
	(segment
		(start 83.59521 -135.347456)
		(end 83.75015 -135.502396)
		(width 0.14224)
		(layer "In11.Cu")
		(net "M_K_MA<11>")
	)
	(segment
		(start 88.481916 -101.031548)
		(end 88.872568 -101.4222)
		(width 0.14224)
		(layer "In11.Cu")
		(net "M_K_MA<11>")
	)
	(segment
		(start 84.529168 -134.722108)
		(end 84.31022 -134.941056)
		(width 0.14224)
		(layer "In11.Cu")
		(net "M_K_MA<11>")
	)
	(segment
		(start 84.31022 -134.941056)
		(end 83.75015 -134.941056)
		(width 0.14224)
		(layer "In11.Cu")
		(net "M_K_MA<11>")
	)
	(segment
		(start 84.706968 -131.0386)
		(end 84.440014 -131.305554)
		(width 0.14224)
		(layer "In11.Cu")
		(net "M_K_MA<11>")
	)
	(segment
		(start 84.706968 -130.491738)
		(end 84.706968 -131.0386)
		(width 0.14224)
		(layer "In11.Cu")
		(net "M_K_MA<11>")
	)
	(segment
		(start 84.440014 -131.305554)
		(end 84.440014 -131.838446)
		(width 0.14224)
		(layer "In11.Cu")
		(net "M_K_MA<11>")
	)
	(segment
		(start 88.872568 -101.7524)
		(end 88.481916 -102.143052)
		(width 0.14224)
		(layer "In11.Cu")
		(net "M_K_MA<11>")
	)
	(segment
		(start 84.440014 -131.838446)
		(end 84.529168 -131.9276)
		(width 0.14224)
		(layer "In11.Cu")
		(net "M_K_MA<11>")
	)
	(segment
		(start 84.46516 -135.705088)
		(end 84.46516 -135.9027)
		(width 0.14224)
		(layer "In11.Cu")
		(net "M_K_MA<11>")
	)
	(segment
		(start 88.240616 -99.988116)
		(end 88.481916 -100.229416)
		(width 0.0889)
		(layer "In11.Cu")
		(net "M_K_MA<11>")
	)
	(segment
		(start 88.481916 -102.143052)
		(end 88.481916 -121.11736)
		(width 0.14224)
		(layer "In11.Cu")
		(net "M_K_MA<11>")
	)
	(segment
		(start 88.872568 -101.4222)
		(end 88.872568 -101.7524)
		(width 0.14224)
		(layer "In11.Cu")
		(net "M_K_MA<11>")
	)
	(segment
		(start 84.262468 -135.502396)
		(end 84.46516 -135.705088)
		(width 0.14224)
		(layer "In11.Cu")
		(net "M_K_MA<11>")
	)
	(arc
		(start 88.293702 -99.472242)
		(mid 88.254143 -99.567812)
		(end 88.240616 -99.670362)
		(width 0.0889)
		(layer "In11.Cu")
		(net "M_K_MA<11>")
	)
	(arc
		(start 88.37168 -99.140518)
		(mid 88.357105 -99.312116)
		(end 88.293702 -99.472242)
		(width 0.0889)
		(layer "In11.Cu")
		(net "M_K_MA<11>")
	)
	(segment
		(start 102.799388 -137.67054)
		(end 102.799388 -136.387332)
		(width 0.1651)
		(layer "F.Cu")
		(net "M_K_MA<10>")
	)
	(segment
		(start 102.799388 -136.387332)
		(end 102.799642 -136.387078)
		(width 0.1651)
		(layer "F.Cu")
		(net "M_K_MA<10>")
	)
	(segment
		(start 94.649798 -98.18624)
		(end 95.221298 -98.18624)
		(width 0.1651)
		(layer "F.Cu")
		(net "M_K_MA<10>")
	)
	(via
		(at 102.799388 -129.539746)
		(size 0.508)
		(drill 0.254)
		(layers "F.Cu" "B.Cu")
		(net "M_K_MA<10>")
	)
	(via
		(at 94.649798 -98.18624)
		(size 0.508)
		(drill 0.254)
		(layers "F.Cu" "B.Cu")
		(net "M_K_MA<10>")
	)
	(via
		(at 102.799642 -136.387078)
		(size 0.4572)
		(drill 0.2032)
		(layers "F.Cu" "B.Cu")
		(net "M_K_MA<10>")
	)
	(segment
		(start 102.799388 -128.276096)
		(end 102.799388 -129.539746)
		(width 0.1651)
		(layer "B.Cu")
		(net "M_K_MA<10>")
	)
	(segment
		(start 102.486968 -135.390636)
		(end 102.799388 -135.703056)
		(width 0.14224)
		(layer "In11.Cu")
		(net "M_K_MA<10>")
	)
	(segment
		(start 97.829116 -122.697748)
		(end 102.799388 -127.66802)
		(width 0.14224)
		(layer "In11.Cu")
		(net "M_K_MA<10>")
	)
	(segment
		(start 102.36708 -134.728712)
		(end 102.486968 -134.8486)
		(width 0.14224)
		(layer "In11.Cu")
		(net "M_K_MA<10>")
	)
	(segment
		(start 102.427278 -131.30911)
		(end 102.427278 -131.88569)
		(width 0.14224)
		(layer "In11.Cu")
		(net "M_K_MA<10>")
	)
	(segment
		(start 102.361492 -130.579876)
		(end 102.361492 -131.243324)
		(width 0.14224)
		(layer "In11.Cu")
		(net "M_K_MA<10>")
	)
	(segment
		(start 97.127568 -101.8794)
		(end 97.127568 -103.43896)
		(width 0.0889)
		(layer "In11.Cu")
		(net "M_K_MA<10>")
	)
	(segment
		(start 102.799388 -127.66802)
		(end 102.799388 -129.539746)
		(width 0.14224)
		(layer "In11.Cu")
		(net "M_K_MA<10>")
	)
	(segment
		(start 102.36708 -131.945888)
		(end 102.36708 -134.728712)
		(width 0.14224)
		(layer "In11.Cu")
		(net "M_K_MA<10>")
	)
	(segment
		(start 94.649798 -98.18624)
		(end 95.102172 -98.638614)
		(width 0.0889)
		(layer "In11.Cu")
		(net "M_K_MA<10>")
	)
	(segment
		(start 102.799388 -135.703056)
		(end 102.799388 -136.386824)
		(width 0.14224)
		(layer "In11.Cu")
		(net "M_K_MA<10>")
	)
	(segment
		(start 97.127568 -103.43896)
		(end 97.829116 -104.140508)
		(width 0.0889)
		(layer "In11.Cu")
		(net "M_K_MA<10>")
	)
	(segment
		(start 95.102172 -98.638614)
		(end 95.102172 -99.854004)
		(width 0.0889)
		(layer "In11.Cu")
		(net "M_K_MA<10>")
	)
	(segment
		(start 95.102172 -99.854004)
		(end 97.127568 -101.8794)
		(width 0.0889)
		(layer "In11.Cu")
		(net "M_K_MA<10>")
	)
	(segment
		(start 102.486968 -134.8486)
		(end 102.486968 -135.390636)
		(width 0.14224)
		(layer "In11.Cu")
		(net "M_K_MA<10>")
	)
	(segment
		(start 102.427278 -131.88569)
		(end 102.36708 -131.945888)
		(width 0.14224)
		(layer "In11.Cu")
		(net "M_K_MA<10>")
	)
	(segment
		(start 102.486968 -130.4544)
		(end 102.361492 -130.579876)
		(width 0.14224)
		(layer "In11.Cu")
		(net "M_K_MA<10>")
	)
	(segment
		(start 102.486968 -129.852166)
		(end 102.486968 -130.4544)
		(width 0.14224)
		(layer "In11.Cu")
		(net "M_K_MA<10>")
	)
	(segment
		(start 102.799388 -129.539746)
		(end 102.486968 -129.852166)
		(width 0.14224)
		(layer "In11.Cu")
		(net "M_K_MA<10>")
	)
	(segment
		(start 102.361492 -131.243324)
		(end 102.427278 -131.30911)
		(width 0.14224)
		(layer "In11.Cu")
		(net "M_K_MA<10>")
	)
	(segment
		(start 97.829116 -104.140508)
		(end 97.829116 -104.466136)
		(width 0.0889)
		(layer "In11.Cu")
		(net "M_K_MA<10>")
	)
	(segment
		(start 102.799388 -136.386824)
		(end 102.799642 -136.387078)
		(width 0.14224)
		(layer "In11.Cu")
		(net "M_K_MA<10>")
	)
	(segment
		(start 97.829116 -104.466136)
		(end 97.829116 -122.697748)
		(width 0.14224)
		(layer "In11.Cu")
		(net "M_K_MA<10>")
	)
	(segment
		(start 98.010218 -126.190756)
		(end 98.010218 -104.28859)
		(width 0.1651)
		(layer "F.Cu")
		(net "M_K_MA<0>")
	)
	(segment
		(start 100.810568 -129.896616)
		(end 99.2505 -128.336548)
		(width 0.1651)
		(layer "F.Cu")
		(net "M_K_MA<0>")
	)
	(segment
		(start 99.2505 -127.431038)
		(end 98.010218 -126.190756)
		(width 0.1651)
		(layer "F.Cu")
		(net "M_K_MA<0>")
	)
	(segment
		(start 96.563688 -100.322888)
		(end 96.079818 -99.67214)
		(width 0.0889)
		(layer "F.Cu")
		(net "M_K_MA<0>")
	)
	(segment
		(start 101.099366 -133.0706)
		(end 101.099366 -134.367778)
		(width 0.1651)
		(layer "F.Cu")
		(net "M_K_MA<0>")
	)
	(segment
		(start 99.2505 -128.336548)
		(end 99.2505 -127.431038)
		(width 0.1651)
		(layer "F.Cu")
		(net "M_K_MA<0>")
	)
	(segment
		(start 101.099366 -130.902456)
		(end 100.810568 -130.613658)
		(width 0.1651)
		(layer "F.Cu")
		(net "M_K_MA<0>")
	)
	(segment
		(start 98.010218 -103.75265)
		(end 96.721168 -102.4636)
		(width 0.0889)
		(layer "F.Cu")
		(net "M_K_MA<0>")
	)
	(segment
		(start 96.600518 -101.373178)
		(end 96.591628 -101.357938)
		(width 0.0889)
		(layer "F.Cu")
		(net "M_K_MA<0>")
	)
	(segment
		(start 96.591628 -101.357938)
		(end 96.586802 -101.349302)
		(width 0.0889)
		(layer "F.Cu")
		(net "M_K_MA<0>")
	)
	(segment
		(start 96.721168 -102.4636)
		(end 96.721168 -101.704648)
		(width 0.0889)
		(layer "F.Cu")
		(net "M_K_MA<0>")
	)
	(segment
		(start 100.810568 -130.613658)
		(end 100.810568 -129.896616)
		(width 0.1651)
		(layer "F.Cu")
		(net "M_K_MA<0>")
	)
	(segment
		(start 98.010218 -104.28859)
		(end 98.010218 -103.75265)
		(width 0.0889)
		(layer "F.Cu")
		(net "M_K_MA<0>")
	)
	(via
		(at 101.099366 -134.367778)
		(size 0.508)
		(drill 0.254)
		(layers "F.Cu" "B.Cu")
		(net "M_K_MA<0>")
	)
	(via
		(at 101.099366 -130.902456)
		(size 0.508)
		(drill 0.254)
		(layers "F.Cu" "B.Cu")
		(net "M_K_MA<0>")
	)
	(arc
		(start 96.586802 -101.349302)
		(mid 96.538047 -101.15295)
		(end 96.591628 -100.957888)
		(width 0.0889)
		(layer "F.Cu")
		(net "M_K_MA<0>")
	)
	(arc
		(start 96.591628 -100.957888)
		(mid 96.670317 -100.636301)
		(end 96.563688 -100.322888)
		(width 0.0889)
		(layer "F.Cu")
		(net "M_K_MA<0>")
	)
	(arc
		(start 96.721168 -101.704648)
		(mid 96.690066 -101.528277)
		(end 96.600518 -101.373178)
		(width 0.0889)
		(layer "F.Cu")
		(net "M_K_MA<0>")
	)
	(segment
		(start 101.099366 -132.876036)
		(end 101.099366 -130.902456)
		(width 0.1651)
		(layer "B.Cu")
		(net "M_K_MA<0>")
	)
	(segment
		(start 101.099366 -130.902456)
		(end 101.099366 -134.367778)
		(width 0.14224)
		(layer "In9.Cu")
		(net "M_K_MA<0>")
	)
	(segment
		(start 84.919312 -91.25204)
		(end 84.347812 -91.25204)
		(width 0.1651)
		(layer "F.Cu")
		(net "M_K_ECC<7>")
	)
	(segment
		(start 74.749406 -133.0706)
		(end 74.749406 -134.340346)
		(width 0.1651)
		(layer "F.Cu")
		(net "M_K_ECC<7>")
	)
	(via
		(at 75.59929 -130.330956)
		(size 0.508)
		(drill 0.254)
		(layers "F.Cu" "B.Cu")
		(net "M_K_ECC<7>")
	)
	(via
		(at 74.749406 -134.340346)
		(size 0.508)
		(drill 0.254)
		(layers "F.Cu" "B.Cu")
		(net "M_K_ECC<7>")
	)
	(via
		(at 84.347812 -91.25204)
		(size 0.508)
		(drill 0.254)
		(layers "F.Cu" "B.Cu")
		(net "M_K_ECC<7>")
	)
	(segment
		(start 75.59929 -128.276096)
		(end 75.59929 -130.330956)
		(width 0.1651)
		(layer "B.Cu")
		(net "M_K_ECC<7>")
	)
	(segment
		(start 75.599544 -128.276096)
		(end 75.59929 -128.276096)
		(width 0.1651)
		(layer "B.Cu")
		(net "M_K_ECC<7>")
	)
	(segment
		(start 78.479396 -117.602)
		(end 77.112368 -117.602)
		(width 0.14224)
		(layer "In2.Cu")
		(net "M_K_ECC<7>")
	)
	(segment
		(start 75.576938 -130.330956)
		(end 75.148694 -130.7592)
		(width 0.14224)
		(layer "In2.Cu")
		(net "M_K_ECC<7>")
	)
	(segment
		(start 77.892148 -118.383304)
		(end 78.033626 -118.524782)
		(width 0.14224)
		(layer "In2.Cu")
		(net "M_K_ECC<7>")
	)
	(segment
		(start 75.941174 -129.989072)
		(end 75.59929 -130.330956)
		(width 0.14224)
		(layer "In2.Cu")
		(net "M_K_ECC<7>")
	)
	(segment
		(start 83.949286 -100.768912)
		(end 83.255612 -101.462586)
		(width 0.0889)
		(layer "In2.Cu")
		(net "M_K_ECC<7>")
	)
	(segment
		(start 78.610968 -110.261654)
		(end 78.610968 -115.867434)
		(width 0.14224)
		(layer "In2.Cu")
		(net "M_K_ECC<7>")
	)
	(segment
		(start 75.148694 -131.188968)
		(end 75.193144 -131.233418)
		(width 0.14224)
		(layer "In2.Cu")
		(net "M_K_ECC<7>")
	)
	(segment
		(start 77.137768 -116.907818)
		(end 78.50886 -116.907818)
		(width 0.14224)
		(layer "In2.Cu")
		(net "M_K_ECC<7>")
	)
	(segment
		(start 75.193144 -131.233418)
		(end 75.193144 -131.9022)
		(width 0.14224)
		(layer "In2.Cu")
		(net "M_K_ECC<7>")
	)
	(segment
		(start 76.934568 -116.704618)
		(end 77.137768 -116.907818)
		(width 0.14224)
		(layer "In2.Cu")
		(net "M_K_ECC<7>")
	)
	(segment
		(start 83.996276 -95.405702)
		(end 84.001102 -95.414338)
		(width 0.0889)
		(layer "In2.Cu")
		(net "M_K_ECC<7>")
	)
	(segment
		(start 75.59929 -130.330956)
		(end 75.576938 -130.330956)
		(width 0.14224)
		(layer "In2.Cu")
		(net "M_K_ECC<7>")
	)
	(segment
		(start 78.256384 -116.222018)
		(end 77.137768 -116.222018)
		(width 0.14224)
		(layer "In2.Cu")
		(net "M_K_ECC<7>")
	)
	(segment
		(start 76.985368 -123.0122)
		(end 75.952096 -124.045472)
		(width 0.14224)
		(layer "In2.Cu")
		(net "M_K_ECC<7>")
	)
	(segment
		(start 83.255612 -101.462586)
		(end 83.255612 -103.090726)
		(width 0.0889)
		(layer "In2.Cu")
		(net "M_K_ECC<7>")
	)
	(segment
		(start 83.883246 -96.208596)
		(end 83.883246 -96.42348)
		(width 0.0889)
		(layer "In2.Cu")
		(net "M_K_ECC<7>")
	)
	(segment
		(start 78.675992 -117.405404)
		(end 78.479396 -117.602)
		(width 0.14224)
		(layer "In2.Cu")
		(net "M_K_ECC<7>")
	)
	(segment
		(start 74.910696 -132.184648)
		(end 74.910696 -132.457952)
		(width 0.14224)
		(layer "In2.Cu")
		(net "M_K_ECC<7>")
	)
	(segment
		(start 75.167744 -133.0198)
		(end 74.910696 -133.276848)
		(width 0.14224)
		(layer "In2.Cu")
		(net "M_K_ECC<7>")
	)
	(segment
		(start 75.199494 -134.162546)
		(end 75.021694 -134.340346)
		(width 0.14224)
		(layer "In2.Cu")
		(net "M_K_ECC<7>")
	)
	(segment
		(start 76.985368 -118.228364)
		(end 77.140308 -118.383304)
		(width 0.14224)
		(layer "In2.Cu")
		(net "M_K_ECC<7>")
	)
	(segment
		(start 84.865972 -92.52712)
		(end 84.859622 -92.537788)
		(width 0.0889)
		(layer "In2.Cu")
		(net "M_K_ECC<7>")
	)
	(segment
		(start 75.199494 -133.83895)
		(end 75.199494 -134.162546)
		(width 0.14224)
		(layer "In2.Cu")
		(net "M_K_ECC<7>")
	)
	(segment
		(start 83.949286 -100.769166)
		(end 83.949286 -100.768912)
		(width 0.0889)
		(layer "In2.Cu")
		(net "M_K_ECC<7>")
	)
	(segment
		(start 78.610968 -115.867434)
		(end 78.256384 -116.222018)
		(width 0.14224)
		(layer "In2.Cu")
		(net "M_K_ECC<7>")
	)
	(segment
		(start 74.910696 -132.457952)
		(end 75.167744 -132.715)
		(width 0.14224)
		(layer "In2.Cu")
		(net "M_K_ECC<7>")
	)
	(segment
		(start 77.140308 -118.383304)
		(end 77.892148 -118.383304)
		(width 0.14224)
		(layer "In2.Cu")
		(net "M_K_ECC<7>")
	)
	(segment
		(start 75.952096 -124.045472)
		(end 75.952096 -125.407928)
		(width 0.14224)
		(layer "In2.Cu")
		(net "M_K_ECC<7>")
	)
	(segment
		(start 75.193144 -131.9022)
		(end 74.910696 -132.184648)
		(width 0.14224)
		(layer "In2.Cu")
		(net "M_K_ECC<7>")
	)
	(segment
		(start 84.001102 -95.414338)
		(end 84.007452 -95.425006)
		(width 0.0889)
		(layer "In2.Cu")
		(net "M_K_ECC<7>")
	)
	(segment
		(start 75.148694 -130.7592)
		(end 75.148694 -131.188968)
		(width 0.14224)
		(layer "In2.Cu")
		(net "M_K_ECC<7>")
	)
	(segment
		(start 78.675992 -117.07495)
		(end 78.675992 -117.405404)
		(width 0.14224)
		(layer "In2.Cu")
		(net "M_K_ECC<7>")
	)
	(segment
		(start 78.50886 -116.907818)
		(end 78.675992 -117.07495)
		(width 0.14224)
		(layer "In2.Cu")
		(net "M_K_ECC<7>")
	)
	(segment
		(start 74.910696 -133.550152)
		(end 75.199494 -133.83895)
		(width 0.14224)
		(layer "In2.Cu")
		(net "M_K_ECC<7>")
	)
	(segment
		(start 77.865224 -119.071644)
		(end 77.140308 -119.071644)
		(width 0.14224)
		(layer "In2.Cu")
		(net "M_K_ECC<7>")
	)
	(segment
		(start 78.033626 -118.524782)
		(end 78.033626 -118.903242)
		(width 0.14224)
		(layer "In2.Cu")
		(net "M_K_ECC<7>")
	)
	(segment
		(start 75.952096 -125.407928)
		(end 76.248768 -125.7046)
		(width 0.14224)
		(layer "In2.Cu")
		(net "M_K_ECC<7>")
	)
	(segment
		(start 84.004912 -96.545146)
		(end 84.004912 -100.71354)
		(width 0.0889)
		(layer "In2.Cu")
		(net "M_K_ECC<7>")
	)
	(segment
		(start 75.952096 -126.839472)
		(end 75.952096 -129.989072)
		(width 0.14224)
		(layer "In2.Cu")
		(net "M_K_ECC<7>")
	)
	(segment
		(start 76.248768 -125.7046)
		(end 76.248768 -126.5428)
		(width 0.14224)
		(layer "In2.Cu")
		(net "M_K_ECC<7>")
	)
	(segment
		(start 84.001102 -96.004888)
		(end 83.883246 -96.208596)
		(width 0.0889)
		(layer "In2.Cu")
		(net "M_K_ECC<7>")
	)
	(segment
		(start 84.859622 -92.537788)
		(end 84.854796 -92.546424)
		(width 0.0889)
		(layer "In2.Cu")
		(net "M_K_ECC<7>")
	)
	(segment
		(start 78.033626 -118.903242)
		(end 77.865224 -119.071644)
		(width 0.14224)
		(layer "In2.Cu")
		(net "M_K_ECC<7>")
	)
	(segment
		(start 84.004912 -100.71354)
		(end 83.949286 -100.769166)
		(width 0.0889)
		(layer "In2.Cu")
		(net "M_K_ECC<7>")
	)
	(segment
		(start 75.167744 -132.715)
		(end 75.167744 -133.0198)
		(width 0.14224)
		(layer "In2.Cu")
		(net "M_K_ECC<7>")
	)
	(segment
		(start 77.112368 -117.602)
		(end 76.985368 -117.729)
		(width 0.14224)
		(layer "In2.Cu")
		(net "M_K_ECC<7>")
	)
	(segment
		(start 75.021694 -134.340346)
		(end 74.749406 -134.340346)
		(width 0.14224)
		(layer "In2.Cu")
		(net "M_K_ECC<7>")
	)
	(segment
		(start 74.910696 -133.276848)
		(end 74.910696 -133.550152)
		(width 0.14224)
		(layer "In2.Cu")
		(net "M_K_ECC<7>")
	)
	(segment
		(start 76.985368 -117.729)
		(end 76.985368 -118.228364)
		(width 0.14224)
		(layer "In2.Cu")
		(net "M_K_ECC<7>")
	)
	(segment
		(start 76.248768 -126.5428)
		(end 75.952096 -126.839472)
		(width 0.14224)
		(layer "In2.Cu")
		(net "M_K_ECC<7>")
	)
	(segment
		(start 83.255612 -103.090726)
		(end 83.4644 -103.299514)
		(width 0.0889)
		(layer "In2.Cu")
		(net "M_K_ECC<7>")
	)
	(segment
		(start 77.140308 -119.071644)
		(end 76.985368 -119.226584)
		(width 0.14224)
		(layer "In2.Cu")
		(net "M_K_ECC<7>")
	)
	(segment
		(start 83.883246 -96.42348)
		(end 84.004912 -96.545146)
		(width 0.0889)
		(layer "In2.Cu")
		(net "M_K_ECC<7>")
	)
	(segment
		(start 75.952096 -129.989072)
		(end 75.941174 -129.989072)
		(width 0.14224)
		(layer "In2.Cu")
		(net "M_K_ECC<7>")
	)
	(segment
		(start 76.985368 -119.226584)
		(end 76.985368 -123.0122)
		(width 0.14224)
		(layer "In2.Cu")
		(net "M_K_ECC<7>")
	)
	(segment
		(start 77.137768 -116.222018)
		(end 76.934568 -116.425218)
		(width 0.14224)
		(layer "In2.Cu")
		(net "M_K_ECC<7>")
	)
	(segment
		(start 76.934568 -116.425218)
		(end 76.934568 -116.704618)
		(width 0.14224)
		(layer "In2.Cu")
		(net "M_K_ECC<7>")
	)
	(segment
		(start 84.369402 -93.82379)
		(end 84.329778 -93.82379)
		(width 0.0889)
		(layer "In2.Cu")
		(net "M_K_ECC<7>")
	)
	(segment
		(start 83.4644 -103.299514)
		(end 83.4644 -105.408222)
		(width 0.14224)
		(layer "In2.Cu")
		(net "M_K_ECC<7>")
	)
	(segment
		(start 83.4644 -105.408222)
		(end 78.610968 -110.261654)
		(width 0.14224)
		(layer "In2.Cu")
		(net "M_K_ECC<7>")
	)
	(arc
		(start 84.347812 -91.25204)
		(mid 84.622996 -91.585446)
		(end 84.859622 -91.947238)
		(width 0.0889)
		(layer "In2.Cu")
		(net "M_K_ECC<7>")
	)
	(arc
		(start 84.329778 -93.82379)
		(mid 83.996862 -94.031242)
		(end 84.001102 -94.423484)
		(width 0.0889)
		(layer "In2.Cu")
		(net "M_K_ECC<7>")
	)
	(arc
		(start 84.007452 -95.425006)
		(mid 84.08025 -95.715769)
		(end 84.001102 -96.004888)
		(width 0.0889)
		(layer "In2.Cu")
		(net "M_K_ECC<7>")
	)
	(arc
		(start 84.001102 -94.423484)
		(mid 84.080233 -94.718886)
		(end 84.001102 -95.014288)
		(width 0.0889)
		(layer "In2.Cu")
		(net "M_K_ECC<7>")
	)
	(arc
		(start 84.854796 -92.546424)
		(mid 84.806041 -92.742776)
		(end 84.859622 -92.937838)
		(width 0.0889)
		(layer "In2.Cu")
		(net "M_K_ECC<7>")
	)
	(arc
		(start 84.001102 -95.014288)
		(mid 83.947632 -95.209351)
		(end 83.996276 -95.405702)
		(width 0.0889)
		(layer "In2.Cu")
		(net "M_K_ECC<7>")
	)
	(arc
		(start 84.859622 -91.947238)
		(mid 84.938844 -92.236356)
		(end 84.865972 -92.52712)
		(width 0.0889)
		(layer "In2.Cu")
		(net "M_K_ECC<7>")
	)
	(arc
		(start 84.859622 -92.937838)
		(mid 84.864876 -93.519346)
		(end 84.369402 -93.82379)
		(width 0.0889)
		(layer "In2.Cu")
		(net "M_K_ECC<7>")
	)
	(segment
		(start 75.731624 -136.35228)
		(end 75.599544 -136.2202)
		(width 0.1651)
		(layer "F.Cu")
		(net "M_K_ECC<6>")
	)
	(segment
		(start 75.599544 -136.7028)
		(end 75.731624 -136.57072)
		(width 0.1651)
		(layer "F.Cu")
		(net "M_K_ECC<6>")
	)
	(segment
		(start 75.599544 -137.67054)
		(end 75.599544 -136.7028)
		(width 0.1651)
		(layer "F.Cu")
		(net "M_K_ECC<6>")
	)
	(segment
		(start 84.919312 -89.27084)
		(end 84.347812 -89.27084)
		(width 0.1651)
		(layer "F.Cu")
		(net "M_K_ECC<6>")
	)
	(segment
		(start 75.731624 -136.57072)
		(end 75.731624 -136.35228)
		(width 0.1651)
		(layer "F.Cu")
		(net "M_K_ECC<6>")
	)
	(segment
		(start 75.599544 -136.2202)
		(end 75.599544 -135.915654)
		(width 0.1651)
		(layer "F.Cu")
		(net "M_K_ECC<6>")
	)
	(segment
		(start 75.599544 -135.915654)
		(end 75.59929 -135.9154)
		(width 0.1651)
		(layer "F.Cu")
		(net "M_K_ECC<6>")
	)
	(via
		(at 74.749406 -131.611878)
		(size 0.508)
		(drill 0.254)
		(layers "F.Cu" "B.Cu")
		(net "M_K_ECC<6>")
	)
	(via
		(at 75.59929 -135.9154)
		(size 0.508)
		(drill 0.254)
		(layers "F.Cu" "B.Cu")
		(net "M_K_ECC<6>")
	)
	(via
		(at 84.347812 -89.27084)
		(size 0.508)
		(drill 0.254)
		(layers "F.Cu" "B.Cu")
		(net "M_K_ECC<6>")
	)
	(segment
		(start 74.749406 -132.876036)
		(end 74.749406 -131.611878)
		(width 0.1651)
		(layer "B.Cu")
		(net "M_K_ECC<6>")
	)
	(segment
		(start 77.07376 -115.317016)
		(end 76.820776 -115.57)
		(width 0.14224)
		(layer "In2.Cu")
		(net "M_K_ECC<6>")
	)
	(segment
		(start 83.948524 -90.290396)
		(end 83.948016 -91.232736)
		(width 0.0889)
		(layer "In2.Cu")
		(net "M_K_ECC<6>")
	)
	(segment
		(start 77.974952 -109.980984)
		(end 77.974952 -113.690654)
		(width 0.14224)
		(layer "In2.Cu")
		(net "M_K_ECC<6>")
	)
	(segment
		(start 77.07376 -114.935254)
		(end 77.07376 -115.317016)
		(width 0.14224)
		(layer "In2.Cu")
		(net "M_K_ECC<6>")
	)
	(segment
		(start 83.06562 -103.050594)
		(end 82.8167 -103.299514)
		(width 0.0889)
		(layer "In2.Cu")
		(net "M_K_ECC<6>")
	)
	(segment
		(start 83.836002 -95.909638)
		(end 83.693254 -96.15678)
		(width 0.0889)
		(layer "In2.Cu")
		(net "M_K_ECC<6>")
	)
	(segment
		(start 83.06562 -101.383846)
		(end 83.06562 -103.050594)
		(width 0.0889)
		(layer "In2.Cu")
		(net "M_K_ECC<6>")
	)
	(segment
		(start 83.836002 -95.509588)
		(end 83.840828 -95.518224)
		(width 0.0889)
		(layer "In2.Cu")
		(net "M_K_ECC<6>")
	)
	(segment
		(start 75.317096 -127.008128)
		(end 75.317096 -129.732278)
		(width 0.14224)
		(layer "In2.Cu")
		(net "M_K_ECC<6>")
	)
	(segment
		(start 84.694522 -92.442538)
		(end 84.688172 -92.453206)
		(width 0.0889)
		(layer "In2.Cu")
		(net "M_K_ECC<6>")
	)
	(segment
		(start 84.699348 -92.433902)
		(end 84.694522 -92.442538)
		(width 0.0889)
		(layer "In2.Cu")
		(net "M_K_ECC<6>")
	)
	(segment
		(start 76.604368 -114.732054)
		(end 76.87056 -114.732054)
		(width 0.14224)
		(layer "In2.Cu")
		(net "M_K_ECC<6>")
	)
	(segment
		(start 83.693254 -96.50222)
		(end 83.81492 -96.623886)
		(width 0.0889)
		(layer "In2.Cu")
		(net "M_K_ECC<6>")
	)
	(segment
		(start 83.81492 -96.623886)
		(end 83.81492 -100.634546)
		(width 0.0889)
		(layer "In2.Cu")
		(net "M_K_ECC<6>")
	)
	(segment
		(start 77.974952 -113.690654)
		(end 77.746352 -113.919254)
		(width 0.14224)
		(layer "In2.Cu")
		(net "M_K_ECC<6>")
	)
	(segment
		(start 77.746352 -113.919254)
		(end 76.604368 -113.919254)
		(width 0.14224)
		(layer "In2.Cu")
		(net "M_K_ECC<6>")
	)
	(segment
		(start 74.316336 -134.632446)
		(end 75.59929 -135.9154)
		(width 0.14224)
		(layer "In2.Cu")
		(net "M_K_ECC<6>")
	)
	(segment
		(start 82.8167 -105.139236)
		(end 77.974952 -109.980984)
		(width 0.14224)
		(layer "In2.Cu")
		(net "M_K_ECC<6>")
	)
	(segment
		(start 75.435968 -125.3236)
		(end 75.181968 -125.5776)
		(width 0.14224)
		(layer "In2.Cu")
		(net "M_K_ECC<6>")
	)
	(segment
		(start 76.820776 -115.57)
		(end 76.528168 -115.57)
		(width 0.14224)
		(layer "In2.Cu")
		(net "M_K_ECC<6>")
	)
	(segment
		(start 76.324968 -122.7328)
		(end 75.435968 -123.6218)
		(width 0.14224)
		(layer "In2.Cu")
		(net "M_K_ECC<6>")
	)
	(segment
		(start 82.8167 -103.299514)
		(end 82.8167 -105.139236)
		(width 0.14224)
		(layer "In2.Cu")
		(net "M_K_ECC<6>")
	)
	(segment
		(start 76.528168 -115.57)
		(end 76.324968 -115.7732)
		(width 0.14224)
		(layer "In2.Cu")
		(net "M_K_ECC<6>")
	)
	(segment
		(start 76.604368 -113.919254)
		(end 76.401168 -114.122454)
		(width 0.14224)
		(layer "In2.Cu")
		(net "M_K_ECC<6>")
	)
	(segment
		(start 76.87056 -114.732054)
		(end 77.07376 -114.935254)
		(width 0.14224)
		(layer "In2.Cu")
		(net "M_K_ECC<6>")
	)
	(segment
		(start 83.836002 -94.518988)
		(end 83.840828 -94.527624)
		(width 0.0889)
		(layer "In2.Cu")
		(net "M_K_ECC<6>")
	)
	(segment
		(start 74.316336 -132.044948)
		(end 74.316336 -134.632446)
		(width 0.14224)
		(layer "In2.Cu")
		(net "M_K_ECC<6>")
	)
	(segment
		(start 76.401168 -114.528854)
		(end 76.604368 -114.732054)
		(width 0.14224)
		(layer "In2.Cu")
		(net "M_K_ECC<6>")
	)
	(segment
		(start 74.749406 -131.611878)
		(end 74.316336 -132.044948)
		(width 0.14224)
		(layer "In2.Cu")
		(net "M_K_ECC<6>")
	)
	(segment
		(start 75.181968 -125.5776)
		(end 75.181968 -126.873)
		(width 0.14224)
		(layer "In2.Cu")
		(net "M_K_ECC<6>")
	)
	(segment
		(start 74.580496 -130.468878)
		(end 74.580496 -131.442968)
		(width 0.14224)
		(layer "In2.Cu")
		(net "M_K_ECC<6>")
	)
	(segment
		(start 76.324968 -115.7732)
		(end 76.324968 -122.7328)
		(width 0.14224)
		(layer "In2.Cu")
		(net "M_K_ECC<6>")
	)
	(segment
		(start 84.347812 -89.27084)
		(end 83.979258 -90.105738)
		(width 0.0889)
		(layer "In2.Cu")
		(net "M_K_ECC<6>")
	)
	(segment
		(start 76.401168 -114.122454)
		(end 76.401168 -114.528854)
		(width 0.14224)
		(layer "In2.Cu")
		(net "M_K_ECC<6>")
	)
	(segment
		(start 75.317096 -129.732278)
		(end 74.580496 -130.468878)
		(width 0.14224)
		(layer "In2.Cu")
		(net "M_K_ECC<6>")
	)
	(segment
		(start 75.181968 -126.873)
		(end 75.317096 -127.008128)
		(width 0.14224)
		(layer "In2.Cu")
		(net "M_K_ECC<6>")
	)
	(segment
		(start 84.365846 -93.633036)
		(end 84.330032 -93.633036)
		(width 0.0889)
		(layer "In2.Cu")
		(net "M_K_ECC<6>")
	)
	(segment
		(start 83.693254 -96.15678)
		(end 83.693254 -96.50222)
		(width 0.0889)
		(layer "In2.Cu")
		(net "M_K_ECC<6>")
	)
	(segment
		(start 83.81492 -100.634546)
		(end 83.06562 -101.383846)
		(width 0.0889)
		(layer "In2.Cu")
		(net "M_K_ECC<6>")
	)
	(segment
		(start 83.829652 -95.49892)
		(end 83.836002 -95.509588)
		(width 0.0889)
		(layer "In2.Cu")
		(net "M_K_ECC<6>")
	)
	(segment
		(start 75.435968 -123.6218)
		(end 75.435968 -125.3236)
		(width 0.14224)
		(layer "In2.Cu")
		(net "M_K_ECC<6>")
	)
	(segment
		(start 74.580496 -131.442968)
		(end 74.749406 -131.611878)
		(width 0.14224)
		(layer "In2.Cu")
		(net "M_K_ECC<6>")
	)
	(arc
		(start 84.694522 -93.033088)
		(mid 84.698932 -93.425551)
		(end 84.365846 -93.633036)
		(width 0.0889)
		(layer "In2.Cu")
		(net "M_K_ECC<6>")
	)
	(arc
		(start 84.694522 -92.042488)
		(mid 84.747992 -92.237551)
		(end 84.699348 -92.433902)
		(width 0.0889)
		(layer "In2.Cu")
		(net "M_K_ECC<6>")
	)
	(arc
		(start 84.330032 -93.633036)
		(mid 83.831781 -93.935876)
		(end 83.836002 -94.518988)
		(width 0.0889)
		(layer "In2.Cu")
		(net "M_K_ECC<6>")
	)
	(arc
		(start 84.073492 -91.543632)
		(mid 84.290095 -91.734614)
		(end 84.534248 -91.888818)
		(width 0.0889)
		(layer "In2.Cu")
		(net "M_K_ECC<6>")
	)
	(arc
		(start 83.836002 -94.919038)
		(mid 83.75678 -95.208156)
		(end 83.829652 -95.49892)
		(width 0.0889)
		(layer "In2.Cu")
		(net "M_K_ECC<6>")
	)
	(arc
		(start 83.979258 -90.105738)
		(mid 83.952949 -90.196245)
		(end 83.948524 -90.290396)
		(width 0.0889)
		(layer "In2.Cu")
		(net "M_K_ECC<6>")
	)
	(arc
		(start 83.840828 -94.527624)
		(mid 83.889583 -94.723976)
		(end 83.836002 -94.919038)
		(width 0.0889)
		(layer "In2.Cu")
		(net "M_K_ECC<6>")
	)
	(arc
		(start 84.688172 -92.453206)
		(mid 84.615374 -92.743969)
		(end 84.694522 -93.033088)
		(width 0.0889)
		(layer "In2.Cu")
		(net "M_K_ECC<6>")
	)
	(arc
		(start 83.948016 -91.232736)
		(mid 83.976583 -91.401989)
		(end 84.073492 -91.543632)
		(width 0.0889)
		(layer "In2.Cu")
		(net "M_K_ECC<6>")
	)
	(arc
		(start 84.534248 -91.888818)
		(mid 84.62536 -91.95421)
		(end 84.694522 -92.042488)
		(width 0.0889)
		(layer "In2.Cu")
		(net "M_K_ECC<6>")
	)
	(arc
		(start 83.840828 -95.518224)
		(mid 83.889583 -95.714576)
		(end 83.836002 -95.909638)
		(width 0.0889)
		(layer "In2.Cu")
		(net "M_K_ECC<6>")
	)
	(segment
		(start 68.799456 -133.0706)
		(end 68.799456 -134.340346)
		(width 0.1651)
		(layer "F.Cu")
		(net "M_K_ECC<5>")
	)
	(segment
		(start 82.343752 -90.756486)
		(end 81.772252 -90.756486)
		(width 0.1651)
		(layer "F.Cu")
		(net "M_K_ECC<5>")
	)
	(via
		(at 81.772252 -90.756486)
		(size 0.508)
		(drill 0.254)
		(layers "F.Cu" "B.Cu")
		(net "M_K_ECC<5>")
	)
	(via
		(at 68.799456 -134.340346)
		(size 0.508)
		(drill 0.254)
		(layers "F.Cu" "B.Cu")
		(net "M_K_ECC<5>")
	)
	(via
		(at 69.57314 -130.330956)
		(size 0.508)
		(drill 0.254)
		(layers "F.Cu" "B.Cu")
		(net "M_K_ECC<5>")
	)
	(segment
		(start 69.64934 -130.254756)
		(end 69.57314 -130.330956)
		(width 0.1651)
		(layer "B.Cu")
		(net "M_K_ECC<5>")
	)
	(segment
		(start 69.64934 -128.276096)
		(end 69.64934 -130.254756)
		(width 0.1651)
		(layer "B.Cu")
		(net "M_K_ECC<5>")
	)
	(segment
		(start 69.695568 -127.78994)
		(end 69.492368 -127.99314)
		(width 0.14224)
		(layer "In2.Cu")
		(net "M_K_ECC<5>")
	)
	(segment
		(start 81.772252 -90.418412)
		(end 81.71434 -90.3605)
		(width 0.0889)
		(layer "In2.Cu")
		(net "M_K_ECC<5>")
	)
	(segment
		(start 70.800722 -122.52198)
		(end 70.645782 -122.67692)
		(width 0.14224)
		(layer "In2.Cu")
		(net "M_K_ECC<5>")
	)
	(segment
		(start 80.562196 -96.396302)
		(end 80.567022 -96.404938)
		(width 0.0889)
		(layer "In2.Cu")
		(net "M_K_ECC<5>")
	)
	(segment
		(start 80.567022 -95.414338)
		(end 80.573372 -95.425006)
		(width 0.0889)
		(layer "In2.Cu")
		(net "M_K_ECC<5>")
	)
	(segment
		(start 80.931512 -91.84259)
		(end 80.898746 -91.84259)
		(width 0.0889)
		(layer "In2.Cu")
		(net "M_K_ECC<5>")
	)
	(segment
		(start 80.562196 -92.433902)
		(end 80.567022 -92.442538)
		(width 0.0889)
		(layer "In2.Cu")
		(net "M_K_ECC<5>")
	)
	(segment
		(start 70.228968 -122.82932)
		(end 70.228968 -125.603)
		(width 0.14224)
		(layer "In2.Cu")
		(net "M_K_ECC<5>")
	)
	(segment
		(start 70.80758 -120.829578)
		(end 70.80758 -121.182638)
		(width 0.14224)
		(layer "In2.Cu")
		(net "M_K_ECC<5>")
	)
	(segment
		(start 70.244208 -122.01398)
		(end 70.645782 -122.01398)
		(width 0.14224)
		(layer "In2.Cu")
		(net "M_K_ECC<5>")
	)
	(segment
		(start 70.230492 -121.35104)
		(end 70.08241 -121.499122)
		(width 0.14224)
		(layer "In2.Cu")
		(net "M_K_ECC<5>")
	)
	(segment
		(start 80.562196 -95.405702)
		(end 80.567022 -95.414338)
		(width 0.0889)
		(layer "In2.Cu")
		(net "M_K_ECC<5>")
	)
	(segment
		(start 70.08241 -121.852182)
		(end 70.244208 -122.01398)
		(width 0.14224)
		(layer "In2.Cu")
		(net "M_K_ECC<5>")
	)
	(segment
		(start 69.57314 -130.330956)
		(end 69.550788 -130.330956)
		(width 0.14224)
		(layer "In2.Cu")
		(net "M_K_ECC<5>")
	)
	(segment
		(start 69.224144 -134.187946)
		(end 69.071744 -134.340346)
		(width 0.14224)
		(layer "In2.Cu")
		(net "M_K_ECC<5>")
	)
	(segment
		(start 78.879446 -103.585518)
		(end 72.159368 -110.305596)
		(width 0.14224)
		(layer "In2.Cu")
		(net "M_K_ECC<5>")
	)
	(segment
		(start 80.567022 -97.395538)
		(end 80.573372 -97.406206)
		(width 0.0889)
		(layer "In2.Cu")
		(net "M_K_ECC<5>")
	)
	(segment
		(start 70.666102 -120.6881)
		(end 70.80758 -120.829578)
		(width 0.14224)
		(layer "In2.Cu")
		(net "M_K_ECC<5>")
	)
	(segment
		(start 70.381368 -122.67692)
		(end 70.228968 -122.82932)
		(width 0.14224)
		(layer "In2.Cu")
		(net "M_K_ECC<5>")
	)
	(segment
		(start 79.734918 -99.27209)
		(end 78.80223 -100.204778)
		(width 0.0889)
		(layer "In2.Cu")
		(net "M_K_ECC<5>")
	)
	(segment
		(start 81.772252 -90.756486)
		(end 81.772252 -90.418412)
		(width 0.0889)
		(layer "In2.Cu")
		(net "M_K_ECC<5>")
	)
	(segment
		(start 70.645782 -122.67692)
		(end 70.381368 -122.67692)
		(width 0.14224)
		(layer "In2.Cu")
		(net "M_K_ECC<5>")
	)
	(segment
		(start 80.562196 -93.424502)
		(end 80.567022 -93.433138)
		(width 0.0889)
		(layer "In2.Cu")
		(net "M_K_ECC<5>")
	)
	(segment
		(start 70.645782 -122.01398)
		(end 70.800722 -122.16892)
		(width 0.14224)
		(layer "In2.Cu")
		(net "M_K_ECC<5>")
	)
	(segment
		(start 70.800722 -122.16892)
		(end 70.800722 -122.52198)
		(width 0.14224)
		(layer "In2.Cu")
		(net "M_K_ECC<5>")
	)
	(segment
		(start 69.550788 -130.330956)
		(end 69.122544 -130.7592)
		(width 0.14224)
		(layer "In2.Cu")
		(net "M_K_ECC<5>")
	)
	(segment
		(start 78.80223 -101.623622)
		(end 78.879446 -101.700838)
		(width 0.0889)
		(layer "In2.Cu")
		(net "M_K_ECC<5>")
	)
	(segment
		(start 80.573372 -94.01302)
		(end 80.567022 -94.023688)
		(width 0.0889)
		(layer "In2.Cu")
		(net "M_K_ECC<5>")
	)
	(segment
		(start 70.08241 -121.499122)
		(end 70.08241 -121.852182)
		(width 0.14224)
		(layer "In2.Cu")
		(net "M_K_ECC<5>")
	)
	(segment
		(start 80.567022 -92.442538)
		(end 80.573372 -92.453206)
		(width 0.0889)
		(layer "In2.Cu")
		(net "M_K_ECC<5>")
	)
	(segment
		(start 72.159368 -110.305596)
		(end 72.159368 -118.2878)
		(width 0.14224)
		(layer "In2.Cu")
		(net "M_K_ECC<5>")
	)
	(segment
		(start 78.879446 -101.700838)
		(end 78.879446 -103.585518)
		(width 0.14224)
		(layer "In2.Cu")
		(net "M_K_ECC<5>")
	)
	(segment
		(start 78.80223 -100.204778)
		(end 78.80223 -101.623622)
		(width 0.0889)
		(layer "In2.Cu")
		(net "M_K_ECC<5>")
	)
	(segment
		(start 70.237096 -120.6881)
		(end 70.666102 -120.6881)
		(width 0.14224)
		(layer "In2.Cu")
		(net "M_K_ECC<5>")
	)
	(segment
		(start 70.051168 -125.7808)
		(end 70.051168 -127.5842)
		(width 0.14224)
		(layer "In2.Cu")
		(net "M_K_ECC<5>")
	)
	(segment
		(start 68.960746 -132.216144)
		(end 68.960746 -132.553456)
		(width 0.14224)
		(layer "In2.Cu")
		(net "M_K_ECC<5>")
	)
	(segment
		(start 69.122544 -130.7592)
		(end 69.122544 -131.318)
		(width 0.14224)
		(layer "In2.Cu")
		(net "M_K_ECC<5>")
	)
	(segment
		(start 70.228968 -125.603)
		(end 70.051168 -125.7808)
		(width 0.14224)
		(layer "In2.Cu")
		(net "M_K_ECC<5>")
	)
	(segment
		(start 68.960746 -132.553456)
		(end 69.198744 -132.791454)
		(width 0.14224)
		(layer "In2.Cu")
		(net "M_K_ECC<5>")
	)
	(segment
		(start 80.567022 -98.386138)
		(end 80.573372 -98.396806)
		(width 0.0889)
		(layer "In2.Cu")
		(net "M_K_ECC<5>")
	)
	(segment
		(start 69.957696 -128.709928)
		(end 69.957696 -129.9464)
		(width 0.14224)
		(layer "In2.Cu")
		(net "M_K_ECC<5>")
	)
	(segment
		(start 68.960746 -133.696456)
		(end 69.224144 -133.959854)
		(width 0.14224)
		(layer "In2.Cu")
		(net "M_K_ECC<5>")
	)
	(segment
		(start 69.198744 -133.146546)
		(end 68.960746 -133.384544)
		(width 0.14224)
		(layer "In2.Cu")
		(net "M_K_ECC<5>")
	)
	(segment
		(start 80.562196 -97.386902)
		(end 80.567022 -97.395538)
		(width 0.0889)
		(layer "In2.Cu")
		(net "M_K_ECC<5>")
	)
	(segment
		(start 69.492368 -127.99314)
		(end 69.492368 -128.39954)
		(width 0.14224)
		(layer "In2.Cu")
		(net "M_K_ECC<5>")
	)
	(segment
		(start 69.122544 -131.318)
		(end 69.249544 -131.445)
		(width 0.14224)
		(layer "In2.Cu")
		(net "M_K_ECC<5>")
	)
	(segment
		(start 70.100952 -120.346216)
		(end 70.100952 -120.551956)
		(width 0.14224)
		(layer "In2.Cu")
		(net "M_K_ECC<5>")
	)
	(segment
		(start 70.80758 -121.182638)
		(end 70.639178 -121.35104)
		(width 0.14224)
		(layer "In2.Cu")
		(net "M_K_ECC<5>")
	)
	(segment
		(start 69.224144 -133.959854)
		(end 69.224144 -134.187946)
		(width 0.14224)
		(layer "In2.Cu")
		(net "M_K_ECC<5>")
	)
	(segment
		(start 70.100952 -120.551956)
		(end 70.237096 -120.6881)
		(width 0.14224)
		(layer "In2.Cu")
		(net "M_K_ECC<5>")
	)
	(segment
		(start 69.249544 -131.927346)
		(end 68.960746 -132.216144)
		(width 0.14224)
		(layer "In2.Cu")
		(net "M_K_ECC<5>")
	)
	(segment
		(start 68.960746 -133.384544)
		(end 68.960746 -133.696456)
		(width 0.14224)
		(layer "In2.Cu")
		(net "M_K_ECC<5>")
	)
	(segment
		(start 70.639178 -121.35104)
		(end 70.230492 -121.35104)
		(width 0.14224)
		(layer "In2.Cu")
		(net "M_K_ECC<5>")
	)
	(segment
		(start 80.562196 -98.377502)
		(end 80.567022 -98.386138)
		(width 0.0889)
		(layer "In2.Cu")
		(net "M_K_ECC<5>")
	)
	(segment
		(start 69.850508 -128.60274)
		(end 69.957696 -128.709928)
		(width 0.14224)
		(layer "In2.Cu")
		(net "M_K_ECC<5>")
	)
	(segment
		(start 69.695568 -128.60274)
		(end 69.850508 -128.60274)
		(width 0.14224)
		(layer "In2.Cu")
		(net "M_K_ECC<5>")
	)
	(segment
		(start 69.492368 -128.39954)
		(end 69.695568 -128.60274)
		(width 0.14224)
		(layer "In2.Cu")
		(net "M_K_ECC<5>")
	)
	(segment
		(start 72.159368 -118.2878)
		(end 70.100952 -120.346216)
		(width 0.14224)
		(layer "In2.Cu")
		(net "M_K_ECC<5>")
	)
	(segment
		(start 69.249544 -131.445)
		(end 69.249544 -131.927346)
		(width 0.14224)
		(layer "In2.Cu")
		(net "M_K_ECC<5>")
	)
	(segment
		(start 70.051168 -127.5842)
		(end 69.845428 -127.78994)
		(width 0.14224)
		(layer "In2.Cu")
		(net "M_K_ECC<5>")
	)
	(segment
		(start 69.198744 -132.791454)
		(end 69.198744 -133.146546)
		(width 0.14224)
		(layer "In2.Cu")
		(net "M_K_ECC<5>")
	)
	(segment
		(start 80.0735 -99.27209)
		(end 79.734918 -99.27209)
		(width 0.0889)
		(layer "In2.Cu")
		(net "M_K_ECC<5>")
	)
	(segment
		(start 69.845428 -127.78994)
		(end 69.695568 -127.78994)
		(width 0.14224)
		(layer "In2.Cu")
		(net "M_K_ECC<5>")
	)
	(segment
		(start 69.071744 -134.340346)
		(end 68.799456 -134.340346)
		(width 0.14224)
		(layer "In2.Cu")
		(net "M_K_ECC<5>")
	)
	(segment
		(start 69.957696 -129.9464)
		(end 69.57314 -130.330956)
		(width 0.14224)
		(layer "In2.Cu")
		(net "M_K_ECC<5>")
	)
	(segment
		(start 80.567022 -96.404938)
		(end 80.573372 -96.415606)
		(width 0.0889)
		(layer "In2.Cu")
		(net "M_K_ECC<5>")
	)
	(arc
		(start 81.71434 -90.3605)
		(mid 81.412071 -90.582049)
		(end 81.425542 -90.956638)
		(width 0.0889)
		(layer "In2.Cu")
		(net "M_K_ECC<5>")
	)
	(arc
		(start 80.573372 -95.425006)
		(mid 80.64617 -95.715769)
		(end 80.567022 -96.004888)
		(width 0.0889)
		(layer "In2.Cu")
		(net "M_K_ECC<5>")
	)
	(arc
		(start 80.567022 -96.995488)
		(mid 80.513552 -97.190551)
		(end 80.562196 -97.386902)
		(width 0.0889)
		(layer "In2.Cu")
		(net "M_K_ECC<5>")
	)
	(arc
		(start 80.573372 -92.453206)
		(mid 80.64617 -92.743969)
		(end 80.567022 -93.033088)
		(width 0.0889)
		(layer "In2.Cu")
		(net "M_K_ECC<5>")
	)
	(arc
		(start 80.567022 -95.014288)
		(mid 80.513552 -95.209351)
		(end 80.562196 -95.405702)
		(width 0.0889)
		(layer "In2.Cu")
		(net "M_K_ECC<5>")
	)
	(arc
		(start 80.567022 -93.433138)
		(mid 80.646244 -93.722256)
		(end 80.573372 -94.01302)
		(width 0.0889)
		(layer "In2.Cu")
		(net "M_K_ECC<5>")
	)
	(arc
		(start 80.573372 -97.406206)
		(mid 80.64617 -97.696969)
		(end 80.567022 -97.986088)
		(width 0.0889)
		(layer "In2.Cu")
		(net "M_K_ECC<5>")
	)
	(arc
		(start 80.567022 -96.004888)
		(mid 80.513552 -96.199951)
		(end 80.562196 -96.396302)
		(width 0.0889)
		(layer "In2.Cu")
		(net "M_K_ECC<5>")
	)
	(arc
		(start 80.573372 -96.415606)
		(mid 80.64617 -96.706369)
		(end 80.567022 -96.995488)
		(width 0.0889)
		(layer "In2.Cu")
		(net "M_K_ECC<5>")
	)
	(arc
		(start 80.567022 -94.023688)
		(mid 80.513523 -94.223586)
		(end 80.567022 -94.423484)
		(width 0.0889)
		(layer "In2.Cu")
		(net "M_K_ECC<5>")
	)
	(arc
		(start 80.898746 -91.84259)
		(mid 80.565828 -92.044581)
		(end 80.562196 -92.433902)
		(width 0.0889)
		(layer "In2.Cu")
		(net "M_K_ECC<5>")
	)
	(arc
		(start 80.567022 -94.423484)
		(mid 80.646153 -94.718886)
		(end 80.567022 -95.014288)
		(width 0.0889)
		(layer "In2.Cu")
		(net "M_K_ECC<5>")
	)
	(arc
		(start 80.567022 -93.033088)
		(mid 80.513552 -93.228151)
		(end 80.562196 -93.424502)
		(width 0.0889)
		(layer "In2.Cu")
		(net "M_K_ECC<5>")
	)
	(arc
		(start 81.425542 -90.956638)
		(mid 81.429871 -91.53981)
		(end 80.931512 -91.84259)
		(width 0.0889)
		(layer "In2.Cu")
		(net "M_K_ECC<5>")
	)
	(arc
		(start 80.573372 -98.396806)
		(mid 80.568523 -98.974426)
		(end 80.0735 -99.27209)
		(width 0.0889)
		(layer "In2.Cu")
		(net "M_K_ECC<5>")
	)
	(arc
		(start 80.567022 -97.986088)
		(mid 80.513552 -98.181151)
		(end 80.562196 -98.377502)
		(width 0.0889)
		(layer "In2.Cu")
		(net "M_K_ECC<5>")
	)
	(segment
		(start 69.64934 -137.67054)
		(end 69.64934 -136.345168)
		(width 0.1651)
		(layer "F.Cu")
		(net "M_K_ECC<4>")
	)
	(segment
		(start 82.343752 -89.765886)
		(end 81.772252 -89.765886)
		(width 0.1651)
		(layer "F.Cu")
		(net "M_K_ECC<4>")
	)
	(segment
		(start 69.64934 -136.345168)
		(end 69.551296 -135.8138)
		(width 0.1651)
		(layer "F.Cu")
		(net "M_K_ECC<4>")
	)
	(via
		(at 68.799456 -131.611878)
		(size 0.508)
		(drill 0.254)
		(layers "F.Cu" "B.Cu")
		(net "M_K_ECC<4>")
	)
	(via
		(at 69.551296 -135.8138)
		(size 0.508)
		(drill 0.254)
		(layers "F.Cu" "B.Cu")
		(net "M_K_ECC<4>")
	)
	(via
		(at 81.772252 -89.765886)
		(size 0.508)
		(drill 0.254)
		(layers "F.Cu" "B.Cu")
		(net "M_K_ECC<4>")
	)
	(segment
		(start 68.799456 -132.876036)
		(end 68.799456 -131.611878)
		(width 0.1651)
		(layer "B.Cu")
		(net "M_K_ECC<4>")
	)
	(segment
		(start 80.401922 -96.500188)
		(end 80.406748 -96.508824)
		(width 0.0889)
		(layer "In2.Cu")
		(net "M_K_ECC<4>")
	)
	(segment
		(start 80.395572 -96.48952)
		(end 80.401922 -96.500188)
		(width 0.0889)
		(layer "In2.Cu")
		(net "M_K_ECC<4>")
	)
	(segment
		(start 69.079364 -125.570996)
		(end 69.289168 -125.7808)
		(width 0.14224)
		(layer "In2.Cu")
		(net "M_K_ECC<4>")
	)
	(segment
		(start 69.009768 -127.889)
		(end 69.009768 -129.0066)
		(width 0.14224)
		(layer "In2.Cu")
		(net "M_K_ECC<4>")
	)
	(segment
		(start 68.366386 -134.57809)
		(end 68.524374 -134.736078)
		(width 0.14224)
		(layer "In2.Cu")
		(net "M_K_ECC<4>")
	)
	(segment
		(start 80.401922 -98.481388)
		(end 80.406748 -98.490024)
		(width 0.0889)
		(layer "In2.Cu")
		(net "M_K_ECC<4>")
	)
	(segment
		(start 69.289168 -127.6096)
		(end 69.009768 -127.889)
		(width 0.14224)
		(layer "In2.Cu")
		(net "M_K_ECC<4>")
	)
	(segment
		(start 80.401922 -92.537788)
		(end 80.406748 -92.546424)
		(width 0.0889)
		(layer "In2.Cu")
		(net "M_K_ECC<4>")
	)
	(segment
		(start 78.611476 -101.100636)
		(end 78.224634 -101.487478)
		(width 0.0889)
		(layer "In2.Cu")
		(net "M_K_ECC<4>")
	)
	(segment
		(start 70.432168 -118.8212)
		(end 70.254368 -118.6434)
		(width 0.14224)
		(layer "In2.Cu")
		(net "M_K_ECC<4>")
	)
	(segment
		(start 80.395572 -97.48012)
		(end 80.401922 -97.490788)
		(width 0.0889)
		(layer "In2.Cu")
		(net "M_K_ECC<4>")
	)
	(segment
		(start 69.284596 -129.757678)
		(end 68.484496 -130.557778)
		(width 0.14224)
		(layer "In2.Cu")
		(net "M_K_ECC<4>")
	)
	(segment
		(start 69.079364 -124.644404)
		(end 69.079364 -125.570996)
		(width 0.14224)
		(layer "In2.Cu")
		(net "M_K_ECC<4>")
	)
	(segment
		(start 81.772252 -90.10396)
		(end 81.706974 -90.169238)
		(width 0.0889)
		(layer "In2.Cu")
		(net "M_K_ECC<4>")
	)
	(segment
		(start 80.070198 -99.081336)
		(end 79.65567 -99.081336)
		(width 0.0889)
		(layer "In2.Cu")
		(net "M_K_ECC<4>")
	)
	(segment
		(start 80.395572 -92.52712)
		(end 80.401922 -92.537788)
		(width 0.0889)
		(layer "In2.Cu")
		(net "M_K_ECC<4>")
	)
	(segment
		(start 79.65567 -99.081336)
		(end 78.611476 -100.12553)
		(width 0.0889)
		(layer "In2.Cu")
		(net "M_K_ECC<4>")
	)
	(segment
		(start 68.484496 -130.557778)
		(end 68.484496 -131.296918)
		(width 0.14224)
		(layer "In2.Cu")
		(net "M_K_ECC<4>")
	)
	(segment
		(start 70.254368 -118.2878)
		(end 70.101968 -118.1354)
		(width 0.14224)
		(layer "In2.Cu")
		(net "M_K_ECC<4>")
	)
	(segment
		(start 70.101968 -118.1354)
		(end 69.746368 -118.1354)
		(width 0.14224)
		(layer "In2.Cu")
		(net "M_K_ECC<4>")
	)
	(segment
		(start 68.799456 -131.611878)
		(end 68.366386 -132.044948)
		(width 0.14224)
		(layer "In2.Cu")
		(net "M_K_ECC<4>")
	)
	(segment
		(start 78.224634 -101.487478)
		(end 78.224634 -103.342186)
		(width 0.14224)
		(layer "In2.Cu")
		(net "M_K_ECC<4>")
	)
	(segment
		(start 80.401922 -97.490788)
		(end 80.406748 -97.499424)
		(width 0.0889)
		(layer "In2.Cu")
		(net "M_K_ECC<4>")
	)
	(segment
		(start 80.401922 -93.928438)
		(end 80.395572 -93.939106)
		(width 0.0889)
		(layer "In2.Cu")
		(net "M_K_ECC<4>")
	)
	(segment
		(start 80.395572 -98.47072)
		(end 80.401922 -98.481388)
		(width 0.0889)
		(layer "In2.Cu")
		(net "M_K_ECC<4>")
	)
	(segment
		(start 80.401922 -95.509588)
		(end 80.406748 -95.518224)
		(width 0.0889)
		(layer "In2.Cu")
		(net "M_K_ECC<4>")
	)
	(segment
		(start 71.498968 -118.2116)
		(end 70.889368 -118.8212)
		(width 0.14224)
		(layer "In2.Cu")
		(net "M_K_ECC<4>")
	)
	(segment
		(start 69.593968 -124.1298)
		(end 69.079364 -124.644404)
		(width 0.14224)
		(layer "In2.Cu")
		(net "M_K_ECC<4>")
	)
	(segment
		(start 68.524374 -134.736078)
		(end 68.524374 -135.03783)
		(width 0.14224)
		(layer "In2.Cu")
		(net "M_K_ECC<4>")
	)
	(segment
		(start 80.401922 -94.518988)
		(end 80.406748 -94.527624)
		(width 0.0889)
		(layer "In2.Cu")
		(net "M_K_ECC<4>")
	)
	(segment
		(start 68.484496 -131.296918)
		(end 68.799456 -131.611878)
		(width 0.14224)
		(layer "In2.Cu")
		(net "M_K_ECC<4>")
	)
	(segment
		(start 70.889368 -118.8212)
		(end 70.432168 -118.8212)
		(width 0.14224)
		(layer "In2.Cu")
		(net "M_K_ECC<4>")
	)
	(segment
		(start 69.746368 -118.1354)
		(end 69.593968 -118.2878)
		(width 0.14224)
		(layer "In2.Cu")
		(net "M_K_ECC<4>")
	)
	(segment
		(start 68.366386 -132.044948)
		(end 68.366386 -134.57809)
		(width 0.14224)
		(layer "In2.Cu")
		(net "M_K_ECC<4>")
	)
	(segment
		(start 69.009768 -129.0066)
		(end 69.284596 -129.281428)
		(width 0.14224)
		(layer "In2.Cu")
		(net "M_K_ECC<4>")
	)
	(segment
		(start 69.593968 -118.2878)
		(end 69.593968 -124.1298)
		(width 0.14224)
		(layer "In2.Cu")
		(net "M_K_ECC<4>")
	)
	(segment
		(start 69.289168 -125.7808)
		(end 69.289168 -127.6096)
		(width 0.14224)
		(layer "In2.Cu")
		(net "M_K_ECC<4>")
	)
	(segment
		(start 71.498968 -110.067852)
		(end 71.498968 -118.2116)
		(width 0.14224)
		(layer "In2.Cu")
		(net "M_K_ECC<4>")
	)
	(segment
		(start 78.224634 -103.342186)
		(end 71.498968 -110.067852)
		(width 0.14224)
		(layer "In2.Cu")
		(net "M_K_ECC<4>")
	)
	(segment
		(start 78.611476 -100.12553)
		(end 78.611476 -101.100636)
		(width 0.0889)
		(layer "In2.Cu")
		(net "M_K_ECC<4>")
	)
	(segment
		(start 80.395572 -95.49892)
		(end 80.401922 -95.509588)
		(width 0.0889)
		(layer "In2.Cu")
		(net "M_K_ECC<4>")
	)
	(segment
		(start 69.300344 -135.8138)
		(end 69.551296 -135.8138)
		(width 0.14224)
		(layer "In2.Cu")
		(net "M_K_ECC<4>")
	)
	(segment
		(start 69.284596 -129.281428)
		(end 69.284596 -129.757678)
		(width 0.14224)
		(layer "In2.Cu")
		(net "M_K_ECC<4>")
	)
	(segment
		(start 80.924908 -91.65209)
		(end 80.892142 -91.65209)
		(width 0.0889)
		(layer "In2.Cu")
		(net "M_K_ECC<4>")
	)
	(segment
		(start 70.254368 -118.6434)
		(end 70.254368 -118.2878)
		(width 0.14224)
		(layer "In2.Cu")
		(net "M_K_ECC<4>")
	)
	(segment
		(start 81.772252 -89.765886)
		(end 81.772252 -90.10396)
		(width 0.0889)
		(layer "In2.Cu")
		(net "M_K_ECC<4>")
	)
	(segment
		(start 68.524374 -135.03783)
		(end 69.300344 -135.8138)
		(width 0.14224)
		(layer "In2.Cu")
		(net "M_K_ECC<4>")
	)
	(arc
		(start 80.406748 -94.527624)
		(mid 80.455503 -94.723976)
		(end 80.401922 -94.919038)
		(width 0.0889)
		(layer "In2.Cu")
		(net "M_K_ECC<4>")
	)
	(arc
		(start 80.892142 -91.65209)
		(mid 80.399752 -91.951023)
		(end 80.395572 -92.52712)
		(width 0.0889)
		(layer "In2.Cu")
		(net "M_K_ECC<4>")
	)
	(arc
		(start 80.406748 -92.546424)
		(mid 80.455503 -92.742776)
		(end 80.401922 -92.937838)
		(width 0.0889)
		(layer "In2.Cu")
		(net "M_K_ECC<4>")
	)
	(arc
		(start 80.401922 -95.909638)
		(mid 80.3227 -96.198756)
		(end 80.395572 -96.48952)
		(width 0.0889)
		(layer "In2.Cu")
		(net "M_K_ECC<4>")
	)
	(arc
		(start 80.406748 -98.490024)
		(mid 80.403001 -98.87928)
		(end 80.070198 -99.081336)
		(width 0.0889)
		(layer "In2.Cu")
		(net "M_K_ECC<4>")
	)
	(arc
		(start 80.401922 -93.528642)
		(mid 80.455421 -93.72854)
		(end 80.401922 -93.928438)
		(width 0.0889)
		(layer "In2.Cu")
		(net "M_K_ECC<4>")
	)
	(arc
		(start 80.401922 -92.937838)
		(mid 80.322791 -93.23324)
		(end 80.401922 -93.528642)
		(width 0.0889)
		(layer "In2.Cu")
		(net "M_K_ECC<4>")
	)
	(arc
		(start 80.401922 -96.900238)
		(mid 80.3227 -97.189356)
		(end 80.395572 -97.48012)
		(width 0.0889)
		(layer "In2.Cu")
		(net "M_K_ECC<4>")
	)
	(arc
		(start 80.401922 -97.890838)
		(mid 80.3227 -98.179956)
		(end 80.395572 -98.47072)
		(width 0.0889)
		(layer "In2.Cu")
		(net "M_K_ECC<4>")
	)
	(arc
		(start 80.401922 -94.919038)
		(mid 80.3227 -95.208156)
		(end 80.395572 -95.49892)
		(width 0.0889)
		(layer "In2.Cu")
		(net "M_K_ECC<4>")
	)
	(arc
		(start 80.406748 -96.508824)
		(mid 80.455503 -96.705176)
		(end 80.401922 -96.900238)
		(width 0.0889)
		(layer "In2.Cu")
		(net "M_K_ECC<4>")
	)
	(arc
		(start 80.406748 -95.518224)
		(mid 80.455503 -95.714576)
		(end 80.401922 -95.909638)
		(width 0.0889)
		(layer "In2.Cu")
		(net "M_K_ECC<4>")
	)
	(arc
		(start 80.395572 -93.939106)
		(mid 80.322774 -94.229869)
		(end 80.401922 -94.518988)
		(width 0.0889)
		(layer "In2.Cu")
		(net "M_K_ECC<4>")
	)
	(arc
		(start 80.406748 -97.499424)
		(mid 80.455503 -97.695776)
		(end 80.401922 -97.890838)
		(width 0.0889)
		(layer "In2.Cu")
		(net "M_K_ECC<4>")
	)
	(arc
		(start 81.260442 -91.051888)
		(mid 81.26319 -91.447355)
		(end 80.924908 -91.65209)
		(width 0.0889)
		(layer "In2.Cu")
		(net "M_K_ECC<4>")
	)
	(arc
		(start 81.706974 -90.169238)
		(mid 81.245005 -90.48978)
		(end 81.260442 -91.051888)
		(width 0.0889)
		(layer "In2.Cu")
		(net "M_K_ECC<4>")
	)
	(segment
		(start 76.449428 -133.0706)
		(end 76.449428 -134.340346)
		(width 0.1651)
		(layer "F.Cu")
		(net "M_K_ECC<3>")
	)
	(segment
		(start 85.777832 -90.756486)
		(end 85.206332 -90.756486)
		(width 0.1651)
		(layer "F.Cu")
		(net "M_K_ECC<3>")
	)
	(via
		(at 76.449428 -134.340346)
		(size 0.508)
		(drill 0.254)
		(layers "F.Cu" "B.Cu")
		(net "M_K_ECC<3>")
	)
	(via
		(at 85.206332 -90.756486)
		(size 0.508)
		(drill 0.254)
		(layers "F.Cu" "B.Cu")
		(net "M_K_ECC<3>")
	)
	(via
		(at 77.299312 -130.330956)
		(size 0.508)
		(drill 0.254)
		(layers "F.Cu" "B.Cu")
		(net "M_K_ECC<3>")
	)
	(segment
		(start 77.299566 -128.276096)
		(end 77.299566 -129.025142)
		(width 0.1651)
		(layer "B.Cu")
		(net "M_K_ECC<3>")
	)
	(segment
		(start 77.299566 -129.025142)
		(end 77.299312 -129.025396)
		(width 0.1651)
		(layer "B.Cu")
		(net "M_K_ECC<3>")
	)
	(segment
		(start 77.299312 -129.025396)
		(end 77.299312 -130.330956)
		(width 0.1651)
		(layer "B.Cu")
		(net "M_K_ECC<3>")
	)
	(segment
		(start 77.766164 -129.877312)
		(end 77.299312 -130.344164)
		(width 0.14224)
		(layer "In2.Cu")
		(net "M_K_ECC<3>")
	)
	(segment
		(start 79.933546 -110.640622)
		(end 79.933546 -121.421652)
		(width 0.14224)
		(layer "In2.Cu")
		(net "M_K_ECC<3>")
	)
	(segment
		(start 77.766164 -127)
		(end 77.766164 -129.877312)
		(width 0.14224)
		(layer "In2.Cu")
		(net "M_K_ECC<3>")
	)
	(segment
		(start 78.462886 -124.167138)
		(end 79.283814 -124.167138)
		(width 0.14224)
		(layer "In2.Cu")
		(net "M_K_ECC<3>")
	)
	(segment
		(start 78.160626 -124.830078)
		(end 77.899768 -125.090936)
		(width 0.14224)
		(layer "In2.Cu")
		(net "M_K_ECC<3>")
	)
	(segment
		(start 79.616046 -122.989594)
		(end 79.616046 -123.342654)
		(width 0.14224)
		(layer "In2.Cu")
		(net "M_K_ECC<3>")
	)
	(segment
		(start 79.42834 -124.311664)
		(end 79.42834 -124.664724)
		(width 0.14224)
		(layer "In2.Cu")
		(net "M_K_ECC<3>")
	)
	(segment
		(start 85.664548 -91.01201)
		(end 85.664548 -91.372944)
		(width 0.0889)
		(layer "In2.Cu")
		(net "M_K_ECC<3>")
	)
	(segment
		(start 84.859622 -95.509588)
		(end 84.854796 -95.518224)
		(width 0.0889)
		(layer "In2.Cu")
		(net "M_K_ECC<3>")
	)
	(segment
		(start 78.462886 -123.504198)
		(end 78.307946 -123.659138)
		(width 0.14224)
		(layer "In2.Cu")
		(net "M_K_ECC<3>")
	)
	(segment
		(start 84.7598 -105.814368)
		(end 79.933546 -110.640622)
		(width 0.14224)
		(layer "In2.Cu")
		(net "M_K_ECC<3>")
	)
	(segment
		(start 85.701378 -91.422474)
		(end 85.718142 -91.451938)
		(width 0.0889)
		(layer "In2.Cu")
		(net "M_K_ECC<3>")
	)
	(segment
		(start 78.307946 -124.012198)
		(end 78.462886 -124.167138)
		(width 0.14224)
		(layer "In2.Cu")
		(net "M_K_ECC<3>")
	)
	(segment
		(start 76.893166 -131.9022)
		(end 76.610718 -132.184648)
		(width 0.14224)
		(layer "In2.Cu")
		(net "M_K_ECC<3>")
	)
	(segment
		(start 77.899768 -126.866396)
		(end 77.766164 -127)
		(width 0.14224)
		(layer "In2.Cu")
		(net "M_K_ECC<3>")
	)
	(segment
		(start 79.283814 -124.167138)
		(end 79.42834 -124.311664)
		(width 0.14224)
		(layer "In2.Cu")
		(net "M_K_ECC<3>")
	)
	(segment
		(start 84.865972 -96.48952)
		(end 84.792312 -96.620584)
		(width 0.0889)
		(layer "In2.Cu")
		(net "M_K_ECC<3>")
	)
	(segment
		(start 79.42834 -124.664724)
		(end 79.262986 -124.830078)
		(width 0.14224)
		(layer "In2.Cu")
		(net "M_K_ECC<3>")
	)
	(segment
		(start 76.893166 -131.233418)
		(end 76.893166 -131.9022)
		(width 0.14224)
		(layer "In2.Cu")
		(net "M_K_ECC<3>")
	)
	(segment
		(start 77.27696 -130.330956)
		(end 76.848716 -130.7592)
		(width 0.14224)
		(layer "In2.Cu")
		(net "M_K_ECC<3>")
	)
	(segment
		(start 79.262986 -124.830078)
		(end 78.160626 -124.830078)
		(width 0.14224)
		(layer "In2.Cu")
		(net "M_K_ECC<3>")
	)
	(segment
		(start 78.462886 -122.841258)
		(end 79.46771 -122.841258)
		(width 0.14224)
		(layer "In2.Cu")
		(net "M_K_ECC<3>")
	)
	(segment
		(start 85.718142 -92.442538)
		(end 85.724492 -92.453206)
		(width 0.0889)
		(layer "In2.Cu")
		(net "M_K_ECC<3>")
	)
	(segment
		(start 79.933546 -121.421652)
		(end 79.409798 -121.9454)
		(width 0.14224)
		(layer "In2.Cu")
		(net "M_K_ECC<3>")
	)
	(segment
		(start 85.713316 -92.433902)
		(end 85.718142 -92.442538)
		(width 0.0889)
		(layer "In2.Cu")
		(net "M_K_ECC<3>")
	)
	(segment
		(start 78.511146 -121.9454)
		(end 78.307946 -122.1486)
		(width 0.14224)
		(layer "In2.Cu")
		(net "M_K_ECC<3>")
	)
	(segment
		(start 76.610718 -133.276848)
		(end 76.610718 -133.550152)
		(width 0.14224)
		(layer "In2.Cu")
		(net "M_K_ECC<3>")
	)
	(segment
		(start 78.307946 -123.659138)
		(end 78.307946 -124.012198)
		(width 0.14224)
		(layer "In2.Cu")
		(net "M_K_ECC<3>")
	)
	(segment
		(start 76.610718 -132.184648)
		(end 76.610718 -132.457952)
		(width 0.14224)
		(layer "In2.Cu")
		(net "M_K_ECC<3>")
	)
	(segment
		(start 79.616046 -123.342654)
		(end 79.454502 -123.504198)
		(width 0.14224)
		(layer "In2.Cu")
		(net "M_K_ECC<3>")
	)
	(segment
		(start 85.282024 -90.832178)
		(end 85.484716 -90.832178)
		(width 0.0889)
		(layer "In2.Cu")
		(net "M_K_ECC<3>")
	)
	(segment
		(start 84.792312 -101.706426)
		(end 84.530184 -101.968554)
		(width 0.0889)
		(layer "In2.Cu")
		(net "M_K_ECC<3>")
	)
	(segment
		(start 79.409798 -121.9454)
		(end 78.511146 -121.9454)
		(width 0.14224)
		(layer "In2.Cu")
		(net "M_K_ECC<3>")
	)
	(segment
		(start 84.7598 -103.299514)
		(end 84.7598 -105.814368)
		(width 0.14224)
		(layer "In2.Cu")
		(net "M_K_ECC<3>")
	)
	(segment
		(start 77.299312 -130.330956)
		(end 77.27696 -130.330956)
		(width 0.14224)
		(layer "In2.Cu")
		(net "M_K_ECC<3>")
	)
	(segment
		(start 84.865972 -95.49892)
		(end 84.859622 -95.509588)
		(width 0.0889)
		(layer "In2.Cu")
		(net "M_K_ECC<3>")
	)
	(segment
		(start 84.530184 -101.968554)
		(end 84.530184 -103.069898)
		(width 0.0889)
		(layer "In2.Cu")
		(net "M_K_ECC<3>")
	)
	(segment
		(start 76.721716 -134.340346)
		(end 76.449428 -134.340346)
		(width 0.14224)
		(layer "In2.Cu")
		(net "M_K_ECC<3>")
	)
	(segment
		(start 76.899516 -134.162546)
		(end 76.721716 -134.340346)
		(width 0.14224)
		(layer "In2.Cu")
		(net "M_K_ECC<3>")
	)
	(segment
		(start 78.307946 -122.1486)
		(end 78.307946 -122.686318)
		(width 0.14224)
		(layer "In2.Cu")
		(net "M_K_ECC<3>")
	)
	(segment
		(start 76.867766 -133.0198)
		(end 76.610718 -133.276848)
		(width 0.14224)
		(layer "In2.Cu")
		(net "M_K_ECC<3>")
	)
	(segment
		(start 76.848716 -130.7592)
		(end 76.848716 -131.188968)
		(width 0.14224)
		(layer "In2.Cu")
		(net "M_K_ECC<3>")
	)
	(segment
		(start 76.610718 -133.550152)
		(end 76.899516 -133.83895)
		(width 0.14224)
		(layer "In2.Cu")
		(net "M_K_ECC<3>")
	)
	(segment
		(start 78.307946 -122.686318)
		(end 78.462886 -122.841258)
		(width 0.14224)
		(layer "In2.Cu")
		(net "M_K_ECC<3>")
	)
	(segment
		(start 85.664548 -91.372944)
		(end 85.701378 -91.422474)
		(width 0.0889)
		(layer "In2.Cu")
		(net "M_K_ECC<3>")
	)
	(segment
		(start 85.224112 -94.31909)
		(end 85.188298 -94.31909)
		(width 0.0889)
		(layer "In2.Cu")
		(net "M_K_ECC<3>")
	)
	(segment
		(start 76.867766 -132.715)
		(end 76.867766 -133.0198)
		(width 0.14224)
		(layer "In2.Cu")
		(net "M_K_ECC<3>")
	)
	(segment
		(start 79.454502 -123.504198)
		(end 78.462886 -123.504198)
		(width 0.14224)
		(layer "In2.Cu")
		(net "M_K_ECC<3>")
	)
	(segment
		(start 85.713316 -93.424502)
		(end 85.718142 -93.433138)
		(width 0.0889)
		(layer "In2.Cu")
		(net "M_K_ECC<3>")
	)
	(segment
		(start 85.718142 -91.451938)
		(end 85.724492 -91.462606)
		(width 0.0889)
		(layer "In2.Cu")
		(net "M_K_ECC<3>")
	)
	(segment
		(start 76.610718 -132.457952)
		(end 76.867766 -132.715)
		(width 0.14224)
		(layer "In2.Cu")
		(net "M_K_ECC<3>")
	)
	(segment
		(start 77.899768 -125.090936)
		(end 77.899768 -126.866396)
		(width 0.14224)
		(layer "In2.Cu")
		(net "M_K_ECC<3>")
	)
	(segment
		(start 76.848716 -131.188968)
		(end 76.893166 -131.233418)
		(width 0.14224)
		(layer "In2.Cu")
		(net "M_K_ECC<3>")
	)
	(segment
		(start 84.530184 -103.069898)
		(end 84.7598 -103.299514)
		(width 0.0889)
		(layer "In2.Cu")
		(net "M_K_ECC<3>")
	)
	(segment
		(start 76.899516 -133.83895)
		(end 76.899516 -134.162546)
		(width 0.14224)
		(layer "In2.Cu")
		(net "M_K_ECC<3>")
	)
	(segment
		(start 85.484716 -90.832178)
		(end 85.664548 -91.01201)
		(width 0.0889)
		(layer "In2.Cu")
		(net "M_K_ECC<3>")
	)
	(segment
		(start 79.46771 -122.841258)
		(end 79.616046 -122.989594)
		(width 0.14224)
		(layer "In2.Cu")
		(net "M_K_ECC<3>")
	)
	(segment
		(start 77.299312 -130.344164)
		(end 77.299312 -130.330956)
		(width 0.14224)
		(layer "In2.Cu")
		(net "M_K_ECC<3>")
	)
	(segment
		(start 84.792312 -96.620584)
		(end 84.792312 -101.706426)
		(width 0.0889)
		(layer "In2.Cu")
		(net "M_K_ECC<3>")
	)
	(segment
		(start 85.206332 -90.756486)
		(end 85.282024 -90.832178)
		(width 0.0889)
		(layer "In2.Cu")
		(net "M_K_ECC<3>")
	)
	(arc
		(start 85.188298 -94.31909)
		(mid 84.855329 -94.526638)
		(end 84.859622 -94.919038)
		(width 0.0889)
		(layer "In2.Cu")
		(net "M_K_ECC<3>")
	)
	(arc
		(start 85.718142 -92.042488)
		(mid 85.664672 -92.237551)
		(end 85.713316 -92.433902)
		(width 0.0889)
		(layer "In2.Cu")
		(net "M_K_ECC<3>")
	)
	(arc
		(start 85.724492 -92.453206)
		(mid 85.79729 -92.743969)
		(end 85.718142 -93.033088)
		(width 0.0889)
		(layer "In2.Cu")
		(net "M_K_ECC<3>")
	)
	(arc
		(start 85.718142 -93.433138)
		(mid 85.722471 -94.01631)
		(end 85.224112 -94.31909)
		(width 0.0889)
		(layer "In2.Cu")
		(net "M_K_ECC<3>")
	)
	(arc
		(start 84.859622 -94.919038)
		(mid 84.938844 -95.208156)
		(end 84.865972 -95.49892)
		(width 0.0889)
		(layer "In2.Cu")
		(net "M_K_ECC<3>")
	)
	(arc
		(start 85.724492 -91.462606)
		(mid 85.79729 -91.753369)
		(end 85.718142 -92.042488)
		(width 0.0889)
		(layer "In2.Cu")
		(net "M_K_ECC<3>")
	)
	(arc
		(start 85.718142 -93.033088)
		(mid 85.664672 -93.228151)
		(end 85.713316 -93.424502)
		(width 0.0889)
		(layer "In2.Cu")
		(net "M_K_ECC<3>")
	)
	(arc
		(start 84.859622 -95.909638)
		(mid 84.938844 -96.198756)
		(end 84.865972 -96.48952)
		(width 0.0889)
		(layer "In2.Cu")
		(net "M_K_ECC<3>")
	)
	(arc
		(start 84.854796 -95.518224)
		(mid 84.806041 -95.714576)
		(end 84.859622 -95.909638)
		(width 0.0889)
		(layer "In2.Cu")
		(net "M_K_ECC<3>")
	)
	(segment
		(start 77.299312 -136.192768)
		(end 77.299312 -135.9154)
		(width 0.1651)
		(layer "F.Cu")
		(net "M_K_ECC<2>")
	)
	(segment
		(start 77.299312 -137.67054)
		(end 77.299312 -136.679432)
		(width 0.1651)
		(layer "F.Cu")
		(net "M_K_ECC<2>")
	)
	(segment
		(start 77.299312 -136.679432)
		(end 77.430884 -136.54786)
		(width 0.1651)
		(layer "F.Cu")
		(net "M_K_ECC<2>")
	)
	(segment
		(start 77.299566 -137.67054)
		(end 77.299312 -137.67054)
		(width 0.1651)
		(layer "F.Cu")
		(net "M_K_ECC<2>")
	)
	(segment
		(start 85.777832 -89.765886)
		(end 85.206332 -89.765886)
		(width 0.1651)
		(layer "F.Cu")
		(net "M_K_ECC<2>")
	)
	(segment
		(start 77.430884 -136.54786)
		(end 77.430884 -136.32434)
		(width 0.1651)
		(layer "F.Cu")
		(net "M_K_ECC<2>")
	)
	(segment
		(start 77.430884 -136.32434)
		(end 77.299312 -136.192768)
		(width 0.1651)
		(layer "F.Cu")
		(net "M_K_ECC<2>")
	)
	(via
		(at 77.299312 -135.9154)
		(size 0.508)
		(drill 0.254)
		(layers "F.Cu" "B.Cu")
		(net "M_K_ECC<2>")
	)
	(via
		(at 76.449428 -131.611878)
		(size 0.508)
		(drill 0.254)
		(layers "F.Cu" "B.Cu")
		(net "M_K_ECC<2>")
	)
	(via
		(at 85.206332 -89.765886)
		(size 0.508)
		(drill 0.254)
		(layers "F.Cu" "B.Cu")
		(net "M_K_ECC<2>")
	)
	(segment
		(start 76.449428 -132.876036)
		(end 76.449428 -131.611878)
		(width 0.1651)
		(layer "B.Cu")
		(net "M_K_ECC<2>")
	)
	(segment
		(start 85.191346 -91.156536)
		(end 85.1916 -91.156536)
		(width 0.0889)
		(layer "In2.Cu")
		(net "M_K_ECC<2>")
	)
	(segment
		(start 85.395816 -91.274646)
		(end 85.416644 -91.310714)
		(width 0.0889)
		(layer "In2.Cu")
		(net "M_K_ECC<2>")
	)
	(segment
		(start 78.309216 -121.321576)
		(end 77.904848 -121.321576)
		(width 0.14224)
		(layer "In2.Cu")
		(net "M_K_ECC<2>")
	)
	(segment
		(start 84.711032 -89.936574)
		(end 84.985352 -90.210894)
		(width 0.0889)
		(layer "In2.Cu")
		(net "M_K_ECC<2>")
	)
	(segment
		(start 77.290168 -123.9012)
		(end 77.290168 -125.0696)
		(width 0.14224)
		(layer "In2.Cu")
		(net "M_K_ECC<2>")
	)
	(segment
		(start 84.340192 -103.071422)
		(end 84.1121 -103.299514)
		(width 0.0889)
		(layer "In2.Cu")
		(net "M_K_ECC<2>")
	)
	(segment
		(start 77.671168 -123.5202)
		(end 77.290168 -123.9012)
		(width 0.14224)
		(layer "In2.Cu")
		(net "M_K_ECC<2>")
	)
	(segment
		(start 84.711032 -89.451434)
		(end 84.711032 -89.936574)
		(width 0.0889)
		(layer "In2.Cu")
		(net "M_K_ECC<2>")
	)
	(segment
		(start 78.455774 -120.667018)
		(end 78.455774 -121.175018)
		(width 0.14224)
		(layer "In2.Cu")
		(net "M_K_ECC<2>")
	)
	(segment
		(start 85.206332 -89.765886)
		(end 85.206332 -89.461086)
		(width 0.0889)
		(layer "In2.Cu")
		(net "M_K_ECC<2>")
	)
	(segment
		(start 85.416644 -91.35872)
		(end 85.540088 -91.524836)
		(width 0.0889)
		(layer "In2.Cu")
		(net "M_K_ECC<2>")
	)
	(segment
		(start 76.016358 -132.044948)
		(end 76.016358 -134.632446)
		(width 0.14224)
		(layer "In2.Cu")
		(net "M_K_ECC<2>")
	)
	(segment
		(start 84.340192 -101.889814)
		(end 84.340192 -103.071422)
		(width 0.0889)
		(layer "In2.Cu")
		(net "M_K_ECC<2>")
	)
	(segment
		(start 85.546692 -92.52712)
		(end 85.553042 -92.537788)
		(width 0.0889)
		(layer "In2.Cu")
		(net "M_K_ECC<2>")
	)
	(segment
		(start 84.699348 -96.396302)
		(end 84.60232 -96.570038)
		(width 0.0889)
		(layer "In2.Cu")
		(net "M_K_ECC<2>")
	)
	(segment
		(start 84.985352 -90.210894)
		(end 84.985352 -90.365834)
		(width 0.0889)
		(layer "In2.Cu")
		(net "M_K_ECC<2>")
	)
	(segment
		(start 84.699348 -95.405702)
		(end 84.694522 -95.414338)
		(width 0.0889)
		(layer "In2.Cu")
		(net "M_K_ECC<2>")
	)
	(segment
		(start 84.60232 -101.627686)
		(end 84.340192 -101.889814)
		(width 0.0889)
		(layer "In2.Cu")
		(net "M_K_ECC<2>")
	)
	(segment
		(start 76.104496 -130.633978)
		(end 76.104496 -131.266946)
		(width 0.14224)
		(layer "In2.Cu")
		(net "M_K_ECC<2>")
	)
	(segment
		(start 84.60232 -96.570038)
		(end 84.60232 -101.627686)
		(width 0.0889)
		(layer "In2.Cu")
		(net "M_K_ECC<2>")
	)
	(segment
		(start 84.1121 -103.299514)
		(end 84.1121 -105.623868)
		(width 0.14224)
		(layer "In2.Cu")
		(net "M_K_ECC<2>")
	)
	(segment
		(start 76.968096 -126.9238)
		(end 76.968096 -129.770378)
		(width 0.14224)
		(layer "In2.Cu")
		(net "M_K_ECC<2>")
	)
	(segment
		(start 85.553042 -92.537788)
		(end 85.557868 -92.546424)
		(width 0.0889)
		(layer "In2.Cu")
		(net "M_K_ECC<2>")
	)
	(segment
		(start 77.77226 -119.884444)
		(end 77.77226 -120.305576)
		(width 0.14224)
		(layer "In2.Cu")
		(net "M_K_ECC<2>")
	)
	(segment
		(start 77.290168 -125.0696)
		(end 76.883768 -125.476)
		(width 0.14224)
		(layer "In2.Cu")
		(net "M_K_ECC<2>")
	)
	(segment
		(start 78.455774 -121.175018)
		(end 78.309216 -121.321576)
		(width 0.14224)
		(layer "In2.Cu")
		(net "M_K_ECC<2>")
	)
	(segment
		(start 85.206332 -89.461086)
		(end 85.023452 -89.278206)
		(width 0.0889)
		(layer "In2.Cu")
		(net "M_K_ECC<2>")
	)
	(segment
		(start 76.016358 -134.632446)
		(end 77.299312 -135.9154)
		(width 0.14224)
		(layer "In2.Cu")
		(net "M_K_ECC<2>")
	)
	(segment
		(start 76.104496 -131.266946)
		(end 76.449428 -131.611878)
		(width 0.14224)
		(layer "In2.Cu")
		(net "M_K_ECC<2>")
	)
	(segment
		(start 84.769452 -90.866468)
		(end 84.859622 -90.956638)
		(width 0.0889)
		(layer "In2.Cu")
		(net "M_K_ECC<2>")
	)
	(segment
		(start 85.224366 -94.128336)
		(end 85.184742 -94.128336)
		(width 0.0889)
		(layer "In2.Cu")
		(net "M_K_ECC<2>")
	)
	(segment
		(start 77.97546 -120.508776)
		(end 78.297532 -120.508776)
		(width 0.14224)
		(layer "In2.Cu")
		(net "M_K_ECC<2>")
	)
	(segment
		(start 84.694522 -95.414338)
		(end 84.688172 -95.425006)
		(width 0.0889)
		(layer "In2.Cu")
		(net "M_K_ECC<2>")
	)
	(segment
		(start 85.416644 -91.310714)
		(end 85.416644 -91.35872)
		(width 0.0889)
		(layer "In2.Cu")
		(net "M_K_ECC<2>")
	)
	(segment
		(start 77.904848 -121.321576)
		(end 77.671168 -121.555256)
		(width 0.14224)
		(layer "In2.Cu")
		(net "M_K_ECC<2>")
	)
	(segment
		(start 77.671168 -121.555256)
		(end 77.671168 -123.5202)
		(width 0.14224)
		(layer "In2.Cu")
		(net "M_K_ECC<2>")
	)
	(segment
		(start 85.540088 -91.524836)
		(end 85.557868 -91.555824)
		(width 0.0889)
		(layer "In2.Cu")
		(net "M_K_ECC<2>")
	)
	(segment
		(start 78.297532 -120.508776)
		(end 78.455774 -120.667018)
		(width 0.14224)
		(layer "In2.Cu")
		(net "M_K_ECC<2>")
	)
	(segment
		(start 84.985352 -90.365834)
		(end 84.769452 -90.581734)
		(width 0.0889)
		(layer "In2.Cu")
		(net "M_K_ECC<2>")
	)
	(segment
		(start 77.77226 -120.305576)
		(end 77.97546 -120.508776)
		(width 0.14224)
		(layer "In2.Cu")
		(net "M_K_ECC<2>")
	)
	(segment
		(start 79.25943 -118.397274)
		(end 77.77226 -119.884444)
		(width 0.14224)
		(layer "In2.Cu")
		(net "M_K_ECC<2>")
	)
	(segment
		(start 85.023452 -89.278206)
		(end 84.88426 -89.278206)
		(width 0.0889)
		(layer "In2.Cu")
		(net "M_K_ECC<2>")
	)
	(segment
		(start 76.883768 -125.476)
		(end 76.883768 -126.839472)
		(width 0.14224)
		(layer "In2.Cu")
		(net "M_K_ECC<2>")
	)
	(segment
		(start 76.449428 -131.611878)
		(end 76.016358 -132.044948)
		(width 0.14224)
		(layer "In2.Cu")
		(net "M_K_ECC<2>")
	)
	(segment
		(start 84.769452 -90.581734)
		(end 84.769452 -90.866468)
		(width 0.0889)
		(layer "In2.Cu")
		(net "M_K_ECC<2>")
	)
	(segment
		(start 76.968096 -129.770378)
		(end 76.104496 -130.633978)
		(width 0.14224)
		(layer "In2.Cu")
		(net "M_K_ECC<2>")
	)
	(segment
		(start 84.1121 -105.623868)
		(end 79.25943 -110.476538)
		(width 0.14224)
		(layer "In2.Cu")
		(net "M_K_ECC<2>")
	)
	(segment
		(start 79.25943 -110.476538)
		(end 79.25943 -118.397274)
		(width 0.14224)
		(layer "In2.Cu")
		(net "M_K_ECC<2>")
	)
	(segment
		(start 76.883768 -126.839472)
		(end 76.968096 -126.9238)
		(width 0.14224)
		(layer "In2.Cu")
		(net "M_K_ECC<2>")
	)
	(segment
		(start 84.88426 -89.278206)
		(end 84.711032 -89.451434)
		(width 0.0889)
		(layer "In2.Cu")
		(net "M_K_ECC<2>")
	)
	(arc
		(start 84.688172 -95.425006)
		(mid 84.615374 -95.715769)
		(end 84.694522 -96.004888)
		(width 0.0889)
		(layer "In2.Cu")
		(net "M_K_ECC<2>")
	)
	(arc
		(start 85.1916 -91.156536)
		(mid 85.309569 -91.188181)
		(end 85.395816 -91.274646)
		(width 0.0889)
		(layer "In2.Cu")
		(net "M_K_ECC<2>")
	)
	(arc
		(start 84.694522 -95.014288)
		(mid 84.747992 -95.209351)
		(end 84.699348 -95.405702)
		(width 0.0889)
		(layer "In2.Cu")
		(net "M_K_ECC<2>")
	)
	(arc
		(start 85.553042 -92.937838)
		(mid 85.473911 -93.23324)
		(end 85.553042 -93.528642)
		(width 0.0889)
		(layer "In2.Cu")
		(net "M_K_ECC<2>")
	)
	(arc
		(start 84.859622 -90.956638)
		(mid 84.999701 -91.099374)
		(end 85.191346 -91.156536)
		(width 0.0889)
		(layer "In2.Cu")
		(net "M_K_ECC<2>")
	)
	(arc
		(start 85.557868 -92.546424)
		(mid 85.606623 -92.742776)
		(end 85.553042 -92.937838)
		(width 0.0889)
		(layer "In2.Cu")
		(net "M_K_ECC<2>")
	)
	(arc
		(start 85.553042 -91.947238)
		(mid 85.47382 -92.236356)
		(end 85.546692 -92.52712)
		(width 0.0889)
		(layer "In2.Cu")
		(net "M_K_ECC<2>")
	)
	(arc
		(start 85.553042 -93.528642)
		(mid 85.557287 -93.920887)
		(end 85.224366 -94.128336)
		(width 0.0889)
		(layer "In2.Cu")
		(net "M_K_ECC<2>")
	)
	(arc
		(start 85.557868 -91.555824)
		(mid 85.606623 -91.752176)
		(end 85.553042 -91.947238)
		(width 0.0889)
		(layer "In2.Cu")
		(net "M_K_ECC<2>")
	)
	(arc
		(start 84.694522 -96.004888)
		(mid 84.747992 -96.199951)
		(end 84.699348 -96.396302)
		(width 0.0889)
		(layer "In2.Cu")
		(net "M_K_ECC<2>")
	)
	(arc
		(start 85.184742 -94.128336)
		(mid 84.689265 -94.432779)
		(end 84.694522 -95.014288)
		(width 0.0889)
		(layer "In2.Cu")
		(net "M_K_ECC<2>")
	)
	(segment
		(start 70.499478 -133.0706)
		(end 70.499478 -134.340346)
		(width 0.1651)
		(layer "F.Cu")
		(net "M_K_ECC<1>")
	)
	(segment
		(start 83.202272 -91.25204)
		(end 82.630772 -91.25204)
		(width 0.1651)
		(layer "F.Cu")
		(net "M_K_ECC<1>")
	)
	(via
		(at 70.499478 -134.340346)
		(size 0.508)
		(drill 0.254)
		(layers "F.Cu" "B.Cu")
		(net "M_K_ECC<1>")
	)
	(via
		(at 82.630772 -91.25204)
		(size 0.508)
		(drill 0.254)
		(layers "F.Cu" "B.Cu")
		(net "M_K_ECC<1>")
	)
	(via
		(at 71.171562 -130.330956)
		(size 0.508)
		(drill 0.254)
		(layers "F.Cu" "B.Cu")
		(net "M_K_ECC<1>")
	)
	(segment
		(start 71.349362 -129.649982)
		(end 71.171562 -129.827782)
		(width 0.1651)
		(layer "B.Cu")
		(net "M_K_ECC<1>")
	)
	(segment
		(start 71.349362 -128.276096)
		(end 71.349362 -129.649982)
		(width 0.1651)
		(layer "B.Cu")
		(net "M_K_ECC<1>")
	)
	(segment
		(start 71.171562 -129.827782)
		(end 71.171562 -130.330956)
		(width 0.1651)
		(layer "B.Cu")
		(net "M_K_ECC<1>")
	)
	(segment
		(start 71.659496 -129.843022)
		(end 71.171562 -130.330956)
		(width 0.14224)
		(layer "In2.Cu")
		(net "M_K_ECC<1>")
	)
	(segment
		(start 80.471264 -100.132134)
		(end 79.969868 -100.63353)
		(width 0.0889)
		(layer "In2.Cu")
		(net "M_K_ECC<1>")
	)
	(segment
		(start 70.660768 -133.643624)
		(end 70.900544 -133.8834)
		(width 0.14224)
		(layer "In2.Cu")
		(net "M_K_ECC<1>")
	)
	(segment
		(start 81.425542 -96.900238)
		(end 81.431892 -96.910906)
		(width 0.0889)
		(layer "In2.Cu")
		(net "M_K_ECC<1>")
	)
	(segment
		(start 81.425542 -94.518988)
		(end 81.420716 -94.527624)
		(width 0.0889)
		(layer "In2.Cu")
		(net "M_K_ECC<1>")
	)
	(segment
		(start 70.875144 -132.6896)
		(end 70.875144 -133.1214)
		(width 0.14224)
		(layer "In2.Cu")
		(net "M_K_ECC<1>")
	)
	(segment
		(start 82.630772 -91.25204)
		(end 82.300826 -92.013786)
		(width 0.0889)
		(layer "In2.Cu")
		(net "M_K_ECC<1>")
	)
	(segment
		(start 71.829168 -122.9106)
		(end 71.829168 -124.0536)
		(width 0.14224)
		(layer "In2.Cu")
		(net "M_K_ECC<1>")
	)
	(segment
		(start 70.660768 -132.475224)
		(end 70.875144 -132.6896)
		(width 0.14224)
		(layer "In2.Cu")
		(net "M_K_ECC<1>")
	)
	(segment
		(start 81.431892 -98.47072)
		(end 81.425542 -98.481388)
		(width 0.0889)
		(layer "In2.Cu")
		(net "M_K_ECC<1>")
	)
	(segment
		(start 70.951344 -131.419346)
		(end 70.951344 -131.823968)
		(width 0.14224)
		(layer "In2.Cu")
		(net "M_K_ECC<1>")
	)
	(segment
		(start 80.179672 -102.060756)
		(end 80.179672 -104.099614)
		(width 0.14224)
		(layer "In2.Cu")
		(net "M_K_ECC<1>")
	)
	(segment
		(start 71.973948 -122.76582)
		(end 71.829168 -122.9106)
		(width 0.14224)
		(layer "In2.Cu")
		(net "M_K_ECC<1>")
	)
	(segment
		(start 81.425542 -97.490788)
		(end 81.420716 -97.499424)
		(width 0.0889)
		(layer "In2.Cu")
		(net "M_K_ECC<1>")
	)
	(segment
		(start 80.566514 -99.967034)
		(end 80.471264 -100.132134)
		(width 0.0889)
		(layer "In2.Cu")
		(net "M_K_ECC<1>")
	)
	(segment
		(start 79.969868 -100.63353)
		(end 79.969868 -101.850952)
		(width 0.0889)
		(layer "In2.Cu")
		(net "M_K_ECC<1>")
	)
	(segment
		(start 81.431892 -96.48952)
		(end 81.425542 -96.500188)
		(width 0.0889)
		(layer "In2.Cu")
		(net "M_K_ECC<1>")
	)
	(segment
		(start 81.431892 -95.49892)
		(end 81.425542 -95.509588)
		(width 0.0889)
		(layer "In2.Cu")
		(net "M_K_ECC<1>")
	)
	(segment
		(start 81.425542 -95.509588)
		(end 81.420716 -95.518224)
		(width 0.0889)
		(layer "In2.Cu")
		(net "M_K_ECC<1>")
	)
	(segment
		(start 73.276968 -121.38533)
		(end 72.895968 -121.38533)
		(width 0.14224)
		(layer "In2.Cu")
		(net "M_K_ECC<1>")
	)
	(segment
		(start 81.425542 -98.481388)
		(end 81.420716 -98.490024)
		(width 0.0889)
		(layer "In2.Cu")
		(net "M_K_ECC<1>")
	)
	(segment
		(start 73.454768 -110.824518)
		(end 73.454768 -121.20753)
		(width 0.14224)
		(layer "In2.Cu")
		(net "M_K_ECC<1>")
	)
	(segment
		(start 72.616568 -122.555)
		(end 72.405748 -122.76582)
		(width 0.14224)
		(layer "In2.Cu")
		(net "M_K_ECC<1>")
	)
	(segment
		(start 71.659496 -124.223272)
		(end 71.659496 -129.843022)
		(width 0.14224)
		(layer "In2.Cu")
		(net "M_K_ECC<1>")
	)
	(segment
		(start 72.616568 -122.25782)
		(end 72.616568 -122.555)
		(width 0.14224)
		(layer "In2.Cu")
		(net "M_K_ECC<1>")
	)
	(segment
		(start 79.969868 -101.850952)
		(end 80.179672 -102.060756)
		(width 0.0889)
		(layer "In2.Cu")
		(net "M_K_ECC<1>")
	)
	(segment
		(start 81.425542 -96.500188)
		(end 81.420716 -96.508824)
		(width 0.0889)
		(layer "In2.Cu")
		(net "M_K_ECC<1>")
	)
	(segment
		(start 72.037448 -119.984266)
		(end 71.829168 -120.192546)
		(width 0.14224)
		(layer "In2.Cu")
		(net "M_K_ECC<1>")
	)
	(segment
		(start 73.454768 -121.20753)
		(end 73.276968 -121.38533)
		(width 0.14224)
		(layer "In2.Cu")
		(net "M_K_ECC<1>")
	)
	(segment
		(start 70.720966 -130.7592)
		(end 70.720966 -131.188968)
		(width 0.14224)
		(layer "In2.Cu")
		(net "M_K_ECC<1>")
	)
	(segment
		(start 70.951344 -131.823968)
		(end 70.660768 -132.114544)
		(width 0.14224)
		(layer "In2.Cu")
		(net "M_K_ECC<1>")
	)
	(segment
		(start 71.829168 -124.0536)
		(end 71.659496 -124.223272)
		(width 0.14224)
		(layer "In2.Cu")
		(net "M_K_ECC<1>")
	)
	(segment
		(start 71.14921 -130.330956)
		(end 70.720966 -130.7592)
		(width 0.14224)
		(layer "In2.Cu")
		(net "M_K_ECC<1>")
	)
	(segment
		(start 70.748398 -134.340346)
		(end 70.499478 -134.340346)
		(width 0.14224)
		(layer "In2.Cu")
		(net "M_K_ECC<1>")
	)
	(segment
		(start 70.900544 -134.1882)
		(end 70.748398 -134.340346)
		(width 0.14224)
		(layer "In2.Cu")
		(net "M_K_ECC<1>")
	)
	(segment
		(start 80.9371 -99.76739)
		(end 80.895698 -99.76739)
		(width 0.0889)
		(layer "In2.Cu")
		(net "M_K_ECC<1>")
	)
	(segment
		(start 70.875144 -133.1214)
		(end 70.660768 -133.335776)
		(width 0.14224)
		(layer "In2.Cu")
		(net "M_K_ECC<1>")
	)
	(segment
		(start 72.895968 -121.38533)
		(end 72.692768 -121.18213)
		(width 0.14224)
		(layer "In2.Cu")
		(net "M_K_ECC<1>")
	)
	(segment
		(start 72.692768 -120.233186)
		(end 72.443848 -119.984266)
		(width 0.14224)
		(layer "In2.Cu")
		(net "M_K_ECC<1>")
	)
	(segment
		(start 70.660768 -133.335776)
		(end 70.660768 -133.643624)
		(width 0.14224)
		(layer "In2.Cu")
		(net "M_K_ECC<1>")
	)
	(segment
		(start 72.443848 -119.984266)
		(end 72.037448 -119.984266)
		(width 0.14224)
		(layer "In2.Cu")
		(net "M_K_ECC<1>")
	)
	(segment
		(start 72.405748 -122.76582)
		(end 71.973948 -122.76582)
		(width 0.14224)
		(layer "In2.Cu")
		(net "M_K_ECC<1>")
	)
	(segment
		(start 71.829168 -120.192546)
		(end 71.829168 -121.9454)
		(width 0.14224)
		(layer "In2.Cu")
		(net "M_K_ECC<1>")
	)
	(segment
		(start 81.425542 -98.881438)
		(end 81.427066 -98.883724)
		(width 0.0889)
		(layer "In2.Cu")
		(net "M_K_ECC<1>")
	)
	(segment
		(start 70.900544 -133.8834)
		(end 70.900544 -134.1882)
		(width 0.14224)
		(layer "In2.Cu")
		(net "M_K_ECC<1>")
	)
	(segment
		(start 72.461628 -122.10288)
		(end 72.616568 -122.25782)
		(width 0.14224)
		(layer "In2.Cu")
		(net "M_K_ECC<1>")
	)
	(segment
		(start 80.567022 -99.967288)
		(end 80.566514 -99.967034)
		(width 0.0889)
		(layer "In2.Cu")
		(net "M_K_ECC<1>")
	)
	(segment
		(start 71.829168 -121.9454)
		(end 71.986648 -122.10288)
		(width 0.14224)
		(layer "In2.Cu")
		(net "M_K_ECC<1>")
	)
	(segment
		(start 82.300826 -92.013786)
		(end 82.284062 -92.042488)
		(width 0.0889)
		(layer "In2.Cu")
		(net "M_K_ECC<1>")
	)
	(segment
		(start 70.660768 -132.114544)
		(end 70.660768 -132.475224)
		(width 0.14224)
		(layer "In2.Cu")
		(net "M_K_ECC<1>")
	)
	(segment
		(start 81.793842 -92.337636)
		(end 81.761076 -92.337636)
		(width 0.0889)
		(layer "In2.Cu")
		(net "M_K_ECC<1>")
	)
	(segment
		(start 80.179672 -104.099614)
		(end 73.454768 -110.824518)
		(width 0.14224)
		(layer "In2.Cu")
		(net "M_K_ECC<1>")
	)
	(segment
		(start 71.986648 -122.10288)
		(end 72.461628 -122.10288)
		(width 0.14224)
		(layer "In2.Cu")
		(net "M_K_ECC<1>")
	)
	(segment
		(start 70.720966 -131.188968)
		(end 70.951344 -131.419346)
		(width 0.14224)
		(layer "In2.Cu")
		(net "M_K_ECC<1>")
	)
	(segment
		(start 81.425542 -93.928438)
		(end 81.431892 -93.939106)
		(width 0.0889)
		(layer "In2.Cu")
		(net "M_K_ECC<1>")
	)
	(segment
		(start 71.171562 -130.330956)
		(end 71.14921 -130.330956)
		(width 0.14224)
		(layer "In2.Cu")
		(net "M_K_ECC<1>")
	)
	(segment
		(start 72.692768 -121.18213)
		(end 72.692768 -120.233186)
		(width 0.14224)
		(layer "In2.Cu")
		(net "M_K_ECC<1>")
	)
	(arc
		(start 81.420716 -97.499424)
		(mid 81.371961 -97.695776)
		(end 81.425542 -97.890838)
		(width 0.0889)
		(layer "In2.Cu")
		(net "M_K_ECC<1>")
	)
	(arc
		(start 81.431892 -96.910906)
		(mid 81.50469 -97.201669)
		(end 81.425542 -97.490788)
		(width 0.0889)
		(layer "In2.Cu")
		(net "M_K_ECC<1>")
	)
	(arc
		(start 81.425542 -95.909638)
		(mid 81.504764 -96.198756)
		(end 81.431892 -96.48952)
		(width 0.0889)
		(layer "In2.Cu")
		(net "M_K_ECC<1>")
	)
	(arc
		(start 81.425542 -93.528642)
		(mid 81.372043 -93.72854)
		(end 81.425542 -93.928438)
		(width 0.0889)
		(layer "In2.Cu")
		(net "M_K_ECC<1>")
	)
	(arc
		(start 82.284062 -92.042488)
		(mid 82.077058 -92.253352)
		(end 81.793842 -92.337636)
		(width 0.0889)
		(layer "In2.Cu")
		(net "M_K_ECC<1>")
	)
	(arc
		(start 80.895698 -99.76739)
		(mid 80.705769 -99.82526)
		(end 80.567022 -99.967288)
		(width 0.0889)
		(layer "In2.Cu")
		(net "M_K_ECC<1>")
	)
	(arc
		(start 81.420716 -95.518224)
		(mid 81.371961 -95.714576)
		(end 81.425542 -95.909638)
		(width 0.0889)
		(layer "In2.Cu")
		(net "M_K_ECC<1>")
	)
	(arc
		(start 81.427066 -98.883724)
		(mid 81.442355 -99.469907)
		(end 80.9371 -99.76739)
		(width 0.0889)
		(layer "In2.Cu")
		(net "M_K_ECC<1>")
	)
	(arc
		(start 81.425542 -94.919038)
		(mid 81.504764 -95.208156)
		(end 81.431892 -95.49892)
		(width 0.0889)
		(layer "In2.Cu")
		(net "M_K_ECC<1>")
	)
	(arc
		(start 81.431892 -93.939106)
		(mid 81.50469 -94.229869)
		(end 81.425542 -94.518988)
		(width 0.0889)
		(layer "In2.Cu")
		(net "M_K_ECC<1>")
	)
	(arc
		(start 81.420716 -96.508824)
		(mid 81.371961 -96.705176)
		(end 81.425542 -96.900238)
		(width 0.0889)
		(layer "In2.Cu")
		(net "M_K_ECC<1>")
	)
	(arc
		(start 81.761076 -92.337636)
		(mid 81.422907 -92.542434)
		(end 81.425542 -92.937838)
		(width 0.0889)
		(layer "In2.Cu")
		(net "M_K_ECC<1>")
	)
	(arc
		(start 81.420716 -94.527624)
		(mid 81.371961 -94.723976)
		(end 81.425542 -94.919038)
		(width 0.0889)
		(layer "In2.Cu")
		(net "M_K_ECC<1>")
	)
	(arc
		(start 81.420716 -98.490024)
		(mid 81.371961 -98.686376)
		(end 81.425542 -98.881438)
		(width 0.0889)
		(layer "In2.Cu")
		(net "M_K_ECC<1>")
	)
	(arc
		(start 81.425542 -92.937838)
		(mid 81.504673 -93.23324)
		(end 81.425542 -93.528642)
		(width 0.0889)
		(layer "In2.Cu")
		(net "M_K_ECC<1>")
	)
	(arc
		(start 81.425542 -97.890838)
		(mid 81.504764 -98.179956)
		(end 81.431892 -98.47072)
		(width 0.0889)
		(layer "In2.Cu")
		(net "M_K_ECC<1>")
	)
	(segment
		(start 83.202272 -89.27084)
		(end 82.630772 -89.27084)
		(width 0.1651)
		(layer "F.Cu")
		(net "M_K_ECC<0>")
	)
	(segment
		(start 71.349362 -137.676382)
		(end 71.171562 -135.8138)
		(width 0.1651)
		(layer "F.Cu")
		(net "M_K_ECC<0>")
	)
	(segment
		(start 71.349362 -137.67054)
		(end 71.349362 -137.676382)
		(width 0.1651)
		(layer "F.Cu")
		(net "M_K_ECC<0>")
	)
	(via
		(at 82.630772 -89.27084)
		(size 0.508)
		(drill 0.254)
		(layers "F.Cu" "B.Cu")
		(net "M_K_ECC<0>")
	)
	(via
		(at 70.499478 -131.611878)
		(size 0.508)
		(drill 0.254)
		(layers "F.Cu" "B.Cu")
		(net "M_K_ECC<0>")
	)
	(via
		(at 71.171562 -135.8138)
		(size 0.508)
		(drill 0.254)
		(layers "F.Cu" "B.Cu")
		(net "M_K_ECC<0>")
	)
	(segment
		(start 70.499478 -132.876036)
		(end 70.499478 -131.611878)
		(width 0.1651)
		(layer "B.Cu")
		(net "M_K_ECC<0>")
	)
	(segment
		(start 81.254092 -94.01302)
		(end 81.260442 -94.023688)
		(width 0.0889)
		(layer "In2.Cu")
		(net "M_K_ECC<0>")
	)
	(segment
		(start 71.299832 -120.010936)
		(end 71.299832 -123.643136)
		(width 0.14224)
		(layer "In2.Cu")
		(net "M_K_ECC<0>")
	)
	(segment
		(start 70.135496 -131.247896)
		(end 70.499478 -131.611878)
		(width 0.14224)
		(layer "In2.Cu")
		(net "M_K_ECC<0>")
	)
	(segment
		(start 70.986396 -127.659892)
		(end 70.783196 -127.863092)
		(width 0.14224)
		(layer "In2.Cu")
		(net "M_K_ECC<0>")
	)
	(segment
		(start 70.704964 -124.238004)
		(end 70.704964 -125.443996)
		(width 0.14224)
		(layer "In2.Cu")
		(net "M_K_ECC<0>")
	)
	(segment
		(start 71.299832 -123.643136)
		(end 70.704964 -124.238004)
		(width 0.14224)
		(layer "In2.Cu")
		(net "M_K_ECC<0>")
	)
	(segment
		(start 82.118962 -90.556588)
		(end 82.123788 -90.565224)
		(width 0.0889)
		(layer "In2.Cu")
		(net "M_K_ECC<0>")
	)
	(segment
		(start 70.066408 -135.00481)
		(end 70.875398 -135.8138)
		(width 0.14224)
		(layer "In2.Cu")
		(net "M_K_ECC<0>")
	)
	(segment
		(start 81.265268 -95.405702)
		(end 81.260442 -95.414338)
		(width 0.0889)
		(layer "In2.Cu")
		(net "M_K_ECC<0>")
	)
	(segment
		(start 72.794368 -118.5164)
		(end 71.299832 -120.010936)
		(width 0.14224)
		(layer "In2.Cu")
		(net "M_K_ECC<0>")
	)
	(segment
		(start 70.711568 -128.675892)
		(end 70.783196 -128.675892)
		(width 0.14224)
		(layer "In2.Cu")
		(net "M_K_ECC<0>")
	)
	(segment
		(start 70.711568 -127.863092)
		(end 70.508368 -128.066292)
		(width 0.14224)
		(layer "In2.Cu")
		(net "M_K_ECC<0>")
	)
	(segment
		(start 81.260442 -95.414338)
		(end 81.254092 -95.425006)
		(width 0.0889)
		(layer "In2.Cu")
		(net "M_K_ECC<0>")
	)
	(segment
		(start 79.779876 -101.839522)
		(end 79.527146 -102.092252)
		(width 0.0889)
		(layer "In2.Cu")
		(net "M_K_ECC<0>")
	)
	(segment
		(start 82.630772 -89.27084)
		(end 82.135726 -89.936574)
		(width 0.0889)
		(layer "In2.Cu")
		(net "M_K_ECC<0>")
	)
	(segment
		(start 81.260442 -96.404938)
		(end 81.254092 -96.415606)
		(width 0.0889)
		(layer "In2.Cu")
		(net "M_K_ECC<0>")
	)
	(segment
		(start 70.986396 -128.879092)
		(end 70.986396 -129.757678)
		(width 0.14224)
		(layer "In2.Cu")
		(net "M_K_ECC<0>")
	)
	(segment
		(start 80.319118 -100.015548)
		(end 79.779876 -100.55479)
		(width 0.0889)
		(layer "In2.Cu")
		(net "M_K_ECC<0>")
	)
	(segment
		(start 70.508368 -128.066292)
		(end 70.508368 -128.472692)
		(width 0.14224)
		(layer "In2.Cu")
		(net "M_K_ECC<0>")
	)
	(segment
		(start 81.260442 -98.386138)
		(end 81.254092 -98.396806)
		(width 0.0889)
		(layer "In2.Cu")
		(net "M_K_ECC<0>")
	)
	(segment
		(start 80.401922 -99.872038)
		(end 80.319118 -100.015548)
		(width 0.0889)
		(layer "In2.Cu")
		(net "M_K_ECC<0>")
	)
	(segment
		(start 80.920082 -99.576636)
		(end 80.895952 -99.576636)
		(width 0.0889)
		(layer "In2.Cu")
		(net "M_K_ECC<0>")
	)
	(segment
		(start 79.527146 -102.092252)
		(end 79.527146 -103.835962)
		(width 0.14224)
		(layer "In2.Cu")
		(net "M_K_ECC<0>")
	)
	(segment
		(start 70.499478 -131.611878)
		(end 70.066408 -132.044948)
		(width 0.14224)
		(layer "In2.Cu")
		(net "M_K_ECC<0>")
	)
	(segment
		(start 70.986396 -129.757678)
		(end 70.135496 -130.608578)
		(width 0.14224)
		(layer "In2.Cu")
		(net "M_K_ECC<0>")
	)
	(segment
		(start 70.783196 -128.675892)
		(end 70.986396 -128.879092)
		(width 0.14224)
		(layer "In2.Cu")
		(net "M_K_ECC<0>")
	)
	(segment
		(start 79.527146 -103.835962)
		(end 72.794368 -110.56874)
		(width 0.14224)
		(layer "In2.Cu")
		(net "M_K_ECC<0>")
	)
	(segment
		(start 82.135726 -89.936574)
		(end 82.118962 -89.966038)
		(width 0.0889)
		(layer "In2.Cu")
		(net "M_K_ECC<0>")
	)
	(segment
		(start 70.986396 -125.725428)
		(end 70.986396 -127.659892)
		(width 0.14224)
		(layer "In2.Cu")
		(net "M_K_ECC<0>")
	)
	(segment
		(start 70.066408 -132.044948)
		(end 70.066408 -135.00481)
		(width 0.14224)
		(layer "In2.Cu")
		(net "M_K_ECC<0>")
	)
	(segment
		(start 70.508368 -128.472692)
		(end 70.711568 -128.675892)
		(width 0.14224)
		(layer "In2.Cu")
		(net "M_K_ECC<0>")
	)
	(segment
		(start 81.265268 -98.377502)
		(end 81.260442 -98.386138)
		(width 0.0889)
		(layer "In2.Cu")
		(net "M_K_ECC<0>")
	)
	(segment
		(start 81.265268 -93.424502)
		(end 81.260442 -93.433138)
		(width 0.0889)
		(layer "In2.Cu")
		(net "M_K_ECC<0>")
	)
	(segment
		(start 81.265268 -96.396302)
		(end 81.260442 -96.404938)
		(width 0.0889)
		(layer "In2.Cu")
		(net "M_K_ECC<0>")
	)
	(segment
		(start 79.779876 -100.55479)
		(end 79.779876 -101.839522)
		(width 0.0889)
		(layer "In2.Cu")
		(net "M_K_ECC<0>")
	)
	(segment
		(start 70.704964 -125.443996)
		(end 70.986396 -125.725428)
		(width 0.14224)
		(layer "In2.Cu")
		(net "M_K_ECC<0>")
	)
	(segment
		(start 81.260442 -98.976688)
		(end 81.261204 -98.977704)
		(width 0.0889)
		(layer "In2.Cu")
		(net "M_K_ECC<0>")
	)
	(segment
		(start 70.783196 -127.863092)
		(end 70.711568 -127.863092)
		(width 0.14224)
		(layer "In2.Cu")
		(net "M_K_ECC<0>")
	)
	(segment
		(start 82.118962 -91.547188)
		(end 82.123788 -91.555824)
		(width 0.0889)
		(layer "In2.Cu")
		(net "M_K_ECC<0>")
	)
	(segment
		(start 82.112612 -90.54592)
		(end 82.118962 -90.556588)
		(width 0.0889)
		(layer "In2.Cu")
		(net "M_K_ECC<0>")
	)
	(segment
		(start 82.112612 -91.53652)
		(end 82.118962 -91.547188)
		(width 0.0889)
		(layer "In2.Cu")
		(net "M_K_ECC<0>")
	)
	(segment
		(start 72.794368 -110.56874)
		(end 72.794368 -118.5164)
		(width 0.14224)
		(layer "In2.Cu")
		(net "M_K_ECC<0>")
	)
	(segment
		(start 70.875398 -135.8138)
		(end 71.171562 -135.8138)
		(width 0.14224)
		(layer "In2.Cu")
		(net "M_K_ECC<0>")
	)
	(segment
		(start 70.135496 -130.608578)
		(end 70.135496 -131.247896)
		(width 0.14224)
		(layer "In2.Cu")
		(net "M_K_ECC<0>")
	)
	(segment
		(start 81.787238 -92.147136)
		(end 81.754472 -92.147136)
		(width 0.0889)
		(layer "In2.Cu")
		(net "M_K_ECC<0>")
	)
	(arc
		(start 81.260442 -93.033088)
		(mid 81.313912 -93.228151)
		(end 81.265268 -93.424502)
		(width 0.0889)
		(layer "In2.Cu")
		(net "M_K_ECC<0>")
	)
	(arc
		(start 81.254092 -96.415606)
		(mid 81.181294 -96.706369)
		(end 81.260442 -96.995488)
		(width 0.0889)
		(layer "In2.Cu")
		(net "M_K_ECC<0>")
	)
	(arc
		(start 80.895952 -99.576636)
		(mid 80.610528 -99.660103)
		(end 80.401922 -99.872038)
		(width 0.0889)
		(layer "In2.Cu")
		(net "M_K_ECC<0>")
	)
	(arc
		(start 82.123788 -91.555824)
		(mid 82.120041 -91.94508)
		(end 81.787238 -92.147136)
		(width 0.0889)
		(layer "In2.Cu")
		(net "M_K_ECC<0>")
	)
	(arc
		(start 81.254092 -95.425006)
		(mid 81.181294 -95.715769)
		(end 81.260442 -96.004888)
		(width 0.0889)
		(layer "In2.Cu")
		(net "M_K_ECC<0>")
	)
	(arc
		(start 81.754472 -92.147136)
		(mid 81.256221 -92.449976)
		(end 81.260442 -93.033088)
		(width 0.0889)
		(layer "In2.Cu")
		(net "M_K_ECC<0>")
	)
	(arc
		(start 81.260442 -97.395284)
		(mid 81.181311 -97.690686)
		(end 81.260442 -97.986088)
		(width 0.0889)
		(layer "In2.Cu")
		(net "M_K_ECC<0>")
	)
	(arc
		(start 82.123788 -90.565224)
		(mid 82.172543 -90.761576)
		(end 82.118962 -90.956638)
		(width 0.0889)
		(layer "In2.Cu")
		(net "M_K_ECC<0>")
	)
	(arc
		(start 81.254092 -98.396806)
		(mid 81.181294 -98.687569)
		(end 81.260442 -98.976688)
		(width 0.0889)
		(layer "In2.Cu")
		(net "M_K_ECC<0>")
	)
	(arc
		(start 81.260442 -96.004888)
		(mid 81.313912 -96.199951)
		(end 81.265268 -96.396302)
		(width 0.0889)
		(layer "In2.Cu")
		(net "M_K_ECC<0>")
	)
	(arc
		(start 81.260442 -95.014288)
		(mid 81.313912 -95.209351)
		(end 81.265268 -95.405702)
		(width 0.0889)
		(layer "In2.Cu")
		(net "M_K_ECC<0>")
	)
	(arc
		(start 82.118962 -90.956638)
		(mid 82.03974 -91.245756)
		(end 82.112612 -91.53652)
		(width 0.0889)
		(layer "In2.Cu")
		(net "M_K_ECC<0>")
	)
	(arc
		(start 81.261204 -98.977704)
		(mid 81.264789 -99.376413)
		(end 80.920082 -99.576636)
		(width 0.0889)
		(layer "In2.Cu")
		(net "M_K_ECC<0>")
	)
	(arc
		(start 81.260442 -94.023688)
		(mid 81.313941 -94.223586)
		(end 81.260442 -94.423484)
		(width 0.0889)
		(layer "In2.Cu")
		(net "M_K_ECC<0>")
	)
	(arc
		(start 81.260442 -93.433138)
		(mid 81.18122 -93.722256)
		(end 81.254092 -94.01302)
		(width 0.0889)
		(layer "In2.Cu")
		(net "M_K_ECC<0>")
	)
	(arc
		(start 82.118962 -89.966038)
		(mid 82.03974 -90.255156)
		(end 82.112612 -90.54592)
		(width 0.0889)
		(layer "In2.Cu")
		(net "M_K_ECC<0>")
	)
	(arc
		(start 81.260442 -97.986088)
		(mid 81.313912 -98.181151)
		(end 81.265268 -98.377502)
		(width 0.0889)
		(layer "In2.Cu")
		(net "M_K_ECC<0>")
	)
	(arc
		(start 81.260442 -96.995488)
		(mid 81.313941 -97.195386)
		(end 81.260442 -97.395284)
		(width 0.0889)
		(layer "In2.Cu")
		(net "M_K_ECC<0>")
	)
	(arc
		(start 81.260442 -94.423484)
		(mid 81.181311 -94.718886)
		(end 81.260442 -95.014288)
		(width 0.0889)
		(layer "In2.Cu")
		(net "M_K_ECC<0>")
	)
	(segment
		(start 34.799524 -133.693154)
		(end 34.363406 -134.129272)
		(width 0.1651)
		(layer "F.Cu")
		(net "M_K_DQS_DP<9>")
	)
	(segment
		(start 34.30016 -134.26694)
		(end 34.278824 -134.313168)
		(width 0.1651)
		(layer "F.Cu")
		(net "M_K_DQS_DP<9>")
	)
	(segment
		(start 34.278824 -135.131302)
		(end 34.360358 -135.355584)
		(width 0.1651)
		(layer "F.Cu")
		(net "M_K_DQS_DP<9>")
	)
	(segment
		(start 34.360358 -135.355584)
		(end 34.74212 -135.737346)
		(width 0.1651)
		(layer "F.Cu")
		(net "M_K_DQS_DP<9>")
	)
	(segment
		(start 34.363406 -134.129272)
		(end 34.30016 -134.26694)
		(width 0.1651)
		(layer "F.Cu")
		(net "M_K_DQS_DP<9>")
	)
	(segment
		(start 68.607686 -85.803486)
		(end 68.036186 -85.803486)
		(width 0.1651)
		(layer "F.Cu")
		(net "M_K_DQS_DP<9>")
	)
	(segment
		(start 34.799524 -133.0706)
		(end 34.799524 -133.693154)
		(width 0.1651)
		(layer "F.Cu")
		(net "M_K_DQS_DP<9>")
	)
	(segment
		(start 34.278824 -134.313168)
		(end 34.278824 -135.131302)
		(width 0.1651)
		(layer "F.Cu")
		(net "M_K_DQS_DP<9>")
	)
	(via
		(at 68.036186 -85.803486)
		(size 0.508)
		(drill 0.254)
		(layers "F.Cu" "B.Cu")
		(net "M_K_DQS_DP<9>")
	)
	(via
		(at 34.74212 -135.737346)
		(size 0.508)
		(drill 0.254)
		(layers "F.Cu" "B.Cu")
		(net "M_K_DQS_DP<9>")
	)
	(via
		(at 34.74212 -130.2258)
		(size 0.508)
		(drill 0.254)
		(layers "F.Cu" "B.Cu")
		(net "M_K_DQS_DP<9>")
	)
	(segment
		(start 34.34334 -131.80187)
		(end 34.266124 -131.669536)
		(width 0.1651)
		(layer "B.Cu")
		(net "M_K_DQS_DP<9>")
	)
	(segment
		(start 34.266124 -130.773932)
		(end 34.3535 -130.61442)
		(width 0.1651)
		(layer "B.Cu")
		(net "M_K_DQS_DP<9>")
	)
	(segment
		(start 34.266124 -131.669536)
		(end 34.266124 -130.773932)
		(width 0.1651)
		(layer "B.Cu")
		(net "M_K_DQS_DP<9>")
	)
	(segment
		(start 34.3535 -130.61442)
		(end 34.74212 -130.2258)
		(width 0.1651)
		(layer "B.Cu")
		(net "M_K_DQS_DP<9>")
	)
	(segment
		(start 34.799524 -132.258054)
		(end 34.34334 -131.80187)
		(width 0.1651)
		(layer "B.Cu")
		(net "M_K_DQS_DP<9>")
	)
	(segment
		(start 34.799524 -132.876036)
		(end 34.799524 -132.258054)
		(width 0.1651)
		(layer "B.Cu")
		(net "M_K_DQS_DP<9>")
	)
	(segment
		(start 51.773328 -99.268026)
		(end 51.773328 -100.827586)
		(width 0.14224)
		(layer "In2.Cu")
		(net "M_K_DQS_DP<9>")
	)
	(segment
		(start 35.309048 -120.331738)
		(end 35.309048 -128.69672)
		(width 0.14224)
		(layer "In2.Cu")
		(net "M_K_DQS_DP<9>")
	)
	(segment
		(start 66.645028 -86.41588)
		(end 66.467228 -86.41588)
		(width 0.0889)
		(layer "In2.Cu")
		(net "M_K_DQS_DP<9>")
	)
	(segment
		(start 35.840416 -119.05361)
		(end 36.17849 -119.05361)
		(width 0.14224)
		(layer "In2.Cu")
		(net "M_K_DQS_DP<9>")
	)
	(segment
		(start 35.461448 -117.969538)
		(end 35.461448 -118.674642)
		(width 0.14224)
		(layer "In2.Cu")
		(net "M_K_DQS_DP<9>")
	)
	(segment
		(start 64.65697 -86.384384)
		(end 51.773328 -99.268026)
		(width 0.14224)
		(layer "In2.Cu")
		(net "M_K_DQS_DP<9>")
	)
	(segment
		(start 66.187828 -86.31428)
		(end 66.086228 -86.41588)
		(width 0.0889)
		(layer "In2.Cu")
		(net "M_K_DQS_DP<9>")
	)
	(segment
		(start 35.309048 -128.69672)
		(end 35.151568 -128.8542)
		(width 0.14224)
		(layer "In2.Cu")
		(net "M_K_DQS_DP<9>")
	)
	(segment
		(start 39.027354 -113.57356)
		(end 38.036754 -113.57356)
		(width 0.14224)
		(layer "In2.Cu")
		(net "M_K_DQS_DP<9>")
	)
	(segment
		(start 35.840416 -116.76761)
		(end 36.10356 -116.76761)
		(width 0.14224)
		(layer "In2.Cu")
		(net "M_K_DQS_DP<9>")
	)
	(segment
		(start 35.151568 -129.159)
		(end 35.309048 -129.31648)
		(width 0.14224)
		(layer "In2.Cu")
		(net "M_K_DQS_DP<9>")
	)
	(segment
		(start 68.349368 -86.04758)
		(end 68.350384 -86.05139)
		(width 0.0889)
		(layer "In2.Cu")
		(net "M_K_DQS_DP<9>")
	)
	(segment
		(start 35.309048 -129.31648)
		(end 35.309048 -129.938272)
		(width 0.14224)
		(layer "In2.Cu")
		(net "M_K_DQS_DP<9>")
	)
	(segment
		(start 36.07816 -117.64137)
		(end 35.789616 -117.64137)
		(width 0.14224)
		(layer "In2.Cu")
		(net "M_K_DQS_DP<9>")
	)
	(segment
		(start 35.713416 -119.92737)
		(end 35.309048 -120.331738)
		(width 0.14224)
		(layer "In2.Cu")
		(net "M_K_DQS_DP<9>")
	)
	(segment
		(start 66.086228 -86.41588)
		(end 65.800732 -86.41588)
		(width 0.0889)
		(layer "In2.Cu")
		(net "M_K_DQS_DP<9>")
	)
	(segment
		(start 35.563048 -116.490242)
		(end 35.840416 -116.76761)
		(width 0.14224)
		(layer "In2.Cu")
		(net "M_K_DQS_DP<9>")
	)
	(segment
		(start 35.151568 -128.8542)
		(end 35.151568 -129.159)
		(width 0.14224)
		(layer "In2.Cu")
		(net "M_K_DQS_DP<9>")
	)
	(segment
		(start 65.747138 -86.384384)
		(end 64.65697 -86.384384)
		(width 0.14224)
		(layer "In2.Cu")
		(net "M_K_DQS_DP<9>")
	)
	(segment
		(start 68.036186 -85.803486)
		(end 68.329302 -85.97265)
		(width 0.0889)
		(layer "In2.Cu")
		(net "M_K_DQS_DP<9>")
	)
	(segment
		(start 67.188842 -86.69909)
		(end 66.928238 -86.69909)
		(width 0.0889)
		(layer "In2.Cu")
		(net "M_K_DQS_DP<9>")
	)
	(segment
		(start 65.800732 -86.41588)
		(end 65.769236 -86.384384)
		(width 0.0889)
		(layer "In2.Cu")
		(net "M_K_DQS_DP<9>")
	)
	(segment
		(start 36.274248 -117.445282)
		(end 36.07816 -117.64137)
		(width 0.14224)
		(layer "In2.Cu")
		(net "M_K_DQS_DP<9>")
	)
	(segment
		(start 66.365628 -86.31428)
		(end 66.187828 -86.31428)
		(width 0.0889)
		(layer "In2.Cu")
		(net "M_K_DQS_DP<9>")
	)
	(segment
		(start 68.329302 -85.97265)
		(end 68.349368 -86.04758)
		(width 0.0889)
		(layer "In2.Cu")
		(net "M_K_DQS_DP<9>")
	)
	(segment
		(start 36.10229 -119.92737)
		(end 35.713416 -119.92737)
		(width 0.14224)
		(layer "In2.Cu")
		(net "M_K_DQS_DP<9>")
	)
	(segment
		(start 35.309048 -129.938272)
		(end 34.991294 -130.256026)
		(width 0.14224)
		(layer "In2.Cu")
		(net "M_K_DQS_DP<9>")
	)
	(segment
		(start 35.563048 -116.047266)
		(end 35.563048 -116.490242)
		(width 0.14224)
		(layer "In2.Cu")
		(net "M_K_DQS_DP<9>")
	)
	(segment
		(start 34.237168 -130.6576)
		(end 34.237168 -135.232394)
		(width 0.14224)
		(layer "In2.Cu")
		(net "M_K_DQS_DP<9>")
	)
	(segment
		(start 35.789616 -117.64137)
		(end 35.461448 -117.969538)
		(width 0.14224)
		(layer "In2.Cu")
		(net "M_K_DQS_DP<9>")
	)
	(segment
		(start 38.036754 -113.57356)
		(end 35.563048 -116.047266)
		(width 0.14224)
		(layer "In2.Cu")
		(net "M_K_DQS_DP<9>")
	)
	(segment
		(start 35.461448 -118.674642)
		(end 35.840416 -119.05361)
		(width 0.14224)
		(layer "In2.Cu")
		(net "M_K_DQS_DP<9>")
	)
	(segment
		(start 34.991294 -130.256026)
		(end 34.772346 -130.256026)
		(width 0.14224)
		(layer "In2.Cu")
		(net "M_K_DQS_DP<9>")
	)
	(segment
		(start 36.10356 -116.76761)
		(end 36.274248 -116.938298)
		(width 0.14224)
		(layer "In2.Cu")
		(net "M_K_DQS_DP<9>")
	)
	(segment
		(start 36.17849 -119.05361)
		(end 36.323016 -119.198136)
		(width 0.14224)
		(layer "In2.Cu")
		(net "M_K_DQS_DP<9>")
	)
	(segment
		(start 34.668968 -130.2258)
		(end 34.237168 -130.6576)
		(width 0.14224)
		(layer "In2.Cu")
		(net "M_K_DQS_DP<9>")
	)
	(segment
		(start 51.773328 -100.827586)
		(end 39.027354 -113.57356)
		(width 0.14224)
		(layer "In2.Cu")
		(net "M_K_DQS_DP<9>")
	)
	(segment
		(start 34.74212 -130.2258)
		(end 34.668968 -130.2258)
		(width 0.14224)
		(layer "In2.Cu")
		(net "M_K_DQS_DP<9>")
	)
	(segment
		(start 66.467228 -86.41588)
		(end 66.365628 -86.31428)
		(width 0.0889)
		(layer "In2.Cu")
		(net "M_K_DQS_DP<9>")
	)
	(segment
		(start 65.769236 -86.384384)
		(end 65.747138 -86.384384)
		(width 0.0889)
		(layer "In2.Cu")
		(net "M_K_DQS_DP<9>")
	)
	(segment
		(start 66.928238 -86.69909)
		(end 66.645028 -86.41588)
		(width 0.0889)
		(layer "In2.Cu")
		(net "M_K_DQS_DP<9>")
	)
	(segment
		(start 68.051172 -86.203536)
		(end 68.018406 -86.203536)
		(width 0.0889)
		(layer "In2.Cu")
		(net "M_K_DQS_DP<9>")
	)
	(segment
		(start 36.323016 -119.706644)
		(end 36.10229 -119.92737)
		(width 0.14224)
		(layer "In2.Cu")
		(net "M_K_DQS_DP<9>")
	)
	(segment
		(start 34.772346 -130.256026)
		(end 34.74212 -130.2258)
		(width 0.14224)
		(layer "In2.Cu")
		(net "M_K_DQS_DP<9>")
	)
	(segment
		(start 36.274248 -116.938298)
		(end 36.274248 -117.445282)
		(width 0.14224)
		(layer "In2.Cu")
		(net "M_K_DQS_DP<9>")
	)
	(segment
		(start 36.323016 -119.198136)
		(end 36.323016 -119.706644)
		(width 0.14224)
		(layer "In2.Cu")
		(net "M_K_DQS_DP<9>")
	)
	(segment
		(start 34.237168 -135.232394)
		(end 34.74212 -135.737346)
		(width 0.14224)
		(layer "In2.Cu")
		(net "M_K_DQS_DP<9>")
	)
	(arc
		(start 68.147184 -86.188042)
		(mid 68.09965 -86.198708)
		(end 68.051172 -86.203536)
		(width 0.0889)
		(layer "In2.Cu")
		(net "M_K_DQS_DP<9>")
	)
	(arc
		(start 67.524376 -86.498938)
		(mid 67.382693 -86.642742)
		(end 67.188842 -86.69909)
		(width 0.0889)
		(layer "In2.Cu")
		(net "M_K_DQS_DP<9>")
	)
	(arc
		(start 68.350384 -86.05139)
		(mid 68.259484 -86.135622)
		(end 68.147184 -86.188042)
		(width 0.0889)
		(layer "In2.Cu")
		(net "M_K_DQS_DP<9>")
	)
	(arc
		(start 68.018406 -86.203536)
		(mid 67.732982 -86.287003)
		(end 67.524376 -86.498938)
		(width 0.0889)
		(layer "In2.Cu")
		(net "M_K_DQS_DP<9>")
	)
	(segment
		(start 73.899522 -137.67054)
		(end 73.899522 -136.664446)
		(width 0.1651)
		(layer "F.Cu")
		(net "M_K_DQS_DP<8>")
	)
	(segment
		(start 73.937368 -136.6266)
		(end 73.937368 -135.255)
		(width 0.1651)
		(layer "F.Cu")
		(net "M_K_DQS_DP<8>")
	)
	(segment
		(start 84.060792 -90.756486)
		(end 83.489292 -90.756486)
		(width 0.1651)
		(layer "F.Cu")
		(net "M_K_DQS_DP<8>")
	)
	(segment
		(start 73.899522 -136.664446)
		(end 73.937368 -136.6266)
		(width 0.1651)
		(layer "F.Cu")
		(net "M_K_DQS_DP<8>")
	)
	(segment
		(start 73.693528 -135.01116)
		(end 73.437496 -135.01116)
		(width 0.1651)
		(layer "F.Cu")
		(net "M_K_DQS_DP<8>")
	)
	(segment
		(start 73.937368 -135.255)
		(end 73.693528 -135.01116)
		(width 0.1651)
		(layer "F.Cu")
		(net "M_K_DQS_DP<8>")
	)
	(via
		(at 73.437496 -135.01116)
		(size 0.508)
		(drill 0.254)
		(layers "F.Cu" "B.Cu")
		(net "M_K_DQS_DP<8>")
	)
	(via
		(at 83.489292 -90.756486)
		(size 0.508)
		(drill 0.254)
		(layers "F.Cu" "B.Cu")
		(net "M_K_DQS_DP<8>")
	)
	(via
		(at 73.437496 -130.940556)
		(size 0.508)
		(drill 0.254)
		(layers "F.Cu" "B.Cu")
		(net "M_K_DQS_DP<8>")
	)
	(segment
		(start 73.899522 -128.276096)
		(end 73.899522 -129.425954)
		(width 0.1651)
		(layer "B.Cu")
		(net "M_K_DQS_DP<8>")
	)
	(segment
		(start 73.679812 -130.940556)
		(end 73.437496 -130.940556)
		(width 0.1651)
		(layer "B.Cu")
		(net "M_K_DQS_DP<8>")
	)
	(segment
		(start 73.937368 -129.4638)
		(end 73.937368 -130.683)
		(width 0.1651)
		(layer "B.Cu")
		(net "M_K_DQS_DP<8>")
	)
	(segment
		(start 73.937368 -130.683)
		(end 73.679812 -130.940556)
		(width 0.1651)
		(layer "B.Cu")
		(net "M_K_DQS_DP<8>")
	)
	(segment
		(start 73.899522 -129.425954)
		(end 73.937368 -129.4638)
		(width 0.1651)
		(layer "B.Cu")
		(net "M_K_DQS_DP<8>")
	)
	(segment
		(start 73.062846 -133.435852)
		(end 73.062846 -133.662166)
		(width 0.14224)
		(layer "In2.Cu")
		(net "M_K_DQS_DP<8>")
	)
	(segment
		(start 73.440544 -132.842)
		(end 73.440544 -133.118352)
		(width 0.14224)
		(layer "In2.Cu")
		(net "M_K_DQS_DP<8>")
	)
	(segment
		(start 83.142582 -94.518988)
		(end 83.137756 -94.527624)
		(width 0.0889)
		(layer "In2.Cu")
		(net "M_K_DQS_DP<8>")
	)
	(segment
		(start 76.71054 -113.22812)
		(end 75.855576 -113.22812)
		(width 0.14224)
		(layer "In2.Cu")
		(net "M_K_DQS_DP<8>")
	)
	(segment
		(start 73.643744 -133.858)
		(end 73.897744 -134.112)
		(width 0.14224)
		(layer "In2.Cu")
		(net "M_K_DQS_DP<8>")
	)
	(segment
		(start 73.200006 -133.298692)
		(end 73.062846 -133.435852)
		(width 0.14224)
		(layer "In2.Cu")
		(net "M_K_DQS_DP<8>")
	)
	(segment
		(start 73.437496 -130.940556)
		(end 73.872344 -131.375404)
		(width 0.14224)
		(layer "In2.Cu")
		(net "M_K_DQS_DP<8>")
	)
	(segment
		(start 84.005928 -92.450412)
		(end 84.006944 -92.45219)
		(width 0.0889)
		(layer "In2.Cu")
		(net "M_K_DQS_DP<8>")
	)
	(segment
		(start 76.028042 -111.597694)
		(end 76.24953 -111.819182)
		(width 0.14224)
		(layer "In2.Cu")
		(net "M_K_DQS_DP<8>")
	)
	(segment
		(start 83.233768 -96.067372)
		(end 83.233768 -100.085144)
		(width 0.0889)
		(layer "In2.Cu")
		(net "M_K_DQS_DP<8>")
	)
	(segment
		(start 82.114644 -103.505)
		(end 82.114644 -103.527098)
		(width 0.0889)
		(layer "In2.Cu")
		(net "M_K_DQS_DP<8>")
	)
	(segment
		(start 76.028042 -111.166148)
		(end 76.028042 -111.597694)
		(width 0.14224)
		(layer "In2.Cu")
		(net "M_K_DQS_DP<8>")
	)
	(segment
		(start 76.24953 -111.819182)
		(end 76.70292 -111.819182)
		(width 0.14224)
		(layer "In2.Cu")
		(net "M_K_DQS_DP<8>")
	)
	(segment
		(start 73.260204 -133.298692)
		(end 73.200006 -133.298692)
		(width 0.14224)
		(layer "In2.Cu")
		(net "M_K_DQS_DP<8>")
	)
	(segment
		(start 84.003896 -92.44711)
		(end 84.004404 -92.447872)
		(width 0.0889)
		(layer "In2.Cu")
		(net "M_K_DQS_DP<8>")
	)
	(segment
		(start 82.075274 -101.931978)
		(end 82.075274 -103.46563)
		(width 0.0889)
		(layer "In2.Cu")
		(net "M_K_DQS_DP<8>")
	)
	(segment
		(start 76.248768 -110.945422)
		(end 76.028042 -111.166148)
		(width 0.14224)
		(layer "In2.Cu")
		(net "M_K_DQS_DP<8>")
	)
	(segment
		(start 73.23328 -132.0546)
		(end 73.062846 -132.225034)
		(width 0.14224)
		(layer "In2.Cu")
		(net "M_K_DQS_DP<8>")
	)
	(segment
		(start 74.296016 -130.082036)
		(end 73.437496 -130.940556)
		(width 0.14224)
		(layer "In2.Cu")
		(net "M_K_DQS_DP<8>")
	)
	(segment
		(start 82.114644 -103.527098)
		(end 82.114644 -104.87025)
		(width 0.14224)
		(layer "In2.Cu")
		(net "M_K_DQS_DP<8>")
	)
	(segment
		(start 83.502246 -93.32849)
		(end 83.478116 -93.32849)
		(width 0.0889)
		(layer "In2.Cu")
		(net "M_K_DQS_DP<8>")
	)
	(segment
		(start 84.001102 -92.442284)
		(end 84.003388 -92.446094)
		(width 0.0889)
		(layer "In2.Cu")
		(net "M_K_DQS_DP<8>")
	)
	(segment
		(start 73.618344 -132.0546)
		(end 73.23328 -132.0546)
		(width 0.14224)
		(layer "In2.Cu")
		(net "M_K_DQS_DP<8>")
	)
	(segment
		(start 77.2922 -109.692694)
		(end 77.2922 -110.567216)
		(width 0.14224)
		(layer "In2.Cu")
		(net "M_K_DQS_DP<8>")
	)
	(segment
		(start 73.872344 -131.375404)
		(end 73.872344 -131.8006)
		(width 0.14224)
		(layer "In2.Cu")
		(net "M_K_DQS_DP<8>")
	)
	(segment
		(start 73.177654 -132.6642)
		(end 73.262744 -132.6642)
		(width 0.14224)
		(layer "In2.Cu")
		(net "M_K_DQS_DP<8>")
	)
	(segment
		(start 73.262744 -132.6642)
		(end 73.440544 -132.842)
		(width 0.14224)
		(layer "In2.Cu")
		(net "M_K_DQS_DP<8>")
	)
	(segment
		(start 73.062846 -132.225034)
		(end 73.062846 -132.549392)
		(width 0.14224)
		(layer "In2.Cu")
		(net "M_K_DQS_DP<8>")
	)
	(segment
		(start 84.004404 -92.447872)
		(end 84.005928 -92.450412)
		(width 0.0889)
		(layer "In2.Cu")
		(net "M_K_DQS_DP<8>")
	)
	(segment
		(start 74.296016 -123.727718)
		(end 74.296016 -130.082036)
		(width 0.14224)
		(layer "In2.Cu")
		(net "M_K_DQS_DP<8>")
	)
	(segment
		(start 82.114644 -104.87025)
		(end 77.2922 -109.692694)
		(width 0.14224)
		(layer "In2.Cu")
		(net "M_K_DQS_DP<8>")
	)
	(segment
		(start 76.913994 -110.945422)
		(end 76.248768 -110.945422)
		(width 0.14224)
		(layer "In2.Cu")
		(net "M_K_DQS_DP<8>")
	)
	(segment
		(start 73.897744 -134.112)
		(end 73.897744 -134.550912)
		(width 0.14224)
		(layer "In2.Cu")
		(net "M_K_DQS_DP<8>")
	)
	(segment
		(start 77.2922 -110.567216)
		(end 76.913994 -110.945422)
		(width 0.14224)
		(layer "In2.Cu")
		(net "M_K_DQS_DP<8>")
	)
	(segment
		(start 73.872344 -131.8006)
		(end 73.618344 -132.0546)
		(width 0.14224)
		(layer "In2.Cu")
		(net "M_K_DQS_DP<8>")
	)
	(segment
		(start 82.075274 -103.46563)
		(end 82.114644 -103.505)
		(width 0.0889)
		(layer "In2.Cu")
		(net "M_K_DQS_DP<8>")
	)
	(segment
		(start 73.062846 -133.662166)
		(end 73.25868 -133.858)
		(width 0.14224)
		(layer "In2.Cu")
		(net "M_K_DQS_DP<8>")
	)
	(segment
		(start 73.897744 -134.550912)
		(end 73.437496 -135.01116)
		(width 0.14224)
		(layer "In2.Cu")
		(net "M_K_DQS_DP<8>")
	)
	(segment
		(start 75.687936 -113.39576)
		(end 75.687936 -122.335798)
		(width 0.14224)
		(layer "In2.Cu")
		(net "M_K_DQS_DP<8>")
	)
	(segment
		(start 81.996788 -101.795834)
		(end 82.075274 -101.931978)
		(width 0.0889)
		(layer "In2.Cu")
		(net "M_K_DQS_DP<8>")
	)
	(segment
		(start 83.148932 -95.49892)
		(end 83.142582 -95.509588)
		(width 0.0889)
		(layer "In2.Cu")
		(net "M_K_DQS_DP<8>")
	)
	(segment
		(start 77.081888 -112.856772)
		(end 76.71054 -113.22812)
		(width 0.14224)
		(layer "In2.Cu")
		(net "M_K_DQS_DP<8>")
	)
	(segment
		(start 75.687936 -122.335798)
		(end 74.296016 -123.727718)
		(width 0.14224)
		(layer "In2.Cu")
		(net "M_K_DQS_DP<8>")
	)
	(segment
		(start 83.142582 -93.928438)
		(end 83.148932 -93.939106)
		(width 0.0889)
		(layer "In2.Cu")
		(net "M_K_DQS_DP<8>")
	)
	(segment
		(start 83.489292 -90.756486)
		(end 83.49107 -90.760296)
		(width 0.0889)
		(layer "In2.Cu")
		(net "M_K_DQS_DP<8>")
	)
	(segment
		(start 73.440544 -133.118352)
		(end 73.260204 -133.298692)
		(width 0.14224)
		(layer "In2.Cu")
		(net "M_K_DQS_DP<8>")
	)
	(segment
		(start 76.70292 -111.819182)
		(end 77.081888 -112.19815)
		(width 0.14224)
		(layer "In2.Cu")
		(net "M_K_DQS_DP<8>")
	)
	(segment
		(start 84.003388 -92.446094)
		(end 84.003896 -92.44711)
		(width 0.0889)
		(layer "In2.Cu")
		(net "M_K_DQS_DP<8>")
	)
	(segment
		(start 75.855576 -113.22812)
		(end 75.687936 -113.39576)
		(width 0.14224)
		(layer "In2.Cu")
		(net "M_K_DQS_DP<8>")
	)
	(segment
		(start 84.006944 -92.45219)
		(end 84.007452 -92.453206)
		(width 0.0889)
		(layer "In2.Cu")
		(net "M_K_DQS_DP<8>")
	)
	(segment
		(start 82.072226 -101.246686)
		(end 81.985104 -101.422708)
		(width 0.0889)
		(layer "In2.Cu")
		(net "M_K_DQS_DP<8>")
	)
	(segment
		(start 83.142582 -95.909384)
		(end 83.233768 -96.067372)
		(width 0.0889)
		(layer "In2.Cu")
		(net "M_K_DQS_DP<8>")
	)
	(segment
		(start 77.081888 -112.19815)
		(end 77.081888 -112.856772)
		(width 0.14224)
		(layer "In2.Cu")
		(net "M_K_DQS_DP<8>")
	)
	(segment
		(start 83.233768 -100.085144)
		(end 82.072226 -101.246686)
		(width 0.0889)
		(layer "In2.Cu")
		(net "M_K_DQS_DP<8>")
	)
	(segment
		(start 73.25868 -133.858)
		(end 73.643744 -133.858)
		(width 0.14224)
		(layer "In2.Cu")
		(net "M_K_DQS_DP<8>")
	)
	(segment
		(start 73.062846 -132.549392)
		(end 73.177654 -132.6642)
		(width 0.14224)
		(layer "In2.Cu")
		(net "M_K_DQS_DP<8>")
	)
	(arc
		(start 81.985104 -101.422708)
		(mid 81.944267 -101.610718)
		(end 81.996788 -101.795834)
		(width 0.0889)
		(layer "In2.Cu")
		(net "M_K_DQS_DP<8>")
	)
	(arc
		(start 83.137756 -94.527624)
		(mid 83.089001 -94.723976)
		(end 83.142582 -94.919038)
		(width 0.0889)
		(layer "In2.Cu")
		(net "M_K_DQS_DP<8>")
	)
	(arc
		(start 84.007452 -92.453206)
		(mid 84.001275 -93.033138)
		(end 83.502246 -93.32849)
		(width 0.0889)
		(layer "In2.Cu")
		(net "M_K_DQS_DP<8>")
	)
	(arc
		(start 83.478116 -93.32849)
		(mid 83.140001 -93.533192)
		(end 83.142582 -93.928438)
		(width 0.0889)
		(layer "In2.Cu")
		(net "M_K_DQS_DP<8>")
	)
	(arc
		(start 83.148932 -93.939106)
		(mid 83.22173 -94.229869)
		(end 83.142582 -94.518988)
		(width 0.0889)
		(layer "In2.Cu")
		(net "M_K_DQS_DP<8>")
	)
	(arc
		(start 83.142582 -95.509588)
		(mid 83.089083 -95.709486)
		(end 83.142582 -95.909384)
		(width 0.0889)
		(layer "In2.Cu")
		(net "M_K_DQS_DP<8>")
	)
	(arc
		(start 83.836002 -91.547188)
		(mid 83.885817 -91.692913)
		(end 83.876896 -91.846654)
		(width 0.0889)
		(layer "In2.Cu")
		(net "M_K_DQS_DP<8>")
	)
	(arc
		(start 83.49107 -90.760296)
		(mid 83.641888 -91.163232)
		(end 83.836002 -91.547188)
		(width 0.0889)
		(layer "In2.Cu")
		(net "M_K_DQS_DP<8>")
	)
	(arc
		(start 83.876896 -91.846654)
		(mid 83.891294 -92.154412)
		(end 84.001102 -92.442284)
		(width 0.0889)
		(layer "In2.Cu")
		(net "M_K_DQS_DP<8>")
	)
	(arc
		(start 83.142582 -94.919038)
		(mid 83.221804 -95.208156)
		(end 83.148932 -95.49892)
		(width 0.0889)
		(layer "In2.Cu")
		(net "M_K_DQS_DP<8>")
	)
	(segment
		(start 147.643596 -135.01116)
		(end 147.387564 -135.01116)
		(width 0.1651)
		(layer "F.Cu")
		(net "M_K_DQS_DP<7>")
	)
	(segment
		(start 147.84959 -137.67054)
		(end 147.84959 -136.664446)
		(width 0.1651)
		(layer "F.Cu")
		(net "M_K_DQS_DP<7>")
	)
	(segment
		(start 147.887436 -136.6266)
		(end 147.887436 -135.255)
		(width 0.1651)
		(layer "F.Cu")
		(net "M_K_DQS_DP<7>")
	)
	(segment
		(start 147.84959 -136.664446)
		(end 147.887436 -136.6266)
		(width 0.1651)
		(layer "F.Cu")
		(net "M_K_DQS_DP<7>")
	)
	(segment
		(start 123.363228 -98.500184)
		(end 123.934728 -98.500184)
		(width 0.1651)
		(layer "F.Cu")
		(net "M_K_DQS_DP<7>")
	)
	(segment
		(start 147.849336 -137.67054)
		(end 147.84959 -137.67054)
		(width 0.1651)
		(layer "F.Cu")
		(net "M_K_DQS_DP<7>")
	)
	(segment
		(start 147.887436 -135.255)
		(end 147.643596 -135.01116)
		(width 0.1651)
		(layer "F.Cu")
		(net "M_K_DQS_DP<7>")
	)
	(via
		(at 123.934728 -98.500184)
		(size 0.508)
		(drill 0.254)
		(layers "F.Cu" "B.Cu")
		(net "M_K_DQS_DP<7>")
	)
	(via
		(at 147.387564 -135.01116)
		(size 0.508)
		(drill 0.254)
		(layers "F.Cu" "B.Cu")
		(net "M_K_DQS_DP<7>")
	)
	(via
		(at 147.387564 -130.940556)
		(size 0.508)
		(drill 0.254)
		(layers "F.Cu" "B.Cu")
		(net "M_K_DQS_DP<7>")
	)
	(segment
		(start 147.84959 -129.425954)
		(end 147.887436 -129.4638)
		(width 0.1651)
		(layer "B.Cu")
		(net "M_K_DQS_DP<7>")
	)
	(segment
		(start 147.62988 -130.940556)
		(end 147.387564 -130.940556)
		(width 0.1651)
		(layer "B.Cu")
		(net "M_K_DQS_DP<7>")
	)
	(segment
		(start 147.887436 -129.4638)
		(end 147.887436 -130.683)
		(width 0.1651)
		(layer "B.Cu")
		(net "M_K_DQS_DP<7>")
	)
	(segment
		(start 147.84959 -128.276096)
		(end 147.84959 -129.425954)
		(width 0.1651)
		(layer "B.Cu")
		(net "M_K_DQS_DP<7>")
	)
	(segment
		(start 147.849336 -128.276096)
		(end 147.84959 -128.276096)
		(width 0.1651)
		(layer "B.Cu")
		(net "M_K_DQS_DP<7>")
	)
	(segment
		(start 147.887436 -130.683)
		(end 147.62988 -130.940556)
		(width 0.1651)
		(layer "B.Cu")
		(net "M_K_DQS_DP<7>")
	)
	(segment
		(start 147.012914 -132.225034)
		(end 147.012914 -132.549392)
		(width 0.14224)
		(layer "In2.Cu")
		(net "M_K_DQS_DP<7>")
	)
	(segment
		(start 149.243288 -128.204722)
		(end 148.266404 -129.181606)
		(width 0.14224)
		(layer "In2.Cu")
		(net "M_K_DQS_DP<7>")
	)
	(segment
		(start 146.621246 -115.576096)
		(end 147.22856 -116.18341)
		(width 0.14224)
		(layer "In2.Cu")
		(net "M_K_DQS_DP<7>")
	)
	(segment
		(start 147.012914 -133.662166)
		(end 147.208748 -133.858)
		(width 0.14224)
		(layer "In2.Cu")
		(net "M_K_DQS_DP<7>")
	)
	(segment
		(start 146.982688 -117.324886)
		(end 147.408392 -117.75059)
		(width 0.14224)
		(layer "In2.Cu")
		(net "M_K_DQS_DP<7>")
	)
	(segment
		(start 146.982688 -116.96573)
		(end 146.982688 -117.324886)
		(width 0.14224)
		(layer "In2.Cu")
		(net "M_K_DQS_DP<7>")
	)
	(segment
		(start 147.847812 -134.550912)
		(end 147.387564 -135.01116)
		(width 0.14224)
		(layer "In2.Cu")
		(net "M_K_DQS_DP<7>")
	)
	(segment
		(start 147.012914 -133.435852)
		(end 147.012914 -133.662166)
		(width 0.14224)
		(layer "In2.Cu")
		(net "M_K_DQS_DP<7>")
	)
	(segment
		(start 147.408392 -117.75059)
		(end 147.721066 -117.75059)
		(width 0.14224)
		(layer "In2.Cu")
		(net "M_K_DQS_DP<7>")
	)
	(segment
		(start 148.541232 -117.466618)
		(end 149.243288 -118.168674)
		(width 0.14224)
		(layer "In2.Cu")
		(net "M_K_DQS_DP<7>")
	)
	(segment
		(start 147.210272 -133.298692)
		(end 147.150074 -133.298692)
		(width 0.14224)
		(layer "In2.Cu")
		(net "M_K_DQS_DP<7>")
	)
	(segment
		(start 149.243288 -118.168674)
		(end 149.243288 -128.204722)
		(width 0.14224)
		(layer "In2.Cu")
		(net "M_K_DQS_DP<7>")
	)
	(segment
		(start 128.908048 -105.283)
		(end 129.962148 -106.3371)
		(width 0.14224)
		(layer "In2.Cu")
		(net "M_K_DQS_DP<7>")
	)
	(segment
		(start 127.791972 -104.222804)
		(end 128.852168 -105.283)
		(width 0.0889)
		(layer "In2.Cu")
		(net "M_K_DQS_DP<7>")
	)
	(segment
		(start 147.568412 -132.0546)
		(end 147.183348 -132.0546)
		(width 0.14224)
		(layer "In2.Cu")
		(net "M_K_DQS_DP<7>")
	)
	(segment
		(start 147.012914 -132.549392)
		(end 147.127722 -132.6642)
		(width 0.14224)
		(layer "In2.Cu")
		(net "M_K_DQS_DP<7>")
	)
	(segment
		(start 147.593812 -133.858)
		(end 147.847812 -134.112)
		(width 0.14224)
		(layer "In2.Cu")
		(net "M_K_DQS_DP<7>")
	)
	(segment
		(start 147.390612 -132.842)
		(end 147.390612 -133.118352)
		(width 0.14224)
		(layer "In2.Cu")
		(net "M_K_DQS_DP<7>")
	)
	(segment
		(start 133.843268 -106.3371)
		(end 134.694168 -107.188)
		(width 0.14224)
		(layer "In2.Cu")
		(net "M_K_DQS_DP<7>")
	)
	(segment
		(start 147.721066 -117.75059)
		(end 148.005038 -117.466618)
		(width 0.14224)
		(layer "In2.Cu")
		(net "M_K_DQS_DP<7>")
	)
	(segment
		(start 148.266404 -130.061716)
		(end 147.387564 -130.940556)
		(width 0.14224)
		(layer "In2.Cu")
		(net "M_K_DQS_DP<7>")
	)
	(segment
		(start 147.822412 -131.375404)
		(end 147.822412 -131.8006)
		(width 0.14224)
		(layer "In2.Cu")
		(net "M_K_DQS_DP<7>")
	)
	(segment
		(start 126.03861 -104.222804)
		(end 127.791972 -104.222804)
		(width 0.0889)
		(layer "In2.Cu")
		(net "M_K_DQS_DP<7>")
	)
	(segment
		(start 147.22856 -116.719858)
		(end 146.982688 -116.96573)
		(width 0.14224)
		(layer "In2.Cu")
		(net "M_K_DQS_DP<7>")
	)
	(segment
		(start 124.441712 -102.1588)
		(end 124.446538 -102.167436)
		(width 0.0889)
		(layer "In2.Cu")
		(net "M_K_DQS_DP<7>")
	)
	(segment
		(start 147.183348 -132.0546)
		(end 147.012914 -132.225034)
		(width 0.14224)
		(layer "In2.Cu")
		(net "M_K_DQS_DP<7>")
	)
	(segment
		(start 148.266404 -129.181606)
		(end 148.266404 -130.061716)
		(width 0.14224)
		(layer "In2.Cu")
		(net "M_K_DQS_DP<7>")
	)
	(segment
		(start 147.390612 -133.118352)
		(end 147.210272 -133.298692)
		(width 0.14224)
		(layer "In2.Cu")
		(net "M_K_DQS_DP<7>")
	)
	(segment
		(start 128.852168 -105.283)
		(end 128.908048 -105.283)
		(width 0.0889)
		(layer "In2.Cu")
		(net "M_K_DQS_DP<7>")
	)
	(segment
		(start 136.84504 -107.188)
		(end 145.50263 -115.84559)
		(width 0.14224)
		(layer "In2.Cu")
		(net "M_K_DQS_DP<7>")
	)
	(segment
		(start 124.581666 -102.76586)
		(end 126.03861 -104.222804)
		(width 0.0889)
		(layer "In2.Cu")
		(net "M_K_DQS_DP<7>")
	)
	(segment
		(start 124.452888 -100.766118)
		(end 124.446538 -100.776786)
		(width 0.0889)
		(layer "In2.Cu")
		(net "M_K_DQS_DP<7>")
	)
	(segment
		(start 147.150074 -133.298692)
		(end 147.012914 -133.435852)
		(width 0.14224)
		(layer "In2.Cu")
		(net "M_K_DQS_DP<7>")
	)
	(segment
		(start 147.212812 -132.6642)
		(end 147.390612 -132.842)
		(width 0.14224)
		(layer "In2.Cu")
		(net "M_K_DQS_DP<7>")
	)
	(segment
		(start 147.22856 -116.18341)
		(end 147.22856 -116.719858)
		(width 0.14224)
		(layer "In2.Cu")
		(net "M_K_DQS_DP<7>")
	)
	(segment
		(start 124.441712 -100.1776)
		(end 124.446538 -100.186236)
		(width 0.0889)
		(layer "In2.Cu")
		(net "M_K_DQS_DP<7>")
	)
	(segment
		(start 145.815304 -115.84559)
		(end 146.084798 -115.576096)
		(width 0.14224)
		(layer "In2.Cu")
		(net "M_K_DQS_DP<7>")
	)
	(segment
		(start 145.50263 -115.84559)
		(end 145.815304 -115.84559)
		(width 0.14224)
		(layer "In2.Cu")
		(net "M_K_DQS_DP<7>")
	)
	(segment
		(start 147.127722 -132.6642)
		(end 147.212812 -132.6642)
		(width 0.14224)
		(layer "In2.Cu")
		(net "M_K_DQS_DP<7>")
	)
	(segment
		(start 124.581666 -102.680516)
		(end 124.581666 -102.76586)
		(width 0.0889)
		(layer "In2.Cu")
		(net "M_K_DQS_DP<7>")
	)
	(segment
		(start 148.005038 -117.466618)
		(end 148.541232 -117.466618)
		(width 0.14224)
		(layer "In2.Cu")
		(net "M_K_DQS_DP<7>")
	)
	(segment
		(start 124.446538 -102.167436)
		(end 124.452888 -102.178104)
		(width 0.0889)
		(layer "In2.Cu")
		(net "M_K_DQS_DP<7>")
	)
	(segment
		(start 134.694168 -107.188)
		(end 136.84504 -107.188)
		(width 0.14224)
		(layer "In2.Cu")
		(net "M_K_DQS_DP<7>")
	)
	(segment
		(start 129.962148 -106.3371)
		(end 133.843268 -106.3371)
		(width 0.14224)
		(layer "In2.Cu")
		(net "M_K_DQS_DP<7>")
	)
	(segment
		(start 147.822412 -131.8006)
		(end 147.568412 -132.0546)
		(width 0.14224)
		(layer "In2.Cu")
		(net "M_K_DQS_DP<7>")
	)
	(segment
		(start 147.847812 -134.112)
		(end 147.847812 -134.550912)
		(width 0.14224)
		(layer "In2.Cu")
		(net "M_K_DQS_DP<7>")
	)
	(segment
		(start 147.387564 -130.940556)
		(end 147.822412 -131.375404)
		(width 0.14224)
		(layer "In2.Cu")
		(net "M_K_DQS_DP<7>")
	)
	(segment
		(start 147.208748 -133.858)
		(end 147.593812 -133.858)
		(width 0.14224)
		(layer "In2.Cu")
		(net "M_K_DQS_DP<7>")
	)
	(segment
		(start 146.084798 -115.576096)
		(end 146.621246 -115.576096)
		(width 0.14224)
		(layer "In2.Cu")
		(net "M_K_DQS_DP<7>")
	)
	(arc
		(start 124.446538 -101.767386)
		(mid 124.393068 -101.962449)
		(end 124.441712 -102.1588)
		(width 0.0889)
		(layer "In2.Cu")
		(net "M_K_DQS_DP<7>")
	)
	(arc
		(start 124.446538 -99.786186)
		(mid 124.393068 -99.981249)
		(end 124.441712 -100.1776)
		(width 0.0889)
		(layer "In2.Cu")
		(net "M_K_DQS_DP<7>")
	)
	(arc
		(start 124.446538 -100.776786)
		(mid 124.393039 -100.976684)
		(end 124.446538 -101.176582)
		(width 0.0889)
		(layer "In2.Cu")
		(net "M_K_DQS_DP<7>")
	)
	(arc
		(start 124.446538 -101.176582)
		(mid 124.525669 -101.471984)
		(end 124.446538 -101.767386)
		(width 0.0889)
		(layer "In2.Cu")
		(net "M_K_DQS_DP<7>")
	)
	(arc
		(start 123.934728 -98.500184)
		(mid 124.187399 -98.824771)
		(end 124.424948 -99.160584)
		(width 0.0889)
		(layer "In2.Cu")
		(net "M_K_DQS_DP<7>")
	)
	(arc
		(start 124.424948 -99.160584)
		(mid 124.52543 -99.470306)
		(end 124.446538 -99.786186)
		(width 0.0889)
		(layer "In2.Cu")
		(net "M_K_DQS_DP<7>")
	)
	(arc
		(start 124.452888 -102.178104)
		(mid 124.548959 -102.421189)
		(end 124.581666 -102.680516)
		(width 0.0889)
		(layer "In2.Cu")
		(net "M_K_DQS_DP<7>")
	)
	(arc
		(start 124.446538 -100.186236)
		(mid 124.52576 -100.475354)
		(end 124.452888 -100.766118)
		(width 0.0889)
		(layer "In2.Cu")
		(net "M_K_DQS_DP<7>")
	)
	(segment
		(start 138.293602 -135.01116)
		(end 138.03757 -135.01116)
		(width 0.1651)
		(layer "F.Cu")
		(net "M_K_DQS_DP<6>")
	)
	(segment
		(start 118.212362 -98.500184)
		(end 118.783862 -98.500184)
		(width 0.1651)
		(layer "F.Cu")
		(net "M_K_DQS_DP<6>")
	)
	(segment
		(start 138.537442 -136.6266)
		(end 138.537442 -135.255)
		(width 0.1651)
		(layer "F.Cu")
		(net "M_K_DQS_DP<6>")
	)
	(segment
		(start 138.537442 -135.255)
		(end 138.293602 -135.01116)
		(width 0.1651)
		(layer "F.Cu")
		(net "M_K_DQS_DP<6>")
	)
	(segment
		(start 138.499596 -137.67054)
		(end 138.499596 -136.664446)
		(width 0.1651)
		(layer "F.Cu")
		(net "M_K_DQS_DP<6>")
	)
	(segment
		(start 138.499342 -137.67054)
		(end 138.499596 -137.67054)
		(width 0.1651)
		(layer "F.Cu")
		(net "M_K_DQS_DP<6>")
	)
	(segment
		(start 138.499596 -136.664446)
		(end 138.537442 -136.6266)
		(width 0.1651)
		(layer "F.Cu")
		(net "M_K_DQS_DP<6>")
	)
	(via
		(at 138.03757 -135.01116)
		(size 0.508)
		(drill 0.254)
		(layers "F.Cu" "B.Cu")
		(net "M_K_DQS_DP<6>")
	)
	(via
		(at 138.03757 -130.940556)
		(size 0.508)
		(drill 0.254)
		(layers "F.Cu" "B.Cu")
		(net "M_K_DQS_DP<6>")
	)
	(via
		(at 118.783862 -98.500184)
		(size 0.508)
		(drill 0.254)
		(layers "F.Cu" "B.Cu")
		(net "M_K_DQS_DP<6>")
	)
	(segment
		(start 138.279886 -130.940556)
		(end 138.03757 -130.940556)
		(width 0.1651)
		(layer "B.Cu")
		(net "M_K_DQS_DP<6>")
	)
	(segment
		(start 138.537442 -130.683)
		(end 138.279886 -130.940556)
		(width 0.1651)
		(layer "B.Cu")
		(net "M_K_DQS_DP<6>")
	)
	(segment
		(start 138.499596 -128.276096)
		(end 138.499596 -129.425954)
		(width 0.1651)
		(layer "B.Cu")
		(net "M_K_DQS_DP<6>")
	)
	(segment
		(start 138.499596 -129.425954)
		(end 138.537442 -129.4638)
		(width 0.1651)
		(layer "B.Cu")
		(net "M_K_DQS_DP<6>")
	)
	(segment
		(start 138.537442 -129.4638)
		(end 138.537442 -130.683)
		(width 0.1651)
		(layer "B.Cu")
		(net "M_K_DQS_DP<6>")
	)
	(segment
		(start 138.499342 -128.276096)
		(end 138.499596 -128.276096)
		(width 0.1651)
		(layer "B.Cu")
		(net "M_K_DQS_DP<6>")
	)
	(segment
		(start 121.155968 -112.808766)
		(end 124.767086 -116.419884)
		(width 0.14224)
		(layer "In2.Cu")
		(net "M_K_DQS_DP<6>")
	)
	(segment
		(start 131.92506 -115.37188)
		(end 132.304028 -115.750848)
		(width 0.14224)
		(layer "In2.Cu")
		(net "M_K_DQS_DP<6>")
	)
	(segment
		(start 119.302022 -103.169466)
		(end 119.302784 -103.170736)
		(width 0.0889)
		(layer "In2.Cu")
		(net "M_K_DQS_DP<6>")
	)
	(segment
		(start 124.767086 -116.419884)
		(end 130.6703 -116.419884)
		(width 0.14224)
		(layer "In2.Cu")
		(net "M_K_DQS_DP<6>")
	)
	(segment
		(start 138.472418 -131.375404)
		(end 138.472418 -131.8006)
		(width 0.14224)
		(layer "In2.Cu")
		(net "M_K_DQS_DP<6>")
	)
	(segment
		(start 137.66292 -132.225034)
		(end 137.66292 -132.549392)
		(width 0.14224)
		(layer "In2.Cu")
		(net "M_K_DQS_DP<6>")
	)
	(segment
		(start 137.66292 -133.435852)
		(end 137.66292 -133.662166)
		(width 0.14224)
		(layer "In2.Cu")
		(net "M_K_DQS_DP<6>")
	)
	(segment
		(start 138.497818 -134.550912)
		(end 138.03757 -135.01116)
		(width 0.14224)
		(layer "In2.Cu")
		(net "M_K_DQS_DP<6>")
	)
	(segment
		(start 130.891788 -115.750086)
		(end 131.269994 -115.37188)
		(width 0.14224)
		(layer "In2.Cu")
		(net "M_K_DQS_DP<6>")
	)
	(segment
		(start 130.891788 -116.198396)
		(end 130.891788 -115.750086)
		(width 0.14224)
		(layer "In2.Cu")
		(net "M_K_DQS_DP<6>")
	)
	(segment
		(start 119.241824 -106.019346)
		(end 119.108982 -106.152188)
		(width 0.0889)
		(layer "In2.Cu")
		(net "M_K_DQS_DP<6>")
	)
	(segment
		(start 119.295672 -102.167436)
		(end 119.302022 -102.178104)
		(width 0.0889)
		(layer "In2.Cu")
		(net "M_K_DQS_DP<6>")
	)
	(segment
		(start 138.497818 -134.112)
		(end 138.497818 -134.550912)
		(width 0.14224)
		(layer "In2.Cu")
		(net "M_K_DQS_DP<6>")
	)
	(segment
		(start 138.81989 -130.158236)
		(end 138.03757 -130.940556)
		(width 0.14224)
		(layer "In2.Cu")
		(net "M_K_DQS_DP<6>")
	)
	(segment
		(start 133.556756 -115.37188)
		(end 134.18566 -115.37188)
		(width 0.14224)
		(layer "In2.Cu")
		(net "M_K_DQS_DP<6>")
	)
	(segment
		(start 130.6703 -116.419884)
		(end 130.891788 -116.198396)
		(width 0.14224)
		(layer "In2.Cu")
		(net "M_K_DQS_DP<6>")
	)
	(segment
		(start 137.862818 -132.6642)
		(end 138.040618 -132.842)
		(width 0.14224)
		(layer "In2.Cu")
		(net "M_K_DQS_DP<6>")
	)
	(segment
		(start 119.148352 -106.651298)
		(end 119.148352 -110.031784)
		(width 0.14224)
		(layer "In2.Cu")
		(net "M_K_DQS_DP<6>")
	)
	(segment
		(start 138.81989 -120.00611)
		(end 138.81989 -130.158236)
		(width 0.14224)
		(layer "In2.Cu")
		(net "M_K_DQS_DP<6>")
	)
	(segment
		(start 119.108982 -106.58983)
		(end 119.148352 -106.6292)
		(width 0.0889)
		(layer "In2.Cu")
		(net "M_K_DQS_DP<6>")
	)
	(segment
		(start 132.497068 -116.354352)
		(end 132.984748 -116.354352)
		(width 0.14224)
		(layer "In2.Cu")
		(net "M_K_DQS_DP<6>")
	)
	(segment
		(start 119.108982 -106.152188)
		(end 119.108982 -106.58983)
		(width 0.0889)
		(layer "In2.Cu")
		(net "M_K_DQS_DP<6>")
	)
	(segment
		(start 137.66292 -132.549392)
		(end 137.777728 -132.6642)
		(width 0.14224)
		(layer "In2.Cu")
		(net "M_K_DQS_DP<6>")
	)
	(segment
		(start 119.290846 -101.1682)
		(end 119.295672 -101.176836)
		(width 0.0889)
		(layer "In2.Cu")
		(net "M_K_DQS_DP<6>")
	)
	(segment
		(start 119.298212 -103.162354)
		(end 119.302022 -103.169466)
		(width 0.0889)
		(layer "In2.Cu")
		(net "M_K_DQS_DP<6>")
	)
	(segment
		(start 137.860278 -133.298692)
		(end 137.80008 -133.298692)
		(width 0.14224)
		(layer "In2.Cu")
		(net "M_K_DQS_DP<6>")
	)
	(segment
		(start 119.148352 -110.031784)
		(end 121.155968 -112.0394)
		(width 0.14224)
		(layer "In2.Cu")
		(net "M_K_DQS_DP<6>")
	)
	(segment
		(start 119.241824 -103.948738)
		(end 119.241824 -106.019346)
		(width 0.0889)
		(layer "In2.Cu")
		(net "M_K_DQS_DP<6>")
	)
	(segment
		(start 138.472418 -131.8006)
		(end 138.218418 -132.0546)
		(width 0.14224)
		(layer "In2.Cu")
		(net "M_K_DQS_DP<6>")
	)
	(segment
		(start 138.03757 -130.940556)
		(end 138.472418 -131.375404)
		(width 0.14224)
		(layer "In2.Cu")
		(net "M_K_DQS_DP<6>")
	)
	(segment
		(start 138.218418 -132.0546)
		(end 137.833354 -132.0546)
		(width 0.14224)
		(layer "In2.Cu")
		(net "M_K_DQS_DP<6>")
	)
	(segment
		(start 132.984748 -116.354352)
		(end 133.177788 -116.161312)
		(width 0.14224)
		(layer "In2.Cu")
		(net "M_K_DQS_DP<6>")
	)
	(segment
		(start 132.304028 -116.161312)
		(end 132.497068 -116.354352)
		(width 0.14224)
		(layer "In2.Cu")
		(net "M_K_DQS_DP<6>")
	)
	(segment
		(start 137.833354 -132.0546)
		(end 137.66292 -132.225034)
		(width 0.14224)
		(layer "In2.Cu")
		(net "M_K_DQS_DP<6>")
	)
	(segment
		(start 121.155968 -112.0394)
		(end 121.155968 -112.808766)
		(width 0.14224)
		(layer "In2.Cu")
		(net "M_K_DQS_DP<6>")
	)
	(segment
		(start 137.80008 -133.298692)
		(end 137.66292 -133.435852)
		(width 0.14224)
		(layer "In2.Cu")
		(net "M_K_DQS_DP<6>")
	)
	(segment
		(start 138.040618 -132.842)
		(end 138.040618 -133.118352)
		(width 0.14224)
		(layer "In2.Cu")
		(net "M_K_DQS_DP<6>")
	)
	(segment
		(start 119.290846 -102.1588)
		(end 119.295672 -102.167436)
		(width 0.0889)
		(layer "In2.Cu")
		(net "M_K_DQS_DP<6>")
	)
	(segment
		(start 131.269994 -115.37188)
		(end 131.92506 -115.37188)
		(width 0.14224)
		(layer "In2.Cu")
		(net "M_K_DQS_DP<6>")
	)
	(segment
		(start 138.040618 -133.118352)
		(end 137.860278 -133.298692)
		(width 0.14224)
		(layer "In2.Cu")
		(net "M_K_DQS_DP<6>")
	)
	(segment
		(start 133.177788 -116.161312)
		(end 133.177788 -115.750848)
		(width 0.14224)
		(layer "In2.Cu")
		(net "M_K_DQS_DP<6>")
	)
	(segment
		(start 137.66292 -133.662166)
		(end 137.858754 -133.858)
		(width 0.14224)
		(layer "In2.Cu")
		(net "M_K_DQS_DP<6>")
	)
	(segment
		(start 134.18566 -115.37188)
		(end 138.81989 -120.00611)
		(width 0.14224)
		(layer "In2.Cu")
		(net "M_K_DQS_DP<6>")
	)
	(segment
		(start 119.295672 -101.176836)
		(end 119.302022 -101.187504)
		(width 0.0889)
		(layer "In2.Cu")
		(net "M_K_DQS_DP<6>")
	)
	(segment
		(start 137.858754 -133.858)
		(end 138.243818 -133.858)
		(width 0.14224)
		(layer "In2.Cu")
		(net "M_K_DQS_DP<6>")
	)
	(segment
		(start 138.243818 -133.858)
		(end 138.497818 -134.112)
		(width 0.14224)
		(layer "In2.Cu")
		(net "M_K_DQS_DP<6>")
	)
	(segment
		(start 132.304028 -115.750848)
		(end 132.304028 -116.161312)
		(width 0.14224)
		(layer "In2.Cu")
		(net "M_K_DQS_DP<6>")
	)
	(segment
		(start 119.290846 -103.1494)
		(end 119.298212 -103.162354)
		(width 0.0889)
		(layer "In2.Cu")
		(net "M_K_DQS_DP<6>")
	)
	(segment
		(start 133.177788 -115.750848)
		(end 133.556756 -115.37188)
		(width 0.14224)
		(layer "In2.Cu")
		(net "M_K_DQS_DP<6>")
	)
	(segment
		(start 119.148352 -106.6292)
		(end 119.148352 -106.651298)
		(width 0.0889)
		(layer "In2.Cu")
		(net "M_K_DQS_DP<6>")
	)
	(segment
		(start 137.777728 -132.6642)
		(end 137.862818 -132.6642)
		(width 0.14224)
		(layer "In2.Cu")
		(net "M_K_DQS_DP<6>")
	)
	(arc
		(start 118.783862 -98.500184)
		(mid 118.935514 -98.905423)
		(end 119.130572 -99.291648)
		(width 0.0889)
		(layer "In2.Cu")
		(net "M_K_DQS_DP<6>")
	)
	(arc
		(start 119.266716 -100.127562)
		(mid 119.283538 -100.162656)
		(end 119.302022 -100.196904)
		(width 0.0889)
		(layer "In2.Cu")
		(net "M_K_DQS_DP<6>")
	)
	(arc
		(start 119.302022 -101.187504)
		(mid 119.37482 -101.478267)
		(end 119.295672 -101.767386)
		(width 0.0889)
		(layer "In2.Cu")
		(net "M_K_DQS_DP<6>")
	)
	(arc
		(start 119.130572 -99.291648)
		(mid 119.176285 -99.413385)
		(end 119.18061 -99.543362)
		(width 0.0889)
		(layer "In2.Cu")
		(net "M_K_DQS_DP<6>")
	)
	(arc
		(start 119.295672 -103.748586)
		(mid 119.255537 -103.845112)
		(end 119.241824 -103.948738)
		(width 0.0889)
		(layer "In2.Cu")
		(net "M_K_DQS_DP<6>")
	)
	(arc
		(start 119.295672 -100.776786)
		(mid 119.242202 -100.971849)
		(end 119.290846 -101.1682)
		(width 0.0889)
		(layer "In2.Cu")
		(net "M_K_DQS_DP<6>")
	)
	(arc
		(start 119.302022 -100.196904)
		(mid 119.37482 -100.487667)
		(end 119.295672 -100.776786)
		(width 0.0889)
		(layer "In2.Cu")
		(net "M_K_DQS_DP<6>")
	)
	(arc
		(start 119.302784 -103.170736)
		(mid 119.37475 -103.460606)
		(end 119.295672 -103.748586)
		(width 0.0889)
		(layer "In2.Cu")
		(net "M_K_DQS_DP<6>")
	)
	(arc
		(start 119.295672 -102.757986)
		(mid 119.242202 -102.953049)
		(end 119.290846 -103.1494)
		(width 0.0889)
		(layer "In2.Cu")
		(net "M_K_DQS_DP<6>")
	)
	(arc
		(start 119.302022 -102.178104)
		(mid 119.37482 -102.468867)
		(end 119.295672 -102.757986)
		(width 0.0889)
		(layer "In2.Cu")
		(net "M_K_DQS_DP<6>")
	)
	(arc
		(start 119.18061 -99.543362)
		(mid 119.182934 -99.841468)
		(end 119.266716 -100.127562)
		(width 0.0889)
		(layer "In2.Cu")
		(net "M_K_DQS_DP<6>")
	)
	(arc
		(start 119.295672 -101.767386)
		(mid 119.242202 -101.962449)
		(end 119.290846 -102.1588)
		(width 0.0889)
		(layer "In2.Cu")
		(net "M_K_DQS_DP<6>")
	)
	(segment
		(start 129.149602 -137.67054)
		(end 129.149602 -136.664446)
		(width 0.1651)
		(layer "F.Cu")
		(net "M_K_DQS_DP<5>")
	)
	(segment
		(start 129.187448 -136.6266)
		(end 129.187448 -135.255)
		(width 0.1651)
		(layer "F.Cu")
		(net "M_K_DQS_DP<5>")
	)
	(segment
		(start 113.061242 -98.500184)
		(end 113.632742 -98.500184)
		(width 0.1651)
		(layer "F.Cu")
		(net "M_K_DQS_DP<5>")
	)
	(segment
		(start 129.149348 -137.67054)
		(end 129.149602 -137.67054)
		(width 0.1651)
		(layer "F.Cu")
		(net "M_K_DQS_DP<5>")
	)
	(segment
		(start 129.187448 -135.255)
		(end 128.943608 -135.01116)
		(width 0.1651)
		(layer "F.Cu")
		(net "M_K_DQS_DP<5>")
	)
	(segment
		(start 128.943608 -135.01116)
		(end 128.687576 -135.01116)
		(width 0.1651)
		(layer "F.Cu")
		(net "M_K_DQS_DP<5>")
	)
	(segment
		(start 129.149602 -136.664446)
		(end 129.187448 -136.6266)
		(width 0.1651)
		(layer "F.Cu")
		(net "M_K_DQS_DP<5>")
	)
	(via
		(at 113.632742 -98.500184)
		(size 0.508)
		(drill 0.254)
		(layers "F.Cu" "B.Cu")
		(net "M_K_DQS_DP<5>")
	)
	(via
		(at 128.687576 -130.940556)
		(size 0.508)
		(drill 0.254)
		(layers "F.Cu" "B.Cu")
		(net "M_K_DQS_DP<5>")
	)
	(via
		(at 128.687576 -135.01116)
		(size 0.508)
		(drill 0.254)
		(layers "F.Cu" "B.Cu")
		(net "M_K_DQS_DP<5>")
	)
	(segment
		(start 128.929892 -130.940556)
		(end 128.687576 -130.940556)
		(width 0.1651)
		(layer "B.Cu")
		(net "M_K_DQS_DP<5>")
	)
	(segment
		(start 129.187448 -130.683)
		(end 128.929892 -130.940556)
		(width 0.1651)
		(layer "B.Cu")
		(net "M_K_DQS_DP<5>")
	)
	(segment
		(start 129.187448 -129.4638)
		(end 129.187448 -130.683)
		(width 0.1651)
		(layer "B.Cu")
		(net "M_K_DQS_DP<5>")
	)
	(segment
		(start 129.149602 -129.425954)
		(end 129.187448 -129.4638)
		(width 0.1651)
		(layer "B.Cu")
		(net "M_K_DQS_DP<5>")
	)
	(segment
		(start 129.149348 -128.276096)
		(end 129.149602 -128.276096)
		(width 0.1651)
		(layer "B.Cu")
		(net "M_K_DQS_DP<5>")
	)
	(segment
		(start 129.149602 -128.276096)
		(end 129.149602 -129.425954)
		(width 0.1651)
		(layer "B.Cu")
		(net "M_K_DQS_DP<5>")
	)
	(segment
		(start 111.13643 -113.901728)
		(end 111.422942 -113.901728)
		(width 0.14224)
		(layer "In2.Cu")
		(net "M_K_DQS_DP<5>")
	)
	(segment
		(start 129.122424 -131.8006)
		(end 128.868424 -132.0546)
		(width 0.14224)
		(layer "In2.Cu")
		(net "M_K_DQS_DP<5>")
	)
	(segment
		(start 128.312926 -133.435852)
		(end 128.312926 -133.662166)
		(width 0.14224)
		(layer "In2.Cu")
		(net "M_K_DQS_DP<5>")
	)
	(segment
		(start 128.687576 -130.940556)
		(end 129.122424 -131.375404)
		(width 0.14224)
		(layer "In2.Cu")
		(net "M_K_DQS_DP<5>")
	)
	(segment
		(start 110.975902 -113.7412)
		(end 111.13643 -113.901728)
		(width 0.14224)
		(layer "In2.Cu")
		(net "M_K_DQS_DP<5>")
	)
	(segment
		(start 114.223546 -100.673154)
		(end 114.223546 -100.481638)
		(width 0.0889)
		(layer "In2.Cu")
		(net "M_K_DQS_DP<5>")
	)
	(segment
		(start 110.975902 -113.38814)
		(end 110.975902 -113.7412)
		(width 0.14224)
		(layer "In2.Cu")
		(net "M_K_DQS_DP<5>")
	)
	(segment
		(start 128.450086 -133.298692)
		(end 128.312926 -133.435852)
		(width 0.14224)
		(layer "In2.Cu")
		(net "M_K_DQS_DP<5>")
	)
	(segment
		(start 129.12471 -123.815856)
		(end 129.546096 -124.237242)
		(width 0.14224)
		(layer "In2.Cu")
		(net "M_K_DQS_DP<5>")
	)
	(segment
		(start 128.690624 -132.842)
		(end 128.690624 -133.118352)
		(width 0.14224)
		(layer "In2.Cu")
		(net "M_K_DQS_DP<5>")
	)
	(segment
		(start 119.743728 -123.815856)
		(end 129.12471 -123.815856)
		(width 0.14224)
		(layer "In2.Cu")
		(net "M_K_DQS_DP<5>")
	)
	(segment
		(start 128.690624 -133.118352)
		(end 128.510284 -133.298692)
		(width 0.14224)
		(layer "In2.Cu")
		(net "M_K_DQS_DP<5>")
	)
	(segment
		(start 128.48336 -132.0546)
		(end 128.312926 -132.225034)
		(width 0.14224)
		(layer "In2.Cu")
		(net "M_K_DQS_DP<5>")
	)
	(segment
		(start 128.312926 -132.549392)
		(end 128.427734 -132.6642)
		(width 0.14224)
		(layer "In2.Cu")
		(net "M_K_DQS_DP<5>")
	)
	(segment
		(start 111.125254 -113.238788)
		(end 110.975902 -113.38814)
		(width 0.14224)
		(layer "In2.Cu")
		(net "M_K_DQS_DP<5>")
	)
	(segment
		(start 112.35309 -102.813104)
		(end 112.35309 -104.04221)
		(width 0.0889)
		(layer "In2.Cu")
		(net "M_K_DQS_DP<5>")
	)
	(segment
		(start 111.695992 -106.23423)
		(end 111.735362 -106.2736)
		(width 0.0889)
		(layer "In2.Cu")
		(net "M_K_DQS_DP<5>")
	)
	(segment
		(start 111.695992 -104.699308)
		(end 111.695992 -106.23423)
		(width 0.0889)
		(layer "In2.Cu")
		(net "M_K_DQS_DP<5>")
	)
	(segment
		(start 111.735362 -112.926368)
		(end 111.422942 -113.238788)
		(width 0.14224)
		(layer "In2.Cu")
		(net "M_K_DQS_DP<5>")
	)
	(segment
		(start 129.122424 -131.375404)
		(end 129.122424 -131.8006)
		(width 0.14224)
		(layer "In2.Cu")
		(net "M_K_DQS_DP<5>")
	)
	(segment
		(start 111.422942 -113.901728)
		(end 111.735362 -114.214148)
		(width 0.14224)
		(layer "In2.Cu")
		(net "M_K_DQS_DP<5>")
	)
	(segment
		(start 128.427734 -132.6642)
		(end 128.512824 -132.6642)
		(width 0.14224)
		(layer "In2.Cu")
		(net "M_K_DQS_DP<5>")
	)
	(segment
		(start 111.735362 -106.2736)
		(end 111.735362 -106.295698)
		(width 0.0889)
		(layer "In2.Cu")
		(net "M_K_DQS_DP<5>")
	)
	(segment
		(start 111.735362 -106.295698)
		(end 111.735362 -112.926368)
		(width 0.14224)
		(layer "In2.Cu")
		(net "M_K_DQS_DP<5>")
	)
	(segment
		(start 128.893824 -133.858)
		(end 129.147824 -134.112)
		(width 0.14224)
		(layer "In2.Cu")
		(net "M_K_DQS_DP<5>")
	)
	(segment
		(start 111.735362 -115.80749)
		(end 119.743728 -123.815856)
		(width 0.14224)
		(layer "In2.Cu")
		(net "M_K_DQS_DP<5>")
	)
	(segment
		(start 113.050066 -102.557834)
		(end 112.60836 -102.557834)
		(width 0.0889)
		(layer "In2.Cu")
		(net "M_K_DQS_DP<5>")
	)
	(segment
		(start 113.689892 -101.206808)
		(end 113.689892 -101.918008)
		(width 0.0889)
		(layer "In2.Cu")
		(net "M_K_DQS_DP<5>")
	)
	(segment
		(start 129.147824 -134.112)
		(end 129.147824 -134.550912)
		(width 0.14224)
		(layer "In2.Cu")
		(net "M_K_DQS_DP<5>")
	)
	(segment
		(start 113.689892 -101.918008)
		(end 113.050066 -102.557834)
		(width 0.0889)
		(layer "In2.Cu")
		(net "M_K_DQS_DP<5>")
	)
	(segment
		(start 129.546096 -124.237242)
		(end 129.546096 -130.082036)
		(width 0.14224)
		(layer "In2.Cu")
		(net "M_K_DQS_DP<5>")
	)
	(segment
		(start 128.868424 -132.0546)
		(end 128.48336 -132.0546)
		(width 0.14224)
		(layer "In2.Cu")
		(net "M_K_DQS_DP<5>")
	)
	(segment
		(start 128.312926 -132.225034)
		(end 128.312926 -132.549392)
		(width 0.14224)
		(layer "In2.Cu")
		(net "M_K_DQS_DP<5>")
	)
	(segment
		(start 129.546096 -130.082036)
		(end 128.687576 -130.940556)
		(width 0.14224)
		(layer "In2.Cu")
		(net "M_K_DQS_DP<5>")
	)
	(segment
		(start 111.735362 -114.214148)
		(end 111.735362 -115.80749)
		(width 0.14224)
		(layer "In2.Cu")
		(net "M_K_DQS_DP<5>")
	)
	(segment
		(start 112.60836 -102.557834)
		(end 112.35309 -102.813104)
		(width 0.0889)
		(layer "In2.Cu")
		(net "M_K_DQS_DP<5>")
	)
	(segment
		(start 128.50876 -133.858)
		(end 128.893824 -133.858)
		(width 0.14224)
		(layer "In2.Cu")
		(net "M_K_DQS_DP<5>")
	)
	(segment
		(start 128.312926 -133.662166)
		(end 128.50876 -133.858)
		(width 0.14224)
		(layer "In2.Cu")
		(net "M_K_DQS_DP<5>")
	)
	(segment
		(start 128.510284 -133.298692)
		(end 128.450086 -133.298692)
		(width 0.14224)
		(layer "In2.Cu")
		(net "M_K_DQS_DP<5>")
	)
	(segment
		(start 111.422942 -113.238788)
		(end 111.125254 -113.238788)
		(width 0.14224)
		(layer "In2.Cu")
		(net "M_K_DQS_DP<5>")
	)
	(segment
		(start 128.512824 -132.6642)
		(end 128.690624 -132.842)
		(width 0.14224)
		(layer "In2.Cu")
		(net "M_K_DQS_DP<5>")
	)
	(segment
		(start 129.147824 -134.550912)
		(end 128.687576 -135.01116)
		(width 0.14224)
		(layer "In2.Cu")
		(net "M_K_DQS_DP<5>")
	)
	(segment
		(start 112.35309 -104.04221)
		(end 111.695992 -104.699308)
		(width 0.0889)
		(layer "In2.Cu")
		(net "M_K_DQS_DP<5>")
	)
	(segment
		(start 114.223546 -100.673154)
		(end 113.689892 -101.206808)
		(width 0.0889)
		(layer "In2.Cu")
		(net "M_K_DQS_DP<5>")
	)
	(arc
		(start 114.02949 -99.543362)
		(mid 114.025232 -99.413372)
		(end 113.979452 -99.291648)
		(width 0.0889)
		(layer "In2.Cu")
		(net "M_K_DQS_DP<5>")
	)
	(arc
		(start 113.979452 -99.291648)
		(mid 113.784397 -98.905422)
		(end 113.632742 -98.500184)
		(width 0.0889)
		(layer "In2.Cu")
		(net "M_K_DQS_DP<5>")
	)
	(arc
		(start 114.144552 -100.186744)
		(mid 114.037158 -99.873968)
		(end 114.02949 -99.543362)
		(width 0.0889)
		(layer "In2.Cu")
		(net "M_K_DQS_DP<5>")
	)
	(arc
		(start 114.223546 -100.481638)
		(mid 114.203421 -100.329003)
		(end 114.144552 -100.186744)
		(width 0.0889)
		(layer "In2.Cu")
		(net "M_K_DQS_DP<5>")
	)
	(segment
		(start 119.799354 -136.664446)
		(end 119.8372 -136.6266)
		(width 0.1651)
		(layer "F.Cu")
		(net "M_K_DQS_DP<4>")
	)
	(segment
		(start 115.160298 -120.47855)
		(end 115.61699 -120.935242)
		(width 0.1651)
		(layer "F.Cu")
		(net "M_K_DQS_DP<4>")
	)
	(segment
		(start 112.398556 -118.841266)
		(end 112.641888 -119.084598)
		(width 0.1651)
		(layer "F.Cu")
		(net "M_K_DQS_DP<4>")
	)
	(segment
		(start 110.815628 -102.729538)
		(end 110.832138 -102.757986)
		(width 0.0889)
		(layer "F.Cu")
		(net "M_K_DQS_DP<4>")
	)
	(segment
		(start 113.050066 -118.883684)
		(end 113.56467 -118.883684)
		(width 0.1651)
		(layer "F.Cu")
		(net "M_K_DQS_DP<4>")
	)
	(segment
		(start 119.8372 -136.6266)
		(end 119.8372 -135.255)
		(width 0.1651)
		(layer "F.Cu")
		(net "M_K_DQS_DP<4>")
	)
	(segment
		(start 110.152942 -106.573574)
		(end 110.152942 -112.517174)
		(width 0.1016)
		(layer "F.Cu")
		(net "M_K_DQS_DP<4>")
	)
	(segment
		(start 115.470178 -121.576338)
		(end 115.470178 -121.833386)
		(width 0.1651)
		(layer "F.Cu")
		(net "M_K_DQS_DP<4>")
	)
	(segment
		(start 110.551468 -112.9157)
		(end 110.551468 -113.3221)
		(width 0.1016)
		(layer "F.Cu")
		(net "M_K_DQS_DP<4>")
	)
	(segment
		(start 110.551468 -113.3221)
		(end 110.516162 -113.357406)
		(width 0.1016)
		(layer "F.Cu")
		(net "M_K_DQS_DP<4>")
	)
	(segment
		(start 114.717068 -120.47855)
		(end 115.160298 -120.47855)
		(width 0.1651)
		(layer "F.Cu")
		(net "M_K_DQS_DP<4>")
	)
	(segment
		(start 115.61699 -120.935242)
		(end 115.61699 -121.429526)
		(width 0.1651)
		(layer "F.Cu")
		(net "M_K_DQS_DP<4>")
	)
	(segment
		(start 113.56467 -118.883684)
		(end 114.07775 -119.396764)
		(width 0.1651)
		(layer "F.Cu")
		(net "M_K_DQS_DP<4>")
	)
	(segment
		(start 120.117108 -126.480316)
		(end 120.117108 -130.16103)
		(width 0.1651)
		(layer "F.Cu")
		(net "M_K_DQS_DP<4>")
	)
	(segment
		(start 119.8372 -135.255)
		(end 119.59336 -135.01116)
		(width 0.1651)
		(layer "F.Cu")
		(net "M_K_DQS_DP<4>")
	)
	(segment
		(start 114.07775 -119.953786)
		(end 113.890298 -120.141238)
		(width 0.1651)
		(layer "F.Cu")
		(net "M_K_DQS_DP<4>")
	)
	(segment
		(start 112.61217 -115.763548)
		(end 112.61217 -118.368572)
		(width 0.1651)
		(layer "F.Cu")
		(net "M_K_DQS_DP<4>")
	)
	(segment
		(start 110.516162 -113.357406)
		(end 110.516162 -113.66754)
		(width 0.1651)
		(layer "F.Cu")
		(net "M_K_DQS_DP<4>")
	)
	(segment
		(start 110.718092 -103.40086)
		(end 110.718092 -104.86517)
		(width 0.0889)
		(layer "F.Cu")
		(net "M_K_DQS_DP<4>")
	)
	(segment
		(start 110.516162 -113.66754)
		(end 112.61217 -115.763548)
		(width 0.1651)
		(layer "F.Cu")
		(net "M_K_DQS_DP<4>")
	)
	(segment
		(start 112.61217 -118.368572)
		(end 112.398556 -118.582186)
		(width 0.1651)
		(layer "F.Cu")
		(net "M_K_DQS_DP<4>")
	)
	(segment
		(start 112.849152 -119.084598)
		(end 113.050066 -118.883684)
		(width 0.1651)
		(layer "F.Cu")
		(net "M_K_DQS_DP<4>")
	)
	(segment
		(start 110.875572 -103.24338)
		(end 110.718092 -103.40086)
		(width 0.0889)
		(layer "F.Cu")
		(net "M_K_DQS_DP<4>")
	)
	(segment
		(start 110.051342 -105.53192)
		(end 110.051342 -106.471974)
		(width 0.0889)
		(layer "F.Cu")
		(net "M_K_DQS_DP<4>")
	)
	(segment
		(start 113.890298 -120.141238)
		(end 113.890298 -120.393206)
		(width 0.1651)
		(layer "F.Cu")
		(net "M_K_DQS_DP<4>")
	)
	(segment
		(start 110.051342 -106.471974)
		(end 110.152942 -106.573574)
		(width 0.0889)
		(layer "F.Cu")
		(net "M_K_DQS_DP<4>")
	)
	(segment
		(start 115.470178 -121.833386)
		(end 120.117108 -126.480316)
		(width 0.1651)
		(layer "F.Cu")
		(net "M_K_DQS_DP<4>")
	)
	(segment
		(start 115.61699 -121.429526)
		(end 115.470178 -121.576338)
		(width 0.1651)
		(layer "F.Cu")
		(net "M_K_DQS_DP<4>")
	)
	(segment
		(start 113.890298 -120.393206)
		(end 114.201194 -120.704102)
		(width 0.1651)
		(layer "F.Cu")
		(net "M_K_DQS_DP<4>")
	)
	(segment
		(start 112.398556 -118.582186)
		(end 112.398556 -118.841266)
		(width 0.1651)
		(layer "F.Cu")
		(net "M_K_DQS_DP<4>")
	)
	(segment
		(start 120.117108 -130.16103)
		(end 119.337582 -130.940556)
		(width 0.1651)
		(layer "F.Cu")
		(net "M_K_DQS_DP<4>")
	)
	(segment
		(start 110.152942 -112.517174)
		(end 110.551468 -112.9157)
		(width 0.1016)
		(layer "F.Cu")
		(net "M_K_DQS_DP<4>")
	)
	(segment
		(start 112.641888 -119.084598)
		(end 112.849152 -119.084598)
		(width 0.1651)
		(layer "F.Cu")
		(net "M_K_DQS_DP<4>")
	)
	(segment
		(start 110.875572 -102.920292)
		(end 110.875572 -103.24338)
		(width 0.0889)
		(layer "F.Cu")
		(net "M_K_DQS_DP<4>")
	)
	(segment
		(start 119.799354 -137.67054)
		(end 119.799354 -136.664446)
		(width 0.1651)
		(layer "F.Cu")
		(net "M_K_DQS_DP<4>")
	)
	(segment
		(start 114.07775 -119.396764)
		(end 114.07775 -119.953786)
		(width 0.1651)
		(layer "F.Cu")
		(net "M_K_DQS_DP<4>")
	)
	(segment
		(start 119.59336 -135.01116)
		(end 119.337328 -135.01116)
		(width 0.1651)
		(layer "F.Cu")
		(net "M_K_DQS_DP<4>")
	)
	(segment
		(start 114.201194 -120.704102)
		(end 114.491516 -120.704102)
		(width 0.1651)
		(layer "F.Cu")
		(net "M_K_DQS_DP<4>")
	)
	(segment
		(start 114.491516 -120.704102)
		(end 114.717068 -120.47855)
		(width 0.1651)
		(layer "F.Cu")
		(net "M_K_DQS_DP<4>")
	)
	(segment
		(start 119.337582 -130.940556)
		(end 119.337328 -130.940556)
		(width 0.1651)
		(layer "F.Cu")
		(net "M_K_DQS_DP<4>")
	)
	(segment
		(start 110.718092 -104.86517)
		(end 110.051342 -105.53192)
		(width 0.0889)
		(layer "F.Cu")
		(net "M_K_DQS_DP<4>")
	)
	(segment
		(start 110.485682 -101.967538)
		(end 110.815628 -102.729538)
		(width 0.0889)
		(layer "F.Cu")
		(net "M_K_DQS_DP<4>")
	)
	(via
		(at 119.337328 -130.940556)
		(size 0.508)
		(drill 0.254)
		(layers "F.Cu" "B.Cu")
		(net "M_K_DQS_DP<4>")
	)
	(via
		(at 119.337328 -135.01116)
		(size 0.508)
		(drill 0.254)
		(layers "F.Cu" "B.Cu")
		(net "M_K_DQS_DP<4>")
	)
	(arc
		(start 110.832138 -102.757986)
		(mid 110.864561 -102.836277)
		(end 110.875572 -102.920292)
		(width 0.0889)
		(layer "F.Cu")
		(net "M_K_DQS_DP<4>")
	)
	(segment
		(start 119.8372 -129.4638)
		(end 119.8372 -130.683)
		(width 0.1651)
		(layer "B.Cu")
		(net "M_K_DQS_DP<4>")
	)
	(segment
		(start 119.799354 -129.425954)
		(end 119.8372 -129.4638)
		(width 0.1651)
		(layer "B.Cu")
		(net "M_K_DQS_DP<4>")
	)
	(segment
		(start 119.579644 -130.940556)
		(end 119.337328 -130.940556)
		(width 0.1651)
		(layer "B.Cu")
		(net "M_K_DQS_DP<4>")
	)
	(segment
		(start 119.8372 -130.683)
		(end 119.579644 -130.940556)
		(width 0.1651)
		(layer "B.Cu")
		(net "M_K_DQS_DP<4>")
	)
	(segment
		(start 119.799354 -128.276096)
		(end 119.799354 -129.425954)
		(width 0.1651)
		(layer "B.Cu")
		(net "M_K_DQS_DP<4>")
	)
	(segment
		(start 119.79783 -134.550912)
		(end 119.79783 -134.112)
		(width 0.14224)
		(layer "In2.Cu")
		(net "M_K_DQS_DP<4>")
	)
	(segment
		(start 118.962932 -133.435852)
		(end 119.100092 -133.298692)
		(width 0.14224)
		(layer "In2.Cu")
		(net "M_K_DQS_DP<4>")
	)
	(segment
		(start 119.77243 -131.8006)
		(end 119.77243 -131.375404)
		(width 0.14224)
		(layer "In2.Cu")
		(net "M_K_DQS_DP<4>")
	)
	(segment
		(start 119.34063 -133.118352)
		(end 119.34063 -132.842)
		(width 0.14224)
		(layer "In2.Cu")
		(net "M_K_DQS_DP<4>")
	)
	(segment
		(start 119.337582 -135.01116)
		(end 119.79783 -134.550912)
		(width 0.14224)
		(layer "In2.Cu")
		(net "M_K_DQS_DP<4>")
	)
	(segment
		(start 119.100092 -133.298692)
		(end 119.16029 -133.298692)
		(width 0.14224)
		(layer "In2.Cu")
		(net "M_K_DQS_DP<4>")
	)
	(segment
		(start 118.962932 -133.662166)
		(end 118.962932 -133.435852)
		(width 0.14224)
		(layer "In2.Cu")
		(net "M_K_DQS_DP<4>")
	)
	(segment
		(start 119.54383 -133.858)
		(end 119.158766 -133.858)
		(width 0.14224)
		(layer "In2.Cu")
		(net "M_K_DQS_DP<4>")
	)
	(segment
		(start 119.16029 -133.298692)
		(end 119.34063 -133.118352)
		(width 0.14224)
		(layer "In2.Cu")
		(net "M_K_DQS_DP<4>")
	)
	(segment
		(start 119.16283 -132.6642)
		(end 119.07774 -132.6642)
		(width 0.14224)
		(layer "In2.Cu")
		(net "M_K_DQS_DP<4>")
	)
	(segment
		(start 119.34063 -132.842)
		(end 119.16283 -132.6642)
		(width 0.14224)
		(layer "In2.Cu")
		(net "M_K_DQS_DP<4>")
	)
	(segment
		(start 119.158766 -133.858)
		(end 118.962932 -133.662166)
		(width 0.14224)
		(layer "In2.Cu")
		(net "M_K_DQS_DP<4>")
	)
	(segment
		(start 119.77243 -131.375404)
		(end 119.337582 -130.940556)
		(width 0.14224)
		(layer "In2.Cu")
		(net "M_K_DQS_DP<4>")
	)
	(segment
		(start 119.07774 -132.6642)
		(end 118.962932 -132.549392)
		(width 0.14224)
		(layer "In2.Cu")
		(net "M_K_DQS_DP<4>")
	)
	(segment
		(start 118.962932 -132.549392)
		(end 118.962932 -132.225034)
		(width 0.14224)
		(layer "In2.Cu")
		(net "M_K_DQS_DP<4>")
	)
	(segment
		(start 119.51843 -132.0546)
		(end 119.77243 -131.8006)
		(width 0.14224)
		(layer "In2.Cu")
		(net "M_K_DQS_DP<4>")
	)
	(segment
		(start 119.79783 -134.112)
		(end 119.54383 -133.858)
		(width 0.14224)
		(layer "In2.Cu")
		(net "M_K_DQS_DP<4>")
	)
	(segment
		(start 119.337582 -130.940556)
		(end 119.337328 -130.940556)
		(width 0.14224)
		(layer "In2.Cu")
		(net "M_K_DQS_DP<4>")
	)
	(segment
		(start 119.337328 -135.01116)
		(end 119.337582 -135.01116)
		(width 0.14224)
		(layer "In2.Cu")
		(net "M_K_DQS_DP<4>")
	)
	(segment
		(start 119.133366 -132.0546)
		(end 119.51843 -132.0546)
		(width 0.14224)
		(layer "In2.Cu")
		(net "M_K_DQS_DP<4>")
	)
	(segment
		(start 118.962932 -132.225034)
		(end 119.133366 -132.0546)
		(width 0.14224)
		(layer "In2.Cu")
		(net "M_K_DQS_DP<4>")
	)
	(segment
		(start 64.549528 -137.67054)
		(end 64.549528 -136.664446)
		(width 0.1651)
		(layer "F.Cu")
		(net "M_K_DQS_DP<3>")
	)
	(segment
		(start 64.587374 -135.255)
		(end 64.343534 -135.01116)
		(width 0.1651)
		(layer "F.Cu")
		(net "M_K_DQS_DP<3>")
	)
	(segment
		(start 77.192886 -96.700086)
		(end 76.621386 -96.700086)
		(width 0.1651)
		(layer "F.Cu")
		(net "M_K_DQS_DP<3>")
	)
	(segment
		(start 64.587374 -136.6266)
		(end 64.587374 -135.255)
		(width 0.1651)
		(layer "F.Cu")
		(net "M_K_DQS_DP<3>")
	)
	(segment
		(start 64.549528 -136.664446)
		(end 64.587374 -136.6266)
		(width 0.1651)
		(layer "F.Cu")
		(net "M_K_DQS_DP<3>")
	)
	(segment
		(start 64.343534 -135.01116)
		(end 64.087502 -135.01116)
		(width 0.1651)
		(layer "F.Cu")
		(net "M_K_DQS_DP<3>")
	)
	(via
		(at 76.621386 -96.700086)
		(size 0.508)
		(drill 0.254)
		(layers "F.Cu" "B.Cu")
		(net "M_K_DQS_DP<3>")
	)
	(via
		(at 64.087502 -130.940556)
		(size 0.508)
		(drill 0.254)
		(layers "F.Cu" "B.Cu")
		(net "M_K_DQS_DP<3>")
	)
	(via
		(at 64.087502 -135.01116)
		(size 0.508)
		(drill 0.254)
		(layers "F.Cu" "B.Cu")
		(net "M_K_DQS_DP<3>")
	)
	(segment
		(start 64.549528 -128.276096)
		(end 64.549528 -129.425954)
		(width 0.1651)
		(layer "B.Cu")
		(net "M_K_DQS_DP<3>")
	)
	(segment
		(start 64.587374 -129.4638)
		(end 64.587374 -130.683)
		(width 0.1651)
		(layer "B.Cu")
		(net "M_K_DQS_DP<3>")
	)
	(segment
		(start 64.549528 -129.425954)
		(end 64.587374 -129.4638)
		(width 0.1651)
		(layer "B.Cu")
		(net "M_K_DQS_DP<3>")
	)
	(segment
		(start 64.329818 -130.940556)
		(end 64.087502 -130.940556)
		(width 0.1651)
		(layer "B.Cu")
		(net "M_K_DQS_DP<3>")
	)
	(segment
		(start 64.587374 -130.683)
		(end 64.329818 -130.940556)
		(width 0.1651)
		(layer "B.Cu")
		(net "M_K_DQS_DP<3>")
	)
	(segment
		(start 64.946022 -118.939056)
		(end 64.946022 -130.082036)
		(width 0.14224)
		(layer "In2.Cu")
		(net "M_K_DQS_DP<3>")
	)
	(segment
		(start 64.652906 -116.743734)
		(end 65.064386 -116.743734)
		(width 0.14224)
		(layer "In2.Cu")
		(net "M_K_DQS_DP<3>")
	)
	(segment
		(start 63.91275 -132.6642)
		(end 64.09055 -132.842)
		(width 0.14224)
		(layer "In2.Cu")
		(net "M_K_DQS_DP<3>")
	)
	(segment
		(start 67.921378 -104.873044)
		(end 67.921632 -104.928416)
		(width 0.0889)
		(layer "In2.Cu")
		(net "M_K_DQS_DP<3>")
	)
	(segment
		(start 65.423288 -118.46179)
		(end 64.946022 -118.939056)
		(width 0.14224)
		(layer "In2.Cu")
		(net "M_K_DQS_DP<3>")
	)
	(segment
		(start 71.123556 -101.453188)
		(end 70.844156 -101.937566)
		(width 0.0889)
		(layer "In2.Cu")
		(net "M_K_DQS_DP<3>")
	)
	(segment
		(start 67.906138 -104.94391)
		(end 66.980308 -105.86974)
		(width 0.14224)
		(layer "In2.Cu")
		(net "M_K_DQS_DP<3>")
	)
	(segment
		(start 64.946022 -130.082036)
		(end 64.087502 -130.940556)
		(width 0.14224)
		(layer "In2.Cu")
		(net "M_K_DQS_DP<3>")
	)
	(segment
		(start 74.9173 -99.27209)
		(end 74.89317 -99.27209)
		(width 0.0889)
		(layer "In2.Cu")
		(net "M_K_DQS_DP<3>")
	)
	(segment
		(start 64.684656 -114.12347)
		(end 65.397888 -114.836702)
		(width 0.14224)
		(layer "In2.Cu")
		(net "M_K_DQS_DP<3>")
	)
	(segment
		(start 64.829436 -112.118394)
		(end 65.423288 -112.712246)
		(width 0.14224)
		(layer "In2.Cu")
		(net "M_K_DQS_DP<3>")
	)
	(segment
		(start 65.064386 -116.743734)
		(end 65.423288 -117.102636)
		(width 0.14224)
		(layer "In2.Cu")
		(net "M_K_DQS_DP<3>")
	)
	(segment
		(start 65.397888 -115.491768)
		(end 65.019682 -115.869974)
		(width 0.14224)
		(layer "In2.Cu")
		(net "M_K_DQS_DP<3>")
	)
	(segment
		(start 75.780646 -98.77679)
		(end 75.74788 -98.77679)
		(width 0.0889)
		(layer "In2.Cu")
		(net "M_K_DQS_DP<3>")
	)
	(segment
		(start 63.91021 -133.298692)
		(end 63.850012 -133.298692)
		(width 0.14224)
		(layer "In2.Cu")
		(net "M_K_DQS_DP<3>")
	)
	(segment
		(start 74.067416 -99.76739)
		(end 74.027792 -99.76739)
		(width 0.0889)
		(layer "In2.Cu")
		(net "M_K_DQS_DP<3>")
	)
	(segment
		(start 72.34174 -100.75799)
		(end 72.3138 -100.75799)
		(width 0.0889)
		(layer "In2.Cu")
		(net "M_K_DQS_DP<3>")
	)
	(segment
		(start 73.205086 -100.26269)
		(end 73.169272 -100.26269)
		(width 0.0889)
		(layer "In2.Cu")
		(net "M_K_DQS_DP<3>")
	)
	(segment
		(start 64.384936 -116.043456)
		(end 64.384936 -116.475764)
		(width 0.14224)
		(layer "In2.Cu")
		(net "M_K_DQS_DP<3>")
	)
	(segment
		(start 66.980308 -109.336586)
		(end 64.829436 -111.487458)
		(width 0.14224)
		(layer "In2.Cu")
		(net "M_K_DQS_DP<3>")
	)
	(segment
		(start 63.712852 -132.225034)
		(end 63.712852 -132.549392)
		(width 0.14224)
		(layer "In2.Cu")
		(net "M_K_DQS_DP<3>")
	)
	(segment
		(start 64.09055 -132.842)
		(end 64.09055 -133.118352)
		(width 0.14224)
		(layer "In2.Cu")
		(net "M_K_DQS_DP<3>")
	)
	(segment
		(start 67.921632 -104.928416)
		(end 67.906138 -104.94391)
		(width 0.0889)
		(layer "In2.Cu")
		(net "M_K_DQS_DP<3>")
	)
	(segment
		(start 65.423288 -113.205768)
		(end 64.684656 -113.9444)
		(width 0.14224)
		(layer "In2.Cu")
		(net "M_K_DQS_DP<3>")
	)
	(segment
		(start 63.908686 -133.858)
		(end 64.29375 -133.858)
		(width 0.14224)
		(layer "In2.Cu")
		(net "M_K_DQS_DP<3>")
	)
	(segment
		(start 65.397888 -114.836702)
		(end 65.397888 -115.491768)
		(width 0.14224)
		(layer "In2.Cu")
		(net "M_K_DQS_DP<3>")
	)
	(segment
		(start 63.883286 -132.0546)
		(end 63.712852 -132.225034)
		(width 0.14224)
		(layer "In2.Cu")
		(net "M_K_DQS_DP<3>")
	)
	(segment
		(start 63.850012 -133.298692)
		(end 63.712852 -133.435852)
		(width 0.14224)
		(layer "In2.Cu")
		(net "M_K_DQS_DP<3>")
	)
	(segment
		(start 64.29375 -133.858)
		(end 64.54775 -134.112)
		(width 0.14224)
		(layer "In2.Cu")
		(net "M_K_DQS_DP<3>")
	)
	(segment
		(start 64.384936 -116.475764)
		(end 64.652906 -116.743734)
		(width 0.14224)
		(layer "In2.Cu")
		(net "M_K_DQS_DP<3>")
	)
	(segment
		(start 64.26835 -132.0546)
		(end 63.883286 -132.0546)
		(width 0.14224)
		(layer "In2.Cu")
		(net "M_K_DQS_DP<3>")
	)
	(segment
		(start 63.82766 -132.6642)
		(end 63.91275 -132.6642)
		(width 0.14224)
		(layer "In2.Cu")
		(net "M_K_DQS_DP<3>")
	)
	(segment
		(start 64.54775 -134.550912)
		(end 64.087502 -135.01116)
		(width 0.14224)
		(layer "In2.Cu")
		(net "M_K_DQS_DP<3>")
	)
	(segment
		(start 64.087502 -130.940556)
		(end 64.52235 -131.375404)
		(width 0.14224)
		(layer "In2.Cu")
		(net "M_K_DQS_DP<3>")
	)
	(segment
		(start 66.980308 -105.86974)
		(end 66.980308 -109.336586)
		(width 0.14224)
		(layer "In2.Cu")
		(net "M_K_DQS_DP<3>")
	)
	(segment
		(start 70.844156 -101.937566)
		(end 67.921378 -104.873044)
		(width 0.0889)
		(layer "In2.Cu")
		(net "M_K_DQS_DP<3>")
	)
	(segment
		(start 64.52235 -131.375404)
		(end 64.52235 -131.8006)
		(width 0.14224)
		(layer "In2.Cu")
		(net "M_K_DQS_DP<3>")
	)
	(segment
		(start 63.712852 -133.662166)
		(end 63.908686 -133.858)
		(width 0.14224)
		(layer "In2.Cu")
		(net "M_K_DQS_DP<3>")
	)
	(segment
		(start 64.09055 -133.118352)
		(end 63.91021 -133.298692)
		(width 0.14224)
		(layer "In2.Cu")
		(net "M_K_DQS_DP<3>")
	)
	(segment
		(start 65.423288 -112.712246)
		(end 65.423288 -113.205768)
		(width 0.14224)
		(layer "In2.Cu")
		(net "M_K_DQS_DP<3>")
	)
	(segment
		(start 64.54775 -134.112)
		(end 64.54775 -134.550912)
		(width 0.14224)
		(layer "In2.Cu")
		(net "M_K_DQS_DP<3>")
	)
	(segment
		(start 71.491856 -101.253036)
		(end 71.455788 -101.253036)
		(width 0.0889)
		(layer "In2.Cu")
		(net "M_K_DQS_DP<3>")
	)
	(segment
		(start 63.712852 -132.549392)
		(end 63.82766 -132.6642)
		(width 0.14224)
		(layer "In2.Cu")
		(net "M_K_DQS_DP<3>")
	)
	(segment
		(start 76.621386 -96.700086)
		(end 76.621386 -97.03816)
		(width 0.0889)
		(layer "In2.Cu")
		(net "M_K_DQS_DP<3>")
	)
	(segment
		(start 64.52235 -131.8006)
		(end 64.26835 -132.0546)
		(width 0.14224)
		(layer "In2.Cu")
		(net "M_K_DQS_DP<3>")
	)
	(segment
		(start 64.829436 -111.487458)
		(end 64.829436 -112.118394)
		(width 0.14224)
		(layer "In2.Cu")
		(net "M_K_DQS_DP<3>")
	)
	(segment
		(start 65.019682 -115.869974)
		(end 64.558418 -115.869974)
		(width 0.14224)
		(layer "In2.Cu")
		(net "M_K_DQS_DP<3>")
	)
	(segment
		(start 64.558418 -115.869974)
		(end 64.384936 -116.043456)
		(width 0.14224)
		(layer "In2.Cu")
		(net "M_K_DQS_DP<3>")
	)
	(segment
		(start 65.423288 -117.102636)
		(end 65.423288 -118.46179)
		(width 0.14224)
		(layer "In2.Cu")
		(net "M_K_DQS_DP<3>")
	)
	(segment
		(start 64.684656 -113.9444)
		(end 64.684656 -114.12347)
		(width 0.14224)
		(layer "In2.Cu")
		(net "M_K_DQS_DP<3>")
	)
	(segment
		(start 63.712852 -133.435852)
		(end 63.712852 -133.662166)
		(width 0.14224)
		(layer "In2.Cu")
		(net "M_K_DQS_DP<3>")
	)
	(arc
		(start 76.3778 -98.363532)
		(mid 76.320407 -98.41736)
		(end 76.274676 -98.481388)
		(width 0.0889)
		(layer "In2.Cu")
		(net "M_K_DQS_DP<3>")
	)
	(arc
		(start 76.467716 -98.311716)
		(mid 76.421067 -98.334691)
		(end 76.3778 -98.363532)
		(width 0.0889)
		(layer "In2.Cu")
		(net "M_K_DQS_DP<3>")
	)
	(arc
		(start 73.169272 -100.26269)
		(mid 72.979343 -100.32056)
		(end 72.840596 -100.462588)
		(width 0.0889)
		(layer "In2.Cu")
		(net "M_K_DQS_DP<3>")
	)
	(arc
		(start 74.557636 -99.472242)
		(mid 74.350632 -99.683106)
		(end 74.067416 -99.76739)
		(width 0.0889)
		(layer "In2.Cu")
		(net "M_K_DQS_DP<3>")
	)
	(arc
		(start 71.455788 -101.253036)
		(mid 71.263771 -101.310144)
		(end 71.123556 -101.453188)
		(width 0.0889)
		(layer "In2.Cu")
		(net "M_K_DQS_DP<3>")
	)
	(arc
		(start 76.812902 -97.33915)
		(mid 77.021774 -97.703236)
		(end 76.79055 -98.053652)
		(width 0.0889)
		(layer "In2.Cu")
		(net "M_K_DQS_DP<3>")
	)
	(arc
		(start 76.274676 -98.481388)
		(mid 76.066068 -98.69332)
		(end 75.780646 -98.77679)
		(width 0.0889)
		(layer "In2.Cu")
		(net "M_K_DQS_DP<3>")
	)
	(arc
		(start 75.416156 -98.976688)
		(mid 75.205443 -99.189767)
		(end 74.9173 -99.27209)
		(width 0.0889)
		(layer "In2.Cu")
		(net "M_K_DQS_DP<3>")
	)
	(arc
		(start 72.840596 -100.462588)
		(mid 72.629883 -100.675667)
		(end 72.34174 -100.75799)
		(width 0.0889)
		(layer "In2.Cu")
		(net "M_K_DQS_DP<3>")
	)
	(arc
		(start 73.699116 -99.967288)
		(mid 73.490508 -100.17922)
		(end 73.205086 -100.26269)
		(width 0.0889)
		(layer "In2.Cu")
		(net "M_K_DQS_DP<3>")
	)
	(arc
		(start 74.89317 -99.27209)
		(mid 74.69932 -99.32844)
		(end 74.557636 -99.472242)
		(width 0.0889)
		(layer "In2.Cu")
		(net "M_K_DQS_DP<3>")
	)
	(arc
		(start 76.610718 -98.20021)
		(mid 76.5467 -98.265551)
		(end 76.467716 -98.311716)
		(width 0.0889)
		(layer "In2.Cu")
		(net "M_K_DQS_DP<3>")
	)
	(arc
		(start 76.621386 -97.03816)
		(mid 76.67823 -97.213426)
		(end 76.812902 -97.33915)
		(width 0.0889)
		(layer "In2.Cu")
		(net "M_K_DQS_DP<3>")
	)
	(arc
		(start 74.027792 -99.76739)
		(mid 73.837863 -99.82526)
		(end 73.699116 -99.967288)
		(width 0.0889)
		(layer "In2.Cu")
		(net "M_K_DQS_DP<3>")
	)
	(arc
		(start 75.74788 -98.77679)
		(mid 75.556238 -98.833956)
		(end 75.416156 -98.976688)
		(width 0.0889)
		(layer "In2.Cu")
		(net "M_K_DQS_DP<3>")
	)
	(arc
		(start 76.79055 -98.053652)
		(mid 76.691586 -98.11583)
		(end 76.610718 -98.20021)
		(width 0.0889)
		(layer "In2.Cu")
		(net "M_K_DQS_DP<3>")
	)
	(arc
		(start 71.982076 -100.957888)
		(mid 71.775072 -101.168752)
		(end 71.491856 -101.253036)
		(width 0.0889)
		(layer "In2.Cu")
		(net "M_K_DQS_DP<3>")
	)
	(arc
		(start 72.3138 -100.75799)
		(mid 72.122158 -100.815156)
		(end 71.982076 -100.957888)
		(width 0.0889)
		(layer "In2.Cu")
		(net "M_K_DQS_DP<3>")
	)
	(segment
		(start 55.199534 -137.67054)
		(end 55.199534 -136.664446)
		(width 0.1651)
		(layer "F.Cu")
		(net "M_K_DQS_DP<2>")
	)
	(segment
		(start 54.99354 -135.01116)
		(end 54.737508 -135.01116)
		(width 0.1651)
		(layer "F.Cu")
		(net "M_K_DQS_DP<2>")
	)
	(segment
		(start 55.23738 -135.255)
		(end 54.99354 -135.01116)
		(width 0.1651)
		(layer "F.Cu")
		(net "M_K_DQS_DP<2>")
	)
	(segment
		(start 72.041766 -94.718886)
		(end 71.470266 -94.718886)
		(width 0.1651)
		(layer "F.Cu")
		(net "M_K_DQS_DP<2>")
	)
	(segment
		(start 55.23738 -136.6266)
		(end 55.23738 -135.255)
		(width 0.1651)
		(layer "F.Cu")
		(net "M_K_DQS_DP<2>")
	)
	(segment
		(start 55.199534 -136.664446)
		(end 55.23738 -136.6266)
		(width 0.1651)
		(layer "F.Cu")
		(net "M_K_DQS_DP<2>")
	)
	(via
		(at 71.470266 -94.718886)
		(size 0.508)
		(drill 0.254)
		(layers "F.Cu" "B.Cu")
		(net "M_K_DQS_DP<2>")
	)
	(via
		(at 54.737508 -135.01116)
		(size 0.508)
		(drill 0.254)
		(layers "F.Cu" "B.Cu")
		(net "M_K_DQS_DP<2>")
	)
	(via
		(at 54.737508 -130.940556)
		(size 0.508)
		(drill 0.254)
		(layers "F.Cu" "B.Cu")
		(net "M_K_DQS_DP<2>")
	)
	(segment
		(start 54.979824 -130.940556)
		(end 54.737508 -130.940556)
		(width 0.1651)
		(layer "B.Cu")
		(net "M_K_DQS_DP<2>")
	)
	(segment
		(start 55.23738 -129.4638)
		(end 55.23738 -130.683)
		(width 0.1651)
		(layer "B.Cu")
		(net "M_K_DQS_DP<2>")
	)
	(segment
		(start 55.199534 -129.425954)
		(end 55.23738 -129.4638)
		(width 0.1651)
		(layer "B.Cu")
		(net "M_K_DQS_DP<2>")
	)
	(segment
		(start 55.199534 -128.276096)
		(end 55.199534 -129.425954)
		(width 0.1651)
		(layer "B.Cu")
		(net "M_K_DQS_DP<2>")
	)
	(segment
		(start 55.23738 -130.683)
		(end 54.979824 -130.940556)
		(width 0.1651)
		(layer "B.Cu")
		(net "M_K_DQS_DP<2>")
	)
	(segment
		(start 53.392832 -112.56772)
		(end 53.129688 -112.830864)
		(width 0.14224)
		(layer "In2.Cu")
		(net "M_K_DQS_DP<2>")
	)
	(segment
		(start 54.533292 -132.0546)
		(end 54.362858 -132.225034)
		(width 0.14224)
		(layer "In2.Cu")
		(net "M_K_DQS_DP<2>")
	)
	(segment
		(start 55.519828 -130.158236)
		(end 54.737508 -130.940556)
		(width 0.14224)
		(layer "In2.Cu")
		(net "M_K_DQS_DP<2>")
	)
	(segment
		(start 70.767194 -94.624144)
		(end 70.506844 -94.624144)
		(width 0.0889)
		(layer "In2.Cu")
		(net "M_K_DQS_DP<2>")
	)
	(segment
		(start 53.17744 -110.971838)
		(end 53.398166 -111.192564)
		(width 0.14224)
		(layer "In2.Cu")
		(net "M_K_DQS_DP<2>")
	)
	(segment
		(start 69.7738 -94.31909)
		(end 68.96481 -94.31909)
		(width 0.0889)
		(layer "In2.Cu")
		(net "M_K_DQS_DP<2>")
	)
	(segment
		(start 54.500018 -133.298692)
		(end 54.362858 -133.435852)
		(width 0.14224)
		(layer "In2.Cu")
		(net "M_K_DQS_DP<2>")
	)
	(segment
		(start 55.415688 -109.939836)
		(end 55.03672 -110.318804)
		(width 0.14224)
		(layer "In2.Cu")
		(net "M_K_DQS_DP<2>")
	)
	(segment
		(start 55.197756 -134.112)
		(end 55.197756 -134.550912)
		(width 0.14224)
		(layer "In2.Cu")
		(net "M_K_DQS_DP<2>")
	)
	(segment
		(start 64.998092 -96.177608)
		(end 64.998092 -96.270064)
		(width 0.0889)
		(layer "In2.Cu")
		(net "M_K_DQS_DP<2>")
	)
	(segment
		(start 64.998092 -96.270064)
		(end 64.672972 -96.595184)
		(width 0.0889)
		(layer "In2.Cu")
		(net "M_K_DQS_DP<2>")
	)
	(segment
		(start 58.478928 -105.293668)
		(end 55.415688 -108.356908)
		(width 0.14224)
		(layer "In2.Cu")
		(net "M_K_DQS_DP<2>")
	)
	(segment
		(start 54.362858 -133.435852)
		(end 54.362858 -133.662166)
		(width 0.14224)
		(layer "In2.Cu")
		(net "M_K_DQS_DP<2>")
	)
	(segment
		(start 64.672972 -96.651064)
		(end 64.657224 -96.666812)
		(width 0.0889)
		(layer "In2.Cu")
		(net "M_K_DQS_DP<2>")
	)
	(segment
		(start 54.362858 -133.662166)
		(end 54.558692 -133.858)
		(width 0.14224)
		(layer "In2.Cu")
		(net "M_K_DQS_DP<2>")
	)
	(segment
		(start 66.537586 -94.638114)
		(end 64.998092 -96.177608)
		(width 0.0889)
		(layer "In2.Cu")
		(net "M_K_DQS_DP<2>")
	)
	(segment
		(start 54.740556 -133.118352)
		(end 54.560216 -133.298692)
		(width 0.14224)
		(layer "In2.Cu")
		(net "M_K_DQS_DP<2>")
	)
	(segment
		(start 53.815488 -114.10188)
		(end 53.815488 -127.103886)
		(width 0.14224)
		(layer "In2.Cu")
		(net "M_K_DQS_DP<2>")
	)
	(segment
		(start 71.470266 -94.718886)
		(end 70.767194 -94.624144)
		(width 0.0889)
		(layer "In2.Cu")
		(net "M_K_DQS_DP<2>")
	)
	(segment
		(start 55.415688 -111.571532)
		(end 55.415688 -112.18926)
		(width 0.14224)
		(layer "In2.Cu")
		(net "M_K_DQS_DP<2>")
	)
	(segment
		(start 64.672972 -96.595184)
		(end 64.672972 -96.651064)
		(width 0.0889)
		(layer "In2.Cu")
		(net "M_K_DQS_DP<2>")
	)
	(segment
		(start 53.17744 -110.53953)
		(end 53.17744 -110.971838)
		(width 0.14224)
		(layer "In2.Cu")
		(net "M_K_DQS_DP<2>")
	)
	(segment
		(start 53.398166 -111.192564)
		(end 55.03672 -111.192564)
		(width 0.14224)
		(layer "In2.Cu")
		(net "M_K_DQS_DP<2>")
	)
	(segment
		(start 64.657224 -96.666812)
		(end 58.478928 -102.845616)
		(width 0.14224)
		(layer "In2.Cu")
		(net "M_K_DQS_DP<2>")
	)
	(segment
		(start 54.740556 -132.842)
		(end 54.740556 -133.118352)
		(width 0.14224)
		(layer "In2.Cu")
		(net "M_K_DQS_DP<2>")
	)
	(segment
		(start 68.96481 -94.31909)
		(end 68.645786 -94.638114)
		(width 0.0889)
		(layer "In2.Cu")
		(net "M_K_DQS_DP<2>")
	)
	(segment
		(start 54.918356 -132.0546)
		(end 54.533292 -132.0546)
		(width 0.14224)
		(layer "In2.Cu")
		(net "M_K_DQS_DP<2>")
	)
	(segment
		(start 55.519828 -128.808226)
		(end 55.519828 -130.158236)
		(width 0.14224)
		(layer "In2.Cu")
		(net "M_K_DQS_DP<2>")
	)
	(segment
		(start 54.558692 -133.858)
		(end 54.943756 -133.858)
		(width 0.14224)
		(layer "In2.Cu")
		(net "M_K_DQS_DP<2>")
	)
	(segment
		(start 53.129688 -113.41608)
		(end 53.815488 -114.10188)
		(width 0.14224)
		(layer "In2.Cu")
		(net "M_K_DQS_DP<2>")
	)
	(segment
		(start 54.362858 -132.225034)
		(end 54.362858 -132.549392)
		(width 0.14224)
		(layer "In2.Cu")
		(net "M_K_DQS_DP<2>")
	)
	(segment
		(start 54.560216 -133.298692)
		(end 54.500018 -133.298692)
		(width 0.14224)
		(layer "In2.Cu")
		(net "M_K_DQS_DP<2>")
	)
	(segment
		(start 70.506844 -94.624144)
		(end 70.013576 -94.414848)
		(width 0.0889)
		(layer "In2.Cu")
		(net "M_K_DQS_DP<2>")
	)
	(segment
		(start 54.737508 -130.940556)
		(end 55.172356 -131.375404)
		(width 0.14224)
		(layer "In2.Cu")
		(net "M_K_DQS_DP<2>")
	)
	(segment
		(start 55.03672 -110.318804)
		(end 53.398166 -110.318804)
		(width 0.14224)
		(layer "In2.Cu")
		(net "M_K_DQS_DP<2>")
	)
	(segment
		(start 55.415688 -108.356908)
		(end 55.415688 -109.939836)
		(width 0.14224)
		(layer "In2.Cu")
		(net "M_K_DQS_DP<2>")
	)
	(segment
		(start 54.943756 -133.858)
		(end 55.197756 -134.112)
		(width 0.14224)
		(layer "In2.Cu")
		(net "M_K_DQS_DP<2>")
	)
	(segment
		(start 55.197756 -134.550912)
		(end 54.737508 -135.01116)
		(width 0.14224)
		(layer "In2.Cu")
		(net "M_K_DQS_DP<2>")
	)
	(segment
		(start 53.815488 -127.103886)
		(end 55.519828 -128.808226)
		(width 0.14224)
		(layer "In2.Cu")
		(net "M_K_DQS_DP<2>")
	)
	(segment
		(start 53.129688 -112.830864)
		(end 53.129688 -113.41608)
		(width 0.14224)
		(layer "In2.Cu")
		(net "M_K_DQS_DP<2>")
	)
	(segment
		(start 54.362858 -132.549392)
		(end 54.477666 -132.6642)
		(width 0.14224)
		(layer "In2.Cu")
		(net "M_K_DQS_DP<2>")
	)
	(segment
		(start 54.562756 -132.6642)
		(end 54.740556 -132.842)
		(width 0.14224)
		(layer "In2.Cu")
		(net "M_K_DQS_DP<2>")
	)
	(segment
		(start 53.398166 -110.318804)
		(end 53.17744 -110.53953)
		(width 0.14224)
		(layer "In2.Cu")
		(net "M_K_DQS_DP<2>")
	)
	(segment
		(start 55.415688 -112.18926)
		(end 55.037228 -112.56772)
		(width 0.14224)
		(layer "In2.Cu")
		(net "M_K_DQS_DP<2>")
	)
	(segment
		(start 55.037228 -112.56772)
		(end 53.392832 -112.56772)
		(width 0.14224)
		(layer "In2.Cu")
		(net "M_K_DQS_DP<2>")
	)
	(segment
		(start 55.03672 -111.192564)
		(end 55.415688 -111.571532)
		(width 0.14224)
		(layer "In2.Cu")
		(net "M_K_DQS_DP<2>")
	)
	(segment
		(start 58.478928 -102.845616)
		(end 58.478928 -105.293668)
		(width 0.14224)
		(layer "In2.Cu")
		(net "M_K_DQS_DP<2>")
	)
	(segment
		(start 54.477666 -132.6642)
		(end 54.562756 -132.6642)
		(width 0.14224)
		(layer "In2.Cu")
		(net "M_K_DQS_DP<2>")
	)
	(segment
		(start 68.645786 -94.638114)
		(end 66.537586 -94.638114)
		(width 0.0889)
		(layer "In2.Cu")
		(net "M_K_DQS_DP<2>")
	)
	(segment
		(start 55.172356 -131.8006)
		(end 54.918356 -132.0546)
		(width 0.14224)
		(layer "In2.Cu")
		(net "M_K_DQS_DP<2>")
	)
	(segment
		(start 55.172356 -131.375404)
		(end 55.172356 -131.8006)
		(width 0.14224)
		(layer "In2.Cu")
		(net "M_K_DQS_DP<2>")
	)
	(arc
		(start 70.013576 -94.414848)
		(mid 69.999726 -94.403484)
		(end 69.985382 -94.39275)
		(width 0.0889)
		(layer "In2.Cu")
		(net "M_K_DQS_DP<2>")
	)
	(arc
		(start 69.985382 -94.39275)
		(mid 69.884849 -94.340817)
		(end 69.7738 -94.31909)
		(width 0.0889)
		(layer "In2.Cu")
		(net "M_K_DQS_DP<2>")
	)
	(segment
		(start 68.095368 -95.411036)
		(end 67.942968 -95.411036)
		(width 0.0889)
		(layer "F.Cu")
		(net "M_K_DQS_DP<1>")
	)
	(segment
		(start 46.430438 -126.13767)
		(end 46.779688 -126.48692)
		(width 0.1651)
		(layer "F.Cu")
		(net "M_K_DQS_DP<1>")
	)
	(segment
		(start 45.887386 -135.255)
		(end 45.643546 -135.01116)
		(width 0.1651)
		(layer "F.Cu")
		(net "M_K_DQS_DP<1>")
	)
	(segment
		(start 45.643546 -135.01116)
		(end 45.387514 -135.01116)
		(width 0.1651)
		(layer "F.Cu")
		(net "M_K_DQS_DP<1>")
	)
	(segment
		(start 45.92193 -130.406394)
		(end 45.387768 -130.940556)
		(width 0.1651)
		(layer "F.Cu")
		(net "M_K_DQS_DP<1>")
	)
	(segment
		(start 66.398648 -95.359474)
		(end 46.779688 -114.978434)
		(width 0.1651)
		(layer "F.Cu")
		(net "M_K_DQS_DP<1>")
	)
	(segment
		(start 45.887386 -136.6266)
		(end 45.887386 -135.255)
		(width 0.1651)
		(layer "F.Cu")
		(net "M_K_DQS_DP<1>")
	)
	(segment
		(start 46.430438 -125.25121)
		(end 46.117256 -125.25121)
		(width 0.1651)
		(layer "F.Cu")
		(net "M_K_DQS_DP<1>")
	)
	(segment
		(start 46.779688 -122.54484)
		(end 46.430438 -122.89409)
		(width 0.1651)
		(layer "F.Cu")
		(net "M_K_DQS_DP<1>")
	)
	(segment
		(start 45.387768 -130.940556)
		(end 45.387514 -130.940556)
		(width 0.1651)
		(layer "F.Cu")
		(net "M_K_DQS_DP<1>")
	)
	(segment
		(start 45.938948 -125.429518)
		(end 45.938948 -125.959362)
		(width 0.1651)
		(layer "F.Cu")
		(net "M_K_DQS_DP<1>")
	)
	(segment
		(start 46.779688 -121.77268)
		(end 46.779688 -122.54484)
		(width 0.1651)
		(layer "F.Cu")
		(net "M_K_DQS_DP<1>")
	)
	(segment
		(start 46.779688 -124.1298)
		(end 46.779688 -124.90196)
		(width 0.1651)
		(layer "F.Cu")
		(net "M_K_DQS_DP<1>")
	)
	(segment
		(start 46.117256 -125.25121)
		(end 45.938948 -125.429518)
		(width 0.1651)
		(layer "F.Cu")
		(net "M_K_DQS_DP<1>")
	)
	(segment
		(start 46.117256 -126.13767)
		(end 46.430438 -126.13767)
		(width 0.1651)
		(layer "F.Cu")
		(net "M_K_DQS_DP<1>")
	)
	(segment
		(start 68.607686 -95.709486)
		(end 68.89496 -95.543878)
		(width 0.0889)
		(layer "F.Cu")
		(net "M_K_DQS_DP<1>")
	)
	(segment
		(start 45.84954 -137.67054)
		(end 45.84954 -136.664446)
		(width 0.1651)
		(layer "F.Cu")
		(net "M_K_DQS_DP<1>")
	)
	(segment
		(start 46.779688 -119.75592)
		(end 45.992288 -120.54332)
		(width 0.1651)
		(layer "F.Cu")
		(net "M_K_DQS_DP<1>")
	)
	(segment
		(start 45.992288 -120.54332)
		(end 45.992288 -120.98528)
		(width 0.1651)
		(layer "F.Cu")
		(net "M_K_DQS_DP<1>")
	)
	(segment
		(start 46.779688 -124.90196)
		(end 46.430438 -125.25121)
		(width 0.1651)
		(layer "F.Cu")
		(net "M_K_DQS_DP<1>")
	)
	(segment
		(start 46.779688 -126.48692)
		(end 46.779688 -127.083312)
		(width 0.1651)
		(layer "F.Cu")
		(net "M_K_DQS_DP<1>")
	)
	(segment
		(start 46.430438 -122.89409)
		(end 46.117256 -122.89409)
		(width 0.1651)
		(layer "F.Cu")
		(net "M_K_DQS_DP<1>")
	)
	(segment
		(start 45.992288 -120.98528)
		(end 46.779688 -121.77268)
		(width 0.1651)
		(layer "F.Cu")
		(net "M_K_DQS_DP<1>")
	)
	(segment
		(start 67.942968 -95.411036)
		(end 67.841368 -95.309436)
		(width 0.0889)
		(layer "F.Cu")
		(net "M_K_DQS_DP<1>")
	)
	(segment
		(start 46.117256 -122.89409)
		(end 45.938948 -123.072398)
		(width 0.1651)
		(layer "F.Cu")
		(net "M_K_DQS_DP<1>")
	)
	(segment
		(start 45.938948 -123.072398)
		(end 45.938948 -123.602242)
		(width 0.1651)
		(layer "F.Cu")
		(net "M_K_DQS_DP<1>")
	)
	(segment
		(start 45.938948 -123.602242)
		(end 46.117256 -123.78055)
		(width 0.1651)
		(layer "F.Cu")
		(net "M_K_DQS_DP<1>")
	)
	(segment
		(start 67.409568 -95.359474)
		(end 66.398648 -95.359474)
		(width 0.1651)
		(layer "F.Cu")
		(net "M_K_DQS_DP<1>")
	)
	(segment
		(start 46.117256 -123.78055)
		(end 46.430438 -123.78055)
		(width 0.1651)
		(layer "F.Cu")
		(net "M_K_DQS_DP<1>")
	)
	(segment
		(start 68.61937 -95.30969)
		(end 68.501768 -95.309436)
		(width 0.0889)
		(layer "F.Cu")
		(net "M_K_DQS_DP<1>")
	)
	(segment
		(start 46.430438 -123.78055)
		(end 46.779688 -124.1298)
		(width 0.1651)
		(layer "F.Cu")
		(net "M_K_DQS_DP<1>")
	)
	(segment
		(start 45.938948 -125.959362)
		(end 46.117256 -126.13767)
		(width 0.1651)
		(layer "F.Cu")
		(net "M_K_DQS_DP<1>")
	)
	(segment
		(start 45.84954 -136.664446)
		(end 45.887386 -136.6266)
		(width 0.1651)
		(layer "F.Cu")
		(net "M_K_DQS_DP<1>")
	)
	(segment
		(start 45.92193 -127.94107)
		(end 45.92193 -130.406394)
		(width 0.1651)
		(layer "F.Cu")
		(net "M_K_DQS_DP<1>")
	)
	(segment
		(start 67.459606 -95.309436)
		(end 67.409568 -95.359474)
		(width 0.0889)
		(layer "F.Cu")
		(net "M_K_DQS_DP<1>")
	)
	(segment
		(start 68.501768 -95.309436)
		(end 68.196968 -95.309436)
		(width 0.0889)
		(layer "F.Cu")
		(net "M_K_DQS_DP<1>")
	)
	(segment
		(start 68.196968 -95.309436)
		(end 68.095368 -95.411036)
		(width 0.0889)
		(layer "F.Cu")
		(net "M_K_DQS_DP<1>")
	)
	(segment
		(start 46.779688 -127.083312)
		(end 45.92193 -127.94107)
		(width 0.1651)
		(layer "F.Cu")
		(net "M_K_DQS_DP<1>")
	)
	(segment
		(start 67.841368 -95.309436)
		(end 67.459606 -95.309436)
		(width 0.0889)
		(layer "F.Cu")
		(net "M_K_DQS_DP<1>")
	)
	(segment
		(start 68.89496 -95.543878)
		(end 68.918074 -95.457264)
		(width 0.0889)
		(layer "F.Cu")
		(net "M_K_DQS_DP<1>")
	)
	(segment
		(start 46.779688 -114.978434)
		(end 46.779688 -119.75592)
		(width 0.1651)
		(layer "F.Cu")
		(net "M_K_DQS_DP<1>")
	)
	(via
		(at 45.387514 -135.01116)
		(size 0.508)
		(drill 0.254)
		(layers "F.Cu" "B.Cu")
		(net "M_K_DQS_DP<1>")
	)
	(via
		(at 45.387514 -130.940556)
		(size 0.508)
		(drill 0.254)
		(layers "F.Cu" "B.Cu")
		(net "M_K_DQS_DP<1>")
	)
	(arc
		(start 68.918074 -95.457264)
		(mid 68.784797 -95.350969)
		(end 68.61937 -95.30969)
		(width 0.0889)
		(layer "F.Cu")
		(net "M_K_DQS_DP<1>")
	)
	(segment
		(start 45.887386 -130.683)
		(end 45.62983 -130.940556)
		(width 0.1651)
		(layer "B.Cu")
		(net "M_K_DQS_DP<1>")
	)
	(segment
		(start 45.887386 -129.4638)
		(end 45.887386 -130.683)
		(width 0.1651)
		(layer "B.Cu")
		(net "M_K_DQS_DP<1>")
	)
	(segment
		(start 45.84954 -128.276096)
		(end 45.84954 -129.425954)
		(width 0.1651)
		(layer "B.Cu")
		(net "M_K_DQS_DP<1>")
	)
	(segment
		(start 45.84954 -129.425954)
		(end 45.887386 -129.4638)
		(width 0.1651)
		(layer "B.Cu")
		(net "M_K_DQS_DP<1>")
	)
	(segment
		(start 45.62983 -130.940556)
		(end 45.387514 -130.940556)
		(width 0.1651)
		(layer "B.Cu")
		(net "M_K_DQS_DP<1>")
	)
	(segment
		(start 45.847762 -134.550912)
		(end 45.847762 -134.112)
		(width 0.14224)
		(layer "In2.Cu")
		(net "M_K_DQS_DP<1>")
	)
	(segment
		(start 45.127672 -132.6642)
		(end 45.012864 -132.549392)
		(width 0.14224)
		(layer "In2.Cu")
		(net "M_K_DQS_DP<1>")
	)
	(segment
		(start 45.390562 -133.118352)
		(end 45.390562 -132.842)
		(width 0.14224)
		(layer "In2.Cu")
		(net "M_K_DQS_DP<1>")
	)
	(segment
		(start 45.012864 -132.225034)
		(end 45.183298 -132.0546)
		(width 0.14224)
		(layer "In2.Cu")
		(net "M_K_DQS_DP<1>")
	)
	(segment
		(start 45.012864 -133.435852)
		(end 45.150024 -133.298692)
		(width 0.14224)
		(layer "In2.Cu")
		(net "M_K_DQS_DP<1>")
	)
	(segment
		(start 45.568362 -132.0546)
		(end 45.822362 -131.8006)
		(width 0.14224)
		(layer "In2.Cu")
		(net "M_K_DQS_DP<1>")
	)
	(segment
		(start 45.150024 -133.298692)
		(end 45.210222 -133.298692)
		(width 0.14224)
		(layer "In2.Cu")
		(net "M_K_DQS_DP<1>")
	)
	(segment
		(start 45.212762 -132.6642)
		(end 45.127672 -132.6642)
		(width 0.14224)
		(layer "In2.Cu")
		(net "M_K_DQS_DP<1>")
	)
	(segment
		(start 45.012864 -133.662166)
		(end 45.012864 -133.435852)
		(width 0.14224)
		(layer "In2.Cu")
		(net "M_K_DQS_DP<1>")
	)
	(segment
		(start 45.847762 -134.112)
		(end 45.593762 -133.858)
		(width 0.14224)
		(layer "In2.Cu")
		(net "M_K_DQS_DP<1>")
	)
	(segment
		(start 45.210222 -133.298692)
		(end 45.390562 -133.118352)
		(width 0.14224)
		(layer "In2.Cu")
		(net "M_K_DQS_DP<1>")
	)
	(segment
		(start 45.208698 -133.858)
		(end 45.012864 -133.662166)
		(width 0.14224)
		(layer "In2.Cu")
		(net "M_K_DQS_DP<1>")
	)
	(segment
		(start 45.593762 -133.858)
		(end 45.208698 -133.858)
		(width 0.14224)
		(layer "In2.Cu")
		(net "M_K_DQS_DP<1>")
	)
	(segment
		(start 45.822362 -131.375404)
		(end 45.387514 -130.940556)
		(width 0.14224)
		(layer "In2.Cu")
		(net "M_K_DQS_DP<1>")
	)
	(segment
		(start 45.387514 -135.01116)
		(end 45.847762 -134.550912)
		(width 0.14224)
		(layer "In2.Cu")
		(net "M_K_DQS_DP<1>")
	)
	(segment
		(start 45.012864 -132.549392)
		(end 45.012864 -132.225034)
		(width 0.14224)
		(layer "In2.Cu")
		(net "M_K_DQS_DP<1>")
	)
	(segment
		(start 45.183298 -132.0546)
		(end 45.568362 -132.0546)
		(width 0.14224)
		(layer "In2.Cu")
		(net "M_K_DQS_DP<1>")
	)
	(segment
		(start 45.822362 -131.8006)
		(end 45.822362 -131.375404)
		(width 0.14224)
		(layer "In2.Cu")
		(net "M_K_DQS_DP<1>")
	)
	(segment
		(start 45.390562 -132.842)
		(end 45.212762 -132.6642)
		(width 0.14224)
		(layer "In2.Cu")
		(net "M_K_DQS_DP<1>")
	)
	(segment
		(start 71.763382 -134.129272)
		(end 71.700136 -134.26694)
		(width 0.1651)
		(layer "F.Cu")
		(net "M_K_DQS_DP<17>")
	)
	(segment
		(start 71.6788 -134.313168)
		(end 71.6788 -135.131302)
		(width 0.1651)
		(layer "F.Cu")
		(net "M_K_DQS_DP<17>")
	)
	(segment
		(start 72.1995 -133.693154)
		(end 71.763382 -134.129272)
		(width 0.1651)
		(layer "F.Cu")
		(net "M_K_DQS_DP<17>")
	)
	(segment
		(start 84.060792 -88.775286)
		(end 83.489292 -88.775286)
		(width 0.1651)
		(layer "F.Cu")
		(net "M_K_DQS_DP<17>")
	)
	(segment
		(start 72.1995 -133.0706)
		(end 72.1995 -133.693154)
		(width 0.1651)
		(layer "F.Cu")
		(net "M_K_DQS_DP<17>")
	)
	(segment
		(start 71.6788 -135.131302)
		(end 71.760334 -135.355584)
		(width 0.1651)
		(layer "F.Cu")
		(net "M_K_DQS_DP<17>")
	)
	(segment
		(start 71.760334 -135.355584)
		(end 72.142096 -135.737346)
		(width 0.1651)
		(layer "F.Cu")
		(net "M_K_DQS_DP<17>")
	)
	(segment
		(start 71.700136 -134.26694)
		(end 71.6788 -134.313168)
		(width 0.1651)
		(layer "F.Cu")
		(net "M_K_DQS_DP<17>")
	)
	(via
		(at 72.142096 -130.2258)
		(size 0.508)
		(drill 0.254)
		(layers "F.Cu" "B.Cu")
		(net "M_K_DQS_DP<17>")
	)
	(via
		(at 83.489292 -88.775286)
		(size 0.508)
		(drill 0.254)
		(layers "F.Cu" "B.Cu")
		(net "M_K_DQS_DP<17>")
	)
	(via
		(at 72.142096 -135.737346)
		(size 0.508)
		(drill 0.254)
		(layers "F.Cu" "B.Cu")
		(net "M_K_DQS_DP<17>")
	)
	(segment
		(start 71.743316 -131.80187)
		(end 71.6661 -131.669536)
		(width 0.1651)
		(layer "B.Cu")
		(net "M_K_DQS_DP<17>")
	)
	(segment
		(start 72.1995 -132.258054)
		(end 71.743316 -131.80187)
		(width 0.1651)
		(layer "B.Cu")
		(net "M_K_DQS_DP<17>")
	)
	(segment
		(start 71.6661 -130.773932)
		(end 71.753476 -130.61442)
		(width 0.1651)
		(layer "B.Cu")
		(net "M_K_DQS_DP<17>")
	)
	(segment
		(start 72.1995 -132.876036)
		(end 72.1995 -132.258054)
		(width 0.1651)
		(layer "B.Cu")
		(net "M_K_DQS_DP<17>")
	)
	(segment
		(start 71.753476 -130.61442)
		(end 72.142096 -130.2258)
		(width 0.1651)
		(layer "B.Cu")
		(net "M_K_DQS_DP<17>")
	)
	(segment
		(start 71.6661 -131.669536)
		(end 71.6661 -130.773932)
		(width 0.1651)
		(layer "B.Cu")
		(net "M_K_DQS_DP<17>")
	)
	(segment
		(start 80.838802 -104.392984)
		(end 74.247248 -110.984538)
		(width 0.14224)
		(layer "In2.Cu")
		(net "M_K_DQS_DP<17>")
	)
	(segment
		(start 82.118962 -94.518988)
		(end 82.123788 -94.527624)
		(width 0.0889)
		(layer "In2.Cu")
		(net "M_K_DQS_DP<17>")
	)
	(segment
		(start 74.247248 -110.984538)
		(end 74.247248 -121.846086)
		(width 0.14224)
		(layer "In2.Cu")
		(net "M_K_DQS_DP<17>")
	)
	(segment
		(start 72.484996 -128.222756)
		(end 72.655176 -128.392936)
		(width 0.14224)
		(layer "In2.Cu")
		(net "M_K_DQS_DP<17>")
	)
	(segment
		(start 80.878172 -100.997512)
		(end 80.878172 -102.66553)
		(width 0.0889)
		(layer "In2.Cu")
		(net "M_K_DQS_DP<17>")
	)
	(segment
		(start 72.655176 -123.438158)
		(end 72.655176 -127.798576)
		(width 0.14224)
		(layer "In2.Cu")
		(net "M_K_DQS_DP<17>")
	)
	(segment
		(start 72.484996 -128.817116)
		(end 72.484996 -129.071116)
		(width 0.14224)
		(layer "In2.Cu")
		(net "M_K_DQS_DP<17>")
	)
	(segment
		(start 82.641948 -92.64269)
		(end 82.609182 -92.64269)
		(width 0.0889)
		(layer "In2.Cu")
		(net "M_K_DQS_DP<17>")
	)
	(segment
		(start 82.112612 -95.49892)
		(end 82.118962 -95.509588)
		(width 0.0889)
		(layer "In2.Cu")
		(net "M_K_DQS_DP<17>")
	)
	(segment
		(start 82.977482 -91.451938)
		(end 82.971132 -91.462606)
		(width 0.0889)
		(layer "In2.Cu")
		(net "M_K_DQS_DP<17>")
	)
	(segment
		(start 72.655176 -127.798576)
		(end 72.484996 -127.968756)
		(width 0.14224)
		(layer "In2.Cu")
		(net "M_K_DQS_DP<17>")
	)
	(segment
		(start 83.489292 -88.775286)
		(end 83.489292 -89.11336)
		(width 0.0889)
		(layer "In2.Cu")
		(net "M_K_DQS_DP<17>")
	)
	(segment
		(start 72.428608 -130.2258)
		(end 72.142096 -130.2258)
		(width 0.14224)
		(layer "In2.Cu")
		(net "M_K_DQS_DP<17>")
	)
	(segment
		(start 81.939384 -97.147634)
		(end 81.939384 -99.9363)
		(width 0.0889)
		(layer "In2.Cu")
		(net "M_K_DQS_DP<17>")
	)
	(segment
		(start 72.142096 -130.2258)
		(end 72.068944 -130.2258)
		(width 0.14224)
		(layer "In2.Cu")
		(net "M_K_DQS_DP<17>")
	)
	(segment
		(start 80.878172 -102.66553)
		(end 80.838802 -102.7049)
		(width 0.0889)
		(layer "In2.Cu")
		(net "M_K_DQS_DP<17>")
	)
	(segment
		(start 72.484996 -129.071116)
		(end 72.655176 -129.241296)
		(width 0.14224)
		(layer "In2.Cu")
		(net "M_K_DQS_DP<17>")
	)
	(segment
		(start 72.484996 -127.968756)
		(end 72.484996 -128.222756)
		(width 0.14224)
		(layer "In2.Cu")
		(net "M_K_DQS_DP<17>")
	)
	(segment
		(start 80.838802 -102.726998)
		(end 80.838802 -104.392984)
		(width 0.14224)
		(layer "In2.Cu")
		(net "M_K_DQS_DP<17>")
	)
	(segment
		(start 82.112612 -96.48952)
		(end 82.118962 -96.500188)
		(width 0.0889)
		(layer "In2.Cu")
		(net "M_K_DQS_DP<17>")
	)
	(segment
		(start 82.118962 -95.509588)
		(end 82.123788 -95.518224)
		(width 0.0889)
		(layer "In2.Cu")
		(net "M_K_DQS_DP<17>")
	)
	(segment
		(start 82.982308 -91.443302)
		(end 82.977482 -91.451938)
		(width 0.0889)
		(layer "In2.Cu")
		(net "M_K_DQS_DP<17>")
	)
	(segment
		(start 72.655176 -129.241296)
		(end 72.655176 -129.999232)
		(width 0.14224)
		(layer "In2.Cu")
		(net "M_K_DQS_DP<17>")
	)
	(segment
		(start 72.068944 -130.2258)
		(end 71.637144 -130.6576)
		(width 0.14224)
		(layer "In2.Cu")
		(net "M_K_DQS_DP<17>")
	)
	(segment
		(start 81.939384 -99.9363)
		(end 80.878172 -100.997512)
		(width 0.0889)
		(layer "In2.Cu")
		(net "M_K_DQS_DP<17>")
	)
	(segment
		(start 80.838802 -102.7049)
		(end 80.838802 -102.726998)
		(width 0.0889)
		(layer "In2.Cu")
		(net "M_K_DQS_DP<17>")
	)
	(segment
		(start 74.247248 -121.846086)
		(end 72.655176 -123.438158)
		(width 0.14224)
		(layer "In2.Cu")
		(net "M_K_DQS_DP<17>")
	)
	(segment
		(start 72.655176 -129.999232)
		(end 72.428608 -130.2258)
		(width 0.14224)
		(layer "In2.Cu")
		(net "M_K_DQS_DP<17>")
	)
	(segment
		(start 82.982308 -90.452702)
		(end 82.977482 -90.461338)
		(width 0.0889)
		(layer "In2.Cu")
		(net "M_K_DQS_DP<17>")
	)
	(segment
		(start 71.637144 -130.6576)
		(end 71.637144 -135.232394)
		(width 0.14224)
		(layer "In2.Cu")
		(net "M_K_DQS_DP<17>")
	)
	(segment
		(start 82.092038 -96.943926)
		(end 81.939384 -97.147634)
		(width 0.0889)
		(layer "In2.Cu")
		(net "M_K_DQS_DP<17>")
	)
	(segment
		(start 83.489292 -89.11336)
		(end 83.424014 -89.178638)
		(width 0.0889)
		(layer "In2.Cu")
		(net "M_K_DQS_DP<17>")
	)
	(segment
		(start 82.118962 -93.928438)
		(end 82.112612 -93.939106)
		(width 0.0889)
		(layer "In2.Cu")
		(net "M_K_DQS_DP<17>")
	)
	(segment
		(start 71.637144 -135.232394)
		(end 72.142096 -135.737346)
		(width 0.14224)
		(layer "In2.Cu")
		(net "M_K_DQS_DP<17>")
	)
	(segment
		(start 72.655176 -128.392936)
		(end 72.655176 -128.646936)
		(width 0.14224)
		(layer "In2.Cu")
		(net "M_K_DQS_DP<17>")
	)
	(segment
		(start 72.655176 -128.646936)
		(end 72.484996 -128.817116)
		(width 0.14224)
		(layer "In2.Cu")
		(net "M_K_DQS_DP<17>")
	)
	(segment
		(start 82.977482 -90.461338)
		(end 82.971132 -90.472006)
		(width 0.0889)
		(layer "In2.Cu")
		(net "M_K_DQS_DP<17>")
	)
	(arc
		(start 82.971132 -90.472006)
		(mid 82.898334 -90.762769)
		(end 82.977482 -91.051888)
		(width 0.0889)
		(layer "In2.Cu")
		(net "M_K_DQS_DP<17>")
	)
	(arc
		(start 82.123788 -94.527624)
		(mid 82.172543 -94.723976)
		(end 82.118962 -94.919038)
		(width 0.0889)
		(layer "In2.Cu")
		(net "M_K_DQS_DP<17>")
	)
	(arc
		(start 82.145632 -96.555814)
		(mid 82.168922 -96.75677)
		(end 82.092038 -96.943926)
		(width 0.0889)
		(layer "In2.Cu")
		(net "M_K_DQS_DP<17>")
	)
	(arc
		(start 82.118962 -93.528642)
		(mid 82.172461 -93.72854)
		(end 82.118962 -93.928438)
		(width 0.0889)
		(layer "In2.Cu")
		(net "M_K_DQS_DP<17>")
	)
	(arc
		(start 82.977482 -91.051888)
		(mid 83.030952 -91.246951)
		(end 82.982308 -91.443302)
		(width 0.0889)
		(layer "In2.Cu")
		(net "M_K_DQS_DP<17>")
	)
	(arc
		(start 82.118962 -94.919038)
		(mid 82.03974 -95.208156)
		(end 82.112612 -95.49892)
		(width 0.0889)
		(layer "In2.Cu")
		(net "M_K_DQS_DP<17>")
	)
	(arc
		(start 82.123788 -95.518224)
		(mid 82.172543 -95.714576)
		(end 82.118962 -95.909638)
		(width 0.0889)
		(layer "In2.Cu")
		(net "M_K_DQS_DP<17>")
	)
	(arc
		(start 82.112612 -93.939106)
		(mid 82.039814 -94.229869)
		(end 82.118962 -94.518988)
		(width 0.0889)
		(layer "In2.Cu")
		(net "M_K_DQS_DP<17>")
	)
	(arc
		(start 82.118962 -96.500188)
		(mid 82.133376 -96.527484)
		(end 82.145632 -96.555814)
		(width 0.0889)
		(layer "In2.Cu")
		(net "M_K_DQS_DP<17>")
	)
	(arc
		(start 82.118962 -95.909638)
		(mid 82.03974 -96.198756)
		(end 82.112612 -96.48952)
		(width 0.0889)
		(layer "In2.Cu")
		(net "M_K_DQS_DP<17>")
	)
	(arc
		(start 83.424014 -89.178638)
		(mid 82.962045 -89.49918)
		(end 82.977482 -90.061288)
		(width 0.0889)
		(layer "In2.Cu")
		(net "M_K_DQS_DP<17>")
	)
	(arc
		(start 82.971132 -91.462606)
		(mid 82.898334 -91.753369)
		(end 82.977482 -92.042488)
		(width 0.0889)
		(layer "In2.Cu")
		(net "M_K_DQS_DP<17>")
	)
	(arc
		(start 82.977482 -92.042488)
		(mid 82.98023 -92.437955)
		(end 82.641948 -92.64269)
		(width 0.0889)
		(layer "In2.Cu")
		(net "M_K_DQS_DP<17>")
	)
	(arc
		(start 82.977482 -90.061288)
		(mid 83.030952 -90.256351)
		(end 82.982308 -90.452702)
		(width 0.0889)
		(layer "In2.Cu")
		(net "M_K_DQS_DP<17>")
	)
	(arc
		(start 82.609182 -92.64269)
		(mid 82.113705 -92.947133)
		(end 82.118962 -93.528642)
		(width 0.0889)
		(layer "In2.Cu")
		(net "M_K_DQS_DP<17>")
	)
	(segment
		(start 145.628868 -134.313168)
		(end 145.628868 -135.131302)
		(width 0.1651)
		(layer "F.Cu")
		(net "M_K_DQS_DP<16>")
	)
	(segment
		(start 146.149568 -133.693154)
		(end 145.71345 -134.129272)
		(width 0.1651)
		(layer "F.Cu")
		(net "M_K_DQS_DP<16>")
	)
	(segment
		(start 123.363228 -97.509584)
		(end 123.934728 -97.509584)
		(width 0.1651)
		(layer "F.Cu")
		(net "M_K_DQS_DP<16>")
	)
	(segment
		(start 145.710402 -135.355584)
		(end 146.092164 -135.737346)
		(width 0.1651)
		(layer "F.Cu")
		(net "M_K_DQS_DP<16>")
	)
	(segment
		(start 145.650204 -134.26694)
		(end 145.628868 -134.313168)
		(width 0.1651)
		(layer "F.Cu")
		(net "M_K_DQS_DP<16>")
	)
	(segment
		(start 146.149568 -133.0706)
		(end 146.149568 -133.693154)
		(width 0.1651)
		(layer "F.Cu")
		(net "M_K_DQS_DP<16>")
	)
	(segment
		(start 145.628868 -135.131302)
		(end 145.710402 -135.355584)
		(width 0.1651)
		(layer "F.Cu")
		(net "M_K_DQS_DP<16>")
	)
	(segment
		(start 145.71345 -134.129272)
		(end 145.650204 -134.26694)
		(width 0.1651)
		(layer "F.Cu")
		(net "M_K_DQS_DP<16>")
	)
	(via
		(at 123.934728 -97.509584)
		(size 0.4826)
		(drill 0.254)
		(layers "F.Cu" "B.Cu")
		(net "M_K_DQS_DP<16>")
	)
	(via
		(at 146.092164 -130.2258)
		(size 0.508)
		(drill 0.254)
		(layers "F.Cu" "B.Cu")
		(net "M_K_DQS_DP<16>")
	)
	(via
		(at 146.092164 -135.737346)
		(size 0.508)
		(drill 0.254)
		(layers "F.Cu" "B.Cu")
		(net "M_K_DQS_DP<16>")
	)
	(segment
		(start 145.616168 -131.669536)
		(end 145.616168 -130.773932)
		(width 0.1651)
		(layer "B.Cu")
		(net "M_K_DQS_DP<16>")
	)
	(segment
		(start 146.149568 -132.876036)
		(end 146.149568 -132.258054)
		(width 0.1651)
		(layer "B.Cu")
		(net "M_K_DQS_DP<16>")
	)
	(segment
		(start 146.149568 -132.258054)
		(end 145.693384 -131.80187)
		(width 0.1651)
		(layer "B.Cu")
		(net "M_K_DQS_DP<16>")
	)
	(segment
		(start 145.693384 -131.80187)
		(end 145.616168 -131.669536)
		(width 0.1651)
		(layer "B.Cu")
		(net "M_K_DQS_DP<16>")
	)
	(segment
		(start 145.616168 -130.773932)
		(end 145.703544 -130.61442)
		(width 0.1651)
		(layer "B.Cu")
		(net "M_K_DQS_DP<16>")
	)
	(segment
		(start 145.703544 -130.61442)
		(end 146.092164 -130.2258)
		(width 0.1651)
		(layer "B.Cu")
		(net "M_K_DQS_DP<16>")
	)
	(segment
		(start 146.092164 -130.2258)
		(end 146.019012 -130.2258)
		(width 0.14224)
		(layer "In2.Cu")
		(net "M_K_DQS_DP<16>")
	)
	(segment
		(start 123.422918 -99.195636)
		(end 123.416568 -99.206304)
		(width 0.0889)
		(layer "In2.Cu")
		(net "M_K_DQS_DP<16>")
	)
	(segment
		(start 147.714208 -123.519946)
		(end 147.556728 -123.677426)
		(width 0.14224)
		(layer "In2.Cu")
		(net "M_K_DQS_DP<16>")
	)
	(segment
		(start 147.556728 -122.854466)
		(end 147.556728 -123.108466)
		(width 0.14224)
		(layer "In2.Cu")
		(net "M_K_DQS_DP<16>")
	)
	(segment
		(start 147.556728 -126.146306)
		(end 147.556728 -126.400306)
		(width 0.14224)
		(layer "In2.Cu")
		(net "M_K_DQS_DP<16>")
	)
	(segment
		(start 123.427744 -99.187)
		(end 123.422918 -99.195636)
		(width 0.0889)
		(layer "In2.Cu")
		(net "M_K_DQS_DP<16>")
	)
	(segment
		(start 147.714208 -124.088906)
		(end 147.714208 -124.342906)
		(width 0.14224)
		(layer "In2.Cu")
		(net "M_K_DQS_DP<16>")
	)
	(segment
		(start 147.556728 -127.223266)
		(end 147.714208 -127.380746)
		(width 0.14224)
		(layer "In2.Cu")
		(net "M_K_DQS_DP<16>")
	)
	(segment
		(start 147.556728 -125.323346)
		(end 147.556728 -125.577346)
		(width 0.14224)
		(layer "In2.Cu")
		(net "M_K_DQS_DP<16>")
	)
	(segment
		(start 146.630644 -129.96672)
		(end 146.371564 -130.2258)
		(width 0.14224)
		(layer "In2.Cu")
		(net "M_K_DQS_DP<16>")
	)
	(segment
		(start 147.368514 -128.034288)
		(end 147.221194 -128.034288)
		(width 0.14224)
		(layer "In2.Cu")
		(net "M_K_DQS_DP<16>")
	)
	(segment
		(start 147.556728 -123.108466)
		(end 147.714208 -123.265946)
		(width 0.14224)
		(layer "In2.Cu")
		(net "M_K_DQS_DP<16>")
	)
	(segment
		(start 147.714208 -122.696986)
		(end 147.556728 -122.854466)
		(width 0.14224)
		(layer "In2.Cu")
		(net "M_K_DQS_DP<16>")
	)
	(segment
		(start 147.714208 -123.265946)
		(end 147.714208 -123.519946)
		(width 0.14224)
		(layer "In2.Cu")
		(net "M_K_DQS_DP<16>")
	)
	(segment
		(start 123.934728 -97.509584)
		(end 123.934728 -97.17151)
		(width 0.0889)
		(layer "In2.Cu")
		(net "M_K_DQS_DP<16>")
	)
	(segment
		(start 147.556728 -126.400306)
		(end 147.714208 -126.557786)
		(width 0.14224)
		(layer "In2.Cu")
		(net "M_K_DQS_DP<16>")
	)
	(segment
		(start 147.041616 -128.213866)
		(end 147.041616 -128.361186)
		(width 0.14224)
		(layer "In2.Cu")
		(net "M_K_DQS_DP<16>")
	)
	(segment
		(start 133.375908 -107.38104)
		(end 134.264908 -108.27004)
		(width 0.14224)
		(layer "In2.Cu")
		(net "M_K_DQS_DP<16>")
	)
	(segment
		(start 147.714208 -127.688594)
		(end 147.368514 -128.034288)
		(width 0.14224)
		(layer "In2.Cu")
		(net "M_K_DQS_DP<16>")
	)
	(segment
		(start 147.556728 -125.577346)
		(end 147.714208 -125.734826)
		(width 0.14224)
		(layer "In2.Cu")
		(net "M_K_DQS_DP<16>")
	)
	(segment
		(start 147.714208 -122.398282)
		(end 147.714208 -122.696986)
		(width 0.14224)
		(layer "In2.Cu")
		(net "M_K_DQS_DP<16>")
	)
	(segment
		(start 145.587212 -135.232394)
		(end 146.092164 -135.737346)
		(width 0.14224)
		(layer "In2.Cu")
		(net "M_K_DQS_DP<16>")
	)
	(segment
		(start 128.321054 -106.181906)
		(end 128.336548 -106.1974)
		(width 0.0889)
		(layer "In2.Cu")
		(net "M_K_DQS_DP<16>")
	)
	(segment
		(start 129.520188 -107.38104)
		(end 133.375908 -107.38104)
		(width 0.14224)
		(layer "In2.Cu")
		(net "M_K_DQS_DP<16>")
	)
	(segment
		(start 123.422918 -102.757986)
		(end 123.667266 -103.181404)
		(width 0.0889)
		(layer "In2.Cu")
		(net "M_K_DQS_DP<16>")
	)
	(segment
		(start 146.371564 -130.2258)
		(end 146.092164 -130.2258)
		(width 0.14224)
		(layer "In2.Cu")
		(net "M_K_DQS_DP<16>")
	)
	(segment
		(start 134.264908 -108.27004)
		(end 136.09828 -108.27004)
		(width 0.14224)
		(layer "In2.Cu")
		(net "M_K_DQS_DP<16>")
	)
	(segment
		(start 147.714208 -121.907554)
		(end 147.595844 -122.025918)
		(width 0.14224)
		(layer "In2.Cu")
		(net "M_K_DQS_DP<16>")
	)
	(segment
		(start 123.422918 -102.167436)
		(end 123.416568 -102.178104)
		(width 0.0889)
		(layer "In2.Cu")
		(net "M_K_DQS_DP<16>")
	)
	(segment
		(start 123.416568 -100.766118)
		(end 123.422918 -100.776786)
		(width 0.0889)
		(layer "In2.Cu")
		(net "M_K_DQS_DP<16>")
	)
	(segment
		(start 147.714208 -125.165866)
		(end 147.556728 -125.323346)
		(width 0.14224)
		(layer "In2.Cu")
		(net "M_K_DQS_DP<16>")
	)
	(segment
		(start 147.221194 -128.034288)
		(end 147.041616 -128.213866)
		(width 0.14224)
		(layer "In2.Cu")
		(net "M_K_DQS_DP<16>")
	)
	(segment
		(start 123.427744 -102.1588)
		(end 123.422918 -102.167436)
		(width 0.0889)
		(layer "In2.Cu")
		(net "M_K_DQS_DP<16>")
	)
	(segment
		(start 147.714208 -125.734826)
		(end 147.714208 -125.988826)
		(width 0.14224)
		(layer "In2.Cu")
		(net "M_K_DQS_DP<16>")
	)
	(segment
		(start 125.613668 -105.156)
		(end 127.350774 -105.156)
		(width 0.0889)
		(layer "In2.Cu")
		(net "M_K_DQS_DP<16>")
	)
	(segment
		(start 123.667266 -103.181404)
		(end 123.667266 -103.209598)
		(width 0.0889)
		(layer "In2.Cu")
		(net "M_K_DQS_DP<16>")
	)
	(segment
		(start 147.556728 -124.754386)
		(end 147.714208 -124.911866)
		(width 0.14224)
		(layer "In2.Cu")
		(net "M_K_DQS_DP<16>")
	)
	(segment
		(start 128.336548 -106.1974)
		(end 129.520188 -107.38104)
		(width 0.14224)
		(layer "In2.Cu")
		(net "M_K_DQS_DP<16>")
	)
	(segment
		(start 123.427744 -100.1776)
		(end 123.422918 -100.186236)
		(width 0.0889)
		(layer "In2.Cu")
		(net "M_K_DQS_DP<16>")
	)
	(segment
		(start 145.587212 -130.6576)
		(end 145.587212 -135.232394)
		(width 0.14224)
		(layer "In2.Cu")
		(net "M_K_DQS_DP<16>")
	)
	(segment
		(start 147.556728 -123.677426)
		(end 147.556728 -123.931426)
		(width 0.14224)
		(layer "In2.Cu")
		(net "M_K_DQS_DP<16>")
	)
	(segment
		(start 123.667266 -103.209598)
		(end 125.613668 -105.156)
		(width 0.0889)
		(layer "In2.Cu")
		(net "M_K_DQS_DP<16>")
	)
	(segment
		(start 147.595844 -122.279918)
		(end 147.714208 -122.398282)
		(width 0.14224)
		(layer "In2.Cu")
		(net "M_K_DQS_DP<16>")
	)
	(segment
		(start 128.321308 -106.126534)
		(end 128.321054 -106.181906)
		(width 0.0889)
		(layer "In2.Cu")
		(net "M_K_DQS_DP<16>")
	)
	(segment
		(start 147.041616 -128.361186)
		(end 146.630644 -128.772158)
		(width 0.14224)
		(layer "In2.Cu")
		(net "M_K_DQS_DP<16>")
	)
	(segment
		(start 127.350774 -105.156)
		(end 128.321308 -106.126534)
		(width 0.0889)
		(layer "In2.Cu")
		(net "M_K_DQS_DP<16>")
	)
	(segment
		(start 147.714208 -124.911866)
		(end 147.714208 -125.165866)
		(width 0.14224)
		(layer "In2.Cu")
		(net "M_K_DQS_DP<16>")
	)
	(segment
		(start 146.630644 -128.772158)
		(end 146.630644 -129.96672)
		(width 0.14224)
		(layer "In2.Cu")
		(net "M_K_DQS_DP<16>")
	)
	(segment
		(start 136.09828 -108.27004)
		(end 147.714208 -119.885968)
		(width 0.14224)
		(layer "In2.Cu")
		(net "M_K_DQS_DP<16>")
	)
	(segment
		(start 147.556728 -123.931426)
		(end 147.714208 -124.088906)
		(width 0.14224)
		(layer "In2.Cu")
		(net "M_K_DQS_DP<16>")
	)
	(segment
		(start 147.595844 -122.025918)
		(end 147.595844 -122.279918)
		(width 0.14224)
		(layer "In2.Cu")
		(net "M_K_DQS_DP<16>")
	)
	(segment
		(start 147.556728 -124.500386)
		(end 147.556728 -124.754386)
		(width 0.14224)
		(layer "In2.Cu")
		(net "M_K_DQS_DP<16>")
	)
	(segment
		(start 146.019012 -130.2258)
		(end 145.587212 -130.6576)
		(width 0.14224)
		(layer "In2.Cu")
		(net "M_K_DQS_DP<16>")
	)
	(segment
		(start 123.949714 -97.909634)
		(end 123.916948 -97.909634)
		(width 0.0889)
		(layer "In2.Cu")
		(net "M_K_DQS_DP<16>")
	)
	(segment
		(start 147.714208 -119.885968)
		(end 147.714208 -121.907554)
		(width 0.14224)
		(layer "In2.Cu")
		(net "M_K_DQS_DP<16>")
	)
	(segment
		(start 123.934728 -97.17151)
		(end 123.99264 -97.113598)
		(width 0.0889)
		(layer "In2.Cu")
		(net "M_K_DQS_DP<16>")
	)
	(segment
		(start 147.714208 -126.811786)
		(end 147.556728 -126.969266)
		(width 0.14224)
		(layer "In2.Cu")
		(net "M_K_DQS_DP<16>")
	)
	(segment
		(start 147.714208 -125.988826)
		(end 147.556728 -126.146306)
		(width 0.14224)
		(layer "In2.Cu")
		(net "M_K_DQS_DP<16>")
	)
	(segment
		(start 147.556728 -126.969266)
		(end 147.556728 -127.223266)
		(width 0.14224)
		(layer "In2.Cu")
		(net "M_K_DQS_DP<16>")
	)
	(segment
		(start 147.714208 -124.342906)
		(end 147.556728 -124.500386)
		(width 0.14224)
		(layer "In2.Cu")
		(net "M_K_DQS_DP<16>")
	)
	(segment
		(start 147.714208 -127.380746)
		(end 147.714208 -127.688594)
		(width 0.14224)
		(layer "In2.Cu")
		(net "M_K_DQS_DP<16>")
	)
	(segment
		(start 147.714208 -126.557786)
		(end 147.714208 -126.811786)
		(width 0.14224)
		(layer "In2.Cu")
		(net "M_K_DQS_DP<16>")
	)
	(arc
		(start 123.422918 -100.186236)
		(mid 123.343696 -100.475354)
		(end 123.416568 -100.766118)
		(width 0.0889)
		(layer "In2.Cu")
		(net "M_K_DQS_DP<16>")
	)
	(arc
		(start 123.422918 -100.776786)
		(mid 123.476417 -100.976684)
		(end 123.422918 -101.176582)
		(width 0.0889)
		(layer "In2.Cu")
		(net "M_K_DQS_DP<16>")
	)
	(arc
		(start 123.916948 -97.909634)
		(mid 123.418697 -98.212474)
		(end 123.422918 -98.795586)
		(width 0.0889)
		(layer "In2.Cu")
		(net "M_K_DQS_DP<16>")
	)
	(arc
		(start 123.422918 -101.176582)
		(mid 123.343787 -101.471984)
		(end 123.422918 -101.767386)
		(width 0.0889)
		(layer "In2.Cu")
		(net "M_K_DQS_DP<16>")
	)
	(arc
		(start 123.416568 -102.178104)
		(mid 123.34377 -102.468867)
		(end 123.422918 -102.757986)
		(width 0.0889)
		(layer "In2.Cu")
		(net "M_K_DQS_DP<16>")
	)
	(arc
		(start 123.99264 -97.113598)
		(mid 124.334563 -97.531139)
		(end 123.949714 -97.909634)
		(width 0.0889)
		(layer "In2.Cu")
		(net "M_K_DQS_DP<16>")
	)
	(arc
		(start 123.416568 -99.206304)
		(mid 123.34377 -99.497067)
		(end 123.422918 -99.786186)
		(width 0.0889)
		(layer "In2.Cu")
		(net "M_K_DQS_DP<16>")
	)
	(arc
		(start 123.422918 -98.795586)
		(mid 123.476388 -98.990649)
		(end 123.427744 -99.187)
		(width 0.0889)
		(layer "In2.Cu")
		(net "M_K_DQS_DP<16>")
	)
	(arc
		(start 123.422918 -99.786186)
		(mid 123.476388 -99.981249)
		(end 123.427744 -100.1776)
		(width 0.0889)
		(layer "In2.Cu")
		(net "M_K_DQS_DP<16>")
	)
	(arc
		(start 123.422918 -101.767386)
		(mid 123.476388 -101.962449)
		(end 123.427744 -102.1588)
		(width 0.0889)
		(layer "In2.Cu")
		(net "M_K_DQS_DP<16>")
	)
	(segment
		(start 136.30021 -134.26694)
		(end 136.278874 -134.313168)
		(width 0.1651)
		(layer "F.Cu")
		(net "M_K_DQS_DP<15>")
	)
	(segment
		(start 136.363456 -134.129272)
		(end 136.30021 -134.26694)
		(width 0.1651)
		(layer "F.Cu")
		(net "M_K_DQS_DP<15>")
	)
	(segment
		(start 136.799574 -133.0706)
		(end 136.799574 -133.693154)
		(width 0.1651)
		(layer "F.Cu")
		(net "M_K_DQS_DP<15>")
	)
	(segment
		(start 118.212362 -97.509584)
		(end 118.783862 -97.509584)
		(width 0.1651)
		(layer "F.Cu")
		(net "M_K_DQS_DP<15>")
	)
	(segment
		(start 136.360408 -135.355584)
		(end 136.74217 -135.737346)
		(width 0.1651)
		(layer "F.Cu")
		(net "M_K_DQS_DP<15>")
	)
	(segment
		(start 136.278874 -135.131302)
		(end 136.360408 -135.355584)
		(width 0.1651)
		(layer "F.Cu")
		(net "M_K_DQS_DP<15>")
	)
	(segment
		(start 136.799574 -133.693154)
		(end 136.363456 -134.129272)
		(width 0.1651)
		(layer "F.Cu")
		(net "M_K_DQS_DP<15>")
	)
	(segment
		(start 136.278874 -134.313168)
		(end 136.278874 -135.131302)
		(width 0.1651)
		(layer "F.Cu")
		(net "M_K_DQS_DP<15>")
	)
	(via
		(at 136.74217 -130.2258)
		(size 0.508)
		(drill 0.254)
		(layers "F.Cu" "B.Cu")
		(net "M_K_DQS_DP<15>")
	)
	(via
		(at 118.783862 -97.509584)
		(size 0.508)
		(drill 0.254)
		(layers "F.Cu" "B.Cu")
		(net "M_K_DQS_DP<15>")
	)
	(via
		(at 136.74217 -135.737346)
		(size 0.508)
		(drill 0.254)
		(layers "F.Cu" "B.Cu")
		(net "M_K_DQS_DP<15>")
	)
	(segment
		(start 136.34339 -131.80187)
		(end 136.266174 -131.669536)
		(width 0.1651)
		(layer "B.Cu")
		(net "M_K_DQS_DP<15>")
	)
	(segment
		(start 136.266174 -131.669536)
		(end 136.266174 -130.773932)
		(width 0.1651)
		(layer "B.Cu")
		(net "M_K_DQS_DP<15>")
	)
	(segment
		(start 136.799574 -132.876036)
		(end 136.799574 -132.258054)
		(width 0.1651)
		(layer "B.Cu")
		(net "M_K_DQS_DP<15>")
	)
	(segment
		(start 136.799574 -132.258054)
		(end 136.34339 -131.80187)
		(width 0.1651)
		(layer "B.Cu")
		(net "M_K_DQS_DP<15>")
	)
	(segment
		(start 136.35355 -130.61442)
		(end 136.74217 -130.2258)
		(width 0.1651)
		(layer "B.Cu")
		(net "M_K_DQS_DP<15>")
	)
	(segment
		(start 136.266174 -130.773932)
		(end 136.35355 -130.61442)
		(width 0.1651)
		(layer "B.Cu")
		(net "M_K_DQS_DP<15>")
	)
	(segment
		(start 137.104628 -128.787144)
		(end 137.104628 -129.041144)
		(width 0.14224)
		(layer "In2.Cu")
		(net "M_K_DQS_DP<15>")
	)
	(segment
		(start 137.02157 -130.2258)
		(end 136.74217 -130.2258)
		(width 0.14224)
		(layer "In2.Cu")
		(net "M_K_DQS_DP<15>")
	)
	(segment
		(start 124.088398 -117.656102)
		(end 134.422642 -117.656102)
		(width 0.14224)
		(layer "In2.Cu")
		(net "M_K_DQS_DP<15>")
	)
	(segment
		(start 119.997728 -112.50676)
		(end 119.997728 -113.565432)
		(width 0.14224)
		(layer "In2.Cu")
		(net "M_K_DQS_DP<15>")
	)
	(segment
		(start 136.669018 -130.2258)
		(end 136.237218 -130.6576)
		(width 0.14224)
		(layer "In2.Cu")
		(net "M_K_DQS_DP<15>")
	)
	(segment
		(start 118.276878 -103.1494)
		(end 118.12143 -103.427276)
		(width 0.0889)
		(layer "In2.Cu")
		(net "M_K_DQS_DP<15>")
	)
	(segment
		(start 137.262108 -128.629664)
		(end 137.104628 -128.787144)
		(width 0.14224)
		(layer "In2.Cu")
		(net "M_K_DQS_DP<15>")
	)
	(segment
		(start 118.272052 -99.785932)
		(end 118.276878 -99.794568)
		(width 0.0889)
		(layer "In2.Cu")
		(net "M_K_DQS_DP<15>")
	)
	(segment
		(start 118.12143 -104.740456)
		(end 117.981222 -104.880664)
		(width 0.0889)
		(layer "In2.Cu")
		(net "M_K_DQS_DP<15>")
	)
	(segment
		(start 117.981222 -104.880664)
		(end 117.981222 -105.70083)
		(width 0.0889)
		(layer "In2.Cu")
		(net "M_K_DQS_DP<15>")
	)
	(segment
		(start 118.276878 -98.1964)
		(end 118.272052 -98.205036)
		(width 0.0889)
		(layer "In2.Cu")
		(net "M_K_DQS_DP<15>")
	)
	(segment
		(start 118.798848 -97.909634)
		(end 118.766082 -97.909634)
		(width 0.0889)
		(layer "In2.Cu")
		(net "M_K_DQS_DP<15>")
	)
	(segment
		(start 118.783862 -97.509584)
		(end 118.445788 -97.509584)
		(width 0.0889)
		(layer "In2.Cu")
		(net "M_K_DQS_DP<15>")
	)
	(segment
		(start 137.262108 -129.198624)
		(end 137.262108 -129.985262)
		(width 0.14224)
		(layer "In2.Cu")
		(net "M_K_DQS_DP<15>")
	)
	(segment
		(start 137.262108 -129.985262)
		(end 137.02157 -130.2258)
		(width 0.14224)
		(layer "In2.Cu")
		(net "M_K_DQS_DP<15>")
	)
	(segment
		(start 118.263162 -101.751892)
		(end 118.272052 -101.767132)
		(width 0.0889)
		(layer "In2.Cu")
		(net "M_K_DQS_DP<15>")
	)
	(segment
		(start 134.422642 -117.656102)
		(end 137.262108 -120.495568)
		(width 0.14224)
		(layer "In2.Cu")
		(net "M_K_DQS_DP<15>")
	)
	(segment
		(start 117.941852 -105.762298)
		(end 117.941852 -110.450884)
		(width 0.14224)
		(layer "In2.Cu")
		(net "M_K_DQS_DP<15>")
	)
	(segment
		(start 118.445788 -97.509584)
		(end 118.387876 -97.451672)
		(width 0.0889)
		(layer "In2.Cu")
		(net "M_K_DQS_DP<15>")
	)
	(segment
		(start 118.272052 -101.767132)
		(end 118.276878 -101.775768)
		(width 0.0889)
		(layer "In2.Cu")
		(net "M_K_DQS_DP<15>")
	)
	(segment
		(start 117.981222 -105.70083)
		(end 117.941852 -105.7402)
		(width 0.0889)
		(layer "In2.Cu")
		(net "M_K_DQS_DP<15>")
	)
	(segment
		(start 136.74217 -130.2258)
		(end 136.669018 -130.2258)
		(width 0.14224)
		(layer "In2.Cu")
		(net "M_K_DQS_DP<15>")
	)
	(segment
		(start 137.104628 -129.041144)
		(end 137.262108 -129.198624)
		(width 0.14224)
		(layer "In2.Cu")
		(net "M_K_DQS_DP<15>")
	)
	(segment
		(start 117.941852 -110.450884)
		(end 119.997728 -112.50676)
		(width 0.14224)
		(layer "In2.Cu")
		(net "M_K_DQS_DP<15>")
	)
	(segment
		(start 118.12143 -103.427276)
		(end 118.12143 -104.740456)
		(width 0.0889)
		(layer "In2.Cu")
		(net "M_K_DQS_DP<15>")
	)
	(segment
		(start 118.272052 -98.205036)
		(end 118.265702 -98.215704)
		(width 0.0889)
		(layer "In2.Cu")
		(net "M_K_DQS_DP<15>")
	)
	(segment
		(start 118.272052 -100.776532)
		(end 118.27891 -100.788724)
		(width 0.0889)
		(layer "In2.Cu")
		(net "M_K_DQS_DP<15>")
	)
	(segment
		(start 118.265702 -100.765864)
		(end 118.272052 -100.776532)
		(width 0.0889)
		(layer "In2.Cu")
		(net "M_K_DQS_DP<15>")
	)
	(segment
		(start 137.262108 -120.495568)
		(end 137.262108 -128.629664)
		(width 0.14224)
		(layer "In2.Cu")
		(net "M_K_DQS_DP<15>")
	)
	(segment
		(start 119.997728 -113.565432)
		(end 124.088398 -117.656102)
		(width 0.14224)
		(layer "In2.Cu")
		(net "M_K_DQS_DP<15>")
	)
	(segment
		(start 136.237218 -130.6576)
		(end 136.237218 -135.232394)
		(width 0.14224)
		(layer "In2.Cu")
		(net "M_K_DQS_DP<15>")
	)
	(segment
		(start 118.276878 -99.187)
		(end 118.272052 -99.195636)
		(width 0.0889)
		(layer "In2.Cu")
		(net "M_K_DQS_DP<15>")
	)
	(segment
		(start 136.237218 -135.232394)
		(end 136.74217 -135.737346)
		(width 0.14224)
		(layer "In2.Cu")
		(net "M_K_DQS_DP<15>")
	)
	(segment
		(start 117.941852 -105.7402)
		(end 117.941852 -105.762298)
		(width 0.0889)
		(layer "In2.Cu")
		(net "M_K_DQS_DP<15>")
	)
	(arc
		(start 118.387876 -97.451672)
		(mid 118.664604 -97.127568)
		(end 119.076724 -97.236534)
		(width 0.0889)
		(layer "In2.Cu")
		(net "M_K_DQS_DP<15>")
	)
	(arc
		(start 118.27891 -100.788724)
		(mid 118.325586 -100.983425)
		(end 118.272052 -101.176328)
		(width 0.0889)
		(layer "In2.Cu")
		(net "M_K_DQS_DP<15>")
	)
	(arc
		(start 119.076724 -97.236534)
		(mid 119.153976 -97.66236)
		(end 118.798848 -97.909634)
		(width 0.0889)
		(layer "In2.Cu")
		(net "M_K_DQS_DP<15>")
	)
	(arc
		(start 118.272052 -102.167182)
		(mid 118.192921 -102.462584)
		(end 118.272052 -102.757986)
		(width 0.0889)
		(layer "In2.Cu")
		(net "M_K_DQS_DP<15>")
	)
	(arc
		(start 118.272052 -101.176328)
		(mid 118.192863 -101.462943)
		(end 118.263162 -101.751892)
		(width 0.0889)
		(layer "In2.Cu")
		(net "M_K_DQS_DP<15>")
	)
	(arc
		(start 118.766082 -97.909634)
		(mid 118.48248 -97.986488)
		(end 118.276878 -98.1964)
		(width 0.0889)
		(layer "In2.Cu")
		(net "M_K_DQS_DP<15>")
	)
	(arc
		(start 118.272052 -100.185982)
		(mid 118.19283 -100.4751)
		(end 118.265702 -100.765864)
		(width 0.0889)
		(layer "In2.Cu")
		(net "M_K_DQS_DP<15>")
	)
	(arc
		(start 118.276878 -99.794568)
		(mid 118.325633 -99.99092)
		(end 118.272052 -100.185982)
		(width 0.0889)
		(layer "In2.Cu")
		(net "M_K_DQS_DP<15>")
	)
	(arc
		(start 118.272052 -99.195636)
		(mid 118.193047 -99.490784)
		(end 118.272052 -99.785932)
		(width 0.0889)
		(layer "In2.Cu")
		(net "M_K_DQS_DP<15>")
	)
	(arc
		(start 118.272052 -102.757986)
		(mid 118.325522 -102.953049)
		(end 118.276878 -103.1494)
		(width 0.0889)
		(layer "In2.Cu")
		(net "M_K_DQS_DP<15>")
	)
	(arc
		(start 118.272052 -98.795586)
		(mid 118.325522 -98.990649)
		(end 118.276878 -99.187)
		(width 0.0889)
		(layer "In2.Cu")
		(net "M_K_DQS_DP<15>")
	)
	(arc
		(start 118.265702 -98.215704)
		(mid 118.192904 -98.506467)
		(end 118.272052 -98.795586)
		(width 0.0889)
		(layer "In2.Cu")
		(net "M_K_DQS_DP<15>")
	)
	(arc
		(start 118.276878 -101.775768)
		(mid 118.325633 -101.97212)
		(end 118.272052 -102.167182)
		(width 0.0889)
		(layer "In2.Cu")
		(net "M_K_DQS_DP<15>")
	)
	(segment
		(start 127.013462 -134.129272)
		(end 126.950216 -134.26694)
		(width 0.1651)
		(layer "F.Cu")
		(net "M_K_DQS_DP<14>")
	)
	(segment
		(start 127.44958 -133.693154)
		(end 127.013462 -134.129272)
		(width 0.1651)
		(layer "F.Cu")
		(net "M_K_DQS_DP<14>")
	)
	(segment
		(start 126.92888 -135.131302)
		(end 127.010414 -135.355584)
		(width 0.1651)
		(layer "F.Cu")
		(net "M_K_DQS_DP<14>")
	)
	(segment
		(start 113.061242 -96.518984)
		(end 113.632742 -96.518984)
		(width 0.1651)
		(layer "F.Cu")
		(net "M_K_DQS_DP<14>")
	)
	(segment
		(start 127.44958 -133.0706)
		(end 127.44958 -133.693154)
		(width 0.1651)
		(layer "F.Cu")
		(net "M_K_DQS_DP<14>")
	)
	(segment
		(start 126.92888 -134.313168)
		(end 126.92888 -135.131302)
		(width 0.1651)
		(layer "F.Cu")
		(net "M_K_DQS_DP<14>")
	)
	(segment
		(start 127.010414 -135.355584)
		(end 127.392176 -135.737346)
		(width 0.1651)
		(layer "F.Cu")
		(net "M_K_DQS_DP<14>")
	)
	(segment
		(start 126.950216 -134.26694)
		(end 126.92888 -134.313168)
		(width 0.1651)
		(layer "F.Cu")
		(net "M_K_DQS_DP<14>")
	)
	(via
		(at 127.392176 -130.2258)
		(size 0.508)
		(drill 0.254)
		(layers "F.Cu" "B.Cu")
		(net "M_K_DQS_DP<14>")
	)
	(via
		(at 113.632742 -96.518984)
		(size 0.508)
		(drill 0.254)
		(layers "F.Cu" "B.Cu")
		(net "M_K_DQS_DP<14>")
	)
	(via
		(at 127.392176 -135.737346)
		(size 0.508)
		(drill 0.254)
		(layers "F.Cu" "B.Cu")
		(net "M_K_DQS_DP<14>")
	)
	(segment
		(start 126.91618 -131.669536)
		(end 126.91618 -130.773932)
		(width 0.1651)
		(layer "B.Cu")
		(net "M_K_DQS_DP<14>")
	)
	(segment
		(start 127.003556 -130.61442)
		(end 127.392176 -130.2258)
		(width 0.1651)
		(layer "B.Cu")
		(net "M_K_DQS_DP<14>")
	)
	(segment
		(start 126.91618 -130.773932)
		(end 127.003556 -130.61442)
		(width 0.1651)
		(layer "B.Cu")
		(net "M_K_DQS_DP<14>")
	)
	(segment
		(start 126.993396 -131.80187)
		(end 126.91618 -131.669536)
		(width 0.1651)
		(layer "B.Cu")
		(net "M_K_DQS_DP<14>")
	)
	(segment
		(start 127.44958 -132.258054)
		(end 126.993396 -131.80187)
		(width 0.1651)
		(layer "B.Cu")
		(net "M_K_DQS_DP<14>")
	)
	(segment
		(start 127.44958 -132.876036)
		(end 127.44958 -132.258054)
		(width 0.1651)
		(layer "B.Cu")
		(net "M_K_DQS_DP<14>")
	)
	(segment
		(start 127.747776 -128.915668)
		(end 127.747776 -129.169668)
		(width 0.14224)
		(layer "In2.Cu")
		(net "M_K_DQS_DP<14>")
	)
	(segment
		(start 122.862848 -126.807214)
		(end 123.47448 -127.418846)
		(width 0.14224)
		(layer "In2.Cu")
		(net "M_K_DQS_DP<14>")
	)
	(segment
		(start 112.794796 -100.385626)
		(end 112.78997 -100.38588)
		(width 0.0889)
		(layer "In2.Cu")
		(net "M_K_DQS_DP<14>")
	)
	(segment
		(start 127.257048 -127.418846)
		(end 127.905256 -128.067054)
		(width 0.14224)
		(layer "In2.Cu")
		(net "M_K_DQS_DP<14>")
	)
	(segment
		(start 123.47448 -127.418846)
		(end 123.939808 -127.418846)
		(width 0.14224)
		(layer "In2.Cu")
		(net "M_K_DQS_DP<14>")
	)
	(segment
		(start 126.154688 -127.418846)
		(end 126.408688 -127.418846)
		(width 0.14224)
		(layer "In2.Cu")
		(net "M_K_DQS_DP<14>")
	)
	(segment
		(start 109.676692 -105.00106)
		(end 109.676692 -106.15803)
		(width 0.0889)
		(layer "In2.Cu")
		(net "M_K_DQS_DP<14>")
	)
	(segment
		(start 109.637322 -106.219498)
		(end 109.637322 -115.549426)
		(width 0.14224)
		(layer "In2.Cu")
		(net "M_K_DQS_DP<14>")
	)
	(segment
		(start 113.120932 -99.786186)
		(end 113.125758 -99.794568)
		(width 0.0889)
		(layer "In2.Cu")
		(net "M_K_DQS_DP<14>")
	)
	(segment
		(start 125.585728 -127.418846)
		(end 125.743208 -127.576326)
		(width 0.14224)
		(layer "In2.Cu")
		(net "M_K_DQS_DP<14>")
	)
	(segment
		(start 111.324898 -103.352854)
		(end 109.676692 -105.00106)
		(width 0.0889)
		(layer "In2.Cu")
		(net "M_K_DQS_DP<14>")
	)
	(segment
		(start 126.408688 -127.418846)
		(end 126.566168 -127.576326)
		(width 0.14224)
		(layer "In2.Cu")
		(net "M_K_DQS_DP<14>")
	)
	(segment
		(start 122.862848 -126.072646)
		(end 122.862848 -126.807214)
		(width 0.14224)
		(layer "In2.Cu")
		(net "M_K_DQS_DP<14>")
	)
	(segment
		(start 121.93397 -125.143768)
		(end 122.261122 -125.47092)
		(width 0.14224)
		(layer "In2.Cu")
		(net "M_K_DQS_DP<14>")
	)
	(segment
		(start 127.905256 -128.758188)
		(end 127.747776 -128.915668)
		(width 0.14224)
		(layer "In2.Cu")
		(net "M_K_DQS_DP<14>")
	)
	(segment
		(start 126.977648 -127.418846)
		(end 127.257048 -127.418846)
		(width 0.14224)
		(layer "In2.Cu")
		(net "M_K_DQS_DP<14>")
	)
	(segment
		(start 124.351288 -127.576326)
		(end 124.508768 -127.418846)
		(width 0.14224)
		(layer "In2.Cu")
		(net "M_K_DQS_DP<14>")
	)
	(segment
		(start 126.820168 -127.576326)
		(end 126.977648 -127.418846)
		(width 0.14224)
		(layer "In2.Cu")
		(net "M_K_DQS_DP<14>")
	)
	(segment
		(start 112.262412 -100.681028)
		(end 111.324898 -102.305866)
		(width 0.0889)
		(layer "In2.Cu")
		(net "M_K_DQS_DP<14>")
	)
	(segment
		(start 111.324898 -102.305866)
		(end 111.324898 -103.352854)
		(width 0.0889)
		(layer "In2.Cu")
		(net "M_K_DQS_DP<14>")
	)
	(segment
		(start 113.632742 -96.518984)
		(end 113.47958 -96.938846)
		(width 0.0889)
		(layer "In2.Cu")
		(net "M_K_DQS_DP<14>")
	)
	(segment
		(start 125.997208 -127.576326)
		(end 126.154688 -127.418846)
		(width 0.14224)
		(layer "In2.Cu")
		(net "M_K_DQS_DP<14>")
	)
	(segment
		(start 124.920248 -127.576326)
		(end 125.174248 -127.576326)
		(width 0.14224)
		(layer "In2.Cu")
		(net "M_K_DQS_DP<14>")
	)
	(segment
		(start 125.174248 -127.576326)
		(end 125.331728 -127.418846)
		(width 0.14224)
		(layer "In2.Cu")
		(net "M_K_DQS_DP<14>")
	)
	(segment
		(start 124.762768 -127.418846)
		(end 124.920248 -127.576326)
		(width 0.14224)
		(layer "In2.Cu")
		(net "M_K_DQS_DP<14>")
	)
	(segment
		(start 113.120932 -99.195636)
		(end 113.114582 -99.206304)
		(width 0.0889)
		(layer "In2.Cu")
		(net "M_K_DQS_DP<14>")
	)
	(segment
		(start 127.671576 -130.2258)
		(end 127.392176 -130.2258)
		(width 0.14224)
		(layer "In2.Cu")
		(net "M_K_DQS_DP<14>")
	)
	(segment
		(start 126.887224 -130.641344)
		(end 126.887224 -135.232394)
		(width 0.14224)
		(layer "In2.Cu")
		(net "M_K_DQS_DP<14>")
	)
	(segment
		(start 126.566168 -127.576326)
		(end 126.820168 -127.576326)
		(width 0.14224)
		(layer "In2.Cu")
		(net "M_K_DQS_DP<14>")
	)
	(segment
		(start 127.747776 -129.169668)
		(end 127.905256 -129.327148)
		(width 0.14224)
		(layer "In2.Cu")
		(net "M_K_DQS_DP<14>")
	)
	(segment
		(start 124.508768 -127.418846)
		(end 124.762768 -127.418846)
		(width 0.14224)
		(layer "In2.Cu")
		(net "M_K_DQS_DP<14>")
	)
	(segment
		(start 125.743208 -127.576326)
		(end 125.997208 -127.576326)
		(width 0.14224)
		(layer "In2.Cu")
		(net "M_K_DQS_DP<14>")
	)
	(segment
		(start 124.097288 -127.576326)
		(end 124.351288 -127.576326)
		(width 0.14224)
		(layer "In2.Cu")
		(net "M_K_DQS_DP<14>")
	)
	(segment
		(start 113.125758 -98.1964)
		(end 113.120932 -98.205036)
		(width 0.0889)
		(layer "In2.Cu")
		(net "M_K_DQS_DP<14>")
	)
	(segment
		(start 122.261122 -125.662944)
		(end 122.4407 -125.842522)
		(width 0.14224)
		(layer "In2.Cu")
		(net "M_K_DQS_DP<14>")
	)
	(segment
		(start 123.939808 -127.418846)
		(end 124.097288 -127.576326)
		(width 0.14224)
		(layer "In2.Cu")
		(net "M_K_DQS_DP<14>")
	)
	(segment
		(start 113.120932 -98.205036)
		(end 113.114582 -98.215704)
		(width 0.0889)
		(layer "In2.Cu")
		(net "M_K_DQS_DP<14>")
	)
	(segment
		(start 122.4407 -125.842522)
		(end 122.632724 -125.842522)
		(width 0.14224)
		(layer "In2.Cu")
		(net "M_K_DQS_DP<14>")
	)
	(segment
		(start 109.676692 -106.15803)
		(end 109.637322 -106.1974)
		(width 0.0889)
		(layer "In2.Cu")
		(net "M_K_DQS_DP<14>")
	)
	(segment
		(start 122.261122 -125.47092)
		(end 122.261122 -125.662944)
		(width 0.14224)
		(layer "In2.Cu")
		(net "M_K_DQS_DP<14>")
	)
	(segment
		(start 127.392176 -130.2258)
		(end 127.302768 -130.2258)
		(width 0.14224)
		(layer "In2.Cu")
		(net "M_K_DQS_DP<14>")
	)
	(segment
		(start 127.905256 -129.327148)
		(end 127.905256 -129.99212)
		(width 0.14224)
		(layer "In2.Cu")
		(net "M_K_DQS_DP<14>")
	)
	(segment
		(start 109.637322 -115.549426)
		(end 119.231664 -125.143768)
		(width 0.14224)
		(layer "In2.Cu")
		(net "M_K_DQS_DP<14>")
	)
	(segment
		(start 126.887224 -135.232394)
		(end 127.392176 -135.737346)
		(width 0.14224)
		(layer "In2.Cu")
		(net "M_K_DQS_DP<14>")
	)
	(segment
		(start 127.905256 -128.067054)
		(end 127.905256 -128.758188)
		(width 0.14224)
		(layer "In2.Cu")
		(net "M_K_DQS_DP<14>")
	)
	(segment
		(start 122.632724 -125.842522)
		(end 122.862848 -126.072646)
		(width 0.14224)
		(layer "In2.Cu")
		(net "M_K_DQS_DP<14>")
	)
	(segment
		(start 127.905256 -129.99212)
		(end 127.671576 -130.2258)
		(width 0.14224)
		(layer "In2.Cu")
		(net "M_K_DQS_DP<14>")
	)
	(segment
		(start 113.125758 -99.187)
		(end 113.120932 -99.195636)
		(width 0.0889)
		(layer "In2.Cu")
		(net "M_K_DQS_DP<14>")
	)
	(segment
		(start 119.231664 -125.143768)
		(end 121.93397 -125.143768)
		(width 0.14224)
		(layer "In2.Cu")
		(net "M_K_DQS_DP<14>")
	)
	(segment
		(start 109.637322 -106.1974)
		(end 109.637322 -106.219498)
		(width 0.0889)
		(layer "In2.Cu")
		(net "M_K_DQS_DP<14>")
	)
	(segment
		(start 112.78997 -100.38588)
		(end 112.752124 -100.38588)
		(width 0.0889)
		(layer "In2.Cu")
		(net "M_K_DQS_DP<14>")
	)
	(segment
		(start 127.302768 -130.2258)
		(end 126.887224 -130.641344)
		(width 0.14224)
		(layer "In2.Cu")
		(net "M_K_DQS_DP<14>")
	)
	(segment
		(start 125.331728 -127.418846)
		(end 125.585728 -127.418846)
		(width 0.14224)
		(layer "In2.Cu")
		(net "M_K_DQS_DP<14>")
	)
	(arc
		(start 113.114582 -99.206304)
		(mid 113.041784 -99.497067)
		(end 113.120932 -99.786186)
		(width 0.0889)
		(layer "In2.Cu")
		(net "M_K_DQS_DP<14>")
	)
	(arc
		(start 113.125758 -99.794568)
		(mid 113.123386 -100.181389)
		(end 112.794796 -100.385626)
		(width 0.0889)
		(layer "In2.Cu")
		(net "M_K_DQS_DP<14>")
	)
	(arc
		(start 113.120932 -97.804986)
		(mid 113.174402 -98.000049)
		(end 113.125758 -98.1964)
		(width 0.0889)
		(layer "In2.Cu")
		(net "M_K_DQS_DP<14>")
	)
	(arc
		(start 112.752124 -100.38588)
		(mid 112.46922 -100.470299)
		(end 112.262412 -100.681028)
		(width 0.0889)
		(layer "In2.Cu")
		(net "M_K_DQS_DP<14>")
	)
	(arc
		(start 113.47958 -96.938846)
		(mid 113.086764 -97.283512)
		(end 113.120932 -97.804986)
		(width 0.0889)
		(layer "In2.Cu")
		(net "M_K_DQS_DP<14>")
	)
	(arc
		(start 113.120932 -98.795586)
		(mid 113.174402 -98.990649)
		(end 113.125758 -99.187)
		(width 0.0889)
		(layer "In2.Cu")
		(net "M_K_DQS_DP<14>")
	)
	(arc
		(start 113.114582 -98.215704)
		(mid 113.041784 -98.506467)
		(end 113.120932 -98.795586)
		(width 0.0889)
		(layer "In2.Cu")
		(net "M_K_DQS_DP<14>")
	)
	(segment
		(start 118.781068 -128.594358)
		(end 118.781068 -129.756154)
		(width 0.1651)
		(layer "F.Cu")
		(net "M_K_DQS_DP<13>")
	)
	(segment
		(start 117.660166 -135.355584)
		(end 118.041928 -135.737346)
		(width 0.1651)
		(layer "F.Cu")
		(net "M_K_DQS_DP<13>")
	)
	(segment
		(start 114.234722 -122.740166)
		(end 114.468402 -122.973846)
		(width 0.1651)
		(layer "F.Cu")
		(net "M_K_DQS_DP<13>")
	)
	(segment
		(start 109.179868 -113.2205)
		(end 109.179868 -113.7666)
		(width 0.1016)
		(layer "F.Cu")
		(net "M_K_DQS_DP<13>")
	)
	(segment
		(start 118.099332 -133.0706)
		(end 118.099332 -133.693408)
		(width 0.1651)
		(layer "F.Cu")
		(net "M_K_DQS_DP<13>")
	)
	(segment
		(start 111.153448 -116.267738)
		(end 111.153448 -117.1067)
		(width 0.1651)
		(layer "F.Cu")
		(net "M_K_DQS_DP<13>")
	)
	(segment
		(start 108.971842 -113.012474)
		(end 109.179868 -113.2205)
		(width 0.1016)
		(layer "F.Cu")
		(net "M_K_DQS_DP<13>")
	)
	(segment
		(start 118.590568 -128.403858)
		(end 118.781068 -128.594358)
		(width 0.1651)
		(layer "F.Cu")
		(net "M_K_DQS_DP<13>")
	)
	(segment
		(start 109.973872 -101.272086)
		(end 109.978698 -101.280722)
		(width 0.0889)
		(layer "F.Cu")
		(net "M_K_DQS_DP<13>")
	)
	(segment
		(start 110.485682 -100.29952)
		(end 110.391956 -100.393246)
		(width 0.0889)
		(layer "F.Cu")
		(net "M_K_DQS_DP<13>")
	)
	(segment
		(start 111.153448 -118.5037)
		(end 111.026448 -118.6307)
		(width 0.1651)
		(layer "F.Cu")
		(net "M_K_DQS_DP<13>")
	)
	(segment
		(start 111.026448 -118.9609)
		(end 111.153448 -119.0879)
		(width 0.1651)
		(layer "F.Cu")
		(net "M_K_DQS_DP<13>")
	)
	(segment
		(start 118.781068 -129.756154)
		(end 118.311422 -130.2258)
		(width 0.1651)
		(layer "F.Cu")
		(net "M_K_DQS_DP<13>")
	)
	(segment
		(start 118.099332 -133.693408)
		(end 117.663214 -134.129526)
		(width 0.1651)
		(layer "F.Cu")
		(net "M_K_DQS_DP<13>")
	)
	(segment
		(start 118.781068 -127.386842)
		(end 118.590568 -127.577342)
		(width 0.1651)
		(layer "F.Cu")
		(net "M_K_DQS_DP<13>")
	)
	(segment
		(start 114.234722 -122.560588)
		(end 114.234722 -122.740166)
		(width 0.1651)
		(layer "F.Cu")
		(net "M_K_DQS_DP<13>")
	)
	(segment
		(start 111.026448 -117.2337)
		(end 111.026448 -117.5639)
		(width 0.1651)
		(layer "F.Cu")
		(net "M_K_DQS_DP<13>")
	)
	(segment
		(start 108.971842 -106.586274)
		(end 108.971842 -113.012474)
		(width 0.1016)
		(layer "F.Cu")
		(net "M_K_DQS_DP<13>")
	)
	(segment
		(start 118.590568 -127.577342)
		(end 118.590568 -128.403858)
		(width 0.1651)
		(layer "F.Cu")
		(net "M_K_DQS_DP<13>")
	)
	(segment
		(start 111.026448 -117.5639)
		(end 111.153448 -117.6909)
		(width 0.1651)
		(layer "F.Cu")
		(net "M_K_DQS_DP<13>")
	)
	(segment
		(start 117.663214 -134.129526)
		(end 117.599968 -134.26694)
		(width 0.1651)
		(layer "F.Cu")
		(net "M_K_DQS_DP<13>")
	)
	(segment
		(start 117.578632 -134.313168)
		(end 117.578632 -135.131302)
		(width 0.1651)
		(layer "F.Cu")
		(net "M_K_DQS_DP<13>")
	)
	(segment
		(start 109.073442 -106.484674)
		(end 108.971842 -106.586274)
		(width 0.0889)
		(layer "F.Cu")
		(net "M_K_DQS_DP<13>")
	)
	(segment
		(start 109.230668 -113.8174)
		(end 109.230668 -114.344958)
		(width 0.1651)
		(layer "F.Cu")
		(net "M_K_DQS_DP<13>")
	)
	(segment
		(start 109.902752 -104.318308)
		(end 109.073442 -105.147618)
		(width 0.0889)
		(layer "F.Cu")
		(net "M_K_DQS_DP<13>")
	)
	(segment
		(start 118.311422 -130.2258)
		(end 118.041928 -130.2258)
		(width 0.1651)
		(layer "F.Cu")
		(net "M_K_DQS_DP<13>")
	)
	(segment
		(start 114.468402 -122.973846)
		(end 114.64798 -122.973846)
		(width 0.1651)
		(layer "F.Cu")
		(net "M_K_DQS_DP<13>")
	)
	(segment
		(start 109.179868 -113.7666)
		(end 109.230668 -113.8174)
		(width 0.1016)
		(layer "F.Cu")
		(net "M_K_DQS_DP<13>")
	)
	(segment
		(start 117.578632 -135.131302)
		(end 117.660166 -135.355584)
		(width 0.1651)
		(layer "F.Cu")
		(net "M_K_DQS_DP<13>")
	)
	(segment
		(start 111.153448 -119.0879)
		(end 111.153448 -119.479314)
		(width 0.1651)
		(layer "F.Cu")
		(net "M_K_DQS_DP<13>")
	)
	(segment
		(start 109.230668 -114.344958)
		(end 111.153448 -116.267738)
		(width 0.1651)
		(layer "F.Cu")
		(net "M_K_DQS_DP<13>")
	)
	(segment
		(start 109.967522 -102.252018)
		(end 109.973872 -102.262686)
		(width 0.0889)
		(layer "F.Cu")
		(net "M_K_DQS_DP<13>")
	)
	(segment
		(start 118.781068 -127.106934)
		(end 118.781068 -127.386842)
		(width 0.1651)
		(layer "F.Cu")
		(net "M_K_DQS_DP<13>")
	)
	(segment
		(start 117.599968 -134.26694)
		(end 117.578632 -134.313168)
		(width 0.1651)
		(layer "F.Cu")
		(net "M_K_DQS_DP<13>")
	)
	(segment
		(start 114.64798 -122.973846)
		(end 118.781068 -127.106934)
		(width 0.1651)
		(layer "F.Cu")
		(net "M_K_DQS_DP<13>")
	)
	(segment
		(start 110.485682 -99.986338)
		(end 110.485682 -100.29952)
		(width 0.0889)
		(layer "F.Cu")
		(net "M_K_DQS_DP<13>")
	)
	(segment
		(start 111.153448 -117.6909)
		(end 111.153448 -118.5037)
		(width 0.1651)
		(layer "F.Cu")
		(net "M_K_DQS_DP<13>")
	)
	(segment
		(start 111.026448 -118.6307)
		(end 111.026448 -118.9609)
		(width 0.1651)
		(layer "F.Cu")
		(net "M_K_DQS_DP<13>")
	)
	(segment
		(start 111.153448 -117.1067)
		(end 111.026448 -117.2337)
		(width 0.1651)
		(layer "F.Cu")
		(net "M_K_DQS_DP<13>")
	)
	(segment
		(start 109.973872 -102.262686)
		(end 109.978698 -102.271322)
		(width 0.0889)
		(layer "F.Cu")
		(net "M_K_DQS_DP<13>")
	)
	(segment
		(start 109.902752 -102.92842)
		(end 109.902752 -104.318308)
		(width 0.0889)
		(layer "F.Cu")
		(net "M_K_DQS_DP<13>")
	)
	(segment
		(start 109.073442 -105.147618)
		(end 109.073442 -106.484674)
		(width 0.0889)
		(layer "F.Cu")
		(net "M_K_DQS_DP<13>")
	)
	(segment
		(start 111.153448 -119.479314)
		(end 114.234722 -122.560588)
		(width 0.1651)
		(layer "F.Cu")
		(net "M_K_DQS_DP<13>")
	)
	(via
		(at 118.041928 -135.737346)
		(size 0.508)
		(drill 0.254)
		(layers "F.Cu" "B.Cu")
		(net "M_K_DQS_DP<13>")
	)
	(via
		(at 118.041928 -130.2258)
		(size 0.508)
		(drill 0.254)
		(layers "F.Cu" "B.Cu")
		(net "M_K_DQS_DP<13>")
	)
	(arc
		(start 109.973872 -101.672136)
		(mid 109.89465 -101.961254)
		(end 109.967522 -102.252018)
		(width 0.0889)
		(layer "F.Cu")
		(net "M_K_DQS_DP<13>")
	)
	(arc
		(start 109.978698 -101.280722)
		(mid 110.027453 -101.477074)
		(end 109.973872 -101.672136)
		(width 0.0889)
		(layer "F.Cu")
		(net "M_K_DQS_DP<13>")
	)
	(arc
		(start 110.391956 -100.393246)
		(mid 109.952065 -100.722839)
		(end 109.973872 -101.272086)
		(width 0.0889)
		(layer "F.Cu")
		(net "M_K_DQS_DP<13>")
	)
	(arc
		(start 109.973872 -102.662736)
		(mid 109.920806 -102.790892)
		(end 109.902752 -102.92842)
		(width 0.0889)
		(layer "F.Cu")
		(net "M_K_DQS_DP<13>")
	)
	(arc
		(start 109.978698 -102.271322)
		(mid 110.027453 -102.467674)
		(end 109.973872 -102.662736)
		(width 0.0889)
		(layer "F.Cu")
		(net "M_K_DQS_DP<13>")
	)
	(segment
		(start 117.653308 -130.61442)
		(end 118.041928 -130.2258)
		(width 0.1651)
		(layer "B.Cu")
		(net "M_K_DQS_DP<13>")
	)
	(segment
		(start 117.643148 -131.80187)
		(end 117.565932 -131.669536)
		(width 0.1651)
		(layer "B.Cu")
		(net "M_K_DQS_DP<13>")
	)
	(segment
		(start 118.099332 -132.876036)
		(end 118.099332 -132.258054)
		(width 0.1651)
		(layer "B.Cu")
		(net "M_K_DQS_DP<13>")
	)
	(segment
		(start 117.565932 -131.669536)
		(end 117.565932 -130.773932)
		(width 0.1651)
		(layer "B.Cu")
		(net "M_K_DQS_DP<13>")
	)
	(segment
		(start 117.565932 -130.773932)
		(end 117.653308 -130.61442)
		(width 0.1651)
		(layer "B.Cu")
		(net "M_K_DQS_DP<13>")
	)
	(segment
		(start 118.099332 -132.258054)
		(end 117.643148 -131.80187)
		(width 0.1651)
		(layer "B.Cu")
		(net "M_K_DQS_DP<13>")
	)
	(segment
		(start 118.041928 -135.737346)
		(end 117.53723 -135.232648)
		(width 0.14224)
		(layer "In2.Cu")
		(net "M_K_DQS_DP<13>")
	)
	(segment
		(start 117.53723 -130.644138)
		(end 117.955568 -130.2258)
		(width 0.14224)
		(layer "In2.Cu")
		(net "M_K_DQS_DP<13>")
	)
	(segment
		(start 117.53723 -135.232648)
		(end 117.53723 -130.644138)
		(width 0.14224)
		(layer "In2.Cu")
		(net "M_K_DQS_DP<13>")
	)
	(segment
		(start 117.955568 -130.2258)
		(end 118.041928 -130.2258)
		(width 0.14224)
		(layer "In2.Cu")
		(net "M_K_DQS_DP<13>")
	)
	(segment
		(start 62.849506 -133.0706)
		(end 62.849506 -133.693154)
		(width 0.1651)
		(layer "F.Cu")
		(net "M_K_DQS_DP<12>")
	)
	(segment
		(start 62.413388 -134.129272)
		(end 62.350142 -134.26694)
		(width 0.1651)
		(layer "F.Cu")
		(net "M_K_DQS_DP<12>")
	)
	(segment
		(start 62.328806 -135.131302)
		(end 62.41034 -135.355584)
		(width 0.1651)
		(layer "F.Cu")
		(net "M_K_DQS_DP<12>")
	)
	(segment
		(start 62.350142 -134.26694)
		(end 62.328806 -134.313168)
		(width 0.1651)
		(layer "F.Cu")
		(net "M_K_DQS_DP<12>")
	)
	(segment
		(start 62.41034 -135.355584)
		(end 62.792102 -135.737346)
		(width 0.1651)
		(layer "F.Cu")
		(net "M_K_DQS_DP<12>")
	)
	(segment
		(start 77.192886 -94.718886)
		(end 76.621386 -94.718886)
		(width 0.1651)
		(layer "F.Cu")
		(net "M_K_DQS_DP<12>")
	)
	(segment
		(start 62.328806 -134.313168)
		(end 62.328806 -135.131302)
		(width 0.1651)
		(layer "F.Cu")
		(net "M_K_DQS_DP<12>")
	)
	(segment
		(start 62.849506 -133.693154)
		(end 62.413388 -134.129272)
		(width 0.1651)
		(layer "F.Cu")
		(net "M_K_DQS_DP<12>")
	)
	(via
		(at 76.621386 -94.718886)
		(size 0.508)
		(drill 0.254)
		(layers "F.Cu" "B.Cu")
		(net "M_K_DQS_DP<12>")
	)
	(via
		(at 62.792102 -130.2258)
		(size 0.508)
		(drill 0.254)
		(layers "F.Cu" "B.Cu")
		(net "M_K_DQS_DP<12>")
	)
	(via
		(at 62.792102 -135.737346)
		(size 0.508)
		(drill 0.254)
		(layers "F.Cu" "B.Cu")
		(net "M_K_DQS_DP<12>")
	)
	(segment
		(start 62.403482 -130.61442)
		(end 62.792102 -130.2258)
		(width 0.1651)
		(layer "B.Cu")
		(net "M_K_DQS_DP<12>")
	)
	(segment
		(start 62.393322 -131.80187)
		(end 62.316106 -131.669536)
		(width 0.1651)
		(layer "B.Cu")
		(net "M_K_DQS_DP<12>")
	)
	(segment
		(start 62.849506 -132.258054)
		(end 62.393322 -131.80187)
		(width 0.1651)
		(layer "B.Cu")
		(net "M_K_DQS_DP<12>")
	)
	(segment
		(start 62.316106 -130.773932)
		(end 62.403482 -130.61442)
		(width 0.1651)
		(layer "B.Cu")
		(net "M_K_DQS_DP<12>")
	)
	(segment
		(start 62.316106 -131.669536)
		(end 62.316106 -130.773932)
		(width 0.1651)
		(layer "B.Cu")
		(net "M_K_DQS_DP<12>")
	)
	(segment
		(start 62.849506 -132.876036)
		(end 62.849506 -132.258054)
		(width 0.1651)
		(layer "B.Cu")
		(net "M_K_DQS_DP<12>")
	)
	(segment
		(start 68.655692 -101.984302)
		(end 68.655692 -102.534974)
		(width 0.0889)
		(layer "In2.Cu")
		(net "M_K_DQS_DP<12>")
	)
	(segment
		(start 71.4883 -100.071936)
		(end 71.448676 -100.071936)
		(width 0.0889)
		(layer "In2.Cu")
		(net "M_K_DQS_DP<12>")
	)
	(segment
		(start 65.544954 -105.589832)
		(end 65.544954 -108.99394)
		(width 0.14224)
		(layer "In2.Cu")
		(net "M_K_DQS_DP<12>")
	)
	(segment
		(start 68.308474 -102.826312)
		(end 68.292726 -102.84206)
		(width 0.0889)
		(layer "In2.Cu")
		(net "M_K_DQS_DP<12>")
	)
	(segment
		(start 76.621386 -94.718886)
		(end 76.621386 -95.05696)
		(width 0.0889)
		(layer "In2.Cu")
		(net "M_K_DQS_DP<12>")
	)
	(segment
		(start 63.283592 -127.927608)
		(end 63.149734 -128.061466)
		(width 0.14224)
		(layer "In2.Cu")
		(net "M_K_DQS_DP<12>")
	)
	(segment
		(start 63.126112 -129.138426)
		(end 63.283592 -129.295906)
		(width 0.14224)
		(layer "In2.Cu")
		(net "M_K_DQS_DP<12>")
	)
	(segment
		(start 63.040768 -130.2258)
		(end 62.792102 -130.2258)
		(width 0.14224)
		(layer "In2.Cu")
		(net "M_K_DQS_DP<12>")
	)
	(segment
		(start 73.202292 -99.081336)
		(end 73.174352 -99.081336)
		(width 0.0889)
		(layer "In2.Cu")
		(net "M_K_DQS_DP<12>")
	)
	(segment
		(start 76.109576 -96.404938)
		(end 76.103226 -96.415606)
		(width 0.0889)
		(layer "In2.Cu")
		(net "M_K_DQS_DP<12>")
	)
	(segment
		(start 70.622922 -100.567236)
		(end 70.598792 -100.567236)
		(width 0.0889)
		(layer "In2.Cu")
		(net "M_K_DQS_DP<12>")
	)
	(segment
		(start 63.283592 -128.726946)
		(end 63.126112 -128.884426)
		(width 0.14224)
		(layer "In2.Cu")
		(net "M_K_DQS_DP<12>")
	)
	(segment
		(start 63.149734 -128.061466)
		(end 63.149734 -128.315466)
		(width 0.14224)
		(layer "In2.Cu")
		(net "M_K_DQS_DP<12>")
	)
	(segment
		(start 62.28715 -130.6576)
		(end 62.28715 -135.232394)
		(width 0.14224)
		(layer "In2.Cu")
		(net "M_K_DQS_DP<12>")
	)
	(segment
		(start 76.621386 -95.05696)
		(end 76.556108 -95.122238)
		(width 0.0889)
		(layer "In2.Cu")
		(net "M_K_DQS_DP<12>")
	)
	(segment
		(start 63.283592 -129.295906)
		(end 63.283592 -129.982976)
		(width 0.14224)
		(layer "In2.Cu")
		(net "M_K_DQS_DP<12>")
	)
	(segment
		(start 69.768212 -101.062536)
		(end 69.735446 -101.062536)
		(width 0.0889)
		(layer "In2.Cu")
		(net "M_K_DQS_DP<12>")
	)
	(segment
		(start 63.126112 -128.884426)
		(end 63.126112 -129.138426)
		(width 0.14224)
		(layer "In2.Cu")
		(net "M_K_DQS_DP<12>")
	)
	(segment
		(start 68.292726 -102.84206)
		(end 65.544954 -105.589832)
		(width 0.14224)
		(layer "In2.Cu")
		(net "M_K_DQS_DP<12>")
	)
	(segment
		(start 62.28715 -135.232394)
		(end 62.792102 -135.737346)
		(width 0.14224)
		(layer "In2.Cu")
		(net "M_K_DQS_DP<12>")
	)
	(segment
		(start 76.114402 -96.396302)
		(end 76.109576 -96.404938)
		(width 0.0889)
		(layer "In2.Cu")
		(net "M_K_DQS_DP<12>")
	)
	(segment
		(start 72.34682 -99.576636)
		(end 72.311006 -99.576636)
		(width 0.0889)
		(layer "In2.Cu")
		(net "M_K_DQS_DP<12>")
	)
	(segment
		(start 74.057002 -98.58629)
		(end 74.024236 -98.58629)
		(width 0.0889)
		(layer "In2.Cu")
		(net "M_K_DQS_DP<12>")
	)
	(segment
		(start 65.544954 -108.99394)
		(end 63.283592 -111.255302)
		(width 0.14224)
		(layer "In2.Cu")
		(net "M_K_DQS_DP<12>")
	)
	(segment
		(start 75.774042 -97.59569)
		(end 75.741276 -97.59569)
		(width 0.0889)
		(layer "In2.Cu")
		(net "M_K_DQS_DP<12>")
	)
	(segment
		(start 69.241416 -101.357938)
		(end 69.185536 -101.454458)
		(width 0.0889)
		(layer "In2.Cu")
		(net "M_K_DQS_DP<12>")
	)
	(segment
		(start 74.919332 -98.090736)
		(end 74.886566 -98.090736)
		(width 0.0889)
		(layer "In2.Cu")
		(net "M_K_DQS_DP<12>")
	)
	(segment
		(start 62.71895 -130.2258)
		(end 62.28715 -130.6576)
		(width 0.14224)
		(layer "In2.Cu")
		(net "M_K_DQS_DP<12>")
	)
	(segment
		(start 63.283592 -111.255302)
		(end 63.283592 -127.927608)
		(width 0.14224)
		(layer "In2.Cu")
		(net "M_K_DQS_DP<12>")
	)
	(segment
		(start 63.149734 -128.315466)
		(end 63.283592 -128.449324)
		(width 0.14224)
		(layer "In2.Cu")
		(net "M_K_DQS_DP<12>")
	)
	(segment
		(start 68.364354 -102.826312)
		(end 68.308474 -102.826312)
		(width 0.0889)
		(layer "In2.Cu")
		(net "M_K_DQS_DP<12>")
	)
	(segment
		(start 63.283592 -129.982976)
		(end 63.040768 -130.2258)
		(width 0.14224)
		(layer "In2.Cu")
		(net "M_K_DQS_DP<12>")
	)
	(segment
		(start 62.792102 -130.2258)
		(end 62.71895 -130.2258)
		(width 0.14224)
		(layer "In2.Cu")
		(net "M_K_DQS_DP<12>")
	)
	(segment
		(start 63.283592 -128.449324)
		(end 63.283592 -128.726946)
		(width 0.14224)
		(layer "In2.Cu")
		(net "M_K_DQS_DP<12>")
	)
	(segment
		(start 68.655692 -102.534974)
		(end 68.364354 -102.826312)
		(width 0.0889)
		(layer "In2.Cu")
		(net "M_K_DQS_DP<12>")
	)
	(segment
		(start 69.185536 -101.454458)
		(end 68.655692 -101.984302)
		(width 0.0889)
		(layer "In2.Cu")
		(net "M_K_DQS_DP<12>")
	)
	(arc
		(start 71.816976 -99.872038)
		(mid 71.678232 -100.014071)
		(end 71.4883 -100.071936)
		(width 0.0889)
		(layer "In2.Cu")
		(net "M_K_DQS_DP<12>")
	)
	(arc
		(start 76.109576 -96.995488)
		(mid 76.112324 -97.390955)
		(end 75.774042 -97.59569)
		(width 0.0889)
		(layer "In2.Cu")
		(net "M_K_DQS_DP<12>")
	)
	(arc
		(start 76.556108 -95.122238)
		(mid 76.094139 -95.44278)
		(end 76.109576 -96.004888)
		(width 0.0889)
		(layer "In2.Cu")
		(net "M_K_DQS_DP<12>")
	)
	(arc
		(start 69.735446 -101.062536)
		(mid 69.450022 -101.146003)
		(end 69.241416 -101.357938)
		(width 0.0889)
		(layer "In2.Cu")
		(net "M_K_DQS_DP<12>")
	)
	(arc
		(start 76.109576 -96.004888)
		(mid 76.163046 -96.199951)
		(end 76.114402 -96.396302)
		(width 0.0889)
		(layer "In2.Cu")
		(net "M_K_DQS_DP<12>")
	)
	(arc
		(start 72.311006 -99.576636)
		(mid 72.025582 -99.660103)
		(end 71.816976 -99.872038)
		(width 0.0889)
		(layer "In2.Cu")
		(net "M_K_DQS_DP<12>")
	)
	(arc
		(start 73.534016 -98.881438)
		(mid 73.393937 -99.024174)
		(end 73.202292 -99.081336)
		(width 0.0889)
		(layer "In2.Cu")
		(net "M_K_DQS_DP<12>")
	)
	(arc
		(start 70.099936 -100.862638)
		(mid 69.959857 -101.005374)
		(end 69.768212 -101.062536)
		(width 0.0889)
		(layer "In2.Cu")
		(net "M_K_DQS_DP<12>")
	)
	(arc
		(start 70.958456 -100.367084)
		(mid 70.816773 -100.510888)
		(end 70.622922 -100.567236)
		(width 0.0889)
		(layer "In2.Cu")
		(net "M_K_DQS_DP<12>")
	)
	(arc
		(start 73.174352 -99.081336)
		(mid 72.886207 -99.163655)
		(end 72.675496 -99.376738)
		(width 0.0889)
		(layer "In2.Cu")
		(net "M_K_DQS_DP<12>")
	)
	(arc
		(start 74.392536 -98.386138)
		(mid 74.250853 -98.529942)
		(end 74.057002 -98.58629)
		(width 0.0889)
		(layer "In2.Cu")
		(net "M_K_DQS_DP<12>")
	)
	(arc
		(start 75.741276 -97.59569)
		(mid 75.458059 -97.679971)
		(end 75.251056 -97.890838)
		(width 0.0889)
		(layer "In2.Cu")
		(net "M_K_DQS_DP<12>")
	)
	(arc
		(start 76.103226 -96.415606)
		(mid 76.030428 -96.706369)
		(end 76.109576 -96.995488)
		(width 0.0889)
		(layer "In2.Cu")
		(net "M_K_DQS_DP<12>")
	)
	(arc
		(start 70.598792 -100.567236)
		(mid 70.310647 -100.649555)
		(end 70.099936 -100.862638)
		(width 0.0889)
		(layer "In2.Cu")
		(net "M_K_DQS_DP<12>")
	)
	(arc
		(start 71.448676 -100.071936)
		(mid 71.165459 -100.156217)
		(end 70.958456 -100.367084)
		(width 0.0889)
		(layer "In2.Cu")
		(net "M_K_DQS_DP<12>")
	)
	(arc
		(start 74.886566 -98.090736)
		(mid 74.601142 -98.174203)
		(end 74.392536 -98.386138)
		(width 0.0889)
		(layer "In2.Cu")
		(net "M_K_DQS_DP<12>")
	)
	(arc
		(start 74.024236 -98.58629)
		(mid 73.741019 -98.670571)
		(end 73.534016 -98.881438)
		(width 0.0889)
		(layer "In2.Cu")
		(net "M_K_DQS_DP<12>")
	)
	(arc
		(start 72.675496 -99.376738)
		(mid 72.536752 -99.518771)
		(end 72.34682 -99.576636)
		(width 0.0889)
		(layer "In2.Cu")
		(net "M_K_DQS_DP<12>")
	)
	(arc
		(start 75.251056 -97.890838)
		(mid 75.110977 -98.033574)
		(end 74.919332 -98.090736)
		(width 0.0889)
		(layer "In2.Cu")
		(net "M_K_DQS_DP<12>")
	)
	(segment
		(start 73.758806 -95.709486)
		(end 73.187306 -95.709486)
		(width 0.1651)
		(layer "F.Cu")
		(net "M_K_DQS_DP<11>")
	)
	(segment
		(start 53.063394 -134.129272)
		(end 53.000148 -134.26694)
		(width 0.1651)
		(layer "F.Cu")
		(net "M_K_DQS_DP<11>")
	)
	(segment
		(start 52.978812 -135.131302)
		(end 53.060346 -135.355584)
		(width 0.1651)
		(layer "F.Cu")
		(net "M_K_DQS_DP<11>")
	)
	(segment
		(start 52.978812 -134.313168)
		(end 52.978812 -135.131302)
		(width 0.1651)
		(layer "F.Cu")
		(net "M_K_DQS_DP<11>")
	)
	(segment
		(start 53.060346 -135.355584)
		(end 53.442108 -135.737346)
		(width 0.1651)
		(layer "F.Cu")
		(net "M_K_DQS_DP<11>")
	)
	(segment
		(start 53.000148 -134.26694)
		(end 52.978812 -134.313168)
		(width 0.1651)
		(layer "F.Cu")
		(net "M_K_DQS_DP<11>")
	)
	(segment
		(start 53.499512 -133.0706)
		(end 53.499512 -133.693154)
		(width 0.1651)
		(layer "F.Cu")
		(net "M_K_DQS_DP<11>")
	)
	(segment
		(start 53.499512 -133.693154)
		(end 53.063394 -134.129272)
		(width 0.1651)
		(layer "F.Cu")
		(net "M_K_DQS_DP<11>")
	)
	(via
		(at 53.442108 -135.737346)
		(size 0.508)
		(drill 0.254)
		(layers "F.Cu" "B.Cu")
		(net "M_K_DQS_DP<11>")
	)
	(via
		(at 73.187306 -95.709486)
		(size 0.508)
		(drill 0.254)
		(layers "F.Cu" "B.Cu")
		(net "M_K_DQS_DP<11>")
	)
	(via
		(at 53.442108 -130.2258)
		(size 0.508)
		(drill 0.254)
		(layers "F.Cu" "B.Cu")
		(net "M_K_DQS_DP<11>")
	)
	(segment
		(start 53.043328 -131.80187)
		(end 52.966112 -131.669536)
		(width 0.1651)
		(layer "B.Cu")
		(net "M_K_DQS_DP<11>")
	)
	(segment
		(start 53.499512 -132.876036)
		(end 53.499512 -132.258054)
		(width 0.1651)
		(layer "B.Cu")
		(net "M_K_DQS_DP<11>")
	)
	(segment
		(start 52.966112 -131.669536)
		(end 52.966112 -130.773932)
		(width 0.1651)
		(layer "B.Cu")
		(net "M_K_DQS_DP<11>")
	)
	(segment
		(start 52.966112 -130.773932)
		(end 53.053488 -130.61442)
		(width 0.1651)
		(layer "B.Cu")
		(net "M_K_DQS_DP<11>")
	)
	(segment
		(start 53.053488 -130.61442)
		(end 53.442108 -130.2258)
		(width 0.1651)
		(layer "B.Cu")
		(net "M_K_DQS_DP<11>")
	)
	(segment
		(start 53.499512 -132.258054)
		(end 53.043328 -131.80187)
		(width 0.1651)
		(layer "B.Cu")
		(net "M_K_DQS_DP<11>")
	)
	(segment
		(start 57.461658 -102.14737)
		(end 57.461658 -104.554782)
		(width 0.14224)
		(layer "In2.Cu")
		(net "M_K_DQS_DP<11>")
	)
	(segment
		(start 51.692048 -112.11179)
		(end 51.590448 -112.21339)
		(width 0.14224)
		(layer "In2.Cu")
		(net "M_K_DQS_DP<11>")
	)
	(segment
		(start 53.368956 -130.2258)
		(end 52.937156 -130.6576)
		(width 0.14224)
		(layer "In2.Cu")
		(net "M_K_DQS_DP<11>")
	)
	(segment
		(start 73.187306 -95.709486)
		(end 72.89419 -95.540576)
		(width 0.0889)
		(layer "In2.Cu")
		(net "M_K_DQS_DP<11>")
	)
	(segment
		(start 67.120008 -93.609414)
		(end 66.055494 -93.609414)
		(width 0.0889)
		(layer "In2.Cu")
		(net "M_K_DQS_DP<11>")
	)
	(segment
		(start 52.555648 -127.853948)
		(end 53.955188 -129.253488)
		(width 0.14224)
		(layer "In2.Cu")
		(net "M_K_DQS_DP<11>")
	)
	(segment
		(start 66.055494 -93.609414)
		(end 65.497202 -94.167706)
		(width 0.0889)
		(layer "In2.Cu")
		(net "M_K_DQS_DP<11>")
	)
	(segment
		(start 51.692048 -110.324392)
		(end 51.692048 -112.11179)
		(width 0.14224)
		(layer "In2.Cu")
		(net "M_K_DQS_DP<11>")
	)
	(segment
		(start 51.692048 -113.865914)
		(end 52.504086 -114.677952)
		(width 0.14224)
		(layer "In2.Cu")
		(net "M_K_DQS_DP<11>")
	)
	(segment
		(start 67.695572 -93.03385)
		(end 67.120008 -93.609414)
		(width 0.0889)
		(layer "In2.Cu")
		(net "M_K_DQS_DP<11>")
	)
	(segment
		(start 53.721508 -130.2258)
		(end 53.442108 -130.2258)
		(width 0.14224)
		(layer "In2.Cu")
		(net "M_K_DQS_DP<11>")
	)
	(segment
		(start 52.07 -115.78971)
		(end 52.07 -116.479574)
		(width 0.14224)
		(layer "In2.Cu")
		(net "M_K_DQS_DP<11>")
	)
	(segment
		(start 53.955188 -129.253488)
		(end 53.955188 -129.99212)
		(width 0.14224)
		(layer "In2.Cu")
		(net "M_K_DQS_DP<11>")
	)
	(segment
		(start 72.89419 -95.540576)
		(end 72.870314 -95.451422)
		(width 0.0889)
		(layer "In2.Cu")
		(net "M_K_DQS_DP<11>")
	)
	(segment
		(start 57.461658 -104.554782)
		(end 51.692048 -110.324392)
		(width 0.14224)
		(layer "In2.Cu")
		(net "M_K_DQS_DP<11>")
	)
	(segment
		(start 52.937156 -135.232394)
		(end 53.442108 -135.737346)
		(width 0.14224)
		(layer "In2.Cu")
		(net "M_K_DQS_DP<11>")
	)
	(segment
		(start 52.07 -116.479574)
		(end 52.555648 -116.965222)
		(width 0.14224)
		(layer "In2.Cu")
		(net "M_K_DQS_DP<11>")
	)
	(segment
		(start 53.955188 -129.99212)
		(end 53.721508 -130.2258)
		(width 0.14224)
		(layer "In2.Cu")
		(net "M_K_DQS_DP<11>")
	)
	(segment
		(start 52.504086 -115.355624)
		(end 52.07 -115.78971)
		(width 0.14224)
		(layer "In2.Cu")
		(net "M_K_DQS_DP<11>")
	)
	(segment
		(start 52.555648 -116.965222)
		(end 52.555648 -127.853948)
		(width 0.14224)
		(layer "In2.Cu")
		(net "M_K_DQS_DP<11>")
	)
	(segment
		(start 51.590448 -112.67821)
		(end 51.692048 -112.77981)
		(width 0.14224)
		(layer "In2.Cu")
		(net "M_K_DQS_DP<11>")
	)
	(segment
		(start 51.692048 -112.77981)
		(end 51.692048 -113.865914)
		(width 0.14224)
		(layer "In2.Cu")
		(net "M_K_DQS_DP<11>")
	)
	(segment
		(start 69.36359 -93.03385)
		(end 67.695572 -93.03385)
		(width 0.0889)
		(layer "In2.Cu")
		(net "M_K_DQS_DP<11>")
	)
	(segment
		(start 52.504086 -114.677952)
		(end 52.504086 -115.355624)
		(width 0.14224)
		(layer "In2.Cu")
		(net "M_K_DQS_DP<11>")
	)
	(segment
		(start 53.442108 -130.2258)
		(end 53.368956 -130.2258)
		(width 0.14224)
		(layer "In2.Cu")
		(net "M_K_DQS_DP<11>")
	)
	(segment
		(start 51.590448 -112.21339)
		(end 51.590448 -112.67821)
		(width 0.14224)
		(layer "In2.Cu")
		(net "M_K_DQS_DP<11>")
	)
	(segment
		(start 65.441322 -94.167706)
		(end 65.425574 -94.183454)
		(width 0.0889)
		(layer "In2.Cu")
		(net "M_K_DQS_DP<11>")
	)
	(segment
		(start 70.629526 -93.633036)
		(end 70.593712 -93.633036)
		(width 0.0889)
		(layer "In2.Cu")
		(net "M_K_DQS_DP<11>")
	)
	(segment
		(start 65.425574 -94.183454)
		(end 57.461658 -102.14737)
		(width 0.14224)
		(layer "In2.Cu")
		(net "M_K_DQS_DP<11>")
	)
	(segment
		(start 52.937156 -130.6576)
		(end 52.937156 -135.232394)
		(width 0.14224)
		(layer "In2.Cu")
		(net "M_K_DQS_DP<11>")
	)
	(segment
		(start 69.765926 -93.137736)
		(end 69.467476 -93.137736)
		(width 0.0889)
		(layer "In2.Cu")
		(net "M_K_DQS_DP<11>")
	)
	(segment
		(start 71.491856 -94.128336)
		(end 71.452232 -94.128336)
		(width 0.0889)
		(layer "In2.Cu")
		(net "M_K_DQS_DP<11>")
	)
	(segment
		(start 65.497202 -94.167706)
		(end 65.441322 -94.167706)
		(width 0.0889)
		(layer "In2.Cu")
		(net "M_K_DQS_DP<11>")
	)
	(segment
		(start 72.34174 -94.623636)
		(end 72.31761 -94.623636)
		(width 0.0889)
		(layer "In2.Cu")
		(net "M_K_DQS_DP<11>")
	)
	(segment
		(start 69.467476 -93.137736)
		(end 69.36359 -93.03385)
		(width 0.0889)
		(layer "In2.Cu")
		(net "M_K_DQS_DP<11>")
	)
	(arc
		(start 70.593712 -93.633036)
		(mid 70.403783 -93.575166)
		(end 70.265036 -93.433138)
		(width 0.0889)
		(layer "In2.Cu")
		(net "M_K_DQS_DP<11>")
	)
	(arc
		(start 71.123556 -93.928438)
		(mid 70.914948 -93.716506)
		(end 70.629526 -93.633036)
		(width 0.0889)
		(layer "In2.Cu")
		(net "M_K_DQS_DP<11>")
	)
	(arc
		(start 72.870314 -95.451422)
		(mid 72.827022 -94.896362)
		(end 72.34174 -94.623636)
		(width 0.0889)
		(layer "In2.Cu")
		(net "M_K_DQS_DP<11>")
	)
	(arc
		(start 72.31761 -94.623636)
		(mid 72.12376 -94.567286)
		(end 71.982076 -94.423484)
		(width 0.0889)
		(layer "In2.Cu")
		(net "M_K_DQS_DP<11>")
	)
	(arc
		(start 70.265036 -93.433138)
		(mid 70.054213 -93.219995)
		(end 69.765926 -93.137736)
		(width 0.0889)
		(layer "In2.Cu")
		(net "M_K_DQS_DP<11>")
	)
	(arc
		(start 71.452232 -94.128336)
		(mid 71.262303 -94.070466)
		(end 71.123556 -93.928438)
		(width 0.0889)
		(layer "In2.Cu")
		(net "M_K_DQS_DP<11>")
	)
	(arc
		(start 71.982076 -94.423484)
		(mid 71.775072 -94.21262)
		(end 71.491856 -94.128336)
		(width 0.0889)
		(layer "In2.Cu")
		(net "M_K_DQS_DP<11>")
	)
	(segment
		(start 44.149518 -133.693154)
		(end 43.7134 -134.129272)
		(width 0.1651)
		(layer "F.Cu")
		(net "M_K_DQS_DP<10>")
	)
	(segment
		(start 65.856104 -94.08287)
		(end 44.698666 -115.240308)
		(width 0.1651)
		(layer "F.Cu")
		(net "M_K_DQS_DP<10>")
	)
	(segment
		(start 44.644564 -128.564894)
		(end 44.644564 -128.892554)
		(width 0.1651)
		(layer "F.Cu")
		(net "M_K_DQS_DP<10>")
	)
	(segment
		(start 44.549568 -128.215898)
		(end 44.549568 -128.469898)
		(width 0.1651)
		(layer "F.Cu")
		(net "M_K_DQS_DP<10>")
	)
	(segment
		(start 44.549568 -128.469898)
		(end 44.644564 -128.564894)
		(width 0.1651)
		(layer "F.Cu")
		(net "M_K_DQS_DP<10>")
	)
	(segment
		(start 67.582034 -94.128336)
		(end 67.536568 -94.08287)
		(width 0.0889)
		(layer "F.Cu")
		(net "M_K_DQS_DP<10>")
	)
	(segment
		(start 44.644564 -119.733314)
		(end 44.644564 -128.120902)
		(width 0.1651)
		(layer "F.Cu")
		(net "M_K_DQS_DP<10>")
	)
	(segment
		(start 44.552616 -129.238502)
		(end 44.644564 -129.33045)
		(width 0.1651)
		(layer "F.Cu")
		(net "M_K_DQS_DP<10>")
	)
	(segment
		(start 45.36948 -116.338604)
		(end 45.547788 -116.516912)
		(width 0.1651)
		(layer "F.Cu")
		(net "M_K_DQS_DP<10>")
	)
	(segment
		(start 43.710352 -135.355584)
		(end 44.092114 -135.737346)
		(width 0.1651)
		(layer "F.Cu")
		(net "M_K_DQS_DP<10>")
	)
	(segment
		(start 44.644564 -128.892554)
		(end 44.552616 -128.984502)
		(width 0.1651)
		(layer "F.Cu")
		(net "M_K_DQS_DP<10>")
	)
	(segment
		(start 45.31868 -119.384064)
		(end 44.993814 -119.384064)
		(width 0.1651)
		(layer "F.Cu")
		(net "M_K_DQS_DP<10>")
	)
	(segment
		(start 43.628818 -135.131302)
		(end 43.710352 -135.355584)
		(width 0.1651)
		(layer "F.Cu")
		(net "M_K_DQS_DP<10>")
	)
	(segment
		(start 69.060568 -94.17685)
		(end 68.70446 -94.135956)
		(width 0.0889)
		(layer "F.Cu")
		(net "M_K_DQS_DP<10>")
	)
	(segment
		(start 45.044614 -116.338604)
		(end 45.36948 -116.338604)
		(width 0.1651)
		(layer "F.Cu")
		(net "M_K_DQS_DP<10>")
	)
	(segment
		(start 44.339256 -130.2258)
		(end 44.092114 -130.2258)
		(width 0.1651)
		(layer "F.Cu")
		(net "M_K_DQS_DP<10>")
	)
	(segment
		(start 44.698666 -115.240308)
		(end 44.698666 -115.992656)
		(width 0.1651)
		(layer "F.Cu")
		(net "M_K_DQS_DP<10>")
	)
	(segment
		(start 44.644564 -129.33045)
		(end 44.644564 -129.920492)
		(width 0.1651)
		(layer "F.Cu")
		(net "M_K_DQS_DP<10>")
	)
	(segment
		(start 43.650154 -134.26694)
		(end 43.628818 -134.313168)
		(width 0.1651)
		(layer "F.Cu")
		(net "M_K_DQS_DP<10>")
	)
	(segment
		(start 44.644564 -128.120902)
		(end 44.549568 -128.215898)
		(width 0.1651)
		(layer "F.Cu")
		(net "M_K_DQS_DP<10>")
	)
	(segment
		(start 44.698666 -115.992656)
		(end 45.044614 -116.338604)
		(width 0.1651)
		(layer "F.Cu")
		(net "M_K_DQS_DP<10>")
	)
	(segment
		(start 43.7134 -134.129272)
		(end 43.650154 -134.26694)
		(width 0.1651)
		(layer "F.Cu")
		(net "M_K_DQS_DP<10>")
	)
	(segment
		(start 44.149518 -133.0706)
		(end 44.149518 -133.693154)
		(width 0.1651)
		(layer "F.Cu")
		(net "M_K_DQS_DP<10>")
	)
	(segment
		(start 68.629276 -94.128336)
		(end 67.582034 -94.128336)
		(width 0.0889)
		(layer "F.Cu")
		(net "M_K_DQS_DP<10>")
	)
	(segment
		(start 45.547788 -116.516912)
		(end 45.547788 -119.154956)
		(width 0.1651)
		(layer "F.Cu")
		(net "M_K_DQS_DP<10>")
	)
	(segment
		(start 44.552616 -128.984502)
		(end 44.552616 -129.238502)
		(width 0.1651)
		(layer "F.Cu")
		(net "M_K_DQS_DP<10>")
	)
	(segment
		(start 45.547788 -119.154956)
		(end 45.31868 -119.384064)
		(width 0.1651)
		(layer "F.Cu")
		(net "M_K_DQS_DP<10>")
	)
	(segment
		(start 43.628818 -134.313168)
		(end 43.628818 -135.131302)
		(width 0.1651)
		(layer "F.Cu")
		(net "M_K_DQS_DP<10>")
	)
	(segment
		(start 44.644564 -129.920492)
		(end 44.339256 -130.2258)
		(width 0.1651)
		(layer "F.Cu")
		(net "M_K_DQS_DP<10>")
	)
	(segment
		(start 67.536568 -94.08287)
		(end 65.856104 -94.08287)
		(width 0.1651)
		(layer "F.Cu")
		(net "M_K_DQS_DP<10>")
	)
	(segment
		(start 69.466206 -94.223586)
		(end 69.060568 -94.17685)
		(width 0.0889)
		(layer "F.Cu")
		(net "M_K_DQS_DP<10>")
	)
	(segment
		(start 44.993814 -119.384064)
		(end 44.644564 -119.733314)
		(width 0.1651)
		(layer "F.Cu")
		(net "M_K_DQS_DP<10>")
	)
	(via
		(at 44.092114 -130.2258)
		(size 0.508)
		(drill 0.254)
		(layers "F.Cu" "B.Cu")
		(net "M_K_DQS_DP<10>")
	)
	(via
		(at 44.092114 -135.737346)
		(size 0.508)
		(drill 0.254)
		(layers "F.Cu" "B.Cu")
		(net "M_K_DQS_DP<10>")
	)
	(arc
		(start 68.70446 -94.135956)
		(mid 68.66699 -94.130945)
		(end 68.629276 -94.128336)
		(width 0.0889)
		(layer "F.Cu")
		(net "M_K_DQS_DP<10>")
	)
	(segment
		(start 43.693334 -131.80187)
		(end 43.616118 -131.669536)
		(width 0.1651)
		(layer "B.Cu")
		(net "M_K_DQS_DP<10>")
	)
	(segment
		(start 43.703494 -130.61442)
		(end 44.092114 -130.2258)
		(width 0.1651)
		(layer "B.Cu")
		(net "M_K_DQS_DP<10>")
	)
	(segment
		(start 43.616118 -130.773932)
		(end 43.703494 -130.61442)
		(width 0.1651)
		(layer "B.Cu")
		(net "M_K_DQS_DP<10>")
	)
	(segment
		(start 43.616118 -131.669536)
		(end 43.616118 -130.773932)
		(width 0.1651)
		(layer "B.Cu")
		(net "M_K_DQS_DP<10>")
	)
	(segment
		(start 44.149518 -132.876036)
		(end 44.149518 -132.258054)
		(width 0.1651)
		(layer "B.Cu")
		(net "M_K_DQS_DP<10>")
	)
	(segment
		(start 44.149518 -132.258054)
		(end 43.693334 -131.80187)
		(width 0.1651)
		(layer "B.Cu")
		(net "M_K_DQS_DP<10>")
	)
	(segment
		(start 43.587162 -135.232394)
		(end 43.587162 -130.6576)
		(width 0.14224)
		(layer "In2.Cu")
		(net "M_K_DQS_DP<10>")
	)
	(segment
		(start 44.018962 -130.2258)
		(end 44.092114 -130.2258)
		(width 0.14224)
		(layer "In2.Cu")
		(net "M_K_DQS_DP<10>")
	)
	(segment
		(start 44.092114 -135.737346)
		(end 43.587162 -135.232394)
		(width 0.14224)
		(layer "In2.Cu")
		(net "M_K_DQS_DP<10>")
	)
	(segment
		(start 43.587162 -130.6576)
		(end 44.018962 -130.2258)
		(width 0.14224)
		(layer "In2.Cu")
		(net "M_K_DQS_DP<10>")
	)
	(segment
		(start 36.537392 -135.255)
		(end 36.293552 -135.01116)
		(width 0.1651)
		(layer "F.Cu")
		(net "M_K_DQS_DP<0>")
	)
	(segment
		(start 36.499546 -136.664446)
		(end 36.537392 -136.6266)
		(width 0.1651)
		(layer "F.Cu")
		(net "M_K_DQS_DP<0>")
	)
	(segment
		(start 36.293552 -135.01116)
		(end 36.03752 -135.01116)
		(width 0.1651)
		(layer "F.Cu")
		(net "M_K_DQS_DP<0>")
	)
	(segment
		(start 68.607686 -87.784686)
		(end 68.036186 -87.784686)
		(width 0.1651)
		(layer "F.Cu")
		(net "M_K_DQS_DP<0>")
	)
	(segment
		(start 36.537392 -136.6266)
		(end 36.537392 -135.255)
		(width 0.1651)
		(layer "F.Cu")
		(net "M_K_DQS_DP<0>")
	)
	(segment
		(start 36.499546 -137.67054)
		(end 36.499546 -136.664446)
		(width 0.1651)
		(layer "F.Cu")
		(net "M_K_DQS_DP<0>")
	)
	(via
		(at 36.03752 -130.940556)
		(size 0.508)
		(drill 0.254)
		(layers "F.Cu" "B.Cu")
		(net "M_K_DQS_DP<0>")
	)
	(via
		(at 68.036186 -87.784686)
		(size 0.508)
		(drill 0.254)
		(layers "F.Cu" "B.Cu")
		(net "M_K_DQS_DP<0>")
	)
	(via
		(at 36.03752 -135.01116)
		(size 0.508)
		(drill 0.254)
		(layers "F.Cu" "B.Cu")
		(net "M_K_DQS_DP<0>")
	)
	(segment
		(start 36.279836 -130.940556)
		(end 36.03752 -130.940556)
		(width 0.1651)
		(layer "B.Cu")
		(net "M_K_DQS_DP<0>")
	)
	(segment
		(start 36.537392 -130.683)
		(end 36.279836 -130.940556)
		(width 0.1651)
		(layer "B.Cu")
		(net "M_K_DQS_DP<0>")
	)
	(segment
		(start 36.537392 -129.4638)
		(end 36.537392 -130.683)
		(width 0.1651)
		(layer "B.Cu")
		(net "M_K_DQS_DP<0>")
	)
	(segment
		(start 36.499546 -129.425954)
		(end 36.537392 -129.4638)
		(width 0.1651)
		(layer "B.Cu")
		(net "M_K_DQS_DP<0>")
	)
	(segment
		(start 36.499546 -128.276096)
		(end 36.499546 -129.425954)
		(width 0.1651)
		(layer "B.Cu")
		(net "M_K_DQS_DP<0>")
	)
	(segment
		(start 36.504372 -130.549396)
		(end 36.42868 -130.549396)
		(width 0.14224)
		(layer "In2.Cu")
		(net "M_K_DQS_DP<0>")
	)
	(segment
		(start 65.996566 -87.563198)
		(end 65.733676 -87.563198)
		(width 0.0889)
		(layer "In2.Cu")
		(net "M_K_DQS_DP<0>")
	)
	(segment
		(start 35.66287 -133.435852)
		(end 35.80003 -133.298692)
		(width 0.14224)
		(layer "In2.Cu")
		(net "M_K_DQS_DP<0>")
	)
	(segment
		(start 36.472368 -131.8006)
		(end 36.472368 -131.375404)
		(width 0.14224)
		(layer "In2.Cu")
		(net "M_K_DQS_DP<0>")
	)
	(segment
		(start 36.619688 -124.21108)
		(end 36.841176 -124.432568)
		(width 0.14224)
		(layer "In2.Cu")
		(net "M_K_DQS_DP<0>")
	)
	(segment
		(start 37.559488 -127.810768)
		(end 36.822888 -128.547368)
		(width 0.14224)
		(layer "In2.Cu")
		(net "M_K_DQS_DP<0>")
	)
	(segment
		(start 36.035488 -133.123432)
		(end 36.035488 -132.83692)
		(width 0.14224)
		(layer "In2.Cu")
		(net "M_K_DQS_DP<0>")
	)
	(segment
		(start 37.181282 -124.432568)
		(end 37.559488 -124.810774)
		(width 0.14224)
		(layer "In2.Cu")
		(net "M_K_DQS_DP<0>")
	)
	(segment
		(start 36.218368 -132.0546)
		(end 36.472368 -131.8006)
		(width 0.14224)
		(layer "In2.Cu")
		(net "M_K_DQS_DP<0>")
	)
	(segment
		(start 37.181282 -122.146568)
		(end 37.559488 -122.524774)
		(width 0.14224)
		(layer "In2.Cu")
		(net "M_K_DQS_DP<0>")
	)
	(segment
		(start 37.559488 -115.490752)
		(end 37.559488 -120.89384)
		(width 0.14224)
		(layer "In2.Cu")
		(net "M_K_DQS_DP<0>")
	)
	(segment
		(start 35.777678 -132.6642)
		(end 35.66287 -132.549392)
		(width 0.14224)
		(layer "In2.Cu")
		(net "M_K_DQS_DP<0>")
	)
	(segment
		(start 37.559488 -120.89384)
		(end 37.18052 -121.272808)
		(width 0.14224)
		(layer "In2.Cu")
		(net "M_K_DQS_DP<0>")
	)
	(segment
		(start 37.08781 -126.718568)
		(end 37.559488 -127.190246)
		(width 0.14224)
		(layer "In2.Cu")
		(net "M_K_DQS_DP<0>")
	)
	(segment
		(start 37.181282 -125.844808)
		(end 36.790376 -125.844808)
		(width 0.14224)
		(layer "In2.Cu")
		(net "M_K_DQS_DP<0>")
	)
	(segment
		(start 37.181282 -123.558808)
		(end 36.841176 -123.558808)
		(width 0.14224)
		(layer "In2.Cu")
		(net "M_K_DQS_DP<0>")
	)
	(segment
		(start 37.559488 -125.466602)
		(end 37.181282 -125.844808)
		(width 0.14224)
		(layer "In2.Cu")
		(net "M_K_DQS_DP<0>")
	)
	(segment
		(start 36.497768 -134.112)
		(end 36.243768 -133.858)
		(width 0.14224)
		(layer "In2.Cu")
		(net "M_K_DQS_DP<0>")
	)
	(segment
		(start 35.862768 -132.6642)
		(end 35.777678 -132.6642)
		(width 0.14224)
		(layer "In2.Cu")
		(net "M_K_DQS_DP<0>")
	)
	(segment
		(start 68.329302 -87.615776)
		(end 68.349368 -87.540846)
		(width 0.0889)
		(layer "In2.Cu")
		(net "M_K_DQS_DP<0>")
	)
	(segment
		(start 37.559488 -122.524774)
		(end 37.559488 -123.180602)
		(width 0.14224)
		(layer "In2.Cu")
		(net "M_K_DQS_DP<0>")
	)
	(segment
		(start 36.891976 -122.146568)
		(end 37.181282 -122.146568)
		(width 0.14224)
		(layer "In2.Cu")
		(net "M_K_DQS_DP<0>")
	)
	(segment
		(start 36.822888 -128.547368)
		(end 36.822888 -130.23088)
		(width 0.14224)
		(layer "In2.Cu")
		(net "M_K_DQS_DP<0>")
	)
	(segment
		(start 35.858704 -133.858)
		(end 35.66287 -133.662166)
		(width 0.14224)
		(layer "In2.Cu")
		(net "M_K_DQS_DP<0>")
	)
	(segment
		(start 36.035488 -132.83692)
		(end 35.862768 -132.6642)
		(width 0.14224)
		(layer "In2.Cu")
		(net "M_K_DQS_DP<0>")
	)
	(segment
		(start 36.891976 -121.272808)
		(end 36.670488 -121.494296)
		(width 0.14224)
		(layer "In2.Cu")
		(net "M_K_DQS_DP<0>")
	)
	(segment
		(start 52.855368 -101.219)
		(end 39.473632 -114.600736)
		(width 0.14224)
		(layer "In2.Cu")
		(net "M_K_DQS_DP<0>")
	)
	(segment
		(start 35.860228 -133.298692)
		(end 36.035488 -133.123432)
		(width 0.14224)
		(layer "In2.Cu")
		(net "M_K_DQS_DP<0>")
	)
	(segment
		(start 52.855368 -99.625404)
		(end 52.855368 -101.219)
		(width 0.14224)
		(layer "In2.Cu")
		(net "M_K_DQS_DP<0>")
	)
	(segment
		(start 36.841176 -124.432568)
		(end 37.181282 -124.432568)
		(width 0.14224)
		(layer "In2.Cu")
		(net "M_K_DQS_DP<0>")
	)
	(segment
		(start 35.66287 -132.549392)
		(end 35.66287 -132.225034)
		(width 0.14224)
		(layer "In2.Cu")
		(net "M_K_DQS_DP<0>")
	)
	(segment
		(start 37.559488 -123.180602)
		(end 37.181282 -123.558808)
		(width 0.14224)
		(layer "In2.Cu")
		(net "M_K_DQS_DP<0>")
	)
	(segment
		(start 65.733676 -87.563198)
		(end 65.698116 -87.598758)
		(width 0.0889)
		(layer "In2.Cu")
		(net "M_K_DQS_DP<0>")
	)
	(segment
		(start 65.698116 -87.598758)
		(end 64.882014 -87.598758)
		(width 0.14224)
		(layer "In2.Cu")
		(net "M_K_DQS_DP<0>")
	)
	(segment
		(start 36.472368 -131.375404)
		(end 36.03752 -130.940556)
		(width 0.14224)
		(layer "In2.Cu")
		(net "M_K_DQS_DP<0>")
	)
	(segment
		(start 38.449504 -114.600736)
		(end 37.559488 -115.490752)
		(width 0.14224)
		(layer "In2.Cu")
		(net "M_K_DQS_DP<0>")
	)
	(segment
		(start 68.349368 -87.540846)
		(end 68.350384 -87.537036)
		(width 0.0889)
		(layer "In2.Cu")
		(net "M_K_DQS_DP<0>")
	)
	(segment
		(start 36.670488 -121.494296)
		(end 36.670488 -121.92508)
		(width 0.14224)
		(layer "In2.Cu")
		(net "M_K_DQS_DP<0>")
	)
	(segment
		(start 68.047362 -87.384636)
		(end 67.869816 -87.384636)
		(width 0.0889)
		(layer "In2.Cu")
		(net "M_K_DQS_DP<0>")
	)
	(segment
		(start 35.66287 -133.662166)
		(end 35.66287 -133.435852)
		(width 0.14224)
		(layer "In2.Cu")
		(net "M_K_DQS_DP<0>")
	)
	(segment
		(start 39.473632 -114.600736)
		(end 38.449504 -114.600736)
		(width 0.14224)
		(layer "In2.Cu")
		(net "M_K_DQS_DP<0>")
	)
	(segment
		(start 36.790376 -126.718568)
		(end 37.08781 -126.718568)
		(width 0.14224)
		(layer "In2.Cu")
		(net "M_K_DQS_DP<0>")
	)
	(segment
		(start 36.568888 -126.49708)
		(end 36.790376 -126.718568)
		(width 0.14224)
		(layer "In2.Cu")
		(net "M_K_DQS_DP<0>")
	)
	(segment
		(start 37.559488 -127.190246)
		(end 37.559488 -127.810768)
		(width 0.14224)
		(layer "In2.Cu")
		(net "M_K_DQS_DP<0>")
	)
	(segment
		(start 37.18052 -121.272808)
		(end 36.891976 -121.272808)
		(width 0.14224)
		(layer "In2.Cu")
		(net "M_K_DQS_DP<0>")
	)
	(segment
		(start 36.790376 -125.844808)
		(end 36.568888 -126.066296)
		(width 0.14224)
		(layer "In2.Cu")
		(net "M_K_DQS_DP<0>")
	)
	(segment
		(start 36.619688 -123.780296)
		(end 36.619688 -124.21108)
		(width 0.14224)
		(layer "In2.Cu")
		(net "M_K_DQS_DP<0>")
	)
	(segment
		(start 36.841176 -123.558808)
		(end 36.619688 -123.780296)
		(width 0.14224)
		(layer "In2.Cu")
		(net "M_K_DQS_DP<0>")
	)
	(segment
		(start 35.66287 -132.225034)
		(end 35.833304 -132.0546)
		(width 0.14224)
		(layer "In2.Cu")
		(net "M_K_DQS_DP<0>")
	)
	(segment
		(start 35.80003 -133.298692)
		(end 35.860228 -133.298692)
		(width 0.14224)
		(layer "In2.Cu")
		(net "M_K_DQS_DP<0>")
	)
	(segment
		(start 36.42868 -130.549396)
		(end 36.03752 -130.940556)
		(width 0.14224)
		(layer "In2.Cu")
		(net "M_K_DQS_DP<0>")
	)
	(segment
		(start 36.568888 -126.066296)
		(end 36.568888 -126.49708)
		(width 0.14224)
		(layer "In2.Cu")
		(net "M_K_DQS_DP<0>")
	)
	(segment
		(start 36.03752 -135.01116)
		(end 36.497768 -134.550912)
		(width 0.14224)
		(layer "In2.Cu")
		(net "M_K_DQS_DP<0>")
	)
	(segment
		(start 66.831464 -87.88019)
		(end 66.514472 -87.563198)
		(width 0.0889)
		(layer "In2.Cu")
		(net "M_K_DQS_DP<0>")
	)
	(segment
		(start 68.036186 -87.784686)
		(end 68.329302 -87.615776)
		(width 0.0889)
		(layer "In2.Cu")
		(net "M_K_DQS_DP<0>")
	)
	(segment
		(start 66.063368 -87.63)
		(end 65.996566 -87.563198)
		(width 0.0889)
		(layer "In2.Cu")
		(net "M_K_DQS_DP<0>")
	)
	(segment
		(start 35.833304 -132.0546)
		(end 36.218368 -132.0546)
		(width 0.14224)
		(layer "In2.Cu")
		(net "M_K_DQS_DP<0>")
	)
	(segment
		(start 36.243768 -133.858)
		(end 35.858704 -133.858)
		(width 0.14224)
		(layer "In2.Cu")
		(net "M_K_DQS_DP<0>")
	)
	(segment
		(start 66.317368 -87.563198)
		(end 66.250566 -87.63)
		(width 0.0889)
		(layer "In2.Cu")
		(net "M_K_DQS_DP<0>")
	)
	(segment
		(start 66.250566 -87.63)
		(end 66.063368 -87.63)
		(width 0.0889)
		(layer "In2.Cu")
		(net "M_K_DQS_DP<0>")
	)
	(segment
		(start 64.882014 -87.598758)
		(end 52.855368 -99.625404)
		(width 0.14224)
		(layer "In2.Cu")
		(net "M_K_DQS_DP<0>")
	)
	(segment
		(start 66.514472 -87.563198)
		(end 66.317368 -87.563198)
		(width 0.0889)
		(layer "In2.Cu")
		(net "M_K_DQS_DP<0>")
	)
	(segment
		(start 36.670488 -121.92508)
		(end 36.891976 -122.146568)
		(width 0.14224)
		(layer "In2.Cu")
		(net "M_K_DQS_DP<0>")
	)
	(segment
		(start 67.304158 -87.88019)
		(end 66.831464 -87.88019)
		(width 0.0889)
		(layer "In2.Cu")
		(net "M_K_DQS_DP<0>")
	)
	(segment
		(start 37.559488 -124.810774)
		(end 37.559488 -125.466602)
		(width 0.14224)
		(layer "In2.Cu")
		(net "M_K_DQS_DP<0>")
	)
	(segment
		(start 36.822888 -130.23088)
		(end 36.504372 -130.549396)
		(width 0.14224)
		(layer "In2.Cu")
		(net "M_K_DQS_DP<0>")
	)
	(segment
		(start 36.497768 -134.550912)
		(end 36.497768 -134.112)
		(width 0.14224)
		(layer "In2.Cu")
		(net "M_K_DQS_DP<0>")
	)
	(arc
		(start 68.350384 -87.537036)
		(mid 68.293307 -87.478143)
		(end 68.225416 -87.432134)
		(width 0.0889)
		(layer "In2.Cu")
		(net "M_K_DQS_DP<0>")
	)
	(arc
		(start 67.869816 -87.384636)
		(mid 67.744329 -87.464469)
		(end 67.653154 -87.581994)
		(width 0.0889)
		(layer "In2.Cu")
		(net "M_K_DQS_DP<0>")
	)
	(arc
		(start 67.653154 -87.581994)
		(mid 67.507054 -87.764328)
		(end 67.304158 -87.88019)
		(width 0.0889)
		(layer "In2.Cu")
		(net "M_K_DQS_DP<0>")
	)
	(arc
		(start 68.225416 -87.432134)
		(mid 68.139162 -87.397981)
		(end 68.047362 -87.384636)
		(width 0.0889)
		(layer "In2.Cu")
		(net "M_K_DQS_DP<0>")
	)
	(segment
		(start 35.165284 -135.25373)
		(end 34.957004 -135.25373)
		(width 0.1651)
		(layer "F.Cu")
		(net "M_K_DQS_DN<9>")
	)
	(segment
		(start 35.649408 -133.729984)
		(end 35.231324 -134.148068)
		(width 0.1651)
		(layer "F.Cu")
		(net "M_K_DQS_DN<9>")
	)
	(segment
		(start 35.231324 -134.148068)
		(end 35.231324 -134.5692)
		(width 0.1651)
		(layer "F.Cu")
		(net "M_K_DQS_DN<9>")
	)
	(segment
		(start 34.767774 -135.0645)
		(end 34.748724 -135.0645)
		(width 0.1651)
		(layer "F.Cu")
		(net "M_K_DQS_DN<9>")
	)
	(segment
		(start 34.957004 -135.25373)
		(end 34.767774 -135.0645)
		(width 0.1651)
		(layer "F.Cu")
		(net "M_K_DQS_DN<9>")
	)
	(segment
		(start 35.231324 -134.5692)
		(end 35.417252 -134.755128)
		(width 0.1651)
		(layer "F.Cu")
		(net "M_K_DQS_DN<9>")
	)
	(segment
		(start 35.417252 -135.001762)
		(end 35.165284 -135.25373)
		(width 0.1651)
		(layer "F.Cu")
		(net "M_K_DQS_DN<9>")
	)
	(segment
		(start 35.417252 -134.755128)
		(end 35.417252 -135.001762)
		(width 0.1651)
		(layer "F.Cu")
		(net "M_K_DQS_DN<9>")
	)
	(segment
		(start 69.466206 -86.29904)
		(end 68.894706 -86.29904)
		(width 0.1651)
		(layer "F.Cu")
		(net "M_K_DQS_DN<9>")
	)
	(segment
		(start 35.649408 -133.0706)
		(end 35.649408 -133.729984)
		(width 0.1651)
		(layer "F.Cu")
		(net "M_K_DQS_DN<9>")
	)
	(via
		(at 68.894706 -86.29904)
		(size 0.508)
		(drill 0.254)
		(layers "F.Cu" "B.Cu")
		(net "M_K_DQS_DN<9>")
	)
	(via
		(at 34.748724 -135.0645)
		(size 0.508)
		(drill 0.254)
		(layers "F.Cu" "B.Cu")
		(net "M_K_DQS_DN<9>")
	)
	(via
		(at 34.74212 -130.8862)
		(size 0.508)
		(drill 0.254)
		(layers "F.Cu" "B.Cu")
		(net "M_K_DQS_DN<9>")
	)
	(segment
		(start 34.936684 -130.691636)
		(end 34.74212 -130.8862)
		(width 0.1651)
		(layer "B.Cu")
		(net "M_K_DQS_DN<9>")
	)
	(segment
		(start 35.649408 -132.876036)
		(end 35.649662 -132.875528)
		(width 0.1651)
		(layer "B.Cu")
		(net "M_K_DQS_DN<9>")
	)
	(segment
		(start 35.383724 -130.9116)
		(end 35.16376 -130.691636)
		(width 0.1651)
		(layer "B.Cu")
		(net "M_K_DQS_DN<9>")
	)
	(segment
		(start 35.649662 -132.875528)
		(end 35.649662 -132.219192)
		(width 0.1651)
		(layer "B.Cu")
		(net "M_K_DQS_DN<9>")
	)
	(segment
		(start 35.649662 -132.219192)
		(end 35.205924 -131.775454)
		(width 0.1651)
		(layer "B.Cu")
		(net "M_K_DQS_DN<9>")
	)
	(segment
		(start 35.383724 -131.2418)
		(end 35.383724 -130.9116)
		(width 0.1651)
		(layer "B.Cu")
		(net "M_K_DQS_DN<9>")
	)
	(segment
		(start 35.16376 -130.691636)
		(end 34.936684 -130.691636)
		(width 0.1651)
		(layer "B.Cu")
		(net "M_K_DQS_DN<9>")
	)
	(segment
		(start 35.205924 -131.4196)
		(end 35.383724 -131.2418)
		(width 0.1651)
		(layer "B.Cu")
		(net "M_K_DQS_DN<9>")
	)
	(segment
		(start 35.205924 -131.775454)
		(end 35.205924 -131.4196)
		(width 0.1651)
		(layer "B.Cu")
		(net "M_K_DQS_DN<9>")
	)
	(segment
		(start 67.195446 -86.88959)
		(end 66.849244 -86.88959)
		(width 0.0889)
		(layer "In2.Cu")
		(net "M_K_DQS_DN<9>")
	)
	(segment
		(start 35.176968 -131.7244)
		(end 34.897568 -132.0038)
		(width 0.14224)
		(layer "In2.Cu")
		(net "M_K_DQS_DN<9>")
	)
	(segment
		(start 36.543488 -117.557042)
		(end 36.18992 -117.91061)
		(width 0.14224)
		(layer "In2.Cu")
		(net "M_K_DQS_DN<9>")
	)
	(segment
		(start 34.948368 -132.78866)
		(end 34.948368 -133.14172)
		(width 0.14224)
		(layer "In2.Cu")
		(net "M_K_DQS_DN<9>")
	)
	(segment
		(start 34.948368 -133.14172)
		(end 34.793428 -133.29666)
		(width 0.14224)
		(layer "In2.Cu")
		(net "M_K_DQS_DN<9>")
	)
	(segment
		(start 35.176968 -131.321048)
		(end 35.176968 -131.7244)
		(width 0.14224)
		(layer "In2.Cu")
		(net "M_K_DQS_DN<9>")
	)
	(segment
		(start 34.74212 -130.8862)
		(end 35.176968 -131.321048)
		(width 0.14224)
		(layer "In2.Cu")
		(net "M_K_DQS_DN<9>")
	)
	(segment
		(start 35.578288 -120.443498)
		(end 35.578288 -130.050032)
		(width 0.14224)
		(layer "In2.Cu")
		(net "M_K_DQS_DN<9>")
	)
	(segment
		(start 36.592256 -119.818404)
		(end 36.21405 -120.19661)
		(width 0.14224)
		(layer "In2.Cu")
		(net "M_K_DQS_DN<9>")
	)
	(segment
		(start 34.668968 -133.9596)
		(end 34.994088 -133.9596)
		(width 0.14224)
		(layer "In2.Cu")
		(net "M_K_DQS_DN<9>")
	)
	(segment
		(start 66.566034 -86.60638)
		(end 65.836292 -86.60638)
		(width 0.0889)
		(layer "In2.Cu")
		(net "M_K_DQS_DN<9>")
	)
	(segment
		(start 34.646108 -133.29666)
		(end 34.506408 -133.43636)
		(width 0.14224)
		(layer "In2.Cu")
		(net "M_K_DQS_DN<9>")
	)
	(segment
		(start 36.543488 -116.826538)
		(end 36.543488 -117.557042)
		(width 0.14224)
		(layer "In2.Cu")
		(net "M_K_DQS_DN<9>")
	)
	(segment
		(start 52.042568 -100.939346)
		(end 39.139114 -113.8428)
		(width 0.14224)
		(layer "In2.Cu")
		(net "M_K_DQS_DN<9>")
	)
	(segment
		(start 35.825176 -120.19661)
		(end 35.578288 -120.443498)
		(width 0.14224)
		(layer "In2.Cu")
		(net "M_K_DQS_DN<9>")
	)
	(segment
		(start 36.21405 -120.19661)
		(end 35.825176 -120.19661)
		(width 0.14224)
		(layer "In2.Cu")
		(net "M_K_DQS_DN<9>")
	)
	(segment
		(start 34.994088 -133.9596)
		(end 35.181794 -134.147306)
		(width 0.14224)
		(layer "In2.Cu")
		(net "M_K_DQS_DN<9>")
	)
	(segment
		(start 36.592256 -119.086376)
		(end 36.592256 -119.818404)
		(width 0.14224)
		(layer "In2.Cu")
		(net "M_K_DQS_DN<9>")
	)
	(segment
		(start 35.832288 -116.378482)
		(end 35.952176 -116.49837)
		(width 0.14224)
		(layer "In2.Cu")
		(net "M_K_DQS_DN<9>")
	)
	(segment
		(start 34.638488 -132.63372)
		(end 34.793428 -132.63372)
		(width 0.14224)
		(layer "In2.Cu")
		(net "M_K_DQS_DN<9>")
	)
	(segment
		(start 52.042568 -99.379786)
		(end 52.042568 -100.939346)
		(width 0.14224)
		(layer "In2.Cu")
		(net "M_K_DQS_DN<9>")
	)
	(segment
		(start 34.506408 -133.79704)
		(end 34.668968 -133.9596)
		(width 0.14224)
		(layer "In2.Cu")
		(net "M_K_DQS_DN<9>")
	)
	(segment
		(start 68.349368 -86.355682)
		(end 68.20027 -86.371176)
		(width 0.0889)
		(layer "In2.Cu")
		(net "M_K_DQS_DN<9>")
	)
	(segment
		(start 68.894706 -86.29904)
		(end 68.501768 -86.339934)
		(width 0.0889)
		(layer "In2.Cu")
		(net "M_K_DQS_DN<9>")
	)
	(segment
		(start 34.506408 -133.43636)
		(end 34.506408 -133.79704)
		(width 0.14224)
		(layer "In2.Cu")
		(net "M_K_DQS_DN<9>")
	)
	(segment
		(start 35.578288 -130.050032)
		(end 34.74212 -130.8862)
		(width 0.14224)
		(layer "In2.Cu")
		(net "M_K_DQS_DN<9>")
	)
	(segment
		(start 36.21532 -116.49837)
		(end 36.220908 -116.503704)
		(width 0.14224)
		(layer "In2.Cu")
		(net "M_K_DQS_DN<9>")
	)
	(segment
		(start 35.952176 -118.78437)
		(end 36.29025 -118.78437)
		(width 0.14224)
		(layer "In2.Cu")
		(net "M_K_DQS_DN<9>")
	)
	(segment
		(start 35.952176 -116.49837)
		(end 36.21532 -116.49837)
		(width 0.14224)
		(layer "In2.Cu")
		(net "M_K_DQS_DN<9>")
	)
	(segment
		(start 35.730688 -118.081298)
		(end 35.730688 -118.562882)
		(width 0.14224)
		(layer "In2.Cu")
		(net "M_K_DQS_DN<9>")
	)
	(segment
		(start 35.181794 -134.147306)
		(end 35.181794 -134.63143)
		(width 0.14224)
		(layer "In2.Cu")
		(net "M_K_DQS_DN<9>")
	)
	(segment
		(start 65.789048 -86.653624)
		(end 64.76873 -86.653624)
		(width 0.14224)
		(layer "In2.Cu")
		(net "M_K_DQS_DN<9>")
	)
	(segment
		(start 38.148514 -113.8428)
		(end 35.832288 -116.159026)
		(width 0.14224)
		(layer "In2.Cu")
		(net "M_K_DQS_DN<9>")
	)
	(segment
		(start 35.181794 -134.63143)
		(end 34.748724 -135.0645)
		(width 0.14224)
		(layer "In2.Cu")
		(net "M_K_DQS_DN<9>")
	)
	(segment
		(start 65.836292 -86.60638)
		(end 65.789048 -86.653624)
		(width 0.0889)
		(layer "In2.Cu")
		(net "M_K_DQS_DN<9>")
	)
	(segment
		(start 64.76873 -86.653624)
		(end 52.042568 -99.379786)
		(width 0.14224)
		(layer "In2.Cu")
		(net "M_K_DQS_DN<9>")
	)
	(segment
		(start 68.501768 -86.339934)
		(end 68.349368 -86.355682)
		(width 0.0889)
		(layer "In2.Cu")
		(net "M_K_DQS_DN<9>")
	)
	(segment
		(start 34.506408 -132.50164)
		(end 34.638488 -132.63372)
		(width 0.14224)
		(layer "In2.Cu")
		(net "M_K_DQS_DN<9>")
	)
	(segment
		(start 34.897568 -132.0038)
		(end 34.656268 -132.0038)
		(width 0.14224)
		(layer "In2.Cu")
		(net "M_K_DQS_DN<9>")
	)
	(segment
		(start 34.793428 -132.63372)
		(end 34.948368 -132.78866)
		(width 0.14224)
		(layer "In2.Cu")
		(net "M_K_DQS_DN<9>")
	)
	(segment
		(start 34.506408 -132.15366)
		(end 34.506408 -132.50164)
		(width 0.14224)
		(layer "In2.Cu")
		(net "M_K_DQS_DN<9>")
	)
	(segment
		(start 35.832288 -116.159026)
		(end 35.832288 -116.378482)
		(width 0.14224)
		(layer "In2.Cu")
		(net "M_K_DQS_DN<9>")
	)
	(segment
		(start 66.849244 -86.88959)
		(end 66.566034 -86.60638)
		(width 0.0889)
		(layer "In2.Cu")
		(net "M_K_DQS_DN<9>")
	)
	(segment
		(start 39.139114 -113.8428)
		(end 38.148514 -113.8428)
		(width 0.14224)
		(layer "In2.Cu")
		(net "M_K_DQS_DN<9>")
	)
	(segment
		(start 34.793428 -133.29666)
		(end 34.646108 -133.29666)
		(width 0.14224)
		(layer "In2.Cu")
		(net "M_K_DQS_DN<9>")
	)
	(segment
		(start 36.220908 -116.503704)
		(end 36.543488 -116.826538)
		(width 0.14224)
		(layer "In2.Cu")
		(net "M_K_DQS_DN<9>")
	)
	(segment
		(start 36.18992 -117.91061)
		(end 35.901376 -117.91061)
		(width 0.14224)
		(layer "In2.Cu")
		(net "M_K_DQS_DN<9>")
	)
	(segment
		(start 68.057776 -86.394036)
		(end 68.02501 -86.394036)
		(width 0.0889)
		(layer "In2.Cu")
		(net "M_K_DQS_DN<9>")
	)
	(segment
		(start 34.656268 -132.0038)
		(end 34.506408 -132.15366)
		(width 0.14224)
		(layer "In2.Cu")
		(net "M_K_DQS_DN<9>")
	)
	(segment
		(start 35.730688 -118.562882)
		(end 35.952176 -118.78437)
		(width 0.14224)
		(layer "In2.Cu")
		(net "M_K_DQS_DN<9>")
	)
	(segment
		(start 36.29025 -118.78437)
		(end 36.592256 -119.086376)
		(width 0.14224)
		(layer "In2.Cu")
		(net "M_K_DQS_DN<9>")
	)
	(segment
		(start 35.901376 -117.91061)
		(end 35.730688 -118.081298)
		(width 0.14224)
		(layer "In2.Cu")
		(net "M_K_DQS_DN<9>")
	)
	(arc
		(start 67.689476 -86.594188)
		(mid 67.480868 -86.80612)
		(end 67.195446 -86.88959)
		(width 0.0889)
		(layer "In2.Cu")
		(net "M_K_DQS_DN<9>")
	)
	(arc
		(start 68.02501 -86.394036)
		(mid 67.83116 -86.450386)
		(end 67.689476 -86.594188)
		(width 0.0889)
		(layer "In2.Cu")
		(net "M_K_DQS_DN<9>")
	)
	(arc
		(start 68.20027 -86.371176)
		(mid 68.129723 -86.386964)
		(end 68.057776 -86.394036)
		(width 0.0889)
		(layer "In2.Cu")
		(net "M_K_DQS_DN<9>")
	)
	(segment
		(start 73.049384 -137.67054)
		(end 73.049384 -136.60247)
		(width 0.1651)
		(layer "F.Cu")
		(net "M_K_DQS_DN<8>")
	)
	(segment
		(start 72.667368 -135.788654)
		(end 72.997822 -135.4582)
		(width 0.1651)
		(layer "F.Cu")
		(net "M_K_DQS_DN<8>")
	)
	(segment
		(start 72.997822 -135.4582)
		(end 73.22185 -135.4582)
		(width 0.1651)
		(layer "F.Cu")
		(net "M_K_DQS_DN<8>")
	)
	(segment
		(start 73.049384 -136.60247)
		(end 72.667368 -136.220454)
		(width 0.1651)
		(layer "F.Cu")
		(net "M_K_DQS_DN<8>")
	)
	(segment
		(start 84.060792 -91.747086)
		(end 83.489292 -91.747086)
		(width 0.1651)
		(layer "F.Cu")
		(net "M_K_DQS_DN<8>")
	)
	(segment
		(start 73.22185 -135.4582)
		(end 73.437496 -135.673846)
		(width 0.1651)
		(layer "F.Cu")
		(net "M_K_DQS_DN<8>")
	)
	(segment
		(start 72.667368 -136.220454)
		(end 72.667368 -135.788654)
		(width 0.1651)
		(layer "F.Cu")
		(net "M_K_DQS_DN<8>")
	)
	(via
		(at 83.489292 -91.747086)
		(size 0.508)
		(drill 0.254)
		(layers "F.Cu" "B.Cu")
		(net "M_K_DQS_DN<8>")
	)
	(via
		(at 73.437496 -135.673846)
		(size 0.508)
		(drill 0.254)
		(layers "F.Cu" "B.Cu")
		(net "M_K_DQS_DN<8>")
	)
	(via
		(at 73.437496 -130.280156)
		(size 0.508)
		(drill 0.254)
		(layers "F.Cu" "B.Cu")
		(net "M_K_DQS_DN<8>")
	)
	(segment
		(start 72.921368 -129.565146)
		(end 72.667368 -129.819146)
		(width 0.1651)
		(layer "B.Cu")
		(net "M_K_DQS_DN<8>")
	)
	(segment
		(start 73.049384 -128.276096)
		(end 73.049384 -129.18313)
		(width 0.1651)
		(layer "B.Cu")
		(net "M_K_DQS_DN<8>")
	)
	(segment
		(start 73.212452 -130.5052)
		(end 73.437496 -130.280156)
		(width 0.1651)
		(layer "B.Cu")
		(net "M_K_DQS_DN<8>")
	)
	(segment
		(start 72.667368 -129.819146)
		(end 72.667368 -130.1496)
		(width 0.1651)
		(layer "B.Cu")
		(net "M_K_DQS_DN<8>")
	)
	(segment
		(start 73.022968 -130.5052)
		(end 73.212452 -130.5052)
		(width 0.1651)
		(layer "B.Cu")
		(net "M_K_DQS_DN<8>")
	)
	(segment
		(start 73.049384 -129.18313)
		(end 72.921368 -129.311146)
		(width 0.1651)
		(layer "B.Cu")
		(net "M_K_DQS_DN<8>")
	)
	(segment
		(start 72.667368 -130.1496)
		(end 73.022968 -130.5052)
		(width 0.1651)
		(layer "B.Cu")
		(net "M_K_DQS_DN<8>")
	)
	(segment
		(start 72.921368 -129.311146)
		(end 72.921368 -129.565146)
		(width 0.1651)
		(layer "B.Cu")
		(net "M_K_DQS_DN<8>")
	)
	(segment
		(start 73.892918 -126.905258)
		(end 74.026776 -127.039116)
		(width 0.14224)
		(layer "In2.Cu")
		(net "M_K_DQS_DN<8>")
	)
	(segment
		(start 72.793606 -132.11302)
		(end 72.793606 -133.77418)
		(width 0.14224)
		(layer "In2.Cu")
		(net "M_K_DQS_DN<8>")
	)
	(segment
		(start 73.869296 -129.120138)
		(end 73.869296 -129.374138)
		(width 0.14224)
		(layer "In2.Cu")
		(net "M_K_DQS_DN<8>")
	)
	(segment
		(start 77.023468 -109.580426)
		(end 77.02296 -109.580426)
		(width 0.14224)
		(layer "In2.Cu")
		(net "M_K_DQS_DN<8>")
	)
	(segment
		(start 75.743816 -112.95888)
		(end 75.418696 -113.284)
		(width 0.14224)
		(layer "In2.Cu")
		(net "M_K_DQS_DN<8>")
	)
	(segment
		(start 75.418696 -121.970038)
		(end 75.418696 -122.224038)
		(width 0.14224)
		(layer "In2.Cu")
		(net "M_K_DQS_DN<8>")
	)
	(segment
		(start 74.026776 -127.885698)
		(end 74.026776 -128.139698)
		(width 0.14224)
		(layer "In2.Cu")
		(net "M_K_DQS_DN<8>")
	)
	(segment
		(start 75.261216 -121.812558)
		(end 75.418696 -121.970038)
		(width 0.14224)
		(layer "In2.Cu")
		(net "M_K_DQS_DN<8>")
	)
	(segment
		(start 76.802234 -110.676182)
		(end 76.137008 -110.676182)
		(width 0.14224)
		(layer "In2.Cu")
		(net "M_K_DQS_DN<8>")
	)
	(segment
		(start 73.889362 -125.266196)
		(end 74.026776 -125.40361)
		(width 0.14224)
		(layer "In2.Cu")
		(net "M_K_DQS_DN<8>")
	)
	(segment
		(start 75.418696 -120.324118)
		(end 75.418696 -120.578118)
		(width 0.14224)
		(layer "In2.Cu")
		(net "M_K_DQS_DN<8>")
	)
	(segment
		(start 81.884774 -103.46563)
		(end 81.845404 -103.505)
		(width 0.0889)
		(layer "In2.Cu")
		(net "M_K_DQS_DN<8>")
	)
	(segment
		(start 75.261216 -119.343678)
		(end 75.418696 -119.501158)
		(width 0.14224)
		(layer "In2.Cu")
		(net "M_K_DQS_DN<8>")
	)
	(segment
		(start 83.043268 -96.119188)
		(end 83.043268 -100.00615)
		(width 0.0889)
		(layer "In2.Cu")
		(net "M_K_DQS_DN<8>")
	)
	(segment
		(start 75.418696 -119.755158)
		(end 75.261216 -119.912638)
		(width 0.14224)
		(layer "In2.Cu")
		(net "M_K_DQS_DN<8>")
	)
	(segment
		(start 73.895966 -126.0856)
		(end 74.026776 -126.21641)
		(width 0.14224)
		(layer "In2.Cu")
		(net "M_K_DQS_DN<8>")
	)
	(segment
		(start 75.261216 -119.089678)
		(end 75.261216 -119.343678)
		(width 0.14224)
		(layer "In2.Cu")
		(net "M_K_DQS_DN<8>")
	)
	(segment
		(start 73.869296 -127.728218)
		(end 74.026776 -127.885698)
		(width 0.14224)
		(layer "In2.Cu")
		(net "M_K_DQS_DN<8>")
	)
	(segment
		(start 74.026776 -126.5174)
		(end 73.892918 -126.651258)
		(width 0.14224)
		(layer "In2.Cu")
		(net "M_K_DQS_DN<8>")
	)
	(segment
		(start 74.026776 -124.024898)
		(end 73.869296 -124.182378)
		(width 0.14224)
		(layer "In2.Cu")
		(net "M_K_DQS_DN<8>")
	)
	(segment
		(start 76.13777 -112.088422)
		(end 76.59116 -112.088422)
		(width 0.14224)
		(layer "In2.Cu")
		(net "M_K_DQS_DN<8>")
	)
	(segment
		(start 74.026776 -127.039116)
		(end 74.026776 -127.316738)
		(width 0.14224)
		(layer "In2.Cu")
		(net "M_K_DQS_DN<8>")
	)
	(segment
		(start 82.982308 -95.405702)
		(end 82.977482 -95.414338)
		(width 0.0889)
		(layer "In2.Cu")
		(net "M_K_DQS_DN<8>")
	)
	(segment
		(start 73.869296 -124.182378)
		(end 73.869296 -124.436378)
		(width 0.14224)
		(layer "In2.Cu")
		(net "M_K_DQS_DN<8>")
	)
	(segment
		(start 73.869296 -129.374138)
		(end 74.026776 -129.531618)
		(width 0.14224)
		(layer "In2.Cu")
		(net "M_K_DQS_DN<8>")
	)
	(segment
		(start 75.418696 -118.932198)
		(end 75.261216 -119.089678)
		(width 0.14224)
		(layer "In2.Cu")
		(net "M_K_DQS_DN<8>")
	)
	(segment
		(start 74.026776 -125.40361)
		(end 74.026776 -125.70079)
		(width 0.14224)
		(layer "In2.Cu")
		(net "M_K_DQS_DN<8>")
	)
	(segment
		(start 74.026776 -124.593858)
		(end 74.026776 -124.874782)
		(width 0.14224)
		(layer "In2.Cu")
		(net "M_K_DQS_DN<8>")
	)
	(segment
		(start 75.261216 -120.735598)
		(end 75.261216 -120.989598)
		(width 0.14224)
		(layer "In2.Cu")
		(net "M_K_DQS_DN<8>")
	)
	(segment
		(start 83.504278 -93.137736)
		(end 83.476338 -93.137736)
		(width 0.0889)
		(layer "In2.Cu")
		(net "M_K_DQS_DN<8>")
	)
	(segment
		(start 75.261216 -119.912638)
		(end 75.261216 -120.166638)
		(width 0.14224)
		(layer "In2.Cu")
		(net "M_K_DQS_DN<8>")
	)
	(segment
		(start 75.418696 -119.501158)
		(end 75.418696 -119.755158)
		(width 0.14224)
		(layer "In2.Cu")
		(net "M_K_DQS_DN<8>")
	)
	(segment
		(start 73.004426 -135.240776)
		(end 73.437496 -135.673846)
		(width 0.14224)
		(layer "In2.Cu")
		(net "M_K_DQS_DN<8>")
	)
	(segment
		(start 76.59116 -112.088422)
		(end 76.812648 -112.30991)
		(width 0.14224)
		(layer "In2.Cu")
		(net "M_K_DQS_DN<8>")
	)
	(segment
		(start 75.418696 -121.401078)
		(end 75.261216 -121.558558)
		(width 0.14224)
		(layer "In2.Cu")
		(net "M_K_DQS_DN<8>")
	)
	(segment
		(start 81.831688 -101.891084)
		(end 81.884774 -101.983032)
		(width 0.0889)
		(layer "In2.Cu")
		(net "M_K_DQS_DN<8>")
	)
	(segment
		(start 73.892918 -126.651258)
		(end 73.892918 -126.905258)
		(width 0.14224)
		(layer "In2.Cu")
		(net "M_K_DQS_DN<8>")
	)
	(segment
		(start 83.84032 -92.545408)
		(end 83.840828 -92.546424)
		(width 0.0889)
		(layer "In2.Cu")
		(net "M_K_DQS_DN<8>")
	)
	(segment
		(start 73.869296 -127.474218)
		(end 73.869296 -127.728218)
		(width 0.14224)
		(layer "In2.Cu")
		(net "M_K_DQS_DN<8>")
	)
	(segment
		(start 74.788522 -122.631454)
		(end 74.788522 -122.854212)
		(width 0.14224)
		(layer "In2.Cu")
		(net "M_K_DQS_DN<8>")
	)
	(segment
		(start 75.191112 -122.451622)
		(end 74.9681 -122.451622)
		(width 0.14224)
		(layer "In2.Cu")
		(net "M_K_DQS_DN<8>")
	)
	(segment
		(start 75.261216 -120.989598)
		(end 75.418696 -121.147078)
		(width 0.14224)
		(layer "In2.Cu")
		(net "M_K_DQS_DN<8>")
	)
	(segment
		(start 76.59878 -112.95888)
		(end 75.743816 -112.95888)
		(width 0.14224)
		(layer "In2.Cu")
		(net "M_K_DQS_DN<8>")
	)
	(segment
		(start 75.261216 -121.558558)
		(end 75.261216 -121.812558)
		(width 0.14224)
		(layer "In2.Cu")
		(net "M_K_DQS_DN<8>")
	)
	(segment
		(start 74.385932 -123.03379)
		(end 74.206354 -123.213622)
		(width 0.14224)
		(layer "In2.Cu")
		(net "M_K_DQS_DN<8>")
	)
	(segment
		(start 77.02296 -110.455456)
		(end 76.802234 -110.676182)
		(width 0.14224)
		(layer "In2.Cu")
		(net "M_K_DQS_DN<8>")
	)
	(segment
		(start 73.437496 -130.280156)
		(end 73.364344 -130.280156)
		(width 0.14224)
		(layer "In2.Cu")
		(net "M_K_DQS_DN<8>")
	)
	(segment
		(start 73.716896 -130.280156)
		(end 73.437496 -130.280156)
		(width 0.14224)
		(layer "In2.Cu")
		(net "M_K_DQS_DN<8>")
	)
	(segment
		(start 74.206354 -123.43638)
		(end 74.026776 -123.615958)
		(width 0.14224)
		(layer "In2.Cu")
		(net "M_K_DQS_DN<8>")
	)
	(segment
		(start 73.869296 -124.436378)
		(end 74.026776 -124.593858)
		(width 0.14224)
		(layer "In2.Cu")
		(net "M_K_DQS_DN<8>")
	)
	(segment
		(start 73.004426 -131.9022)
		(end 72.793606 -132.11302)
		(width 0.14224)
		(layer "In2.Cu")
		(net "M_K_DQS_DN<8>")
	)
	(segment
		(start 77.02296 -109.580426)
		(end 77.02296 -110.455456)
		(width 0.14224)
		(layer "In2.Cu")
		(net "M_K_DQS_DN<8>")
	)
	(segment
		(start 74.206354 -123.213622)
		(end 74.206354 -123.43638)
		(width 0.14224)
		(layer "In2.Cu")
		(net "M_K_DQS_DN<8>")
	)
	(segment
		(start 83.836002 -92.537788)
		(end 83.84032 -92.545408)
		(width 0.0889)
		(layer "In2.Cu")
		(net "M_K_DQS_DN<8>")
	)
	(segment
		(start 73.869296 -128.551178)
		(end 74.026776 -128.708658)
		(width 0.14224)
		(layer "In2.Cu")
		(net "M_K_DQS_DN<8>")
	)
	(segment
		(start 74.026776 -129.531618)
		(end 74.026776 -129.970276)
		(width 0.14224)
		(layer "In2.Cu")
		(net "M_K_DQS_DN<8>")
	)
	(segment
		(start 81.845404 -103.527098)
		(end 81.845404 -104.75849)
		(width 0.14224)
		(layer "In2.Cu")
		(net "M_K_DQS_DN<8>")
	)
	(segment
		(start 74.026776 -126.21641)
		(end 74.026776 -126.5174)
		(width 0.14224)
		(layer "In2.Cu")
		(net "M_K_DQS_DN<8>")
	)
	(segment
		(start 82.971132 -94.01302)
		(end 82.977482 -94.023688)
		(width 0.0889)
		(layer "In2.Cu")
		(net "M_K_DQS_DN<8>")
	)
	(segment
		(start 74.026776 -128.962658)
		(end 73.869296 -129.120138)
		(width 0.14224)
		(layer "In2.Cu")
		(net "M_K_DQS_DN<8>")
	)
	(segment
		(start 73.364344 -130.280156)
		(end 73.004426 -130.640074)
		(width 0.14224)
		(layer "In2.Cu")
		(net "M_K_DQS_DN<8>")
	)
	(segment
		(start 75.758802 -111.054388)
		(end 75.758802 -111.709454)
		(width 0.14224)
		(layer "In2.Cu")
		(net "M_K_DQS_DN<8>")
	)
	(segment
		(start 74.026776 -124.874782)
		(end 73.889362 -125.012196)
		(width 0.14224)
		(layer "In2.Cu")
		(net "M_K_DQS_DN<8>")
	)
	(segment
		(start 75.418696 -113.284)
		(end 75.418696 -118.932198)
		(width 0.14224)
		(layer "In2.Cu")
		(net "M_K_DQS_DN<8>")
	)
	(segment
		(start 72.793606 -133.77418)
		(end 73.004426 -133.985)
		(width 0.14224)
		(layer "In2.Cu")
		(net "M_K_DQS_DN<8>")
	)
	(segment
		(start 82.977482 -95.414338)
		(end 82.971132 -95.425006)
		(width 0.0889)
		(layer "In2.Cu")
		(net "M_K_DQS_DN<8>")
	)
	(segment
		(start 73.869296 -128.297178)
		(end 73.869296 -128.551178)
		(width 0.14224)
		(layer "In2.Cu")
		(net "M_K_DQS_DN<8>")
	)
	(segment
		(start 81.884774 -101.983032)
		(end 81.884774 -103.46563)
		(width 0.0889)
		(layer "In2.Cu")
		(net "M_K_DQS_DN<8>")
	)
	(segment
		(start 76.812648 -112.745012)
		(end 76.59878 -112.95888)
		(width 0.14224)
		(layer "In2.Cu")
		(net "M_K_DQS_DN<8>")
	)
	(segment
		(start 74.788522 -122.854212)
		(end 74.608944 -123.03379)
		(width 0.14224)
		(layer "In2.Cu")
		(net "M_K_DQS_DN<8>")
	)
	(segment
		(start 74.026776 -125.70079)
		(end 73.895966 -125.8316)
		(width 0.14224)
		(layer "In2.Cu")
		(net "M_K_DQS_DN<8>")
	)
	(segment
		(start 74.026776 -128.139698)
		(end 73.869296 -128.297178)
		(width 0.14224)
		(layer "In2.Cu")
		(net "M_K_DQS_DN<8>")
	)
	(segment
		(start 75.418696 -120.578118)
		(end 75.261216 -120.735598)
		(width 0.14224)
		(layer "In2.Cu")
		(net "M_K_DQS_DN<8>")
	)
	(segment
		(start 81.845404 -103.505)
		(end 81.845404 -103.527098)
		(width 0.0889)
		(layer "In2.Cu")
		(net "M_K_DQS_DN<8>")
	)
	(segment
		(start 73.889362 -125.012196)
		(end 73.889362 -125.266196)
		(width 0.14224)
		(layer "In2.Cu")
		(net "M_K_DQS_DN<8>")
	)
	(segment
		(start 74.9681 -122.451622)
		(end 74.788522 -122.631454)
		(width 0.14224)
		(layer "In2.Cu")
		(net "M_K_DQS_DN<8>")
	)
	(segment
		(start 74.608944 -123.03379)
		(end 74.385932 -123.03379)
		(width 0.14224)
		(layer "In2.Cu")
		(net "M_K_DQS_DN<8>")
	)
	(segment
		(start 83.489292 -91.747086)
		(end 83.49107 -91.750896)
		(width 0.0889)
		(layer "In2.Cu")
		(net "M_K_DQS_DN<8>")
	)
	(segment
		(start 76.812648 -112.30991)
		(end 76.812648 -112.745012)
		(width 0.14224)
		(layer "In2.Cu")
		(net "M_K_DQS_DN<8>")
	)
	(segment
		(start 74.026776 -127.316738)
		(end 73.869296 -127.474218)
		(width 0.14224)
		(layer "In2.Cu")
		(net "M_K_DQS_DN<8>")
	)
	(segment
		(start 75.418696 -122.224038)
		(end 75.191112 -122.451622)
		(width 0.14224)
		(layer "In2.Cu")
		(net "M_K_DQS_DN<8>")
	)
	(segment
		(start 74.026776 -129.970276)
		(end 73.716896 -130.280156)
		(width 0.14224)
		(layer "In2.Cu")
		(net "M_K_DQS_DN<8>")
	)
	(segment
		(start 81.915254 -101.13391)
		(end 81.814162 -101.338126)
		(width 0.0889)
		(layer "In2.Cu")
		(net "M_K_DQS_DN<8>")
	)
	(segment
		(start 73.895966 -125.8316)
		(end 73.895966 -126.0856)
		(width 0.14224)
		(layer "In2.Cu")
		(net "M_K_DQS_DN<8>")
	)
	(segment
		(start 75.261216 -120.166638)
		(end 75.418696 -120.324118)
		(width 0.14224)
		(layer "In2.Cu")
		(net "M_K_DQS_DN<8>")
	)
	(segment
		(start 83.043268 -100.00615)
		(end 81.915254 -101.13391)
		(width 0.0889)
		(layer "In2.Cu")
		(net "M_K_DQS_DN<8>")
	)
	(segment
		(start 73.004426 -133.985)
		(end 73.004426 -135.240776)
		(width 0.14224)
		(layer "In2.Cu")
		(net "M_K_DQS_DN<8>")
	)
	(segment
		(start 74.026776 -128.708658)
		(end 74.026776 -128.962658)
		(width 0.14224)
		(layer "In2.Cu")
		(net "M_K_DQS_DN<8>")
	)
	(segment
		(start 82.977228 -96.004634)
		(end 83.043268 -96.119188)
		(width 0.0889)
		(layer "In2.Cu")
		(net "M_K_DQS_DN<8>")
	)
	(segment
		(start 75.758802 -111.709454)
		(end 76.13777 -112.088422)
		(width 0.14224)
		(layer "In2.Cu")
		(net "M_K_DQS_DN<8>")
	)
	(segment
		(start 81.845404 -104.75849)
		(end 77.023468 -109.580426)
		(width 0.14224)
		(layer "In2.Cu")
		(net "M_K_DQS_DN<8>")
	)
	(segment
		(start 76.137008 -110.676182)
		(end 75.758802 -111.054388)
		(width 0.14224)
		(layer "In2.Cu")
		(net "M_K_DQS_DN<8>")
	)
	(segment
		(start 73.004426 -130.640074)
		(end 73.004426 -131.9022)
		(width 0.14224)
		(layer "In2.Cu")
		(net "M_K_DQS_DN<8>")
	)
	(segment
		(start 75.418696 -121.147078)
		(end 75.418696 -121.401078)
		(width 0.14224)
		(layer "In2.Cu")
		(net "M_K_DQS_DN<8>")
	)
	(segment
		(start 74.026776 -123.615958)
		(end 74.026776 -124.024898)
		(width 0.14224)
		(layer "In2.Cu")
		(net "M_K_DQS_DN<8>")
	)
	(arc
		(start 83.49107 -91.750896)
		(mid 83.641888 -92.153832)
		(end 83.836002 -92.537788)
		(width 0.0889)
		(layer "In2.Cu")
		(net "M_K_DQS_DN<8>")
	)
	(arc
		(start 82.971132 -95.425006)
		(mid 82.898207 -95.71563)
		(end 82.977228 -96.004634)
		(width 0.0889)
		(layer "In2.Cu")
		(net "M_K_DQS_DN<8>")
	)
	(arc
		(start 82.977482 -94.423484)
		(mid 82.898351 -94.718886)
		(end 82.977482 -95.014288)
		(width 0.0889)
		(layer "In2.Cu")
		(net "M_K_DQS_DN<8>")
	)
	(arc
		(start 82.977482 -95.014288)
		(mid 83.030952 -95.209351)
		(end 82.982308 -95.405702)
		(width 0.0889)
		(layer "In2.Cu")
		(net "M_K_DQS_DN<8>")
	)
	(arc
		(start 81.814162 -101.338126)
		(mid 81.753641 -101.616801)
		(end 81.831688 -101.891084)
		(width 0.0889)
		(layer "In2.Cu")
		(net "M_K_DQS_DN<8>")
	)
	(arc
		(start 83.476338 -93.137736)
		(mid 82.977457 -93.433173)
		(end 82.971132 -94.01302)
		(width 0.0889)
		(layer "In2.Cu")
		(net "M_K_DQS_DN<8>")
	)
	(arc
		(start 83.840828 -92.546424)
		(mid 83.837081 -92.93568)
		(end 83.504278 -93.137736)
		(width 0.0889)
		(layer "In2.Cu")
		(net "M_K_DQS_DN<8>")
	)
	(arc
		(start 82.977482 -94.023688)
		(mid 83.030981 -94.223586)
		(end 82.977482 -94.423484)
		(width 0.0889)
		(layer "In2.Cu")
		(net "M_K_DQS_DN<8>")
	)
	(segment
		(start 146.999452 -137.67054)
		(end 146.999452 -136.60247)
		(width 0.1651)
		(layer "F.Cu")
		(net "M_K_DQS_DN<7>")
	)
	(segment
		(start 146.999452 -136.60247)
		(end 146.617436 -136.220454)
		(width 0.1651)
		(layer "F.Cu")
		(net "M_K_DQS_DN<7>")
	)
	(segment
		(start 146.617436 -136.220454)
		(end 146.617436 -135.788654)
		(width 0.1651)
		(layer "F.Cu")
		(net "M_K_DQS_DN<7>")
	)
	(segment
		(start 147.171918 -135.4582)
		(end 147.387564 -135.673846)
		(width 0.1651)
		(layer "F.Cu")
		(net "M_K_DQS_DN<7>")
	)
	(segment
		(start 146.94789 -135.4582)
		(end 147.171918 -135.4582)
		(width 0.1651)
		(layer "F.Cu")
		(net "M_K_DQS_DN<7>")
	)
	(segment
		(start 123.363228 -99.490784)
		(end 123.934728 -99.490784)
		(width 0.1651)
		(layer "F.Cu")
		(net "M_K_DQS_DN<7>")
	)
	(segment
		(start 146.617436 -135.788654)
		(end 146.94789 -135.4582)
		(width 0.1651)
		(layer "F.Cu")
		(net "M_K_DQS_DN<7>")
	)
	(via
		(at 147.387564 -130.280156)
		(size 0.508)
		(drill 0.254)
		(layers "F.Cu" "B.Cu")
		(net "M_K_DQS_DN<7>")
	)
	(via
		(at 123.934728 -99.490784)
		(size 0.508)
		(drill 0.254)
		(layers "F.Cu" "B.Cu")
		(net "M_K_DQS_DN<7>")
	)
	(via
		(at 147.387564 -135.673846)
		(size 0.508)
		(drill 0.254)
		(layers "F.Cu" "B.Cu")
		(net "M_K_DQS_DN<7>")
	)
	(segment
		(start 146.871436 -129.565146)
		(end 146.617436 -129.819146)
		(width 0.1651)
		(layer "B.Cu")
		(net "M_K_DQS_DN<7>")
	)
	(segment
		(start 147.16252 -130.5052)
		(end 147.387564 -130.280156)
		(width 0.1651)
		(layer "B.Cu")
		(net "M_K_DQS_DN<7>")
	)
	(segment
		(start 146.617436 -130.1496)
		(end 146.973036 -130.5052)
		(width 0.1651)
		(layer "B.Cu")
		(net "M_K_DQS_DN<7>")
	)
	(segment
		(start 146.973036 -130.5052)
		(end 147.16252 -130.5052)
		(width 0.1651)
		(layer "B.Cu")
		(net "M_K_DQS_DN<7>")
	)
	(segment
		(start 146.999452 -128.276096)
		(end 146.999452 -129.18313)
		(width 0.1651)
		(layer "B.Cu")
		(net "M_K_DQS_DN<7>")
	)
	(segment
		(start 146.871436 -129.311146)
		(end 146.871436 -129.565146)
		(width 0.1651)
		(layer "B.Cu")
		(net "M_K_DQS_DN<7>")
	)
	(segment
		(start 146.999452 -129.18313)
		(end 146.871436 -129.311146)
		(width 0.1651)
		(layer "B.Cu")
		(net "M_K_DQS_DN<7>")
	)
	(segment
		(start 146.617436 -129.819146)
		(end 146.617436 -130.1496)
		(width 0.1651)
		(layer "B.Cu")
		(net "M_K_DQS_DN<7>")
	)
	(segment
		(start 146.713448 -116.853208)
		(end 146.713448 -117.436646)
		(width 0.14224)
		(layer "In2.Cu")
		(net "M_K_DQS_DN<7>")
	)
	(segment
		(start 147.296632 -118.01983)
		(end 147.832826 -118.01983)
		(width 0.14224)
		(layer "In2.Cu")
		(net "M_K_DQS_DN<7>")
	)
	(segment
		(start 128.687068 -105.44302)
		(end 129.850388 -106.60634)
		(width 0.14224)
		(layer "In2.Cu")
		(net "M_K_DQS_DN<7>")
	)
	(segment
		(start 146.743674 -133.77418)
		(end 146.954494 -133.985)
		(width 0.14224)
		(layer "In2.Cu")
		(net "M_K_DQS_DN<7>")
	)
	(segment
		(start 147.997164 -129.069846)
		(end 147.997164 -129.949956)
		(width 0.14224)
		(layer "In2.Cu")
		(net "M_K_DQS_DN<7>")
	)
	(segment
		(start 148.816568 -124.102368)
		(end 148.816568 -124.356368)
		(width 0.14224)
		(layer "In2.Cu")
		(net "M_K_DQS_DN<7>")
	)
	(segment
		(start 148.429472 -117.735858)
		(end 148.974048 -118.280434)
		(width 0.14224)
		(layer "In2.Cu")
		(net "M_K_DQS_DN<7>")
	)
	(segment
		(start 148.604732 -128.462278)
		(end 148.473922 -128.462278)
		(width 0.14224)
		(layer "In2.Cu")
		(net "M_K_DQS_DN<7>")
	)
	(segment
		(start 148.816568 -127.394208)
		(end 148.816568 -127.648208)
		(width 0.14224)
		(layer "In2.Cu")
		(net "M_K_DQS_DN<7>")
	)
	(segment
		(start 124.391166 -102.680262)
		(end 124.391166 -102.844854)
		(width 0.0889)
		(layer "In2.Cu")
		(net "M_K_DQS_DN<7>")
	)
	(segment
		(start 128.687322 -105.387648)
		(end 128.687068 -105.44302)
		(width 0.0889)
		(layer "In2.Cu")
		(net "M_K_DQS_DN<7>")
	)
	(segment
		(start 148.816568 -126.571248)
		(end 148.816568 -126.825248)
		(width 0.14224)
		(layer "In2.Cu")
		(net "M_K_DQS_DN<7>")
	)
	(segment
		(start 148.816568 -125.748288)
		(end 148.816568 -126.002288)
		(width 0.14224)
		(layer "In2.Cu")
		(net "M_K_DQS_DN<7>")
	)
	(segment
		(start 148.974048 -126.159768)
		(end 148.974048 -126.413768)
		(width 0.14224)
		(layer "In2.Cu")
		(net "M_K_DQS_DN<7>")
	)
	(segment
		(start 148.816568 -124.356368)
		(end 148.974048 -124.513848)
		(width 0.14224)
		(layer "In2.Cu")
		(net "M_K_DQS_DN<7>")
	)
	(segment
		(start 148.974048 -123.121928)
		(end 148.816568 -123.279408)
		(width 0.14224)
		(layer "In2.Cu")
		(net "M_K_DQS_DN<7>")
	)
	(segment
		(start 146.954494 -131.9022)
		(end 146.743674 -132.11302)
		(width 0.14224)
		(layer "In2.Cu")
		(net "M_K_DQS_DN<7>")
	)
	(segment
		(start 123.934728 -99.490784)
		(end 123.934728 -99.15271)
		(width 0.0889)
		(layer "In2.Cu")
		(net "M_K_DQS_DN<7>")
	)
	(segment
		(start 148.974048 -118.280434)
		(end 148.974048 -123.121928)
		(width 0.14224)
		(layer "In2.Cu")
		(net "M_K_DQS_DN<7>")
	)
	(segment
		(start 129.850388 -106.60634)
		(end 133.731508 -106.60634)
		(width 0.14224)
		(layer "In2.Cu")
		(net "M_K_DQS_DN<7>")
	)
	(segment
		(start 134.582408 -107.45724)
		(end 136.73328 -107.45724)
		(width 0.14224)
		(layer "In2.Cu")
		(net "M_K_DQS_DN<7>")
	)
	(segment
		(start 148.816568 -126.002288)
		(end 148.974048 -126.159768)
		(width 0.14224)
		(layer "In2.Cu")
		(net "M_K_DQS_DN<7>")
	)
	(segment
		(start 148.116798 -117.735858)
		(end 148.429472 -117.735858)
		(width 0.14224)
		(layer "In2.Cu")
		(net "M_K_DQS_DN<7>")
	)
	(segment
		(start 146.508724 -115.845336)
		(end 146.95932 -116.295932)
		(width 0.14224)
		(layer "In2.Cu")
		(net "M_K_DQS_DN<7>")
	)
	(segment
		(start 146.954494 -130.640074)
		(end 146.954494 -131.9022)
		(width 0.14224)
		(layer "In2.Cu")
		(net "M_K_DQS_DN<7>")
	)
	(segment
		(start 148.816568 -125.179328)
		(end 148.974048 -125.336808)
		(width 0.14224)
		(layer "In2.Cu")
		(net "M_K_DQS_DN<7>")
	)
	(segment
		(start 146.19732 -115.845336)
		(end 146.508724 -115.845336)
		(width 0.14224)
		(layer "In2.Cu")
		(net "M_K_DQS_DN<7>")
	)
	(segment
		(start 147.387564 -130.280156)
		(end 147.314412 -130.280156)
		(width 0.14224)
		(layer "In2.Cu")
		(net "M_K_DQS_DN<7>")
	)
	(segment
		(start 148.816568 -123.533408)
		(end 148.974048 -123.690888)
		(width 0.14224)
		(layer "In2.Cu")
		(net "M_K_DQS_DN<7>")
	)
	(segment
		(start 148.974048 -123.690888)
		(end 148.974048 -123.944888)
		(width 0.14224)
		(layer "In2.Cu")
		(net "M_K_DQS_DN<7>")
	)
	(segment
		(start 148.294344 -128.772666)
		(end 147.997164 -129.069846)
		(width 0.14224)
		(layer "In2.Cu")
		(net "M_K_DQS_DN<7>")
	)
	(segment
		(start 146.95932 -116.295932)
		(end 146.95932 -116.607336)
		(width 0.14224)
		(layer "In2.Cu")
		(net "M_K_DQS_DN<7>")
	)
	(segment
		(start 124.391166 -102.844854)
		(end 125.959616 -104.413304)
		(width 0.0889)
		(layer "In2.Cu")
		(net "M_K_DQS_DN<7>")
	)
	(segment
		(start 148.974048 -126.982728)
		(end 148.974048 -127.236728)
		(width 0.14224)
		(layer "In2.Cu")
		(net "M_K_DQS_DN<7>")
	)
	(segment
		(start 148.974048 -124.513848)
		(end 148.974048 -124.767848)
		(width 0.14224)
		(layer "In2.Cu")
		(net "M_K_DQS_DN<7>")
	)
	(segment
		(start 124.275088 -102.252018)
		(end 124.287788 -102.273354)
		(width 0.0889)
		(layer "In2.Cu")
		(net "M_K_DQS_DN<7>")
	)
	(segment
		(start 124.281438 -101.272086)
		(end 124.286264 -101.280722)
		(width 0.0889)
		(layer "In2.Cu")
		(net "M_K_DQS_DN<7>")
	)
	(segment
		(start 125.959616 -104.413304)
		(end 127.712978 -104.413304)
		(width 0.0889)
		(layer "In2.Cu")
		(net "M_K_DQS_DN<7>")
	)
	(segment
		(start 136.73328 -107.45724)
		(end 145.39087 -116.11483)
		(width 0.14224)
		(layer "In2.Cu")
		(net "M_K_DQS_DN<7>")
	)
	(segment
		(start 123.934728 -99.15271)
		(end 123.99264 -99.094798)
		(width 0.0889)
		(layer "In2.Cu")
		(net "M_K_DQS_DN<7>")
	)
	(segment
		(start 148.974048 -128.092962)
		(end 148.604732 -128.462278)
		(width 0.14224)
		(layer "In2.Cu")
		(net "M_K_DQS_DN<7>")
	)
	(segment
		(start 148.473922 -128.462278)
		(end 148.294344 -128.641856)
		(width 0.14224)
		(layer "In2.Cu")
		(net "M_K_DQS_DN<7>")
	)
	(segment
		(start 148.974048 -125.336808)
		(end 148.974048 -125.590808)
		(width 0.14224)
		(layer "In2.Cu")
		(net "M_K_DQS_DN<7>")
	)
	(segment
		(start 145.39087 -116.11483)
		(end 145.927826 -116.11483)
		(width 0.14224)
		(layer "In2.Cu")
		(net "M_K_DQS_DN<7>")
	)
	(segment
		(start 145.927826 -116.11483)
		(end 146.19732 -115.845336)
		(width 0.14224)
		(layer "In2.Cu")
		(net "M_K_DQS_DN<7>")
	)
	(segment
		(start 146.95932 -116.607336)
		(end 146.713448 -116.853208)
		(width 0.14224)
		(layer "In2.Cu")
		(net "M_K_DQS_DN<7>")
	)
	(segment
		(start 147.832826 -118.01983)
		(end 148.116798 -117.735858)
		(width 0.14224)
		(layer "In2.Cu")
		(net "M_K_DQS_DN<7>")
	)
	(segment
		(start 147.997164 -129.949956)
		(end 147.666964 -130.280156)
		(width 0.14224)
		(layer "In2.Cu")
		(net "M_K_DQS_DN<7>")
	)
	(segment
		(start 148.974048 -123.944888)
		(end 148.816568 -124.102368)
		(width 0.14224)
		(layer "In2.Cu")
		(net "M_K_DQS_DN<7>")
	)
	(segment
		(start 147.314412 -130.280156)
		(end 146.954494 -130.640074)
		(width 0.14224)
		(layer "In2.Cu")
		(net "M_K_DQS_DN<7>")
	)
	(segment
		(start 146.713448 -117.436646)
		(end 147.296632 -118.01983)
		(width 0.14224)
		(layer "In2.Cu")
		(net "M_K_DQS_DN<7>")
	)
	(segment
		(start 148.974048 -124.767848)
		(end 148.816568 -124.925328)
		(width 0.14224)
		(layer "In2.Cu")
		(net "M_K_DQS_DN<7>")
	)
	(segment
		(start 148.294344 -128.641856)
		(end 148.294344 -128.772666)
		(width 0.14224)
		(layer "In2.Cu")
		(net "M_K_DQS_DN<7>")
	)
	(segment
		(start 147.666964 -130.280156)
		(end 147.387564 -130.280156)
		(width 0.14224)
		(layer "In2.Cu")
		(net "M_K_DQS_DN<7>")
	)
	(segment
		(start 148.974048 -125.590808)
		(end 148.816568 -125.748288)
		(width 0.14224)
		(layer "In2.Cu")
		(net "M_K_DQS_DN<7>")
	)
	(segment
		(start 148.816568 -124.925328)
		(end 148.816568 -125.179328)
		(width 0.14224)
		(layer "In2.Cu")
		(net "M_K_DQS_DN<7>")
	)
	(segment
		(start 148.974048 -127.805688)
		(end 148.974048 -128.092962)
		(width 0.14224)
		(layer "In2.Cu")
		(net "M_K_DQS_DN<7>")
	)
	(segment
		(start 124.281438 -100.681536)
		(end 124.275088 -100.692204)
		(width 0.0889)
		(layer "In2.Cu")
		(net "M_K_DQS_DN<7>")
	)
	(segment
		(start 127.712978 -104.413304)
		(end 128.687322 -105.387648)
		(width 0.0889)
		(layer "In2.Cu")
		(net "M_K_DQS_DN<7>")
	)
	(segment
		(start 133.731508 -106.60634)
		(end 134.582408 -107.45724)
		(width 0.14224)
		(layer "In2.Cu")
		(net "M_K_DQS_DN<7>")
	)
	(segment
		(start 148.816568 -127.648208)
		(end 148.974048 -127.805688)
		(width 0.14224)
		(layer "In2.Cu")
		(net "M_K_DQS_DN<7>")
	)
	(segment
		(start 148.974048 -127.236728)
		(end 148.816568 -127.394208)
		(width 0.14224)
		(layer "In2.Cu")
		(net "M_K_DQS_DN<7>")
	)
	(segment
		(start 146.954494 -135.240776)
		(end 147.387564 -135.673846)
		(width 0.14224)
		(layer "In2.Cu")
		(net "M_K_DQS_DN<7>")
	)
	(segment
		(start 146.743674 -132.11302)
		(end 146.743674 -133.77418)
		(width 0.14224)
		(layer "In2.Cu")
		(net "M_K_DQS_DN<7>")
	)
	(segment
		(start 148.816568 -123.279408)
		(end 148.816568 -123.533408)
		(width 0.14224)
		(layer "In2.Cu")
		(net "M_K_DQS_DN<7>")
	)
	(segment
		(start 146.954494 -133.985)
		(end 146.954494 -135.240776)
		(width 0.14224)
		(layer "In2.Cu")
		(net "M_K_DQS_DN<7>")
	)
	(segment
		(start 148.974048 -126.413768)
		(end 148.816568 -126.571248)
		(width 0.14224)
		(layer "In2.Cu")
		(net "M_K_DQS_DN<7>")
	)
	(segment
		(start 148.816568 -126.825248)
		(end 148.974048 -126.982728)
		(width 0.14224)
		(layer "In2.Cu")
		(net "M_K_DQS_DN<7>")
	)
	(arc
		(start 124.287788 -102.273354)
		(mid 124.364847 -102.470359)
		(end 124.391166 -102.680262)
		(width 0.0889)
		(layer "In2.Cu")
		(net "M_K_DQS_DN<7>")
	)
	(arc
		(start 123.99264 -99.094798)
		(mid 124.14789 -99.15208)
		(end 124.266706 -99.267264)
		(width 0.0889)
		(layer "In2.Cu")
		(net "M_K_DQS_DN<7>")
	)
	(arc
		(start 124.281438 -101.672136)
		(mid 124.202216 -101.961254)
		(end 124.275088 -102.252018)
		(width 0.0889)
		(layer "In2.Cu")
		(net "M_K_DQS_DN<7>")
	)
	(arc
		(start 124.266706 -99.267264)
		(mid 124.334703 -99.476974)
		(end 124.281438 -99.690936)
		(width 0.0889)
		(layer "In2.Cu")
		(net "M_K_DQS_DN<7>")
	)
	(arc
		(start 124.286264 -101.280722)
		(mid 124.335019 -101.477074)
		(end 124.281438 -101.672136)
		(width 0.0889)
		(layer "In2.Cu")
		(net "M_K_DQS_DN<7>")
	)
	(arc
		(start 124.281438 -99.690936)
		(mid 124.202307 -99.986338)
		(end 124.281438 -100.28174)
		(width 0.0889)
		(layer "In2.Cu")
		(net "M_K_DQS_DN<7>")
	)
	(arc
		(start 124.275088 -100.692204)
		(mid 124.20229 -100.982967)
		(end 124.281438 -101.272086)
		(width 0.0889)
		(layer "In2.Cu")
		(net "M_K_DQS_DN<7>")
	)
	(arc
		(start 124.281438 -100.28174)
		(mid 124.334937 -100.481638)
		(end 124.281438 -100.681536)
		(width 0.0889)
		(layer "In2.Cu")
		(net "M_K_DQS_DN<7>")
	)
	(segment
		(start 137.267442 -135.788654)
		(end 137.597896 -135.4582)
		(width 0.1651)
		(layer "F.Cu")
		(net "M_K_DQS_DN<6>")
	)
	(segment
		(start 137.597896 -135.4582)
		(end 137.821924 -135.4582)
		(width 0.1651)
		(layer "F.Cu")
		(net "M_K_DQS_DN<6>")
	)
	(segment
		(start 137.649458 -136.60247)
		(end 137.267442 -136.220454)
		(width 0.1651)
		(layer "F.Cu")
		(net "M_K_DQS_DN<6>")
	)
	(segment
		(start 118.212362 -99.490784)
		(end 118.783862 -99.490784)
		(width 0.1651)
		(layer "F.Cu")
		(net "M_K_DQS_DN<6>")
	)
	(segment
		(start 137.267442 -136.220454)
		(end 137.267442 -135.788654)
		(width 0.1651)
		(layer "F.Cu")
		(net "M_K_DQS_DN<6>")
	)
	(segment
		(start 137.821924 -135.4582)
		(end 138.03757 -135.673846)
		(width 0.1651)
		(layer "F.Cu")
		(net "M_K_DQS_DN<6>")
	)
	(segment
		(start 137.649458 -137.67054)
		(end 137.649458 -136.60247)
		(width 0.1651)
		(layer "F.Cu")
		(net "M_K_DQS_DN<6>")
	)
	(via
		(at 118.783862 -99.490784)
		(size 0.508)
		(drill 0.254)
		(layers "F.Cu" "B.Cu")
		(net "M_K_DQS_DN<6>")
	)
	(via
		(at 138.03757 -135.673846)
		(size 0.508)
		(drill 0.254)
		(layers "F.Cu" "B.Cu")
		(net "M_K_DQS_DN<6>")
	)
	(via
		(at 138.03757 -130.280156)
		(size 0.508)
		(drill 0.254)
		(layers "F.Cu" "B.Cu")
		(net "M_K_DQS_DN<6>")
	)
	(segment
		(start 137.623042 -130.5052)
		(end 137.812526 -130.5052)
		(width 0.1651)
		(layer "B.Cu")
		(net "M_K_DQS_DN<6>")
	)
	(segment
		(start 137.267442 -130.1496)
		(end 137.623042 -130.5052)
		(width 0.1651)
		(layer "B.Cu")
		(net "M_K_DQS_DN<6>")
	)
	(segment
		(start 137.649458 -129.18313)
		(end 137.521442 -129.311146)
		(width 0.1651)
		(layer "B.Cu")
		(net "M_K_DQS_DN<6>")
	)
	(segment
		(start 137.521442 -129.311146)
		(end 137.521442 -129.565146)
		(width 0.1651)
		(layer "B.Cu")
		(net "M_K_DQS_DN<6>")
	)
	(segment
		(start 137.521442 -129.565146)
		(end 137.267442 -129.819146)
		(width 0.1651)
		(layer "B.Cu")
		(net "M_K_DQS_DN<6>")
	)
	(segment
		(start 137.812526 -130.5052)
		(end 138.03757 -130.280156)
		(width 0.1651)
		(layer "B.Cu")
		(net "M_K_DQS_DN<6>")
	)
	(segment
		(start 137.267442 -129.819146)
		(end 137.267442 -130.1496)
		(width 0.1651)
		(layer "B.Cu")
		(net "M_K_DQS_DN<6>")
	)
	(segment
		(start 137.649458 -128.276096)
		(end 137.649458 -129.18313)
		(width 0.1651)
		(layer "B.Cu")
		(net "M_K_DQS_DN<6>")
	)
	(segment
		(start 133.668516 -115.64112)
		(end 134.0739 -115.64112)
		(width 0.14224)
		(layer "In2.Cu")
		(net "M_K_DQS_DN<6>")
	)
	(segment
		(start 138.55065 -120.11787)
		(end 138.55065 -120.64492)
		(width 0.14224)
		(layer "In2.Cu")
		(net "M_K_DQS_DN<6>")
	)
	(segment
		(start 119.124222 -102.252018)
		(end 119.130572 -102.262686)
		(width 0.0889)
		(layer "In2.Cu")
		(net "M_K_DQS_DN<6>")
	)
	(segment
		(start 124.655326 -116.689124)
		(end 130.78206 -116.689124)
		(width 0.14224)
		(layer "In2.Cu")
		(net "M_K_DQS_DN<6>")
	)
	(segment
		(start 138.55065 -123.93676)
		(end 138.37285 -124.11456)
		(width 0.14224)
		(layer "In2.Cu")
		(net "M_K_DQS_DN<6>")
	)
	(segment
		(start 138.37285 -123.2916)
		(end 138.37285 -123.47448)
		(width 0.14224)
		(layer "In2.Cu")
		(net "M_K_DQS_DN<6>")
	)
	(segment
		(start 138.37285 -129.17424)
		(end 138.55065 -129.35204)
		(width 0.14224)
		(layer "In2.Cu")
		(net "M_K_DQS_DN<6>")
	)
	(segment
		(start 138.55065 -120.64492)
		(end 138.37285 -120.82272)
		(width 0.14224)
		(layer "In2.Cu")
		(net "M_K_DQS_DN<6>")
	)
	(segment
		(start 131.8133 -115.64112)
		(end 132.034788 -115.862608)
		(width 0.14224)
		(layer "In2.Cu")
		(net "M_K_DQS_DN<6>")
	)
	(segment
		(start 132.034788 -116.273072)
		(end 132.385308 -116.623592)
		(width 0.14224)
		(layer "In2.Cu")
		(net "M_K_DQS_DN<6>")
	)
	(segment
		(start 119.051324 -105.940352)
		(end 118.918482 -106.073194)
		(width 0.0889)
		(layer "In2.Cu")
		(net "M_K_DQS_DN<6>")
	)
	(segment
		(start 138.37285 -120.82272)
		(end 138.37285 -121.0056)
		(width 0.14224)
		(layer "In2.Cu")
		(net "M_K_DQS_DN<6>")
	)
	(segment
		(start 138.15568 -119.9388)
		(end 138.37158 -119.9388)
		(width 0.14224)
		(layer "In2.Cu")
		(net "M_K_DQS_DN<6>")
	)
	(segment
		(start 137.39368 -133.77418)
		(end 137.6045 -133.985)
		(width 0.14224)
		(layer "In2.Cu")
		(net "M_K_DQS_DN<6>")
	)
	(segment
		(start 118.918482 -106.073194)
		(end 118.918482 -106.58983)
		(width 0.0889)
		(layer "In2.Cu")
		(net "M_K_DQS_DN<6>")
	)
	(segment
		(start 138.55065 -122.29084)
		(end 138.37285 -122.46864)
		(width 0.14224)
		(layer "In2.Cu")
		(net "M_K_DQS_DN<6>")
	)
	(segment
		(start 138.55065 -130.046476)
		(end 138.267186 -130.32994)
		(width 0.14224)
		(layer "In2.Cu")
		(net "M_K_DQS_DN<6>")
	)
	(segment
		(start 138.55065 -122.82932)
		(end 138.55065 -123.1138)
		(width 0.14224)
		(layer "In2.Cu")
		(net "M_K_DQS_DN<6>")
	)
	(segment
		(start 138.55065 -122.00636)
		(end 138.55065 -122.29084)
		(width 0.14224)
		(layer "In2.Cu")
		(net "M_K_DQS_DN<6>")
	)
	(segment
		(start 137.6045 -135.240776)
		(end 138.03757 -135.673846)
		(width 0.14224)
		(layer "In2.Cu")
		(net "M_K_DQS_DN<6>")
	)
	(segment
		(start 119.051324 -103.948992)
		(end 119.051324 -105.940352)
		(width 0.0889)
		(layer "In2.Cu")
		(net "M_K_DQS_DN<6>")
	)
	(segment
		(start 138.37285 -128.291336)
		(end 138.55065 -128.469136)
		(width 0.14224)
		(layer "In2.Cu")
		(net "M_K_DQS_DN<6>")
	)
	(segment
		(start 138.37285 -124.11456)
		(end 138.37285 -124.29744)
		(width 0.14224)
		(layer "In2.Cu")
		(net "M_K_DQS_DN<6>")
	)
	(segment
		(start 119.130572 -102.262686)
		(end 119.135398 -102.271322)
		(width 0.0889)
		(layer "In2.Cu")
		(net "M_K_DQS_DN<6>")
	)
	(segment
		(start 118.918482 -106.58983)
		(end 118.879112 -106.6292)
		(width 0.0889)
		(layer "In2.Cu")
		(net "M_K_DQS_DN<6>")
	)
	(segment
		(start 138.55065 -129.35204)
		(end 138.55065 -130.046476)
		(width 0.14224)
		(layer "In2.Cu")
		(net "M_K_DQS_DN<6>")
	)
	(segment
		(start 138.37285 -128.934464)
		(end 138.37285 -129.17424)
		(width 0.14224)
		(layer "In2.Cu")
		(net "M_K_DQS_DN<6>")
	)
	(segment
		(start 138.267186 -130.32994)
		(end 138.087354 -130.32994)
		(width 0.14224)
		(layer "In2.Cu")
		(net "M_K_DQS_DN<6>")
	)
	(segment
		(start 138.55065 -128.469136)
		(end 138.55065 -128.756664)
		(width 0.14224)
		(layer "In2.Cu")
		(net "M_K_DQS_DN<6>")
	)
	(segment
		(start 138.55065 -123.1138)
		(end 138.37285 -123.2916)
		(width 0.14224)
		(layer "In2.Cu")
		(net "M_K_DQS_DN<6>")
	)
	(segment
		(start 133.447028 -115.862608)
		(end 133.668516 -115.64112)
		(width 0.14224)
		(layer "In2.Cu")
		(net "M_K_DQS_DN<6>")
	)
	(segment
		(start 136.802368 -118.585488)
		(end 136.98728 -118.7704)
		(width 0.14224)
		(layer "In2.Cu")
		(net "M_K_DQS_DN<6>")
	)
	(segment
		(start 118.879112 -106.651298)
		(end 118.879112 -110.143544)
		(width 0.14224)
		(layer "In2.Cu")
		(net "M_K_DQS_DN<6>")
	)
	(segment
		(start 131.382516 -115.64112)
		(end 131.8133 -115.64112)
		(width 0.14224)
		(layer "In2.Cu")
		(net "M_K_DQS_DN<6>")
	)
	(segment
		(start 133.096508 -116.623592)
		(end 133.447028 -116.273072)
		(width 0.14224)
		(layer "In2.Cu")
		(net "M_K_DQS_DN<6>")
	)
	(segment
		(start 138.37285 -127.131064)
		(end 138.37285 -127.402336)
		(width 0.14224)
		(layer "In2.Cu")
		(net "M_K_DQS_DN<6>")
	)
	(segment
		(start 119.124222 -101.261418)
		(end 119.130572 -101.272086)
		(width 0.0889)
		(layer "In2.Cu")
		(net "M_K_DQS_DN<6>")
	)
	(segment
		(start 138.37285 -122.65152)
		(end 138.55065 -122.82932)
		(width 0.14224)
		(layer "In2.Cu")
		(net "M_K_DQS_DN<6>")
	)
	(segment
		(start 137.411968 -118.979188)
		(end 137.411968 -119.195088)
		(width 0.14224)
		(layer "In2.Cu")
		(net "M_K_DQS_DN<6>")
	)
	(segment
		(start 137.81278 -119.38)
		(end 137.996168 -119.563388)
		(width 0.14224)
		(layer "In2.Cu")
		(net "M_K_DQS_DN<6>")
	)
	(segment
		(start 137.20318 -118.7704)
		(end 137.411968 -118.979188)
		(width 0.14224)
		(layer "In2.Cu")
		(net "M_K_DQS_DN<6>")
	)
	(segment
		(start 134.0739 -115.64112)
		(end 136.802368 -118.369588)
		(width 0.14224)
		(layer "In2.Cu")
		(net "M_K_DQS_DN<6>")
	)
	(segment
		(start 138.37285 -121.0056)
		(end 138.55065 -121.1834)
		(width 0.14224)
		(layer "In2.Cu")
		(net "M_K_DQS_DN<6>")
	)
	(segment
		(start 138.55065 -127.893064)
		(end 138.37285 -128.070864)
		(width 0.14224)
		(layer "In2.Cu")
		(net "M_K_DQS_DN<6>")
	)
	(segment
		(start 137.996168 -119.779288)
		(end 138.15568 -119.9388)
		(width 0.14224)
		(layer "In2.Cu")
		(net "M_K_DQS_DN<6>")
	)
	(segment
		(start 118.879112 -110.143544)
		(end 120.886728 -112.15116)
		(width 0.14224)
		(layer "In2.Cu")
		(net "M_K_DQS_DN<6>")
	)
	(segment
		(start 136.802368 -118.369588)
		(end 136.802368 -118.585488)
		(width 0.14224)
		(layer "In2.Cu")
		(net "M_K_DQS_DN<6>")
	)
	(segment
		(start 138.37285 -124.29744)
		(end 138.55065 -124.47524)
		(width 0.14224)
		(layer "In2.Cu")
		(net "M_K_DQS_DN<6>")
	)
	(segment
		(start 136.98728 -118.7704)
		(end 137.20318 -118.7704)
		(width 0.14224)
		(layer "In2.Cu")
		(net "M_K_DQS_DN<6>")
	)
	(segment
		(start 131.161028 -115.862608)
		(end 131.382516 -115.64112)
		(width 0.14224)
		(layer "In2.Cu")
		(net "M_K_DQS_DN<6>")
	)
	(segment
		(start 138.37285 -123.47448)
		(end 138.55065 -123.65228)
		(width 0.14224)
		(layer "In2.Cu")
		(net "M_K_DQS_DN<6>")
	)
	(segment
		(start 119.130572 -101.272086)
		(end 119.135398 -101.280722)
		(width 0.0889)
		(layer "In2.Cu")
		(net "M_K_DQS_DN<6>")
	)
	(segment
		(start 120.886728 -112.920526)
		(end 124.655326 -116.689124)
		(width 0.14224)
		(layer "In2.Cu")
		(net "M_K_DQS_DN<6>")
	)
	(segment
		(start 119.130572 -103.253286)
		(end 119.135398 -103.261922)
		(width 0.0889)
		(layer "In2.Cu")
		(net "M_K_DQS_DN<6>")
	)
	(segment
		(start 138.55065 -126.953264)
		(end 138.37285 -127.131064)
		(width 0.14224)
		(layer "In2.Cu")
		(net "M_K_DQS_DN<6>")
	)
	(segment
		(start 137.996168 -119.563388)
		(end 137.996168 -119.779288)
		(width 0.14224)
		(layer "In2.Cu")
		(net "M_K_DQS_DN<6>")
	)
	(segment
		(start 137.6045 -131.9022)
		(end 137.39368 -132.11302)
		(width 0.14224)
		(layer "In2.Cu")
		(net "M_K_DQS_DN<6>")
	)
	(segment
		(start 137.6045 -130.640074)
		(end 137.6045 -131.9022)
		(width 0.14224)
		(layer "In2.Cu")
		(net "M_K_DQS_DN<6>")
	)
	(segment
		(start 138.087354 -130.32994)
		(end 138.03757 -130.280156)
		(width 0.14224)
		(layer "In2.Cu")
		(net "M_K_DQS_DN<6>")
	)
	(segment
		(start 120.886728 -112.15116)
		(end 120.886728 -112.920526)
		(width 0.14224)
		(layer "In2.Cu")
		(net "M_K_DQS_DN<6>")
	)
	(segment
		(start 137.411968 -119.195088)
		(end 137.59688 -119.38)
		(width 0.14224)
		(layer "In2.Cu")
		(net "M_K_DQS_DN<6>")
	)
	(segment
		(start 138.55065 -124.47524)
		(end 138.55065 -126.953264)
		(width 0.14224)
		(layer "In2.Cu")
		(net "M_K_DQS_DN<6>")
	)
	(segment
		(start 138.37285 -128.070864)
		(end 138.37285 -128.291336)
		(width 0.14224)
		(layer "In2.Cu")
		(net "M_K_DQS_DN<6>")
	)
	(segment
		(start 130.78206 -116.689124)
		(end 131.161028 -116.310156)
		(width 0.14224)
		(layer "In2.Cu")
		(net "M_K_DQS_DN<6>")
	)
	(segment
		(start 138.37285 -127.402336)
		(end 138.55065 -127.580136)
		(width 0.14224)
		(layer "In2.Cu")
		(net "M_K_DQS_DN<6>")
	)
	(segment
		(start 137.59688 -119.38)
		(end 137.81278 -119.38)
		(width 0.14224)
		(layer "In2.Cu")
		(net "M_K_DQS_DN<6>")
	)
	(segment
		(start 132.385308 -116.623592)
		(end 133.096508 -116.623592)
		(width 0.14224)
		(layer "In2.Cu")
		(net "M_K_DQS_DN<6>")
	)
	(segment
		(start 137.39368 -132.11302)
		(end 137.39368 -133.77418)
		(width 0.14224)
		(layer "In2.Cu")
		(net "M_K_DQS_DN<6>")
	)
	(segment
		(start 138.37158 -119.9388)
		(end 138.55065 -120.11787)
		(width 0.14224)
		(layer "In2.Cu")
		(net "M_K_DQS_DN<6>")
	)
	(segment
		(start 138.55065 -128.756664)
		(end 138.37285 -128.934464)
		(width 0.14224)
		(layer "In2.Cu")
		(net "M_K_DQS_DN<6>")
	)
	(segment
		(start 133.447028 -116.273072)
		(end 133.447028 -115.862608)
		(width 0.14224)
		(layer "In2.Cu")
		(net "M_K_DQS_DN<6>")
	)
	(segment
		(start 138.37285 -122.46864)
		(end 138.37285 -122.65152)
		(width 0.14224)
		(layer "In2.Cu")
		(net "M_K_DQS_DN<6>")
	)
	(segment
		(start 137.964418 -130.280156)
		(end 137.6045 -130.640074)
		(width 0.14224)
		(layer "In2.Cu")
		(net "M_K_DQS_DN<6>")
	)
	(segment
		(start 138.55065 -127.580136)
		(end 138.55065 -127.893064)
		(width 0.14224)
		(layer "In2.Cu")
		(net "M_K_DQS_DN<6>")
	)
	(segment
		(start 119.124222 -103.242618)
		(end 119.130572 -103.253286)
		(width 0.0889)
		(layer "In2.Cu")
		(net "M_K_DQS_DN<6>")
	)
	(segment
		(start 138.55065 -123.65228)
		(end 138.55065 -123.93676)
		(width 0.14224)
		(layer "In2.Cu")
		(net "M_K_DQS_DN<6>")
	)
	(segment
		(start 137.6045 -133.985)
		(end 137.6045 -135.240776)
		(width 0.14224)
		(layer "In2.Cu")
		(net "M_K_DQS_DN<6>")
	)
	(segment
		(start 138.03757 -130.280156)
		(end 137.964418 -130.280156)
		(width 0.14224)
		(layer "In2.Cu")
		(net "M_K_DQS_DN<6>")
	)
	(segment
		(start 138.55065 -121.46788)
		(end 138.37285 -121.64568)
		(width 0.14224)
		(layer "In2.Cu")
		(net "M_K_DQS_DN<6>")
	)
	(segment
		(start 138.37285 -121.82856)
		(end 138.55065 -122.00636)
		(width 0.14224)
		(layer "In2.Cu")
		(net "M_K_DQS_DN<6>")
	)
	(segment
		(start 131.161028 -116.310156)
		(end 131.161028 -115.862608)
		(width 0.14224)
		(layer "In2.Cu")
		(net "M_K_DQS_DN<6>")
	)
	(segment
		(start 118.879112 -106.6292)
		(end 118.879112 -106.651298)
		(width 0.0889)
		(layer "In2.Cu")
		(net "M_K_DQS_DN<6>")
	)
	(segment
		(start 138.37285 -121.64568)
		(end 138.37285 -121.82856)
		(width 0.14224)
		(layer "In2.Cu")
		(net "M_K_DQS_DN<6>")
	)
	(segment
		(start 132.034788 -115.862608)
		(end 132.034788 -116.273072)
		(width 0.14224)
		(layer "In2.Cu")
		(net "M_K_DQS_DN<6>")
	)
	(segment
		(start 138.55065 -121.1834)
		(end 138.55065 -121.46788)
		(width 0.14224)
		(layer "In2.Cu")
		(net "M_K_DQS_DN<6>")
	)
	(arc
		(start 119.130572 -102.662736)
		(mid 119.05135 -102.951854)
		(end 119.124222 -103.242618)
		(width 0.0889)
		(layer "In2.Cu")
		(net "M_K_DQS_DN<6>")
	)
	(arc
		(start 119.135398 -100.290122)
		(mid 119.184153 -100.486474)
		(end 119.130572 -100.681536)
		(width 0.0889)
		(layer "In2.Cu")
		(net "M_K_DQS_DN<6>")
	)
	(arc
		(start 119.135398 -101.280722)
		(mid 119.184153 -101.477074)
		(end 119.130572 -101.672136)
		(width 0.0889)
		(layer "In2.Cu")
		(net "M_K_DQS_DN<6>")
	)
	(arc
		(start 119.135398 -102.271322)
		(mid 119.184153 -102.467674)
		(end 119.130572 -102.662736)
		(width 0.0889)
		(layer "In2.Cu")
		(net "M_K_DQS_DN<6>")
	)
	(arc
		(start 119.10314 -100.233988)
		(mid 119.119097 -100.262154)
		(end 119.135398 -100.290122)
		(width 0.0889)
		(layer "In2.Cu")
		(net "M_K_DQS_DN<6>")
	)
	(arc
		(start 119.130572 -103.653336)
		(mid 119.071447 -103.79594)
		(end 119.051324 -103.948992)
		(width 0.0889)
		(layer "In2.Cu")
		(net "M_K_DQS_DN<6>")
	)
	(arc
		(start 119.130572 -100.681536)
		(mid 119.05135 -100.970654)
		(end 119.124222 -101.261418)
		(width 0.0889)
		(layer "In2.Cu")
		(net "M_K_DQS_DN<6>")
	)
	(arc
		(start 119.130572 -101.672136)
		(mid 119.05135 -101.961254)
		(end 119.124222 -102.252018)
		(width 0.0889)
		(layer "In2.Cu")
		(net "M_K_DQS_DN<6>")
	)
	(arc
		(start 118.783862 -99.490784)
		(mid 118.924235 -99.870663)
		(end 119.10314 -100.233988)
		(width 0.0889)
		(layer "In2.Cu")
		(net "M_K_DQS_DN<6>")
	)
	(arc
		(start 119.135398 -103.261922)
		(mid 119.184153 -103.458274)
		(end 119.130572 -103.653336)
		(width 0.0889)
		(layer "In2.Cu")
		(net "M_K_DQS_DN<6>")
	)
	(segment
		(start 113.061242 -99.490784)
		(end 113.632742 -99.490784)
		(width 0.1651)
		(layer "F.Cu")
		(net "M_K_DQS_DN<5>")
	)
	(segment
		(start 128.299464 -137.67054)
		(end 128.299464 -136.60247)
		(width 0.1651)
		(layer "F.Cu")
		(net "M_K_DQS_DN<5>")
	)
	(segment
		(start 127.917448 -135.788654)
		(end 128.247902 -135.4582)
		(width 0.1651)
		(layer "F.Cu")
		(net "M_K_DQS_DN<5>")
	)
	(segment
		(start 128.47193 -135.4582)
		(end 128.687576 -135.673846)
		(width 0.1651)
		(layer "F.Cu")
		(net "M_K_DQS_DN<5>")
	)
	(segment
		(start 128.299464 -136.60247)
		(end 127.917448 -136.220454)
		(width 0.1651)
		(layer "F.Cu")
		(net "M_K_DQS_DN<5>")
	)
	(segment
		(start 127.917448 -136.220454)
		(end 127.917448 -135.788654)
		(width 0.1651)
		(layer "F.Cu")
		(net "M_K_DQS_DN<5>")
	)
	(segment
		(start 128.247902 -135.4582)
		(end 128.47193 -135.4582)
		(width 0.1651)
		(layer "F.Cu")
		(net "M_K_DQS_DN<5>")
	)
	(via
		(at 128.687576 -135.673846)
		(size 0.508)
		(drill 0.254)
		(layers "F.Cu" "B.Cu")
		(net "M_K_DQS_DN<5>")
	)
	(via
		(at 128.687576 -130.280156)
		(size 0.508)
		(drill 0.254)
		(layers "F.Cu" "B.Cu")
		(net "M_K_DQS_DN<5>")
	)
	(via
		(at 113.632742 -99.490784)
		(size 0.508)
		(drill 0.254)
		(layers "F.Cu" "B.Cu")
		(net "M_K_DQS_DN<5>")
	)
	(segment
		(start 127.917448 -130.1496)
		(end 128.273048 -130.5052)
		(width 0.1651)
		(layer "B.Cu")
		(net "M_K_DQS_DN<5>")
	)
	(segment
		(start 128.299464 -129.18313)
		(end 128.171448 -129.311146)
		(width 0.1651)
		(layer "B.Cu")
		(net "M_K_DQS_DN<5>")
	)
	(segment
		(start 127.917448 -129.819146)
		(end 127.917448 -130.1496)
		(width 0.1651)
		(layer "B.Cu")
		(net "M_K_DQS_DN<5>")
	)
	(segment
		(start 128.462532 -130.5052)
		(end 128.687576 -130.280156)
		(width 0.1651)
		(layer "B.Cu")
		(net "M_K_DQS_DN<5>")
	)
	(segment
		(start 128.299464 -128.276096)
		(end 128.299464 -129.18313)
		(width 0.1651)
		(layer "B.Cu")
		(net "M_K_DQS_DN<5>")
	)
	(segment
		(start 128.273048 -130.5052)
		(end 128.462532 -130.5052)
		(width 0.1651)
		(layer "B.Cu")
		(net "M_K_DQS_DN<5>")
	)
	(segment
		(start 128.171448 -129.311146)
		(end 128.171448 -129.565146)
		(width 0.1651)
		(layer "B.Cu")
		(net "M_K_DQS_DN<5>")
	)
	(segment
		(start 128.171448 -129.565146)
		(end 127.917448 -129.819146)
		(width 0.1651)
		(layer "B.Cu")
		(net "M_K_DQS_DN<5>")
	)
	(segment
		(start 129.276856 -129.970276)
		(end 128.966976 -130.280156)
		(width 0.14224)
		(layer "In2.Cu")
		(net "M_K_DQS_DN<5>")
	)
	(segment
		(start 128.254506 -130.640074)
		(end 128.254506 -131.9022)
		(width 0.14224)
		(layer "In2.Cu")
		(net "M_K_DQS_DN<5>")
	)
	(segment
		(start 119.631968 -124.085096)
		(end 121.540778 -124.085096)
		(width 0.14224)
		(layer "In2.Cu")
		(net "M_K_DQS_DN<5>")
	)
	(segment
		(start 128.254506 -135.240776)
		(end 128.687576 -135.673846)
		(width 0.14224)
		(layer "In2.Cu")
		(net "M_K_DQS_DN<5>")
	)
	(segment
		(start 128.254506 -131.9022)
		(end 128.043686 -132.11302)
		(width 0.14224)
		(layer "In2.Cu")
		(net "M_K_DQS_DN<5>")
	)
	(segment
		(start 129.152904 -125.279912)
		(end 129.152904 -125.533912)
		(width 0.14224)
		(layer "In2.Cu")
		(net "M_K_DQS_DN<5>")
	)
	(segment
		(start 129.119376 -127.524002)
		(end 129.276856 -127.681482)
		(width 0.14224)
		(layer "In2.Cu")
		(net "M_K_DQS_DN<5>")
	)
	(segment
		(start 125.244098 -124.242576)
		(end 125.401578 -124.085096)
		(width 0.14224)
		(layer "In2.Cu")
		(net "M_K_DQS_DN<5>")
	)
	(segment
		(start 128.535938 -124.242576)
		(end 128.693418 -124.085096)
		(width 0.14224)
		(layer "In2.Cu")
		(net "M_K_DQS_DN<5>")
	)
	(segment
		(start 124.832618 -124.085096)
		(end 124.990098 -124.242576)
		(width 0.14224)
		(layer "In2.Cu")
		(net "M_K_DQS_DN<5>")
	)
	(segment
		(start 122.521218 -124.242576)
		(end 122.775218 -124.242576)
		(width 0.14224)
		(layer "In2.Cu")
		(net "M_K_DQS_DN<5>")
	)
	(segment
		(start 111.505492 -106.23423)
		(end 111.466122 -106.2736)
		(width 0.0889)
		(layer "In2.Cu")
		(net "M_K_DQS_DN<5>")
	)
	(segment
		(start 128.043686 -132.11302)
		(end 128.043686 -133.77418)
		(width 0.14224)
		(layer "In2.Cu")
		(net "M_K_DQS_DN<5>")
	)
	(segment
		(start 128.281938 -124.242576)
		(end 128.535938 -124.242576)
		(width 0.14224)
		(layer "In2.Cu")
		(net "M_K_DQS_DN<5>")
	)
	(segment
		(start 127.301498 -124.085096)
		(end 127.458978 -124.242576)
		(width 0.14224)
		(layer "In2.Cu")
		(net "M_K_DQS_DN<5>")
	)
	(segment
		(start 124.009658 -124.085096)
		(end 124.167138 -124.242576)
		(width 0.14224)
		(layer "In2.Cu")
		(net "M_K_DQS_DN<5>")
	)
	(segment
		(start 122.932698 -124.085096)
		(end 123.186698 -124.085096)
		(width 0.14224)
		(layer "In2.Cu")
		(net "M_K_DQS_DN<5>")
	)
	(segment
		(start 129.276856 -127.112522)
		(end 129.119376 -127.270002)
		(width 0.14224)
		(layer "In2.Cu")
		(net "M_K_DQS_DN<5>")
	)
	(segment
		(start 122.109738 -124.085096)
		(end 122.363738 -124.085096)
		(width 0.14224)
		(layer "In2.Cu")
		(net "M_K_DQS_DN<5>")
	)
	(segment
		(start 128.124458 -124.085096)
		(end 128.281938 -124.242576)
		(width 0.14224)
		(layer "In2.Cu")
		(net "M_K_DQS_DN<5>")
	)
	(segment
		(start 129.119376 -128.092962)
		(end 129.119376 -128.346962)
		(width 0.14224)
		(layer "In2.Cu")
		(net "M_K_DQS_DN<5>")
	)
	(segment
		(start 129.16154 -126.423166)
		(end 129.276856 -126.538482)
		(width 0.14224)
		(layer "In2.Cu")
		(net "M_K_DQS_DN<5>")
	)
	(segment
		(start 126.636018 -124.242576)
		(end 126.890018 -124.242576)
		(width 0.14224)
		(layer "In2.Cu")
		(net "M_K_DQS_DN<5>")
	)
	(segment
		(start 127.458978 -124.242576)
		(end 127.712978 -124.242576)
		(width 0.14224)
		(layer "In2.Cu")
		(net "M_K_DQS_DN<5>")
	)
	(segment
		(start 114.033046 -100.481892)
		(end 114.033046 -100.59416)
		(width 0.0889)
		(layer "In2.Cu")
		(net "M_K_DQS_DN<5>")
	)
	(segment
		(start 129.16154 -126.169166)
		(end 129.16154 -126.423166)
		(width 0.14224)
		(layer "In2.Cu")
		(net "M_K_DQS_DN<5>")
	)
	(segment
		(start 129.276856 -125.15596)
		(end 129.152904 -125.279912)
		(width 0.14224)
		(layer "In2.Cu")
		(net "M_K_DQS_DN<5>")
	)
	(segment
		(start 129.119376 -128.915922)
		(end 129.119376 -129.169922)
		(width 0.14224)
		(layer "In2.Cu")
		(net "M_K_DQS_DN<5>")
	)
	(segment
		(start 129.276856 -125.657864)
		(end 129.276856 -126.05385)
		(width 0.14224)
		(layer "In2.Cu")
		(net "M_K_DQS_DN<5>")
	)
	(segment
		(start 111.466122 -106.295698)
		(end 111.466122 -112.814608)
		(width 0.14224)
		(layer "In2.Cu")
		(net "M_K_DQS_DN<5>")
	)
	(segment
		(start 123.344178 -124.242576)
		(end 123.598178 -124.242576)
		(width 0.14224)
		(layer "In2.Cu")
		(net "M_K_DQS_DN<5>")
	)
	(segment
		(start 110.706662 -113.85296)
		(end 111.02467 -114.170968)
		(width 0.14224)
		(layer "In2.Cu")
		(net "M_K_DQS_DN<5>")
	)
	(segment
		(start 126.478538 -124.085096)
		(end 126.636018 -124.242576)
		(width 0.14224)
		(layer "In2.Cu")
		(net "M_K_DQS_DN<5>")
	)
	(segment
		(start 128.614424 -130.280156)
		(end 128.254506 -130.640074)
		(width 0.14224)
		(layer "In2.Cu")
		(net "M_K_DQS_DN<5>")
	)
	(segment
		(start 124.578618 -124.085096)
		(end 124.832618 -124.085096)
		(width 0.14224)
		(layer "In2.Cu")
		(net "M_K_DQS_DN<5>")
	)
	(segment
		(start 126.890018 -124.242576)
		(end 127.047498 -124.085096)
		(width 0.14224)
		(layer "In2.Cu")
		(net "M_K_DQS_DN<5>")
	)
	(segment
		(start 114.033046 -100.59416)
		(end 113.499392 -101.127814)
		(width 0.0889)
		(layer "In2.Cu")
		(net "M_K_DQS_DN<5>")
	)
	(segment
		(start 129.152904 -125.533912)
		(end 129.276856 -125.657864)
		(width 0.14224)
		(layer "In2.Cu")
		(net "M_K_DQS_DN<5>")
	)
	(segment
		(start 128.966976 -130.280156)
		(end 128.687576 -130.280156)
		(width 0.14224)
		(layer "In2.Cu")
		(net "M_K_DQS_DN<5>")
	)
	(segment
		(start 111.466122 -115.91925)
		(end 119.631968 -124.085096)
		(width 0.14224)
		(layer "In2.Cu")
		(net "M_K_DQS_DN<5>")
	)
	(segment
		(start 121.540778 -124.085096)
		(end 121.698258 -124.242576)
		(width 0.14224)
		(layer "In2.Cu")
		(net "M_K_DQS_DN<5>")
	)
	(segment
		(start 129.276856 -124.349002)
		(end 129.276856 -125.15596)
		(width 0.14224)
		(layer "In2.Cu")
		(net "M_K_DQS_DN<5>")
	)
	(segment
		(start 123.755658 -124.085096)
		(end 124.009658 -124.085096)
		(width 0.14224)
		(layer "In2.Cu")
		(net "M_K_DQS_DN<5>")
	)
	(segment
		(start 129.119376 -127.270002)
		(end 129.119376 -127.524002)
		(width 0.14224)
		(layer "In2.Cu")
		(net "M_K_DQS_DN<5>")
	)
	(segment
		(start 129.276856 -128.758442)
		(end 129.119376 -128.915922)
		(width 0.14224)
		(layer "In2.Cu")
		(net "M_K_DQS_DN<5>")
	)
	(segment
		(start 112.16259 -103.963216)
		(end 111.505492 -104.620314)
		(width 0.0889)
		(layer "In2.Cu")
		(net "M_K_DQS_DN<5>")
	)
	(segment
		(start 113.499392 -101.127814)
		(end 113.499392 -101.839014)
		(width 0.0889)
		(layer "In2.Cu")
		(net "M_K_DQS_DN<5>")
	)
	(segment
		(start 123.186698 -124.085096)
		(end 123.344178 -124.242576)
		(width 0.14224)
		(layer "In2.Cu")
		(net "M_K_DQS_DN<5>")
	)
	(segment
		(start 111.311182 -112.969548)
		(end 111.013494 -112.969548)
		(width 0.14224)
		(layer "In2.Cu")
		(net "M_K_DQS_DN<5>")
	)
	(segment
		(start 122.775218 -124.242576)
		(end 122.932698 -124.085096)
		(width 0.14224)
		(layer "In2.Cu")
		(net "M_K_DQS_DN<5>")
	)
	(segment
		(start 128.687576 -130.280156)
		(end 128.614424 -130.280156)
		(width 0.14224)
		(layer "In2.Cu")
		(net "M_K_DQS_DN<5>")
	)
	(segment
		(start 121.698258 -124.242576)
		(end 121.952258 -124.242576)
		(width 0.14224)
		(layer "In2.Cu")
		(net "M_K_DQS_DN<5>")
	)
	(segment
		(start 112.16259 -102.73411)
		(end 112.16259 -103.963216)
		(width 0.0889)
		(layer "In2.Cu")
		(net "M_K_DQS_DN<5>")
	)
	(segment
		(start 111.311182 -114.170968)
		(end 111.466122 -114.325908)
		(width 0.14224)
		(layer "In2.Cu")
		(net "M_K_DQS_DN<5>")
	)
	(segment
		(start 129.276856 -126.05385)
		(end 129.16154 -126.169166)
		(width 0.14224)
		(layer "In2.Cu")
		(net "M_K_DQS_DN<5>")
	)
	(segment
		(start 129.276856 -127.935482)
		(end 129.119376 -128.092962)
		(width 0.14224)
		(layer "In2.Cu")
		(net "M_K_DQS_DN<5>")
	)
	(segment
		(start 124.990098 -124.242576)
		(end 125.244098 -124.242576)
		(width 0.14224)
		(layer "In2.Cu")
		(net "M_K_DQS_DN<5>")
	)
	(segment
		(start 129.276856 -127.681482)
		(end 129.276856 -127.935482)
		(width 0.14224)
		(layer "In2.Cu")
		(net "M_K_DQS_DN<5>")
	)
	(segment
		(start 129.276856 -128.504442)
		(end 129.276856 -128.758442)
		(width 0.14224)
		(layer "In2.Cu")
		(net "M_K_DQS_DN<5>")
	)
	(segment
		(start 111.466122 -114.325908)
		(end 111.466122 -115.91925)
		(width 0.14224)
		(layer "In2.Cu")
		(net "M_K_DQS_DN<5>")
	)
	(segment
		(start 111.505492 -104.620314)
		(end 111.505492 -106.23423)
		(width 0.0889)
		(layer "In2.Cu")
		(net "M_K_DQS_DN<5>")
	)
	(segment
		(start 129.276856 -126.538482)
		(end 129.276856 -127.112522)
		(width 0.14224)
		(layer "In2.Cu")
		(net "M_K_DQS_DN<5>")
	)
	(segment
		(start 128.043686 -133.77418)
		(end 128.254506 -133.985)
		(width 0.14224)
		(layer "In2.Cu")
		(net "M_K_DQS_DN<5>")
	)
	(segment
		(start 123.598178 -124.242576)
		(end 123.755658 -124.085096)
		(width 0.14224)
		(layer "In2.Cu")
		(net "M_K_DQS_DN<5>")
	)
	(segment
		(start 127.870458 -124.085096)
		(end 128.124458 -124.085096)
		(width 0.14224)
		(layer "In2.Cu")
		(net "M_K_DQS_DN<5>")
	)
	(segment
		(start 111.02467 -114.170968)
		(end 111.311182 -114.170968)
		(width 0.14224)
		(layer "In2.Cu")
		(net "M_K_DQS_DN<5>")
	)
	(segment
		(start 124.167138 -124.242576)
		(end 124.421138 -124.242576)
		(width 0.14224)
		(layer "In2.Cu")
		(net "M_K_DQS_DN<5>")
	)
	(segment
		(start 112.971072 -102.367334)
		(end 112.529366 -102.367334)
		(width 0.0889)
		(layer "In2.Cu")
		(net "M_K_DQS_DN<5>")
	)
	(segment
		(start 127.047498 -124.085096)
		(end 127.301498 -124.085096)
		(width 0.14224)
		(layer "In2.Cu")
		(net "M_K_DQS_DN<5>")
	)
	(segment
		(start 112.529366 -102.367334)
		(end 112.16259 -102.73411)
		(width 0.0889)
		(layer "In2.Cu")
		(net "M_K_DQS_DN<5>")
	)
	(segment
		(start 110.706662 -113.27638)
		(end 110.706662 -113.85296)
		(width 0.14224)
		(layer "In2.Cu")
		(net "M_K_DQS_DN<5>")
	)
	(segment
		(start 128.693418 -124.085096)
		(end 129.01295 -124.085096)
		(width 0.14224)
		(layer "In2.Cu")
		(net "M_K_DQS_DN<5>")
	)
	(segment
		(start 122.363738 -124.085096)
		(end 122.521218 -124.242576)
		(width 0.14224)
		(layer "In2.Cu")
		(net "M_K_DQS_DN<5>")
	)
	(segment
		(start 111.013494 -112.969548)
		(end 110.706662 -113.27638)
		(width 0.14224)
		(layer "In2.Cu")
		(net "M_K_DQS_DN<5>")
	)
	(segment
		(start 111.466122 -106.2736)
		(end 111.466122 -106.295698)
		(width 0.0889)
		(layer "In2.Cu")
		(net "M_K_DQS_DN<5>")
	)
	(segment
		(start 127.712978 -124.242576)
		(end 127.870458 -124.085096)
		(width 0.14224)
		(layer "In2.Cu")
		(net "M_K_DQS_DN<5>")
	)
	(segment
		(start 129.276856 -129.327402)
		(end 129.276856 -129.970276)
		(width 0.14224)
		(layer "In2.Cu")
		(net "M_K_DQS_DN<5>")
	)
	(segment
		(start 128.254506 -133.985)
		(end 128.254506 -135.240776)
		(width 0.14224)
		(layer "In2.Cu")
		(net "M_K_DQS_DN<5>")
	)
	(segment
		(start 111.466122 -112.814608)
		(end 111.311182 -112.969548)
		(width 0.14224)
		(layer "In2.Cu")
		(net "M_K_DQS_DN<5>")
	)
	(segment
		(start 113.499392 -101.839014)
		(end 112.971072 -102.367334)
		(width 0.0889)
		(layer "In2.Cu")
		(net "M_K_DQS_DN<5>")
	)
	(segment
		(start 129.01295 -124.085096)
		(end 129.276856 -124.349002)
		(width 0.14224)
		(layer "In2.Cu")
		(net "M_K_DQS_DN<5>")
	)
	(segment
		(start 129.119376 -129.169922)
		(end 129.276856 -129.327402)
		(width 0.14224)
		(layer "In2.Cu")
		(net "M_K_DQS_DN<5>")
	)
	(segment
		(start 124.421138 -124.242576)
		(end 124.578618 -124.085096)
		(width 0.14224)
		(layer "In2.Cu")
		(net "M_K_DQS_DN<5>")
	)
	(segment
		(start 129.119376 -128.346962)
		(end 129.276856 -128.504442)
		(width 0.14224)
		(layer "In2.Cu")
		(net "M_K_DQS_DN<5>")
	)
	(segment
		(start 121.952258 -124.242576)
		(end 122.109738 -124.085096)
		(width 0.14224)
		(layer "In2.Cu")
		(net "M_K_DQS_DN<5>")
	)
	(segment
		(start 125.401578 -124.085096)
		(end 126.478538 -124.085096)
		(width 0.14224)
		(layer "In2.Cu")
		(net "M_K_DQS_DN<5>")
	)
	(arc
		(start 113.632742 -99.490784)
		(mid 113.784214 -99.895978)
		(end 113.979452 -100.281994)
		(width 0.0889)
		(layer "In2.Cu")
		(net "M_K_DQS_DN<5>")
	)
	(arc
		(start 113.979452 -100.281994)
		(mid 114.019406 -100.378418)
		(end 114.033046 -100.481892)
		(width 0.0889)
		(layer "In2.Cu")
		(net "M_K_DQS_DN<5>")
	)
	(segment
		(start 112.52073 -119.376698)
		(end 112.97031 -119.376698)
		(width 0.1651)
		(layer "F.Cu")
		(net "M_K_DQS_DN<4>")
	)
	(segment
		(start 112.32007 -118.247414)
		(end 112.106456 -118.461028)
		(width 0.1651)
		(layer "F.Cu")
		(net "M_K_DQS_DN<4>")
	)
	(segment
		(start 119.825008 -130.039872)
		(end 119.584724 -130.280156)
		(width 0.1651)
		(layer "F.Cu")
		(net "M_K_DQS_DN<4>")
	)
	(segment
		(start 115.32489 -121.0564)
		(end 115.32489 -121.308368)
		(width 0.1651)
		(layer "F.Cu")
		(net "M_K_DQS_DN<4>")
	)
	(segment
		(start 111.32566 -115.069874)
		(end 111.505238 -115.069874)
		(width 0.1651)
		(layer "F.Cu")
		(net "M_K_DQS_DN<4>")
	)
	(segment
		(start 112.19307 -117.154706)
		(end 112.19307 -117.408706)
		(width 0.1651)
		(layer "F.Cu")
		(net "M_K_DQS_DN<4>")
	)
	(segment
		(start 119.698008 -128.035558)
		(end 119.825008 -128.162558)
		(width 0.1651)
		(layer "F.Cu")
		(net "M_K_DQS_DN<4>")
	)
	(segment
		(start 109.759242 -106.570526)
		(end 109.759242 -112.682274)
		(width 0.1016)
		(layer "F.Cu")
		(net "M_K_DQS_DN<4>")
	)
	(segment
		(start 110.60684 -114.171476)
		(end 110.60684 -114.351054)
		(width 0.1651)
		(layer "F.Cu")
		(net "M_K_DQS_DN<4>")
	)
	(segment
		(start 116.914168 -123.913646)
		(end 117.094 -124.093224)
		(width 0.1651)
		(layer "F.Cu")
		(net "M_K_DQS_DN<4>")
	)
	(segment
		(start 118.840504 -125.839728)
		(end 119.063262 -125.839728)
		(width 0.1651)
		(layer "F.Cu")
		(net "M_K_DQS_DN<4>")
	)
	(segment
		(start 109.759242 -112.682274)
		(end 110.157768 -113.0808)
		(width 0.1016)
		(layer "F.Cu")
		(net "M_K_DQS_DN<4>")
	)
	(segment
		(start 114.612674 -120.996202)
		(end 114.838226 -120.77065)
		(width 0.1651)
		(layer "F.Cu")
		(net "M_K_DQS_DN<4>")
	)
	(segment
		(start 110.485682 -103.364538)
		(end 110.527592 -103.406448)
		(width 0.0889)
		(layer "F.Cu")
		(net "M_K_DQS_DN<4>")
	)
	(segment
		(start 114.080036 -120.996202)
		(end 114.612674 -120.996202)
		(width 0.1651)
		(layer "F.Cu")
		(net "M_K_DQS_DN<4>")
	)
	(segment
		(start 119.825008 -129.686558)
		(end 119.825008 -130.039872)
		(width 0.1651)
		(layer "F.Cu")
		(net "M_K_DQS_DN<4>")
	)
	(segment
		(start 110.527592 -104.786176)
		(end 109.860842 -105.452926)
		(width 0.0889)
		(layer "F.Cu")
		(net "M_K_DQS_DN<4>")
	)
	(segment
		(start 119.825008 -128.416558)
		(end 119.698008 -128.543558)
		(width 0.1651)
		(layer "F.Cu")
		(net "M_K_DQS_DN<4>")
	)
	(segment
		(start 115.727734 -122.727212)
		(end 115.907566 -122.90679)
		(width 0.1651)
		(layer "F.Cu")
		(net "M_K_DQS_DN<4>")
	)
	(segment
		(start 115.727734 -122.5042)
		(end 115.727734 -122.727212)
		(width 0.1651)
		(layer "F.Cu")
		(net "M_K_DQS_DN<4>")
	)
	(segment
		(start 118.660672 -125.437138)
		(end 118.660672 -125.66015)
		(width 0.1651)
		(layer "F.Cu")
		(net "M_K_DQS_DN<4>")
	)
	(segment
		(start 115.178078 -121.954544)
		(end 115.727734 -122.5042)
		(width 0.1651)
		(layer "F.Cu")
		(net "M_K_DQS_DN<4>")
	)
	(segment
		(start 110.786672 -114.530886)
		(end 110.96625 -114.530886)
		(width 0.1651)
		(layer "F.Cu")
		(net "M_K_DQS_DN<4>")
	)
	(segment
		(start 119.121682 -135.4582)
		(end 119.337328 -135.673846)
		(width 0.1651)
		(layer "F.Cu")
		(net "M_K_DQS_DN<4>")
	)
	(segment
		(start 116.130324 -122.90679)
		(end 116.309902 -123.086368)
		(width 0.1651)
		(layer "F.Cu")
		(net "M_K_DQS_DN<4>")
	)
	(segment
		(start 112.106456 -118.461028)
		(end 112.106456 -118.962424)
		(width 0.1651)
		(layer "F.Cu")
		(net "M_K_DQS_DN<4>")
	)
	(segment
		(start 119.698008 -128.797558)
		(end 119.825008 -128.924558)
		(width 0.1651)
		(layer "F.Cu")
		(net "M_K_DQS_DN<4>")
	)
	(segment
		(start 113.78565 -119.517922)
		(end 113.78565 -119.832628)
		(width 0.1651)
		(layer "F.Cu")
		(net "M_K_DQS_DN<4>")
	)
	(segment
		(start 118.078504 -124.85497)
		(end 118.078504 -125.077982)
		(width 0.1651)
		(layer "F.Cu")
		(net "M_K_DQS_DN<4>")
	)
	(segment
		(start 110.157768 -113.0808)
		(end 110.157768 -113.3221)
		(width 0.1016)
		(layer "F.Cu")
		(net "M_K_DQS_DN<4>")
	)
	(segment
		(start 119.825008 -127.400558)
		(end 119.825008 -127.654558)
		(width 0.1651)
		(layer "F.Cu")
		(net "M_K_DQS_DN<4>")
	)
	(segment
		(start 118.94947 -137.67054)
		(end 118.949216 -137.67054)
		(width 0.1651)
		(layer "F.Cu")
		(net "M_K_DQS_DN<4>")
	)
	(segment
		(start 119.422672 -126.421896)
		(end 119.64543 -126.421896)
		(width 0.1651)
		(layer "F.Cu")
		(net "M_K_DQS_DN<4>")
	)
	(segment
		(start 119.584724 -130.280156)
		(end 119.337328 -130.280156)
		(width 0.1651)
		(layer "F.Cu")
		(net "M_K_DQS_DN<4>")
	)
	(segment
		(start 116.712238 -123.488704)
		(end 116.914168 -123.690634)
		(width 0.1651)
		(layer "F.Cu")
		(net "M_K_DQS_DN<4>")
	)
	(segment
		(start 112.106456 -118.962424)
		(end 112.52073 -119.376698)
		(width 0.1651)
		(layer "F.Cu")
		(net "M_K_DQS_DN<4>")
	)
	(segment
		(start 118.258336 -125.25756)
		(end 118.481094 -125.25756)
		(width 0.1651)
		(layer "F.Cu")
		(net "M_K_DQS_DN<4>")
	)
	(segment
		(start 112.32007 -117.027706)
		(end 112.19307 -117.154706)
		(width 0.1651)
		(layer "F.Cu")
		(net "M_K_DQS_DN<4>")
	)
	(segment
		(start 119.698008 -129.305558)
		(end 119.698008 -129.559558)
		(width 0.1651)
		(layer "F.Cu")
		(net "M_K_DQS_DN<4>")
	)
	(segment
		(start 117.094 -124.093224)
		(end 117.316758 -124.093224)
		(width 0.1651)
		(layer "F.Cu")
		(net "M_K_DQS_DN<4>")
	)
	(segment
		(start 111.864648 -115.608862)
		(end 112.044226 -115.608862)
		(width 0.1651)
		(layer "F.Cu")
		(net "M_K_DQS_DN<4>")
	)
	(segment
		(start 116.914168 -123.690634)
		(end 116.914168 -123.913646)
		(width 0.1651)
		(layer "F.Cu")
		(net "M_K_DQS_DN<4>")
	)
	(segment
		(start 119.825008 -126.892558)
		(end 119.698008 -127.019558)
		(width 0.1651)
		(layer "F.Cu")
		(net "M_K_DQS_DN<4>")
	)
	(segment
		(start 119.825008 -127.654558)
		(end 119.698008 -127.781558)
		(width 0.1651)
		(layer "F.Cu")
		(net "M_K_DQS_DN<4>")
	)
	(segment
		(start 118.5672 -136.220454)
		(end 118.5672 -135.788654)
		(width 0.1651)
		(layer "F.Cu")
		(net "M_K_DQS_DN<4>")
	)
	(segment
		(start 118.949216 -137.67054)
		(end 118.949216 -136.60247)
		(width 0.1651)
		(layer "F.Cu")
		(net "M_K_DQS_DN<4>")
	)
	(segment
		(start 112.19307 -117.408706)
		(end 112.32007 -117.535706)
		(width 0.1651)
		(layer "F.Cu")
		(net "M_K_DQS_DN<4>")
	)
	(segment
		(start 113.598198 -120.02008)
		(end 113.598198 -120.514364)
		(width 0.1651)
		(layer "F.Cu")
		(net "M_K_DQS_DN<4>")
	)
	(segment
		(start 112.32007 -117.535706)
		(end 112.32007 -118.247414)
		(width 0.1651)
		(layer "F.Cu")
		(net "M_K_DQS_DN<4>")
	)
	(segment
		(start 112.32007 -115.884706)
		(end 112.32007 -117.027706)
		(width 0.1651)
		(layer "F.Cu")
		(net "M_K_DQS_DN<4>")
	)
	(segment
		(start 116.48948 -123.488704)
		(end 116.712238 -123.488704)
		(width 0.1651)
		(layer "F.Cu")
		(net "M_K_DQS_DN<4>")
	)
	(segment
		(start 112.97031 -119.376698)
		(end 113.171224 -119.175784)
		(width 0.1651)
		(layer "F.Cu")
		(net "M_K_DQS_DN<4>")
	)
	(segment
		(start 119.24284 -126.019306)
		(end 119.24284 -126.242318)
		(width 0.1651)
		(layer "F.Cu")
		(net "M_K_DQS_DN<4>")
	)
	(segment
		(start 117.676168 -124.675392)
		(end 117.898926 -124.675392)
		(width 0.1651)
		(layer "F.Cu")
		(net "M_K_DQS_DN<4>")
	)
	(segment
		(start 118.5672 -135.788654)
		(end 118.897654 -135.4582)
		(width 0.1651)
		(layer "F.Cu")
		(net "M_K_DQS_DN<4>")
	)
	(segment
		(start 110.224062 -113.788698)
		(end 110.60684 -114.171476)
		(width 0.1651)
		(layer "F.Cu")
		(net "M_K_DQS_DN<4>")
	)
	(segment
		(start 110.485682 -102.958138)
		(end 110.485682 -103.364538)
		(width 0.0889)
		(layer "F.Cu")
		(net "M_K_DQS_DN<4>")
	)
	(segment
		(start 119.825008 -126.601474)
		(end 119.825008 -126.892558)
		(width 0.1651)
		(layer "F.Cu")
		(net "M_K_DQS_DN<4>")
	)
	(segment
		(start 119.698008 -127.019558)
		(end 119.698008 -127.273558)
		(width 0.1651)
		(layer "F.Cu")
		(net "M_K_DQS_DN<4>")
	)
	(segment
		(start 119.698008 -127.273558)
		(end 119.825008 -127.400558)
		(width 0.1651)
		(layer "F.Cu")
		(net "M_K_DQS_DN<4>")
	)
	(segment
		(start 113.78565 -119.832628)
		(end 113.598198 -120.02008)
		(width 0.1651)
		(layer "F.Cu")
		(net "M_K_DQS_DN<4>")
	)
	(segment
		(start 118.897654 -135.4582)
		(end 119.121682 -135.4582)
		(width 0.1651)
		(layer "F.Cu")
		(net "M_K_DQS_DN<4>")
	)
	(segment
		(start 110.527592 -103.406448)
		(end 110.527592 -104.786176)
		(width 0.0889)
		(layer "F.Cu")
		(net "M_K_DQS_DN<4>")
	)
	(segment
		(start 111.145828 -114.890042)
		(end 111.32566 -115.069874)
		(width 0.1651)
		(layer "F.Cu")
		(net "M_K_DQS_DN<4>")
	)
	(segment
		(start 119.64543 -126.421896)
		(end 119.825008 -126.601474)
		(width 0.1651)
		(layer "F.Cu")
		(net "M_K_DQS_DN<4>")
	)
	(segment
		(start 110.96625 -114.530886)
		(end 111.145828 -114.710464)
		(width 0.1651)
		(layer "F.Cu")
		(net "M_K_DQS_DN<4>")
	)
	(segment
		(start 110.208568 -113.3729)
		(end 110.224062 -113.388394)
		(width 0.1651)
		(layer "F.Cu")
		(net "M_K_DQS_DN<4>")
	)
	(segment
		(start 110.224062 -113.388394)
		(end 110.224062 -113.788698)
		(width 0.1651)
		(layer "F.Cu")
		(net "M_K_DQS_DN<4>")
	)
	(segment
		(start 116.309902 -123.086368)
		(end 116.309902 -123.309126)
		(width 0.1651)
		(layer "F.Cu")
		(net "M_K_DQS_DN<4>")
	)
	(segment
		(start 115.907566 -122.90679)
		(end 116.130324 -122.90679)
		(width 0.1651)
		(layer "F.Cu")
		(net "M_K_DQS_DN<4>")
	)
	(segment
		(start 117.316758 -124.093224)
		(end 117.496336 -124.272802)
		(width 0.1651)
		(layer "F.Cu")
		(net "M_K_DQS_DN<4>")
	)
	(segment
		(start 116.309902 -123.309126)
		(end 116.48948 -123.488704)
		(width 0.1651)
		(layer "F.Cu")
		(net "M_K_DQS_DN<4>")
	)
	(segment
		(start 117.898926 -124.675392)
		(end 118.078504 -124.85497)
		(width 0.1651)
		(layer "F.Cu")
		(net "M_K_DQS_DN<4>")
	)
	(segment
		(start 112.044226 -115.608862)
		(end 112.32007 -115.884706)
		(width 0.1651)
		(layer "F.Cu")
		(net "M_K_DQS_DN<4>")
	)
	(segment
		(start 119.698008 -128.543558)
		(end 119.698008 -128.797558)
		(width 0.1651)
		(layer "F.Cu")
		(net "M_K_DQS_DN<4>")
	)
	(segment
		(start 110.157768 -113.3221)
		(end 110.208568 -113.3729)
		(width 0.1016)
		(layer "F.Cu")
		(net "M_K_DQS_DN<4>")
	)
	(segment
		(start 118.481094 -125.25756)
		(end 118.660672 -125.437138)
		(width 0.1651)
		(layer "F.Cu")
		(net "M_K_DQS_DN<4>")
	)
	(segment
		(start 117.496336 -124.272802)
		(end 117.496336 -124.495814)
		(width 0.1651)
		(layer "F.Cu")
		(net "M_K_DQS_DN<4>")
	)
	(segment
		(start 119.825008 -128.924558)
		(end 119.825008 -129.178558)
		(width 0.1651)
		(layer "F.Cu")
		(net "M_K_DQS_DN<4>")
	)
	(segment
		(start 115.32489 -121.308368)
		(end 115.178078 -121.45518)
		(width 0.1651)
		(layer "F.Cu")
		(net "M_K_DQS_DN<4>")
	)
	(segment
		(start 119.698008 -129.559558)
		(end 119.825008 -129.686558)
		(width 0.1651)
		(layer "F.Cu")
		(net "M_K_DQS_DN<4>")
	)
	(segment
		(start 119.698008 -127.781558)
		(end 119.698008 -128.035558)
		(width 0.1651)
		(layer "F.Cu")
		(net "M_K_DQS_DN<4>")
	)
	(segment
		(start 111.145828 -114.710464)
		(end 111.145828 -114.890042)
		(width 0.1651)
		(layer "F.Cu")
		(net "M_K_DQS_DN<4>")
	)
	(segment
		(start 115.178078 -121.45518)
		(end 115.178078 -121.954544)
		(width 0.1651)
		(layer "F.Cu")
		(net "M_K_DQS_DN<4>")
	)
	(segment
		(start 118.078504 -125.077982)
		(end 118.258336 -125.25756)
		(width 0.1651)
		(layer "F.Cu")
		(net "M_K_DQS_DN<4>")
	)
	(segment
		(start 118.660672 -125.66015)
		(end 118.840504 -125.839728)
		(width 0.1651)
		(layer "F.Cu")
		(net "M_K_DQS_DN<4>")
	)
	(segment
		(start 113.598198 -120.514364)
		(end 114.080036 -120.996202)
		(width 0.1651)
		(layer "F.Cu")
		(net "M_K_DQS_DN<4>")
	)
	(segment
		(start 114.838226 -120.77065)
		(end 115.03914 -120.77065)
		(width 0.1651)
		(layer "F.Cu")
		(net "M_K_DQS_DN<4>")
	)
	(segment
		(start 109.860842 -106.468926)
		(end 109.759242 -106.570526)
		(width 0.0889)
		(layer "F.Cu")
		(net "M_K_DQS_DN<4>")
	)
	(segment
		(start 111.505238 -115.069874)
		(end 111.684816 -115.249452)
		(width 0.1651)
		(layer "F.Cu")
		(net "M_K_DQS_DN<4>")
	)
	(segment
		(start 111.684816 -115.42903)
		(end 111.864648 -115.608862)
		(width 0.1651)
		(layer "F.Cu")
		(net "M_K_DQS_DN<4>")
	)
	(segment
		(start 113.443512 -119.175784)
		(end 113.78565 -119.517922)
		(width 0.1651)
		(layer "F.Cu")
		(net "M_K_DQS_DN<4>")
	)
	(segment
		(start 113.171224 -119.175784)
		(end 113.443512 -119.175784)
		(width 0.1651)
		(layer "F.Cu")
		(net "M_K_DQS_DN<4>")
	)
	(segment
		(start 109.860842 -105.452926)
		(end 109.860842 -106.468926)
		(width 0.0889)
		(layer "F.Cu")
		(net "M_K_DQS_DN<4>")
	)
	(segment
		(start 119.063262 -125.839728)
		(end 119.24284 -126.019306)
		(width 0.1651)
		(layer "F.Cu")
		(net "M_K_DQS_DN<4>")
	)
	(segment
		(start 111.684816 -115.249452)
		(end 111.684816 -115.42903)
		(width 0.1651)
		(layer "F.Cu")
		(net "M_K_DQS_DN<4>")
	)
	(segment
		(start 115.03914 -120.77065)
		(end 115.32489 -121.0564)
		(width 0.1651)
		(layer "F.Cu")
		(net "M_K_DQS_DN<4>")
	)
	(segment
		(start 117.496336 -124.495814)
		(end 117.676168 -124.675392)
		(width 0.1651)
		(layer "F.Cu")
		(net "M_K_DQS_DN<4>")
	)
	(segment
		(start 110.60684 -114.351054)
		(end 110.786672 -114.530886)
		(width 0.1651)
		(layer "F.Cu")
		(net "M_K_DQS_DN<4>")
	)
	(segment
		(start 119.825008 -128.162558)
		(end 119.825008 -128.416558)
		(width 0.1651)
		(layer "F.Cu")
		(net "M_K_DQS_DN<4>")
	)
	(segment
		(start 119.825008 -129.178558)
		(end 119.698008 -129.305558)
		(width 0.1651)
		(layer "F.Cu")
		(net "M_K_DQS_DN<4>")
	)
	(segment
		(start 119.24284 -126.242318)
		(end 119.422672 -126.421896)
		(width 0.1651)
		(layer "F.Cu")
		(net "M_K_DQS_DN<4>")
	)
	(segment
		(start 118.949216 -136.60247)
		(end 118.5672 -136.220454)
		(width 0.1651)
		(layer "F.Cu")
		(net "M_K_DQS_DN<4>")
	)
	(via
		(at 119.337328 -135.673846)
		(size 0.508)
		(drill 0.254)
		(layers "F.Cu" "B.Cu")
		(net "M_K_DQS_DN<4>")
	)
	(via
		(at 119.337328 -130.280156)
		(size 0.508)
		(drill 0.254)
		(layers "F.Cu" "B.Cu")
		(net "M_K_DQS_DN<4>")
	)
	(segment
		(start 118.5672 -130.1496)
		(end 118.9228 -130.5052)
		(width 0.1651)
		(layer "B.Cu")
		(net "M_K_DQS_DN<4>")
	)
	(segment
		(start 119.112284 -130.5052)
		(end 119.337328 -130.280156)
		(width 0.1651)
		(layer "B.Cu")
		(net "M_K_DQS_DN<4>")
	)
	(segment
		(start 118.94947 -128.276096)
		(end 118.94947 -129.182876)
		(width 0.1651)
		(layer "B.Cu")
		(net "M_K_DQS_DN<4>")
	)
	(segment
		(start 118.8212 -129.565146)
		(end 118.5672 -129.819146)
		(width 0.1651)
		(layer "B.Cu")
		(net "M_K_DQS_DN<4>")
	)
	(segment
		(start 118.8212 -129.311146)
		(end 118.8212 -129.565146)
		(width 0.1651)
		(layer "B.Cu")
		(net "M_K_DQS_DN<4>")
	)
	(segment
		(start 118.5672 -129.819146)
		(end 118.5672 -130.1496)
		(width 0.1651)
		(layer "B.Cu")
		(net "M_K_DQS_DN<4>")
	)
	(segment
		(start 118.9228 -130.5052)
		(end 119.112284 -130.5052)
		(width 0.1651)
		(layer "B.Cu")
		(net "M_K_DQS_DN<4>")
	)
	(segment
		(start 118.94947 -129.182876)
		(end 118.8212 -129.311146)
		(width 0.1651)
		(layer "B.Cu")
		(net "M_K_DQS_DN<4>")
	)
	(segment
		(start 119.337328 -135.673846)
		(end 118.904258 -135.240776)
		(width 0.14224)
		(layer "In2.Cu")
		(net "M_K_DQS_DN<4>")
	)
	(segment
		(start 118.904258 -130.62331)
		(end 119.247412 -130.280156)
		(width 0.14224)
		(layer "In2.Cu")
		(net "M_K_DQS_DN<4>")
	)
	(segment
		(start 118.904258 -135.240776)
		(end 118.904258 -133.984746)
		(width 0.14224)
		(layer "In2.Cu")
		(net "M_K_DQS_DN<4>")
	)
	(segment
		(start 118.904258 -131.902454)
		(end 118.904258 -130.62331)
		(width 0.14224)
		(layer "In2.Cu")
		(net "M_K_DQS_DN<4>")
	)
	(segment
		(start 119.247412 -130.280156)
		(end 119.337328 -130.280156)
		(width 0.14224)
		(layer "In2.Cu")
		(net "M_K_DQS_DN<4>")
	)
	(segment
		(start 118.693692 -133.77418)
		(end 118.693692 -132.11302)
		(width 0.14224)
		(layer "In2.Cu")
		(net "M_K_DQS_DN<4>")
	)
	(segment
		(start 118.693692 -132.11302)
		(end 118.904258 -131.902454)
		(width 0.14224)
		(layer "In2.Cu")
		(net "M_K_DQS_DN<4>")
	)
	(segment
		(start 118.904258 -133.984746)
		(end 118.693692 -133.77418)
		(width 0.14224)
		(layer "In2.Cu")
		(net "M_K_DQS_DN<4>")
	)
	(segment
		(start 63.69939 -136.60247)
		(end 63.317374 -136.220454)
		(width 0.1651)
		(layer "F.Cu")
		(net "M_K_DQS_DN<3>")
	)
	(segment
		(start 77.192886 -97.690686)
		(end 76.621386 -97.690686)
		(width 0.1651)
		(layer "F.Cu")
		(net "M_K_DQS_DN<3>")
	)
	(segment
		(start 63.647828 -135.4582)
		(end 63.871856 -135.4582)
		(width 0.1651)
		(layer "F.Cu")
		(net "M_K_DQS_DN<3>")
	)
	(segment
		(start 63.69939 -137.67054)
		(end 63.69939 -136.60247)
		(width 0.1651)
		(layer "F.Cu")
		(net "M_K_DQS_DN<3>")
	)
	(segment
		(start 63.317374 -135.788654)
		(end 63.647828 -135.4582)
		(width 0.1651)
		(layer "F.Cu")
		(net "M_K_DQS_DN<3>")
	)
	(segment
		(start 63.871856 -135.4582)
		(end 64.087502 -135.673846)
		(width 0.1651)
		(layer "F.Cu")
		(net "M_K_DQS_DN<3>")
	)
	(segment
		(start 63.317374 -136.220454)
		(end 63.317374 -135.788654)
		(width 0.1651)
		(layer "F.Cu")
		(net "M_K_DQS_DN<3>")
	)
	(via
		(at 64.087502 -135.673846)
		(size 0.508)
		(drill 0.254)
		(layers "F.Cu" "B.Cu")
		(net "M_K_DQS_DN<3>")
	)
	(via
		(at 76.621386 -97.690686)
		(size 0.508)
		(drill 0.254)
		(layers "F.Cu" "B.Cu")
		(net "M_K_DQS_DN<3>")
	)
	(via
		(at 64.087502 -130.280156)
		(size 0.508)
		(drill 0.254)
		(layers "F.Cu" "B.Cu")
		(net "M_K_DQS_DN<3>")
	)
	(segment
		(start 63.571374 -129.565146)
		(end 63.317374 -129.819146)
		(width 0.1651)
		(layer "B.Cu")
		(net "M_K_DQS_DN<3>")
	)
	(segment
		(start 63.69939 -128.276096)
		(end 63.69939 -129.18313)
		(width 0.1651)
		(layer "B.Cu")
		(net "M_K_DQS_DN<3>")
	)
	(segment
		(start 63.862458 -130.5052)
		(end 64.087502 -130.280156)
		(width 0.1651)
		(layer "B.Cu")
		(net "M_K_DQS_DN<3>")
	)
	(segment
		(start 63.571374 -129.311146)
		(end 63.571374 -129.565146)
		(width 0.1651)
		(layer "B.Cu")
		(net "M_K_DQS_DN<3>")
	)
	(segment
		(start 63.672974 -130.5052)
		(end 63.862458 -130.5052)
		(width 0.1651)
		(layer "B.Cu")
		(net "M_K_DQS_DN<3>")
	)
	(segment
		(start 63.317374 -130.1496)
		(end 63.672974 -130.5052)
		(width 0.1651)
		(layer "B.Cu")
		(net "M_K_DQS_DN<3>")
	)
	(segment
		(start 63.69939 -129.18313)
		(end 63.571374 -129.311146)
		(width 0.1651)
		(layer "B.Cu")
		(net "M_K_DQS_DN<3>")
	)
	(segment
		(start 63.317374 -129.819146)
		(end 63.317374 -130.1496)
		(width 0.1651)
		(layer "B.Cu")
		(net "M_K_DQS_DN<3>")
	)
	(segment
		(start 64.519302 -123.714764)
		(end 64.676782 -123.872244)
		(width 0.14224)
		(layer "In2.Cu")
		(net "M_K_DQS_DN<3>")
	)
	(segment
		(start 64.676782 -118.827296)
		(end 64.676782 -119.188484)
		(width 0.14224)
		(layer "In2.Cu")
		(net "M_K_DQS_DN<3>")
	)
	(segment
		(start 64.519302 -127.575564)
		(end 64.519302 -127.829564)
		(width 0.14224)
		(layer "In2.Cu")
		(net "M_K_DQS_DN<3>")
	)
	(segment
		(start 64.519302 -128.652524)
		(end 64.676782 -128.810004)
		(width 0.14224)
		(layer "In2.Cu")
		(net "M_K_DQS_DN<3>")
	)
	(segment
		(start 64.676782 -120.834404)
		(end 64.519302 -120.991884)
		(width 0.14224)
		(layer "In2.Cu")
		(net "M_K_DQS_DN<3>")
	)
	(segment
		(start 64.676782 -119.757444)
		(end 64.676782 -120.011444)
		(width 0.14224)
		(layer "In2.Cu")
		(net "M_K_DQS_DN<3>")
	)
	(segment
		(start 64.446658 -115.600734)
		(end 64.115696 -115.931696)
		(width 0.14224)
		(layer "In2.Cu")
		(net "M_K_DQS_DN<3>")
	)
	(segment
		(start 64.90716 -115.600734)
		(end 64.446658 -115.600734)
		(width 0.14224)
		(layer "In2.Cu")
		(net "M_K_DQS_DN<3>")
	)
	(segment
		(start 64.996568 -117.656102)
		(end 64.996568 -117.910102)
		(width 0.14224)
		(layer "In2.Cu")
		(net "M_K_DQS_DN<3>")
	)
	(segment
		(start 64.676782 -124.952506)
		(end 64.522604 -125.106684)
		(width 0.14224)
		(layer "In2.Cu")
		(net "M_K_DQS_DN<3>")
	)
	(segment
		(start 64.415416 -114.23523)
		(end 65.128648 -114.948462)
		(width 0.14224)
		(layer "In2.Cu")
		(net "M_K_DQS_DN<3>")
	)
	(segment
		(start 64.519302 -127.829564)
		(end 64.676782 -127.987044)
		(width 0.14224)
		(layer "In2.Cu")
		(net "M_K_DQS_DN<3>")
	)
	(segment
		(start 63.443612 -132.11302)
		(end 63.443612 -133.77418)
		(width 0.14224)
		(layer "In2.Cu")
		(net "M_K_DQS_DN<3>")
	)
	(segment
		(start 67.787012 -104.737916)
		(end 67.731132 -104.737916)
		(width 0.0889)
		(layer "In2.Cu")
		(net "M_K_DQS_DN<3>")
	)
	(segment
		(start 74.06386 -99.576636)
		(end 74.028046 -99.576636)
		(width 0.0889)
		(layer "In2.Cu")
		(net "M_K_DQS_DN<3>")
	)
	(segment
		(start 64.519302 -119.345964)
		(end 64.519302 -119.599964)
		(width 0.14224)
		(layer "In2.Cu")
		(net "M_K_DQS_DN<3>")
	)
	(segment
		(start 64.676782 -122.226324)
		(end 64.676782 -122.480324)
		(width 0.14224)
		(layer "In2.Cu")
		(net "M_K_DQS_DN<3>")
	)
	(segment
		(start 63.654432 -131.9022)
		(end 63.443612 -132.11302)
		(width 0.14224)
		(layer "In2.Cu")
		(net "M_K_DQS_DN<3>")
	)
	(segment
		(start 64.541146 -117.012974)
		(end 64.952626 -117.012974)
		(width 0.14224)
		(layer "In2.Cu")
		(net "M_K_DQS_DN<3>")
	)
	(segment
		(start 63.654432 -135.240776)
		(end 64.087502 -135.673846)
		(width 0.14224)
		(layer "In2.Cu")
		(net "M_K_DQS_DN<3>")
	)
	(segment
		(start 64.519302 -123.460764)
		(end 64.519302 -123.714764)
		(width 0.14224)
		(layer "In2.Cu")
		(net "M_K_DQS_DN<3>")
	)
	(segment
		(start 64.560196 -111.375698)
		(end 64.560196 -112.230154)
		(width 0.14224)
		(layer "In2.Cu")
		(net "M_K_DQS_DN<3>")
	)
	(segment
		(start 64.522604 -125.106684)
		(end 64.522604 -125.360684)
		(width 0.14224)
		(layer "In2.Cu")
		(net "M_K_DQS_DN<3>")
	)
	(segment
		(start 64.952626 -117.012974)
		(end 65.154048 -117.214396)
		(width 0.14224)
		(layer "In2.Cu")
		(net "M_K_DQS_DN<3>")
	)
	(segment
		(start 65.128648 -114.948462)
		(end 65.128648 -115.379246)
		(width 0.14224)
		(layer "In2.Cu")
		(net "M_K_DQS_DN<3>")
	)
	(segment
		(start 64.676782 -122.480324)
		(end 64.519302 -122.637804)
		(width 0.14224)
		(layer "In2.Cu")
		(net "M_K_DQS_DN<3>")
	)
	(segment
		(start 64.01435 -130.280156)
		(end 63.654432 -130.640074)
		(width 0.14224)
		(layer "In2.Cu")
		(net "M_K_DQS_DN<3>")
	)
	(segment
		(start 64.676782 -127.987044)
		(end 64.676782 -128.241044)
		(width 0.14224)
		(layer "In2.Cu")
		(net "M_K_DQS_DN<3>")
	)
	(segment
		(start 71.485252 -101.062536)
		(end 71.452486 -101.062536)
		(width 0.0889)
		(layer "In2.Cu")
		(net "M_K_DQS_DN<3>")
	)
	(segment
		(start 64.676782 -128.241044)
		(end 64.519302 -128.398524)
		(width 0.14224)
		(layer "In2.Cu")
		(net "M_K_DQS_DN<3>")
	)
	(segment
		(start 64.676782 -129.970276)
		(end 64.366902 -130.280156)
		(width 0.14224)
		(layer "In2.Cu")
		(net "M_K_DQS_DN<3>")
	)
	(segment
		(start 73.20534 -100.071936)
		(end 73.165716 -100.071936)
		(width 0.0889)
		(layer "In2.Cu")
		(net "M_K_DQS_DN<3>")
	)
	(segment
		(start 64.519302 -124.537724)
		(end 64.676782 -124.695204)
		(width 0.14224)
		(layer "In2.Cu")
		(net "M_K_DQS_DN<3>")
	)
	(segment
		(start 64.676782 -121.657364)
		(end 64.519302 -121.814844)
		(width 0.14224)
		(layer "In2.Cu")
		(net "M_K_DQS_DN<3>")
	)
	(segment
		(start 64.676782 -124.126244)
		(end 64.519302 -124.283724)
		(width 0.14224)
		(layer "In2.Cu")
		(net "M_K_DQS_DN<3>")
	)
	(segment
		(start 65.154048 -117.498622)
		(end 64.996568 -117.656102)
		(width 0.14224)
		(layer "In2.Cu")
		(net "M_K_DQS_DN<3>")
	)
	(segment
		(start 64.676782 -127.418084)
		(end 64.519302 -127.575564)
		(width 0.14224)
		(layer "In2.Cu")
		(net "M_K_DQS_DN<3>")
	)
	(segment
		(start 63.654432 -130.640074)
		(end 63.654432 -131.9022)
		(width 0.14224)
		(layer "In2.Cu")
		(net "M_K_DQS_DN<3>")
	)
	(segment
		(start 67.731132 -104.737916)
		(end 67.715384 -104.753664)
		(width 0.0889)
		(layer "In2.Cu")
		(net "M_K_DQS_DN<3>")
	)
	(segment
		(start 64.519302 -124.283724)
		(end 64.519302 -124.537724)
		(width 0.14224)
		(layer "In2.Cu")
		(net "M_K_DQS_DN<3>")
	)
	(segment
		(start 66.711068 -105.75798)
		(end 66.711068 -109.224826)
		(width 0.14224)
		(layer "In2.Cu")
		(net "M_K_DQS_DN<3>")
	)
	(segment
		(start 64.519302 -122.637804)
		(end 64.519302 -122.891804)
		(width 0.14224)
		(layer "In2.Cu")
		(net "M_K_DQS_DN<3>")
	)
	(segment
		(start 64.519302 -129.221484)
		(end 64.519302 -129.475484)
		(width 0.14224)
		(layer "In2.Cu")
		(net "M_K_DQS_DN<3>")
	)
	(segment
		(start 64.519302 -129.475484)
		(end 64.676782 -129.632964)
		(width 0.14224)
		(layer "In2.Cu")
		(net "M_K_DQS_DN<3>")
	)
	(segment
		(start 66.711068 -109.224826)
		(end 64.560196 -111.375698)
		(width 0.14224)
		(layer "In2.Cu")
		(net "M_K_DQS_DN<3>")
	)
	(segment
		(start 64.676782 -124.695204)
		(end 64.676782 -124.952506)
		(width 0.14224)
		(layer "In2.Cu")
		(net "M_K_DQS_DN<3>")
	)
	(segment
		(start 64.676782 -125.514862)
		(end 64.676782 -125.809248)
		(width 0.14224)
		(layer "In2.Cu")
		(net "M_K_DQS_DN<3>")
	)
	(segment
		(start 64.519302 -122.891804)
		(end 64.676782 -123.049284)
		(width 0.14224)
		(layer "In2.Cu")
		(net "M_K_DQS_DN<3>")
	)
	(segment
		(start 64.676782 -121.403364)
		(end 64.676782 -121.657364)
		(width 0.14224)
		(layer "In2.Cu")
		(net "M_K_DQS_DN<3>")
	)
	(segment
		(start 64.676782 -120.580404)
		(end 64.676782 -120.834404)
		(width 0.14224)
		(layer "In2.Cu")
		(net "M_K_DQS_DN<3>")
	)
	(segment
		(start 64.676782 -129.064004)
		(end 64.519302 -129.221484)
		(width 0.14224)
		(layer "In2.Cu")
		(net "M_K_DQS_DN<3>")
	)
	(segment
		(start 64.676782 -125.809248)
		(end 64.522858 -125.963172)
		(width 0.14224)
		(layer "In2.Cu")
		(net "M_K_DQS_DN<3>")
	)
	(segment
		(start 64.676782 -126.371096)
		(end 64.676782 -126.595124)
		(width 0.14224)
		(layer "In2.Cu")
		(net "M_K_DQS_DN<3>")
	)
	(segment
		(start 64.519302 -127.006604)
		(end 64.676782 -127.164084)
		(width 0.14224)
		(layer "In2.Cu")
		(net "M_K_DQS_DN<3>")
	)
	(segment
		(start 64.676782 -123.049284)
		(end 64.676782 -123.303284)
		(width 0.14224)
		(layer "In2.Cu")
		(net "M_K_DQS_DN<3>")
	)
	(segment
		(start 75.774042 -98.58629)
		(end 75.741276 -98.58629)
		(width 0.0889)
		(layer "In2.Cu")
		(net "M_K_DQS_DN<3>")
	)
	(segment
		(start 64.560196 -112.230154)
		(end 65.154048 -112.824006)
		(width 0.14224)
		(layer "In2.Cu")
		(net "M_K_DQS_DN<3>")
	)
	(segment
		(start 70.692264 -101.819456)
		(end 67.787012 -104.737916)
		(width 0.0889)
		(layer "In2.Cu")
		(net "M_K_DQS_DN<3>")
	)
	(segment
		(start 64.519302 -120.422924)
		(end 64.676782 -120.580404)
		(width 0.14224)
		(layer "In2.Cu")
		(net "M_K_DQS_DN<3>")
	)
	(segment
		(start 74.919332 -99.081336)
		(end 74.891392 -99.081336)
		(width 0.0889)
		(layer "In2.Cu")
		(net "M_K_DQS_DN<3>")
	)
	(segment
		(start 64.115696 -115.931696)
		(end 64.115696 -116.587524)
		(width 0.14224)
		(layer "In2.Cu")
		(net "M_K_DQS_DN<3>")
	)
	(segment
		(start 64.676782 -126.595124)
		(end 64.519302 -126.752604)
		(width 0.14224)
		(layer "In2.Cu")
		(net "M_K_DQS_DN<3>")
	)
	(segment
		(start 65.154048 -118.35003)
		(end 64.676782 -118.827296)
		(width 0.14224)
		(layer "In2.Cu")
		(net "M_K_DQS_DN<3>")
	)
	(segment
		(start 64.087502 -130.280156)
		(end 64.01435 -130.280156)
		(width 0.14224)
		(layer "In2.Cu")
		(net "M_K_DQS_DN<3>")
	)
	(segment
		(start 70.958202 -101.357938)
		(end 70.692264 -101.819456)
		(width 0.0889)
		(layer "In2.Cu")
		(net "M_K_DQS_DN<3>")
	)
	(segment
		(start 64.115696 -116.587524)
		(end 64.541146 -117.012974)
		(width 0.14224)
		(layer "In2.Cu")
		(net "M_K_DQS_DN<3>")
	)
	(segment
		(start 64.676782 -123.303284)
		(end 64.519302 -123.460764)
		(width 0.14224)
		(layer "In2.Cu")
		(net "M_K_DQS_DN<3>")
	)
	(segment
		(start 64.522604 -125.360684)
		(end 64.676782 -125.514862)
		(width 0.14224)
		(layer "In2.Cu")
		(net "M_K_DQS_DN<3>")
	)
	(segment
		(start 64.519302 -122.068844)
		(end 64.676782 -122.226324)
		(width 0.14224)
		(layer "In2.Cu")
		(net "M_K_DQS_DN<3>")
	)
	(segment
		(start 64.519302 -128.398524)
		(end 64.519302 -128.652524)
		(width 0.14224)
		(layer "In2.Cu")
		(net "M_K_DQS_DN<3>")
	)
	(segment
		(start 64.676782 -128.810004)
		(end 64.676782 -129.064004)
		(width 0.14224)
		(layer "In2.Cu")
		(net "M_K_DQS_DN<3>")
	)
	(segment
		(start 64.519302 -121.814844)
		(end 64.519302 -122.068844)
		(width 0.14224)
		(layer "In2.Cu")
		(net "M_K_DQS_DN<3>")
	)
	(segment
		(start 63.654432 -133.985)
		(end 63.654432 -135.240776)
		(width 0.14224)
		(layer "In2.Cu")
		(net "M_K_DQS_DN<3>")
	)
	(segment
		(start 64.519302 -119.599964)
		(end 64.676782 -119.757444)
		(width 0.14224)
		(layer "In2.Cu")
		(net "M_K_DQS_DN<3>")
	)
	(segment
		(start 64.522858 -126.217172)
		(end 64.676782 -126.371096)
		(width 0.14224)
		(layer "In2.Cu")
		(net "M_K_DQS_DN<3>")
	)
	(segment
		(start 64.996568 -117.910102)
		(end 65.154048 -118.067582)
		(width 0.14224)
		(layer "In2.Cu")
		(net "M_K_DQS_DN<3>")
	)
	(segment
		(start 64.676782 -119.188484)
		(end 64.519302 -119.345964)
		(width 0.14224)
		(layer "In2.Cu")
		(net "M_K_DQS_DN<3>")
	)
	(segment
		(start 64.519302 -126.752604)
		(end 64.519302 -127.006604)
		(width 0.14224)
		(layer "In2.Cu")
		(net "M_K_DQS_DN<3>")
	)
	(segment
		(start 64.366902 -130.280156)
		(end 64.087502 -130.280156)
		(width 0.14224)
		(layer "In2.Cu")
		(net "M_K_DQS_DN<3>")
	)
	(segment
		(start 64.522858 -125.963172)
		(end 64.522858 -126.217172)
		(width 0.14224)
		(layer "In2.Cu")
		(net "M_K_DQS_DN<3>")
	)
	(segment
		(start 65.154048 -117.214396)
		(end 65.154048 -117.498622)
		(width 0.14224)
		(layer "In2.Cu")
		(net "M_K_DQS_DN<3>")
	)
	(segment
		(start 65.154048 -113.094008)
		(end 64.415416 -113.83264)
		(width 0.14224)
		(layer "In2.Cu")
		(net "M_K_DQS_DN<3>")
	)
	(segment
		(start 64.415416 -113.83264)
		(end 64.415416 -114.23523)
		(width 0.14224)
		(layer "In2.Cu")
		(net "M_K_DQS_DN<3>")
	)
	(segment
		(start 64.519302 -120.168924)
		(end 64.519302 -120.422924)
		(width 0.14224)
		(layer "In2.Cu")
		(net "M_K_DQS_DN<3>")
	)
	(segment
		(start 64.676782 -129.632964)
		(end 64.676782 -129.970276)
		(width 0.14224)
		(layer "In2.Cu")
		(net "M_K_DQS_DN<3>")
	)
	(segment
		(start 65.154048 -112.824006)
		(end 65.154048 -113.094008)
		(width 0.14224)
		(layer "In2.Cu")
		(net "M_K_DQS_DN<3>")
	)
	(segment
		(start 65.128648 -115.379246)
		(end 64.90716 -115.600734)
		(width 0.14224)
		(layer "In2.Cu")
		(net "M_K_DQS_DN<3>")
	)
	(segment
		(start 64.676782 -123.872244)
		(end 64.676782 -124.126244)
		(width 0.14224)
		(layer "In2.Cu")
		(net "M_K_DQS_DN<3>")
	)
	(segment
		(start 64.676782 -127.164084)
		(end 64.676782 -127.418084)
		(width 0.14224)
		(layer "In2.Cu")
		(net "M_K_DQS_DN<3>")
	)
	(segment
		(start 63.443612 -133.77418)
		(end 63.654432 -133.985)
		(width 0.14224)
		(layer "In2.Cu")
		(net "M_K_DQS_DN<3>")
	)
	(segment
		(start 64.676782 -120.011444)
		(end 64.519302 -120.168924)
		(width 0.14224)
		(layer "In2.Cu")
		(net "M_K_DQS_DN<3>")
	)
	(segment
		(start 65.154048 -118.067582)
		(end 65.154048 -118.35003)
		(width 0.14224)
		(layer "In2.Cu")
		(net "M_K_DQS_DN<3>")
	)
	(segment
		(start 64.519302 -121.245884)
		(end 64.676782 -121.403364)
		(width 0.14224)
		(layer "In2.Cu")
		(net "M_K_DQS_DN<3>")
	)
	(segment
		(start 67.715384 -104.753664)
		(end 66.711068 -105.75798)
		(width 0.14224)
		(layer "In2.Cu")
		(net "M_K_DQS_DN<3>")
	)
	(segment
		(start 64.519302 -120.991884)
		(end 64.519302 -121.245884)
		(width 0.14224)
		(layer "In2.Cu")
		(net "M_K_DQS_DN<3>")
	)
	(segment
		(start 72.339962 -100.567236)
		(end 72.315832 -100.567236)
		(width 0.0889)
		(layer "In2.Cu")
		(net "M_K_DQS_DN<3>")
	)
	(arc
		(start 73.165716 -100.071936)
		(mid 72.882499 -100.156217)
		(end 72.675496 -100.367084)
		(width 0.0889)
		(layer "In2.Cu")
		(net "M_K_DQS_DN<3>")
	)
	(arc
		(start 74.392536 -99.376738)
		(mid 74.253792 -99.518771)
		(end 74.06386 -99.576636)
		(width 0.0889)
		(layer "In2.Cu")
		(net "M_K_DQS_DN<3>")
	)
	(arc
		(start 71.816976 -100.862638)
		(mid 71.676897 -101.005374)
		(end 71.485252 -101.062536)
		(width 0.0889)
		(layer "In2.Cu")
		(net "M_K_DQS_DN<3>")
	)
	(arc
		(start 75.251056 -98.881438)
		(mid 75.110977 -99.024174)
		(end 74.919332 -99.081336)
		(width 0.0889)
		(layer "In2.Cu")
		(net "M_K_DQS_DN<3>")
	)
	(arc
		(start 72.675496 -100.367084)
		(mid 72.533813 -100.510888)
		(end 72.339962 -100.567236)
		(width 0.0889)
		(layer "In2.Cu")
		(net "M_K_DQS_DN<3>")
	)
	(arc
		(start 76.621386 -97.690686)
		(mid 76.478687 -97.981233)
		(end 76.248768 -98.2091)
		(width 0.0889)
		(layer "In2.Cu")
		(net "M_K_DQS_DN<3>")
	)
	(arc
		(start 72.315832 -100.567236)
		(mid 72.027687 -100.649555)
		(end 71.816976 -100.862638)
		(width 0.0889)
		(layer "In2.Cu")
		(net "M_K_DQS_DN<3>")
	)
	(arc
		(start 74.028046 -99.576636)
		(mid 73.742622 -99.660103)
		(end 73.534016 -99.872038)
		(width 0.0889)
		(layer "In2.Cu")
		(net "M_K_DQS_DN<3>")
	)
	(arc
		(start 76.109576 -98.386138)
		(mid 75.967893 -98.529942)
		(end 75.774042 -98.58629)
		(width 0.0889)
		(layer "In2.Cu")
		(net "M_K_DQS_DN<3>")
	)
	(arc
		(start 71.452486 -101.062536)
		(mid 71.166921 -101.145945)
		(end 70.958202 -101.357938)
		(width 0.0889)
		(layer "In2.Cu")
		(net "M_K_DQS_DN<3>")
	)
	(arc
		(start 73.534016 -99.872038)
		(mid 73.395272 -100.014071)
		(end 73.20534 -100.071936)
		(width 0.0889)
		(layer "In2.Cu")
		(net "M_K_DQS_DN<3>")
	)
	(arc
		(start 76.248768 -98.2091)
		(mid 76.172819 -98.292625)
		(end 76.109576 -98.386138)
		(width 0.0889)
		(layer "In2.Cu")
		(net "M_K_DQS_DN<3>")
	)
	(arc
		(start 74.891392 -99.081336)
		(mid 74.603247 -99.163655)
		(end 74.392536 -99.376738)
		(width 0.0889)
		(layer "In2.Cu")
		(net "M_K_DQS_DN<3>")
	)
	(arc
		(start 75.741276 -98.58629)
		(mid 75.458059 -98.670571)
		(end 75.251056 -98.881438)
		(width 0.0889)
		(layer "In2.Cu")
		(net "M_K_DQS_DN<3>")
	)
	(segment
		(start 53.96738 -135.788654)
		(end 54.297834 -135.4582)
		(width 0.1651)
		(layer "F.Cu")
		(net "M_K_DQS_DN<2>")
	)
	(segment
		(start 54.349396 -137.67054)
		(end 54.349396 -136.60247)
		(width 0.1651)
		(layer "F.Cu")
		(net "M_K_DQS_DN<2>")
	)
	(segment
		(start 54.349396 -136.60247)
		(end 53.96738 -136.220454)
		(width 0.1651)
		(layer "F.Cu")
		(net "M_K_DQS_DN<2>")
	)
	(segment
		(start 53.96738 -136.220454)
		(end 53.96738 -135.788654)
		(width 0.1651)
		(layer "F.Cu")
		(net "M_K_DQS_DN<2>")
	)
	(segment
		(start 54.297834 -135.4582)
		(end 54.521862 -135.4582)
		(width 0.1651)
		(layer "F.Cu")
		(net "M_K_DQS_DN<2>")
	)
	(segment
		(start 54.521862 -135.4582)
		(end 54.737508 -135.673846)
		(width 0.1651)
		(layer "F.Cu")
		(net "M_K_DQS_DN<2>")
	)
	(segment
		(start 71.183246 -94.223586)
		(end 70.611746 -94.223586)
		(width 0.1651)
		(layer "F.Cu")
		(net "M_K_DQS_DN<2>")
	)
	(via
		(at 54.737508 -130.280156)
		(size 0.508)
		(drill 0.254)
		(layers "F.Cu" "B.Cu")
		(net "M_K_DQS_DN<2>")
	)
	(via
		(at 54.737508 -135.673846)
		(size 0.508)
		(drill 0.254)
		(layers "F.Cu" "B.Cu")
		(net "M_K_DQS_DN<2>")
	)
	(via
		(at 70.611746 -94.223586)
		(size 0.508)
		(drill 0.254)
		(layers "F.Cu" "B.Cu")
		(net "M_K_DQS_DN<2>")
	)
	(segment
		(start 53.96738 -130.1496)
		(end 54.32298 -130.5052)
		(width 0.1651)
		(layer "B.Cu")
		(net "M_K_DQS_DN<2>")
	)
	(segment
		(start 54.22138 -129.565146)
		(end 53.96738 -129.819146)
		(width 0.1651)
		(layer "B.Cu")
		(net "M_K_DQS_DN<2>")
	)
	(segment
		(start 54.512464 -130.5052)
		(end 54.737508 -130.280156)
		(width 0.1651)
		(layer "B.Cu")
		(net "M_K_DQS_DN<2>")
	)
	(segment
		(start 54.32298 -130.5052)
		(end 54.512464 -130.5052)
		(width 0.1651)
		(layer "B.Cu")
		(net "M_K_DQS_DN<2>")
	)
	(segment
		(start 54.349396 -129.18313)
		(end 54.22138 -129.311146)
		(width 0.1651)
		(layer "B.Cu")
		(net "M_K_DQS_DN<2>")
	)
	(segment
		(start 54.349396 -128.276096)
		(end 54.349396 -129.18313)
		(width 0.1651)
		(layer "B.Cu")
		(net "M_K_DQS_DN<2>")
	)
	(segment
		(start 54.22138 -129.311146)
		(end 54.22138 -129.565146)
		(width 0.1651)
		(layer "B.Cu")
		(net "M_K_DQS_DN<2>")
	)
	(segment
		(start 53.96738 -129.819146)
		(end 53.96738 -130.1496)
		(width 0.1651)
		(layer "B.Cu")
		(net "M_K_DQS_DN<2>")
	)
	(segment
		(start 70.611746 -94.223586)
		(end 70.013576 -94.137734)
		(width 0.0889)
		(layer "In2.Cu")
		(net "M_K_DQS_DN<2>")
	)
	(segment
		(start 53.546248 -122.796808)
		(end 53.546248 -123.050808)
		(width 0.14224)
		(layer "In2.Cu")
		(net "M_K_DQS_DN<2>")
	)
	(segment
		(start 53.992526 -127.662686)
		(end 53.992526 -127.885698)
		(width 0.14224)
		(layer "In2.Cu")
		(net "M_K_DQS_DN<2>")
	)
	(segment
		(start 53.546248 -124.696728)
		(end 53.393848 -124.849128)
		(width 0.14224)
		(layer "In2.Cu")
		(net "M_K_DQS_DN<2>")
	)
	(segment
		(start 53.393848 -124.849128)
		(end 53.393848 -125.113288)
		(width 0.14224)
		(layer "In2.Cu")
		(net "M_K_DQS_DN<2>")
	)
	(segment
		(start 69.909436 -94.128082)
		(end 69.774562 -94.12859)
		(width 0.0889)
		(layer "In2.Cu")
		(net "M_K_DQS_DN<2>")
	)
	(segment
		(start 55.250588 -128.920748)
		(end 55.250588 -130.046476)
		(width 0.14224)
		(layer "In2.Cu")
		(net "M_K_DQS_DN<2>")
	)
	(segment
		(start 69.774562 -94.12859)
		(end 68.885816 -94.12859)
		(width 0.0889)
		(layer "In2.Cu")
		(net "M_K_DQS_DN<2>")
	)
	(segment
		(start 53.546248 -122.227848)
		(end 53.393848 -122.380248)
		(width 0.14224)
		(layer "In2.Cu")
		(net "M_K_DQS_DN<2>")
	)
	(segment
		(start 53.439568 -121.826782)
		(end 53.546248 -121.933462)
		(width 0.14224)
		(layer "In2.Cu")
		(net "M_K_DQS_DN<2>")
	)
	(segment
		(start 53.546248 -123.619768)
		(end 53.546248 -123.873768)
		(width 0.14224)
		(layer "In2.Cu")
		(net "M_K_DQS_DN<2>")
	)
	(segment
		(start 54.58206 -128.475232)
		(end 54.761638 -128.65481)
		(width 0.14224)
		(layer "In2.Cu")
		(net "M_K_DQS_DN<2>")
	)
	(segment
		(start 54.304438 -133.985)
		(end 54.304438 -135.240776)
		(width 0.14224)
		(layer "In2.Cu")
		(net "M_K_DQS_DN<2>")
	)
	(segment
		(start 53.393848 -124.026168)
		(end 53.393848 -124.290328)
		(width 0.14224)
		(layer "In2.Cu")
		(net "M_K_DQS_DN<2>")
	)
	(segment
		(start 53.286406 -110.049564)
		(end 52.9082 -110.42777)
		(width 0.14224)
		(layer "In2.Cu")
		(net "M_K_DQS_DN<2>")
	)
	(segment
		(start 53.393848 -125.113288)
		(end 53.546248 -125.265688)
		(width 0.14224)
		(layer "In2.Cu")
		(net "M_K_DQS_DN<2>")
	)
	(segment
		(start 54.304438 -135.240776)
		(end 54.737508 -135.673846)
		(width 0.14224)
		(layer "In2.Cu")
		(net "M_K_DQS_DN<2>")
	)
	(segment
		(start 53.546248 -126.911608)
		(end 53.546248 -127.216408)
		(width 0.14224)
		(layer "In2.Cu")
		(net "M_K_DQS_DN<2>")
	)
	(segment
		(start 53.992526 -127.885698)
		(end 54.172104 -128.065276)
		(width 0.14224)
		(layer "In2.Cu")
		(net "M_K_DQS_DN<2>")
	)
	(segment
		(start 66.458592 -94.447614)
		(end 64.807592 -96.098614)
		(width 0.0889)
		(layer "In2.Cu")
		(net "M_K_DQS_DN<2>")
	)
	(segment
		(start 64.46647 -96.475804)
		(end 58.209688 -102.73284)
		(width 0.14224)
		(layer "In2.Cu")
		(net "M_K_DQS_DN<2>")
	)
	(segment
		(start 53.546248 -126.088648)
		(end 53.546248 -126.342648)
		(width 0.14224)
		(layer "In2.Cu")
		(net "M_K_DQS_DN<2>")
	)
	(segment
		(start 54.664356 -130.280156)
		(end 54.304438 -130.640074)
		(width 0.14224)
		(layer "In2.Cu")
		(net "M_K_DQS_DN<2>")
	)
	(segment
		(start 52.9082 -111.083598)
		(end 53.286406 -111.461804)
		(width 0.14224)
		(layer "In2.Cu")
		(net "M_K_DQS_DN<2>")
	)
	(segment
		(start 54.304438 -130.640074)
		(end 54.304438 -131.9022)
		(width 0.14224)
		(layer "In2.Cu")
		(net "M_K_DQS_DN<2>")
	)
	(segment
		(start 53.546248 -123.873768)
		(end 53.393848 -124.026168)
		(width 0.14224)
		(layer "In2.Cu")
		(net "M_K_DQS_DN<2>")
	)
	(segment
		(start 53.393848 -122.644408)
		(end 53.546248 -122.796808)
		(width 0.14224)
		(layer "In2.Cu")
		(net "M_K_DQS_DN<2>")
	)
	(segment
		(start 55.016908 -130.280156)
		(end 54.737508 -130.280156)
		(width 0.14224)
		(layer "In2.Cu")
		(net "M_K_DQS_DN<2>")
	)
	(segment
		(start 54.924706 -112.29848)
		(end 53.281072 -112.29848)
		(width 0.14224)
		(layer "In2.Cu")
		(net "M_K_DQS_DN<2>")
	)
	(segment
		(start 54.92496 -111.461804)
		(end 55.146448 -111.683292)
		(width 0.14224)
		(layer "In2.Cu")
		(net "M_K_DQS_DN<2>")
	)
	(segment
		(start 54.98465 -128.65481)
		(end 55.250588 -128.920748)
		(width 0.14224)
		(layer "In2.Cu")
		(net "M_K_DQS_DN<2>")
	)
	(segment
		(start 54.093618 -133.77418)
		(end 54.304438 -133.985)
		(width 0.14224)
		(layer "In2.Cu")
		(net "M_K_DQS_DN<2>")
	)
	(segment
		(start 53.393848 -122.380248)
		(end 53.393848 -122.644408)
		(width 0.14224)
		(layer "In2.Cu")
		(net "M_K_DQS_DN<2>")
	)
	(segment
		(start 53.546248 -125.265688)
		(end 53.546248 -125.519688)
		(width 0.14224)
		(layer "In2.Cu")
		(net "M_K_DQS_DN<2>")
	)
	(segment
		(start 53.393848 -125.672088)
		(end 53.393848 -125.936248)
		(width 0.14224)
		(layer "In2.Cu")
		(net "M_K_DQS_DN<2>")
	)
	(segment
		(start 54.92496 -110.049564)
		(end 53.286406 -110.049564)
		(width 0.14224)
		(layer "In2.Cu")
		(net "M_K_DQS_DN<2>")
	)
	(segment
		(start 55.146448 -109.828076)
		(end 54.92496 -110.049564)
		(width 0.14224)
		(layer "In2.Cu")
		(net "M_K_DQS_DN<2>")
	)
	(segment
		(start 53.546248 -121.933462)
		(end 53.546248 -122.227848)
		(width 0.14224)
		(layer "In2.Cu")
		(net "M_K_DQS_DN<2>")
	)
	(segment
		(start 53.393848 -123.467368)
		(end 53.546248 -123.619768)
		(width 0.14224)
		(layer "In2.Cu")
		(net "M_K_DQS_DN<2>")
	)
	(segment
		(start 53.546248 -114.21364)
		(end 53.546248 -121.451878)
		(width 0.14224)
		(layer "In2.Cu")
		(net "M_K_DQS_DN<2>")
	)
	(segment
		(start 53.393848 -125.936248)
		(end 53.546248 -126.088648)
		(width 0.14224)
		(layer "In2.Cu")
		(net "M_K_DQS_DN<2>")
	)
	(segment
		(start 53.393848 -126.495048)
		(end 53.393848 -126.759208)
		(width 0.14224)
		(layer "In2.Cu")
		(net "M_K_DQS_DN<2>")
	)
	(segment
		(start 54.737508 -130.280156)
		(end 54.664356 -130.280156)
		(width 0.14224)
		(layer "In2.Cu")
		(net "M_K_DQS_DN<2>")
	)
	(segment
		(start 64.807592 -96.19107)
		(end 64.538606 -96.460056)
		(width 0.0889)
		(layer "In2.Cu")
		(net "M_K_DQS_DN<2>")
	)
	(segment
		(start 54.172104 -128.065276)
		(end 54.395116 -128.065276)
		(width 0.14224)
		(layer "In2.Cu")
		(net "M_K_DQS_DN<2>")
	)
	(segment
		(start 54.093618 -132.11302)
		(end 54.093618 -133.77418)
		(width 0.14224)
		(layer "In2.Cu")
		(net "M_K_DQS_DN<2>")
	)
	(segment
		(start 53.393848 -123.203208)
		(end 53.393848 -123.467368)
		(width 0.14224)
		(layer "In2.Cu")
		(net "M_K_DQS_DN<2>")
	)
	(segment
		(start 64.482218 -96.460056)
		(end 64.46647 -96.475804)
		(width 0.0889)
		(layer "In2.Cu")
		(net "M_K_DQS_DN<2>")
	)
	(segment
		(start 53.393848 -126.759208)
		(end 53.546248 -126.911608)
		(width 0.14224)
		(layer "In2.Cu")
		(net "M_K_DQS_DN<2>")
	)
	(segment
		(start 53.546248 -124.442728)
		(end 53.546248 -124.696728)
		(width 0.14224)
		(layer "In2.Cu")
		(net "M_K_DQS_DN<2>")
	)
	(segment
		(start 53.546248 -125.519688)
		(end 53.393848 -125.672088)
		(width 0.14224)
		(layer "In2.Cu")
		(net "M_K_DQS_DN<2>")
	)
	(segment
		(start 53.286406 -111.461804)
		(end 54.92496 -111.461804)
		(width 0.14224)
		(layer "In2.Cu")
		(net "M_K_DQS_DN<2>")
	)
	(segment
		(start 53.546248 -123.050808)
		(end 53.393848 -123.203208)
		(width 0.14224)
		(layer "In2.Cu")
		(net "M_K_DQS_DN<2>")
	)
	(segment
		(start 54.58206 -128.25222)
		(end 54.58206 -128.475232)
		(width 0.14224)
		(layer "In2.Cu")
		(net "M_K_DQS_DN<2>")
	)
	(segment
		(start 53.281072 -112.29848)
		(end 52.860448 -112.719104)
		(width 0.14224)
		(layer "In2.Cu")
		(net "M_K_DQS_DN<2>")
	)
	(segment
		(start 53.546248 -126.342648)
		(end 53.393848 -126.495048)
		(width 0.14224)
		(layer "In2.Cu")
		(net "M_K_DQS_DN<2>")
	)
	(segment
		(start 53.439568 -121.558558)
		(end 53.439568 -121.826782)
		(width 0.14224)
		(layer "In2.Cu")
		(net "M_K_DQS_DN<2>")
	)
	(segment
		(start 58.209688 -105.181908)
		(end 55.146448 -108.245148)
		(width 0.14224)
		(layer "In2.Cu")
		(net "M_K_DQS_DN<2>")
	)
	(segment
		(start 53.546248 -121.451878)
		(end 53.439568 -121.558558)
		(width 0.14224)
		(layer "In2.Cu")
		(net "M_K_DQS_DN<2>")
	)
	(segment
		(start 52.860448 -113.52784)
		(end 53.546248 -114.21364)
		(width 0.14224)
		(layer "In2.Cu")
		(net "M_K_DQS_DN<2>")
	)
	(segment
		(start 55.146448 -112.076738)
		(end 54.924706 -112.29848)
		(width 0.14224)
		(layer "In2.Cu")
		(net "M_K_DQS_DN<2>")
	)
	(segment
		(start 53.546248 -127.216408)
		(end 53.992526 -127.662686)
		(width 0.14224)
		(layer "In2.Cu")
		(net "M_K_DQS_DN<2>")
	)
	(segment
		(start 70.013576 -94.137734)
		(end 69.909436 -94.128082)
		(width 0.0889)
		(layer "In2.Cu")
		(net "M_K_DQS_DN<2>")
	)
	(segment
		(start 53.393848 -124.290328)
		(end 53.546248 -124.442728)
		(width 0.14224)
		(layer "In2.Cu")
		(net "M_K_DQS_DN<2>")
	)
	(segment
		(start 54.395116 -128.065276)
		(end 54.58206 -128.25222)
		(width 0.14224)
		(layer "In2.Cu")
		(net "M_K_DQS_DN<2>")
	)
	(segment
		(start 55.146448 -108.245148)
		(end 55.146448 -109.828076)
		(width 0.14224)
		(layer "In2.Cu")
		(net "M_K_DQS_DN<2>")
	)
	(segment
		(start 54.761638 -128.65481)
		(end 54.98465 -128.65481)
		(width 0.14224)
		(layer "In2.Cu")
		(net "M_K_DQS_DN<2>")
	)
	(segment
		(start 64.807592 -96.098614)
		(end 64.807592 -96.19107)
		(width 0.0889)
		(layer "In2.Cu")
		(net "M_K_DQS_DN<2>")
	)
	(segment
		(start 54.304438 -131.9022)
		(end 54.093618 -132.11302)
		(width 0.14224)
		(layer "In2.Cu")
		(net "M_K_DQS_DN<2>")
	)
	(segment
		(start 52.860448 -112.719104)
		(end 52.860448 -113.52784)
		(width 0.14224)
		(layer "In2.Cu")
		(net "M_K_DQS_DN<2>")
	)
	(segment
		(start 52.9082 -110.42777)
		(end 52.9082 -111.083598)
		(width 0.14224)
		(layer "In2.Cu")
		(net "M_K_DQS_DN<2>")
	)
	(segment
		(start 64.538606 -96.460056)
		(end 64.482218 -96.460056)
		(width 0.0889)
		(layer "In2.Cu")
		(net "M_K_DQS_DN<2>")
	)
	(segment
		(start 68.566792 -94.447614)
		(end 66.458592 -94.447614)
		(width 0.0889)
		(layer "In2.Cu")
		(net "M_K_DQS_DN<2>")
	)
	(segment
		(start 58.209688 -102.73284)
		(end 58.209688 -105.181908)
		(width 0.14224)
		(layer "In2.Cu")
		(net "M_K_DQS_DN<2>")
	)
	(segment
		(start 55.146448 -111.683292)
		(end 55.146448 -112.076738)
		(width 0.14224)
		(layer "In2.Cu")
		(net "M_K_DQS_DN<2>")
	)
	(segment
		(start 68.885816 -94.12859)
		(end 68.566792 -94.447614)
		(width 0.0889)
		(layer "In2.Cu")
		(net "M_K_DQS_DN<2>")
	)
	(segment
		(start 55.250588 -130.046476)
		(end 55.016908 -130.280156)
		(width 0.14224)
		(layer "In2.Cu")
		(net "M_K_DQS_DN<2>")
	)
	(segment
		(start 45.62983 -130.038094)
		(end 45.387768 -130.280156)
		(width 0.1651)
		(layer "F.Cu")
		(net "M_K_DQS_DN<1>")
	)
	(segment
		(start 67.478148 -95.118936)
		(end 67.426586 -95.067374)
		(width 0.0889)
		(layer "F.Cu")
		(net "M_K_DQS_DN<1>")
	)
	(segment
		(start 46.487588 -121.893838)
		(end 46.487588 -122.423682)
		(width 0.1651)
		(layer "F.Cu")
		(net "M_K_DQS_DN<1>")
	)
	(segment
		(start 45.62983 -129.861056)
		(end 45.62983 -130.038094)
		(width 0.1651)
		(layer "F.Cu")
		(net "M_K_DQS_DN<1>")
	)
	(segment
		(start 45.996098 -124.07265)
		(end 46.30928 -124.07265)
		(width 0.1651)
		(layer "F.Cu")
		(net "M_K_DQS_DN<1>")
	)
	(segment
		(start 45.62983 -128.337056)
		(end 45.62983 -128.591056)
		(width 0.1651)
		(layer "F.Cu")
		(net "M_K_DQS_DN<1>")
	)
	(segment
		(start 45.62983 -128.591056)
		(end 45.50283 -128.718056)
		(width 0.1651)
		(layer "F.Cu")
		(net "M_K_DQS_DN<1>")
	)
	(segment
		(start 46.30928 -122.60199)
		(end 45.996098 -122.60199)
		(width 0.1651)
		(layer "F.Cu")
		(net "M_K_DQS_DN<1>")
	)
	(segment
		(start 45.646848 -122.95124)
		(end 45.646848 -123.7234)
		(width 0.1651)
		(layer "F.Cu")
		(net "M_K_DQS_DN<1>")
	)
	(segment
		(start 45.646848 -125.30836)
		(end 45.646848 -126.08052)
		(width 0.1651)
		(layer "F.Cu")
		(net "M_K_DQS_DN<1>")
	)
	(segment
		(start 46.487588 -124.250958)
		(end 46.487588 -124.780802)
		(width 0.1651)
		(layer "F.Cu")
		(net "M_K_DQS_DN<1>")
	)
	(segment
		(start 45.700188 -120.422162)
		(end 45.700188 -121.106438)
		(width 0.1651)
		(layer "F.Cu")
		(net "M_K_DQS_DN<1>")
	)
	(segment
		(start 45.646848 -126.08052)
		(end 45.996098 -126.42977)
		(width 0.1651)
		(layer "F.Cu")
		(net "M_K_DQS_DN<1>")
	)
	(segment
		(start 46.30928 -126.42977)
		(end 46.487588 -126.608078)
		(width 0.1651)
		(layer "F.Cu")
		(net "M_K_DQS_DN<1>")
	)
	(segment
		(start 66.27749 -95.067374)
		(end 46.487588 -114.857276)
		(width 0.1651)
		(layer "F.Cu")
		(net "M_K_DQS_DN<1>")
	)
	(segment
		(start 45.996098 -122.60199)
		(end 45.646848 -122.95124)
		(width 0.1651)
		(layer "F.Cu")
		(net "M_K_DQS_DN<1>")
	)
	(segment
		(start 46.487588 -114.857276)
		(end 46.487588 -119.634762)
		(width 0.1651)
		(layer "F.Cu")
		(net "M_K_DQS_DN<1>")
	)
	(segment
		(start 45.55617 -128.263396)
		(end 45.62983 -128.337056)
		(width 0.1651)
		(layer "F.Cu")
		(net "M_K_DQS_DN<1>")
	)
	(segment
		(start 45.387768 -130.280156)
		(end 45.387514 -130.280156)
		(width 0.1651)
		(layer "F.Cu")
		(net "M_K_DQS_DN<1>")
	)
	(segment
		(start 45.171868 -135.4582)
		(end 45.387514 -135.673846)
		(width 0.1651)
		(layer "F.Cu")
		(net "M_K_DQS_DN<1>")
	)
	(segment
		(start 69.466206 -95.21444)
		(end 69.060568 -95.167196)
		(width 0.0889)
		(layer "F.Cu")
		(net "M_K_DQS_DN<1>")
	)
	(segment
		(start 67.426586 -95.067374)
		(end 67.404488 -95.067374)
		(width 0.0889)
		(layer "F.Cu")
		(net "M_K_DQS_DN<1>")
	)
	(segment
		(start 46.30928 -124.95911)
		(end 45.996098 -124.95911)
		(width 0.1651)
		(layer "F.Cu")
		(net "M_K_DQS_DN<1>")
	)
	(segment
		(start 67.404488 -95.067374)
		(end 66.27749 -95.067374)
		(width 0.1651)
		(layer "F.Cu")
		(net "M_K_DQS_DN<1>")
	)
	(segment
		(start 45.996098 -126.42977)
		(end 46.30928 -126.42977)
		(width 0.1651)
		(layer "F.Cu")
		(net "M_K_DQS_DN<1>")
	)
	(segment
		(start 45.55617 -127.893572)
		(end 45.55617 -128.263396)
		(width 0.1651)
		(layer "F.Cu")
		(net "M_K_DQS_DN<1>")
	)
	(segment
		(start 45.62983 -129.353056)
		(end 45.50283 -129.480056)
		(width 0.1651)
		(layer "F.Cu")
		(net "M_K_DQS_DN<1>")
	)
	(segment
		(start 46.487588 -122.423682)
		(end 46.30928 -122.60199)
		(width 0.1651)
		(layer "F.Cu")
		(net "M_K_DQS_DN<1>")
	)
	(segment
		(start 44.600368 -135.805672)
		(end 44.94784 -135.4582)
		(width 0.1651)
		(layer "F.Cu")
		(net "M_K_DQS_DN<1>")
	)
	(segment
		(start 46.30928 -124.07265)
		(end 46.487588 -124.250958)
		(width 0.1651)
		(layer "F.Cu")
		(net "M_K_DQS_DN<1>")
	)
	(segment
		(start 45.62983 -129.099056)
		(end 45.62983 -129.353056)
		(width 0.1651)
		(layer "F.Cu")
		(net "M_K_DQS_DN<1>")
	)
	(segment
		(start 45.50283 -128.718056)
		(end 45.50283 -128.972056)
		(width 0.1651)
		(layer "F.Cu")
		(net "M_K_DQS_DN<1>")
	)
	(segment
		(start 69.060568 -95.167196)
		(end 68.679568 -95.123)
		(width 0.0889)
		(layer "F.Cu")
		(net "M_K_DQS_DN<1>")
	)
	(segment
		(start 44.94784 -135.4582)
		(end 45.171868 -135.4582)
		(width 0.1651)
		(layer "F.Cu")
		(net "M_K_DQS_DN<1>")
	)
	(segment
		(start 46.487588 -124.780802)
		(end 46.30928 -124.95911)
		(width 0.1651)
		(layer "F.Cu")
		(net "M_K_DQS_DN<1>")
	)
	(segment
		(start 46.487588 -126.608078)
		(end 46.487588 -126.962154)
		(width 0.1651)
		(layer "F.Cu")
		(net "M_K_DQS_DN<1>")
	)
	(segment
		(start 45.50283 -129.480056)
		(end 45.50283 -129.734056)
		(width 0.1651)
		(layer "F.Cu")
		(net "M_K_DQS_DN<1>")
	)
	(segment
		(start 45.996098 -124.95911)
		(end 45.646848 -125.30836)
		(width 0.1651)
		(layer "F.Cu")
		(net "M_K_DQS_DN<1>")
	)
	(segment
		(start 44.600368 -136.203436)
		(end 44.600368 -135.805672)
		(width 0.1651)
		(layer "F.Cu")
		(net "M_K_DQS_DN<1>")
	)
	(segment
		(start 45.50283 -128.972056)
		(end 45.62983 -129.099056)
		(width 0.1651)
		(layer "F.Cu")
		(net "M_K_DQS_DN<1>")
	)
	(segment
		(start 45.50283 -129.734056)
		(end 45.62983 -129.861056)
		(width 0.1651)
		(layer "F.Cu")
		(net "M_K_DQS_DN<1>")
	)
	(segment
		(start 46.487588 -126.962154)
		(end 45.55617 -127.893572)
		(width 0.1651)
		(layer "F.Cu")
		(net "M_K_DQS_DN<1>")
	)
	(segment
		(start 44.999402 -136.60247)
		(end 44.600368 -136.203436)
		(width 0.1651)
		(layer "F.Cu")
		(net "M_K_DQS_DN<1>")
	)
	(segment
		(start 68.625466 -95.118936)
		(end 67.478148 -95.118936)
		(width 0.0889)
		(layer "F.Cu")
		(net "M_K_DQS_DN<1>")
	)
	(segment
		(start 44.999402 -137.67054)
		(end 44.999402 -136.60247)
		(width 0.1651)
		(layer "F.Cu")
		(net "M_K_DQS_DN<1>")
	)
	(segment
		(start 45.646848 -123.7234)
		(end 45.996098 -124.07265)
		(width 0.1651)
		(layer "F.Cu")
		(net "M_K_DQS_DN<1>")
	)
	(segment
		(start 45.700188 -121.106438)
		(end 46.487588 -121.893838)
		(width 0.1651)
		(layer "F.Cu")
		(net "M_K_DQS_DN<1>")
	)
	(segment
		(start 46.487588 -119.634762)
		(end 45.700188 -120.422162)
		(width 0.1651)
		(layer "F.Cu")
		(net "M_K_DQS_DN<1>")
	)
	(via
		(at 45.387514 -135.673846)
		(size 0.508)
		(drill 0.254)
		(layers "F.Cu" "B.Cu")
		(net "M_K_DQS_DN<1>")
	)
	(via
		(at 45.387514 -130.280156)
		(size 0.508)
		(drill 0.254)
		(layers "F.Cu" "B.Cu")
		(net "M_K_DQS_DN<1>")
	)
	(arc
		(start 68.679568 -95.123)
		(mid 68.652564 -95.120341)
		(end 68.625466 -95.118936)
		(width 0.0889)
		(layer "F.Cu")
		(net "M_K_DQS_DN<1>")
	)
	(segment
		(start 44.617386 -130.1496)
		(end 44.972986 -130.5052)
		(width 0.1651)
		(layer "B.Cu")
		(net "M_K_DQS_DN<1>")
	)
	(segment
		(start 44.871386 -129.311146)
		(end 44.871386 -129.565146)
		(width 0.1651)
		(layer "B.Cu")
		(net "M_K_DQS_DN<1>")
	)
	(segment
		(start 44.999402 -129.18313)
		(end 44.871386 -129.311146)
		(width 0.1651)
		(layer "B.Cu")
		(net "M_K_DQS_DN<1>")
	)
	(segment
		(start 44.871386 -129.565146)
		(end 44.617386 -129.819146)
		(width 0.1651)
		(layer "B.Cu")
		(net "M_K_DQS_DN<1>")
	)
	(segment
		(start 45.16247 -130.5052)
		(end 45.387514 -130.280156)
		(width 0.1651)
		(layer "B.Cu")
		(net "M_K_DQS_DN<1>")
	)
	(segment
		(start 44.999402 -128.276096)
		(end 44.999402 -129.18313)
		(width 0.1651)
		(layer "B.Cu")
		(net "M_K_DQS_DN<1>")
	)
	(segment
		(start 44.972986 -130.5052)
		(end 45.16247 -130.5052)
		(width 0.1651)
		(layer "B.Cu")
		(net "M_K_DQS_DN<1>")
	)
	(segment
		(start 44.617386 -129.819146)
		(end 44.617386 -130.1496)
		(width 0.1651)
		(layer "B.Cu")
		(net "M_K_DQS_DN<1>")
	)
	(segment
		(start 44.954444 -135.240776)
		(end 44.954444 -133.985)
		(width 0.14224)
		(layer "In2.Cu")
		(net "M_K_DQS_DN<1>")
	)
	(segment
		(start 44.743624 -133.77418)
		(end 44.743624 -132.11302)
		(width 0.14224)
		(layer "In2.Cu")
		(net "M_K_DQS_DN<1>")
	)
	(segment
		(start 45.314362 -130.280156)
		(end 45.387514 -130.280156)
		(width 0.14224)
		(layer "In2.Cu")
		(net "M_K_DQS_DN<1>")
	)
	(segment
		(start 44.954444 -133.985)
		(end 44.743624 -133.77418)
		(width 0.14224)
		(layer "In2.Cu")
		(net "M_K_DQS_DN<1>")
	)
	(segment
		(start 44.743624 -132.11302)
		(end 44.954444 -131.9022)
		(width 0.14224)
		(layer "In2.Cu")
		(net "M_K_DQS_DN<1>")
	)
	(segment
		(start 45.387514 -135.673846)
		(end 44.954444 -135.240776)
		(width 0.14224)
		(layer "In2.Cu")
		(net "M_K_DQS_DN<1>")
	)
	(segment
		(start 44.954444 -131.9022)
		(end 44.954444 -130.640074)
		(width 0.14224)
		(layer "In2.Cu")
		(net "M_K_DQS_DN<1>")
	)
	(segment
		(start 44.954444 -130.640074)
		(end 45.314362 -130.280156)
		(width 0.14224)
		(layer "In2.Cu")
		(net "M_K_DQS_DN<1>")
	)
	(segment
		(start 84.060792 -89.765886)
		(end 83.489292 -89.765886)
		(width 0.1651)
		(layer "F.Cu")
		(net "M_K_DQS_DN<17>")
	)
	(segment
		(start 72.817228 -135.001762)
		(end 72.56526 -135.25373)
		(width 0.1651)
		(layer "F.Cu")
		(net "M_K_DQS_DN<17>")
	)
	(segment
		(start 72.817228 -134.755128)
		(end 72.817228 -135.001762)
		(width 0.1651)
		(layer "F.Cu")
		(net "M_K_DQS_DN<17>")
	)
	(segment
		(start 73.049384 -133.0706)
		(end 73.049384 -133.729984)
		(width 0.1651)
		(layer "F.Cu")
		(net "M_K_DQS_DN<17>")
	)
	(segment
		(start 72.56526 -135.25373)
		(end 72.35698 -135.25373)
		(width 0.1651)
		(layer "F.Cu")
		(net "M_K_DQS_DN<17>")
	)
	(segment
		(start 72.6313 -134.5692)
		(end 72.817228 -134.755128)
		(width 0.1651)
		(layer "F.Cu")
		(net "M_K_DQS_DN<17>")
	)
	(segment
		(start 73.049384 -133.729984)
		(end 72.6313 -134.148068)
		(width 0.1651)
		(layer "F.Cu")
		(net "M_K_DQS_DN<17>")
	)
	(segment
		(start 72.6313 -134.148068)
		(end 72.6313 -134.5692)
		(width 0.1651)
		(layer "F.Cu")
		(net "M_K_DQS_DN<17>")
	)
	(segment
		(start 72.35698 -135.25373)
		(end 72.16775 -135.0645)
		(width 0.1651)
		(layer "F.Cu")
		(net "M_K_DQS_DN<17>")
	)
	(segment
		(start 72.16775 -135.0645)
		(end 72.1487 -135.0645)
		(width 0.1651)
		(layer "F.Cu")
		(net "M_K_DQS_DN<17>")
	)
	(via
		(at 72.1487 -135.0645)
		(size 0.508)
		(drill 0.254)
		(layers "F.Cu" "B.Cu")
		(net "M_K_DQS_DN<17>")
	)
	(via
		(at 72.142096 -130.8862)
		(size 0.508)
		(drill 0.254)
		(layers "F.Cu" "B.Cu")
		(net "M_K_DQS_DN<17>")
	)
	(via
		(at 83.489292 -89.765886)
		(size 0.508)
		(drill 0.254)
		(layers "F.Cu" "B.Cu")
		(net "M_K_DQS_DN<17>")
	)
	(segment
		(start 72.6059 -131.4196)
		(end 72.7837 -131.2418)
		(width 0.1651)
		(layer "B.Cu")
		(net "M_K_DQS_DN<17>")
	)
	(segment
		(start 72.33666 -130.691636)
		(end 72.142096 -130.8862)
		(width 0.1651)
		(layer "B.Cu")
		(net "M_K_DQS_DN<17>")
	)
	(segment
		(start 72.563736 -130.691636)
		(end 72.33666 -130.691636)
		(width 0.1651)
		(layer "B.Cu")
		(net "M_K_DQS_DN<17>")
	)
	(segment
		(start 73.049638 -132.219192)
		(end 72.6059 -131.775454)
		(width 0.1651)
		(layer "B.Cu")
		(net "M_K_DQS_DN<17>")
	)
	(segment
		(start 73.049638 -132.875528)
		(end 73.049638 -132.219192)
		(width 0.1651)
		(layer "B.Cu")
		(net "M_K_DQS_DN<17>")
	)
	(segment
		(start 72.7837 -131.2418)
		(end 72.7837 -130.9116)
		(width 0.1651)
		(layer "B.Cu")
		(net "M_K_DQS_DN<17>")
	)
	(segment
		(start 72.6059 -131.775454)
		(end 72.6059 -131.4196)
		(width 0.1651)
		(layer "B.Cu")
		(net "M_K_DQS_DN<17>")
	)
	(segment
		(start 72.7837 -130.9116)
		(end 72.563736 -130.691636)
		(width 0.1651)
		(layer "B.Cu")
		(net "M_K_DQS_DN<17>")
	)
	(segment
		(start 73.049384 -132.876036)
		(end 73.049638 -132.875528)
		(width 0.1651)
		(layer "B.Cu")
		(net "M_K_DQS_DN<17>")
	)
	(segment
		(start 72.193404 -133.29666)
		(end 72.348344 -133.14172)
		(width 0.14224)
		(layer "In2.Cu")
		(net "M_K_DQS_DN<17>")
	)
	(segment
		(start 81.108042 -102.726998)
		(end 81.108042 -102.7049)
		(width 0.0889)
		(layer "In2.Cu")
		(net "M_K_DQS_DN<17>")
	)
	(segment
		(start 83.142582 -90.556588)
		(end 83.148932 -90.54592)
		(width 0.0889)
		(layer "In2.Cu")
		(net "M_K_DQS_DN<17>")
	)
	(segment
		(start 72.348344 -133.14172)
		(end 72.348344 -132.78866)
		(width 0.14224)
		(layer "In2.Cu")
		(net "M_K_DQS_DN<17>")
	)
	(segment
		(start 81.068672 -101.076506)
		(end 82.129884 -100.015294)
		(width 0.0889)
		(layer "In2.Cu")
		(net "M_K_DQS_DN<17>")
	)
	(segment
		(start 72.58177 -134.147306)
		(end 72.394064 -133.9596)
		(width 0.14224)
		(layer "In2.Cu")
		(net "M_K_DQS_DN<17>")
	)
	(segment
		(start 72.046084 -133.29666)
		(end 72.193404 -133.29666)
		(width 0.14224)
		(layer "In2.Cu")
		(net "M_K_DQS_DN<17>")
	)
	(segment
		(start 72.576944 -131.7244)
		(end 72.576944 -131.321048)
		(width 0.14224)
		(layer "In2.Cu")
		(net "M_K_DQS_DN<17>")
	)
	(segment
		(start 81.108042 -104.505506)
		(end 81.108042 -102.726998)
		(width 0.14224)
		(layer "In2.Cu")
		(net "M_K_DQS_DN<17>")
	)
	(segment
		(start 83.43138 -89.3699)
		(end 83.489292 -89.427812)
		(width 0.0889)
		(layer "In2.Cu")
		(net "M_K_DQS_DN<17>")
	)
	(segment
		(start 82.284062 -93.433138)
		(end 82.279236 -93.424502)
		(width 0.0889)
		(layer "In2.Cu")
		(net "M_K_DQS_DN<17>")
	)
	(segment
		(start 72.056244 -132.0038)
		(end 72.297544 -132.0038)
		(width 0.14224)
		(layer "In2.Cu")
		(net "M_K_DQS_DN<17>")
	)
	(segment
		(start 72.068944 -133.9596)
		(end 71.906384 -133.79704)
		(width 0.14224)
		(layer "In2.Cu")
		(net "M_K_DQS_DN<17>")
	)
	(segment
		(start 82.129884 -97.211134)
		(end 82.244692 -97.058226)
		(width 0.0889)
		(layer "In2.Cu")
		(net "M_K_DQS_DN<17>")
	)
	(segment
		(start 72.1487 -135.0645)
		(end 72.58177 -134.63143)
		(width 0.14224)
		(layer "In2.Cu")
		(net "M_K_DQS_DN<17>")
	)
	(segment
		(start 74.516488 -121.958608)
		(end 74.516488 -111.09706)
		(width 0.14224)
		(layer "In2.Cu")
		(net "M_K_DQS_DN<17>")
	)
	(segment
		(start 72.142096 -130.8862)
		(end 72.149462 -130.8862)
		(width 0.14224)
		(layer "In2.Cu")
		(net "M_K_DQS_DN<17>")
	)
	(segment
		(start 72.297544 -132.0038)
		(end 72.576944 -131.7244)
		(width 0.14224)
		(layer "In2.Cu")
		(net "M_K_DQS_DN<17>")
	)
	(segment
		(start 82.290412 -95.425006)
		(end 82.284062 -95.414338)
		(width 0.0889)
		(layer "In2.Cu")
		(net "M_K_DQS_DN<17>")
	)
	(segment
		(start 72.038464 -132.63372)
		(end 71.906384 -132.50164)
		(width 0.14224)
		(layer "In2.Cu")
		(net "M_K_DQS_DN<17>")
	)
	(segment
		(start 83.137756 -91.555824)
		(end 83.142582 -91.547188)
		(width 0.0889)
		(layer "In2.Cu")
		(net "M_K_DQS_DN<17>")
	)
	(segment
		(start 72.193404 -132.63372)
		(end 72.038464 -132.63372)
		(width 0.14224)
		(layer "In2.Cu")
		(net "M_K_DQS_DN<17>")
	)
	(segment
		(start 72.348344 -132.78866)
		(end 72.193404 -132.63372)
		(width 0.14224)
		(layer "In2.Cu")
		(net "M_K_DQS_DN<17>")
	)
	(segment
		(start 72.394064 -133.9596)
		(end 72.068944 -133.9596)
		(width 0.14224)
		(layer "In2.Cu")
		(net "M_K_DQS_DN<17>")
	)
	(segment
		(start 82.284062 -96.404938)
		(end 82.279236 -96.396302)
		(width 0.0889)
		(layer "In2.Cu")
		(net "M_K_DQS_DN<17>")
	)
	(segment
		(start 82.129884 -100.015294)
		(end 82.129884 -97.211134)
		(width 0.0889)
		(layer "In2.Cu")
		(net "M_K_DQS_DN<17>")
	)
	(segment
		(start 82.284062 -95.414338)
		(end 82.279236 -95.405702)
		(width 0.0889)
		(layer "In2.Cu")
		(net "M_K_DQS_DN<17>")
	)
	(segment
		(start 71.906384 -133.43636)
		(end 72.046084 -133.29666)
		(width 0.14224)
		(layer "In2.Cu")
		(net "M_K_DQS_DN<17>")
	)
	(segment
		(start 81.068672 -102.66553)
		(end 81.068672 -101.076506)
		(width 0.0889)
		(layer "In2.Cu")
		(net "M_K_DQS_DN<17>")
	)
	(segment
		(start 72.58177 -134.63143)
		(end 72.58177 -134.147306)
		(width 0.14224)
		(layer "In2.Cu")
		(net "M_K_DQS_DN<17>")
	)
	(segment
		(start 71.906384 -132.50164)
		(end 71.906384 -132.15366)
		(width 0.14224)
		(layer "In2.Cu")
		(net "M_K_DQS_DN<17>")
	)
	(segment
		(start 72.924416 -130.111246)
		(end 72.924416 -123.55068)
		(width 0.14224)
		(layer "In2.Cu")
		(net "M_K_DQS_DN<17>")
	)
	(segment
		(start 83.489292 -89.427812)
		(end 83.489292 -89.765886)
		(width 0.0889)
		(layer "In2.Cu")
		(net "M_K_DQS_DN<17>")
	)
	(segment
		(start 71.906384 -133.79704)
		(end 71.906384 -133.43636)
		(width 0.14224)
		(layer "In2.Cu")
		(net "M_K_DQS_DN<17>")
	)
	(segment
		(start 72.576944 -131.321048)
		(end 72.142096 -130.8862)
		(width 0.14224)
		(layer "In2.Cu")
		(net "M_K_DQS_DN<17>")
	)
	(segment
		(start 72.924416 -123.55068)
		(end 74.516488 -121.958608)
		(width 0.14224)
		(layer "In2.Cu")
		(net "M_K_DQS_DN<17>")
	)
	(segment
		(start 71.906384 -132.15366)
		(end 72.056244 -132.0038)
		(width 0.14224)
		(layer "In2.Cu")
		(net "M_K_DQS_DN<17>")
	)
	(segment
		(start 83.142582 -91.547188)
		(end 83.148932 -91.53652)
		(width 0.0889)
		(layer "In2.Cu")
		(net "M_K_DQS_DN<17>")
	)
	(segment
		(start 74.516488 -111.09706)
		(end 81.108042 -104.505506)
		(width 0.14224)
		(layer "In2.Cu")
		(net "M_K_DQS_DN<17>")
	)
	(segment
		(start 83.137756 -90.565224)
		(end 83.142582 -90.556588)
		(width 0.0889)
		(layer "In2.Cu")
		(net "M_K_DQS_DN<17>")
	)
	(segment
		(start 81.108042 -102.7049)
		(end 81.068672 -102.66553)
		(width 0.0889)
		(layer "In2.Cu")
		(net "M_K_DQS_DN<17>")
	)
	(segment
		(start 82.284062 -94.023688)
		(end 82.290412 -94.01302)
		(width 0.0889)
		(layer "In2.Cu")
		(net "M_K_DQS_DN<17>")
	)
	(segment
		(start 82.615786 -92.83319)
		(end 82.648552 -92.83319)
		(width 0.0889)
		(layer "In2.Cu")
		(net "M_K_DQS_DN<17>")
	)
	(segment
		(start 72.149462 -130.8862)
		(end 72.924416 -130.111246)
		(width 0.14224)
		(layer "In2.Cu")
		(net "M_K_DQS_DN<17>")
	)
	(arc
		(start 82.279236 -93.424502)
		(mid 82.282983 -93.035246)
		(end 82.615786 -92.83319)
		(width 0.0889)
		(layer "In2.Cu")
		(net "M_K_DQS_DN<17>")
	)
	(arc
		(start 82.290412 -94.01302)
		(mid 82.36321 -93.722257)
		(end 82.284062 -93.433138)
		(width 0.0889)
		(layer "In2.Cu")
		(net "M_K_DQS_DN<17>")
	)
	(arc
		(start 82.284062 -94.423484)
		(mid 82.230563 -94.223586)
		(end 82.284062 -94.023688)
		(width 0.0889)
		(layer "In2.Cu")
		(net "M_K_DQS_DN<17>")
	)
	(arc
		(start 83.148932 -91.53652)
		(mid 83.22173 -91.245757)
		(end 83.142582 -90.956638)
		(width 0.0889)
		(layer "In2.Cu")
		(net "M_K_DQS_DN<17>")
	)
	(arc
		(start 83.148932 -90.54592)
		(mid 83.22173 -90.255157)
		(end 83.142582 -89.966038)
		(width 0.0889)
		(layer "In2.Cu")
		(net "M_K_DQS_DN<17>")
	)
	(arc
		(start 83.142582 -90.956638)
		(mid 83.089112 -90.761575)
		(end 83.137756 -90.565224)
		(width 0.0889)
		(layer "In2.Cu")
		(net "M_K_DQS_DN<17>")
	)
	(arc
		(start 83.142582 -91.947238)
		(mid 83.089112 -91.752175)
		(end 83.137756 -91.555824)
		(width 0.0889)
		(layer "In2.Cu")
		(net "M_K_DQS_DN<17>")
	)
	(arc
		(start 83.142582 -89.966038)
		(mid 83.128987 -89.591389)
		(end 83.43138 -89.3699)
		(width 0.0889)
		(layer "In2.Cu")
		(net "M_K_DQS_DN<17>")
	)
	(arc
		(start 82.284062 -95.014288)
		(mid 82.363193 -94.718886)
		(end 82.284062 -94.423484)
		(width 0.0889)
		(layer "In2.Cu")
		(net "M_K_DQS_DN<17>")
	)
	(arc
		(start 82.279236 -96.396302)
		(mid 82.230481 -96.19995)
		(end 82.284062 -96.004888)
		(width 0.0889)
		(layer "In2.Cu")
		(net "M_K_DQS_DN<17>")
	)
	(arc
		(start 82.244692 -97.058226)
		(mid 82.357832 -96.782901)
		(end 82.323432 -96.487234)
		(width 0.0889)
		(layer "In2.Cu")
		(net "M_K_DQS_DN<17>")
	)
	(arc
		(start 82.284062 -96.004888)
		(mid 82.363284 -95.71577)
		(end 82.290412 -95.425006)
		(width 0.0889)
		(layer "In2.Cu")
		(net "M_K_DQS_DN<17>")
	)
	(arc
		(start 82.323432 -96.487234)
		(mid 82.305323 -96.445332)
		(end 82.284062 -96.404938)
		(width 0.0889)
		(layer "In2.Cu")
		(net "M_K_DQS_DN<17>")
	)
	(arc
		(start 82.279236 -95.405702)
		(mid 82.230481 -95.20935)
		(end 82.284062 -95.014288)
		(width 0.0889)
		(layer "In2.Cu")
		(net "M_K_DQS_DN<17>")
	)
	(arc
		(start 82.648552 -92.83319)
		(mid 83.146803 -92.53035)
		(end 83.142582 -91.947238)
		(width 0.0889)
		(layer "In2.Cu")
		(net "M_K_DQS_DN<17>")
	)
	(segment
		(start 146.581368 -134.5692)
		(end 146.767296 -134.755128)
		(width 0.1651)
		(layer "F.Cu")
		(net "M_K_DQS_DN<16>")
	)
	(segment
		(start 146.581368 -134.148068)
		(end 146.581368 -134.5692)
		(width 0.1651)
		(layer "F.Cu")
		(net "M_K_DQS_DN<16>")
	)
	(segment
		(start 146.999452 -133.0706)
		(end 146.999452 -133.729984)
		(width 0.1651)
		(layer "F.Cu")
		(net "M_K_DQS_DN<16>")
	)
	(segment
		(start 146.515328 -135.25373)
		(end 146.307048 -135.25373)
		(width 0.1651)
		(layer "F.Cu")
		(net "M_K_DQS_DN<16>")
	)
	(segment
		(start 123.363228 -96.518984)
		(end 123.934728 -96.518984)
		(width 0.1651)
		(layer "F.Cu")
		(net "M_K_DQS_DN<16>")
	)
	(segment
		(start 146.307048 -135.25373)
		(end 146.117818 -135.0645)
		(width 0.1651)
		(layer "F.Cu")
		(net "M_K_DQS_DN<16>")
	)
	(segment
		(start 146.767296 -134.755128)
		(end 146.767296 -135.001762)
		(width 0.1651)
		(layer "F.Cu")
		(net "M_K_DQS_DN<16>")
	)
	(segment
		(start 146.117818 -135.0645)
		(end 146.098768 -135.0645)
		(width 0.1651)
		(layer "F.Cu")
		(net "M_K_DQS_DN<16>")
	)
	(segment
		(start 146.767296 -135.001762)
		(end 146.515328 -135.25373)
		(width 0.1651)
		(layer "F.Cu")
		(net "M_K_DQS_DN<16>")
	)
	(segment
		(start 146.999452 -133.729984)
		(end 146.581368 -134.148068)
		(width 0.1651)
		(layer "F.Cu")
		(net "M_K_DQS_DN<16>")
	)
	(via
		(at 146.092164 -130.8862)
		(size 0.508)
		(drill 0.254)
		(layers "F.Cu" "B.Cu")
		(net "M_K_DQS_DN<16>")
	)
	(via
		(at 146.098768 -135.0645)
		(size 0.508)
		(drill 0.254)
		(layers "F.Cu" "B.Cu")
		(net "M_K_DQS_DN<16>")
	)
	(via
		(at 123.934728 -96.518984)
		(size 0.508)
		(drill 0.254)
		(layers "F.Cu" "B.Cu")
		(net "M_K_DQS_DN<16>")
	)
	(segment
		(start 146.513804 -130.691636)
		(end 146.286728 -130.691636)
		(width 0.1651)
		(layer "B.Cu")
		(net "M_K_DQS_DN<16>")
	)
	(segment
		(start 146.733768 -130.9116)
		(end 146.513804 -130.691636)
		(width 0.1651)
		(layer "B.Cu")
		(net "M_K_DQS_DN<16>")
	)
	(segment
		(start 146.286728 -130.691636)
		(end 146.092164 -130.8862)
		(width 0.1651)
		(layer "B.Cu")
		(net "M_K_DQS_DN<16>")
	)
	(segment
		(start 146.555968 -131.775454)
		(end 146.555968 -131.4196)
		(width 0.1651)
		(layer "B.Cu")
		(net "M_K_DQS_DN<16>")
	)
	(segment
		(start 146.733768 -131.2418)
		(end 146.733768 -130.9116)
		(width 0.1651)
		(layer "B.Cu")
		(net "M_K_DQS_DN<16>")
	)
	(segment
		(start 146.999706 -132.875528)
		(end 146.999706 -132.219192)
		(width 0.1651)
		(layer "B.Cu")
		(net "M_K_DQS_DN<16>")
	)
	(segment
		(start 146.555968 -131.4196)
		(end 146.733768 -131.2418)
		(width 0.1651)
		(layer "B.Cu")
		(net "M_K_DQS_DN<16>")
	)
	(segment
		(start 146.999706 -132.219192)
		(end 146.555968 -131.775454)
		(width 0.1651)
		(layer "B.Cu")
		(net "M_K_DQS_DN<16>")
	)
	(segment
		(start 146.999452 -132.876036)
		(end 146.999706 -132.875528)
		(width 0.1651)
		(layer "B.Cu")
		(net "M_K_DQS_DN<16>")
	)
	(segment
		(start 147.983448 -127.800354)
		(end 146.899884 -128.883918)
		(width 0.14224)
		(layer "In2.Cu")
		(net "M_K_DQS_DN<16>")
	)
	(segment
		(start 123.588018 -102.262686)
		(end 123.583192 -102.271322)
		(width 0.0889)
		(layer "In2.Cu")
		(net "M_K_DQS_DN<16>")
	)
	(segment
		(start 146.006312 -132.0038)
		(end 145.856452 -132.15366)
		(width 0.14224)
		(layer "In2.Cu")
		(net "M_K_DQS_DN<16>")
	)
	(segment
		(start 146.344132 -133.9596)
		(end 146.531838 -134.147306)
		(width 0.14224)
		(layer "In2.Cu")
		(net "M_K_DQS_DN<16>")
	)
	(segment
		(start 146.298412 -132.78866)
		(end 146.298412 -133.14172)
		(width 0.14224)
		(layer "In2.Cu")
		(net "M_K_DQS_DN<16>")
	)
	(segment
		(start 147.983448 -119.774208)
		(end 147.983448 -127.800354)
		(width 0.14224)
		(layer "In2.Cu")
		(net "M_K_DQS_DN<16>")
	)
	(segment
		(start 127.429768 -104.9655)
		(end 128.455674 -105.991406)
		(width 0.0889)
		(layer "In2.Cu")
		(net "M_K_DQS_DN<16>")
	)
	(segment
		(start 136.21004 -108.0008)
		(end 147.983448 -119.774208)
		(width 0.14224)
		(layer "In2.Cu")
		(net "M_K_DQS_DN<16>")
	)
	(segment
		(start 146.247612 -132.0038)
		(end 146.006312 -132.0038)
		(width 0.14224)
		(layer "In2.Cu")
		(net "M_K_DQS_DN<16>")
	)
	(segment
		(start 123.588018 -102.662736)
		(end 123.857766 -103.13035)
		(width 0.0889)
		(layer "In2.Cu")
		(net "M_K_DQS_DN<16>")
	)
	(segment
		(start 128.511554 -105.991406)
		(end 128.527302 -106.007154)
		(width 0.0889)
		(layer "In2.Cu")
		(net "M_K_DQS_DN<16>")
	)
	(segment
		(start 123.934728 -96.857058)
		(end 124.000006 -96.922336)
		(width 0.0889)
		(layer "In2.Cu")
		(net "M_K_DQS_DN<16>")
	)
	(segment
		(start 146.531838 -134.147306)
		(end 146.531838 -134.63143)
		(width 0.14224)
		(layer "In2.Cu")
		(net "M_K_DQS_DN<16>")
	)
	(segment
		(start 146.527012 -131.7244)
		(end 146.247612 -132.0038)
		(width 0.14224)
		(layer "In2.Cu")
		(net "M_K_DQS_DN<16>")
	)
	(segment
		(start 123.956318 -98.100134)
		(end 123.923552 -98.100134)
		(width 0.0889)
		(layer "In2.Cu")
		(net "M_K_DQS_DN<16>")
	)
	(segment
		(start 123.934728 -96.518984)
		(end 123.934728 -96.857058)
		(width 0.0889)
		(layer "In2.Cu")
		(net "M_K_DQS_DN<16>")
	)
	(segment
		(start 146.899884 -130.07848)
		(end 146.092164 -130.8862)
		(width 0.14224)
		(layer "In2.Cu")
		(net "M_K_DQS_DN<16>")
	)
	(segment
		(start 123.594368 -102.252018)
		(end 123.588018 -102.262686)
		(width 0.0889)
		(layer "In2.Cu")
		(net "M_K_DQS_DN<16>")
	)
	(segment
		(start 123.857766 -103.13035)
		(end 125.692916 -104.9655)
		(width 0.0889)
		(layer "In2.Cu")
		(net "M_K_DQS_DN<16>")
	)
	(segment
		(start 146.298412 -133.14172)
		(end 146.143472 -133.29666)
		(width 0.14224)
		(layer "In2.Cu")
		(net "M_K_DQS_DN<16>")
	)
	(segment
		(start 146.899884 -128.883918)
		(end 146.899884 -130.07848)
		(width 0.14224)
		(layer "In2.Cu")
		(net "M_K_DQS_DN<16>")
	)
	(segment
		(start 129.631948 -107.1118)
		(end 133.487668 -107.1118)
		(width 0.14224)
		(layer "In2.Cu")
		(net "M_K_DQS_DN<16>")
	)
	(segment
		(start 128.527302 -106.007154)
		(end 129.631948 -107.1118)
		(width 0.14224)
		(layer "In2.Cu")
		(net "M_K_DQS_DN<16>")
	)
	(segment
		(start 125.692916 -104.9655)
		(end 127.429768 -104.9655)
		(width 0.0889)
		(layer "In2.Cu")
		(net "M_K_DQS_DN<16>")
	)
	(segment
		(start 123.588018 -99.290886)
		(end 123.583192 -99.299522)
		(width 0.0889)
		(layer "In2.Cu")
		(net "M_K_DQS_DN<16>")
	)
	(segment
		(start 146.143472 -132.63372)
		(end 146.298412 -132.78866)
		(width 0.14224)
		(layer "In2.Cu")
		(net "M_K_DQS_DN<16>")
	)
	(segment
		(start 145.856452 -132.15366)
		(end 145.856452 -132.50164)
		(width 0.14224)
		(layer "In2.Cu")
		(net "M_K_DQS_DN<16>")
	)
	(segment
		(start 145.856452 -133.79704)
		(end 146.019012 -133.9596)
		(width 0.14224)
		(layer "In2.Cu")
		(net "M_K_DQS_DN<16>")
	)
	(segment
		(start 123.594368 -99.280218)
		(end 123.588018 -99.290886)
		(width 0.0889)
		(layer "In2.Cu")
		(net "M_K_DQS_DN<16>")
	)
	(segment
		(start 145.856452 -132.50164)
		(end 145.988532 -132.63372)
		(width 0.14224)
		(layer "In2.Cu")
		(net "M_K_DQS_DN<16>")
	)
	(segment
		(start 123.588018 -101.272086)
		(end 123.583192 -101.280722)
		(width 0.0889)
		(layer "In2.Cu")
		(net "M_K_DQS_DN<16>")
	)
	(segment
		(start 146.527012 -131.321048)
		(end 146.527012 -131.7244)
		(width 0.14224)
		(layer "In2.Cu")
		(net "M_K_DQS_DN<16>")
	)
	(segment
		(start 128.455674 -105.991406)
		(end 128.511554 -105.991406)
		(width 0.0889)
		(layer "In2.Cu")
		(net "M_K_DQS_DN<16>")
	)
	(segment
		(start 146.143472 -133.29666)
		(end 145.996152 -133.29666)
		(width 0.14224)
		(layer "In2.Cu")
		(net "M_K_DQS_DN<16>")
	)
	(segment
		(start 146.092164 -130.8862)
		(end 146.527012 -131.321048)
		(width 0.14224)
		(layer "In2.Cu")
		(net "M_K_DQS_DN<16>")
	)
	(segment
		(start 145.988532 -132.63372)
		(end 146.143472 -132.63372)
		(width 0.14224)
		(layer "In2.Cu")
		(net "M_K_DQS_DN<16>")
	)
	(segment
		(start 134.376668 -108.0008)
		(end 136.21004 -108.0008)
		(width 0.14224)
		(layer "In2.Cu")
		(net "M_K_DQS_DN<16>")
	)
	(segment
		(start 145.856452 -133.43636)
		(end 145.856452 -133.79704)
		(width 0.14224)
		(layer "In2.Cu")
		(net "M_K_DQS_DN<16>")
	)
	(segment
		(start 123.588018 -100.681536)
		(end 123.594368 -100.692204)
		(width 0.0889)
		(layer "In2.Cu")
		(net "M_K_DQS_DN<16>")
	)
	(segment
		(start 146.531838 -134.63143)
		(end 146.098768 -135.0645)
		(width 0.14224)
		(layer "In2.Cu")
		(net "M_K_DQS_DN<16>")
	)
	(segment
		(start 145.996152 -133.29666)
		(end 145.856452 -133.43636)
		(width 0.14224)
		(layer "In2.Cu")
		(net "M_K_DQS_DN<16>")
	)
	(segment
		(start 133.487668 -107.1118)
		(end 134.376668 -108.0008)
		(width 0.14224)
		(layer "In2.Cu")
		(net "M_K_DQS_DN<16>")
	)
	(segment
		(start 146.019012 -133.9596)
		(end 146.344132 -133.9596)
		(width 0.14224)
		(layer "In2.Cu")
		(net "M_K_DQS_DN<16>")
	)
	(arc
		(start 124.000006 -96.922336)
		(mid 124.525187 -97.531489)
		(end 123.956318 -98.100134)
		(width 0.0889)
		(layer "In2.Cu")
		(net "M_K_DQS_DN<16>")
	)
	(arc
		(start 123.594368 -100.692204)
		(mid 123.667166 -100.982967)
		(end 123.588018 -101.272086)
		(width 0.0889)
		(layer "In2.Cu")
		(net "M_K_DQS_DN<16>")
	)
	(arc
		(start 123.588018 -98.700336)
		(mid 123.66724 -98.989454)
		(end 123.594368 -99.280218)
		(width 0.0889)
		(layer "In2.Cu")
		(net "M_K_DQS_DN<16>")
	)
	(arc
		(start 123.588018 -100.28174)
		(mid 123.534519 -100.481638)
		(end 123.588018 -100.681536)
		(width 0.0889)
		(layer "In2.Cu")
		(net "M_K_DQS_DN<16>")
	)
	(arc
		(start 123.583192 -101.280722)
		(mid 123.534437 -101.477074)
		(end 123.588018 -101.672136)
		(width 0.0889)
		(layer "In2.Cu")
		(net "M_K_DQS_DN<16>")
	)
	(arc
		(start 123.583192 -99.299522)
		(mid 123.534437 -99.495874)
		(end 123.588018 -99.690936)
		(width 0.0889)
		(layer "In2.Cu")
		(net "M_K_DQS_DN<16>")
	)
	(arc
		(start 123.583192 -102.271322)
		(mid 123.534437 -102.467674)
		(end 123.588018 -102.662736)
		(width 0.0889)
		(layer "In2.Cu")
		(net "M_K_DQS_DN<16>")
	)
	(arc
		(start 123.923552 -98.100134)
		(mid 123.585383 -98.304932)
		(end 123.588018 -98.700336)
		(width 0.0889)
		(layer "In2.Cu")
		(net "M_K_DQS_DN<16>")
	)
	(arc
		(start 123.588018 -99.690936)
		(mid 123.667149 -99.986338)
		(end 123.588018 -100.28174)
		(width 0.0889)
		(layer "In2.Cu")
		(net "M_K_DQS_DN<16>")
	)
	(arc
		(start 123.588018 -101.672136)
		(mid 123.66724 -101.961254)
		(end 123.594368 -102.252018)
		(width 0.0889)
		(layer "In2.Cu")
		(net "M_K_DQS_DN<16>")
	)
	(segment
		(start 137.417302 -135.001762)
		(end 137.165334 -135.25373)
		(width 0.1651)
		(layer "F.Cu")
		(net "M_K_DQS_DN<15>")
	)
	(segment
		(start 137.231374 -134.148068)
		(end 137.231374 -134.5692)
		(width 0.1651)
		(layer "F.Cu")
		(net "M_K_DQS_DN<15>")
	)
	(segment
		(start 118.212362 -96.518984)
		(end 118.783862 -96.518984)
		(width 0.1651)
		(layer "F.Cu")
		(net "M_K_DQS_DN<15>")
	)
	(segment
		(start 137.649458 -133.729984)
		(end 137.231374 -134.148068)
		(width 0.1651)
		(layer "F.Cu")
		(net "M_K_DQS_DN<15>")
	)
	(segment
		(start 137.231374 -134.5692)
		(end 137.417302 -134.755128)
		(width 0.1651)
		(layer "F.Cu")
		(net "M_K_DQS_DN<15>")
	)
	(segment
		(start 137.417302 -134.755128)
		(end 137.417302 -135.001762)
		(width 0.1651)
		(layer "F.Cu")
		(net "M_K_DQS_DN<15>")
	)
	(segment
		(start 137.649458 -133.0706)
		(end 137.649458 -133.729984)
		(width 0.1651)
		(layer "F.Cu")
		(net "M_K_DQS_DN<15>")
	)
	(segment
		(start 136.767824 -135.0645)
		(end 136.748774 -135.0645)
		(width 0.1651)
		(layer "F.Cu")
		(net "M_K_DQS_DN<15>")
	)
	(segment
		(start 137.165334 -135.25373)
		(end 136.957054 -135.25373)
		(width 0.1651)
		(layer "F.Cu")
		(net "M_K_DQS_DN<15>")
	)
	(segment
		(start 136.957054 -135.25373)
		(end 136.767824 -135.0645)
		(width 0.1651)
		(layer "F.Cu")
		(net "M_K_DQS_DN<15>")
	)
	(via
		(at 136.74217 -130.8862)
		(size 0.508)
		(drill 0.254)
		(layers "F.Cu" "B.Cu")
		(net "M_K_DQS_DN<15>")
	)
	(via
		(at 118.783862 -96.518984)
		(size 0.508)
		(drill 0.254)
		(layers "F.Cu" "B.Cu")
		(net "M_K_DQS_DN<15>")
	)
	(via
		(at 136.748774 -135.0645)
		(size 0.508)
		(drill 0.254)
		(layers "F.Cu" "B.Cu")
		(net "M_K_DQS_DN<15>")
	)
	(segment
		(start 137.205974 -131.4196)
		(end 137.383774 -131.2418)
		(width 0.1651)
		(layer "B.Cu")
		(net "M_K_DQS_DN<15>")
	)
	(segment
		(start 137.205974 -131.775454)
		(end 137.205974 -131.4196)
		(width 0.1651)
		(layer "B.Cu")
		(net "M_K_DQS_DN<15>")
	)
	(segment
		(start 137.383774 -130.9116)
		(end 137.16381 -130.691636)
		(width 0.1651)
		(layer "B.Cu")
		(net "M_K_DQS_DN<15>")
	)
	(segment
		(start 137.649458 -132.219446)
		(end 137.649712 -132.219192)
		(width 0.1651)
		(layer "B.Cu")
		(net "M_K_DQS_DN<15>")
	)
	(segment
		(start 137.649458 -132.876036)
		(end 137.649458 -132.219446)
		(width 0.1651)
		(layer "B.Cu")
		(net "M_K_DQS_DN<15>")
	)
	(segment
		(start 136.936734 -130.691636)
		(end 136.74217 -130.8862)
		(width 0.1651)
		(layer "B.Cu")
		(net "M_K_DQS_DN<15>")
	)
	(segment
		(start 137.16381 -130.691636)
		(end 136.936734 -130.691636)
		(width 0.1651)
		(layer "B.Cu")
		(net "M_K_DQS_DN<15>")
	)
	(segment
		(start 137.383774 -131.2418)
		(end 137.383774 -130.9116)
		(width 0.1651)
		(layer "B.Cu")
		(net "M_K_DQS_DN<15>")
	)
	(segment
		(start 137.649712 -132.219192)
		(end 137.205974 -131.775454)
		(width 0.1651)
		(layer "B.Cu")
		(net "M_K_DQS_DN<15>")
	)
	(segment
		(start 137.531348 -120.383808)
		(end 137.531348 -130.097022)
		(width 0.14224)
		(layer "In2.Cu")
		(net "M_K_DQS_DN<15>")
	)
	(segment
		(start 118.805452 -98.100134)
		(end 118.772686 -98.100134)
		(width 0.0889)
		(layer "In2.Cu")
		(net "M_K_DQS_DN<15>")
	)
	(segment
		(start 136.669018 -133.9596)
		(end 136.994138 -133.9596)
		(width 0.14224)
		(layer "In2.Cu")
		(net "M_K_DQS_DN<15>")
	)
	(segment
		(start 137.531348 -130.097022)
		(end 136.74217 -130.8862)
		(width 0.14224)
		(layer "In2.Cu")
		(net "M_K_DQS_DN<15>")
	)
	(segment
		(start 136.506458 -132.15366)
		(end 136.506458 -132.50164)
		(width 0.14224)
		(layer "In2.Cu")
		(net "M_K_DQS_DN<15>")
	)
	(segment
		(start 120.266968 -113.453672)
		(end 124.200158 -117.386862)
		(width 0.14224)
		(layer "In2.Cu")
		(net "M_K_DQS_DN<15>")
	)
	(segment
		(start 118.31193 -103.47706)
		(end 118.31193 -104.81945)
		(width 0.0889)
		(layer "In2.Cu")
		(net "M_K_DQS_DN<15>")
	)
	(segment
		(start 136.994138 -133.9596)
		(end 137.181844 -134.147306)
		(width 0.14224)
		(layer "In2.Cu")
		(net "M_K_DQS_DN<15>")
	)
	(segment
		(start 137.181844 -134.63143)
		(end 136.748774 -135.0645)
		(width 0.14224)
		(layer "In2.Cu")
		(net "M_K_DQS_DN<15>")
	)
	(segment
		(start 136.638538 -132.63372)
		(end 136.793478 -132.63372)
		(width 0.14224)
		(layer "In2.Cu")
		(net "M_K_DQS_DN<15>")
	)
	(segment
		(start 136.948418 -133.14172)
		(end 136.793478 -133.29666)
		(width 0.14224)
		(layer "In2.Cu")
		(net "M_K_DQS_DN<15>")
	)
	(segment
		(start 137.181844 -134.147306)
		(end 137.181844 -134.63143)
		(width 0.14224)
		(layer "In2.Cu")
		(net "M_K_DQS_DN<15>")
	)
	(segment
		(start 118.432326 -101.663246)
		(end 118.437152 -101.671882)
		(width 0.0889)
		(layer "In2.Cu")
		(net "M_K_DQS_DN<15>")
	)
	(segment
		(start 118.443502 -98.289618)
		(end 118.437152 -98.300286)
		(width 0.0889)
		(layer "In2.Cu")
		(net "M_K_DQS_DN<15>")
	)
	(segment
		(start 118.443502 -99.280218)
		(end 118.437152 -99.290886)
		(width 0.0889)
		(layer "In2.Cu")
		(net "M_K_DQS_DN<15>")
	)
	(segment
		(start 136.948418 -132.78866)
		(end 136.948418 -133.14172)
		(width 0.14224)
		(layer "In2.Cu")
		(net "M_K_DQS_DN<15>")
	)
	(segment
		(start 136.506458 -133.79704)
		(end 136.669018 -133.9596)
		(width 0.14224)
		(layer "In2.Cu")
		(net "M_K_DQS_DN<15>")
	)
	(segment
		(start 118.430294 -100.668836)
		(end 118.446042 -100.696268)
		(width 0.0889)
		(layer "In2.Cu")
		(net "M_K_DQS_DN<15>")
	)
	(segment
		(start 136.74217 -130.8862)
		(end 137.177018 -131.321048)
		(width 0.14224)
		(layer "In2.Cu")
		(net "M_K_DQS_DN<15>")
	)
	(segment
		(start 136.506458 -132.50164)
		(end 136.638538 -132.63372)
		(width 0.14224)
		(layer "In2.Cu")
		(net "M_K_DQS_DN<15>")
	)
	(segment
		(start 118.171722 -105.70083)
		(end 118.211092 -105.7402)
		(width 0.0889)
		(layer "In2.Cu")
		(net "M_K_DQS_DN<15>")
	)
	(segment
		(start 118.437152 -99.690682)
		(end 118.443502 -99.70135)
		(width 0.0889)
		(layer "In2.Cu")
		(net "M_K_DQS_DN<15>")
	)
	(segment
		(start 118.211092 -110.339124)
		(end 120.266968 -112.395)
		(width 0.14224)
		(layer "In2.Cu")
		(net "M_K_DQS_DN<15>")
	)
	(segment
		(start 136.897618 -132.0038)
		(end 136.656318 -132.0038)
		(width 0.14224)
		(layer "In2.Cu")
		(net "M_K_DQS_DN<15>")
	)
	(segment
		(start 136.656318 -132.0038)
		(end 136.506458 -132.15366)
		(width 0.14224)
		(layer "In2.Cu")
		(net "M_K_DQS_DN<15>")
	)
	(segment
		(start 118.437152 -98.300286)
		(end 118.432326 -98.308922)
		(width 0.0889)
		(layer "In2.Cu")
		(net "M_K_DQS_DN<15>")
	)
	(segment
		(start 137.177018 -131.7244)
		(end 136.897618 -132.0038)
		(width 0.14224)
		(layer "In2.Cu")
		(net "M_K_DQS_DN<15>")
	)
	(segment
		(start 118.171722 -104.959658)
		(end 118.171722 -105.70083)
		(width 0.0889)
		(layer "In2.Cu")
		(net "M_K_DQS_DN<15>")
	)
	(segment
		(start 118.211092 -105.762298)
		(end 118.211092 -110.339124)
		(width 0.14224)
		(layer "In2.Cu")
		(net "M_K_DQS_DN<15>")
	)
	(segment
		(start 124.200158 -117.386862)
		(end 134.535164 -117.386862)
		(width 0.14224)
		(layer "In2.Cu")
		(net "M_K_DQS_DN<15>")
	)
	(segment
		(start 136.793478 -132.63372)
		(end 136.948418 -132.78866)
		(width 0.14224)
		(layer "In2.Cu")
		(net "M_K_DQS_DN<15>")
	)
	(segment
		(start 118.211092 -105.7402)
		(end 118.211092 -105.762298)
		(width 0.0889)
		(layer "In2.Cu")
		(net "M_K_DQS_DN<15>")
	)
	(segment
		(start 134.535164 -117.386862)
		(end 134.534656 -117.387116)
		(width 0.14224)
		(layer "In2.Cu")
		(net "M_K_DQS_DN<15>")
	)
	(segment
		(start 134.534656 -117.387116)
		(end 137.531348 -120.383808)
		(width 0.14224)
		(layer "In2.Cu")
		(net "M_K_DQS_DN<15>")
	)
	(segment
		(start 136.646158 -133.29666)
		(end 136.506458 -133.43636)
		(width 0.14224)
		(layer "In2.Cu")
		(net "M_K_DQS_DN<15>")
	)
	(segment
		(start 136.793478 -133.29666)
		(end 136.646158 -133.29666)
		(width 0.14224)
		(layer "In2.Cu")
		(net "M_K_DQS_DN<15>")
	)
	(segment
		(start 118.437152 -101.671882)
		(end 118.443502 -101.68255)
		(width 0.0889)
		(layer "In2.Cu")
		(net "M_K_DQS_DN<15>")
	)
	(segment
		(start 118.443756 -103.241602)
		(end 118.31193 -103.47706)
		(width 0.0889)
		(layer "In2.Cu")
		(net "M_K_DQS_DN<15>")
	)
	(segment
		(start 120.266968 -112.395)
		(end 120.266968 -113.453672)
		(width 0.14224)
		(layer "In2.Cu")
		(net "M_K_DQS_DN<15>")
	)
	(segment
		(start 118.31193 -104.81945)
		(end 118.171722 -104.959658)
		(width 0.0889)
		(layer "In2.Cu")
		(net "M_K_DQS_DN<15>")
	)
	(segment
		(start 137.177018 -131.321048)
		(end 137.177018 -131.7244)
		(width 0.14224)
		(layer "In2.Cu")
		(net "M_K_DQS_DN<15>")
	)
	(segment
		(start 136.506458 -133.43636)
		(end 136.506458 -133.79704)
		(width 0.14224)
		(layer "In2.Cu")
		(net "M_K_DQS_DN<15>")
	)
	(arc
		(start 119.215662 -97.10674)
		(mid 119.329591 -97.735098)
		(end 118.805452 -98.100134)
		(width 0.0889)
		(layer "In2.Cu")
		(net "M_K_DQS_DN<15>")
	)
	(arc
		(start 118.772686 -98.100134)
		(mid 118.582766 -98.150883)
		(end 118.443502 -98.289618)
		(width 0.0889)
		(layer "In2.Cu")
		(net "M_K_DQS_DN<15>")
	)
	(arc
		(start 118.437152 -98.700336)
		(mid 118.516374 -98.989454)
		(end 118.443502 -99.280218)
		(width 0.0889)
		(layer "In2.Cu")
		(net "M_K_DQS_DN<15>")
	)
	(arc
		(start 118.443502 -101.68255)
		(mid 118.5163 -101.973313)
		(end 118.437152 -102.262432)
		(width 0.0889)
		(layer "In2.Cu")
		(net "M_K_DQS_DN<15>")
	)
	(arc
		(start 118.437152 -100.281232)
		(mid 118.383714 -100.474137)
		(end 118.430294 -100.668836)
		(width 0.0889)
		(layer "In2.Cu")
		(net "M_K_DQS_DN<15>")
	)
	(arc
		(start 118.783862 -96.518984)
		(mid 118.982577 -96.825487)
		(end 119.215662 -97.10674)
		(width 0.0889)
		(layer "In2.Cu")
		(net "M_K_DQS_DN<15>")
	)
	(arc
		(start 118.443502 -99.70135)
		(mid 118.5163 -99.992113)
		(end 118.437152 -100.281232)
		(width 0.0889)
		(layer "In2.Cu")
		(net "M_K_DQS_DN<15>")
	)
	(arc
		(start 118.437152 -102.262432)
		(mid 118.383526 -102.462584)
		(end 118.437152 -102.662736)
		(width 0.0889)
		(layer "In2.Cu")
		(net "M_K_DQS_DN<15>")
	)
	(arc
		(start 118.432326 -98.308922)
		(mid 118.383571 -98.505274)
		(end 118.437152 -98.700336)
		(width 0.0889)
		(layer "In2.Cu")
		(net "M_K_DQS_DN<15>")
	)
	(arc
		(start 118.437152 -99.290886)
		(mid 118.383653 -99.490784)
		(end 118.437152 -99.690682)
		(width 0.0889)
		(layer "In2.Cu")
		(net "M_K_DQS_DN<15>")
	)
	(arc
		(start 118.446042 -100.696268)
		(mid 118.516439 -100.985219)
		(end 118.437152 -101.271832)
		(width 0.0889)
		(layer "In2.Cu")
		(net "M_K_DQS_DN<15>")
	)
	(arc
		(start 118.437152 -101.271832)
		(mid 118.383682 -101.466895)
		(end 118.432326 -101.663246)
		(width 0.0889)
		(layer "In2.Cu")
		(net "M_K_DQS_DN<15>")
	)
	(arc
		(start 118.437152 -102.662736)
		(mid 118.516244 -102.951316)
		(end 118.443756 -103.241602)
		(width 0.0889)
		(layer "In2.Cu")
		(net "M_K_DQS_DN<15>")
	)
	(segment
		(start 127.60706 -135.25373)
		(end 127.41783 -135.0645)
		(width 0.1651)
		(layer "F.Cu")
		(net "M_K_DQS_DN<14>")
	)
	(segment
		(start 128.299464 -133.0706)
		(end 128.299464 -133.729984)
		(width 0.1651)
		(layer "F.Cu")
		(net "M_K_DQS_DN<14>")
	)
	(segment
		(start 127.81534 -135.25373)
		(end 127.60706 -135.25373)
		(width 0.1651)
		(layer "F.Cu")
		(net "M_K_DQS_DN<14>")
	)
	(segment
		(start 128.299464 -133.729984)
		(end 127.88138 -134.148068)
		(width 0.1651)
		(layer "F.Cu")
		(net "M_K_DQS_DN<14>")
	)
	(segment
		(start 127.88138 -134.5692)
		(end 128.067308 -134.755128)
		(width 0.1651)
		(layer "F.Cu")
		(net "M_K_DQS_DN<14>")
	)
	(segment
		(start 127.88138 -134.148068)
		(end 127.88138 -134.5692)
		(width 0.1651)
		(layer "F.Cu")
		(net "M_K_DQS_DN<14>")
	)
	(segment
		(start 127.41783 -135.0645)
		(end 127.39878 -135.0645)
		(width 0.1651)
		(layer "F.Cu")
		(net "M_K_DQS_DN<14>")
	)
	(segment
		(start 128.067308 -134.755128)
		(end 128.067308 -135.001762)
		(width 0.1651)
		(layer "F.Cu")
		(net "M_K_DQS_DN<14>")
	)
	(segment
		(start 128.067308 -135.001762)
		(end 127.81534 -135.25373)
		(width 0.1651)
		(layer "F.Cu")
		(net "M_K_DQS_DN<14>")
	)
	(segment
		(start 113.061242 -97.509584)
		(end 113.632742 -97.509584)
		(width 0.1651)
		(layer "F.Cu")
		(net "M_K_DQS_DN<14>")
	)
	(via
		(at 127.39878 -135.0645)
		(size 0.508)
		(drill 0.254)
		(layers "F.Cu" "B.Cu")
		(net "M_K_DQS_DN<14>")
	)
	(via
		(at 127.392176 -130.8862)
		(size 0.508)
		(drill 0.254)
		(layers "F.Cu" "B.Cu")
		(net "M_K_DQS_DN<14>")
	)
	(via
		(at 113.632742 -97.509584)
		(size 0.508)
		(drill 0.254)
		(layers "F.Cu" "B.Cu")
		(net "M_K_DQS_DN<14>")
	)
	(segment
		(start 127.85598 -131.775454)
		(end 127.85598 -131.4196)
		(width 0.1651)
		(layer "B.Cu")
		(net "M_K_DQS_DN<14>")
	)
	(segment
		(start 128.299718 -132.875528)
		(end 128.299718 -132.219192)
		(width 0.1651)
		(layer "B.Cu")
		(net "M_K_DQS_DN<14>")
	)
	(segment
		(start 128.03378 -131.2418)
		(end 128.03378 -130.9116)
		(width 0.1651)
		(layer "B.Cu")
		(net "M_K_DQS_DN<14>")
	)
	(segment
		(start 127.85598 -131.4196)
		(end 128.03378 -131.2418)
		(width 0.1651)
		(layer "B.Cu")
		(net "M_K_DQS_DN<14>")
	)
	(segment
		(start 128.299464 -132.876036)
		(end 128.299718 -132.875528)
		(width 0.1651)
		(layer "B.Cu")
		(net "M_K_DQS_DN<14>")
	)
	(segment
		(start 127.813816 -130.691636)
		(end 127.58674 -130.691636)
		(width 0.1651)
		(layer "B.Cu")
		(net "M_K_DQS_DN<14>")
	)
	(segment
		(start 128.03378 -130.9116)
		(end 127.813816 -130.691636)
		(width 0.1651)
		(layer "B.Cu")
		(net "M_K_DQS_DN<14>")
	)
	(segment
		(start 128.299718 -132.219192)
		(end 127.85598 -131.775454)
		(width 0.1651)
		(layer "B.Cu")
		(net "M_K_DQS_DN<14>")
	)
	(segment
		(start 127.58674 -130.691636)
		(end 127.392176 -130.8862)
		(width 0.1651)
		(layer "B.Cu")
		(net "M_K_DQS_DN<14>")
	)
	(segment
		(start 127.156464 -133.43636)
		(end 127.156464 -133.79704)
		(width 0.14224)
		(layer "In2.Cu")
		(net "M_K_DQS_DN<14>")
	)
	(segment
		(start 128.174496 -127.955294)
		(end 128.174496 -130.10388)
		(width 0.14224)
		(layer "In2.Cu")
		(net "M_K_DQS_DN<14>")
	)
	(segment
		(start 109.867192 -105.080054)
		(end 109.867192 -106.15803)
		(width 0.0889)
		(layer "In2.Cu")
		(net "M_K_DQS_DN<14>")
	)
	(segment
		(start 111.515398 -103.431848)
		(end 109.867192 -105.080054)
		(width 0.0889)
		(layer "In2.Cu")
		(net "M_K_DQS_DN<14>")
	)
	(segment
		(start 127.443484 -133.29666)
		(end 127.296164 -133.29666)
		(width 0.14224)
		(layer "In2.Cu")
		(net "M_K_DQS_DN<14>")
	)
	(segment
		(start 127.296164 -133.29666)
		(end 127.156464 -133.43636)
		(width 0.14224)
		(layer "In2.Cu")
		(net "M_K_DQS_DN<14>")
	)
	(segment
		(start 127.827024 -131.7244)
		(end 127.547624 -132.0038)
		(width 0.14224)
		(layer "In2.Cu")
		(net "M_K_DQS_DN<14>")
	)
	(segment
		(start 127.306324 -132.0038)
		(end 127.156464 -132.15366)
		(width 0.14224)
		(layer "In2.Cu")
		(net "M_K_DQS_DN<14>")
	)
	(segment
		(start 109.906562 -106.1974)
		(end 109.906562 -106.219498)
		(width 0.0889)
		(layer "In2.Cu")
		(net "M_K_DQS_DN<14>")
	)
	(segment
		(start 127.83185 -134.147306)
		(end 127.83185 -134.63143)
		(width 0.14224)
		(layer "In2.Cu")
		(net "M_K_DQS_DN<14>")
	)
	(segment
		(start 109.867192 -106.15803)
		(end 109.906562 -106.1974)
		(width 0.0889)
		(layer "In2.Cu")
		(net "M_K_DQS_DN<14>")
	)
	(segment
		(start 127.156464 -132.15366)
		(end 127.156464 -132.50164)
		(width 0.14224)
		(layer "In2.Cu")
		(net "M_K_DQS_DN<14>")
	)
	(segment
		(start 127.443484 -132.63372)
		(end 127.598424 -132.78866)
		(width 0.14224)
		(layer "In2.Cu")
		(net "M_K_DQS_DN<14>")
	)
	(segment
		(start 127.547624 -132.0038)
		(end 127.306324 -132.0038)
		(width 0.14224)
		(layer "In2.Cu")
		(net "M_K_DQS_DN<14>")
	)
	(segment
		(start 119.343424 -124.874528)
		(end 122.04573 -124.874528)
		(width 0.14224)
		(layer "In2.Cu")
		(net "M_K_DQS_DN<14>")
	)
	(segment
		(start 113.583974 -97.104454)
		(end 113.57483 -97.113598)
		(width 0.0889)
		(layer "In2.Cu")
		(net "M_K_DQS_DN<14>")
	)
	(segment
		(start 127.288544 -132.63372)
		(end 127.443484 -132.63372)
		(width 0.14224)
		(layer "In2.Cu")
		(net "M_K_DQS_DN<14>")
	)
	(segment
		(start 127.598424 -133.14172)
		(end 127.443484 -133.29666)
		(width 0.14224)
		(layer "In2.Cu")
		(net "M_K_DQS_DN<14>")
	)
	(segment
		(start 123.58624 -127.149606)
		(end 127.368808 -127.149606)
		(width 0.14224)
		(layer "In2.Cu")
		(net "M_K_DQS_DN<14>")
	)
	(segment
		(start 112.795812 -100.57638)
		(end 112.756188 -100.57638)
		(width 0.0889)
		(layer "In2.Cu")
		(net "M_K_DQS_DN<14>")
	)
	(segment
		(start 113.292382 -99.280218)
		(end 113.286032 -99.290886)
		(width 0.0889)
		(layer "In2.Cu")
		(net "M_K_DQS_DN<14>")
	)
	(segment
		(start 127.156464 -132.50164)
		(end 127.288544 -132.63372)
		(width 0.14224)
		(layer "In2.Cu")
		(net "M_K_DQS_DN<14>")
	)
	(segment
		(start 113.793778 -97.104454)
		(end 113.583974 -97.104454)
		(width 0.0889)
		(layer "In2.Cu")
		(net "M_K_DQS_DN<14>")
	)
	(segment
		(start 113.898426 -97.334832)
		(end 113.898426 -97.209102)
		(width 0.0889)
		(layer "In2.Cu")
		(net "M_K_DQS_DN<14>")
	)
	(segment
		(start 128.174496 -130.10388)
		(end 127.392176 -130.8862)
		(width 0.14224)
		(layer "In2.Cu")
		(net "M_K_DQS_DN<14>")
	)
	(segment
		(start 123.132088 -125.960886)
		(end 123.132088 -126.695454)
		(width 0.14224)
		(layer "In2.Cu")
		(net "M_K_DQS_DN<14>")
	)
	(segment
		(start 127.644144 -133.9596)
		(end 127.83185 -134.147306)
		(width 0.14224)
		(layer "In2.Cu")
		(net "M_K_DQS_DN<14>")
	)
	(segment
		(start 113.286032 -98.300286)
		(end 113.281206 -98.308922)
		(width 0.0889)
		(layer "In2.Cu")
		(net "M_K_DQS_DN<14>")
	)
	(segment
		(start 127.368808 -127.149606)
		(end 128.174496 -127.955294)
		(width 0.14224)
		(layer "In2.Cu")
		(net "M_K_DQS_DN<14>")
	)
	(segment
		(start 127.392176 -130.8862)
		(end 127.827024 -131.321048)
		(width 0.14224)
		(layer "In2.Cu")
		(net "M_K_DQS_DN<14>")
	)
	(segment
		(start 127.83185 -134.63143)
		(end 127.39878 -135.0645)
		(width 0.14224)
		(layer "In2.Cu")
		(net "M_K_DQS_DN<14>")
	)
	(segment
		(start 113.292382 -98.289618)
		(end 113.286032 -98.300286)
		(width 0.0889)
		(layer "In2.Cu")
		(net "M_K_DQS_DN<14>")
	)
	(segment
		(start 123.132088 -126.695454)
		(end 123.58624 -127.149606)
		(width 0.14224)
		(layer "In2.Cu")
		(net "M_K_DQS_DN<14>")
	)
	(segment
		(start 109.906562 -115.437666)
		(end 119.343424 -124.874528)
		(width 0.14224)
		(layer "In2.Cu")
		(net "M_K_DQS_DN<14>")
	)
	(segment
		(start 112.427512 -100.776278)
		(end 111.515398 -102.35692)
		(width 0.0889)
		(layer "In2.Cu")
		(net "M_K_DQS_DN<14>")
	)
	(segment
		(start 113.898426 -97.209102)
		(end 113.793778 -97.104454)
		(width 0.0889)
		(layer "In2.Cu")
		(net "M_K_DQS_DN<14>")
	)
	(segment
		(start 127.827024 -131.321048)
		(end 127.827024 -131.7244)
		(width 0.14224)
		(layer "In2.Cu")
		(net "M_K_DQS_DN<14>")
	)
	(segment
		(start 113.286032 -99.290886)
		(end 113.281206 -99.299522)
		(width 0.0889)
		(layer "In2.Cu")
		(net "M_K_DQS_DN<14>")
	)
	(segment
		(start 122.04573 -124.874528)
		(end 123.132088 -125.960886)
		(width 0.14224)
		(layer "In2.Cu")
		(net "M_K_DQS_DN<14>")
	)
	(segment
		(start 127.319024 -133.9596)
		(end 127.644144 -133.9596)
		(width 0.14224)
		(layer "In2.Cu")
		(net "M_K_DQS_DN<14>")
	)
	(segment
		(start 113.632742 -97.509584)
		(end 113.723674 -97.509584)
		(width 0.0889)
		(layer "In2.Cu")
		(net "M_K_DQS_DN<14>")
	)
	(segment
		(start 127.156464 -133.79704)
		(end 127.319024 -133.9596)
		(width 0.14224)
		(layer "In2.Cu")
		(net "M_K_DQS_DN<14>")
	)
	(segment
		(start 111.515398 -102.35692)
		(end 111.515398 -103.431848)
		(width 0.0889)
		(layer "In2.Cu")
		(net "M_K_DQS_DN<14>")
	)
	(segment
		(start 109.906562 -106.219498)
		(end 109.906562 -115.437666)
		(width 0.14224)
		(layer "In2.Cu")
		(net "M_K_DQS_DN<14>")
	)
	(segment
		(start 127.598424 -132.78866)
		(end 127.598424 -133.14172)
		(width 0.14224)
		(layer "In2.Cu")
		(net "M_K_DQS_DN<14>")
	)
	(segment
		(start 113.723674 -97.509584)
		(end 113.898426 -97.334832)
		(width 0.0889)
		(layer "In2.Cu")
		(net "M_K_DQS_DN<14>")
	)
	(arc
		(start 113.286032 -99.690936)
		(mid 113.289141 -99.696183)
		(end 113.292382 -99.70135)
		(width 0.0889)
		(layer "In2.Cu")
		(net "M_K_DQS_DN<14>")
	)
	(arc
		(start 113.528856 -97.122996)
		(mid 113.262688 -97.356491)
		(end 113.286032 -97.709736)
		(width 0.0889)
		(layer "In2.Cu")
		(net "M_K_DQS_DN<14>")
	)
	(arc
		(start 112.756188 -100.57638)
		(mid 112.566259 -100.63425)
		(end 112.427512 -100.776278)
		(width 0.0889)
		(layer "In2.Cu")
		(net "M_K_DQS_DN<14>")
	)
	(arc
		(start 113.281206 -98.308922)
		(mid 113.232451 -98.505274)
		(end 113.286032 -98.700336)
		(width 0.0889)
		(layer "In2.Cu")
		(net "M_K_DQS_DN<14>")
	)
	(arc
		(start 113.286032 -98.700336)
		(mid 113.365254 -98.989454)
		(end 113.292382 -99.280218)
		(width 0.0889)
		(layer "In2.Cu")
		(net "M_K_DQS_DN<14>")
	)
	(arc
		(start 113.292382 -99.70135)
		(mid 113.288351 -100.277532)
		(end 112.795812 -100.57638)
		(width 0.0889)
		(layer "In2.Cu")
		(net "M_K_DQS_DN<14>")
	)
	(arc
		(start 113.286032 -97.709736)
		(mid 113.365254 -97.998854)
		(end 113.292382 -98.289618)
		(width 0.0889)
		(layer "In2.Cu")
		(net "M_K_DQS_DN<14>")
	)
	(arc
		(start 113.57483 -97.113598)
		(mid 113.551706 -97.117628)
		(end 113.528856 -97.122996)
		(width 0.0889)
		(layer "In2.Cu")
		(net "M_K_DQS_DN<14>")
	)
	(arc
		(start 113.281206 -99.299522)
		(mid 113.232451 -99.495874)
		(end 113.286032 -99.690936)
		(width 0.0889)
		(layer "In2.Cu")
		(net "M_K_DQS_DN<14>")
	)
	(segment
		(start 110.485682 -100.976684)
		(end 110.485682 -100.645214)
		(width 0.0889)
		(layer "F.Cu")
		(net "M_K_DQS_DN<13>")
	)
	(segment
		(start 119.073168 -129.877312)
		(end 118.06428 -130.8862)
		(width 0.1651)
		(layer "F.Cu")
		(net "M_K_DQS_DN<13>")
	)
	(segment
		(start 119.073168 -128.4732)
		(end 119.073168 -129.877312)
		(width 0.1651)
		(layer "F.Cu")
		(net "M_K_DQS_DN<13>")
	)
	(segment
		(start 118.94947 -133.0706)
		(end 118.94947 -133.72973)
		(width 0.1651)
		(layer "F.Cu")
		(net "M_K_DQS_DN<13>")
	)
	(segment
		(start 118.71706 -134.755128)
		(end 118.71706 -135.001762)
		(width 0.1651)
		(layer "F.Cu")
		(net "M_K_DQS_DN<13>")
	)
	(segment
		(start 118.882668 -128.2827)
		(end 119.073168 -128.4732)
		(width 0.1651)
		(layer "F.Cu")
		(net "M_K_DQS_DN<13>")
	)
	(segment
		(start 109.522768 -114.2238)
		(end 111.445548 -116.14658)
		(width 0.1651)
		(layer "F.Cu")
		(net "M_K_DQS_DN<13>")
	)
	(segment
		(start 118.94947 -133.72973)
		(end 118.531132 -134.148068)
		(width 0.1651)
		(layer "F.Cu")
		(net "M_K_DQS_DN<13>")
	)
	(segment
		(start 111.445548 -119.358156)
		(end 119.073168 -126.985776)
		(width 0.1651)
		(layer "F.Cu")
		(net "M_K_DQS_DN<13>")
	)
	(segment
		(start 110.093252 -104.397302)
		(end 109.263942 -105.226612)
		(width 0.0889)
		(layer "F.Cu")
		(net "M_K_DQS_DN<13>")
	)
	(segment
		(start 118.71706 -135.001762)
		(end 118.465092 -135.25373)
		(width 0.1651)
		(layer "F.Cu")
		(net "M_K_DQS_DN<13>")
	)
	(segment
		(start 118.531132 -134.148068)
		(end 118.531132 -134.5692)
		(width 0.1651)
		(layer "F.Cu")
		(net "M_K_DQS_DN<13>")
	)
	(segment
		(start 109.263942 -106.471974)
		(end 109.365542 -106.573574)
		(width 0.0889)
		(layer "F.Cu")
		(net "M_K_DQS_DN<13>")
	)
	(segment
		(start 111.445548 -116.14658)
		(end 111.445548 -119.358156)
		(width 0.1651)
		(layer "F.Cu")
		(net "M_K_DQS_DN<13>")
	)
	(segment
		(start 109.573568 -113.0554)
		(end 109.573568 -113.7666)
		(width 0.1016)
		(layer "F.Cu")
		(net "M_K_DQS_DN<13>")
	)
	(segment
		(start 109.573568 -113.7666)
		(end 109.522768 -113.8174)
		(width 0.1016)
		(layer "F.Cu")
		(net "M_K_DQS_DN<13>")
	)
	(segment
		(start 118.06428 -130.8862)
		(end 118.041928 -130.8862)
		(width 0.1651)
		(layer "F.Cu")
		(net "M_K_DQS_DN<13>")
	)
	(segment
		(start 118.067582 -135.0645)
		(end 118.048532 -135.0645)
		(width 0.1651)
		(layer "F.Cu")
		(net "M_K_DQS_DN<13>")
	)
	(segment
		(start 110.134146 -102.1588)
		(end 110.134146 -102.158038)
		(width 0.0889)
		(layer "F.Cu")
		(net "M_K_DQS_DN<13>")
	)
	(segment
		(start 110.134146 -102.158038)
		(end 110.145576 -102.17912)
		(width 0.0889)
		(layer "F.Cu")
		(net "M_K_DQS_DN<13>")
	)
	(segment
		(start 119.073168 -127.508)
		(end 118.882668 -127.6985)
		(width 0.1651)
		(layer "F.Cu")
		(net "M_K_DQS_DN<13>")
	)
	(segment
		(start 118.531132 -134.5692)
		(end 118.71706 -134.755128)
		(width 0.1651)
		(layer "F.Cu")
		(net "M_K_DQS_DN<13>")
	)
	(segment
		(start 109.365542 -112.847374)
		(end 109.573568 -113.0554)
		(width 0.1016)
		(layer "F.Cu")
		(net "M_K_DQS_DN<13>")
	)
	(segment
		(start 110.138972 -102.757986)
		(end 110.138718 -102.75824)
		(width 0.0889)
		(layer "F.Cu")
		(net "M_K_DQS_DN<13>")
	)
	(segment
		(start 110.093252 -102.928166)
		(end 110.093252 -104.397302)
		(width 0.0889)
		(layer "F.Cu")
		(net "M_K_DQS_DN<13>")
	)
	(segment
		(start 109.365542 -106.573574)
		(end 109.365542 -112.847374)
		(width 0.1016)
		(layer "F.Cu")
		(net "M_K_DQS_DN<13>")
	)
	(segment
		(start 118.882668 -127.6985)
		(end 118.882668 -128.2827)
		(width 0.1651)
		(layer "F.Cu")
		(net "M_K_DQS_DN<13>")
	)
	(segment
		(start 118.465092 -135.25373)
		(end 118.256812 -135.25373)
		(width 0.1651)
		(layer "F.Cu")
		(net "M_K_DQS_DN<13>")
	)
	(segment
		(start 110.485682 -100.645214)
		(end 110.422182 -100.581714)
		(width 0.0889)
		(layer "F.Cu")
		(net "M_K_DQS_DN<13>")
	)
	(segment
		(start 109.522768 -113.8174)
		(end 109.522768 -114.2238)
		(width 0.1651)
		(layer "F.Cu")
		(net "M_K_DQS_DN<13>")
	)
	(segment
		(start 109.263942 -105.226612)
		(end 109.263942 -106.471974)
		(width 0.0889)
		(layer "F.Cu")
		(net "M_K_DQS_DN<13>")
	)
	(segment
		(start 118.256812 -135.25373)
		(end 118.067582 -135.0645)
		(width 0.1651)
		(layer "F.Cu")
		(net "M_K_DQS_DN<13>")
	)
	(segment
		(start 119.073168 -126.985776)
		(end 119.073168 -127.508)
		(width 0.1651)
		(layer "F.Cu")
		(net "M_K_DQS_DN<13>")
	)
	(via
		(at 118.041928 -130.8862)
		(size 0.508)
		(drill 0.254)
		(layers "F.Cu" "B.Cu")
		(net "M_K_DQS_DN<13>")
	)
	(via
		(at 118.048532 -135.0645)
		(size 0.508)
		(drill 0.254)
		(layers "F.Cu" "B.Cu")
		(net "M_K_DQS_DN<13>")
	)
	(arc
		(start 110.138718 -102.75824)
		(mid 110.104823 -102.840216)
		(end 110.093252 -102.928166)
		(width 0.0889)
		(layer "F.Cu")
		(net "M_K_DQS_DN<13>")
	)
	(arc
		(start 110.145576 -102.17912)
		(mid 110.217974 -102.469405)
		(end 110.138972 -102.757986)
		(width 0.0889)
		(layer "F.Cu")
		(net "M_K_DQS_DN<13>")
	)
	(arc
		(start 110.422182 -100.581714)
		(mid 110.124461 -100.804774)
		(end 110.138972 -101.176582)
		(width 0.0889)
		(layer "F.Cu")
		(net "M_K_DQS_DN<13>")
	)
	(arc
		(start 110.138972 -101.176582)
		(mid 110.218103 -101.471984)
		(end 110.138972 -101.767386)
		(width 0.0889)
		(layer "F.Cu")
		(net "M_K_DQS_DN<13>")
	)
	(arc
		(start 110.138972 -101.767386)
		(mid 110.085502 -101.962449)
		(end 110.134146 -102.1588)
		(width 0.0889)
		(layer "F.Cu")
		(net "M_K_DQS_DN<13>")
	)
	(segment
		(start 118.94947 -132.876036)
		(end 118.94947 -132.219192)
		(width 0.1651)
		(layer "B.Cu")
		(net "M_K_DQS_DN<13>")
	)
	(segment
		(start 118.94947 -132.219192)
		(end 118.505732 -131.775454)
		(width 0.1651)
		(layer "B.Cu")
		(net "M_K_DQS_DN<13>")
	)
	(segment
		(start 118.683532 -130.9116)
		(end 118.463568 -130.691636)
		(width 0.1651)
		(layer "B.Cu")
		(net "M_K_DQS_DN<13>")
	)
	(segment
		(start 118.505732 -131.775454)
		(end 118.505732 -131.4196)
		(width 0.1651)
		(layer "B.Cu")
		(net "M_K_DQS_DN<13>")
	)
	(segment
		(start 118.683532 -131.2418)
		(end 118.683532 -130.9116)
		(width 0.1651)
		(layer "B.Cu")
		(net "M_K_DQS_DN<13>")
	)
	(segment
		(start 118.463568 -130.691636)
		(end 118.236492 -130.691636)
		(width 0.1651)
		(layer "B.Cu")
		(net "M_K_DQS_DN<13>")
	)
	(segment
		(start 118.505732 -131.4196)
		(end 118.683532 -131.2418)
		(width 0.1651)
		(layer "B.Cu")
		(net "M_K_DQS_DN<13>")
	)
	(segment
		(start 118.236492 -130.691636)
		(end 118.041928 -130.8862)
		(width 0.1651)
		(layer "B.Cu")
		(net "M_K_DQS_DN<13>")
	)
	(segment
		(start 118.09349 -132.63372)
		(end 117.93855 -132.63372)
		(width 0.14224)
		(layer "In2.Cu")
		(net "M_K_DQS_DN<13>")
	)
	(segment
		(start 118.47703 -131.321302)
		(end 118.041928 -130.8862)
		(width 0.14224)
		(layer "In2.Cu")
		(net "M_K_DQS_DN<13>")
	)
	(segment
		(start 118.048532 -135.0645)
		(end 118.048786 -135.0645)
		(width 0.14224)
		(layer "In2.Cu")
		(net "M_K_DQS_DN<13>")
	)
	(segment
		(start 117.80647 -133.79704)
		(end 117.80647 -133.43636)
		(width 0.14224)
		(layer "In2.Cu")
		(net "M_K_DQS_DN<13>")
	)
	(segment
		(start 117.93855 -132.63372)
		(end 117.80647 -132.50164)
		(width 0.14224)
		(layer "In2.Cu")
		(net "M_K_DQS_DN<13>")
	)
	(segment
		(start 117.96903 -133.9596)
		(end 117.80647 -133.79704)
		(width 0.14224)
		(layer "In2.Cu")
		(net "M_K_DQS_DN<13>")
	)
	(segment
		(start 118.24843 -133.14172)
		(end 118.24843 -132.78866)
		(width 0.14224)
		(layer "In2.Cu")
		(net "M_K_DQS_DN<13>")
	)
	(segment
		(start 118.24843 -132.78866)
		(end 118.09349 -132.63372)
		(width 0.14224)
		(layer "In2.Cu")
		(net "M_K_DQS_DN<13>")
	)
	(segment
		(start 117.80647 -132.50164)
		(end 117.80647 -132.15366)
		(width 0.14224)
		(layer "In2.Cu")
		(net "M_K_DQS_DN<13>")
	)
	(segment
		(start 117.95633 -132.0038)
		(end 118.19763 -132.0038)
		(width 0.14224)
		(layer "In2.Cu")
		(net "M_K_DQS_DN<13>")
	)
	(segment
		(start 118.47703 -131.7244)
		(end 118.47703 -131.321302)
		(width 0.14224)
		(layer "In2.Cu")
		(net "M_K_DQS_DN<13>")
	)
	(segment
		(start 118.29415 -133.9596)
		(end 117.96903 -133.9596)
		(width 0.14224)
		(layer "In2.Cu")
		(net "M_K_DQS_DN<13>")
	)
	(segment
		(start 118.481856 -134.63143)
		(end 118.481856 -134.147306)
		(width 0.14224)
		(layer "In2.Cu")
		(net "M_K_DQS_DN<13>")
	)
	(segment
		(start 118.09349 -133.29666)
		(end 118.24843 -133.14172)
		(width 0.14224)
		(layer "In2.Cu")
		(net "M_K_DQS_DN<13>")
	)
	(segment
		(start 118.481856 -134.147306)
		(end 118.29415 -133.9596)
		(width 0.14224)
		(layer "In2.Cu")
		(net "M_K_DQS_DN<13>")
	)
	(segment
		(start 117.80647 -132.15366)
		(end 117.95633 -132.0038)
		(width 0.14224)
		(layer "In2.Cu")
		(net "M_K_DQS_DN<13>")
	)
	(segment
		(start 118.19763 -132.0038)
		(end 118.47703 -131.7244)
		(width 0.14224)
		(layer "In2.Cu")
		(net "M_K_DQS_DN<13>")
	)
	(segment
		(start 117.94617 -133.29666)
		(end 118.09349 -133.29666)
		(width 0.14224)
		(layer "In2.Cu")
		(net "M_K_DQS_DN<13>")
	)
	(segment
		(start 117.80647 -133.43636)
		(end 117.94617 -133.29666)
		(width 0.14224)
		(layer "In2.Cu")
		(net "M_K_DQS_DN<13>")
	)
	(segment
		(start 118.048786 -135.0645)
		(end 118.481856 -134.63143)
		(width 0.14224)
		(layer "In2.Cu")
		(net "M_K_DQS_DN<13>")
	)
	(segment
		(start 63.281306 -134.148068)
		(end 63.281306 -134.5692)
		(width 0.1651)
		(layer "F.Cu")
		(net "M_K_DQS_DN<12>")
	)
	(segment
		(start 63.69939 -133.0706)
		(end 63.69939 -133.729984)
		(width 0.1651)
		(layer "F.Cu")
		(net "M_K_DQS_DN<12>")
	)
	(segment
		(start 63.467234 -134.755128)
		(end 63.467234 -135.001762)
		(width 0.1651)
		(layer "F.Cu")
		(net "M_K_DQS_DN<12>")
	)
	(segment
		(start 77.192886 -95.709486)
		(end 76.621386 -95.709486)
		(width 0.1651)
		(layer "F.Cu")
		(net "M_K_DQS_DN<12>")
	)
	(segment
		(start 62.817756 -135.0645)
		(end 62.798706 -135.0645)
		(width 0.1651)
		(layer "F.Cu")
		(net "M_K_DQS_DN<12>")
	)
	(segment
		(start 63.467234 -135.001762)
		(end 63.215266 -135.25373)
		(width 0.1651)
		(layer "F.Cu")
		(net "M_K_DQS_DN<12>")
	)
	(segment
		(start 63.69939 -133.729984)
		(end 63.281306 -134.148068)
		(width 0.1651)
		(layer "F.Cu")
		(net "M_K_DQS_DN<12>")
	)
	(segment
		(start 63.006986 -135.25373)
		(end 62.817756 -135.0645)
		(width 0.1651)
		(layer "F.Cu")
		(net "M_K_DQS_DN<12>")
	)
	(segment
		(start 63.215266 -135.25373)
		(end 63.006986 -135.25373)
		(width 0.1651)
		(layer "F.Cu")
		(net "M_K_DQS_DN<12>")
	)
	(segment
		(start 63.281306 -134.5692)
		(end 63.467234 -134.755128)
		(width 0.1651)
		(layer "F.Cu")
		(net "M_K_DQS_DN<12>")
	)
	(via
		(at 76.621386 -95.709486)
		(size 0.508)
		(drill 0.254)
		(layers "F.Cu" "B.Cu")
		(net "M_K_DQS_DN<12>")
	)
	(via
		(at 62.798706 -135.0645)
		(size 0.508)
		(drill 0.254)
		(layers "F.Cu" "B.Cu")
		(net "M_K_DQS_DN<12>")
	)
	(via
		(at 62.792102 -130.8862)
		(size 0.508)
		(drill 0.254)
		(layers "F.Cu" "B.Cu")
		(net "M_K_DQS_DN<12>")
	)
	(segment
		(start 63.213742 -130.691636)
		(end 62.986666 -130.691636)
		(width 0.1651)
		(layer "B.Cu")
		(net "M_K_DQS_DN<12>")
	)
	(segment
		(start 63.255906 -131.775454)
		(end 63.255906 -131.4196)
		(width 0.1651)
		(layer "B.Cu")
		(net "M_K_DQS_DN<12>")
	)
	(segment
		(start 63.69939 -132.218938)
		(end 63.255906 -131.775454)
		(width 0.1651)
		(layer "B.Cu")
		(net "M_K_DQS_DN<12>")
	)
	(segment
		(start 62.986666 -130.691636)
		(end 62.792102 -130.8862)
		(width 0.1651)
		(layer "B.Cu")
		(net "M_K_DQS_DN<12>")
	)
	(segment
		(start 63.433706 -130.9116)
		(end 63.213742 -130.691636)
		(width 0.1651)
		(layer "B.Cu")
		(net "M_K_DQS_DN<12>")
	)
	(segment
		(start 63.433706 -131.2418)
		(end 63.433706 -130.9116)
		(width 0.1651)
		(layer "B.Cu")
		(net "M_K_DQS_DN<12>")
	)
	(segment
		(start 63.255906 -131.4196)
		(end 63.433706 -131.2418)
		(width 0.1651)
		(layer "B.Cu")
		(net "M_K_DQS_DN<12>")
	)
	(segment
		(start 63.69939 -132.876036)
		(end 63.69939 -132.218938)
		(width 0.1651)
		(layer "B.Cu")
		(net "M_K_DQS_DN<12>")
	)
	(segment
		(start 68.846192 -102.063296)
		(end 69.337936 -101.571552)
		(width 0.0889)
		(layer "In2.Cu")
		(net "M_K_DQS_DN<12>")
	)
	(segment
		(start 62.99835 -132.78866)
		(end 62.84341 -132.63372)
		(width 0.14224)
		(layer "In2.Cu")
		(net "M_K_DQS_DN<12>")
	)
	(segment
		(start 62.69609 -133.29666)
		(end 62.84341 -133.29666)
		(width 0.14224)
		(layer "In2.Cu")
		(net "M_K_DQS_DN<12>")
	)
	(segment
		(start 68.483226 -103.032814)
		(end 68.49872 -103.01732)
		(width 0.0889)
		(layer "In2.Cu")
		(net "M_K_DQS_DN<12>")
	)
	(segment
		(start 62.94755 -132.0038)
		(end 63.22695 -131.7244)
		(width 0.14224)
		(layer "In2.Cu")
		(net "M_K_DQS_DN<12>")
	)
	(segment
		(start 75.74788 -97.78619)
		(end 75.780646 -97.78619)
		(width 0.0889)
		(layer "In2.Cu")
		(net "M_K_DQS_DN<12>")
	)
	(segment
		(start 73.17613 -99.27209)
		(end 73.20026 -99.27209)
		(width 0.0889)
		(layer "In2.Cu")
		(net "M_K_DQS_DN<12>")
	)
	(segment
		(start 62.55639 -132.50164)
		(end 62.55639 -132.15366)
		(width 0.14224)
		(layer "In2.Cu")
		(net "M_K_DQS_DN<12>")
	)
	(segment
		(start 63.04407 -133.9596)
		(end 62.71895 -133.9596)
		(width 0.14224)
		(layer "In2.Cu")
		(net "M_K_DQS_DN<12>")
	)
	(segment
		(start 62.99835 -133.14172)
		(end 62.99835 -132.78866)
		(width 0.14224)
		(layer "In2.Cu")
		(net "M_K_DQS_DN<12>")
	)
	(segment
		(start 62.70625 -132.0038)
		(end 62.94755 -132.0038)
		(width 0.14224)
		(layer "In2.Cu")
		(net "M_K_DQS_DN<12>")
	)
	(segment
		(start 62.55639 -133.79704)
		(end 62.55639 -133.43636)
		(width 0.14224)
		(layer "In2.Cu")
		(net "M_K_DQS_DN<12>")
	)
	(segment
		(start 69.337936 -101.571552)
		(end 69.406516 -101.453188)
		(width 0.0889)
		(layer "In2.Cu")
		(net "M_K_DQS_DN<12>")
	)
	(segment
		(start 69.738748 -101.253036)
		(end 69.774816 -101.253036)
		(width 0.0889)
		(layer "In2.Cu")
		(net "M_K_DQS_DN<12>")
	)
	(segment
		(start 63.22695 -131.321048)
		(end 62.792102 -130.8862)
		(width 0.14224)
		(layer "In2.Cu")
		(net "M_K_DQS_DN<12>")
	)
	(segment
		(start 76.274676 -96.500188)
		(end 76.281026 -96.48952)
		(width 0.0889)
		(layer "In2.Cu")
		(net "M_K_DQS_DN<12>")
	)
	(segment
		(start 74.89317 -98.281236)
		(end 74.925936 -98.281236)
		(width 0.0889)
		(layer "In2.Cu")
		(net "M_K_DQS_DN<12>")
	)
	(segment
		(start 70.59676 -100.75799)
		(end 70.6247 -100.75799)
		(width 0.0889)
		(layer "In2.Cu")
		(net "M_K_DQS_DN<12>")
	)
	(segment
		(start 62.55639 -132.15366)
		(end 62.70625 -132.0038)
		(width 0.14224)
		(layer "In2.Cu")
		(net "M_K_DQS_DN<12>")
	)
	(segment
		(start 62.68847 -132.63372)
		(end 62.55639 -132.50164)
		(width 0.14224)
		(layer "In2.Cu")
		(net "M_K_DQS_DN<12>")
	)
	(segment
		(start 63.552832 -130.12547)
		(end 63.552832 -111.367062)
		(width 0.14224)
		(layer "In2.Cu")
		(net "M_K_DQS_DN<12>")
	)
	(segment
		(start 72.310752 -99.76739)
		(end 72.350376 -99.76739)
		(width 0.0889)
		(layer "In2.Cu")
		(net "M_K_DQS_DN<12>")
	)
	(segment
		(start 76.563474 -95.3135)
		(end 76.621386 -95.371412)
		(width 0.0889)
		(layer "In2.Cu")
		(net "M_K_DQS_DN<12>")
	)
	(segment
		(start 63.552832 -111.367062)
		(end 65.814194 -109.1057)
		(width 0.14224)
		(layer "In2.Cu")
		(net "M_K_DQS_DN<12>")
	)
	(segment
		(start 63.231776 -134.63143)
		(end 63.231776 -134.147306)
		(width 0.14224)
		(layer "In2.Cu")
		(net "M_K_DQS_DN<12>")
	)
	(segment
		(start 65.814194 -109.1057)
		(end 65.814194 -105.701592)
		(width 0.14224)
		(layer "In2.Cu")
		(net "M_K_DQS_DN<12>")
	)
	(segment
		(start 76.26985 -96.508824)
		(end 76.274676 -96.500188)
		(width 0.0889)
		(layer "In2.Cu")
		(net "M_K_DQS_DN<12>")
	)
	(segment
		(start 62.55639 -133.43636)
		(end 62.69609 -133.29666)
		(width 0.14224)
		(layer "In2.Cu")
		(net "M_K_DQS_DN<12>")
	)
	(segment
		(start 62.792102 -130.8862)
		(end 63.552832 -130.12547)
		(width 0.14224)
		(layer "In2.Cu")
		(net "M_K_DQS_DN<12>")
	)
	(segment
		(start 76.621386 -95.371412)
		(end 76.621386 -95.709486)
		(width 0.0889)
		(layer "In2.Cu")
		(net "M_K_DQS_DN<12>")
	)
	(segment
		(start 68.49872 -103.01732)
		(end 68.49872 -102.96144)
		(width 0.0889)
		(layer "In2.Cu")
		(net "M_K_DQS_DN<12>")
	)
	(segment
		(start 68.49872 -102.96144)
		(end 68.846192 -102.613968)
		(width 0.0889)
		(layer "In2.Cu")
		(net "M_K_DQS_DN<12>")
	)
	(segment
		(start 65.814194 -105.701592)
		(end 66.4972 -105.018586)
		(width 0.14224)
		(layer "In2.Cu")
		(net "M_K_DQS_DN<12>")
	)
	(segment
		(start 66.4972 -105.018586)
		(end 68.483226 -103.032814)
		(width 0.14224)
		(layer "In2.Cu")
		(net "M_K_DQS_DN<12>")
	)
	(segment
		(start 62.798706 -135.0645)
		(end 63.231776 -134.63143)
		(width 0.14224)
		(layer "In2.Cu")
		(net "M_K_DQS_DN<12>")
	)
	(segment
		(start 74.03084 -98.77679)
		(end 74.063606 -98.77679)
		(width 0.0889)
		(layer "In2.Cu")
		(net "M_K_DQS_DN<12>")
	)
	(segment
		(start 63.22695 -131.7244)
		(end 63.22695 -131.321048)
		(width 0.14224)
		(layer "In2.Cu")
		(net "M_K_DQS_DN<12>")
	)
	(segment
		(start 62.84341 -133.29666)
		(end 62.99835 -133.14172)
		(width 0.14224)
		(layer "In2.Cu")
		(net "M_K_DQS_DN<12>")
	)
	(segment
		(start 62.71895 -133.9596)
		(end 62.55639 -133.79704)
		(width 0.14224)
		(layer "In2.Cu")
		(net "M_K_DQS_DN<12>")
	)
	(segment
		(start 62.84341 -132.63372)
		(end 62.68847 -132.63372)
		(width 0.14224)
		(layer "In2.Cu")
		(net "M_K_DQS_DN<12>")
	)
	(segment
		(start 71.452232 -100.26269)
		(end 71.488046 -100.26269)
		(width 0.0889)
		(layer "In2.Cu")
		(net "M_K_DQS_DN<12>")
	)
	(segment
		(start 63.231776 -134.147306)
		(end 63.04407 -133.9596)
		(width 0.14224)
		(layer "In2.Cu")
		(net "M_K_DQS_DN<12>")
	)
	(segment
		(start 68.846192 -102.613968)
		(end 68.846192 -102.063296)
		(width 0.0889)
		(layer "In2.Cu")
		(net "M_K_DQS_DN<12>")
	)
	(arc
		(start 74.063606 -98.77679)
		(mid 74.34903 -98.693323)
		(end 74.557636 -98.481388)
		(width 0.0889)
		(layer "In2.Cu")
		(net "M_K_DQS_DN<12>")
	)
	(arc
		(start 74.557636 -98.481388)
		(mid 74.699319 -98.337584)
		(end 74.89317 -98.281236)
		(width 0.0889)
		(layer "In2.Cu")
		(net "M_K_DQS_DN<12>")
	)
	(arc
		(start 76.281026 -96.48952)
		(mid 76.353824 -96.198757)
		(end 76.274676 -95.909638)
		(width 0.0889)
		(layer "In2.Cu")
		(net "M_K_DQS_DN<12>")
	)
	(arc
		(start 76.274676 -95.909638)
		(mid 76.261081 -95.534989)
		(end 76.563474 -95.3135)
		(width 0.0889)
		(layer "In2.Cu")
		(net "M_K_DQS_DN<12>")
	)
	(arc
		(start 69.406516 -101.453188)
		(mid 69.546784 -101.310232)
		(end 69.738748 -101.253036)
		(width 0.0889)
		(layer "In2.Cu")
		(net "M_K_DQS_DN<12>")
	)
	(arc
		(start 71.488046 -100.26269)
		(mid 71.77347 -100.179223)
		(end 71.982076 -99.967288)
		(width 0.0889)
		(layer "In2.Cu")
		(net "M_K_DQS_DN<12>")
	)
	(arc
		(start 72.840596 -99.472242)
		(mid 72.982279 -99.328438)
		(end 73.17613 -99.27209)
		(width 0.0889)
		(layer "In2.Cu")
		(net "M_K_DQS_DN<12>")
	)
	(arc
		(start 69.774816 -101.253036)
		(mid 70.058033 -101.168755)
		(end 70.265036 -100.957888)
		(width 0.0889)
		(layer "In2.Cu")
		(net "M_K_DQS_DN<12>")
	)
	(arc
		(start 74.925936 -98.281236)
		(mid 75.209153 -98.196955)
		(end 75.416156 -97.986088)
		(width 0.0889)
		(layer "In2.Cu")
		(net "M_K_DQS_DN<12>")
	)
	(arc
		(start 73.699116 -98.976688)
		(mid 73.839195 -98.833952)
		(end 74.03084 -98.77679)
		(width 0.0889)
		(layer "In2.Cu")
		(net "M_K_DQS_DN<12>")
	)
	(arc
		(start 70.6247 -100.75799)
		(mid 70.912845 -100.675671)
		(end 71.123556 -100.462588)
		(width 0.0889)
		(layer "In2.Cu")
		(net "M_K_DQS_DN<12>")
	)
	(arc
		(start 75.416156 -97.986088)
		(mid 75.556235 -97.843352)
		(end 75.74788 -97.78619)
		(width 0.0889)
		(layer "In2.Cu")
		(net "M_K_DQS_DN<12>")
	)
	(arc
		(start 76.274676 -96.900238)
		(mid 76.221206 -96.705175)
		(end 76.26985 -96.508824)
		(width 0.0889)
		(layer "In2.Cu")
		(net "M_K_DQS_DN<12>")
	)
	(arc
		(start 72.350376 -99.76739)
		(mid 72.633593 -99.683109)
		(end 72.840596 -99.472242)
		(width 0.0889)
		(layer "In2.Cu")
		(net "M_K_DQS_DN<12>")
	)
	(arc
		(start 71.982076 -99.967288)
		(mid 72.12082 -99.825255)
		(end 72.310752 -99.76739)
		(width 0.0889)
		(layer "In2.Cu")
		(net "M_K_DQS_DN<12>")
	)
	(arc
		(start 75.780646 -97.78619)
		(mid 76.278897 -97.48335)
		(end 76.274676 -96.900238)
		(width 0.0889)
		(layer "In2.Cu")
		(net "M_K_DQS_DN<12>")
	)
	(arc
		(start 70.265036 -100.957888)
		(mid 70.405115 -100.815152)
		(end 70.59676 -100.75799)
		(width 0.0889)
		(layer "In2.Cu")
		(net "M_K_DQS_DN<12>")
	)
	(arc
		(start 73.20026 -99.27209)
		(mid 73.488405 -99.189771)
		(end 73.699116 -98.976688)
		(width 0.0889)
		(layer "In2.Cu")
		(net "M_K_DQS_DN<12>")
	)
	(arc
		(start 71.123556 -100.462588)
		(mid 71.2623 -100.320555)
		(end 71.452232 -100.26269)
		(width 0.0889)
		(layer "In2.Cu")
		(net "M_K_DQS_DN<12>")
	)
	(segment
		(start 54.11724 -134.755128)
		(end 54.11724 -135.001762)
		(width 0.1651)
		(layer "F.Cu")
		(net "M_K_DQS_DN<11>")
	)
	(segment
		(start 54.349396 -133.0706)
		(end 54.349396 -133.729984)
		(width 0.1651)
		(layer "F.Cu")
		(net "M_K_DQS_DN<11>")
	)
	(segment
		(start 53.467762 -135.0645)
		(end 53.448712 -135.0645)
		(width 0.1651)
		(layer "F.Cu")
		(net "M_K_DQS_DN<11>")
	)
	(segment
		(start 53.656992 -135.25373)
		(end 53.467762 -135.0645)
		(width 0.1651)
		(layer "F.Cu")
		(net "M_K_DQS_DN<11>")
	)
	(segment
		(start 53.931312 -134.5692)
		(end 54.11724 -134.755128)
		(width 0.1651)
		(layer "F.Cu")
		(net "M_K_DQS_DN<11>")
	)
	(segment
		(start 53.931312 -134.148068)
		(end 53.931312 -134.5692)
		(width 0.1651)
		(layer "F.Cu")
		(net "M_K_DQS_DN<11>")
	)
	(segment
		(start 54.349396 -133.729984)
		(end 53.931312 -134.148068)
		(width 0.1651)
		(layer "F.Cu")
		(net "M_K_DQS_DN<11>")
	)
	(segment
		(start 54.11724 -135.001762)
		(end 53.865272 -135.25373)
		(width 0.1651)
		(layer "F.Cu")
		(net "M_K_DQS_DN<11>")
	)
	(segment
		(start 72.900286 -95.21444)
		(end 72.328786 -95.21444)
		(width 0.1651)
		(layer "F.Cu")
		(net "M_K_DQS_DN<11>")
	)
	(segment
		(start 53.865272 -135.25373)
		(end 53.656992 -135.25373)
		(width 0.1651)
		(layer "F.Cu")
		(net "M_K_DQS_DN<11>")
	)
	(via
		(at 53.442108 -130.8862)
		(size 0.508)
		(drill 0.254)
		(layers "F.Cu" "B.Cu")
		(net "M_K_DQS_DN<11>")
	)
	(via
		(at 72.328786 -95.21444)
		(size 0.508)
		(drill 0.254)
		(layers "F.Cu" "B.Cu")
		(net "M_K_DQS_DN<11>")
	)
	(via
		(at 53.448712 -135.0645)
		(size 0.508)
		(drill 0.254)
		(layers "F.Cu" "B.Cu")
		(net "M_K_DQS_DN<11>")
	)
	(segment
		(start 54.083712 -130.9116)
		(end 53.863748 -130.691636)
		(width 0.1651)
		(layer "B.Cu")
		(net "M_K_DQS_DN<11>")
	)
	(segment
		(start 53.905912 -131.775454)
		(end 53.905912 -131.4196)
		(width 0.1651)
		(layer "B.Cu")
		(net "M_K_DQS_DN<11>")
	)
	(segment
		(start 54.34965 -132.219192)
		(end 53.905912 -131.775454)
		(width 0.1651)
		(layer "B.Cu")
		(net "M_K_DQS_DN<11>")
	)
	(segment
		(start 53.636672 -130.691636)
		(end 53.442108 -130.8862)
		(width 0.1651)
		(layer "B.Cu")
		(net "M_K_DQS_DN<11>")
	)
	(segment
		(start 54.34965 -132.875528)
		(end 54.34965 -132.219192)
		(width 0.1651)
		(layer "B.Cu")
		(net "M_K_DQS_DN<11>")
	)
	(segment
		(start 54.349396 -132.876036)
		(end 54.34965 -132.875528)
		(width 0.1651)
		(layer "B.Cu")
		(net "M_K_DQS_DN<11>")
	)
	(segment
		(start 53.905912 -131.4196)
		(end 54.083712 -131.2418)
		(width 0.1651)
		(layer "B.Cu")
		(net "M_K_DQS_DN<11>")
	)
	(segment
		(start 53.863748 -130.691636)
		(end 53.636672 -130.691636)
		(width 0.1651)
		(layer "B.Cu")
		(net "M_K_DQS_DN<11>")
	)
	(segment
		(start 54.083712 -131.2418)
		(end 54.083712 -130.9116)
		(width 0.1651)
		(layer "B.Cu")
		(net "M_K_DQS_DN<11>")
	)
	(segment
		(start 53.881782 -134.218426)
		(end 53.881782 -134.63143)
		(width 0.14224)
		(layer "In2.Cu")
		(net "M_K_DQS_DN<11>")
	)
	(segment
		(start 53.517038 -133.29666)
		(end 53.346096 -133.29666)
		(width 0.14224)
		(layer "In2.Cu")
		(net "M_K_DQS_DN<11>")
	)
	(segment
		(start 53.865272 -128.55956)
		(end 54.04485 -128.739392)
		(width 0.14224)
		(layer "In2.Cu")
		(net "M_K_DQS_DN<11>")
	)
	(segment
		(start 72.328786 -95.21444)
		(end 72.621902 -95.38335)
		(width 0.0889)
		(layer "In2.Cu")
		(net "M_K_DQS_DN<11>")
	)
	(segment
		(start 69.284596 -93.22435)
		(end 67.774566 -93.22435)
		(width 0.0889)
		(layer "In2.Cu")
		(net "M_K_DQS_DN<11>")
	)
	(segment
		(start 54.224428 -130.10388)
		(end 53.442108 -130.8862)
		(width 0.14224)
		(layer "In2.Cu")
		(net "M_K_DQS_DN<11>")
	)
	(segment
		(start 53.64226 -128.55956)
		(end 53.865272 -128.55956)
		(width 0.14224)
		(layer "In2.Cu")
		(net "M_K_DQS_DN<11>")
	)
	(segment
		(start 53.876956 -131.321048)
		(end 53.876956 -131.7244)
		(width 0.14224)
		(layer "In2.Cu")
		(net "M_K_DQS_DN<11>")
	)
	(segment
		(start 53.462682 -128.379982)
		(end 53.64226 -128.55956)
		(width 0.14224)
		(layer "In2.Cu")
		(net "M_K_DQS_DN<11>")
	)
	(segment
		(start 54.04485 -128.96215)
		(end 54.224428 -129.141728)
		(width 0.14224)
		(layer "In2.Cu")
		(net "M_K_DQS_DN<11>")
	)
	(segment
		(start 53.206396 -133.79704)
		(end 53.368956 -133.9596)
		(width 0.14224)
		(layer "In2.Cu")
		(net "M_K_DQS_DN<11>")
	)
	(segment
		(start 53.338476 -132.63372)
		(end 53.517038 -132.63372)
		(width 0.14224)
		(layer "In2.Cu")
		(net "M_K_DQS_DN<11>")
	)
	(segment
		(start 70.62978 -93.82379)
		(end 70.590156 -93.82379)
		(width 0.0889)
		(layer "In2.Cu")
		(net "M_K_DQS_DN<11>")
	)
	(segment
		(start 69.388482 -93.328236)
		(end 69.284596 -93.22435)
		(width 0.0889)
		(layer "In2.Cu")
		(net "M_K_DQS_DN<11>")
	)
	(segment
		(start 71.4883 -94.31909)
		(end 71.452486 -94.31909)
		(width 0.0889)
		(layer "In2.Cu")
		(net "M_K_DQS_DN<11>")
	)
	(segment
		(start 54.224428 -129.141728)
		(end 54.224428 -130.10388)
		(width 0.14224)
		(layer "In2.Cu")
		(net "M_K_DQS_DN<11>")
	)
	(segment
		(start 53.206396 -132.15366)
		(end 53.206396 -132.50164)
		(width 0.14224)
		(layer "In2.Cu")
		(net "M_K_DQS_DN<11>")
	)
	(segment
		(start 72.343772 -94.81439)
		(end 72.315832 -94.81439)
		(width 0.0889)
		(layer "In2.Cu")
		(net "M_K_DQS_DN<11>")
	)
	(segment
		(start 53.356256 -132.0038)
		(end 53.206396 -132.15366)
		(width 0.14224)
		(layer "In2.Cu")
		(net "M_K_DQS_DN<11>")
	)
	(segment
		(start 53.346096 -133.29666)
		(end 53.206396 -133.43636)
		(width 0.14224)
		(layer "In2.Cu")
		(net "M_K_DQS_DN<11>")
	)
	(segment
		(start 54.04485 -128.739392)
		(end 54.04485 -128.96215)
		(width 0.14224)
		(layer "In2.Cu")
		(net "M_K_DQS_DN<11>")
	)
	(segment
		(start 65.616074 -94.373954)
		(end 57.730898 -102.25913)
		(width 0.14224)
		(layer "In2.Cu")
		(net "M_K_DQS_DN<11>")
	)
	(segment
		(start 53.671978 -133.14172)
		(end 53.517038 -133.29666)
		(width 0.14224)
		(layer "In2.Cu")
		(net "M_K_DQS_DN<11>")
	)
	(segment
		(start 53.671978 -132.78866)
		(end 53.671978 -133.14172)
		(width 0.14224)
		(layer "In2.Cu")
		(net "M_K_DQS_DN<11>")
	)
	(segment
		(start 52.33924 -116.367814)
		(end 52.824888 -116.853462)
		(width 0.14224)
		(layer "In2.Cu")
		(net "M_K_DQS_DN<11>")
	)
	(segment
		(start 70.58533 -93.82379)
		(end 70.58533 -93.823536)
		(width 0.0889)
		(layer "In2.Cu")
		(net "M_K_DQS_DN<11>")
	)
	(segment
		(start 53.442108 -130.8862)
		(end 53.876956 -131.321048)
		(width 0.14224)
		(layer "In2.Cu")
		(net "M_K_DQS_DN<11>")
	)
	(segment
		(start 53.876956 -131.7244)
		(end 53.597556 -132.0038)
		(width 0.14224)
		(layer "In2.Cu")
		(net "M_K_DQS_DN<11>")
	)
	(segment
		(start 53.462682 -128.157224)
		(end 53.462682 -128.379982)
		(width 0.14224)
		(layer "In2.Cu")
		(net "M_K_DQS_DN<11>")
	)
	(segment
		(start 52.33924 -115.90147)
		(end 52.33924 -116.367814)
		(width 0.14224)
		(layer "In2.Cu")
		(net "M_K_DQS_DN<11>")
	)
	(segment
		(start 53.206396 -132.50164)
		(end 53.338476 -132.63372)
		(width 0.14224)
		(layer "In2.Cu")
		(net "M_K_DQS_DN<11>")
	)
	(segment
		(start 72.621902 -95.38335)
		(end 72.700642 -95.362014)
		(width 0.0889)
		(layer "In2.Cu")
		(net "M_K_DQS_DN<11>")
	)
	(segment
		(start 67.774566 -93.22435)
		(end 67.199002 -93.799914)
		(width 0.0889)
		(layer "In2.Cu")
		(net "M_K_DQS_DN<11>")
	)
	(segment
		(start 53.060092 -127.977392)
		(end 53.283104 -127.977392)
		(width 0.14224)
		(layer "In2.Cu")
		(net "M_K_DQS_DN<11>")
	)
	(segment
		(start 65.631568 -94.35846)
		(end 65.616074 -94.373954)
		(width 0.0889)
		(layer "In2.Cu")
		(net "M_K_DQS_DN<11>")
	)
	(segment
		(start 53.206396 -133.43636)
		(end 53.206396 -133.79704)
		(width 0.14224)
		(layer "In2.Cu")
		(net "M_K_DQS_DN<11>")
	)
	(segment
		(start 65.631314 -94.303088)
		(end 65.631568 -94.35846)
		(width 0.0889)
		(layer "In2.Cu")
		(net "M_K_DQS_DN<11>")
	)
	(segment
		(start 53.517038 -132.63372)
		(end 53.671978 -132.78866)
		(width 0.14224)
		(layer "In2.Cu")
		(net "M_K_DQS_DN<11>")
	)
	(segment
		(start 52.824888 -127.742188)
		(end 53.060092 -127.977392)
		(width 0.14224)
		(layer "In2.Cu")
		(net "M_K_DQS_DN<11>")
	)
	(segment
		(start 53.622956 -133.9596)
		(end 53.881782 -134.218426)
		(width 0.14224)
		(layer "In2.Cu")
		(net "M_K_DQS_DN<11>")
	)
	(segment
		(start 67.199002 -93.799914)
		(end 66.134488 -93.799914)
		(width 0.0889)
		(layer "In2.Cu")
		(net "M_K_DQS_DN<11>")
	)
	(segment
		(start 69.76364 -93.328236)
		(end 69.388482 -93.328236)
		(width 0.0889)
		(layer "In2.Cu")
		(net "M_K_DQS_DN<11>")
	)
	(segment
		(start 52.773326 -114.56543)
		(end 52.773326 -115.467384)
		(width 0.14224)
		(layer "In2.Cu")
		(net "M_K_DQS_DN<11>")
	)
	(segment
		(start 51.961288 -113.753392)
		(end 52.773326 -114.56543)
		(width 0.14224)
		(layer "In2.Cu")
		(net "M_K_DQS_DN<11>")
	)
	(segment
		(start 53.881782 -134.63143)
		(end 53.448712 -135.0645)
		(width 0.14224)
		(layer "In2.Cu")
		(net "M_K_DQS_DN<11>")
	)
	(segment
		(start 52.824888 -116.853462)
		(end 52.824888 -127.742188)
		(width 0.14224)
		(layer "In2.Cu")
		(net "M_K_DQS_DN<11>")
	)
	(segment
		(start 53.368956 -133.9596)
		(end 53.622956 -133.9596)
		(width 0.14224)
		(layer "In2.Cu")
		(net "M_K_DQS_DN<11>")
	)
	(segment
		(start 52.773326 -115.467384)
		(end 52.33924 -115.90147)
		(width 0.14224)
		(layer "In2.Cu")
		(net "M_K_DQS_DN<11>")
	)
	(segment
		(start 57.730898 -104.666542)
		(end 51.961288 -110.436152)
		(width 0.14224)
		(layer "In2.Cu")
		(net "M_K_DQS_DN<11>")
	)
	(segment
		(start 66.134488 -93.799914)
		(end 65.631314 -94.303088)
		(width 0.0889)
		(layer "In2.Cu")
		(net "M_K_DQS_DN<11>")
	)
	(segment
		(start 53.597556 -132.0038)
		(end 53.356256 -132.0038)
		(width 0.14224)
		(layer "In2.Cu")
		(net "M_K_DQS_DN<11>")
	)
	(segment
		(start 53.283104 -127.977392)
		(end 53.462682 -128.157224)
		(width 0.14224)
		(layer "In2.Cu")
		(net "M_K_DQS_DN<11>")
	)
	(segment
		(start 57.730898 -102.25913)
		(end 57.730898 -104.666542)
		(width 0.14224)
		(layer "In2.Cu")
		(net "M_K_DQS_DN<11>")
	)
	(segment
		(start 51.961288 -110.436152)
		(end 51.961288 -113.753392)
		(width 0.14224)
		(layer "In2.Cu")
		(net "M_K_DQS_DN<11>")
	)
	(arc
		(start 71.816976 -94.518988)
		(mid 71.678232 -94.376955)
		(end 71.4883 -94.31909)
		(width 0.0889)
		(layer "In2.Cu")
		(net "M_K_DQS_DN<11>")
	)
	(arc
		(start 70.958456 -94.023688)
		(mid 70.819712 -93.881655)
		(end 70.62978 -93.82379)
		(width 0.0889)
		(layer "In2.Cu")
		(net "M_K_DQS_DN<11>")
	)
	(arc
		(start 70.590156 -93.82379)
		(mid 70.587743 -93.823794)
		(end 70.58533 -93.82379)
		(width 0.0889)
		(layer "In2.Cu")
		(net "M_K_DQS_DN<11>")
	)
	(arc
		(start 70.099936 -93.528388)
		(mid 69.957893 -93.384476)
		(end 69.76364 -93.328236)
		(width 0.0889)
		(layer "In2.Cu")
		(net "M_K_DQS_DN<11>")
	)
	(arc
		(start 72.315832 -94.81439)
		(mid 72.027687 -94.732071)
		(end 71.816976 -94.518988)
		(width 0.0889)
		(layer "In2.Cu")
		(net "M_K_DQS_DN<11>")
	)
	(arc
		(start 70.58533 -93.823536)
		(mid 70.304807 -93.738152)
		(end 70.099936 -93.528388)
		(width 0.0889)
		(layer "In2.Cu")
		(net "M_K_DQS_DN<11>")
	)
	(arc
		(start 72.700642 -95.362014)
		(mid 72.663902 -94.995875)
		(end 72.343772 -94.81439)
		(width 0.0889)
		(layer "In2.Cu")
		(net "M_K_DQS_DN<11>")
	)
	(arc
		(start 71.452486 -94.31909)
		(mid 71.167062 -94.235623)
		(end 70.958456 -94.023688)
		(width 0.0889)
		(layer "In2.Cu")
		(net "M_K_DQS_DN<11>")
	)
	(segment
		(start 44.999402 -133.0706)
		(end 44.999402 -133.729984)
		(width 0.1651)
		(layer "F.Cu")
		(net "M_K_DQS_DN<10>")
	)
	(segment
		(start 67.592702 -94.318836)
		(end 67.536568 -94.37497)
		(width 0.0889)
		(layer "F.Cu")
		(net "M_K_DQS_DN<10>")
	)
	(segment
		(start 67.942968 -94.318836)
		(end 67.592702 -94.318836)
		(width 0.0889)
		(layer "F.Cu")
		(net "M_K_DQS_DN<10>")
	)
	(segment
		(start 44.936664 -119.854472)
		(end 44.936664 -130.04165)
		(width 0.1651)
		(layer "F.Cu")
		(net "M_K_DQS_DN<10>")
	)
	(segment
		(start 44.936664 -130.04165)
		(end 44.092114 -130.8862)
		(width 0.1651)
		(layer "F.Cu")
		(net "M_K_DQS_DN<10>")
	)
	(segment
		(start 44.990766 -115.871498)
		(end 45.165772 -116.046504)
		(width 0.1651)
		(layer "F.Cu")
		(net "M_K_DQS_DN<10>")
	)
	(segment
		(start 44.117768 -135.0645)
		(end 44.098718 -135.0645)
		(width 0.1651)
		(layer "F.Cu")
		(net "M_K_DQS_DN<10>")
	)
	(segment
		(start 45.490638 -116.046504)
		(end 45.839888 -116.395754)
		(width 0.1651)
		(layer "F.Cu")
		(net "M_K_DQS_DN<10>")
	)
	(segment
		(start 68.298568 -94.318836)
		(end 68.196968 -94.420436)
		(width 0.0889)
		(layer "F.Cu")
		(net "M_K_DQS_DN<10>")
	)
	(segment
		(start 44.306998 -135.25373)
		(end 44.117768 -135.0645)
		(width 0.1651)
		(layer "F.Cu")
		(net "M_K_DQS_DN<10>")
	)
	(segment
		(start 68.196968 -94.420436)
		(end 68.044568 -94.420436)
		(width 0.0889)
		(layer "F.Cu")
		(net "M_K_DQS_DN<10>")
	)
	(segment
		(start 68.044568 -94.420436)
		(end 67.942968 -94.318836)
		(width 0.0889)
		(layer "F.Cu")
		(net "M_K_DQS_DN<10>")
	)
	(segment
		(start 45.114972 -119.676164)
		(end 44.936664 -119.854472)
		(width 0.1651)
		(layer "F.Cu")
		(net "M_K_DQS_DN<10>")
	)
	(segment
		(start 67.536568 -94.37497)
		(end 65.977262 -94.37497)
		(width 0.1651)
		(layer "F.Cu")
		(net "M_K_DQS_DN<10>")
	)
	(segment
		(start 45.839888 -116.395754)
		(end 45.839888 -119.276114)
		(width 0.1651)
		(layer "F.Cu")
		(net "M_K_DQS_DN<10>")
	)
	(segment
		(start 68.89496 -94.553278)
		(end 68.918074 -94.466664)
		(width 0.0889)
		(layer "F.Cu")
		(net "M_K_DQS_DN<10>")
	)
	(segment
		(start 44.990766 -115.361466)
		(end 44.990766 -115.871498)
		(width 0.1651)
		(layer "F.Cu")
		(net "M_K_DQS_DN<10>")
	)
	(segment
		(start 68.62572 -94.31909)
		(end 68.620132 -94.318836)
		(width 0.0889)
		(layer "F.Cu")
		(net "M_K_DQS_DN<10>")
	)
	(segment
		(start 44.767246 -135.001762)
		(end 44.515278 -135.25373)
		(width 0.1651)
		(layer "F.Cu")
		(net "M_K_DQS_DN<10>")
	)
	(segment
		(start 45.165772 -116.046504)
		(end 45.490638 -116.046504)
		(width 0.1651)
		(layer "F.Cu")
		(net "M_K_DQS_DN<10>")
	)
	(segment
		(start 44.515278 -135.25373)
		(end 44.306998 -135.25373)
		(width 0.1651)
		(layer "F.Cu")
		(net "M_K_DQS_DN<10>")
	)
	(segment
		(start 44.999402 -133.729984)
		(end 44.581318 -134.148068)
		(width 0.1651)
		(layer "F.Cu")
		(net "M_K_DQS_DN<10>")
	)
	(segment
		(start 65.977262 -94.37497)
		(end 44.990766 -115.361466)
		(width 0.1651)
		(layer "F.Cu")
		(net "M_K_DQS_DN<10>")
	)
	(segment
		(start 68.620132 -94.318836)
		(end 68.298568 -94.318836)
		(width 0.0889)
		(layer "F.Cu")
		(net "M_K_DQS_DN<10>")
	)
	(segment
		(start 44.767246 -134.755128)
		(end 44.767246 -135.001762)
		(width 0.1651)
		(layer "F.Cu")
		(net "M_K_DQS_DN<10>")
	)
	(segment
		(start 68.607686 -94.718886)
		(end 68.89496 -94.553278)
		(width 0.0889)
		(layer "F.Cu")
		(net "M_K_DQS_DN<10>")
	)
	(segment
		(start 45.439838 -119.676164)
		(end 45.114972 -119.676164)
		(width 0.1651)
		(layer "F.Cu")
		(net "M_K_DQS_DN<10>")
	)
	(segment
		(start 44.581318 -134.148068)
		(end 44.581318 -134.5692)
		(width 0.1651)
		(layer "F.Cu")
		(net "M_K_DQS_DN<10>")
	)
	(segment
		(start 44.581318 -134.5692)
		(end 44.767246 -134.755128)
		(width 0.1651)
		(layer "F.Cu")
		(net "M_K_DQS_DN<10>")
	)
	(segment
		(start 45.839888 -119.276114)
		(end 45.439838 -119.676164)
		(width 0.1651)
		(layer "F.Cu")
		(net "M_K_DQS_DN<10>")
	)
	(via
		(at 44.092114 -130.8862)
		(size 0.508)
		(drill 0.254)
		(layers "F.Cu" "B.Cu")
		(net "M_K_DQS_DN<10>")
	)
	(via
		(at 44.098718 -135.0645)
		(size 0.508)
		(drill 0.254)
		(layers "F.Cu" "B.Cu")
		(net "M_K_DQS_DN<10>")
	)
	(arc
		(start 68.673218 -94.32417)
		(mid 68.649545 -94.320917)
		(end 68.62572 -94.31909)
		(width 0.0889)
		(layer "F.Cu")
		(net "M_K_DQS_DN<10>")
	)
	(arc
		(start 68.918074 -94.466664)
		(mid 68.808675 -94.373031)
		(end 68.673218 -94.32417)
		(width 0.0889)
		(layer "F.Cu")
		(net "M_K_DQS_DN<10>")
	)
	(segment
		(start 44.733718 -130.9116)
		(end 44.513754 -130.691636)
		(width 0.1651)
		(layer "B.Cu")
		(net "M_K_DQS_DN<10>")
	)
	(segment
		(start 44.555918 -131.4196)
		(end 44.733718 -131.2418)
		(width 0.1651)
		(layer "B.Cu")
		(net "M_K_DQS_DN<10>")
	)
	(segment
		(start 44.555918 -131.775454)
		(end 44.555918 -131.4196)
		(width 0.1651)
		(layer "B.Cu")
		(net "M_K_DQS_DN<10>")
	)
	(segment
		(start 44.733718 -131.2418)
		(end 44.733718 -130.9116)
		(width 0.1651)
		(layer "B.Cu")
		(net "M_K_DQS_DN<10>")
	)
	(segment
		(start 44.999402 -132.876036)
		(end 44.999402 -132.218938)
		(width 0.1651)
		(layer "B.Cu")
		(net "M_K_DQS_DN<10>")
	)
	(segment
		(start 44.999402 -132.218938)
		(end 44.555918 -131.775454)
		(width 0.1651)
		(layer "B.Cu")
		(net "M_K_DQS_DN<10>")
	)
	(segment
		(start 44.286678 -130.691636)
		(end 44.092114 -130.8862)
		(width 0.1651)
		(layer "B.Cu")
		(net "M_K_DQS_DN<10>")
	)
	(segment
		(start 44.513754 -130.691636)
		(end 44.286678 -130.691636)
		(width 0.1651)
		(layer "B.Cu")
		(net "M_K_DQS_DN<10>")
	)
	(segment
		(start 43.856402 -132.15366)
		(end 44.006262 -132.0038)
		(width 0.14224)
		(layer "In2.Cu")
		(net "M_K_DQS_DN<10>")
	)
	(segment
		(start 44.018962 -133.9596)
		(end 43.856402 -133.79704)
		(width 0.14224)
		(layer "In2.Cu")
		(net "M_K_DQS_DN<10>")
	)
	(segment
		(start 43.856402 -133.79704)
		(end 43.856402 -133.43636)
		(width 0.14224)
		(layer "In2.Cu")
		(net "M_K_DQS_DN<10>")
	)
	(segment
		(start 43.856402 -132.50164)
		(end 43.856402 -132.15366)
		(width 0.14224)
		(layer "In2.Cu")
		(net "M_K_DQS_DN<10>")
	)
	(segment
		(start 44.344082 -133.9596)
		(end 44.018962 -133.9596)
		(width 0.14224)
		(layer "In2.Cu")
		(net "M_K_DQS_DN<10>")
	)
	(segment
		(start 43.856402 -133.43636)
		(end 43.996102 -133.29666)
		(width 0.14224)
		(layer "In2.Cu")
		(net "M_K_DQS_DN<10>")
	)
	(segment
		(start 44.526962 -131.7244)
		(end 44.526962 -131.321048)
		(width 0.14224)
		(layer "In2.Cu")
		(net "M_K_DQS_DN<10>")
	)
	(segment
		(start 43.996102 -133.29666)
		(end 44.143422 -133.29666)
		(width 0.14224)
		(layer "In2.Cu")
		(net "M_K_DQS_DN<10>")
	)
	(segment
		(start 44.298362 -132.78866)
		(end 44.143422 -132.63372)
		(width 0.14224)
		(layer "In2.Cu")
		(net "M_K_DQS_DN<10>")
	)
	(segment
		(start 44.143422 -132.63372)
		(end 43.988482 -132.63372)
		(width 0.14224)
		(layer "In2.Cu")
		(net "M_K_DQS_DN<10>")
	)
	(segment
		(start 44.531788 -134.63143)
		(end 44.531788 -134.147306)
		(width 0.14224)
		(layer "In2.Cu")
		(net "M_K_DQS_DN<10>")
	)
	(segment
		(start 44.298362 -133.14172)
		(end 44.298362 -132.78866)
		(width 0.14224)
		(layer "In2.Cu")
		(net "M_K_DQS_DN<10>")
	)
	(segment
		(start 44.098718 -135.0645)
		(end 44.531788 -134.63143)
		(width 0.14224)
		(layer "In2.Cu")
		(net "M_K_DQS_DN<10>")
	)
	(segment
		(start 44.006262 -132.0038)
		(end 44.247562 -132.0038)
		(width 0.14224)
		(layer "In2.Cu")
		(net "M_K_DQS_DN<10>")
	)
	(segment
		(start 44.531788 -134.147306)
		(end 44.344082 -133.9596)
		(width 0.14224)
		(layer "In2.Cu")
		(net "M_K_DQS_DN<10>")
	)
	(segment
		(start 44.247562 -132.0038)
		(end 44.526962 -131.7244)
		(width 0.14224)
		(layer "In2.Cu")
		(net "M_K_DQS_DN<10>")
	)
	(segment
		(start 44.526962 -131.321048)
		(end 44.092114 -130.8862)
		(width 0.14224)
		(layer "In2.Cu")
		(net "M_K_DQS_DN<10>")
	)
	(segment
		(start 44.143422 -133.29666)
		(end 44.298362 -133.14172)
		(width 0.14224)
		(layer "In2.Cu")
		(net "M_K_DQS_DN<10>")
	)
	(segment
		(start 43.988482 -132.63372)
		(end 43.856402 -132.50164)
		(width 0.14224)
		(layer "In2.Cu")
		(net "M_K_DQS_DN<10>")
	)
	(segment
		(start 69.466206 -87.28964)
		(end 68.894706 -87.28964)
		(width 0.1651)
		(layer "F.Cu")
		(net "M_K_DQS_DN<0>")
	)
	(segment
		(start 35.649408 -136.60247)
		(end 35.267392 -136.220454)
		(width 0.1651)
		(layer "F.Cu")
		(net "M_K_DQS_DN<0>")
	)
	(segment
		(start 35.821874 -135.4582)
		(end 36.03752 -135.673846)
		(width 0.1651)
		(layer "F.Cu")
		(net "M_K_DQS_DN<0>")
	)
	(segment
		(start 35.649408 -137.67054)
		(end 35.649408 -136.60247)
		(width 0.1651)
		(layer "F.Cu")
		(net "M_K_DQS_DN<0>")
	)
	(segment
		(start 35.597846 -135.4582)
		(end 35.821874 -135.4582)
		(width 0.1651)
		(layer "F.Cu")
		(net "M_K_DQS_DN<0>")
	)
	(segment
		(start 35.267392 -135.788654)
		(end 35.597846 -135.4582)
		(width 0.1651)
		(layer "F.Cu")
		(net "M_K_DQS_DN<0>")
	)
	(segment
		(start 35.267392 -136.220454)
		(end 35.267392 -135.788654)
		(width 0.1651)
		(layer "F.Cu")
		(net "M_K_DQS_DN<0>")
	)
	(via
		(at 68.894706 -87.28964)
		(size 0.508)
		(drill 0.254)
		(layers "F.Cu" "B.Cu")
		(net "M_K_DQS_DN<0>")
	)
	(via
		(at 36.03752 -135.673846)
		(size 0.508)
		(drill 0.254)
		(layers "F.Cu" "B.Cu")
		(net "M_K_DQS_DN<0>")
	)
	(via
		(at 36.03752 -130.280156)
		(size 0.508)
		(drill 0.254)
		(layers "F.Cu" "B.Cu")
		(net "M_K_DQS_DN<0>")
	)
	(segment
		(start 35.267392 -130.1496)
		(end 35.622992 -130.5052)
		(width 0.1651)
		(layer "B.Cu")
		(net "M_K_DQS_DN<0>")
	)
	(segment
		(start 35.649408 -128.276096)
		(end 35.649408 -129.18313)
		(width 0.1651)
		(layer "B.Cu")
		(net "M_K_DQS_DN<0>")
	)
	(segment
		(start 35.649408 -129.18313)
		(end 35.521392 -129.311146)
		(width 0.1651)
		(layer "B.Cu")
		(net "M_K_DQS_DN<0>")
	)
	(segment
		(start 35.521392 -129.311146)
		(end 35.521392 -129.565146)
		(width 0.1651)
		(layer "B.Cu")
		(net "M_K_DQS_DN<0>")
	)
	(segment
		(start 35.812476 -130.5052)
		(end 36.03752 -130.280156)
		(width 0.1651)
		(layer "B.Cu")
		(net "M_K_DQS_DN<0>")
	)
	(segment
		(start 35.521392 -129.565146)
		(end 35.267392 -129.819146)
		(width 0.1651)
		(layer "B.Cu")
		(net "M_K_DQS_DN<0>")
	)
	(segment
		(start 35.622992 -130.5052)
		(end 35.812476 -130.5052)
		(width 0.1651)
		(layer "B.Cu")
		(net "M_K_DQS_DN<0>")
	)
	(segment
		(start 35.267392 -129.819146)
		(end 35.267392 -130.1496)
		(width 0.1651)
		(layer "B.Cu")
		(net "M_K_DQS_DN<0>")
	)
	(segment
		(start 38.337744 -114.331496)
		(end 37.290248 -115.378992)
		(width 0.14224)
		(layer "In2.Cu")
		(net "M_K_DQS_DN<0>")
	)
	(segment
		(start 37.290248 -120.78208)
		(end 37.06876 -121.003568)
		(width 0.14224)
		(layer "In2.Cu")
		(net "M_K_DQS_DN<0>")
	)
	(segment
		(start 37.06876 -125.575568)
		(end 36.677854 -125.575568)
		(width 0.14224)
		(layer "In2.Cu")
		(net "M_K_DQS_DN<0>")
	)
	(segment
		(start 36.392612 -130.280156)
		(end 36.03752 -130.280156)
		(width 0.14224)
		(layer "In2.Cu")
		(net "M_K_DQS_DN<0>")
	)
	(segment
		(start 52.586128 -99.513644)
		(end 52.586128 -101.10724)
		(width 0.14224)
		(layer "In2.Cu")
		(net "M_K_DQS_DN<0>")
	)
	(segment
		(start 36.299648 -126.609602)
		(end 36.677854 -126.987808)
		(width 0.14224)
		(layer "In2.Cu")
		(net "M_K_DQS_DN<0>")
	)
	(segment
		(start 35.964368 -130.280156)
		(end 36.03752 -130.280156)
		(width 0.14224)
		(layer "In2.Cu")
		(net "M_K_DQS_DN<0>")
	)
	(segment
		(start 36.779454 -122.415808)
		(end 37.06876 -122.415808)
		(width 0.14224)
		(layer "In2.Cu")
		(net "M_K_DQS_DN<0>")
	)
	(segment
		(start 36.03752 -135.673846)
		(end 35.60445 -135.240776)
		(width 0.14224)
		(layer "In2.Cu")
		(net "M_K_DQS_DN<0>")
	)
	(segment
		(start 35.60445 -130.640074)
		(end 35.964368 -130.280156)
		(width 0.14224)
		(layer "In2.Cu")
		(net "M_K_DQS_DN<0>")
	)
	(segment
		(start 36.421568 -128.9304)
		(end 36.421568 -129.286)
		(width 0.14224)
		(layer "In2.Cu")
		(net "M_K_DQS_DN<0>")
	)
	(segment
		(start 65.741296 -87.372698)
		(end 65.698116 -87.329518)
		(width 0.0889)
		(layer "In2.Cu")
		(net "M_K_DQS_DN<0>")
	)
	(segment
		(start 37.06876 -122.415808)
		(end 37.290248 -122.637296)
		(width 0.14224)
		(layer "In2.Cu")
		(net "M_K_DQS_DN<0>")
	)
	(segment
		(start 35.39363 -133.77418)
		(end 35.39363 -132.11302)
		(width 0.14224)
		(layer "In2.Cu")
		(net "M_K_DQS_DN<0>")
	)
	(segment
		(start 39.361872 -114.331496)
		(end 38.337744 -114.331496)
		(width 0.14224)
		(layer "In2.Cu")
		(net "M_K_DQS_DN<0>")
	)
	(segment
		(start 37.290248 -123.06808)
		(end 37.06876 -123.289568)
		(width 0.14224)
		(layer "In2.Cu")
		(net "M_K_DQS_DN<0>")
	)
	(segment
		(start 37.290248 -122.637296)
		(end 37.290248 -123.06808)
		(width 0.14224)
		(layer "In2.Cu")
		(net "M_K_DQS_DN<0>")
	)
	(segment
		(start 35.60445 -133.985)
		(end 35.39363 -133.77418)
		(width 0.14224)
		(layer "In2.Cu")
		(net "M_K_DQS_DN<0>")
	)
	(segment
		(start 36.779454 -121.003568)
		(end 36.401248 -121.381774)
		(width 0.14224)
		(layer "In2.Cu")
		(net "M_K_DQS_DN<0>")
	)
	(segment
		(start 36.677854 -125.575568)
		(end 36.299648 -125.953774)
		(width 0.14224)
		(layer "In2.Cu")
		(net "M_K_DQS_DN<0>")
	)
	(segment
		(start 37.290248 -127.302768)
		(end 37.290248 -127.698246)
		(width 0.14224)
		(layer "In2.Cu")
		(net "M_K_DQS_DN<0>")
	)
	(segment
		(start 37.290248 -127.698246)
		(end 36.553648 -128.434846)
		(width 0.14224)
		(layer "In2.Cu")
		(net "M_K_DQS_DN<0>")
	)
	(segment
		(start 36.350448 -123.667774)
		(end 36.350448 -124.323602)
		(width 0.14224)
		(layer "In2.Cu")
		(net "M_K_DQS_DN<0>")
	)
	(segment
		(start 66.910458 -87.68969)
		(end 66.593466 -87.372698)
		(width 0.0889)
		(layer "In2.Cu")
		(net "M_K_DQS_DN<0>")
	)
	(segment
		(start 36.553648 -128.434846)
		(end 36.553648 -128.79832)
		(width 0.14224)
		(layer "In2.Cu")
		(net "M_K_DQS_DN<0>")
	)
	(segment
		(start 36.401248 -122.037602)
		(end 36.779454 -122.415808)
		(width 0.14224)
		(layer "In2.Cu")
		(net "M_K_DQS_DN<0>")
	)
	(segment
		(start 36.677854 -126.987808)
		(end 36.975288 -126.987808)
		(width 0.14224)
		(layer "In2.Cu")
		(net "M_K_DQS_DN<0>")
	)
	(segment
		(start 37.06876 -121.003568)
		(end 36.779454 -121.003568)
		(width 0.14224)
		(layer "In2.Cu")
		(net "M_K_DQS_DN<0>")
	)
	(segment
		(start 37.290248 -115.378992)
		(end 37.290248 -120.78208)
		(width 0.14224)
		(layer "In2.Cu")
		(net "M_K_DQS_DN<0>")
	)
	(segment
		(start 36.728654 -124.701808)
		(end 37.06876 -124.701808)
		(width 0.14224)
		(layer "In2.Cu")
		(net "M_K_DQS_DN<0>")
	)
	(segment
		(start 36.401248 -121.381774)
		(end 36.401248 -122.037602)
		(width 0.14224)
		(layer "In2.Cu")
		(net "M_K_DQS_DN<0>")
	)
	(segment
		(start 36.553648 -128.79832)
		(end 36.421568 -128.9304)
		(width 0.14224)
		(layer "In2.Cu")
		(net "M_K_DQS_DN<0>")
	)
	(segment
		(start 64.770254 -87.329518)
		(end 52.586128 -99.513644)
		(width 0.14224)
		(layer "In2.Cu")
		(net "M_K_DQS_DN<0>")
	)
	(segment
		(start 52.586128 -101.10724)
		(end 39.361872 -114.331496)
		(width 0.14224)
		(layer "In2.Cu")
		(net "M_K_DQS_DN<0>")
	)
	(segment
		(start 37.290248 -124.923296)
		(end 37.290248 -125.35408)
		(width 0.14224)
		(layer "In2.Cu")
		(net "M_K_DQS_DN<0>")
	)
	(segment
		(start 36.553648 -129.41808)
		(end 36.553648 -130.11912)
		(width 0.14224)
		(layer "In2.Cu")
		(net "M_K_DQS_DN<0>")
	)
	(segment
		(start 36.421568 -129.286)
		(end 36.553648 -129.41808)
		(width 0.14224)
		(layer "In2.Cu")
		(net "M_K_DQS_DN<0>")
	)
	(segment
		(start 36.975288 -126.987808)
		(end 37.290248 -127.302768)
		(width 0.14224)
		(layer "In2.Cu")
		(net "M_K_DQS_DN<0>")
	)
	(segment
		(start 37.290248 -125.35408)
		(end 37.06876 -125.575568)
		(width 0.14224)
		(layer "In2.Cu")
		(net "M_K_DQS_DN<0>")
	)
	(segment
		(start 68.053966 -87.194136)
		(end 67.833494 -87.194136)
		(width 0.0889)
		(layer "In2.Cu")
		(net "M_K_DQS_DN<0>")
	)
	(segment
		(start 35.60445 -131.9022)
		(end 35.60445 -130.640074)
		(width 0.14224)
		(layer "In2.Cu")
		(net "M_K_DQS_DN<0>")
	)
	(segment
		(start 35.39363 -132.11302)
		(end 35.60445 -131.9022)
		(width 0.14224)
		(layer "In2.Cu")
		(net "M_K_DQS_DN<0>")
	)
	(segment
		(start 66.593466 -87.372698)
		(end 65.741296 -87.372698)
		(width 0.0889)
		(layer "In2.Cu")
		(net "M_K_DQS_DN<0>")
	)
	(segment
		(start 36.553648 -130.11912)
		(end 36.392612 -130.280156)
		(width 0.14224)
		(layer "In2.Cu")
		(net "M_K_DQS_DN<0>")
	)
	(segment
		(start 36.728654 -123.289568)
		(end 36.350448 -123.667774)
		(width 0.14224)
		(layer "In2.Cu")
		(net "M_K_DQS_DN<0>")
	)
	(segment
		(start 68.894706 -87.28964)
		(end 68.417694 -87.28964)
		(width 0.0889)
		(layer "In2.Cu")
		(net "M_K_DQS_DN<0>")
	)
	(segment
		(start 65.698116 -87.329518)
		(end 64.770254 -87.329518)
		(width 0.14224)
		(layer "In2.Cu")
		(net "M_K_DQS_DN<0>")
	)
	(segment
		(start 67.267836 -87.68969)
		(end 66.910458 -87.68969)
		(width 0.0889)
		(layer "In2.Cu")
		(net "M_K_DQS_DN<0>")
	)
	(segment
		(start 37.06876 -124.701808)
		(end 37.290248 -124.923296)
		(width 0.14224)
		(layer "In2.Cu")
		(net "M_K_DQS_DN<0>")
	)
	(segment
		(start 37.06876 -123.289568)
		(end 36.728654 -123.289568)
		(width 0.14224)
		(layer "In2.Cu")
		(net "M_K_DQS_DN<0>")
	)
	(segment
		(start 36.350448 -124.323602)
		(end 36.728654 -124.701808)
		(width 0.14224)
		(layer "In2.Cu")
		(net "M_K_DQS_DN<0>")
	)
	(segment
		(start 35.60445 -135.240776)
		(end 35.60445 -133.985)
		(width 0.14224)
		(layer "In2.Cu")
		(net "M_K_DQS_DN<0>")
	)
	(segment
		(start 36.299648 -125.953774)
		(end 36.299648 -126.609602)
		(width 0.14224)
		(layer "In2.Cu")
		(net "M_K_DQS_DN<0>")
	)
	(arc
		(start 67.833494 -87.194136)
		(mid 67.630596 -87.309996)
		(end 67.484498 -87.492332)
		(width 0.0889)
		(layer "In2.Cu")
		(net "M_K_DQS_DN<0>")
	)
	(arc
		(start 68.417694 -87.28964)
		(mid 68.365052 -87.283132)
		(end 68.315586 -87.263986)
		(width 0.0889)
		(layer "In2.Cu")
		(net "M_K_DQS_DN<0>")
	)
	(arc
		(start 67.484498 -87.492332)
		(mid 67.393384 -87.609924)
		(end 67.267836 -87.68969)
		(width 0.0889)
		(layer "In2.Cu")
		(net "M_K_DQS_DN<0>")
	)
	(arc
		(start 68.315586 -87.263986)
		(mid 68.188831 -87.213873)
		(end 68.053966 -87.194136)
		(width 0.0889)
		(layer "In2.Cu")
		(net "M_K_DQS_DN<0>")
	)
	(segment
		(start 42.449496 -133.0706)
		(end 42.449496 -134.340346)
		(width 0.1651)
		(layer "F.Cu")
		(net "M_K_DQ<9>")
	)
	(segment
		(start 43.964606 -127.559816)
		(end 43.254168 -128.270254)
		(width 0.1651)
		(layer "F.Cu")
		(net "M_K_DQ<9>")
	)
	(segment
		(start 44.562268 -117.489986)
		(end 44.155106 -117.489986)
		(width 0.1651)
		(layer "F.Cu")
		(net "M_K_DQ<9>")
	)
	(segment
		(start 43.990006 -117.997986)
		(end 44.155106 -118.163086)
		(width 0.1651)
		(layer "F.Cu")
		(net "M_K_DQ<9>")
	)
	(segment
		(start 44.562268 -118.836186)
		(end 44.155106 -118.836186)
		(width 0.1651)
		(layer "F.Cu")
		(net "M_K_DQ<9>")
	)
	(segment
		(start 43.628564 -130.156204)
		(end 43.453812 -130.330956)
		(width 0.1651)
		(layer "F.Cu")
		(net "M_K_DQ<9>")
	)
	(segment
		(start 65.88633 -93.091)
		(end 43.964606 -115.012724)
		(width 0.1651)
		(layer "F.Cu")
		(net "M_K_DQ<9>")
	)
	(segment
		(start 43.254168 -128.270254)
		(end 43.254168 -128.5494)
		(width 0.1651)
		(layer "F.Cu")
		(net "M_K_DQ<9>")
	)
	(segment
		(start 44.155106 -116.816886)
		(end 44.562268 -116.816886)
		(width 0.1651)
		(layer "F.Cu")
		(net "M_K_DQ<9>")
	)
	(segment
		(start 44.155106 -117.489986)
		(end 43.990006 -117.655086)
		(width 0.1651)
		(layer "F.Cu")
		(net "M_K_DQ<9>")
	)
	(segment
		(start 44.155106 -118.163086)
		(end 44.562268 -118.163086)
		(width 0.1651)
		(layer "F.Cu")
		(net "M_K_DQ<9>")
	)
	(segment
		(start 44.727368 -116.981986)
		(end 44.727368 -117.324886)
		(width 0.1651)
		(layer "F.Cu")
		(net "M_K_DQ<9>")
	)
	(segment
		(start 44.727368 -118.328186)
		(end 44.727368 -118.671086)
		(width 0.1651)
		(layer "F.Cu")
		(net "M_K_DQ<9>")
	)
	(segment
		(start 43.628564 -128.923796)
		(end 43.628564 -130.156204)
		(width 0.1651)
		(layer "F.Cu")
		(net "M_K_DQ<9>")
	)
	(segment
		(start 68.607686 -92.737686)
		(end 68.254372 -93.091)
		(width 0.0889)
		(layer "F.Cu")
		(net "M_K_DQ<9>")
	)
	(segment
		(start 43.964606 -116.626386)
		(end 44.155106 -116.816886)
		(width 0.1651)
		(layer "F.Cu")
		(net "M_K_DQ<9>")
	)
	(segment
		(start 43.254168 -128.5494)
		(end 43.628564 -128.923796)
		(width 0.1651)
		(layer "F.Cu")
		(net "M_K_DQ<9>")
	)
	(segment
		(start 44.562268 -118.163086)
		(end 44.727368 -118.328186)
		(width 0.1651)
		(layer "F.Cu")
		(net "M_K_DQ<9>")
	)
	(segment
		(start 68.254372 -93.091)
		(end 67.4878 -93.091)
		(width 0.0889)
		(layer "F.Cu")
		(net "M_K_DQ<9>")
	)
	(segment
		(start 43.453812 -130.330956)
		(end 43.12158 -130.330956)
		(width 0.1651)
		(layer "F.Cu")
		(net "M_K_DQ<9>")
	)
	(segment
		(start 43.990006 -117.655086)
		(end 43.990006 -117.997986)
		(width 0.1651)
		(layer "F.Cu")
		(net "M_K_DQ<9>")
	)
	(segment
		(start 44.727368 -117.324886)
		(end 44.562268 -117.489986)
		(width 0.1651)
		(layer "F.Cu")
		(net "M_K_DQ<9>")
	)
	(segment
		(start 44.562268 -116.816886)
		(end 44.727368 -116.981986)
		(width 0.1651)
		(layer "F.Cu")
		(net "M_K_DQ<9>")
	)
	(segment
		(start 44.155106 -118.836186)
		(end 43.964606 -119.026686)
		(width 0.1651)
		(layer "F.Cu")
		(net "M_K_DQ<9>")
	)
	(segment
		(start 43.964606 -119.026686)
		(end 43.964606 -127.559816)
		(width 0.1651)
		(layer "F.Cu")
		(net "M_K_DQ<9>")
	)
	(segment
		(start 67.4878 -93.091)
		(end 65.88633 -93.091)
		(width 0.1651)
		(layer "F.Cu")
		(net "M_K_DQ<9>")
	)
	(segment
		(start 44.727368 -118.671086)
		(end 44.562268 -118.836186)
		(width 0.1651)
		(layer "F.Cu")
		(net "M_K_DQ<9>")
	)
	(segment
		(start 43.964606 -115.012724)
		(end 43.964606 -116.626386)
		(width 0.1651)
		(layer "F.Cu")
		(net "M_K_DQ<9>")
	)
	(via
		(at 43.12158 -130.330956)
		(size 0.508)
		(drill 0.254)
		(layers "F.Cu" "B.Cu")
		(net "M_K_DQ<9>")
	)
	(via
		(at 42.449496 -134.340346)
		(size 0.508)
		(drill 0.254)
		(layers "F.Cu" "B.Cu")
		(net "M_K_DQ<9>")
	)
	(segment
		(start 43.29938 -129.649982)
		(end 43.12158 -129.827782)
		(width 0.1651)
		(layer "B.Cu")
		(net "M_K_DQ<9>")
	)
	(segment
		(start 43.12158 -129.827782)
		(end 43.12158 -130.330956)
		(width 0.1651)
		(layer "B.Cu")
		(net "M_K_DQ<9>")
	)
	(segment
		(start 43.29938 -128.276096)
		(end 43.29938 -129.649982)
		(width 0.1651)
		(layer "B.Cu")
		(net "M_K_DQ<9>")
	)
	(segment
		(start 42.610786 -133.643624)
		(end 42.850562 -133.8834)
		(width 0.14224)
		(layer "In2.Cu")
		(net "M_K_DQ<9>")
	)
	(segment
		(start 42.850562 -133.8834)
		(end 42.850562 -134.1882)
		(width 0.14224)
		(layer "In2.Cu")
		(net "M_K_DQ<9>")
	)
	(segment
		(start 42.670984 -131.188968)
		(end 42.901362 -131.419346)
		(width 0.14224)
		(layer "In2.Cu")
		(net "M_K_DQ<9>")
	)
	(segment
		(start 42.610786 -132.114544)
		(end 42.610786 -132.475224)
		(width 0.14224)
		(layer "In2.Cu")
		(net "M_K_DQ<9>")
	)
	(segment
		(start 42.825162 -132.6896)
		(end 42.825162 -133.1214)
		(width 0.14224)
		(layer "In2.Cu")
		(net "M_K_DQ<9>")
	)
	(segment
		(start 43.12158 -130.330956)
		(end 42.844212 -130.330956)
		(width 0.14224)
		(layer "In2.Cu")
		(net "M_K_DQ<9>")
	)
	(segment
		(start 42.610786 -132.475224)
		(end 42.825162 -132.6896)
		(width 0.14224)
		(layer "In2.Cu")
		(net "M_K_DQ<9>")
	)
	(segment
		(start 42.901362 -131.419346)
		(end 42.901362 -131.823968)
		(width 0.14224)
		(layer "In2.Cu")
		(net "M_K_DQ<9>")
	)
	(segment
		(start 42.610786 -133.335776)
		(end 42.610786 -133.643624)
		(width 0.14224)
		(layer "In2.Cu")
		(net "M_K_DQ<9>")
	)
	(segment
		(start 42.850562 -134.1882)
		(end 42.698416 -134.340346)
		(width 0.14224)
		(layer "In2.Cu")
		(net "M_K_DQ<9>")
	)
	(segment
		(start 42.844212 -130.330956)
		(end 42.670984 -130.504184)
		(width 0.14224)
		(layer "In2.Cu")
		(net "M_K_DQ<9>")
	)
	(segment
		(start 42.698416 -134.340346)
		(end 42.449496 -134.340346)
		(width 0.14224)
		(layer "In2.Cu")
		(net "M_K_DQ<9>")
	)
	(segment
		(start 42.670984 -130.504184)
		(end 42.670984 -131.188968)
		(width 0.14224)
		(layer "In2.Cu")
		(net "M_K_DQ<9>")
	)
	(segment
		(start 42.901362 -131.823968)
		(end 42.610786 -132.114544)
		(width 0.14224)
		(layer "In2.Cu")
		(net "M_K_DQ<9>")
	)
	(segment
		(start 42.825162 -133.1214)
		(end 42.610786 -133.335776)
		(width 0.14224)
		(layer "In2.Cu")
		(net "M_K_DQ<9>")
	)
	(segment
		(start 42.542968 -128.8542)
		(end 42.937684 -129.248916)
		(width 0.1651)
		(layer "F.Cu")
		(net "M_K_DQ<8>")
	)
	(segment
		(start 42.937684 -129.248916)
		(end 42.937684 -129.710688)
		(width 0.1651)
		(layer "F.Cu")
		(net "M_K_DQ<8>")
	)
	(segment
		(start 42.937684 -129.710688)
		(end 42.449496 -130.198876)
		(width 0.1651)
		(layer "F.Cu")
		(net "M_K_DQ<8>")
	)
	(segment
		(start 69.466206 -92.24264)
		(end 67.46367 -92.24264)
		(width 0.0889)
		(layer "F.Cu")
		(net "M_K_DQ<8>")
	)
	(segment
		(start 65.780158 -92.24264)
		(end 43.279568 -114.74323)
		(width 0.1651)
		(layer "F.Cu")
		(net "M_K_DQ<8>")
	)
	(segment
		(start 67.46367 -92.24264)
		(end 65.780158 -92.24264)
		(width 0.1651)
		(layer "F.Cu")
		(net "M_K_DQ<8>")
	)
	(segment
		(start 42.542968 -127.889)
		(end 42.542968 -128.8542)
		(width 0.1651)
		(layer "F.Cu")
		(net "M_K_DQ<8>")
	)
	(segment
		(start 42.449496 -130.198876)
		(end 42.449496 -131.611878)
		(width 0.1651)
		(layer "F.Cu")
		(net "M_K_DQ<8>")
	)
	(segment
		(start 43.279568 -127.1524)
		(end 42.542968 -127.889)
		(width 0.1651)
		(layer "F.Cu")
		(net "M_K_DQ<8>")
	)
	(segment
		(start 43.29938 -137.67054)
		(end 43.29938 -137.676382)
		(width 0.1651)
		(layer "F.Cu")
		(net "M_K_DQ<8>")
	)
	(segment
		(start 43.29938 -137.676382)
		(end 43.12158 -135.8138)
		(width 0.1651)
		(layer "F.Cu")
		(net "M_K_DQ<8>")
	)
	(segment
		(start 43.279568 -114.74323)
		(end 43.279568 -127.1524)
		(width 0.1651)
		(layer "F.Cu")
		(net "M_K_DQ<8>")
	)
	(via
		(at 43.12158 -135.8138)
		(size 0.508)
		(drill 0.254)
		(layers "F.Cu" "B.Cu")
		(net "M_K_DQ<8>")
	)
	(via
		(at 42.449496 -131.611878)
		(size 0.508)
		(drill 0.254)
		(layers "F.Cu" "B.Cu")
		(net "M_K_DQ<8>")
	)
	(segment
		(start 42.449496 -132.876036)
		(end 42.449496 -131.611878)
		(width 0.1651)
		(layer "B.Cu")
		(net "M_K_DQ<8>")
	)
	(segment
		(start 42.016426 -135.00481)
		(end 42.016426 -132.044948)
		(width 0.14224)
		(layer "In2.Cu")
		(net "M_K_DQ<8>")
	)
	(segment
		(start 42.016426 -132.044948)
		(end 42.449496 -131.611878)
		(width 0.14224)
		(layer "In2.Cu")
		(net "M_K_DQ<8>")
	)
	(segment
		(start 43.12158 -135.8138)
		(end 42.825416 -135.8138)
		(width 0.14224)
		(layer "In2.Cu")
		(net "M_K_DQ<8>")
	)
	(segment
		(start 42.825416 -135.8138)
		(end 42.016426 -135.00481)
		(width 0.14224)
		(layer "In2.Cu")
		(net "M_K_DQ<8>")
	)
	(segment
		(start 69.466206 -88.28024)
		(end 68.894706 -88.28024)
		(width 0.1651)
		(layer "F.Cu")
		(net "M_K_DQ<7>")
	)
	(segment
		(start 37.34943 -133.0706)
		(end 37.34943 -134.340346)
		(width 0.1651)
		(layer "F.Cu")
		(net "M_K_DQ<7>")
	)
	(via
		(at 38.199314 -130.330956)
		(size 0.508)
		(drill 0.254)
		(layers "F.Cu" "B.Cu")
		(net "M_K_DQ<7>")
	)
	(via
		(at 37.34943 -134.340346)
		(size 0.508)
		(drill 0.254)
		(layers "F.Cu" "B.Cu")
		(net "M_K_DQ<7>")
	)
	(via
		(at 68.894706 -88.28024)
		(size 0.508)
		(drill 0.254)
		(layers "F.Cu" "B.Cu")
		(net "M_K_DQ<7>")
	)
	(segment
		(start 38.199568 -128.276096)
		(end 38.199314 -128.276096)
		(width 0.1651)
		(layer "B.Cu")
		(net "M_K_DQ<7>")
	)
	(segment
		(start 38.199314 -128.276096)
		(end 38.199314 -130.330956)
		(width 0.1651)
		(layer "B.Cu")
		(net "M_K_DQ<7>")
	)
	(segment
		(start 38.199314 -130.330956)
		(end 38.176962 -130.330956)
		(width 0.14224)
		(layer "In2.Cu")
		(net "M_K_DQ<7>")
	)
	(segment
		(start 37.793168 -131.9022)
		(end 37.51072 -132.184648)
		(width 0.14224)
		(layer "In2.Cu")
		(net "M_K_DQ<7>")
	)
	(segment
		(start 67.313302 -88.802464)
		(end 65.870836 -88.802464)
		(width 0.0889)
		(layer "In2.Cu")
		(net "M_K_DQ<7>")
	)
	(segment
		(start 38.936168 -128.8796)
		(end 38.55212 -129.263648)
		(width 0.14224)
		(layer "In2.Cu")
		(net "M_K_DQ<7>")
	)
	(segment
		(start 40.333168 -123.7234)
		(end 39.926768 -123.7234)
		(width 0.14224)
		(layer "In2.Cu")
		(net "M_K_DQ<7>")
	)
	(segment
		(start 37.793168 -131.233418)
		(end 37.793168 -131.9022)
		(width 0.14224)
		(layer "In2.Cu")
		(net "M_K_DQ<7>")
	)
	(segment
		(start 38.55212 -129.263648)
		(end 38.55212 -129.989072)
		(width 0.14224)
		(layer "In2.Cu")
		(net "M_K_DQ<7>")
	)
	(segment
		(start 37.767768 -132.715)
		(end 37.767768 -133.0198)
		(width 0.14224)
		(layer "In2.Cu")
		(net "M_K_DQ<7>")
	)
	(segment
		(start 39.139368 -119.650002)
		(end 38.936168 -119.853202)
		(width 0.14224)
		(layer "In2.Cu")
		(net "M_K_DQ<7>")
	)
	(segment
		(start 39.748968 -123.5456)
		(end 39.748968 -119.853202)
		(width 0.14224)
		(layer "In2.Cu")
		(net "M_K_DQ<7>")
	)
	(segment
		(start 40.561768 -123.4948)
		(end 40.333168 -123.7234)
		(width 0.14224)
		(layer "In2.Cu")
		(net "M_K_DQ<7>")
	)
	(segment
		(start 38.936168 -119.853202)
		(end 38.936168 -128.8796)
		(width 0.14224)
		(layer "In2.Cu")
		(net "M_K_DQ<7>")
	)
	(segment
		(start 37.767768 -133.0198)
		(end 37.51072 -133.276848)
		(width 0.14224)
		(layer "In2.Cu")
		(net "M_K_DQ<7>")
	)
	(segment
		(start 38.55212 -129.989072)
		(end 38.541198 -129.989072)
		(width 0.14224)
		(layer "In2.Cu")
		(net "M_K_DQ<7>")
	)
	(segment
		(start 39.545768 -119.650002)
		(end 39.139368 -119.650002)
		(width 0.14224)
		(layer "In2.Cu")
		(net "M_K_DQ<7>")
	)
	(segment
		(start 37.621718 -134.340346)
		(end 37.34943 -134.340346)
		(width 0.14224)
		(layer "In2.Cu")
		(net "M_K_DQ<7>")
	)
	(segment
		(start 37.799518 -134.162546)
		(end 37.621718 -134.340346)
		(width 0.14224)
		(layer "In2.Cu")
		(net "M_K_DQ<7>")
	)
	(segment
		(start 65.870836 -88.802464)
		(end 65.032636 -88.802464)
		(width 0.14224)
		(layer "In2.Cu")
		(net "M_K_DQ<7>")
	)
	(segment
		(start 37.51072 -132.457952)
		(end 37.767768 -132.715)
		(width 0.14224)
		(layer "In2.Cu")
		(net "M_K_DQ<7>")
	)
	(segment
		(start 67.835526 -88.28024)
		(end 67.313302 -88.802464)
		(width 0.0889)
		(layer "In2.Cu")
		(net "M_K_DQ<7>")
	)
	(segment
		(start 37.799518 -133.83895)
		(end 37.799518 -134.162546)
		(width 0.14224)
		(layer "In2.Cu")
		(net "M_K_DQ<7>")
	)
	(segment
		(start 68.894706 -88.28024)
		(end 67.835526 -88.28024)
		(width 0.0889)
		(layer "In2.Cu")
		(net "M_K_DQ<7>")
	)
	(segment
		(start 39.748968 -119.853202)
		(end 39.545768 -119.650002)
		(width 0.14224)
		(layer "In2.Cu")
		(net "M_K_DQ<7>")
	)
	(segment
		(start 37.51072 -133.276848)
		(end 37.51072 -133.550152)
		(width 0.14224)
		(layer "In2.Cu")
		(net "M_K_DQ<7>")
	)
	(segment
		(start 53.820568 -101.6254)
		(end 40.561768 -114.8842)
		(width 0.14224)
		(layer "In2.Cu")
		(net "M_K_DQ<7>")
	)
	(segment
		(start 38.176962 -130.330956)
		(end 37.748718 -130.7592)
		(width 0.14224)
		(layer "In2.Cu")
		(net "M_K_DQ<7>")
	)
	(segment
		(start 39.926768 -123.7234)
		(end 39.748968 -123.5456)
		(width 0.14224)
		(layer "In2.Cu")
		(net "M_K_DQ<7>")
	)
	(segment
		(start 37.748718 -131.188968)
		(end 37.793168 -131.233418)
		(width 0.14224)
		(layer "In2.Cu")
		(net "M_K_DQ<7>")
	)
	(segment
		(start 37.51072 -133.550152)
		(end 37.799518 -133.83895)
		(width 0.14224)
		(layer "In2.Cu")
		(net "M_K_DQ<7>")
	)
	(segment
		(start 53.820568 -100.014532)
		(end 53.820568 -101.6254)
		(width 0.14224)
		(layer "In2.Cu")
		(net "M_K_DQ<7>")
	)
	(segment
		(start 40.561768 -114.8842)
		(end 40.561768 -123.4948)
		(width 0.14224)
		(layer "In2.Cu")
		(net "M_K_DQ<7>")
	)
	(segment
		(start 65.032636 -88.802464)
		(end 53.820568 -100.014532)
		(width 0.14224)
		(layer "In2.Cu")
		(net "M_K_DQ<7>")
	)
	(segment
		(start 37.51072 -132.184648)
		(end 37.51072 -132.457952)
		(width 0.14224)
		(layer "In2.Cu")
		(net "M_K_DQ<7>")
	)
	(segment
		(start 38.541198 -129.989072)
		(end 38.199314 -130.330956)
		(width 0.14224)
		(layer "In2.Cu")
		(net "M_K_DQ<7>")
	)
	(segment
		(start 37.748718 -130.7592)
		(end 37.748718 -131.188968)
		(width 0.14224)
		(layer "In2.Cu")
		(net "M_K_DQ<7>")
	)
	(segment
		(start 38.199568 -136.7028)
		(end 38.331648 -136.57072)
		(width 0.1651)
		(layer "F.Cu")
		(net "M_K_DQ<6>")
	)
	(segment
		(start 38.331648 -136.57072)
		(end 38.331648 -136.35228)
		(width 0.1651)
		(layer "F.Cu")
		(net "M_K_DQ<6>")
	)
	(segment
		(start 67.749166 -88.28024)
		(end 67.101466 -88.28024)
		(width 0.1651)
		(layer "F.Cu")
		(net "M_K_DQ<6>")
	)
	(segment
		(start 38.199568 -135.915654)
		(end 38.199314 -135.9154)
		(width 0.1651)
		(layer "F.Cu")
		(net "M_K_DQ<6>")
	)
	(segment
		(start 38.199568 -136.2202)
		(end 38.199568 -135.915654)
		(width 0.1651)
		(layer "F.Cu")
		(net "M_K_DQ<6>")
	)
	(segment
		(start 38.199568 -137.67054)
		(end 38.199568 -136.7028)
		(width 0.1651)
		(layer "F.Cu")
		(net "M_K_DQ<6>")
	)
	(segment
		(start 38.331648 -136.35228)
		(end 38.199568 -136.2202)
		(width 0.1651)
		(layer "F.Cu")
		(net "M_K_DQ<6>")
	)
	(via
		(at 38.199314 -135.9154)
		(size 0.508)
		(drill 0.254)
		(layers "F.Cu" "B.Cu")
		(net "M_K_DQ<6>")
	)
	(via
		(at 67.101466 -88.28024)
		(size 0.508)
		(drill 0.254)
		(layers "F.Cu" "B.Cu")
		(net "M_K_DQ<6>")
	)
	(via
		(at 37.34943 -131.611878)
		(size 0.508)
		(drill 0.254)
		(layers "F.Cu" "B.Cu")
		(net "M_K_DQ<6>")
	)
	(segment
		(start 37.34943 -132.876036)
		(end 37.34943 -131.611878)
		(width 0.1651)
		(layer "B.Cu")
		(net "M_K_DQ<6>")
	)
	(segment
		(start 67.101466 -88.28024)
		(end 65.870836 -88.28024)
		(width 0.0889)
		(layer "In2.Cu")
		(net "M_K_DQ<6>")
	)
	(segment
		(start 38.917372 -115.545616)
		(end 38.510972 -115.545616)
		(width 0.14224)
		(layer "In2.Cu")
		(net "M_K_DQ<6>")
	)
	(segment
		(start 39.317168 -119.09298)
		(end 39.113968 -118.88978)
		(width 0.14224)
		(layer "In2.Cu")
		(net "M_K_DQ<6>")
	)
	(segment
		(start 37.18052 -130.468878)
		(end 37.18052 -131.442968)
		(width 0.14224)
		(layer "In2.Cu")
		(net "M_K_DQ<6>")
	)
	(segment
		(start 39.926768 -118.88978)
		(end 39.723568 -119.09298)
		(width 0.14224)
		(layer "In2.Cu")
		(net "M_K_DQ<6>")
	)
	(segment
		(start 64.877696 -88.28024)
		(end 53.337968 -99.819968)
		(width 0.14224)
		(layer "In2.Cu")
		(net "M_K_DQ<6>")
	)
	(segment
		(start 65.870836 -88.28024)
		(end 64.877696 -88.28024)
		(width 0.14224)
		(layer "In2.Cu")
		(net "M_K_DQ<6>")
	)
	(segment
		(start 39.113968 -115.742212)
		(end 38.917372 -115.545616)
		(width 0.14224)
		(layer "In2.Cu")
		(net "M_K_DQ<6>")
	)
	(segment
		(start 39.926768 -114.8334)
		(end 39.926768 -118.88978)
		(width 0.14224)
		(layer "In2.Cu")
		(net "M_K_DQ<6>")
	)
	(segment
		(start 38.301168 -128.6002)
		(end 37.91712 -128.984248)
		(width 0.14224)
		(layer "In2.Cu")
		(net "M_K_DQ<6>")
	)
	(segment
		(start 53.337968 -101.4222)
		(end 39.926768 -114.8334)
		(width 0.14224)
		(layer "In2.Cu")
		(net "M_K_DQ<6>")
	)
	(segment
		(start 37.91712 -129.732278)
		(end 37.18052 -130.468878)
		(width 0.14224)
		(layer "In2.Cu")
		(net "M_K_DQ<6>")
	)
	(segment
		(start 37.34943 -131.611878)
		(end 36.91636 -132.044948)
		(width 0.14224)
		(layer "In2.Cu")
		(net "M_K_DQ<6>")
	)
	(segment
		(start 36.91636 -132.044948)
		(end 36.91636 -134.632446)
		(width 0.14224)
		(layer "In2.Cu")
		(net "M_K_DQ<6>")
	)
	(segment
		(start 39.113968 -118.88978)
		(end 39.113968 -115.742212)
		(width 0.14224)
		(layer "In2.Cu")
		(net "M_K_DQ<6>")
	)
	(segment
		(start 38.301168 -115.75542)
		(end 38.301168 -128.6002)
		(width 0.14224)
		(layer "In2.Cu")
		(net "M_K_DQ<6>")
	)
	(segment
		(start 37.91712 -128.984248)
		(end 37.91712 -129.732278)
		(width 0.14224)
		(layer "In2.Cu")
		(net "M_K_DQ<6>")
	)
	(segment
		(start 37.18052 -131.442968)
		(end 37.34943 -131.611878)
		(width 0.14224)
		(layer "In2.Cu")
		(net "M_K_DQ<6>")
	)
	(segment
		(start 38.510972 -115.545616)
		(end 38.301168 -115.75542)
		(width 0.14224)
		(layer "In2.Cu")
		(net "M_K_DQ<6>")
	)
	(segment
		(start 39.723568 -119.09298)
		(end 39.317168 -119.09298)
		(width 0.14224)
		(layer "In2.Cu")
		(net "M_K_DQ<6>")
	)
	(segment
		(start 36.91636 -134.632446)
		(end 38.199314 -135.9154)
		(width 0.14224)
		(layer "In2.Cu")
		(net "M_K_DQ<6>")
	)
	(segment
		(start 53.337968 -99.819968)
		(end 53.337968 -101.4222)
		(width 0.14224)
		(layer "In2.Cu")
		(net "M_K_DQ<6>")
	)
	(segment
		(start 148.699474 -133.0706)
		(end 148.699474 -134.340346)
		(width 0.1651)
		(layer "F.Cu")
		(net "M_K_DQ<63>")
	)
	(segment
		(start 124.221748 -99.986338)
		(end 124.793248 -99.986338)
		(width 0.1651)
		(layer "F.Cu")
		(net "M_K_DQ<63>")
	)
	(via
		(at 124.793248 -99.986338)
		(size 0.4826)
		(drill 0.254)
		(layers "F.Cu" "B.Cu")
		(net "M_K_DQ<63>")
	)
	(via
		(at 148.699474 -134.340346)
		(size 0.508)
		(drill 0.254)
		(layers "F.Cu" "B.Cu")
		(net "M_K_DQ<63>")
	)
	(via
		(at 149.549358 -130.330956)
		(size 0.508)
		(drill 0.254)
		(layers "F.Cu" "B.Cu")
		(net "M_K_DQ<63>")
	)
	(segment
		(start 149.549358 -128.276096)
		(end 149.549358 -130.330956)
		(width 0.1651)
		(layer "B.Cu")
		(net "M_K_DQ<63>")
	)
	(segment
		(start 149.902164 -129.989072)
		(end 149.891242 -129.989072)
		(width 0.14224)
		(layer "In2.Cu")
		(net "M_K_DQ<63>")
	)
	(segment
		(start 145.772378 -114.275616)
		(end 147.159726 -114.275616)
		(width 0.14224)
		(layer "In2.Cu")
		(net "M_K_DQ<63>")
	)
	(segment
		(start 148.860764 -132.184648)
		(end 148.860764 -132.457952)
		(width 0.14224)
		(layer "In2.Cu")
		(net "M_K_DQ<63>")
	)
	(segment
		(start 149.143212 -131.9022)
		(end 148.860764 -132.184648)
		(width 0.14224)
		(layer "In2.Cu")
		(net "M_K_DQ<63>")
	)
	(segment
		(start 150.49881 -122.64009)
		(end 150.49881 -123.134374)
		(width 0.14224)
		(layer "In2.Cu")
		(net "M_K_DQ<63>")
	)
	(segment
		(start 149.549358 -130.330956)
		(end 149.527006 -130.330956)
		(width 0.14224)
		(layer "In2.Cu")
		(net "M_K_DQ<63>")
	)
	(segment
		(start 149.891242 -129.989072)
		(end 149.549358 -130.330956)
		(width 0.14224)
		(layer "In2.Cu")
		(net "M_K_DQ<63>")
	)
	(segment
		(start 149.143212 -131.233418)
		(end 149.143212 -131.9022)
		(width 0.14224)
		(layer "In2.Cu")
		(net "M_K_DQ<63>")
	)
	(segment
		(start 149.902164 -129.368804)
		(end 149.902164 -129.989072)
		(width 0.14224)
		(layer "In2.Cu")
		(net "M_K_DQ<63>")
	)
	(segment
		(start 125.139958 -101.767386)
		(end 125.305566 -102.054152)
		(width 0.0889)
		(layer "In2.Cu")
		(net "M_K_DQ<63>")
	)
	(segment
		(start 145.621248 -113.905538)
		(end 145.621248 -114.124486)
		(width 0.14224)
		(layer "In2.Cu")
		(net "M_K_DQ<63>")
	)
	(segment
		(start 149.117812 -133.0198)
		(end 148.860764 -133.276848)
		(width 0.14224)
		(layer "In2.Cu")
		(net "M_K_DQ<63>")
	)
	(segment
		(start 125.305566 -102.448106)
		(end 126.34976 -103.4923)
		(width 0.0889)
		(layer "In2.Cu")
		(net "M_K_DQ<63>")
	)
	(segment
		(start 145.046446 -113.330736)
		(end 145.308574 -113.068862)
		(width 0.14224)
		(layer "In2.Cu")
		(net "M_K_DQ<63>")
	)
	(segment
		(start 152.169368 -122.194066)
		(end 151.926544 -122.43689)
		(width 0.14224)
		(layer "In2.Cu")
		(net "M_K_DQ<63>")
	)
	(segment
		(start 129.537968 -103.4923)
		(end 131.366768 -105.3211)
		(width 0.0889)
		(layer "In2.Cu")
		(net "M_K_DQ<63>")
	)
	(segment
		(start 152.169368 -119.285258)
		(end 152.169368 -122.194066)
		(width 0.14224)
		(layer "In2.Cu")
		(net "M_K_DQ<63>")
	)
	(segment
		(start 145.527522 -113.068862)
		(end 145.883376 -113.424716)
		(width 0.14224)
		(layer "In2.Cu")
		(net "M_K_DQ<63>")
	)
	(segment
		(start 137.719562 -106.2228)
		(end 144.827498 -113.330736)
		(width 0.14224)
		(layer "In2.Cu")
		(net "M_K_DQ<63>")
	)
	(segment
		(start 148.971762 -134.340346)
		(end 148.699474 -134.340346)
		(width 0.14224)
		(layer "In2.Cu")
		(net "M_K_DQ<63>")
	)
	(segment
		(start 149.098762 -130.7592)
		(end 149.098762 -131.188968)
		(width 0.14224)
		(layer "In2.Cu")
		(net "M_K_DQ<63>")
	)
	(segment
		(start 132.636768 -105.3211)
		(end 132.776468 -105.1814)
		(width 0.0889)
		(layer "In2.Cu")
		(net "M_K_DQ<63>")
	)
	(segment
		(start 150.70201 -122.43689)
		(end 150.49881 -122.64009)
		(width 0.14224)
		(layer "In2.Cu")
		(net "M_K_DQ<63>")
	)
	(segment
		(start 145.883376 -113.643664)
		(end 145.621248 -113.905538)
		(width 0.14224)
		(layer "In2.Cu")
		(net "M_K_DQ<63>")
	)
	(segment
		(start 149.149562 -134.162546)
		(end 148.971762 -134.340346)
		(width 0.14224)
		(layer "In2.Cu")
		(net "M_K_DQ<63>")
	)
	(segment
		(start 148.860764 -132.457952)
		(end 149.117812 -132.715)
		(width 0.14224)
		(layer "In2.Cu")
		(net "M_K_DQ<63>")
	)
	(segment
		(start 149.149562 -133.83895)
		(end 149.149562 -134.162546)
		(width 0.14224)
		(layer "In2.Cu")
		(net "M_K_DQ<63>")
	)
	(segment
		(start 149.117812 -132.715)
		(end 149.117812 -133.0198)
		(width 0.14224)
		(layer "In2.Cu")
		(net "M_K_DQ<63>")
	)
	(segment
		(start 148.860764 -133.550152)
		(end 149.149562 -133.83895)
		(width 0.14224)
		(layer "In2.Cu")
		(net "M_K_DQ<63>")
	)
	(segment
		(start 135.21944 -106.2228)
		(end 137.719562 -106.2228)
		(width 0.14224)
		(layer "In2.Cu")
		(net "M_K_DQ<63>")
	)
	(segment
		(start 134.17804 -105.1814)
		(end 135.21944 -106.2228)
		(width 0.14224)
		(layer "In2.Cu")
		(net "M_K_DQ<63>")
	)
	(segment
		(start 150.70201 -123.337574)
		(end 151.525478 -123.337574)
		(width 0.14224)
		(layer "In2.Cu")
		(net "M_K_DQ<63>")
	)
	(segment
		(start 151.525478 -123.337574)
		(end 151.728678 -123.540774)
		(width 0.14224)
		(layer "In2.Cu")
		(net "M_K_DQ<63>")
	)
	(segment
		(start 148.860764 -133.276848)
		(end 148.860764 -133.550152)
		(width 0.14224)
		(layer "In2.Cu")
		(net "M_K_DQ<63>")
	)
	(segment
		(start 150.49881 -123.134374)
		(end 150.70201 -123.337574)
		(width 0.14224)
		(layer "In2.Cu")
		(net "M_K_DQ<63>")
	)
	(segment
		(start 132.776468 -105.1814)
		(end 134.17804 -105.1814)
		(width 0.14224)
		(layer "In2.Cu")
		(net "M_K_DQ<63>")
	)
	(segment
		(start 125.305566 -102.054152)
		(end 125.305566 -102.448106)
		(width 0.0889)
		(layer "In2.Cu")
		(net "M_K_DQ<63>")
	)
	(segment
		(start 131.366768 -105.3211)
		(end 132.636768 -105.3211)
		(width 0.0889)
		(layer "In2.Cu")
		(net "M_K_DQ<63>")
	)
	(segment
		(start 150.543768 -124.353574)
		(end 150.543768 -128.7272)
		(width 0.14224)
		(layer "In2.Cu")
		(net "M_K_DQ<63>")
	)
	(segment
		(start 145.883376 -113.424716)
		(end 145.883376 -113.643664)
		(width 0.14224)
		(layer "In2.Cu")
		(net "M_K_DQ<63>")
	)
	(segment
		(start 151.926544 -122.43689)
		(end 150.70201 -122.43689)
		(width 0.14224)
		(layer "In2.Cu")
		(net "M_K_DQ<63>")
	)
	(segment
		(start 126.34976 -103.4923)
		(end 129.537968 -103.4923)
		(width 0.0889)
		(layer "In2.Cu")
		(net "M_K_DQ<63>")
	)
	(segment
		(start 151.728678 -123.947174)
		(end 151.525478 -124.150374)
		(width 0.14224)
		(layer "In2.Cu")
		(net "M_K_DQ<63>")
	)
	(segment
		(start 125.010672 -100.533454)
		(end 125.139958 -100.776786)
		(width 0.0889)
		(layer "In2.Cu")
		(net "M_K_DQ<63>")
	)
	(segment
		(start 151.525478 -124.150374)
		(end 150.746968 -124.150374)
		(width 0.14224)
		(layer "In2.Cu")
		(net "M_K_DQ<63>")
	)
	(segment
		(start 147.159726 -114.275616)
		(end 152.169368 -119.285258)
		(width 0.14224)
		(layer "In2.Cu")
		(net "M_K_DQ<63>")
	)
	(segment
		(start 151.728678 -123.540774)
		(end 151.728678 -123.947174)
		(width 0.14224)
		(layer "In2.Cu")
		(net "M_K_DQ<63>")
	)
	(segment
		(start 150.543768 -128.7272)
		(end 149.902164 -129.368804)
		(width 0.14224)
		(layer "In2.Cu")
		(net "M_K_DQ<63>")
	)
	(segment
		(start 124.793248 -99.986338)
		(end 125.010672 -100.533454)
		(width 0.0889)
		(layer "In2.Cu")
		(net "M_K_DQ<63>")
	)
	(segment
		(start 149.098762 -131.188968)
		(end 149.143212 -131.233418)
		(width 0.14224)
		(layer "In2.Cu")
		(net "M_K_DQ<63>")
	)
	(segment
		(start 150.746968 -124.150374)
		(end 150.543768 -124.353574)
		(width 0.14224)
		(layer "In2.Cu")
		(net "M_K_DQ<63>")
	)
	(segment
		(start 144.827498 -113.330736)
		(end 145.046446 -113.330736)
		(width 0.14224)
		(layer "In2.Cu")
		(net "M_K_DQ<63>")
	)
	(segment
		(start 149.527006 -130.330956)
		(end 149.098762 -130.7592)
		(width 0.14224)
		(layer "In2.Cu")
		(net "M_K_DQ<63>")
	)
	(segment
		(start 145.621248 -114.124486)
		(end 145.772378 -114.275616)
		(width 0.14224)
		(layer "In2.Cu")
		(net "M_K_DQ<63>")
	)
	(segment
		(start 145.308574 -113.068862)
		(end 145.527522 -113.068862)
		(width 0.14224)
		(layer "In2.Cu")
		(net "M_K_DQ<63>")
	)
	(arc
		(start 125.139958 -101.176582)
		(mid 125.060827 -101.471984)
		(end 125.139958 -101.767386)
		(width 0.0889)
		(layer "In2.Cu")
		(net "M_K_DQ<63>")
	)
	(arc
		(start 125.139958 -100.776786)
		(mid 125.193457 -100.976684)
		(end 125.139958 -101.176582)
		(width 0.0889)
		(layer "In2.Cu")
		(net "M_K_DQ<63>")
	)
	(segment
		(start 149.549612 -136.7028)
		(end 149.681692 -136.57072)
		(width 0.1651)
		(layer "F.Cu")
		(net "M_K_DQ<62>")
	)
	(segment
		(start 149.549612 -137.67054)
		(end 149.549612 -136.7028)
		(width 0.1651)
		(layer "F.Cu")
		(net "M_K_DQ<62>")
	)
	(segment
		(start 149.681692 -136.57072)
		(end 149.681692 -136.35228)
		(width 0.1651)
		(layer "F.Cu")
		(net "M_K_DQ<62>")
	)
	(segment
		(start 149.681692 -136.35228)
		(end 149.549612 -136.2202)
		(width 0.1651)
		(layer "F.Cu")
		(net "M_K_DQ<62>")
	)
	(segment
		(start 149.549612 -135.915654)
		(end 149.549358 -135.9154)
		(width 0.1651)
		(layer "F.Cu")
		(net "M_K_DQ<62>")
	)
	(segment
		(start 149.549358 -137.67054)
		(end 149.549612 -137.67054)
		(width 0.1651)
		(layer "F.Cu")
		(net "M_K_DQ<62>")
	)
	(segment
		(start 149.549612 -136.2202)
		(end 149.549612 -135.915654)
		(width 0.1651)
		(layer "F.Cu")
		(net "M_K_DQ<62>")
	)
	(segment
		(start 124.221748 -101.967538)
		(end 124.793248 -101.967538)
		(width 0.1651)
		(layer "F.Cu")
		(net "M_K_DQ<62>")
	)
	(via
		(at 124.793248 -101.967538)
		(size 0.508)
		(drill 0.254)
		(layers "F.Cu" "B.Cu")
		(net "M_K_DQ<62>")
	)
	(via
		(at 148.699474 -131.611878)
		(size 0.508)
		(drill 0.254)
		(layers "F.Cu" "B.Cu")
		(net "M_K_DQ<62>")
	)
	(via
		(at 149.549358 -135.9154)
		(size 0.508)
		(drill 0.254)
		(layers "F.Cu" "B.Cu")
		(net "M_K_DQ<62>")
	)
	(segment
		(start 148.699474 -132.876036)
		(end 148.699474 -131.611878)
		(width 0.1651)
		(layer "B.Cu")
		(net "M_K_DQ<62>")
	)
	(segment
		(start 148.530564 -130.468878)
		(end 148.530564 -131.442968)
		(width 0.14224)
		(layer "In2.Cu")
		(net "M_K_DQ<62>")
	)
	(segment
		(start 132.636768 -105.5116)
		(end 132.789168 -105.664)
		(width 0.0889)
		(layer "In2.Cu")
		(net "M_K_DQ<62>")
	)
	(segment
		(start 151.342344 -121.80951)
		(end 150.935944 -121.80951)
		(width 0.14224)
		(layer "In2.Cu")
		(net "M_K_DQ<62>")
	)
	(segment
		(start 149.908768 -128.507744)
		(end 149.267164 -129.149348)
		(width 0.14224)
		(layer "In2.Cu")
		(net "M_K_DQ<62>")
	)
	(segment
		(start 150.123144 -119.942102)
		(end 149.908768 -120.156478)
		(width 0.14224)
		(layer "In2.Cu")
		(net "M_K_DQ<62>")
	)
	(segment
		(start 149.267164 -129.732278)
		(end 148.530564 -130.468878)
		(width 0.14224)
		(layer "In2.Cu")
		(net "M_K_DQ<62>")
	)
	(segment
		(start 150.529544 -119.942102)
		(end 150.123144 -119.942102)
		(width 0.14224)
		(layer "In2.Cu")
		(net "M_K_DQ<62>")
	)
	(segment
		(start 146.896582 -114.910616)
		(end 151.534368 -119.548402)
		(width 0.14224)
		(layer "In2.Cu")
		(net "M_K_DQ<62>")
	)
	(segment
		(start 148.266404 -132.044948)
		(end 148.266404 -134.632446)
		(width 0.14224)
		(layer "In2.Cu")
		(net "M_K_DQ<62>")
	)
	(segment
		(start 148.266404 -134.632446)
		(end 149.549358 -135.9154)
		(width 0.14224)
		(layer "In2.Cu")
		(net "M_K_DQ<62>")
	)
	(segment
		(start 124.793248 -101.967538)
		(end 125.115066 -102.289356)
		(width 0.0889)
		(layer "In2.Cu")
		(net "M_K_DQ<62>")
	)
	(segment
		(start 150.935944 -121.80951)
		(end 150.721568 -121.595134)
		(width 0.14224)
		(layer "In2.Cu")
		(net "M_K_DQ<62>")
	)
	(segment
		(start 133.983476 -105.664)
		(end 135.024876 -106.7054)
		(width 0.14224)
		(layer "In2.Cu")
		(net "M_K_DQ<62>")
	)
	(segment
		(start 125.115066 -102.527354)
		(end 126.270512 -103.6828)
		(width 0.0889)
		(layer "In2.Cu")
		(net "M_K_DQ<62>")
	)
	(segment
		(start 137.284714 -106.7054)
		(end 145.48993 -114.910616)
		(width 0.14224)
		(layer "In2.Cu")
		(net "M_K_DQ<62>")
	)
	(segment
		(start 148.530564 -131.442968)
		(end 148.699474 -131.611878)
		(width 0.14224)
		(layer "In2.Cu")
		(net "M_K_DQ<62>")
	)
	(segment
		(start 129.45872 -103.6828)
		(end 131.28752 -105.5116)
		(width 0.0889)
		(layer "In2.Cu")
		(net "M_K_DQ<62>")
	)
	(segment
		(start 150.721568 -120.134126)
		(end 150.529544 -119.942102)
		(width 0.14224)
		(layer "In2.Cu")
		(net "M_K_DQ<62>")
	)
	(segment
		(start 149.908768 -120.156478)
		(end 149.908768 -128.507744)
		(width 0.14224)
		(layer "In2.Cu")
		(net "M_K_DQ<62>")
	)
	(segment
		(start 150.721568 -121.595134)
		(end 150.721568 -120.134126)
		(width 0.14224)
		(layer "In2.Cu")
		(net "M_K_DQ<62>")
	)
	(segment
		(start 125.115066 -102.289356)
		(end 125.115066 -102.527354)
		(width 0.0889)
		(layer "In2.Cu")
		(net "M_K_DQ<62>")
	)
	(segment
		(start 135.024876 -106.7054)
		(end 137.284714 -106.7054)
		(width 0.14224)
		(layer "In2.Cu")
		(net "M_K_DQ<62>")
	)
	(segment
		(start 149.267164 -129.149348)
		(end 149.267164 -129.732278)
		(width 0.14224)
		(layer "In2.Cu")
		(net "M_K_DQ<62>")
	)
	(segment
		(start 132.789168 -105.664)
		(end 133.983476 -105.664)
		(width 0.14224)
		(layer "In2.Cu")
		(net "M_K_DQ<62>")
	)
	(segment
		(start 148.699474 -131.611878)
		(end 148.266404 -132.044948)
		(width 0.14224)
		(layer "In2.Cu")
		(net "M_K_DQ<62>")
	)
	(segment
		(start 151.534368 -121.617486)
		(end 151.342344 -121.80951)
		(width 0.14224)
		(layer "In2.Cu")
		(net "M_K_DQ<62>")
	)
	(segment
		(start 126.270512 -103.6828)
		(end 129.45872 -103.6828)
		(width 0.0889)
		(layer "In2.Cu")
		(net "M_K_DQ<62>")
	)
	(segment
		(start 131.28752 -105.5116)
		(end 132.636768 -105.5116)
		(width 0.0889)
		(layer "In2.Cu")
		(net "M_K_DQ<62>")
	)
	(segment
		(start 151.534368 -119.548402)
		(end 151.534368 -121.617486)
		(width 0.14224)
		(layer "In2.Cu")
		(net "M_K_DQ<62>")
	)
	(segment
		(start 145.48993 -114.910616)
		(end 146.896582 -114.910616)
		(width 0.14224)
		(layer "In2.Cu")
		(net "M_K_DQ<62>")
	)
	(segment
		(start 142.749524 -133.0706)
		(end 142.749524 -134.340346)
		(width 0.1651)
		(layer "F.Cu")
		(net "M_K_DQ<61>")
	)
	(segment
		(start 122.217688 -98.500184)
		(end 121.646188 -98.500184)
		(width 0.1651)
		(layer "F.Cu")
		(net "M_K_DQ<61>")
	)
	(via
		(at 122.217688 -98.500184)
		(size 0.508)
		(drill 0.254)
		(layers "F.Cu" "B.Cu")
		(net "M_K_DQ<61>")
	)
	(via
		(at 142.749524 -134.340346)
		(size 0.508)
		(drill 0.254)
		(layers "F.Cu" "B.Cu")
		(net "M_K_DQ<61>")
	)
	(via
		(at 143.577564 -130.244596)
		(size 0.508)
		(drill 0.254)
		(layers "F.Cu" "B.Cu")
		(net "M_K_DQ<61>")
	)
	(segment
		(start 143.599408 -128.276096)
		(end 143.599408 -130.222752)
		(width 0.1651)
		(layer "B.Cu")
		(net "M_K_DQ<61>")
	)
	(segment
		(start 143.599408 -130.222752)
		(end 143.577564 -130.244596)
		(width 0.1651)
		(layer "B.Cu")
		(net "M_K_DQ<61>")
	)
	(segment
		(start 142.697962 -118.061486)
		(end 143.112744 -118.061486)
		(width 0.14224)
		(layer "In2.Cu")
		(net "M_K_DQ<61>")
	)
	(segment
		(start 144.009364 -129.216658)
		(end 143.660368 -129.565654)
		(width 0.14224)
		(layer "In2.Cu")
		(net "M_K_DQ<61>")
	)
	(segment
		(start 138.099546 -113.46307)
		(end 138.514328 -113.46307)
		(width 0.14224)
		(layer "In2.Cu")
		(net "M_K_DQ<61>")
	)
	(segment
		(start 135.4328 -110.381542)
		(end 135.4328 -110.796324)
		(width 0.14224)
		(layer "In2.Cu")
		(net "M_K_DQ<61>")
	)
	(segment
		(start 141.18082 -116.129562)
		(end 141.18082 -116.544344)
		(width 0.14224)
		(layer "In2.Cu")
		(net "M_K_DQ<61>")
	)
	(segment
		(start 121.877328 -100.270818)
		(end 121.870978 -100.281486)
		(width 0.0889)
		(layer "In2.Cu")
		(net "M_K_DQ<61>")
	)
	(segment
		(start 143.123412 -133.909054)
		(end 143.123412 -134.16661)
		(width 0.14224)
		(layer "In2.Cu")
		(net "M_K_DQ<61>")
	)
	(segment
		(start 139.24915 -114.612674)
		(end 139.663932 -114.612674)
		(width 0.14224)
		(layer "In2.Cu")
		(net "M_K_DQ<61>")
	)
	(segment
		(start 139.663932 -114.612674)
		(end 140.031216 -114.979958)
		(width 0.14224)
		(layer "In2.Cu")
		(net "M_K_DQ<61>")
	)
	(segment
		(start 134.830058 -109.7788)
		(end 135.4328 -110.381542)
		(width 0.14224)
		(layer "In2.Cu")
		(net "M_K_DQ<61>")
	)
	(segment
		(start 121.877328 -99.280218)
		(end 121.870978 -99.290886)
		(width 0.0889)
		(layer "In2.Cu")
		(net "M_K_DQ<61>")
	)
	(segment
		(start 143.199612 -131.445)
		(end 143.199612 -131.927346)
		(width 0.14224)
		(layer "In2.Cu")
		(net "M_K_DQ<61>")
	)
	(segment
		(start 145.025364 -123.1392)
		(end 144.822164 -122.936)
		(width 0.14224)
		(layer "In2.Cu")
		(net "M_K_DQ<61>")
	)
	(segment
		(start 129.681986 -109.7788)
		(end 134.830058 -109.7788)
		(width 0.14224)
		(layer "In2.Cu")
		(net "M_K_DQ<61>")
	)
	(segment
		(start 140.031216 -114.979958)
		(end 140.031216 -115.39474)
		(width 0.14224)
		(layer "In2.Cu")
		(net "M_K_DQ<61>")
	)
	(segment
		(start 143.072612 -130.749548)
		(end 143.072612 -131.318)
		(width 0.14224)
		(layer "In2.Cu")
		(net "M_K_DQ<61>")
	)
	(segment
		(start 121.870978 -100.281486)
		(end 121.866152 -100.290122)
		(width 0.0889)
		(layer "In2.Cu")
		(net "M_K_DQ<61>")
	)
	(segment
		(start 143.112744 -118.061486)
		(end 145.634964 -120.583706)
		(width 0.14224)
		(layer "In2.Cu")
		(net "M_K_DQ<61>")
	)
	(segment
		(start 138.881612 -113.830354)
		(end 138.881612 -114.245136)
		(width 0.14224)
		(layer "In2.Cu")
		(net "M_K_DQ<61>")
	)
	(segment
		(start 144.212564 -121.9708)
		(end 144.009364 -122.174)
		(width 0.14224)
		(layer "In2.Cu")
		(net "M_K_DQ<61>")
	)
	(segment
		(start 135.800338 -111.163862)
		(end 136.21512 -111.163862)
		(width 0.14224)
		(layer "In2.Cu")
		(net "M_K_DQ<61>")
	)
	(segment
		(start 142.910814 -133.384544)
		(end 142.910814 -133.696456)
		(width 0.14224)
		(layer "In2.Cu")
		(net "M_K_DQ<61>")
	)
	(segment
		(start 142.910814 -132.553456)
		(end 143.126968 -132.76961)
		(width 0.14224)
		(layer "In2.Cu")
		(net "M_K_DQ<61>")
	)
	(segment
		(start 121.952766 -104.060498)
		(end 125.067568 -107.1753)
		(width 0.0889)
		(layer "In2.Cu")
		(net "M_K_DQ<61>")
	)
	(segment
		(start 143.660368 -130.161792)
		(end 143.577564 -130.244596)
		(width 0.14224)
		(layer "In2.Cu")
		(net "M_K_DQ<61>")
	)
	(segment
		(start 138.881612 -114.245136)
		(end 139.24915 -114.612674)
		(width 0.14224)
		(layer "In2.Cu")
		(net "M_K_DQ<61>")
	)
	(segment
		(start 136.582404 -111.945928)
		(end 136.949942 -112.313466)
		(width 0.14224)
		(layer "In2.Cu")
		(net "M_K_DQ<61>")
	)
	(segment
		(start 122.084338 -102.385876)
		(end 121.952766 -102.517448)
		(width 0.0889)
		(layer "In2.Cu")
		(net "M_K_DQ<61>")
	)
	(segment
		(start 121.952766 -102.517448)
		(end 121.952766 -104.060498)
		(width 0.0889)
		(layer "In2.Cu")
		(net "M_K_DQ<61>")
	)
	(segment
		(start 141.548358 -116.911882)
		(end 141.96314 -116.911882)
		(width 0.14224)
		(layer "In2.Cu")
		(net "M_K_DQ<61>")
	)
	(segment
		(start 136.949942 -112.313466)
		(end 137.364724 -112.313466)
		(width 0.14224)
		(layer "In2.Cu")
		(net "M_K_DQ<61>")
	)
	(segment
		(start 137.364724 -112.313466)
		(end 137.732008 -112.68075)
		(width 0.14224)
		(layer "In2.Cu")
		(net "M_K_DQ<61>")
	)
	(segment
		(start 140.398754 -115.762278)
		(end 140.813536 -115.762278)
		(width 0.14224)
		(layer "In2.Cu")
		(net "M_K_DQ<61>")
	)
	(segment
		(start 125.397768 -107.1753)
		(end 126.735078 -108.51261)
		(width 0.14224)
		(layer "In2.Cu")
		(net "M_K_DQ<61>")
	)
	(segment
		(start 143.123412 -134.16661)
		(end 142.949676 -134.340346)
		(width 0.14224)
		(layer "In2.Cu")
		(net "M_K_DQ<61>")
	)
	(segment
		(start 137.732008 -113.095532)
		(end 138.099546 -113.46307)
		(width 0.14224)
		(layer "In2.Cu")
		(net "M_K_DQ<61>")
	)
	(segment
		(start 140.813536 -115.762278)
		(end 141.18082 -116.129562)
		(width 0.14224)
		(layer "In2.Cu")
		(net "M_K_DQ<61>")
	)
	(segment
		(start 143.126968 -133.16839)
		(end 142.910814 -133.384544)
		(width 0.14224)
		(layer "In2.Cu")
		(net "M_K_DQ<61>")
	)
	(segment
		(start 144.822164 -122.936)
		(end 144.822164 -122.174)
		(width 0.14224)
		(layer "In2.Cu")
		(net "M_K_DQ<61>")
	)
	(segment
		(start 144.822164 -122.174)
		(end 144.618964 -121.9708)
		(width 0.14224)
		(layer "In2.Cu")
		(net "M_K_DQ<61>")
	)
	(segment
		(start 143.660368 -129.565654)
		(end 143.660368 -130.161792)
		(width 0.14224)
		(layer "In2.Cu")
		(net "M_K_DQ<61>")
	)
	(segment
		(start 121.870978 -99.290886)
		(end 121.866152 -99.299522)
		(width 0.0889)
		(layer "In2.Cu")
		(net "M_K_DQ<61>")
	)
	(segment
		(start 143.072612 -131.318)
		(end 143.199612 -131.445)
		(width 0.14224)
		(layer "In2.Cu")
		(net "M_K_DQ<61>")
	)
	(segment
		(start 143.577564 -130.244596)
		(end 143.072612 -130.749548)
		(width 0.14224)
		(layer "In2.Cu")
		(net "M_K_DQ<61>")
	)
	(segment
		(start 125.067568 -107.1753)
		(end 125.397768 -107.1753)
		(width 0.0889)
		(layer "In2.Cu")
		(net "M_K_DQ<61>")
	)
	(segment
		(start 141.96314 -116.911882)
		(end 142.330424 -117.279166)
		(width 0.14224)
		(layer "In2.Cu")
		(net "M_K_DQ<61>")
	)
	(segment
		(start 140.031216 -115.39474)
		(end 140.398754 -115.762278)
		(width 0.14224)
		(layer "In2.Cu")
		(net "M_K_DQ<61>")
	)
	(segment
		(start 145.634964 -122.936)
		(end 145.431764 -123.1392)
		(width 0.14224)
		(layer "In2.Cu")
		(net "M_K_DQ<61>")
	)
	(segment
		(start 144.009364 -122.174)
		(end 144.009364 -129.216658)
		(width 0.14224)
		(layer "In2.Cu")
		(net "M_K_DQ<61>")
	)
	(segment
		(start 128.415796 -108.51261)
		(end 129.681986 -109.7788)
		(width 0.14224)
		(layer "In2.Cu")
		(net "M_K_DQ<61>")
	)
	(segment
		(start 122.084338 -101.05136)
		(end 122.084338 -102.385876)
		(width 0.0889)
		(layer "In2.Cu")
		(net "M_K_DQ<61>")
	)
	(segment
		(start 142.910814 -132.216144)
		(end 142.910814 -132.553456)
		(width 0.14224)
		(layer "In2.Cu")
		(net "M_K_DQ<61>")
	)
	(segment
		(start 122.217688 -98.500184)
		(end 122.217688 -98.16211)
		(width 0.0889)
		(layer "In2.Cu")
		(net "M_K_DQ<61>")
	)
	(segment
		(start 122.217688 -98.16211)
		(end 122.159776 -98.104198)
		(width 0.0889)
		(layer "In2.Cu")
		(net "M_K_DQ<61>")
	)
	(segment
		(start 145.431764 -123.1392)
		(end 145.025364 -123.1392)
		(width 0.14224)
		(layer "In2.Cu")
		(net "M_K_DQ<61>")
	)
	(segment
		(start 141.18082 -116.544344)
		(end 141.548358 -116.911882)
		(width 0.14224)
		(layer "In2.Cu")
		(net "M_K_DQ<61>")
	)
	(segment
		(start 136.21512 -111.163862)
		(end 136.582404 -111.531146)
		(width 0.14224)
		(layer "In2.Cu")
		(net "M_K_DQ<61>")
	)
	(segment
		(start 142.910814 -133.696456)
		(end 143.123412 -133.909054)
		(width 0.14224)
		(layer "In2.Cu")
		(net "M_K_DQ<61>")
	)
	(segment
		(start 145.634964 -120.583706)
		(end 145.634964 -122.936)
		(width 0.14224)
		(layer "In2.Cu")
		(net "M_K_DQ<61>")
	)
	(segment
		(start 142.330424 -117.693948)
		(end 142.697962 -118.061486)
		(width 0.14224)
		(layer "In2.Cu")
		(net "M_K_DQ<61>")
	)
	(segment
		(start 136.582404 -111.531146)
		(end 136.582404 -111.945928)
		(width 0.14224)
		(layer "In2.Cu")
		(net "M_K_DQ<61>")
	)
	(segment
		(start 144.618964 -121.9708)
		(end 144.212564 -121.9708)
		(width 0.14224)
		(layer "In2.Cu")
		(net "M_K_DQ<61>")
	)
	(segment
		(start 142.949676 -134.340346)
		(end 142.749524 -134.340346)
		(width 0.14224)
		(layer "In2.Cu")
		(net "M_K_DQ<61>")
	)
	(segment
		(start 142.330424 -117.279166)
		(end 142.330424 -117.693948)
		(width 0.14224)
		(layer "In2.Cu")
		(net "M_K_DQ<61>")
	)
	(segment
		(start 143.199612 -131.927346)
		(end 142.910814 -132.216144)
		(width 0.14224)
		(layer "In2.Cu")
		(net "M_K_DQ<61>")
	)
	(segment
		(start 143.126968 -132.76961)
		(end 143.126968 -133.16839)
		(width 0.14224)
		(layer "In2.Cu")
		(net "M_K_DQ<61>")
	)
	(segment
		(start 135.4328 -110.796324)
		(end 135.800338 -111.163862)
		(width 0.14224)
		(layer "In2.Cu")
		(net "M_K_DQ<61>")
	)
	(segment
		(start 121.870978 -100.681536)
		(end 122.084338 -101.05136)
		(width 0.0889)
		(layer "In2.Cu")
		(net "M_K_DQ<61>")
	)
	(segment
		(start 126.735078 -108.51261)
		(end 128.415796 -108.51261)
		(width 0.14224)
		(layer "In2.Cu")
		(net "M_K_DQ<61>")
	)
	(segment
		(start 137.732008 -112.68075)
		(end 137.732008 -113.095532)
		(width 0.14224)
		(layer "In2.Cu")
		(net "M_K_DQ<61>")
	)
	(segment
		(start 138.514328 -113.46307)
		(end 138.881612 -113.830354)
		(width 0.14224)
		(layer "In2.Cu")
		(net "M_K_DQ<61>")
	)
	(arc
		(start 121.870978 -98.700336)
		(mid 121.9502 -98.989454)
		(end 121.877328 -99.280218)
		(width 0.0889)
		(layer "In2.Cu")
		(net "M_K_DQ<61>")
	)
	(arc
		(start 121.866152 -99.299522)
		(mid 121.817397 -99.495874)
		(end 121.870978 -99.690936)
		(width 0.0889)
		(layer "In2.Cu")
		(net "M_K_DQ<61>")
	)
	(arc
		(start 121.870978 -99.690936)
		(mid 121.9502 -99.980054)
		(end 121.877328 -100.270818)
		(width 0.0889)
		(layer "In2.Cu")
		(net "M_K_DQ<61>")
	)
	(arc
		(start 122.159776 -98.104198)
		(mid 121.857507 -98.325747)
		(end 121.870978 -98.700336)
		(width 0.0889)
		(layer "In2.Cu")
		(net "M_K_DQ<61>")
	)
	(arc
		(start 121.866152 -100.290122)
		(mid 121.817397 -100.486474)
		(end 121.870978 -100.681536)
		(width 0.0889)
		(layer "In2.Cu")
		(net "M_K_DQ<61>")
	)
	(segment
		(start 122.217688 -97.509584)
		(end 121.646188 -97.509584)
		(width 0.1651)
		(layer "F.Cu")
		(net "M_K_DQ<60>")
	)
	(segment
		(start 143.599408 -136.345168)
		(end 143.501364 -135.8138)
		(width 0.1651)
		(layer "F.Cu")
		(net "M_K_DQ<60>")
	)
	(segment
		(start 143.599408 -137.67054)
		(end 143.599408 -136.345168)
		(width 0.1651)
		(layer "F.Cu")
		(net "M_K_DQ<60>")
	)
	(via
		(at 142.749524 -131.611878)
		(size 0.508)
		(drill 0.254)
		(layers "F.Cu" "B.Cu")
		(net "M_K_DQ<60>")
	)
	(via
		(at 143.501364 -135.8138)
		(size 0.508)
		(drill 0.254)
		(layers "F.Cu" "B.Cu")
		(net "M_K_DQ<60>")
	)
	(via
		(at 122.217688 -97.509584)
		(size 0.508)
		(drill 0.254)
		(layers "F.Cu" "B.Cu")
		(net "M_K_DQ<60>")
	)
	(segment
		(start 142.749524 -132.876036)
		(end 142.749524 -131.611878)
		(width 0.1651)
		(layer "B.Cu")
		(net "M_K_DQ<60>")
	)
	(segment
		(start 122.217688 -97.847658)
		(end 122.15241 -97.912936)
		(width 0.0889)
		(layer "In2.Cu")
		(net "M_K_DQ<60>")
	)
	(segment
		(start 121.705878 -99.195636)
		(end 121.699528 -99.206304)
		(width 0.0889)
		(layer "In2.Cu")
		(net "M_K_DQ<60>")
	)
	(segment
		(start 142.441168 -118.669054)
		(end 142.441168 -120.290082)
		(width 0.14224)
		(layer "In2.Cu")
		(net "M_K_DQ<60>")
	)
	(segment
		(start 144.227804 -121.317766)
		(end 142.644368 -121.317766)
		(width 0.14224)
		(layer "In2.Cu")
		(net "M_K_DQ<60>")
	)
	(segment
		(start 121.762266 -102.438454)
		(end 121.762266 -104.139492)
		(width 0.0889)
		(layer "In2.Cu")
		(net "M_K_DQ<60>")
	)
	(segment
		(start 143.374364 -126.684278)
		(end 143.206724 -126.851918)
		(width 0.14224)
		(layer "In2.Cu")
		(net "M_K_DQ<60>")
	)
	(segment
		(start 121.893838 -102.306882)
		(end 121.762266 -102.438454)
		(width 0.0889)
		(layer "In2.Cu")
		(net "M_K_DQ<60>")
	)
	(segment
		(start 142.316454 -132.044948)
		(end 142.316454 -134.57809)
		(width 0.14224)
		(layer "In2.Cu")
		(net "M_K_DQ<60>")
	)
	(segment
		(start 126.388368 -108.9914)
		(end 128.217168 -108.9914)
		(width 0.14224)
		(layer "In2.Cu")
		(net "M_K_DQ<60>")
	)
	(segment
		(start 121.893838 -101.102668)
		(end 121.893838 -102.306882)
		(width 0.0889)
		(layer "In2.Cu")
		(net "M_K_DQ<60>")
	)
	(segment
		(start 142.441168 -121.927366)
		(end 142.644368 -122.130566)
		(width 0.14224)
		(layer "In2.Cu")
		(net "M_K_DQ<60>")
	)
	(segment
		(start 142.644368 -122.130566)
		(end 143.171164 -122.130566)
		(width 0.14224)
		(layer "In2.Cu")
		(net "M_K_DQ<60>")
	)
	(segment
		(start 142.316454 -134.57809)
		(end 142.474442 -134.736078)
		(width 0.14224)
		(layer "In2.Cu")
		(net "M_K_DQ<60>")
	)
	(segment
		(start 143.250412 -135.8138)
		(end 143.501364 -135.8138)
		(width 0.14224)
		(layer "In2.Cu")
		(net "M_K_DQ<60>")
	)
	(segment
		(start 128.217168 -108.9914)
		(end 129.639568 -110.4138)
		(width 0.14224)
		(layer "In2.Cu")
		(net "M_K_DQ<60>")
	)
	(segment
		(start 129.639568 -110.4138)
		(end 134.185914 -110.4138)
		(width 0.14224)
		(layer "In2.Cu")
		(net "M_K_DQ<60>")
	)
	(segment
		(start 144.433544 -120.705626)
		(end 144.433544 -121.112026)
		(width 0.14224)
		(layer "In2.Cu")
		(net "M_K_DQ<60>")
	)
	(segment
		(start 142.474442 -135.03783)
		(end 143.250412 -135.8138)
		(width 0.14224)
		(layer "In2.Cu")
		(net "M_K_DQ<60>")
	)
	(segment
		(start 143.206724 -129.86385)
		(end 142.434564 -130.63601)
		(width 0.14224)
		(layer "In2.Cu")
		(net "M_K_DQ<60>")
	)
	(segment
		(start 121.710704 -100.1776)
		(end 121.705878 -100.186236)
		(width 0.0889)
		(layer "In2.Cu")
		(net "M_K_DQ<60>")
	)
	(segment
		(start 142.656052 -120.504966)
		(end 144.232884 -120.504966)
		(width 0.14224)
		(layer "In2.Cu")
		(net "M_K_DQ<60>")
	)
	(segment
		(start 124.965968 -107.343194)
		(end 124.965968 -107.569)
		(width 0.0889)
		(layer "In2.Cu")
		(net "M_K_DQ<60>")
	)
	(segment
		(start 143.374364 -122.333766)
		(end 143.374364 -126.684278)
		(width 0.14224)
		(layer "In2.Cu")
		(net "M_K_DQ<60>")
	)
	(segment
		(start 144.433544 -121.112026)
		(end 144.227804 -121.317766)
		(width 0.14224)
		(layer "In2.Cu")
		(net "M_K_DQ<60>")
	)
	(segment
		(start 142.474442 -134.736078)
		(end 142.474442 -135.03783)
		(width 0.14224)
		(layer "In2.Cu")
		(net "M_K_DQ<60>")
	)
	(segment
		(start 121.705878 -100.776786)
		(end 121.893838 -101.102668)
		(width 0.0889)
		(layer "In2.Cu")
		(net "M_K_DQ<60>")
	)
	(segment
		(start 143.206724 -126.851918)
		(end 143.206724 -129.86385)
		(width 0.14224)
		(layer "In2.Cu")
		(net "M_K_DQ<60>")
	)
	(segment
		(start 142.441168 -121.520966)
		(end 142.441168 -121.927366)
		(width 0.14224)
		(layer "In2.Cu")
		(net "M_K_DQ<60>")
	)
	(segment
		(start 124.965968 -107.569)
		(end 126.388368 -108.9914)
		(width 0.14224)
		(layer "In2.Cu")
		(net "M_K_DQ<60>")
	)
	(segment
		(start 142.434564 -131.296918)
		(end 142.749524 -131.611878)
		(width 0.14224)
		(layer "In2.Cu")
		(net "M_K_DQ<60>")
	)
	(segment
		(start 142.434564 -130.63601)
		(end 142.434564 -131.296918)
		(width 0.14224)
		(layer "In2.Cu")
		(net "M_K_DQ<60>")
	)
	(segment
		(start 121.705878 -100.186236)
		(end 121.699528 -100.196904)
		(width 0.0889)
		(layer "In2.Cu")
		(net "M_K_DQ<60>")
	)
	(segment
		(start 121.762266 -104.139492)
		(end 124.965968 -107.343194)
		(width 0.0889)
		(layer "In2.Cu")
		(net "M_K_DQ<60>")
	)
	(segment
		(start 122.217688 -97.509584)
		(end 122.217688 -97.847658)
		(width 0.0889)
		(layer "In2.Cu")
		(net "M_K_DQ<60>")
	)
	(segment
		(start 142.749524 -131.611878)
		(end 142.316454 -132.044948)
		(width 0.14224)
		(layer "In2.Cu")
		(net "M_K_DQ<60>")
	)
	(segment
		(start 143.171164 -122.130566)
		(end 143.374364 -122.333766)
		(width 0.14224)
		(layer "In2.Cu")
		(net "M_K_DQ<60>")
	)
	(segment
		(start 134.185914 -110.4138)
		(end 142.441168 -118.669054)
		(width 0.14224)
		(layer "In2.Cu")
		(net "M_K_DQ<60>")
	)
	(segment
		(start 144.232884 -120.504966)
		(end 144.433544 -120.705626)
		(width 0.14224)
		(layer "In2.Cu")
		(net "M_K_DQ<60>")
	)
	(segment
		(start 142.644368 -121.317766)
		(end 142.441168 -121.520966)
		(width 0.14224)
		(layer "In2.Cu")
		(net "M_K_DQ<60>")
	)
	(segment
		(start 142.441168 -120.290082)
		(end 142.656052 -120.504966)
		(width 0.14224)
		(layer "In2.Cu")
		(net "M_K_DQ<60>")
	)
	(segment
		(start 121.710704 -99.187)
		(end 121.705878 -99.195636)
		(width 0.0889)
		(layer "In2.Cu")
		(net "M_K_DQ<60>")
	)
	(arc
		(start 122.15241 -97.912936)
		(mid 121.690441 -98.233478)
		(end 121.705878 -98.795586)
		(width 0.0889)
		(layer "In2.Cu")
		(net "M_K_DQ<60>")
	)
	(arc
		(start 121.705878 -98.795586)
		(mid 121.759348 -98.990649)
		(end 121.710704 -99.187)
		(width 0.0889)
		(layer "In2.Cu")
		(net "M_K_DQ<60>")
	)
	(arc
		(start 121.705878 -99.786186)
		(mid 121.759348 -99.981249)
		(end 121.710704 -100.1776)
		(width 0.0889)
		(layer "In2.Cu")
		(net "M_K_DQ<60>")
	)
	(arc
		(start 121.699528 -100.196904)
		(mid 121.62673 -100.487667)
		(end 121.705878 -100.776786)
		(width 0.0889)
		(layer "In2.Cu")
		(net "M_K_DQ<60>")
	)
	(arc
		(start 121.699528 -99.206304)
		(mid 121.62673 -99.497067)
		(end 121.705878 -99.786186)
		(width 0.0889)
		(layer "In2.Cu")
		(net "M_K_DQ<60>")
	)
	(segment
		(start 31.39948 -133.0706)
		(end 31.39948 -134.340346)
		(width 0.1651)
		(layer "F.Cu")
		(net "M_K_DQ<5>")
	)
	(segment
		(start 67.749166 -84.31784)
		(end 67.101466 -84.31784)
		(width 0.1651)
		(layer "F.Cu")
		(net "M_K_DQ<5>")
	)
	(via
		(at 32.173164 -130.330956)
		(size 0.508)
		(drill 0.254)
		(layers "F.Cu" "B.Cu")
		(net "M_K_DQ<5>")
	)
	(via
		(at 67.101466 -84.31784)
		(size 0.508)
		(drill 0.254)
		(layers "F.Cu" "B.Cu")
		(net "M_K_DQ<5>")
	)
	(via
		(at 31.39948 -134.340346)
		(size 0.508)
		(drill 0.254)
		(layers "F.Cu" "B.Cu")
		(net "M_K_DQ<5>")
	)
	(segment
		(start 32.249364 -130.254756)
		(end 32.173164 -130.330956)
		(width 0.1651)
		(layer "B.Cu")
		(net "M_K_DQ<5>")
	)
	(segment
		(start 32.249364 -128.276096)
		(end 32.249364 -130.254756)
		(width 0.1651)
		(layer "B.Cu")
		(net "M_K_DQ<5>")
	)
	(segment
		(start 31.56077 -133.696456)
		(end 31.824168 -133.959854)
		(width 0.14224)
		(layer "In2.Cu")
		(net "M_K_DQ<5>")
	)
	(segment
		(start 33.11652 -119.32539)
		(end 32.967168 -119.474742)
		(width 0.14224)
		(layer "In2.Cu")
		(net "M_K_DQ<5>")
	)
	(segment
		(start 33.209484 -117.99951)
		(end 33.054544 -118.15445)
		(width 0.14224)
		(layer "In2.Cu")
		(net "M_K_DQ<5>")
	)
	(segment
		(start 50.289968 -98.71964)
		(end 50.289968 -100.203)
		(width 0.14224)
		(layer "In2.Cu")
		(net "M_K_DQ<5>")
	)
	(segment
		(start 32.150812 -130.330956)
		(end 31.722568 -130.7592)
		(width 0.14224)
		(layer "In2.Cu")
		(net "M_K_DQ<5>")
	)
	(segment
		(start 65.845182 -84.413344)
		(end 64.596264 -84.413344)
		(width 0.14224)
		(layer "In2.Cu")
		(net "M_K_DQ<5>")
	)
	(segment
		(start 33.054544 -117.18163)
		(end 33.209484 -117.33657)
		(width 0.14224)
		(layer "In2.Cu")
		(net "M_K_DQ<5>")
	)
	(segment
		(start 32.173164 -130.330956)
		(end 32.150812 -130.330956)
		(width 0.14224)
		(layer "In2.Cu")
		(net "M_K_DQ<5>")
	)
	(segment
		(start 64.596264 -84.413344)
		(end 50.289968 -98.71964)
		(width 0.14224)
		(layer "In2.Cu")
		(net "M_K_DQ<5>")
	)
	(segment
		(start 33.122108 -120.184926)
		(end 33.548828 -120.184926)
		(width 0.14224)
		(layer "In2.Cu")
		(net "M_K_DQ<5>")
	)
	(segment
		(start 31.671768 -134.340346)
		(end 31.39948 -134.340346)
		(width 0.14224)
		(layer "In2.Cu")
		(net "M_K_DQ<5>")
	)
	(segment
		(start 32.967168 -128.7526)
		(end 32.55772 -129.162048)
		(width 0.14224)
		(layer "In2.Cu")
		(net "M_K_DQ<5>")
	)
	(segment
		(start 31.798768 -132.884164)
		(end 31.798768 -133.146546)
		(width 0.14224)
		(layer "In2.Cu")
		(net "M_K_DQ<5>")
	)
	(segment
		(start 37.374576 -112.0902)
		(end 33.3629 -116.101876)
		(width 0.14224)
		(layer "In2.Cu")
		(net "M_K_DQ<5>")
	)
	(segment
		(start 33.122108 -120.847866)
		(end 32.967168 -121.002806)
		(width 0.14224)
		(layer "In2.Cu")
		(net "M_K_DQ<5>")
	)
	(segment
		(start 31.824168 -134.187946)
		(end 31.671768 -134.340346)
		(width 0.14224)
		(layer "In2.Cu")
		(net "M_K_DQ<5>")
	)
	(segment
		(start 31.722568 -130.7592)
		(end 31.722568 -131.318)
		(width 0.14224)
		(layer "In2.Cu")
		(net "M_K_DQ<5>")
	)
	(segment
		(start 32.55772 -129.9464)
		(end 32.173164 -130.330956)
		(width 0.14224)
		(layer "In2.Cu")
		(net "M_K_DQ<5>")
	)
	(segment
		(start 33.587944 -118.81739)
		(end 33.587944 -119.17045)
		(width 0.14224)
		(layer "In2.Cu")
		(net "M_K_DQ<5>")
	)
	(segment
		(start 66.553842 -84.31784)
		(end 66.458338 -84.413344)
		(width 0.0889)
		(layer "In2.Cu")
		(net "M_K_DQ<5>")
	)
	(segment
		(start 33.433004 -119.32539)
		(end 33.11652 -119.32539)
		(width 0.14224)
		(layer "In2.Cu")
		(net "M_K_DQ<5>")
	)
	(segment
		(start 32.967168 -119.474742)
		(end 32.967168 -120.029986)
		(width 0.14224)
		(layer "In2.Cu")
		(net "M_K_DQ<5>")
	)
	(segment
		(start 33.054544 -118.50751)
		(end 33.209484 -118.66245)
		(width 0.14224)
		(layer "In2.Cu")
		(net "M_K_DQ<5>")
	)
	(segment
		(start 31.824168 -133.959854)
		(end 31.824168 -134.187946)
		(width 0.14224)
		(layer "In2.Cu")
		(net "M_K_DQ<5>")
	)
	(segment
		(start 31.798768 -133.146546)
		(end 31.56077 -133.384544)
		(width 0.14224)
		(layer "In2.Cu")
		(net "M_K_DQ<5>")
	)
	(segment
		(start 31.722568 -131.318)
		(end 31.849568 -131.445)
		(width 0.14224)
		(layer "In2.Cu")
		(net "M_K_DQ<5>")
	)
	(segment
		(start 33.587944 -119.17045)
		(end 33.433004 -119.32539)
		(width 0.14224)
		(layer "In2.Cu")
		(net "M_K_DQ<5>")
	)
	(segment
		(start 33.706562 -117.50167)
		(end 33.706562 -117.85473)
		(width 0.14224)
		(layer "In2.Cu")
		(net "M_K_DQ<5>")
	)
	(segment
		(start 33.209484 -117.33657)
		(end 33.541462 -117.33657)
		(width 0.14224)
		(layer "In2.Cu")
		(net "M_K_DQ<5>")
	)
	(segment
		(start 33.054544 -116.846604)
		(end 33.054544 -117.18163)
		(width 0.14224)
		(layer "In2.Cu")
		(net "M_K_DQ<5>")
	)
	(segment
		(start 33.538668 -120.847866)
		(end 33.122108 -120.847866)
		(width 0.14224)
		(layer "In2.Cu")
		(net "M_K_DQ<5>")
	)
	(segment
		(start 31.56077 -132.308854)
		(end 31.56077 -132.646166)
		(width 0.14224)
		(layer "In2.Cu")
		(net "M_K_DQ<5>")
	)
	(segment
		(start 33.561782 -117.99951)
		(end 33.209484 -117.99951)
		(width 0.14224)
		(layer "In2.Cu")
		(net "M_K_DQ<5>")
	)
	(segment
		(start 33.706562 -117.85473)
		(end 33.561782 -117.99951)
		(width 0.14224)
		(layer "In2.Cu")
		(net "M_K_DQ<5>")
	)
	(segment
		(start 38.402768 -112.0902)
		(end 37.374576 -112.0902)
		(width 0.14224)
		(layer "In2.Cu")
		(net "M_K_DQ<5>")
	)
	(segment
		(start 33.433004 -118.66245)
		(end 33.587944 -118.81739)
		(width 0.14224)
		(layer "In2.Cu")
		(net "M_K_DQ<5>")
	)
	(segment
		(start 32.967168 -121.002806)
		(end 32.967168 -128.7526)
		(width 0.14224)
		(layer "In2.Cu")
		(net "M_K_DQ<5>")
	)
	(segment
		(start 32.55772 -129.162048)
		(end 32.55772 -129.9464)
		(width 0.14224)
		(layer "In2.Cu")
		(net "M_K_DQ<5>")
	)
	(segment
		(start 32.967168 -120.029986)
		(end 33.122108 -120.184926)
		(width 0.14224)
		(layer "In2.Cu")
		(net "M_K_DQ<5>")
	)
	(segment
		(start 33.3629 -116.101876)
		(end 33.054544 -116.846604)
		(width 0.14224)
		(layer "In2.Cu")
		(net "M_K_DQ<5>")
	)
	(segment
		(start 67.101466 -84.31784)
		(end 66.553842 -84.31784)
		(width 0.0889)
		(layer "In2.Cu")
		(net "M_K_DQ<5>")
	)
	(segment
		(start 33.054544 -118.15445)
		(end 33.054544 -118.50751)
		(width 0.14224)
		(layer "In2.Cu")
		(net "M_K_DQ<5>")
	)
	(segment
		(start 50.289968 -100.203)
		(end 38.402768 -112.0902)
		(width 0.14224)
		(layer "In2.Cu")
		(net "M_K_DQ<5>")
	)
	(segment
		(start 31.849568 -132.020056)
		(end 31.56077 -132.308854)
		(width 0.14224)
		(layer "In2.Cu")
		(net "M_K_DQ<5>")
	)
	(segment
		(start 31.56077 -132.646166)
		(end 31.798768 -132.884164)
		(width 0.14224)
		(layer "In2.Cu")
		(net "M_K_DQ<5>")
	)
	(segment
		(start 33.548828 -120.184926)
		(end 33.698688 -120.334786)
		(width 0.14224)
		(layer "In2.Cu")
		(net "M_K_DQ<5>")
	)
	(segment
		(start 31.56077 -133.384544)
		(end 31.56077 -133.696456)
		(width 0.14224)
		(layer "In2.Cu")
		(net "M_K_DQ<5>")
	)
	(segment
		(start 33.209484 -118.66245)
		(end 33.433004 -118.66245)
		(width 0.14224)
		(layer "In2.Cu")
		(net "M_K_DQ<5>")
	)
	(segment
		(start 33.698688 -120.687846)
		(end 33.538668 -120.847866)
		(width 0.14224)
		(layer "In2.Cu")
		(net "M_K_DQ<5>")
	)
	(segment
		(start 33.541462 -117.33657)
		(end 33.706562 -117.50167)
		(width 0.14224)
		(layer "In2.Cu")
		(net "M_K_DQ<5>")
	)
	(segment
		(start 31.849568 -131.445)
		(end 31.849568 -132.020056)
		(width 0.14224)
		(layer "In2.Cu")
		(net "M_K_DQ<5>")
	)
	(segment
		(start 66.458338 -84.413344)
		(end 65.845182 -84.413344)
		(width 0.0889)
		(layer "In2.Cu")
		(net "M_K_DQ<5>")
	)
	(segment
		(start 33.698688 -120.334786)
		(end 33.698688 -120.687846)
		(width 0.14224)
		(layer "In2.Cu")
		(net "M_K_DQ<5>")
	)
	(segment
		(start 125.080268 -101.471984)
		(end 125.651768 -101.471984)
		(width 0.1651)
		(layer "F.Cu")
		(net "M_K_DQ<59>")
	)
	(segment
		(start 150.399496 -133.0706)
		(end 150.399496 -134.340346)
		(width 0.1651)
		(layer "F.Cu")
		(net "M_K_DQ<59>")
	)
	(via
		(at 151.24938 -130.330956)
		(size 0.508)
		(drill 0.254)
		(layers "F.Cu" "B.Cu")
		(net "M_K_DQ<59>")
	)
	(via
		(at 150.399496 -134.340346)
		(size 0.508)
		(drill 0.254)
		(layers "F.Cu" "B.Cu")
		(net "M_K_DQ<59>")
	)
	(via
		(at 125.651768 -101.471984)
		(size 0.4826)
		(drill 0.254)
		(layers "F.Cu" "B.Cu")
		(net "M_K_DQ<59>")
	)
	(segment
		(start 151.24938 -128.276096)
		(end 151.24938 -130.330956)
		(width 0.1651)
		(layer "B.Cu")
		(net "M_K_DQ<59>")
	)
	(segment
		(start 131.342384 -104.2289)
		(end 132.497068 -104.2289)
		(width 0.0889)
		(layer "In2.Cu")
		(net "M_K_DQ<59>")
	)
	(segment
		(start 152.496012 -126.64313)
		(end 152.138634 -126.64313)
		(width 0.14224)
		(layer "In2.Cu")
		(net "M_K_DQ<59>")
	)
	(segment
		(start 132.497068 -104.2289)
		(end 132.712968 -104.013)
		(width 0.0889)
		(layer "In2.Cu")
		(net "M_K_DQ<59>")
	)
	(segment
		(start 151.227028 -130.330956)
		(end 150.798784 -130.7592)
		(width 0.14224)
		(layer "In2.Cu")
		(net "M_K_DQ<59>")
	)
	(segment
		(start 150.671784 -134.340346)
		(end 150.399496 -134.340346)
		(width 0.14224)
		(layer "In2.Cu")
		(net "M_K_DQ<59>")
	)
	(segment
		(start 134.363968 -104.013)
		(end 135.506968 -105.156)
		(width 0.14224)
		(layer "In2.Cu")
		(net "M_K_DQ<59>")
	)
	(segment
		(start 150.560786 -132.184648)
		(end 150.560786 -132.457952)
		(width 0.14224)
		(layer "In2.Cu")
		(net "M_K_DQ<59>")
	)
	(segment
		(start 150.817834 -133.0198)
		(end 150.560786 -133.276848)
		(width 0.14224)
		(layer "In2.Cu")
		(net "M_K_DQ<59>")
	)
	(segment
		(start 135.506968 -105.156)
		(end 138.44905 -105.156)
		(width 0.14224)
		(layer "In2.Cu")
		(net "M_K_DQ<59>")
	)
	(segment
		(start 129.881376 -102.767892)
		(end 131.342384 -104.2289)
		(width 0.0889)
		(layer "In2.Cu")
		(net "M_K_DQ<59>")
	)
	(segment
		(start 152.659334 -128.530858)
		(end 152.659334 -126.806452)
		(width 0.14224)
		(layer "In2.Cu")
		(net "M_K_DQ<59>")
	)
	(segment
		(start 152.823164 -128.694688)
		(end 152.659334 -128.530858)
		(width 0.14224)
		(layer "In2.Cu")
		(net "M_K_DQ<59>")
	)
	(segment
		(start 150.817834 -132.715)
		(end 150.817834 -133.0198)
		(width 0.14224)
		(layer "In2.Cu")
		(net "M_K_DQ<59>")
	)
	(segment
		(start 146.617944 -111.9378)
		(end 153.21026 -118.530116)
		(width 0.14224)
		(layer "In2.Cu")
		(net "M_K_DQ<59>")
	)
	(segment
		(start 152.659334 -126.806452)
		(end 152.496012 -126.64313)
		(width 0.14224)
		(layer "In2.Cu")
		(net "M_K_DQ<59>")
	)
	(segment
		(start 151.578564 -129.394204)
		(end 151.578564 -130.01498)
		(width 0.14224)
		(layer "In2.Cu")
		(net "M_K_DQ<59>")
	)
	(segment
		(start 138.44905 -105.156)
		(end 145.23085 -111.9378)
		(width 0.14224)
		(layer "In2.Cu")
		(net "M_K_DQ<59>")
	)
	(segment
		(start 151.24938 -130.344164)
		(end 151.24938 -130.330956)
		(width 0.14224)
		(layer "In2.Cu")
		(net "M_K_DQ<59>")
	)
	(segment
		(start 153.21026 -128.567688)
		(end 153.08326 -128.694688)
		(width 0.14224)
		(layer "In2.Cu")
		(net "M_K_DQ<59>")
	)
	(segment
		(start 150.798784 -130.7592)
		(end 150.798784 -131.188968)
		(width 0.14224)
		(layer "In2.Cu")
		(net "M_K_DQ<59>")
	)
	(segment
		(start 150.798784 -131.188968)
		(end 150.843234 -131.233418)
		(width 0.14224)
		(layer "In2.Cu")
		(net "M_K_DQ<59>")
	)
	(segment
		(start 132.712968 -104.013)
		(end 134.363968 -104.013)
		(width 0.14224)
		(layer "In2.Cu")
		(net "M_K_DQ<59>")
	)
	(segment
		(start 151.971248 -129.00152)
		(end 151.578564 -129.394204)
		(width 0.14224)
		(layer "In2.Cu")
		(net "M_K_DQ<59>")
	)
	(segment
		(start 150.849584 -134.162546)
		(end 150.671784 -134.340346)
		(width 0.14224)
		(layer "In2.Cu")
		(net "M_K_DQ<59>")
	)
	(segment
		(start 150.560786 -133.276848)
		(end 150.560786 -133.550152)
		(width 0.14224)
		(layer "In2.Cu")
		(net "M_K_DQ<59>")
	)
	(segment
		(start 125.651768 -101.471984)
		(end 126.029466 -101.849682)
		(width 0.0889)
		(layer "In2.Cu")
		(net "M_K_DQ<59>")
	)
	(segment
		(start 152.138634 -126.64313)
		(end 151.971248 -126.810516)
		(width 0.14224)
		(layer "In2.Cu")
		(net "M_K_DQ<59>")
	)
	(segment
		(start 153.21026 -118.530116)
		(end 153.21026 -128.567688)
		(width 0.14224)
		(layer "In2.Cu")
		(net "M_K_DQ<59>")
	)
	(segment
		(start 126.029466 -101.849682)
		(end 126.029466 -102.145846)
		(width 0.0889)
		(layer "In2.Cu")
		(net "M_K_DQ<59>")
	)
	(segment
		(start 150.843234 -131.9022)
		(end 150.560786 -132.184648)
		(width 0.14224)
		(layer "In2.Cu")
		(net "M_K_DQ<59>")
	)
	(segment
		(start 153.08326 -128.694688)
		(end 152.823164 -128.694688)
		(width 0.14224)
		(layer "In2.Cu")
		(net "M_K_DQ<59>")
	)
	(segment
		(start 151.971248 -126.810516)
		(end 151.971248 -129.00152)
		(width 0.14224)
		(layer "In2.Cu")
		(net "M_K_DQ<59>")
	)
	(segment
		(start 126.651512 -102.767892)
		(end 129.881376 -102.767892)
		(width 0.0889)
		(layer "In2.Cu")
		(net "M_K_DQ<59>")
	)
	(segment
		(start 150.560786 -132.457952)
		(end 150.817834 -132.715)
		(width 0.14224)
		(layer "In2.Cu")
		(net "M_K_DQ<59>")
	)
	(segment
		(start 150.849584 -133.83895)
		(end 150.849584 -134.162546)
		(width 0.14224)
		(layer "In2.Cu")
		(net "M_K_DQ<59>")
	)
	(segment
		(start 126.029466 -102.145846)
		(end 126.651512 -102.767892)
		(width 0.0889)
		(layer "In2.Cu")
		(net "M_K_DQ<59>")
	)
	(segment
		(start 145.23085 -111.9378)
		(end 146.617944 -111.9378)
		(width 0.14224)
		(layer "In2.Cu")
		(net "M_K_DQ<59>")
	)
	(segment
		(start 150.843234 -131.233418)
		(end 150.843234 -131.9022)
		(width 0.14224)
		(layer "In2.Cu")
		(net "M_K_DQ<59>")
	)
	(segment
		(start 151.578564 -130.01498)
		(end 151.24938 -130.344164)
		(width 0.14224)
		(layer "In2.Cu")
		(net "M_K_DQ<59>")
	)
	(segment
		(start 151.24938 -130.330956)
		(end 151.227028 -130.330956)
		(width 0.14224)
		(layer "In2.Cu")
		(net "M_K_DQ<59>")
	)
	(segment
		(start 150.560786 -133.550152)
		(end 150.849584 -133.83895)
		(width 0.14224)
		(layer "In2.Cu")
		(net "M_K_DQ<59>")
	)
	(segment
		(start 151.24938 -137.67054)
		(end 151.24938 -136.679432)
		(width 0.1651)
		(layer "F.Cu")
		(net "M_K_DQ<58>")
	)
	(segment
		(start 151.380952 -136.54786)
		(end 151.380952 -136.32434)
		(width 0.1651)
		(layer "F.Cu")
		(net "M_K_DQ<58>")
	)
	(segment
		(start 151.24938 -136.192768)
		(end 151.24938 -135.9154)
		(width 0.1651)
		(layer "F.Cu")
		(net "M_K_DQ<58>")
	)
	(segment
		(start 151.380952 -136.32434)
		(end 151.24938 -136.192768)
		(width 0.1651)
		(layer "F.Cu")
		(net "M_K_DQ<58>")
	)
	(segment
		(start 151.24938 -136.679432)
		(end 151.380952 -136.54786)
		(width 0.1651)
		(layer "F.Cu")
		(net "M_K_DQ<58>")
	)
	(segment
		(start 125.080268 -100.481638)
		(end 125.651768 -100.481638)
		(width 0.1651)
		(layer "F.Cu")
		(net "M_K_DQ<58>")
	)
	(via
		(at 150.399496 -131.611878)
		(size 0.508)
		(drill 0.254)
		(layers "F.Cu" "B.Cu")
		(net "M_K_DQ<58>")
	)
	(via
		(at 125.651768 -100.481638)
		(size 0.508)
		(drill 0.254)
		(layers "F.Cu" "B.Cu")
		(net "M_K_DQ<58>")
	)
	(via
		(at 151.24938 -135.9154)
		(size 0.508)
		(drill 0.254)
		(layers "F.Cu" "B.Cu")
		(net "M_K_DQ<58>")
	)
	(segment
		(start 150.399496 -132.876036)
		(end 150.399496 -131.611878)
		(width 0.1651)
		(layer "B.Cu")
		(net "M_K_DQ<58>")
	)
	(segment
		(start 132.484114 -104.4194)
		(end 132.712714 -104.648)
		(width 0.0889)
		(layer "In2.Cu")
		(net "M_K_DQ<58>")
	)
	(segment
		(start 125.447552 -101.01707)
		(end 125.300232 -101.280722)
		(width 0.0889)
		(layer "In2.Cu")
		(net "M_K_DQ<58>")
	)
	(segment
		(start 144.840706 -112.4458)
		(end 146.2278 -112.4458)
		(width 0.14224)
		(layer "In2.Cu")
		(net "M_K_DQ<58>")
	)
	(segment
		(start 135.363204 -105.6894)
		(end 138.084306 -105.6894)
		(width 0.14224)
		(layer "In2.Cu")
		(net "M_K_DQ<58>")
	)
	(segment
		(start 134.321804 -104.648)
		(end 135.363204 -105.6894)
		(width 0.14224)
		(layer "In2.Cu")
		(net "M_K_DQ<58>")
	)
	(segment
		(start 151.991568 -125.092968)
		(end 151.79675 -124.89815)
		(width 0.14224)
		(layer "In2.Cu")
		(net "M_K_DQ<58>")
	)
	(segment
		(start 125.895608 -102.281736)
		(end 126.572264 -102.958392)
		(width 0.0889)
		(layer "In2.Cu")
		(net "M_K_DQ<58>")
	)
	(segment
		(start 151.991568 -125.785372)
		(end 151.991568 -125.092968)
		(width 0.14224)
		(layer "In2.Cu")
		(net "M_K_DQ<58>")
	)
	(segment
		(start 125.341126 -101.728016)
		(end 125.894592 -102.281482)
		(width 0.0889)
		(layer "In2.Cu")
		(net "M_K_DQ<58>")
	)
	(segment
		(start 125.651768 -100.481638)
		(end 125.651768 -100.812854)
		(width 0.0889)
		(layer "In2.Cu")
		(net "M_K_DQ<58>")
	)
	(segment
		(start 151.178768 -128.9558)
		(end 150.918164 -129.216404)
		(width 0.14224)
		(layer "In2.Cu")
		(net "M_K_DQ<58>")
	)
	(segment
		(start 125.305058 -101.672136)
		(end 125.341126 -101.728016)
		(width 0.0889)
		(layer "In2.Cu")
		(net "M_K_DQ<58>")
	)
	(segment
		(start 125.651768 -100.812854)
		(end 125.447552 -101.01707)
		(width 0.0889)
		(layer "In2.Cu")
		(net "M_K_DQ<58>")
	)
	(segment
		(start 132.712714 -104.648)
		(end 134.321804 -104.648)
		(width 0.14224)
		(layer "In2.Cu")
		(net "M_K_DQ<58>")
	)
	(segment
		(start 125.894592 -102.281736)
		(end 125.895608 -102.281736)
		(width 0.0889)
		(layer "In2.Cu")
		(net "M_K_DQ<58>")
	)
	(segment
		(start 151.178768 -125.109732)
		(end 151.178768 -128.9558)
		(width 0.14224)
		(layer "In2.Cu")
		(net "M_K_DQ<58>")
	)
	(segment
		(start 131.263136 -104.4194)
		(end 132.484114 -104.4194)
		(width 0.0889)
		(layer "In2.Cu")
		(net "M_K_DQ<58>")
	)
	(segment
		(start 152.200356 -125.99416)
		(end 151.991568 -125.785372)
		(width 0.14224)
		(layer "In2.Cu")
		(net "M_K_DQ<58>")
	)
	(segment
		(start 152.597612 -125.99416)
		(end 152.200356 -125.99416)
		(width 0.14224)
		(layer "In2.Cu")
		(net "M_K_DQ<58>")
	)
	(segment
		(start 150.918164 -129.216404)
		(end 150.918164 -129.770378)
		(width 0.14224)
		(layer "In2.Cu")
		(net "M_K_DQ<58>")
	)
	(segment
		(start 125.894592 -102.281482)
		(end 125.894592 -102.281736)
		(width 0.0889)
		(layer "In2.Cu")
		(net "M_K_DQ<58>")
	)
	(segment
		(start 150.289768 -131.50215)
		(end 150.399496 -131.611878)
		(width 0.14224)
		(layer "In2.Cu")
		(net "M_K_DQ<58>")
	)
	(segment
		(start 146.2278 -112.4458)
		(end 152.742646 -118.960646)
		(width 0.14224)
		(layer "In2.Cu")
		(net "M_K_DQ<58>")
	)
	(segment
		(start 150.918164 -129.770378)
		(end 150.289768 -130.398774)
		(width 0.14224)
		(layer "In2.Cu")
		(net "M_K_DQ<58>")
	)
	(segment
		(start 151.39035 -124.89815)
		(end 151.178768 -125.109732)
		(width 0.14224)
		(layer "In2.Cu")
		(net "M_K_DQ<58>")
	)
	(segment
		(start 149.966426 -134.632446)
		(end 151.24938 -135.9154)
		(width 0.14224)
		(layer "In2.Cu")
		(net "M_K_DQ<58>")
	)
	(segment
		(start 151.79675 -124.89815)
		(end 151.39035 -124.89815)
		(width 0.14224)
		(layer "In2.Cu")
		(net "M_K_DQ<58>")
	)
	(segment
		(start 138.084306 -105.6894)
		(end 144.840706 -112.4458)
		(width 0.14224)
		(layer "In2.Cu")
		(net "M_K_DQ<58>")
	)
	(segment
		(start 152.742646 -125.849126)
		(end 152.597612 -125.99416)
		(width 0.14224)
		(layer "In2.Cu")
		(net "M_K_DQ<58>")
	)
	(segment
		(start 126.572264 -102.958392)
		(end 129.802128 -102.958392)
		(width 0.0889)
		(layer "In2.Cu")
		(net "M_K_DQ<58>")
	)
	(segment
		(start 149.966426 -132.044948)
		(end 149.966426 -134.632446)
		(width 0.14224)
		(layer "In2.Cu")
		(net "M_K_DQ<58>")
	)
	(segment
		(start 150.399496 -131.611878)
		(end 149.966426 -132.044948)
		(width 0.14224)
		(layer "In2.Cu")
		(net "M_K_DQ<58>")
	)
	(segment
		(start 129.802128 -102.958392)
		(end 131.263136 -104.4194)
		(width 0.0889)
		(layer "In2.Cu")
		(net "M_K_DQ<58>")
	)
	(segment
		(start 152.742646 -118.960646)
		(end 152.742646 -125.849126)
		(width 0.14224)
		(layer "In2.Cu")
		(net "M_K_DQ<58>")
	)
	(segment
		(start 150.289768 -130.398774)
		(end 150.289768 -131.50215)
		(width 0.14224)
		(layer "In2.Cu")
		(net "M_K_DQ<58>")
	)
	(arc
		(start 125.300232 -101.280722)
		(mid 125.251477 -101.477074)
		(end 125.305058 -101.672136)
		(width 0.0889)
		(layer "In2.Cu")
		(net "M_K_DQ<58>")
	)
	(segment
		(start 122.504708 -98.995738)
		(end 123.076208 -98.995738)
		(width 0.1651)
		(layer "F.Cu")
		(net "M_K_DQ<57>")
	)
	(segment
		(start 144.449546 -133.0706)
		(end 144.449546 -134.340346)
		(width 0.1651)
		(layer "F.Cu")
		(net "M_K_DQ<57>")
	)
	(via
		(at 145.12163 -130.330956)
		(size 0.508)
		(drill 0.254)
		(layers "F.Cu" "B.Cu")
		(net "M_K_DQ<57>")
	)
	(via
		(at 144.449546 -134.340346)
		(size 0.508)
		(drill 0.254)
		(layers "F.Cu" "B.Cu")
		(net "M_K_DQ<57>")
	)
	(via
		(at 123.076208 -98.995738)
		(size 0.4826)
		(drill 0.254)
		(layers "F.Cu" "B.Cu")
		(net "M_K_DQ<57>")
	)
	(segment
		(start 145.29943 -128.276096)
		(end 145.29943 -129.649982)
		(width 0.1651)
		(layer "B.Cu")
		(net "M_K_DQ<57>")
	)
	(segment
		(start 145.29943 -129.649982)
		(end 145.12163 -129.827782)
		(width 0.1651)
		(layer "B.Cu")
		(net "M_K_DQ<57>")
	)
	(segment
		(start 145.12163 -129.827782)
		(end 145.12163 -130.330956)
		(width 0.1651)
		(layer "B.Cu")
		(net "M_K_DQ<57>")
	)
	(segment
		(start 145.12163 -130.330956)
		(end 145.099278 -130.330956)
		(width 0.14224)
		(layer "In2.Cu")
		(net "M_K_DQ<57>")
	)
	(segment
		(start 146.270472 -119.383048)
		(end 146.270472 -119.119904)
		(width 0.14224)
		(layer "In2.Cu")
		(net "M_K_DQ<57>")
	)
	(segment
		(start 145.352008 -127.42672)
		(end 145.352008 -126.979426)
		(width 0.14224)
		(layer "In2.Cu")
		(net "M_K_DQ<57>")
	)
	(segment
		(start 145.455132 -125.15088)
		(end 146.5834 -125.15088)
		(width 0.14224)
		(layer "In2.Cu")
		(net "M_K_DQ<57>")
	)
	(segment
		(start 144.610836 -133.643624)
		(end 144.850612 -133.8834)
		(width 0.14224)
		(layer "In2.Cu")
		(net "M_K_DQ<57>")
	)
	(segment
		(start 122.676158 -103.193342)
		(end 122.676158 -102.79253)
		(width 0.0889)
		(layer "In2.Cu")
		(net "M_K_DQ<57>")
	)
	(segment
		(start 147.190968 -121.12625)
		(end 147.190968 -120.599454)
		(width 0.14224)
		(layer "In2.Cu")
		(net "M_K_DQ<57>")
	)
	(segment
		(start 144.671034 -130.7592)
		(end 144.671034 -131.188968)
		(width 0.14224)
		(layer "In2.Cu")
		(net "M_K_DQ<57>")
	)
	(segment
		(start 146.50593 -127.7366)
		(end 146.35099 -127.58166)
		(width 0.14224)
		(layer "In2.Cu")
		(net "M_K_DQ<57>")
	)
	(segment
		(start 144.610836 -132.475224)
		(end 144.825212 -132.6896)
		(width 0.14224)
		(layer "In2.Cu")
		(net "M_K_DQ<57>")
	)
	(segment
		(start 146.91995 -126.628652)
		(end 146.91995 -126.122176)
		(width 0.14224)
		(layer "In2.Cu")
		(net "M_K_DQ<57>")
	)
	(segment
		(start 146.5834 -125.15088)
		(end 146.904964 -124.829316)
		(width 0.14224)
		(layer "In2.Cu")
		(net "M_K_DQ<57>")
	)
	(segment
		(start 122.746262 -99.757484)
		(end 123.076208 -98.995738)
		(width 0.0889)
		(layer "In2.Cu")
		(net "M_K_DQ<57>")
	)
	(segment
		(start 146.904964 -121.412254)
		(end 147.190968 -121.12625)
		(width 0.14224)
		(layer "In2.Cu")
		(net "M_K_DQ<57>")
	)
	(segment
		(start 147.190968 -120.599454)
		(end 146.904964 -120.31345)
		(width 0.14224)
		(layer "In2.Cu")
		(net "M_K_DQ<57>")
	)
	(segment
		(start 126.048516 -106.5657)
		(end 122.676158 -103.193342)
		(width 0.0889)
		(layer "In2.Cu")
		(net "M_K_DQ<57>")
	)
	(segment
		(start 144.825212 -133.1214)
		(end 144.610836 -133.335776)
		(width 0.14224)
		(layer "In2.Cu")
		(net "M_K_DQ<57>")
	)
	(segment
		(start 126.353316 -106.5657)
		(end 126.048516 -106.5657)
		(width 0.0889)
		(layer "In2.Cu")
		(net "M_K_DQ<57>")
	)
	(segment
		(start 144.825212 -132.6896)
		(end 144.825212 -133.1214)
		(width 0.14224)
		(layer "In2.Cu")
		(net "M_K_DQ<57>")
	)
	(segment
		(start 146.35099 -127.58166)
		(end 145.506948 -127.58166)
		(width 0.14224)
		(layer "In2.Cu")
		(net "M_K_DQ<57>")
	)
	(segment
		(start 122.808238 -102.66045)
		(end 122.808238 -100.322888)
		(width 0.0889)
		(layer "In2.Cu")
		(net "M_K_DQ<57>")
	)
	(segment
		(start 144.901412 -131.419346)
		(end 144.901412 -131.823968)
		(width 0.14224)
		(layer "In2.Cu")
		(net "M_K_DQ<57>")
	)
	(segment
		(start 145.404078 -128.438656)
		(end 145.598134 -128.2446)
		(width 0.14224)
		(layer "In2.Cu")
		(net "M_K_DQ<57>")
	)
	(segment
		(start 145.257012 -125.75159)
		(end 145.257012 -125.349)
		(width 0.14224)
		(layer "In2.Cu")
		(net "M_K_DQ<57>")
	)
	(segment
		(start 128.812798 -107.55503)
		(end 127.342646 -107.55503)
		(width 0.14224)
		(layer "In2.Cu")
		(net "M_K_DQ<57>")
	)
	(segment
		(start 145.827242 -118.676674)
		(end 145.564098 -118.676674)
		(width 0.14224)
		(layer "In2.Cu")
		(net "M_K_DQ<57>")
	)
	(segment
		(start 144.850612 -133.8834)
		(end 144.850612 -134.1882)
		(width 0.14224)
		(layer "In2.Cu")
		(net "M_K_DQ<57>")
	)
	(segment
		(start 144.698466 -134.340346)
		(end 144.449546 -134.340346)
		(width 0.14224)
		(layer "In2.Cu")
		(net "M_K_DQ<57>")
	)
	(segment
		(start 145.506948 -127.58166)
		(end 145.352008 -127.42672)
		(width 0.14224)
		(layer "In2.Cu")
		(net "M_K_DQ<57>")
	)
	(segment
		(start 145.598134 -128.2446)
		(end 146.35099 -128.2446)
		(width 0.14224)
		(layer "In2.Cu")
		(net "M_K_DQ<57>")
	)
	(segment
		(start 146.270472 -119.119904)
		(end 145.827242 -118.676674)
		(width 0.14224)
		(layer "In2.Cu")
		(net "M_K_DQ<57>")
	)
	(segment
		(start 144.850612 -134.1882)
		(end 144.698466 -134.340346)
		(width 0.14224)
		(layer "In2.Cu")
		(net "M_K_DQ<57>")
	)
	(segment
		(start 145.099278 -130.330956)
		(end 144.671034 -130.7592)
		(width 0.14224)
		(layer "In2.Cu")
		(net "M_K_DQ<57>")
	)
	(segment
		(start 146.904964 -120.31345)
		(end 146.904964 -120.01754)
		(width 0.14224)
		(layer "In2.Cu")
		(net "M_K_DQ<57>")
	)
	(segment
		(start 127.342646 -107.55503)
		(end 126.353316 -106.5657)
		(width 0.14224)
		(layer "In2.Cu")
		(net "M_K_DQ<57>")
	)
	(segment
		(start 145.257012 -125.349)
		(end 145.455132 -125.15088)
		(width 0.14224)
		(layer "In2.Cu")
		(net "M_K_DQ<57>")
	)
	(segment
		(start 145.352008 -126.979426)
		(end 145.544032 -126.787402)
		(width 0.14224)
		(layer "In2.Cu")
		(net "M_K_DQ<57>")
	)
	(segment
		(start 146.772376 -125.974602)
		(end 145.480024 -125.974602)
		(width 0.14224)
		(layer "In2.Cu")
		(net "M_K_DQ<57>")
	)
	(segment
		(start 146.35099 -128.2446)
		(end 146.50593 -128.08966)
		(width 0.14224)
		(layer "In2.Cu")
		(net "M_K_DQ<57>")
	)
	(segment
		(start 146.91995 -126.122176)
		(end 146.772376 -125.974602)
		(width 0.14224)
		(layer "In2.Cu")
		(net "M_K_DQ<57>")
	)
	(segment
		(start 144.610836 -133.335776)
		(end 144.610836 -133.643624)
		(width 0.14224)
		(layer "In2.Cu")
		(net "M_K_DQ<57>")
	)
	(segment
		(start 122.729498 -99.786186)
		(end 122.746262 -99.757484)
		(width 0.0889)
		(layer "In2.Cu")
		(net "M_K_DQ<57>")
	)
	(segment
		(start 145.404078 -129.959608)
		(end 145.404078 -128.438656)
		(width 0.14224)
		(layer "In2.Cu")
		(net "M_K_DQ<57>")
	)
	(segment
		(start 145.12163 -130.242056)
		(end 145.404078 -129.959608)
		(width 0.14224)
		(layer "In2.Cu")
		(net "M_K_DQ<57>")
	)
	(segment
		(start 145.12163 -130.330956)
		(end 145.12163 -130.242056)
		(width 0.14224)
		(layer "In2.Cu")
		(net "M_K_DQ<57>")
	)
	(segment
		(start 146.904964 -120.01754)
		(end 146.270472 -119.383048)
		(width 0.14224)
		(layer "In2.Cu")
		(net "M_K_DQ<57>")
	)
	(segment
		(start 122.808238 -100.322888)
		(end 122.724672 -100.1776)
		(width 0.0889)
		(layer "In2.Cu")
		(net "M_K_DQ<57>")
	)
	(segment
		(start 145.544032 -126.787402)
		(end 146.7612 -126.787402)
		(width 0.14224)
		(layer "In2.Cu")
		(net "M_K_DQ<57>")
	)
	(segment
		(start 144.901412 -131.823968)
		(end 144.610836 -132.114544)
		(width 0.14224)
		(layer "In2.Cu")
		(net "M_K_DQ<57>")
	)
	(segment
		(start 145.564098 -118.676674)
		(end 135.675624 -108.7882)
		(width 0.14224)
		(layer "In2.Cu")
		(net "M_K_DQ<57>")
	)
	(segment
		(start 146.7612 -126.787402)
		(end 146.91995 -126.628652)
		(width 0.14224)
		(layer "In2.Cu")
		(net "M_K_DQ<57>")
	)
	(segment
		(start 135.675624 -108.7882)
		(end 130.045968 -108.7882)
		(width 0.14224)
		(layer "In2.Cu")
		(net "M_K_DQ<57>")
	)
	(segment
		(start 144.610836 -132.114544)
		(end 144.610836 -132.475224)
		(width 0.14224)
		(layer "In2.Cu")
		(net "M_K_DQ<57>")
	)
	(segment
		(start 130.045968 -108.7882)
		(end 128.812798 -107.55503)
		(width 0.14224)
		(layer "In2.Cu")
		(net "M_K_DQ<57>")
	)
	(segment
		(start 144.671034 -131.188968)
		(end 144.901412 -131.419346)
		(width 0.14224)
		(layer "In2.Cu")
		(net "M_K_DQ<57>")
	)
	(segment
		(start 146.904964 -124.829316)
		(end 146.904964 -121.412254)
		(width 0.14224)
		(layer "In2.Cu")
		(net "M_K_DQ<57>")
	)
	(segment
		(start 146.50593 -128.08966)
		(end 146.50593 -127.7366)
		(width 0.14224)
		(layer "In2.Cu")
		(net "M_K_DQ<57>")
	)
	(segment
		(start 122.676158 -102.79253)
		(end 122.808238 -102.66045)
		(width 0.0889)
		(layer "In2.Cu")
		(net "M_K_DQ<57>")
	)
	(segment
		(start 145.480024 -125.974602)
		(end 145.257012 -125.75159)
		(width 0.14224)
		(layer "In2.Cu")
		(net "M_K_DQ<57>")
	)
	(arc
		(start 122.724672 -100.1776)
		(mid 122.675917 -99.981248)
		(end 122.729498 -99.786186)
		(width 0.0889)
		(layer "In2.Cu")
		(net "M_K_DQ<57>")
	)
	(segment
		(start 145.29943 -137.67054)
		(end 145.29943 -137.676382)
		(width 0.1651)
		(layer "F.Cu")
		(net "M_K_DQ<56>")
	)
	(segment
		(start 145.29943 -137.676382)
		(end 145.12163 -135.8138)
		(width 0.1651)
		(layer "F.Cu")
		(net "M_K_DQ<56>")
	)
	(segment
		(start 122.504708 -97.014538)
		(end 123.076208 -97.014538)
		(width 0.1651)
		(layer "F.Cu")
		(net "M_K_DQ<56>")
	)
	(via
		(at 144.449546 -131.611878)
		(size 0.508)
		(drill 0.254)
		(layers "F.Cu" "B.Cu")
		(net "M_K_DQ<56>")
	)
	(via
		(at 145.12163 -135.8138)
		(size 0.508)
		(drill 0.254)
		(layers "F.Cu" "B.Cu")
		(net "M_K_DQ<56>")
	)
	(via
		(at 123.076208 -97.014538)
		(size 0.508)
		(drill 0.254)
		(layers "F.Cu" "B.Cu")
		(net "M_K_DQ<56>")
	)
	(segment
		(start 144.449546 -132.876036)
		(end 144.449546 -131.611878)
		(width 0.1651)
		(layer "B.Cu")
		(net "M_K_DQ<56>")
	)
	(segment
		(start 123.076208 -97.014538)
		(end 122.581162 -97.680272)
		(width 0.0889)
		(layer "In2.Cu")
		(net "M_K_DQ<56>")
	)
	(segment
		(start 144.644364 -124.0028)
		(end 144.644364 -129.076196)
		(width 0.14224)
		(layer "In2.Cu")
		(net "M_K_DQ<56>")
	)
	(segment
		(start 122.617738 -100.373942)
		(end 122.617738 -102.581456)
		(width 0.0889)
		(layer "In2.Cu")
		(net "M_K_DQ<56>")
	)
	(segment
		(start 144.092168 -131.2545)
		(end 144.449546 -131.611878)
		(width 0.14224)
		(layer "In2.Cu")
		(net "M_K_DQ<56>")
	)
	(segment
		(start 144.825466 -135.8138)
		(end 145.12163 -135.8138)
		(width 0.14224)
		(layer "In2.Cu")
		(net "M_K_DQ<56>")
	)
	(segment
		(start 145.253964 -123.7996)
		(end 144.847564 -123.7996)
		(width 0.14224)
		(layer "In2.Cu")
		(net "M_K_DQ<56>")
	)
	(segment
		(start 128.614424 -108.03382)
		(end 129.851404 -109.2708)
		(width 0.14224)
		(layer "In2.Cu")
		(net "M_K_DQ<56>")
	)
	(segment
		(start 122.564398 -98.300286)
		(end 122.569224 -98.308922)
		(width 0.0889)
		(layer "In2.Cu")
		(net "M_K_DQ<56>")
	)
	(segment
		(start 144.879568 -129.3114)
		(end 144.879568 -129.814574)
		(width 0.14224)
		(layer "In2.Cu")
		(net "M_K_DQ<56>")
	)
	(segment
		(start 145.457164 -124.0028)
		(end 145.253964 -123.7996)
		(width 0.14224)
		(layer "In2.Cu")
		(net "M_K_DQ<56>")
	)
	(segment
		(start 145.457164 -124.409962)
		(end 145.457164 -124.0028)
		(width 0.14224)
		(layer "In2.Cu")
		(net "M_K_DQ<56>")
	)
	(segment
		(start 144.092168 -130.601974)
		(end 144.092168 -131.2545)
		(width 0.14224)
		(layer "In2.Cu")
		(net "M_K_DQ<56>")
	)
	(segment
		(start 122.486166 -102.713028)
		(end 122.486166 -103.272844)
		(width 0.0889)
		(layer "In2.Cu")
		(net "M_K_DQ<56>")
	)
	(segment
		(start 126.992888 -108.03382)
		(end 128.614424 -108.03382)
		(width 0.14224)
		(layer "In2.Cu")
		(net "M_K_DQ<56>")
	)
	(segment
		(start 144.449546 -131.611878)
		(end 144.016476 -132.044948)
		(width 0.14224)
		(layer "In2.Cu")
		(net "M_K_DQ<56>")
	)
	(segment
		(start 122.581162 -97.680272)
		(end 122.564398 -97.709736)
		(width 0.0889)
		(layer "In2.Cu")
		(net "M_K_DQ<56>")
	)
	(segment
		(start 144.644364 -129.076196)
		(end 144.879568 -129.3114)
		(width 0.14224)
		(layer "In2.Cu")
		(net "M_K_DQ<56>")
	)
	(segment
		(start 122.558048 -100.270818)
		(end 122.617738 -100.373942)
		(width 0.0889)
		(layer "In2.Cu")
		(net "M_K_DQ<56>")
	)
	(segment
		(start 144.016476 -132.044948)
		(end 144.016476 -135.00481)
		(width 0.14224)
		(layer "In2.Cu")
		(net "M_K_DQ<56>")
	)
	(segment
		(start 135.26008 -109.2708)
		(end 146.269964 -120.280684)
		(width 0.14224)
		(layer "In2.Cu")
		(net "M_K_DQ<56>")
	)
	(segment
		(start 125.931168 -106.717846)
		(end 125.931168 -106.9721)
		(width 0.0889)
		(layer "In2.Cu")
		(net "M_K_DQ<56>")
	)
	(segment
		(start 122.617738 -102.581456)
		(end 122.486166 -102.713028)
		(width 0.0889)
		(layer "In2.Cu")
		(net "M_K_DQ<56>")
	)
	(segment
		(start 122.558048 -98.289618)
		(end 122.564398 -98.300286)
		(width 0.0889)
		(layer "In2.Cu")
		(net "M_K_DQ<56>")
	)
	(segment
		(start 122.564398 -99.290886)
		(end 122.569224 -99.299522)
		(width 0.0889)
		(layer "In2.Cu")
		(net "M_K_DQ<56>")
	)
	(segment
		(start 144.016476 -135.00481)
		(end 144.825466 -135.8138)
		(width 0.14224)
		(layer "In2.Cu")
		(net "M_K_DQ<56>")
	)
	(segment
		(start 122.486166 -103.272844)
		(end 125.931168 -106.717846)
		(width 0.0889)
		(layer "In2.Cu")
		(net "M_K_DQ<56>")
	)
	(segment
		(start 146.066764 -124.613162)
		(end 145.660364 -124.613162)
		(width 0.14224)
		(layer "In2.Cu")
		(net "M_K_DQ<56>")
	)
	(segment
		(start 146.269964 -124.409962)
		(end 146.066764 -124.613162)
		(width 0.14224)
		(layer "In2.Cu")
		(net "M_K_DQ<56>")
	)
	(segment
		(start 122.558048 -99.280218)
		(end 122.564398 -99.290886)
		(width 0.0889)
		(layer "In2.Cu")
		(net "M_K_DQ<56>")
	)
	(segment
		(start 144.879568 -129.814574)
		(end 144.092168 -130.601974)
		(width 0.14224)
		(layer "In2.Cu")
		(net "M_K_DQ<56>")
	)
	(segment
		(start 129.851404 -109.2708)
		(end 135.26008 -109.2708)
		(width 0.14224)
		(layer "In2.Cu")
		(net "M_K_DQ<56>")
	)
	(segment
		(start 144.847564 -123.7996)
		(end 144.644364 -124.0028)
		(width 0.14224)
		(layer "In2.Cu")
		(net "M_K_DQ<56>")
	)
	(segment
		(start 146.269964 -120.280684)
		(end 146.269964 -124.409962)
		(width 0.14224)
		(layer "In2.Cu")
		(net "M_K_DQ<56>")
	)
	(segment
		(start 125.931168 -106.9721)
		(end 126.992888 -108.03382)
		(width 0.14224)
		(layer "In2.Cu")
		(net "M_K_DQ<56>")
	)
	(segment
		(start 145.660364 -124.613162)
		(end 145.457164 -124.409962)
		(width 0.14224)
		(layer "In2.Cu")
		(net "M_K_DQ<56>")
	)
	(arc
		(start 122.564398 -97.709736)
		(mid 122.485176 -97.998854)
		(end 122.558048 -98.289618)
		(width 0.0889)
		(layer "In2.Cu")
		(net "M_K_DQ<56>")
	)
	(arc
		(start 122.564398 -98.700336)
		(mid 122.485176 -98.989454)
		(end 122.558048 -99.280218)
		(width 0.0889)
		(layer "In2.Cu")
		(net "M_K_DQ<56>")
	)
	(arc
		(start 122.564398 -99.690936)
		(mid 122.485176 -99.980054)
		(end 122.558048 -100.270818)
		(width 0.0889)
		(layer "In2.Cu")
		(net "M_K_DQ<56>")
	)
	(arc
		(start 122.569224 -98.308922)
		(mid 122.617979 -98.505274)
		(end 122.564398 -98.700336)
		(width 0.0889)
		(layer "In2.Cu")
		(net "M_K_DQ<56>")
	)
	(arc
		(start 122.569224 -99.299522)
		(mid 122.617979 -99.495874)
		(end 122.564398 -99.690936)
		(width 0.0889)
		(layer "In2.Cu")
		(net "M_K_DQ<56>")
	)
	(segment
		(start 139.34948 -133.0706)
		(end 139.34948 -134.340346)
		(width 0.1651)
		(layer "F.Cu")
		(net "M_K_DQ<55>")
	)
	(segment
		(start 119.070882 -98.995738)
		(end 119.642382 -98.995738)
		(width 0.1651)
		(layer "F.Cu")
		(net "M_K_DQ<55>")
	)
	(via
		(at 119.642382 -98.995738)
		(size 0.508)
		(drill 0.254)
		(layers "F.Cu" "B.Cu")
		(net "M_K_DQ<55>")
	)
	(via
		(at 140.199364 -130.330956)
		(size 0.508)
		(drill 0.254)
		(layers "F.Cu" "B.Cu")
		(net "M_K_DQ<55>")
	)
	(via
		(at 139.34948 -134.340346)
		(size 0.508)
		(drill 0.254)
		(layers "F.Cu" "B.Cu")
		(net "M_K_DQ<55>")
	)
	(segment
		(start 140.199364 -128.276096)
		(end 140.199364 -130.330956)
		(width 0.1651)
		(layer "B.Cu")
		(net "M_K_DQ<55>")
	)
	(segment
		(start 141.035278 -127.893318)
		(end 140.880338 -127.738378)
		(width 0.14224)
		(layer "In2.Cu")
		(net "M_K_DQ<55>")
	)
	(segment
		(start 140.589508 -127.738378)
		(end 140.397738 -127.546608)
		(width 0.14224)
		(layer "In2.Cu")
		(net "M_K_DQ<55>")
	)
	(segment
		(start 140.414502 -128.556004)
		(end 140.569188 -128.401318)
		(width 0.14224)
		(layer "In2.Cu")
		(net "M_K_DQ<55>")
	)
	(segment
		(start 140.199364 -130.330956)
		(end 140.414502 -130.115818)
		(width 0.14224)
		(layer "In2.Cu")
		(net "M_K_DQ<55>")
	)
	(segment
		(start 120.160542 -106.192066)
		(end 120.160542 -104.233218)
		(width 0.0889)
		(layer "In2.Cu")
		(net "M_K_DQ<55>")
	)
	(segment
		(start 139.799568 -133.83895)
		(end 139.799568 -134.162546)
		(width 0.14224)
		(layer "In2.Cu")
		(net "M_K_DQ<55>")
	)
	(segment
		(start 120.149366 -103.261922)
		(end 120.154192 -103.253286)
		(width 0.0889)
		(layer "In2.Cu")
		(net "M_K_DQ<55>")
	)
	(segment
		(start 132.401564 -114.337084)
		(end 132.048504 -114.337084)
		(width 0.14224)
		(layer "In2.Cu")
		(net "M_K_DQ<55>")
	)
	(segment
		(start 120.149366 -102.271322)
		(end 120.154192 -102.262686)
		(width 0.0889)
		(layer "In2.Cu")
		(net "M_K_DQ<55>")
	)
	(segment
		(start 133.374384 -114.337084)
		(end 133.219444 -114.182144)
		(width 0.14224)
		(layer "In2.Cu")
		(net "M_K_DQ<55>")
	)
	(segment
		(start 139.793218 -131.233418)
		(end 139.793218 -131.9022)
		(width 0.14224)
		(layer "In2.Cu")
		(net "M_K_DQ<55>")
	)
	(segment
		(start 131.738624 -113.65484)
		(end 131.168648 -113.65484)
		(width 0.14224)
		(layer "In2.Cu")
		(net "M_K_DQ<55>")
	)
	(segment
		(start 140.129768 -119.329454)
		(end 134.455154 -113.65484)
		(width 0.14224)
		(layer "In2.Cu")
		(net "M_K_DQ<55>")
	)
	(segment
		(start 120.137428 -99.661472)
		(end 119.642382 -98.995738)
		(width 0.0889)
		(layer "In2.Cu")
		(net "M_K_DQ<55>")
	)
	(segment
		(start 133.727444 -114.337084)
		(end 133.374384 -114.337084)
		(width 0.14224)
		(layer "In2.Cu")
		(net "M_K_DQ<55>")
	)
	(segment
		(start 140.397738 -127.546608)
		(end 140.397738 -125.69063)
		(width 0.14224)
		(layer "In2.Cu")
		(net "M_K_DQ<55>")
	)
	(segment
		(start 140.397738 -125.69063)
		(end 140.811758 -125.27661)
		(width 0.14224)
		(layer "In2.Cu")
		(net "M_K_DQ<55>")
	)
	(segment
		(start 133.219444 -113.80978)
		(end 133.064504 -113.65484)
		(width 0.14224)
		(layer "In2.Cu")
		(net "M_K_DQ<55>")
	)
	(segment
		(start 134.455154 -113.65484)
		(end 134.037324 -113.65484)
		(width 0.14224)
		(layer "In2.Cu")
		(net "M_K_DQ<55>")
	)
	(segment
		(start 139.767818 -132.715)
		(end 139.767818 -133.0198)
		(width 0.14224)
		(layer "In2.Cu")
		(net "M_K_DQ<55>")
	)
	(segment
		(start 139.51077 -133.276848)
		(end 139.51077 -133.550152)
		(width 0.14224)
		(layer "In2.Cu")
		(net "M_K_DQ<55>")
	)
	(segment
		(start 140.811758 -124.377958)
		(end 140.129768 -123.695968)
		(width 0.14224)
		(layer "In2.Cu")
		(net "M_K_DQ<55>")
	)
	(segment
		(start 120.149366 -101.280722)
		(end 120.154192 -101.272086)
		(width 0.0889)
		(layer "In2.Cu")
		(net "M_K_DQ<55>")
	)
	(segment
		(start 139.748768 -130.7592)
		(end 139.748768 -131.188968)
		(width 0.14224)
		(layer "In2.Cu")
		(net "M_K_DQ<55>")
	)
	(segment
		(start 140.569188 -128.401318)
		(end 140.880338 -128.401318)
		(width 0.14224)
		(layer "In2.Cu")
		(net "M_K_DQ<55>")
	)
	(segment
		(start 139.51077 -133.550152)
		(end 139.799568 -133.83895)
		(width 0.14224)
		(layer "In2.Cu")
		(net "M_K_DQ<55>")
	)
	(segment
		(start 140.129768 -123.695968)
		(end 140.129768 -119.329454)
		(width 0.14224)
		(layer "In2.Cu")
		(net "M_K_DQ<55>")
	)
	(segment
		(start 140.880338 -128.401318)
		(end 141.035278 -128.246378)
		(width 0.14224)
		(layer "In2.Cu")
		(net "M_K_DQ<55>")
	)
	(segment
		(start 133.882384 -114.182144)
		(end 133.727444 -114.337084)
		(width 0.14224)
		(layer "In2.Cu")
		(net "M_K_DQ<55>")
	)
	(segment
		(start 120.154192 -99.690936)
		(end 120.137428 -99.661472)
		(width 0.0889)
		(layer "In2.Cu")
		(net "M_K_DQ<55>")
	)
	(segment
		(start 139.51077 -132.184648)
		(end 139.51077 -132.457952)
		(width 0.14224)
		(layer "In2.Cu")
		(net "M_K_DQ<55>")
	)
	(segment
		(start 125.163834 -115.462304)
		(end 122.273568 -112.572038)
		(width 0.14224)
		(layer "In2.Cu")
		(net "M_K_DQ<55>")
	)
	(segment
		(start 133.064504 -113.65484)
		(end 132.711444 -113.65484)
		(width 0.14224)
		(layer "In2.Cu")
		(net "M_K_DQ<55>")
	)
	(segment
		(start 132.711444 -113.65484)
		(end 132.556504 -113.80978)
		(width 0.14224)
		(layer "In2.Cu")
		(net "M_K_DQ<55>")
	)
	(segment
		(start 120.154192 -103.253286)
		(end 120.160542 -103.242618)
		(width 0.0889)
		(layer "In2.Cu")
		(net "M_K_DQ<55>")
	)
	(segment
		(start 132.556504 -113.80978)
		(end 132.556504 -114.182144)
		(width 0.14224)
		(layer "In2.Cu")
		(net "M_K_DQ<55>")
	)
	(segment
		(start 131.893564 -113.80978)
		(end 131.738624 -113.65484)
		(width 0.14224)
		(layer "In2.Cu")
		(net "M_K_DQ<55>")
	)
	(segment
		(start 140.414502 -130.115818)
		(end 140.414502 -128.556004)
		(width 0.14224)
		(layer "In2.Cu")
		(net "M_K_DQ<55>")
	)
	(segment
		(start 139.621768 -134.340346)
		(end 139.34948 -134.340346)
		(width 0.14224)
		(layer "In2.Cu")
		(net "M_K_DQ<55>")
	)
	(segment
		(start 122.273568 -111.1504)
		(end 120.451372 -109.328204)
		(width 0.14224)
		(layer "In2.Cu")
		(net "M_K_DQ<55>")
	)
	(segment
		(start 122.273568 -112.572038)
		(end 122.273568 -111.1504)
		(width 0.14224)
		(layer "In2.Cu")
		(net "M_K_DQ<55>")
	)
	(segment
		(start 131.893564 -114.182144)
		(end 131.893564 -113.80978)
		(width 0.14224)
		(layer "In2.Cu")
		(net "M_K_DQ<55>")
	)
	(segment
		(start 140.199364 -130.330956)
		(end 140.177012 -130.330956)
		(width 0.14224)
		(layer "In2.Cu")
		(net "M_K_DQ<55>")
	)
	(segment
		(start 120.451372 -106.482896)
		(end 120.160542 -106.192066)
		(width 0.0889)
		(layer "In2.Cu")
		(net "M_K_DQ<55>")
	)
	(segment
		(start 139.748768 -131.188968)
		(end 139.793218 -131.233418)
		(width 0.14224)
		(layer "In2.Cu")
		(net "M_K_DQ<55>")
	)
	(segment
		(start 134.037324 -113.65484)
		(end 133.882384 -113.80978)
		(width 0.14224)
		(layer "In2.Cu")
		(net "M_K_DQ<55>")
	)
	(segment
		(start 139.767818 -133.0198)
		(end 139.51077 -133.276848)
		(width 0.14224)
		(layer "In2.Cu")
		(net "M_K_DQ<55>")
	)
	(segment
		(start 120.451372 -109.328204)
		(end 120.451372 -106.482896)
		(width 0.14224)
		(layer "In2.Cu")
		(net "M_K_DQ<55>")
	)
	(segment
		(start 141.035278 -128.246378)
		(end 141.035278 -127.893318)
		(width 0.14224)
		(layer "In2.Cu")
		(net "M_K_DQ<55>")
	)
	(segment
		(start 132.048504 -114.337084)
		(end 131.893564 -114.182144)
		(width 0.14224)
		(layer "In2.Cu")
		(net "M_K_DQ<55>")
	)
	(segment
		(start 140.811758 -125.27661)
		(end 140.811758 -124.377958)
		(width 0.14224)
		(layer "In2.Cu")
		(net "M_K_DQ<55>")
	)
	(segment
		(start 140.880338 -127.738378)
		(end 140.589508 -127.738378)
		(width 0.14224)
		(layer "In2.Cu")
		(net "M_K_DQ<55>")
	)
	(segment
		(start 133.882384 -113.80978)
		(end 133.882384 -114.182144)
		(width 0.14224)
		(layer "In2.Cu")
		(net "M_K_DQ<55>")
	)
	(segment
		(start 139.51077 -132.457952)
		(end 139.767818 -132.715)
		(width 0.14224)
		(layer "In2.Cu")
		(net "M_K_DQ<55>")
	)
	(segment
		(start 120.154192 -100.281486)
		(end 120.160542 -100.270818)
		(width 0.0889)
		(layer "In2.Cu")
		(net "M_K_DQ<55>")
	)
	(segment
		(start 131.168648 -113.65484)
		(end 129.361184 -115.462304)
		(width 0.14224)
		(layer "In2.Cu")
		(net "M_K_DQ<55>")
	)
	(segment
		(start 139.793218 -131.9022)
		(end 139.51077 -132.184648)
		(width 0.14224)
		(layer "In2.Cu")
		(net "M_K_DQ<55>")
	)
	(segment
		(start 139.799568 -134.162546)
		(end 139.621768 -134.340346)
		(width 0.14224)
		(layer "In2.Cu")
		(net "M_K_DQ<55>")
	)
	(segment
		(start 120.154192 -102.262686)
		(end 120.160542 -102.252018)
		(width 0.0889)
		(layer "In2.Cu")
		(net "M_K_DQ<55>")
	)
	(segment
		(start 132.556504 -114.182144)
		(end 132.401564 -114.337084)
		(width 0.14224)
		(layer "In2.Cu")
		(net "M_K_DQ<55>")
	)
	(segment
		(start 120.149366 -100.290122)
		(end 120.154192 -100.281486)
		(width 0.0889)
		(layer "In2.Cu")
		(net "M_K_DQ<55>")
	)
	(segment
		(start 133.219444 -114.182144)
		(end 133.219444 -113.80978)
		(width 0.14224)
		(layer "In2.Cu")
		(net "M_K_DQ<55>")
	)
	(segment
		(start 120.154192 -101.272086)
		(end 120.160542 -101.261418)
		(width 0.0889)
		(layer "In2.Cu")
		(net "M_K_DQ<55>")
	)
	(segment
		(start 140.177012 -130.330956)
		(end 139.748768 -130.7592)
		(width 0.14224)
		(layer "In2.Cu")
		(net "M_K_DQ<55>")
	)
	(segment
		(start 129.361184 -115.462304)
		(end 125.163834 -115.462304)
		(width 0.14224)
		(layer "In2.Cu")
		(net "M_K_DQ<55>")
	)
	(arc
		(start 120.154192 -101.672136)
		(mid 120.100722 -101.477073)
		(end 120.149366 -101.280722)
		(width 0.0889)
		(layer "In2.Cu")
		(net "M_K_DQ<55>")
	)
	(arc
		(start 120.154192 -103.653336)
		(mid 120.100722 -103.458273)
		(end 120.149366 -103.261922)
		(width 0.0889)
		(layer "In2.Cu")
		(net "M_K_DQ<55>")
	)
	(arc
		(start 120.160542 -102.252018)
		(mid 120.23334 -101.961255)
		(end 120.154192 -101.672136)
		(width 0.0889)
		(layer "In2.Cu")
		(net "M_K_DQ<55>")
	)
	(arc
		(start 120.154192 -100.681536)
		(mid 120.100722 -100.486473)
		(end 120.149366 -100.290122)
		(width 0.0889)
		(layer "In2.Cu")
		(net "M_K_DQ<55>")
	)
	(arc
		(start 120.160542 -100.270818)
		(mid 120.23334 -99.980055)
		(end 120.154192 -99.690936)
		(width 0.0889)
		(layer "In2.Cu")
		(net "M_K_DQ<55>")
	)
	(arc
		(start 120.160542 -103.242618)
		(mid 120.23334 -102.951855)
		(end 120.154192 -102.662736)
		(width 0.0889)
		(layer "In2.Cu")
		(net "M_K_DQ<55>")
	)
	(arc
		(start 120.160542 -101.261418)
		(mid 120.23334 -100.970655)
		(end 120.154192 -100.681536)
		(width 0.0889)
		(layer "In2.Cu")
		(net "M_K_DQ<55>")
	)
	(arc
		(start 120.154192 -102.662736)
		(mid 120.100722 -102.467673)
		(end 120.149366 -102.271322)
		(width 0.0889)
		(layer "In2.Cu")
		(net "M_K_DQ<55>")
	)
	(arc
		(start 120.160542 -104.233218)
		(mid 120.23334 -103.942455)
		(end 120.154192 -103.653336)
		(width 0.0889)
		(layer "In2.Cu")
		(net "M_K_DQ<55>")
	)
	(segment
		(start 140.199618 -136.7028)
		(end 140.199618 -137.67054)
		(width 0.1651)
		(layer "F.Cu")
		(net "M_K_DQ<54>")
	)
	(segment
		(start 140.331698 -136.57072)
		(end 140.199618 -136.7028)
		(width 0.1651)
		(layer "F.Cu")
		(net "M_K_DQ<54>")
	)
	(segment
		(start 140.331698 -136.35228)
		(end 140.331698 -136.57072)
		(width 0.1651)
		(layer "F.Cu")
		(net "M_K_DQ<54>")
	)
	(segment
		(start 119.070882 -97.014538)
		(end 119.642382 -97.014538)
		(width 0.1651)
		(layer "F.Cu")
		(net "M_K_DQ<54>")
	)
	(segment
		(start 140.199364 -135.9154)
		(end 140.199618 -135.915654)
		(width 0.1651)
		(layer "F.Cu")
		(net "M_K_DQ<54>")
	)
	(segment
		(start 140.199618 -135.915654)
		(end 140.199618 -136.2202)
		(width 0.1651)
		(layer "F.Cu")
		(net "M_K_DQ<54>")
	)
	(segment
		(start 140.199618 -137.67054)
		(end 140.199364 -137.67054)
		(width 0.1651)
		(layer "F.Cu")
		(net "M_K_DQ<54>")
	)
	(segment
		(start 140.199618 -136.2202)
		(end 140.331698 -136.35228)
		(width 0.1651)
		(layer "F.Cu")
		(net "M_K_DQ<54>")
	)
	(via
		(at 140.199364 -135.9154)
		(size 0.508)
		(drill 0.254)
		(layers "F.Cu" "B.Cu")
		(net "M_K_DQ<54>")
	)
	(via
		(at 119.642382 -97.014538)
		(size 0.508)
		(drill 0.254)
		(layers "F.Cu" "B.Cu")
		(net "M_K_DQ<54>")
	)
	(via
		(at 139.34948 -131.611878)
		(size 0.508)
		(drill 0.254)
		(layers "F.Cu" "B.Cu")
		(net "M_K_DQ<54>")
	)
	(segment
		(start 139.34948 -132.876036)
		(end 139.34948 -131.611878)
		(width 0.1651)
		(layer "B.Cu")
		(net "M_K_DQ<54>")
	)
	(segment
		(start 119.993918 -101.1682)
		(end 119.989092 -101.176836)
		(width 0.0889)
		(layer "In2.Cu")
		(net "M_K_DQ<54>")
	)
	(segment
		(start 121.740168 -111.7854)
		(end 121.740168 -112.715802)
		(width 0.14224)
		(layer "In2.Cu")
		(net "M_K_DQ<54>")
	)
	(segment
		(start 119.993918 -104.14)
		(end 119.970042 -104.182926)
		(width 0.0889)
		(layer "In2.Cu")
		(net "M_K_DQ<54>")
	)
	(segment
		(start 119.993918 -100.1776)
		(end 119.989092 -100.186236)
		(width 0.0889)
		(layer "In2.Cu")
		(net "M_K_DQ<54>")
	)
	(segment
		(start 138.91641 -132.044948)
		(end 138.91641 -134.632446)
		(width 0.14224)
		(layer "In2.Cu")
		(net "M_K_DQ<54>")
	)
	(segment
		(start 130.81 -114.862864)
		(end 134.697978 -114.862864)
		(width 0.14224)
		(layer "In2.Cu")
		(net "M_K_DQ<54>")
	)
	(segment
		(start 119.989092 -101.176836)
		(end 119.982742 -101.187504)
		(width 0.0889)
		(layer "In2.Cu")
		(net "M_K_DQ<54>")
	)
	(segment
		(start 139.875768 -129.77368)
		(end 139.18057 -130.468878)
		(width 0.14224)
		(layer "In2.Cu")
		(net "M_K_DQ<54>")
	)
	(segment
		(start 139.494768 -125.5014)
		(end 139.748768 -125.7554)
		(width 0.14224)
		(layer "In2.Cu")
		(net "M_K_DQ<54>")
	)
	(segment
		(start 119.993918 -103.1494)
		(end 119.989092 -103.158036)
		(width 0.0889)
		(layer "In2.Cu")
		(net "M_K_DQ<54>")
	)
	(segment
		(start 129.73177 -115.941094)
		(end 130.81 -114.862864)
		(width 0.14224)
		(layer "In2.Cu")
		(net "M_K_DQ<54>")
	)
	(segment
		(start 124.96546 -115.941094)
		(end 129.73177 -115.941094)
		(width 0.14224)
		(layer "In2.Cu")
		(net "M_K_DQ<54>")
	)
	(segment
		(start 119.359172 -99.278694)
		(end 119.368316 -99.287584)
		(width 0.0889)
		(layer "In2.Cu")
		(net "M_K_DQ<54>")
	)
	(segment
		(start 134.697978 -114.862864)
		(end 139.494768 -119.659654)
		(width 0.14224)
		(layer "In2.Cu")
		(net "M_K_DQ<54>")
	)
	(segment
		(start 119.803672 -106.271314)
		(end 119.803672 -109.848904)
		(width 0.14224)
		(layer "In2.Cu")
		(net "M_K_DQ<54>")
	)
	(segment
		(start 119.989092 -100.186236)
		(end 119.982742 -100.196904)
		(width 0.0889)
		(layer "In2.Cu")
		(net "M_K_DQ<54>")
	)
	(segment
		(start 119.970042 -106.104944)
		(end 119.803672 -106.271314)
		(width 0.0889)
		(layer "In2.Cu")
		(net "M_K_DQ<54>")
	)
	(segment
		(start 119.803672 -109.848904)
		(end 121.740168 -111.7854)
		(width 0.14224)
		(layer "In2.Cu")
		(net "M_K_DQ<54>")
	)
	(segment
		(start 121.740168 -112.715802)
		(end 124.96546 -115.941094)
		(width 0.14224)
		(layer "In2.Cu")
		(net "M_K_DQ<54>")
	)
	(segment
		(start 139.748768 -126.336806)
		(end 139.875768 -126.463806)
		(width 0.14224)
		(layer "In2.Cu")
		(net "M_K_DQ<54>")
	)
	(segment
		(start 139.18057 -130.468878)
		(end 139.18057 -131.442968)
		(width 0.14224)
		(layer "In2.Cu")
		(net "M_K_DQ<54>")
	)
	(segment
		(start 139.18057 -131.442968)
		(end 139.34948 -131.611878)
		(width 0.14224)
		(layer "In2.Cu")
		(net "M_K_DQ<54>")
	)
	(segment
		(start 119.989092 -102.167436)
		(end 119.982742 -102.178104)
		(width 0.0889)
		(layer "In2.Cu")
		(net "M_K_DQ<54>")
	)
	(segment
		(start 119.642382 -97.014538)
		(end 119.972328 -97.776284)
		(width 0.0889)
		(layer "In2.Cu")
		(net "M_K_DQ<54>")
	)
	(segment
		(start 138.91641 -134.632446)
		(end 140.199364 -135.9154)
		(width 0.14224)
		(layer "In2.Cu")
		(net "M_K_DQ<54>")
	)
	(segment
		(start 139.34948 -131.611878)
		(end 138.91641 -132.044948)
		(width 0.14224)
		(layer "In2.Cu")
		(net "M_K_DQ<54>")
	)
	(segment
		(start 119.989092 -103.158036)
		(end 119.982742 -103.168704)
		(width 0.0889)
		(layer "In2.Cu")
		(net "M_K_DQ<54>")
	)
	(segment
		(start 119.993918 -102.1588)
		(end 119.989092 -102.167436)
		(width 0.0889)
		(layer "In2.Cu")
		(net "M_K_DQ<54>")
	)
	(segment
		(start 119.970042 -104.182926)
		(end 119.970042 -106.104944)
		(width 0.0889)
		(layer "In2.Cu")
		(net "M_K_DQ<54>")
	)
	(segment
		(start 139.494768 -119.659654)
		(end 139.494768 -125.5014)
		(width 0.14224)
		(layer "In2.Cu")
		(net "M_K_DQ<54>")
	)
	(segment
		(start 119.972328 -97.776284)
		(end 119.989092 -97.804986)
		(width 0.0889)
		(layer "In2.Cu")
		(net "M_K_DQ<54>")
	)
	(segment
		(start 139.748768 -125.7554)
		(end 139.748768 -126.336806)
		(width 0.14224)
		(layer "In2.Cu")
		(net "M_K_DQ<54>")
	)
	(segment
		(start 139.875768 -126.463806)
		(end 139.875768 -129.77368)
		(width 0.14224)
		(layer "In2.Cu")
		(net "M_K_DQ<54>")
	)
	(arc
		(start 119.989092 -103.748586)
		(mid 120.042562 -103.943649)
		(end 119.993918 -104.14)
		(width 0.0889)
		(layer "In2.Cu")
		(net "M_K_DQ<54>")
	)
	(arc
		(start 119.982742 -103.168704)
		(mid 119.909944 -103.459467)
		(end 119.989092 -103.748586)
		(width 0.0889)
		(layer "In2.Cu")
		(net "M_K_DQ<54>")
	)
	(arc
		(start 119.989092 -97.804986)
		(mid 120.01736 -98.145352)
		(end 119.772684 -98.383598)
		(width 0.0889)
		(layer "In2.Cu")
		(net "M_K_DQ<54>")
	)
	(arc
		(start 119.989092 -101.767386)
		(mid 120.042562 -101.962449)
		(end 119.993918 -102.1588)
		(width 0.0889)
		(layer "In2.Cu")
		(net "M_K_DQ<54>")
	)
	(arc
		(start 119.982742 -102.178104)
		(mid 119.909944 -102.468867)
		(end 119.989092 -102.757986)
		(width 0.0889)
		(layer "In2.Cu")
		(net "M_K_DQ<54>")
	)
	(arc
		(start 119.989092 -102.757986)
		(mid 120.042562 -102.953049)
		(end 119.993918 -103.1494)
		(width 0.0889)
		(layer "In2.Cu")
		(net "M_K_DQ<54>")
	)
	(arc
		(start 119.888762 -99.671378)
		(mid 119.944357 -99.724032)
		(end 119.989092 -99.786186)
		(width 0.0889)
		(layer "In2.Cu")
		(net "M_K_DQ<54>")
	)
	(arc
		(start 119.368316 -99.287584)
		(mid 119.584919 -99.478566)
		(end 119.829072 -99.63277)
		(width 0.0889)
		(layer "In2.Cu")
		(net "M_K_DQ<54>")
	)
	(arc
		(start 119.829072 -99.63277)
		(mid 119.859776 -99.650746)
		(end 119.888762 -99.671378)
		(width 0.0889)
		(layer "In2.Cu")
		(net "M_K_DQ<54>")
	)
	(arc
		(start 119.772684 -98.383598)
		(mid 119.499403 -98.549325)
		(end 119.295672 -98.795586)
		(width 0.0889)
		(layer "In2.Cu")
		(net "M_K_DQ<54>")
	)
	(arc
		(start 119.295672 -98.795586)
		(mid 119.245428 -99.04791)
		(end 119.359172 -99.278694)
		(width 0.0889)
		(layer "In2.Cu")
		(net "M_K_DQ<54>")
	)
	(arc
		(start 119.989092 -100.776786)
		(mid 120.042562 -100.971849)
		(end 119.993918 -101.1682)
		(width 0.0889)
		(layer "In2.Cu")
		(net "M_K_DQ<54>")
	)
	(arc
		(start 119.982742 -100.196904)
		(mid 119.909944 -100.487667)
		(end 119.989092 -100.776786)
		(width 0.0889)
		(layer "In2.Cu")
		(net "M_K_DQ<54>")
	)
	(arc
		(start 119.989092 -99.786186)
		(mid 120.042562 -99.981249)
		(end 119.993918 -100.1776)
		(width 0.0889)
		(layer "In2.Cu")
		(net "M_K_DQ<54>")
	)
	(arc
		(start 119.982742 -101.187504)
		(mid 119.909944 -101.478267)
		(end 119.989092 -101.767386)
		(width 0.0889)
		(layer "In2.Cu")
		(net "M_K_DQ<54>")
	)
	(segment
		(start 133.39953 -133.0706)
		(end 133.39953 -134.340346)
		(width 0.1651)
		(layer "F.Cu")
		(net "M_K_DQ<53>")
	)
	(segment
		(start 116.495322 -98.500184)
		(end 117.066822 -98.500184)
		(width 0.1651)
		(layer "F.Cu")
		(net "M_K_DQ<53>")
	)
	(via
		(at 117.066822 -98.500184)
		(size 0.508)
		(drill 0.254)
		(layers "F.Cu" "B.Cu")
		(net "M_K_DQ<53>")
	)
	(via
		(at 134.173214 -130.330956)
		(size 0.508)
		(drill 0.254)
		(layers "F.Cu" "B.Cu")
		(net "M_K_DQ<53>")
	)
	(via
		(at 133.39953 -134.340346)
		(size 0.508)
		(drill 0.254)
		(layers "F.Cu" "B.Cu")
		(net "M_K_DQ<53>")
	)
	(segment
		(start 134.249414 -130.254756)
		(end 134.173214 -130.330956)
		(width 0.1651)
		(layer "B.Cu")
		(net "M_K_DQ<53>")
	)
	(segment
		(start 134.249414 -128.276096)
		(end 134.249414 -130.254756)
		(width 0.1651)
		(layer "B.Cu")
		(net "M_K_DQ<53>")
	)
	(segment
		(start 132.98424 -119.803164)
		(end 132.98424 -120.04548)
		(width 0.14224)
		(layer "In2.Cu")
		(net "M_K_DQ<53>")
	)
	(segment
		(start 118.399814 -113.541302)
		(end 118.399814 -113.76025)
		(width 0.14224)
		(layer "In2.Cu")
		(net "M_K_DQ<53>")
	)
	(segment
		(start 116.729002 -101.256846)
		(end 116.713254 -101.284278)
		(width 0.0889)
		(layer "In2.Cu")
		(net "M_K_DQ<53>")
	)
	(segment
		(start 133.56082 -132.553456)
		(end 133.798818 -132.791454)
		(width 0.14224)
		(layer "In2.Cu")
		(net "M_K_DQ<53>")
	)
	(segment
		(start 131.497832 -120.09501)
		(end 131.785106 -120.09501)
		(width 0.14224)
		(layer "In2.Cu")
		(net "M_K_DQ<53>")
	)
	(segment
		(start 134.637018 -123.233942)
		(end 134.637018 -125.50775)
		(width 0.14224)
		(layer "In2.Cu")
		(net "M_K_DQ<53>")
	)
	(segment
		(start 133.56082 -133.696456)
		(end 133.824218 -133.959854)
		(width 0.14224)
		(layer "In2.Cu")
		(net "M_K_DQ<53>")
	)
	(segment
		(start 117.939566 -114.537998)
		(end 122.995944 -119.594376)
		(width 0.14224)
		(layer "In2.Cu")
		(net "M_K_DQ<53>")
	)
	(segment
		(start 117.939566 -114.220498)
		(end 117.939566 -114.537998)
		(width 0.14224)
		(layer "In2.Cu")
		(net "M_K_DQ<53>")
	)
	(segment
		(start 130.997198 -119.594376)
		(end 131.497832 -120.09501)
		(width 0.14224)
		(layer "In2.Cu")
		(net "M_K_DQ<53>")
	)
	(segment
		(start 117.066568 -112.635538)
		(end 116.5606 -113.141506)
		(width 0.14224)
		(layer "In2.Cu")
		(net "M_K_DQ<53>")
	)
	(segment
		(start 116.666264 -102.462584)
		(end 116.666264 -103.459026)
		(width 0.0889)
		(layer "In2.Cu")
		(net "M_K_DQ<53>")
	)
	(segment
		(start 116.729002 -102.247446)
		(end 116.713254 -102.274878)
		(width 0.0889)
		(layer "In2.Cu")
		(net "M_K_DQ<53>")
	)
	(segment
		(start 116.5606 -113.141506)
		(end 116.5606 -113.337848)
		(width 0.14224)
		(layer "In2.Cu")
		(net "M_K_DQ<53>")
	)
	(segment
		(start 115.980972 -111.23168)
		(end 117.066568 -112.317276)
		(width 0.14224)
		(layer "In2.Cu")
		(net "M_K_DQ<53>")
	)
	(segment
		(start 117.231668 -113.778792)
		(end 117.825012 -113.185448)
		(width 0.14224)
		(layer "In2.Cu")
		(net "M_K_DQ<53>")
	)
	(segment
		(start 134.287768 -125.857)
		(end 134.287768 -127.3556)
		(width 0.14224)
		(layer "In2.Cu")
		(net "M_K_DQ<53>")
	)
	(segment
		(start 133.849618 -131.927346)
		(end 133.56082 -132.216144)
		(width 0.14224)
		(layer "In2.Cu")
		(net "M_K_DQ<53>")
	)
	(segment
		(start 134.637018 -125.50775)
		(end 134.287768 -125.857)
		(width 0.14224)
		(layer "In2.Cu")
		(net "M_K_DQ<53>")
	)
	(segment
		(start 122.995944 -119.594376)
		(end 130.997198 -119.594376)
		(width 0.14224)
		(layer "In2.Cu")
		(net "M_K_DQ<53>")
	)
	(segment
		(start 133.671818 -134.340346)
		(end 133.39953 -134.340346)
		(width 0.14224)
		(layer "In2.Cu")
		(net "M_K_DQ<53>")
	)
	(segment
		(start 131.785106 -120.09501)
		(end 132.380228 -119.499888)
		(width 0.14224)
		(layer "In2.Cu")
		(net "M_K_DQ<53>")
	)
	(segment
		(start 133.798818 -133.146546)
		(end 133.56082 -133.384544)
		(width 0.14224)
		(layer "In2.Cu")
		(net "M_K_DQ<53>")
	)
	(segment
		(start 134.363968 -130.140202)
		(end 134.173214 -130.330956)
		(width 0.14224)
		(layer "In2.Cu")
		(net "M_K_DQ<53>")
	)
	(segment
		(start 116.726462 -100.270818)
		(end 116.720112 -100.281486)
		(width 0.0889)
		(layer "In2.Cu")
		(net "M_K_DQ<53>")
	)
	(segment
		(start 135.227568 -128.364234)
		(end 135.227568 -128.770634)
		(width 0.14224)
		(layer "In2.Cu")
		(net "M_K_DQ<53>")
	)
	(segment
		(start 117.001544 -113.778792)
		(end 117.231668 -113.778792)
		(width 0.14224)
		(layer "In2.Cu")
		(net "M_K_DQ<53>")
	)
	(segment
		(start 133.56082 -133.384544)
		(end 133.56082 -133.696456)
		(width 0.14224)
		(layer "In2.Cu")
		(net "M_K_DQ<53>")
	)
	(segment
		(start 116.720112 -100.281486)
		(end 116.713254 -100.293678)
		(width 0.0889)
		(layer "In2.Cu")
		(net "M_K_DQ<53>")
	)
	(segment
		(start 115.980972 -105.335324)
		(end 115.980972 -111.23168)
		(width 0.14224)
		(layer "In2.Cu")
		(net "M_K_DQ<53>")
	)
	(segment
		(start 135.024368 -128.973834)
		(end 134.567168 -128.973834)
		(width 0.14224)
		(layer "In2.Cu")
		(net "M_K_DQ<53>")
	)
	(segment
		(start 135.227568 -128.770634)
		(end 135.024368 -128.973834)
		(width 0.14224)
		(layer "In2.Cu")
		(net "M_K_DQ<53>")
	)
	(segment
		(start 133.824218 -134.187946)
		(end 133.671818 -134.340346)
		(width 0.14224)
		(layer "In2.Cu")
		(net "M_K_DQ<53>")
	)
	(segment
		(start 135.024368 -128.161034)
		(end 135.227568 -128.364234)
		(width 0.14224)
		(layer "In2.Cu")
		(net "M_K_DQ<53>")
	)
	(segment
		(start 133.722618 -131.318)
		(end 133.849618 -131.445)
		(width 0.14224)
		(layer "In2.Cu")
		(net "M_K_DQ<53>")
	)
	(segment
		(start 115.751864 -105.106216)
		(end 115.980972 -105.335324)
		(width 0.0889)
		(layer "In2.Cu")
		(net "M_K_DQ<53>")
	)
	(segment
		(start 133.798818 -132.791454)
		(end 133.798818 -133.146546)
		(width 0.14224)
		(layer "In2.Cu")
		(net "M_K_DQ<53>")
	)
	(segment
		(start 134.567168 -128.973834)
		(end 134.363968 -129.177034)
		(width 0.14224)
		(layer "In2.Cu")
		(net "M_K_DQ<53>")
	)
	(segment
		(start 117.066568 -112.317276)
		(end 117.066568 -112.635538)
		(width 0.14224)
		(layer "In2.Cu")
		(net "M_K_DQ<53>")
	)
	(segment
		(start 133.56082 -132.216144)
		(end 133.56082 -132.553456)
		(width 0.14224)
		(layer "In2.Cu")
		(net "M_K_DQ<53>")
	)
	(segment
		(start 118.04396 -113.185448)
		(end 118.399814 -113.541302)
		(width 0.14224)
		(layer "In2.Cu")
		(net "M_K_DQ<53>")
	)
	(segment
		(start 132.380228 -119.499888)
		(end 132.680964 -119.499888)
		(width 0.14224)
		(layer "In2.Cu")
		(net "M_K_DQ<53>")
	)
	(segment
		(start 134.287768 -127.3556)
		(end 134.084568 -127.5588)
		(width 0.14224)
		(layer "In2.Cu")
		(net "M_K_DQ<53>")
	)
	(segment
		(start 132.359654 -120.670066)
		(end 132.359654 -120.956578)
		(width 0.14224)
		(layer "In2.Cu")
		(net "M_K_DQ<53>")
	)
	(segment
		(start 116.666264 -103.459026)
		(end 115.751864 -104.373426)
		(width 0.0889)
		(layer "In2.Cu")
		(net "M_K_DQ<53>")
	)
	(segment
		(start 117.825012 -113.185448)
		(end 118.04396 -113.185448)
		(width 0.14224)
		(layer "In2.Cu")
		(net "M_K_DQ<53>")
	)
	(segment
		(start 134.084568 -127.5588)
		(end 134.084568 -128.016)
		(width 0.14224)
		(layer "In2.Cu")
		(net "M_K_DQ<53>")
	)
	(segment
		(start 134.084568 -128.016)
		(end 134.229602 -128.161034)
		(width 0.14224)
		(layer "In2.Cu")
		(net "M_K_DQ<53>")
	)
	(segment
		(start 133.824218 -133.959854)
		(end 133.824218 -134.187946)
		(width 0.14224)
		(layer "In2.Cu")
		(net "M_K_DQ<53>")
	)
	(segment
		(start 133.849618 -131.445)
		(end 133.849618 -131.927346)
		(width 0.14224)
		(layer "In2.Cu")
		(net "M_K_DQ<53>")
	)
	(segment
		(start 116.713254 -102.274878)
		(end 116.713 -102.274878)
		(width 0.0889)
		(layer "In2.Cu")
		(net "M_K_DQ<53>")
	)
	(segment
		(start 134.363968 -129.177034)
		(end 134.363968 -130.140202)
		(width 0.14224)
		(layer "In2.Cu")
		(net "M_K_DQ<53>")
	)
	(segment
		(start 134.229602 -128.161034)
		(end 135.024368 -128.161034)
		(width 0.14224)
		(layer "In2.Cu")
		(net "M_K_DQ<53>")
	)
	(segment
		(start 133.722618 -130.7592)
		(end 133.722618 -131.318)
		(width 0.14224)
		(layer "In2.Cu")
		(net "M_K_DQ<53>")
	)
	(segment
		(start 116.5606 -113.337848)
		(end 117.001544 -113.778792)
		(width 0.14224)
		(layer "In2.Cu")
		(net "M_K_DQ<53>")
	)
	(segment
		(start 115.751864 -104.373426)
		(end 115.751864 -105.106216)
		(width 0.0889)
		(layer "In2.Cu")
		(net "M_K_DQ<53>")
	)
	(segment
		(start 134.150862 -130.330956)
		(end 133.722618 -130.7592)
		(width 0.14224)
		(layer "In2.Cu")
		(net "M_K_DQ<53>")
	)
	(segment
		(start 132.680964 -119.499888)
		(end 132.98424 -119.803164)
		(width 0.14224)
		(layer "In2.Cu")
		(net "M_K_DQ<53>")
	)
	(segment
		(start 134.173214 -130.330956)
		(end 134.150862 -130.330956)
		(width 0.14224)
		(layer "In2.Cu")
		(net "M_K_DQ<53>")
	)
	(segment
		(start 118.399814 -113.76025)
		(end 117.939566 -114.220498)
		(width 0.14224)
		(layer "In2.Cu")
		(net "M_K_DQ<53>")
	)
	(segment
		(start 132.359654 -120.956578)
		(end 134.637018 -123.233942)
		(width 0.14224)
		(layer "In2.Cu")
		(net "M_K_DQ<53>")
	)
	(segment
		(start 132.98424 -120.04548)
		(end 132.359654 -120.670066)
		(width 0.14224)
		(layer "In2.Cu")
		(net "M_K_DQ<53>")
	)
	(arc
		(start 117.066822 -98.500184)
		(mid 116.915267 -98.905465)
		(end 116.720112 -99.291648)
		(width 0.0889)
		(layer "In2.Cu")
		(net "M_K_DQ<53>")
	)
	(arc
		(start 116.720112 -101.671882)
		(mid 116.799301 -101.958497)
		(end 116.729002 -102.247446)
		(width 0.0889)
		(layer "In2.Cu")
		(net "M_K_DQ<53>")
	)
	(arc
		(start 116.713 -102.274878)
		(mid 116.678123 -102.365866)
		(end 116.666264 -102.462584)
		(width 0.0889)
		(layer "In2.Cu")
		(net "M_K_DQ<53>")
	)
	(arc
		(start 116.720112 -100.681282)
		(mid 116.799301 -100.967897)
		(end 116.729002 -101.256846)
		(width 0.0889)
		(layer "In2.Cu")
		(net "M_K_DQ<53>")
	)
	(arc
		(start 116.720112 -99.690936)
		(mid 116.799334 -99.980054)
		(end 116.726462 -100.270818)
		(width 0.0889)
		(layer "In2.Cu")
		(net "M_K_DQ<53>")
	)
	(arc
		(start 116.713254 -100.293678)
		(mid 116.666578 -100.488379)
		(end 116.720112 -100.681282)
		(width 0.0889)
		(layer "In2.Cu")
		(net "M_K_DQ<53>")
	)
	(arc
		(start 116.720112 -99.291648)
		(mid 116.668904 -99.448786)
		(end 116.685568 -99.613212)
		(width 0.0889)
		(layer "In2.Cu")
		(net "M_K_DQ<53>")
	)
	(arc
		(start 116.685568 -99.613212)
		(mid 116.700724 -99.653014)
		(end 116.720112 -99.690936)
		(width 0.0889)
		(layer "In2.Cu")
		(net "M_K_DQ<53>")
	)
	(arc
		(start 116.713254 -101.284278)
		(mid 116.666578 -101.478979)
		(end 116.720112 -101.671882)
		(width 0.0889)
		(layer "In2.Cu")
		(net "M_K_DQ<53>")
	)
	(segment
		(start 116.495322 -97.509584)
		(end 117.066822 -97.509584)
		(width 0.1651)
		(layer "F.Cu")
		(net "M_K_DQ<52>")
	)
	(segment
		(start 134.249414 -137.67054)
		(end 134.249414 -136.345168)
		(width 0.1651)
		(layer "F.Cu")
		(net "M_K_DQ<52>")
	)
	(segment
		(start 134.249414 -136.345168)
		(end 134.15137 -135.8138)
		(width 0.1651)
		(layer "F.Cu")
		(net "M_K_DQ<52>")
	)
	(via
		(at 134.15137 -135.8138)
		(size 0.508)
		(drill 0.254)
		(layers "F.Cu" "B.Cu")
		(net "M_K_DQ<52>")
	)
	(via
		(at 117.066822 -97.509584)
		(size 0.508)
		(drill 0.254)
		(layers "F.Cu" "B.Cu")
		(net "M_K_DQ<52>")
	)
	(via
		(at 133.39953 -131.611878)
		(size 0.508)
		(drill 0.254)
		(layers "F.Cu" "B.Cu")
		(net "M_K_DQ<52>")
	)
	(segment
		(start 133.39953 -132.876036)
		(end 133.39953 -131.611878)
		(width 0.1651)
		(layer "B.Cu")
		(net "M_K_DQ<52>")
	)
	(segment
		(start 119.130572 -117.658896)
		(end 119.417592 -117.658896)
		(width 0.14224)
		(layer "In2.Cu")
		(net "M_K_DQ<52>")
	)
	(segment
		(start 122.71629 -120.229376)
		(end 130.717544 -120.229376)
		(width 0.14224)
		(layer "In2.Cu")
		(net "M_K_DQ<52>")
	)
	(segment
		(start 119.417592 -117.658896)
		(end 119.638318 -117.438424)
		(width 0.14224)
		(layer "In2.Cu")
		(net "M_K_DQ<52>")
	)
	(segment
		(start 133.601968 -127.127)
		(end 133.601968 -129.057146)
		(width 0.14224)
		(layer "In2.Cu")
		(net "M_K_DQ<52>")
	)
	(segment
		(start 133.728968 -126.283466)
		(end 133.728968 -127)
		(width 0.14224)
		(layer "In2.Cu")
		(net "M_K_DQ<52>")
	)
	(segment
		(start 133.39953 -131.611878)
		(end 132.96646 -132.044948)
		(width 0.14224)
		(layer "In2.Cu")
		(net "M_K_DQ<52>")
	)
	(segment
		(start 133.28269 -131.495038)
		(end 133.39953 -131.611878)
		(width 0.14224)
		(layer "In2.Cu")
		(net "M_K_DQ<52>")
	)
	(segment
		(start 119.925338 -117.438424)
		(end 120.21312 -117.726206)
		(width 0.14224)
		(layer "In2.Cu")
		(net "M_K_DQ<52>")
	)
	(segment
		(start 116.56187 -102.15499)
		(end 116.546122 -102.182422)
		(width 0.0889)
		(layer "In2.Cu")
		(net "M_K_DQ<52>")
	)
	(segment
		(start 116.56187 -100.17379)
		(end 116.546122 -100.201222)
		(width 0.0889)
		(layer "In2.Cu")
		(net "M_K_DQ<52>")
	)
	(segment
		(start 115.333272 -105.342944)
		(end 115.333272 -112.846358)
		(width 0.14224)
		(layer "In2.Cu")
		(net "M_K_DQ<52>")
	)
	(segment
		(start 133.601968 -123.1138)
		(end 133.601968 -124.923804)
		(width 0.14224)
		(layer "In2.Cu")
		(net "M_K_DQ<52>")
	)
	(segment
		(start 121.141998 -119.670322)
		(end 121.42978 -119.958104)
		(width 0.14224)
		(layer "In2.Cu")
		(net "M_K_DQ<52>")
	)
	(segment
		(start 119.063516 -116.863622)
		(end 118.84279 -117.084094)
		(width 0.14224)
		(layer "In2.Cu")
		(net "M_K_DQ<52>")
	)
	(segment
		(start 132.96646 -132.044948)
		(end 132.96646 -134.57809)
		(width 0.14224)
		(layer "In2.Cu")
		(net "M_K_DQ<52>")
	)
	(segment
		(start 118.84279 -117.084094)
		(end 118.84279 -117.371114)
		(width 0.14224)
		(layer "In2.Cu")
		(net "M_K_DQ<52>")
	)
	(segment
		(start 120.567196 -118.8085)
		(end 120.787922 -118.588028)
		(width 0.14224)
		(layer "In2.Cu")
		(net "M_K_DQ<52>")
	)
	(segment
		(start 116.608352 -98.152204)
		(end 116.555012 -98.205544)
		(width 0.0889)
		(layer "In2.Cu")
		(net "M_K_DQ<52>")
	)
	(segment
		(start 133.900418 -135.8138)
		(end 134.15137 -135.8138)
		(width 0.14224)
		(layer "In2.Cu")
		(net "M_K_DQ<52>")
	)
	(segment
		(start 115.333272 -112.846358)
		(end 119.063516 -116.576602)
		(width 0.14224)
		(layer "In2.Cu")
		(net "M_K_DQ<52>")
	)
	(segment
		(start 122.224546 -119.737632)
		(end 122.71629 -120.229376)
		(width 0.14224)
		(layer "In2.Cu")
		(net "M_K_DQ<52>")
	)
	(segment
		(start 116.697252 -97.509584)
		(end 116.608352 -97.598484)
		(width 0.0889)
		(layer "In2.Cu")
		(net "M_K_DQ<52>")
	)
	(segment
		(start 121.7168 -119.958104)
		(end 121.937526 -119.737632)
		(width 0.14224)
		(layer "In2.Cu")
		(net "M_K_DQ<52>")
	)
	(segment
		(start 118.84279 -117.371114)
		(end 119.130572 -117.658896)
		(width 0.14224)
		(layer "In2.Cu")
		(net "M_K_DQ<52>")
	)
	(segment
		(start 133.858762 -129.31394)
		(end 133.858762 -129.846578)
		(width 0.14224)
		(layer "In2.Cu")
		(net "M_K_DQ<52>")
	)
	(segment
		(start 117.066822 -97.509584)
		(end 116.697252 -97.509584)
		(width 0.0889)
		(layer "In2.Cu")
		(net "M_K_DQ<52>")
	)
	(segment
		(start 133.728968 -127)
		(end 133.601968 -127.127)
		(width 0.14224)
		(layer "In2.Cu")
		(net "M_K_DQ<52>")
	)
	(segment
		(start 133.678168 -126.232666)
		(end 133.728968 -126.283466)
		(width 0.14224)
		(layer "In2.Cu")
		(net "M_K_DQ<52>")
	)
	(segment
		(start 133.124448 -134.736078)
		(end 133.124448 -135.03783)
		(width 0.14224)
		(layer "In2.Cu")
		(net "M_K_DQ<52>")
	)
	(segment
		(start 116.47551 -103.381048)
		(end 115.561364 -104.295194)
		(width 0.0889)
		(layer "In2.Cu")
		(net "M_K_DQ<52>")
	)
	(segment
		(start 121.141998 -119.383302)
		(end 121.141998 -119.670322)
		(width 0.14224)
		(layer "In2.Cu")
		(net "M_K_DQ<52>")
	)
	(segment
		(start 116.56187 -101.16439)
		(end 116.546122 -101.191822)
		(width 0.0889)
		(layer "In2.Cu")
		(net "M_K_DQ<52>")
	)
	(segment
		(start 121.362724 -119.16283)
		(end 121.141998 -119.383302)
		(width 0.14224)
		(layer "In2.Cu")
		(net "M_K_DQ<52>")
	)
	(segment
		(start 121.42978 -119.958104)
		(end 121.7168 -119.958104)
		(width 0.14224)
		(layer "In2.Cu")
		(net "M_K_DQ<52>")
	)
	(segment
		(start 133.601968 -124.923804)
		(end 133.678168 -125.000004)
		(width 0.14224)
		(layer "In2.Cu")
		(net "M_K_DQ<52>")
	)
	(segment
		(start 120.280176 -118.8085)
		(end 120.567196 -118.8085)
		(width 0.14224)
		(layer "In2.Cu")
		(net "M_K_DQ<52>")
	)
	(segment
		(start 119.638318 -117.438424)
		(end 119.925338 -117.438424)
		(width 0.14224)
		(layer "In2.Cu")
		(net "M_K_DQ<52>")
	)
	(segment
		(start 116.608352 -97.598484)
		(end 116.608352 -98.152204)
		(width 0.0889)
		(layer "In2.Cu")
		(net "M_K_DQ<52>")
	)
	(segment
		(start 133.124448 -135.03783)
		(end 133.900418 -135.8138)
		(width 0.14224)
		(layer "In2.Cu")
		(net "M_K_DQ<52>")
	)
	(segment
		(start 115.561364 -104.295194)
		(end 115.561364 -105.114852)
		(width 0.0889)
		(layer "In2.Cu")
		(net "M_K_DQ<52>")
	)
	(segment
		(start 133.601968 -129.057146)
		(end 133.858762 -129.31394)
		(width 0.14224)
		(layer "In2.Cu")
		(net "M_K_DQ<52>")
	)
	(segment
		(start 130.717544 -120.229376)
		(end 133.601968 -123.1138)
		(width 0.14224)
		(layer "In2.Cu")
		(net "M_K_DQ<52>")
	)
	(segment
		(start 132.96646 -134.57809)
		(end 133.124448 -134.736078)
		(width 0.14224)
		(layer "In2.Cu")
		(net "M_K_DQ<52>")
	)
	(segment
		(start 120.21312 -118.013226)
		(end 119.992394 -118.233698)
		(width 0.14224)
		(layer "In2.Cu")
		(net "M_K_DQ<52>")
	)
	(segment
		(start 121.362724 -118.87581)
		(end 121.362724 -119.16283)
		(width 0.14224)
		(layer "In2.Cu")
		(net "M_K_DQ<52>")
	)
	(segment
		(start 133.28269 -130.42265)
		(end 133.28269 -131.495038)
		(width 0.14224)
		(layer "In2.Cu")
		(net "M_K_DQ<52>")
	)
	(segment
		(start 119.063516 -116.576602)
		(end 119.063516 -116.863622)
		(width 0.14224)
		(layer "In2.Cu")
		(net "M_K_DQ<52>")
	)
	(segment
		(start 116.47551 -102.46233)
		(end 116.47551 -103.381048)
		(width 0.0889)
		(layer "In2.Cu")
		(net "M_K_DQ<52>")
	)
	(segment
		(start 121.937526 -119.737632)
		(end 122.224546 -119.737632)
		(width 0.14224)
		(layer "In2.Cu")
		(net "M_K_DQ<52>")
	)
	(segment
		(start 121.074942 -118.588028)
		(end 121.362724 -118.87581)
		(width 0.14224)
		(layer "In2.Cu")
		(net "M_K_DQ<52>")
	)
	(segment
		(start 133.678168 -125.000004)
		(end 133.678168 -126.232666)
		(width 0.14224)
		(layer "In2.Cu")
		(net "M_K_DQ<52>")
	)
	(segment
		(start 119.992394 -118.233698)
		(end 119.992394 -118.520718)
		(width 0.14224)
		(layer "In2.Cu")
		(net "M_K_DQ<52>")
	)
	(segment
		(start 120.787922 -118.588028)
		(end 121.074942 -118.588028)
		(width 0.14224)
		(layer "In2.Cu")
		(net "M_K_DQ<52>")
	)
	(segment
		(start 120.21312 -117.726206)
		(end 120.21312 -118.013226)
		(width 0.14224)
		(layer "In2.Cu")
		(net "M_K_DQ<52>")
	)
	(segment
		(start 133.858762 -129.846578)
		(end 133.28269 -130.42265)
		(width 0.14224)
		(layer "In2.Cu")
		(net "M_K_DQ<52>")
	)
	(segment
		(start 119.992394 -118.520718)
		(end 120.280176 -118.8085)
		(width 0.14224)
		(layer "In2.Cu")
		(net "M_K_DQ<52>")
	)
	(segment
		(start 115.561364 -105.114852)
		(end 115.333272 -105.342944)
		(width 0.0889)
		(layer "In2.Cu")
		(net "M_K_DQ<52>")
	)
	(arc
		(start 116.555012 -99.196144)
		(mid 116.479254 -99.428491)
		(end 116.503958 -99.671632)
		(width 0.0889)
		(layer "In2.Cu")
		(net "M_K_DQ<52>")
	)
	(arc
		(start 116.555012 -101.767386)
		(mid 116.60845 -101.960291)
		(end 116.56187 -102.15499)
		(width 0.0889)
		(layer "In2.Cu")
		(net "M_K_DQ<52>")
	)
	(arc
		(start 116.555012 -99.786186)
		(mid 116.60845 -99.979091)
		(end 116.56187 -100.17379)
		(width 0.0889)
		(layer "In2.Cu")
		(net "M_K_DQ<52>")
	)
	(arc
		(start 116.503958 -99.671632)
		(mid 116.526519 -99.73023)
		(end 116.555012 -99.786186)
		(width 0.0889)
		(layer "In2.Cu")
		(net "M_K_DQ<52>")
	)
	(arc
		(start 116.546122 -100.201222)
		(mid 116.475725 -100.490173)
		(end 116.555012 -100.776786)
		(width 0.0889)
		(layer "In2.Cu")
		(net "M_K_DQ<52>")
	)
	(arc
		(start 116.525294 -98.263964)
		(mid 116.476734 -98.533689)
		(end 116.555012 -98.796348)
		(width 0.0889)
		(layer "In2.Cu")
		(net "M_K_DQ<52>")
	)
	(arc
		(start 116.546122 -101.191822)
		(mid 116.475725 -101.480773)
		(end 116.555012 -101.767386)
		(width 0.0889)
		(layer "In2.Cu")
		(net "M_K_DQ<52>")
	)
	(arc
		(start 116.555012 -100.776786)
		(mid 116.60845 -100.969691)
		(end 116.56187 -101.16439)
		(width 0.0889)
		(layer "In2.Cu")
		(net "M_K_DQ<52>")
	)
	(arc
		(start 116.555012 -98.796348)
		(mid 116.608511 -98.996246)
		(end 116.555012 -99.196144)
		(width 0.0889)
		(layer "In2.Cu")
		(net "M_K_DQ<52>")
	)
	(arc
		(start 116.546122 -102.182422)
		(mid 116.493463 -102.317999)
		(end 116.47551 -102.46233)
		(width 0.0889)
		(layer "In2.Cu")
		(net "M_K_DQ<52>")
	)
	(arc
		(start 116.555012 -98.205544)
		(mid 116.539303 -98.234321)
		(end 116.525294 -98.263964)
		(width 0.0889)
		(layer "In2.Cu")
		(net "M_K_DQ<52>")
	)
	(segment
		(start 141.049502 -133.0706)
		(end 141.049502 -134.340346)
		(width 0.1651)
		(layer "F.Cu")
		(net "M_K_DQ<51>")
	)
	(segment
		(start 119.929402 -98.500184)
		(end 120.500902 -98.500184)
		(width 0.1651)
		(layer "F.Cu")
		(net "M_K_DQ<51>")
	)
	(via
		(at 120.500902 -98.500184)
		(size 0.508)
		(drill 0.254)
		(layers "F.Cu" "B.Cu")
		(net "M_K_DQ<51>")
	)
	(via
		(at 141.899386 -130.330956)
		(size 0.508)
		(drill 0.254)
		(layers "F.Cu" "B.Cu")
		(net "M_K_DQ<51>")
	)
	(via
		(at 141.049502 -134.340346)
		(size 0.508)
		(drill 0.254)
		(layers "F.Cu" "B.Cu")
		(net "M_K_DQ<51>")
	)
	(segment
		(start 141.899386 -128.276096)
		(end 141.899386 -130.330956)
		(width 0.1651)
		(layer "B.Cu")
		(net "M_K_DQ<51>")
	)
	(segment
		(start 141.44879 -131.188968)
		(end 141.49324 -131.233418)
		(width 0.14224)
		(layer "In2.Cu")
		(net "M_K_DQ<51>")
	)
	(segment
		(start 141.49324 -131.233418)
		(end 141.49324 -131.9022)
		(width 0.14224)
		(layer "In2.Cu")
		(net "M_K_DQ<51>")
	)
	(segment
		(start 121.816368 -108.5088)
		(end 123.727718 -110.42015)
		(width 0.14224)
		(layer "In2.Cu")
		(net "M_K_DQ<51>")
	)
	(segment
		(start 121.012712 -104.148636)
		(end 121.130314 -104.405938)
		(width 0.0889)
		(layer "In2.Cu")
		(net "M_K_DQ<51>")
	)
	(segment
		(start 130.661664 -112.6617)
		(end 131.811776 -112.6617)
		(width 0.14224)
		(layer "In2.Cu")
		(net "M_K_DQ<51>")
	)
	(segment
		(start 142.141702 -130.101848)
		(end 141.899386 -130.344164)
		(width 0.14224)
		(layer "In2.Cu")
		(net "M_K_DQ<51>")
	)
	(segment
		(start 141.399768 -118.745254)
		(end 141.399768 -123.16968)
		(width 0.14224)
		(layer "In2.Cu")
		(net "M_K_DQ<51>")
	)
	(segment
		(start 141.399768 -123.16968)
		(end 142.358364 -124.128276)
		(width 0.14224)
		(layer "In2.Cu")
		(net "M_K_DQ<51>")
	)
	(segment
		(start 141.49959 -133.83895)
		(end 141.49959 -134.162546)
		(width 0.14224)
		(layer "In2.Cu")
		(net "M_K_DQ<51>")
	)
	(segment
		(start 128.829816 -114.493548)
		(end 130.661664 -112.6617)
		(width 0.14224)
		(layer "In2.Cu")
		(net "M_K_DQ<51>")
	)
	(segment
		(start 141.899386 -130.330956)
		(end 141.877034 -130.330956)
		(width 0.14224)
		(layer "In2.Cu")
		(net "M_K_DQ<51>")
	)
	(segment
		(start 121.130314 -104.405938)
		(end 121.130314 -105.934256)
		(width 0.0889)
		(layer "In2.Cu")
		(net "M_K_DQ<51>")
	)
	(segment
		(start 141.46784 -132.715)
		(end 141.46784 -133.0198)
		(width 0.14224)
		(layer "In2.Cu")
		(net "M_K_DQ<51>")
	)
	(segment
		(start 131.966716 -112.1537)
		(end 132.121656 -111.99876)
		(width 0.14224)
		(layer "In2.Cu")
		(net "M_K_DQ<51>")
	)
	(segment
		(start 121.012712 -102.167436)
		(end 121.021602 -102.182676)
		(width 0.0889)
		(layer "In2.Cu")
		(net "M_K_DQ<51>")
	)
	(segment
		(start 142.358364 -126.2634)
		(end 142.141702 -126.480062)
		(width 0.14224)
		(layer "In2.Cu")
		(net "M_K_DQ<51>")
	)
	(segment
		(start 120.97893 -99.138486)
		(end 120.979692 -99.139756)
		(width 0.0889)
		(layer "In2.Cu")
		(net "M_K_DQ<51>")
	)
	(segment
		(start 121.012712 -103.158036)
		(end 121.021602 -103.173276)
		(width 0.0889)
		(layer "In2.Cu")
		(net "M_K_DQ<51>")
	)
	(segment
		(start 133.292596 -112.1537)
		(end 133.447536 -111.99876)
		(width 0.14224)
		(layer "In2.Cu")
		(net "M_K_DQ<51>")
	)
	(segment
		(start 133.800596 -111.99876)
		(end 133.955536 -112.1537)
		(width 0.14224)
		(layer "In2.Cu")
		(net "M_K_DQ<51>")
	)
	(segment
		(start 141.46784 -133.0198)
		(end 141.210792 -133.276848)
		(width 0.14224)
		(layer "In2.Cu")
		(net "M_K_DQ<51>")
	)
	(segment
		(start 141.44879 -130.7592)
		(end 141.44879 -131.188968)
		(width 0.14224)
		(layer "In2.Cu")
		(net "M_K_DQ<51>")
	)
	(segment
		(start 123.727718 -110.42015)
		(end 123.727718 -112.624362)
		(width 0.14224)
		(layer "In2.Cu")
		(net "M_K_DQ<51>")
	)
	(segment
		(start 121.689368 -106.242358)
		(end 121.816368 -106.369358)
		(width 0.14224)
		(layer "In2.Cu")
		(net "M_K_DQ<51>")
	)
	(segment
		(start 133.137656 -112.6617)
		(end 133.292596 -112.50676)
		(width 0.14224)
		(layer "In2.Cu")
		(net "M_K_DQ<51>")
	)
	(segment
		(start 141.877034 -130.330956)
		(end 141.44879 -130.7592)
		(width 0.14224)
		(layer "In2.Cu")
		(net "M_K_DQ<51>")
	)
	(segment
		(start 133.955536 -112.1537)
		(end 133.955536 -112.50676)
		(width 0.14224)
		(layer "In2.Cu")
		(net "M_K_DQ<51>")
	)
	(segment
		(start 141.210792 -133.276848)
		(end 141.210792 -133.550152)
		(width 0.14224)
		(layer "In2.Cu")
		(net "M_K_DQ<51>")
	)
	(segment
		(start 132.629656 -112.50676)
		(end 132.784596 -112.6617)
		(width 0.14224)
		(layer "In2.Cu")
		(net "M_K_DQ<51>")
	)
	(segment
		(start 133.292596 -112.50676)
		(end 133.292596 -112.1537)
		(width 0.14224)
		(layer "In2.Cu")
		(net "M_K_DQ<51>")
	)
	(segment
		(start 125.596904 -114.493548)
		(end 128.829816 -114.493548)
		(width 0.14224)
		(layer "In2.Cu")
		(net "M_K_DQ<51>")
	)
	(segment
		(start 121.438416 -106.242358)
		(end 121.689368 -106.242358)
		(width 0.0889)
		(layer "In2.Cu")
		(net "M_K_DQ<51>")
	)
	(segment
		(start 134.110476 -112.6617)
		(end 135.316214 -112.6617)
		(width 0.14224)
		(layer "In2.Cu")
		(net "M_K_DQ<51>")
	)
	(segment
		(start 121.012712 -101.176836)
		(end 121.021602 -101.192076)
		(width 0.0889)
		(layer "In2.Cu")
		(net "M_K_DQ<51>")
	)
	(segment
		(start 141.899386 -130.344164)
		(end 141.899386 -130.330956)
		(width 0.14224)
		(layer "In2.Cu")
		(net "M_K_DQ<51>")
	)
	(segment
		(start 132.784596 -112.6617)
		(end 133.137656 -112.6617)
		(width 0.14224)
		(layer "In2.Cu")
		(net "M_K_DQ<51>")
	)
	(segment
		(start 131.966716 -112.50676)
		(end 131.966716 -112.1537)
		(width 0.14224)
		(layer "In2.Cu")
		(net "M_K_DQ<51>")
	)
	(segment
		(start 133.447536 -111.99876)
		(end 133.800596 -111.99876)
		(width 0.14224)
		(layer "In2.Cu")
		(net "M_K_DQ<51>")
	)
	(segment
		(start 141.49324 -131.9022)
		(end 141.210792 -132.184648)
		(width 0.14224)
		(layer "In2.Cu")
		(net "M_K_DQ<51>")
	)
	(segment
		(start 132.629656 -112.1537)
		(end 132.629656 -112.50676)
		(width 0.14224)
		(layer "In2.Cu")
		(net "M_K_DQ<51>")
	)
	(segment
		(start 131.811776 -112.6617)
		(end 131.966716 -112.50676)
		(width 0.14224)
		(layer "In2.Cu")
		(net "M_K_DQ<51>")
	)
	(segment
		(start 135.316214 -112.6617)
		(end 141.399768 -118.745254)
		(width 0.14224)
		(layer "In2.Cu")
		(net "M_K_DQ<51>")
	)
	(segment
		(start 132.121656 -111.99876)
		(end 132.474716 -111.99876)
		(width 0.14224)
		(layer "In2.Cu")
		(net "M_K_DQ<51>")
	)
	(segment
		(start 141.210792 -132.457952)
		(end 141.46784 -132.715)
		(width 0.14224)
		(layer "In2.Cu")
		(net "M_K_DQ<51>")
	)
	(segment
		(start 141.32179 -134.340346)
		(end 141.049502 -134.340346)
		(width 0.14224)
		(layer "In2.Cu")
		(net "M_K_DQ<51>")
	)
	(segment
		(start 123.727718 -112.624362)
		(end 125.596904 -114.493548)
		(width 0.14224)
		(layer "In2.Cu")
		(net "M_K_DQ<51>")
	)
	(segment
		(start 141.49959 -134.162546)
		(end 141.32179 -134.340346)
		(width 0.14224)
		(layer "In2.Cu")
		(net "M_K_DQ<51>")
	)
	(segment
		(start 141.210792 -133.550152)
		(end 141.49959 -133.83895)
		(width 0.14224)
		(layer "In2.Cu")
		(net "M_K_DQ<51>")
	)
	(segment
		(start 133.955536 -112.50676)
		(end 134.110476 -112.6617)
		(width 0.14224)
		(layer "In2.Cu")
		(net "M_K_DQ<51>")
	)
	(segment
		(start 142.358364 -124.128276)
		(end 142.358364 -126.2634)
		(width 0.14224)
		(layer "In2.Cu")
		(net "M_K_DQ<51>")
	)
	(segment
		(start 142.141702 -126.480062)
		(end 142.141702 -130.101848)
		(width 0.14224)
		(layer "In2.Cu")
		(net "M_K_DQ<51>")
	)
	(segment
		(start 121.012712 -100.186236)
		(end 121.021602 -100.201476)
		(width 0.0889)
		(layer "In2.Cu")
		(net "M_K_DQ<51>")
	)
	(segment
		(start 121.130314 -105.934256)
		(end 121.438416 -106.242358)
		(width 0.0889)
		(layer "In2.Cu")
		(net "M_K_DQ<51>")
	)
	(segment
		(start 121.816368 -106.369358)
		(end 121.816368 -108.5088)
		(width 0.14224)
		(layer "In2.Cu")
		(net "M_K_DQ<51>")
	)
	(segment
		(start 132.474716 -111.99876)
		(end 132.629656 -112.1537)
		(width 0.14224)
		(layer "In2.Cu")
		(net "M_K_DQ<51>")
	)
	(segment
		(start 141.210792 -132.184648)
		(end 141.210792 -132.457952)
		(width 0.14224)
		(layer "In2.Cu")
		(net "M_K_DQ<51>")
	)
	(arc
		(start 121.012712 -100.77704)
		(mid 120.959179 -100.976938)
		(end 121.012712 -101.176836)
		(width 0.0889)
		(layer "In2.Cu")
		(net "M_K_DQ<51>")
	)
	(arc
		(start 120.979692 -99.139756)
		(mid 121.001324 -99.175046)
		(end 121.021602 -99.21113)
		(width 0.0889)
		(layer "In2.Cu")
		(net "M_K_DQ<51>")
	)
	(arc
		(start 121.021602 -102.182676)
		(mid 121.091999 -102.471627)
		(end 121.012712 -102.75824)
		(width 0.0889)
		(layer "In2.Cu")
		(net "M_K_DQ<51>")
	)
	(arc
		(start 121.021602 -103.173276)
		(mid 121.091999 -103.462227)
		(end 121.012712 -103.74884)
		(width 0.0889)
		(layer "In2.Cu")
		(net "M_K_DQ<51>")
	)
	(arc
		(start 121.012712 -99.78644)
		(mid 120.959179 -99.986338)
		(end 121.012712 -100.186236)
		(width 0.0889)
		(layer "In2.Cu")
		(net "M_K_DQ<51>")
	)
	(arc
		(start 120.500902 -98.500184)
		(mid 120.756216 -98.807127)
		(end 120.97893 -99.138486)
		(width 0.0889)
		(layer "In2.Cu")
		(net "M_K_DQ<51>")
	)
	(arc
		(start 121.021602 -101.192076)
		(mid 121.091999 -101.481027)
		(end 121.012712 -101.76764)
		(width 0.0889)
		(layer "In2.Cu")
		(net "M_K_DQ<51>")
	)
	(arc
		(start 121.012712 -101.76764)
		(mid 120.959179 -101.967538)
		(end 121.012712 -102.167436)
		(width 0.0889)
		(layer "In2.Cu")
		(net "M_K_DQ<51>")
	)
	(arc
		(start 121.021602 -100.201476)
		(mid 121.091999 -100.490427)
		(end 121.012712 -100.77704)
		(width 0.0889)
		(layer "In2.Cu")
		(net "M_K_DQ<51>")
	)
	(arc
		(start 121.021602 -99.21113)
		(mid 121.091907 -99.499937)
		(end 121.012712 -99.78644)
		(width 0.0889)
		(layer "In2.Cu")
		(net "M_K_DQ<51>")
	)
	(arc
		(start 121.012712 -102.75824)
		(mid 120.959179 -102.958138)
		(end 121.012712 -103.158036)
		(width 0.0889)
		(layer "In2.Cu")
		(net "M_K_DQ<51>")
	)
	(arc
		(start 121.012712 -103.74884)
		(mid 120.959179 -103.948738)
		(end 121.012712 -104.148636)
		(width 0.0889)
		(layer "In2.Cu")
		(net "M_K_DQ<51>")
	)
	(segment
		(start 141.899386 -137.67054)
		(end 141.899386 -136.679432)
		(width 0.1651)
		(layer "F.Cu")
		(net "M_K_DQ<50>")
	)
	(segment
		(start 119.929402 -97.509584)
		(end 120.500902 -97.509584)
		(width 0.1651)
		(layer "F.Cu")
		(net "M_K_DQ<50>")
	)
	(segment
		(start 142.030958 -136.32434)
		(end 141.899386 -136.192768)
		(width 0.1651)
		(layer "F.Cu")
		(net "M_K_DQ<50>")
	)
	(segment
		(start 141.899386 -136.192768)
		(end 141.899386 -135.9154)
		(width 0.1651)
		(layer "F.Cu")
		(net "M_K_DQ<50>")
	)
	(segment
		(start 141.899386 -136.679432)
		(end 142.030958 -136.54786)
		(width 0.1651)
		(layer "F.Cu")
		(net "M_K_DQ<50>")
	)
	(segment
		(start 142.030958 -136.54786)
		(end 142.030958 -136.32434)
		(width 0.1651)
		(layer "F.Cu")
		(net "M_K_DQ<50>")
	)
	(via
		(at 141.049502 -131.611878)
		(size 0.508)
		(drill 0.254)
		(layers "F.Cu" "B.Cu")
		(net "M_K_DQ<50>")
	)
	(via
		(at 141.899386 -135.9154)
		(size 0.508)
		(drill 0.254)
		(layers "F.Cu" "B.Cu")
		(net "M_K_DQ<50>")
	)
	(via
		(at 120.500902 -97.509584)
		(size 0.508)
		(drill 0.254)
		(layers "F.Cu" "B.Cu")
		(net "M_K_DQ<50>")
	)
	(segment
		(start 141.049502 -132.876036)
		(end 141.049502 -131.611878)
		(width 0.1651)
		(layer "B.Cu")
		(net "M_K_DQ<50>")
	)
	(segment
		(start 140.616432 -132.044948)
		(end 140.616432 -134.632446)
		(width 0.14224)
		(layer "In2.Cu")
		(net "M_K_DQ<50>")
	)
	(segment
		(start 121.288556 -106.714544)
		(end 121.288556 -109.073188)
		(width 0.14224)
		(layer "In2.Cu")
		(net "M_K_DQ<50>")
	)
	(segment
		(start 140.70457 -130.692398)
		(end 140.70457 -131.266946)
		(width 0.14224)
		(layer "In2.Cu")
		(net "M_K_DQ<50>")
	)
	(segment
		(start 120.37822 -98.881184)
		(end 120.403366 -98.89236)
		(width 0.0889)
		(layer "In2.Cu")
		(net "M_K_DQ<50>")
	)
	(segment
		(start 129.079498 -114.983514)
		(end 130.917188 -113.145824)
		(width 0.14224)
		(layer "In2.Cu")
		(net "M_K_DQ<50>")
	)
	(segment
		(start 120.500902 -97.509584)
		(end 120.171464 -98.270568)
		(width 0.0889)
		(layer "In2.Cu")
		(net "M_K_DQ<50>")
	)
	(segment
		(start 141.506702 -129.890266)
		(end 140.70457 -130.692398)
		(width 0.14224)
		(layer "In2.Cu")
		(net "M_K_DQ<50>")
	)
	(segment
		(start 120.838468 -103.238046)
		(end 120.847358 -103.253286)
		(width 0.0889)
		(layer "In2.Cu")
		(net "M_K_DQ<50>")
	)
	(segment
		(start 141.506702 -126.364746)
		(end 141.506702 -129.890266)
		(width 0.14224)
		(layer "In2.Cu")
		(net "M_K_DQ<50>")
	)
	(segment
		(start 120.838468 -100.266246)
		(end 120.847358 -100.281486)
		(width 0.0889)
		(layer "In2.Cu")
		(net "M_K_DQ<50>")
	)
	(segment
		(start 121.288556 -109.073188)
		(end 122.883168 -110.6678)
		(width 0.14224)
		(layer "In2.Cu")
		(net "M_K_DQ<50>")
	)
	(segment
		(start 120.838468 -104.228646)
		(end 120.939814 -104.449372)
		(width 0.0889)
		(layer "In2.Cu")
		(net "M_K_DQ<50>")
	)
	(segment
		(start 120.171464 -98.270568)
		(end 120.149366 -98.308922)
		(width 0.0889)
		(layer "In2.Cu")
		(net "M_K_DQ<50>")
	)
	(segment
		(start 141.049502 -131.611878)
		(end 140.616432 -132.044948)
		(width 0.14224)
		(layer "In2.Cu")
		(net "M_K_DQ<50>")
	)
	(segment
		(start 141.56817 -124.236226)
		(end 141.56817 -124.803408)
		(width 0.14224)
		(layer "In2.Cu")
		(net "M_K_DQ<50>")
	)
	(segment
		(start 140.764768 -123.432824)
		(end 141.56817 -124.236226)
		(width 0.14224)
		(layer "In2.Cu")
		(net "M_K_DQ<50>")
	)
	(segment
		(start 125.362208 -114.983514)
		(end 129.079498 -114.983514)
		(width 0.14224)
		(layer "In2.Cu")
		(net "M_K_DQ<50>")
	)
	(segment
		(start 120.939814 -104.449372)
		(end 120.939814 -106.012996)
		(width 0.0889)
		(layer "In2.Cu")
		(net "M_K_DQ<50>")
	)
	(segment
		(start 141.56817 -124.803408)
		(end 141.450568 -124.92101)
		(width 0.14224)
		(layer "In2.Cu")
		(net "M_K_DQ<50>")
	)
	(segment
		(start 141.450568 -124.92101)
		(end 141.450568 -126.308612)
		(width 0.14224)
		(layer "In2.Cu")
		(net "M_K_DQ<50>")
	)
	(segment
		(start 122.883168 -112.504474)
		(end 125.362208 -114.983514)
		(width 0.14224)
		(layer "In2.Cu")
		(net "M_K_DQ<50>")
	)
	(segment
		(start 141.450568 -126.308612)
		(end 141.506702 -126.364746)
		(width 0.14224)
		(layer "In2.Cu")
		(net "M_K_DQ<50>")
	)
	(segment
		(start 120.838468 -101.256846)
		(end 120.847358 -101.272086)
		(width 0.0889)
		(layer "In2.Cu")
		(net "M_K_DQ<50>")
	)
	(segment
		(start 122.883168 -110.6678)
		(end 122.883168 -112.504474)
		(width 0.14224)
		(layer "In2.Cu")
		(net "M_K_DQ<50>")
	)
	(segment
		(start 120.939814 -106.012996)
		(end 121.288556 -106.361738)
		(width 0.0889)
		(layer "In2.Cu")
		(net "M_K_DQ<50>")
	)
	(segment
		(start 134.860538 -113.145824)
		(end 140.764768 -119.050054)
		(width 0.14224)
		(layer "In2.Cu")
		(net "M_K_DQ<50>")
	)
	(segment
		(start 120.838468 -102.247446)
		(end 120.847358 -102.262686)
		(width 0.0889)
		(layer "In2.Cu")
		(net "M_K_DQ<50>")
	)
	(segment
		(start 140.764768 -119.050054)
		(end 140.764768 -123.432824)
		(width 0.14224)
		(layer "In2.Cu")
		(net "M_K_DQ<50>")
	)
	(segment
		(start 140.70457 -131.266946)
		(end 141.049502 -131.611878)
		(width 0.14224)
		(layer "In2.Cu")
		(net "M_K_DQ<50>")
	)
	(segment
		(start 130.917188 -113.145824)
		(end 134.860538 -113.145824)
		(width 0.14224)
		(layer "In2.Cu")
		(net "M_K_DQ<50>")
	)
	(segment
		(start 140.616432 -134.632446)
		(end 141.899386 -135.9154)
		(width 0.14224)
		(layer "In2.Cu")
		(net "M_K_DQ<50>")
	)
	(segment
		(start 121.288556 -106.361738)
		(end 121.288556 -106.714544)
		(width 0.0889)
		(layer "In2.Cu")
		(net "M_K_DQ<50>")
	)
	(arc
		(start 120.847358 -100.281486)
		(mid 120.900891 -100.481384)
		(end 120.847358 -100.681282)
		(width 0.0889)
		(layer "In2.Cu")
		(net "M_K_DQ<50>")
	)
	(arc
		(start 120.847358 -101.671882)
		(mid 120.768169 -101.958497)
		(end 120.838468 -102.247446)
		(width 0.0889)
		(layer "In2.Cu")
		(net "M_K_DQ<50>")
	)
	(arc
		(start 120.847358 -99.690682)
		(mid 120.768169 -99.977297)
		(end 120.838468 -100.266246)
		(width 0.0889)
		(layer "In2.Cu")
		(net "M_K_DQ<50>")
	)
	(arc
		(start 120.847358 -99.29114)
		(mid 120.900925 -99.490928)
		(end 120.847358 -99.690682)
		(width 0.0889)
		(layer "In2.Cu")
		(net "M_K_DQ<50>")
	)
	(arc
		(start 120.149366 -98.308922)
		(mid 120.129326 -98.648811)
		(end 120.37822 -98.881184)
		(width 0.0889)
		(layer "In2.Cu")
		(net "M_K_DQ<50>")
	)
	(arc
		(start 120.80494 -99.224592)
		(mid 120.826802 -99.25745)
		(end 120.847358 -99.29114)
		(width 0.0889)
		(layer "In2.Cu")
		(net "M_K_DQ<50>")
	)
	(arc
		(start 120.403366 -98.89236)
		(mid 120.626959 -99.030909)
		(end 120.80494 -99.224592)
		(width 0.0889)
		(layer "In2.Cu")
		(net "M_K_DQ<50>")
	)
	(arc
		(start 120.847358 -101.272086)
		(mid 120.900891 -101.471984)
		(end 120.847358 -101.671882)
		(width 0.0889)
		(layer "In2.Cu")
		(net "M_K_DQ<50>")
	)
	(arc
		(start 120.847358 -103.253286)
		(mid 120.900891 -103.453184)
		(end 120.847358 -103.653082)
		(width 0.0889)
		(layer "In2.Cu")
		(net "M_K_DQ<50>")
	)
	(arc
		(start 120.847358 -103.653082)
		(mid 120.768169 -103.939697)
		(end 120.838468 -104.228646)
		(width 0.0889)
		(layer "In2.Cu")
		(net "M_K_DQ<50>")
	)
	(arc
		(start 120.847358 -100.681282)
		(mid 120.768169 -100.967897)
		(end 120.838468 -101.256846)
		(width 0.0889)
		(layer "In2.Cu")
		(net "M_K_DQ<50>")
	)
	(arc
		(start 120.847358 -102.662482)
		(mid 120.768169 -102.949097)
		(end 120.838468 -103.238046)
		(width 0.0889)
		(layer "In2.Cu")
		(net "M_K_DQ<50>")
	)
	(arc
		(start 120.847358 -102.262686)
		(mid 120.900891 -102.462584)
		(end 120.847358 -102.662482)
		(width 0.0889)
		(layer "In2.Cu")
		(net "M_K_DQ<50>")
	)
	(segment
		(start 69.466206 -84.31784)
		(end 68.894706 -84.31784)
		(width 0.1651)
		(layer "F.Cu")
		(net "M_K_DQ<4>")
	)
	(segment
		(start 32.249364 -137.67054)
		(end 32.249364 -136.345168)
		(width 0.1651)
		(layer "F.Cu")
		(net "M_K_DQ<4>")
	)
	(segment
		(start 32.249364 -136.345168)
		(end 32.15132 -135.8138)
		(width 0.1651)
		(layer "F.Cu")
		(net "M_K_DQ<4>")
	)
	(via
		(at 31.39948 -131.611878)
		(size 0.508)
		(drill 0.254)
		(layers "F.Cu" "B.Cu")
		(net "M_K_DQ<4>")
	)
	(via
		(at 32.15132 -135.8138)
		(size 0.508)
		(drill 0.254)
		(layers "F.Cu" "B.Cu")
		(net "M_K_DQ<4>")
	)
	(via
		(at 68.894706 -84.31784)
		(size 0.508)
		(drill 0.254)
		(layers "F.Cu" "B.Cu")
		(net "M_K_DQ<4>")
	)
	(segment
		(start 31.39948 -132.876036)
		(end 31.39948 -131.611878)
		(width 0.1651)
		(layer "B.Cu")
		(net "M_K_DQ<4>")
	)
	(segment
		(start 31.242508 -131.454906)
		(end 31.39948 -131.611878)
		(width 0.14224)
		(layer "In2.Cu")
		(net "M_K_DQ<4>")
	)
	(segment
		(start 68.082922 -84.31784)
		(end 67.48399 -84.069682)
		(width 0.0889)
		(layer "In2.Cu")
		(net "M_K_DQ<4>")
	)
	(segment
		(start 32.476186 -116.9543)
		(end 32.476186 -128.205738)
		(width 0.14224)
		(layer "In2.Cu")
		(net "M_K_DQ<4>")
	)
	(segment
		(start 37.156136 -111.6076)
		(end 32.947864 -115.815872)
		(width 0.14224)
		(layer "In2.Cu")
		(net "M_K_DQ<4>")
	)
	(segment
		(start 32.476186 -128.205738)
		(end 31.784036 -129.877058)
		(width 0.14224)
		(layer "In2.Cu")
		(net "M_K_DQ<4>")
	)
	(segment
		(start 68.894706 -84.31784)
		(end 68.082922 -84.31784)
		(width 0.0889)
		(layer "In2.Cu")
		(net "M_K_DQ<4>")
	)
	(segment
		(start 67.297046 -83.882738)
		(end 65.817496 -83.882738)
		(width 0.0889)
		(layer "In2.Cu")
		(net "M_K_DQ<4>")
	)
	(segment
		(start 64.449706 -83.882738)
		(end 49.807368 -98.525076)
		(width 0.14224)
		(layer "In2.Cu")
		(net "M_K_DQ<4>")
	)
	(segment
		(start 32.947864 -115.815872)
		(end 32.476186 -116.9543)
		(width 0.14224)
		(layer "In2.Cu")
		(net "M_K_DQ<4>")
	)
	(segment
		(start 67.48399 -84.069682)
		(end 67.297046 -83.882738)
		(width 0.0889)
		(layer "In2.Cu")
		(net "M_K_DQ<4>")
	)
	(segment
		(start 30.96641 -132.657596)
		(end 30.96641 -134.436358)
		(width 0.14224)
		(layer "In2.Cu")
		(net "M_K_DQ<4>")
	)
	(segment
		(start 31.39948 -131.611878)
		(end 30.96641 -132.657596)
		(width 0.14224)
		(layer "In2.Cu")
		(net "M_K_DQ<4>")
	)
	(segment
		(start 49.807368 -99.9744)
		(end 38.174168 -111.6076)
		(width 0.14224)
		(layer "In2.Cu")
		(net "M_K_DQ<4>")
	)
	(segment
		(start 65.817496 -83.882738)
		(end 64.449706 -83.882738)
		(width 0.14224)
		(layer "In2.Cu")
		(net "M_K_DQ<4>")
	)
	(segment
		(start 38.174168 -111.6076)
		(end 37.156136 -111.6076)
		(width 0.14224)
		(layer "In2.Cu")
		(net "M_K_DQ<4>")
	)
	(segment
		(start 31.242508 -130.418586)
		(end 31.242508 -131.454906)
		(width 0.14224)
		(layer "In2.Cu")
		(net "M_K_DQ<4>")
	)
	(segment
		(start 31.784036 -129.877058)
		(end 31.242508 -130.418586)
		(width 0.14224)
		(layer "In2.Cu")
		(net "M_K_DQ<4>")
	)
	(segment
		(start 30.96641 -134.436358)
		(end 31.102554 -134.765034)
		(width 0.14224)
		(layer "In2.Cu")
		(net "M_K_DQ<4>")
	)
	(segment
		(start 49.807368 -98.525076)
		(end 49.807368 -99.9744)
		(width 0.14224)
		(layer "In2.Cu")
		(net "M_K_DQ<4>")
	)
	(segment
		(start 31.102554 -134.765034)
		(end 32.15132 -135.8138)
		(width 0.14224)
		(layer "In2.Cu")
		(net "M_K_DQ<4>")
	)
	(segment
		(start 135.099552 -133.0706)
		(end 135.099552 -134.340346)
		(width 0.1651)
		(layer "F.Cu")
		(net "M_K_DQ<49>")
	)
	(segment
		(start 117.353842 -98.995738)
		(end 117.925342 -98.995738)
		(width 0.1651)
		(layer "F.Cu")
		(net "M_K_DQ<49>")
	)
	(via
		(at 135.099552 -134.340346)
		(size 0.508)
		(drill 0.254)
		(layers "F.Cu" "B.Cu")
		(net "M_K_DQ<49>")
	)
	(via
		(at 117.925342 -98.995738)
		(size 0.508)
		(drill 0.254)
		(layers "F.Cu" "B.Cu")
		(net "M_K_DQ<49>")
	)
	(via
		(at 135.771636 -130.330956)
		(size 0.508)
		(drill 0.254)
		(layers "F.Cu" "B.Cu")
		(net "M_K_DQ<49>")
	)
	(segment
		(start 135.949436 -129.649982)
		(end 135.771636 -129.827782)
		(width 0.1651)
		(layer "B.Cu")
		(net "M_K_DQ<49>")
	)
	(segment
		(start 135.949436 -128.276096)
		(end 135.949436 -129.649982)
		(width 0.1651)
		(layer "B.Cu")
		(net "M_K_DQ<49>")
	)
	(segment
		(start 135.771636 -129.827782)
		(end 135.771636 -130.330956)
		(width 0.1651)
		(layer "B.Cu")
		(net "M_K_DQ<49>")
	)
	(segment
		(start 135.260842 -132.475224)
		(end 135.475218 -132.6896)
		(width 0.14224)
		(layer "In2.Cu")
		(net "M_K_DQ<49>")
	)
	(segment
		(start 134.508748 -120.326912)
		(end 134.221474 -120.614186)
		(width 0.14224)
		(layer "In2.Cu")
		(net "M_K_DQ<49>")
	)
	(segment
		(start 135.475218 -133.1214)
		(end 135.260842 -133.335776)
		(width 0.14224)
		(layer "In2.Cu")
		(net "M_K_DQ<49>")
	)
	(segment
		(start 117.014498 -105.271316)
		(end 117.276372 -105.53319)
		(width 0.0889)
		(layer "In2.Cu")
		(net "M_K_DQ<49>")
	)
	(segment
		(start 117.276372 -110.776004)
		(end 119.479568 -112.9792)
		(width 0.14224)
		(layer "In2.Cu")
		(net "M_K_DQ<49>")
	)
	(segment
		(start 135.551418 -131.419346)
		(end 135.551418 -131.823968)
		(width 0.14224)
		(layer "In2.Cu")
		(net "M_K_DQ<49>")
	)
	(segment
		(start 135.749284 -130.330956)
		(end 135.32104 -130.7592)
		(width 0.14224)
		(layer "In2.Cu")
		(net "M_K_DQ<49>")
	)
	(segment
		(start 136.522968 -127.762254)
		(end 136.522968 -129.1082)
		(width 0.14224)
		(layer "In2.Cu")
		(net "M_K_DQ<49>")
	)
	(segment
		(start 134.796276 -120.326912)
		(end 134.508748 -120.326912)
		(width 0.14224)
		(layer "In2.Cu")
		(net "M_K_DQ<49>")
	)
	(segment
		(start 135.500618 -134.1882)
		(end 135.348472 -134.340346)
		(width 0.14224)
		(layer "In2.Cu")
		(net "M_K_DQ<49>")
	)
	(segment
		(start 117.925342 -98.995738)
		(end 117.63248 -99.661472)
		(width 0.0889)
		(layer "In2.Cu")
		(net "M_K_DQ<49>")
	)
	(segment
		(start 119.479568 -112.9792)
		(end 119.479568 -114.0714)
		(width 0.14224)
		(layer "In2.Cu")
		(net "M_K_DQ<49>")
	)
	(segment
		(start 135.551418 -131.823968)
		(end 135.260842 -132.114544)
		(width 0.14224)
		(layer "In2.Cu")
		(net "M_K_DQ<49>")
	)
	(segment
		(start 117.276372 -105.53319)
		(end 117.276372 -110.776004)
		(width 0.14224)
		(layer "In2.Cu")
		(net "M_K_DQ<49>")
	)
	(segment
		(start 135.475218 -132.6896)
		(end 135.475218 -133.1214)
		(width 0.14224)
		(layer "In2.Cu")
		(net "M_K_DQ<49>")
	)
	(segment
		(start 136.522968 -129.1082)
		(end 136.25957 -129.371598)
		(width 0.14224)
		(layer "In2.Cu")
		(net "M_K_DQ<49>")
	)
	(segment
		(start 133.943344 -118.324376)
		(end 136.778238 -121.15927)
		(width 0.14224)
		(layer "In2.Cu")
		(net "M_K_DQ<49>")
	)
	(segment
		(start 123.732544 -118.324376)
		(end 133.943344 -118.324376)
		(width 0.14224)
		(layer "In2.Cu")
		(net "M_K_DQ<49>")
	)
	(segment
		(start 117.584982 -100.76561)
		(end 117.578632 -100.776278)
		(width 0.0889)
		(layer "In2.Cu")
		(net "M_K_DQ<49>")
	)
	(segment
		(start 117.578632 -102.166928)
		(end 117.584982 -102.177596)
		(width 0.0889)
		(layer "In2.Cu")
		(net "M_K_DQ<49>")
	)
	(segment
		(start 136.225788 -121.756424)
		(end 134.796276 -120.326912)
		(width 0.14224)
		(layer "In2.Cu")
		(net "M_K_DQ<49>")
	)
	(segment
		(start 135.260842 -133.643624)
		(end 135.500618 -133.8834)
		(width 0.14224)
		(layer "In2.Cu")
		(net "M_K_DQ<49>")
	)
	(segment
		(start 117.525038 -102.957884)
		(end 117.525038 -104.62006)
		(width 0.0889)
		(layer "In2.Cu")
		(net "M_K_DQ<49>")
	)
	(segment
		(start 136.25957 -129.754122)
		(end 135.771636 -130.242056)
		(width 0.14224)
		(layer "In2.Cu")
		(net "M_K_DQ<49>")
	)
	(segment
		(start 135.260842 -133.335776)
		(end 135.260842 -133.643624)
		(width 0.14224)
		(layer "In2.Cu")
		(net "M_K_DQ<49>")
	)
	(segment
		(start 117.014498 -105.1306)
		(end 117.014498 -105.271316)
		(width 0.0889)
		(layer "In2.Cu")
		(net "M_K_DQ<49>")
	)
	(segment
		(start 117.525038 -104.62006)
		(end 117.014498 -105.1306)
		(width 0.0889)
		(layer "In2.Cu")
		(net "M_K_DQ<49>")
	)
	(segment
		(start 117.578632 -100.776278)
		(end 117.573806 -100.784914)
		(width 0.0889)
		(layer "In2.Cu")
		(net "M_K_DQ<49>")
	)
	(segment
		(start 136.778238 -121.46915)
		(end 136.490964 -121.756424)
		(width 0.14224)
		(layer "In2.Cu")
		(net "M_K_DQ<49>")
	)
	(segment
		(start 134.221474 -120.901714)
		(end 136.25957 -122.93981)
		(width 0.14224)
		(layer "In2.Cu")
		(net "M_K_DQ<49>")
	)
	(segment
		(start 136.778238 -121.15927)
		(end 136.778238 -121.46915)
		(width 0.14224)
		(layer "In2.Cu")
		(net "M_K_DQ<49>")
	)
	(segment
		(start 135.260842 -132.114544)
		(end 135.260842 -132.475224)
		(width 0.14224)
		(layer "In2.Cu")
		(net "M_K_DQ<49>")
	)
	(segment
		(start 119.479568 -114.0714)
		(end 123.732544 -118.324376)
		(width 0.14224)
		(layer "In2.Cu")
		(net "M_K_DQ<49>")
	)
	(segment
		(start 135.771636 -130.330956)
		(end 135.749284 -130.330956)
		(width 0.14224)
		(layer "In2.Cu")
		(net "M_K_DQ<49>")
	)
	(segment
		(start 136.25957 -127.498856)
		(end 136.522968 -127.762254)
		(width 0.14224)
		(layer "In2.Cu")
		(net "M_K_DQ<49>")
	)
	(segment
		(start 135.32104 -130.7592)
		(end 135.32104 -131.188968)
		(width 0.14224)
		(layer "In2.Cu")
		(net "M_K_DQ<49>")
	)
	(segment
		(start 134.221474 -120.614186)
		(end 134.221474 -120.901714)
		(width 0.14224)
		(layer "In2.Cu")
		(net "M_K_DQ<49>")
	)
	(segment
		(start 135.500618 -133.8834)
		(end 135.500618 -134.1882)
		(width 0.14224)
		(layer "In2.Cu")
		(net "M_K_DQ<49>")
	)
	(segment
		(start 135.771636 -130.242056)
		(end 135.771636 -130.330956)
		(width 0.14224)
		(layer "In2.Cu")
		(net "M_K_DQ<49>")
	)
	(segment
		(start 136.25957 -129.371598)
		(end 136.25957 -129.754122)
		(width 0.14224)
		(layer "In2.Cu")
		(net "M_K_DQ<49>")
	)
	(segment
		(start 135.348472 -134.340346)
		(end 135.099552 -134.340346)
		(width 0.14224)
		(layer "In2.Cu")
		(net "M_K_DQ<49>")
	)
	(segment
		(start 135.32104 -131.188968)
		(end 135.551418 -131.419346)
		(width 0.14224)
		(layer "In2.Cu")
		(net "M_K_DQ<49>")
	)
	(segment
		(start 136.25957 -122.93981)
		(end 136.25957 -127.498856)
		(width 0.14224)
		(layer "In2.Cu")
		(net "M_K_DQ<49>")
	)
	(segment
		(start 136.490964 -121.756424)
		(end 136.225788 -121.756424)
		(width 0.14224)
		(layer "In2.Cu")
		(net "M_K_DQ<49>")
	)
	(arc
		(start 117.578632 -99.786186)
		(mid 117.526132 -99.962255)
		(end 117.557296 -100.14331)
		(width 0.0889)
		(layer "In2.Cu")
		(net "M_K_DQ<49>")
	)
	(arc
		(start 117.63248 -99.661472)
		(mid 117.60916 -99.725386)
		(end 117.578632 -99.786186)
		(width 0.0889)
		(layer "In2.Cu")
		(net "M_K_DQ<49>")
	)
	(arc
		(start 117.578632 -101.176328)
		(mid 117.657763 -101.47173)
		(end 117.578632 -101.767132)
		(width 0.0889)
		(layer "In2.Cu")
		(net "M_K_DQ<49>")
	)
	(arc
		(start 117.578632 -102.757986)
		(mid 117.538678 -102.85441)
		(end 117.525038 -102.957884)
		(width 0.0889)
		(layer "In2.Cu")
		(net "M_K_DQ<49>")
	)
	(arc
		(start 117.573806 -100.784914)
		(mid 117.525051 -100.981266)
		(end 117.578632 -101.176328)
		(width 0.0889)
		(layer "In2.Cu")
		(net "M_K_DQ<49>")
	)
	(arc
		(start 117.578632 -100.185728)
		(mid 117.657854 -100.474846)
		(end 117.584982 -100.76561)
		(width 0.0889)
		(layer "In2.Cu")
		(net "M_K_DQ<49>")
	)
	(arc
		(start 117.584982 -102.177596)
		(mid 117.657902 -102.468613)
		(end 117.578632 -102.757986)
		(width 0.0889)
		(layer "In2.Cu")
		(net "M_K_DQ<49>")
	)
	(arc
		(start 117.557296 -100.14331)
		(mid 117.567261 -100.164873)
		(end 117.578632 -100.185728)
		(width 0.0889)
		(layer "In2.Cu")
		(net "M_K_DQ<49>")
	)
	(arc
		(start 117.578632 -101.767132)
		(mid 117.525133 -101.96703)
		(end 117.578632 -102.166928)
		(width 0.0889)
		(layer "In2.Cu")
		(net "M_K_DQ<49>")
	)
	(segment
		(start 117.353842 -97.014538)
		(end 117.925342 -97.014538)
		(width 0.1651)
		(layer "F.Cu")
		(net "M_K_DQ<48>")
	)
	(segment
		(start 135.949436 -137.67054)
		(end 135.949436 -137.676382)
		(width 0.1651)
		(layer "F.Cu")
		(net "M_K_DQ<48>")
	)
	(segment
		(start 135.949436 -137.676382)
		(end 135.771636 -135.8138)
		(width 0.1651)
		(layer "F.Cu")
		(net "M_K_DQ<48>")
	)
	(via
		(at 117.925342 -97.014538)
		(size 0.508)
		(drill 0.254)
		(layers "F.Cu" "B.Cu")
		(net "M_K_DQ<48>")
	)
	(via
		(at 135.771636 -135.8138)
		(size 0.508)
		(drill 0.254)
		(layers "F.Cu" "B.Cu")
		(net "M_K_DQ<48>")
	)
	(via
		(at 135.099552 -131.611878)
		(size 0.508)
		(drill 0.254)
		(layers "F.Cu" "B.Cu")
		(net "M_K_DQ<48>")
	)
	(segment
		(start 135.099552 -132.876036)
		(end 135.099552 -131.611878)
		(width 0.1651)
		(layer "B.Cu")
		(net "M_K_DQ<48>")
	)
	(segment
		(start 116.628672 -105.5243)
		(end 116.628672 -110.941358)
		(width 0.14224)
		(layer "In2.Cu")
		(net "M_K_DQ<48>")
	)
	(segment
		(start 116.823744 -105.051352)
		(end 116.823744 -105.329228)
		(width 0.0889)
		(layer "In2.Cu")
		(net "M_K_DQ<48>")
	)
	(segment
		(start 117.546882 -97.555304)
		(end 117.474492 -97.482914)
		(width 0.0889)
		(layer "In2.Cu")
		(net "M_K_DQ<48>")
	)
	(segment
		(start 123.427998 -118.959376)
		(end 133.693408 -118.959376)
		(width 0.14224)
		(layer "In2.Cu")
		(net "M_K_DQ<48>")
	)
	(segment
		(start 135.557768 -129.770124)
		(end 134.882382 -130.44551)
		(width 0.14224)
		(layer "In2.Cu")
		(net "M_K_DQ<48>")
	)
	(segment
		(start 118.933468 -113.246154)
		(end 118.933468 -114.464846)
		(width 0.14224)
		(layer "In2.Cu")
		(net "M_K_DQ<48>")
	)
	(segment
		(start 135.794496 -129.074672)
		(end 135.557768 -129.3114)
		(width 0.14224)
		(layer "In2.Cu")
		(net "M_K_DQ<48>")
	)
	(segment
		(start 135.583168 -127.696976)
		(end 135.794496 -127.908304)
		(width 0.14224)
		(layer "In2.Cu")
		(net "M_K_DQ<48>")
	)
	(segment
		(start 135.794496 -127.908304)
		(end 135.794496 -129.074672)
		(width 0.14224)
		(layer "In2.Cu")
		(net "M_K_DQ<48>")
	)
	(segment
		(start 134.882382 -130.44551)
		(end 134.882382 -131.394708)
		(width 0.14224)
		(layer "In2.Cu")
		(net "M_K_DQ<48>")
	)
	(segment
		(start 134.666482 -132.044948)
		(end 134.666482 -135.00481)
		(width 0.14224)
		(layer "In2.Cu")
		(net "M_K_DQ<48>")
	)
	(segment
		(start 116.823744 -105.329228)
		(end 116.628672 -105.5243)
		(width 0.0889)
		(layer "In2.Cu")
		(net "M_K_DQ<48>")
	)
	(segment
		(start 133.693408 -118.959376)
		(end 134.138416 -119.404384)
		(width 0.14224)
		(layer "In2.Cu")
		(net "M_K_DQ<48>")
	)
	(segment
		(start 117.564408 -97.014538)
		(end 117.925342 -97.014538)
		(width 0.0889)
		(layer "In2.Cu")
		(net "M_K_DQ<48>")
	)
	(segment
		(start 118.933468 -114.464846)
		(end 123.427998 -118.959376)
		(width 0.14224)
		(layer "In2.Cu")
		(net "M_K_DQ<48>")
	)
	(segment
		(start 135.099552 -131.611878)
		(end 134.666482 -132.044948)
		(width 0.14224)
		(layer "In2.Cu")
		(net "M_K_DQ<48>")
	)
	(segment
		(start 117.474492 -97.104454)
		(end 117.564408 -97.014538)
		(width 0.0889)
		(layer "In2.Cu")
		(net "M_K_DQ<48>")
	)
	(segment
		(start 135.297164 -126.098808)
		(end 135.583168 -126.384812)
		(width 0.14224)
		(layer "In2.Cu")
		(net "M_K_DQ<48>")
	)
	(segment
		(start 134.666482 -135.00481)
		(end 135.475472 -135.8138)
		(width 0.14224)
		(layer "In2.Cu")
		(net "M_K_DQ<48>")
	)
	(segment
		(start 117.418358 -101.662992)
		(end 117.413532 -101.671628)
		(width 0.0889)
		(layer "In2.Cu")
		(net "M_K_DQ<48>")
	)
	(segment
		(start 134.138416 -119.736362)
		(end 133.259576 -120.615202)
		(width 0.14224)
		(layer "In2.Cu")
		(net "M_K_DQ<48>")
	)
	(segment
		(start 116.628672 -110.941358)
		(end 118.933468 -113.246154)
		(width 0.14224)
		(layer "In2.Cu")
		(net "M_K_DQ<48>")
	)
	(segment
		(start 135.583168 -126.384812)
		(end 135.583168 -127.696976)
		(width 0.14224)
		(layer "In2.Cu")
		(net "M_K_DQ<48>")
	)
	(segment
		(start 117.413532 -100.681028)
		(end 117.407182 -100.691696)
		(width 0.0889)
		(layer "In2.Cu")
		(net "M_K_DQ<48>")
	)
	(segment
		(start 135.475472 -135.8138)
		(end 135.771636 -135.8138)
		(width 0.14224)
		(layer "In2.Cu")
		(net "M_K_DQ<48>")
	)
	(segment
		(start 117.334284 -104.540812)
		(end 116.823744 -105.051352)
		(width 0.0889)
		(layer "In2.Cu")
		(net "M_K_DQ<48>")
	)
	(segment
		(start 117.546882 -97.875852)
		(end 117.546882 -97.555304)
		(width 0.0889)
		(layer "In2.Cu")
		(net "M_K_DQ<48>")
	)
	(segment
		(start 117.334284 -102.958138)
		(end 117.334284 -104.540812)
		(width 0.0889)
		(layer "In2.Cu")
		(net "M_K_DQ<48>")
	)
	(segment
		(start 117.413532 -102.262432)
		(end 117.418358 -102.271068)
		(width 0.0889)
		(layer "In2.Cu")
		(net "M_K_DQ<48>")
	)
	(segment
		(start 135.297164 -122.929396)
		(end 135.297164 -126.098808)
		(width 0.14224)
		(layer "In2.Cu")
		(net "M_K_DQ<48>")
	)
	(segment
		(start 133.259576 -120.891808)
		(end 135.297164 -122.929396)
		(width 0.14224)
		(layer "In2.Cu")
		(net "M_K_DQ<48>")
	)
	(segment
		(start 135.557768 -129.3114)
		(end 135.557768 -129.770124)
		(width 0.14224)
		(layer "In2.Cu")
		(net "M_K_DQ<48>")
	)
	(segment
		(start 117.474492 -97.482914)
		(end 117.474492 -97.104454)
		(width 0.0889)
		(layer "In2.Cu")
		(net "M_K_DQ<48>")
	)
	(segment
		(start 134.882382 -131.394708)
		(end 135.099552 -131.611878)
		(width 0.14224)
		(layer "In2.Cu")
		(net "M_K_DQ<48>")
	)
	(segment
		(start 133.259576 -120.615202)
		(end 133.259576 -120.891808)
		(width 0.14224)
		(layer "In2.Cu")
		(net "M_K_DQ<48>")
	)
	(segment
		(start 134.138416 -119.404384)
		(end 134.138416 -119.736362)
		(width 0.14224)
		(layer "In2.Cu")
		(net "M_K_DQ<48>")
	)
	(arc
		(start 117.387878 -100.231956)
		(mid 117.400076 -100.256921)
		(end 117.413532 -100.281232)
		(width 0.0889)
		(layer "In2.Cu")
		(net "M_K_DQ<48>")
	)
	(arc
		(start 117.407182 -100.691696)
		(mid 117.334384 -100.982459)
		(end 117.413532 -101.271578)
		(width 0.0889)
		(layer "In2.Cu")
		(net "M_K_DQ<48>")
	)
	(arc
		(start 117.413532 -101.271578)
		(mid 117.467002 -101.466641)
		(end 117.418358 -101.662992)
		(width 0.0889)
		(layer "In2.Cu")
		(net "M_K_DQ<48>")
	)
	(arc
		(start 117.530118 -98.068638)
		(mid 117.526675 -97.971217)
		(end 117.546882 -97.875852)
		(width 0.0889)
		(layer "In2.Cu")
		(net "M_K_DQ<48>")
	)
	(arc
		(start 117.413532 -102.662482)
		(mid 117.354432 -102.80509)
		(end 117.334284 -102.958138)
		(width 0.0889)
		(layer "In2.Cu")
		(net "M_K_DQ<48>")
	)
	(arc
		(start 117.413532 -101.671628)
		(mid 117.334401 -101.96703)
		(end 117.413532 -102.262432)
		(width 0.0889)
		(layer "In2.Cu")
		(net "M_K_DQ<48>")
	)
	(arc
		(start 117.413532 -98.700844)
		(mid 117.334401 -98.996246)
		(end 117.413532 -99.291648)
		(width 0.0889)
		(layer "In2.Cu")
		(net "M_K_DQ<48>")
	)
	(arc
		(start 117.413532 -99.291648)
		(mid 117.467006 -99.491292)
		(end 117.413532 -99.690936)
		(width 0.0889)
		(layer "In2.Cu")
		(net "M_K_DQ<48>")
	)
	(arc
		(start 117.413532 -99.690936)
		(mid 117.335064 -99.958335)
		(end 117.387878 -100.231956)
		(width 0.0889)
		(layer "In2.Cu")
		(net "M_K_DQ<48>")
	)
	(arc
		(start 117.530118 -98.068638)
		(mid 117.526189 -98.394773)
		(end 117.413532 -98.700844)
		(width 0.0889)
		(layer "In2.Cu")
		(net "M_K_DQ<48>")
	)
	(arc
		(start 117.413532 -100.281232)
		(mid 117.467031 -100.48113)
		(end 117.413532 -100.681028)
		(width 0.0889)
		(layer "In2.Cu")
		(net "M_K_DQ<48>")
	)
	(arc
		(start 117.418358 -102.271068)
		(mid 117.467113 -102.46742)
		(end 117.413532 -102.662482)
		(width 0.0889)
		(layer "In2.Cu")
		(net "M_K_DQ<48>")
	)
	(segment
		(start 113.919762 -98.995738)
		(end 114.491262 -98.995738)
		(width 0.1651)
		(layer "F.Cu")
		(net "M_K_DQ<47>")
	)
	(segment
		(start 129.999486 -133.0706)
		(end 129.999486 -134.340346)
		(width 0.1651)
		(layer "F.Cu")
		(net "M_K_DQ<47>")
	)
	(via
		(at 130.84937 -130.330956)
		(size 0.508)
		(drill 0.254)
		(layers "F.Cu" "B.Cu")
		(net "M_K_DQ<47>")
	)
	(via
		(at 129.999486 -134.340346)
		(size 0.508)
		(drill 0.254)
		(layers "F.Cu" "B.Cu")
		(net "M_K_DQ<47>")
	)
	(via
		(at 114.491262 -98.995738)
		(size 0.508)
		(drill 0.254)
		(layers "F.Cu" "B.Cu")
		(net "M_K_DQ<47>")
	)
	(segment
		(start 130.84937 -128.276096)
		(end 130.84937 -130.330956)
		(width 0.1651)
		(layer "B.Cu")
		(net "M_K_DQ<47>")
	)
	(segment
		(start 115.153694 -117.543072)
		(end 115.509548 -117.898926)
		(width 0.14224)
		(layer "In2.Cu")
		(net "M_K_DQ<47>")
	)
	(segment
		(start 118.751858 -120.623584)
		(end 118.602506 -120.772936)
		(width 0.14224)
		(layer "In2.Cu")
		(net "M_K_DQ<47>")
	)
	(segment
		(start 130.398774 -130.7592)
		(end 130.398774 -131.188968)
		(width 0.14224)
		(layer "In2.Cu")
		(net "M_K_DQ<47>")
	)
	(segment
		(start 131.061968 -129.220468)
		(end 131.061968 -130.127756)
		(width 0.14224)
		(layer "In2.Cu")
		(net "M_K_DQ<47>")
	)
	(segment
		(start 115.081304 -99.82708)
		(end 115.081304 -101.591618)
		(width 0.0889)
		(layer "In2.Cu")
		(net "M_K_DQ<47>")
	)
	(segment
		(start 120.125998 -122.515376)
		(end 129.70129 -122.515376)
		(width 0.14224)
		(layer "In2.Cu")
		(net "M_K_DQ<47>")
	)
	(segment
		(start 118.95836 -121.347738)
		(end 119.177308 -121.347738)
		(width 0.14224)
		(layer "In2.Cu")
		(net "M_K_DQ<47>")
	)
	(segment
		(start 131.519168 -128.204468)
		(end 131.722368 -128.407668)
		(width 0.14224)
		(layer "In2.Cu")
		(net "M_K_DQ<47>")
	)
	(segment
		(start 118.177056 -120.048782)
		(end 118.396004 -120.048782)
		(width 0.14224)
		(layer "In2.Cu")
		(net "M_K_DQ<47>")
	)
	(segment
		(start 130.443224 -131.233418)
		(end 130.443224 -131.9022)
		(width 0.14224)
		(layer "In2.Cu")
		(net "M_K_DQ<47>")
	)
	(segment
		(start 130.443224 -131.9022)
		(end 130.160776 -132.184648)
		(width 0.14224)
		(layer "In2.Cu")
		(net "M_K_DQ<47>")
	)
	(segment
		(start 115.877848 -117.749574)
		(end 116.096796 -117.749574)
		(width 0.14224)
		(layer "In2.Cu")
		(net "M_K_DQ<47>")
	)
	(segment
		(start 118.751858 -120.404636)
		(end 118.751858 -120.623584)
		(width 0.14224)
		(layer "In2.Cu")
		(net "M_K_DQ<47>")
	)
	(segment
		(start 130.160776 -132.184648)
		(end 130.160776 -132.457952)
		(width 0.14224)
		(layer "In2.Cu")
		(net "M_K_DQ<47>")
	)
	(segment
		(start 117.602254 -119.255032)
		(end 117.602254 -119.47398)
		(width 0.14224)
		(layer "In2.Cu")
		(net "M_K_DQ<47>")
	)
	(segment
		(start 130.84937 -130.330956)
		(end 130.827018 -130.330956)
		(width 0.14224)
		(layer "In2.Cu")
		(net "M_K_DQ<47>")
	)
	(segment
		(start 131.265168 -129.017268)
		(end 131.061968 -129.220468)
		(width 0.14224)
		(layer "In2.Cu")
		(net "M_K_DQ<47>")
	)
	(segment
		(start 130.858768 -130.330956)
		(end 130.84937 -130.330956)
		(width 0.14224)
		(layer "In2.Cu")
		(net "M_K_DQ<47>")
	)
	(segment
		(start 131.188968 -125.5776)
		(end 130.960368 -125.8062)
		(width 0.14224)
		(layer "In2.Cu")
		(net "M_K_DQ<47>")
	)
	(segment
		(start 115.081304 -101.591618)
		(end 114.235992 -102.43693)
		(width 0.0889)
		(layer "In2.Cu")
		(net "M_K_DQ<47>")
	)
	(segment
		(start 116.303298 -118.692676)
		(end 116.659152 -119.04853)
		(width 0.14224)
		(layer "In2.Cu")
		(net "M_K_DQ<47>")
	)
	(segment
		(start 116.45265 -118.105428)
		(end 116.45265 -118.324376)
		(width 0.14224)
		(layer "In2.Cu")
		(net "M_K_DQ<47>")
	)
	(segment
		(start 130.271774 -134.340346)
		(end 129.999486 -134.340346)
		(width 0.14224)
		(layer "In2.Cu")
		(net "M_K_DQ<47>")
	)
	(segment
		(start 117.027452 -118.899178)
		(end 117.2464 -118.899178)
		(width 0.14224)
		(layer "In2.Cu")
		(net "M_K_DQ<47>")
	)
	(segment
		(start 131.061968 -130.127756)
		(end 130.858768 -130.330956)
		(width 0.14224)
		(layer "In2.Cu")
		(net "M_K_DQ<47>")
	)
	(segment
		(start 114.491262 -98.995738)
		(end 114.986308 -99.661472)
		(width 0.0889)
		(layer "In2.Cu")
		(net "M_K_DQ<47>")
	)
	(segment
		(start 130.160776 -133.550152)
		(end 130.449574 -133.83895)
		(width 0.14224)
		(layer "In2.Cu")
		(net "M_K_DQ<47>")
	)
	(segment
		(start 131.722368 -128.407668)
		(end 131.722368 -128.814068)
		(width 0.14224)
		(layer "In2.Cu")
		(net "M_K_DQ<47>")
	)
	(segment
		(start 115.728496 -117.898926)
		(end 115.877848 -117.749574)
		(width 0.14224)
		(layer "In2.Cu")
		(net "M_K_DQ<47>")
	)
	(segment
		(start 113.138712 -106.021378)
		(end 113.138712 -114.78895)
		(width 0.14224)
		(layer "In2.Cu")
		(net "M_K_DQ<47>")
	)
	(segment
		(start 117.2464 -118.899178)
		(end 117.602254 -119.255032)
		(width 0.14224)
		(layer "In2.Cu")
		(net "M_K_DQ<47>")
	)
	(segment
		(start 118.602506 -120.991884)
		(end 118.95836 -121.347738)
		(width 0.14224)
		(layer "In2.Cu")
		(net "M_K_DQ<47>")
	)
	(segment
		(start 115.153694 -117.324124)
		(end 115.153694 -117.543072)
		(width 0.14224)
		(layer "In2.Cu")
		(net "M_K_DQ<47>")
	)
	(segment
		(start 131.722368 -128.814068)
		(end 131.519168 -129.017268)
		(width 0.14224)
		(layer "In2.Cu")
		(net "M_K_DQ<47>")
	)
	(segment
		(start 130.449574 -134.162546)
		(end 130.271774 -134.340346)
		(width 0.14224)
		(layer "In2.Cu")
		(net "M_K_DQ<47>")
	)
	(segment
		(start 117.602254 -119.47398)
		(end 117.452902 -119.623332)
		(width 0.14224)
		(layer "In2.Cu")
		(net "M_K_DQ<47>")
	)
	(segment
		(start 130.398774 -131.188968)
		(end 130.443224 -131.233418)
		(width 0.14224)
		(layer "In2.Cu")
		(net "M_K_DQ<47>")
	)
	(segment
		(start 118.396004 -120.048782)
		(end 118.751858 -120.404636)
		(width 0.14224)
		(layer "In2.Cu")
		(net "M_K_DQ<47>")
	)
	(segment
		(start 130.160776 -133.276848)
		(end 130.160776 -133.550152)
		(width 0.14224)
		(layer "In2.Cu")
		(net "M_K_DQ<47>")
	)
	(segment
		(start 116.45265 -118.324376)
		(end 116.303298 -118.473728)
		(width 0.14224)
		(layer "In2.Cu")
		(net "M_K_DQ<47>")
	)
	(segment
		(start 130.417824 -133.0198)
		(end 130.160776 -133.276848)
		(width 0.14224)
		(layer "In2.Cu")
		(net "M_K_DQ<47>")
	)
	(segment
		(start 129.70129 -122.515376)
		(end 131.188968 -124.003054)
		(width 0.14224)
		(layer "In2.Cu")
		(net "M_K_DQ<47>")
	)
	(segment
		(start 119.32666 -121.198386)
		(end 119.545608 -121.198386)
		(width 0.14224)
		(layer "In2.Cu")
		(net "M_K_DQ<47>")
	)
	(segment
		(start 119.901462 -121.55424)
		(end 119.901462 -121.773188)
		(width 0.14224)
		(layer "In2.Cu")
		(net "M_K_DQ<47>")
	)
	(segment
		(start 112.888776 -105.771442)
		(end 113.138712 -106.021378)
		(width 0.0889)
		(layer "In2.Cu")
		(net "M_K_DQ<47>")
	)
	(segment
		(start 116.659152 -119.04853)
		(end 116.8781 -119.04853)
		(width 0.14224)
		(layer "In2.Cu")
		(net "M_K_DQ<47>")
	)
	(segment
		(start 130.960368 -127.848868)
		(end 131.315968 -128.204468)
		(width 0.14224)
		(layer "In2.Cu")
		(net "M_K_DQ<47>")
	)
	(segment
		(start 117.452902 -119.623332)
		(end 117.452902 -119.84228)
		(width 0.14224)
		(layer "In2.Cu")
		(net "M_K_DQ<47>")
	)
	(segment
		(start 119.545608 -121.198386)
		(end 119.901462 -121.55424)
		(width 0.14224)
		(layer "In2.Cu")
		(net "M_K_DQ<47>")
	)
	(segment
		(start 116.096796 -117.749574)
		(end 116.45265 -118.105428)
		(width 0.14224)
		(layer "In2.Cu")
		(net "M_K_DQ<47>")
	)
	(segment
		(start 131.188968 -124.003054)
		(end 131.188968 -125.5776)
		(width 0.14224)
		(layer "In2.Cu")
		(net "M_K_DQ<47>")
	)
	(segment
		(start 131.315968 -128.204468)
		(end 131.519168 -128.204468)
		(width 0.14224)
		(layer "In2.Cu")
		(net "M_K_DQ<47>")
	)
	(segment
		(start 117.808756 -120.198134)
		(end 118.027704 -120.198134)
		(width 0.14224)
		(layer "In2.Cu")
		(net "M_K_DQ<47>")
	)
	(segment
		(start 115.509548 -117.898926)
		(end 115.728496 -117.898926)
		(width 0.14224)
		(layer "In2.Cu")
		(net "M_K_DQ<47>")
	)
	(segment
		(start 119.901462 -121.773188)
		(end 119.75211 -121.92254)
		(width 0.14224)
		(layer "In2.Cu")
		(net "M_K_DQ<47>")
	)
	(segment
		(start 112.888776 -105.104946)
		(end 112.888776 -105.771442)
		(width 0.0889)
		(layer "In2.Cu")
		(net "M_K_DQ<47>")
	)
	(segment
		(start 130.417824 -132.715)
		(end 130.417824 -133.0198)
		(width 0.14224)
		(layer "In2.Cu")
		(net "M_K_DQ<47>")
	)
	(segment
		(start 130.449574 -133.83895)
		(end 130.449574 -134.162546)
		(width 0.14224)
		(layer "In2.Cu")
		(net "M_K_DQ<47>")
	)
	(segment
		(start 118.027704 -120.198134)
		(end 118.177056 -120.048782)
		(width 0.14224)
		(layer "In2.Cu")
		(net "M_K_DQ<47>")
	)
	(segment
		(start 130.160776 -132.457952)
		(end 130.417824 -132.715)
		(width 0.14224)
		(layer "In2.Cu")
		(net "M_K_DQ<47>")
	)
	(segment
		(start 114.986308 -99.661472)
		(end 115.081304 -99.82708)
		(width 0.0889)
		(layer "In2.Cu")
		(net "M_K_DQ<47>")
	)
	(segment
		(start 116.303298 -118.473728)
		(end 116.303298 -118.692676)
		(width 0.14224)
		(layer "In2.Cu")
		(net "M_K_DQ<47>")
	)
	(segment
		(start 115.303046 -116.953284)
		(end 115.303046 -117.174772)
		(width 0.14224)
		(layer "In2.Cu")
		(net "M_K_DQ<47>")
	)
	(segment
		(start 130.960368 -125.8062)
		(end 130.960368 -127.848868)
		(width 0.14224)
		(layer "In2.Cu")
		(net "M_K_DQ<47>")
	)
	(segment
		(start 131.519168 -129.017268)
		(end 131.265168 -129.017268)
		(width 0.14224)
		(layer "In2.Cu")
		(net "M_K_DQ<47>")
	)
	(segment
		(start 119.75211 -122.141488)
		(end 120.125998 -122.515376)
		(width 0.14224)
		(layer "In2.Cu")
		(net "M_K_DQ<47>")
	)
	(segment
		(start 115.303046 -117.174772)
		(end 115.153694 -117.324124)
		(width 0.14224)
		(layer "In2.Cu")
		(net "M_K_DQ<47>")
	)
	(segment
		(start 119.177308 -121.347738)
		(end 119.32666 -121.198386)
		(width 0.14224)
		(layer "In2.Cu")
		(net "M_K_DQ<47>")
	)
	(segment
		(start 119.75211 -121.92254)
		(end 119.75211 -122.141488)
		(width 0.14224)
		(layer "In2.Cu")
		(net "M_K_DQ<47>")
	)
	(segment
		(start 117.452902 -119.84228)
		(end 117.808756 -120.198134)
		(width 0.14224)
		(layer "In2.Cu")
		(net "M_K_DQ<47>")
	)
	(segment
		(start 130.827018 -130.330956)
		(end 130.398774 -130.7592)
		(width 0.14224)
		(layer "In2.Cu")
		(net "M_K_DQ<47>")
	)
	(segment
		(start 113.138712 -114.78895)
		(end 115.303046 -116.953284)
		(width 0.14224)
		(layer "In2.Cu")
		(net "M_K_DQ<47>")
	)
	(segment
		(start 114.235992 -102.43693)
		(end 114.235992 -103.75773)
		(width 0.0889)
		(layer "In2.Cu")
		(net "M_K_DQ<47>")
	)
	(segment
		(start 118.602506 -120.772936)
		(end 118.602506 -120.991884)
		(width 0.14224)
		(layer "In2.Cu")
		(net "M_K_DQ<47>")
	)
	(segment
		(start 114.235992 -103.75773)
		(end 112.888776 -105.104946)
		(width 0.0889)
		(layer "In2.Cu")
		(net "M_K_DQ<47>")
	)
	(segment
		(start 116.8781 -119.04853)
		(end 117.027452 -118.899178)
		(width 0.14224)
		(layer "In2.Cu")
		(net "M_K_DQ<47>")
	)
	(segment
		(start 130.84937 -137.67054)
		(end 130.849624 -137.67054)
		(width 0.1651)
		(layer "F.Cu")
		(net "M_K_DQ<46>")
	)
	(segment
		(start 130.981704 -136.57072)
		(end 130.981704 -136.35228)
		(width 0.1651)
		(layer "F.Cu")
		(net "M_K_DQ<46>")
	)
	(segment
		(start 130.849624 -136.2202)
		(end 130.849624 -135.915654)
		(width 0.1651)
		(layer "F.Cu")
		(net "M_K_DQ<46>")
	)
	(segment
		(start 130.849624 -137.67054)
		(end 130.849624 -136.7028)
		(width 0.1651)
		(layer "F.Cu")
		(net "M_K_DQ<46>")
	)
	(segment
		(start 113.919762 -97.014538)
		(end 114.491262 -97.014538)
		(width 0.1651)
		(layer "F.Cu")
		(net "M_K_DQ<46>")
	)
	(segment
		(start 130.981704 -136.35228)
		(end 130.849624 -136.2202)
		(width 0.1651)
		(layer "F.Cu")
		(net "M_K_DQ<46>")
	)
	(segment
		(start 130.849624 -136.7028)
		(end 130.981704 -136.57072)
		(width 0.1651)
		(layer "F.Cu")
		(net "M_K_DQ<46>")
	)
	(segment
		(start 130.849624 -135.915654)
		(end 130.84937 -135.9154)
		(width 0.1651)
		(layer "F.Cu")
		(net "M_K_DQ<46>")
	)
	(via
		(at 114.491262 -97.014538)
		(size 0.508)
		(drill 0.254)
		(layers "F.Cu" "B.Cu")
		(net "M_K_DQ<46>")
	)
	(via
		(at 129.999486 -131.611878)
		(size 0.508)
		(drill 0.254)
		(layers "F.Cu" "B.Cu")
		(net "M_K_DQ<46>")
	)
	(via
		(at 130.84937 -135.9154)
		(size 0.508)
		(drill 0.254)
		(layers "F.Cu" "B.Cu")
		(net "M_K_DQ<46>")
	)
	(segment
		(start 129.999486 -132.876036)
		(end 129.999486 -131.611878)
		(width 0.1651)
		(layer "B.Cu")
		(net "M_K_DQ<46>")
	)
	(segment
		(start 130.426968 -128.143)
		(end 130.477768 -128.1938)
		(width 0.14224)
		(layer "In2.Cu")
		(net "M_K_DQ<46>")
	)
	(segment
		(start 114.046 -103.67899)
		(end 112.698784 -105.026206)
		(width 0.0889)
		(layer "In2.Cu")
		(net "M_K_DQ<46>")
	)
	(segment
		(start 129.566416 -132.044948)
		(end 129.566416 -134.632446)
		(width 0.14224)
		(layer "In2.Cu")
		(net "M_K_DQ<46>")
	)
	(segment
		(start 119.973344 -123.150376)
		(end 129.422144 -123.150376)
		(width 0.14224)
		(layer "In2.Cu")
		(net "M_K_DQ<46>")
	)
	(segment
		(start 112.698784 -105.026206)
		(end 112.698784 -105.732326)
		(width 0.0889)
		(layer "In2.Cu")
		(net "M_K_DQ<46>")
	)
	(segment
		(start 129.830576 -130.468878)
		(end 129.830576 -131.442968)
		(width 0.14224)
		(layer "In2.Cu")
		(net "M_K_DQ<46>")
	)
	(segment
		(start 129.422144 -123.150376)
		(end 130.045968 -123.7742)
		(width 0.14224)
		(layer "In2.Cu")
		(net "M_K_DQ<46>")
	)
	(segment
		(start 114.139726 -99.187)
		(end 114.309144 -99.481132)
		(width 0.0889)
		(layer "In2.Cu")
		(net "M_K_DQ<46>")
	)
	(segment
		(start 129.830576 -131.442968)
		(end 129.999486 -131.611878)
		(width 0.14224)
		(layer "In2.Cu")
		(net "M_K_DQ<46>")
	)
	(segment
		(start 129.566416 -134.632446)
		(end 130.84937 -135.9154)
		(width 0.14224)
		(layer "In2.Cu")
		(net "M_K_DQ<46>")
	)
	(segment
		(start 112.394492 -115.571524)
		(end 119.973344 -123.150376)
		(width 0.14224)
		(layer "In2.Cu")
		(net "M_K_DQ<46>")
	)
	(segment
		(start 114.139726 -98.1964)
		(end 114.144552 -98.205036)
		(width 0.0889)
		(layer "In2.Cu")
		(net "M_K_DQ<46>")
	)
	(segment
		(start 114.161316 -97.776284)
		(end 114.144552 -97.804986)
		(width 0.0889)
		(layer "In2.Cu")
		(net "M_K_DQ<46>")
	)
	(segment
		(start 112.394492 -106.036618)
		(end 112.394492 -115.571524)
		(width 0.14224)
		(layer "In2.Cu")
		(net "M_K_DQ<46>")
	)
	(segment
		(start 130.477768 -128.1938)
		(end 130.477768 -129.821686)
		(width 0.14224)
		(layer "In2.Cu")
		(net "M_K_DQ<46>")
	)
	(segment
		(start 114.491262 -97.014538)
		(end 114.161316 -97.776284)
		(width 0.0889)
		(layer "In2.Cu")
		(net "M_K_DQ<46>")
	)
	(segment
		(start 114.837972 -99.786186)
		(end 114.891312 -99.878388)
		(width 0.0889)
		(layer "In2.Cu")
		(net "M_K_DQ<46>")
	)
	(segment
		(start 130.045968 -125.3744)
		(end 130.426968 -125.7554)
		(width 0.14224)
		(layer "In2.Cu")
		(net "M_K_DQ<46>")
	)
	(segment
		(start 130.477768 -129.821686)
		(end 129.830576 -130.468878)
		(width 0.14224)
		(layer "In2.Cu")
		(net "M_K_DQ<46>")
	)
	(segment
		(start 114.046 -102.35819)
		(end 114.046 -103.67899)
		(width 0.0889)
		(layer "In2.Cu")
		(net "M_K_DQ<46>")
	)
	(segment
		(start 114.144552 -98.205036)
		(end 114.150902 -98.215704)
		(width 0.0889)
		(layer "In2.Cu")
		(net "M_K_DQ<46>")
	)
	(segment
		(start 129.999486 -131.611878)
		(end 129.566416 -132.044948)
		(width 0.14224)
		(layer "In2.Cu")
		(net "M_K_DQ<46>")
	)
	(segment
		(start 130.426968 -125.7554)
		(end 130.426968 -128.143)
		(width 0.14224)
		(layer "In2.Cu")
		(net "M_K_DQ<46>")
	)
	(segment
		(start 114.491262 -99.586288)
		(end 114.506248 -99.586288)
		(width 0.0889)
		(layer "In2.Cu")
		(net "M_K_DQ<46>")
	)
	(segment
		(start 112.698784 -105.732326)
		(end 112.394492 -106.036618)
		(width 0.0889)
		(layer "In2.Cu")
		(net "M_K_DQ<46>")
	)
	(segment
		(start 130.045968 -123.7742)
		(end 130.045968 -125.3744)
		(width 0.14224)
		(layer "In2.Cu")
		(net "M_K_DQ<46>")
	)
	(segment
		(start 114.891312 -99.878388)
		(end 114.891312 -101.512878)
		(width 0.0889)
		(layer "In2.Cu")
		(net "M_K_DQ<46>")
	)
	(segment
		(start 114.891312 -101.512878)
		(end 114.046 -102.35819)
		(width 0.0889)
		(layer "In2.Cu")
		(net "M_K_DQ<46>")
	)
	(arc
		(start 114.309144 -99.481132)
		(mid 114.386117 -99.558101)
		(end 114.491262 -99.586288)
		(width 0.0889)
		(layer "In2.Cu")
		(net "M_K_DQ<46>")
	)
	(arc
		(start 114.150902 -98.215704)
		(mid 114.2237 -98.506467)
		(end 114.144552 -98.795586)
		(width 0.0889)
		(layer "In2.Cu")
		(net "M_K_DQ<46>")
	)
	(arc
		(start 114.144552 -98.795586)
		(mid 114.091082 -98.990649)
		(end 114.139726 -99.187)
		(width 0.0889)
		(layer "In2.Cu")
		(net "M_K_DQ<46>")
	)
	(arc
		(start 114.144552 -97.804986)
		(mid 114.091082 -98.000049)
		(end 114.139726 -98.1964)
		(width 0.0889)
		(layer "In2.Cu")
		(net "M_K_DQ<46>")
	)
	(arc
		(start 114.506248 -99.586288)
		(mid 114.69789 -99.643454)
		(end 114.837972 -99.786186)
		(width 0.0889)
		(layer "In2.Cu")
		(net "M_K_DQ<46>")
	)
	(segment
		(start 124.049536 -133.0706)
		(end 124.049536 -134.340346)
		(width 0.1651)
		(layer "F.Cu")
		(net "M_K_DQ<45>")
	)
	(segment
		(start 111.344202 -98.500184)
		(end 111.915702 -98.500184)
		(width 0.1651)
		(layer "F.Cu")
		(net "M_K_DQ<45>")
	)
	(via
		(at 124.049536 -134.340346)
		(size 0.508)
		(drill 0.254)
		(layers "F.Cu" "B.Cu")
		(net "M_K_DQ<45>")
	)
	(via
		(at 111.915702 -98.500184)
		(size 0.508)
		(drill 0.254)
		(layers "F.Cu" "B.Cu")
		(net "M_K_DQ<45>")
	)
	(via
		(at 124.82322 -130.330956)
		(size 0.508)
		(drill 0.254)
		(layers "F.Cu" "B.Cu")
		(net "M_K_DQ<45>")
	)
	(segment
		(start 124.89942 -130.254756)
		(end 124.82322 -130.330956)
		(width 0.1651)
		(layer "B.Cu")
		(net "M_K_DQ<45>")
	)
	(segment
		(start 124.89942 -128.276096)
		(end 124.89942 -130.254756)
		(width 0.1651)
		(layer "B.Cu")
		(net "M_K_DQ<45>")
	)
	(segment
		(start 109.217968 -119.015256)
		(end 109.217968 -119.297196)
		(width 0.14224)
		(layer "In2.Cu")
		(net "M_K_DQ<45>")
	)
	(segment
		(start 116.528088 -126.672848)
		(end 116.142262 -127.058674)
		(width 0.14224)
		(layer "In2.Cu")
		(net "M_K_DQ<45>")
	)
	(segment
		(start 109.854238 -101.268022)
		(end 109.854238 -101.762052)
		(width 0.0889)
		(layer "In2.Cu")
		(net "M_K_DQ<45>")
	)
	(segment
		(start 109.505242 -119.58447)
		(end 109.798358 -119.58447)
		(width 0.14224)
		(layer "In2.Cu")
		(net "M_K_DQ<45>")
	)
	(segment
		(start 109.217968 -119.297196)
		(end 109.505242 -119.58447)
		(width 0.14224)
		(layer "In2.Cu")
		(net "M_K_DQ<45>")
	)
	(segment
		(start 124.474224 -133.959854)
		(end 124.474224 -134.187946)
		(width 0.14224)
		(layer "In2.Cu")
		(net "M_K_DQ<45>")
	)
	(segment
		(start 110.490762 -119.179594)
		(end 110.779814 -119.468646)
		(width 0.14224)
		(layer "In2.Cu")
		(net "M_K_DQ<45>")
	)
	(segment
		(start 124.210826 -132.216144)
		(end 124.210826 -132.553456)
		(width 0.14224)
		(layer "In2.Cu")
		(net "M_K_DQ<45>")
	)
	(segment
		(start 122.073924 -129.111756)
		(end 124.457968 -129.111756)
		(width 0.14224)
		(layer "In2.Cu")
		(net "M_K_DQ<45>")
	)
	(segment
		(start 117.955568 -127.8128)
		(end 120.774968 -127.8128)
		(width 0.14224)
		(layer "In2.Cu")
		(net "M_K_DQ<45>")
	)
	(segment
		(start 115.378484 -125.523244)
		(end 114.93119 -125.970538)
		(width 0.14224)
		(layer "In2.Cu")
		(net "M_K_DQ<45>")
	)
	(segment
		(start 109.628432 -118.604792)
		(end 109.217968 -119.015256)
		(width 0.14224)
		(layer "In2.Cu")
		(net "M_K_DQ<45>")
	)
	(segment
		(start 120.774968 -127.8128)
		(end 122.073924 -129.111756)
		(width 0.14224)
		(layer "In2.Cu")
		(net "M_K_DQ<45>")
	)
	(segment
		(start 111.915702 -98.500184)
		(end 111.915702 -98.16211)
		(width 0.0889)
		(layer "In2.Cu")
		(net "M_K_DQ<45>")
	)
	(segment
		(start 124.210826 -132.553456)
		(end 124.448824 -132.791454)
		(width 0.14224)
		(layer "In2.Cu")
		(net "M_K_DQ<45>")
	)
	(segment
		(start 124.321824 -134.340346)
		(end 124.049536 -134.340346)
		(width 0.14224)
		(layer "In2.Cu")
		(net "M_K_DQ<45>")
	)
	(segment
		(start 124.800868 -130.330956)
		(end 124.372624 -130.7592)
		(width 0.14224)
		(layer "In2.Cu")
		(net "M_K_DQ<45>")
	)
	(segment
		(start 124.448824 -133.146546)
		(end 124.210826 -133.384544)
		(width 0.14224)
		(layer "In2.Cu")
		(net "M_K_DQ<45>")
	)
	(segment
		(start 107.682792 -116.371624)
		(end 109.628432 -118.317264)
		(width 0.14224)
		(layer "In2.Cu")
		(net "M_K_DQ<45>")
	)
	(segment
		(start 124.372624 -131.318)
		(end 124.499624 -131.445)
		(width 0.14224)
		(layer "In2.Cu")
		(net "M_K_DQ<45>")
	)
	(segment
		(start 124.82322 -130.330956)
		(end 124.800868 -130.330956)
		(width 0.14224)
		(layer "In2.Cu")
		(net "M_K_DQ<45>")
	)
	(segment
		(start 107.682792 -105.965498)
		(end 107.682792 -116.371624)
		(width 0.14224)
		(layer "In2.Cu")
		(net "M_K_DQ<45>")
	)
	(segment
		(start 111.074962 -99.586288)
		(end 111.057182 -99.586288)
		(width 0.0889)
		(layer "In2.Cu")
		(net "M_K_DQ<45>")
	)
	(segment
		(start 124.457968 -129.111756)
		(end 124.661168 -129.314956)
		(width 0.14224)
		(layer "In2.Cu")
		(net "M_K_DQ<45>")
	)
	(segment
		(start 109.854238 -101.762052)
		(end 107.446064 -104.170226)
		(width 0.0889)
		(layer "In2.Cu")
		(net "M_K_DQ<45>")
	)
	(segment
		(start 124.372624 -130.7592)
		(end 124.372624 -131.318)
		(width 0.14224)
		(layer "In2.Cu")
		(net "M_K_DQ<45>")
	)
	(segment
		(start 115.953286 -126.098046)
		(end 116.240814 -126.098046)
		(width 0.14224)
		(layer "In2.Cu")
		(net "M_K_DQ<45>")
	)
	(segment
		(start 124.210826 -133.696456)
		(end 124.474224 -133.959854)
		(width 0.14224)
		(layer "In2.Cu")
		(net "M_K_DQ<45>")
	)
	(segment
		(start 117.390418 -127.24765)
		(end 117.955568 -127.8128)
		(width 0.14224)
		(layer "In2.Cu")
		(net "M_K_DQ<45>")
	)
	(segment
		(start 124.448824 -132.791454)
		(end 124.448824 -133.146546)
		(width 0.14224)
		(layer "In2.Cu")
		(net "M_K_DQ<45>")
	)
	(segment
		(start 124.474224 -134.187946)
		(end 124.321824 -134.340346)
		(width 0.14224)
		(layer "In2.Cu")
		(net "M_K_DQ<45>")
	)
	(segment
		(start 116.429536 -127.633476)
		(end 116.717064 -127.633476)
		(width 0.14224)
		(layer "In2.Cu")
		(net "M_K_DQ<45>")
	)
	(segment
		(start 111.915702 -98.16211)
		(end 111.85779 -98.104198)
		(width 0.0889)
		(layer "In2.Cu")
		(net "M_K_DQ<45>")
	)
	(segment
		(start 110.461044 -120.074944)
		(end 110.461044 -120.318276)
		(width 0.14224)
		(layer "In2.Cu")
		(net "M_K_DQ<45>")
	)
	(segment
		(start 110.714028 -99.780598)
		(end 109.854238 -101.268022)
		(width 0.0889)
		(layer "In2.Cu")
		(net "M_K_DQ<45>")
	)
	(segment
		(start 115.218464 -126.54534)
		(end 115.505992 -126.54534)
		(width 0.14224)
		(layer "In2.Cu")
		(net "M_K_DQ<45>")
	)
	(segment
		(start 116.240814 -126.098046)
		(end 116.528088 -126.38532)
		(width 0.14224)
		(layer "In2.Cu")
		(net "M_K_DQ<45>")
	)
	(segment
		(start 116.528088 -126.38532)
		(end 116.528088 -126.672848)
		(width 0.14224)
		(layer "In2.Cu")
		(net "M_K_DQ<45>")
	)
	(segment
		(start 107.446064 -104.170226)
		(end 107.446064 -105.72877)
		(width 0.0889)
		(layer "In2.Cu")
		(net "M_K_DQ<45>")
	)
	(segment
		(start 109.628432 -118.317264)
		(end 109.628432 -118.604792)
		(width 0.14224)
		(layer "In2.Cu")
		(net "M_K_DQ<45>")
	)
	(segment
		(start 116.142262 -127.346202)
		(end 116.429536 -127.633476)
		(width 0.14224)
		(layer "In2.Cu")
		(net "M_K_DQ<45>")
	)
	(segment
		(start 114.93119 -126.258066)
		(end 115.218464 -126.54534)
		(width 0.14224)
		(layer "In2.Cu")
		(net "M_K_DQ<45>")
	)
	(segment
		(start 124.499624 -131.927346)
		(end 124.210826 -132.216144)
		(width 0.14224)
		(layer "In2.Cu")
		(net "M_K_DQ<45>")
	)
	(segment
		(start 124.210826 -133.384544)
		(end 124.210826 -133.696456)
		(width 0.14224)
		(layer "In2.Cu")
		(net "M_K_DQ<45>")
	)
	(segment
		(start 116.717064 -127.633476)
		(end 117.10289 -127.24765)
		(width 0.14224)
		(layer "In2.Cu")
		(net "M_K_DQ<45>")
	)
	(segment
		(start 110.779814 -119.468646)
		(end 110.779814 -119.756174)
		(width 0.14224)
		(layer "In2.Cu")
		(net "M_K_DQ<45>")
	)
	(segment
		(start 110.203234 -119.179594)
		(end 110.490762 -119.179594)
		(width 0.14224)
		(layer "In2.Cu")
		(net "M_K_DQ<45>")
	)
	(segment
		(start 109.798358 -119.58447)
		(end 110.203234 -119.179594)
		(width 0.14224)
		(layer "In2.Cu")
		(net "M_K_DQ<45>")
	)
	(segment
		(start 114.93119 -125.970538)
		(end 114.93119 -126.258066)
		(width 0.14224)
		(layer "In2.Cu")
		(net "M_K_DQ<45>")
	)
	(segment
		(start 107.446064 -105.72877)
		(end 107.682792 -105.965498)
		(width 0.0889)
		(layer "In2.Cu")
		(net "M_K_DQ<45>")
	)
	(segment
		(start 124.661168 -129.314956)
		(end 124.661168 -130.168904)
		(width 0.14224)
		(layer "In2.Cu")
		(net "M_K_DQ<45>")
	)
	(segment
		(start 115.378484 -125.235716)
		(end 115.378484 -125.523244)
		(width 0.14224)
		(layer "In2.Cu")
		(net "M_K_DQ<45>")
	)
	(segment
		(start 116.142262 -127.058674)
		(end 116.142262 -127.346202)
		(width 0.14224)
		(layer "In2.Cu")
		(net "M_K_DQ<45>")
	)
	(segment
		(start 115.505992 -126.54534)
		(end 115.953286 -126.098046)
		(width 0.14224)
		(layer "In2.Cu")
		(net "M_K_DQ<45>")
	)
	(segment
		(start 110.779814 -119.756174)
		(end 110.461044 -120.074944)
		(width 0.14224)
		(layer "In2.Cu")
		(net "M_K_DQ<45>")
	)
	(segment
		(start 117.10289 -127.24765)
		(end 117.390418 -127.24765)
		(width 0.14224)
		(layer "In2.Cu")
		(net "M_K_DQ<45>")
	)
	(segment
		(start 110.461044 -120.318276)
		(end 115.378484 -125.235716)
		(width 0.14224)
		(layer "In2.Cu")
		(net "M_K_DQ<45>")
	)
	(segment
		(start 124.499624 -131.445)
		(end 124.499624 -131.927346)
		(width 0.14224)
		(layer "In2.Cu")
		(net "M_K_DQ<45>")
	)
	(segment
		(start 124.661168 -130.168904)
		(end 124.82322 -130.330956)
		(width 0.14224)
		(layer "In2.Cu")
		(net "M_K_DQ<45>")
	)
	(arc
		(start 111.568992 -98.700336)
		(mid 111.573321 -99.283508)
		(end 111.074962 -99.586288)
		(width 0.0889)
		(layer "In2.Cu")
		(net "M_K_DQ<45>")
	)
	(arc
		(start 111.057182 -99.586288)
		(mid 110.860021 -99.638247)
		(end 110.714028 -99.780598)
		(width 0.0889)
		(layer "In2.Cu")
		(net "M_K_DQ<45>")
	)
	(arc
		(start 111.85779 -98.104198)
		(mid 111.555521 -98.325747)
		(end 111.568992 -98.700336)
		(width 0.0889)
		(layer "In2.Cu")
		(net "M_K_DQ<45>")
	)
	(segment
		(start 124.89942 -136.345168)
		(end 124.801376 -135.8138)
		(width 0.1651)
		(layer "F.Cu")
		(net "M_K_DQ<44>")
	)
	(segment
		(start 111.344202 -97.509584)
		(end 111.915702 -97.509584)
		(width 0.1651)
		(layer "F.Cu")
		(net "M_K_DQ<44>")
	)
	(segment
		(start 124.89942 -137.67054)
		(end 124.89942 -136.345168)
		(width 0.1651)
		(layer "F.Cu")
		(net "M_K_DQ<44>")
	)
	(via
		(at 124.801376 -135.8138)
		(size 0.508)
		(drill 0.254)
		(layers "F.Cu" "B.Cu")
		(net "M_K_DQ<44>")
	)
	(via
		(at 111.915702 -97.509584)
		(size 0.508)
		(drill 0.254)
		(layers "F.Cu" "B.Cu")
		(net "M_K_DQ<44>")
	)
	(via
		(at 124.049536 -131.611878)
		(size 0.508)
		(drill 0.254)
		(layers "F.Cu" "B.Cu")
		(net "M_K_DQ<44>")
	)
	(segment
		(start 124.049536 -132.876036)
		(end 124.049536 -131.611878)
		(width 0.1651)
		(layer "B.Cu")
		(net "M_K_DQ<44>")
	)
	(segment
		(start 118.784624 -128.2954)
		(end 118.939564 -128.45034)
		(width 0.14224)
		(layer "In2.Cu")
		(net "M_K_DQ<44>")
	)
	(segment
		(start 122.597164 -130.035808)
		(end 122.825764 -129.807208)
		(width 0.14224)
		(layer "In2.Cu")
		(net "M_K_DQ<44>")
	)
	(segment
		(start 114.278156 -126.321312)
		(end 116.252244 -128.2954)
		(width 0.14224)
		(layer "In2.Cu")
		(net "M_K_DQ<44>")
	)
	(segment
		(start 122.825764 -129.807208)
		(end 123.404376 -129.807208)
		(width 0.14224)
		(layer "In2.Cu")
		(net "M_K_DQ<44>")
	)
	(segment
		(start 111.068358 -99.395788)
		(end 111.03229 -99.395788)
		(width 0.0889)
		(layer "In2.Cu")
		(net "M_K_DQ<44>")
	)
	(segment
		(start 117.613684 -128.77038)
		(end 117.768624 -128.92532)
		(width 0.14224)
		(layer "In2.Cu")
		(net "M_K_DQ<44>")
	)
	(segment
		(start 120.374156 -128.2954)
		(end 122.114564 -130.035808)
		(width 0.14224)
		(layer "In2.Cu")
		(net "M_K_DQ<44>")
	)
	(segment
		(start 123.774454 -135.03783)
		(end 124.550424 -135.8138)
		(width 0.14224)
		(layer "In2.Cu")
		(net "M_K_DQ<44>")
	)
	(segment
		(start 124.550424 -135.8138)
		(end 124.801376 -135.8138)
		(width 0.14224)
		(layer "In2.Cu")
		(net "M_K_DQ<44>")
	)
	(segment
		(start 118.276624 -128.45034)
		(end 118.431564 -128.2954)
		(width 0.14224)
		(layer "In2.Cu")
		(net "M_K_DQ<44>")
	)
	(segment
		(start 110.544864 -99.69119)
		(end 109.663738 -101.215444)
		(width 0.0889)
		(layer "In2.Cu")
		(net "M_K_DQ<44>")
	)
	(segment
		(start 119.453152 -129.13233)
		(end 119.602504 -128.982978)
		(width 0.14224)
		(layer "In2.Cu")
		(net "M_K_DQ<44>")
	)
	(segment
		(start 109.663738 -101.68382)
		(end 107.256072 -104.091486)
		(width 0.0889)
		(layer "In2.Cu")
		(net "M_K_DQ<44>")
	)
	(segment
		(start 118.431564 -128.2954)
		(end 118.784624 -128.2954)
		(width 0.14224)
		(layer "In2.Cu")
		(net "M_K_DQ<44>")
	)
	(segment
		(start 123.616466 -134.57809)
		(end 123.774454 -134.736078)
		(width 0.14224)
		(layer "In2.Cu")
		(net "M_K_DQ<44>")
	)
	(segment
		(start 117.768624 -128.92532)
		(end 118.121684 -128.92532)
		(width 0.14224)
		(layer "In2.Cu")
		(net "M_K_DQ<44>")
	)
	(segment
		(start 107.256072 -105.655872)
		(end 106.946446 -105.965498)
		(width 0.0889)
		(layer "In2.Cu")
		(net "M_K_DQ<44>")
	)
	(segment
		(start 119.757444 -128.2954)
		(end 120.374156 -128.2954)
		(width 0.14224)
		(layer "In2.Cu")
		(net "M_K_DQ<44>")
	)
	(segment
		(start 117.458744 -128.2954)
		(end 117.613684 -128.45034)
		(width 0.14224)
		(layer "In2.Cu")
		(net "M_K_DQ<44>")
	)
	(segment
		(start 117.613684 -128.45034)
		(end 117.613684 -128.77038)
		(width 0.14224)
		(layer "In2.Cu")
		(net "M_K_DQ<44>")
	)
	(segment
		(start 106.946446 -117.718078)
		(end 114.278156 -125.049788)
		(width 0.14224)
		(layer "In2.Cu")
		(net "M_K_DQ<44>")
	)
	(segment
		(start 118.276624 -128.77038)
		(end 118.276624 -128.45034)
		(width 0.14224)
		(layer "In2.Cu")
		(net "M_K_DQ<44>")
	)
	(segment
		(start 106.946446 -105.965498)
		(end 106.946446 -117.718078)
		(width 0.14224)
		(layer "In2.Cu")
		(net "M_K_DQ<44>")
	)
	(segment
		(start 123.616466 -132.044948)
		(end 123.616466 -134.57809)
		(width 0.14224)
		(layer "In2.Cu")
		(net "M_K_DQ<44>")
	)
	(segment
		(start 111.915702 -97.847658)
		(end 111.850424 -97.912936)
		(width 0.0889)
		(layer "In2.Cu")
		(net "M_K_DQ<44>")
	)
	(segment
		(start 118.939564 -128.971802)
		(end 119.100092 -129.13233)
		(width 0.14224)
		(layer "In2.Cu")
		(net "M_K_DQ<44>")
	)
	(segment
		(start 116.252244 -128.2954)
		(end 117.458744 -128.2954)
		(width 0.14224)
		(layer "In2.Cu")
		(net "M_K_DQ<44>")
	)
	(segment
		(start 118.121684 -128.92532)
		(end 118.276624 -128.77038)
		(width 0.14224)
		(layer "In2.Cu")
		(net "M_K_DQ<44>")
	)
	(segment
		(start 124.049536 -131.611878)
		(end 123.616466 -132.044948)
		(width 0.14224)
		(layer "In2.Cu")
		(net "M_K_DQ<44>")
	)
	(segment
		(start 123.404376 -129.807208)
		(end 123.848368 -130.2512)
		(width 0.14224)
		(layer "In2.Cu")
		(net "M_K_DQ<44>")
	)
	(segment
		(start 114.278156 -125.049788)
		(end 114.278156 -126.321312)
		(width 0.14224)
		(layer "In2.Cu")
		(net "M_K_DQ<44>")
	)
	(segment
		(start 123.774454 -134.736078)
		(end 123.774454 -135.03783)
		(width 0.14224)
		(layer "In2.Cu")
		(net "M_K_DQ<44>")
	)
	(segment
		(start 111.915702 -97.509584)
		(end 111.915702 -97.847658)
		(width 0.0889)
		(layer "In2.Cu")
		(net "M_K_DQ<44>")
	)
	(segment
		(start 119.100092 -129.13233)
		(end 119.453152 -129.13233)
		(width 0.14224)
		(layer "In2.Cu")
		(net "M_K_DQ<44>")
	)
	(segment
		(start 123.848368 -131.41071)
		(end 124.049536 -131.611878)
		(width 0.14224)
		(layer "In2.Cu")
		(net "M_K_DQ<44>")
	)
	(segment
		(start 123.848368 -130.2512)
		(end 123.848368 -131.41071)
		(width 0.14224)
		(layer "In2.Cu")
		(net "M_K_DQ<44>")
	)
	(segment
		(start 122.114564 -130.035808)
		(end 122.597164 -130.035808)
		(width 0.14224)
		(layer "In2.Cu")
		(net "M_K_DQ<44>")
	)
	(segment
		(start 110.545372 -99.690682)
		(end 110.544864 -99.69119)
		(width 0.0889)
		(layer "In2.Cu")
		(net "M_K_DQ<44>")
	)
	(segment
		(start 119.602504 -128.982978)
		(end 119.602504 -128.45034)
		(width 0.14224)
		(layer "In2.Cu")
		(net "M_K_DQ<44>")
	)
	(segment
		(start 118.939564 -128.45034)
		(end 118.939564 -128.971802)
		(width 0.14224)
		(layer "In2.Cu")
		(net "M_K_DQ<44>")
	)
	(segment
		(start 107.256072 -104.091486)
		(end 107.256072 -105.655872)
		(width 0.0889)
		(layer "In2.Cu")
		(net "M_K_DQ<44>")
	)
	(segment
		(start 109.663738 -101.215444)
		(end 109.663738 -101.68382)
		(width 0.0889)
		(layer "In2.Cu")
		(net "M_K_DQ<44>")
	)
	(segment
		(start 119.602504 -128.45034)
		(end 119.757444 -128.2954)
		(width 0.14224)
		(layer "In2.Cu")
		(net "M_K_DQ<44>")
	)
	(arc
		(start 111.403892 -98.795586)
		(mid 111.40664 -99.191053)
		(end 111.068358 -99.395788)
		(width 0.0889)
		(layer "In2.Cu")
		(net "M_K_DQ<44>")
	)
	(arc
		(start 111.03229 -99.395788)
		(mid 110.75099 -99.480754)
		(end 110.545372 -99.690682)
		(width 0.0889)
		(layer "In2.Cu")
		(net "M_K_DQ<44>")
	)
	(arc
		(start 111.850424 -97.912936)
		(mid 111.388455 -98.233478)
		(end 111.403892 -98.795586)
		(width 0.0889)
		(layer "In2.Cu")
		(net "M_K_DQ<44>")
	)
	(segment
		(start 114.778282 -98.500184)
		(end 115.349782 -98.500184)
		(width 0.1651)
		(layer "F.Cu")
		(net "M_K_DQ<43>")
	)
	(segment
		(start 131.699508 -133.0706)
		(end 131.699508 -134.340346)
		(width 0.1651)
		(layer "F.Cu")
		(net "M_K_DQ<43>")
	)
	(via
		(at 131.699508 -134.340346)
		(size 0.508)
		(drill 0.254)
		(layers "F.Cu" "B.Cu")
		(net "M_K_DQ<43>")
	)
	(via
		(at 132.549392 -130.330956)
		(size 0.508)
		(drill 0.254)
		(layers "F.Cu" "B.Cu")
		(net "M_K_DQ<43>")
	)
	(via
		(at 115.349782 -98.500184)
		(size 0.508)
		(drill 0.254)
		(layers "F.Cu" "B.Cu")
		(net "M_K_DQ<43>")
	)
	(segment
		(start 132.549392 -128.276096)
		(end 132.549392 -130.330956)
		(width 0.1651)
		(layer "B.Cu")
		(net "M_K_DQ<43>")
	)
	(segment
		(start 115.33759 -115.618514)
		(end 115.884706 -116.16563)
		(width 0.14224)
		(layer "In2.Cu")
		(net "M_K_DQ<43>")
	)
	(segment
		(start 118.402862 -118.464838)
		(end 118.501414 -118.366286)
		(width 0.14224)
		(layer "In2.Cu")
		(net "M_K_DQ<43>")
	)
	(segment
		(start 114.868706 -114.930682)
		(end 115.198398 -114.60099)
		(width 0.14224)
		(layer "In2.Cu")
		(net "M_K_DQ<43>")
	)
	(segment
		(start 132.839968 -123.799854)
		(end 132.839968 -124.835412)
		(width 0.14224)
		(layer "In2.Cu")
		(net "M_K_DQ<43>")
	)
	(segment
		(start 117.82806 -118.108984)
		(end 118.183914 -118.464838)
		(width 0.14224)
		(layer "In2.Cu")
		(net "M_K_DQ<43>")
	)
	(segment
		(start 119.552466 -119.614442)
		(end 119.651018 -119.51589)
		(width 0.14224)
		(layer "In2.Cu")
		(net "M_K_DQ<43>")
	)
	(segment
		(start 117.82806 -117.890036)
		(end 117.82806 -118.108984)
		(width 0.14224)
		(layer "In2.Cu")
		(net "M_K_DQ<43>")
	)
	(segment
		(start 117.03431 -117.315234)
		(end 117.253258 -117.315234)
		(width 0.14224)
		(layer "In2.Cu")
		(net "M_K_DQ<43>")
	)
	(segment
		(start 115.856766 -100.16617)
		(end 115.856766 -102.052882)
		(width 0.0889)
		(layer "In2.Cu")
		(net "M_K_DQ<43>")
	)
	(segment
		(start 117.926358 -117.572536)
		(end 117.926358 -117.791484)
		(width 0.14224)
		(layer "In2.Cu")
		(net "M_K_DQ<43>")
	)
	(segment
		(start 116.678456 -116.95938)
		(end 117.03431 -117.315234)
		(width 0.14224)
		(layer "In2.Cu")
		(net "M_K_DQ<43>")
	)
	(segment
		(start 114.469164 -114.750088)
		(end 114.649758 -114.930682)
		(width 0.14224)
		(layer "In2.Cu")
		(net "M_K_DQ<43>")
	)
	(segment
		(start 114.469164 -105.953814)
		(end 114.469164 -114.750088)
		(width 0.14224)
		(layer "In2.Cu")
		(net "M_K_DQ<43>")
	)
	(segment
		(start 114.222784 -104.817926)
		(end 114.222784 -105.707434)
		(width 0.0889)
		(layer "In2.Cu")
		(net "M_K_DQ<43>")
	)
	(segment
		(start 115.667282 -114.850926)
		(end 115.667282 -115.069874)
		(width 0.14224)
		(layer "In2.Cu")
		(net "M_K_DQ<43>")
	)
	(segment
		(start 120.127268 -120.189244)
		(end 120.127268 -120.408192)
		(width 0.14224)
		(layer "In2.Cu")
		(net "M_K_DQ<43>")
	)
	(segment
		(start 116.103654 -116.16563)
		(end 116.202206 -116.067078)
		(width 0.14224)
		(layer "In2.Cu")
		(net "M_K_DQ<43>")
	)
	(segment
		(start 132.143246 -131.9022)
		(end 131.860798 -132.184648)
		(width 0.14224)
		(layer "In2.Cu")
		(net "M_K_DQ<43>")
	)
	(segment
		(start 115.417346 -114.60099)
		(end 115.667282 -114.850926)
		(width 0.14224)
		(layer "In2.Cu")
		(net "M_K_DQ<43>")
	)
	(segment
		(start 120.964452 -121.245376)
		(end 130.28549 -121.245376)
		(width 0.14224)
		(layer "In2.Cu")
		(net "M_K_DQ<43>")
	)
	(segment
		(start 132.549392 -130.330956)
		(end 132.52704 -130.330956)
		(width 0.14224)
		(layer "In2.Cu")
		(net "M_K_DQ<43>")
	)
	(segment
		(start 132.52704 -130.330956)
		(end 132.098796 -130.7592)
		(width 0.14224)
		(layer "In2.Cu")
		(net "M_K_DQ<43>")
	)
	(segment
		(start 117.253258 -117.315234)
		(end 117.35181 -117.216682)
		(width 0.14224)
		(layer "In2.Cu")
		(net "M_K_DQ<43>")
	)
	(segment
		(start 116.776754 -116.64188)
		(end 116.678456 -116.740432)
		(width 0.14224)
		(layer "In2.Cu")
		(net "M_K_DQ<43>")
	)
	(segment
		(start 131.860798 -132.457952)
		(end 132.117846 -132.715)
		(width 0.14224)
		(layer "In2.Cu")
		(net "M_K_DQ<43>")
	)
	(segment
		(start 132.916168 -127.635)
		(end 132.916168 -129.96418)
		(width 0.14224)
		(layer "In2.Cu")
		(net "M_K_DQ<43>")
	)
	(segment
		(start 132.143246 -131.233418)
		(end 132.143246 -131.9022)
		(width 0.14224)
		(layer "In2.Cu")
		(net "M_K_DQ<43>")
	)
	(segment
		(start 115.94084 -99.5045)
		(end 115.939824 -99.505516)
		(width 0.0889)
		(layer "In2.Cu")
		(net "M_K_DQ<43>")
	)
	(segment
		(start 131.860798 -133.550152)
		(end 132.149596 -133.83895)
		(width 0.14224)
		(layer "In2.Cu")
		(net "M_K_DQ<43>")
	)
	(segment
		(start 119.075962 -118.72214)
		(end 119.075962 -118.941088)
		(width 0.14224)
		(layer "In2.Cu")
		(net "M_K_DQ<43>")
	)
	(segment
		(start 131.860798 -132.184648)
		(end 131.860798 -132.457952)
		(width 0.14224)
		(layer "In2.Cu")
		(net "M_K_DQ<43>")
	)
	(segment
		(start 132.149596 -134.162546)
		(end 131.971796 -134.340346)
		(width 0.14224)
		(layer "In2.Cu")
		(net "M_K_DQ<43>")
	)
	(segment
		(start 115.844828 -99.166172)
		(end 115.861338 -99.195382)
		(width 0.0889)
		(layer "In2.Cu")
		(net "M_K_DQ<43>")
	)
	(segment
		(start 116.678456 -116.740432)
		(end 116.678456 -116.95938)
		(width 0.14224)
		(layer "In2.Cu")
		(net "M_K_DQ<43>")
	)
	(segment
		(start 119.075962 -118.941088)
		(end 118.977664 -119.03964)
		(width 0.14224)
		(layer "In2.Cu")
		(net "M_K_DQ<43>")
	)
	(segment
		(start 114.649758 -114.930682)
		(end 114.868706 -114.930682)
		(width 0.14224)
		(layer "In2.Cu")
		(net "M_K_DQ<43>")
	)
	(segment
		(start 118.720108 -118.366286)
		(end 119.075962 -118.72214)
		(width 0.14224)
		(layer "In2.Cu")
		(net "M_K_DQ<43>")
	)
	(segment
		(start 117.35181 -117.216682)
		(end 117.570504 -117.216682)
		(width 0.14224)
		(layer "In2.Cu")
		(net "M_K_DQ<43>")
	)
	(segment
		(start 115.198398 -114.60099)
		(end 115.417346 -114.60099)
		(width 0.14224)
		(layer "In2.Cu")
		(net "M_K_DQ<43>")
	)
	(segment
		(start 117.570504 -117.216682)
		(end 117.926358 -117.572536)
		(width 0.14224)
		(layer "In2.Cu")
		(net "M_K_DQ<43>")
	)
	(segment
		(start 120.127268 -120.408192)
		(end 120.964452 -121.245376)
		(width 0.14224)
		(layer "In2.Cu")
		(net "M_K_DQ<43>")
	)
	(segment
		(start 119.651018 -119.51589)
		(end 119.869712 -119.51589)
		(width 0.14224)
		(layer "In2.Cu")
		(net "M_K_DQ<43>")
	)
	(segment
		(start 132.789168 -124.886212)
		(end 132.789168 -127.508)
		(width 0.14224)
		(layer "In2.Cu")
		(net "M_K_DQ<43>")
	)
	(segment
		(start 115.939824 -100.083112)
		(end 115.856766 -100.16617)
		(width 0.0889)
		(layer "In2.Cu")
		(net "M_K_DQ<43>")
	)
	(segment
		(start 131.971796 -134.340346)
		(end 131.699508 -134.340346)
		(width 0.14224)
		(layer "In2.Cu")
		(net "M_K_DQ<43>")
	)
	(segment
		(start 132.098796 -131.188968)
		(end 132.143246 -131.233418)
		(width 0.14224)
		(layer "In2.Cu")
		(net "M_K_DQ<43>")
	)
	(segment
		(start 115.884706 -116.16563)
		(end 116.103654 -116.16563)
		(width 0.14224)
		(layer "In2.Cu")
		(net "M_K_DQ<43>")
	)
	(segment
		(start 114.222784 -105.707434)
		(end 114.469164 -105.953814)
		(width 0.0889)
		(layer "In2.Cu")
		(net "M_K_DQ<43>")
	)
	(segment
		(start 118.183914 -118.464838)
		(end 118.402862 -118.464838)
		(width 0.14224)
		(layer "In2.Cu")
		(net "M_K_DQ<43>")
	)
	(segment
		(start 115.349782 -98.500184)
		(end 115.844828 -99.166172)
		(width 0.0889)
		(layer "In2.Cu")
		(net "M_K_DQ<43>")
	)
	(segment
		(start 132.098796 -130.7592)
		(end 132.098796 -131.188968)
		(width 0.14224)
		(layer "In2.Cu")
		(net "M_K_DQ<43>")
	)
	(segment
		(start 115.667282 -115.069874)
		(end 115.33759 -115.399566)
		(width 0.14224)
		(layer "In2.Cu")
		(net "M_K_DQ<43>")
	)
	(segment
		(start 120.225566 -119.871744)
		(end 120.225566 -120.090692)
		(width 0.14224)
		(layer "In2.Cu")
		(net "M_K_DQ<43>")
	)
	(segment
		(start 132.149596 -133.83895)
		(end 132.149596 -134.162546)
		(width 0.14224)
		(layer "In2.Cu")
		(net "M_K_DQ<43>")
	)
	(segment
		(start 115.002564 -104.038146)
		(end 114.222784 -104.817926)
		(width 0.0889)
		(layer "In2.Cu")
		(net "M_K_DQ<43>")
	)
	(segment
		(start 116.776754 -116.422932)
		(end 116.776754 -116.64188)
		(width 0.14224)
		(layer "In2.Cu")
		(net "M_K_DQ<43>")
	)
	(segment
		(start 116.4209 -116.067078)
		(end 116.776754 -116.422932)
		(width 0.14224)
		(layer "In2.Cu")
		(net "M_K_DQ<43>")
	)
	(segment
		(start 116.202206 -116.067078)
		(end 116.4209 -116.067078)
		(width 0.14224)
		(layer "In2.Cu")
		(net "M_K_DQ<43>")
	)
	(segment
		(start 115.939824 -99.505516)
		(end 115.939824 -100.083112)
		(width 0.0889)
		(layer "In2.Cu")
		(net "M_K_DQ<43>")
	)
	(segment
		(start 132.789168 -127.508)
		(end 132.916168 -127.635)
		(width 0.14224)
		(layer "In2.Cu")
		(net "M_K_DQ<43>")
	)
	(segment
		(start 117.926358 -117.791484)
		(end 117.82806 -117.890036)
		(width 0.14224)
		(layer "In2.Cu")
		(net "M_K_DQ<43>")
	)
	(segment
		(start 115.861338 -99.195382)
		(end 115.8621 -99.195382)
		(width 0.0889)
		(layer "In2.Cu")
		(net "M_K_DQ<43>")
	)
	(segment
		(start 130.28549 -121.245376)
		(end 132.839968 -123.799854)
		(width 0.14224)
		(layer "In2.Cu")
		(net "M_K_DQ<43>")
	)
	(segment
		(start 132.839968 -124.835412)
		(end 132.789168 -124.886212)
		(width 0.14224)
		(layer "In2.Cu")
		(net "M_K_DQ<43>")
	)
	(segment
		(start 119.869712 -119.51589)
		(end 120.225566 -119.871744)
		(width 0.14224)
		(layer "In2.Cu")
		(net "M_K_DQ<43>")
	)
	(segment
		(start 119.333518 -119.614442)
		(end 119.552466 -119.614442)
		(width 0.14224)
		(layer "In2.Cu")
		(net "M_K_DQ<43>")
	)
	(segment
		(start 118.501414 -118.366286)
		(end 118.720108 -118.366286)
		(width 0.14224)
		(layer "In2.Cu")
		(net "M_K_DQ<43>")
	)
	(segment
		(start 118.977664 -119.258588)
		(end 119.333518 -119.614442)
		(width 0.14224)
		(layer "In2.Cu")
		(net "M_K_DQ<43>")
	)
	(segment
		(start 115.8621 -99.195382)
		(end 115.869212 -99.208336)
		(width 0.0889)
		(layer "In2.Cu")
		(net "M_K_DQ<43>")
	)
	(segment
		(start 115.33759 -115.399566)
		(end 115.33759 -115.618514)
		(width 0.14224)
		(layer "In2.Cu")
		(net "M_K_DQ<43>")
	)
	(segment
		(start 132.117846 -133.0198)
		(end 131.860798 -133.276848)
		(width 0.14224)
		(layer "In2.Cu")
		(net "M_K_DQ<43>")
	)
	(segment
		(start 115.856766 -102.052882)
		(end 115.002564 -102.907084)
		(width 0.0889)
		(layer "In2.Cu")
		(net "M_K_DQ<43>")
	)
	(segment
		(start 115.002564 -102.907084)
		(end 115.002564 -104.038146)
		(width 0.0889)
		(layer "In2.Cu")
		(net "M_K_DQ<43>")
	)
	(segment
		(start 131.860798 -133.276848)
		(end 131.860798 -133.550152)
		(width 0.14224)
		(layer "In2.Cu")
		(net "M_K_DQ<43>")
	)
	(segment
		(start 132.916168 -129.96418)
		(end 132.549392 -130.330956)
		(width 0.14224)
		(layer "In2.Cu")
		(net "M_K_DQ<43>")
	)
	(segment
		(start 132.117846 -132.715)
		(end 132.117846 -133.0198)
		(width 0.14224)
		(layer "In2.Cu")
		(net "M_K_DQ<43>")
	)
	(segment
		(start 118.977664 -119.03964)
		(end 118.977664 -119.258588)
		(width 0.14224)
		(layer "In2.Cu")
		(net "M_K_DQ<43>")
	)
	(segment
		(start 120.225566 -120.090692)
		(end 120.127268 -120.189244)
		(width 0.14224)
		(layer "In2.Cu")
		(net "M_K_DQ<43>")
	)
	(arc
		(start 115.869212 -99.208336)
		(mid 115.924453 -99.351722)
		(end 115.94084 -99.5045)
		(width 0.0889)
		(layer "In2.Cu")
		(net "M_K_DQ<43>")
	)
	(segment
		(start 132.549392 -137.67054)
		(end 132.549392 -136.679432)
		(width 0.1651)
		(layer "F.Cu")
		(net "M_K_DQ<42>")
	)
	(segment
		(start 132.549392 -136.679432)
		(end 132.680964 -136.54786)
		(width 0.1651)
		(layer "F.Cu")
		(net "M_K_DQ<42>")
	)
	(segment
		(start 114.778282 -97.509584)
		(end 115.349782 -97.509584)
		(width 0.1651)
		(layer "F.Cu")
		(net "M_K_DQ<42>")
	)
	(segment
		(start 132.680964 -136.54786)
		(end 132.680964 -136.32434)
		(width 0.1651)
		(layer "F.Cu")
		(net "M_K_DQ<42>")
	)
	(segment
		(start 132.680964 -136.32434)
		(end 132.549392 -136.192768)
		(width 0.1651)
		(layer "F.Cu")
		(net "M_K_DQ<42>")
	)
	(segment
		(start 132.549392 -136.192768)
		(end 132.549392 -135.9154)
		(width 0.1651)
		(layer "F.Cu")
		(net "M_K_DQ<42>")
	)
	(via
		(at 132.549392 -135.9154)
		(size 0.508)
		(drill 0.254)
		(layers "F.Cu" "B.Cu")
		(net "M_K_DQ<42>")
	)
	(via
		(at 131.699508 -131.611878)
		(size 0.508)
		(drill 0.254)
		(layers "F.Cu" "B.Cu")
		(net "M_K_DQ<42>")
	)
	(via
		(at 115.349782 -97.509584)
		(size 0.508)
		(drill 0.254)
		(layers "F.Cu" "B.Cu")
		(net "M_K_DQ<42>")
	)
	(segment
		(start 131.699508 -132.876036)
		(end 131.699508 -131.611878)
		(width 0.1651)
		(layer "B.Cu")
		(net "M_K_DQ<42>")
	)
	(segment
		(start 114.032792 -104.739186)
		(end 114.032792 -105.73639)
		(width 0.0889)
		(layer "In2.Cu")
		(net "M_K_DQ<42>")
	)
	(segment
		(start 115.749832 -99.50196)
		(end 115.749832 -100.004372)
		(width 0.0889)
		(layer "In2.Cu")
		(net "M_K_DQ<42>")
	)
	(segment
		(start 131.544568 -131.456938)
		(end 131.699508 -131.611878)
		(width 0.14224)
		(layer "In2.Cu")
		(net "M_K_DQ<42>")
	)
	(segment
		(start 131.747768 -127.68961)
		(end 131.950968 -127.89281)
		(width 0.14224)
		(layer "In2.Cu")
		(net "M_K_DQ<42>")
	)
	(segment
		(start 131.699508 -131.611878)
		(end 131.266438 -132.044948)
		(width 0.14224)
		(layer "In2.Cu")
		(net "M_K_DQ<42>")
	)
	(segment
		(start 131.950968 -127.08001)
		(end 131.747768 -127.28321)
		(width 0.14224)
		(layer "In2.Cu")
		(net "M_K_DQ<42>")
	)
	(segment
		(start 113.815368 -105.953814)
		(end 113.815368 -114.782346)
		(width 0.14224)
		(layer "In2.Cu")
		(net "M_K_DQ<42>")
	)
	(segment
		(start 131.747768 -127.28321)
		(end 131.747768 -127.68961)
		(width 0.14224)
		(layer "In2.Cu")
		(net "M_K_DQ<42>")
	)
	(segment
		(start 120.913398 -121.880376)
		(end 129.98069 -121.880376)
		(width 0.14224)
		(layer "In2.Cu")
		(net "M_K_DQ<42>")
	)
	(segment
		(start 115.349782 -99.090734)
		(end 115.360958 -99.090734)
		(width 0.0889)
		(layer "In2.Cu")
		(net "M_K_DQ<42>")
	)
	(segment
		(start 131.849368 -125.6284)
		(end 131.976368 -125.7554)
		(width 0.14224)
		(layer "In2.Cu")
		(net "M_K_DQ<42>")
	)
	(segment
		(start 129.98069 -121.880376)
		(end 131.849368 -123.749054)
		(width 0.14224)
		(layer "In2.Cu")
		(net "M_K_DQ<42>")
	)
	(segment
		(start 131.266438 -134.632446)
		(end 132.549392 -135.9154)
		(width 0.14224)
		(layer "In2.Cu")
		(net "M_K_DQ<42>")
	)
	(segment
		(start 132.218176 -126.403608)
		(end 132.218176 -126.87681)
		(width 0.14224)
		(layer "In2.Cu")
		(net "M_K_DQ<42>")
	)
	(segment
		(start 132.218176 -129.805938)
		(end 131.544568 -130.479546)
		(width 0.14224)
		(layer "In2.Cu")
		(net "M_K_DQ<42>")
	)
	(segment
		(start 131.950968 -127.89281)
		(end 132.014976 -127.89281)
		(width 0.14224)
		(layer "In2.Cu")
		(net "M_K_DQ<42>")
	)
	(segment
		(start 131.849368 -123.749054)
		(end 131.849368 -125.6284)
		(width 0.14224)
		(layer "In2.Cu")
		(net "M_K_DQ<42>")
	)
	(segment
		(start 114.812572 -102.828344)
		(end 114.812572 -103.959406)
		(width 0.0889)
		(layer "In2.Cu")
		(net "M_K_DQ<42>")
	)
	(segment
		(start 115.349782 -97.509584)
		(end 115.020344 -98.270568)
		(width 0.0889)
		(layer "In2.Cu")
		(net "M_K_DQ<42>")
	)
	(segment
		(start 115.749832 -100.004372)
		(end 115.666774 -100.08743)
		(width 0.0889)
		(layer "In2.Cu")
		(net "M_K_DQ<42>")
	)
	(segment
		(start 115.003072 -98.700336)
		(end 115.167664 -98.985578)
		(width 0.0889)
		(layer "In2.Cu")
		(net "M_K_DQ<42>")
	)
	(segment
		(start 131.976368 -125.7554)
		(end 131.976368 -126.1618)
		(width 0.14224)
		(layer "In2.Cu")
		(net "M_K_DQ<42>")
	)
	(segment
		(start 115.666774 -101.974142)
		(end 114.812572 -102.828344)
		(width 0.0889)
		(layer "In2.Cu")
		(net "M_K_DQ<42>")
	)
	(segment
		(start 114.032792 -105.73639)
		(end 113.815368 -105.953814)
		(width 0.0889)
		(layer "In2.Cu")
		(net "M_K_DQ<42>")
	)
	(segment
		(start 132.218176 -126.87681)
		(end 132.014976 -127.08001)
		(width 0.14224)
		(layer "In2.Cu")
		(net "M_K_DQ<42>")
	)
	(segment
		(start 115.020344 -98.270568)
		(end 114.998246 -98.308922)
		(width 0.0889)
		(layer "In2.Cu")
		(net "M_K_DQ<42>")
	)
	(segment
		(start 132.014976 -127.08001)
		(end 131.950968 -127.08001)
		(width 0.14224)
		(layer "In2.Cu")
		(net "M_K_DQ<42>")
	)
	(segment
		(start 113.815368 -114.782346)
		(end 120.913398 -121.880376)
		(width 0.14224)
		(layer "In2.Cu")
		(net "M_K_DQ<42>")
	)
	(segment
		(start 132.218176 -128.09601)
		(end 132.218176 -129.805938)
		(width 0.14224)
		(layer "In2.Cu")
		(net "M_K_DQ<42>")
	)
	(segment
		(start 115.666774 -100.08743)
		(end 115.666774 -101.974142)
		(width 0.0889)
		(layer "In2.Cu")
		(net "M_K_DQ<42>")
	)
	(segment
		(start 131.976368 -126.1618)
		(end 132.218176 -126.403608)
		(width 0.14224)
		(layer "In2.Cu")
		(net "M_K_DQ<42>")
	)
	(segment
		(start 114.812572 -103.959406)
		(end 114.032792 -104.739186)
		(width 0.0889)
		(layer "In2.Cu")
		(net "M_K_DQ<42>")
	)
	(segment
		(start 132.014976 -127.89281)
		(end 132.218176 -128.09601)
		(width 0.14224)
		(layer "In2.Cu")
		(net "M_K_DQ<42>")
	)
	(segment
		(start 131.544568 -130.479546)
		(end 131.544568 -131.456938)
		(width 0.14224)
		(layer "In2.Cu")
		(net "M_K_DQ<42>")
	)
	(segment
		(start 131.266438 -132.044948)
		(end 131.266438 -134.632446)
		(width 0.14224)
		(layer "In2.Cu")
		(net "M_K_DQ<42>")
	)
	(arc
		(start 114.998246 -98.308922)
		(mid 114.949491 -98.505274)
		(end 115.003072 -98.700336)
		(width 0.0889)
		(layer "In2.Cu")
		(net "M_K_DQ<42>")
	)
	(arc
		(start 115.167664 -98.985578)
		(mid 115.244637 -99.062547)
		(end 115.349782 -99.090734)
		(width 0.0889)
		(layer "In2.Cu")
		(net "M_K_DQ<42>")
	)
	(arc
		(start 115.360958 -99.090734)
		(mid 115.640563 -99.215809)
		(end 115.749832 -99.50196)
		(width 0.0889)
		(layer "In2.Cu")
		(net "M_K_DQ<42>")
	)
	(segment
		(start 125.749558 -133.0706)
		(end 125.749558 -134.340346)
		(width 0.1651)
		(layer "F.Cu")
		(net "M_K_DQ<41>")
	)
	(segment
		(start 112.202722 -98.995738)
		(end 112.774222 -98.995738)
		(width 0.1651)
		(layer "F.Cu")
		(net "M_K_DQ<41>")
	)
	(via
		(at 126.421642 -130.330956)
		(size 0.508)
		(drill 0.254)
		(layers "F.Cu" "B.Cu")
		(net "M_K_DQ<41>")
	)
	(via
		(at 112.774222 -98.995738)
		(size 0.508)
		(drill 0.254)
		(layers "F.Cu" "B.Cu")
		(net "M_K_DQ<41>")
	)
	(via
		(at 125.749558 -134.340346)
		(size 0.508)
		(drill 0.254)
		(layers "F.Cu" "B.Cu")
		(net "M_K_DQ<41>")
	)
	(segment
		(start 126.599442 -129.649982)
		(end 126.421642 -129.827782)
		(width 0.1651)
		(layer "B.Cu")
		(net "M_K_DQ<41>")
	)
	(segment
		(start 126.421642 -129.827782)
		(end 126.421642 -130.330956)
		(width 0.1651)
		(layer "B.Cu")
		(net "M_K_DQ<41>")
	)
	(segment
		(start 126.599442 -128.276096)
		(end 126.599442 -129.649982)
		(width 0.1651)
		(layer "B.Cu")
		(net "M_K_DQ<41>")
	)
	(segment
		(start 108.978192 -115.838224)
		(end 116.192554 -123.052586)
		(width 0.14224)
		(layer "In2.Cu")
		(net "M_K_DQ<41>")
	)
	(segment
		(start 126.108968 -129.0828)
		(end 126.108968 -129.370328)
		(width 0.14224)
		(layer "In2.Cu")
		(net "M_K_DQ<41>")
	)
	(segment
		(start 126.201424 -131.823968)
		(end 125.910848 -132.114544)
		(width 0.14224)
		(layer "In2.Cu")
		(net "M_K_DQ<41>")
	)
	(segment
		(start 116.147596 -124.247148)
		(end 116.435124 -124.247148)
		(width 0.14224)
		(layer "In2.Cu")
		(net "M_K_DQ<41>")
	)
	(segment
		(start 126.150624 -133.8834)
		(end 126.150624 -134.1882)
		(width 0.14224)
		(layer "In2.Cu")
		(net "M_K_DQ<41>")
	)
	(segment
		(start 126.286768 -129.548128)
		(end 126.591568 -129.548128)
		(width 0.14224)
		(layer "In2.Cu")
		(net "M_K_DQ<41>")
	)
	(segment
		(start 123.06427 -128.197356)
		(end 127.128524 -128.197356)
		(width 0.14224)
		(layer "In2.Cu")
		(net "M_K_DQ<41>")
	)
	(segment
		(start 126.125224 -132.6896)
		(end 126.125224 -133.1214)
		(width 0.14224)
		(layer "In2.Cu")
		(net "M_K_DQ<41>")
	)
	(segment
		(start 110.72241 -103.071168)
		(end 108.74502 -105.048558)
		(width 0.0889)
		(layer "In2.Cu")
		(net "M_K_DQ<41>")
	)
	(segment
		(start 126.39929 -130.330956)
		(end 125.971046 -130.7592)
		(width 0.14224)
		(layer "In2.Cu")
		(net "M_K_DQ<41>")
	)
	(segment
		(start 118.181882 -125.949202)
		(end 118.181882 -126.242318)
		(width 0.14224)
		(layer "In2.Cu")
		(net "M_K_DQ<41>")
	)
	(segment
		(start 115.860322 -123.959874)
		(end 116.147596 -124.247148)
		(width 0.14224)
		(layer "In2.Cu")
		(net "M_K_DQ<41>")
	)
	(segment
		(start 116.192554 -123.052586)
		(end 116.192554 -123.340114)
		(width 0.14224)
		(layer "In2.Cu")
		(net "M_K_DQ<41>")
	)
	(segment
		(start 117.02669 -124.805186)
		(end 117.02669 -125.092714)
		(width 0.14224)
		(layer "In2.Cu")
		(net "M_K_DQ<41>")
	)
	(segment
		(start 125.910848 -133.643624)
		(end 126.150624 -133.8834)
		(width 0.14224)
		(layer "In2.Cu")
		(net "M_K_DQ<41>")
	)
	(segment
		(start 116.435124 -124.247148)
		(end 116.846604 -123.835668)
		(width 0.14224)
		(layer "In2.Cu")
		(net "M_K_DQ<41>")
	)
	(segment
		(start 126.108968 -129.370328)
		(end 126.286768 -129.548128)
		(width 0.14224)
		(layer "In2.Cu")
		(net "M_K_DQ<41>")
	)
	(segment
		(start 126.201424 -131.419346)
		(end 126.201424 -131.823968)
		(width 0.14224)
		(layer "In2.Cu")
		(net "M_K_DQ<41>")
	)
	(segment
		(start 127.272288 -128.34112)
		(end 127.272288 -128.73228)
		(width 0.14224)
		(layer "In2.Cu")
		(net "M_K_DQ<41>")
	)
	(segment
		(start 118.456964 -126.5174)
		(end 121.384314 -126.5174)
		(width 0.14224)
		(layer "In2.Cu")
		(net "M_K_DQ<41>")
	)
	(segment
		(start 118.181882 -126.242318)
		(end 118.456964 -126.5174)
		(width 0.14224)
		(layer "In2.Cu")
		(net "M_K_DQ<41>")
	)
	(segment
		(start 108.74502 -105.048558)
		(end 108.74502 -105.757726)
		(width 0.0889)
		(layer "In2.Cu")
		(net "M_K_DQ<41>")
	)
	(segment
		(start 116.846604 -123.835668)
		(end 117.134132 -123.835668)
		(width 0.14224)
		(layer "In2.Cu")
		(net "M_K_DQ<41>")
	)
	(segment
		(start 125.998478 -134.340346)
		(end 125.749558 -134.340346)
		(width 0.14224)
		(layer "In2.Cu")
		(net "M_K_DQ<41>")
	)
	(segment
		(start 117.134132 -123.835668)
		(end 117.421406 -124.122942)
		(width 0.14224)
		(layer "In2.Cu")
		(net "M_K_DQ<41>")
	)
	(segment
		(start 117.421406 -124.122942)
		(end 117.421406 -124.41047)
		(width 0.14224)
		(layer "In2.Cu")
		(net "M_K_DQ<41>")
	)
	(segment
		(start 126.794768 -130.038856)
		(end 126.502668 -130.330956)
		(width 0.14224)
		(layer "In2.Cu")
		(net "M_K_DQ<41>")
	)
	(segment
		(start 117.601492 -125.379988)
		(end 118.029736 -124.951744)
		(width 0.14224)
		(layer "In2.Cu")
		(net "M_K_DQ<41>")
	)
	(segment
		(start 127.124968 -128.8796)
		(end 126.312168 -128.8796)
		(width 0.14224)
		(layer "In2.Cu")
		(net "M_K_DQ<41>")
	)
	(segment
		(start 111.933482 -100.081334)
		(end 111.900716 -100.081334)
		(width 0.0889)
		(layer "In2.Cu")
		(net "M_K_DQ<41>")
	)
	(segment
		(start 117.421406 -124.41047)
		(end 117.02669 -124.805186)
		(width 0.14224)
		(layer "In2.Cu")
		(net "M_K_DQ<41>")
	)
	(segment
		(start 126.421642 -130.330956)
		(end 126.39929 -130.330956)
		(width 0.14224)
		(layer "In2.Cu")
		(net "M_K_DQ<41>")
	)
	(segment
		(start 126.125224 -133.1214)
		(end 125.910848 -133.335776)
		(width 0.14224)
		(layer "In2.Cu")
		(net "M_K_DQ<41>")
	)
	(segment
		(start 126.591568 -129.548128)
		(end 126.794768 -129.751328)
		(width 0.14224)
		(layer "In2.Cu")
		(net "M_K_DQ<41>")
	)
	(segment
		(start 125.910848 -133.335776)
		(end 125.910848 -133.643624)
		(width 0.14224)
		(layer "In2.Cu")
		(net "M_K_DQ<41>")
	)
	(segment
		(start 112.774222 -98.995738)
		(end 112.444276 -99.75723)
		(width 0.0889)
		(layer "In2.Cu")
		(net "M_K_DQ<41>")
	)
	(segment
		(start 126.150624 -134.1882)
		(end 125.998478 -134.340346)
		(width 0.14224)
		(layer "In2.Cu")
		(net "M_K_DQ<41>")
	)
	(segment
		(start 117.313964 -125.379988)
		(end 117.601492 -125.379988)
		(width 0.14224)
		(layer "In2.Cu")
		(net "M_K_DQ<41>")
	)
	(segment
		(start 126.502668 -130.330956)
		(end 126.421642 -130.330956)
		(width 0.14224)
		(layer "In2.Cu")
		(net "M_K_DQ<41>")
	)
	(segment
		(start 126.794768 -129.751328)
		(end 126.794768 -130.038856)
		(width 0.14224)
		(layer "In2.Cu")
		(net "M_K_DQ<41>")
	)
	(segment
		(start 118.029736 -124.951744)
		(end 118.317264 -124.951744)
		(width 0.14224)
		(layer "In2.Cu")
		(net "M_K_DQ<41>")
	)
	(segment
		(start 118.604538 -125.239018)
		(end 118.604538 -125.526546)
		(width 0.14224)
		(layer "In2.Cu")
		(net "M_K_DQ<41>")
	)
	(segment
		(start 125.971046 -131.188968)
		(end 126.201424 -131.419346)
		(width 0.14224)
		(layer "In2.Cu")
		(net "M_K_DQ<41>")
	)
	(segment
		(start 110.72241 -101.658166)
		(end 110.72241 -103.071168)
		(width 0.0889)
		(layer "In2.Cu")
		(net "M_K_DQ<41>")
	)
	(segment
		(start 126.312168 -128.8796)
		(end 126.108968 -129.0828)
		(width 0.14224)
		(layer "In2.Cu")
		(net "M_K_DQ<41>")
	)
	(segment
		(start 118.317264 -124.951744)
		(end 118.604538 -125.239018)
		(width 0.14224)
		(layer "In2.Cu")
		(net "M_K_DQ<41>")
	)
	(segment
		(start 121.384314 -126.5174)
		(end 123.06427 -128.197356)
		(width 0.14224)
		(layer "In2.Cu")
		(net "M_K_DQ<41>")
	)
	(segment
		(start 127.272288 -128.73228)
		(end 127.124968 -128.8796)
		(width 0.14224)
		(layer "In2.Cu")
		(net "M_K_DQ<41>")
	)
	(segment
		(start 108.74502 -105.757726)
		(end 108.978192 -105.990898)
		(width 0.0889)
		(layer "In2.Cu")
		(net "M_K_DQ<41>")
	)
	(segment
		(start 125.910848 -132.475224)
		(end 126.125224 -132.6896)
		(width 0.14224)
		(layer "In2.Cu")
		(net "M_K_DQ<41>")
	)
	(segment
		(start 112.444276 -99.75723)
		(end 112.427512 -99.785932)
		(width 0.0889)
		(layer "In2.Cu")
		(net "M_K_DQ<41>")
	)
	(segment
		(start 116.192554 -123.340114)
		(end 115.860322 -123.672346)
		(width 0.14224)
		(layer "In2.Cu")
		(net "M_K_DQ<41>")
	)
	(segment
		(start 125.910848 -132.114544)
		(end 125.910848 -132.475224)
		(width 0.14224)
		(layer "In2.Cu")
		(net "M_K_DQ<41>")
	)
	(segment
		(start 125.971046 -130.7592)
		(end 125.971046 -131.188968)
		(width 0.14224)
		(layer "In2.Cu")
		(net "M_K_DQ<41>")
	)
	(segment
		(start 108.978192 -105.990898)
		(end 108.978192 -115.838224)
		(width 0.14224)
		(layer "In2.Cu")
		(net "M_K_DQ<41>")
	)
	(segment
		(start 118.604538 -125.526546)
		(end 118.181882 -125.949202)
		(width 0.14224)
		(layer "In2.Cu")
		(net "M_K_DQ<41>")
	)
	(segment
		(start 127.128524 -128.197356)
		(end 127.272288 -128.34112)
		(width 0.14224)
		(layer "In2.Cu")
		(net "M_K_DQ<41>")
	)
	(segment
		(start 111.319818 -100.62464)
		(end 110.72241 -101.658166)
		(width 0.0889)
		(layer "In2.Cu")
		(net "M_K_DQ<41>")
	)
	(segment
		(start 115.860322 -123.672346)
		(end 115.860322 -123.959874)
		(width 0.14224)
		(layer "In2.Cu")
		(net "M_K_DQ<41>")
	)
	(segment
		(start 117.02669 -125.092714)
		(end 117.313964 -125.379988)
		(width 0.14224)
		(layer "In2.Cu")
		(net "M_K_DQ<41>")
	)
	(arc
		(start 112.427512 -99.785932)
		(mid 112.218904 -99.997864)
		(end 111.933482 -100.081334)
		(width 0.0889)
		(layer "In2.Cu")
		(net "M_K_DQ<41>")
	)
	(arc
		(start 111.624364 -100.207064)
		(mid 111.459049 -100.406341)
		(end 111.319818 -100.62464)
		(width 0.0889)
		(layer "In2.Cu")
		(net "M_K_DQ<41>")
	)
	(arc
		(start 111.900716 -100.081334)
		(mid 111.750122 -100.116926)
		(end 111.624364 -100.207064)
		(width 0.0889)
		(layer "In2.Cu")
		(net "M_K_DQ<41>")
	)
	(segment
		(start 126.599442 -137.676382)
		(end 126.421642 -135.8138)
		(width 0.1651)
		(layer "F.Cu")
		(net "M_K_DQ<40>")
	)
	(segment
		(start 112.202722 -97.014538)
		(end 112.774222 -97.014538)
		(width 0.1651)
		(layer "F.Cu")
		(net "M_K_DQ<40>")
	)
	(segment
		(start 126.599442 -137.67054)
		(end 126.599442 -137.676382)
		(width 0.1651)
		(layer "F.Cu")
		(net "M_K_DQ<40>")
	)
	(via
		(at 125.749558 -131.611878)
		(size 0.508)
		(drill 0.254)
		(layers "F.Cu" "B.Cu")
		(net "M_K_DQ<40>")
	)
	(via
		(at 126.421642 -135.8138)
		(size 0.508)
		(drill 0.254)
		(layers "F.Cu" "B.Cu")
		(net "M_K_DQ<40>")
	)
	(via
		(at 112.774222 -97.014538)
		(size 0.508)
		(drill 0.254)
		(layers "F.Cu" "B.Cu")
		(net "M_K_DQ<40>")
	)
	(segment
		(start 125.749558 -132.876036)
		(end 125.749558 -131.611878)
		(width 0.1651)
		(layer "B.Cu")
		(net "M_K_DQ<40>")
	)
	(segment
		(start 108.555028 -105.766362)
		(end 108.330492 -105.990898)
		(width 0.0889)
		(layer "In2.Cu")
		(net "M_K_DQ<40>")
	)
	(segment
		(start 124.842524 -128.654556)
		(end 125.169168 -128.9812)
		(width 0.14224)
		(layer "In2.Cu")
		(net "M_K_DQ<40>")
	)
	(segment
		(start 111.281464 -100.308664)
		(end 110.532418 -101.604826)
		(width 0.0889)
		(layer "In2.Cu")
		(net "M_K_DQ<40>")
	)
	(segment
		(start 125.169168 -128.9812)
		(end 125.169168 -129.83845)
		(width 0.14224)
		(layer "In2.Cu")
		(net "M_K_DQ<40>")
	)
	(segment
		(start 114.914426 -123.49353)
		(end 114.914426 -123.781058)
		(width 0.14224)
		(layer "In2.Cu")
		(net "M_K_DQ<40>")
	)
	(segment
		(start 125.316488 -132.044948)
		(end 125.316488 -135.00481)
		(width 0.14224)
		(layer "In2.Cu")
		(net "M_K_DQ<40>")
	)
	(segment
		(start 115.160298 -122.96013)
		(end 115.160298 -123.247658)
		(width 0.14224)
		(layer "In2.Cu")
		(net "M_K_DQ<40>")
	)
	(segment
		(start 125.372368 -131.408424)
		(end 125.575822 -131.611878)
		(width 0.14224)
		(layer "In2.Cu")
		(net "M_K_DQ<40>")
	)
	(segment
		(start 111.933736 -99.89058)
		(end 111.897922 -99.89058)
		(width 0.0889)
		(layer "In2.Cu")
		(net "M_K_DQ<40>")
	)
	(segment
		(start 112.577118 -121.51995)
		(end 112.864392 -121.807224)
		(width 0.14224)
		(layer "In2.Cu")
		(net "M_K_DQ<40>")
	)
	(segment
		(start 114.023394 -121.797826)
		(end 114.023394 -122.085354)
		(width 0.14224)
		(layer "In2.Cu")
		(net "M_K_DQ<40>")
	)
	(segment
		(start 112.87379 -120.648222)
		(end 112.87379 -120.93575)
		(width 0.14224)
		(layer "In2.Cu")
		(net "M_K_DQ<40>")
	)
	(segment
		(start 112.256062 -98.289618)
		(end 112.262412 -98.300286)
		(width 0.0889)
		(layer "In2.Cu")
		(net "M_K_DQ<40>")
	)
	(segment
		(start 121.054114 -127.1524)
		(end 122.55627 -128.654556)
		(width 0.14224)
		(layer "In2.Cu")
		(net "M_K_DQ<40>")
	)
	(segment
		(start 126.125478 -135.8138)
		(end 126.421642 -135.8138)
		(width 0.14224)
		(layer "In2.Cu")
		(net "M_K_DQ<40>")
	)
	(segment
		(start 125.749558 -131.611878)
		(end 125.316488 -132.044948)
		(width 0.14224)
		(layer "In2.Cu")
		(net "M_K_DQ<40>")
	)
	(segment
		(start 114.039396 -122.931428)
		(end 114.326924 -122.931428)
		(width 0.14224)
		(layer "In2.Cu")
		(net "M_K_DQ<40>")
	)
	(segment
		(start 108.330492 -105.990898)
		(end 108.330492 -116.104924)
		(width 0.14224)
		(layer "In2.Cu")
		(net "M_K_DQ<40>")
	)
	(segment
		(start 108.330492 -116.104924)
		(end 112.87379 -120.648222)
		(width 0.14224)
		(layer "In2.Cu")
		(net "M_K_DQ<40>")
	)
	(segment
		(start 111.284766 -100.303584)
		(end 111.281464 -100.308664)
		(width 0.0889)
		(layer "In2.Cu")
		(net "M_K_DQ<40>")
	)
	(segment
		(start 112.87379 -120.93575)
		(end 112.577118 -121.232422)
		(width 0.14224)
		(layer "In2.Cu")
		(net "M_K_DQ<40>")
	)
	(segment
		(start 113.15192 -121.807224)
		(end 113.448592 -121.510552)
		(width 0.14224)
		(layer "In2.Cu")
		(net "M_K_DQ<40>")
	)
	(segment
		(start 113.752122 -122.644154)
		(end 114.039396 -122.931428)
		(width 0.14224)
		(layer "In2.Cu")
		(net "M_K_DQ<40>")
	)
	(segment
		(start 114.914426 -123.781058)
		(end 118.285768 -127.1524)
		(width 0.14224)
		(layer "In2.Cu")
		(net "M_K_DQ<40>")
	)
	(segment
		(start 114.585496 -122.672856)
		(end 114.873024 -122.672856)
		(width 0.14224)
		(layer "In2.Cu")
		(net "M_K_DQ<40>")
	)
	(segment
		(start 108.555028 -104.969818)
		(end 108.555028 -105.766362)
		(width 0.0889)
		(layer "In2.Cu")
		(net "M_K_DQ<40>")
	)
	(segment
		(start 112.279176 -97.680272)
		(end 112.262412 -97.709736)
		(width 0.0889)
		(layer "In2.Cu")
		(net "M_K_DQ<40>")
	)
	(segment
		(start 113.448592 -121.510552)
		(end 113.73612 -121.510552)
		(width 0.14224)
		(layer "In2.Cu")
		(net "M_K_DQ<40>")
	)
	(segment
		(start 112.262412 -98.300286)
		(end 112.267238 -98.308922)
		(width 0.0889)
		(layer "In2.Cu")
		(net "M_K_DQ<40>")
	)
	(segment
		(start 114.873024 -122.672856)
		(end 115.160298 -122.96013)
		(width 0.14224)
		(layer "In2.Cu")
		(net "M_K_DQ<40>")
	)
	(segment
		(start 110.532418 -102.992428)
		(end 108.555028 -104.969818)
		(width 0.0889)
		(layer "In2.Cu")
		(net "M_K_DQ<40>")
	)
	(segment
		(start 110.532418 -101.604826)
		(end 110.532418 -102.992428)
		(width 0.0889)
		(layer "In2.Cu")
		(net "M_K_DQ<40>")
	)
	(segment
		(start 114.023394 -122.085354)
		(end 113.752122 -122.356626)
		(width 0.14224)
		(layer "In2.Cu")
		(net "M_K_DQ<40>")
	)
	(segment
		(start 114.326924 -122.931428)
		(end 114.585496 -122.672856)
		(width 0.14224)
		(layer "In2.Cu")
		(net "M_K_DQ<40>")
	)
	(segment
		(start 112.864392 -121.807224)
		(end 113.15192 -121.807224)
		(width 0.14224)
		(layer "In2.Cu")
		(net "M_K_DQ<40>")
	)
	(segment
		(start 113.73612 -121.510552)
		(end 114.023394 -121.797826)
		(width 0.14224)
		(layer "In2.Cu")
		(net "M_K_DQ<40>")
	)
	(segment
		(start 118.285768 -127.1524)
		(end 121.054114 -127.1524)
		(width 0.14224)
		(layer "In2.Cu")
		(net "M_K_DQ<40>")
	)
	(segment
		(start 112.256062 -99.280218)
		(end 112.262412 -99.290886)
		(width 0.0889)
		(layer "In2.Cu")
		(net "M_K_DQ<40>")
	)
	(segment
		(start 122.55627 -128.654556)
		(end 124.842524 -128.654556)
		(width 0.14224)
		(layer "In2.Cu")
		(net "M_K_DQ<40>")
	)
	(segment
		(start 125.575822 -131.611878)
		(end 125.749558 -131.611878)
		(width 0.14224)
		(layer "In2.Cu")
		(net "M_K_DQ<40>")
	)
	(segment
		(start 115.160298 -123.247658)
		(end 114.914426 -123.49353)
		(width 0.14224)
		(layer "In2.Cu")
		(net "M_K_DQ<40>")
	)
	(segment
		(start 113.752122 -122.356626)
		(end 113.752122 -122.644154)
		(width 0.14224)
		(layer "In2.Cu")
		(net "M_K_DQ<40>")
	)
	(segment
		(start 125.169168 -129.83845)
		(end 125.372368 -130.04165)
		(width 0.14224)
		(layer "In2.Cu")
		(net "M_K_DQ<40>")
	)
	(segment
		(start 125.372368 -130.04165)
		(end 125.372368 -131.408424)
		(width 0.14224)
		(layer "In2.Cu")
		(net "M_K_DQ<40>")
	)
	(segment
		(start 112.774222 -97.014538)
		(end 112.279176 -97.680272)
		(width 0.0889)
		(layer "In2.Cu")
		(net "M_K_DQ<40>")
	)
	(segment
		(start 112.577118 -121.232422)
		(end 112.577118 -121.51995)
		(width 0.14224)
		(layer "In2.Cu")
		(net "M_K_DQ<40>")
	)
	(segment
		(start 125.316488 -135.00481)
		(end 126.125478 -135.8138)
		(width 0.14224)
		(layer "In2.Cu")
		(net "M_K_DQ<40>")
	)
	(arc
		(start 112.262412 -98.700336)
		(mid 112.18319 -98.989454)
		(end 112.256062 -99.280218)
		(width 0.0889)
		(layer "In2.Cu")
		(net "M_K_DQ<40>")
	)
	(arc
		(start 112.262412 -97.709736)
		(mid 112.18319 -97.998854)
		(end 112.256062 -98.289618)
		(width 0.0889)
		(layer "In2.Cu")
		(net "M_K_DQ<40>")
	)
	(arc
		(start 111.572802 -100.000054)
		(mid 111.414147 -100.13793)
		(end 111.284766 -100.303584)
		(width 0.0889)
		(layer "In2.Cu")
		(net "M_K_DQ<40>")
	)
	(arc
		(start 112.262412 -99.290886)
		(mid 112.266657 -99.683131)
		(end 111.933736 -99.89058)
		(width 0.0889)
		(layer "In2.Cu")
		(net "M_K_DQ<40>")
	)
	(arc
		(start 111.897922 -99.89058)
		(mid 111.727231 -99.92118)
		(end 111.572802 -100.000054)
		(width 0.0889)
		(layer "In2.Cu")
		(net "M_K_DQ<40>")
	)
	(arc
		(start 112.267238 -98.308922)
		(mid 112.315993 -98.505274)
		(end 112.262412 -98.700336)
		(width 0.0889)
		(layer "In2.Cu")
		(net "M_K_DQ<40>")
	)
	(segment
		(start 39.049452 -133.0706)
		(end 39.049452 -134.340346)
		(width 0.1651)
		(layer "F.Cu")
		(net "M_K_DQ<3>")
	)
	(segment
		(start 69.466206 -89.27084)
		(end 68.894706 -89.27084)
		(width 0.1651)
		(layer "F.Cu")
		(net "M_K_DQ<3>")
	)
	(via
		(at 39.899336 -130.330956)
		(size 0.508)
		(drill 0.254)
		(layers "F.Cu" "B.Cu")
		(net "M_K_DQ<3>")
	)
	(via
		(at 68.894706 -89.27084)
		(size 0.508)
		(drill 0.254)
		(layers "F.Cu" "B.Cu")
		(net "M_K_DQ<3>")
	)
	(via
		(at 39.049452 -134.340346)
		(size 0.508)
		(drill 0.254)
		(layers "F.Cu" "B.Cu")
		(net "M_K_DQ<3>")
	)
	(segment
		(start 39.899336 -128.276096)
		(end 39.899336 -130.330956)
		(width 0.1651)
		(layer "B.Cu")
		(net "M_K_DQ<3>")
	)
	(segment
		(start 43.47972 -113.329466)
		(end 43.47972 -119.5324)
		(width 0.14224)
		(layer "In2.Cu")
		(net "M_K_DQ<3>")
	)
	(segment
		(start 67.824858 -89.27084)
		(end 67.295014 -89.800684)
		(width 0.0889)
		(layer "In2.Cu")
		(net "M_K_DQ<3>")
	)
	(segment
		(start 65.273682 -89.916)
		(end 54.781958 -100.407724)
		(width 0.14224)
		(layer "In2.Cu")
		(net "M_K_DQ<3>")
	)
	(segment
		(start 66.776854 -89.916)
		(end 65.90792 -89.916)
		(width 0.0889)
		(layer "In2.Cu")
		(net "M_K_DQ<3>")
	)
	(segment
		(start 39.46779 -132.715)
		(end 39.46779 -133.0198)
		(width 0.14224)
		(layer "In2.Cu")
		(net "M_K_DQ<3>")
	)
	(segment
		(start 42.66692 -115.1636)
		(end 42.46372 -114.9604)
		(width 0.14224)
		(layer "In2.Cu")
		(net "M_K_DQ<3>")
	)
	(segment
		(start 43.47972 -119.5324)
		(end 43.27652 -119.7356)
		(width 0.14224)
		(layer "In2.Cu")
		(net "M_K_DQ<3>")
	)
	(segment
		(start 39.210742 -133.550152)
		(end 39.49954 -133.83895)
		(width 0.14224)
		(layer "In2.Cu")
		(net "M_K_DQ<3>")
	)
	(segment
		(start 39.32174 -134.340346)
		(end 39.049452 -134.340346)
		(width 0.14224)
		(layer "In2.Cu")
		(net "M_K_DQ<3>")
	)
	(segment
		(start 41.85412 -128.778)
		(end 41.57472 -129.0574)
		(width 0.14224)
		(layer "In2.Cu")
		(net "M_K_DQ<3>")
	)
	(segment
		(start 66.89217 -89.800684)
		(end 66.776854 -89.916)
		(width 0.0889)
		(layer "In2.Cu")
		(net "M_K_DQ<3>")
	)
	(segment
		(start 68.894706 -89.27084)
		(end 67.824858 -89.27084)
		(width 0.0889)
		(layer "In2.Cu")
		(net "M_K_DQ<3>")
	)
	(segment
		(start 39.44874 -130.7592)
		(end 39.44874 -131.188968)
		(width 0.14224)
		(layer "In2.Cu")
		(net "M_K_DQ<3>")
	)
	(segment
		(start 42.05732 -114.9604)
		(end 41.85412 -115.1636)
		(width 0.14224)
		(layer "In2.Cu")
		(net "M_K_DQ<3>")
	)
	(segment
		(start 67.295014 -89.800684)
		(end 66.89217 -89.800684)
		(width 0.0889)
		(layer "In2.Cu")
		(net "M_K_DQ<3>")
	)
	(segment
		(start 42.87012 -119.7356)
		(end 42.66692 -119.5324)
		(width 0.14224)
		(layer "In2.Cu")
		(net "M_K_DQ<3>")
	)
	(segment
		(start 41.57472 -129.0574)
		(end 40.35552 -129.0574)
		(width 0.14224)
		(layer "In2.Cu")
		(net "M_K_DQ<3>")
	)
	(segment
		(start 42.46372 -114.9604)
		(end 42.05732 -114.9604)
		(width 0.14224)
		(layer "In2.Cu")
		(net "M_K_DQ<3>")
	)
	(segment
		(start 39.210742 -133.276848)
		(end 39.210742 -133.550152)
		(width 0.14224)
		(layer "In2.Cu")
		(net "M_K_DQ<3>")
	)
	(segment
		(start 39.899336 -130.330956)
		(end 39.876984 -130.330956)
		(width 0.14224)
		(layer "In2.Cu")
		(net "M_K_DQ<3>")
	)
	(segment
		(start 40.22852 -129.1844)
		(end 40.22852 -130.01498)
		(width 0.14224)
		(layer "In2.Cu")
		(net "M_K_DQ<3>")
	)
	(segment
		(start 54.781958 -102.027228)
		(end 43.47972 -113.329466)
		(width 0.14224)
		(layer "In2.Cu")
		(net "M_K_DQ<3>")
	)
	(segment
		(start 40.22852 -130.01498)
		(end 39.899336 -130.344164)
		(width 0.14224)
		(layer "In2.Cu")
		(net "M_K_DQ<3>")
	)
	(segment
		(start 39.49954 -133.83895)
		(end 39.49954 -134.162546)
		(width 0.14224)
		(layer "In2.Cu")
		(net "M_K_DQ<3>")
	)
	(segment
		(start 65.90792 -89.916)
		(end 65.273682 -89.916)
		(width 0.14224)
		(layer "In2.Cu")
		(net "M_K_DQ<3>")
	)
	(segment
		(start 39.210742 -132.184648)
		(end 39.210742 -132.457952)
		(width 0.14224)
		(layer "In2.Cu")
		(net "M_K_DQ<3>")
	)
	(segment
		(start 39.49319 -131.9022)
		(end 39.210742 -132.184648)
		(width 0.14224)
		(layer "In2.Cu")
		(net "M_K_DQ<3>")
	)
	(segment
		(start 39.49954 -134.162546)
		(end 39.32174 -134.340346)
		(width 0.14224)
		(layer "In2.Cu")
		(net "M_K_DQ<3>")
	)
	(segment
		(start 42.66692 -119.5324)
		(end 42.66692 -115.1636)
		(width 0.14224)
		(layer "In2.Cu")
		(net "M_K_DQ<3>")
	)
	(segment
		(start 39.876984 -130.330956)
		(end 39.44874 -130.7592)
		(width 0.14224)
		(layer "In2.Cu")
		(net "M_K_DQ<3>")
	)
	(segment
		(start 43.27652 -119.7356)
		(end 42.87012 -119.7356)
		(width 0.14224)
		(layer "In2.Cu")
		(net "M_K_DQ<3>")
	)
	(segment
		(start 39.44874 -131.188968)
		(end 39.49319 -131.233418)
		(width 0.14224)
		(layer "In2.Cu")
		(net "M_K_DQ<3>")
	)
	(segment
		(start 40.35552 -129.0574)
		(end 40.22852 -129.1844)
		(width 0.14224)
		(layer "In2.Cu")
		(net "M_K_DQ<3>")
	)
	(segment
		(start 39.210742 -132.457952)
		(end 39.46779 -132.715)
		(width 0.14224)
		(layer "In2.Cu")
		(net "M_K_DQ<3>")
	)
	(segment
		(start 54.781958 -100.407724)
		(end 54.781958 -102.027228)
		(width 0.14224)
		(layer "In2.Cu")
		(net "M_K_DQ<3>")
	)
	(segment
		(start 41.85412 -115.1636)
		(end 41.85412 -128.778)
		(width 0.14224)
		(layer "In2.Cu")
		(net "M_K_DQ<3>")
	)
	(segment
		(start 39.49319 -131.233418)
		(end 39.49319 -131.9022)
		(width 0.14224)
		(layer "In2.Cu")
		(net "M_K_DQ<3>")
	)
	(segment
		(start 39.899336 -130.344164)
		(end 39.899336 -130.330956)
		(width 0.14224)
		(layer "In2.Cu")
		(net "M_K_DQ<3>")
	)
	(segment
		(start 39.46779 -133.0198)
		(end 39.210742 -133.276848)
		(width 0.14224)
		(layer "In2.Cu")
		(net "M_K_DQ<3>")
	)
	(segment
		(start 121.42978 -127.93218)
		(end 121.30278 -128.05918)
		(width 0.1651)
		(layer "F.Cu")
		(net "M_K_DQ<39>")
	)
	(segment
		(start 119.830596 -123.045728)
		(end 120.066054 -123.281186)
		(width 0.1651)
		(layer "F.Cu")
		(net "M_K_DQ<39>")
	)
	(segment
		(start 117.686074 -121.17832)
		(end 117.929152 -121.17832)
		(width 0.1651)
		(layer "F.Cu")
		(net "M_K_DQ<39>")
	)
	(segment
		(start 112.037368 -113.284)
		(end 112.469168 -113.284)
		(width 0.1016)
		(layer "F.Cu")
		(net "M_K_DQ<39>")
	)
	(segment
		(start 117.211348 -120.701054)
		(end 116.917216 -120.995186)
		(width 0.1651)
		(layer "F.Cu")
		(net "M_K_DQ<39>")
	)
	(segment
		(start 118.664482 -123.15952)
		(end 118.95074 -123.445778)
		(width 0.1651)
		(layer "F.Cu")
		(net "M_K_DQ<39>")
	)
	(segment
		(start 121.625868 -126.03226)
		(end 121.460768 -126.19736)
		(width 0.1651)
		(layer "F.Cu")
		(net "M_K_DQ<39>")
	)
	(segment
		(start 111.344202 -103.768144)
		(end 111.494062 -103.918004)
		(width 0.0889)
		(layer "F.Cu")
		(net "M_K_DQ<39>")
	)
	(segment
		(start 110.940342 -112.186974)
		(end 112.037368 -113.284)
		(width 0.1016)
		(layer "F.Cu")
		(net "M_K_DQ<39>")
	)
	(segment
		(start 121.816368 -125.86716)
		(end 121.651268 -126.03226)
		(width 0.1651)
		(layer "F.Cu")
		(net "M_K_DQ<39>")
	)
	(segment
		(start 113.993168 -114.808)
		(end 113.993168 -117.242336)
		(width 0.1651)
		(layer "F.Cu")
		(net "M_K_DQ<39>")
	)
	(segment
		(start 120.066054 -123.281186)
		(end 120.066054 -123.52909)
		(width 0.1651)
		(layer "F.Cu")
		(net "M_K_DQ<39>")
	)
	(segment
		(start 121.30278 -128.05918)
		(end 121.30278 -128.75768)
		(width 0.1651)
		(layer "F.Cu")
		(net "M_K_DQ<39>")
	)
	(segment
		(start 117.211348 -120.460516)
		(end 117.211348 -120.701054)
		(width 0.1651)
		(layer "F.Cu")
		(net "M_K_DQ<39>")
	)
	(segment
		(start 121.779792 -127.93218)
		(end 121.42978 -127.93218)
		(width 0.1651)
		(layer "F.Cu")
		(net "M_K_DQ<39>")
	)
	(segment
		(start 117.412008 -121.452386)
		(end 117.686074 -121.17832)
		(width 0.1651)
		(layer "F.Cu")
		(net "M_K_DQ<39>")
	)
	(segment
		(start 111.494062 -103.918004)
		(end 111.494062 -105.318306)
		(width 0.0889)
		(layer "F.Cu")
		(net "M_K_DQ<39>")
	)
	(segment
		(start 121.767092 -127.10922)
		(end 121.938542 -127.28067)
		(width 0.1651)
		(layer "F.Cu")
		(net "M_K_DQ<39>")
	)
	(segment
		(start 111.344202 -102.462584)
		(end 111.344202 -103.768144)
		(width 0.0889)
		(layer "F.Cu")
		(net "M_K_DQ<39>")
	)
	(segment
		(start 112.469168 -113.284)
		(end 113.993168 -114.808)
		(width 0.1651)
		(layer "F.Cu")
		(net "M_K_DQ<39>")
	)
	(segment
		(start 121.460768 -126.19736)
		(end 121.460768 -126.96952)
		(width 0.1651)
		(layer "F.Cu")
		(net "M_K_DQ<39>")
	)
	(segment
		(start 110.940342 -106.553)
		(end 110.940342 -112.186974)
		(width 0.1016)
		(layer "F.Cu")
		(net "M_K_DQ<39>")
	)
	(segment
		(start 121.30278 -128.75768)
		(end 121.867168 -129.322068)
		(width 0.1651)
		(layer "F.Cu")
		(net "M_K_DQ<39>")
	)
	(segment
		(start 119.582692 -123.045728)
		(end 119.830596 -123.045728)
		(width 0.1651)
		(layer "F.Cu")
		(net "M_K_DQ<39>")
	)
	(segment
		(start 116.917216 -121.175272)
		(end 117.19433 -121.452386)
		(width 0.1651)
		(layer "F.Cu")
		(net "M_K_DQ<39>")
	)
	(segment
		(start 111.494062 -105.318306)
		(end 110.838742 -105.973626)
		(width 0.0889)
		(layer "F.Cu")
		(net "M_K_DQ<39>")
	)
	(segment
		(start 121.867168 -129.322068)
		(end 121.867168 -129.963164)
		(width 0.1651)
		(layer "F.Cu")
		(net "M_K_DQ<39>")
	)
	(segment
		(start 118.664482 -122.895614)
		(end 118.664482 -123.15952)
		(width 0.1651)
		(layer "F.Cu")
		(net "M_K_DQ<39>")
	)
	(segment
		(start 120.649492 -133.0706)
		(end 120.649492 -134.340346)
		(width 0.1651)
		(layer "F.Cu")
		(net "M_K_DQ<39>")
	)
	(segment
		(start 121.938542 -127.28067)
		(end 121.938542 -127.77343)
		(width 0.1651)
		(layer "F.Cu")
		(net "M_K_DQ<39>")
	)
	(segment
		(start 113.993168 -117.242336)
		(end 117.211348 -120.460516)
		(width 0.1651)
		(layer "F.Cu")
		(net "M_K_DQ<39>")
	)
	(segment
		(start 121.600468 -127.10922)
		(end 121.767092 -127.10922)
		(width 0.1651)
		(layer "F.Cu")
		(net "M_K_DQ<39>")
	)
	(segment
		(start 117.19433 -121.452386)
		(end 117.412008 -121.452386)
		(width 0.1651)
		(layer "F.Cu")
		(net "M_K_DQ<39>")
	)
	(segment
		(start 121.867168 -129.963164)
		(end 121.499376 -130.330956)
		(width 0.1651)
		(layer "F.Cu")
		(net "M_K_DQ<39>")
	)
	(segment
		(start 121.938542 -127.77343)
		(end 121.779792 -127.93218)
		(width 0.1651)
		(layer "F.Cu")
		(net "M_K_DQ<39>")
	)
	(segment
		(start 110.838742 -105.973626)
		(end 110.838742 -106.4514)
		(width 0.0889)
		(layer "F.Cu")
		(net "M_K_DQ<39>")
	)
	(segment
		(start 118.996968 -122.563128)
		(end 118.664482 -122.895614)
		(width 0.1651)
		(layer "F.Cu")
		(net "M_K_DQ<39>")
	)
	(segment
		(start 121.651268 -125.2093)
		(end 121.816368 -125.3744)
		(width 0.1651)
		(layer "F.Cu")
		(net "M_K_DQ<39>")
	)
	(segment
		(start 117.929152 -121.17832)
		(end 118.996968 -122.246136)
		(width 0.1651)
		(layer "F.Cu")
		(net "M_K_DQ<39>")
	)
	(segment
		(start 120.762268 -125.2093)
		(end 121.651268 -125.2093)
		(width 0.1651)
		(layer "F.Cu")
		(net "M_K_DQ<39>")
	)
	(segment
		(start 119.698008 -123.897136)
		(end 119.698008 -124.14504)
		(width 0.1651)
		(layer "F.Cu")
		(net "M_K_DQ<39>")
	)
	(segment
		(start 121.460768 -126.96952)
		(end 121.600468 -127.10922)
		(width 0.1651)
		(layer "F.Cu")
		(net "M_K_DQ<39>")
	)
	(segment
		(start 120.066054 -123.52909)
		(end 119.698008 -123.897136)
		(width 0.1651)
		(layer "F.Cu")
		(net "M_K_DQ<39>")
	)
	(segment
		(start 119.182642 -123.445778)
		(end 119.582692 -123.045728)
		(width 0.1651)
		(layer "F.Cu")
		(net "M_K_DQ<39>")
	)
	(segment
		(start 118.996968 -122.246136)
		(end 118.996968 -122.563128)
		(width 0.1651)
		(layer "F.Cu")
		(net "M_K_DQ<39>")
	)
	(segment
		(start 121.651268 -126.03226)
		(end 121.625868 -126.03226)
		(width 0.1651)
		(layer "F.Cu")
		(net "M_K_DQ<39>")
	)
	(segment
		(start 118.95074 -123.445778)
		(end 119.182642 -123.445778)
		(width 0.1651)
		(layer "F.Cu")
		(net "M_K_DQ<39>")
	)
	(segment
		(start 116.917216 -120.995186)
		(end 116.917216 -121.175272)
		(width 0.1651)
		(layer "F.Cu")
		(net "M_K_DQ<39>")
	)
	(segment
		(start 119.698008 -124.14504)
		(end 120.762268 -125.2093)
		(width 0.1651)
		(layer "F.Cu")
		(net "M_K_DQ<39>")
	)
	(segment
		(start 110.838742 -106.4514)
		(end 110.940342 -106.553)
		(width 0.0889)
		(layer "F.Cu")
		(net "M_K_DQ<39>")
	)
	(segment
		(start 121.816368 -125.3744)
		(end 121.816368 -125.86716)
		(width 0.1651)
		(layer "F.Cu")
		(net "M_K_DQ<39>")
	)
	(via
		(at 121.499376 -130.330956)
		(size 0.508)
		(drill 0.254)
		(layers "F.Cu" "B.Cu")
		(net "M_K_DQ<39>")
	)
	(via
		(at 120.649492 -134.340346)
		(size 0.508)
		(drill 0.254)
		(layers "F.Cu" "B.Cu")
		(net "M_K_DQ<39>")
	)
	(segment
		(start 121.499376 -128.276096)
		(end 121.499376 -130.330956)
		(width 0.1651)
		(layer "B.Cu")
		(net "M_K_DQ<39>")
	)
	(segment
		(start 121.06783 -132.715)
		(end 120.810782 -132.457952)
		(width 0.14224)
		(layer "In2.Cu")
		(net "M_K_DQ<39>")
	)
	(segment
		(start 121.09958 -134.162546)
		(end 121.09958 -133.83895)
		(width 0.14224)
		(layer "In2.Cu")
		(net "M_K_DQ<39>")
	)
	(segment
		(start 121.09323 -131.9022)
		(end 121.09323 -131.233418)
		(width 0.14224)
		(layer "In2.Cu")
		(net "M_K_DQ<39>")
	)
	(segment
		(start 120.810782 -132.184648)
		(end 121.09323 -131.9022)
		(width 0.14224)
		(layer "In2.Cu")
		(net "M_K_DQ<39>")
	)
	(segment
		(start 120.810782 -132.457952)
		(end 120.810782 -132.184648)
		(width 0.14224)
		(layer "In2.Cu")
		(net "M_K_DQ<39>")
	)
	(segment
		(start 120.810782 -133.276848)
		(end 121.06783 -133.0198)
		(width 0.14224)
		(layer "In2.Cu")
		(net "M_K_DQ<39>")
	)
	(segment
		(start 121.06783 -133.0198)
		(end 121.06783 -132.715)
		(width 0.14224)
		(layer "In2.Cu")
		(net "M_K_DQ<39>")
	)
	(segment
		(start 121.09958 -133.83895)
		(end 120.810782 -133.550152)
		(width 0.14224)
		(layer "In2.Cu")
		(net "M_K_DQ<39>")
	)
	(segment
		(start 120.649492 -134.340346)
		(end 120.92178 -134.340346)
		(width 0.14224)
		(layer "In2.Cu")
		(net "M_K_DQ<39>")
	)
	(segment
		(start 121.04878 -130.7592)
		(end 121.477024 -130.330956)
		(width 0.14224)
		(layer "In2.Cu")
		(net "M_K_DQ<39>")
	)
	(segment
		(start 121.09323 -131.233418)
		(end 121.04878 -131.188968)
		(width 0.14224)
		(layer "In2.Cu")
		(net "M_K_DQ<39>")
	)
	(segment
		(start 121.04878 -131.188968)
		(end 121.04878 -130.7592)
		(width 0.14224)
		(layer "In2.Cu")
		(net "M_K_DQ<39>")
	)
	(segment
		(start 121.477024 -130.330956)
		(end 121.499376 -130.330956)
		(width 0.14224)
		(layer "In2.Cu")
		(net "M_K_DQ<39>")
	)
	(segment
		(start 120.92178 -134.340346)
		(end 121.09958 -134.162546)
		(width 0.14224)
		(layer "In2.Cu")
		(net "M_K_DQ<39>")
	)
	(segment
		(start 120.810782 -133.550152)
		(end 120.810782 -133.276848)
		(width 0.14224)
		(layer "In2.Cu")
		(net "M_K_DQ<39>")
	)
	(segment
		(start 117.534944 -122.090942)
		(end 117.782848 -122.090942)
		(width 0.1651)
		(layer "F.Cu")
		(net "M_K_DQ<38>")
	)
	(segment
		(start 118.018306 -122.3264)
		(end 118.018306 -122.587258)
		(width 0.1651)
		(layer "F.Cu")
		(net "M_K_DQ<38>")
	)
	(segment
		(start 110.997492 -102.26294)
		(end 110.992666 -102.271576)
		(width 0.0889)
		(layer "F.Cu")
		(net "M_K_DQ<38>")
	)
	(segment
		(start 120.114568 -131.076954)
		(end 120.649492 -131.611878)
		(width 0.1651)
		(layer "F.Cu")
		(net "M_K_DQ<38>")
	)
	(segment
		(start 121.49963 -135.915654)
		(end 121.499376 -135.9154)
		(width 0.1651)
		(layer "F.Cu")
		(net "M_K_DQ<38>")
	)
	(segment
		(start 110.648242 -106.4514)
		(end 110.546642 -106.553)
		(width 0.0889)
		(layer "F.Cu")
		(net "M_K_DQ<38>")
	)
	(segment
		(start 110.997492 -101.67239)
		(end 111.003842 -101.683058)
		(width 0.0889)
		(layer "F.Cu")
		(net "M_K_DQ<38>")
	)
	(segment
		(start 112.024668 -113.8301)
		(end 113.332768 -115.1382)
		(width 0.1651)
		(layer "F.Cu")
		(net "M_K_DQ<38>")
	)
	(segment
		(start 116.994686 -122.39625)
		(end 117.229636 -122.39625)
		(width 0.1651)
		(layer "F.Cu")
		(net "M_K_DQ<38>")
	)
	(segment
		(start 121.49963 -137.67054)
		(end 121.49963 -136.7028)
		(width 0.1651)
		(layer "F.Cu")
		(net "M_K_DQ<38>")
	)
	(segment
		(start 121.49963 -136.2202)
		(end 121.49963 -135.915654)
		(width 0.1651)
		(layer "F.Cu")
		(net "M_K_DQ<38>")
	)
	(segment
		(start 113.332768 -117.536468)
		(end 116.27612 -120.47982)
		(width 0.1651)
		(layer "F.Cu")
		(net "M_K_DQ<38>")
	)
	(segment
		(start 116.27612 -121.677684)
		(end 116.994686 -122.39625)
		(width 0.1651)
		(layer "F.Cu")
		(net "M_K_DQ<38>")
	)
	(segment
		(start 111.303562 -105.239312)
		(end 110.648242 -105.894632)
		(width 0.0889)
		(layer "F.Cu")
		(net "M_K_DQ<38>")
	)
	(segment
		(start 117.725952 -123.127516)
		(end 120.800368 -126.201932)
		(width 0.1651)
		(layer "F.Cu")
		(net "M_K_DQ<38>")
	)
	(segment
		(start 111.04118 -101.181662)
		(end 111.014256 -101.243638)
		(width 0.0889)
		(layer "F.Cu")
		(net "M_K_DQ<38>")
	)
	(segment
		(start 120.114568 -130.892804)
		(end 120.114568 -131.076954)
		(width 0.1651)
		(layer "F.Cu")
		(net "M_K_DQ<38>")
	)
	(segment
		(start 121.499376 -137.67054)
		(end 121.49963 -137.67054)
		(width 0.1651)
		(layer "F.Cu")
		(net "M_K_DQ<38>")
	)
	(segment
		(start 118.018306 -122.587258)
		(end 117.725952 -122.879612)
		(width 0.1651)
		(layer "F.Cu")
		(net "M_K_DQ<38>")
	)
	(segment
		(start 110.648242 -105.894632)
		(end 110.648242 -106.4514)
		(width 0.0889)
		(layer "F.Cu")
		(net "M_K_DQ<38>")
	)
	(segment
		(start 111.303562 -104.011984)
		(end 111.303562 -105.239312)
		(width 0.0889)
		(layer "F.Cu")
		(net "M_K_DQ<38>")
	)
	(segment
		(start 120.800368 -126.201932)
		(end 120.800368 -129.0574)
		(width 0.1651)
		(layer "F.Cu")
		(net "M_K_DQ<38>")
	)
	(segment
		(start 111.15294 -103.242872)
		(end 111.15294 -103.861362)
		(width 0.0889)
		(layer "F.Cu")
		(net "M_K_DQ<38>")
	)
	(segment
		(start 113.332768 -115.1382)
		(end 113.332768 -117.536468)
		(width 0.1651)
		(layer "F.Cu")
		(net "M_K_DQ<38>")
	)
	(segment
		(start 121.181368 -129.826004)
		(end 120.114568 -130.892804)
		(width 0.1651)
		(layer "F.Cu")
		(net "M_K_DQ<38>")
	)
	(segment
		(start 121.181368 -129.4384)
		(end 121.181368 -129.826004)
		(width 0.1651)
		(layer "F.Cu")
		(net "M_K_DQ<38>")
	)
	(segment
		(start 121.63171 -136.57072)
		(end 121.63171 -136.35228)
		(width 0.1651)
		(layer "F.Cu")
		(net "M_K_DQ<38>")
	)
	(segment
		(start 111.04118 -100.78466)
		(end 111.04118 -101.181662)
		(width 0.0889)
		(layer "F.Cu")
		(net "M_K_DQ<38>")
	)
	(segment
		(start 117.725952 -122.879612)
		(end 117.725952 -123.127516)
		(width 0.1651)
		(layer "F.Cu")
		(net "M_K_DQ<38>")
	)
	(segment
		(start 117.782848 -122.090942)
		(end 118.018306 -122.3264)
		(width 0.1651)
		(layer "F.Cu")
		(net "M_K_DQ<38>")
	)
	(segment
		(start 117.229636 -122.39625)
		(end 117.534944 -122.090942)
		(width 0.1651)
		(layer "F.Cu")
		(net "M_K_DQ<38>")
	)
	(segment
		(start 121.49963 -136.7028)
		(end 121.63171 -136.57072)
		(width 0.1651)
		(layer "F.Cu")
		(net "M_K_DQ<38>")
	)
	(segment
		(start 111.344202 -100.481638)
		(end 111.04118 -100.78466)
		(width 0.0889)
		(layer "F.Cu")
		(net "M_K_DQ<38>")
	)
	(segment
		(start 116.27612 -120.47982)
		(end 116.27612 -121.677684)
		(width 0.1651)
		(layer "F.Cu")
		(net "M_K_DQ<38>")
	)
	(segment
		(start 110.546642 -112.352074)
		(end 112.024668 -113.8301)
		(width 0.1016)
		(layer "F.Cu")
		(net "M_K_DQ<38>")
	)
	(segment
		(start 111.014256 -101.243638)
		(end 110.997492 -101.272594)
		(width 0.0889)
		(layer "F.Cu")
		(net "M_K_DQ<38>")
	)
	(segment
		(start 111.15294 -103.861362)
		(end 111.303562 -104.011984)
		(width 0.0889)
		(layer "F.Cu")
		(net "M_K_DQ<38>")
	)
	(segment
		(start 121.63171 -136.35228)
		(end 121.49963 -136.2202)
		(width 0.1651)
		(layer "F.Cu")
		(net "M_K_DQ<38>")
	)
	(segment
		(start 110.546642 -106.553)
		(end 110.546642 -112.352074)
		(width 0.1016)
		(layer "F.Cu")
		(net "M_K_DQ<38>")
	)
	(segment
		(start 120.800368 -129.0574)
		(end 121.181368 -129.4384)
		(width 0.1651)
		(layer "F.Cu")
		(net "M_K_DQ<38>")
	)
	(via
		(at 120.649492 -131.611878)
		(size 0.508)
		(drill 0.254)
		(layers "F.Cu" "B.Cu")
		(net "M_K_DQ<38>")
	)
	(via
		(at 121.499376 -135.9154)
		(size 0.508)
		(drill 0.254)
		(layers "F.Cu" "B.Cu")
		(net "M_K_DQ<38>")
	)
	(arc
		(start 110.992666 -102.271576)
		(mid 110.943911 -102.467928)
		(end 110.997492 -102.66299)
		(width 0.0889)
		(layer "F.Cu")
		(net "M_K_DQ<38>")
	)
	(arc
		(start 110.997492 -102.66299)
		(mid 111.113435 -102.942689)
		(end 111.15294 -103.242872)
		(width 0.0889)
		(layer "F.Cu")
		(net "M_K_DQ<38>")
	)
	(arc
		(start 110.997492 -101.272594)
		(mid 110.943993 -101.472492)
		(end 110.997492 -101.67239)
		(width 0.0889)
		(layer "F.Cu")
		(net "M_K_DQ<38>")
	)
	(arc
		(start 111.003842 -101.683058)
		(mid 111.07664 -101.973821)
		(end 110.997492 -102.26294)
		(width 0.0889)
		(layer "F.Cu")
		(net "M_K_DQ<38>")
	)
	(segment
		(start 120.649492 -132.876036)
		(end 120.649492 -131.611878)
		(width 0.1651)
		(layer "B.Cu")
		(net "M_K_DQ<38>")
	)
	(segment
		(start 121.499376 -135.9154)
		(end 120.216422 -134.632446)
		(width 0.14224)
		(layer "In2.Cu")
		(net "M_K_DQ<38>")
	)
	(segment
		(start 120.216422 -132.044948)
		(end 120.649492 -131.611878)
		(width 0.14224)
		(layer "In2.Cu")
		(net "M_K_DQ<38>")
	)
	(segment
		(start 120.216422 -134.632446)
		(end 120.216422 -132.044948)
		(width 0.14224)
		(layer "In2.Cu")
		(net "M_K_DQ<38>")
	)
	(segment
		(start 114.789966 -126.044198)
		(end 115.039648 -126.29388)
		(width 0.1651)
		(layer "F.Cu")
		(net "M_K_DQ<37>")
	)
	(segment
		(start 108.768896 -100.976684)
		(end 108.46943 -101.6635)
		(width 0.0889)
		(layer "F.Cu")
		(net "M_K_DQ<37>")
	)
	(segment
		(start 114.556286 -126.044198)
		(end 114.789966 -126.044198)
		(width 0.1651)
		(layer "F.Cu")
		(net "M_K_DQ<37>")
	)
	(segment
		(start 115.801902 -127.797814)
		(end 115.801902 -128.107948)
		(width 0.1651)
		(layer "F.Cu")
		(net "M_K_DQ<37>")
	)
	(segment
		(start 113.534698 -126.078488)
		(end 113.534698 -126.287276)
		(width 0.1651)
		(layer "F.Cu")
		(net "M_K_DQ<37>")
	)
	(segment
		(start 107.689142 -103.511858)
		(end 107.689142 -106.426)
		(width 0.0889)
		(layer "F.Cu")
		(net "M_K_DQ<37>")
	)
	(segment
		(start 115.449604 -128.460246)
		(end 115.449604 -128.710182)
		(width 0.1651)
		(layer "F.Cu")
		(net "M_K_DQ<37>")
	)
	(segment
		(start 114.034824 -126.56566)
		(end 114.556286 -126.044198)
		(width 0.1651)
		(layer "F.Cu")
		(net "M_K_DQ<37>")
	)
	(segment
		(start 115.494308 -127.49022)
		(end 115.801902 -127.797814)
		(width 0.1651)
		(layer "F.Cu")
		(net "M_K_DQ<37>")
	)
	(segment
		(start 114.822478 -127.714502)
		(end 115.017296 -127.714502)
		(width 0.1651)
		(layer "F.Cu")
		(net "M_K_DQ<37>")
	)
	(segment
		(start 108.428282 -102.747572)
		(end 108.414312 -102.77094)
		(width 0.0889)
		(layer "F.Cu")
		(net "M_K_DQ<37>")
	)
	(segment
		(start 113.76406 -125.849126)
		(end 113.534698 -126.078488)
		(width 0.1651)
		(layer "F.Cu")
		(net "M_K_DQ<37>")
	)
	(segment
		(start 108.414312 -102.77094)
		(end 108.376212 -102.824788)
		(width 0.0889)
		(layer "F.Cu")
		(net "M_K_DQ<37>")
	)
	(segment
		(start 115.897914 -129.906268)
		(end 115.473226 -130.330956)
		(width 0.1651)
		(layer "F.Cu")
		(net "M_K_DQ<37>")
	)
	(segment
		(start 107.29849 -115.453922)
		(end 108.125768 -116.2812)
		(width 0.1651)
		(layer "F.Cu")
		(net "M_K_DQ<37>")
	)
	(segment
		(start 108.421932 -101.76764)
		(end 108.417106 -101.776276)
		(width 0.0889)
		(layer "F.Cu")
		(net "M_K_DQ<37>")
	)
	(segment
		(start 113.534698 -126.287276)
		(end 113.813082 -126.56566)
		(width 0.1651)
		(layer "F.Cu")
		(net "M_K_DQ<37>")
	)
	(segment
		(start 114.486182 -127.081026)
		(end 114.486182 -127.378206)
		(width 0.1651)
		(layer "F.Cu")
		(net "M_K_DQ<37>")
	)
	(segment
		(start 114.699542 -133.0706)
		(end 114.699542 -134.340346)
		(width 0.1651)
		(layer "F.Cu")
		(net "M_K_DQ<37>")
	)
	(segment
		(start 107.790742 -112.145826)
		(end 107.29849 -112.638078)
		(width 0.1016)
		(layer "F.Cu")
		(net "M_K_DQ<37>")
	)
	(segment
		(start 115.039648 -126.29388)
		(end 115.039648 -126.52756)
		(width 0.1651)
		(layer "F.Cu")
		(net "M_K_DQ<37>")
	)
	(segment
		(start 108.125768 -116.2812)
		(end 108.125768 -119.884444)
		(width 0.1651)
		(layer "F.Cu")
		(net "M_K_DQ<37>")
	)
	(segment
		(start 115.039648 -126.52756)
		(end 114.486182 -127.081026)
		(width 0.1651)
		(layer "F.Cu")
		(net "M_K_DQ<37>")
	)
	(segment
		(start 108.376212 -102.824788)
		(end 107.689142 -103.511858)
		(width 0.0889)
		(layer "F.Cu")
		(net "M_K_DQ<37>")
	)
	(segment
		(start 115.017296 -127.714502)
		(end 115.241578 -127.49022)
		(width 0.1651)
		(layer "F.Cu")
		(net "M_K_DQ<37>")
	)
	(segment
		(start 107.29849 -112.638078)
		(end 107.29849 -115.453922)
		(width 0.1651)
		(layer "F.Cu")
		(net "M_K_DQ<37>")
	)
	(segment
		(start 107.790742 -106.5276)
		(end 107.790742 -112.145826)
		(width 0.1016)
		(layer "F.Cu")
		(net "M_K_DQ<37>")
	)
	(segment
		(start 107.689142 -106.426)
		(end 107.790742 -106.5276)
		(width 0.0889)
		(layer "F.Cu")
		(net "M_K_DQ<37>")
	)
	(segment
		(start 115.897914 -129.158492)
		(end 115.897914 -129.906268)
		(width 0.1651)
		(layer "F.Cu")
		(net "M_K_DQ<37>")
	)
	(segment
		(start 115.449604 -128.710182)
		(end 115.897914 -129.158492)
		(width 0.1651)
		(layer "F.Cu")
		(net "M_K_DQ<37>")
	)
	(segment
		(start 113.813082 -126.56566)
		(end 114.034824 -126.56566)
		(width 0.1651)
		(layer "F.Cu")
		(net "M_K_DQ<37>")
	)
	(segment
		(start 108.125768 -119.884444)
		(end 113.76406 -125.522736)
		(width 0.1651)
		(layer "F.Cu")
		(net "M_K_DQ<37>")
	)
	(segment
		(start 114.486182 -127.378206)
		(end 114.822478 -127.714502)
		(width 0.1651)
		(layer "F.Cu")
		(net "M_K_DQ<37>")
	)
	(segment
		(start 115.241578 -127.49022)
		(end 115.494308 -127.49022)
		(width 0.1651)
		(layer "F.Cu")
		(net "M_K_DQ<37>")
	)
	(segment
		(start 115.801902 -128.107948)
		(end 115.449604 -128.460246)
		(width 0.1651)
		(layer "F.Cu")
		(net "M_K_DQ<37>")
	)
	(segment
		(start 113.76406 -125.522736)
		(end 113.76406 -125.849126)
		(width 0.1651)
		(layer "F.Cu")
		(net "M_K_DQ<37>")
	)
	(via
		(at 115.473226 -130.330956)
		(size 0.508)
		(drill 0.254)
		(layers "F.Cu" "B.Cu")
		(net "M_K_DQ<37>")
	)
	(via
		(at 114.699542 -134.340346)
		(size 0.508)
		(drill 0.254)
		(layers "F.Cu" "B.Cu")
		(net "M_K_DQ<37>")
	)
	(arc
		(start 108.417106 -101.776276)
		(mid 108.368351 -101.972628)
		(end 108.421932 -102.16769)
		(width 0.0889)
		(layer "F.Cu")
		(net "M_K_DQ<37>")
	)
	(arc
		(start 108.46943 -101.6635)
		(mid 108.448212 -101.716725)
		(end 108.421932 -101.76764)
		(width 0.0889)
		(layer "F.Cu")
		(net "M_K_DQ<37>")
	)
	(arc
		(start 108.421932 -102.16769)
		(mid 108.501154 -102.456808)
		(end 108.428282 -102.747572)
		(width 0.0889)
		(layer "F.Cu")
		(net "M_K_DQ<37>")
	)
	(segment
		(start 115.549426 -128.276096)
		(end 115.549426 -130.254756)
		(width 0.1651)
		(layer "B.Cu")
		(net "M_K_DQ<37>")
	)
	(segment
		(start 115.549426 -130.254756)
		(end 115.473226 -130.330956)
		(width 0.1651)
		(layer "B.Cu")
		(net "M_K_DQ<37>")
	)
	(segment
		(start 115.450874 -130.330956)
		(end 115.473226 -130.330956)
		(width 0.14224)
		(layer "In2.Cu")
		(net "M_K_DQ<37>")
	)
	(segment
		(start 115.14963 -131.445)
		(end 115.02263 -131.318)
		(width 0.14224)
		(layer "In2.Cu")
		(net "M_K_DQ<37>")
	)
	(segment
		(start 115.09883 -132.791454)
		(end 114.860832 -132.553456)
		(width 0.14224)
		(layer "In2.Cu")
		(net "M_K_DQ<37>")
	)
	(segment
		(start 115.12423 -133.959854)
		(end 114.860832 -133.696456)
		(width 0.14224)
		(layer "In2.Cu")
		(net "M_K_DQ<37>")
	)
	(segment
		(start 114.699542 -134.340346)
		(end 114.97183 -134.340346)
		(width 0.14224)
		(layer "In2.Cu")
		(net "M_K_DQ<37>")
	)
	(segment
		(start 114.97183 -134.340346)
		(end 115.12423 -134.187946)
		(width 0.14224)
		(layer "In2.Cu")
		(net "M_K_DQ<37>")
	)
	(segment
		(start 115.09883 -133.146546)
		(end 115.09883 -132.791454)
		(width 0.14224)
		(layer "In2.Cu")
		(net "M_K_DQ<37>")
	)
	(segment
		(start 115.02263 -130.7592)
		(end 115.450874 -130.330956)
		(width 0.14224)
		(layer "In2.Cu")
		(net "M_K_DQ<37>")
	)
	(segment
		(start 115.14963 -131.927346)
		(end 115.14963 -131.445)
		(width 0.14224)
		(layer "In2.Cu")
		(net "M_K_DQ<37>")
	)
	(segment
		(start 115.12423 -134.187946)
		(end 115.12423 -133.959854)
		(width 0.14224)
		(layer "In2.Cu")
		(net "M_K_DQ<37>")
	)
	(segment
		(start 114.860832 -133.696456)
		(end 114.860832 -133.384544)
		(width 0.14224)
		(layer "In2.Cu")
		(net "M_K_DQ<37>")
	)
	(segment
		(start 115.02263 -131.318)
		(end 115.02263 -130.7592)
		(width 0.14224)
		(layer "In2.Cu")
		(net "M_K_DQ<37>")
	)
	(segment
		(start 114.860832 -133.384544)
		(end 115.09883 -133.146546)
		(width 0.14224)
		(layer "In2.Cu")
		(net "M_K_DQ<37>")
	)
	(segment
		(start 114.860832 -132.216144)
		(end 115.14963 -131.927346)
		(width 0.14224)
		(layer "In2.Cu")
		(net "M_K_DQ<37>")
	)
	(segment
		(start 114.860832 -132.553456)
		(end 114.860832 -132.216144)
		(width 0.14224)
		(layer "In2.Cu")
		(net "M_K_DQ<37>")
	)
	(segment
		(start 108.261658 -102.654354)
		(end 108.254546 -102.667054)
		(width 0.0889)
		(layer "F.Cu")
		(net "M_K_DQ<36>")
	)
	(segment
		(start 115.549426 -136.345168)
		(end 115.451382 -135.8138)
		(width 0.1651)
		(layer "F.Cu")
		(net "M_K_DQ<36>")
	)
	(segment
		(start 115.20043 -129.780538)
		(end 114.932968 -130.048)
		(width 0.1651)
		(layer "F.Cu")
		(net "M_K_DQ<36>")
	)
	(segment
		(start 108.257086 -101.272086)
		(end 108.261912 -101.280722)
		(width 0.0889)
		(layer "F.Cu")
		(net "M_K_DQ<36>")
	)
	(segment
		(start 106.652568 -112.649)
		(end 106.652568 -115.7478)
		(width 0.1651)
		(layer "F.Cu")
		(net "M_K_DQ<36>")
	)
	(segment
		(start 106.652568 -115.7478)
		(end 107.465368 -116.5606)
		(width 0.1651)
		(layer "F.Cu")
		(net "M_K_DQ<36>")
	)
	(segment
		(start 114.932968 -131.378452)
		(end 114.699542 -131.611878)
		(width 0.1651)
		(layer "F.Cu")
		(net "M_K_DQ<36>")
	)
	(segment
		(start 107.498642 -103.427022)
		(end 107.498642 -106.426)
		(width 0.0889)
		(layer "F.Cu")
		(net "M_K_DQ<36>")
	)
	(segment
		(start 107.498642 -106.426)
		(end 107.397042 -106.5276)
		(width 0.0889)
		(layer "F.Cu")
		(net "M_K_DQ<36>")
	)
	(segment
		(start 114.551968 -128.7526)
		(end 115.20043 -129.401062)
		(width 0.1651)
		(layer "F.Cu")
		(net "M_K_DQ<36>")
	)
	(segment
		(start 109.627416 -100.481638)
		(end 108.804964 -100.386134)
		(width 0.0889)
		(layer "F.Cu")
		(net "M_K_DQ<36>")
	)
	(segment
		(start 114.551968 -128.3462)
		(end 114.551968 -128.7526)
		(width 0.1651)
		(layer "F.Cu")
		(net "M_K_DQ<36>")
	)
	(segment
		(start 115.20043 -129.401062)
		(end 115.20043 -129.780538)
		(width 0.1651)
		(layer "F.Cu")
		(net "M_K_DQ<36>")
	)
	(segment
		(start 108.238544 -102.68712)
		(end 107.498642 -103.427022)
		(width 0.0889)
		(layer "F.Cu")
		(net "M_K_DQ<36>")
	)
	(segment
		(start 107.465368 -116.5606)
		(end 107.465368 -120.135904)
		(width 0.1651)
		(layer "F.Cu")
		(net "M_K_DQ<36>")
	)
	(segment
		(start 114.932968 -130.048)
		(end 114.932968 -131.378452)
		(width 0.1651)
		(layer "F.Cu")
		(net "M_K_DQ<36>")
	)
	(segment
		(start 107.465368 -120.135904)
		(end 112.799368 -125.469904)
		(width 0.1651)
		(layer "F.Cu")
		(net "M_K_DQ<36>")
	)
	(segment
		(start 107.397042 -106.5276)
		(end 107.397042 -111.904526)
		(width 0.1016)
		(layer "F.Cu")
		(net "M_K_DQ<36>")
	)
	(segment
		(start 112.799368 -125.469904)
		(end 112.799368 -126.5936)
		(width 0.1651)
		(layer "F.Cu")
		(net "M_K_DQ<36>")
	)
	(segment
		(start 107.397042 -111.904526)
		(end 106.652568 -112.649)
		(width 0.1016)
		(layer "F.Cu")
		(net "M_K_DQ<36>")
	)
	(segment
		(start 108.804964 -100.386134)
		(end 108.751116 -100.386134)
		(width 0.0889)
		(layer "F.Cu")
		(net "M_K_DQ<36>")
	)
	(segment
		(start 112.799368 -126.5936)
		(end 114.551968 -128.3462)
		(width 0.1651)
		(layer "F.Cu")
		(net "M_K_DQ<36>")
	)
	(segment
		(start 115.549426 -137.67054)
		(end 115.549426 -136.345168)
		(width 0.1651)
		(layer "F.Cu")
		(net "M_K_DQ<36>")
	)
	(via
		(at 114.699542 -131.611878)
		(size 0.508)
		(drill 0.254)
		(layers "F.Cu" "B.Cu")
		(net "M_K_DQ<36>")
	)
	(via
		(at 115.451382 -135.8138)
		(size 0.508)
		(drill 0.254)
		(layers "F.Cu" "B.Cu")
		(net "M_K_DQ<36>")
	)
	(arc
		(start 108.256832 -101.672136)
		(mid 108.177701 -101.967538)
		(end 108.256832 -102.26294)
		(width 0.0889)
		(layer "F.Cu")
		(net "M_K_DQ<36>")
	)
	(arc
		(start 108.254546 -102.667054)
		(mid 108.247286 -102.677679)
		(end 108.238544 -102.68712)
		(width 0.0889)
		(layer "F.Cu")
		(net "M_K_DQ<36>")
	)
	(arc
		(start 108.751116 -100.386134)
		(mid 108.252865 -100.688974)
		(end 108.257086 -101.272086)
		(width 0.0889)
		(layer "F.Cu")
		(net "M_K_DQ<36>")
	)
	(arc
		(start 108.286804 -101.608382)
		(mid 108.273293 -101.640952)
		(end 108.256832 -101.672136)
		(width 0.0889)
		(layer "F.Cu")
		(net "M_K_DQ<36>")
	)
	(arc
		(start 108.256832 -102.26294)
		(mid 108.310302 -102.458003)
		(end 108.261658 -102.654354)
		(width 0.0889)
		(layer "F.Cu")
		(net "M_K_DQ<36>")
	)
	(arc
		(start 108.261912 -101.280722)
		(mid 108.309543 -101.441882)
		(end 108.286804 -101.608382)
		(width 0.0889)
		(layer "F.Cu")
		(net "M_K_DQ<36>")
	)
	(segment
		(start 114.699542 -132.876036)
		(end 114.699542 -131.611878)
		(width 0.1651)
		(layer "B.Cu")
		(net "M_K_DQ<36>")
	)
	(segment
		(start 114.266472 -134.57809)
		(end 114.266472 -132.044948)
		(width 0.14224)
		(layer "In2.Cu")
		(net "M_K_DQ<36>")
	)
	(segment
		(start 115.451382 -135.8138)
		(end 115.20043 -135.8138)
		(width 0.14224)
		(layer "In2.Cu")
		(net "M_K_DQ<36>")
	)
	(segment
		(start 115.20043 -135.8138)
		(end 114.42446 -135.03783)
		(width 0.14224)
		(layer "In2.Cu")
		(net "M_K_DQ<36>")
	)
	(segment
		(start 114.42446 -134.736078)
		(end 114.266472 -134.57809)
		(width 0.14224)
		(layer "In2.Cu")
		(net "M_K_DQ<36>")
	)
	(segment
		(start 114.42446 -135.03783)
		(end 114.42446 -134.736078)
		(width 0.14224)
		(layer "In2.Cu")
		(net "M_K_DQ<36>")
	)
	(segment
		(start 114.266472 -132.044948)
		(end 114.699542 -131.611878)
		(width 0.14224)
		(layer "In2.Cu")
		(net "M_K_DQ<36>")
	)
	(segment
		(start 111.727742 -106.64952)
		(end 111.727742 -111.678974)
		(width 0.1016)
		(layer "F.Cu")
		(net "M_K_DQ<35>")
	)
	(segment
		(start 123.581414 -128.871726)
		(end 124.013214 -128.439926)
		(width 0.1651)
		(layer "F.Cu")
		(net "M_K_DQ<35>")
	)
	(segment
		(start 112.202722 -101.635814)
		(end 112.139222 -101.572314)
		(width 0.0889)
		(layer "F.Cu")
		(net "M_K_DQ<35>")
	)
	(segment
		(start 124.246894 -128.439926)
		(end 124.584968 -128.778)
		(width 0.1651)
		(layer "F.Cu")
		(net "M_K_DQ<35>")
	)
	(segment
		(start 112.286796 -103.92918)
		(end 112.286796 -105.617772)
		(width 0.0889)
		(layer "F.Cu")
		(net "M_K_DQ<35>")
	)
	(segment
		(start 111.851186 -102.1588)
		(end 111.856012 -102.167436)
		(width 0.0889)
		(layer "F.Cu")
		(net "M_K_DQ<35>")
	)
	(segment
		(start 124.013214 -128.439926)
		(end 124.246894 -128.439926)
		(width 0.1651)
		(layer "F.Cu")
		(net "M_K_DQ<35>")
	)
	(segment
		(start 122.349514 -133.0706)
		(end 122.349514 -134.340346)
		(width 0.1651)
		(layer "F.Cu")
		(net "M_K_DQ<35>")
	)
	(segment
		(start 112.202722 -101.967538)
		(end 112.202722 -101.635814)
		(width 0.0889)
		(layer "F.Cu")
		(net "M_K_DQ<35>")
	)
	(segment
		(start 123.162568 -124.502672)
		(end 123.162568 -127.3556)
		(width 0.1651)
		(layer "F.Cu")
		(net "M_K_DQ<35>")
	)
	(segment
		(start 112.037368 -111.9886)
		(end 113.281968 -111.9886)
		(width 0.1651)
		(layer "F.Cu")
		(net "M_K_DQ<35>")
	)
	(segment
		(start 111.626142 -106.278426)
		(end 111.626142 -106.54792)
		(width 0.0889)
		(layer "F.Cu")
		(net "M_K_DQ<35>")
	)
	(segment
		(start 123.379484 -128.871726)
		(end 123.581414 -128.871726)
		(width 0.1651)
		(layer "F.Cu")
		(net "M_K_DQ<35>")
	)
	(segment
		(start 123.162568 -127.3556)
		(end 123.431046 -127.624078)
		(width 0.1651)
		(layer "F.Cu")
		(net "M_K_DQ<35>")
	)
	(segment
		(start 111.856012 -103.18369)
		(end 112.286796 -103.92918)
		(width 0.0889)
		(layer "F.Cu")
		(net "M_K_DQ<35>")
	)
	(segment
		(start 115.390168 -116.730272)
		(end 123.162568 -124.502672)
		(width 0.1651)
		(layer "F.Cu")
		(net "M_K_DQ<35>")
	)
	(segment
		(start 115.390168 -114.0968)
		(end 115.390168 -116.730272)
		(width 0.1651)
		(layer "F.Cu")
		(net "M_K_DQ<35>")
	)
	(segment
		(start 124.022612 -130.330956)
		(end 123.199398 -130.330956)
		(width 0.1651)
		(layer "F.Cu")
		(net "M_K_DQ<35>")
	)
	(segment
		(start 111.727742 -111.678974)
		(end 112.037368 -111.9886)
		(width 0.1016)
		(layer "F.Cu")
		(net "M_K_DQ<35>")
	)
	(segment
		(start 123.431046 -127.857758)
		(end 123.030996 -128.257808)
		(width 0.1651)
		(layer "F.Cu")
		(net "M_K_DQ<35>")
	)
	(segment
		(start 124.584968 -129.7686)
		(end 124.022612 -130.330956)
		(width 0.1651)
		(layer "F.Cu")
		(net "M_K_DQ<35>")
	)
	(segment
		(start 113.281968 -111.9886)
		(end 115.390168 -114.0968)
		(width 0.1651)
		(layer "F.Cu")
		(net "M_K_DQ<35>")
	)
	(segment
		(start 123.030996 -128.523238)
		(end 123.379484 -128.871726)
		(width 0.1651)
		(layer "F.Cu")
		(net "M_K_DQ<35>")
	)
	(segment
		(start 111.626142 -106.54792)
		(end 111.727742 -106.64952)
		(width 0.0889)
		(layer "F.Cu")
		(net "M_K_DQ<35>")
	)
	(segment
		(start 123.030996 -128.257808)
		(end 123.030996 -128.523238)
		(width 0.1651)
		(layer "F.Cu")
		(net "M_K_DQ<35>")
	)
	(segment
		(start 124.584968 -128.778)
		(end 124.584968 -129.7686)
		(width 0.1651)
		(layer "F.Cu")
		(net "M_K_DQ<35>")
	)
	(segment
		(start 112.286796 -105.617772)
		(end 111.626142 -106.278426)
		(width 0.0889)
		(layer "F.Cu")
		(net "M_K_DQ<35>")
	)
	(segment
		(start 111.856012 -102.167436)
		(end 111.862362 -102.178104)
		(width 0.0889)
		(layer "F.Cu")
		(net "M_K_DQ<35>")
	)
	(segment
		(start 123.431046 -127.624078)
		(end 123.431046 -127.857758)
		(width 0.1651)
		(layer "F.Cu")
		(net "M_K_DQ<35>")
	)
	(via
		(at 122.349514 -134.340346)
		(size 0.508)
		(drill 0.254)
		(layers "F.Cu" "B.Cu")
		(net "M_K_DQ<35>")
	)
	(via
		(at 123.199398 -130.330956)
		(size 0.508)
		(drill 0.254)
		(layers "F.Cu" "B.Cu")
		(net "M_K_DQ<35>")
	)
	(arc
		(start 111.862362 -102.178104)
		(mid 111.93516 -102.468867)
		(end 111.856012 -102.757986)
		(width 0.0889)
		(layer "F.Cu")
		(net "M_K_DQ<35>")
	)
	(arc
		(start 112.139222 -101.572314)
		(mid 111.843437 -101.791048)
		(end 111.851186 -102.1588)
		(width 0.0889)
		(layer "F.Cu")
		(net "M_K_DQ<35>")
	)
	(arc
		(start 111.856012 -102.757986)
		(mid 111.798997 -102.970838)
		(end 111.856012 -103.18369)
		(width 0.0889)
		(layer "F.Cu")
		(net "M_K_DQ<35>")
	)
	(segment
		(start 123.199398 -128.276096)
		(end 123.199398 -130.330956)
		(width 0.1651)
		(layer "B.Cu")
		(net "M_K_DQ<35>")
	)
	(segment
		(start 122.510804 -132.184648)
		(end 122.793252 -131.9022)
		(width 0.14224)
		(layer "In2.Cu")
		(net "M_K_DQ<35>")
	)
	(segment
		(start 122.510804 -133.276848)
		(end 122.767852 -133.0198)
		(width 0.14224)
		(layer "In2.Cu")
		(net "M_K_DQ<35>")
	)
	(segment
		(start 122.767852 -132.715)
		(end 122.510804 -132.457952)
		(width 0.14224)
		(layer "In2.Cu")
		(net "M_K_DQ<35>")
	)
	(segment
		(start 122.510804 -132.457952)
		(end 122.510804 -132.184648)
		(width 0.14224)
		(layer "In2.Cu")
		(net "M_K_DQ<35>")
	)
	(segment
		(start 122.767852 -133.0198)
		(end 122.767852 -132.715)
		(width 0.14224)
		(layer "In2.Cu")
		(net "M_K_DQ<35>")
	)
	(segment
		(start 122.510804 -133.550152)
		(end 122.510804 -133.276848)
		(width 0.14224)
		(layer "In2.Cu")
		(net "M_K_DQ<35>")
	)
	(segment
		(start 123.177046 -130.330956)
		(end 123.199398 -130.330956)
		(width 0.14224)
		(layer "In2.Cu")
		(net "M_K_DQ<35>")
	)
	(segment
		(start 122.621802 -134.340346)
		(end 122.799602 -134.162546)
		(width 0.14224)
		(layer "In2.Cu")
		(net "M_K_DQ<35>")
	)
	(segment
		(start 122.748802 -131.188968)
		(end 122.748802 -130.7592)
		(width 0.14224)
		(layer "In2.Cu")
		(net "M_K_DQ<35>")
	)
	(segment
		(start 122.793252 -131.9022)
		(end 122.793252 -131.233418)
		(width 0.14224)
		(layer "In2.Cu")
		(net "M_K_DQ<35>")
	)
	(segment
		(start 122.799602 -133.83895)
		(end 122.510804 -133.550152)
		(width 0.14224)
		(layer "In2.Cu")
		(net "M_K_DQ<35>")
	)
	(segment
		(start 122.799602 -134.162546)
		(end 122.799602 -133.83895)
		(width 0.14224)
		(layer "In2.Cu")
		(net "M_K_DQ<35>")
	)
	(segment
		(start 122.748802 -130.7592)
		(end 123.177046 -130.330956)
		(width 0.14224)
		(layer "In2.Cu")
		(net "M_K_DQ<35>")
	)
	(segment
		(start 122.349514 -134.340346)
		(end 122.621802 -134.340346)
		(width 0.14224)
		(layer "In2.Cu")
		(net "M_K_DQ<35>")
	)
	(segment
		(start 122.793252 -131.233418)
		(end 122.748802 -131.188968)
		(width 0.14224)
		(layer "In2.Cu")
		(net "M_K_DQ<35>")
	)
	(segment
		(start 123.022868 -129.8321)
		(end 122.019568 -130.8354)
		(width 0.1651)
		(layer "F.Cu")
		(net "M_K_DQ<34>")
	)
	(segment
		(start 123.33097 -136.32434)
		(end 123.199398 -136.192768)
		(width 0.1651)
		(layer "F.Cu")
		(net "M_K_DQ<34>")
	)
	(segment
		(start 123.022868 -129.488184)
		(end 123.022868 -129.8321)
		(width 0.1651)
		(layer "F.Cu")
		(net "M_K_DQ<34>")
	)
	(segment
		(start 120.665494 -123.898914)
		(end 120.665494 -124.159264)
		(width 0.1651)
		(layer "F.Cu")
		(net "M_K_DQ<34>")
	)
	(segment
		(start 120.900952 -124.394722)
		(end 121.13641 -124.394722)
		(width 0.1651)
		(layer "F.Cu")
		(net "M_K_DQ<34>")
	)
	(segment
		(start 122.019568 -130.8354)
		(end 122.019568 -131.281932)
		(width 0.1651)
		(layer "F.Cu")
		(net "M_K_DQ<34>")
	)
	(segment
		(start 112.096296 -103.979726)
		(end 112.096296 -105.5116)
		(width 0.0889)
		(layer "F.Cu")
		(net "M_K_DQ<34>")
	)
	(segment
		(start 122.476768 -124.771404)
		(end 122.476768 -128.942084)
		(width 0.1651)
		(layer "F.Cu")
		(net "M_K_DQ<34>")
	)
	(segment
		(start 111.690912 -103.278178)
		(end 112.096042 -103.978964)
		(width 0.0889)
		(layer "F.Cu")
		(net "M_K_DQ<34>")
	)
	(segment
		(start 121.010934 -123.553474)
		(end 120.665494 -123.898914)
		(width 0.1651)
		(layer "F.Cu")
		(net "M_K_DQ<34>")
	)
	(segment
		(start 122.019568 -131.281932)
		(end 122.349514 -131.611878)
		(width 0.1651)
		(layer "F.Cu")
		(net "M_K_DQ<34>")
	)
	(segment
		(start 111.334042 -106.646472)
		(end 111.334042 -111.89462)
		(width 0.1016)
		(layer "F.Cu")
		(net "M_K_DQ<34>")
	)
	(segment
		(start 111.435642 -106.544872)
		(end 111.334042 -106.646472)
		(width 0.0889)
		(layer "F.Cu")
		(net "M_K_DQ<34>")
	)
	(segment
		(start 111.334042 -111.89462)
		(end 112.088422 -112.649)
		(width 0.1016)
		(layer "F.Cu")
		(net "M_K_DQ<34>")
	)
	(segment
		(start 123.199398 -136.679432)
		(end 123.33097 -136.54786)
		(width 0.1651)
		(layer "F.Cu")
		(net "M_K_DQ<34>")
	)
	(segment
		(start 114.653568 -116.948204)
		(end 121.010934 -123.30557)
		(width 0.1651)
		(layer "F.Cu")
		(net "M_K_DQ<34>")
	)
	(segment
		(start 112.900968 -112.649)
		(end 114.653568 -114.4016)
		(width 0.1651)
		(layer "F.Cu")
		(net "M_K_DQ<34>")
	)
	(segment
		(start 112.088422 -112.649)
		(end 112.900968 -112.649)
		(width 0.1651)
		(layer "F.Cu")
		(net "M_K_DQ<34>")
	)
	(segment
		(start 111.690912 -102.262686)
		(end 111.695738 -102.271322)
		(width 0.0889)
		(layer "F.Cu")
		(net "M_K_DQ<34>")
	)
	(segment
		(start 112.096042 -103.978964)
		(end 112.096042 -103.979218)
		(width 0.0889)
		(layer "F.Cu")
		(net "M_K_DQ<34>")
	)
	(segment
		(start 123.33097 -136.54786)
		(end 123.33097 -136.32434)
		(width 0.1651)
		(layer "F.Cu")
		(net "M_K_DQ<34>")
	)
	(segment
		(start 123.199398 -137.67054)
		(end 123.199398 -136.679432)
		(width 0.1651)
		(layer "F.Cu")
		(net "M_K_DQ<34>")
	)
	(segment
		(start 121.494296 -124.036836)
		(end 121.7422 -124.036836)
		(width 0.1651)
		(layer "F.Cu")
		(net "M_K_DQ<34>")
	)
	(segment
		(start 121.7422 -124.036836)
		(end 122.476768 -124.771404)
		(width 0.1651)
		(layer "F.Cu")
		(net "M_K_DQ<34>")
	)
	(segment
		(start 122.476768 -128.942084)
		(end 123.022868 -129.488184)
		(width 0.1651)
		(layer "F.Cu")
		(net "M_K_DQ<34>")
	)
	(segment
		(start 121.010934 -123.30557)
		(end 121.010934 -123.553474)
		(width 0.1651)
		(layer "F.Cu")
		(net "M_K_DQ<34>")
	)
	(segment
		(start 112.202722 -101.308408)
		(end 112.130078 -101.381052)
		(width 0.0889)
		(layer "F.Cu")
		(net "M_K_DQ<34>")
	)
	(segment
		(start 112.096042 -103.979218)
		(end 112.096296 -103.979726)
		(width 0.0889)
		(layer "F.Cu")
		(net "M_K_DQ<34>")
	)
	(segment
		(start 120.665494 -124.159264)
		(end 120.900952 -124.394722)
		(width 0.1651)
		(layer "F.Cu")
		(net "M_K_DQ<34>")
	)
	(segment
		(start 121.13641 -124.394722)
		(end 121.494296 -124.036836)
		(width 0.1651)
		(layer "F.Cu")
		(net "M_K_DQ<34>")
	)
	(segment
		(start 114.653568 -114.4016)
		(end 114.653568 -116.948204)
		(width 0.1651)
		(layer "F.Cu")
		(net "M_K_DQ<34>")
	)
	(segment
		(start 111.684562 -102.252018)
		(end 111.690912 -102.262686)
		(width 0.0889)
		(layer "F.Cu")
		(net "M_K_DQ<34>")
	)
	(segment
		(start 111.435642 -106.172254)
		(end 111.435642 -106.544872)
		(width 0.0889)
		(layer "F.Cu")
		(net "M_K_DQ<34>")
	)
	(segment
		(start 112.096296 -105.5116)
		(end 111.435642 -106.172254)
		(width 0.0889)
		(layer "F.Cu")
		(net "M_K_DQ<34>")
	)
	(segment
		(start 123.199398 -136.192768)
		(end 123.199398 -135.9154)
		(width 0.1651)
		(layer "F.Cu")
		(net "M_K_DQ<34>")
	)
	(segment
		(start 112.202722 -100.976684)
		(end 112.202722 -101.308408)
		(width 0.0889)
		(layer "F.Cu")
		(net "M_K_DQ<34>")
	)
	(via
		(at 123.199398 -135.9154)
		(size 0.508)
		(drill 0.254)
		(layers "F.Cu" "B.Cu")
		(net "M_K_DQ<34>")
	)
	(via
		(at 122.349514 -131.611878)
		(size 0.508)
		(drill 0.254)
		(layers "F.Cu" "B.Cu")
		(net "M_K_DQ<34>")
	)
	(arc
		(start 111.690912 -102.662736)
		(mid 111.608382 -102.970474)
		(end 111.690912 -103.278178)
		(width 0.0889)
		(layer "F.Cu")
		(net "M_K_DQ<34>")
	)
	(arc
		(start 111.695738 -102.271322)
		(mid 111.744493 -102.467674)
		(end 111.690912 -102.662736)
		(width 0.0889)
		(layer "F.Cu")
		(net "M_K_DQ<34>")
	)
	(arc
		(start 112.130078 -101.381052)
		(mid 111.676568 -101.698457)
		(end 111.684562 -102.252018)
		(width 0.0889)
		(layer "F.Cu")
		(net "M_K_DQ<34>")
	)
	(segment
		(start 122.349514 -132.876036)
		(end 122.349514 -131.611878)
		(width 0.1651)
		(layer "B.Cu")
		(net "M_K_DQ<34>")
	)
	(segment
		(start 123.199398 -135.9154)
		(end 121.916444 -134.632446)
		(width 0.14224)
		(layer "In2.Cu")
		(net "M_K_DQ<34>")
	)
	(segment
		(start 121.916444 -134.632446)
		(end 121.916444 -132.044948)
		(width 0.14224)
		(layer "In2.Cu")
		(net "M_K_DQ<34>")
	)
	(segment
		(start 121.916444 -132.044948)
		(end 122.349514 -131.611878)
		(width 0.14224)
		(layer "In2.Cu")
		(net "M_K_DQ<34>")
	)
	(segment
		(start 108.578142 -114.810032)
		(end 110.295944 -116.527834)
		(width 0.1651)
		(layer "F.Cu")
		(net "M_K_DQ<33>")
	)
	(segment
		(start 111.105188 -121.03862)
		(end 111.453676 -121.387108)
		(width 0.1651)
		(layer "F.Cu")
		(net "M_K_DQ<33>")
	)
	(segment
		(start 108.578142 -106.553)
		(end 108.578142 -113.533174)
		(width 0.1016)
		(layer "F.Cu")
		(net "M_K_DQ<33>")
	)
	(segment
		(start 110.09884 -117.754908)
		(end 110.295944 -117.952012)
		(width 0.1651)
		(layer "F.Cu")
		(net "M_K_DQ<33>")
	)
	(segment
		(start 112.964214 -122.438922)
		(end 113.17224 -122.438922)
		(width 0.1651)
		(layer "F.Cu")
		(net "M_K_DQ<33>")
	)
	(segment
		(start 113.782348 -123.71578)
		(end 114.016028 -123.71578)
		(width 0.1651)
		(layer "F.Cu")
		(net "M_K_DQ<33>")
	)
	(segment
		(start 110.295944 -119.95785)
		(end 110.461044 -120.12295)
		(width 0.1651)
		(layer "F.Cu")
		(net "M_K_DQ<33>")
	)
	(segment
		(start 109.643672 -118.428008)
		(end 109.446568 -118.625112)
		(width 0.1651)
		(layer "F.Cu")
		(net "M_K_DQ<33>")
	)
	(segment
		(start 117.578632 -130.094736)
		(end 117.342412 -130.330956)
		(width 0.1651)
		(layer "F.Cu")
		(net "M_K_DQ<33>")
	)
	(segment
		(start 110.295944 -116.884704)
		(end 110.09884 -117.081808)
		(width 0.1651)
		(layer "F.Cu")
		(net "M_K_DQ<33>")
	)
	(segment
		(start 109.643672 -117.081808)
		(end 109.446568 -117.278912)
		(width 0.1651)
		(layer "F.Cu")
		(net "M_K_DQ<33>")
	)
	(segment
		(start 109.446568 -117.557804)
		(end 109.643672 -117.754908)
		(width 0.1651)
		(layer "F.Cu")
		(net "M_K_DQ<33>")
	)
	(segment
		(start 111.21136 -120.471438)
		(end 111.21136 -120.698768)
		(width 0.1651)
		(layer "F.Cu")
		(net "M_K_DQ<33>")
	)
	(segment
		(start 109.446568 -117.278912)
		(end 109.446568 -117.557804)
		(width 0.1651)
		(layer "F.Cu")
		(net "M_K_DQ<33>")
	)
	(segment
		(start 117.43563 -128.806956)
		(end 117.43563 -129.189734)
		(width 0.1651)
		(layer "F.Cu")
		(net "M_K_DQ<33>")
	)
	(segment
		(start 112.851692 -122.551444)
		(end 112.964214 -122.438922)
		(width 0.1651)
		(layer "F.Cu")
		(net "M_K_DQ<33>")
	)
	(segment
		(start 112.008158 -121.274332)
		(end 112.356646 -121.62282)
		(width 0.1651)
		(layer "F.Cu")
		(net "M_K_DQ<33>")
	)
	(segment
		(start 112.356646 -121.882154)
		(end 112.269524 -121.969276)
		(width 0.1651)
		(layer "F.Cu")
		(net "M_K_DQ<33>")
	)
	(segment
		(start 118.006368 -127.946658)
		(end 118.006368 -128.439418)
		(width 0.1651)
		(layer "F.Cu")
		(net "M_K_DQ<33>")
	)
	(segment
		(start 117.342412 -130.330956)
		(end 117.071648 -130.330956)
		(width 0.1651)
		(layer "F.Cu")
		(net "M_K_DQ<33>")
	)
	(segment
		(start 117.841268 -127.781558)
		(end 118.006368 -127.946658)
		(width 0.1651)
		(layer "F.Cu")
		(net "M_K_DQ<33>")
	)
	(segment
		(start 112.269524 -122.202956)
		(end 112.618012 -122.551444)
		(width 0.1651)
		(layer "F.Cu")
		(net "M_K_DQ<33>")
	)
	(segment
		(start 110.09884 -118.428008)
		(end 109.643672 -118.428008)
		(width 0.1651)
		(layer "F.Cu")
		(net "M_K_DQ<33>")
	)
	(segment
		(start 114.317526 -123.647962)
		(end 117.472968 -126.803404)
		(width 0.1651)
		(layer "F.Cu")
		(net "M_K_DQ<33>")
	)
	(segment
		(start 112.618012 -122.551444)
		(end 112.851692 -122.551444)
		(width 0.1651)
		(layer "F.Cu")
		(net "M_K_DQ<33>")
	)
	(segment
		(start 113.520728 -123.046744)
		(end 113.43386 -123.133612)
		(width 0.1651)
		(layer "F.Cu")
		(net "M_K_DQ<33>")
	)
	(segment
		(start 117.638068 -128.604518)
		(end 117.43563 -128.806956)
		(width 0.1651)
		(layer "F.Cu")
		(net "M_K_DQ<33>")
	)
	(segment
		(start 113.43386 -123.133612)
		(end 113.43386 -123.367292)
		(width 0.1651)
		(layer "F.Cu")
		(net "M_K_DQ<33>")
	)
	(segment
		(start 113.520728 -122.78741)
		(end 113.520728 -123.046744)
		(width 0.1651)
		(layer "F.Cu")
		(net "M_K_DQ<33>")
	)
	(segment
		(start 117.638068 -127.781558)
		(end 117.841268 -127.781558)
		(width 0.1651)
		(layer "F.Cu")
		(net "M_K_DQ<33>")
	)
	(segment
		(start 111.453676 -121.387108)
		(end 111.687356 -121.387108)
		(width 0.1651)
		(layer "F.Cu")
		(net "M_K_DQ<33>")
	)
	(segment
		(start 109.372146 -102.717854)
		(end 109.372146 -103.99268)
		(width 0.0889)
		(layer "F.Cu")
		(net "M_K_DQ<33>")
	)
	(segment
		(start 109.372146 -103.99268)
		(end 108.476542 -104.888284)
		(width 0.0889)
		(layer "F.Cu")
		(net "M_K_DQ<33>")
	)
	(segment
		(start 117.578632 -129.332736)
		(end 117.578632 -130.094736)
		(width 0.1651)
		(layer "F.Cu")
		(net "M_K_DQ<33>")
	)
	(segment
		(start 118.006368 -128.439418)
		(end 117.841268 -128.604518)
		(width 0.1651)
		(layer "F.Cu")
		(net "M_K_DQ<33>")
	)
	(segment
		(start 114.016028 -123.71578)
		(end 114.083846 -123.647962)
		(width 0.1651)
		(layer "F.Cu")
		(net "M_K_DQ<33>")
	)
	(segment
		(start 109.643672 -119.101108)
		(end 110.09884 -119.101108)
		(width 0.1651)
		(layer "F.Cu")
		(net "M_K_DQ<33>")
	)
	(segment
		(start 117.43563 -129.189734)
		(end 117.578632 -129.332736)
		(width 0.1651)
		(layer "F.Cu")
		(net "M_K_DQ<33>")
	)
	(segment
		(start 110.295944 -119.298212)
		(end 110.295944 -119.95785)
		(width 0.1651)
		(layer "F.Cu")
		(net "M_K_DQ<33>")
	)
	(segment
		(start 110.461044 -120.12295)
		(end 110.862872 -120.12295)
		(width 0.1651)
		(layer "F.Cu")
		(net "M_K_DQ<33>")
	)
	(segment
		(start 114.083846 -123.647962)
		(end 114.317526 -123.647962)
		(width 0.1651)
		(layer "F.Cu")
		(net "M_K_DQ<33>")
	)
	(segment
		(start 111.21136 -120.698768)
		(end 111.105188 -120.80494)
		(width 0.1651)
		(layer "F.Cu")
		(net "M_K_DQ<33>")
	)
	(segment
		(start 109.446568 -118.625112)
		(end 109.446568 -118.904004)
		(width 0.1651)
		(layer "F.Cu")
		(net "M_K_DQ<33>")
	)
	(segment
		(start 113.43386 -123.367292)
		(end 113.782348 -123.71578)
		(width 0.1651)
		(layer "F.Cu")
		(net "M_K_DQ<33>")
	)
	(segment
		(start 109.446568 -118.904004)
		(end 109.643672 -119.101108)
		(width 0.1651)
		(layer "F.Cu")
		(net "M_K_DQ<33>")
	)
	(segment
		(start 112.269524 -121.969276)
		(end 112.269524 -122.202956)
		(width 0.1651)
		(layer "F.Cu")
		(net "M_K_DQ<33>")
	)
	(segment
		(start 117.841268 -128.604518)
		(end 117.638068 -128.604518)
		(width 0.1651)
		(layer "F.Cu")
		(net "M_K_DQ<33>")
	)
	(segment
		(start 112.356646 -121.62282)
		(end 112.356646 -121.882154)
		(width 0.1651)
		(layer "F.Cu")
		(net "M_K_DQ<33>")
	)
	(segment
		(start 110.09884 -117.081808)
		(end 109.643672 -117.081808)
		(width 0.1651)
		(layer "F.Cu")
		(net "M_K_DQ<33>")
	)
	(segment
		(start 117.472968 -127.616458)
		(end 117.638068 -127.781558)
		(width 0.1651)
		(layer "F.Cu")
		(net "M_K_DQ<33>")
	)
	(segment
		(start 111.800132 -121.274332)
		(end 112.008158 -121.274332)
		(width 0.1651)
		(layer "F.Cu")
		(net "M_K_DQ<33>")
	)
	(segment
		(start 111.105188 -120.80494)
		(end 111.105188 -121.03862)
		(width 0.1651)
		(layer "F.Cu")
		(net "M_K_DQ<33>")
	)
	(segment
		(start 113.17224 -122.438922)
		(end 113.520728 -122.78741)
		(width 0.1651)
		(layer "F.Cu")
		(net "M_K_DQ<33>")
	)
	(segment
		(start 109.627416 -102.462584)
		(end 109.372146 -102.717854)
		(width 0.0889)
		(layer "F.Cu")
		(net "M_K_DQ<33>")
	)
	(segment
		(start 109.643672 -117.754908)
		(end 110.09884 -117.754908)
		(width 0.1651)
		(layer "F.Cu")
		(net "M_K_DQ<33>")
	)
	(segment
		(start 110.862872 -120.12295)
		(end 111.21136 -120.471438)
		(width 0.1651)
		(layer "F.Cu")
		(net "M_K_DQ<33>")
	)
	(segment
		(start 108.578142 -113.533174)
		(end 108.578142 -114.810032)
		(width 0.1651)
		(layer "F.Cu")
		(net "M_K_DQ<33>")
	)
	(segment
		(start 110.09884 -119.101108)
		(end 110.295944 -119.298212)
		(width 0.1651)
		(layer "F.Cu")
		(net "M_K_DQ<33>")
	)
	(segment
		(start 110.295944 -117.952012)
		(end 110.295944 -118.230904)
		(width 0.1651)
		(layer "F.Cu")
		(net "M_K_DQ<33>")
	)
	(segment
		(start 110.295944 -116.527834)
		(end 110.295944 -116.884704)
		(width 0.1651)
		(layer "F.Cu")
		(net "M_K_DQ<33>")
	)
	(segment
		(start 116.399564 -133.0706)
		(end 116.399564 -134.340346)
		(width 0.1651)
		(layer "F.Cu")
		(net "M_K_DQ<33>")
	)
	(segment
		(start 108.476542 -106.4514)
		(end 108.578142 -106.553)
		(width 0.0889)
		(layer "F.Cu")
		(net "M_K_DQ<33>")
	)
	(segment
		(start 117.472968 -126.803404)
		(end 117.472968 -127.616458)
		(width 0.1651)
		(layer "F.Cu")
		(net "M_K_DQ<33>")
	)
	(segment
		(start 108.476542 -104.888284)
		(end 108.476542 -106.4514)
		(width 0.0889)
		(layer "F.Cu")
		(net "M_K_DQ<33>")
	)
	(segment
		(start 110.295944 -118.230904)
		(end 110.09884 -118.428008)
		(width 0.1651)
		(layer "F.Cu")
		(net "M_K_DQ<33>")
	)
	(segment
		(start 111.687356 -121.387108)
		(end 111.800132 -121.274332)
		(width 0.1651)
		(layer "F.Cu")
		(net "M_K_DQ<33>")
	)
	(via
		(at 116.399564 -134.340346)
		(size 0.508)
		(drill 0.254)
		(layers "F.Cu" "B.Cu")
		(net "M_K_DQ<33>")
	)
	(via
		(at 117.071648 -130.330956)
		(size 0.508)
		(drill 0.254)
		(layers "F.Cu" "B.Cu")
		(net "M_K_DQ<33>")
	)
	(segment
		(start 117.249448 -129.649982)
		(end 117.071648 -129.827782)
		(width 0.1651)
		(layer "B.Cu")
		(net "M_K_DQ<33>")
	)
	(segment
		(start 117.071648 -129.827782)
		(end 117.071648 -130.330956)
		(width 0.1651)
		(layer "B.Cu")
		(net "M_K_DQ<33>")
	)
	(segment
		(start 117.249448 -128.276096)
		(end 117.249448 -129.649982)
		(width 0.1651)
		(layer "B.Cu")
		(net "M_K_DQ<33>")
	)
	(segment
		(start 116.77523 -133.1214)
		(end 116.77523 -132.6896)
		(width 0.14224)
		(layer "In2.Cu")
		(net "M_K_DQ<33>")
	)
	(segment
		(start 116.80063 -133.8834)
		(end 116.560854 -133.643624)
		(width 0.14224)
		(layer "In2.Cu")
		(net "M_K_DQ<33>")
	)
	(segment
		(start 116.560854 -133.643624)
		(end 116.560854 -133.335776)
		(width 0.14224)
		(layer "In2.Cu")
		(net "M_K_DQ<33>")
	)
	(segment
		(start 116.399564 -134.340346)
		(end 116.648484 -134.340346)
		(width 0.14224)
		(layer "In2.Cu")
		(net "M_K_DQ<33>")
	)
	(segment
		(start 116.621052 -130.7592)
		(end 117.049296 -130.330956)
		(width 0.14224)
		(layer "In2.Cu")
		(net "M_K_DQ<33>")
	)
	(segment
		(start 116.648484 -134.340346)
		(end 116.80063 -134.1882)
		(width 0.14224)
		(layer "In2.Cu")
		(net "M_K_DQ<33>")
	)
	(segment
		(start 116.85143 -131.419346)
		(end 116.621052 -131.188968)
		(width 0.14224)
		(layer "In2.Cu")
		(net "M_K_DQ<33>")
	)
	(segment
		(start 116.80063 -134.1882)
		(end 116.80063 -133.8834)
		(width 0.14224)
		(layer "In2.Cu")
		(net "M_K_DQ<33>")
	)
	(segment
		(start 116.77523 -132.6896)
		(end 116.560854 -132.475224)
		(width 0.14224)
		(layer "In2.Cu")
		(net "M_K_DQ<33>")
	)
	(segment
		(start 117.049296 -130.330956)
		(end 117.071648 -130.330956)
		(width 0.14224)
		(layer "In2.Cu")
		(net "M_K_DQ<33>")
	)
	(segment
		(start 116.621052 -131.188968)
		(end 116.621052 -130.7592)
		(width 0.14224)
		(layer "In2.Cu")
		(net "M_K_DQ<33>")
	)
	(segment
		(start 116.560854 -132.114544)
		(end 116.85143 -131.823968)
		(width 0.14224)
		(layer "In2.Cu")
		(net "M_K_DQ<33>")
	)
	(segment
		(start 116.85143 -131.823968)
		(end 116.85143 -131.419346)
		(width 0.14224)
		(layer "In2.Cu")
		(net "M_K_DQ<33>")
	)
	(segment
		(start 116.560854 -132.475224)
		(end 116.560854 -132.114544)
		(width 0.14224)
		(layer "In2.Cu")
		(net "M_K_DQ<33>")
	)
	(segment
		(start 116.560854 -133.335776)
		(end 116.77523 -133.1214)
		(width 0.14224)
		(layer "In2.Cu")
		(net "M_K_DQ<33>")
	)
	(segment
		(start 116.023644 -126.308612)
		(end 116.023644 -126.556516)
		(width 0.1651)
		(layer "F.Cu")
		(net "M_K_DQ<32>")
	)
	(segment
		(start 107.938316 -112.759998)
		(end 107.938316 -115.128802)
		(width 0.1651)
		(layer "F.Cu")
		(net "M_K_DQ<32>")
	)
	(segment
		(start 109.402372 -101.96195)
		(end 109.402372 -102.13848)
		(width 0.0889)
		(layer "F.Cu")
		(net "M_K_DQ<32>")
	)
	(segment
		(start 116.990368 -127.275336)
		(end 116.990368 -127.635)
		(width 0.1651)
		(layer "F.Cu")
		(net "M_K_DQ<32>")
	)
	(segment
		(start 108.286042 -106.4514)
		(end 108.184442 -106.553)
		(width 0.0889)
		(layer "F.Cu")
		(net "M_K_DQ<32>")
	)
	(segment
		(start 115.776502 -127.064262)
		(end 116.01196 -127.29972)
		(width 0.1651)
		(layer "F.Cu")
		(net "M_K_DQ<32>")
	)
	(segment
		(start 116.863368 -129.0574)
		(end 116.863368 -129.7686)
		(width 0.1651)
		(layer "F.Cu")
		(net "M_K_DQ<32>")
	)
	(segment
		(start 116.023644 -126.556516)
		(end 115.776502 -126.803658)
		(width 0.1651)
		(layer "F.Cu")
		(net "M_K_DQ<32>")
	)
	(segment
		(start 109.33049 -101.890068)
		(end 109.402372 -101.96195)
		(width 0.0889)
		(layer "F.Cu")
		(net "M_K_DQ<32>")
	)
	(segment
		(start 117.249448 -137.67054)
		(end 117.249448 -137.676382)
		(width 0.1651)
		(layer "F.Cu")
		(net "M_K_DQ<32>")
	)
	(segment
		(start 116.355368 -128.5494)
		(end 116.863368 -129.0574)
		(width 0.1651)
		(layer "F.Cu")
		(net "M_K_DQ<32>")
	)
	(segment
		(start 108.184442 -106.553)
		(end 108.184442 -112.513872)
		(width 0.1016)
		(layer "F.Cu")
		(net "M_K_DQ<32>")
	)
	(segment
		(start 115.948968 -131.161282)
		(end 116.399564 -131.611878)
		(width 0.1651)
		(layer "F.Cu")
		(net "M_K_DQ<32>")
	)
	(segment
		(start 116.75491 -127.039878)
		(end 116.990368 -127.275336)
		(width 0.1651)
		(layer "F.Cu")
		(net "M_K_DQ<32>")
	)
	(segment
		(start 114.073432 -124.9172)
		(end 114.632232 -124.9172)
		(width 0.1651)
		(layer "F.Cu")
		(net "M_K_DQ<32>")
	)
	(segment
		(start 109.402372 -102.13848)
		(end 109.181646 -102.359206)
		(width 0.0889)
		(layer "F.Cu")
		(net "M_K_DQ<32>")
	)
	(segment
		(start 109.013498 -101.889814)
		(end 109.33049 -101.890068)
		(width 0.0889)
		(layer "F.Cu")
		(net "M_K_DQ<32>")
	)
	(segment
		(start 107.938316 -115.128802)
		(end 108.786168 -115.976654)
		(width 0.1651)
		(layer "F.Cu")
		(net "M_K_DQ<32>")
	)
	(segment
		(start 117.249448 -137.676382)
		(end 117.071648 -135.8138)
		(width 0.1651)
		(layer "F.Cu")
		(net "M_K_DQ<32>")
	)
	(segment
		(start 109.181646 -102.359206)
		(end 109.181646 -103.913432)
		(width 0.0889)
		(layer "F.Cu")
		(net "M_K_DQ<32>")
	)
	(segment
		(start 116.863368 -129.7686)
		(end 115.948968 -130.683)
		(width 0.1651)
		(layer "F.Cu")
		(net "M_K_DQ<32>")
	)
	(segment
		(start 108.184442 -112.513872)
		(end 107.938316 -112.759998)
		(width 0.1016)
		(layer "F.Cu")
		(net "M_K_DQ<32>")
	)
	(segment
		(start 116.990368 -127.635)
		(end 116.355368 -128.27)
		(width 0.1651)
		(layer "F.Cu")
		(net "M_K_DQ<32>")
	)
	(segment
		(start 116.355368 -128.27)
		(end 116.355368 -128.5494)
		(width 0.1651)
		(layer "F.Cu")
		(net "M_K_DQ<32>")
	)
	(segment
		(start 108.768896 -101.967538)
		(end 109.013498 -101.889814)
		(width 0.0889)
		(layer "F.Cu")
		(net "M_K_DQ<32>")
	)
	(segment
		(start 108.786168 -119.629936)
		(end 114.073432 -124.9172)
		(width 0.1651)
		(layer "F.Cu")
		(net "M_K_DQ<32>")
	)
	(segment
		(start 116.507006 -127.039878)
		(end 116.75491 -127.039878)
		(width 0.1651)
		(layer "F.Cu")
		(net "M_K_DQ<32>")
	)
	(segment
		(start 114.632232 -124.9172)
		(end 116.023644 -126.308612)
		(width 0.1651)
		(layer "F.Cu")
		(net "M_K_DQ<32>")
	)
	(segment
		(start 115.948968 -130.683)
		(end 115.948968 -131.161282)
		(width 0.1651)
		(layer "F.Cu")
		(net "M_K_DQ<32>")
	)
	(segment
		(start 116.01196 -127.29972)
		(end 116.247164 -127.29972)
		(width 0.1651)
		(layer "F.Cu")
		(net "M_K_DQ<32>")
	)
	(segment
		(start 108.286042 -104.809036)
		(end 108.286042 -106.4514)
		(width 0.0889)
		(layer "F.Cu")
		(net "M_K_DQ<32>")
	)
	(segment
		(start 108.786168 -115.976654)
		(end 108.786168 -119.629936)
		(width 0.1651)
		(layer "F.Cu")
		(net "M_K_DQ<32>")
	)
	(segment
		(start 109.181646 -103.913432)
		(end 108.286042 -104.809036)
		(width 0.0889)
		(layer "F.Cu")
		(net "M_K_DQ<32>")
	)
	(segment
		(start 116.247164 -127.29972)
		(end 116.507006 -127.039878)
		(width 0.1651)
		(layer "F.Cu")
		(net "M_K_DQ<32>")
	)
	(segment
		(start 115.776502 -126.803658)
		(end 115.776502 -127.064262)
		(width 0.1651)
		(layer "F.Cu")
		(net "M_K_DQ<32>")
	)
	(via
		(at 117.071648 -135.8138)
		(size 0.508)
		(drill 0.254)
		(layers "F.Cu" "B.Cu")
		(net "M_K_DQ<32>")
	)
	(via
		(at 116.399564 -131.611878)
		(size 0.508)
		(drill 0.254)
		(layers "F.Cu" "B.Cu")
		(net "M_K_DQ<32>")
	)
	(segment
		(start 116.399564 -132.876036)
		(end 116.399564 -131.611878)
		(width 0.1651)
		(layer "B.Cu")
		(net "M_K_DQ<32>")
	)
	(segment
		(start 115.966494 -132.044948)
		(end 116.399564 -131.611878)
		(width 0.14224)
		(layer "In2.Cu")
		(net "M_K_DQ<32>")
	)
	(segment
		(start 116.775484 -135.8138)
		(end 115.966494 -135.00481)
		(width 0.14224)
		(layer "In2.Cu")
		(net "M_K_DQ<32>")
	)
	(segment
		(start 117.071648 -135.8138)
		(end 116.775484 -135.8138)
		(width 0.14224)
		(layer "In2.Cu")
		(net "M_K_DQ<32>")
	)
	(segment
		(start 115.966494 -135.00481)
		(end 115.966494 -132.044948)
		(width 0.14224)
		(layer "In2.Cu")
		(net "M_K_DQ<32>")
	)
	(segment
		(start 78.051406 -97.19564)
		(end 77.479906 -97.19564)
		(width 0.1651)
		(layer "F.Cu")
		(net "M_K_DQ<31>")
	)
	(segment
		(start 65.399412 -133.0706)
		(end 65.399412 -134.340346)
		(width 0.1651)
		(layer "F.Cu")
		(net "M_K_DQ<31>")
	)
	(via
		(at 66.249296 -130.330956)
		(size 0.508)
		(drill 0.254)
		(layers "F.Cu" "B.Cu")
		(net "M_K_DQ<31>")
	)
	(via
		(at 65.399412 -134.340346)
		(size 0.508)
		(drill 0.254)
		(layers "F.Cu" "B.Cu")
		(net "M_K_DQ<31>")
	)
	(via
		(at 77.479906 -97.19564)
		(size 0.508)
		(drill 0.254)
		(layers "F.Cu" "B.Cu")
		(net "M_K_DQ<31>")
	)
	(segment
		(start 66.24955 -128.276096)
		(end 66.249296 -128.276096)
		(width 0.1651)
		(layer "B.Cu")
		(net "M_K_DQ<31>")
	)
	(segment
		(start 66.249296 -128.276096)
		(end 66.249296 -130.330956)
		(width 0.1651)
		(layer "B.Cu")
		(net "M_K_DQ<31>")
	)
	(segment
		(start 67.851528 -112.039654)
		(end 67.993768 -112.181894)
		(width 0.14224)
		(layer "In2.Cu")
		(net "M_K_DQ<31>")
	)
	(segment
		(start 65.6717 -134.340346)
		(end 65.399412 -134.340346)
		(width 0.14224)
		(layer "In2.Cu")
		(net "M_K_DQ<31>")
	)
	(segment
		(start 65.81775 -133.0198)
		(end 65.560702 -133.276848)
		(width 0.14224)
		(layer "In2.Cu")
		(net "M_K_DQ<31>")
	)
	(segment
		(start 75.780646 -99.76739)
		(end 75.744832 -99.76739)
		(width 0.0889)
		(layer "In2.Cu")
		(net "M_K_DQ<31>")
	)
	(segment
		(start 66.59118 -129.989072)
		(end 66.249296 -130.330956)
		(width 0.14224)
		(layer "In2.Cu")
		(net "M_K_DQ<31>")
	)
	(segment
		(start 74.922126 -100.26269)
		(end 74.886312 -100.26269)
		(width 0.0889)
		(layer "In2.Cu")
		(net "M_K_DQ<31>")
	)
	(segment
		(start 65.560702 -132.457952)
		(end 65.81775 -132.715)
		(width 0.14224)
		(layer "In2.Cu")
		(net "M_K_DQ<31>")
	)
	(segment
		(start 66.249296 -130.330956)
		(end 66.226944 -130.330956)
		(width 0.14224)
		(layer "In2.Cu")
		(net "M_K_DQ<31>")
	)
	(segment
		(start 67.851528 -112.689894)
		(end 66.866008 -112.689894)
		(width 0.14224)
		(layer "In2.Cu")
		(net "M_K_DQ<31>")
	)
	(segment
		(start 66.723768 -112.832134)
		(end 66.723768 -113.197894)
		(width 0.14224)
		(layer "In2.Cu")
		(net "M_K_DQ<31>")
	)
	(segment
		(start 66.866008 -113.990374)
		(end 66.723768 -114.132614)
		(width 0.14224)
		(layer "In2.Cu")
		(net "M_K_DQ<31>")
	)
	(segment
		(start 66.866008 -112.689894)
		(end 66.723768 -112.832134)
		(width 0.14224)
		(layer "In2.Cu")
		(net "M_K_DQ<31>")
	)
	(segment
		(start 67.079368 -128.114552)
		(end 67.079368 -128.520952)
		(width 0.14224)
		(layer "In2.Cu")
		(net "M_K_DQ<31>")
	)
	(segment
		(start 65.560702 -132.184648)
		(end 65.560702 -132.457952)
		(width 0.14224)
		(layer "In2.Cu")
		(net "M_K_DQ<31>")
	)
	(segment
		(start 68.400168 -113.848134)
		(end 68.257928 -113.990374)
		(width 0.14224)
		(layer "In2.Cu")
		(net "M_K_DQ<31>")
	)
	(segment
		(start 66.866008 -113.340134)
		(end 68.257928 -113.340134)
		(width 0.14224)
		(layer "In2.Cu")
		(net "M_K_DQ<31>")
	)
	(segment
		(start 67.993768 -112.547654)
		(end 67.851528 -112.689894)
		(width 0.14224)
		(layer "In2.Cu")
		(net "M_K_DQ<31>")
	)
	(segment
		(start 66.866008 -112.039654)
		(end 67.851528 -112.039654)
		(width 0.14224)
		(layer "In2.Cu")
		(net "M_K_DQ<31>")
	)
	(segment
		(start 70.090284 -104.613964)
		(end 70.033388 -104.67086)
		(width 0.0889)
		(layer "In2.Cu")
		(net "M_K_DQ<31>")
	)
	(segment
		(start 65.8495 -134.162546)
		(end 65.6717 -134.340346)
		(width 0.14224)
		(layer "In2.Cu")
		(net "M_K_DQ<31>")
	)
	(segment
		(start 66.723768 -114.132614)
		(end 66.723768 -125.552454)
		(width 0.14224)
		(layer "In2.Cu")
		(net "M_K_DQ<31>")
	)
	(segment
		(start 67.079368 -128.520952)
		(end 66.876168 -128.724152)
		(width 0.14224)
		(layer "In2.Cu")
		(net "M_K_DQ<31>")
	)
	(segment
		(start 66.805302 -128.724152)
		(end 66.602102 -128.927352)
		(width 0.14224)
		(layer "In2.Cu")
		(net "M_K_DQ<31>")
	)
	(segment
		(start 66.876168 -128.724152)
		(end 66.805302 -128.724152)
		(width 0.14224)
		(layer "In2.Cu")
		(net "M_K_DQ<31>")
	)
	(segment
		(start 66.723768 -125.552454)
		(end 66.602102 -125.67412)
		(width 0.14224)
		(layer "In2.Cu")
		(net "M_K_DQ<31>")
	)
	(segment
		(start 68.196968 -109.8296)
		(end 66.723768 -111.3028)
		(width 0.14224)
		(layer "In2.Cu")
		(net "M_K_DQ<31>")
	)
	(segment
		(start 65.560702 -133.550152)
		(end 65.8495 -133.83895)
		(width 0.14224)
		(layer "In2.Cu")
		(net "M_K_DQ<31>")
	)
	(segment
		(start 67.993768 -112.181894)
		(end 67.993768 -112.547654)
		(width 0.14224)
		(layer "In2.Cu")
		(net "M_K_DQ<31>")
	)
	(segment
		(start 68.196968 -106.50728)
		(end 68.196968 -109.8296)
		(width 0.14224)
		(layer "In2.Cu")
		(net "M_K_DQ<31>")
	)
	(segment
		(start 70.090284 -104.271064)
		(end 70.090284 -104.613964)
		(width 0.0889)
		(layer "In2.Cu")
		(net "M_K_DQ<31>")
	)
	(segment
		(start 68.257928 -113.340134)
		(end 68.400168 -113.482374)
		(width 0.14224)
		(layer "In2.Cu")
		(net "M_K_DQ<31>")
	)
	(segment
		(start 65.84315 -131.9022)
		(end 65.560702 -132.184648)
		(width 0.14224)
		(layer "In2.Cu")
		(net "M_K_DQ<31>")
	)
	(segment
		(start 74.05878 -100.75799)
		(end 74.03084 -100.75799)
		(width 0.0889)
		(layer "In2.Cu")
		(net "M_K_DQ<31>")
	)
	(segment
		(start 66.723768 -113.197894)
		(end 66.866008 -113.340134)
		(width 0.14224)
		(layer "In2.Cu")
		(net "M_K_DQ<31>")
	)
	(segment
		(start 76.61529 -99.272344)
		(end 76.61021 -99.272344)
		(width 0.0889)
		(layer "In2.Cu")
		(net "M_K_DQ<31>")
	)
	(segment
		(start 65.7987 -130.7592)
		(end 65.7987 -131.188968)
		(width 0.14224)
		(layer "In2.Cu")
		(net "M_K_DQ<31>")
	)
	(segment
		(start 77.212444 -98.585274)
		(end 77.212444 -98.681286)
		(width 0.0889)
		(layer "In2.Cu")
		(net "M_K_DQ<31>")
	)
	(segment
		(start 66.226944 -130.330956)
		(end 65.7987 -130.7592)
		(width 0.14224)
		(layer "In2.Cu")
		(net "M_K_DQ<31>")
	)
	(segment
		(start 65.81775 -132.715)
		(end 65.81775 -133.0198)
		(width 0.14224)
		(layer "In2.Cu")
		(net "M_K_DQ<31>")
	)
	(segment
		(start 66.602102 -128.927352)
		(end 66.602102 -129.989072)
		(width 0.14224)
		(layer "In2.Cu")
		(net "M_K_DQ<31>")
	)
	(segment
		(start 68.257928 -113.990374)
		(end 66.866008 -113.990374)
		(width 0.14224)
		(layer "In2.Cu")
		(net "M_K_DQ<31>")
	)
	(segment
		(start 65.560702 -133.276848)
		(end 65.560702 -133.550152)
		(width 0.14224)
		(layer "In2.Cu")
		(net "M_K_DQ<31>")
	)
	(segment
		(start 66.602102 -125.67412)
		(end 66.602102 -127.708152)
		(width 0.14224)
		(layer "In2.Cu")
		(net "M_K_DQ<31>")
	)
	(segment
		(start 66.723768 -111.3028)
		(end 66.723768 -111.897414)
		(width 0.14224)
		(layer "In2.Cu")
		(net "M_K_DQ<31>")
	)
	(segment
		(start 77.479906 -97.19564)
		(end 77.479906 -97.672144)
		(width 0.0889)
		(layer "In2.Cu")
		(net "M_K_DQ<31>")
	)
	(segment
		(start 70.033388 -104.67086)
		(end 68.196968 -106.50728)
		(width 0.14224)
		(layer "In2.Cu")
		(net "M_K_DQ<31>")
	)
	(segment
		(start 65.84315 -131.233418)
		(end 65.84315 -131.9022)
		(width 0.14224)
		(layer "In2.Cu")
		(net "M_K_DQ<31>")
	)
	(segment
		(start 73.208896 -101.253036)
		(end 73.17613 -101.253036)
		(width 0.0889)
		(layer "In2.Cu")
		(net "M_K_DQ<31>")
	)
	(segment
		(start 72.747886 -101.613462)
		(end 70.090284 -104.271064)
		(width 0.0889)
		(layer "In2.Cu")
		(net "M_K_DQ<31>")
	)
	(segment
		(start 66.876168 -127.911352)
		(end 67.079368 -128.114552)
		(width 0.14224)
		(layer "In2.Cu")
		(net "M_K_DQ<31>")
	)
	(segment
		(start 72.840596 -101.452934)
		(end 72.747886 -101.613462)
		(width 0.0889)
		(layer "In2.Cu")
		(net "M_K_DQ<31>")
	)
	(segment
		(start 66.805302 -127.911352)
		(end 66.876168 -127.911352)
		(width 0.14224)
		(layer "In2.Cu")
		(net "M_K_DQ<31>")
	)
	(segment
		(start 66.602102 -129.989072)
		(end 66.59118 -129.989072)
		(width 0.14224)
		(layer "In2.Cu")
		(net "M_K_DQ<31>")
	)
	(segment
		(start 65.8495 -133.83895)
		(end 65.8495 -134.162546)
		(width 0.14224)
		(layer "In2.Cu")
		(net "M_K_DQ<31>")
	)
	(segment
		(start 65.7987 -131.188968)
		(end 65.84315 -131.233418)
		(width 0.14224)
		(layer "In2.Cu")
		(net "M_K_DQ<31>")
	)
	(segment
		(start 68.400168 -113.482374)
		(end 68.400168 -113.848134)
		(width 0.14224)
		(layer "In2.Cu")
		(net "M_K_DQ<31>")
	)
	(segment
		(start 66.602102 -127.708152)
		(end 66.805302 -127.911352)
		(width 0.14224)
		(layer "In2.Cu")
		(net "M_K_DQ<31>")
	)
	(segment
		(start 66.723768 -111.897414)
		(end 66.866008 -112.039654)
		(width 0.14224)
		(layer "In2.Cu")
		(net "M_K_DQ<31>")
	)
	(arc
		(start 76.61021 -99.272344)
		(mid 76.414994 -99.326031)
		(end 76.274676 -99.471988)
		(width 0.0889)
		(layer "In2.Cu")
		(net "M_K_DQ<31>")
	)
	(arc
		(start 75.744832 -99.76739)
		(mid 75.554903 -99.82526)
		(end 75.416156 -99.967288)
		(width 0.0889)
		(layer "In2.Cu")
		(net "M_K_DQ<31>")
	)
	(arc
		(start 77.383894 -98.042984)
		(mid 77.340874 -98.112089)
		(end 77.303122 -98.184208)
		(width 0.0889)
		(layer "In2.Cu")
		(net "M_K_DQ<31>")
	)
	(arc
		(start 77.479906 -97.672144)
		(mid 77.463797 -97.86582)
		(end 77.383894 -98.042984)
		(width 0.0889)
		(layer "In2.Cu")
		(net "M_K_DQ<31>")
	)
	(arc
		(start 73.699116 -100.957888)
		(mid 73.492112 -101.168752)
		(end 73.208896 -101.253036)
		(width 0.0889)
		(layer "In2.Cu")
		(net "M_K_DQ<31>")
	)
	(arc
		(start 76.642976 -99.271836)
		(mid 76.629135 -99.272214)
		(end 76.61529 -99.272344)
		(width 0.0889)
		(layer "In2.Cu")
		(net "M_K_DQ<31>")
	)
	(arc
		(start 76.274676 -99.471988)
		(mid 76.066068 -99.68392)
		(end 75.780646 -99.76739)
		(width 0.0889)
		(layer "In2.Cu")
		(net "M_K_DQ<31>")
	)
	(arc
		(start 74.03084 -100.75799)
		(mid 73.839198 -100.815156)
		(end 73.699116 -100.957888)
		(width 0.0889)
		(layer "In2.Cu")
		(net "M_K_DQ<31>")
	)
	(arc
		(start 74.557636 -100.462588)
		(mid 74.346923 -100.675667)
		(end 74.05878 -100.75799)
		(width 0.0889)
		(layer "In2.Cu")
		(net "M_K_DQ<31>")
	)
	(arc
		(start 73.17613 -101.253036)
		(mid 72.982342 -101.309308)
		(end 72.840596 -101.452934)
		(width 0.0889)
		(layer "In2.Cu")
		(net "M_K_DQ<31>")
	)
	(arc
		(start 77.212444 -98.681286)
		(mid 77.046893 -99.091521)
		(end 76.642976 -99.271836)
		(width 0.0889)
		(layer "In2.Cu")
		(net "M_K_DQ<31>")
	)
	(arc
		(start 75.416156 -99.967288)
		(mid 75.207548 -100.17922)
		(end 74.922126 -100.26269)
		(width 0.0889)
		(layer "In2.Cu")
		(net "M_K_DQ<31>")
	)
	(arc
		(start 77.303122 -98.184208)
		(mid 77.235388 -98.379678)
		(end 77.212444 -98.585274)
		(width 0.0889)
		(layer "In2.Cu")
		(net "M_K_DQ<31>")
	)
	(arc
		(start 74.886312 -100.26269)
		(mid 74.696383 -100.32056)
		(end 74.557636 -100.462588)
		(width 0.0889)
		(layer "In2.Cu")
		(net "M_K_DQ<31>")
	)
	(segment
		(start 66.38163 -136.57072)
		(end 66.38163 -136.35228)
		(width 0.1651)
		(layer "F.Cu")
		(net "M_K_DQ<30>")
	)
	(segment
		(start 66.24955 -135.915654)
		(end 66.249296 -135.9154)
		(width 0.1651)
		(layer "F.Cu")
		(net "M_K_DQ<30>")
	)
	(segment
		(start 66.24955 -136.2202)
		(end 66.24955 -135.915654)
		(width 0.1651)
		(layer "F.Cu")
		(net "M_K_DQ<30>")
	)
	(segment
		(start 66.38163 -136.35228)
		(end 66.24955 -136.2202)
		(width 0.1651)
		(layer "F.Cu")
		(net "M_K_DQ<30>")
	)
	(segment
		(start 66.24955 -136.7028)
		(end 66.38163 -136.57072)
		(width 0.1651)
		(layer "F.Cu")
		(net "M_K_DQ<30>")
	)
	(segment
		(start 78.051406 -95.21444)
		(end 77.479906 -95.21444)
		(width 0.1651)
		(layer "F.Cu")
		(net "M_K_DQ<30>")
	)
	(segment
		(start 66.24955 -137.67054)
		(end 66.24955 -136.7028)
		(width 0.1651)
		(layer "F.Cu")
		(net "M_K_DQ<30>")
	)
	(via
		(at 66.249296 -135.9154)
		(size 0.508)
		(drill 0.254)
		(layers "F.Cu" "B.Cu")
		(net "M_K_DQ<30>")
	)
	(via
		(at 77.479906 -95.21444)
		(size 0.508)
		(drill 0.254)
		(layers "F.Cu" "B.Cu")
		(net "M_K_DQ<30>")
	)
	(via
		(at 65.399412 -131.611878)
		(size 0.508)
		(drill 0.254)
		(layers "F.Cu" "B.Cu")
		(net "M_K_DQ<30>")
	)
	(segment
		(start 65.399412 -132.876036)
		(end 65.399412 -131.611878)
		(width 0.1651)
		(layer "B.Cu")
		(net "M_K_DQ<30>")
	)
	(segment
		(start 65.961768 -122.494294)
		(end 65.570608 -122.494294)
		(width 0.14224)
		(layer "In2.Cu")
		(net "M_K_DQ<30>")
	)
	(segment
		(start 65.230502 -131.442968)
		(end 65.399412 -131.611878)
		(width 0.14224)
		(layer "In2.Cu")
		(net "M_K_DQ<30>")
	)
	(segment
		(start 65.570608 -123.794774)
		(end 65.428368 -123.937014)
		(width 0.14224)
		(layer "In2.Cu")
		(net "M_K_DQ<30>")
	)
	(segment
		(start 65.230502 -130.468878)
		(end 65.230502 -131.442968)
		(width 0.14224)
		(layer "In2.Cu")
		(net "M_K_DQ<30>")
	)
	(segment
		(start 77.14996 -95.976186)
		(end 77.133196 -96.004888)
		(width 0.0889)
		(layer "In2.Cu")
		(net "M_K_DQ<30>")
	)
	(segment
		(start 76.609194 -99.081844)
		(end 76.599796 -99.081844)
		(width 0.0889)
		(layer "In2.Cu")
		(net "M_K_DQ<30>")
	)
	(segment
		(start 77.130148 -97.390458)
		(end 77.139546 -97.406206)
		(width 0.0889)
		(layer "In2.Cu")
		(net "M_K_DQ<30>")
	)
	(segment
		(start 77.212444 -97.691194)
		(end 77.212444 -97.793302)
		(width 0.0889)
		(layer "In2.Cu")
		(net "M_K_DQ<30>")
	)
	(segment
		(start 65.428368 -119.2022)
		(end 65.428368 -121.640854)
		(width 0.14224)
		(layer "In2.Cu")
		(net "M_K_DQ<30>")
	)
	(segment
		(start 72.594216 -101.4984)
		(end 69.911722 -104.180894)
		(width 0.0889)
		(layer "In2.Cu")
		(net "M_K_DQ<30>")
	)
	(segment
		(start 69.607176 -104.180894)
		(end 67.663568 -106.124502)
		(width 0.14224)
		(layer "In2.Cu")
		(net "M_K_DQ<30>")
	)
	(segment
		(start 73.202292 -101.062536)
		(end 73.17359 -101.062536)
		(width 0.0889)
		(layer "In2.Cu")
		(net "M_K_DQ<30>")
	)
	(segment
		(start 65.570608 -122.494294)
		(end 65.428368 -122.636534)
		(width 0.14224)
		(layer "In2.Cu")
		(net "M_K_DQ<30>")
	)
	(segment
		(start 66.088768 -123.312174)
		(end 66.088768 -123.667774)
		(width 0.14224)
		(layer "In2.Cu")
		(net "M_K_DQ<30>")
	)
	(segment
		(start 65.428368 -123.002294)
		(end 65.570608 -123.144534)
		(width 0.14224)
		(layer "In2.Cu")
		(net "M_K_DQ<30>")
	)
	(segment
		(start 65.631568 -121.844054)
		(end 65.921128 -121.844054)
		(width 0.14224)
		(layer "In2.Cu")
		(net "M_K_DQ<30>")
	)
	(segment
		(start 65.921128 -121.844054)
		(end 66.088768 -122.011694)
		(width 0.14224)
		(layer "In2.Cu")
		(net "M_K_DQ<30>")
	)
	(segment
		(start 65.570608 -123.144534)
		(end 65.921128 -123.144534)
		(width 0.14224)
		(layer "In2.Cu")
		(net "M_K_DQ<30>")
	)
	(segment
		(start 65.967102 -125.76048)
		(end 65.967102 -129.732278)
		(width 0.14224)
		(layer "In2.Cu")
		(net "M_K_DQ<30>")
	)
	(segment
		(start 64.966342 -134.632446)
		(end 66.249296 -135.9154)
		(width 0.14224)
		(layer "In2.Cu")
		(net "M_K_DQ<30>")
	)
	(segment
		(start 72.675242 -101.357938)
		(end 72.594216 -101.4984)
		(width 0.0889)
		(layer "In2.Cu")
		(net "M_K_DQ<30>")
	)
	(segment
		(start 77.12837 -96.396302)
		(end 77.133196 -96.404938)
		(width 0.0889)
		(layer "In2.Cu")
		(net "M_K_DQ<30>")
	)
	(segment
		(start 65.921128 -123.144534)
		(end 66.088768 -123.312174)
		(width 0.14224)
		(layer "In2.Cu")
		(net "M_K_DQ<30>")
	)
	(segment
		(start 66.088768 -118.5418)
		(end 65.428368 -119.2022)
		(width 0.14224)
		(layer "In2.Cu")
		(net "M_K_DQ<30>")
	)
	(segment
		(start 65.428368 -123.937014)
		(end 65.428368 -125.221746)
		(width 0.14224)
		(layer "In2.Cu")
		(net "M_K_DQ<30>")
	)
	(segment
		(start 67.663568 -106.124502)
		(end 67.663568 -109.61243)
		(width 0.14224)
		(layer "In2.Cu")
		(net "M_K_DQ<30>")
	)
	(segment
		(start 65.961768 -123.794774)
		(end 65.570608 -123.794774)
		(width 0.14224)
		(layer "In2.Cu")
		(net "M_K_DQ<30>")
	)
	(segment
		(start 75.7809 -99.576636)
		(end 75.745086 -99.576636)
		(width 0.0889)
		(layer "In2.Cu")
		(net "M_K_DQ<30>")
	)
	(segment
		(start 65.428368 -122.636534)
		(end 65.428368 -123.002294)
		(width 0.14224)
		(layer "In2.Cu")
		(net "M_K_DQ<30>")
	)
	(segment
		(start 66.088768 -122.367294)
		(end 65.961768 -122.494294)
		(width 0.14224)
		(layer "In2.Cu")
		(net "M_K_DQ<30>")
	)
	(segment
		(start 77.479906 -95.21444)
		(end 77.14996 -95.976186)
		(width 0.0889)
		(layer "In2.Cu")
		(net "M_K_DQ<30>")
	)
	(segment
		(start 64.966342 -132.044948)
		(end 64.966342 -134.632446)
		(width 0.14224)
		(layer "In2.Cu")
		(net "M_K_DQ<30>")
	)
	(segment
		(start 66.088768 -122.011694)
		(end 66.088768 -122.367294)
		(width 0.14224)
		(layer "In2.Cu")
		(net "M_K_DQ<30>")
	)
	(segment
		(start 65.967102 -129.732278)
		(end 65.230502 -130.468878)
		(width 0.14224)
		(layer "In2.Cu")
		(net "M_K_DQ<30>")
	)
	(segment
		(start 77.133196 -96.404938)
		(end 77.139546 -96.415606)
		(width 0.0889)
		(layer "In2.Cu")
		(net "M_K_DQ<30>")
	)
	(segment
		(start 65.428368 -121.640854)
		(end 65.631568 -121.844054)
		(width 0.14224)
		(layer "In2.Cu")
		(net "M_K_DQ<30>")
	)
	(segment
		(start 74.057002 -100.567236)
		(end 74.032872 -100.567236)
		(width 0.0889)
		(layer "In2.Cu")
		(net "M_K_DQ<30>")
	)
	(segment
		(start 66.088768 -111.18723)
		(end 66.088768 -118.5418)
		(width 0.14224)
		(layer "In2.Cu")
		(net "M_K_DQ<30>")
	)
	(segment
		(start 65.399412 -131.611878)
		(end 64.966342 -132.044948)
		(width 0.14224)
		(layer "In2.Cu")
		(net "M_K_DQ<30>")
	)
	(segment
		(start 67.663568 -109.61243)
		(end 66.088768 -111.18723)
		(width 0.14224)
		(layer "In2.Cu")
		(net "M_K_DQ<30>")
	)
	(segment
		(start 66.088768 -123.667774)
		(end 65.961768 -123.794774)
		(width 0.14224)
		(layer "In2.Cu")
		(net "M_K_DQ<30>")
	)
	(segment
		(start 74.92238 -100.071936)
		(end 74.882756 -100.071936)
		(width 0.0889)
		(layer "In2.Cu")
		(net "M_K_DQ<30>")
	)
	(segment
		(start 65.428368 -125.221746)
		(end 65.967102 -125.76048)
		(width 0.14224)
		(layer "In2.Cu")
		(net "M_K_DQ<30>")
	)
	(segment
		(start 77.02169 -98.429318)
		(end 77.02169 -98.681286)
		(width 0.0889)
		(layer "In2.Cu")
		(net "M_K_DQ<30>")
	)
	(segment
		(start 69.911722 -104.180894)
		(end 69.607176 -104.180894)
		(width 0.0889)
		(layer "In2.Cu")
		(net "M_K_DQ<30>")
	)
	(arc
		(start 77.02169 -98.681286)
		(mid 76.909693 -98.958995)
		(end 76.636372 -99.081336)
		(width 0.0889)
		(layer "In2.Cu")
		(net "M_K_DQ<30>")
	)
	(arc
		(start 77.133196 -96.995488)
		(mid 77.077006 -97.192533)
		(end 77.130148 -97.390458)
		(width 0.0889)
		(layer "In2.Cu")
		(net "M_K_DQ<30>")
	)
	(arc
		(start 74.882756 -100.071936)
		(mid 74.599539 -100.156217)
		(end 74.392536 -100.367084)
		(width 0.0889)
		(layer "In2.Cu")
		(net "M_K_DQ<30>")
	)
	(arc
		(start 77.139546 -96.415606)
		(mid 77.212344 -96.706369)
		(end 77.133196 -96.995488)
		(width 0.0889)
		(layer "In2.Cu")
		(net "M_K_DQ<30>")
	)
	(arc
		(start 77.140054 -98.04781)
		(mid 77.056558 -98.231023)
		(end 77.02169 -98.429318)
		(width 0.0889)
		(layer "In2.Cu")
		(net "M_K_DQ<30>")
	)
	(arc
		(start 73.534016 -100.862638)
		(mid 73.393937 -101.005374)
		(end 73.202292 -101.062536)
		(width 0.0889)
		(layer "In2.Cu")
		(net "M_K_DQ<30>")
	)
	(arc
		(start 76.599796 -99.081844)
		(mid 76.313744 -99.161242)
		(end 76.109576 -99.376738)
		(width 0.0889)
		(layer "In2.Cu")
		(net "M_K_DQ<30>")
	)
	(arc
		(start 75.251056 -99.872038)
		(mid 75.112312 -100.014071)
		(end 74.92238 -100.071936)
		(width 0.0889)
		(layer "In2.Cu")
		(net "M_K_DQ<30>")
	)
	(arc
		(start 75.745086 -99.576636)
		(mid 75.459662 -99.660103)
		(end 75.251056 -99.872038)
		(width 0.0889)
		(layer "In2.Cu")
		(net "M_K_DQ<30>")
	)
	(arc
		(start 77.139546 -97.406206)
		(mid 77.193977 -97.544096)
		(end 77.212444 -97.691194)
		(width 0.0889)
		(layer "In2.Cu")
		(net "M_K_DQ<30>")
	)
	(arc
		(start 74.032872 -100.567236)
		(mid 73.744727 -100.649555)
		(end 73.534016 -100.862638)
		(width 0.0889)
		(layer "In2.Cu")
		(net "M_K_DQ<30>")
	)
	(arc
		(start 73.17105 -101.062536)
		(mid 72.884637 -101.145591)
		(end 72.675242 -101.357938)
		(width 0.0889)
		(layer "In2.Cu")
		(net "M_K_DQ<30>")
	)
	(arc
		(start 73.17359 -101.062536)
		(mid 73.17232 -101.062535)
		(end 73.17105 -101.062536)
		(width 0.0889)
		(layer "In2.Cu")
		(net "M_K_DQ<30>")
	)
	(arc
		(start 74.392536 -100.367084)
		(mid 74.250853 -100.510888)
		(end 74.057002 -100.567236)
		(width 0.0889)
		(layer "In2.Cu")
		(net "M_K_DQ<30>")
	)
	(arc
		(start 76.109576 -99.376738)
		(mid 75.970832 -99.518771)
		(end 75.7809 -99.576636)
		(width 0.0889)
		(layer "In2.Cu")
		(net "M_K_DQ<30>")
	)
	(arc
		(start 77.133196 -96.004888)
		(mid 77.079726 -96.199951)
		(end 77.12837 -96.396302)
		(width 0.0889)
		(layer "In2.Cu")
		(net "M_K_DQ<30>")
	)
	(arc
		(start 76.636372 -99.081336)
		(mid 76.622785 -99.081718)
		(end 76.609194 -99.081844)
		(width 0.0889)
		(layer "In2.Cu")
		(net "M_K_DQ<30>")
	)
	(arc
		(start 77.212444 -97.793302)
		(mid 77.193995 -97.925604)
		(end 77.140054 -98.04781)
		(width 0.0889)
		(layer "In2.Cu")
		(net "M_K_DQ<30>")
	)
	(segment
		(start 40.030908 -136.32434)
		(end 39.899336 -136.192768)
		(width 0.1651)
		(layer "F.Cu")
		(net "M_K_DQ<2>")
	)
	(segment
		(start 39.899336 -136.192768)
		(end 39.899336 -135.9154)
		(width 0.1651)
		(layer "F.Cu")
		(net "M_K_DQ<2>")
	)
	(segment
		(start 67.749166 -89.27084)
		(end 67.101466 -89.27084)
		(width 0.1651)
		(layer "F.Cu")
		(net "M_K_DQ<2>")
	)
	(segment
		(start 39.899336 -136.679432)
		(end 40.030908 -136.54786)
		(width 0.1651)
		(layer "F.Cu")
		(net "M_K_DQ<2>")
	)
	(segment
		(start 39.899336 -137.67054)
		(end 39.899336 -136.679432)
		(width 0.1651)
		(layer "F.Cu")
		(net "M_K_DQ<2>")
	)
	(segment
		(start 40.030908 -136.54786)
		(end 40.030908 -136.32434)
		(width 0.1651)
		(layer "F.Cu")
		(net "M_K_DQ<2>")
	)
	(via
		(at 39.899336 -135.9154)
		(size 0.508)
		(drill 0.254)
		(layers "F.Cu" "B.Cu")
		(net "M_K_DQ<2>")
	)
	(via
		(at 67.101466 -89.27084)
		(size 0.508)
		(drill 0.254)
		(layers "F.Cu" "B.Cu")
		(net "M_K_DQ<2>")
	)
	(via
		(at 39.049452 -131.611878)
		(size 0.508)
		(drill 0.254)
		(layers "F.Cu" "B.Cu")
		(net "M_K_DQ<2>")
	)
	(segment
		(start 39.049452 -132.876036)
		(end 39.049452 -131.611878)
		(width 0.1651)
		(layer "B.Cu")
		(net "M_K_DQ<2>")
	)
	(segment
		(start 38.70452 -130.633978)
		(end 38.70452 -131.266946)
		(width 0.14224)
		(layer "In2.Cu")
		(net "M_K_DQ<2>")
	)
	(segment
		(start 65.893188 -89.27084)
		(end 65.241424 -89.27084)
		(width 0.14224)
		(layer "In2.Cu")
		(net "M_K_DQ<2>")
	)
	(segment
		(start 41.196768 -114.935)
		(end 41.196768 -128.2954)
		(width 0.14224)
		(layer "In2.Cu")
		(net "M_K_DQ<2>")
	)
	(segment
		(start 39.049452 -131.611878)
		(end 38.616382 -132.044948)
		(width 0.14224)
		(layer "In2.Cu")
		(net "M_K_DQ<2>")
	)
	(segment
		(start 54.303168 -101.8286)
		(end 41.196768 -114.935)
		(width 0.14224)
		(layer "In2.Cu")
		(net "M_K_DQ<2>")
	)
	(segment
		(start 40.993568 -128.4986)
		(end 40.587168 -128.4986)
		(width 0.14224)
		(layer "In2.Cu")
		(net "M_K_DQ<2>")
	)
	(segment
		(start 39.571168 -129.76733)
		(end 38.70452 -130.633978)
		(width 0.14224)
		(layer "In2.Cu")
		(net "M_K_DQ<2>")
	)
	(segment
		(start 39.767764 -124.223272)
		(end 39.571168 -124.419868)
		(width 0.14224)
		(layer "In2.Cu")
		(net "M_K_DQ<2>")
	)
	(segment
		(start 67.101466 -89.27084)
		(end 65.893188 -89.27084)
		(width 0.0889)
		(layer "In2.Cu")
		(net "M_K_DQ<2>")
	)
	(segment
		(start 38.70452 -131.266946)
		(end 39.049452 -131.611878)
		(width 0.14224)
		(layer "In2.Cu")
		(net "M_K_DQ<2>")
	)
	(segment
		(start 39.571168 -124.419868)
		(end 39.571168 -129.76733)
		(width 0.14224)
		(layer "In2.Cu")
		(net "M_K_DQ<2>")
	)
	(segment
		(start 40.383968 -124.433076)
		(end 40.174164 -124.223272)
		(width 0.14224)
		(layer "In2.Cu")
		(net "M_K_DQ<2>")
	)
	(segment
		(start 40.174164 -124.223272)
		(end 39.767764 -124.223272)
		(width 0.14224)
		(layer "In2.Cu")
		(net "M_K_DQ<2>")
	)
	(segment
		(start 40.383968 -128.2954)
		(end 40.383968 -124.433076)
		(width 0.14224)
		(layer "In2.Cu")
		(net "M_K_DQ<2>")
	)
	(segment
		(start 54.303168 -100.209096)
		(end 54.303168 -101.8286)
		(width 0.14224)
		(layer "In2.Cu")
		(net "M_K_DQ<2>")
	)
	(segment
		(start 40.587168 -128.4986)
		(end 40.383968 -128.2954)
		(width 0.14224)
		(layer "In2.Cu")
		(net "M_K_DQ<2>")
	)
	(segment
		(start 41.196768 -128.2954)
		(end 40.993568 -128.4986)
		(width 0.14224)
		(layer "In2.Cu")
		(net "M_K_DQ<2>")
	)
	(segment
		(start 38.616382 -132.044948)
		(end 38.616382 -134.632446)
		(width 0.14224)
		(layer "In2.Cu")
		(net "M_K_DQ<2>")
	)
	(segment
		(start 38.616382 -134.632446)
		(end 39.899336 -135.9154)
		(width 0.14224)
		(layer "In2.Cu")
		(net "M_K_DQ<2>")
	)
	(segment
		(start 65.241424 -89.27084)
		(end 54.303168 -100.209096)
		(width 0.14224)
		(layer "In2.Cu")
		(net "M_K_DQ<2>")
	)
	(segment
		(start 75.475846 -96.700086)
		(end 74.904346 -96.700086)
		(width 0.1651)
		(layer "F.Cu")
		(net "M_K_DQ<29>")
	)
	(segment
		(start 59.449462 -133.0706)
		(end 59.449462 -134.340346)
		(width 0.1651)
		(layer "F.Cu")
		(net "M_K_DQ<29>")
	)
	(via
		(at 74.904346 -96.700086)
		(size 0.508)
		(drill 0.254)
		(layers "F.Cu" "B.Cu")
		(net "M_K_DQ<29>")
	)
	(via
		(at 60.223146 -130.330956)
		(size 0.508)
		(drill 0.254)
		(layers "F.Cu" "B.Cu")
		(net "M_K_DQ<29>")
	)
	(via
		(at 59.449462 -134.340346)
		(size 0.508)
		(drill 0.254)
		(layers "F.Cu" "B.Cu")
		(net "M_K_DQ<29>")
	)
	(segment
		(start 60.299346 -130.254756)
		(end 60.223146 -130.330956)
		(width 0.1651)
		(layer "B.Cu")
		(net "M_K_DQ<29>")
	)
	(segment
		(start 60.299346 -128.276096)
		(end 60.299346 -130.254756)
		(width 0.1651)
		(layer "B.Cu")
		(net "M_K_DQ<29>")
	)
	(segment
		(start 60.526168 -122.920506)
		(end 60.681108 -123.075446)
		(width 0.14224)
		(layer "In2.Cu")
		(net "M_K_DQ<29>")
	)
	(segment
		(start 59.72175 -134.340346)
		(end 59.449462 -134.340346)
		(width 0.14224)
		(layer "In2.Cu")
		(net "M_K_DQ<29>")
	)
	(segment
		(start 60.223146 -130.330956)
		(end 60.200794 -130.330956)
		(width 0.14224)
		(layer "In2.Cu")
		(net "M_K_DQ<29>")
	)
	(segment
		(start 60.653168 -129.335784)
		(end 60.653168 -130.124454)
		(width 0.14224)
		(layer "In2.Cu")
		(net "M_K_DQ<29>")
	)
	(segment
		(start 59.610752 -133.696456)
		(end 59.87415 -133.959854)
		(width 0.14224)
		(layer "In2.Cu")
		(net "M_K_DQ<29>")
	)
	(segment
		(start 61.209428 -123.075446)
		(end 61.364368 -123.230386)
		(width 0.14224)
		(layer "In2.Cu")
		(net "M_K_DQ<29>")
	)
	(segment
		(start 59.84875 -132.791454)
		(end 59.84875 -133.146546)
		(width 0.14224)
		(layer "In2.Cu")
		(net "M_K_DQ<29>")
	)
	(segment
		(start 60.200794 -130.330956)
		(end 59.77255 -130.7592)
		(width 0.14224)
		(layer "In2.Cu")
		(net "M_K_DQ<29>")
	)
	(segment
		(start 74.904346 -96.362012)
		(end 74.846434 -96.3041)
		(width 0.0889)
		(layer "In2.Cu")
		(net "M_K_DQ<29>")
	)
	(segment
		(start 69.774816 -99.27209)
		(end 69.74205 -99.27209)
		(width 0.0889)
		(layer "In2.Cu")
		(net "M_K_DQ<29>")
	)
	(segment
		(start 59.84875 -133.146546)
		(end 59.610752 -133.384544)
		(width 0.14224)
		(layer "In2.Cu")
		(net "M_K_DQ<29>")
	)
	(segment
		(start 60.681108 -123.075446)
		(end 61.209428 -123.075446)
		(width 0.14224)
		(layer "In2.Cu")
		(net "M_K_DQ<29>")
	)
	(segment
		(start 66.699892 -101.683566)
		(end 66.400172 -101.683566)
		(width 0.0889)
		(layer "In2.Cu")
		(net "M_K_DQ<29>")
	)
	(segment
		(start 68.061078 -100.322126)
		(end 66.699892 -101.683566)
		(width 0.0889)
		(layer "In2.Cu")
		(net "M_K_DQ<29>")
	)
	(segment
		(start 65.418462 -102.949502)
		(end 63.612268 -104.755696)
		(width 0.14224)
		(layer "In2.Cu")
		(net "M_K_DQ<29>")
	)
	(segment
		(start 60.348368 -125.7808)
		(end 60.348368 -127.405384)
		(width 0.14224)
		(layer "In2.Cu")
		(net "M_K_DQ<29>")
	)
	(segment
		(start 59.87415 -134.187946)
		(end 59.72175 -134.340346)
		(width 0.14224)
		(layer "In2.Cu")
		(net "M_K_DQ<29>")
	)
	(segment
		(start 68.916296 -99.76739)
		(end 68.876672 -99.76739)
		(width 0.0889)
		(layer "In2.Cu")
		(net "M_K_DQ<29>")
	)
	(segment
		(start 60.665614 -111.080296)
		(end 60.665614 -116.7257)
		(width 0.14224)
		(layer "In2.Cu")
		(net "M_K_DQ<29>")
	)
	(segment
		(start 60.681108 -122.262646)
		(end 60.526168 -122.417586)
		(width 0.14224)
		(layer "In2.Cu")
		(net "M_K_DQ<29>")
	)
	(segment
		(start 72.346566 -97.78619)
		(end 72.3138 -97.78619)
		(width 0.0889)
		(layer "In2.Cu")
		(net "M_K_DQ<29>")
	)
	(segment
		(start 60.348368 -127.405384)
		(end 60.653168 -127.710184)
		(width 0.14224)
		(layer "In2.Cu")
		(net "M_K_DQ<29>")
	)
	(segment
		(start 60.653168 -128.218184)
		(end 60.348368 -128.522984)
		(width 0.14224)
		(layer "In2.Cu")
		(net "M_K_DQ<29>")
	)
	(segment
		(start 59.89955 -131.445)
		(end 59.89955 -131.927346)
		(width 0.14224)
		(layer "In2.Cu")
		(net "M_K_DQ<29>")
	)
	(segment
		(start 59.87415 -133.959854)
		(end 59.87415 -134.187946)
		(width 0.14224)
		(layer "In2.Cu")
		(net "M_K_DQ<29>")
	)
	(segment
		(start 60.348368 -129.030984)
		(end 60.653168 -129.335784)
		(width 0.14224)
		(layer "In2.Cu")
		(net "M_K_DQ<29>")
	)
	(segment
		(start 63.612268 -108.133642)
		(end 60.665614 -111.080296)
		(width 0.14224)
		(layer "In2.Cu")
		(net "M_K_DQ<29>")
	)
	(segment
		(start 59.610752 -133.384544)
		(end 59.610752 -133.696456)
		(width 0.14224)
		(layer "In2.Cu")
		(net "M_K_DQ<29>")
	)
	(segment
		(start 59.89955 -131.927346)
		(end 59.610752 -132.216144)
		(width 0.14224)
		(layer "In2.Cu")
		(net "M_K_DQ<29>")
	)
	(segment
		(start 59.77255 -131.318)
		(end 59.89955 -131.445)
		(width 0.14224)
		(layer "In2.Cu")
		(net "M_K_DQ<29>")
	)
	(segment
		(start 60.653168 -130.124454)
		(end 60.446666 -130.330956)
		(width 0.14224)
		(layer "In2.Cu")
		(net "M_K_DQ<29>")
	)
	(segment
		(start 74.904346 -96.700086)
		(end 74.904346 -96.362012)
		(width 0.0889)
		(layer "In2.Cu")
		(net "M_K_DQ<29>")
	)
	(segment
		(start 63.612268 -104.755696)
		(end 63.612268 -108.133642)
		(width 0.14224)
		(layer "In2.Cu")
		(net "M_K_DQ<29>")
	)
	(segment
		(start 61.364368 -117.424454)
		(end 61.364368 -122.107706)
		(width 0.14224)
		(layer "In2.Cu")
		(net "M_K_DQ<29>")
	)
	(segment
		(start 60.526168 -122.417586)
		(end 60.526168 -122.920506)
		(width 0.14224)
		(layer "In2.Cu")
		(net "M_K_DQ<29>")
	)
	(segment
		(start 60.627768 -124.2314)
		(end 60.627768 -125.5014)
		(width 0.14224)
		(layer "In2.Cu")
		(net "M_K_DQ<29>")
	)
	(segment
		(start 66.400172 -101.683566)
		(end 65.418462 -102.665276)
		(width 0.0889)
		(layer "In2.Cu")
		(net "M_K_DQ<29>")
	)
	(segment
		(start 60.348368 -128.522984)
		(end 60.348368 -129.030984)
		(width 0.14224)
		(layer "In2.Cu")
		(net "M_K_DQ<29>")
	)
	(segment
		(start 61.364368 -123.4948)
		(end 60.627768 -124.2314)
		(width 0.14224)
		(layer "In2.Cu")
		(net "M_K_DQ<29>")
	)
	(segment
		(start 68.280026 -100.322126)
		(end 68.061078 -100.322126)
		(width 0.0889)
		(layer "In2.Cu")
		(net "M_K_DQ<29>")
	)
	(segment
		(start 60.653168 -127.710184)
		(end 60.653168 -128.218184)
		(width 0.14224)
		(layer "In2.Cu")
		(net "M_K_DQ<29>")
	)
	(segment
		(start 60.665614 -116.7257)
		(end 61.364368 -117.424454)
		(width 0.14224)
		(layer "In2.Cu")
		(net "M_K_DQ<29>")
	)
	(segment
		(start 73.208896 -97.290636)
		(end 73.17613 -97.290636)
		(width 0.0889)
		(layer "In2.Cu")
		(net "M_K_DQ<29>")
	)
	(segment
		(start 60.446666 -130.330956)
		(end 60.223146 -130.330956)
		(width 0.14224)
		(layer "In2.Cu")
		(net "M_K_DQ<29>")
	)
	(segment
		(start 68.428108 -100.174044)
		(end 68.280026 -100.322126)
		(width 0.0889)
		(layer "In2.Cu")
		(net "M_K_DQ<29>")
	)
	(segment
		(start 59.610752 -132.553456)
		(end 59.84875 -132.791454)
		(width 0.14224)
		(layer "In2.Cu")
		(net "M_K_DQ<29>")
	)
	(segment
		(start 61.209428 -122.262646)
		(end 60.681108 -122.262646)
		(width 0.14224)
		(layer "In2.Cu")
		(net "M_K_DQ<29>")
	)
	(segment
		(start 70.629526 -98.77679)
		(end 70.60057 -98.77679)
		(width 0.0889)
		(layer "In2.Cu")
		(net "M_K_DQ<29>")
	)
	(segment
		(start 68.547996 -99.967288)
		(end 68.547488 -99.967034)
		(width 0.0889)
		(layer "In2.Cu")
		(net "M_K_DQ<29>")
	)
	(segment
		(start 60.627768 -125.5014)
		(end 60.348368 -125.7808)
		(width 0.14224)
		(layer "In2.Cu")
		(net "M_K_DQ<29>")
	)
	(segment
		(start 61.364368 -123.230386)
		(end 61.364368 -123.4948)
		(width 0.14224)
		(layer "In2.Cu")
		(net "M_K_DQ<29>")
	)
	(segment
		(start 61.364368 -122.107706)
		(end 61.209428 -122.262646)
		(width 0.14224)
		(layer "In2.Cu")
		(net "M_K_DQ<29>")
	)
	(segment
		(start 74.063606 -96.79559)
		(end 74.03084 -96.79559)
		(width 0.0889)
		(layer "In2.Cu")
		(net "M_K_DQ<29>")
	)
	(segment
		(start 68.547488 -99.967034)
		(end 68.428108 -100.174044)
		(width 0.0889)
		(layer "In2.Cu")
		(net "M_K_DQ<29>")
	)
	(segment
		(start 59.77255 -130.7592)
		(end 59.77255 -131.318)
		(width 0.14224)
		(layer "In2.Cu")
		(net "M_K_DQ<29>")
	)
	(segment
		(start 59.610752 -132.216144)
		(end 59.610752 -132.553456)
		(width 0.14224)
		(layer "In2.Cu")
		(net "M_K_DQ<29>")
	)
	(segment
		(start 71.491856 -98.281236)
		(end 71.45909 -98.281236)
		(width 0.0889)
		(layer "In2.Cu")
		(net "M_K_DQ<29>")
	)
	(segment
		(start 65.418462 -102.665276)
		(end 65.418462 -102.949502)
		(width 0.0889)
		(layer "In2.Cu")
		(net "M_K_DQ<29>")
	)
	(arc
		(start 72.3138 -97.78619)
		(mid 72.122158 -97.843356)
		(end 71.982076 -97.986088)
		(width 0.0889)
		(layer "In2.Cu")
		(net "M_K_DQ<29>")
	)
	(arc
		(start 74.557636 -96.500188)
		(mid 74.349028 -96.71212)
		(end 74.063606 -96.79559)
		(width 0.0889)
		(layer "In2.Cu")
		(net "M_K_DQ<29>")
	)
	(arc
		(start 73.17613 -97.290636)
		(mid 72.98228 -97.346986)
		(end 72.840596 -97.490788)
		(width 0.0889)
		(layer "In2.Cu")
		(net "M_K_DQ<29>")
	)
	(arc
		(start 70.60057 -98.77679)
		(mid 70.40672 -98.83314)
		(end 70.265036 -98.976942)
		(width 0.0889)
		(layer "In2.Cu")
		(net "M_K_DQ<29>")
	)
	(arc
		(start 72.840596 -97.490788)
		(mid 72.631988 -97.70272)
		(end 72.346566 -97.78619)
		(width 0.0889)
		(layer "In2.Cu")
		(net "M_K_DQ<29>")
	)
	(arc
		(start 73.699116 -96.995488)
		(mid 73.492112 -97.206352)
		(end 73.208896 -97.290636)
		(width 0.0889)
		(layer "In2.Cu")
		(net "M_K_DQ<29>")
	)
	(arc
		(start 69.406516 -99.472242)
		(mid 69.199512 -99.683106)
		(end 68.916296 -99.76739)
		(width 0.0889)
		(layer "In2.Cu")
		(net "M_K_DQ<29>")
	)
	(arc
		(start 68.876672 -99.76739)
		(mid 68.686743 -99.82526)
		(end 68.547996 -99.967288)
		(width 0.0889)
		(layer "In2.Cu")
		(net "M_K_DQ<29>")
	)
	(arc
		(start 69.74205 -99.27209)
		(mid 69.5482 -99.32844)
		(end 69.406516 -99.472242)
		(width 0.0889)
		(layer "In2.Cu")
		(net "M_K_DQ<29>")
	)
	(arc
		(start 74.03084 -96.79559)
		(mid 73.839198 -96.852756)
		(end 73.699116 -96.995488)
		(width 0.0889)
		(layer "In2.Cu")
		(net "M_K_DQ<29>")
	)
	(arc
		(start 71.123556 -98.481388)
		(mid 70.914948 -98.69332)
		(end 70.629526 -98.77679)
		(width 0.0889)
		(layer "In2.Cu")
		(net "M_K_DQ<29>")
	)
	(arc
		(start 71.45909 -98.281236)
		(mid 71.26524 -98.337586)
		(end 71.123556 -98.481388)
		(width 0.0889)
		(layer "In2.Cu")
		(net "M_K_DQ<29>")
	)
	(arc
		(start 74.846434 -96.3041)
		(mid 74.679533 -96.369)
		(end 74.557636 -96.500188)
		(width 0.0889)
		(layer "In2.Cu")
		(net "M_K_DQ<29>")
	)
	(arc
		(start 70.265036 -98.976942)
		(mid 70.058032 -99.187806)
		(end 69.774816 -99.27209)
		(width 0.0889)
		(layer "In2.Cu")
		(net "M_K_DQ<29>")
	)
	(arc
		(start 71.982076 -97.986088)
		(mid 71.775072 -98.196952)
		(end 71.491856 -98.281236)
		(width 0.0889)
		(layer "In2.Cu")
		(net "M_K_DQ<29>")
	)
	(segment
		(start 75.475846 -95.709486)
		(end 74.904346 -95.709486)
		(width 0.1651)
		(layer "F.Cu")
		(net "M_K_DQ<28>")
	)
	(segment
		(start 60.299346 -137.67054)
		(end 60.299346 -136.345168)
		(width 0.1651)
		(layer "F.Cu")
		(net "M_K_DQ<28>")
	)
	(segment
		(start 60.299346 -136.345168)
		(end 60.201302 -135.8138)
		(width 0.1651)
		(layer "F.Cu")
		(net "M_K_DQ<28>")
	)
	(via
		(at 60.201302 -135.8138)
		(size 0.508)
		(drill 0.254)
		(layers "F.Cu" "B.Cu")
		(net "M_K_DQ<28>")
	)
	(via
		(at 59.449462 -131.611878)
		(size 0.508)
		(drill 0.254)
		(layers "F.Cu" "B.Cu")
		(net "M_K_DQ<28>")
	)
	(via
		(at 74.904346 -95.709486)
		(size 0.508)
		(drill 0.254)
		(layers "F.Cu" "B.Cu")
		(net "M_K_DQ<28>")
	)
	(segment
		(start 59.449462 -132.876036)
		(end 59.449462 -131.611878)
		(width 0.1651)
		(layer "B.Cu")
		(net "M_K_DQ<28>")
	)
	(segment
		(start 59.078368 -130.613912)
		(end 59.078368 -131.408424)
		(width 0.14224)
		(layer "In2.Cu")
		(net "M_K_DQ<28>")
	)
	(segment
		(start 68.382896 -99.872038)
		(end 68.275962 -100.057458)
		(width 0.0889)
		(layer "In2.Cu")
		(net "M_K_DQ<28>")
	)
	(segment
		(start 64.9605 -102.491286)
		(end 62.977268 -104.474518)
		(width 0.14224)
		(layer "In2.Cu")
		(net "M_K_DQ<28>")
	)
	(segment
		(start 68.275962 -100.057458)
		(end 68.201286 -100.132134)
		(width 0.0889)
		(layer "In2.Cu")
		(net "M_K_DQ<28>")
	)
	(segment
		(start 69.764402 -99.08159)
		(end 69.731636 -99.08159)
		(width 0.0889)
		(layer "In2.Cu")
		(net "M_K_DQ<28>")
	)
	(segment
		(start 59.916568 -129.775712)
		(end 59.078368 -130.613912)
		(width 0.14224)
		(layer "In2.Cu")
		(net "M_K_DQ<28>")
	)
	(segment
		(start 59.281822 -131.611878)
		(end 59.449462 -131.611878)
		(width 0.14224)
		(layer "In2.Cu")
		(net "M_K_DQ<28>")
	)
	(segment
		(start 60.157614 -110.690152)
		(end 60.157614 -117.030246)
		(width 0.14224)
		(layer "In2.Cu")
		(net "M_K_DQ<28>")
	)
	(segment
		(start 60.602368 -117.475)
		(end 60.602368 -121.3612)
		(width 0.14224)
		(layer "In2.Cu")
		(net "M_K_DQ<28>")
	)
	(segment
		(start 73.202292 -97.100136)
		(end 73.169526 -97.100136)
		(width 0.0889)
		(layer "In2.Cu")
		(net "M_K_DQ<28>")
	)
	(segment
		(start 71.485252 -98.090736)
		(end 71.452486 -98.090736)
		(width 0.0889)
		(layer "In2.Cu")
		(net "M_K_DQ<28>")
	)
	(segment
		(start 59.016392 -134.57809)
		(end 59.17438 -134.736078)
		(width 0.14224)
		(layer "In2.Cu")
		(net "M_K_DQ<28>")
	)
	(segment
		(start 68.201286 -100.132134)
		(end 67.982338 -100.132134)
		(width 0.0889)
		(layer "In2.Cu")
		(net "M_K_DQ<28>")
	)
	(segment
		(start 67.982338 -100.132134)
		(end 66.621152 -101.493574)
		(width 0.0889)
		(layer "In2.Cu")
		(net "M_K_DQ<28>")
	)
	(segment
		(start 59.732164 -124.365004)
		(end 59.732164 -127.52705)
		(width 0.14224)
		(layer "In2.Cu")
		(net "M_K_DQ<28>")
	)
	(segment
		(start 74.904346 -96.04756)
		(end 74.839068 -96.112838)
		(width 0.0889)
		(layer "In2.Cu")
		(net "M_K_DQ<28>")
	)
	(segment
		(start 65.32372 -102.491286)
		(end 64.9605 -102.491286)
		(width 0.0889)
		(layer "In2.Cu")
		(net "M_K_DQ<28>")
	)
	(segment
		(start 59.016392 -132.044948)
		(end 59.016392 -134.57809)
		(width 0.14224)
		(layer "In2.Cu")
		(net "M_K_DQ<28>")
	)
	(segment
		(start 62.977268 -107.870498)
		(end 60.157614 -110.690152)
		(width 0.14224)
		(layer "In2.Cu")
		(net "M_K_DQ<28>")
	)
	(segment
		(start 59.941968 -124.1552)
		(end 59.732164 -124.365004)
		(width 0.14224)
		(layer "In2.Cu")
		(net "M_K_DQ<28>")
	)
	(segment
		(start 59.17438 -134.736078)
		(end 59.17438 -135.03783)
		(width 0.14224)
		(layer "In2.Cu")
		(net "M_K_DQ<28>")
	)
	(segment
		(start 74.057002 -96.60509)
		(end 74.024236 -96.60509)
		(width 0.0889)
		(layer "In2.Cu")
		(net "M_K_DQ<28>")
	)
	(segment
		(start 70.622922 -98.58629)
		(end 70.590156 -98.58629)
		(width 0.0889)
		(layer "In2.Cu")
		(net "M_K_DQ<28>")
	)
	(segment
		(start 68.91274 -99.576636)
		(end 68.876926 -99.576636)
		(width 0.0889)
		(layer "In2.Cu")
		(net "M_K_DQ<28>")
	)
	(segment
		(start 59.078368 -131.408424)
		(end 59.281822 -131.611878)
		(width 0.14224)
		(layer "In2.Cu")
		(net "M_K_DQ<28>")
	)
	(segment
		(start 59.916568 -127.711454)
		(end 59.916568 -129.775712)
		(width 0.14224)
		(layer "In2.Cu")
		(net "M_K_DQ<28>")
	)
	(segment
		(start 59.449462 -131.611878)
		(end 59.016392 -132.044948)
		(width 0.14224)
		(layer "In2.Cu")
		(net "M_K_DQ<28>")
	)
	(segment
		(start 72.339962 -97.59569)
		(end 72.307196 -97.59569)
		(width 0.0889)
		(layer "In2.Cu")
		(net "M_K_DQ<28>")
	)
	(segment
		(start 62.977268 -104.474518)
		(end 62.977268 -107.870498)
		(width 0.14224)
		(layer "In2.Cu")
		(net "M_K_DQ<28>")
	)
	(segment
		(start 59.17438 -135.03783)
		(end 59.95035 -135.8138)
		(width 0.14224)
		(layer "In2.Cu")
		(net "M_K_DQ<28>")
	)
	(segment
		(start 60.157614 -117.030246)
		(end 60.602368 -117.475)
		(width 0.14224)
		(layer "In2.Cu")
		(net "M_K_DQ<28>")
	)
	(segment
		(start 60.602368 -121.3612)
		(end 59.941968 -122.0216)
		(width 0.14224)
		(layer "In2.Cu")
		(net "M_K_DQ<28>")
	)
	(segment
		(start 59.732164 -127.52705)
		(end 59.916568 -127.711454)
		(width 0.14224)
		(layer "In2.Cu")
		(net "M_K_DQ<28>")
	)
	(segment
		(start 66.321432 -101.493574)
		(end 65.32372 -102.491286)
		(width 0.0889)
		(layer "In2.Cu")
		(net "M_K_DQ<28>")
	)
	(segment
		(start 59.95035 -135.8138)
		(end 60.201302 -135.8138)
		(width 0.14224)
		(layer "In2.Cu")
		(net "M_K_DQ<28>")
	)
	(segment
		(start 66.621152 -101.493574)
		(end 66.321432 -101.493574)
		(width 0.0889)
		(layer "In2.Cu")
		(net "M_K_DQ<28>")
	)
	(segment
		(start 59.941968 -122.0216)
		(end 59.941968 -124.1552)
		(width 0.14224)
		(layer "In2.Cu")
		(net "M_K_DQ<28>")
	)
	(segment
		(start 74.904346 -95.709486)
		(end 74.904346 -96.04756)
		(width 0.0889)
		(layer "In2.Cu")
		(net "M_K_DQ<28>")
	)
	(arc
		(start 69.241416 -99.376738)
		(mid 69.102672 -99.518771)
		(end 68.91274 -99.576636)
		(width 0.0889)
		(layer "In2.Cu")
		(net "M_K_DQ<28>")
	)
	(arc
		(start 73.169526 -97.100136)
		(mid 72.884102 -97.183603)
		(end 72.675496 -97.395538)
		(width 0.0889)
		(layer "In2.Cu")
		(net "M_K_DQ<28>")
	)
	(arc
		(start 72.307196 -97.59569)
		(mid 72.023979 -97.679971)
		(end 71.816976 -97.890838)
		(width 0.0889)
		(layer "In2.Cu")
		(net "M_K_DQ<28>")
	)
	(arc
		(start 73.534016 -96.900238)
		(mid 73.393937 -97.042974)
		(end 73.202292 -97.100136)
		(width 0.0889)
		(layer "In2.Cu")
		(net "M_K_DQ<28>")
	)
	(arc
		(start 74.392536 -96.404938)
		(mid 74.250853 -96.548742)
		(end 74.057002 -96.60509)
		(width 0.0889)
		(layer "In2.Cu")
		(net "M_K_DQ<28>")
	)
	(arc
		(start 69.731636 -99.08159)
		(mid 69.448419 -99.165871)
		(end 69.241416 -99.376738)
		(width 0.0889)
		(layer "In2.Cu")
		(net "M_K_DQ<28>")
	)
	(arc
		(start 72.675496 -97.395538)
		(mid 72.533813 -97.539342)
		(end 72.339962 -97.59569)
		(width 0.0889)
		(layer "In2.Cu")
		(net "M_K_DQ<28>")
	)
	(arc
		(start 68.876926 -99.576636)
		(mid 68.591502 -99.660103)
		(end 68.382896 -99.872038)
		(width 0.0889)
		(layer "In2.Cu")
		(net "M_K_DQ<28>")
	)
	(arc
		(start 70.958456 -98.386138)
		(mid 70.816773 -98.529942)
		(end 70.622922 -98.58629)
		(width 0.0889)
		(layer "In2.Cu")
		(net "M_K_DQ<28>")
	)
	(arc
		(start 71.816976 -97.890838)
		(mid 71.676897 -98.033574)
		(end 71.485252 -98.090736)
		(width 0.0889)
		(layer "In2.Cu")
		(net "M_K_DQ<28>")
	)
	(arc
		(start 70.099936 -98.881438)
		(mid 69.958253 -99.025242)
		(end 69.764402 -99.08159)
		(width 0.0889)
		(layer "In2.Cu")
		(net "M_K_DQ<28>")
	)
	(arc
		(start 70.590156 -98.58629)
		(mid 70.306939 -98.670571)
		(end 70.099936 -98.881438)
		(width 0.0889)
		(layer "In2.Cu")
		(net "M_K_DQ<28>")
	)
	(arc
		(start 74.024236 -96.60509)
		(mid 73.741019 -96.689371)
		(end 73.534016 -96.900238)
		(width 0.0889)
		(layer "In2.Cu")
		(net "M_K_DQ<28>")
	)
	(arc
		(start 74.839068 -96.112838)
		(mid 74.580931 -96.205592)
		(end 74.392536 -96.404938)
		(width 0.0889)
		(layer "In2.Cu")
		(net "M_K_DQ<28>")
	)
	(arc
		(start 71.452486 -98.090736)
		(mid 71.167062 -98.174203)
		(end 70.958456 -98.386138)
		(width 0.0889)
		(layer "In2.Cu")
		(net "M_K_DQ<28>")
	)
	(segment
		(start 67.099434 -133.0706)
		(end 67.099434 -134.340346)
		(width 0.1651)
		(layer "F.Cu")
		(net "M_K_DQ<27>")
	)
	(segment
		(start 78.909672 -96.700086)
		(end 78.338172 -96.700086)
		(width 0.1651)
		(layer "F.Cu")
		(net "M_K_DQ<27>")
	)
	(via
		(at 67.949318 -130.330956)
		(size 0.508)
		(drill 0.254)
		(layers "F.Cu" "B.Cu")
		(net "M_K_DQ<27>")
	)
	(via
		(at 67.099434 -134.340346)
		(size 0.508)
		(drill 0.254)
		(layers "F.Cu" "B.Cu")
		(net "M_K_DQ<27>")
	)
	(via
		(at 78.338172 -96.700086)
		(size 0.508)
		(drill 0.254)
		(layers "F.Cu" "B.Cu")
		(net "M_K_DQ<27>")
	)
	(segment
		(start 67.949318 -128.276096)
		(end 67.949318 -130.330956)
		(width 0.1651)
		(layer "B.Cu")
		(net "M_K_DQ<27>")
	)
	(segment
		(start 67.949572 -128.276096)
		(end 67.949318 -128.276096)
		(width 0.1651)
		(layer "B.Cu")
		(net "M_K_DQ<27>")
	)
	(segment
		(start 68.831968 -116.1542)
		(end 68.405502 -116.1542)
		(width 0.14224)
		(layer "In2.Cu")
		(net "M_K_DQ<27>")
	)
	(segment
		(start 67.260724 -133.276848)
		(end 67.260724 -133.550152)
		(width 0.14224)
		(layer "In2.Cu")
		(net "M_K_DQ<27>")
	)
	(segment
		(start 67.260724 -132.457952)
		(end 67.517772 -132.715)
		(width 0.14224)
		(layer "In2.Cu")
		(net "M_K_DQ<27>")
	)
	(segment
		(start 72.640444 -102.877874)
		(end 72.640444 -103.558594)
		(width 0.0889)
		(layer "In2.Cu")
		(net "M_K_DQ<27>")
	)
	(segment
		(start 69.644768 -116.6622)
		(end 69.466968 -116.84)
		(width 0.14224)
		(layer "In2.Cu")
		(net "M_K_DQ<27>")
	)
	(segment
		(start 70.279768 -110.9218)
		(end 70.279768 -111.28756)
		(width 0.14224)
		(layer "In2.Cu")
		(net "M_K_DQ<27>")
	)
	(segment
		(start 70.279768 -113.52276)
		(end 70.279768 -113.88852)
		(width 0.14224)
		(layer "In2.Cu")
		(net "M_K_DQ<27>")
	)
	(segment
		(start 69.787008 -113.38052)
		(end 70.137528 -113.38052)
		(width 0.14224)
		(layer "In2.Cu")
		(net "M_K_DQ<27>")
	)
	(segment
		(start 70.279768 -111.28756)
		(end 70.137528 -111.4298)
		(width 0.14224)
		(layer "In2.Cu")
		(net "M_K_DQ<27>")
	)
	(segment
		(start 68.278502 -122.585734)
		(end 68.425568 -122.7328)
		(width 0.14224)
		(layer "In2.Cu")
		(net "M_K_DQ<27>")
	)
	(segment
		(start 69.644768 -113.23828)
		(end 69.787008 -113.38052)
		(width 0.14224)
		(layer "In2.Cu")
		(net "M_K_DQ<27>")
	)
	(segment
		(start 68.958968 -116.2812)
		(end 68.831968 -116.1542)
		(width 0.14224)
		(layer "In2.Cu")
		(net "M_K_DQ<27>")
	)
	(segment
		(start 67.549522 -134.162546)
		(end 67.371722 -134.340346)
		(width 0.14224)
		(layer "In2.Cu")
		(net "M_K_DQ<27>")
	)
	(segment
		(start 67.543172 -131.9022)
		(end 67.260724 -132.184648)
		(width 0.14224)
		(layer "In2.Cu")
		(net "M_K_DQ<27>")
	)
	(segment
		(start 70.137528 -114.03076)
		(end 69.787008 -114.03076)
		(width 0.14224)
		(layer "In2.Cu")
		(net "M_K_DQ<27>")
	)
	(segment
		(start 68.278502 -126.429008)
		(end 68.278502 -130.01498)
		(width 0.14224)
		(layer "In2.Cu")
		(net "M_K_DQ<27>")
	)
	(segment
		(start 69.466968 -116.84)
		(end 69.111368 -116.84)
		(width 0.14224)
		(layer "In2.Cu")
		(net "M_K_DQ<27>")
	)
	(segment
		(start 67.926966 -130.330956)
		(end 67.498722 -130.7592)
		(width 0.14224)
		(layer "In2.Cu")
		(net "M_K_DQ<27>")
	)
	(segment
		(start 69.644768 -111.9378)
		(end 69.787008 -112.08004)
		(width 0.14224)
		(layer "In2.Cu")
		(net "M_K_DQ<27>")
	)
	(segment
		(start 70.137528 -112.73028)
		(end 69.787008 -112.73028)
		(width 0.14224)
		(layer "In2.Cu")
		(net "M_K_DQ<27>")
	)
	(segment
		(start 71.333614 -105.19029)
		(end 69.644768 -106.879136)
		(width 0.14224)
		(layer "In2.Cu")
		(net "M_K_DQ<27>")
	)
	(segment
		(start 67.498722 -130.7592)
		(end 67.498722 -131.188968)
		(width 0.14224)
		(layer "In2.Cu")
		(net "M_K_DQ<27>")
	)
	(segment
		(start 67.498722 -131.188968)
		(end 67.543172 -131.233418)
		(width 0.14224)
		(layer "In2.Cu")
		(net "M_K_DQ<27>")
	)
	(segment
		(start 69.111368 -116.84)
		(end 68.958968 -116.6876)
		(width 0.14224)
		(layer "In2.Cu")
		(net "M_K_DQ<27>")
	)
	(segment
		(start 67.949318 -130.344164)
		(end 67.949318 -130.330956)
		(width 0.14224)
		(layer "In2.Cu")
		(net "M_K_DQ<27>")
	)
	(segment
		(start 69.787008 -110.77956)
		(end 70.137528 -110.77956)
		(width 0.14224)
		(layer "In2.Cu")
		(net "M_K_DQ<27>")
	)
	(segment
		(start 68.405502 -116.1542)
		(end 68.278502 -116.2812)
		(width 0.14224)
		(layer "In2.Cu")
		(net "M_K_DQ<27>")
	)
	(segment
		(start 68.425568 -126.281942)
		(end 68.278502 -126.429008)
		(width 0.14224)
		(layer "In2.Cu")
		(net "M_K_DQ<27>")
	)
	(segment
		(start 75.784456 -100.757736)
		(end 75.744832 -100.757736)
		(width 0.0889)
		(layer "In2.Cu")
		(net "M_K_DQ<27>")
	)
	(segment
		(start 69.644768 -112.87252)
		(end 69.644768 -113.23828)
		(width 0.14224)
		(layer "In2.Cu")
		(net "M_K_DQ<27>")
	)
	(segment
		(start 78.338172 -96.700086)
		(end 78.338172 -96.362012)
		(width 0.0889)
		(layer "In2.Cu")
		(net "M_K_DQ<27>")
	)
	(segment
		(start 69.787008 -112.73028)
		(end 69.644768 -112.87252)
		(width 0.14224)
		(layer "In2.Cu")
		(net "M_K_DQ<27>")
	)
	(segment
		(start 70.137528 -111.4298)
		(end 69.787008 -111.4298)
		(width 0.14224)
		(layer "In2.Cu")
		(net "M_K_DQ<27>")
	)
	(segment
		(start 70.279768 -112.58804)
		(end 70.137528 -112.73028)
		(width 0.14224)
		(layer "In2.Cu")
		(net "M_K_DQ<27>")
	)
	(segment
		(start 74.922126 -101.253036)
		(end 74.886312 -101.253036)
		(width 0.0889)
		(layer "In2.Cu")
		(net "M_K_DQ<27>")
	)
	(segment
		(start 73.085452 -102.432866)
		(end 72.640444 -102.877874)
		(width 0.0889)
		(layer "In2.Cu")
		(net "M_K_DQ<27>")
	)
	(segment
		(start 76.63434 -100.262436)
		(end 76.61021 -100.262436)
		(width 0.0889)
		(layer "In2.Cu")
		(net "M_K_DQ<27>")
	)
	(segment
		(start 67.549522 -133.83895)
		(end 67.549522 -134.162546)
		(width 0.14224)
		(layer "In2.Cu")
		(net "M_K_DQ<27>")
	)
	(segment
		(start 70.137528 -110.77956)
		(end 70.279768 -110.9218)
		(width 0.14224)
		(layer "In2.Cu")
		(net "M_K_DQ<27>")
	)
	(segment
		(start 68.278502 -130.01498)
		(end 67.949318 -130.344164)
		(width 0.14224)
		(layer "In2.Cu")
		(net "M_K_DQ<27>")
	)
	(segment
		(start 69.787008 -114.03076)
		(end 69.644768 -114.173)
		(width 0.14224)
		(layer "In2.Cu")
		(net "M_K_DQ<27>")
	)
	(segment
		(start 69.644768 -106.879136)
		(end 69.644768 -110.63732)
		(width 0.14224)
		(layer "In2.Cu")
		(net "M_K_DQ<27>")
	)
	(segment
		(start 69.787008 -111.4298)
		(end 69.644768 -111.57204)
		(width 0.14224)
		(layer "In2.Cu")
		(net "M_K_DQ<27>")
	)
	(segment
		(start 67.371722 -134.340346)
		(end 67.099434 -134.340346)
		(width 0.14224)
		(layer "In2.Cu")
		(net "M_K_DQ<27>")
	)
	(segment
		(start 78.000606 -98.466148)
		(end 77.991716 -98.481388)
		(width 0.0889)
		(layer "In2.Cu")
		(net "M_K_DQ<27>")
	)
	(segment
		(start 67.260724 -133.550152)
		(end 67.549522 -133.83895)
		(width 0.14224)
		(layer "In2.Cu")
		(net "M_K_DQ<27>")
	)
	(segment
		(start 67.517772 -133.0198)
		(end 67.260724 -133.276848)
		(width 0.14224)
		(layer "In2.Cu")
		(net "M_K_DQ<27>")
	)
	(segment
		(start 74.466196 -101.611176)
		(end 73.644506 -102.432866)
		(width 0.0889)
		(layer "In2.Cu")
		(net "M_K_DQ<27>")
	)
	(segment
		(start 70.279768 -112.22228)
		(end 70.279768 -112.58804)
		(width 0.14224)
		(layer "In2.Cu")
		(net "M_K_DQ<27>")
	)
	(segment
		(start 69.644768 -111.57204)
		(end 69.644768 -111.9378)
		(width 0.14224)
		(layer "In2.Cu")
		(net "M_K_DQ<27>")
	)
	(segment
		(start 67.949318 -130.330956)
		(end 67.926966 -130.330956)
		(width 0.14224)
		(layer "In2.Cu")
		(net "M_K_DQ<27>")
	)
	(segment
		(start 71.333614 -104.865424)
		(end 71.333614 -105.19029)
		(width 0.0889)
		(layer "In2.Cu")
		(net "M_K_DQ<27>")
	)
	(segment
		(start 70.137528 -113.38052)
		(end 70.279768 -113.52276)
		(width 0.14224)
		(layer "In2.Cu")
		(net "M_K_DQ<27>")
	)
	(segment
		(start 68.278502 -116.2812)
		(end 68.278502 -122.585734)
		(width 0.14224)
		(layer "In2.Cu")
		(net "M_K_DQ<27>")
	)
	(segment
		(start 68.425568 -122.7328)
		(end 68.425568 -126.281942)
		(width 0.14224)
		(layer "In2.Cu")
		(net "M_K_DQ<27>")
	)
	(segment
		(start 70.279768 -113.88852)
		(end 70.137528 -114.03076)
		(width 0.14224)
		(layer "In2.Cu")
		(net "M_K_DQ<27>")
	)
	(segment
		(start 69.787008 -112.08004)
		(end 70.137528 -112.08004)
		(width 0.14224)
		(layer "In2.Cu")
		(net "M_K_DQ<27>")
	)
	(segment
		(start 74.557636 -101.452934)
		(end 74.466196 -101.611176)
		(width 0.0889)
		(layer "In2.Cu")
		(net "M_K_DQ<27>")
	)
	(segment
		(start 70.137528 -112.08004)
		(end 70.279768 -112.22228)
		(width 0.14224)
		(layer "In2.Cu")
		(net "M_K_DQ<27>")
	)
	(segment
		(start 68.958968 -116.6876)
		(end 68.958968 -116.2812)
		(width 0.14224)
		(layer "In2.Cu")
		(net "M_K_DQ<27>")
	)
	(segment
		(start 72.640444 -103.558594)
		(end 71.333614 -104.865424)
		(width 0.0889)
		(layer "In2.Cu")
		(net "M_K_DQ<27>")
	)
	(segment
		(start 69.644768 -114.173)
		(end 69.644768 -116.6622)
		(width 0.14224)
		(layer "In2.Cu")
		(net "M_K_DQ<27>")
	)
	(segment
		(start 78.000606 -97.475548)
		(end 77.991716 -97.490788)
		(width 0.0889)
		(layer "In2.Cu")
		(net "M_K_DQ<27>")
	)
	(segment
		(start 73.644506 -102.432866)
		(end 73.085452 -102.432866)
		(width 0.0889)
		(layer "In2.Cu")
		(net "M_K_DQ<27>")
	)
	(segment
		(start 69.644768 -110.63732)
		(end 69.787008 -110.77956)
		(width 0.14224)
		(layer "In2.Cu")
		(net "M_K_DQ<27>")
	)
	(segment
		(start 77.497686 -99.76739)
		(end 77.479906 -99.76739)
		(width 0.0889)
		(layer "In2.Cu")
		(net "M_K_DQ<27>")
	)
	(segment
		(start 67.517772 -132.715)
		(end 67.517772 -133.0198)
		(width 0.14224)
		(layer "In2.Cu")
		(net "M_K_DQ<27>")
	)
	(segment
		(start 78.338172 -96.362012)
		(end 78.280514 -96.304354)
		(width 0.0889)
		(layer "In2.Cu")
		(net "M_K_DQ<27>")
	)
	(segment
		(start 67.260724 -132.184648)
		(end 67.260724 -132.457952)
		(width 0.14224)
		(layer "In2.Cu")
		(net "M_K_DQ<27>")
	)
	(segment
		(start 67.543172 -131.233418)
		(end 67.543172 -131.9022)
		(width 0.14224)
		(layer "In2.Cu")
		(net "M_K_DQ<27>")
	)
	(arc
		(start 77.991716 -97.890584)
		(mid 78.070905 -98.177199)
		(end 78.000606 -98.466148)
		(width 0.0889)
		(layer "In2.Cu")
		(net "M_K_DQ<27>")
	)
	(arc
		(start 77.46492 -99.767136)
		(mid 77.273278 -99.824302)
		(end 77.133196 -99.967034)
		(width 0.0889)
		(layer "In2.Cu")
		(net "M_K_DQ<27>")
	)
	(arc
		(start 75.744832 -100.757736)
		(mid 75.554903 -100.815606)
		(end 75.416156 -100.957634)
		(width 0.0889)
		(layer "In2.Cu")
		(net "M_K_DQ<27>")
	)
	(arc
		(start 77.991716 -98.481388)
		(mid 77.938183 -98.681286)
		(end 77.991716 -98.881184)
		(width 0.0889)
		(layer "In2.Cu")
		(net "M_K_DQ<27>")
	)
	(arc
		(start 75.416156 -100.957634)
		(mid 75.207548 -101.169566)
		(end 74.922126 -101.253036)
		(width 0.0889)
		(layer "In2.Cu")
		(net "M_K_DQ<27>")
	)
	(arc
		(start 76.274676 -100.462588)
		(mid 76.067672 -100.673452)
		(end 75.784456 -100.757736)
		(width 0.0889)
		(layer "In2.Cu")
		(net "M_K_DQ<27>")
	)
	(arc
		(start 77.991716 -98.881184)
		(mid 77.996044 -99.46436)
		(end 77.497686 -99.76739)
		(width 0.0889)
		(layer "In2.Cu")
		(net "M_K_DQ<27>")
	)
	(arc
		(start 77.991716 -96.899984)
		(mid 78.070905 -97.186599)
		(end 78.000606 -97.475548)
		(width 0.0889)
		(layer "In2.Cu")
		(net "M_K_DQ<27>")
	)
	(arc
		(start 77.133196 -99.967034)
		(mid 76.922483 -100.180113)
		(end 76.63434 -100.262436)
		(width 0.0889)
		(layer "In2.Cu")
		(net "M_K_DQ<27>")
	)
	(arc
		(start 74.886312 -101.253036)
		(mid 74.696383 -101.310906)
		(end 74.557636 -101.452934)
		(width 0.0889)
		(layer "In2.Cu")
		(net "M_K_DQ<27>")
	)
	(arc
		(start 77.991716 -97.490788)
		(mid 77.938183 -97.690686)
		(end 77.991716 -97.890584)
		(width 0.0889)
		(layer "In2.Cu")
		(net "M_K_DQ<27>")
	)
	(arc
		(start 76.61021 -100.262436)
		(mid 76.41636 -100.318786)
		(end 76.274676 -100.462588)
		(width 0.0889)
		(layer "In2.Cu")
		(net "M_K_DQ<27>")
	)
	(arc
		(start 78.280514 -96.304354)
		(mid 77.978317 -96.525636)
		(end 77.991716 -96.899984)
		(width 0.0889)
		(layer "In2.Cu")
		(net "M_K_DQ<27>")
	)
	(arc
		(start 77.479906 -99.76739)
		(mid 77.472412 -99.767326)
		(end 77.46492 -99.767136)
		(width 0.0889)
		(layer "In2.Cu")
		(net "M_K_DQ<27>")
	)
	(segment
		(start 78.909672 -95.709486)
		(end 78.338172 -95.709486)
		(width 0.1651)
		(layer "F.Cu")
		(net "M_K_DQ<26>")
	)
	(segment
		(start 68.08089 -136.32434)
		(end 67.949318 -136.192768)
		(width 0.1651)
		(layer "F.Cu")
		(net "M_K_DQ<26>")
	)
	(segment
		(start 67.949318 -137.67054)
		(end 67.949318 -136.679432)
		(width 0.1651)
		(layer "F.Cu")
		(net "M_K_DQ<26>")
	)
	(segment
		(start 67.949318 -136.192768)
		(end 67.949318 -135.9154)
		(width 0.1651)
		(layer "F.Cu")
		(net "M_K_DQ<26>")
	)
	(segment
		(start 68.08089 -136.54786)
		(end 68.08089 -136.32434)
		(width 0.1651)
		(layer "F.Cu")
		(net "M_K_DQ<26>")
	)
	(segment
		(start 67.949318 -136.679432)
		(end 68.08089 -136.54786)
		(width 0.1651)
		(layer "F.Cu")
		(net "M_K_DQ<26>")
	)
	(segment
		(start 67.949572 -137.67054)
		(end 67.949318 -137.67054)
		(width 0.1651)
		(layer "F.Cu")
		(net "M_K_DQ<26>")
	)
	(via
		(at 78.338172 -95.709486)
		(size 0.508)
		(drill 0.254)
		(layers "F.Cu" "B.Cu")
		(net "M_K_DQ<26>")
	)
	(via
		(at 67.099434 -131.611878)
		(size 0.508)
		(drill 0.254)
		(layers "F.Cu" "B.Cu")
		(net "M_K_DQ<26>")
	)
	(via
		(at 67.949318 -135.9154)
		(size 0.508)
		(drill 0.254)
		(layers "F.Cu" "B.Cu")
		(net "M_K_DQ<26>")
	)
	(segment
		(start 67.099434 -132.876036)
		(end 67.099434 -131.611878)
		(width 0.1651)
		(layer "B.Cu")
		(net "M_K_DQ<26>")
	)
	(segment
		(start 67.099434 -131.611878)
		(end 66.666364 -132.044948)
		(width 0.14224)
		(layer "In2.Cu")
		(net "M_K_DQ<26>")
	)
	(segment
		(start 74.392536 -101.35743)
		(end 74.313542 -101.494082)
		(width 0.0889)
		(layer "In2.Cu")
		(net "M_K_DQ<26>")
	)
	(segment
		(start 68.831968 -115.6462)
		(end 68.527168 -115.6462)
		(width 0.14224)
		(layer "In2.Cu")
		(net "M_K_DQ<26>")
	)
	(segment
		(start 66.754502 -131.266946)
		(end 67.099434 -131.611878)
		(width 0.14224)
		(layer "In2.Cu")
		(net "M_K_DQ<26>")
	)
	(segment
		(start 77.492098 -99.576636)
		(end 77.458316 -99.576636)
		(width 0.0889)
		(layer "In2.Cu")
		(net "M_K_DQ<26>")
	)
	(segment
		(start 73.565258 -102.242366)
		(end 73.00722 -102.242366)
		(width 0.0889)
		(layer "In2.Cu")
		(net "M_K_DQ<26>")
	)
	(segment
		(start 67.638168 -123.952)
		(end 67.536568 -124.0536)
		(width 0.14224)
		(layer "In2.Cu")
		(net "M_K_DQ<26>")
	)
	(segment
		(start 67.536568 -124.0536)
		(end 67.536568 -125.729746)
		(width 0.14224)
		(layer "In2.Cu")
		(net "M_K_DQ<26>")
	)
	(segment
		(start 67.638168 -114.681)
		(end 67.638168 -123.952)
		(width 0.14224)
		(layer "In2.Cu")
		(net "M_K_DQ<26>")
	)
	(segment
		(start 67.618102 -125.81128)
		(end 67.618102 -129.770378)
		(width 0.14224)
		(layer "In2.Cu")
		(net "M_K_DQ<26>")
	)
	(segment
		(start 68.984368 -106.636058)
		(end 68.984368 -115.4938)
		(width 0.14224)
		(layer "In2.Cu")
		(net "M_K_DQ<26>")
	)
	(segment
		(start 68.196968 -114.5286)
		(end 67.790568 -114.5286)
		(width 0.14224)
		(layer "In2.Cu")
		(net "M_K_DQ<26>")
	)
	(segment
		(start 73.00722 -102.242366)
		(end 72.450452 -102.799134)
		(width 0.0889)
		(layer "In2.Cu")
		(net "M_K_DQ<26>")
	)
	(segment
		(start 66.666364 -134.632446)
		(end 67.949318 -135.9154)
		(width 0.14224)
		(layer "In2.Cu")
		(net "M_K_DQ<26>")
	)
	(segment
		(start 72.450452 -102.799134)
		(end 72.450452 -103.479854)
		(width 0.0889)
		(layer "In2.Cu")
		(net "M_K_DQ<26>")
	)
	(segment
		(start 75.7809 -100.566982)
		(end 75.745086 -100.566982)
		(width 0.0889)
		(layer "In2.Cu")
		(net "M_K_DQ<26>")
	)
	(segment
		(start 77.826362 -97.395538)
		(end 77.817472 -97.410778)
		(width 0.0889)
		(layer "In2.Cu")
		(net "M_K_DQ<26>")
	)
	(segment
		(start 74.92238 -101.062282)
		(end 74.882756 -101.062282)
		(width 0.0889)
		(layer "In2.Cu")
		(net "M_K_DQ<26>")
	)
	(segment
		(start 74.313542 -101.494082)
		(end 73.565258 -102.242366)
		(width 0.0889)
		(layer "In2.Cu")
		(net "M_K_DQ<26>")
	)
	(segment
		(start 68.374768 -114.7064)
		(end 68.196968 -114.5286)
		(width 0.14224)
		(layer "In2.Cu")
		(net "M_K_DQ<26>")
	)
	(segment
		(start 67.536568 -125.729746)
		(end 67.618102 -125.81128)
		(width 0.14224)
		(layer "In2.Cu")
		(net "M_K_DQ<26>")
	)
	(segment
		(start 67.618102 -129.770378)
		(end 66.754502 -130.633978)
		(width 0.14224)
		(layer "In2.Cu")
		(net "M_K_DQ<26>")
	)
	(segment
		(start 72.450452 -103.479854)
		(end 71.198232 -104.732074)
		(width 0.0889)
		(layer "In2.Cu")
		(net "M_K_DQ<26>")
	)
	(segment
		(start 66.666364 -132.044948)
		(end 66.666364 -134.632446)
		(width 0.14224)
		(layer "In2.Cu")
		(net "M_K_DQ<26>")
	)
	(segment
		(start 70.888352 -104.732074)
		(end 70.882002 -104.738424)
		(width 0.0889)
		(layer "In2.Cu")
		(net "M_K_DQ<26>")
	)
	(segment
		(start 71.198232 -104.732074)
		(end 70.888352 -104.732074)
		(width 0.0889)
		(layer "In2.Cu")
		(net "M_K_DQ<26>")
	)
	(segment
		(start 70.882002 -104.738424)
		(end 68.984368 -106.636058)
		(width 0.14224)
		(layer "In2.Cu")
		(net "M_K_DQ<26>")
	)
	(segment
		(start 68.374768 -115.4938)
		(end 68.374768 -114.7064)
		(width 0.14224)
		(layer "In2.Cu")
		(net "M_K_DQ<26>")
	)
	(segment
		(start 67.790568 -114.5286)
		(end 67.638168 -114.681)
		(width 0.14224)
		(layer "In2.Cu")
		(net "M_K_DQ<26>")
	)
	(segment
		(start 68.984368 -115.4938)
		(end 68.831968 -115.6462)
		(width 0.14224)
		(layer "In2.Cu")
		(net "M_K_DQ<26>")
	)
	(segment
		(start 66.754502 -130.633978)
		(end 66.754502 -131.266946)
		(width 0.14224)
		(layer "In2.Cu")
		(net "M_K_DQ<26>")
	)
	(segment
		(start 78.338172 -95.709486)
		(end 78.338172 -96.04756)
		(width 0.0889)
		(layer "In2.Cu")
		(net "M_K_DQ<26>")
	)
	(segment
		(start 68.527168 -115.6462)
		(end 68.374768 -115.4938)
		(width 0.14224)
		(layer "In2.Cu")
		(net "M_K_DQ<26>")
	)
	(segment
		(start 76.636372 -100.071682)
		(end 76.608432 -100.071682)
		(width 0.0889)
		(layer "In2.Cu")
		(net "M_K_DQ<26>")
	)
	(segment
		(start 78.338172 -96.04756)
		(end 78.272894 -96.112838)
		(width 0.0889)
		(layer "In2.Cu")
		(net "M_K_DQ<26>")
	)
	(arc
		(start 77.826362 -97.986342)
		(mid 77.879895 -98.18624)
		(end 77.826362 -98.386138)
		(width 0.0889)
		(layer "In2.Cu")
		(net "M_K_DQ<26>")
	)
	(arc
		(start 77.458316 -99.576636)
		(mid 77.175099 -99.660917)
		(end 76.968096 -99.871784)
		(width 0.0889)
		(layer "In2.Cu")
		(net "M_K_DQ<26>")
	)
	(arc
		(start 75.745086 -100.566982)
		(mid 75.459662 -100.650449)
		(end 75.251056 -100.862384)
		(width 0.0889)
		(layer "In2.Cu")
		(net "M_K_DQ<26>")
	)
	(arc
		(start 77.826362 -98.386138)
		(mid 77.821784 -98.39368)
		(end 77.817472 -98.401378)
		(width 0.0889)
		(layer "In2.Cu")
		(net "M_K_DQ<26>")
	)
	(arc
		(start 77.817472 -97.410778)
		(mid 77.747075 -97.699729)
		(end 77.826362 -97.986342)
		(width 0.0889)
		(layer "In2.Cu")
		(net "M_K_DQ<26>")
	)
	(arc
		(start 78.272894 -96.112838)
		(mid 77.810675 -96.433435)
		(end 77.826362 -96.995742)
		(width 0.0889)
		(layer "In2.Cu")
		(net "M_K_DQ<26>")
	)
	(arc
		(start 74.882756 -101.062282)
		(mid 74.599539 -101.146563)
		(end 74.392536 -101.35743)
		(width 0.0889)
		(layer "In2.Cu")
		(net "M_K_DQ<26>")
	)
	(arc
		(start 77.817472 -98.401378)
		(mid 77.747075 -98.690329)
		(end 77.826362 -98.976942)
		(width 0.0889)
		(layer "In2.Cu")
		(net "M_K_DQ<26>")
	)
	(arc
		(start 77.826362 -96.995742)
		(mid 77.879895 -97.19564)
		(end 77.826362 -97.395538)
		(width 0.0889)
		(layer "In2.Cu")
		(net "M_K_DQ<26>")
	)
	(arc
		(start 77.826362 -98.976942)
		(mid 77.829287 -99.37158)
		(end 77.492098 -99.576636)
		(width 0.0889)
		(layer "In2.Cu")
		(net "M_K_DQ<26>")
	)
	(arc
		(start 75.251056 -100.862384)
		(mid 75.112312 -101.004417)
		(end 74.92238 -101.062282)
		(width 0.0889)
		(layer "In2.Cu")
		(net "M_K_DQ<26>")
	)
	(arc
		(start 76.968096 -99.871784)
		(mid 76.828017 -100.01452)
		(end 76.636372 -100.071682)
		(width 0.0889)
		(layer "In2.Cu")
		(net "M_K_DQ<26>")
	)
	(arc
		(start 76.608432 -100.071682)
		(mid 76.320287 -100.154001)
		(end 76.109576 -100.367084)
		(width 0.0889)
		(layer "In2.Cu")
		(net "M_K_DQ<26>")
	)
	(arc
		(start 76.109576 -100.367084)
		(mid 75.970832 -100.509117)
		(end 75.7809 -100.566982)
		(width 0.0889)
		(layer "In2.Cu")
		(net "M_K_DQ<26>")
	)
	(segment
		(start 76.334366 -97.19564)
		(end 75.762866 -97.19564)
		(width 0.1651)
		(layer "F.Cu")
		(net "M_K_DQ<25>")
	)
	(segment
		(start 61.149484 -133.0706)
		(end 61.149484 -134.340346)
		(width 0.1651)
		(layer "F.Cu")
		(net "M_K_DQ<25>")
	)
	(via
		(at 61.821568 -130.330956)
		(size 0.508)
		(drill 0.254)
		(layers "F.Cu" "B.Cu")
		(net "M_K_DQ<25>")
	)
	(via
		(at 61.149484 -134.340346)
		(size 0.508)
		(drill 0.254)
		(layers "F.Cu" "B.Cu")
		(net "M_K_DQ<25>")
	)
	(via
		(at 75.762866 -97.19564)
		(size 0.508)
		(drill 0.254)
		(layers "F.Cu" "B.Cu")
		(net "M_K_DQ<25>")
	)
	(segment
		(start 61.999368 -129.649982)
		(end 61.821568 -129.827782)
		(width 0.1651)
		(layer "B.Cu")
		(net "M_K_DQ<25>")
	)
	(segment
		(start 61.999368 -128.276096)
		(end 61.999368 -129.649982)
		(width 0.1651)
		(layer "B.Cu")
		(net "M_K_DQ<25>")
	)
	(segment
		(start 61.821568 -129.827782)
		(end 61.821568 -130.330956)
		(width 0.1651)
		(layer "B.Cu")
		(net "M_K_DQ<25>")
	)
	(segment
		(start 61.719968 -114.19459)
		(end 61.874908 -114.34953)
		(width 0.14224)
		(layer "In2.Cu")
		(net "M_K_DQ<25>")
	)
	(segment
		(start 69.771006 -100.26269)
		(end 69.735192 -100.26269)
		(width 0.0889)
		(layer "In2.Cu")
		(net "M_K_DQ<25>")
	)
	(segment
		(start 68.709032 -100.75799)
		(end 68.459604 -101.007418)
		(width 0.0889)
		(layer "In2.Cu")
		(net "M_K_DQ<25>")
	)
	(segment
		(start 68.459604 -101.422454)
		(end 66.46164 -103.420418)
		(width 0.0889)
		(layer "In2.Cu")
		(net "M_K_DQ<25>")
	)
	(segment
		(start 61.874908 -113.53673)
		(end 61.719968 -113.69167)
		(width 0.14224)
		(layer "In2.Cu")
		(net "M_K_DQ<25>")
	)
	(segment
		(start 61.370972 -130.7592)
		(end 61.370972 -131.188968)
		(width 0.14224)
		(layer "In2.Cu")
		(net "M_K_DQ<25>")
	)
	(segment
		(start 62.583568 -116.13007)
		(end 62.583568 -123.9266)
		(width 0.14224)
		(layer "In2.Cu")
		(net "M_K_DQ<25>")
	)
	(segment
		(start 62.428628 -115.97513)
		(end 62.583568 -116.13007)
		(width 0.14224)
		(layer "In2.Cu")
		(net "M_K_DQ<25>")
	)
	(segment
		(start 61.874908 -115.16233)
		(end 61.719968 -115.31727)
		(width 0.14224)
		(layer "In2.Cu")
		(net "M_K_DQ<25>")
	)
	(segment
		(start 62.583568 -112.87887)
		(end 62.583568 -113.38179)
		(width 0.14224)
		(layer "In2.Cu")
		(net "M_K_DQ<25>")
	)
	(segment
		(start 62.322964 -124.187204)
		(end 62.322964 -129.82956)
		(width 0.14224)
		(layer "In2.Cu")
		(net "M_K_DQ<25>")
	)
	(segment
		(start 61.398404 -134.340346)
		(end 61.149484 -134.340346)
		(width 0.14224)
		(layer "In2.Cu")
		(net "M_K_DQ<25>")
	)
	(segment
		(start 61.874908 -115.97513)
		(end 62.428628 -115.97513)
		(width 0.14224)
		(layer "In2.Cu")
		(net "M_K_DQ<25>")
	)
	(segment
		(start 61.719968 -115.82019)
		(end 61.874908 -115.97513)
		(width 0.14224)
		(layer "In2.Cu")
		(net "M_K_DQ<25>")
	)
	(segment
		(start 62.583568 -113.38179)
		(end 62.428628 -113.53673)
		(width 0.14224)
		(layer "In2.Cu")
		(net "M_K_DQ<25>")
	)
	(segment
		(start 61.60135 -131.823968)
		(end 61.310774 -132.114544)
		(width 0.14224)
		(layer "In2.Cu")
		(net "M_K_DQ<25>")
	)
	(segment
		(start 62.583568 -114.50447)
		(end 62.583568 -115.00739)
		(width 0.14224)
		(layer "In2.Cu")
		(net "M_K_DQ<25>")
	)
	(segment
		(start 61.55055 -134.1882)
		(end 61.398404 -134.340346)
		(width 0.14224)
		(layer "In2.Cu")
		(net "M_K_DQ<25>")
	)
	(segment
		(start 62.428628 -113.53673)
		(end 61.874908 -113.53673)
		(width 0.14224)
		(layer "In2.Cu")
		(net "M_K_DQ<25>")
	)
	(segment
		(start 64.896492 -108.665772)
		(end 62.583568 -110.978696)
		(width 0.14224)
		(layer "In2.Cu")
		(net "M_K_DQ<25>")
	)
	(segment
		(start 62.583568 -123.9266)
		(end 62.322964 -124.187204)
		(width 0.14224)
		(layer "In2.Cu")
		(net "M_K_DQ<25>")
	)
	(segment
		(start 62.428628 -111.91113)
		(end 62.052708 -111.91113)
		(width 0.14224)
		(layer "In2.Cu")
		(net "M_K_DQ<25>")
	)
	(segment
		(start 61.874908 -114.34953)
		(end 62.428628 -114.34953)
		(width 0.14224)
		(layer "In2.Cu")
		(net "M_K_DQ<25>")
	)
	(segment
		(start 72.346566 -98.77679)
		(end 72.3138 -98.77679)
		(width 0.0889)
		(layer "In2.Cu")
		(net "M_K_DQ<25>")
	)
	(segment
		(start 61.799216 -130.330956)
		(end 61.370972 -130.7592)
		(width 0.14224)
		(layer "In2.Cu")
		(net "M_K_DQ<25>")
	)
	(segment
		(start 62.428628 -115.16233)
		(end 61.874908 -115.16233)
		(width 0.14224)
		(layer "In2.Cu")
		(net "M_K_DQ<25>")
	)
	(segment
		(start 61.370972 -131.188968)
		(end 61.60135 -131.419346)
		(width 0.14224)
		(layer "In2.Cu")
		(net "M_K_DQ<25>")
	)
	(segment
		(start 61.310774 -132.114544)
		(end 61.310774 -132.475224)
		(width 0.14224)
		(layer "In2.Cu")
		(net "M_K_DQ<25>")
	)
	(segment
		(start 74.94143 -97.290636)
		(end 74.89317 -97.290636)
		(width 0.0889)
		(layer "In2.Cu")
		(net "M_K_DQ<25>")
	)
	(segment
		(start 68.90766 -100.75799)
		(end 68.709032 -100.75799)
		(width 0.0889)
		(layer "In2.Cu")
		(net "M_K_DQ<25>")
	)
	(segment
		(start 62.583568 -111.75619)
		(end 62.428628 -111.91113)
		(width 0.14224)
		(layer "In2.Cu")
		(net "M_K_DQ<25>")
	)
	(segment
		(start 61.719968 -115.31727)
		(end 61.719968 -115.82019)
		(width 0.14224)
		(layer "In2.Cu")
		(net "M_K_DQ<25>")
	)
	(segment
		(start 75.762866 -97.19564)
		(end 74.94143 -97.290636)
		(width 0.0889)
		(layer "In2.Cu")
		(net "M_K_DQ<25>")
	)
	(segment
		(start 66.46164 -103.420418)
		(end 66.46164 -103.739188)
		(width 0.0889)
		(layer "In2.Cu")
		(net "M_K_DQ<25>")
	)
	(segment
		(start 61.52515 -132.6896)
		(end 61.52515 -133.1214)
		(width 0.14224)
		(layer "In2.Cu")
		(net "M_K_DQ<25>")
	)
	(segment
		(start 68.459604 -101.007418)
		(end 68.459604 -101.422454)
		(width 0.0889)
		(layer "In2.Cu")
		(net "M_K_DQ<25>")
	)
	(segment
		(start 61.310774 -133.643624)
		(end 61.55055 -133.8834)
		(width 0.14224)
		(layer "In2.Cu")
		(net "M_K_DQ<25>")
	)
	(segment
		(start 61.52515 -133.1214)
		(end 61.310774 -133.335776)
		(width 0.14224)
		(layer "In2.Cu")
		(net "M_K_DQ<25>")
	)
	(segment
		(start 62.052708 -111.91113)
		(end 61.897768 -112.06607)
		(width 0.14224)
		(layer "In2.Cu")
		(net "M_K_DQ<25>")
	)
	(segment
		(start 61.55055 -133.8834)
		(end 61.55055 -134.1882)
		(width 0.14224)
		(layer "In2.Cu")
		(net "M_K_DQ<25>")
	)
	(segment
		(start 61.897768 -112.56899)
		(end 62.052708 -112.72393)
		(width 0.14224)
		(layer "In2.Cu")
		(net "M_K_DQ<25>")
	)
	(segment
		(start 74.063606 -97.78619)
		(end 74.03084 -97.78619)
		(width 0.0889)
		(layer "In2.Cu")
		(net "M_K_DQ<25>")
	)
	(segment
		(start 62.583568 -110.978696)
		(end 62.583568 -111.75619)
		(width 0.14224)
		(layer "In2.Cu")
		(net "M_K_DQ<25>")
	)
	(segment
		(start 61.821568 -130.330956)
		(end 61.799216 -130.330956)
		(width 0.14224)
		(layer "In2.Cu")
		(net "M_K_DQ<25>")
	)
	(segment
		(start 64.896492 -105.304336)
		(end 64.896492 -108.665772)
		(width 0.14224)
		(layer "In2.Cu")
		(net "M_K_DQ<25>")
	)
	(segment
		(start 61.310774 -133.335776)
		(end 61.310774 -133.643624)
		(width 0.14224)
		(layer "In2.Cu")
		(net "M_K_DQ<25>")
	)
	(segment
		(start 61.897768 -112.06607)
		(end 61.897768 -112.56899)
		(width 0.14224)
		(layer "In2.Cu")
		(net "M_K_DQ<25>")
	)
	(segment
		(start 62.428628 -114.34953)
		(end 62.583568 -114.50447)
		(width 0.14224)
		(layer "In2.Cu")
		(net "M_K_DQ<25>")
	)
	(segment
		(start 61.60135 -131.419346)
		(end 61.60135 -131.823968)
		(width 0.14224)
		(layer "In2.Cu")
		(net "M_K_DQ<25>")
	)
	(segment
		(start 71.48322 -99.27209)
		(end 71.45909 -99.27209)
		(width 0.0889)
		(layer "In2.Cu")
		(net "M_K_DQ<25>")
	)
	(segment
		(start 62.428628 -112.72393)
		(end 62.583568 -112.87887)
		(width 0.14224)
		(layer "In2.Cu")
		(net "M_K_DQ<25>")
	)
	(segment
		(start 66.46164 -103.739188)
		(end 64.896492 -105.304336)
		(width 0.14224)
		(layer "In2.Cu")
		(net "M_K_DQ<25>")
	)
	(segment
		(start 70.633336 -99.76739)
		(end 70.593712 -99.76739)
		(width 0.0889)
		(layer "In2.Cu")
		(net "M_K_DQ<25>")
	)
	(segment
		(start 61.310774 -132.475224)
		(end 61.52515 -132.6896)
		(width 0.14224)
		(layer "In2.Cu")
		(net "M_K_DQ<25>")
	)
	(segment
		(start 61.719968 -113.69167)
		(end 61.719968 -114.19459)
		(width 0.14224)
		(layer "In2.Cu")
		(net "M_K_DQ<25>")
	)
	(segment
		(start 62.583568 -115.00739)
		(end 62.428628 -115.16233)
		(width 0.14224)
		(layer "In2.Cu")
		(net "M_K_DQ<25>")
	)
	(segment
		(start 62.322964 -129.82956)
		(end 61.821568 -130.330956)
		(width 0.14224)
		(layer "In2.Cu")
		(net "M_K_DQ<25>")
	)
	(segment
		(start 73.208896 -98.281236)
		(end 73.17613 -98.281236)
		(width 0.0889)
		(layer "In2.Cu")
		(net "M_K_DQ<25>")
	)
	(segment
		(start 62.052708 -112.72393)
		(end 62.428628 -112.72393)
		(width 0.14224)
		(layer "In2.Cu")
		(net "M_K_DQ<25>")
	)
	(arc
		(start 73.699116 -97.986088)
		(mid 73.492112 -98.196952)
		(end 73.208896 -98.281236)
		(width 0.0889)
		(layer "In2.Cu")
		(net "M_K_DQ<25>")
	)
	(arc
		(start 72.840596 -98.481388)
		(mid 72.631988 -98.69332)
		(end 72.346566 -98.77679)
		(width 0.0889)
		(layer "In2.Cu")
		(net "M_K_DQ<25>")
	)
	(arc
		(start 72.3138 -98.77679)
		(mid 72.122158 -98.833956)
		(end 71.982076 -98.976688)
		(width 0.0889)
		(layer "In2.Cu")
		(net "M_K_DQ<25>")
	)
	(arc
		(start 71.123556 -99.472242)
		(mid 70.916552 -99.683106)
		(end 70.633336 -99.76739)
		(width 0.0889)
		(layer "In2.Cu")
		(net "M_K_DQ<25>")
	)
	(arc
		(start 71.982076 -98.976688)
		(mid 71.771363 -99.189767)
		(end 71.48322 -99.27209)
		(width 0.0889)
		(layer "In2.Cu")
		(net "M_K_DQ<25>")
	)
	(arc
		(start 73.17613 -98.281236)
		(mid 72.98228 -98.337586)
		(end 72.840596 -98.481388)
		(width 0.0889)
		(layer "In2.Cu")
		(net "M_K_DQ<25>")
	)
	(arc
		(start 71.45909 -99.27209)
		(mid 71.26524 -99.32844)
		(end 71.123556 -99.472242)
		(width 0.0889)
		(layer "In2.Cu")
		(net "M_K_DQ<25>")
	)
	(arc
		(start 70.265036 -99.967288)
		(mid 70.056428 -100.17922)
		(end 69.771006 -100.26269)
		(width 0.0889)
		(layer "In2.Cu")
		(net "M_K_DQ<25>")
	)
	(arc
		(start 70.593712 -99.76739)
		(mid 70.403783 -99.82526)
		(end 70.265036 -99.967288)
		(width 0.0889)
		(layer "In2.Cu")
		(net "M_K_DQ<25>")
	)
	(arc
		(start 69.735192 -100.26269)
		(mid 69.545263 -100.32056)
		(end 69.406516 -100.462588)
		(width 0.0889)
		(layer "In2.Cu")
		(net "M_K_DQ<25>")
	)
	(arc
		(start 74.557636 -97.490788)
		(mid 74.349028 -97.70272)
		(end 74.063606 -97.78619)
		(width 0.0889)
		(layer "In2.Cu")
		(net "M_K_DQ<25>")
	)
	(arc
		(start 74.03084 -97.78619)
		(mid 73.839198 -97.843356)
		(end 73.699116 -97.986088)
		(width 0.0889)
		(layer "In2.Cu")
		(net "M_K_DQ<25>")
	)
	(arc
		(start 74.89317 -97.290636)
		(mid 74.69932 -97.346986)
		(end 74.557636 -97.490788)
		(width 0.0889)
		(layer "In2.Cu")
		(net "M_K_DQ<25>")
	)
	(arc
		(start 69.406516 -100.462588)
		(mid 69.195803 -100.675667)
		(end 68.90766 -100.75799)
		(width 0.0889)
		(layer "In2.Cu")
		(net "M_K_DQ<25>")
	)
	(segment
		(start 61.999368 -137.676382)
		(end 61.821568 -135.8138)
		(width 0.1651)
		(layer "F.Cu")
		(net "M_K_DQ<24>")
	)
	(segment
		(start 76.334366 -95.21444)
		(end 75.762866 -95.21444)
		(width 0.1651)
		(layer "F.Cu")
		(net "M_K_DQ<24>")
	)
	(segment
		(start 61.999368 -137.67054)
		(end 61.999368 -137.676382)
		(width 0.1651)
		(layer "F.Cu")
		(net "M_K_DQ<24>")
	)
	(via
		(at 61.821568 -135.8138)
		(size 0.508)
		(drill 0.254)
		(layers "F.Cu" "B.Cu")
		(net "M_K_DQ<24>")
	)
	(via
		(at 61.149484 -131.611878)
		(size 0.508)
		(drill 0.254)
		(layers "F.Cu" "B.Cu")
		(net "M_K_DQ<24>")
	)
	(via
		(at 75.762866 -95.21444)
		(size 0.508)
		(drill 0.254)
		(layers "F.Cu" "B.Cu")
		(net "M_K_DQ<24>")
	)
	(segment
		(start 61.149484 -132.876036)
		(end 61.149484 -131.611878)
		(width 0.1651)
		(layer "B.Cu")
		(net "M_K_DQ<24>")
	)
	(segment
		(start 61.525404 -135.8138)
		(end 61.821568 -135.8138)
		(width 0.14224)
		(layer "In2.Cu")
		(net "M_K_DQ<24>")
	)
	(segment
		(start 73.202292 -98.090736)
		(end 73.169526 -98.090736)
		(width 0.0889)
		(layer "In2.Cu")
		(net "M_K_DQ<24>")
	)
	(segment
		(start 68.269612 -101.343714)
		(end 66.307462 -103.305864)
		(width 0.0889)
		(layer "In2.Cu")
		(net "M_K_DQ<24>")
	)
	(segment
		(start 75.251056 -96.500188)
		(end 75.255882 -96.508824)
		(width 0.0889)
		(layer "In2.Cu")
		(net "M_K_DQ<24>")
	)
	(segment
		(start 61.288168 -128.4224)
		(end 61.542168 -128.6764)
		(width 0.14224)
		(layer "In2.Cu")
		(net "M_K_DQ<24>")
	)
	(segment
		(start 61.542168 -128.6764)
		(end 61.542168 -129.851912)
		(width 0.14224)
		(layer "In2.Cu")
		(net "M_K_DQ<24>")
	)
	(segment
		(start 68.269612 -100.928678)
		(end 68.269612 -101.343714)
		(width 0.0889)
		(layer "In2.Cu")
		(net "M_K_DQ<24>")
	)
	(segment
		(start 75.244706 -96.48952)
		(end 75.251056 -96.500188)
		(width 0.0889)
		(layer "In2.Cu")
		(net "M_K_DQ<24>")
	)
	(segment
		(start 70.62978 -99.576636)
		(end 70.593966 -99.576636)
		(width 0.0889)
		(layer "In2.Cu")
		(net "M_K_DQ<24>")
	)
	(segment
		(start 75.26782 -95.880174)
		(end 75.251056 -95.909638)
		(width 0.0889)
		(layer "In2.Cu")
		(net "M_K_DQ<24>")
	)
	(segment
		(start 61.196474 -111.44758)
		(end 61.196474 -116.392706)
		(width 0.14224)
		(layer "In2.Cu")
		(net "M_K_DQ<24>")
	)
	(segment
		(start 64.247268 -105.037382)
		(end 64.247268 -108.396786)
		(width 0.14224)
		(layer "In2.Cu")
		(net "M_K_DQ<24>")
	)
	(segment
		(start 60.716414 -135.00481)
		(end 61.525404 -135.8138)
		(width 0.14224)
		(layer "In2.Cu")
		(net "M_K_DQ<24>")
	)
	(segment
		(start 60.954158 -131.416552)
		(end 61.149484 -131.611878)
		(width 0.14224)
		(layer "In2.Cu")
		(net "M_K_DQ<24>")
	)
	(segment
		(start 64.247268 -108.396786)
		(end 61.196474 -111.44758)
		(width 0.14224)
		(layer "In2.Cu")
		(net "M_K_DQ<24>")
	)
	(segment
		(start 75.762866 -95.21444)
		(end 75.26782 -95.880174)
		(width 0.0889)
		(layer "In2.Cu")
		(net "M_K_DQ<24>")
	)
	(segment
		(start 69.77126 -100.071936)
		(end 69.731636 -100.071936)
		(width 0.0889)
		(layer "In2.Cu")
		(net "M_K_DQ<24>")
	)
	(segment
		(start 66.307462 -103.305864)
		(end 66.003678 -103.305864)
		(width 0.0889)
		(layer "In2.Cu")
		(net "M_K_DQ<24>")
	)
	(segment
		(start 74.919332 -97.100136)
		(end 74.886566 -97.100136)
		(width 0.0889)
		(layer "In2.Cu")
		(net "M_K_DQ<24>")
	)
	(segment
		(start 61.288168 -124.572268)
		(end 61.288168 -128.4224)
		(width 0.14224)
		(layer "In2.Cu")
		(net "M_K_DQ<24>")
	)
	(segment
		(start 68.895976 -100.566728)
		(end 68.631562 -100.566728)
		(width 0.0889)
		(layer "In2.Cu")
		(net "M_K_DQ<24>")
	)
	(segment
		(start 71.485252 -99.081336)
		(end 71.457312 -99.081336)
		(width 0.0889)
		(layer "In2.Cu")
		(net "M_K_DQ<24>")
	)
	(segment
		(start 72.339962 -98.58629)
		(end 72.307196 -98.58629)
		(width 0.0889)
		(layer "In2.Cu")
		(net "M_K_DQ<24>")
	)
	(segment
		(start 61.196474 -116.392706)
		(end 61.897768 -117.094)
		(width 0.14224)
		(layer "In2.Cu")
		(net "M_K_DQ<24>")
	)
	(segment
		(start 61.897768 -123.962668)
		(end 61.288168 -124.572268)
		(width 0.14224)
		(layer "In2.Cu")
		(net "M_K_DQ<24>")
	)
	(segment
		(start 60.716414 -132.044948)
		(end 60.716414 -135.00481)
		(width 0.14224)
		(layer "In2.Cu")
		(net "M_K_DQ<24>")
	)
	(segment
		(start 61.897768 -117.094)
		(end 61.897768 -123.962668)
		(width 0.14224)
		(layer "In2.Cu")
		(net "M_K_DQ<24>")
	)
	(segment
		(start 60.954158 -130.439922)
		(end 60.954158 -131.416552)
		(width 0.14224)
		(layer "In2.Cu")
		(net "M_K_DQ<24>")
	)
	(segment
		(start 74.057002 -97.59569)
		(end 74.024236 -97.59569)
		(width 0.0889)
		(layer "In2.Cu")
		(net "M_K_DQ<24>")
	)
	(segment
		(start 61.149484 -131.611878)
		(end 60.716414 -132.044948)
		(width 0.14224)
		(layer "In2.Cu")
		(net "M_K_DQ<24>")
	)
	(segment
		(start 66.003678 -103.305864)
		(end 65.991232 -103.293418)
		(width 0.0889)
		(layer "In2.Cu")
		(net "M_K_DQ<24>")
	)
	(segment
		(start 65.991232 -103.293418)
		(end 64.247268 -105.037382)
		(width 0.14224)
		(layer "In2.Cu")
		(net "M_K_DQ<24>")
	)
	(segment
		(start 61.542168 -129.851912)
		(end 60.954158 -130.439922)
		(width 0.14224)
		(layer "In2.Cu")
		(net "M_K_DQ<24>")
	)
	(segment
		(start 68.631562 -100.566728)
		(end 68.269612 -100.928678)
		(width 0.0889)
		(layer "In2.Cu")
		(net "M_K_DQ<24>")
	)
	(arc
		(start 72.307196 -98.58629)
		(mid 72.023979 -98.670571)
		(end 71.816976 -98.881438)
		(width 0.0889)
		(layer "In2.Cu")
		(net "M_K_DQ<24>")
	)
	(arc
		(start 70.958456 -99.376738)
		(mid 70.819712 -99.518771)
		(end 70.62978 -99.576636)
		(width 0.0889)
		(layer "In2.Cu")
		(net "M_K_DQ<24>")
	)
	(arc
		(start 74.886566 -97.100136)
		(mid 74.601142 -97.183603)
		(end 74.392536 -97.395538)
		(width 0.0889)
		(layer "In2.Cu")
		(net "M_K_DQ<24>")
	)
	(arc
		(start 69.241416 -100.367084)
		(mid 69.095454 -100.513191)
		(end 68.895976 -100.566728)
		(width 0.0889)
		(layer "In2.Cu")
		(net "M_K_DQ<24>")
	)
	(arc
		(start 72.675496 -98.386138)
		(mid 72.533813 -98.529942)
		(end 72.339962 -98.58629)
		(width 0.0889)
		(layer "In2.Cu")
		(net "M_K_DQ<24>")
	)
	(arc
		(start 70.593966 -99.576636)
		(mid 70.308542 -99.660103)
		(end 70.099936 -99.872038)
		(width 0.0889)
		(layer "In2.Cu")
		(net "M_K_DQ<24>")
	)
	(arc
		(start 74.024236 -97.59569)
		(mid 73.741019 -97.679971)
		(end 73.534016 -97.890838)
		(width 0.0889)
		(layer "In2.Cu")
		(net "M_K_DQ<24>")
	)
	(arc
		(start 73.534016 -97.890838)
		(mid 73.393937 -98.033574)
		(end 73.202292 -98.090736)
		(width 0.0889)
		(layer "In2.Cu")
		(net "M_K_DQ<24>")
	)
	(arc
		(start 73.169526 -98.090736)
		(mid 72.884102 -98.174203)
		(end 72.675496 -98.386138)
		(width 0.0889)
		(layer "In2.Cu")
		(net "M_K_DQ<24>")
	)
	(arc
		(start 71.457312 -99.081336)
		(mid 71.169167 -99.163655)
		(end 70.958456 -99.376738)
		(width 0.0889)
		(layer "In2.Cu")
		(net "M_K_DQ<24>")
	)
	(arc
		(start 71.816976 -98.881438)
		(mid 71.676897 -99.024174)
		(end 71.485252 -99.081336)
		(width 0.0889)
		(layer "In2.Cu")
		(net "M_K_DQ<24>")
	)
	(arc
		(start 70.099936 -99.872038)
		(mid 69.961192 -100.014071)
		(end 69.77126 -100.071936)
		(width 0.0889)
		(layer "In2.Cu")
		(net "M_K_DQ<24>")
	)
	(arc
		(start 69.731636 -100.071936)
		(mid 69.448419 -100.156217)
		(end 69.241416 -100.367084)
		(width 0.0889)
		(layer "In2.Cu")
		(net "M_K_DQ<24>")
	)
	(arc
		(start 74.392536 -97.395538)
		(mid 74.250853 -97.539342)
		(end 74.057002 -97.59569)
		(width 0.0889)
		(layer "In2.Cu")
		(net "M_K_DQ<24>")
	)
	(arc
		(start 75.251056 -95.909638)
		(mid 75.171834 -96.198756)
		(end 75.244706 -96.48952)
		(width 0.0889)
		(layer "In2.Cu")
		(net "M_K_DQ<24>")
	)
	(arc
		(start 75.255882 -96.508824)
		(mid 75.252135 -96.89808)
		(end 74.919332 -97.100136)
		(width 0.0889)
		(layer "In2.Cu")
		(net "M_K_DQ<24>")
	)
	(segment
		(start 56.049418 -133.0706)
		(end 56.049418 -134.340346)
		(width 0.1651)
		(layer "F.Cu")
		(net "M_K_DQ<23>")
	)
	(segment
		(start 71.183246 -95.21444)
		(end 70.611746 -95.21444)
		(width 0.1651)
		(layer "F.Cu")
		(net "M_K_DQ<23>")
	)
	(via
		(at 56.049418 -134.340346)
		(size 0.508)
		(drill 0.254)
		(layers "F.Cu" "B.Cu")
		(net "M_K_DQ<23>")
	)
	(via
		(at 70.611746 -95.21444)
		(size 0.508)
		(drill 0.254)
		(layers "F.Cu" "B.Cu")
		(net "M_K_DQ<23>")
	)
	(via
		(at 56.899302 -130.330956)
		(size 0.508)
		(drill 0.254)
		(layers "F.Cu" "B.Cu")
		(net "M_K_DQ<23>")
	)
	(segment
		(start 56.899556 -128.276096)
		(end 56.899302 -128.276096)
		(width 0.1651)
		(layer "B.Cu")
		(net "M_K_DQ<23>")
	)
	(segment
		(start 56.899302 -128.276096)
		(end 56.899302 -130.330956)
		(width 0.1651)
		(layer "B.Cu")
		(net "M_K_DQ<23>")
	)
	(segment
		(start 56.614568 -116.488718)
		(end 56.756808 -116.630958)
		(width 0.14224)
		(layer "In2.Cu")
		(net "M_K_DQ<23>")
	)
	(segment
		(start 56.756808 -112.079278)
		(end 56.614568 -112.221518)
		(width 0.14224)
		(layer "In2.Cu")
		(net "M_K_DQ<23>")
	)
	(segment
		(start 57.241186 -129.989072)
		(end 56.899302 -130.330956)
		(width 0.14224)
		(layer "In2.Cu")
		(net "M_K_DQ<23>")
	)
	(segment
		(start 57.539128 -115.980718)
		(end 56.756808 -115.980718)
		(width 0.14224)
		(layer "In2.Cu")
		(net "M_K_DQ<23>")
	)
	(segment
		(start 70.611746 -95.21444)
		(end 70.276466 -95.21444)
		(width 0.0889)
		(layer "In2.Cu")
		(net "M_K_DQ<23>")
	)
	(segment
		(start 56.467756 -132.715)
		(end 56.467756 -133.0198)
		(width 0.14224)
		(layer "In2.Cu")
		(net "M_K_DQ<23>")
	)
	(segment
		(start 56.210708 -132.457952)
		(end 56.467756 -132.715)
		(width 0.14224)
		(layer "In2.Cu")
		(net "M_K_DQ<23>")
	)
	(segment
		(start 56.614568 -114.822478)
		(end 56.614568 -115.188238)
		(width 0.14224)
		(layer "In2.Cu")
		(net "M_K_DQ<23>")
	)
	(segment
		(start 56.493156 -131.9022)
		(end 56.210708 -132.184648)
		(width 0.14224)
		(layer "In2.Cu")
		(net "M_K_DQ<23>")
	)
	(segment
		(start 57.539128 -112.729518)
		(end 57.681368 -112.871758)
		(width 0.14224)
		(layer "In2.Cu")
		(net "M_K_DQ<23>")
	)
	(segment
		(start 56.87695 -130.330956)
		(end 56.448706 -130.7592)
		(width 0.14224)
		(layer "In2.Cu")
		(net "M_K_DQ<23>")
	)
	(segment
		(start 56.614568 -113.887758)
		(end 56.756808 -114.029998)
		(width 0.14224)
		(layer "In2.Cu")
		(net "M_K_DQ<23>")
	)
	(segment
		(start 57.539128 -110.778798)
		(end 56.756808 -110.778798)
		(width 0.14224)
		(layer "In2.Cu")
		(net "M_K_DQ<23>")
	)
	(segment
		(start 57.539128 -114.029998)
		(end 57.681368 -114.172238)
		(width 0.14224)
		(layer "In2.Cu")
		(net "M_K_DQ<23>")
	)
	(segment
		(start 56.899302 -130.330956)
		(end 56.87695 -130.330956)
		(width 0.14224)
		(layer "In2.Cu")
		(net "M_K_DQ<23>")
	)
	(segment
		(start 57.539128 -115.330478)
		(end 57.681368 -115.472718)
		(width 0.14224)
		(layer "In2.Cu")
		(net "M_K_DQ<23>")
	)
	(segment
		(start 57.681368 -111.937038)
		(end 57.539128 -112.079278)
		(width 0.14224)
		(layer "In2.Cu")
		(net "M_K_DQ<23>")
	)
	(segment
		(start 69.408294 -95.425006)
		(end 66.867532 -95.425006)
		(width 0.0889)
		(layer "In2.Cu")
		(net "M_K_DQ<23>")
	)
	(segment
		(start 57.681368 -114.172238)
		(end 57.681368 -114.537998)
		(width 0.14224)
		(layer "In2.Cu")
		(net "M_K_DQ<23>")
	)
	(segment
		(start 56.448706 -130.7592)
		(end 56.448706 -131.188968)
		(width 0.14224)
		(layer "In2.Cu")
		(net "M_K_DQ<23>")
	)
	(segment
		(start 56.868568 -127.4826)
		(end 57.084468 -127.6985)
		(width 0.14224)
		(layer "In2.Cu")
		(net "M_K_DQ<23>")
	)
	(segment
		(start 57.252108 -129.38506)
		(end 57.252108 -129.989072)
		(width 0.14224)
		(layer "In2.Cu")
		(net "M_K_DQ<23>")
	)
	(segment
		(start 56.756808 -112.729518)
		(end 57.539128 -112.729518)
		(width 0.14224)
		(layer "In2.Cu")
		(net "M_K_DQ<23>")
	)
	(segment
		(start 57.681368 -115.838478)
		(end 57.539128 -115.980718)
		(width 0.14224)
		(layer "In2.Cu")
		(net "M_K_DQ<23>")
	)
	(segment
		(start 56.756808 -116.630958)
		(end 57.539128 -116.630958)
		(width 0.14224)
		(layer "In2.Cu")
		(net "M_K_DQ<23>")
	)
	(segment
		(start 56.614568 -113.521998)
		(end 56.614568 -113.887758)
		(width 0.14224)
		(layer "In2.Cu")
		(net "M_K_DQ<23>")
	)
	(segment
		(start 56.499506 -134.162546)
		(end 56.321706 -134.340346)
		(width 0.14224)
		(layer "In2.Cu")
		(net "M_K_DQ<23>")
	)
	(segment
		(start 56.614568 -111.286798)
		(end 56.756808 -111.429038)
		(width 0.14224)
		(layer "In2.Cu")
		(net "M_K_DQ<23>")
	)
	(segment
		(start 56.499506 -133.83895)
		(end 56.499506 -134.162546)
		(width 0.14224)
		(layer "In2.Cu")
		(net "M_K_DQ<23>")
	)
	(segment
		(start 56.448706 -131.188968)
		(end 56.493156 -131.233418)
		(width 0.14224)
		(layer "In2.Cu")
		(net "M_K_DQ<23>")
	)
	(segment
		(start 57.554368 -128.651)
		(end 57.554368 -129.0828)
		(width 0.14224)
		(layer "In2.Cu")
		(net "M_K_DQ<23>")
	)
	(segment
		(start 55.242968 -120.142)
		(end 55.115968 -120.269)
		(width 0.14224)
		(layer "In2.Cu")
		(net "M_K_DQ<23>")
	)
	(segment
		(start 57.681368 -111.571278)
		(end 57.681368 -111.937038)
		(width 0.14224)
		(layer "In2.Cu")
		(net "M_K_DQ<23>")
	)
	(segment
		(start 57.681368 -114.537998)
		(end 57.539128 -114.680238)
		(width 0.14224)
		(layer "In2.Cu")
		(net "M_K_DQ<23>")
	)
	(segment
		(start 56.210708 -132.184648)
		(end 56.210708 -132.457952)
		(width 0.14224)
		(layer "In2.Cu")
		(net "M_K_DQ<23>")
	)
	(segment
		(start 57.539128 -116.630958)
		(end 57.681368 -116.773198)
		(width 0.14224)
		(layer "In2.Cu")
		(net "M_K_DQ<23>")
	)
	(segment
		(start 57.084468 -128.1811)
		(end 57.554368 -128.651)
		(width 0.14224)
		(layer "In2.Cu")
		(net "M_K_DQ<23>")
	)
	(segment
		(start 56.563768 -118.7704)
		(end 56.563768 -120.015)
		(width 0.14224)
		(layer "In2.Cu")
		(net "M_K_DQ<23>")
	)
	(segment
		(start 57.084468 -127.6985)
		(end 57.084468 -128.1811)
		(width 0.14224)
		(layer "In2.Cu")
		(net "M_K_DQ<23>")
	)
	(segment
		(start 57.681368 -115.472718)
		(end 57.681368 -115.838478)
		(width 0.14224)
		(layer "In2.Cu")
		(net "M_K_DQ<23>")
	)
	(segment
		(start 57.681368 -108.314998)
		(end 57.681368 -110.636558)
		(width 0.14224)
		(layer "In2.Cu")
		(net "M_K_DQ<23>")
	)
	(segment
		(start 57.681368 -113.237518)
		(end 57.539128 -113.379758)
		(width 0.14224)
		(layer "In2.Cu")
		(net "M_K_DQ<23>")
	)
	(segment
		(start 56.436768 -120.142)
		(end 55.242968 -120.142)
		(width 0.14224)
		(layer "In2.Cu")
		(net "M_K_DQ<23>")
	)
	(segment
		(start 56.563768 -120.015)
		(end 56.436768 -120.142)
		(width 0.14224)
		(layer "In2.Cu")
		(net "M_K_DQ<23>")
	)
	(segment
		(start 57.539128 -112.079278)
		(end 56.756808 -112.079278)
		(width 0.14224)
		(layer "In2.Cu")
		(net "M_K_DQ<23>")
	)
	(segment
		(start 55.115968 -120.269)
		(end 55.115968 -126.5428)
		(width 0.14224)
		(layer "In2.Cu")
		(net "M_K_DQ<23>")
	)
	(segment
		(start 59.877452 -106.118914)
		(end 57.681368 -108.314998)
		(width 0.14224)
		(layer "In2.Cu")
		(net "M_K_DQ<23>")
	)
	(segment
		(start 57.539128 -114.680238)
		(end 56.756808 -114.680238)
		(width 0.14224)
		(layer "In2.Cu")
		(net "M_K_DQ<23>")
	)
	(segment
		(start 65.783206 -96.509332)
		(end 65.783206 -97.068132)
		(width 0.0889)
		(layer "In2.Cu")
		(net "M_K_DQ<23>")
	)
	(segment
		(start 57.252108 -129.989072)
		(end 57.241186 -129.989072)
		(width 0.14224)
		(layer "In2.Cu")
		(net "M_K_DQ<23>")
	)
	(segment
		(start 56.210708 -133.550152)
		(end 56.499506 -133.83895)
		(width 0.14224)
		(layer "In2.Cu")
		(net "M_K_DQ<23>")
	)
	(segment
		(start 56.614568 -110.921038)
		(end 56.614568 -111.286798)
		(width 0.14224)
		(layer "In2.Cu")
		(net "M_K_DQ<23>")
	)
	(segment
		(start 59.877452 -103.26497)
		(end 59.877452 -106.118914)
		(width 0.14224)
		(layer "In2.Cu")
		(net "M_K_DQ<23>")
	)
	(segment
		(start 66.867532 -95.425006)
		(end 65.783206 -96.509332)
		(width 0.0889)
		(layer "In2.Cu")
		(net "M_K_DQ<23>")
	)
	(segment
		(start 56.321706 -134.340346)
		(end 56.049418 -134.340346)
		(width 0.14224)
		(layer "In2.Cu")
		(net "M_K_DQ<23>")
	)
	(segment
		(start 56.493156 -131.233418)
		(end 56.493156 -131.9022)
		(width 0.14224)
		(layer "In2.Cu")
		(net "M_K_DQ<23>")
	)
	(segment
		(start 57.539128 -113.379758)
		(end 56.756808 -113.379758)
		(width 0.14224)
		(layer "In2.Cu")
		(net "M_K_DQ<23>")
	)
	(segment
		(start 70.18147 -95.309436)
		(end 69.523864 -95.309436)
		(width 0.0889)
		(layer "In2.Cu")
		(net "M_K_DQ<23>")
	)
	(segment
		(start 57.681368 -112.871758)
		(end 57.681368 -113.237518)
		(width 0.14224)
		(layer "In2.Cu")
		(net "M_K_DQ<23>")
	)
	(segment
		(start 57.681368 -117.6528)
		(end 56.563768 -118.7704)
		(width 0.14224)
		(layer "In2.Cu")
		(net "M_K_DQ<23>")
	)
	(segment
		(start 65.52819 -97.614232)
		(end 59.877452 -103.26497)
		(width 0.14224)
		(layer "In2.Cu")
		(net "M_K_DQ<23>")
	)
	(segment
		(start 65.558416 -97.614232)
		(end 65.52819 -97.614232)
		(width 0.14224)
		(layer "In2.Cu")
		(net "M_K_DQ<23>")
	)
	(segment
		(start 56.756808 -113.379758)
		(end 56.614568 -113.521998)
		(width 0.14224)
		(layer "In2.Cu")
		(net "M_K_DQ<23>")
	)
	(segment
		(start 70.276466 -95.21444)
		(end 70.18147 -95.309436)
		(width 0.0889)
		(layer "In2.Cu")
		(net "M_K_DQ<23>")
	)
	(segment
		(start 57.539128 -111.429038)
		(end 57.681368 -111.571278)
		(width 0.14224)
		(layer "In2.Cu")
		(net "M_K_DQ<23>")
	)
	(segment
		(start 56.756808 -115.980718)
		(end 56.614568 -116.122958)
		(width 0.14224)
		(layer "In2.Cu")
		(net "M_K_DQ<23>")
	)
	(segment
		(start 56.756808 -110.778798)
		(end 56.614568 -110.921038)
		(width 0.14224)
		(layer "In2.Cu")
		(net "M_K_DQ<23>")
	)
	(segment
		(start 56.756808 -115.330478)
		(end 57.539128 -115.330478)
		(width 0.14224)
		(layer "In2.Cu")
		(net "M_K_DQ<23>")
	)
	(segment
		(start 56.055768 -127.4826)
		(end 56.868568 -127.4826)
		(width 0.14224)
		(layer "In2.Cu")
		(net "M_K_DQ<23>")
	)
	(segment
		(start 56.614568 -112.221518)
		(end 56.614568 -112.587278)
		(width 0.14224)
		(layer "In2.Cu")
		(net "M_K_DQ<23>")
	)
	(segment
		(start 56.614568 -116.122958)
		(end 56.614568 -116.488718)
		(width 0.14224)
		(layer "In2.Cu")
		(net "M_K_DQ<23>")
	)
	(segment
		(start 56.614568 -115.188238)
		(end 56.756808 -115.330478)
		(width 0.14224)
		(layer "In2.Cu")
		(net "M_K_DQ<23>")
	)
	(segment
		(start 56.756808 -114.680238)
		(end 56.614568 -114.822478)
		(width 0.14224)
		(layer "In2.Cu")
		(net "M_K_DQ<23>")
	)
	(segment
		(start 56.210708 -133.276848)
		(end 56.210708 -133.550152)
		(width 0.14224)
		(layer "In2.Cu")
		(net "M_K_DQ<23>")
	)
	(segment
		(start 57.681368 -116.773198)
		(end 57.681368 -117.6528)
		(width 0.14224)
		(layer "In2.Cu")
		(net "M_K_DQ<23>")
	)
	(segment
		(start 55.115968 -126.5428)
		(end 56.055768 -127.4826)
		(width 0.14224)
		(layer "In2.Cu")
		(net "M_K_DQ<23>")
	)
	(segment
		(start 57.554368 -129.0828)
		(end 57.252108 -129.38506)
		(width 0.14224)
		(layer "In2.Cu")
		(net "M_K_DQ<23>")
	)
	(segment
		(start 56.467756 -133.0198)
		(end 56.210708 -133.276848)
		(width 0.14224)
		(layer "In2.Cu")
		(net "M_K_DQ<23>")
	)
	(segment
		(start 65.783206 -97.068132)
		(end 65.558416 -97.292922)
		(width 0.0889)
		(layer "In2.Cu")
		(net "M_K_DQ<23>")
	)
	(segment
		(start 69.523864 -95.309436)
		(end 69.408294 -95.425006)
		(width 0.0889)
		(layer "In2.Cu")
		(net "M_K_DQ<23>")
	)
	(segment
		(start 57.681368 -110.636558)
		(end 57.539128 -110.778798)
		(width 0.14224)
		(layer "In2.Cu")
		(net "M_K_DQ<23>")
	)
	(segment
		(start 65.558416 -97.292922)
		(end 65.558416 -97.614232)
		(width 0.0889)
		(layer "In2.Cu")
		(net "M_K_DQ<23>")
	)
	(segment
		(start 56.614568 -112.587278)
		(end 56.756808 -112.729518)
		(width 0.14224)
		(layer "In2.Cu")
		(net "M_K_DQ<23>")
	)
	(segment
		(start 56.756808 -114.029998)
		(end 57.539128 -114.029998)
		(width 0.14224)
		(layer "In2.Cu")
		(net "M_K_DQ<23>")
	)
	(segment
		(start 56.756808 -111.429038)
		(end 57.539128 -111.429038)
		(width 0.14224)
		(layer "In2.Cu")
		(net "M_K_DQ<23>")
	)
	(segment
		(start 56.899556 -137.67054)
		(end 56.899556 -136.7028)
		(width 0.1651)
		(layer "F.Cu")
		(net "M_K_DQ<22>")
	)
	(segment
		(start 57.031636 -136.57072)
		(end 57.031636 -136.35228)
		(width 0.1651)
		(layer "F.Cu")
		(net "M_K_DQ<22>")
	)
	(segment
		(start 72.900286 -96.20504)
		(end 72.328786 -96.20504)
		(width 0.1651)
		(layer "F.Cu")
		(net "M_K_DQ<22>")
	)
	(segment
		(start 57.031636 -136.35228)
		(end 56.899556 -136.2202)
		(width 0.1651)
		(layer "F.Cu")
		(net "M_K_DQ<22>")
	)
	(segment
		(start 56.899556 -136.7028)
		(end 57.031636 -136.57072)
		(width 0.1651)
		(layer "F.Cu")
		(net "M_K_DQ<22>")
	)
	(segment
		(start 56.899556 -136.2202)
		(end 56.899556 -135.915654)
		(width 0.1651)
		(layer "F.Cu")
		(net "M_K_DQ<22>")
	)
	(segment
		(start 56.899556 -135.915654)
		(end 56.899302 -135.9154)
		(width 0.1651)
		(layer "F.Cu")
		(net "M_K_DQ<22>")
	)
	(via
		(at 56.049418 -131.612894)
		(size 0.508)
		(drill 0.254)
		(layers "F.Cu" "B.Cu")
		(net "M_K_DQ<22>")
	)
	(via
		(at 56.899302 -135.9154)
		(size 0.508)
		(drill 0.254)
		(layers "F.Cu" "B.Cu")
		(net "M_K_DQ<22>")
	)
	(via
		(at 72.328786 -96.20504)
		(size 0.508)
		(drill 0.254)
		(layers "F.Cu" "B.Cu")
		(net "M_K_DQ<22>")
	)
	(segment
		(start 56.049418 -132.876036)
		(end 56.049418 -131.612894)
		(width 0.1651)
		(layer "B.Cu")
		(net "M_K_DQ<22>")
	)
	(segment
		(start 56.049418 -131.612894)
		(end 55.616348 -132.045964)
		(width 0.14224)
		(layer "In2.Cu")
		(net "M_K_DQ<22>")
	)
	(segment
		(start 55.776368 -110.8964)
		(end 56.081168 -111.2012)
		(width 0.14224)
		(layer "In2.Cu")
		(net "M_K_DQ<22>")
	)
	(segment
		(start 56.538368 -129.3368)
		(end 56.538368 -129.811018)
		(width 0.14224)
		(layer "In2.Cu")
		(net "M_K_DQ<22>")
	)
	(segment
		(start 55.877968 -115.8494)
		(end 55.471568 -115.8494)
		(width 0.14224)
		(layer "In2.Cu")
		(net "M_K_DQ<22>")
	)
	(segment
		(start 72.328786 -96.20504)
		(end 71.83374 -95.539052)
		(width 0.0889)
		(layer "In2.Cu")
		(net "M_K_DQ<22>")
	)
	(segment
		(start 66.788792 -95.235014)
		(end 65.593214 -96.430592)
		(width 0.0889)
		(layer "In2.Cu")
		(net "M_K_DQ<22>")
	)
	(segment
		(start 55.471568 -115.8494)
		(end 55.268368 -115.6462)
		(width 0.14224)
		(layer "In2.Cu")
		(net "M_K_DQ<22>")
	)
	(segment
		(start 65.593214 -96.989392)
		(end 65.451736 -97.13087)
		(width 0.0889)
		(layer "In2.Cu")
		(net "M_K_DQ<22>")
	)
	(segment
		(start 59.230768 -103.025702)
		(end 59.230768 -105.850944)
		(width 0.14224)
		(layer "In2.Cu")
		(net "M_K_DQ<22>")
	)
	(segment
		(start 54.684168 -113.2586)
		(end 54.480968 -113.4618)
		(width 0.14224)
		(layer "In2.Cu")
		(net "M_K_DQ<22>")
	)
	(segment
		(start 56.538368 -129.811018)
		(end 55.674768 -130.674618)
		(width 0.14224)
		(layer "In2.Cu")
		(net "M_K_DQ<22>")
	)
	(segment
		(start 65.451736 -97.13087)
		(end 65.1256 -97.13087)
		(width 0.0889)
		(layer "In2.Cu")
		(net "M_K_DQ<22>")
	)
	(segment
		(start 55.268368 -113.4618)
		(end 55.065168 -113.2586)
		(width 0.14224)
		(layer "In2.Cu")
		(net "M_K_DQ<22>")
	)
	(segment
		(start 56.081168 -111.2012)
		(end 56.081168 -115.6462)
		(width 0.14224)
		(layer "In2.Cu")
		(net "M_K_DQ<22>")
	)
	(segment
		(start 55.674768 -131.238244)
		(end 56.049418 -131.612894)
		(width 0.14224)
		(layer "In2.Cu")
		(net "M_K_DQ<22>")
	)
	(segment
		(start 55.776368 -110.5662)
		(end 55.776368 -110.8964)
		(width 0.14224)
		(layer "In2.Cu")
		(net "M_K_DQ<22>")
	)
	(segment
		(start 69.927216 -95.118936)
		(end 69.44487 -95.118936)
		(width 0.0889)
		(layer "In2.Cu")
		(net "M_K_DQ<22>")
	)
	(segment
		(start 70.626732 -94.81439)
		(end 70.59676 -94.81439)
		(width 0.0889)
		(layer "In2.Cu")
		(net "M_K_DQ<22>")
	)
	(segment
		(start 55.065168 -113.2586)
		(end 54.684168 -113.2586)
		(width 0.14224)
		(layer "In2.Cu")
		(net "M_K_DQ<22>")
	)
	(segment
		(start 54.480968 -113.4618)
		(end 54.480968 -126.821946)
		(width 0.14224)
		(layer "In2.Cu")
		(net "M_K_DQ<22>")
	)
	(segment
		(start 56.081168 -110.2614)
		(end 55.776368 -110.5662)
		(width 0.14224)
		(layer "In2.Cu")
		(net "M_K_DQ<22>")
	)
	(segment
		(start 56.817768 -129.0574)
		(end 56.538368 -129.3368)
		(width 0.14224)
		(layer "In2.Cu")
		(net "M_K_DQ<22>")
	)
	(segment
		(start 71.481442 -95.309436)
		(end 71.448676 -95.309436)
		(width 0.0889)
		(layer "In2.Cu")
		(net "M_K_DQ<22>")
	)
	(segment
		(start 69.44487 -95.118936)
		(end 69.328792 -95.235014)
		(width 0.0889)
		(layer "In2.Cu")
		(net "M_K_DQ<22>")
	)
	(segment
		(start 54.480968 -126.821946)
		(end 56.081422 -128.4224)
		(width 0.14224)
		(layer "In2.Cu")
		(net "M_K_DQ<22>")
	)
	(segment
		(start 56.817768 -128.6002)
		(end 56.817768 -129.0574)
		(width 0.14224)
		(layer "In2.Cu")
		(net "M_K_DQ<22>")
	)
	(segment
		(start 55.616348 -132.045964)
		(end 55.616348 -134.632446)
		(width 0.14224)
		(layer "In2.Cu")
		(net "M_K_DQ<22>")
	)
	(segment
		(start 71.83374 -95.539052)
		(end 71.816976 -95.509588)
		(width 0.0889)
		(layer "In2.Cu")
		(net "M_K_DQ<22>")
	)
	(segment
		(start 56.081422 -128.4224)
		(end 56.639968 -128.4224)
		(width 0.14224)
		(layer "In2.Cu")
		(net "M_K_DQ<22>")
	)
	(segment
		(start 56.639968 -128.4224)
		(end 56.817768 -128.6002)
		(width 0.14224)
		(layer "In2.Cu")
		(net "M_K_DQ<22>")
	)
	(segment
		(start 65.593214 -96.430592)
		(end 65.593214 -96.989392)
		(width 0.0889)
		(layer "In2.Cu")
		(net "M_K_DQ<22>")
	)
	(segment
		(start 55.616348 -134.632446)
		(end 56.899302 -135.9154)
		(width 0.14224)
		(layer "In2.Cu")
		(net "M_K_DQ<22>")
	)
	(segment
		(start 70.265036 -95.014288)
		(end 69.927216 -95.118936)
		(width 0.0889)
		(layer "In2.Cu")
		(net "M_K_DQ<22>")
	)
	(segment
		(start 56.081168 -115.6462)
		(end 55.877968 -115.8494)
		(width 0.14224)
		(layer "In2.Cu")
		(net "M_K_DQ<22>")
	)
	(segment
		(start 55.268368 -115.6462)
		(end 55.268368 -113.4618)
		(width 0.14224)
		(layer "In2.Cu")
		(net "M_K_DQ<22>")
	)
	(segment
		(start 65.1256 -97.13087)
		(end 59.230768 -103.025702)
		(width 0.14224)
		(layer "In2.Cu")
		(net "M_K_DQ<22>")
	)
	(segment
		(start 55.674768 -130.674618)
		(end 55.674768 -131.238244)
		(width 0.14224)
		(layer "In2.Cu")
		(net "M_K_DQ<22>")
	)
	(segment
		(start 56.081168 -109.000544)
		(end 56.081168 -110.2614)
		(width 0.14224)
		(layer "In2.Cu")
		(net "M_K_DQ<22>")
	)
	(segment
		(start 69.328792 -95.235014)
		(end 66.788792 -95.235014)
		(width 0.0889)
		(layer "In2.Cu")
		(net "M_K_DQ<22>")
	)
	(segment
		(start 59.230768 -105.850944)
		(end 56.081168 -109.000544)
		(width 0.14224)
		(layer "In2.Cu")
		(net "M_K_DQ<22>")
	)
	(arc
		(start 71.816976 -95.509588)
		(mid 71.675293 -95.365784)
		(end 71.481442 -95.309436)
		(width 0.0889)
		(layer "In2.Cu")
		(net "M_K_DQ<22>")
	)
	(arc
		(start 70.59676 -94.81439)
		(mid 70.405118 -94.871556)
		(end 70.265036 -95.014288)
		(width 0.0889)
		(layer "In2.Cu")
		(net "M_K_DQ<22>")
	)
	(arc
		(start 70.958456 -95.014288)
		(mid 70.818377 -94.871552)
		(end 70.626732 -94.81439)
		(width 0.0889)
		(layer "In2.Cu")
		(net "M_K_DQ<22>")
	)
	(arc
		(start 71.448676 -95.309436)
		(mid 71.165459 -95.225155)
		(end 70.958456 -95.014288)
		(width 0.0889)
		(layer "In2.Cu")
		(net "M_K_DQ<22>")
	)
	(segment
		(start 72.900286 -93.23324)
		(end 72.328786 -93.23324)
		(width 0.1651)
		(layer "F.Cu")
		(net "M_K_DQ<21>")
	)
	(segment
		(start 50.099468 -133.0706)
		(end 50.099468 -134.340346)
		(width 0.1651)
		(layer "F.Cu")
		(net "M_K_DQ<21>")
	)
	(via
		(at 50.099468 -134.340346)
		(size 0.508)
		(drill 0.254)
		(layers "F.Cu" "B.Cu")
		(net "M_K_DQ<21>")
	)
	(via
		(at 50.873152 -130.330956)
		(size 0.508)
		(drill 0.254)
		(layers "F.Cu" "B.Cu")
		(net "M_K_DQ<21>")
	)
	(via
		(at 72.328786 -93.23324)
		(size 0.508)
		(drill 0.254)
		(layers "F.Cu" "B.Cu")
		(net "M_K_DQ<21>")
	)
	(segment
		(start 50.949352 -130.254756)
		(end 50.873152 -130.330956)
		(width 0.1651)
		(layer "B.Cu")
		(net "M_K_DQ<21>")
	)
	(segment
		(start 50.949352 -128.276096)
		(end 50.949352 -130.254756)
		(width 0.1651)
		(layer "B.Cu")
		(net "M_K_DQ<21>")
	)
	(segment
		(start 67.108324 -91.297506)
		(end 66.869056 -91.536774)
		(width 0.0889)
		(layer "In2.Cu")
		(net "M_K_DQ<21>")
	)
	(segment
		(start 49.746408 -127.323088)
		(end 50.452528 -127.323088)
		(width 0.14224)
		(layer "In2.Cu")
		(net "M_K_DQ<21>")
	)
	(segment
		(start 50.371756 -134.340346)
		(end 50.099468 -134.340346)
		(width 0.14224)
		(layer "In2.Cu")
		(net "M_K_DQ<21>")
	)
	(segment
		(start 50.873152 -129.030984)
		(end 50.873152 -130.330956)
		(width 0.14224)
		(layer "In2.Cu")
		(net "M_K_DQ<21>")
	)
	(segment
		(start 69.764402 -91.347036)
		(end 69.528182 -91.347036)
		(width 0.0889)
		(layer "In2.Cu")
		(net "M_K_DQ<21>")
	)
	(segment
		(start 50.498756 -132.791454)
		(end 50.498756 -133.146546)
		(width 0.14224)
		(layer "In2.Cu")
		(net "M_K_DQ<21>")
	)
	(segment
		(start 71.83374 -92.566998)
		(end 71.816976 -92.537788)
		(width 0.0889)
		(layer "In2.Cu")
		(net "M_K_DQ<21>")
	)
	(segment
		(start 50.549556 -131.927346)
		(end 50.260758 -132.216144)
		(width 0.14224)
		(layer "In2.Cu")
		(net "M_K_DQ<21>")
	)
	(segment
		(start 50.594768 -127.465328)
		(end 50.594768 -127.831088)
		(width 0.14224)
		(layer "In2.Cu")
		(net "M_K_DQ<21>")
	)
	(segment
		(start 70.626732 -91.84259)
		(end 70.593966 -91.84259)
		(width 0.0889)
		(layer "In2.Cu")
		(net "M_K_DQ<21>")
	)
	(segment
		(start 66.869056 -91.536774)
		(end 65.800478 -91.536774)
		(width 0.14224)
		(layer "In2.Cu")
		(net "M_K_DQ<21>")
	)
	(segment
		(start 50.465736 -128.623568)
		(end 50.873152 -129.030984)
		(width 0.14224)
		(layer "In2.Cu")
		(net "M_K_DQ<21>")
	)
	(segment
		(start 69.478652 -91.297506)
		(end 67.108324 -91.297506)
		(width 0.0889)
		(layer "In2.Cu")
		(net "M_K_DQ<21>")
	)
	(segment
		(start 49.654968 -128.115568)
		(end 49.654968 -128.481328)
		(width 0.14224)
		(layer "In2.Cu")
		(net "M_K_DQ<21>")
	)
	(segment
		(start 50.452528 -127.323088)
		(end 50.594768 -127.465328)
		(width 0.14224)
		(layer "In2.Cu")
		(net "M_K_DQ<21>")
	)
	(segment
		(start 71.481442 -92.337636)
		(end 71.448676 -92.337636)
		(width 0.0889)
		(layer "In2.Cu")
		(net "M_K_DQ<21>")
	)
	(segment
		(start 49.604168 -109.595412)
		(end 49.604168 -127.180848)
		(width 0.14224)
		(layer "In2.Cu")
		(net "M_K_DQ<21>")
	)
	(segment
		(start 50.498756 -133.146546)
		(end 50.260758 -133.384544)
		(width 0.14224)
		(layer "In2.Cu")
		(net "M_K_DQ<21>")
	)
	(segment
		(start 69.528182 -91.347036)
		(end 69.478652 -91.297506)
		(width 0.0889)
		(layer "In2.Cu")
		(net "M_K_DQ<21>")
	)
	(segment
		(start 49.604168 -127.180848)
		(end 49.746408 -127.323088)
		(width 0.14224)
		(layer "In2.Cu")
		(net "M_K_DQ<21>")
	)
	(segment
		(start 50.549556 -131.445)
		(end 50.549556 -131.927346)
		(width 0.14224)
		(layer "In2.Cu")
		(net "M_K_DQ<21>")
	)
	(segment
		(start 56.025288 -101.311964)
		(end 56.025288 -103.174292)
		(width 0.14224)
		(layer "In2.Cu")
		(net "M_K_DQ<21>")
	)
	(segment
		(start 50.422556 -130.7592)
		(end 50.422556 -131.318)
		(width 0.14224)
		(layer "In2.Cu")
		(net "M_K_DQ<21>")
	)
	(segment
		(start 50.873152 -130.330956)
		(end 50.8508 -130.330956)
		(width 0.14224)
		(layer "In2.Cu")
		(net "M_K_DQ<21>")
	)
	(segment
		(start 56.025288 -103.174292)
		(end 49.604168 -109.595412)
		(width 0.14224)
		(layer "In2.Cu")
		(net "M_K_DQ<21>")
	)
	(segment
		(start 49.797208 -127.973328)
		(end 49.654968 -128.115568)
		(width 0.14224)
		(layer "In2.Cu")
		(net "M_K_DQ<21>")
	)
	(segment
		(start 50.594768 -127.831088)
		(end 50.452528 -127.973328)
		(width 0.14224)
		(layer "In2.Cu")
		(net "M_K_DQ<21>")
	)
	(segment
		(start 50.260758 -132.216144)
		(end 50.260758 -132.553456)
		(width 0.14224)
		(layer "In2.Cu")
		(net "M_K_DQ<21>")
	)
	(segment
		(start 50.260758 -133.696456)
		(end 50.524156 -133.959854)
		(width 0.14224)
		(layer "In2.Cu")
		(net "M_K_DQ<21>")
	)
	(segment
		(start 72.328786 -93.23324)
		(end 71.83374 -92.566998)
		(width 0.0889)
		(layer "In2.Cu")
		(net "M_K_DQ<21>")
	)
	(segment
		(start 50.524156 -133.959854)
		(end 50.524156 -134.187946)
		(width 0.14224)
		(layer "In2.Cu")
		(net "M_K_DQ<21>")
	)
	(segment
		(start 50.524156 -134.187946)
		(end 50.371756 -134.340346)
		(width 0.14224)
		(layer "In2.Cu")
		(net "M_K_DQ<21>")
	)
	(segment
		(start 50.422556 -131.318)
		(end 50.549556 -131.445)
		(width 0.14224)
		(layer "In2.Cu")
		(net "M_K_DQ<21>")
	)
	(segment
		(start 65.800478 -91.536774)
		(end 56.025288 -101.311964)
		(width 0.14224)
		(layer "In2.Cu")
		(net "M_K_DQ<21>")
	)
	(segment
		(start 49.797208 -128.623568)
		(end 50.465736 -128.623568)
		(width 0.14224)
		(layer "In2.Cu")
		(net "M_K_DQ<21>")
	)
	(segment
		(start 50.260758 -133.384544)
		(end 50.260758 -133.696456)
		(width 0.14224)
		(layer "In2.Cu")
		(net "M_K_DQ<21>")
	)
	(segment
		(start 50.260758 -132.553456)
		(end 50.498756 -132.791454)
		(width 0.14224)
		(layer "In2.Cu")
		(net "M_K_DQ<21>")
	)
	(segment
		(start 49.654968 -128.481328)
		(end 49.797208 -128.623568)
		(width 0.14224)
		(layer "In2.Cu")
		(net "M_K_DQ<21>")
	)
	(segment
		(start 50.452528 -127.973328)
		(end 49.797208 -127.973328)
		(width 0.14224)
		(layer "In2.Cu")
		(net "M_K_DQ<21>")
	)
	(segment
		(start 50.8508 -130.330956)
		(end 50.422556 -130.7592)
		(width 0.14224)
		(layer "In2.Cu")
		(net "M_K_DQ<21>")
	)
	(arc
		(start 70.958456 -92.042488)
		(mid 70.818377 -91.899752)
		(end 70.626732 -91.84259)
		(width 0.0889)
		(layer "In2.Cu")
		(net "M_K_DQ<21>")
	)
	(arc
		(start 70.593966 -91.84259)
		(mid 70.308542 -91.759123)
		(end 70.099936 -91.547188)
		(width 0.0889)
		(layer "In2.Cu")
		(net "M_K_DQ<21>")
	)
	(arc
		(start 71.448676 -92.337636)
		(mid 71.165459 -92.253355)
		(end 70.958456 -92.042488)
		(width 0.0889)
		(layer "In2.Cu")
		(net "M_K_DQ<21>")
	)
	(arc
		(start 70.099936 -91.547188)
		(mid 69.958253 -91.403384)
		(end 69.764402 -91.347036)
		(width 0.0889)
		(layer "In2.Cu")
		(net "M_K_DQ<21>")
	)
	(arc
		(start 71.816976 -92.537788)
		(mid 71.675293 -92.393984)
		(end 71.481442 -92.337636)
		(width 0.0889)
		(layer "In2.Cu")
		(net "M_K_DQ<21>")
	)
	(segment
		(start 50.949352 -137.67054)
		(end 50.949352 -136.345168)
		(width 0.1651)
		(layer "F.Cu")
		(net "M_K_DQ<20>")
	)
	(segment
		(start 73.758806 -93.72854)
		(end 73.187306 -93.72854)
		(width 0.1651)
		(layer "F.Cu")
		(net "M_K_DQ<20>")
	)
	(segment
		(start 50.949352 -136.345168)
		(end 50.851308 -135.8138)
		(width 0.1651)
		(layer "F.Cu")
		(net "M_K_DQ<20>")
	)
	(via
		(at 73.187306 -93.72854)
		(size 0.508)
		(drill 0.254)
		(layers "F.Cu" "B.Cu")
		(net "M_K_DQ<20>")
	)
	(via
		(at 50.851308 -135.8138)
		(size 0.508)
		(drill 0.254)
		(layers "F.Cu" "B.Cu")
		(net "M_K_DQ<20>")
	)
	(via
		(at 50.099468 -131.611878)
		(size 0.508)
		(drill 0.254)
		(layers "F.Cu" "B.Cu")
		(net "M_K_DQ<20>")
	)
	(segment
		(start 50.099468 -132.876036)
		(end 50.099468 -131.611878)
		(width 0.1651)
		(layer "B.Cu")
		(net "M_K_DQ<20>")
	)
	(segment
		(start 50.099468 -131.611878)
		(end 50.099468 -131.787646)
		(width 0.14224)
		(layer "In2.Cu")
		(net "M_K_DQ<20>")
	)
	(segment
		(start 69.606414 -91.156536)
		(end 69.557392 -91.107514)
		(width 0.0889)
		(layer "In2.Cu")
		(net "M_K_DQ<20>")
	)
	(segment
		(start 48.969168 -109.3216)
		(end 48.969168 -128.275842)
		(width 0.14224)
		(layer "In2.Cu")
		(net "M_K_DQ<20>")
	)
	(segment
		(start 69.557392 -91.107514)
		(end 67.080384 -91.107514)
		(width 0.0889)
		(layer "In2.Cu")
		(net "M_K_DQ<20>")
	)
	(segment
		(start 55.546498 -101.11359)
		(end 55.546498 -102.74427)
		(width 0.14224)
		(layer "In2.Cu")
		(net "M_K_DQ<20>")
	)
	(segment
		(start 55.546498 -102.74427)
		(end 48.969168 -109.3216)
		(width 0.14224)
		(layer "In2.Cu")
		(net "M_K_DQ<20>")
	)
	(segment
		(start 49.824386 -135.03783)
		(end 50.600356 -135.8138)
		(width 0.14224)
		(layer "In2.Cu")
		(net "M_K_DQ<20>")
	)
	(segment
		(start 49.824386 -134.736078)
		(end 49.824386 -135.03783)
		(width 0.14224)
		(layer "In2.Cu")
		(net "M_K_DQ<20>")
	)
	(segment
		(start 49.666398 -134.57809)
		(end 49.824386 -134.736078)
		(width 0.14224)
		(layer "In2.Cu")
		(net "M_K_DQ<20>")
	)
	(segment
		(start 48.969168 -128.275842)
		(end 49.975262 -130.705098)
		(width 0.14224)
		(layer "In2.Cu")
		(net "M_K_DQ<20>")
	)
	(segment
		(start 50.099468 -131.787646)
		(end 49.666398 -132.220716)
		(width 0.14224)
		(layer "In2.Cu")
		(net "M_K_DQ<20>")
	)
	(segment
		(start 70.633336 -91.65209)
		(end 70.60057 -91.65209)
		(width 0.0889)
		(layer "In2.Cu")
		(net "M_K_DQ<20>")
	)
	(segment
		(start 49.666398 -132.220716)
		(end 49.666398 -134.57809)
		(width 0.14224)
		(layer "In2.Cu")
		(net "M_K_DQ<20>")
	)
	(segment
		(start 71.488046 -92.147136)
		(end 71.45528 -92.147136)
		(width 0.0889)
		(layer "In2.Cu")
		(net "M_K_DQ<20>")
	)
	(segment
		(start 65.771014 -90.889074)
		(end 55.546498 -101.11359)
		(width 0.14224)
		(layer "In2.Cu")
		(net "M_K_DQ<20>")
	)
	(segment
		(start 66.861944 -90.889074)
		(end 65.771014 -90.889074)
		(width 0.14224)
		(layer "In2.Cu")
		(net "M_K_DQ<20>")
	)
	(segment
		(start 69.771006 -91.156536)
		(end 69.606414 -91.156536)
		(width 0.0889)
		(layer "In2.Cu")
		(net "M_K_DQ<20>")
	)
	(segment
		(start 49.975262 -130.705098)
		(end 49.975262 -131.311904)
		(width 0.14224)
		(layer "In2.Cu")
		(net "M_K_DQ<20>")
	)
	(segment
		(start 67.080384 -91.107514)
		(end 66.861944 -90.889074)
		(width 0.0889)
		(layer "In2.Cu")
		(net "M_K_DQ<20>")
	)
	(segment
		(start 72.350376 -92.64269)
		(end 72.31761 -92.64269)
		(width 0.0889)
		(layer "In2.Cu")
		(net "M_K_DQ<20>")
	)
	(segment
		(start 50.600356 -135.8138)
		(end 50.851308 -135.8138)
		(width 0.14224)
		(layer "In2.Cu")
		(net "M_K_DQ<20>")
	)
	(segment
		(start 49.975262 -131.311904)
		(end 50.099468 -131.611878)
		(width 0.14224)
		(layer "In2.Cu")
		(net "M_K_DQ<20>")
	)
	(segment
		(start 73.187306 -93.72854)
		(end 72.840596 -92.937838)
		(width 0.0889)
		(layer "In2.Cu")
		(net "M_K_DQ<20>")
	)
	(arc
		(start 70.265036 -91.451938)
		(mid 70.056428 -91.240006)
		(end 69.771006 -91.156536)
		(width 0.0889)
		(layer "In2.Cu")
		(net "M_K_DQ<20>")
	)
	(arc
		(start 72.31761 -92.64269)
		(mid 72.12376 -92.58634)
		(end 71.982076 -92.442538)
		(width 0.0889)
		(layer "In2.Cu")
		(net "M_K_DQ<20>")
	)
	(arc
		(start 70.60057 -91.65209)
		(mid 70.40672 -91.59574)
		(end 70.265036 -91.451938)
		(width 0.0889)
		(layer "In2.Cu")
		(net "M_K_DQ<20>")
	)
	(arc
		(start 71.45528 -92.147136)
		(mid 71.263638 -92.08997)
		(end 71.123556 -91.947238)
		(width 0.0889)
		(layer "In2.Cu")
		(net "M_K_DQ<20>")
	)
	(arc
		(start 71.982076 -92.442538)
		(mid 71.773468 -92.230606)
		(end 71.488046 -92.147136)
		(width 0.0889)
		(layer "In2.Cu")
		(net "M_K_DQ<20>")
	)
	(arc
		(start 72.840596 -92.937838)
		(mid 72.633592 -92.726974)
		(end 72.350376 -92.64269)
		(width 0.0889)
		(layer "In2.Cu")
		(net "M_K_DQ<20>")
	)
	(arc
		(start 71.123556 -91.947238)
		(mid 70.916552 -91.736374)
		(end 70.633336 -91.65209)
		(width 0.0889)
		(layer "In2.Cu")
		(net "M_K_DQ<20>")
	)
	(segment
		(start 67.749166 -85.30844)
		(end 67.101466 -85.30844)
		(width 0.1651)
		(layer "F.Cu")
		(net "M_K_DQ<1>")
	)
	(segment
		(start 33.099502 -133.0706)
		(end 33.099502 -134.340346)
		(width 0.1651)
		(layer "F.Cu")
		(net "M_K_DQ<1>")
	)
	(via
		(at 67.101466 -85.30844)
		(size 0.508)
		(drill 0.254)
		(layers "F.Cu" "B.Cu")
		(net "M_K_DQ<1>")
	)
	(via
		(at 33.099502 -134.340346)
		(size 0.508)
		(drill 0.254)
		(layers "F.Cu" "B.Cu")
		(net "M_K_DQ<1>")
	)
	(via
		(at 33.771586 -130.330956)
		(size 0.508)
		(drill 0.254)
		(layers "F.Cu" "B.Cu")
		(net "M_K_DQ<1>")
	)
	(segment
		(start 33.949386 -128.276096)
		(end 33.949386 -129.649982)
		(width 0.1651)
		(layer "B.Cu")
		(net "M_K_DQ<1>")
	)
	(segment
		(start 33.771586 -129.827782)
		(end 33.771586 -130.330956)
		(width 0.1651)
		(layer "B.Cu")
		(net "M_K_DQ<1>")
	)
	(segment
		(start 33.949386 -129.649982)
		(end 33.771586 -129.827782)
		(width 0.1651)
		(layer "B.Cu")
		(net "M_K_DQ<1>")
	)
	(segment
		(start 34.66211 -124.112274)
		(end 34.81705 -124.267214)
		(width 0.14224)
		(layer "In2.Cu")
		(net "M_K_DQ<1>")
	)
	(segment
		(start 33.348422 -134.340346)
		(end 33.099502 -134.340346)
		(width 0.14224)
		(layer "In2.Cu")
		(net "M_K_DQ<1>")
	)
	(segment
		(start 34.655506 -127.426974)
		(end 34.221674 -127.426974)
		(width 0.14224)
		(layer "In2.Cu")
		(net "M_K_DQ<1>")
	)
	(segment
		(start 37.869114 -113.0554)
		(end 34.698686 -116.225828)
		(width 0.14224)
		(layer "In2.Cu")
		(net "M_K_DQ<1>")
	)
	(segment
		(start 34.810446 -123.314714)
		(end 34.675826 -123.449334)
		(width 0.14224)
		(layer "In2.Cu")
		(net "M_K_DQ<1>")
	)
	(segment
		(start 34.877756 -125.946154)
		(end 34.722816 -126.101094)
		(width 0.14224)
		(layer "In2.Cu")
		(net "M_K_DQ<1>")
	)
	(segment
		(start 33.260792 -132.114544)
		(end 33.260792 -132.475224)
		(width 0.14224)
		(layer "In2.Cu")
		(net "M_K_DQ<1>")
	)
	(segment
		(start 34.22142 -126.764034)
		(end 34.655506 -126.764034)
		(width 0.14224)
		(layer "In2.Cu")
		(net "M_K_DQ<1>")
	)
	(segment
		(start 34.22142 -126.101094)
		(end 34.06648 -126.256034)
		(width 0.14224)
		(layer "In2.Cu")
		(net "M_K_DQ<1>")
	)
	(segment
		(start 34.113724 -123.943872)
		(end 34.282126 -124.112274)
		(width 0.14224)
		(layer "In2.Cu")
		(net "M_K_DQ<1>")
	)
	(segment
		(start 33.260792 -132.475224)
		(end 33.475168 -132.6896)
		(width 0.14224)
		(layer "In2.Cu")
		(net "M_K_DQ<1>")
	)
	(segment
		(start 34.25952 -128.12776)
		(end 34.25952 -129.843022)
		(width 0.14224)
		(layer "In2.Cu")
		(net "M_K_DQ<1>")
	)
	(segment
		(start 34.722816 -125.438154)
		(end 34.877756 -125.593094)
		(width 0.14224)
		(layer "In2.Cu")
		(net "M_K_DQ<1>")
	)
	(segment
		(start 34.261806 -122.123454)
		(end 34.106866 -122.278394)
		(width 0.14224)
		(layer "In2.Cu")
		(net "M_K_DQ<1>")
	)
	(segment
		(start 34.113724 -123.590812)
		(end 34.113724 -123.943872)
		(width 0.14224)
		(layer "In2.Cu")
		(net "M_K_DQ<1>")
	)
	(segment
		(start 34.675826 -123.449334)
		(end 34.255202 -123.449334)
		(width 0.14224)
		(layer "In2.Cu")
		(net "M_K_DQ<1>")
	)
	(segment
		(start 33.260792 -133.335776)
		(end 33.260792 -133.643624)
		(width 0.14224)
		(layer "In2.Cu")
		(net "M_K_DQ<1>")
	)
	(segment
		(start 51.280568 -100.583746)
		(end 38.808914 -113.0554)
		(width 0.14224)
		(layer "In2.Cu")
		(net "M_K_DQ<1>")
	)
	(segment
		(start 33.32099 -130.7592)
		(end 33.32099 -131.188968)
		(width 0.14224)
		(layer "In2.Cu")
		(net "M_K_DQ<1>")
	)
	(segment
		(start 33.260792 -133.643624)
		(end 33.500568 -133.8834)
		(width 0.14224)
		(layer "In2.Cu")
		(net "M_K_DQ<1>")
	)
	(segment
		(start 34.810446 -127.272034)
		(end 34.655506 -127.426974)
		(width 0.14224)
		(layer "In2.Cu")
		(net "M_K_DQ<1>")
	)
	(segment
		(start 33.500568 -134.1882)
		(end 33.348422 -134.340346)
		(width 0.14224)
		(layer "In2.Cu")
		(net "M_K_DQ<1>")
	)
	(segment
		(start 34.073338 -124.930154)
		(end 34.073338 -125.283214)
		(width 0.14224)
		(layer "In2.Cu")
		(net "M_K_DQ<1>")
	)
	(segment
		(start 33.475168 -133.1214)
		(end 33.260792 -133.335776)
		(width 0.14224)
		(layer "In2.Cu")
		(net "M_K_DQ<1>")
	)
	(segment
		(start 34.228278 -124.775214)
		(end 34.073338 -124.930154)
		(width 0.14224)
		(layer "In2.Cu")
		(net "M_K_DQ<1>")
	)
	(segment
		(start 33.32099 -131.188968)
		(end 33.551368 -131.419346)
		(width 0.14224)
		(layer "In2.Cu")
		(net "M_K_DQ<1>")
	)
	(segment
		(start 34.66211 -124.775214)
		(end 34.228278 -124.775214)
		(width 0.14224)
		(layer "In2.Cu")
		(net "M_K_DQ<1>")
	)
	(segment
		(start 34.698686 -121.938796)
		(end 34.514028 -122.123454)
		(width 0.14224)
		(layer "In2.Cu")
		(net "M_K_DQ<1>")
	)
	(segment
		(start 65.863724 -85.683344)
		(end 64.680846 -85.683344)
		(width 0.14224)
		(layer "In2.Cu")
		(net "M_K_DQ<1>")
	)
	(segment
		(start 33.500568 -133.8834)
		(end 33.500568 -134.1882)
		(width 0.14224)
		(layer "In2.Cu")
		(net "M_K_DQ<1>")
	)
	(segment
		(start 64.680846 -85.683344)
		(end 51.280568 -99.083622)
		(width 0.14224)
		(layer "In2.Cu")
		(net "M_K_DQ<1>")
	)
	(segment
		(start 66.726562 -85.683344)
		(end 65.863724 -85.683344)
		(width 0.0889)
		(layer "In2.Cu")
		(net "M_K_DQ<1>")
	)
	(segment
		(start 34.25952 -129.843022)
		(end 33.771586 -130.330956)
		(width 0.14224)
		(layer "In2.Cu")
		(net "M_K_DQ<1>")
	)
	(segment
		(start 34.81705 -124.267214)
		(end 34.81705 -124.620274)
		(width 0.14224)
		(layer "In2.Cu")
		(net "M_K_DQ<1>")
	)
	(segment
		(start 33.551368 -131.823968)
		(end 33.260792 -132.114544)
		(width 0.14224)
		(layer "In2.Cu")
		(net "M_K_DQ<1>")
	)
	(segment
		(start 34.877756 -125.593094)
		(end 34.877756 -125.946154)
		(width 0.14224)
		(layer "In2.Cu")
		(net "M_K_DQ<1>")
	)
	(segment
		(start 51.280568 -99.083622)
		(end 51.280568 -100.583746)
		(width 0.14224)
		(layer "In2.Cu")
		(net "M_K_DQ<1>")
	)
	(segment
		(start 34.066734 -127.934974)
		(end 34.25952 -128.12776)
		(width 0.14224)
		(layer "In2.Cu")
		(net "M_K_DQ<1>")
	)
	(segment
		(start 34.073338 -125.283214)
		(end 34.228278 -125.438154)
		(width 0.14224)
		(layer "In2.Cu")
		(net "M_K_DQ<1>")
	)
	(segment
		(start 34.698686 -116.225828)
		(end 34.698686 -121.938796)
		(width 0.14224)
		(layer "In2.Cu")
		(net "M_K_DQ<1>")
	)
	(segment
		(start 33.749234 -130.330956)
		(end 33.32099 -130.7592)
		(width 0.14224)
		(layer "In2.Cu")
		(net "M_K_DQ<1>")
	)
	(segment
		(start 34.261806 -122.786394)
		(end 34.635186 -122.786394)
		(width 0.14224)
		(layer "In2.Cu")
		(net "M_K_DQ<1>")
	)
	(segment
		(start 34.635186 -122.786394)
		(end 34.810446 -122.961654)
		(width 0.14224)
		(layer "In2.Cu")
		(net "M_K_DQ<1>")
	)
	(segment
		(start 34.106866 -122.631454)
		(end 34.261806 -122.786394)
		(width 0.14224)
		(layer "In2.Cu")
		(net "M_K_DQ<1>")
	)
	(segment
		(start 34.06648 -126.256034)
		(end 34.06648 -126.609094)
		(width 0.14224)
		(layer "In2.Cu")
		(net "M_K_DQ<1>")
	)
	(segment
		(start 34.066734 -127.581914)
		(end 34.066734 -127.934974)
		(width 0.14224)
		(layer "In2.Cu")
		(net "M_K_DQ<1>")
	)
	(segment
		(start 38.808914 -113.0554)
		(end 37.869114 -113.0554)
		(width 0.14224)
		(layer "In2.Cu")
		(net "M_K_DQ<1>")
	)
	(segment
		(start 34.655506 -126.764034)
		(end 34.810446 -126.918974)
		(width 0.14224)
		(layer "In2.Cu")
		(net "M_K_DQ<1>")
	)
	(segment
		(start 34.282126 -124.112274)
		(end 34.66211 -124.112274)
		(width 0.14224)
		(layer "In2.Cu")
		(net "M_K_DQ<1>")
	)
	(segment
		(start 33.551368 -131.419346)
		(end 33.551368 -131.823968)
		(width 0.14224)
		(layer "In2.Cu")
		(net "M_K_DQ<1>")
	)
	(segment
		(start 34.810446 -126.918974)
		(end 34.810446 -127.272034)
		(width 0.14224)
		(layer "In2.Cu")
		(net "M_K_DQ<1>")
	)
	(segment
		(start 34.81705 -124.620274)
		(end 34.66211 -124.775214)
		(width 0.14224)
		(layer "In2.Cu")
		(net "M_K_DQ<1>")
	)
	(segment
		(start 34.06648 -126.609094)
		(end 34.22142 -126.764034)
		(width 0.14224)
		(layer "In2.Cu")
		(net "M_K_DQ<1>")
	)
	(segment
		(start 34.228278 -125.438154)
		(end 34.722816 -125.438154)
		(width 0.14224)
		(layer "In2.Cu")
		(net "M_K_DQ<1>")
	)
	(segment
		(start 34.810446 -122.961654)
		(end 34.810446 -123.314714)
		(width 0.14224)
		(layer "In2.Cu")
		(net "M_K_DQ<1>")
	)
	(segment
		(start 34.255202 -123.449334)
		(end 34.113724 -123.590812)
		(width 0.14224)
		(layer "In2.Cu")
		(net "M_K_DQ<1>")
	)
	(segment
		(start 34.221674 -127.426974)
		(end 34.066734 -127.581914)
		(width 0.14224)
		(layer "In2.Cu")
		(net "M_K_DQ<1>")
	)
	(segment
		(start 67.101466 -85.30844)
		(end 66.726562 -85.683344)
		(width 0.0889)
		(layer "In2.Cu")
		(net "M_K_DQ<1>")
	)
	(segment
		(start 34.106866 -122.278394)
		(end 34.106866 -122.631454)
		(width 0.14224)
		(layer "In2.Cu")
		(net "M_K_DQ<1>")
	)
	(segment
		(start 33.475168 -132.6896)
		(end 33.475168 -133.1214)
		(width 0.14224)
		(layer "In2.Cu")
		(net "M_K_DQ<1>")
	)
	(segment
		(start 34.514028 -122.123454)
		(end 34.261806 -122.123454)
		(width 0.14224)
		(layer "In2.Cu")
		(net "M_K_DQ<1>")
	)
	(segment
		(start 33.771586 -130.330956)
		(end 33.749234 -130.330956)
		(width 0.14224)
		(layer "In2.Cu")
		(net "M_K_DQ<1>")
	)
	(segment
		(start 34.722816 -126.101094)
		(end 34.22142 -126.101094)
		(width 0.14224)
		(layer "In2.Cu")
		(net "M_K_DQ<1>")
	)
	(segment
		(start 57.74944 -133.0706)
		(end 57.74944 -134.340346)
		(width 0.1651)
		(layer "F.Cu")
		(net "M_K_DQ<19>")
	)
	(segment
		(start 71.183246 -96.20504)
		(end 70.611746 -96.20504)
		(width 0.1651)
		(layer "F.Cu")
		(net "M_K_DQ<19>")
	)
	(via
		(at 70.611746 -96.20504)
		(size 0.508)
		(drill 0.254)
		(layers "F.Cu" "B.Cu")
		(net "M_K_DQ<19>")
	)
	(via
		(at 58.599324 -130.330956)
		(size 0.508)
		(drill 0.254)
		(layers "F.Cu" "B.Cu")
		(net "M_K_DQ<19>")
	)
	(via
		(at 57.74944 -134.340346)
		(size 0.508)
		(drill 0.254)
		(layers "F.Cu" "B.Cu")
		(net "M_K_DQ<19>")
	)
	(segment
		(start 58.599324 -128.276096)
		(end 58.599324 -130.330956)
		(width 0.1651)
		(layer "B.Cu")
		(net "M_K_DQ<19>")
	)
	(segment
		(start 58.599578 -128.276096)
		(end 58.599324 -128.276096)
		(width 0.1651)
		(layer "B.Cu")
		(net "M_K_DQ<19>")
	)
	(segment
		(start 69.02069 -96.187006)
		(end 67.318128 -96.187006)
		(width 0.0889)
		(layer "In2.Cu")
		(net "M_K_DQ<19>")
	)
	(segment
		(start 57.671208 -119.668798)
		(end 58.504328 -119.668798)
		(width 0.14224)
		(layer "In2.Cu")
		(net "M_K_DQ<19>")
	)
	(segment
		(start 57.91073 -133.276848)
		(end 57.91073 -133.550152)
		(width 0.14224)
		(layer "In2.Cu")
		(net "M_K_DQ<19>")
	)
	(segment
		(start 58.504328 -123.570238)
		(end 58.646568 -123.712478)
		(width 0.14224)
		(layer "In2.Cu")
		(net "M_K_DQ<19>")
	)
	(segment
		(start 57.671208 -119.018558)
		(end 57.528968 -119.160798)
		(width 0.14224)
		(layer "In2.Cu")
		(net "M_K_DQ<19>")
	)
	(segment
		(start 57.528968 -123.062238)
		(end 57.528968 -123.427998)
		(width 0.14224)
		(layer "In2.Cu")
		(net "M_K_DQ<19>")
	)
	(segment
		(start 57.528968 -122.127518)
		(end 57.671208 -122.269758)
		(width 0.14224)
		(layer "In2.Cu")
		(net "M_K_DQ<19>")
	)
	(segment
		(start 59.285632 -108.774738)
		(end 59.066684 -108.774738)
		(width 0.14224)
		(layer "In2.Cu")
		(net "M_K_DQ<19>")
	)
	(segment
		(start 61.010038 -107.050332)
		(end 61.285882 -107.32643)
		(width 0.14224)
		(layer "In2.Cu")
		(net "M_K_DQ<19>")
	)
	(segment
		(start 59.561476 -109.050836)
		(end 59.285632 -108.774738)
		(width 0.14224)
		(layer "In2.Cu")
		(net "M_K_DQ<19>")
	)
	(segment
		(start 57.528968 -120.461278)
		(end 57.528968 -120.827038)
		(width 0.14224)
		(layer "In2.Cu")
		(net "M_K_DQ<19>")
	)
	(segment
		(start 57.671208 -121.619518)
		(end 57.528968 -121.761758)
		(width 0.14224)
		(layer "In2.Cu")
		(net "M_K_DQ<19>")
	)
	(segment
		(start 57.671208 -122.919998)
		(end 57.528968 -123.062238)
		(width 0.14224)
		(layer "In2.Cu")
		(net "M_K_DQ<19>")
	)
	(segment
		(start 58.504328 -119.018558)
		(end 57.671208 -119.018558)
		(width 0.14224)
		(layer "In2.Cu")
		(net "M_K_DQ<19>")
	)
	(segment
		(start 69.13372 -96.300036)
		(end 69.02069 -96.187006)
		(width 0.0889)
		(layer "In2.Cu")
		(net "M_K_DQ<19>")
	)
	(segment
		(start 57.671208 -125.520958)
		(end 57.528968 -125.663198)
		(width 0.14224)
		(layer "In2.Cu")
		(net "M_K_DQ<19>")
	)
	(segment
		(start 65.213992 -99.466146)
		(end 65.213992 -99.791012)
		(width 0.0889)
		(layer "In2.Cu")
		(net "M_K_DQ<19>")
	)
	(segment
		(start 58.646568 -109.194854)
		(end 58.646568 -118.876318)
		(width 0.14224)
		(layer "In2.Cu")
		(net "M_K_DQ<19>")
	)
	(segment
		(start 58.199528 -133.83895)
		(end 58.199528 -134.162546)
		(width 0.14224)
		(layer "In2.Cu")
		(net "M_K_DQ<19>")
	)
	(segment
		(start 58.148728 -131.188968)
		(end 58.193178 -131.233418)
		(width 0.14224)
		(layer "In2.Cu")
		(net "M_K_DQ<19>")
	)
	(segment
		(start 58.504328 -122.269758)
		(end 58.646568 -122.411998)
		(width 0.14224)
		(layer "In2.Cu")
		(net "M_K_DQ<19>")
	)
	(segment
		(start 60.71108 -107.901232)
		(end 60.435236 -107.625134)
		(width 0.14224)
		(layer "In2.Cu")
		(net "M_K_DQ<19>")
	)
	(segment
		(start 57.671208 -124.870718)
		(end 58.504328 -124.870718)
		(width 0.14224)
		(layer "In2.Cu")
		(net "M_K_DQ<19>")
	)
	(segment
		(start 57.528968 -121.761758)
		(end 57.528968 -122.127518)
		(width 0.14224)
		(layer "In2.Cu")
		(net "M_K_DQ<19>")
	)
	(segment
		(start 57.528968 -119.526558)
		(end 57.671208 -119.668798)
		(width 0.14224)
		(layer "In2.Cu")
		(net "M_K_DQ<19>")
	)
	(segment
		(start 61.181996 -106.659426)
		(end 61.010038 -106.831384)
		(width 0.14224)
		(layer "In2.Cu")
		(net "M_K_DQ<19>")
	)
	(segment
		(start 57.528968 -124.728478)
		(end 57.671208 -124.870718)
		(width 0.14224)
		(layer "In2.Cu")
		(net "M_K_DQ<19>")
	)
	(segment
		(start 58.646568 -125.378718)
		(end 58.504328 -125.520958)
		(width 0.14224)
		(layer "In2.Cu")
		(net "M_K_DQ<19>")
	)
	(segment
		(start 57.91073 -133.550152)
		(end 58.199528 -133.83895)
		(width 0.14224)
		(layer "In2.Cu")
		(net "M_K_DQ<19>")
	)
	(segment
		(start 58.504328 -120.319038)
		(end 57.671208 -120.319038)
		(width 0.14224)
		(layer "In2.Cu")
		(net "M_K_DQ<19>")
	)
	(segment
		(start 58.504328 -125.520958)
		(end 57.671208 -125.520958)
		(width 0.14224)
		(layer "In2.Cu")
		(net "M_K_DQ<19>")
	)
	(segment
		(start 58.576972 -130.330956)
		(end 58.148728 -130.7592)
		(width 0.14224)
		(layer "In2.Cu")
		(net "M_K_DQ<19>")
	)
	(segment
		(start 58.928508 -130.01498)
		(end 58.599324 -130.344164)
		(width 0.14224)
		(layer "In2.Cu")
		(net "M_K_DQ<19>")
	)
	(segment
		(start 65.213992 -99.791012)
		(end 61.181996 -103.823008)
		(width 0.14224)
		(layer "In2.Cu")
		(net "M_K_DQ<19>")
	)
	(segment
		(start 58.193178 -131.233418)
		(end 58.193178 -131.9022)
		(width 0.14224)
		(layer "In2.Cu")
		(net "M_K_DQ<19>")
	)
	(segment
		(start 58.193178 -131.9022)
		(end 57.91073 -132.184648)
		(width 0.14224)
		(layer "In2.Cu")
		(net "M_K_DQ<19>")
	)
	(segment
		(start 58.646568 -122.777758)
		(end 58.504328 -122.919998)
		(width 0.14224)
		(layer "In2.Cu")
		(net "M_K_DQ<19>")
	)
	(segment
		(start 70.140576 -96.300036)
		(end 69.13372 -96.300036)
		(width 0.0889)
		(layer "In2.Cu")
		(net "M_K_DQ<19>")
	)
	(segment
		(start 57.671208 -126.171198)
		(end 58.504328 -126.171198)
		(width 0.14224)
		(layer "In2.Cu")
		(net "M_K_DQ<19>")
	)
	(segment
		(start 58.504328 -119.668798)
		(end 58.646568 -119.811038)
		(width 0.14224)
		(layer "In2.Cu")
		(net "M_K_DQ<19>")
	)
	(segment
		(start 57.528968 -125.663198)
		(end 57.528968 -126.028958)
		(width 0.14224)
		(layer "In2.Cu")
		(net "M_K_DQ<19>")
	)
	(segment
		(start 61.285882 -107.32643)
		(end 61.285882 -107.545378)
		(width 0.14224)
		(layer "In2.Cu")
		(net "M_K_DQ<19>")
	)
	(segment
		(start 58.504328 -124.870718)
		(end 58.646568 -125.012958)
		(width 0.14224)
		(layer "In2.Cu")
		(net "M_K_DQ<19>")
	)
	(segment
		(start 57.671208 -122.269758)
		(end 58.504328 -122.269758)
		(width 0.14224)
		(layer "In2.Cu")
		(net "M_K_DQ<19>")
	)
	(segment
		(start 58.167778 -133.0198)
		(end 57.91073 -133.276848)
		(width 0.14224)
		(layer "In2.Cu")
		(net "M_K_DQ<19>")
	)
	(segment
		(start 59.066684 -108.774738)
		(end 58.646568 -109.194854)
		(width 0.14224)
		(layer "In2.Cu")
		(net "M_K_DQ<19>")
	)
	(segment
		(start 57.671208 -120.969278)
		(end 58.504328 -120.969278)
		(width 0.14224)
		(layer "In2.Cu")
		(net "M_K_DQ<19>")
	)
	(segment
		(start 58.928508 -128.32334)
		(end 58.928508 -130.01498)
		(width 0.14224)
		(layer "In2.Cu")
		(net "M_K_DQ<19>")
	)
	(segment
		(start 60.136278 -108.476034)
		(end 60.136278 -108.694982)
		(width 0.14224)
		(layer "In2.Cu")
		(net "M_K_DQ<19>")
	)
	(segment
		(start 58.021728 -134.340346)
		(end 57.74944 -134.340346)
		(width 0.14224)
		(layer "In2.Cu")
		(net "M_K_DQ<19>")
	)
	(segment
		(start 58.504328 -120.969278)
		(end 58.646568 -121.111518)
		(width 0.14224)
		(layer "In2.Cu")
		(net "M_K_DQ<19>")
	)
	(segment
		(start 58.646568 -119.811038)
		(end 58.646568 -120.176798)
		(width 0.14224)
		(layer "In2.Cu")
		(net "M_K_DQ<19>")
	)
	(segment
		(start 59.860434 -108.199936)
		(end 60.136278 -108.476034)
		(width 0.14224)
		(layer "In2.Cu")
		(net "M_K_DQ<19>")
	)
	(segment
		(start 57.528968 -119.160798)
		(end 57.528968 -119.526558)
		(width 0.14224)
		(layer "In2.Cu")
		(net "M_K_DQ<19>")
	)
	(segment
		(start 57.528968 -124.362718)
		(end 57.528968 -124.728478)
		(width 0.14224)
		(layer "In2.Cu")
		(net "M_K_DQ<19>")
	)
	(segment
		(start 57.671208 -124.220478)
		(end 57.528968 -124.362718)
		(width 0.14224)
		(layer "In2.Cu")
		(net "M_K_DQ<19>")
	)
	(segment
		(start 57.91073 -132.184648)
		(end 57.91073 -132.457952)
		(width 0.14224)
		(layer "In2.Cu")
		(net "M_K_DQ<19>")
	)
	(segment
		(start 58.646568 -125.012958)
		(end 58.646568 -125.378718)
		(width 0.14224)
		(layer "In2.Cu")
		(net "M_K_DQ<19>")
	)
	(segment
		(start 66.750184 -97.929954)
		(end 65.213992 -99.466146)
		(width 0.0889)
		(layer "In2.Cu")
		(net "M_K_DQ<19>")
	)
	(segment
		(start 58.504328 -124.220478)
		(end 57.671208 -124.220478)
		(width 0.14224)
		(layer "In2.Cu")
		(net "M_K_DQ<19>")
	)
	(segment
		(start 59.780424 -109.050836)
		(end 59.561476 -109.050836)
		(width 0.14224)
		(layer "In2.Cu")
		(net "M_K_DQ<19>")
	)
	(segment
		(start 58.504328 -121.619518)
		(end 57.671208 -121.619518)
		(width 0.14224)
		(layer "In2.Cu")
		(net "M_K_DQ<19>")
	)
	(segment
		(start 58.199528 -134.162546)
		(end 58.021728 -134.340346)
		(width 0.14224)
		(layer "In2.Cu")
		(net "M_K_DQ<19>")
	)
	(segment
		(start 61.181996 -103.823008)
		(end 61.181996 -106.659426)
		(width 0.14224)
		(layer "In2.Cu")
		(net "M_K_DQ<19>")
	)
	(segment
		(start 57.671208 -120.319038)
		(end 57.528968 -120.461278)
		(width 0.14224)
		(layer "In2.Cu")
		(net "M_K_DQ<19>")
	)
	(segment
		(start 57.91073 -132.457952)
		(end 58.167778 -132.715)
		(width 0.14224)
		(layer "In2.Cu")
		(net "M_K_DQ<19>")
	)
	(segment
		(start 58.646568 -120.176798)
		(end 58.504328 -120.319038)
		(width 0.14224)
		(layer "In2.Cu")
		(net "M_K_DQ<19>")
	)
	(segment
		(start 58.646568 -128.0414)
		(end 58.928508 -128.32334)
		(width 0.14224)
		(layer "In2.Cu")
		(net "M_K_DQ<19>")
	)
	(segment
		(start 57.528968 -126.028958)
		(end 57.671208 -126.171198)
		(width 0.14224)
		(layer "In2.Cu")
		(net "M_K_DQ<19>")
	)
	(segment
		(start 58.148728 -130.7592)
		(end 58.148728 -131.188968)
		(width 0.14224)
		(layer "In2.Cu")
		(net "M_K_DQ<19>")
	)
	(segment
		(start 58.646568 -121.111518)
		(end 58.646568 -121.477278)
		(width 0.14224)
		(layer "In2.Cu")
		(net "M_K_DQ<19>")
	)
	(segment
		(start 60.136278 -108.694982)
		(end 59.780424 -109.050836)
		(width 0.14224)
		(layer "In2.Cu")
		(net "M_K_DQ<19>")
	)
	(segment
		(start 67.318128 -96.187006)
		(end 66.750184 -96.75495)
		(width 0.0889)
		(layer "In2.Cu")
		(net "M_K_DQ<19>")
	)
	(segment
		(start 70.235572 -96.20504)
		(end 70.140576 -96.300036)
		(width 0.0889)
		(layer "In2.Cu")
		(net "M_K_DQ<19>")
	)
	(segment
		(start 58.646568 -126.313438)
		(end 58.646568 -128.0414)
		(width 0.14224)
		(layer "In2.Cu")
		(net "M_K_DQ<19>")
	)
	(segment
		(start 58.599324 -130.344164)
		(end 58.599324 -130.330956)
		(width 0.14224)
		(layer "In2.Cu")
		(net "M_K_DQ<19>")
	)
	(segment
		(start 70.611746 -96.20504)
		(end 70.235572 -96.20504)
		(width 0.0889)
		(layer "In2.Cu")
		(net "M_K_DQ<19>")
	)
	(segment
		(start 58.504328 -126.171198)
		(end 58.646568 -126.313438)
		(width 0.14224)
		(layer "In2.Cu")
		(net "M_K_DQ<19>")
	)
	(segment
		(start 58.599324 -130.330956)
		(end 58.576972 -130.330956)
		(width 0.14224)
		(layer "In2.Cu")
		(net "M_K_DQ<19>")
	)
	(segment
		(start 60.435236 -107.625134)
		(end 60.216288 -107.625134)
		(width 0.14224)
		(layer "In2.Cu")
		(net "M_K_DQ<19>")
	)
	(segment
		(start 57.528968 -123.427998)
		(end 57.671208 -123.570238)
		(width 0.14224)
		(layer "In2.Cu")
		(net "M_K_DQ<19>")
	)
	(segment
		(start 61.010038 -106.831384)
		(end 61.010038 -107.050332)
		(width 0.14224)
		(layer "In2.Cu")
		(net "M_K_DQ<19>")
	)
	(segment
		(start 66.750184 -96.75495)
		(end 66.750184 -97.929954)
		(width 0.0889)
		(layer "In2.Cu")
		(net "M_K_DQ<19>")
	)
	(segment
		(start 58.646568 -118.876318)
		(end 58.504328 -119.018558)
		(width 0.14224)
		(layer "In2.Cu")
		(net "M_K_DQ<19>")
	)
	(segment
		(start 57.671208 -123.570238)
		(end 58.504328 -123.570238)
		(width 0.14224)
		(layer "In2.Cu")
		(net "M_K_DQ<19>")
	)
	(segment
		(start 58.646568 -124.078238)
		(end 58.504328 -124.220478)
		(width 0.14224)
		(layer "In2.Cu")
		(net "M_K_DQ<19>")
	)
	(segment
		(start 58.504328 -122.919998)
		(end 57.671208 -122.919998)
		(width 0.14224)
		(layer "In2.Cu")
		(net "M_K_DQ<19>")
	)
	(segment
		(start 61.285882 -107.545378)
		(end 60.930028 -107.901232)
		(width 0.14224)
		(layer "In2.Cu")
		(net "M_K_DQ<19>")
	)
	(segment
		(start 58.646568 -123.712478)
		(end 58.646568 -124.078238)
		(width 0.14224)
		(layer "In2.Cu")
		(net "M_K_DQ<19>")
	)
	(segment
		(start 58.167778 -132.715)
		(end 58.167778 -133.0198)
		(width 0.14224)
		(layer "In2.Cu")
		(net "M_K_DQ<19>")
	)
	(segment
		(start 58.646568 -122.411998)
		(end 58.646568 -122.777758)
		(width 0.14224)
		(layer "In2.Cu")
		(net "M_K_DQ<19>")
	)
	(segment
		(start 59.860434 -107.980988)
		(end 59.860434 -108.199936)
		(width 0.14224)
		(layer "In2.Cu")
		(net "M_K_DQ<19>")
	)
	(segment
		(start 60.930028 -107.901232)
		(end 60.71108 -107.901232)
		(width 0.14224)
		(layer "In2.Cu")
		(net "M_K_DQ<19>")
	)
	(segment
		(start 60.216288 -107.625134)
		(end 59.860434 -107.980988)
		(width 0.14224)
		(layer "In2.Cu")
		(net "M_K_DQ<19>")
	)
	(segment
		(start 58.646568 -121.477278)
		(end 58.504328 -121.619518)
		(width 0.14224)
		(layer "In2.Cu")
		(net "M_K_DQ<19>")
	)
	(segment
		(start 57.528968 -120.827038)
		(end 57.671208 -120.969278)
		(width 0.14224)
		(layer "In2.Cu")
		(net "M_K_DQ<19>")
	)
	(segment
		(start 58.730896 -136.32434)
		(end 58.599324 -136.192768)
		(width 0.1651)
		(layer "F.Cu")
		(net "M_K_DQ<18>")
	)
	(segment
		(start 58.599324 -137.67054)
		(end 58.599324 -136.679432)
		(width 0.1651)
		(layer "F.Cu")
		(net "M_K_DQ<18>")
	)
	(segment
		(start 58.599324 -136.679432)
		(end 58.730896 -136.54786)
		(width 0.1651)
		(layer "F.Cu")
		(net "M_K_DQ<18>")
	)
	(segment
		(start 58.599324 -136.192768)
		(end 58.599324 -135.9154)
		(width 0.1651)
		(layer "F.Cu")
		(net "M_K_DQ<18>")
	)
	(segment
		(start 58.599578 -137.67054)
		(end 58.599324 -137.67054)
		(width 0.1651)
		(layer "F.Cu")
		(net "M_K_DQ<18>")
	)
	(segment
		(start 72.041766 -96.700086)
		(end 71.470266 -96.700086)
		(width 0.1651)
		(layer "F.Cu")
		(net "M_K_DQ<18>")
	)
	(segment
		(start 58.730896 -136.54786)
		(end 58.730896 -136.32434)
		(width 0.1651)
		(layer "F.Cu")
		(net "M_K_DQ<18>")
	)
	(via
		(at 58.599324 -135.9154)
		(size 0.508)
		(drill 0.254)
		(layers "F.Cu" "B.Cu")
		(net "M_K_DQ<18>")
	)
	(via
		(at 57.74944 -131.611878)
		(size 0.508)
		(drill 0.254)
		(layers "F.Cu" "B.Cu")
		(net "M_K_DQ<18>")
	)
	(via
		(at 71.470266 -96.700086)
		(size 0.508)
		(drill 0.254)
		(layers "F.Cu" "B.Cu")
		(net "M_K_DQ<18>")
	)
	(segment
		(start 57.74944 -132.876036)
		(end 57.74944 -131.611878)
		(width 0.1651)
		(layer "B.Cu")
		(net "M_K_DQ<18>")
	)
	(segment
		(start 57.404508 -130.633978)
		(end 57.404508 -131.266946)
		(width 0.14224)
		(layer "In2.Cu")
		(net "M_K_DQ<18>")
	)
	(segment
		(start 56.868568 -121.484644)
		(end 56.868568 -121.850404)
		(width 0.14224)
		(layer "In2.Cu")
		(net "M_K_DQ<18>")
	)
	(segment
		(start 57.833768 -126.9238)
		(end 58.011568 -127.1016)
		(width 0.14224)
		(layer "In2.Cu")
		(net "M_K_DQ<18>")
	)
	(segment
		(start 56.868568 -125.386084)
		(end 56.868568 -125.751844)
		(width 0.14224)
		(layer "In2.Cu")
		(net "M_K_DQ<18>")
	)
	(segment
		(start 60.541916 -103.54691)
		(end 60.541916 -106.39425)
		(width 0.14224)
		(layer "In2.Cu")
		(net "M_K_DQ<18>")
	)
	(segment
		(start 55.776368 -126.036324)
		(end 55.776368 -126.365)
		(width 0.14224)
		(layer "In2.Cu")
		(net "M_K_DQ<18>")
	)
	(segment
		(start 55.918608 -123.293124)
		(end 55.776368 -123.435364)
		(width 0.14224)
		(layer "In2.Cu")
		(net "M_K_DQ<18>")
	)
	(segment
		(start 58.011568 -127.1016)
		(end 58.011568 -128.4224)
		(width 0.14224)
		(layer "In2.Cu")
		(net "M_K_DQ<18>")
	)
	(segment
		(start 55.918608 -123.943364)
		(end 56.726328 -123.943364)
		(width 0.14224)
		(layer "In2.Cu")
		(net "M_K_DQ<18>")
	)
	(segment
		(start 66.560192 -97.851214)
		(end 65.086992 -99.324414)
		(width 0.0889)
		(layer "In2.Cu")
		(net "M_K_DQ<18>")
	)
	(segment
		(start 55.979568 -120.6246)
		(end 55.776368 -120.8278)
		(width 0.14224)
		(layer "In2.Cu")
		(net "M_K_DQ<18>")
	)
	(segment
		(start 65.086992 -99.324414)
		(end 64.764412 -99.324414)
		(width 0.0889)
		(layer "In2.Cu")
		(net "M_K_DQ<18>")
	)
	(segment
		(start 56.335168 -126.9238)
		(end 57.833768 -126.9238)
		(width 0.14224)
		(layer "In2.Cu")
		(net "M_K_DQ<18>")
	)
	(segment
		(start 57.046368 -120.4976)
		(end 56.919368 -120.6246)
		(width 0.14224)
		(layer "In2.Cu")
		(net "M_K_DQ<18>")
	)
	(segment
		(start 60.541916 -106.39425)
		(end 58.163968 -108.772198)
		(width 0.14224)
		(layer "In2.Cu")
		(net "M_K_DQ<18>")
	)
	(segment
		(start 66.560192 -96.67621)
		(end 66.560192 -97.851214)
		(width 0.0889)
		(layer "In2.Cu")
		(net "M_K_DQ<18>")
	)
	(segment
		(start 55.776368 -122.134884)
		(end 55.776368 -122.500644)
		(width 0.14224)
		(layer "In2.Cu")
		(net "M_K_DQ<18>")
	)
	(segment
		(start 70.028816 -96.109536)
		(end 69.212714 -96.109536)
		(width 0.0889)
		(layer "In2.Cu")
		(net "M_K_DQ<18>")
	)
	(segment
		(start 71.470266 -96.700086)
		(end 71.470266 -96.309688)
		(width 0.0889)
		(layer "In2.Cu")
		(net "M_K_DQ<18>")
	)
	(segment
		(start 69.100192 -95.997014)
		(end 67.239388 -95.997014)
		(width 0.0889)
		(layer "In2.Cu")
		(net "M_K_DQ<18>")
	)
	(segment
		(start 57.404508 -131.266946)
		(end 57.74944 -131.611878)
		(width 0.14224)
		(layer "In2.Cu")
		(net "M_K_DQ<18>")
	)
	(segment
		(start 57.74944 -131.611878)
		(end 57.31637 -132.044948)
		(width 0.14224)
		(layer "In2.Cu")
		(net "M_K_DQ<18>")
	)
	(segment
		(start 56.726328 -123.943364)
		(end 56.868568 -124.085604)
		(width 0.14224)
		(layer "In2.Cu")
		(net "M_K_DQ<18>")
	)
	(segment
		(start 55.776368 -124.735844)
		(end 55.776368 -125.101604)
		(width 0.14224)
		(layer "In2.Cu")
		(net "M_K_DQ<18>")
	)
	(segment
		(start 55.776368 -120.8278)
		(end 55.776368 -121.200164)
		(width 0.14224)
		(layer "In2.Cu")
		(net "M_K_DQ<18>")
	)
	(segment
		(start 55.776368 -121.200164)
		(end 55.918608 -121.342404)
		(width 0.14224)
		(layer "In2.Cu")
		(net "M_K_DQ<18>")
	)
	(segment
		(start 56.868568 -125.751844)
		(end 56.726328 -125.894084)
		(width 0.14224)
		(layer "In2.Cu")
		(net "M_K_DQ<18>")
	)
	(segment
		(start 56.726328 -121.342404)
		(end 56.868568 -121.484644)
		(width 0.14224)
		(layer "In2.Cu")
		(net "M_K_DQ<18>")
	)
	(segment
		(start 56.726328 -125.894084)
		(end 55.918608 -125.894084)
		(width 0.14224)
		(layer "In2.Cu")
		(net "M_K_DQ<18>")
	)
	(segment
		(start 55.776368 -123.801124)
		(end 55.918608 -123.943364)
		(width 0.14224)
		(layer "In2.Cu")
		(net "M_K_DQ<18>")
	)
	(segment
		(start 55.918608 -121.992644)
		(end 55.776368 -122.134884)
		(width 0.14224)
		(layer "In2.Cu")
		(net "M_K_DQ<18>")
	)
	(segment
		(start 55.776368 -126.365)
		(end 56.335168 -126.9238)
		(width 0.14224)
		(layer "In2.Cu")
		(net "M_K_DQ<18>")
	)
	(segment
		(start 56.726328 -121.992644)
		(end 55.918608 -121.992644)
		(width 0.14224)
		(layer "In2.Cu")
		(net "M_K_DQ<18>")
	)
	(segment
		(start 56.726328 -123.293124)
		(end 55.918608 -123.293124)
		(width 0.14224)
		(layer "In2.Cu")
		(net "M_K_DQ<18>")
	)
	(segment
		(start 58.268108 -129.770378)
		(end 57.404508 -130.633978)
		(width 0.14224)
		(layer "In2.Cu")
		(net "M_K_DQ<18>")
	)
	(segment
		(start 55.776368 -125.101604)
		(end 55.918608 -125.243844)
		(width 0.14224)
		(layer "In2.Cu")
		(net "M_K_DQ<18>")
	)
	(segment
		(start 57.31637 -132.044948)
		(end 57.31637 -134.632446)
		(width 0.14224)
		(layer "In2.Cu")
		(net "M_K_DQ<18>")
	)
	(segment
		(start 58.268108 -128.67894)
		(end 58.268108 -129.770378)
		(width 0.14224)
		(layer "In2.Cu")
		(net "M_K_DQ<18>")
	)
	(segment
		(start 70.916292 -95.755714)
		(end 70.382638 -95.755714)
		(width 0.0889)
		(layer "In2.Cu")
		(net "M_K_DQ<18>")
	)
	(segment
		(start 56.868568 -123.150884)
		(end 56.726328 -123.293124)
		(width 0.14224)
		(layer "In2.Cu")
		(net "M_K_DQ<18>")
	)
	(segment
		(start 56.868568 -124.085604)
		(end 56.868568 -124.451364)
		(width 0.14224)
		(layer "In2.Cu")
		(net "M_K_DQ<18>")
	)
	(segment
		(start 67.239388 -95.997014)
		(end 66.560192 -96.67621)
		(width 0.0889)
		(layer "In2.Cu")
		(net "M_K_DQ<18>")
	)
	(segment
		(start 56.919368 -120.6246)
		(end 55.979568 -120.6246)
		(width 0.14224)
		(layer "In2.Cu")
		(net "M_K_DQ<18>")
	)
	(segment
		(start 55.776368 -122.500644)
		(end 55.918608 -122.642884)
		(width 0.14224)
		(layer "In2.Cu")
		(net "M_K_DQ<18>")
	)
	(segment
		(start 55.918608 -121.342404)
		(end 56.726328 -121.342404)
		(width 0.14224)
		(layer "In2.Cu")
		(net "M_K_DQ<18>")
	)
	(segment
		(start 56.726328 -125.243844)
		(end 56.868568 -125.386084)
		(width 0.14224)
		(layer "In2.Cu")
		(net "M_K_DQ<18>")
	)
	(segment
		(start 56.868568 -121.850404)
		(end 56.726328 -121.992644)
		(width 0.14224)
		(layer "In2.Cu")
		(net "M_K_DQ<18>")
	)
	(segment
		(start 55.918608 -122.642884)
		(end 56.726328 -122.642884)
		(width 0.14224)
		(layer "In2.Cu")
		(net "M_K_DQ<18>")
	)
	(segment
		(start 70.382638 -95.755714)
		(end 70.028816 -96.109536)
		(width 0.0889)
		(layer "In2.Cu")
		(net "M_K_DQ<18>")
	)
	(segment
		(start 56.726328 -124.593604)
		(end 55.918608 -124.593604)
		(width 0.14224)
		(layer "In2.Cu")
		(net "M_K_DQ<18>")
	)
	(segment
		(start 56.868568 -124.451364)
		(end 56.726328 -124.593604)
		(width 0.14224)
		(layer "In2.Cu")
		(net "M_K_DQ<18>")
	)
	(segment
		(start 55.918608 -125.894084)
		(end 55.776368 -126.036324)
		(width 0.14224)
		(layer "In2.Cu")
		(net "M_K_DQ<18>")
	)
	(segment
		(start 55.918608 -125.243844)
		(end 56.726328 -125.243844)
		(width 0.14224)
		(layer "In2.Cu")
		(net "M_K_DQ<18>")
	)
	(segment
		(start 71.470266 -96.309688)
		(end 70.916292 -95.755714)
		(width 0.0889)
		(layer "In2.Cu")
		(net "M_K_DQ<18>")
	)
	(segment
		(start 69.212714 -96.109536)
		(end 69.100192 -95.997014)
		(width 0.0889)
		(layer "In2.Cu")
		(net "M_K_DQ<18>")
	)
	(segment
		(start 58.163968 -117.856)
		(end 57.046368 -118.9736)
		(width 0.14224)
		(layer "In2.Cu")
		(net "M_K_DQ<18>")
	)
	(segment
		(start 56.726328 -122.642884)
		(end 56.868568 -122.785124)
		(width 0.14224)
		(layer "In2.Cu")
		(net "M_K_DQ<18>")
	)
	(segment
		(start 64.764412 -99.324414)
		(end 60.541916 -103.54691)
		(width 0.14224)
		(layer "In2.Cu")
		(net "M_K_DQ<18>")
	)
	(segment
		(start 58.011568 -128.4224)
		(end 58.268108 -128.67894)
		(width 0.14224)
		(layer "In2.Cu")
		(net "M_K_DQ<18>")
	)
	(segment
		(start 55.776368 -123.435364)
		(end 55.776368 -123.801124)
		(width 0.14224)
		(layer "In2.Cu")
		(net "M_K_DQ<18>")
	)
	(segment
		(start 58.163968 -108.772198)
		(end 58.163968 -117.856)
		(width 0.14224)
		(layer "In2.Cu")
		(net "M_K_DQ<18>")
	)
	(segment
		(start 55.918608 -124.593604)
		(end 55.776368 -124.735844)
		(width 0.14224)
		(layer "In2.Cu")
		(net "M_K_DQ<18>")
	)
	(segment
		(start 56.868568 -122.785124)
		(end 56.868568 -123.150884)
		(width 0.14224)
		(layer "In2.Cu")
		(net "M_K_DQ<18>")
	)
	(segment
		(start 57.31637 -134.632446)
		(end 58.599324 -135.9154)
		(width 0.14224)
		(layer "In2.Cu")
		(net "M_K_DQ<18>")
	)
	(segment
		(start 57.046368 -118.9736)
		(end 57.046368 -120.4976)
		(width 0.14224)
		(layer "In2.Cu")
		(net "M_K_DQ<18>")
	)
	(segment
		(start 51.79949 -133.0706)
		(end 51.79949 -134.340346)
		(width 0.1651)
		(layer "F.Cu")
		(net "M_K_DQ<17>")
	)
	(segment
		(start 72.041766 -93.72854)
		(end 71.470266 -93.72854)
		(width 0.1651)
		(layer "F.Cu")
		(net "M_K_DQ<17>")
	)
	(via
		(at 71.470266 -93.72854)
		(size 0.508)
		(drill 0.254)
		(layers "F.Cu" "B.Cu")
		(net "M_K_DQ<17>")
	)
	(via
		(at 51.79949 -134.340346)
		(size 0.508)
		(drill 0.254)
		(layers "F.Cu" "B.Cu")
		(net "M_K_DQ<17>")
	)
	(via
		(at 52.471574 -130.330956)
		(size 0.508)
		(drill 0.254)
		(layers "F.Cu" "B.Cu")
		(net "M_K_DQ<17>")
	)
	(segment
		(start 52.471574 -129.827782)
		(end 52.471574 -130.330956)
		(width 0.1651)
		(layer "B.Cu")
		(net "M_K_DQ<17>")
	)
	(segment
		(start 52.649374 -129.649982)
		(end 52.471574 -129.827782)
		(width 0.1651)
		(layer "B.Cu")
		(net "M_K_DQ<17>")
	)
	(segment
		(start 52.649374 -128.276096)
		(end 52.649374 -129.649982)
		(width 0.1651)
		(layer "B.Cu")
		(net "M_K_DQ<17>")
	)
	(segment
		(start 50.924968 -124.288804)
		(end 50.924968 -124.654564)
		(width 0.14224)
		(layer "In2.Cu")
		(net "M_K_DQ<17>")
	)
	(segment
		(start 71.470266 -93.72854)
		(end 70.97522 -93.062298)
		(width 0.0889)
		(layer "In2.Cu")
		(net "M_K_DQ<17>")
	)
	(segment
		(start 66.674746 -92.869258)
		(end 65.822322 -92.869258)
		(width 0.14224)
		(layer "In2.Cu")
		(net "M_K_DQ<17>")
	)
	(segment
		(start 52.067968 -124.004324)
		(end 51.925728 -124.146564)
		(width 0.14224)
		(layer "In2.Cu")
		(net "M_K_DQ<17>")
	)
	(segment
		(start 50.924968 -110.076996)
		(end 50.924968 -123.354084)
		(width 0.14224)
		(layer "In2.Cu")
		(net "M_K_DQ<17>")
	)
	(segment
		(start 70.97522 -93.062298)
		(end 70.958456 -93.033088)
		(width 0.0889)
		(layer "In2.Cu")
		(net "M_K_DQ<17>")
	)
	(segment
		(start 52.200556 -133.8834)
		(end 52.200556 -134.1882)
		(width 0.14224)
		(layer "In2.Cu")
		(net "M_K_DQ<17>")
	)
	(segment
		(start 65.822322 -92.869258)
		(end 56.982868 -101.708712)
		(width 0.14224)
		(layer "In2.Cu")
		(net "M_K_DQ<17>")
	)
	(segment
		(start 52.251356 -131.419346)
		(end 52.251356 -131.823968)
		(width 0.14224)
		(layer "In2.Cu")
		(net "M_K_DQ<17>")
	)
	(segment
		(start 52.067968 -124.939044)
		(end 52.067968 -125.304804)
		(width 0.14224)
		(layer "In2.Cu")
		(net "M_K_DQ<17>")
	)
	(segment
		(start 52.175156 -132.6896)
		(end 52.175156 -133.1214)
		(width 0.14224)
		(layer "In2.Cu")
		(net "M_K_DQ<17>")
	)
	(segment
		(start 51.067208 -125.447044)
		(end 50.924968 -125.589284)
		(width 0.14224)
		(layer "In2.Cu")
		(net "M_K_DQ<17>")
	)
	(segment
		(start 52.855368 -129.947162)
		(end 52.471574 -130.330956)
		(width 0.14224)
		(layer "In2.Cu")
		(net "M_K_DQ<17>")
	)
	(segment
		(start 52.020978 -131.188968)
		(end 52.251356 -131.419346)
		(width 0.14224)
		(layer "In2.Cu")
		(net "M_K_DQ<17>")
	)
	(segment
		(start 51.737768 -126.4666)
		(end 51.737768 -127.9144)
		(width 0.14224)
		(layer "In2.Cu")
		(net "M_K_DQ<17>")
	)
	(segment
		(start 51.534568 -126.2634)
		(end 51.737768 -126.4666)
		(width 0.14224)
		(layer "In2.Cu")
		(net "M_K_DQ<17>")
	)
	(segment
		(start 51.925728 -123.496324)
		(end 52.067968 -123.638564)
		(width 0.14224)
		(layer "In2.Cu")
		(net "M_K_DQ<17>")
	)
	(segment
		(start 51.128168 -126.2634)
		(end 51.534568 -126.2634)
		(width 0.14224)
		(layer "In2.Cu")
		(net "M_K_DQ<17>")
	)
	(segment
		(start 51.737768 -127.9144)
		(end 52.855368 -129.032)
		(width 0.14224)
		(layer "In2.Cu")
		(net "M_K_DQ<17>")
	)
	(segment
		(start 52.04841 -134.340346)
		(end 51.79949 -134.340346)
		(width 0.14224)
		(layer "In2.Cu")
		(net "M_K_DQ<17>")
	)
	(segment
		(start 52.200556 -134.1882)
		(end 52.04841 -134.340346)
		(width 0.14224)
		(layer "In2.Cu")
		(net "M_K_DQ<17>")
	)
	(segment
		(start 51.925728 -124.796804)
		(end 52.067968 -124.939044)
		(width 0.14224)
		(layer "In2.Cu")
		(net "M_K_DQ<17>")
	)
	(segment
		(start 52.855368 -129.032)
		(end 52.855368 -129.947162)
		(width 0.14224)
		(layer "In2.Cu")
		(net "M_K_DQ<17>")
	)
	(segment
		(start 52.175156 -133.1214)
		(end 51.96078 -133.335776)
		(width 0.14224)
		(layer "In2.Cu")
		(net "M_K_DQ<17>")
	)
	(segment
		(start 51.96078 -133.335776)
		(end 51.96078 -133.643624)
		(width 0.14224)
		(layer "In2.Cu")
		(net "M_K_DQ<17>")
	)
	(segment
		(start 67.29857 -92.337636)
		(end 67.049904 -92.586302)
		(width 0.0889)
		(layer "In2.Cu")
		(net "M_K_DQ<17>")
	)
	(segment
		(start 51.96078 -132.475224)
		(end 52.175156 -132.6896)
		(width 0.14224)
		(layer "In2.Cu")
		(net "M_K_DQ<17>")
	)
	(segment
		(start 52.020978 -130.7592)
		(end 52.020978 -131.188968)
		(width 0.14224)
		(layer "In2.Cu")
		(net "M_K_DQ<17>")
	)
	(segment
		(start 52.449222 -130.330956)
		(end 52.020978 -130.7592)
		(width 0.14224)
		(layer "In2.Cu")
		(net "M_K_DQ<17>")
	)
	(segment
		(start 66.957702 -92.586302)
		(end 66.674746 -92.869258)
		(width 0.0889)
		(layer "In2.Cu")
		(net "M_K_DQ<17>")
	)
	(segment
		(start 67.049904 -92.586302)
		(end 66.957702 -92.586302)
		(width 0.0889)
		(layer "In2.Cu")
		(net "M_K_DQ<17>")
	)
	(segment
		(start 50.924968 -124.654564)
		(end 51.067208 -124.796804)
		(width 0.14224)
		(layer "In2.Cu")
		(net "M_K_DQ<17>")
	)
	(segment
		(start 52.251356 -131.823968)
		(end 51.96078 -132.114544)
		(width 0.14224)
		(layer "In2.Cu")
		(net "M_K_DQ<17>")
	)
	(segment
		(start 51.96078 -132.114544)
		(end 51.96078 -132.475224)
		(width 0.14224)
		(layer "In2.Cu")
		(net "M_K_DQ<17>")
	)
	(segment
		(start 69.764402 -92.337636)
		(end 67.29857 -92.337636)
		(width 0.0889)
		(layer "In2.Cu")
		(net "M_K_DQ<17>")
	)
	(segment
		(start 51.067208 -124.146564)
		(end 50.924968 -124.288804)
		(width 0.14224)
		(layer "In2.Cu")
		(net "M_K_DQ<17>")
	)
	(segment
		(start 70.626732 -92.83319)
		(end 70.593966 -92.83319)
		(width 0.0889)
		(layer "In2.Cu")
		(net "M_K_DQ<17>")
	)
	(segment
		(start 51.067208 -124.796804)
		(end 51.925728 -124.796804)
		(width 0.14224)
		(layer "In2.Cu")
		(net "M_K_DQ<17>")
	)
	(segment
		(start 50.924968 -123.354084)
		(end 51.067208 -123.496324)
		(width 0.14224)
		(layer "In2.Cu")
		(net "M_K_DQ<17>")
	)
	(segment
		(start 51.067208 -123.496324)
		(end 51.925728 -123.496324)
		(width 0.14224)
		(layer "In2.Cu")
		(net "M_K_DQ<17>")
	)
	(segment
		(start 52.471574 -130.330956)
		(end 52.449222 -130.330956)
		(width 0.14224)
		(layer "In2.Cu")
		(net "M_K_DQ<17>")
	)
	(segment
		(start 50.924968 -125.589284)
		(end 50.924968 -126.0602)
		(width 0.14224)
		(layer "In2.Cu")
		(net "M_K_DQ<17>")
	)
	(segment
		(start 51.96078 -133.643624)
		(end 52.200556 -133.8834)
		(width 0.14224)
		(layer "In2.Cu")
		(net "M_K_DQ<17>")
	)
	(segment
		(start 56.982868 -104.019096)
		(end 50.924968 -110.076996)
		(width 0.14224)
		(layer "In2.Cu")
		(net "M_K_DQ<17>")
	)
	(segment
		(start 52.067968 -123.638564)
		(end 52.067968 -124.004324)
		(width 0.14224)
		(layer "In2.Cu")
		(net "M_K_DQ<17>")
	)
	(segment
		(start 50.924968 -126.0602)
		(end 51.128168 -126.2634)
		(width 0.14224)
		(layer "In2.Cu")
		(net "M_K_DQ<17>")
	)
	(segment
		(start 56.982868 -101.708712)
		(end 56.982868 -104.019096)
		(width 0.14224)
		(layer "In2.Cu")
		(net "M_K_DQ<17>")
	)
	(segment
		(start 51.925728 -124.146564)
		(end 51.067208 -124.146564)
		(width 0.14224)
		(layer "In2.Cu")
		(net "M_K_DQ<17>")
	)
	(segment
		(start 51.925728 -125.447044)
		(end 51.067208 -125.447044)
		(width 0.14224)
		(layer "In2.Cu")
		(net "M_K_DQ<17>")
	)
	(segment
		(start 52.067968 -125.304804)
		(end 51.925728 -125.447044)
		(width 0.14224)
		(layer "In2.Cu")
		(net "M_K_DQ<17>")
	)
	(arc
		(start 70.593966 -92.83319)
		(mid 70.308542 -92.749723)
		(end 70.099936 -92.537788)
		(width 0.0889)
		(layer "In2.Cu")
		(net "M_K_DQ<17>")
	)
	(arc
		(start 70.958456 -93.033088)
		(mid 70.818377 -92.890352)
		(end 70.626732 -92.83319)
		(width 0.0889)
		(layer "In2.Cu")
		(net "M_K_DQ<17>")
	)
	(arc
		(start 70.099936 -92.537788)
		(mid 69.958253 -92.393984)
		(end 69.764402 -92.337636)
		(width 0.0889)
		(layer "In2.Cu")
		(net "M_K_DQ<17>")
	)
	(segment
		(start 52.649374 -137.67054)
		(end 52.649374 -137.676382)
		(width 0.1651)
		(layer "F.Cu")
		(net "M_K_DQ<16>")
	)
	(segment
		(start 52.649374 -137.676382)
		(end 52.471574 -135.8138)
		(width 0.1651)
		(layer "F.Cu")
		(net "M_K_DQ<16>")
	)
	(segment
		(start 73.758806 -94.718886)
		(end 73.187306 -94.718886)
		(width 0.1651)
		(layer "F.Cu")
		(net "M_K_DQ<16>")
	)
	(via
		(at 52.471574 -135.8138)
		(size 0.508)
		(drill 0.254)
		(layers "F.Cu" "B.Cu")
		(net "M_K_DQ<16>")
	)
	(via
		(at 73.187306 -94.718886)
		(size 0.508)
		(drill 0.254)
		(layers "F.Cu" "B.Cu")
		(net "M_K_DQ<16>")
	)
	(via
		(at 51.79949 -131.611878)
		(size 0.508)
		(drill 0.254)
		(layers "F.Cu" "B.Cu")
		(net "M_K_DQ<16>")
	)
	(segment
		(start 51.79949 -132.876036)
		(end 51.79949 -131.611878)
		(width 0.1651)
		(layer "B.Cu")
		(net "M_K_DQ<16>")
	)
	(segment
		(start 51.36642 -132.044948)
		(end 51.36642 -135.00481)
		(width 0.14224)
		(layer "In2.Cu")
		(net "M_K_DQ<16>")
	)
	(segment
		(start 52.17541 -135.8138)
		(end 52.471574 -135.8138)
		(width 0.14224)
		(layer "In2.Cu")
		(net "M_K_DQ<16>")
	)
	(segment
		(start 65.793112 -92.221304)
		(end 56.504078 -101.510338)
		(width 0.14224)
		(layer "In2.Cu")
		(net "M_K_DQ<16>")
	)
	(segment
		(start 51.79949 -131.611878)
		(end 51.36642 -132.044948)
		(width 0.14224)
		(layer "In2.Cu")
		(net "M_K_DQ<16>")
	)
	(segment
		(start 52.220368 -129.2098)
		(end 52.220368 -129.7686)
		(width 0.14224)
		(layer "In2.Cu")
		(net "M_K_DQ<16>")
	)
	(segment
		(start 73.187306 -94.718886)
		(end 72.857614 -93.957648)
		(width 0.0889)
		(layer "In2.Cu")
		(net "M_K_DQ<16>")
	)
	(segment
		(start 71.48322 -93.137736)
		(end 71.45528 -93.137736)
		(width 0.0889)
		(layer "In2.Cu")
		(net "M_K_DQ<16>")
	)
	(segment
		(start 66.849752 -92.39631)
		(end 66.674746 -92.221304)
		(width 0.0889)
		(layer "In2.Cu")
		(net "M_K_DQ<16>")
	)
	(segment
		(start 51.077368 -128.0668)
		(end 52.220368 -129.2098)
		(width 0.14224)
		(layer "In2.Cu")
		(net "M_K_DQ<16>")
	)
	(segment
		(start 51.435508 -130.55346)
		(end 51.435508 -131.299204)
		(width 0.14224)
		(layer "In2.Cu")
		(net "M_K_DQ<16>")
	)
	(segment
		(start 56.504078 -103.599742)
		(end 50.264568 -109.839252)
		(width 0.14224)
		(layer "In2.Cu")
		(net "M_K_DQ<16>")
	)
	(segment
		(start 66.971164 -92.39631)
		(end 66.849752 -92.39631)
		(width 0.0889)
		(layer "In2.Cu")
		(net "M_K_DQ<16>")
	)
	(segment
		(start 51.435508 -131.299204)
		(end 51.748182 -131.611878)
		(width 0.14224)
		(layer "In2.Cu")
		(net "M_K_DQ<16>")
	)
	(segment
		(start 72.857614 -93.957648)
		(end 72.840596 -93.928438)
		(width 0.0889)
		(layer "In2.Cu")
		(net "M_K_DQ<16>")
	)
	(segment
		(start 72.346566 -93.633036)
		(end 72.310752 -93.633036)
		(width 0.0889)
		(layer "In2.Cu")
		(net "M_K_DQ<16>")
	)
	(segment
		(start 52.220368 -129.7686)
		(end 51.435508 -130.55346)
		(width 0.14224)
		(layer "In2.Cu")
		(net "M_K_DQ<16>")
	)
	(segment
		(start 51.36642 -135.00481)
		(end 52.17541 -135.8138)
		(width 0.14224)
		(layer "In2.Cu")
		(net "M_K_DQ<16>")
	)
	(segment
		(start 66.674746 -92.221304)
		(end 65.793112 -92.221304)
		(width 0.14224)
		(layer "In2.Cu")
		(net "M_K_DQ<16>")
	)
	(segment
		(start 69.771006 -92.147136)
		(end 67.220338 -92.147136)
		(width 0.0889)
		(layer "In2.Cu")
		(net "M_K_DQ<16>")
	)
	(segment
		(start 67.220338 -92.147136)
		(end 66.971164 -92.39631)
		(width 0.0889)
		(layer "In2.Cu")
		(net "M_K_DQ<16>")
	)
	(segment
		(start 50.264568 -126.3142)
		(end 51.077368 -127.127)
		(width 0.14224)
		(layer "In2.Cu")
		(net "M_K_DQ<16>")
	)
	(segment
		(start 51.077368 -127.127)
		(end 51.077368 -128.0668)
		(width 0.14224)
		(layer "In2.Cu")
		(net "M_K_DQ<16>")
	)
	(segment
		(start 56.504078 -101.510338)
		(end 56.504078 -103.599742)
		(width 0.14224)
		(layer "In2.Cu")
		(net "M_K_DQ<16>")
	)
	(segment
		(start 50.264568 -109.839252)
		(end 50.264568 -126.3142)
		(width 0.14224)
		(layer "In2.Cu")
		(net "M_K_DQ<16>")
	)
	(segment
		(start 51.748182 -131.611878)
		(end 51.79949 -131.611878)
		(width 0.14224)
		(layer "In2.Cu")
		(net "M_K_DQ<16>")
	)
	(segment
		(start 70.633336 -92.64269)
		(end 70.60057 -92.64269)
		(width 0.0889)
		(layer "In2.Cu")
		(net "M_K_DQ<16>")
	)
	(arc
		(start 72.840596 -93.928438)
		(mid 72.631988 -93.716506)
		(end 72.346566 -93.633036)
		(width 0.0889)
		(layer "In2.Cu")
		(net "M_K_DQ<16>")
	)
	(arc
		(start 71.982076 -93.433138)
		(mid 71.771363 -93.220059)
		(end 71.48322 -93.137736)
		(width 0.0889)
		(layer "In2.Cu")
		(net "M_K_DQ<16>")
	)
	(arc
		(start 72.310752 -93.633036)
		(mid 72.120823 -93.575166)
		(end 71.982076 -93.433138)
		(width 0.0889)
		(layer "In2.Cu")
		(net "M_K_DQ<16>")
	)
	(arc
		(start 71.123556 -92.937838)
		(mid 70.916552 -92.726974)
		(end 70.633336 -92.64269)
		(width 0.0889)
		(layer "In2.Cu")
		(net "M_K_DQ<16>")
	)
	(arc
		(start 70.60057 -92.64269)
		(mid 70.40672 -92.58634)
		(end 70.265036 -92.442538)
		(width 0.0889)
		(layer "In2.Cu")
		(net "M_K_DQ<16>")
	)
	(arc
		(start 70.265036 -92.442538)
		(mid 70.056428 -92.230606)
		(end 69.771006 -92.147136)
		(width 0.0889)
		(layer "In2.Cu")
		(net "M_K_DQ<16>")
	)
	(arc
		(start 71.45528 -93.137736)
		(mid 71.263638 -93.08057)
		(end 71.123556 -92.937838)
		(width 0.0889)
		(layer "In2.Cu")
		(net "M_K_DQ<16>")
	)
	(segment
		(start 49.054766 -123.0376)
		(end 48.854106 -122.83694)
		(width 0.1651)
		(layer "F.Cu")
		(net "M_K_DQ<15>")
	)
	(segment
		(start 68.159122 -97.242122)
		(end 67.69735 -97.242122)
		(width 0.0889)
		(layer "F.Cu")
		(net "M_K_DQ<15>")
	)
	(segment
		(start 48.678846 -118.607078)
		(end 48.346106 -118.607078)
		(width 0.1651)
		(layer "F.Cu")
		(net "M_K_DQ<15>")
	)
	(segment
		(start 47.927768 -129.032)
		(end 47.927768 -129.952496)
		(width 0.1651)
		(layer "F.Cu")
		(net "M_K_DQ<15>")
	)
	(segment
		(start 68.607686 -97.690686)
		(end 68.159122 -97.242122)
		(width 0.0889)
		(layer "F.Cu")
		(net "M_K_DQ<15>")
	)
	(segment
		(start 47.927768 -129.952496)
		(end 47.549308 -130.330956)
		(width 0.1651)
		(layer "F.Cu")
		(net "M_K_DQ<15>")
	)
	(segment
		(start 66.449956 -97.242122)
		(end 49.537366 -114.154712)
		(width 0.1651)
		(layer "F.Cu")
		(net "M_K_DQ<15>")
	)
	(segment
		(start 67.69735 -97.242122)
		(end 66.449956 -97.242122)
		(width 0.1651)
		(layer "F.Cu")
		(net "M_K_DQ<15>")
	)
	(segment
		(start 49.537366 -114.154712)
		(end 49.537366 -122.88774)
		(width 0.1651)
		(layer "F.Cu")
		(net "M_K_DQ<15>")
	)
	(segment
		(start 49.387506 -123.0376)
		(end 49.054766 -123.0376)
		(width 0.1651)
		(layer "F.Cu")
		(net "M_K_DQ<15>")
	)
	(segment
		(start 48.170846 -128.788922)
		(end 47.927768 -129.032)
		(width 0.1651)
		(layer "F.Cu")
		(net "M_K_DQ<15>")
	)
	(segment
		(start 48.854106 -122.83694)
		(end 48.854106 -118.782338)
		(width 0.1651)
		(layer "F.Cu")
		(net "M_K_DQ<15>")
	)
	(segment
		(start 49.537366 -122.88774)
		(end 49.387506 -123.0376)
		(width 0.1651)
		(layer "F.Cu")
		(net "M_K_DQ<15>")
	)
	(segment
		(start 48.170846 -118.782338)
		(end 48.170846 -128.788922)
		(width 0.1651)
		(layer "F.Cu")
		(net "M_K_DQ<15>")
	)
	(segment
		(start 46.699424 -133.0706)
		(end 46.699424 -134.340346)
		(width 0.1651)
		(layer "F.Cu")
		(net "M_K_DQ<15>")
	)
	(segment
		(start 48.346106 -118.607078)
		(end 48.170846 -118.782338)
		(width 0.1651)
		(layer "F.Cu")
		(net "M_K_DQ<15>")
	)
	(segment
		(start 48.854106 -118.782338)
		(end 48.678846 -118.607078)
		(width 0.1651)
		(layer "F.Cu")
		(net "M_K_DQ<15>")
	)
	(via
		(at 47.549308 -130.330956)
		(size 0.508)
		(drill 0.254)
		(layers "F.Cu" "B.Cu")
		(net "M_K_DQ<15>")
	)
	(via
		(at 46.699424 -134.340346)
		(size 0.508)
		(drill 0.254)
		(layers "F.Cu" "B.Cu")
		(net "M_K_DQ<15>")
	)
	(segment
		(start 47.549308 -128.276096)
		(end 47.549308 -130.330956)
		(width 0.1651)
		(layer "B.Cu")
		(net "M_K_DQ<15>")
	)
	(segment
		(start 47.549562 -128.276096)
		(end 47.549308 -128.276096)
		(width 0.1651)
		(layer "B.Cu")
		(net "M_K_DQ<15>")
	)
	(segment
		(start 47.143162 -131.9022)
		(end 47.143162 -131.233418)
		(width 0.14224)
		(layer "In2.Cu")
		(net "M_K_DQ<15>")
	)
	(segment
		(start 46.860714 -133.550152)
		(end 46.860714 -133.276848)
		(width 0.14224)
		(layer "In2.Cu")
		(net "M_K_DQ<15>")
	)
	(segment
		(start 46.971712 -134.340346)
		(end 47.149512 -134.162546)
		(width 0.14224)
		(layer "In2.Cu")
		(net "M_K_DQ<15>")
	)
	(segment
		(start 47.098712 -131.188968)
		(end 47.098712 -130.7592)
		(width 0.14224)
		(layer "In2.Cu")
		(net "M_K_DQ<15>")
	)
	(segment
		(start 46.699424 -134.340346)
		(end 46.971712 -134.340346)
		(width 0.14224)
		(layer "In2.Cu")
		(net "M_K_DQ<15>")
	)
	(segment
		(start 46.860714 -133.276848)
		(end 47.117762 -133.0198)
		(width 0.14224)
		(layer "In2.Cu")
		(net "M_K_DQ<15>")
	)
	(segment
		(start 47.526956 -130.330956)
		(end 47.549308 -130.330956)
		(width 0.14224)
		(layer "In2.Cu")
		(net "M_K_DQ<15>")
	)
	(segment
		(start 47.117762 -133.0198)
		(end 47.117762 -132.715)
		(width 0.14224)
		(layer "In2.Cu")
		(net "M_K_DQ<15>")
	)
	(segment
		(start 47.149512 -134.162546)
		(end 47.149512 -133.83895)
		(width 0.14224)
		(layer "In2.Cu")
		(net "M_K_DQ<15>")
	)
	(segment
		(start 47.117762 -132.715)
		(end 46.860714 -132.457952)
		(width 0.14224)
		(layer "In2.Cu")
		(net "M_K_DQ<15>")
	)
	(segment
		(start 46.860714 -132.184648)
		(end 47.143162 -131.9022)
		(width 0.14224)
		(layer "In2.Cu")
		(net "M_K_DQ<15>")
	)
	(segment
		(start 46.860714 -132.457952)
		(end 46.860714 -132.184648)
		(width 0.14224)
		(layer "In2.Cu")
		(net "M_K_DQ<15>")
	)
	(segment
		(start 47.143162 -131.233418)
		(end 47.098712 -131.188968)
		(width 0.14224)
		(layer "In2.Cu")
		(net "M_K_DQ<15>")
	)
	(segment
		(start 47.149512 -133.83895)
		(end 46.860714 -133.550152)
		(width 0.14224)
		(layer "In2.Cu")
		(net "M_K_DQ<15>")
	)
	(segment
		(start 47.098712 -130.7592)
		(end 47.526956 -130.330956)
		(width 0.14224)
		(layer "In2.Cu")
		(net "M_K_DQ<15>")
	)
	(segment
		(start 69.466206 -96.20504)
		(end 67.73291 -96.20504)
		(width 0.0889)
		(layer "F.Cu")
		(net "M_K_DQ<14>")
	)
	(segment
		(start 48.003968 -115.1382)
		(end 47.671228 -115.1382)
		(width 0.1651)
		(layer "F.Cu")
		(net "M_K_DQ<14>")
	)
	(segment
		(start 47.681642 -136.57072)
		(end 47.681642 -136.35228)
		(width 0.1651)
		(layer "F.Cu")
		(net "M_K_DQ<14>")
	)
	(segment
		(start 47.549562 -136.2202)
		(end 47.549562 -135.915654)
		(width 0.1651)
		(layer "F.Cu")
		(net "M_K_DQ<14>")
	)
	(segment
		(start 47.495968 -128.524)
		(end 47.241968 -128.778)
		(width 0.1651)
		(layer "F.Cu")
		(net "M_K_DQ<14>")
	)
	(segment
		(start 47.241968 -129.7432)
		(end 46.699424 -130.285744)
		(width 0.1651)
		(layer "F.Cu")
		(net "M_K_DQ<14>")
	)
	(segment
		(start 46.699424 -130.285744)
		(end 46.699424 -131.611878)
		(width 0.1651)
		(layer "F.Cu")
		(net "M_K_DQ<14>")
	)
	(segment
		(start 47.549562 -135.915654)
		(end 47.549308 -135.9154)
		(width 0.1651)
		(layer "F.Cu")
		(net "M_K_DQ<14>")
	)
	(segment
		(start 48.179228 -115.31346)
		(end 48.003968 -115.1382)
		(width 0.1651)
		(layer "F.Cu")
		(net "M_K_DQ<14>")
	)
	(segment
		(start 47.549562 -136.7028)
		(end 47.681642 -136.57072)
		(width 0.1651)
		(layer "F.Cu")
		(net "M_K_DQ<14>")
	)
	(segment
		(start 48.862488 -117.75694)
		(end 48.687228 -117.9322)
		(width 0.1651)
		(layer "F.Cu")
		(net "M_K_DQ<14>")
	)
	(segment
		(start 67.73291 -96.20504)
		(end 66.52006 -96.20504)
		(width 0.1651)
		(layer "F.Cu")
		(net "M_K_DQ<14>")
	)
	(segment
		(start 47.241968 -128.778)
		(end 47.241968 -129.7432)
		(width 0.1651)
		(layer "F.Cu")
		(net "M_K_DQ<14>")
	)
	(segment
		(start 47.549562 -137.67054)
		(end 47.549562 -136.7028)
		(width 0.1651)
		(layer "F.Cu")
		(net "M_K_DQ<14>")
	)
	(segment
		(start 48.687228 -117.9322)
		(end 48.354488 -117.9322)
		(width 0.1651)
		(layer "F.Cu")
		(net "M_K_DQ<14>")
	)
	(segment
		(start 47.681642 -136.35228)
		(end 47.549562 -136.2202)
		(width 0.1651)
		(layer "F.Cu")
		(net "M_K_DQ<14>")
	)
	(segment
		(start 48.862488 -113.862612)
		(end 48.862488 -117.75694)
		(width 0.1651)
		(layer "F.Cu")
		(net "M_K_DQ<14>")
	)
	(segment
		(start 48.179228 -117.75694)
		(end 48.179228 -115.31346)
		(width 0.1651)
		(layer "F.Cu")
		(net "M_K_DQ<14>")
	)
	(segment
		(start 66.52006 -96.20504)
		(end 48.862488 -113.862612)
		(width 0.1651)
		(layer "F.Cu")
		(net "M_K_DQ<14>")
	)
	(segment
		(start 47.671228 -115.1382)
		(end 47.495968 -115.31346)
		(width 0.1651)
		(layer "F.Cu")
		(net "M_K_DQ<14>")
	)
	(segment
		(start 48.354488 -117.9322)
		(end 48.179228 -117.75694)
		(width 0.1651)
		(layer "F.Cu")
		(net "M_K_DQ<14>")
	)
	(segment
		(start 47.495968 -115.31346)
		(end 47.495968 -128.524)
		(width 0.1651)
		(layer "F.Cu")
		(net "M_K_DQ<14>")
	)
	(via
		(at 46.699424 -131.611878)
		(size 0.508)
		(drill 0.254)
		(layers "F.Cu" "B.Cu")
		(net "M_K_DQ<14>")
	)
	(via
		(at 47.549308 -135.9154)
		(size 0.508)
		(drill 0.254)
		(layers "F.Cu" "B.Cu")
		(net "M_K_DQ<14>")
	)
	(segment
		(start 46.699424 -132.876036)
		(end 46.699424 -131.611878)
		(width 0.1651)
		(layer "B.Cu")
		(net "M_K_DQ<14>")
	)
	(segment
		(start 46.266354 -134.632446)
		(end 46.266354 -132.044948)
		(width 0.14224)
		(layer "In2.Cu")
		(net "M_K_DQ<14>")
	)
	(segment
		(start 46.266354 -132.044948)
		(end 46.699424 -131.611878)
		(width 0.14224)
		(layer "In2.Cu")
		(net "M_K_DQ<14>")
	)
	(segment
		(start 47.549308 -135.9154)
		(end 46.266354 -134.632446)
		(width 0.14224)
		(layer "In2.Cu")
		(net "M_K_DQ<14>")
	)
	(segment
		(start 41.88841 -129.965704)
		(end 41.523158 -130.330956)
		(width 0.1651)
		(layer "F.Cu")
		(net "M_K_DQ<13>")
	)
	(segment
		(start 69.466206 -91.25204)
		(end 69.399404 -91.318842)
		(width 0.0889)
		(layer "F.Cu")
		(net "M_K_DQ<13>")
	)
	(segment
		(start 65.501266 -91.567)
		(end 42.593768 -114.474498)
		(width 0.1651)
		(layer "F.Cu")
		(net "M_K_DQ<13>")
	)
	(segment
		(start 67.44208 -91.567)
		(end 65.501266 -91.567)
		(width 0.1651)
		(layer "F.Cu")
		(net "M_K_DQ<13>")
	)
	(segment
		(start 41.88841 -127.451104)
		(end 41.88841 -129.965704)
		(width 0.1651)
		(layer "F.Cu")
		(net "M_K_DQ<13>")
	)
	(segment
		(start 40.749474 -133.0706)
		(end 40.749474 -134.340346)
		(width 0.1651)
		(layer "F.Cu")
		(net "M_K_DQ<13>")
	)
	(segment
		(start 67.690238 -91.318842)
		(end 67.44208 -91.567)
		(width 0.0889)
		(layer "F.Cu")
		(net "M_K_DQ<13>")
	)
	(segment
		(start 69.399404 -91.318842)
		(end 67.690238 -91.318842)
		(width 0.0889)
		(layer "F.Cu")
		(net "M_K_DQ<13>")
	)
	(segment
		(start 42.593768 -114.474498)
		(end 42.593768 -126.745746)
		(width 0.1651)
		(layer "F.Cu")
		(net "M_K_DQ<13>")
	)
	(segment
		(start 42.593768 -126.745746)
		(end 41.88841 -127.451104)
		(width 0.1651)
		(layer "F.Cu")
		(net "M_K_DQ<13>")
	)
	(via
		(at 40.749474 -134.340346)
		(size 0.508)
		(drill 0.254)
		(layers "F.Cu" "B.Cu")
		(net "M_K_DQ<13>")
	)
	(via
		(at 41.523158 -130.330956)
		(size 0.508)
		(drill 0.254)
		(layers "F.Cu" "B.Cu")
		(net "M_K_DQ<13>")
	)
	(segment
		(start 41.599358 -128.276096)
		(end 41.599358 -130.254756)
		(width 0.1651)
		(layer "B.Cu")
		(net "M_K_DQ<13>")
	)
	(segment
		(start 41.599358 -130.254756)
		(end 41.523158 -130.330956)
		(width 0.1651)
		(layer "B.Cu")
		(net "M_K_DQ<13>")
	)
	(segment
		(start 41.174162 -134.187946)
		(end 41.174162 -133.959854)
		(width 0.14224)
		(layer "In2.Cu")
		(net "M_K_DQ<13>")
	)
	(segment
		(start 40.910764 -133.696456)
		(end 40.910764 -133.384544)
		(width 0.14224)
		(layer "In2.Cu")
		(net "M_K_DQ<13>")
	)
	(segment
		(start 41.148762 -133.146546)
		(end 41.148762 -132.791454)
		(width 0.14224)
		(layer "In2.Cu")
		(net "M_K_DQ<13>")
	)
	(segment
		(start 41.072562 -130.7592)
		(end 41.500806 -130.330956)
		(width 0.14224)
		(layer "In2.Cu")
		(net "M_K_DQ<13>")
	)
	(segment
		(start 40.749474 -134.340346)
		(end 41.021762 -134.340346)
		(width 0.14224)
		(layer "In2.Cu")
		(net "M_K_DQ<13>")
	)
	(segment
		(start 41.072562 -131.318)
		(end 41.072562 -130.7592)
		(width 0.14224)
		(layer "In2.Cu")
		(net "M_K_DQ<13>")
	)
	(segment
		(start 41.148762 -132.791454)
		(end 40.910764 -132.553456)
		(width 0.14224)
		(layer "In2.Cu")
		(net "M_K_DQ<13>")
	)
	(segment
		(start 41.199562 -131.445)
		(end 41.072562 -131.318)
		(width 0.14224)
		(layer "In2.Cu")
		(net "M_K_DQ<13>")
	)
	(segment
		(start 40.910764 -133.384544)
		(end 41.148762 -133.146546)
		(width 0.14224)
		(layer "In2.Cu")
		(net "M_K_DQ<13>")
	)
	(segment
		(start 40.910764 -132.553456)
		(end 40.910764 -132.216144)
		(width 0.14224)
		(layer "In2.Cu")
		(net "M_K_DQ<13>")
	)
	(segment
		(start 41.021762 -134.340346)
		(end 41.174162 -134.187946)
		(width 0.14224)
		(layer "In2.Cu")
		(net "M_K_DQ<13>")
	)
	(segment
		(start 40.910764 -132.216144)
		(end 41.199562 -131.927346)
		(width 0.14224)
		(layer "In2.Cu")
		(net "M_K_DQ<13>")
	)
	(segment
		(start 41.500806 -130.330956)
		(end 41.523158 -130.330956)
		(width 0.14224)
		(layer "In2.Cu")
		(net "M_K_DQ<13>")
	)
	(segment
		(start 41.199562 -131.927346)
		(end 41.199562 -131.445)
		(width 0.14224)
		(layer "In2.Cu")
		(net "M_K_DQ<13>")
	)
	(segment
		(start 41.174162 -133.959854)
		(end 40.910764 -133.696456)
		(width 0.14224)
		(layer "In2.Cu")
		(net "M_K_DQ<13>")
	)
	(segment
		(start 40.749474 -130.374898)
		(end 40.749474 -131.611878)
		(width 0.1651)
		(layer "F.Cu")
		(net "M_K_DQ<12>")
	)
	(segment
		(start 41.907968 -126.4412)
		(end 41.215564 -127.133604)
		(width 0.1651)
		(layer "F.Cu")
		(net "M_K_DQ<12>")
	)
	(segment
		(start 41.907968 -114.205766)
		(end 41.907968 -126.4412)
		(width 0.1651)
		(layer "F.Cu")
		(net "M_K_DQ<12>")
	)
	(segment
		(start 65.357248 -90.756486)
		(end 41.907968 -114.205766)
		(width 0.1651)
		(layer "F.Cu")
		(net "M_K_DQ<12>")
	)
	(segment
		(start 41.215564 -129.908808)
		(end 40.749474 -130.374898)
		(width 0.1651)
		(layer "F.Cu")
		(net "M_K_DQ<12>")
	)
	(segment
		(start 41.215564 -127.133604)
		(end 41.215564 -129.908808)
		(width 0.1651)
		(layer "F.Cu")
		(net "M_K_DQ<12>")
	)
	(segment
		(start 67.43573 -90.756486)
		(end 65.357248 -90.756486)
		(width 0.1651)
		(layer "F.Cu")
		(net "M_K_DQ<12>")
	)
	(segment
		(start 68.607686 -90.756486)
		(end 67.43573 -90.756486)
		(width 0.0889)
		(layer "F.Cu")
		(net "M_K_DQ<12>")
	)
	(segment
		(start 41.599358 -136.345168)
		(end 41.501314 -135.8138)
		(width 0.1651)
		(layer "F.Cu")
		(net "M_K_DQ<12>")
	)
	(segment
		(start 41.599358 -137.67054)
		(end 41.599358 -136.345168)
		(width 0.1651)
		(layer "F.Cu")
		(net "M_K_DQ<12>")
	)
	(via
		(at 41.501314 -135.8138)
		(size 0.508)
		(drill 0.254)
		(layers "F.Cu" "B.Cu")
		(net "M_K_DQ<12>")
	)
	(via
		(at 40.749474 -131.611878)
		(size 0.508)
		(drill 0.254)
		(layers "F.Cu" "B.Cu")
		(net "M_K_DQ<12>")
	)
	(segment
		(start 40.749474 -132.876036)
		(end 40.749474 -131.611878)
		(width 0.1651)
		(layer "B.Cu")
		(net "M_K_DQ<12>")
	)
	(segment
		(start 41.250362 -135.8138)
		(end 40.474392 -135.03783)
		(width 0.14224)
		(layer "In2.Cu")
		(net "M_K_DQ<12>")
	)
	(segment
		(start 40.474392 -135.03783)
		(end 40.474392 -134.736078)
		(width 0.14224)
		(layer "In2.Cu")
		(net "M_K_DQ<12>")
	)
	(segment
		(start 41.501314 -135.8138)
		(end 41.250362 -135.8138)
		(width 0.14224)
		(layer "In2.Cu")
		(net "M_K_DQ<12>")
	)
	(segment
		(start 40.474392 -134.736078)
		(end 40.316404 -134.57809)
		(width 0.14224)
		(layer "In2.Cu")
		(net "M_K_DQ<12>")
	)
	(segment
		(start 40.316404 -134.57809)
		(end 40.316404 -132.044948)
		(width 0.14224)
		(layer "In2.Cu")
		(net "M_K_DQ<12>")
	)
	(segment
		(start 40.316404 -132.044948)
		(end 40.749474 -131.611878)
		(width 0.14224)
		(layer "In2.Cu")
		(net "M_K_DQ<12>")
	)
	(segment
		(start 50.899568 -114.7318)
		(end 50.899568 -123.921012)
		(width 0.1651)
		(layer "F.Cu")
		(net "M_K_DQ<11>")
	)
	(segment
		(start 51.407568 -124.086112)
		(end 51.572668 -123.921012)
		(width 0.1651)
		(layer "F.Cu")
		(net "M_K_DQ<11>")
	)
	(segment
		(start 67.828668 -98.28149)
		(end 67.572636 -98.537522)
		(width 0.0889)
		(layer "F.Cu")
		(net "M_K_DQ<11>")
	)
	(segment
		(start 51.737768 -120.5484)
		(end 52.080668 -120.5484)
		(width 0.1651)
		(layer "F.Cu")
		(net "M_K_DQ<11>")
	)
	(segment
		(start 52.245768 -127.362712)
		(end 52.004468 -127.604012)
		(width 0.1651)
		(layer "F.Cu")
		(net "M_K_DQ<11>")
	)
	(segment
		(start 67.093846 -98.537522)
		(end 50.899568 -114.7318)
		(width 0.1651)
		(layer "F.Cu")
		(net "M_K_DQ<11>")
	)
	(segment
		(start 50.016156 -127.604012)
		(end 49.533048 -128.08712)
		(width 0.1651)
		(layer "F.Cu")
		(net "M_K_DQ<11>")
	)
	(segment
		(start 52.245768 -120.7135)
		(end 52.245768 -127.362712)
		(width 0.1651)
		(layer "F.Cu")
		(net "M_K_DQ<11>")
	)
	(segment
		(start 51.572668 -123.921012)
		(end 51.572668 -120.7135)
		(width 0.1651)
		(layer "F.Cu")
		(net "M_K_DQ<11>")
	)
	(segment
		(start 48.399446 -133.0706)
		(end 48.399446 -134.340346)
		(width 0.1651)
		(layer "F.Cu")
		(net "M_K_DQ<11>")
	)
	(segment
		(start 69.224144 -98.681286)
		(end 68.824348 -98.28149)
		(width 0.0889)
		(layer "F.Cu")
		(net "M_K_DQ<11>")
	)
	(segment
		(start 50.899568 -123.921012)
		(end 51.064668 -124.086112)
		(width 0.1651)
		(layer "F.Cu")
		(net "M_K_DQ<11>")
	)
	(segment
		(start 51.572668 -120.7135)
		(end 51.737768 -120.5484)
		(width 0.1651)
		(layer "F.Cu")
		(net "M_K_DQ<11>")
	)
	(segment
		(start 49.533048 -128.08712)
		(end 49.533048 -130.047238)
		(width 0.1651)
		(layer "F.Cu")
		(net "M_K_DQ<11>")
	)
	(segment
		(start 49.533048 -130.047238)
		(end 49.24933 -130.330956)
		(width 0.1651)
		(layer "F.Cu")
		(net "M_K_DQ<11>")
	)
	(segment
		(start 52.004468 -127.604012)
		(end 50.016156 -127.604012)
		(width 0.1651)
		(layer "F.Cu")
		(net "M_K_DQ<11>")
	)
	(segment
		(start 67.572636 -98.537522)
		(end 67.093846 -98.537522)
		(width 0.1651)
		(layer "F.Cu")
		(net "M_K_DQ<11>")
	)
	(segment
		(start 52.080668 -120.5484)
		(end 52.245768 -120.7135)
		(width 0.1651)
		(layer "F.Cu")
		(net "M_K_DQ<11>")
	)
	(segment
		(start 70.324726 -98.681286)
		(end 69.224144 -98.681286)
		(width 0.0889)
		(layer "F.Cu")
		(net "M_K_DQ<11>")
	)
	(segment
		(start 68.824348 -98.28149)
		(end 67.828668 -98.28149)
		(width 0.0889)
		(layer "F.Cu")
		(net "M_K_DQ<11>")
	)
	(segment
		(start 51.064668 -124.086112)
		(end 51.407568 -124.086112)
		(width 0.1651)
		(layer "F.Cu")
		(net "M_K_DQ<11>")
	)
	(via
		(at 49.24933 -130.330956)
		(size 0.508)
		(drill 0.254)
		(layers "F.Cu" "B.Cu")
		(net "M_K_DQ<11>")
	)
	(via
		(at 48.399446 -134.340346)
		(size 0.508)
		(drill 0.254)
		(layers "F.Cu" "B.Cu")
		(net "M_K_DQ<11>")
	)
	(segment
		(start 49.24933 -128.276096)
		(end 49.24933 -130.330956)
		(width 0.1651)
		(layer "B.Cu")
		(net "M_K_DQ<11>")
	)
	(segment
		(start 49.249584 -128.276096)
		(end 49.24933 -128.276096)
		(width 0.1651)
		(layer "B.Cu")
		(net "M_K_DQ<11>")
	)
	(segment
		(start 48.560736 -132.184648)
		(end 48.560736 -132.457952)
		(width 0.14224)
		(layer "In2.Cu")
		(net "M_K_DQ<11>")
	)
	(segment
		(start 48.560736 -133.276848)
		(end 48.560736 -133.550152)
		(width 0.14224)
		(layer "In2.Cu")
		(net "M_K_DQ<11>")
	)
	(segment
		(start 48.560736 -133.550152)
		(end 48.849534 -133.83895)
		(width 0.14224)
		(layer "In2.Cu")
		(net "M_K_DQ<11>")
	)
	(segment
		(start 48.798734 -131.188968)
		(end 48.843184 -131.233418)
		(width 0.14224)
		(layer "In2.Cu")
		(net "M_K_DQ<11>")
	)
	(segment
		(start 48.843184 -131.233418)
		(end 48.843184 -131.9022)
		(width 0.14224)
		(layer "In2.Cu")
		(net "M_K_DQ<11>")
	)
	(segment
		(start 48.671734 -134.340346)
		(end 48.399446 -134.340346)
		(width 0.14224)
		(layer "In2.Cu")
		(net "M_K_DQ<11>")
	)
	(segment
		(start 48.798734 -130.7592)
		(end 48.798734 -131.188968)
		(width 0.14224)
		(layer "In2.Cu")
		(net "M_K_DQ<11>")
	)
	(segment
		(start 48.817784 -133.0198)
		(end 48.560736 -133.276848)
		(width 0.14224)
		(layer "In2.Cu")
		(net "M_K_DQ<11>")
	)
	(segment
		(start 49.226978 -130.330956)
		(end 48.798734 -130.7592)
		(width 0.14224)
		(layer "In2.Cu")
		(net "M_K_DQ<11>")
	)
	(segment
		(start 48.849534 -134.162546)
		(end 48.671734 -134.340346)
		(width 0.14224)
		(layer "In2.Cu")
		(net "M_K_DQ<11>")
	)
	(segment
		(start 48.817784 -132.715)
		(end 48.817784 -133.0198)
		(width 0.14224)
		(layer "In2.Cu")
		(net "M_K_DQ<11>")
	)
	(segment
		(start 48.560736 -132.457952)
		(end 48.817784 -132.715)
		(width 0.14224)
		(layer "In2.Cu")
		(net "M_K_DQ<11>")
	)
	(segment
		(start 48.849534 -133.83895)
		(end 48.849534 -134.162546)
		(width 0.14224)
		(layer "In2.Cu")
		(net "M_K_DQ<11>")
	)
	(segment
		(start 48.843184 -131.9022)
		(end 48.560736 -132.184648)
		(width 0.14224)
		(layer "In2.Cu")
		(net "M_K_DQ<11>")
	)
	(segment
		(start 49.24933 -130.330956)
		(end 49.226978 -130.330956)
		(width 0.14224)
		(layer "In2.Cu")
		(net "M_K_DQ<11>")
	)
	(segment
		(start 49.249584 -137.67054)
		(end 49.24933 -137.67054)
		(width 0.1651)
		(layer "F.Cu")
		(net "M_K_DQ<10>")
	)
	(segment
		(start 49.713896 -126.8476)
		(end 49.538636 -126.67234)
		(width 0.1651)
		(layer "F.Cu")
		(net "M_K_DQ<10>")
	)
	(segment
		(start 49.24933 -136.679432)
		(end 49.380902 -136.54786)
		(width 0.1651)
		(layer "F.Cu")
		(net "M_K_DQ<10>")
	)
	(segment
		(start 50.221896 -114.43716)
		(end 50.221896 -126.67234)
		(width 0.1651)
		(layer "F.Cu")
		(net "M_K_DQ<10>")
	)
	(segment
		(start 49.538636 -126.67234)
		(end 49.538636 -123.87326)
		(width 0.1651)
		(layer "F.Cu")
		(net "M_K_DQ<10>")
	)
	(segment
		(start 49.380902 -136.32434)
		(end 49.24933 -136.192768)
		(width 0.1651)
		(layer "F.Cu")
		(net "M_K_DQ<10>")
	)
	(segment
		(start 49.380902 -136.54786)
		(end 49.380902 -136.32434)
		(width 0.1651)
		(layer "F.Cu")
		(net "M_K_DQ<10>")
	)
	(segment
		(start 69.224906 -97.690686)
		(end 68.850256 -98.065336)
		(width 0.0889)
		(layer "F.Cu")
		(net "M_K_DQ<10>")
	)
	(segment
		(start 50.046636 -126.8476)
		(end 49.713896 -126.8476)
		(width 0.1651)
		(layer "F.Cu")
		(net "M_K_DQ<10>")
	)
	(segment
		(start 49.24933 -137.67054)
		(end 49.24933 -136.679432)
		(width 0.1651)
		(layer "F.Cu")
		(net "M_K_DQ<10>")
	)
	(segment
		(start 68.850256 -98.065336)
		(end 67.86245 -98.065336)
		(width 0.0889)
		(layer "F.Cu")
		(net "M_K_DQ<10>")
	)
	(segment
		(start 67.686936 -97.889822)
		(end 66.769234 -97.889822)
		(width 0.1651)
		(layer "F.Cu")
		(net "M_K_DQ<10>")
	)
	(segment
		(start 49.363376 -123.698)
		(end 49.030636 -123.698)
		(width 0.1651)
		(layer "F.Cu")
		(net "M_K_DQ<10>")
	)
	(segment
		(start 48.855376 -123.87326)
		(end 48.855376 -129.888996)
		(width 0.1651)
		(layer "F.Cu")
		(net "M_K_DQ<10>")
	)
	(segment
		(start 49.24933 -136.192768)
		(end 49.24933 -135.9154)
		(width 0.1651)
		(layer "F.Cu")
		(net "M_K_DQ<10>")
	)
	(segment
		(start 48.855376 -129.888996)
		(end 48.399446 -130.344926)
		(width 0.1651)
		(layer "F.Cu")
		(net "M_K_DQ<10>")
	)
	(segment
		(start 49.030636 -123.698)
		(end 48.855376 -123.87326)
		(width 0.1651)
		(layer "F.Cu")
		(net "M_K_DQ<10>")
	)
	(segment
		(start 50.221896 -126.67234)
		(end 50.046636 -126.8476)
		(width 0.1651)
		(layer "F.Cu")
		(net "M_K_DQ<10>")
	)
	(segment
		(start 66.769234 -97.889822)
		(end 50.221896 -114.43716)
		(width 0.1651)
		(layer "F.Cu")
		(net "M_K_DQ<10>")
	)
	(segment
		(start 49.538636 -123.87326)
		(end 49.363376 -123.698)
		(width 0.1651)
		(layer "F.Cu")
		(net "M_K_DQ<10>")
	)
	(segment
		(start 48.399446 -130.344926)
		(end 48.399446 -131.611878)
		(width 0.1651)
		(layer "F.Cu")
		(net "M_K_DQ<10>")
	)
	(segment
		(start 67.86245 -98.065336)
		(end 67.686936 -97.889822)
		(width 0.0889)
		(layer "F.Cu")
		(net "M_K_DQ<10>")
	)
	(segment
		(start 70.324726 -97.690686)
		(end 69.224906 -97.690686)
		(width 0.0889)
		(layer "F.Cu")
		(net "M_K_DQ<10>")
	)
	(via
		(at 48.399446 -131.611878)
		(size 0.508)
		(drill 0.254)
		(layers "F.Cu" "B.Cu")
		(net "M_K_DQ<10>")
	)
	(via
		(at 49.24933 -135.9154)
		(size 0.508)
		(drill 0.254)
		(layers "F.Cu" "B.Cu")
		(net "M_K_DQ<10>")
	)
	(segment
		(start 48.399446 -132.876036)
		(end 48.399446 -131.611878)
		(width 0.1651)
		(layer "B.Cu")
		(net "M_K_DQ<10>")
	)
	(segment
		(start 49.24933 -135.9154)
		(end 47.966376 -134.632446)
		(width 0.14224)
		(layer "In2.Cu")
		(net "M_K_DQ<10>")
	)
	(segment
		(start 47.966376 -134.632446)
		(end 47.966376 -132.044948)
		(width 0.14224)
		(layer "In2.Cu")
		(net "M_K_DQ<10>")
	)
	(segment
		(start 47.966376 -132.044948)
		(end 48.399446 -131.611878)
		(width 0.14224)
		(layer "In2.Cu")
		(net "M_K_DQ<10>")
	)
	(segment
		(start 33.949386 -137.67054)
		(end 33.949386 -137.676382)
		(width 0.1651)
		(layer "F.Cu")
		(net "M_K_DQ<0>")
	)
	(segment
		(start 33.949386 -137.676382)
		(end 33.771586 -135.8138)
		(width 0.1651)
		(layer "F.Cu")
		(net "M_K_DQ<0>")
	)
	(segment
		(start 69.466206 -85.30844)
		(end 68.894706 -85.30844)
		(width 0.1651)
		(layer "F.Cu")
		(net "M_K_DQ<0>")
	)
	(via
		(at 33.099502 -131.611878)
		(size 0.508)
		(drill 0.254)
		(layers "F.Cu" "B.Cu")
		(net "M_K_DQ<0>")
	)
	(via
		(at 68.894706 -85.30844)
		(size 0.508)
		(drill 0.254)
		(layers "F.Cu" "B.Cu")
		(net "M_K_DQ<0>")
	)
	(via
		(at 33.771586 -135.8138)
		(size 0.508)
		(drill 0.254)
		(layers "F.Cu" "B.Cu")
		(net "M_K_DQ<0>")
	)
	(segment
		(start 33.099502 -132.876036)
		(end 33.099502 -131.611878)
		(width 0.1651)
		(layer "B.Cu")
		(net "M_K_DQ<0>")
	)
	(segment
		(start 33.602168 -121.92)
		(end 33.602168 -129.722118)
		(width 0.14224)
		(layer "In2.Cu")
		(net "M_K_DQ<0>")
	)
	(segment
		(start 32.814768 -131.327144)
		(end 33.099502 -131.611878)
		(width 0.14224)
		(layer "In2.Cu")
		(net "M_K_DQ<0>")
	)
	(segment
		(start 34.173414 -116.065554)
		(end 34.173414 -121.348754)
		(width 0.14224)
		(layer "In2.Cu")
		(net "M_K_DQ<0>")
	)
	(segment
		(start 68.894706 -85.30844)
		(end 67.868292 -85.30844)
		(width 0.0889)
		(layer "In2.Cu")
		(net "M_K_DQ<0>")
	)
	(segment
		(start 34.173414 -121.348754)
		(end 33.602168 -121.92)
		(width 0.14224)
		(layer "In2.Cu")
		(net "M_K_DQ<0>")
	)
	(segment
		(start 33.602168 -129.722118)
		(end 32.814768 -130.509518)
		(width 0.14224)
		(layer "In2.Cu")
		(net "M_K_DQ<0>")
	)
	(segment
		(start 67.373754 -84.813902)
		(end 67.20967 -84.813902)
		(width 0.0889)
		(layer "In2.Cu")
		(net "M_K_DQ<0>")
	)
	(segment
		(start 65.859914 -85.048344)
		(end 64.638428 -85.048344)
		(width 0.14224)
		(layer "In2.Cu")
		(net "M_K_DQ<0>")
	)
	(segment
		(start 38.605968 -112.5728)
		(end 37.666168 -112.5728)
		(width 0.14224)
		(layer "In2.Cu")
		(net "M_K_DQ<0>")
	)
	(segment
		(start 67.20967 -84.813902)
		(end 66.796158 -84.81441)
		(width 0.0889)
		(layer "In2.Cu")
		(net "M_K_DQ<0>")
	)
	(segment
		(start 66.796158 -84.81441)
		(end 66.562224 -85.048344)
		(width 0.0889)
		(layer "In2.Cu")
		(net "M_K_DQ<0>")
	)
	(segment
		(start 33.099502 -131.611878)
		(end 32.666432 -132.044948)
		(width 0.14224)
		(layer "In2.Cu")
		(net "M_K_DQ<0>")
	)
	(segment
		(start 32.814768 -130.509518)
		(end 32.814768 -131.327144)
		(width 0.14224)
		(layer "In2.Cu")
		(net "M_K_DQ<0>")
	)
	(segment
		(start 66.562224 -85.048344)
		(end 65.859914 -85.048344)
		(width 0.0889)
		(layer "In2.Cu")
		(net "M_K_DQ<0>")
	)
	(segment
		(start 64.638428 -85.048344)
		(end 50.772568 -98.914204)
		(width 0.14224)
		(layer "In2.Cu")
		(net "M_K_DQ<0>")
	)
	(segment
		(start 32.666432 -132.044948)
		(end 32.666432 -134.708646)
		(width 0.14224)
		(layer "In2.Cu")
		(net "M_K_DQ<0>")
	)
	(segment
		(start 67.868292 -85.30844)
		(end 67.373754 -84.813902)
		(width 0.0889)
		(layer "In2.Cu")
		(net "M_K_DQ<0>")
	)
	(segment
		(start 50.772568 -98.914204)
		(end 50.772568 -100.4062)
		(width 0.14224)
		(layer "In2.Cu")
		(net "M_K_DQ<0>")
	)
	(segment
		(start 50.772568 -100.4062)
		(end 38.605968 -112.5728)
		(width 0.14224)
		(layer "In2.Cu")
		(net "M_K_DQ<0>")
	)
	(segment
		(start 37.666168 -112.5728)
		(end 34.173414 -116.065554)
		(width 0.14224)
		(layer "In2.Cu")
		(net "M_K_DQ<0>")
	)
	(segment
		(start 32.666432 -134.708646)
		(end 33.771586 -135.8138)
		(width 0.14224)
		(layer "In2.Cu")
		(net "M_K_DQ<0>")
	)
	(segment
		(start 109.180884 -124.199396)
		(end 109.009942 -124.370338)
		(width 0.1651)
		(layer "F.Cu")
		(net "M_K_CS_N<7>")
	)
	(segment
		(start 106.528616 -121.867168)
		(end 106.688636 -121.707148)
		(width 0.1651)
		(layer "F.Cu")
		(net "M_K_CS_N<7>")
	)
	(segment
		(start 105.421684 -120.420892)
		(end 105.63606 -120.420892)
		(width 0.1651)
		(layer "F.Cu")
		(net "M_K_CS_N<7>")
	)
	(segment
		(start 103.620062 -102.595934)
		(end 103.620062 -102.938834)
		(width 0.1651)
		(layer "F.Cu")
		(net "M_K_CS_N<7>")
	)
	(segment
		(start 106.05262 -121.391172)
		(end 106.05262 -121.624852)
		(width 0.1651)
		(layer "F.Cu")
		(net "M_K_CS_N<7>")
	)
	(segment
		(start 106.21264 -121.231152)
		(end 106.05262 -121.391172)
		(width 0.1651)
		(layer "F.Cu")
		(net "M_K_CS_N<7>")
	)
	(segment
		(start 103.587296 -100.711)
		(end 104.239568 -100.711)
		(width 0.1651)
		(layer "F.Cu")
		(net "M_K_CS_N<7>")
	)
	(segment
		(start 106.05262 -121.624852)
		(end 106.294936 -121.867168)
		(width 0.1651)
		(layer "F.Cu")
		(net "M_K_CS_N<7>")
	)
	(segment
		(start 109.009942 -124.586238)
		(end 109.241844 -124.81814)
		(width 0.1651)
		(layer "F.Cu")
		(net "M_K_CS_N<7>")
	)
	(segment
		(start 104.290368 -103.119936)
		(end 104.455468 -103.285036)
		(width 0.1651)
		(layer "F.Cu")
		(net "M_K_CS_N<7>")
	)
	(segment
		(start 104.455468 -103.7209)
		(end 105.156508 -104.42194)
		(width 0.1651)
		(layer "F.Cu")
		(net "M_K_CS_N<7>")
	)
	(segment
		(start 109.241844 -124.81814)
		(end 109.514132 -124.81814)
		(width 0.1651)
		(layer "F.Cu")
		(net "M_K_CS_N<7>")
	)
	(segment
		(start 103.76916 -102.446836)
		(end 103.620062 -102.595934)
		(width 0.1651)
		(layer "F.Cu")
		(net "M_K_CS_N<7>")
	)
	(segment
		(start 108.06176 -123.414536)
		(end 108.06176 -123.644406)
		(width 0.1651)
		(layer "F.Cu")
		(net "M_K_CS_N<7>")
	)
	(segment
		(start 108.704888 -123.7234)
		(end 108.938568 -123.7234)
		(width 0.1651)
		(layer "F.Cu")
		(net "M_K_CS_N<7>")
	)
	(segment
		(start 108.541566 -123.886722)
		(end 108.704888 -123.7234)
		(width 0.1651)
		(layer "F.Cu")
		(net "M_K_CS_N<7>")
	)
	(segment
		(start 103.620062 -102.938834)
		(end 103.801164 -103.119936)
		(width 0.1651)
		(layer "F.Cu")
		(net "M_K_CS_N<7>")
	)
	(segment
		(start 107.752896 -122.771408)
		(end 107.986576 -122.771408)
		(width 0.1651)
		(layer "F.Cu")
		(net "M_K_CS_N<7>")
	)
	(segment
		(start 111.237014 -127.3429)
		(end 112.99952 -129.105406)
		(width 0.1651)
		(layer "F.Cu")
		(net "M_K_CS_N<7>")
	)
	(segment
		(start 106.688636 -121.707148)
		(end 106.922316 -121.707148)
		(width 0.1651)
		(layer "F.Cu")
		(net "M_K_CS_N<7>")
	)
	(segment
		(start 105.63606 -120.420892)
		(end 106.21264 -120.997472)
		(width 0.1651)
		(layer "F.Cu")
		(net "M_K_CS_N<7>")
	)
	(segment
		(start 102.947724 -100.071428)
		(end 103.587296 -100.711)
		(width 0.1651)
		(layer "F.Cu")
		(net "M_K_CS_N<7>")
	)
	(segment
		(start 107.109768 -122.462544)
		(end 107.109768 -122.692414)
		(width 0.1651)
		(layer "F.Cu")
		(net "M_K_CS_N<7>")
	)
	(segment
		(start 108.228892 -123.013724)
		(end 108.228892 -123.247404)
		(width 0.1651)
		(layer "F.Cu")
		(net "M_K_CS_N<7>")
	)
	(segment
		(start 104.455468 -100.9269)
		(end 104.455468 -102.281736)
		(width 0.1651)
		(layer "F.Cu")
		(net "M_K_CS_N<7>")
	)
	(segment
		(start 107.986576 -122.771408)
		(end 108.228892 -123.013724)
		(width 0.1651)
		(layer "F.Cu")
		(net "M_K_CS_N<7>")
	)
	(segment
		(start 106.922316 -121.707148)
		(end 107.2769 -122.061732)
		(width 0.1651)
		(layer "F.Cu")
		(net "M_K_CS_N<7>")
	)
	(segment
		(start 108.938568 -123.7234)
		(end 109.180884 -123.965716)
		(width 0.1651)
		(layer "F.Cu")
		(net "M_K_CS_N<7>")
	)
	(segment
		(start 109.65688 -124.675392)
		(end 109.89056 -124.675392)
		(width 0.1651)
		(layer "F.Cu")
		(net "M_K_CS_N<7>")
	)
	(segment
		(start 109.009942 -124.370338)
		(end 109.009942 -124.586238)
		(width 0.1651)
		(layer "F.Cu")
		(net "M_K_CS_N<7>")
	)
	(segment
		(start 107.2769 -122.061732)
		(end 107.2769 -122.295412)
		(width 0.1651)
		(layer "F.Cu")
		(net "M_K_CS_N<7>")
	)
	(segment
		(start 105.156508 -120.155716)
		(end 105.421684 -120.420892)
		(width 0.1651)
		(layer "F.Cu")
		(net "M_K_CS_N<7>")
	)
	(segment
		(start 112.99952 -129.105406)
		(end 112.99952 -129.568956)
		(width 0.1651)
		(layer "F.Cu")
		(net "M_K_CS_N<7>")
	)
	(segment
		(start 106.294936 -121.867168)
		(end 106.528616 -121.867168)
		(width 0.1651)
		(layer "F.Cu")
		(net "M_K_CS_N<7>")
	)
	(segment
		(start 104.290368 -102.446836)
		(end 103.76916 -102.446836)
		(width 0.1651)
		(layer "F.Cu")
		(net "M_K_CS_N<7>")
	)
	(segment
		(start 108.304076 -123.886722)
		(end 108.541566 -123.886722)
		(width 0.1651)
		(layer "F.Cu")
		(net "M_K_CS_N<7>")
	)
	(segment
		(start 109.180884 -123.965716)
		(end 109.180884 -124.199396)
		(width 0.1651)
		(layer "F.Cu")
		(net "M_K_CS_N<7>")
	)
	(segment
		(start 111.237014 -126.021846)
		(end 111.237014 -127.3429)
		(width 0.1651)
		(layer "F.Cu")
		(net "M_K_CS_N<7>")
	)
	(segment
		(start 107.109768 -122.692414)
		(end 107.352084 -122.93473)
		(width 0.1651)
		(layer "F.Cu")
		(net "M_K_CS_N<7>")
	)
	(segment
		(start 107.352084 -122.93473)
		(end 107.589574 -122.93473)
		(width 0.1651)
		(layer "F.Cu")
		(net "M_K_CS_N<7>")
	)
	(segment
		(start 109.89056 -124.675392)
		(end 111.237014 -126.021846)
		(width 0.1651)
		(layer "F.Cu")
		(net "M_K_CS_N<7>")
	)
	(segment
		(start 108.06176 -123.644406)
		(end 108.304076 -123.886722)
		(width 0.1651)
		(layer "F.Cu")
		(net "M_K_CS_N<7>")
	)
	(segment
		(start 105.156508 -104.42194)
		(end 105.156508 -120.155716)
		(width 0.1651)
		(layer "F.Cu")
		(net "M_K_CS_N<7>")
	)
	(segment
		(start 107.2769 -122.295412)
		(end 107.109768 -122.462544)
		(width 0.1651)
		(layer "F.Cu")
		(net "M_K_CS_N<7>")
	)
	(segment
		(start 109.514132 -124.81814)
		(end 109.65688 -124.675392)
		(width 0.1651)
		(layer "F.Cu")
		(net "M_K_CS_N<7>")
	)
	(segment
		(start 103.801164 -103.119936)
		(end 104.290368 -103.119936)
		(width 0.1651)
		(layer "F.Cu")
		(net "M_K_CS_N<7>")
	)
	(segment
		(start 102.947724 -99.67214)
		(end 102.947724 -100.071428)
		(width 0.1651)
		(layer "F.Cu")
		(net "M_K_CS_N<7>")
	)
	(segment
		(start 107.589574 -122.93473)
		(end 107.752896 -122.771408)
		(width 0.1651)
		(layer "F.Cu")
		(net "M_K_CS_N<7>")
	)
	(segment
		(start 104.455468 -103.285036)
		(end 104.455468 -103.7209)
		(width 0.1651)
		(layer "F.Cu")
		(net "M_K_CS_N<7>")
	)
	(segment
		(start 106.21264 -120.997472)
		(end 106.21264 -121.231152)
		(width 0.1651)
		(layer "F.Cu")
		(net "M_K_CS_N<7>")
	)
	(segment
		(start 104.239568 -100.711)
		(end 104.455468 -100.9269)
		(width 0.1651)
		(layer "F.Cu")
		(net "M_K_CS_N<7>")
	)
	(segment
		(start 104.455468 -102.281736)
		(end 104.290368 -102.446836)
		(width 0.1651)
		(layer "F.Cu")
		(net "M_K_CS_N<7>")
	)
	(segment
		(start 108.228892 -123.247404)
		(end 108.06176 -123.414536)
		(width 0.1651)
		(layer "F.Cu")
		(net "M_K_CS_N<7>")
	)
	(via
		(at 112.99952 -129.568956)
		(size 0.508)
		(drill 0.254)
		(layers "F.Cu" "B.Cu")
		(net "M_K_CS_N<7>")
	)
	(segment
		(start 112.99952 -129.568956)
		(end 112.99952 -128.276096)
		(width 0.1651)
		(layer "B.Cu")
		(net "M_K_CS_N<7>")
	)
	(segment
		(start 105.065068 -103.517446)
		(end 105.660698 -104.113076)
		(width 0.1651)
		(layer "F.Cu")
		(net "M_K_CS_N<6>")
	)
	(segment
		(start 113.256568 -129.9718)
		(end 113.256568 -130.28168)
		(width 0.1651)
		(layer "F.Cu")
		(net "M_K_CS_N<6>")
	)
	(segment
		(start 104.483916 -99.6696)
		(end 105.065068 -100.250752)
		(width 0.0889)
		(layer "F.Cu")
		(net "M_K_CS_N<6>")
	)
	(segment
		(start 113.485168 -129.7432)
		(end 113.256568 -129.9718)
		(width 0.1651)
		(layer "F.Cu")
		(net "M_K_CS_N<6>")
	)
	(segment
		(start 113.485168 -128.992376)
		(end 113.485168 -129.7432)
		(width 0.1651)
		(layer "F.Cu")
		(net "M_K_CS_N<6>")
	)
	(segment
		(start 102.947724 -97.690686)
		(end 103.322374 -98.554032)
		(width 0.0889)
		(layer "F.Cu")
		(net "M_K_CS_N<6>")
	)
	(segment
		(start 105.660698 -104.113076)
		(end 105.660698 -119.715026)
		(width 0.1651)
		(layer "F.Cu")
		(net "M_K_CS_N<6>")
	)
	(segment
		(start 103.322374 -98.554032)
		(end 103.322374 -99.27717)
		(width 0.0889)
		(layer "F.Cu")
		(net "M_K_CS_N<6>")
	)
	(segment
		(start 111.808768 -125.863096)
		(end 111.808768 -127.315976)
		(width 0.1651)
		(layer "F.Cu")
		(net "M_K_CS_N<6>")
	)
	(segment
		(start 105.660698 -119.715026)
		(end 111.808768 -125.863096)
		(width 0.1651)
		(layer "F.Cu")
		(net "M_K_CS_N<6>")
	)
	(segment
		(start 103.322374 -99.27717)
		(end 103.714804 -99.6696)
		(width 0.0889)
		(layer "F.Cu")
		(net "M_K_CS_N<6>")
	)
	(segment
		(start 113.256568 -130.28168)
		(end 112.99952 -130.902456)
		(width 0.1651)
		(layer "F.Cu")
		(net "M_K_CS_N<6>")
	)
	(segment
		(start 103.714804 -99.6696)
		(end 104.483916 -99.6696)
		(width 0.0889)
		(layer "F.Cu")
		(net "M_K_CS_N<6>")
	)
	(segment
		(start 105.065068 -100.250752)
		(end 105.065068 -100.615242)
		(width 0.0889)
		(layer "F.Cu")
		(net "M_K_CS_N<6>")
	)
	(segment
		(start 111.808768 -127.315976)
		(end 113.485168 -128.992376)
		(width 0.1651)
		(layer "F.Cu")
		(net "M_K_CS_N<6>")
	)
	(segment
		(start 105.065068 -100.615242)
		(end 105.065068 -103.517446)
		(width 0.1651)
		(layer "F.Cu")
		(net "M_K_CS_N<6>")
	)
	(via
		(at 112.99952 -130.902456)
		(size 0.508)
		(drill 0.254)
		(layers "F.Cu" "B.Cu")
		(net "M_K_CS_N<6>")
	)
	(segment
		(start 112.99952 -132.876036)
		(end 112.99952 -130.902456)
		(width 0.1651)
		(layer "B.Cu")
		(net "M_K_CS_N<6>")
	)
	(segment
		(start 102.635558 -106.030522)
		(end 102.635558 -121.992644)
		(width 0.1651)
		(layer "F.Cu")
		(net "M_K_CS_N<5>")
	)
	(segment
		(start 108.92409 -128.131824)
		(end 108.92409 -128.549146)
		(width 0.1651)
		(layer "F.Cu")
		(net "M_K_CS_N<5>")
	)
	(segment
		(start 110.247684 -129.389378)
		(end 110.247684 -129.729484)
		(width 0.1651)
		(layer "F.Cu")
		(net "M_K_CS_N<5>")
	)
	(segment
		(start 108.175552 -127.83566)
		(end 108.627926 -127.83566)
		(width 0.1651)
		(layer "F.Cu")
		(net "M_K_CS_N<5>")
	)
	(segment
		(start 100.216462 -102.529894)
		(end 102.635558 -104.94899)
		(width 0.0889)
		(layer "F.Cu")
		(net "M_K_CS_N<5>")
	)
	(segment
		(start 99.513898 -99.67214)
		(end 100.025708 -100.367084)
		(width 0.0889)
		(layer "F.Cu")
		(net "M_K_CS_N<5>")
	)
	(segment
		(start 102.635558 -104.94899)
		(end 102.635558 -106.030522)
		(width 0.0889)
		(layer "F.Cu")
		(net "M_K_CS_N<5>")
	)
	(segment
		(start 109.381544 -129.0066)
		(end 109.864906 -129.0066)
		(width 0.1651)
		(layer "F.Cu")
		(net "M_K_CS_N<5>")
	)
	(segment
		(start 109.864906 -129.0066)
		(end 110.247684 -129.389378)
		(width 0.1651)
		(layer "F.Cu")
		(net "M_K_CS_N<5>")
	)
	(segment
		(start 110.247684 -129.729484)
		(end 109.840014 -130.137154)
		(width 0.1651)
		(layer "F.Cu")
		(net "M_K_CS_N<5>")
	)
	(segment
		(start 108.627926 -127.83566)
		(end 108.92409 -128.131824)
		(width 0.1651)
		(layer "F.Cu")
		(net "M_K_CS_N<5>")
	)
	(segment
		(start 100.034598 -101.373178)
		(end 100.216462 -101.555042)
		(width 0.0889)
		(layer "F.Cu")
		(net "M_K_CS_N<5>")
	)
	(segment
		(start 107.664504 -127.324612)
		(end 108.175552 -127.83566)
		(width 0.1651)
		(layer "F.Cu")
		(net "M_K_CS_N<5>")
	)
	(segment
		(start 100.025708 -101.357938)
		(end 100.034598 -101.373178)
		(width 0.0889)
		(layer "F.Cu")
		(net "M_K_CS_N<5>")
	)
	(segment
		(start 100.025708 -100.367084)
		(end 100.032058 -100.377752)
		(width 0.0889)
		(layer "F.Cu")
		(net "M_K_CS_N<5>")
	)
	(segment
		(start 108.92409 -128.549146)
		(end 109.381544 -129.0066)
		(width 0.1651)
		(layer "F.Cu")
		(net "M_K_CS_N<5>")
	)
	(segment
		(start 109.840014 -130.137154)
		(end 109.840014 -130.661918)
		(width 0.1651)
		(layer "F.Cu")
		(net "M_K_CS_N<5>")
	)
	(segment
		(start 102.635558 -121.992644)
		(end 107.664504 -127.02159)
		(width 0.1651)
		(layer "F.Cu")
		(net "M_K_CS_N<5>")
	)
	(segment
		(start 100.216462 -101.555042)
		(end 100.216462 -102.529894)
		(width 0.0889)
		(layer "F.Cu")
		(net "M_K_CS_N<5>")
	)
	(segment
		(start 109.840014 -130.661918)
		(end 109.599476 -130.902456)
		(width 0.1651)
		(layer "F.Cu")
		(net "M_K_CS_N<5>")
	)
	(segment
		(start 107.664504 -127.02159)
		(end 107.664504 -127.324612)
		(width 0.1651)
		(layer "F.Cu")
		(net "M_K_CS_N<5>")
	)
	(via
		(at 109.599476 -130.902456)
		(size 0.508)
		(drill 0.254)
		(layers "F.Cu" "B.Cu")
		(net "M_K_CS_N<5>")
	)
	(arc
		(start 100.032058 -100.377752)
		(mid 100.104978 -100.668769)
		(end 100.025708 -100.958142)
		(width 0.0889)
		(layer "F.Cu")
		(net "M_K_CS_N<5>")
	)
	(arc
		(start 100.025708 -100.958142)
		(mid 99.972175 -101.15804)
		(end 100.025708 -101.357938)
		(width 0.0889)
		(layer "F.Cu")
		(net "M_K_CS_N<5>")
	)
	(segment
		(start 109.599476 -132.876036)
		(end 109.599476 -130.902456)
		(width 0.1651)
		(layer "B.Cu")
		(net "M_K_CS_N<5>")
	)
	(segment
		(start 106.550968 -129.921)
		(end 106.65968 -129.812288)
		(width 0.1651)
		(layer "F.Cu")
		(net "M_K_CS_N<4>")
	)
	(segment
		(start 100.618798 -105.151682)
		(end 100.677218 -105.093262)
		(width 0.1651)
		(layer "F.Cu")
		(net "M_K_CS_N<4>")
	)
	(segment
		(start 100.618798 -123.164854)
		(end 100.618798 -105.151682)
		(width 0.1651)
		(layer "F.Cu")
		(net "M_K_CS_N<4>")
	)
	(segment
		(start 100.677218 -104.641904)
		(end 98.473768 -102.438454)
		(width 0.0889)
		(layer "F.Cu")
		(net "M_K_CS_N<4>")
	)
	(segment
		(start 106.65968 -129.812288)
		(end 106.65968 -129.343912)
		(width 0.1651)
		(layer "F.Cu")
		(net "M_K_CS_N<4>")
	)
	(segment
		(start 105.865168 -128.5494)
		(end 104.511348 -128.5494)
		(width 0.1651)
		(layer "F.Cu")
		(net "M_K_CS_N<4>")
	)
	(segment
		(start 103.390192 -127.428244)
		(end 103.390192 -125.936248)
		(width 0.1651)
		(layer "F.Cu")
		(net "M_K_CS_N<4>")
	)
	(segment
		(start 98.473768 -101.571806)
		(end 98.197162 -101.2952)
		(width 0.0889)
		(layer "F.Cu")
		(net "M_K_CS_N<4>")
	)
	(segment
		(start 103.390192 -125.936248)
		(end 100.618798 -123.164854)
		(width 0.1651)
		(layer "F.Cu")
		(net "M_K_CS_N<4>")
	)
	(segment
		(start 106.65968 -129.343912)
		(end 105.865168 -128.5494)
		(width 0.1651)
		(layer "F.Cu")
		(net "M_K_CS_N<4>")
	)
	(segment
		(start 106.550968 -130.5052)
		(end 106.550968 -129.921)
		(width 0.1651)
		(layer "F.Cu")
		(net "M_K_CS_N<4>")
	)
	(segment
		(start 98.197162 -101.2952)
		(end 98.197162 -100.510594)
		(width 0.0889)
		(layer "F.Cu")
		(net "M_K_CS_N<4>")
	)
	(segment
		(start 105.349294 -131.611878)
		(end 106.18089 -131.611878)
		(width 0.1651)
		(layer "F.Cu")
		(net "M_K_CS_N<4>")
	)
	(segment
		(start 106.677968 -130.6322)
		(end 106.550968 -130.5052)
		(width 0.1651)
		(layer "F.Cu")
		(net "M_K_CS_N<4>")
	)
	(segment
		(start 106.677968 -131.1148)
		(end 106.677968 -130.6322)
		(width 0.1651)
		(layer "F.Cu")
		(net "M_K_CS_N<4>")
	)
	(segment
		(start 98.473768 -102.438454)
		(end 98.473768 -101.571806)
		(width 0.0889)
		(layer "F.Cu")
		(net "M_K_CS_N<4>")
	)
	(segment
		(start 104.511348 -128.5494)
		(end 103.390192 -127.428244)
		(width 0.1651)
		(layer "F.Cu")
		(net "M_K_CS_N<4>")
	)
	(segment
		(start 98.197162 -100.510594)
		(end 98.016568 -100.33)
		(width 0.0889)
		(layer "F.Cu")
		(net "M_K_CS_N<4>")
	)
	(segment
		(start 100.677218 -105.093262)
		(end 100.677218 -104.641904)
		(width 0.0889)
		(layer "F.Cu")
		(net "M_K_CS_N<4>")
	)
	(segment
		(start 98.016568 -100.33)
		(end 98.016568 -99.89185)
		(width 0.0889)
		(layer "F.Cu")
		(net "M_K_CS_N<4>")
	)
	(segment
		(start 98.016568 -99.89185)
		(end 97.796858 -99.67214)
		(width 0.0889)
		(layer "F.Cu")
		(net "M_K_CS_N<4>")
	)
	(segment
		(start 106.18089 -131.611878)
		(end 106.677968 -131.1148)
		(width 0.1651)
		(layer "F.Cu")
		(net "M_K_CS_N<4>")
	)
	(via
		(at 105.349294 -131.611878)
		(size 0.508)
		(drill 0.254)
		(layers "F.Cu" "B.Cu")
		(net "M_K_CS_N<4>")
	)
	(segment
		(start 105.349548 -132.876036)
		(end 105.349548 -131.612132)
		(width 0.1651)
		(layer "B.Cu")
		(net "M_K_CS_N<4>")
	)
	(segment
		(start 105.349548 -131.612132)
		(end 105.349294 -131.611878)
		(width 0.1651)
		(layer "B.Cu")
		(net "M_K_CS_N<4>")
	)
	(segment
		(start 102.156768 -102.1588)
		(end 104.652318 -104.65435)
		(width 0.1651)
		(layer "F.Cu")
		(net "M_K_CS_N<3>")
	)
	(segment
		(start 105.048812 -121.347484)
		(end 105.048812 -121.347738)
		(width 0.1651)
		(layer "F.Cu")
		(net "M_K_CS_N<3>")
	)
	(segment
		(start 101.848412 -101.501956)
		(end 101.877368 -101.530912)
		(width 0.0889)
		(layer "F.Cu")
		(net "M_K_CS_N<3>")
	)
	(segment
		(start 112.99952 -136.387586)
		(end 113.000028 -136.387078)
		(width 0.1651)
		(layer "F.Cu")
		(net "M_K_CS_N<3>")
	)
	(segment
		(start 105.048812 -121.347738)
		(end 109.548676 -125.847602)
		(width 0.1651)
		(layer "F.Cu")
		(net "M_K_CS_N<3>")
	)
	(segment
		(start 101.877368 -101.530912)
		(end 101.877368 -101.981)
		(width 0.0889)
		(layer "F.Cu")
		(net "M_K_CS_N<3>")
	)
	(segment
		(start 109.548676 -125.847602)
		(end 110.12297 -125.847602)
		(width 0.1651)
		(layer "F.Cu")
		(net "M_K_CS_N<3>")
	)
	(segment
		(start 102.055168 -102.1588)
		(end 102.156768 -102.1588)
		(width 0.0889)
		(layer "F.Cu")
		(net "M_K_CS_N<3>")
	)
	(segment
		(start 101.725984 -100.338128)
		(end 101.742494 -100.367084)
		(width 0.0889)
		(layer "F.Cu")
		(net "M_K_CS_N<3>")
	)
	(segment
		(start 110.12297 -125.847602)
		(end 110.538768 -126.2634)
		(width 0.1651)
		(layer "F.Cu")
		(net "M_K_CS_N<3>")
	)
	(segment
		(start 101.877368 -101.981)
		(end 102.055168 -102.1588)
		(width 0.0889)
		(layer "F.Cu")
		(net "M_K_CS_N<3>")
	)
	(segment
		(start 110.538768 -126.2634)
		(end 110.538768 -126.8476)
		(width 0.1651)
		(layer "F.Cu")
		(net "M_K_CS_N<3>")
	)
	(segment
		(start 112.99952 -137.67054)
		(end 112.99952 -136.387586)
		(width 0.1651)
		(layer "F.Cu")
		(net "M_K_CS_N<3>")
	)
	(segment
		(start 101.230684 -99.67214)
		(end 101.267768 -99.721924)
		(width 0.0889)
		(layer "F.Cu")
		(net "M_K_CS_N<3>")
	)
	(segment
		(start 104.652318 -104.65435)
		(end 104.652318 -120.95099)
		(width 0.1651)
		(layer "F.Cu")
		(net "M_K_CS_N<3>")
	)
	(segment
		(start 101.737668 -101.349302)
		(end 101.742494 -101.357938)
		(width 0.0889)
		(layer "F.Cu")
		(net "M_K_CS_N<3>")
	)
	(segment
		(start 104.652318 -120.95099)
		(end 105.048812 -121.347484)
		(width 0.1651)
		(layer "F.Cu")
		(net "M_K_CS_N<3>")
	)
	(segment
		(start 101.267768 -99.721924)
		(end 101.725984 -100.338128)
		(width 0.0889)
		(layer "F.Cu")
		(net "M_K_CS_N<3>")
	)
	(via
		(at 110.538768 -126.8476)
		(size 0.508)
		(drill 0.254)
		(layers "F.Cu" "B.Cu")
		(net "M_K_CS_N<3>")
	)
	(via
		(at 113.000028 -136.387078)
		(size 0.4572)
		(drill 0.2032)
		(layers "F.Cu" "B.Cu")
		(net "M_K_CS_N<3>")
	)
	(arc
		(start 101.742494 -100.957888)
		(mid 101.689024 -101.152951)
		(end 101.737668 -101.349302)
		(width 0.0889)
		(layer "F.Cu")
		(net "M_K_CS_N<3>")
	)
	(arc
		(start 101.742494 -101.357938)
		(mid 101.790975 -101.43324)
		(end 101.848412 -101.501956)
		(width 0.0889)
		(layer "F.Cu")
		(net "M_K_CS_N<3>")
	)
	(arc
		(start 101.742494 -100.367084)
		(mid 101.821625 -100.662486)
		(end 101.742494 -100.957888)
		(width 0.0889)
		(layer "F.Cu")
		(net "M_K_CS_N<3>")
	)
	(segment
		(start 112.545368 -130.556)
		(end 112.545368 -131.191)
		(width 0.14224)
		(layer "In9.Cu")
		(net "M_K_CS_N<3>")
	)
	(segment
		(start 110.538768 -126.8476)
		(end 110.538768 -127.9144)
		(width 0.14224)
		(layer "In9.Cu")
		(net "M_K_CS_N<3>")
	)
	(segment
		(start 112.646968 -130.0226)
		(end 112.646968 -130.4544)
		(width 0.14224)
		(layer "In9.Cu")
		(net "M_K_CS_N<3>")
	)
	(segment
		(start 110.538768 -127.9144)
		(end 112.646968 -130.0226)
		(width 0.14224)
		(layer "In9.Cu")
		(net "M_K_CS_N<3>")
	)
	(segment
		(start 112.99952 -135.074152)
		(end 112.99952 -136.38657)
		(width 0.14224)
		(layer "In9.Cu")
		(net "M_K_CS_N<3>")
	)
	(segment
		(start 112.773968 -131.4196)
		(end 112.773968 -133.8326)
		(width 0.14224)
		(layer "In9.Cu")
		(net "M_K_CS_N<3>")
	)
	(segment
		(start 112.773968 -133.8326)
		(end 112.58931 -134.017258)
		(width 0.14224)
		(layer "In9.Cu")
		(net "M_K_CS_N<3>")
	)
	(segment
		(start 112.58931 -134.017258)
		(end 112.58931 -134.663942)
		(width 0.14224)
		(layer "In9.Cu")
		(net "M_K_CS_N<3>")
	)
	(segment
		(start 112.646968 -130.4544)
		(end 112.545368 -130.556)
		(width 0.14224)
		(layer "In9.Cu")
		(net "M_K_CS_N<3>")
	)
	(segment
		(start 112.545368 -131.191)
		(end 112.773968 -131.4196)
		(width 0.14224)
		(layer "In9.Cu")
		(net "M_K_CS_N<3>")
	)
	(segment
		(start 112.99952 -136.38657)
		(end 113.000028 -136.387078)
		(width 0.14224)
		(layer "In9.Cu")
		(net "M_K_CS_N<3>")
	)
	(segment
		(start 112.58931 -134.663942)
		(end 112.99952 -135.074152)
		(width 0.14224)
		(layer "In9.Cu")
		(net "M_K_CS_N<3>")
	)
	(segment
		(start 112.06607 -128.882902)
		(end 111.675672 -128.721104)
		(width 0.1651)
		(layer "F.Cu")
		(net "M_K_CS_N<2>")
	)
	(segment
		(start 112.405668 -129.6543)
		(end 112.405668 -129.2225)
		(width 0.1651)
		(layer "F.Cu")
		(net "M_K_CS_N<2>")
	)
	(segment
		(start 101.267768 -100.748084)
		(end 101.230684 -100.662486)
		(width 0.0889)
		(layer "F.Cu")
		(net "M_K_CS_N<2>")
	)
	(segment
		(start 104.148128 -121.19356)
		(end 104.148128 -104.937814)
		(width 0.1651)
		(layer "F.Cu")
		(net "M_K_CS_N<2>")
	)
	(segment
		(start 111.675672 -128.721104)
		(end 108.609384 -125.654816)
		(width 0.1651)
		(layer "F.Cu")
		(net "M_K_CS_N<2>")
	)
	(segment
		(start 112.545368 -131.2164)
		(end 112.545368 -130.6322)
		(width 0.1651)
		(layer "F.Cu")
		(net "M_K_CS_N<2>")
	)
	(segment
		(start 101.648768 -102.438454)
		(end 101.648768 -101.717602)
		(width 0.0889)
		(layer "F.Cu")
		(net "M_K_CS_N<2>")
	)
	(segment
		(start 112.723168 -129.9718)
		(end 112.405668 -129.6543)
		(width 0.1651)
		(layer "F.Cu")
		(net "M_K_CS_N<2>")
	)
	(segment
		(start 112.723168 -130.4544)
		(end 112.723168 -129.9718)
		(width 0.1651)
		(layer "F.Cu")
		(net "M_K_CS_N<2>")
	)
	(segment
		(start 101.560122 -101.42347)
		(end 101.267768 -100.748084)
		(width 0.0889)
		(layer "F.Cu")
		(net "M_K_CS_N<2>")
	)
	(segment
		(start 112.405668 -129.2225)
		(end 112.06607 -128.882902)
		(width 0.1651)
		(layer "F.Cu")
		(net "M_K_CS_N<2>")
	)
	(segment
		(start 101.577394 -101.453188)
		(end 101.560122 -101.42347)
		(width 0.0889)
		(layer "F.Cu")
		(net "M_K_CS_N<2>")
	)
	(segment
		(start 112.545368 -130.6322)
		(end 112.723168 -130.4544)
		(width 0.1651)
		(layer "F.Cu")
		(net "M_K_CS_N<2>")
	)
	(segment
		(start 112.99952 -131.670552)
		(end 112.545368 -131.2164)
		(width 0.1651)
		(layer "F.Cu")
		(net "M_K_CS_N<2>")
	)
	(segment
		(start 102.073202 -102.862888)
		(end 101.648768 -102.438454)
		(width 0.0889)
		(layer "F.Cu")
		(net "M_K_CS_N<2>")
	)
	(segment
		(start 112.99952 -133.0706)
		(end 112.99952 -131.670552)
		(width 0.1651)
		(layer "F.Cu")
		(net "M_K_CS_N<2>")
	)
	(segment
		(start 108.609384 -125.654816)
		(end 104.148128 -121.19356)
		(width 0.1651)
		(layer "F.Cu")
		(net "M_K_CS_N<2>")
	)
	(segment
		(start 104.148128 -104.937814)
		(end 102.073202 -102.862888)
		(width 0.1651)
		(layer "F.Cu")
		(net "M_K_CS_N<2>")
	)
	(via
		(at 108.609384 -125.654816)
		(size 0.508)
		(drill 0.254)
		(layers "F.Cu" "B.Cu")
		(net "M_K_CS_N<2>")
	)
	(arc
		(start 101.648768 -101.717602)
		(mid 101.630597 -101.580671)
		(end 101.577394 -101.453188)
		(width 0.0889)
		(layer "F.Cu")
		(net "M_K_CS_N<2>")
	)
	(segment
		(start 109.116368 -130.683)
		(end 109.116368 -131.1148)
		(width 0.1651)
		(layer "F.Cu")
		(net "M_K_CS_N<1>")
	)
	(segment
		(start 109.206284 -129.985516)
		(end 109.206284 -130.593084)
		(width 0.1651)
		(layer "F.Cu")
		(net "M_K_CS_N<1>")
	)
	(segment
		(start 102.131368 -105.671112)
		(end 102.131368 -104.775254)
		(width 0.0889)
		(layer "F.Cu")
		(net "M_K_CS_N<1>")
	)
	(segment
		(start 109.116368 -131.1148)
		(end 109.548168 -131.5466)
		(width 0.1651)
		(layer "F.Cu")
		(net "M_K_CS_N<1>")
	)
	(segment
		(start 109.596682 -133.073648)
		(end 109.599476 -133.0706)
		(width 0.1651)
		(layer "F.Cu")
		(net "M_K_CS_N<1>")
	)
	(segment
		(start 109.548168 -131.5466)
		(end 109.548168 -133.025134)
		(width 0.1651)
		(layer "F.Cu")
		(net "M_K_CS_N<1>")
	)
	(segment
		(start 99.86518 -101.461824)
		(end 99.860354 -101.453188)
		(width 0.0889)
		(layer "F.Cu")
		(net "M_K_CS_N<1>")
	)
	(segment
		(start 108.836968 -129.1082)
		(end 108.836968 -129.6162)
		(width 0.1651)
		(layer "F.Cu")
		(net "M_K_CS_N<1>")
	)
	(segment
		(start 99.860354 -101.453188)
		(end 99.851464 -101.437948)
		(width 0.0889)
		(layer "F.Cu")
		(net "M_K_CS_N<1>")
	)
	(segment
		(start 109.206284 -130.593084)
		(end 109.116368 -130.683)
		(width 0.1651)
		(layer "F.Cu")
		(net "M_K_CS_N<1>")
	)
	(segment
		(start 99.920044 -102.56393)
		(end 99.920044 -101.677216)
		(width 0.0889)
		(layer "F.Cu")
		(net "M_K_CS_N<1>")
	)
	(segment
		(start 102.131368 -122.4026)
		(end 102.131368 -105.671112)
		(width 0.1651)
		(layer "F.Cu")
		(net "M_K_CS_N<1>")
	)
	(segment
		(start 108.836968 -129.6162)
		(end 109.206284 -129.985516)
		(width 0.1651)
		(layer "F.Cu")
		(net "M_K_CS_N<1>")
	)
	(segment
		(start 106.393996 -126.665228)
		(end 102.131368 -122.4026)
		(width 0.1651)
		(layer "F.Cu")
		(net "M_K_CS_N<1>")
	)
	(segment
		(start 106.393996 -126.665228)
		(end 108.836968 -129.1082)
		(width 0.1651)
		(layer "F.Cu")
		(net "M_K_CS_N<1>")
	)
	(segment
		(start 109.548168 -133.025134)
		(end 109.596682 -133.073648)
		(width 0.1651)
		(layer "F.Cu")
		(net "M_K_CS_N<1>")
	)
	(segment
		(start 99.820476 -101.370384)
		(end 99.513898 -100.662486)
		(width 0.0889)
		(layer "F.Cu")
		(net "M_K_CS_N<1>")
	)
	(segment
		(start 102.131368 -104.775254)
		(end 99.920044 -102.56393)
		(width 0.0889)
		(layer "F.Cu")
		(net "M_K_CS_N<1>")
	)
	(via
		(at 106.393996 -126.665228)
		(size 0.508)
		(drill 0.254)
		(layers "F.Cu" "B.Cu")
		(net "M_K_CS_N<1>")
	)
	(arc
		(start 99.920044 -101.677216)
		(mid 99.906108 -101.566083)
		(end 99.86518 -101.461824)
		(width 0.0889)
		(layer "F.Cu")
		(net "M_K_CS_N<1>")
	)
	(arc
		(start 99.851464 -101.437948)
		(mid 99.83491 -101.404652)
		(end 99.820476 -101.370384)
		(width 0.0889)
		(layer "F.Cu")
		(net "M_K_CS_N<1>")
	)
	(segment
		(start 102.410768 -126.540514)
		(end 102.410768 -127.4572)
		(width 0.1651)
		(layer "F.Cu")
		(net "M_K_CS_N<0>")
	)
	(segment
		(start 101.906578 -125.496574)
		(end 102.160832 -125.496574)
		(width 0.1651)
		(layer "F.Cu")
		(net "M_K_CS_N<0>")
	)
	(segment
		(start 102.160832 -125.496574)
		(end 102.410768 -125.74651)
		(width 0.1651)
		(layer "F.Cu")
		(net "M_K_CS_N<0>")
	)
	(segment
		(start 100.114608 -123.399042)
		(end 101.33838 -124.622814)
		(width 0.1651)
		(layer "F.Cu")
		(net "M_K_CS_N<0>")
	)
	(segment
		(start 105.814368 -130.048)
		(end 105.814368 -130.4798)
		(width 0.1651)
		(layer "F.Cu")
		(net "M_K_CS_N<0>")
	)
	(segment
		(start 98.194368 -102.4382)
		(end 100.143818 -104.38765)
		(width 0.0889)
		(layer "F.Cu")
		(net "M_K_CS_N<0>")
	)
	(segment
		(start 100.143818 -104.38765)
		(end 100.143818 -104.915462)
		(width 0.0889)
		(layer "F.Cu")
		(net "M_K_CS_N<0>")
	)
	(segment
		(start 101.486208 -125.683264)
		(end 101.719888 -125.683264)
		(width 0.1651)
		(layer "F.Cu")
		(net "M_K_CS_N<0>")
	)
	(segment
		(start 101.719888 -125.683264)
		(end 101.906578 -125.496574)
		(width 0.1651)
		(layer "F.Cu")
		(net "M_K_CS_N<0>")
	)
	(segment
		(start 102.410768 -127.4572)
		(end 104.036368 -129.0828)
		(width 0.1651)
		(layer "F.Cu")
		(net "M_K_CS_N<0>")
	)
	(segment
		(start 105.349548 -132.326634)
		(end 105.349548 -133.0706)
		(width 0.1651)
		(layer "F.Cu")
		(net "M_K_CS_N<0>")
	)
	(segment
		(start 104.849168 -129.0828)
		(end 105.814368 -130.048)
		(width 0.1651)
		(layer "F.Cu")
		(net "M_K_CS_N<0>")
	)
	(segment
		(start 97.796858 -101.653086)
		(end 98.194368 -102.050596)
		(width 0.0889)
		(layer "F.Cu")
		(net "M_K_CS_N<0>")
	)
	(segment
		(start 101.168708 -125.106684)
		(end 101.168708 -125.365764)
		(width 0.1651)
		(layer "F.Cu")
		(net "M_K_CS_N<0>")
	)
	(segment
		(start 105.814368 -130.4798)
		(end 104.874568 -131.4196)
		(width 0.1651)
		(layer "F.Cu")
		(net "M_K_CS_N<0>")
	)
	(segment
		(start 101.33838 -124.937012)
		(end 101.168708 -125.106684)
		(width 0.1651)
		(layer "F.Cu")
		(net "M_K_CS_N<0>")
	)
	(segment
		(start 101.168708 -125.365764)
		(end 101.486208 -125.683264)
		(width 0.1651)
		(layer "F.Cu")
		(net "M_K_CS_N<0>")
	)
	(segment
		(start 104.874568 -131.851654)
		(end 105.349548 -132.326634)
		(width 0.1651)
		(layer "F.Cu")
		(net "M_K_CS_N<0>")
	)
	(segment
		(start 101.33838 -124.622814)
		(end 101.33838 -124.937012)
		(width 0.1651)
		(layer "F.Cu")
		(net "M_K_CS_N<0>")
	)
	(segment
		(start 100.114608 -104.944672)
		(end 100.114608 -123.399042)
		(width 0.1651)
		(layer "F.Cu")
		(net "M_K_CS_N<0>")
	)
	(segment
		(start 102.410768 -125.74651)
		(end 102.410768 -126.540514)
		(width 0.1651)
		(layer "F.Cu")
		(net "M_K_CS_N<0>")
	)
	(segment
		(start 104.874568 -131.4196)
		(end 104.874568 -131.851654)
		(width 0.1651)
		(layer "F.Cu")
		(net "M_K_CS_N<0>")
	)
	(segment
		(start 100.143818 -104.915462)
		(end 100.114608 -104.944672)
		(width 0.1651)
		(layer "F.Cu")
		(net "M_K_CS_N<0>")
	)
	(segment
		(start 104.036368 -129.0828)
		(end 104.849168 -129.0828)
		(width 0.1651)
		(layer "F.Cu")
		(net "M_K_CS_N<0>")
	)
	(segment
		(start 98.194368 -102.050596)
		(end 98.194368 -102.4382)
		(width 0.0889)
		(layer "F.Cu")
		(net "M_K_CS_N<0>")
	)
	(via
		(at 102.410768 -126.540514)
		(size 0.508)
		(drill 0.254)
		(layers "F.Cu" "B.Cu")
		(net "M_K_CS_N<0>")
	)
	(segment
		(start 93.494352 -127.113538)
		(end 93.15831 -127.44958)
		(width 0.1651)
		(layer "F.Cu")
		(net "M_K_CLK_DP<3>")
	)
	(segment
		(start 93.15831 -124.26188)
		(end 93.494352 -124.597922)
		(width 0.1651)
		(layer "F.Cu")
		(net "M_K_CLK_DP<3>")
	)
	(segment
		(start 95.29064 -117.797834)
		(end 92.193618 -120.894856)
		(width 0.1651)
		(layer "F.Cu")
		(net "M_K_CLK_DP<3>")
	)
	(segment
		(start 92.358718 -127.44958)
		(end 92.193618 -127.61468)
		(width 0.1651)
		(layer "F.Cu")
		(net "M_K_CLK_DP<3>")
	)
	(segment
		(start 93.375226 -128.48717)
		(end 93.94952 -129.061464)
		(width 0.1651)
		(layer "F.Cu")
		(net "M_K_CLK_DP<3>")
	)
	(segment
		(start 92.469462 -128.48717)
		(end 93.375226 -128.48717)
		(width 0.1651)
		(layer "F.Cu")
		(net "M_K_CLK_DP<3>")
	)
	(segment
		(start 95.235268 -103.907082)
		(end 95.235268 -104.12349)
		(width 0.0889)
		(layer "F.Cu")
		(net "M_K_CLK_DP<3>")
	)
	(segment
		(start 92.358718 -124.26188)
		(end 93.15831 -124.26188)
		(width 0.1651)
		(layer "F.Cu")
		(net "M_K_CLK_DP<3>")
	)
	(segment
		(start 93.267022 -101.938836)
		(end 95.235268 -103.907082)
		(width 0.0889)
		(layer "F.Cu")
		(net "M_K_CLK_DP<3>")
	)
	(segment
		(start 93.494352 -124.597922)
		(end 93.494352 -125.183138)
		(width 0.1651)
		(layer "F.Cu")
		(net "M_K_CLK_DP<3>")
	)
	(segment
		(start 92.193618 -127.61468)
		(end 92.193618 -128.211326)
		(width 0.1651)
		(layer "F.Cu")
		(net "M_K_CLK_DP<3>")
	)
	(segment
		(start 92.193618 -126.02718)
		(end 92.358718 -126.19228)
		(width 0.1651)
		(layer "F.Cu")
		(net "M_K_CLK_DP<3>")
	)
	(segment
		(start 92.358718 -125.51918)
		(end 92.193618 -125.68428)
		(width 0.1651)
		(layer "F.Cu")
		(net "M_K_CLK_DP<3>")
	)
	(segment
		(start 92.193618 -120.894856)
		(end 92.193618 -124.09678)
		(width 0.1651)
		(layer "F.Cu")
		(net "M_K_CLK_DP<3>")
	)
	(segment
		(start 92.337382 -130.3782)
		(end 92.033598 -130.074416)
		(width 0.1651)
		(layer "F.Cu")
		(net "M_K_CLK_DP<3>")
	)
	(segment
		(start 93.15831 -125.51918)
		(end 92.358718 -125.51918)
		(width 0.1651)
		(layer "F.Cu")
		(net "M_K_CLK_DP<3>")
	)
	(segment
		(start 92.033598 -130.074416)
		(end 92.033598 -129.776982)
		(width 0.1651)
		(layer "F.Cu")
		(net "M_K_CLK_DP<3>")
	)
	(segment
		(start 92.193618 -124.09678)
		(end 92.358718 -124.26188)
		(width 0.1651)
		(layer "F.Cu")
		(net "M_K_CLK_DP<3>")
	)
	(segment
		(start 95.29064 -104.178862)
		(end 95.29064 -104.180894)
		(width 0.0889)
		(layer "F.Cu")
		(net "M_K_CLK_DP<3>")
	)
	(segment
		(start 93.15831 -127.44958)
		(end 92.358718 -127.44958)
		(width 0.1651)
		(layer "F.Cu")
		(net "M_K_CLK_DP<3>")
	)
	(segment
		(start 93.15831 -126.19228)
		(end 93.494352 -126.528322)
		(width 0.1651)
		(layer "F.Cu")
		(net "M_K_CLK_DP<3>")
	)
	(segment
		(start 93.504258 -101.15804)
		(end 93.267022 -101.395276)
		(width 0.0889)
		(layer "F.Cu")
		(net "M_K_CLK_DP<3>")
	)
	(segment
		(start 93.494352 -125.183138)
		(end 93.15831 -125.51918)
		(width 0.1651)
		(layer "F.Cu")
		(net "M_K_CLK_DP<3>")
	)
	(segment
		(start 92.033598 -129.776982)
		(end 91.825572 -129.568956)
		(width 0.1651)
		(layer "F.Cu")
		(net "M_K_CLK_DP<3>")
	)
	(segment
		(start 95.29064 -104.180894)
		(end 95.29064 -117.797834)
		(width 0.1651)
		(layer "F.Cu")
		(net "M_K_CLK_DP<3>")
	)
	(segment
		(start 93.94952 -129.061464)
		(end 93.94952 -129.870962)
		(width 0.1651)
		(layer "F.Cu")
		(net "M_K_CLK_DP<3>")
	)
	(segment
		(start 93.442282 -130.3782)
		(end 92.337382 -130.3782)
		(width 0.1651)
		(layer "F.Cu")
		(net "M_K_CLK_DP<3>")
	)
	(segment
		(start 92.193618 -128.211326)
		(end 92.469462 -128.48717)
		(width 0.1651)
		(layer "F.Cu")
		(net "M_K_CLK_DP<3>")
	)
	(segment
		(start 95.235268 -104.12349)
		(end 95.29064 -104.178862)
		(width 0.0889)
		(layer "F.Cu")
		(net "M_K_CLK_DP<3>")
	)
	(segment
		(start 93.494352 -126.528322)
		(end 93.494352 -127.113538)
		(width 0.1651)
		(layer "F.Cu")
		(net "M_K_CLK_DP<3>")
	)
	(segment
		(start 93.267022 -101.395276)
		(end 93.267022 -101.938836)
		(width 0.0889)
		(layer "F.Cu")
		(net "M_K_CLK_DP<3>")
	)
	(segment
		(start 92.358718 -126.19228)
		(end 93.15831 -126.19228)
		(width 0.1651)
		(layer "F.Cu")
		(net "M_K_CLK_DP<3>")
	)
	(segment
		(start 92.193618 -125.68428)
		(end 92.193618 -126.02718)
		(width 0.1651)
		(layer "F.Cu")
		(net "M_K_CLK_DP<3>")
	)
	(segment
		(start 93.94952 -129.870962)
		(end 93.442282 -130.3782)
		(width 0.1651)
		(layer "F.Cu")
		(net "M_K_CLK_DP<3>")
	)
	(via
		(at 91.825572 -129.568956)
		(size 0.508)
		(drill 0.254)
		(layers "F.Cu" "B.Cu")
		(net "M_K_CLK_DP<3>")
	)
	(segment
		(start 91.749372 -129.492756)
		(end 91.825572 -129.568956)
		(width 0.1651)
		(layer "B.Cu")
		(net "M_K_CLK_DP<3>")
	)
	(segment
		(start 91.749372 -128.276096)
		(end 91.749372 -129.492756)
		(width 0.1651)
		(layer "B.Cu")
		(net "M_K_CLK_DP<3>")
	)
	(segment
		(start 95.476568 -102.553008)
		(end 96.657922 -103.734362)
		(width 0.0889)
		(layer "F.Cu")
		(net "M_K_CLK_DP<1>")
	)
	(segment
		(start 95.511874 -133.364732)
		(end 95.161354 -133.715252)
		(width 0.1651)
		(layer "F.Cu")
		(net "M_K_CLK_DP<1>")
	)
	(segment
		(start 96.6089 -104.173782)
		(end 96.6089 -115.088162)
		(width 0.1651)
		(layer "F.Cu")
		(net "M_K_CLK_DP<1>")
	)
	(segment
		(start 95.572072 -101.350572)
		(end 95.570548 -101.353874)
		(width 0.0889)
		(layer "F.Cu")
		(net "M_K_CLK_DP<1>")
	)
	(segment
		(start 95.514668 -129.8702)
		(end 95.514668 -130.3655)
		(width 0.1651)
		(layer "F.Cu")
		(net "M_K_CLK_DP<1>")
	)
	(segment
		(start 96.014794 -120.153176)
		(end 95.888302 -120.279668)
		(width 0.1651)
		(layer "F.Cu")
		(net "M_K_CLK_DP<1>")
	)
	(segment
		(start 95.079058 -100.784152)
		(end 95.079312 -100.783898)
		(width 0.0889)
		(layer "F.Cu")
		(net "M_K_CLK_DP<1>")
	)
	(segment
		(start 95.514668 -127.9271)
		(end 95.400368 -128.0414)
		(width 0.1651)
		(layer "F.Cu")
		(net "M_K_CLK_DP<1>")
	)
	(segment
		(start 95.514668 -128.651)
		(end 95.514668 -129.1463)
		(width 0.1651)
		(layer "F.Cu")
		(net "M_K_CLK_DP<1>")
	)
	(segment
		(start 92.028264 -136.253474)
		(end 91.749372 -136.532366)
		(width 0.1651)
		(layer "F.Cu")
		(net "M_K_CLK_DP<1>")
	)
	(segment
		(start 95.221298 -101.15804)
		(end 95.036894 -101.342698)
		(width 0.0889)
		(layer "F.Cu")
		(net "M_K_CLK_DP<1>")
	)
	(segment
		(start 95.161354 -133.835902)
		(end 94.586552 -134.410704)
		(width 0.1651)
		(layer "F.Cu")
		(net "M_K_CLK_DP<1>")
	)
	(segment
		(start 95.161354 -133.715252)
		(end 95.161354 -133.835902)
		(width 0.1651)
		(layer "F.Cu")
		(net "M_K_CLK_DP<1>")
	)
	(segment
		(start 94.11843 -134.761224)
		(end 94.11843 -134.878826)
		(width 0.1651)
		(layer "F.Cu")
		(net "M_K_CLK_DP<1>")
	)
	(segment
		(start 96.6089 -115.088162)
		(end 96.6089 -118.674134)
		(width 0.1651)
		(layer "F.Cu")
		(net "M_K_CLK_DP<1>")
	)
	(segment
		(start 95.632524 -133.364732)
		(end 95.511874 -133.364732)
		(width 0.1651)
		(layer "F.Cu")
		(net "M_K_CLK_DP<1>")
	)
	(segment
		(start 96.014794 -122.961654)
		(end 95.514668 -123.46178)
		(width 0.1651)
		(layer "F.Cu")
		(net "M_K_CLK_DP<1>")
	)
	(segment
		(start 96.009968 -130.8608)
		(end 96.009968 -132.987288)
		(width 0.1651)
		(layer "F.Cu")
		(net "M_K_CLK_DP<1>")
	)
	(segment
		(start 95.514668 -130.3655)
		(end 96.009968 -130.8608)
		(width 0.1651)
		(layer "F.Cu")
		(net "M_K_CLK_DP<1>")
	)
	(segment
		(start 94.11843 -134.878826)
		(end 93.74124 -135.256016)
		(width 0.1651)
		(layer "F.Cu")
		(net "M_K_CLK_DP<1>")
	)
	(segment
		(start 95.514668 -126.7079)
		(end 95.400368 -126.8222)
		(width 0.1651)
		(layer "F.Cu")
		(net "M_K_CLK_DP<1>")
	)
	(segment
		(start 95.514668 -123.46178)
		(end 95.514668 -126.7079)
		(width 0.1651)
		(layer "F.Cu")
		(net "M_K_CLK_DP<1>")
	)
	(segment
		(start 95.476568 -101.54158)
		(end 95.476568 -102.553008)
		(width 0.0889)
		(layer "F.Cu")
		(net "M_K_CLK_DP<1>")
	)
	(segment
		(start 96.657922 -103.734362)
		(end 96.657922 -104.11968)
		(width 0.0889)
		(layer "F.Cu")
		(net "M_K_CLK_DP<1>")
	)
	(segment
		(start 91.749372 -136.532366)
		(end 91.749372 -137.67054)
		(width 0.1651)
		(layer "F.Cu")
		(net "M_K_CLK_DP<1>")
	)
	(segment
		(start 95.400368 -128.0414)
		(end 95.400368 -128.5367)
		(width 0.1651)
		(layer "F.Cu")
		(net "M_K_CLK_DP<1>")
	)
	(segment
		(start 96.014794 -120.90146)
		(end 96.014794 -122.961654)
		(width 0.1651)
		(layer "F.Cu")
		(net "M_K_CLK_DP<1>")
	)
	(segment
		(start 92.511372 -135.256016)
		(end 92.028264 -135.739124)
		(width 0.1651)
		(layer "F.Cu")
		(net "M_K_CLK_DP<1>")
	)
	(segment
		(start 92.028264 -135.739124)
		(end 92.028264 -136.253474)
		(width 0.1651)
		(layer "F.Cu")
		(net "M_K_CLK_DP<1>")
	)
	(segment
		(start 96.657922 -104.11968)
		(end 96.6089 -104.168702)
		(width 0.0889)
		(layer "F.Cu")
		(net "M_K_CLK_DP<1>")
	)
	(segment
		(start 93.74124 -135.256016)
		(end 92.511372 -135.256016)
		(width 0.1651)
		(layer "F.Cu")
		(net "M_K_CLK_DP<1>")
	)
	(segment
		(start 96.014794 -119.26824)
		(end 96.014794 -120.153176)
		(width 0.1651)
		(layer "F.Cu")
		(net "M_K_CLK_DP<1>")
	)
	(segment
		(start 95.570548 -101.353874)
		(end 95.476568 -101.54158)
		(width 0.0889)
		(layer "F.Cu")
		(net "M_K_CLK_DP<1>")
	)
	(segment
		(start 95.400368 -127.3175)
		(end 95.514668 -127.4318)
		(width 0.1651)
		(layer "F.Cu")
		(net "M_K_CLK_DP<1>")
	)
	(segment
		(start 96.009968 -132.987288)
		(end 95.632524 -133.364732)
		(width 0.1651)
		(layer "F.Cu")
		(net "M_K_CLK_DP<1>")
	)
	(segment
		(start 95.514668 -129.1463)
		(end 95.400368 -129.2606)
		(width 0.1651)
		(layer "F.Cu")
		(net "M_K_CLK_DP<1>")
	)
	(segment
		(start 95.888302 -120.279668)
		(end 95.888302 -120.774968)
		(width 0.1651)
		(layer "F.Cu")
		(net "M_K_CLK_DP<1>")
	)
	(segment
		(start 94.46895 -134.410704)
		(end 94.11843 -134.761224)
		(width 0.1651)
		(layer "F.Cu")
		(net "M_K_CLK_DP<1>")
	)
	(segment
		(start 95.400368 -126.8222)
		(end 95.400368 -127.3175)
		(width 0.1651)
		(layer "F.Cu")
		(net "M_K_CLK_DP<1>")
	)
	(segment
		(start 95.400368 -128.5367)
		(end 95.514668 -128.651)
		(width 0.1651)
		(layer "F.Cu")
		(net "M_K_CLK_DP<1>")
	)
	(segment
		(start 96.6089 -118.674134)
		(end 96.014794 -119.26824)
		(width 0.1651)
		(layer "F.Cu")
		(net "M_K_CLK_DP<1>")
	)
	(segment
		(start 94.823534 -101.257608)
		(end 94.821248 -101.168708)
		(width 0.0889)
		(layer "F.Cu")
		(net "M_K_CLK_DP<1>")
	)
	(segment
		(start 95.07855 -100.784152)
		(end 95.079058 -100.784152)
		(width 0.0889)
		(layer "F.Cu")
		(net "M_K_CLK_DP<1>")
	)
	(segment
		(start 94.586552 -134.410704)
		(end 94.46895 -134.410704)
		(width 0.1651)
		(layer "F.Cu")
		(net "M_K_CLK_DP<1>")
	)
	(segment
		(start 95.400368 -129.2606)
		(end 95.400368 -129.7559)
		(width 0.1651)
		(layer "F.Cu")
		(net "M_K_CLK_DP<1>")
	)
	(segment
		(start 95.400368 -129.7559)
		(end 95.514668 -129.8702)
		(width 0.1651)
		(layer "F.Cu")
		(net "M_K_CLK_DP<1>")
	)
	(segment
		(start 95.888302 -120.774968)
		(end 96.014794 -120.90146)
		(width 0.1651)
		(layer "F.Cu")
		(net "M_K_CLK_DP<1>")
	)
	(segment
		(start 96.6089 -104.168702)
		(end 96.6089 -104.173782)
		(width 0.0889)
		(layer "F.Cu")
		(net "M_K_CLK_DP<1>")
	)
	(segment
		(start 95.57385 -101.348032)
		(end 95.572072 -101.350572)
		(width 0.0889)
		(layer "F.Cu")
		(net "M_K_CLK_DP<1>")
	)
	(segment
		(start 95.514668 -127.4318)
		(end 95.514668 -127.9271)
		(width 0.1651)
		(layer "F.Cu")
		(net "M_K_CLK_DP<1>")
	)
	(via
		(at 96.6089 -115.088162)
		(size 0.508)
		(drill 0.254)
		(layers "F.Cu" "B.Cu")
		(net "M_K_CLK_DP<1>")
	)
	(arc
		(start 95.036894 -101.342698)
		(mid 94.902194 -101.370417)
		(end 94.823534 -101.257608)
		(width 0.0889)
		(layer "F.Cu")
		(net "M_K_CLK_DP<1>")
	)
	(arc
		(start 94.821248 -101.16566)
		(mid 94.889584 -100.934213)
		(end 95.07855 -100.784152)
		(width 0.0889)
		(layer "F.Cu")
		(net "M_K_CLK_DP<1>")
	)
	(arc
		(start 95.079312 -100.783898)
		(mid 95.52254 -100.894183)
		(end 95.57385 -101.348032)
		(width 0.0889)
		(layer "F.Cu")
		(net "M_K_CLK_DP<1>")
	)
	(arc
		(start 94.821248 -101.168708)
		(mid 94.82125 -101.167184)
		(end 94.821248 -101.16566)
		(width 0.0889)
		(layer "F.Cu")
		(net "M_K_CLK_DP<1>")
	)
	(segment
		(start 93.697552 -117.996716)
		(end 93.697552 -117.858794)
		(width 0.1651)
		(layer "F.Cu")
		(net "M_K_CLK_DP<2>")
	)
	(segment
		(start 93.504258 -99.077018)
		(end 93.504258 -99.17684)
		(width 0.0889)
		(layer "F.Cu")
		(net "M_K_CLK_DP<2>")
	)
	(segment
		(start 91.082368 -120.772682)
		(end 91.082368 -120.473978)
		(width 0.1651)
		(layer "F.Cu")
		(net "M_K_CLK_DP<2>")
	)
	(segment
		(start 92.322904 -119.233442)
		(end 92.47251 -119.233442)
		(width 0.1651)
		(layer "F.Cu")
		(net "M_K_CLK_DP<2>")
	)
	(segment
		(start 91.082368 -124.86132)
		(end 91.20886 -124.734828)
		(width 0.1651)
		(layer "F.Cu")
		(net "M_K_CLK_DP<2>")
	)
	(segment
		(start 91.20886 -127.221996)
		(end 91.20886 -126.726696)
		(width 0.1651)
		(layer "F.Cu")
		(net "M_K_CLK_DP<2>")
	)
	(segment
		(start 91.61145 -120.123966)
		(end 91.961716 -119.773446)
		(width 0.1651)
		(layer "F.Cu")
		(net "M_K_CLK_DP<2>")
	)
	(segment
		(start 90.734388 -130.680714)
		(end 90.805254 -130.609848)
		(width 0.1651)
		(layer "F.Cu")
		(net "M_K_CLK_DP<2>")
	)
	(segment
		(start 92.82303 -118.733316)
		(end 93.20911 -118.347236)
		(width 0.1651)
		(layer "F.Cu")
		(net "M_K_CLK_DP<2>")
	)
	(segment
		(start 94.493842 -110.206282)
		(end 94.493842 -109.710982)
		(width 0.1651)
		(layer "F.Cu")
		(net "M_K_CLK_DP<2>")
	)
	(segment
		(start 94.328742 -104.033574)
		(end 92.257372 -101.962204)
		(width 0.0889)
		(layer "F.Cu")
		(net "M_K_CLK_DP<2>")
	)
	(segment
		(start 94.328742 -104.155748)
		(end 94.328742 -104.033574)
		(width 0.0889)
		(layer "F.Cu")
		(net "M_K_CLK_DP<2>")
	)
	(segment
		(start 93.168978 -98.957638)
		(end 93.193616 -98.933)
		(width 0.0889)
		(layer "F.Cu")
		(net "M_K_CLK_DP<2>")
	)
	(segment
		(start 91.082368 -127.749554)
		(end 91.082368 -127.348488)
		(width 0.1651)
		(layer "F.Cu")
		(net "M_K_CLK_DP<2>")
	)
	(segment
		(start 91.082368 -126.104904)
		(end 91.20886 -125.978412)
		(width 0.1651)
		(layer "F.Cu")
		(net "M_K_CLK_DP<2>")
	)
	(segment
		(start 94.493842 -107.272582)
		(end 94.379542 -107.158282)
		(width 0.1651)
		(layer "F.Cu")
		(net "M_K_CLK_DP<2>")
	)
	(segment
		(start 94.493842 -108.491782)
		(end 94.379542 -108.377482)
		(width 0.1651)
		(layer "F.Cu")
		(net "M_K_CLK_DP<2>")
	)
	(segment
		(start 94.493842 -107.767882)
		(end 94.493842 -107.272582)
		(width 0.1651)
		(layer "F.Cu")
		(net "M_K_CLK_DP<2>")
	)
	(segment
		(start 93.347032 -118.347236)
		(end 93.697552 -117.996716)
		(width 0.1651)
		(layer "F.Cu")
		(net "M_K_CLK_DP<2>")
	)
	(segment
		(start 91.082368 -128.70053)
		(end 91.082368 -128.52019)
		(width 0.1651)
		(layer "F.Cu")
		(net "M_K_CLK_DP<2>")
	)
	(segment
		(start 91.998546 -131.002278)
		(end 91.998546 -131.14401)
		(width 0.1651)
		(layer "F.Cu")
		(net "M_K_CLK_DP<2>")
	)
	(segment
		(start 94.379542 -109.596682)
		(end 94.379542 -109.101382)
		(width 0.1651)
		(layer "F.Cu")
		(net "M_K_CLK_DP<2>")
	)
	(segment
		(start 91.20886 -122.24766)
		(end 91.20886 -121.75236)
		(width 0.1651)
		(layer "F.Cu")
		(net "M_K_CLK_DP<2>")
	)
	(segment
		(start 93.697552 -117.858794)
		(end 94.379542 -117.176804)
		(width 0.1651)
		(layer "F.Cu")
		(net "M_K_CLK_DP<2>")
	)
	(segment
		(start 94.379542 -105.939082)
		(end 94.379542 -104.206548)
		(width 0.1651)
		(layer "F.Cu")
		(net "M_K_CLK_DP<2>")
	)
	(segment
		(start 91.961716 -119.773446)
		(end 91.961716 -119.59463)
		(width 0.1651)
		(layer "F.Cu")
		(net "M_K_CLK_DP<2>")
	)
	(segment
		(start 90.707718 -129.07518)
		(end 91.082368 -128.70053)
		(width 0.1651)
		(layer "F.Cu")
		(net "M_K_CLK_DP<2>")
	)
	(segment
		(start 94.379542 -106.662982)
		(end 94.493842 -106.548682)
		(width 0.1651)
		(layer "F.Cu")
		(net "M_K_CLK_DP<2>")
	)
	(segment
		(start 91.20886 -124.239528)
		(end 91.082368 -124.113036)
		(width 0.1651)
		(layer "F.Cu")
		(net "M_K_CLK_DP<2>")
	)
	(segment
		(start 92.257372 -101.962204)
		(end 92.257372 -101.525324)
		(width 0.0889)
		(layer "F.Cu")
		(net "M_K_CLK_DP<2>")
	)
	(segment
		(start 91.20886 -126.726696)
		(end 91.082368 -126.600204)
		(width 0.1651)
		(layer "F.Cu")
		(net "M_K_CLK_DP<2>")
	)
	(segment
		(start 91.082368 -122.869452)
		(end 91.082368 -122.374152)
		(width 0.1651)
		(layer "F.Cu")
		(net "M_K_CLK_DP<2>")
	)
	(segment
		(start 91.20886 -125.978412)
		(end 91.20886 -125.483112)
		(width 0.1651)
		(layer "F.Cu")
		(net "M_K_CLK_DP<2>")
	)
	(segment
		(start 91.225624 -128.376934)
		(end 91.225624 -127.89281)
		(width 0.1651)
		(layer "F.Cu")
		(net "M_K_CLK_DP<2>")
	)
	(segment
		(start 94.493842 -108.987082)
		(end 94.493842 -108.491782)
		(width 0.1651)
		(layer "F.Cu")
		(net "M_K_CLK_DP<2>")
	)
	(segment
		(start 92.47251 -119.233442)
		(end 92.82303 -118.882922)
		(width 0.1651)
		(layer "F.Cu")
		(net "M_K_CLK_DP<2>")
	)
	(segment
		(start 91.20886 -124.734828)
		(end 91.20886 -124.239528)
		(width 0.1651)
		(layer "F.Cu")
		(net "M_K_CLK_DP<2>")
	)
	(segment
		(start 91.082368 -121.625868)
		(end 91.082368 -121.259346)
		(width 0.1651)
		(layer "F.Cu")
		(net "M_K_CLK_DP<2>")
	)
	(segment
		(start 91.082368 -123.617736)
		(end 91.20886 -123.491244)
		(width 0.1651)
		(layer "F.Cu")
		(net "M_K_CLK_DP<2>")
	)
	(segment
		(start 94.493842 -106.548682)
		(end 94.493842 -106.053382)
		(width 0.1651)
		(layer "F.Cu")
		(net "M_K_CLK_DP<2>")
	)
	(segment
		(start 93.20911 -118.347236)
		(end 93.347032 -118.347236)
		(width 0.1651)
		(layer "F.Cu")
		(net "M_K_CLK_DP<2>")
	)
	(segment
		(start 94.379542 -104.206548)
		(end 94.328742 -104.155748)
		(width 0.0889)
		(layer "F.Cu")
		(net "M_K_CLK_DP<2>")
	)
	(segment
		(start 91.082368 -128.52019)
		(end 91.225624 -128.376934)
		(width 0.1651)
		(layer "F.Cu")
		(net "M_K_CLK_DP<2>")
	)
	(segment
		(start 91.20886 -123.491244)
		(end 91.20886 -122.995944)
		(width 0.1651)
		(layer "F.Cu")
		(net "M_K_CLK_DP<2>")
	)
	(segment
		(start 90.734388 -131.153916)
		(end 90.734388 -130.680714)
		(width 0.1651)
		(layer "F.Cu")
		(net "M_K_CLK_DP<2>")
	)
	(segment
		(start 94.379542 -107.158282)
		(end 94.379542 -106.662982)
		(width 0.1651)
		(layer "F.Cu")
		(net "M_K_CLK_DP<2>")
	)
	(segment
		(start 94.379542 -107.882182)
		(end 94.493842 -107.767882)
		(width 0.1651)
		(layer "F.Cu")
		(net "M_K_CLK_DP<2>")
	)
	(segment
		(start 90.707718 -129.810256)
		(end 90.707718 -129.07518)
		(width 0.1651)
		(layer "F.Cu")
		(net "M_K_CLK_DP<2>")
	)
	(segment
		(start 91.43238 -120.123966)
		(end 91.61145 -120.123966)
		(width 0.1651)
		(layer "F.Cu")
		(net "M_K_CLK_DP<2>")
	)
	(segment
		(start 92.257372 -101.525324)
		(end 92.299028 -101.453188)
		(width 0.0889)
		(layer "F.Cu")
		(net "M_K_CLK_DP<2>")
	)
	(segment
		(start 91.857068 -130.8608)
		(end 91.998546 -131.002278)
		(width 0.1651)
		(layer "F.Cu")
		(net "M_K_CLK_DP<2>")
	)
	(segment
		(start 91.225624 -127.89281)
		(end 91.082368 -127.749554)
		(width 0.1651)
		(layer "F.Cu")
		(net "M_K_CLK_DP<2>")
	)
	(segment
		(start 94.379542 -109.101382)
		(end 94.493842 -108.987082)
		(width 0.1651)
		(layer "F.Cu")
		(net "M_K_CLK_DP<2>")
	)
	(segment
		(start 94.493842 -109.710982)
		(end 94.379542 -109.596682)
		(width 0.1651)
		(layer "F.Cu")
		(net "M_K_CLK_DP<2>")
	)
	(segment
		(start 93.14688 -100.00615)
		(end 93.16466 -99.97059)
		(width 0.0889)
		(layer "F.Cu")
		(net "M_K_CLK_DP<2>")
	)
	(segment
		(start 91.998546 -131.14401)
		(end 91.802204 -131.340352)
		(width 0.1651)
		(layer "F.Cu")
		(net "M_K_CLK_DP<2>")
	)
	(segment
		(start 90.805254 -130.609848)
		(end 90.805254 -129.907792)
		(width 0.1651)
		(layer "F.Cu")
		(net "M_K_CLK_DP<2>")
	)
	(segment
		(start 94.379542 -117.176804)
		(end 94.379542 -110.320582)
		(width 0.1651)
		(layer "F.Cu")
		(net "M_K_CLK_DP<2>")
	)
	(segment
		(start 91.082368 -121.259346)
		(end 91.1606 -121.181114)
		(width 0.1651)
		(layer "F.Cu")
		(net "M_K_CLK_DP<2>")
	)
	(segment
		(start 90.805254 -129.907792)
		(end 90.707718 -129.810256)
		(width 0.1651)
		(layer "F.Cu")
		(net "M_K_CLK_DP<2>")
	)
	(segment
		(start 91.20886 -121.75236)
		(end 91.082368 -121.625868)
		(width 0.1651)
		(layer "F.Cu")
		(net "M_K_CLK_DP<2>")
	)
	(segment
		(start 92.82303 -118.882922)
		(end 92.82303 -118.733316)
		(width 0.1651)
		(layer "F.Cu")
		(net "M_K_CLK_DP<2>")
	)
	(segment
		(start 91.802204 -131.340352)
		(end 90.920824 -131.340352)
		(width 0.1651)
		(layer "F.Cu")
		(net "M_K_CLK_DP<2>")
	)
	(segment
		(start 91.20886 -125.483112)
		(end 91.082368 -125.35662)
		(width 0.1651)
		(layer "F.Cu")
		(net "M_K_CLK_DP<2>")
	)
	(segment
		(start 91.961716 -119.59463)
		(end 92.322904 -119.233442)
		(width 0.1651)
		(layer "F.Cu")
		(net "M_K_CLK_DP<2>")
	)
	(segment
		(start 91.20886 -122.995944)
		(end 91.082368 -122.869452)
		(width 0.1651)
		(layer "F.Cu")
		(net "M_K_CLK_DP<2>")
	)
	(segment
		(start 94.379542 -110.320582)
		(end 94.493842 -110.206282)
		(width 0.1651)
		(layer "F.Cu")
		(net "M_K_CLK_DP<2>")
	)
	(segment
		(start 94.379542 -108.377482)
		(end 94.379542 -107.882182)
		(width 0.1651)
		(layer "F.Cu")
		(net "M_K_CLK_DP<2>")
	)
	(segment
		(start 94.493842 -106.053382)
		(end 94.379542 -105.939082)
		(width 0.1651)
		(layer "F.Cu")
		(net "M_K_CLK_DP<2>")
	)
	(segment
		(start 91.082368 -122.374152)
		(end 91.20886 -122.24766)
		(width 0.1651)
		(layer "F.Cu")
		(net "M_K_CLK_DP<2>")
	)
	(segment
		(start 91.082368 -127.348488)
		(end 91.20886 -127.221996)
		(width 0.1651)
		(layer "F.Cu")
		(net "M_K_CLK_DP<2>")
	)
	(segment
		(start 90.920824 -131.340352)
		(end 90.734388 -131.153916)
		(width 0.1651)
		(layer "F.Cu")
		(net "M_K_CLK_DP<2>")
	)
	(segment
		(start 92.634562 -101.253036)
		(end 92.667328 -101.253036)
		(width 0.0889)
		(layer "F.Cu")
		(net "M_K_CLK_DP<2>")
	)
	(segment
		(start 91.1606 -121.181114)
		(end 91.1606 -120.850914)
		(width 0.1651)
		(layer "F.Cu")
		(net "M_K_CLK_DP<2>")
	)
	(segment
		(start 91.1606 -120.850914)
		(end 91.082368 -120.772682)
		(width 0.1651)
		(layer "F.Cu")
		(net "M_K_CLK_DP<2>")
	)
	(segment
		(start 91.082368 -124.113036)
		(end 91.082368 -123.617736)
		(width 0.1651)
		(layer "F.Cu")
		(net "M_K_CLK_DP<2>")
	)
	(segment
		(start 91.082368 -125.35662)
		(end 91.082368 -124.86132)
		(width 0.1651)
		(layer "F.Cu")
		(net "M_K_CLK_DP<2>")
	)
	(segment
		(start 91.082368 -126.600204)
		(end 91.082368 -126.104904)
		(width 0.1651)
		(layer "F.Cu")
		(net "M_K_CLK_DP<2>")
	)
	(segment
		(start 91.082368 -120.473978)
		(end 91.43238 -120.123966)
		(width 0.1651)
		(layer "F.Cu")
		(net "M_K_CLK_DP<2>")
	)
	(via
		(at 91.857068 -130.8608)
		(size 0.508)
		(drill 0.254)
		(layers "F.Cu" "B.Cu")
		(net "M_K_CLK_DP<2>")
	)
	(arc
		(start 93.157548 -100.367084)
		(mid 93.106706 -100.187948)
		(end 93.14688 -100.00615)
		(width 0.0889)
		(layer "F.Cu")
		(net "M_K_CLK_DP<2>")
	)
	(arc
		(start 93.157548 -99.376992)
		(mid 93.103909 -99.165695)
		(end 93.168978 -98.957638)
		(width 0.0889)
		(layer "F.Cu")
		(net "M_K_CLK_DP<2>")
	)
	(arc
		(start 93.444568 -98.933)
		(mid 93.488719 -98.999076)
		(end 93.504258 -99.077018)
		(width 0.0889)
		(layer "F.Cu")
		(net "M_K_CLK_DP<2>")
	)
	(arc
		(start 92.299028 -101.453188)
		(mid 92.440711 -101.309384)
		(end 92.634562 -101.253036)
		(width 0.0889)
		(layer "F.Cu")
		(net "M_K_CLK_DP<2>")
	)
	(arc
		(start 93.193616 -98.933)
		(mid 93.319092 -98.881026)
		(end 93.444568 -98.933)
		(width 0.0889)
		(layer "F.Cu")
		(net "M_K_CLK_DP<2>")
	)
	(arc
		(start 92.667328 -101.253036)
		(mid 93.162805 -100.948593)
		(end 93.157548 -100.367084)
		(width 0.0889)
		(layer "F.Cu")
		(net "M_K_CLK_DP<2>")
	)
	(arc
		(start 93.16466 -99.97059)
		(mid 93.238878 -99.672846)
		(end 93.157548 -99.376992)
		(width 0.0889)
		(layer "F.Cu")
		(net "M_K_CLK_DP<2>")
	)
	(segment
		(start 91.749372 -130.968496)
		(end 91.857068 -130.8608)
		(width 0.1651)
		(layer "B.Cu")
		(net "M_K_CLK_DP<2>")
	)
	(segment
		(start 91.749372 -132.876036)
		(end 91.749372 -130.968496)
		(width 0.1651)
		(layer "B.Cu")
		(net "M_K_CLK_DP<2>")
	)
	(segment
		(start 93.850968 -101.357938)
		(end 93.846904 -101.364542)
		(width 0.0889)
		(layer "F.Cu")
		(net "M_K_CLK_DP<0>")
	)
	(segment
		(start 93.781372 -101.952044)
		(end 95.846646 -104.017318)
		(width 0.0889)
		(layer "F.Cu")
		(net "M_K_CLK_DP<0>")
	)
	(segment
		(start 93.293946 -123.773946)
		(end 92.957904 -123.437904)
		(width 0.1651)
		(layer "F.Cu")
		(net "M_K_CLK_DP<0>")
	)
	(segment
		(start 94.498668 -120.421146)
		(end 94.498668 -119.37746)
		(width 0.1651)
		(layer "F.Cu")
		(net "M_K_CLK_DP<0>")
	)
	(segment
		(start 95.795846 -104.136444)
		(end 95.795846 -104.158542)
		(width 0.0889)
		(layer "F.Cu")
		(net "M_K_CLK_DP<0>")
	)
	(segment
		(start 95.006922 -122.516646)
		(end 95.172022 -122.351546)
		(width 0.1651)
		(layer "F.Cu")
		(net "M_K_CLK_DP<0>")
	)
	(segment
		(start 93.293946 -120.586246)
		(end 94.333568 -120.586246)
		(width 0.1651)
		(layer "F.Cu")
		(net "M_K_CLK_DP<0>")
	)
	(segment
		(start 91.749372 -132.404104)
		(end 92.224606 -131.92887)
		(width 0.1651)
		(layer "F.Cu")
		(net "M_K_CLK_DP<0>")
	)
	(segment
		(start 93.846396 -101.365304)
		(end 93.781372 -101.497892)
		(width 0.0889)
		(layer "F.Cu")
		(net "M_K_CLK_DP<0>")
	)
	(segment
		(start 93.781372 -101.497892)
		(end 93.781372 -101.952044)
		(width 0.0889)
		(layer "F.Cu")
		(net "M_K_CLK_DP<0>")
	)
	(segment
		(start 95.846646 -104.085644)
		(end 95.795846 -104.136444)
		(width 0.0889)
		(layer "F.Cu")
		(net "M_K_CLK_DP<0>")
	)
	(segment
		(start 92.957904 -121.507504)
		(end 92.957904 -120.922288)
		(width 0.1651)
		(layer "F.Cu")
		(net "M_K_CLK_DP<0>")
	)
	(segment
		(start 93.293946 -122.516646)
		(end 95.006922 -122.516646)
		(width 0.1651)
		(layer "F.Cu")
		(net "M_K_CLK_DP<0>")
	)
	(segment
		(start 92.957904 -122.852688)
		(end 93.293946 -122.516646)
		(width 0.1651)
		(layer "F.Cu")
		(net "M_K_CLK_DP<0>")
	)
	(segment
		(start 93.846904 -101.364542)
		(end 93.84665 -101.364542)
		(width 0.0889)
		(layer "F.Cu")
		(net "M_K_CLK_DP<0>")
	)
	(segment
		(start 95.795846 -104.158542)
		(end 95.795846 -117.39245)
		(width 0.1651)
		(layer "F.Cu")
		(net "M_K_CLK_DP<0>")
	)
	(segment
		(start 92.957904 -120.922288)
		(end 93.293946 -120.586246)
		(width 0.1651)
		(layer "F.Cu")
		(net "M_K_CLK_DP<0>")
	)
	(segment
		(start 95.006922 -121.843546)
		(end 93.293946 -121.843546)
		(width 0.1651)
		(layer "F.Cu")
		(net "M_K_CLK_DP<0>")
	)
	(segment
		(start 94.394274 -130.298698)
		(end 94.394274 -124.042424)
		(width 0.1651)
		(layer "F.Cu")
		(net "M_K_CLK_DP<0>")
	)
	(segment
		(start 93.84665 -101.364542)
		(end 93.846396 -101.365304)
		(width 0.0889)
		(layer "F.Cu")
		(net "M_K_CLK_DP<0>")
	)
	(segment
		(start 95.846646 -104.017318)
		(end 95.846646 -104.085644)
		(width 0.0889)
		(layer "F.Cu")
		(net "M_K_CLK_DP<0>")
	)
	(segment
		(start 91.749372 -133.0706)
		(end 91.749372 -132.404104)
		(width 0.1651)
		(layer "F.Cu")
		(net "M_K_CLK_DP<0>")
	)
	(segment
		(start 92.957904 -123.437904)
		(end 92.957904 -122.852688)
		(width 0.1651)
		(layer "F.Cu")
		(net "M_K_CLK_DP<0>")
	)
	(segment
		(start 95.172022 -122.008646)
		(end 95.006922 -121.843546)
		(width 0.1651)
		(layer "F.Cu")
		(net "M_K_CLK_DP<0>")
	)
	(segment
		(start 92.592906 -131.643374)
		(end 93.049598 -131.643374)
		(width 0.1651)
		(layer "F.Cu")
		(net "M_K_CLK_DP<0>")
	)
	(segment
		(start 94.195138 -100.031296)
		(end 93.983048 -100.209096)
		(width 0.0889)
		(layer "F.Cu")
		(net "M_K_CLK_DP<0>")
	)
	(segment
		(start 95.172022 -122.351546)
		(end 95.172022 -122.008646)
		(width 0.1651)
		(layer "F.Cu")
		(net "M_K_CLK_DP<0>")
	)
	(segment
		(start 94.125796 -123.773946)
		(end 93.293946 -123.773946)
		(width 0.1651)
		(layer "F.Cu")
		(net "M_K_CLK_DP<0>")
	)
	(segment
		(start 93.855794 -101.349302)
		(end 93.850968 -101.357938)
		(width 0.0889)
		(layer "F.Cu")
		(net "M_K_CLK_DP<0>")
	)
	(segment
		(start 93.293946 -121.843546)
		(end 92.957904 -121.507504)
		(width 0.1651)
		(layer "F.Cu")
		(net "M_K_CLK_DP<0>")
	)
	(segment
		(start 94.498668 -119.37746)
		(end 95.795846 -118.080282)
		(width 0.1651)
		(layer "F.Cu")
		(net "M_K_CLK_DP<0>")
	)
	(segment
		(start 92.224606 -131.92887)
		(end 92.30741 -131.92887)
		(width 0.1651)
		(layer "F.Cu")
		(net "M_K_CLK_DP<0>")
	)
	(segment
		(start 94.333568 -120.586246)
		(end 94.498668 -120.421146)
		(width 0.1651)
		(layer "F.Cu")
		(net "M_K_CLK_DP<0>")
	)
	(segment
		(start 92.30741 -131.92887)
		(end 92.592906 -131.643374)
		(width 0.1651)
		(layer "F.Cu")
		(net "M_K_CLK_DP<0>")
	)
	(segment
		(start 93.049598 -131.643374)
		(end 94.394274 -130.298698)
		(width 0.1651)
		(layer "F.Cu")
		(net "M_K_CLK_DP<0>")
	)
	(segment
		(start 95.795846 -118.080282)
		(end 95.795846 -117.39245)
		(width 0.1651)
		(layer "F.Cu")
		(net "M_K_CLK_DP<0>")
	)
	(segment
		(start 94.394274 -124.042424)
		(end 94.125796 -123.773946)
		(width 0.1651)
		(layer "F.Cu")
		(net "M_K_CLK_DP<0>")
	)
	(via
		(at 95.795846 -117.39245)
		(size 0.508)
		(drill 0.254)
		(layers "F.Cu" "B.Cu")
		(net "M_K_CLK_DP<0>")
	)
	(arc
		(start 93.850968 -100.957888)
		(mid 93.904438 -101.152951)
		(end 93.855794 -101.349302)
		(width 0.0889)
		(layer "F.Cu")
		(net "M_K_CLK_DP<0>")
	)
	(arc
		(start 94.362778 -99.67214)
		(mid 94.31881 -99.870323)
		(end 94.195138 -100.031296)
		(width 0.0889)
		(layer "F.Cu")
		(net "M_K_CLK_DP<0>")
	)
	(arc
		(start 93.983048 -100.209096)
		(mid 93.780643 -100.559415)
		(end 93.850968 -100.957888)
		(width 0.0889)
		(layer "F.Cu")
		(net "M_K_CLK_DP<0>")
	)
	(segment
		(start 91.901518 -125.563122)
		(end 91.901518 -126.148338)
		(width 0.1651)
		(layer "F.Cu")
		(net "M_K_CLK_DN<3>")
	)
	(segment
		(start 92.800424 -101.4984)
		(end 92.984828 -101.4984)
		(width 0.0889)
		(layer "F.Cu")
		(net "M_K_CLK_DN<3>")
	)
	(segment
		(start 92.258388 -120.246902)
		(end 92.258388 -120.416828)
		(width 0.1651)
		(layer "F.Cu")
		(net "M_K_CLK_DN<3>")
	)
	(segment
		(start 93.321124 -130.0861)
		(end 92.45854 -130.0861)
		(width 0.1651)
		(layer "F.Cu")
		(net "M_K_CLK_DN<3>")
	)
	(segment
		(start 94.99854 -116.482876)
		(end 94.89694 -116.584476)
		(width 0.1651)
		(layer "F.Cu")
		(net "M_K_CLK_DN<3>")
	)
	(segment
		(start 94.99854 -117.676676)
		(end 94.439232 -118.235984)
		(width 0.1651)
		(layer "F.Cu")
		(net "M_K_CLK_DN<3>")
	)
	(segment
		(start 94.89694 -114.196876)
		(end 94.89694 -114.692176)
		(width 0.1651)
		(layer "F.Cu")
		(net "M_K_CLK_DN<3>")
	)
	(segment
		(start 91.901518 -121.73077)
		(end 91.775026 -121.857262)
		(width 0.1651)
		(layer "F.Cu")
		(net "M_K_CLK_DN<3>")
	)
	(segment
		(start 92.23756 -126.48438)
		(end 93.037152 -126.48438)
		(width 0.1651)
		(layer "F.Cu")
		(net "M_K_CLK_DN<3>")
	)
	(segment
		(start 93.076522 -102.01783)
		(end 95.044768 -103.986076)
		(width 0.0889)
		(layer "F.Cu")
		(net "M_K_CLK_DN<3>")
	)
	(segment
		(start 94.99854 -110.513876)
		(end 94.89694 -110.615476)
		(width 0.1651)
		(layer "F.Cu")
		(net "M_K_CLK_DN<3>")
	)
	(segment
		(start 94.99854 -104.161844)
		(end 94.99854 -104.180132)
		(width 0.0889)
		(layer "F.Cu")
		(net "M_K_CLK_DN<3>")
	)
	(segment
		(start 94.99854 -114.793776)
		(end 94.99854 -115.289076)
		(width 0.1651)
		(layer "F.Cu")
		(net "M_K_CLK_DN<3>")
	)
	(segment
		(start 91.775026 -121.857262)
		(end 91.775026 -122.352562)
		(width 0.1651)
		(layer "F.Cu")
		(net "M_K_CLK_DN<3>")
	)
	(segment
		(start 92.325698 -129.766568)
		(end 92.52331 -129.568956)
		(width 0.1651)
		(layer "F.Cu")
		(net "M_K_CLK_DN<3>")
	)
	(segment
		(start 93.974158 -118.586504)
		(end 93.974158 -118.701058)
		(width 0.1651)
		(layer "F.Cu")
		(net "M_K_CLK_DN<3>")
	)
	(segment
		(start 94.89694 -115.390676)
		(end 94.89694 -115.885976)
		(width 0.1651)
		(layer "F.Cu")
		(net "M_K_CLK_DN<3>")
	)
	(segment
		(start 94.99854 -117.181376)
		(end 94.99854 -117.676676)
		(width 0.1651)
		(layer "F.Cu")
		(net "M_K_CLK_DN<3>")
	)
	(segment
		(start 92.608654 -119.896636)
		(end 92.258388 -120.246902)
		(width 0.1651)
		(layer "F.Cu")
		(net "M_K_CLK_DN<3>")
	)
	(segment
		(start 91.775026 -123.596146)
		(end 91.901518 -123.722638)
		(width 0.1651)
		(layer "F.Cu")
		(net "M_K_CLK_DN<3>")
	)
	(segment
		(start 94.99854 -112.406176)
		(end 94.99854 -112.901476)
		(width 0.1651)
		(layer "F.Cu")
		(net "M_K_CLK_DN<3>")
	)
	(segment
		(start 91.775026 -122.352562)
		(end 91.901518 -122.479054)
		(width 0.1651)
		(layer "F.Cu")
		(net "M_K_CLK_DN<3>")
	)
	(segment
		(start 93.974158 -118.701058)
		(end 93.65107 -119.024146)
		(width 0.1651)
		(layer "F.Cu")
		(net "M_K_CLK_DN<3>")
	)
	(segment
		(start 94.99854 -114.095276)
		(end 94.89694 -114.196876)
		(width 0.1651)
		(layer "F.Cu")
		(net "M_K_CLK_DN<3>")
	)
	(segment
		(start 94.89694 -113.498376)
		(end 94.99854 -113.599976)
		(width 0.1651)
		(layer "F.Cu")
		(net "M_K_CLK_DN<3>")
	)
	(segment
		(start 92.77858 -119.896636)
		(end 92.608654 -119.896636)
		(width 0.1651)
		(layer "F.Cu")
		(net "M_K_CLK_DN<3>")
	)
	(segment
		(start 92.325698 -129.953258)
		(end 92.325698 -129.766568)
		(width 0.1651)
		(layer "F.Cu")
		(net "M_K_CLK_DN<3>")
	)
	(segment
		(start 92.645738 -101.653086)
		(end 92.800424 -101.4984)
		(width 0.0889)
		(layer "F.Cu")
		(net "M_K_CLK_DN<3>")
	)
	(segment
		(start 94.99854 -111.707676)
		(end 94.89694 -111.809276)
		(width 0.1651)
		(layer "F.Cu")
		(net "M_K_CLK_DN<3>")
	)
	(segment
		(start 94.89694 -111.110776)
		(end 94.99854 -111.212376)
		(width 0.1651)
		(layer "F.Cu")
		(net "M_K_CLK_DN<3>")
	)
	(segment
		(start 94.89694 -110.615476)
		(end 94.89694 -111.110776)
		(width 0.1651)
		(layer "F.Cu")
		(net "M_K_CLK_DN<3>")
	)
	(segment
		(start 93.499432 -119.024146)
		(end 93.149166 -119.374412)
		(width 0.1651)
		(layer "F.Cu")
		(net "M_K_CLK_DN<3>")
	)
	(segment
		(start 93.65107 -119.024146)
		(end 93.499432 -119.024146)
		(width 0.1651)
		(layer "F.Cu")
		(net "M_K_CLK_DN<3>")
	)
	(segment
		(start 93.037152 -125.22708)
		(end 92.23756 -125.22708)
		(width 0.1651)
		(layer "F.Cu")
		(net "M_K_CLK_DN<3>")
	)
	(segment
		(start 91.775026 -123.100846)
		(end 91.775026 -123.596146)
		(width 0.1651)
		(layer "F.Cu")
		(net "M_K_CLK_DN<3>")
	)
	(segment
		(start 93.037152 -126.48438)
		(end 93.202252 -126.64948)
		(width 0.1651)
		(layer "F.Cu")
		(net "M_K_CLK_DN<3>")
	)
	(segment
		(start 92.23756 -125.22708)
		(end 91.901518 -125.563122)
		(width 0.1651)
		(layer "F.Cu")
		(net "M_K_CLK_DN<3>")
	)
	(segment
		(start 91.901518 -122.479054)
		(end 91.901518 -122.974354)
		(width 0.1651)
		(layer "F.Cu")
		(net "M_K_CLK_DN<3>")
	)
	(segment
		(start 94.89694 -117.079776)
		(end 94.99854 -117.181376)
		(width 0.1651)
		(layer "F.Cu")
		(net "M_K_CLK_DN<3>")
	)
	(segment
		(start 94.99854 -112.901476)
		(end 94.89694 -113.003076)
		(width 0.1651)
		(layer "F.Cu")
		(net "M_K_CLK_DN<3>")
	)
	(segment
		(start 93.202252 -126.64948)
		(end 93.202252 -126.99238)
		(width 0.1651)
		(layer "F.Cu")
		(net "M_K_CLK_DN<3>")
	)
	(segment
		(start 94.99854 -115.987576)
		(end 94.99854 -116.482876)
		(width 0.1651)
		(layer "F.Cu")
		(net "M_K_CLK_DN<3>")
	)
	(segment
		(start 94.99854 -111.212376)
		(end 94.99854 -111.707676)
		(width 0.1651)
		(layer "F.Cu")
		(net "M_K_CLK_DN<3>")
	)
	(segment
		(start 91.901518 -127.493522)
		(end 91.901518 -128.332484)
		(width 0.1651)
		(layer "F.Cu")
		(net "M_K_CLK_DN<3>")
	)
	(segment
		(start 93.037152 -124.55398)
		(end 93.202252 -124.71908)
		(width 0.1651)
		(layer "F.Cu")
		(net "M_K_CLK_DN<3>")
	)
	(segment
		(start 91.901518 -126.148338)
		(end 92.23756 -126.48438)
		(width 0.1651)
		(layer "F.Cu")
		(net "M_K_CLK_DN<3>")
	)
	(segment
		(start 93.149166 -119.374412)
		(end 93.149166 -119.52605)
		(width 0.1651)
		(layer "F.Cu")
		(net "M_K_CLK_DN<3>")
	)
	(segment
		(start 93.149166 -119.52605)
		(end 92.77858 -119.896636)
		(width 0.1651)
		(layer "F.Cu")
		(net "M_K_CLK_DN<3>")
	)
	(segment
		(start 93.65742 -129.749804)
		(end 93.321124 -130.0861)
		(width 0.1651)
		(layer "F.Cu")
		(net "M_K_CLK_DN<3>")
	)
	(segment
		(start 92.23756 -124.55398)
		(end 93.037152 -124.55398)
		(width 0.1651)
		(layer "F.Cu")
		(net "M_K_CLK_DN<3>")
	)
	(segment
		(start 91.901518 -128.332484)
		(end 92.348304 -128.77927)
		(width 0.1651)
		(layer "F.Cu")
		(net "M_K_CLK_DN<3>")
	)
	(segment
		(start 94.99854 -104.180132)
		(end 94.99854 -110.513876)
		(width 0.1651)
		(layer "F.Cu")
		(net "M_K_CLK_DN<3>")
	)
	(segment
		(start 92.348304 -128.77927)
		(end 93.254068 -128.77927)
		(width 0.1651)
		(layer "F.Cu")
		(net "M_K_CLK_DN<3>")
	)
	(segment
		(start 92.23756 -127.15748)
		(end 91.901518 -127.493522)
		(width 0.1651)
		(layer "F.Cu")
		(net "M_K_CLK_DN<3>")
	)
	(segment
		(start 93.254068 -128.77927)
		(end 93.65742 -129.182622)
		(width 0.1651)
		(layer "F.Cu")
		(net "M_K_CLK_DN<3>")
	)
	(segment
		(start 91.901518 -124.217938)
		(end 92.23756 -124.55398)
		(width 0.1651)
		(layer "F.Cu")
		(net "M_K_CLK_DN<3>")
	)
	(segment
		(start 92.258388 -120.416828)
		(end 91.901518 -120.773698)
		(width 0.1651)
		(layer "F.Cu")
		(net "M_K_CLK_DN<3>")
	)
	(segment
		(start 93.202252 -124.71908)
		(end 93.202252 -125.06198)
		(width 0.1651)
		(layer "F.Cu")
		(net "M_K_CLK_DN<3>")
	)
	(segment
		(start 94.89694 -112.304576)
		(end 94.99854 -112.406176)
		(width 0.1651)
		(layer "F.Cu")
		(net "M_K_CLK_DN<3>")
	)
	(segment
		(start 92.984828 -101.4984)
		(end 93.076522 -101.590094)
		(width 0.0889)
		(layer "F.Cu")
		(net "M_K_CLK_DN<3>")
	)
	(segment
		(start 92.45854 -130.0861)
		(end 92.325698 -129.953258)
		(width 0.1651)
		(layer "F.Cu")
		(net "M_K_CLK_DN<3>")
	)
	(segment
		(start 94.89694 -114.692176)
		(end 94.99854 -114.793776)
		(width 0.1651)
		(layer "F.Cu")
		(net "M_K_CLK_DN<3>")
	)
	(segment
		(start 95.044768 -103.986076)
		(end 95.044768 -104.115616)
		(width 0.0889)
		(layer "F.Cu")
		(net "M_K_CLK_DN<3>")
	)
	(segment
		(start 94.89694 -116.584476)
		(end 94.89694 -117.079776)
		(width 0.1651)
		(layer "F.Cu")
		(net "M_K_CLK_DN<3>")
	)
	(segment
		(start 93.202252 -125.06198)
		(end 93.037152 -125.22708)
		(width 0.1651)
		(layer "F.Cu")
		(net "M_K_CLK_DN<3>")
	)
	(segment
		(start 94.99854 -115.289076)
		(end 94.89694 -115.390676)
		(width 0.1651)
		(layer "F.Cu")
		(net "M_K_CLK_DN<3>")
	)
	(segment
		(start 91.901518 -123.722638)
		(end 91.901518 -124.217938)
		(width 0.1651)
		(layer "F.Cu")
		(net "M_K_CLK_DN<3>")
	)
	(segment
		(start 94.89694 -111.809276)
		(end 94.89694 -112.304576)
		(width 0.1651)
		(layer "F.Cu")
		(net "M_K_CLK_DN<3>")
	)
	(segment
		(start 94.89694 -113.003076)
		(end 94.89694 -113.498376)
		(width 0.1651)
		(layer "F.Cu")
		(net "M_K_CLK_DN<3>")
	)
	(segment
		(start 91.901518 -122.974354)
		(end 91.775026 -123.100846)
		(width 0.1651)
		(layer "F.Cu")
		(net "M_K_CLK_DN<3>")
	)
	(segment
		(start 94.324678 -118.235984)
		(end 93.974158 -118.586504)
		(width 0.1651)
		(layer "F.Cu")
		(net "M_K_CLK_DN<3>")
	)
	(segment
		(start 93.076522 -101.590094)
		(end 93.076522 -102.01783)
		(width 0.0889)
		(layer "F.Cu")
		(net "M_K_CLK_DN<3>")
	)
	(segment
		(start 93.65742 -129.182622)
		(end 93.65742 -129.749804)
		(width 0.1651)
		(layer "F.Cu")
		(net "M_K_CLK_DN<3>")
	)
	(segment
		(start 93.037152 -127.15748)
		(end 92.23756 -127.15748)
		(width 0.1651)
		(layer "F.Cu")
		(net "M_K_CLK_DN<3>")
	)
	(segment
		(start 91.901518 -120.773698)
		(end 91.901518 -121.73077)
		(width 0.1651)
		(layer "F.Cu")
		(net "M_K_CLK_DN<3>")
	)
	(segment
		(start 94.99854 -113.599976)
		(end 94.99854 -114.095276)
		(width 0.1651)
		(layer "F.Cu")
		(net "M_K_CLK_DN<3>")
	)
	(segment
		(start 93.202252 -126.99238)
		(end 93.037152 -127.15748)
		(width 0.1651)
		(layer "F.Cu")
		(net "M_K_CLK_DN<3>")
	)
	(segment
		(start 95.044768 -104.115616)
		(end 94.99854 -104.161844)
		(width 0.0889)
		(layer "F.Cu")
		(net "M_K_CLK_DN<3>")
	)
	(segment
		(start 94.439232 -118.235984)
		(end 94.324678 -118.235984)
		(width 0.1651)
		(layer "F.Cu")
		(net "M_K_CLK_DN<3>")
	)
	(segment
		(start 94.89694 -115.885976)
		(end 94.99854 -115.987576)
		(width 0.1651)
		(layer "F.Cu")
		(net "M_K_CLK_DN<3>")
	)
	(via
		(at 92.52331 -129.568956)
		(size 0.508)
		(drill 0.254)
		(layers "F.Cu" "B.Cu")
		(net "M_K_CLK_DN<3>")
	)
	(segment
		(start 92.59951 -129.492756)
		(end 92.52331 -129.568956)
		(width 0.1651)
		(layer "B.Cu")
		(net "M_K_CLK_DN<3>")
	)
	(segment
		(start 92.59951 -128.276096)
		(end 92.59951 -129.492756)
		(width 0.1651)
		(layer "B.Cu")
		(net "M_K_CLK_DN<3>")
	)
	(segment
		(start 93.862398 -135.548116)
		(end 96.302068 -133.108446)
		(width 0.1651)
		(layer "F.Cu")
		(net "M_K_CLK_DN<1>")
	)
	(segment
		(start 96.306894 -119.389398)
		(end 96.306894 -123.082812)
		(width 0.1651)
		(layer "F.Cu")
		(net "M_K_CLK_DN<1>")
	)
	(segment
		(start 96.901 -104.173782)
		(end 96.901 -118.795292)
		(width 0.1651)
		(layer "F.Cu")
		(net "M_K_CLK_DN<1>")
	)
	(segment
		(start 95.738696 -101.44379)
		(end 95.667322 -101.586538)
		(width 0.0889)
		(layer "F.Cu")
		(net "M_K_CLK_DN<1>")
	)
	(segment
		(start 96.901 -104.151684)
		(end 96.901 -104.173782)
		(width 0.0889)
		(layer "F.Cu")
		(net "M_K_CLK_DN<1>")
	)
	(segment
		(start 92.320364 -136.27862)
		(end 92.320364 -135.860282)
		(width 0.1651)
		(layer "F.Cu")
		(net "M_K_CLK_DN<1>")
	)
	(segment
		(start 92.59951 -137.67054)
		(end 92.59951 -136.557766)
		(width 0.1651)
		(layer "F.Cu")
		(net "M_K_CLK_DN<1>")
	)
	(segment
		(start 96.901 -118.795292)
		(end 96.306894 -119.389398)
		(width 0.1651)
		(layer "F.Cu")
		(net "M_K_CLK_DN<1>")
	)
	(segment
		(start 96.306894 -123.082812)
		(end 95.806768 -123.582938)
		(width 0.1651)
		(layer "F.Cu")
		(net "M_K_CLK_DN<1>")
	)
	(segment
		(start 96.848422 -104.099106)
		(end 96.901 -104.151684)
		(width 0.0889)
		(layer "F.Cu")
		(net "M_K_CLK_DN<1>")
	)
	(segment
		(start 95.806768 -130.244342)
		(end 95.806768 -126.555246)
		(width 0.1651)
		(layer "F.Cu")
		(net "M_K_CLK_DN<1>")
	)
	(segment
		(start 95.667322 -101.586538)
		(end 95.667322 -102.474268)
		(width 0.0889)
		(layer "F.Cu")
		(net "M_K_CLK_DN<1>")
	)
	(segment
		(start 96.302068 -130.739642)
		(end 95.806768 -130.244342)
		(width 0.1651)
		(layer "F.Cu")
		(net "M_K_CLK_DN<1>")
	)
	(segment
		(start 92.59951 -136.557766)
		(end 92.320364 -136.27862)
		(width 0.1651)
		(layer "F.Cu")
		(net "M_K_CLK_DN<1>")
	)
	(segment
		(start 92.63253 -135.548116)
		(end 93.862398 -135.548116)
		(width 0.1651)
		(layer "F.Cu")
		(net "M_K_CLK_DN<1>")
	)
	(segment
		(start 95.739458 -101.44252)
		(end 95.738696 -101.44379)
		(width 0.0889)
		(layer "F.Cu")
		(net "M_K_CLK_DN<1>")
	)
	(segment
		(start 96.848422 -103.655368)
		(end 96.848422 -104.099106)
		(width 0.0889)
		(layer "F.Cu")
		(net "M_K_CLK_DN<1>")
	)
	(segment
		(start 95.667322 -102.474268)
		(end 96.848422 -103.655368)
		(width 0.0889)
		(layer "F.Cu")
		(net "M_K_CLK_DN<1>")
	)
	(segment
		(start 95.806768 -123.582938)
		(end 95.806768 -126.555246)
		(width 0.1651)
		(layer "F.Cu")
		(net "M_K_CLK_DN<1>")
	)
	(segment
		(start 92.320364 -135.860282)
		(end 92.63253 -135.548116)
		(width 0.1651)
		(layer "F.Cu")
		(net "M_K_CLK_DN<1>")
	)
	(segment
		(start 94.362778 -101.653086)
		(end 94.476316 -101.539294)
		(width 0.0889)
		(layer "F.Cu")
		(net "M_K_CLK_DN<1>")
	)
	(segment
		(start 96.302068 -133.108446)
		(end 96.302068 -130.739642)
		(width 0.1651)
		(layer "F.Cu")
		(net "M_K_CLK_DN<1>")
	)
	(via
		(at 95.806768 -126.555246)
		(size 0.508)
		(drill 0.254)
		(layers "F.Cu" "B.Cu")
		(net "M_K_CLK_DN<1>")
	)
	(arc
		(start 94.630494 -101.167438)
		(mid 94.731968 -100.82684)
		(end 95.010478 -100.606098)
		(width 0.0889)
		(layer "F.Cu")
		(net "M_K_CLK_DN<1>")
	)
	(arc
		(start 95.010478 -100.606098)
		(mid 95.666742 -100.769884)
		(end 95.739458 -101.44252)
		(width 0.0889)
		(layer "F.Cu")
		(net "M_K_CLK_DN<1>")
	)
	(arc
		(start 94.476316 -101.539294)
		(mid 94.590396 -101.3687)
		(end 94.630494 -101.167438)
		(width 0.0889)
		(layer "F.Cu")
		(net "M_K_CLK_DN<1>")
	)
	(segment
		(start 92.986098 -99.882706)
		(end 92.992448 -99.872038)
		(width 0.0889)
		(layer "F.Cu")
		(net "M_K_CLK_DN<2>")
	)
	(segment
		(start 90.442288 -130.559556)
		(end 90.513154 -130.48869)
		(width 0.1651)
		(layer "F.Cu")
		(net "M_K_CLK_DN<2>")
	)
	(segment
		(start 90.790268 -120.35282)
		(end 94.087442 -117.055646)
		(width 0.1651)
		(layer "F.Cu")
		(net "M_K_CLK_DN<2>")
	)
	(segment
		(start 92.290646 -131.265168)
		(end 91.923362 -131.632452)
		(width 0.1651)
		(layer "F.Cu")
		(net "M_K_CLK_DN<2>")
	)
	(segment
		(start 92.52331 -130.848608)
		(end 92.290646 -131.081272)
		(width 0.1651)
		(layer "F.Cu")
		(net "M_K_CLK_DN<2>")
	)
	(segment
		(start 90.513154 -130.48869)
		(end 90.513154 -130.02895)
		(width 0.1651)
		(layer "F.Cu")
		(net "M_K_CLK_DN<2>")
	)
	(segment
		(start 93.009212 -98.853498)
		(end 93.200982 -98.55962)
		(width 0.0889)
		(layer "F.Cu")
		(net "M_K_CLK_DN<2>")
	)
	(segment
		(start 90.415618 -128.954022)
		(end 90.790268 -128.579372)
		(width 0.1651)
		(layer "F.Cu")
		(net "M_K_CLK_DN<2>")
	)
	(segment
		(start 94.087442 -104.26446)
		(end 94.138242 -104.21366)
		(width 0.0889)
		(layer "F.Cu")
		(net "M_K_CLK_DN<2>")
	)
	(segment
		(start 94.087442 -117.055646)
		(end 94.087442 -104.26446)
		(width 0.1651)
		(layer "F.Cu")
		(net "M_K_CLK_DN<2>")
	)
	(segment
		(start 90.799666 -131.632452)
		(end 90.442288 -131.275074)
		(width 0.1651)
		(layer "F.Cu")
		(net "M_K_CLK_DN<2>")
	)
	(segment
		(start 94.138242 -104.112568)
		(end 92.066872 -102.041198)
		(width 0.0889)
		(layer "F.Cu")
		(net "M_K_CLK_DN<2>")
	)
	(segment
		(start 90.513154 -130.02895)
		(end 90.415618 -129.931414)
		(width 0.1651)
		(layer "F.Cu")
		(net "M_K_CLK_DN<2>")
	)
	(segment
		(start 92.632022 -101.062536)
		(end 92.660724 -101.062536)
		(width 0.0889)
		(layer "F.Cu")
		(net "M_K_CLK_DN<2>")
	)
	(segment
		(start 92.066872 -101.47427)
		(end 92.133928 -101.357938)
		(width 0.0889)
		(layer "F.Cu")
		(net "M_K_CLK_DN<2>")
	)
	(segment
		(start 90.790268 -128.579372)
		(end 90.790268 -120.35282)
		(width 0.1651)
		(layer "F.Cu")
		(net "M_K_CLK_DN<2>")
	)
	(segment
		(start 90.415618 -129.931414)
		(end 90.415618 -128.954022)
		(width 0.1651)
		(layer "F.Cu")
		(net "M_K_CLK_DN<2>")
	)
	(segment
		(start 91.923362 -131.632452)
		(end 90.799666 -131.632452)
		(width 0.1651)
		(layer "F.Cu")
		(net "M_K_CLK_DN<2>")
	)
	(segment
		(start 92.066872 -102.041198)
		(end 92.066872 -101.47427)
		(width 0.0889)
		(layer "F.Cu")
		(net "M_K_CLK_DN<2>")
	)
	(segment
		(start 92.997274 -100.471224)
		(end 92.992448 -100.462588)
		(width 0.0889)
		(layer "F.Cu")
		(net "M_K_CLK_DN<2>")
	)
	(segment
		(start 92.290646 -131.081272)
		(end 92.290646 -131.265168)
		(width 0.1651)
		(layer "F.Cu")
		(net "M_K_CLK_DN<2>")
	)
	(segment
		(start 94.138242 -104.21366)
		(end 94.138242 -104.112568)
		(width 0.0889)
		(layer "F.Cu")
		(net "M_K_CLK_DN<2>")
	)
	(segment
		(start 90.442288 -131.275074)
		(end 90.442288 -130.559556)
		(width 0.1651)
		(layer "F.Cu")
		(net "M_K_CLK_DN<2>")
	)
	(via
		(at 92.52331 -130.848608)
		(size 0.508)
		(drill 0.254)
		(layers "F.Cu" "B.Cu")
		(net "M_K_CLK_DN<2>")
	)
	(arc
		(start 92.992448 -100.462588)
		(mid 92.913226 -100.17347)
		(end 92.986098 -99.882706)
		(width 0.0889)
		(layer "F.Cu")
		(net "M_K_CLK_DN<2>")
	)
	(arc
		(start 93.200982 -98.55962)
		(mid 93.342956 -98.365081)
		(end 93.504258 -98.18624)
		(width 0.0889)
		(layer "F.Cu")
		(net "M_K_CLK_DN<2>")
	)
	(arc
		(start 92.133928 -101.357938)
		(mid 92.344281 -101.144966)
		(end 92.632022 -101.062536)
		(width 0.0889)
		(layer "F.Cu")
		(net "M_K_CLK_DN<2>")
	)
	(arc
		(start 92.992448 -99.872038)
		(mid 93.045947 -99.67214)
		(end 92.992448 -99.472242)
		(width 0.0889)
		(layer "F.Cu")
		(net "M_K_CLK_DN<2>")
	)
	(arc
		(start 92.992448 -99.472242)
		(mid 92.913374 -99.160513)
		(end 93.009212 -98.853498)
		(width 0.0889)
		(layer "F.Cu")
		(net "M_K_CLK_DN<2>")
	)
	(arc
		(start 92.660724 -101.062536)
		(mid 92.993642 -100.860545)
		(end 92.997274 -100.471224)
		(width 0.0889)
		(layer "F.Cu")
		(net "M_K_CLK_DN<2>")
	)
	(segment
		(start 92.59951 -132.876036)
		(end 92.59951 -130.924808)
		(width 0.1651)
		(layer "B.Cu")
		(net "M_K_CLK_DN<2>")
	)
	(segment
		(start 92.59951 -130.924808)
		(end 92.52331 -130.848608)
		(width 0.1651)
		(layer "B.Cu")
		(net "M_K_CLK_DN<2>")
	)
	(segment
		(start 93.250004 -123.316746)
		(end 93.415104 -123.481846)
		(width 0.1651)
		(layer "F.Cu")
		(net "M_K_CLK_DN<0>")
	)
	(segment
		(start 94.362778 -100.662486)
		(end 94.491556 -100.533708)
		(width 0.0889)
		(layer "F.Cu")
		(net "M_K_CLK_DN<0>")
	)
	(segment
		(start 93.415104 -122.808746)
		(end 93.250004 -122.973846)
		(width 0.1651)
		(layer "F.Cu")
		(net "M_K_CLK_DN<0>")
	)
	(segment
		(start 94.686374 -126.715012)
		(end 94.77375 -126.802388)
		(width 0.1651)
		(layer "F.Cu")
		(net "M_K_CLK_DN<0>")
	)
	(segment
		(start 94.77375 -126.802388)
		(end 94.77375 -127.297688)
		(width 0.1651)
		(layer "F.Cu")
		(net "M_K_CLK_DN<0>")
	)
	(segment
		(start 96.087946 -118.20144)
		(end 95.62084 -118.668546)
		(width 0.1651)
		(layer "F.Cu")
		(net "M_K_CLK_DN<0>")
	)
	(segment
		(start 94.686374 -130.419856)
		(end 93.170756 -131.935474)
		(width 0.1651)
		(layer "F.Cu")
		(net "M_K_CLK_DN<0>")
	)
	(segment
		(start 94.77375 -126.104904)
		(end 94.686374 -126.19228)
		(width 0.1651)
		(layer "F.Cu")
		(net "M_K_CLK_DN<0>")
	)
	(segment
		(start 93.250004 -122.973846)
		(end 93.250004 -123.316746)
		(width 0.1651)
		(layer "F.Cu")
		(net "M_K_CLK_DN<0>")
	)
	(segment
		(start 94.78264 -127.995172)
		(end 94.78264 -128.490472)
		(width 0.1651)
		(layer "F.Cu")
		(net "M_K_CLK_DN<0>")
	)
	(segment
		(start 92.714064 -131.935474)
		(end 92.59951 -132.050028)
		(width 0.1651)
		(layer "F.Cu")
		(net "M_K_CLK_DN<0>")
	)
	(segment
		(start 93.415104 -123.481846)
		(end 94.246954 -123.481846)
		(width 0.1651)
		(layer "F.Cu")
		(net "M_K_CLK_DN<0>")
	)
	(segment
		(start 93.170756 -131.935474)
		(end 92.714064 -131.935474)
		(width 0.1651)
		(layer "F.Cu")
		(net "M_K_CLK_DN<0>")
	)
	(segment
		(start 94.78264 -128.490472)
		(end 94.686374 -128.586738)
		(width 0.1651)
		(layer "F.Cu")
		(net "M_K_CLK_DN<0>")
	)
	(segment
		(start 96.037146 -103.938324)
		(end 96.037146 -104.102662)
		(width 0.0889)
		(layer "F.Cu")
		(net "M_K_CLK_DN<0>")
	)
	(segment
		(start 94.686374 -128.586738)
		(end 94.686374 -130.419856)
		(width 0.1651)
		(layer "F.Cu")
		(net "M_K_CLK_DN<0>")
	)
	(segment
		(start 95.464122 -122.472704)
		(end 95.12808 -122.808746)
		(width 0.1651)
		(layer "F.Cu")
		(net "M_K_CLK_DN<0>")
	)
	(segment
		(start 94.246954 -123.481846)
		(end 94.686374 -123.921266)
		(width 0.1651)
		(layer "F.Cu")
		(net "M_K_CLK_DN<0>")
	)
	(segment
		(start 94.790768 -119.498618)
		(end 94.790768 -120.542304)
		(width 0.1651)
		(layer "F.Cu")
		(net "M_K_CLK_DN<0>")
	)
	(segment
		(start 93.415104 -121.551446)
		(end 95.12808 -121.551446)
		(width 0.1651)
		(layer "F.Cu")
		(net "M_K_CLK_DN<0>")
	)
	(segment
		(start 94.454726 -120.878346)
		(end 93.415104 -120.878346)
		(width 0.1651)
		(layer "F.Cu")
		(net "M_K_CLK_DN<0>")
	)
	(segment
		(start 94.686374 -124.798582)
		(end 94.686374 -125.522228)
		(width 0.1651)
		(layer "F.Cu")
		(net "M_K_CLK_DN<0>")
	)
	(segment
		(start 95.62084 -118.668546)
		(end 95.62084 -118.78437)
		(width 0.1651)
		(layer "F.Cu")
		(net "M_K_CLK_DN<0>")
	)
	(segment
		(start 94.686374 -127.898906)
		(end 94.78264 -127.995172)
		(width 0.1651)
		(layer "F.Cu")
		(net "M_K_CLK_DN<0>")
	)
	(segment
		(start 93.415104 -120.878346)
		(end 93.250004 -121.043446)
		(width 0.1651)
		(layer "F.Cu")
		(net "M_K_CLK_DN<0>")
	)
	(segment
		(start 95.154496 -119.13489)
		(end 94.790768 -119.498618)
		(width 0.1651)
		(layer "F.Cu")
		(net "M_K_CLK_DN<0>")
	)
	(segment
		(start 94.351094 -100.259134)
		(end 94.299278 -100.267516)
		(width 0.0889)
		(layer "F.Cu")
		(net "M_K_CLK_DN<0>")
	)
	(segment
		(start 94.686374 -127.385064)
		(end 94.686374 -127.898906)
		(width 0.1651)
		(layer "F.Cu")
		(net "M_K_CLK_DN<0>")
	)
	(segment
		(start 94.77375 -125.609604)
		(end 94.77375 -126.104904)
		(width 0.1651)
		(layer "F.Cu")
		(net "M_K_CLK_DN<0>")
	)
	(segment
		(start 95.12808 -121.551446)
		(end 95.464122 -121.887488)
		(width 0.1651)
		(layer "F.Cu")
		(net "M_K_CLK_DN<0>")
	)
	(segment
		(start 94.77375 -127.297688)
		(end 94.686374 -127.385064)
		(width 0.1651)
		(layer "F.Cu")
		(net "M_K_CLK_DN<0>")
	)
	(segment
		(start 94.790768 -120.542304)
		(end 94.454726 -120.878346)
		(width 0.1651)
		(layer "F.Cu")
		(net "M_K_CLK_DN<0>")
	)
	(segment
		(start 94.686374 -125.522228)
		(end 94.77375 -125.609604)
		(width 0.1651)
		(layer "F.Cu")
		(net "M_K_CLK_DN<0>")
	)
	(segment
		(start 94.686374 -123.921266)
		(end 94.686374 -124.798582)
		(width 0.1651)
		(layer "F.Cu")
		(net "M_K_CLK_DN<0>")
	)
	(segment
		(start 94.022418 -101.44252)
		(end 94.01429 -101.456236)
		(width 0.0889)
		(layer "F.Cu")
		(net "M_K_CLK_DN<0>")
	)
	(segment
		(start 93.250004 -121.043446)
		(end 93.250004 -121.386346)
		(width 0.1651)
		(layer "F.Cu")
		(net "M_K_CLK_DN<0>")
	)
	(segment
		(start 95.464122 -121.887488)
		(end 95.464122 -122.472704)
		(width 0.1651)
		(layer "F.Cu")
		(net "M_K_CLK_DN<0>")
	)
	(segment
		(start 94.01429 -101.456236)
		(end 93.971872 -101.542342)
		(width 0.0889)
		(layer "F.Cu")
		(net "M_K_CLK_DN<0>")
	)
	(segment
		(start 93.971872 -101.87305)
		(end 96.037146 -103.938324)
		(width 0.0889)
		(layer "F.Cu")
		(net "M_K_CLK_DN<0>")
	)
	(segment
		(start 95.12808 -122.808746)
		(end 93.415104 -122.808746)
		(width 0.1651)
		(layer "F.Cu")
		(net "M_K_CLK_DN<0>")
	)
	(segment
		(start 93.971872 -101.542342)
		(end 93.971872 -101.87305)
		(width 0.0889)
		(layer "F.Cu")
		(net "M_K_CLK_DN<0>")
	)
	(segment
		(start 96.037146 -104.102662)
		(end 96.087946 -104.153462)
		(width 0.0889)
		(layer "F.Cu")
		(net "M_K_CLK_DN<0>")
	)
	(segment
		(start 92.59951 -132.050028)
		(end 92.59951 -133.0706)
		(width 0.1651)
		(layer "F.Cu")
		(net "M_K_CLK_DN<0>")
	)
	(segment
		(start 96.087946 -104.153462)
		(end 96.087946 -118.20144)
		(width 0.1651)
		(layer "F.Cu")
		(net "M_K_CLK_DN<0>")
	)
	(segment
		(start 94.686374 -126.19228)
		(end 94.686374 -126.715012)
		(width 0.1651)
		(layer "F.Cu")
		(net "M_K_CLK_DN<0>")
	)
	(segment
		(start 93.250004 -121.386346)
		(end 93.415104 -121.551446)
		(width 0.1651)
		(layer "F.Cu")
		(net "M_K_CLK_DN<0>")
	)
	(segment
		(start 95.27032 -119.13489)
		(end 95.154496 -119.13489)
		(width 0.1651)
		(layer "F.Cu")
		(net "M_K_CLK_DN<0>")
	)
	(segment
		(start 95.62084 -118.78437)
		(end 95.27032 -119.13489)
		(width 0.1651)
		(layer "F.Cu")
		(net "M_K_CLK_DN<0>")
	)
	(via
		(at 94.686374 -124.798582)
		(size 0.508)
		(drill 0.254)
		(layers "F.Cu" "B.Cu")
		(net "M_K_CLK_DN<0>")
	)
	(arc
		(start 94.299278 -100.267516)
		(mid 94.001339 -100.490704)
		(end 94.016068 -100.862638)
		(width 0.0889)
		(layer "F.Cu")
		(net "M_K_CLK_DN<0>")
	)
	(arc
		(start 94.491556 -100.533708)
		(mid 94.521222 -100.345358)
		(end 94.351094 -100.259134)
		(width 0.0889)
		(layer "F.Cu")
		(net "M_K_CLK_DN<0>")
	)
	(arc
		(start 94.016068 -100.862638)
		(mid 94.09529 -101.151756)
		(end 94.022418 -101.44252)
		(width 0.0889)
		(layer "F.Cu")
		(net "M_K_CLK_DN<0>")
	)
	(segment
		(start 86.717124 -100.257102)
		(end 86.492842 -100.412296)
		(width 0.0889)
		(layer "F.Cu")
		(net "M_K_CKE<3>")
	)
	(segment
		(start 86.408768 -100.589334)
		(end 86.408768 -101.677724)
		(width 0.0889)
		(layer "F.Cu")
		(net "M_K_CKE<3>")
	)
	(segment
		(start 87.494872 -99.67214)
		(end 86.90991 -100.257102)
		(width 0.0889)
		(layer "F.Cu")
		(net "M_K_CKE<3>")
	)
	(segment
		(start 86.612984 -102.332028)
		(end 86.612984 -113.658142)
		(width 0.1651)
		(layer "F.Cu")
		(net "M_K_CKE<3>")
	)
	(segment
		(start 86.612984 -101.88194)
		(end 86.612984 -102.332028)
		(width 0.0889)
		(layer "F.Cu")
		(net "M_K_CKE<3>")
	)
	(segment
		(start 86.492842 -100.412296)
		(end 86.408768 -100.589334)
		(width 0.0889)
		(layer "F.Cu")
		(net "M_K_CKE<3>")
	)
	(segment
		(start 78.999334 -128.425702)
		(end 78.999334 -129.568956)
		(width 0.1651)
		(layer "F.Cu")
		(net "M_K_CKE<3>")
	)
	(segment
		(start 86.90991 -100.257102)
		(end 86.717124 -100.257102)
		(width 0.0889)
		(layer "F.Cu")
		(net "M_K_CKE<3>")
	)
	(segment
		(start 81.962244 -125.462792)
		(end 78.999334 -128.425702)
		(width 0.1651)
		(layer "F.Cu")
		(net "M_K_CKE<3>")
	)
	(segment
		(start 81.962244 -118.308882)
		(end 81.962244 -125.462792)
		(width 0.1651)
		(layer "F.Cu")
		(net "M_K_CKE<3>")
	)
	(segment
		(start 86.612984 -113.658142)
		(end 81.962244 -118.308882)
		(width 0.1651)
		(layer "F.Cu")
		(net "M_K_CKE<3>")
	)
	(segment
		(start 86.408768 -101.677724)
		(end 86.612984 -101.88194)
		(width 0.0889)
		(layer "F.Cu")
		(net "M_K_CKE<3>")
	)
	(via
		(at 78.999334 -129.568956)
		(size 0.508)
		(drill 0.254)
		(layers "F.Cu" "B.Cu")
		(net "M_K_CKE<3>")
	)
	(segment
		(start 78.999334 -129.568956)
		(end 78.999334 -128.276096)
		(width 0.1651)
		(layer "B.Cu")
		(net "M_K_CKE<3>")
	)
	(segment
		(start 79.499968 -129.7686)
		(end 79.271368 -129.9972)
		(width 0.1651)
		(layer "F.Cu")
		(net "M_K_CKE<2>")
	)
	(segment
		(start 87.067136 -101.969824)
		(end 87.145114 -102.047802)
		(width 0.0889)
		(layer "F.Cu")
		(net "M_K_CKE<2>")
	)
	(segment
		(start 82.495136 -125.70206)
		(end 79.499968 -128.697228)
		(width 0.1651)
		(layer "F.Cu")
		(net "M_K_CKE<2>")
	)
	(segment
		(start 79.550768 -130.6322)
		(end 79.550768 -131.287774)
		(width 0.1651)
		(layer "F.Cu")
		(net "M_K_CKE<2>")
	)
	(segment
		(start 87.067136 -101.51364)
		(end 87.067136 -101.969824)
		(width 0.0889)
		(layer "F.Cu")
		(net "M_K_CKE<2>")
	)
	(segment
		(start 87.894922 -100.89261)
		(end 87.645748 -101.141784)
		(width 0.0889)
		(layer "F.Cu")
		(net "M_K_CKE<2>")
	)
	(segment
		(start 79.499968 -128.697228)
		(end 79.499968 -129.7686)
		(width 0.1651)
		(layer "F.Cu")
		(net "M_K_CKE<2>")
	)
	(segment
		(start 87.145114 -102.338886)
		(end 87.145114 -114.058446)
		(width 0.1651)
		(layer "F.Cu")
		(net "M_K_CKE<2>")
	)
	(segment
		(start 87.645748 -101.141784)
		(end 87.438992 -101.141784)
		(width 0.0889)
		(layer "F.Cu")
		(net "M_K_CKE<2>")
	)
	(segment
		(start 87.145114 -114.058446)
		(end 82.495136 -118.708424)
		(width 0.1651)
		(layer "F.Cu")
		(net "M_K_CKE<2>")
	)
	(segment
		(start 87.438992 -101.141784)
		(end 87.067136 -101.51364)
		(width 0.0889)
		(layer "F.Cu")
		(net "M_K_CKE<2>")
	)
	(segment
		(start 88.353392 -99.17684)
		(end 87.894922 -99.781614)
		(width 0.0889)
		(layer "F.Cu")
		(net "M_K_CKE<2>")
	)
	(segment
		(start 79.550768 -131.287774)
		(end 79.849472 -131.586478)
		(width 0.1651)
		(layer "F.Cu")
		(net "M_K_CKE<2>")
	)
	(segment
		(start 82.495136 -118.708424)
		(end 82.495136 -125.70206)
		(width 0.1651)
		(layer "F.Cu")
		(net "M_K_CKE<2>")
	)
	(segment
		(start 87.894922 -99.781614)
		(end 87.894922 -100.89261)
		(width 0.0889)
		(layer "F.Cu")
		(net "M_K_CKE<2>")
	)
	(segment
		(start 79.271368 -129.9972)
		(end 79.271368 -130.3528)
		(width 0.1651)
		(layer "F.Cu")
		(net "M_K_CKE<2>")
	)
	(segment
		(start 87.145114 -102.047802)
		(end 87.145114 -102.338886)
		(width 0.0889)
		(layer "F.Cu")
		(net "M_K_CKE<2>")
	)
	(segment
		(start 79.271368 -130.3528)
		(end 79.550768 -130.6322)
		(width 0.1651)
		(layer "F.Cu")
		(net "M_K_CKE<2>")
	)
	(via
		(at 79.849472 -131.586478)
		(size 0.508)
		(drill 0.254)
		(layers "F.Cu" "B.Cu")
		(net "M_K_CKE<2>")
	)
	(segment
		(start 79.849472 -132.876036)
		(end 79.849472 -131.586478)
		(width 0.1651)
		(layer "B.Cu")
		(net "M_K_CKE<2>")
	)
	(segment
		(start 78.999334 -136.387078)
		(end 78.999334 -137.67054)
		(width 0.1651)
		(layer "F.Cu")
		(net "M_K_CKE<1>")
	)
	(segment
		(start 87.727536 -101.88575)
		(end 87.727536 -102.543356)
		(width 0.0889)
		(layer "F.Cu")
		(net "M_K_CKE<1>")
	)
	(segment
		(start 87.727536 -102.543356)
		(end 87.727536 -114.353594)
		(width 0.1651)
		(layer "F.Cu")
		(net "M_K_CKE<1>")
	)
	(segment
		(start 83.038188 -119.042942)
		(end 83.038188 -126.28118)
		(width 0.1651)
		(layer "F.Cu")
		(net "M_K_CKE<1>")
	)
	(segment
		(start 87.727536 -114.353594)
		(end 83.038188 -119.042942)
		(width 0.1651)
		(layer "F.Cu")
		(net "M_K_CKE<1>")
	)
	(segment
		(start 87.494872 -101.653086)
		(end 87.727536 -101.88575)
		(width 0.0889)
		(layer "F.Cu")
		(net "M_K_CKE<1>")
	)
	(via
		(at 83.038188 -126.28118)
		(size 0.508)
		(drill 0.254)
		(layers "F.Cu" "B.Cu")
		(net "M_K_CKE<1>")
	)
	(via
		(at 78.999334 -136.387078)
		(size 0.4572)
		(drill 0.2032)
		(layers "F.Cu" "B.Cu")
		(net "M_K_CKE<1>")
	)
	(segment
		(start 79.439008 -135.947404)
		(end 78.999334 -136.387078)
		(width 0.14224)
		(layer "In11.Cu")
		(net "M_K_CKE<1>")
	)
	(segment
		(start 83.038188 -126.28118)
		(end 82.250788 -126.28118)
		(width 0.14224)
		(layer "In11.Cu")
		(net "M_K_CKE<1>")
	)
	(segment
		(start 79.439008 -134.07136)
		(end 79.439008 -135.947404)
		(width 0.14224)
		(layer "In11.Cu")
		(net "M_K_CKE<1>")
	)
	(segment
		(start 81.16316 -131.29006)
		(end 80.338168 -132.115052)
		(width 0.14224)
		(layer "In11.Cu")
		(net "M_K_CKE<1>")
	)
	(segment
		(start 80.338168 -132.115052)
		(end 80.338168 -133.1722)
		(width 0.14224)
		(layer "In11.Cu")
		(net "M_K_CKE<1>")
	)
	(segment
		(start 80.338168 -133.1722)
		(end 79.439008 -134.07136)
		(width 0.14224)
		(layer "In11.Cu")
		(net "M_K_CKE<1>")
	)
	(segment
		(start 81.080864 -129.856992)
		(end 81.080864 -130.454146)
		(width 0.14224)
		(layer "In11.Cu")
		(net "M_K_CKE<1>")
	)
	(segment
		(start 81.431892 -127.100076)
		(end 81.431892 -129.505964)
		(width 0.14224)
		(layer "In11.Cu")
		(net "M_K_CKE<1>")
	)
	(segment
		(start 81.080864 -130.454146)
		(end 81.16316 -130.536442)
		(width 0.14224)
		(layer "In11.Cu")
		(net "M_K_CKE<1>")
	)
	(segment
		(start 81.16316 -130.536442)
		(end 81.16316 -131.29006)
		(width 0.14224)
		(layer "In11.Cu")
		(net "M_K_CKE<1>")
	)
	(segment
		(start 81.431892 -129.505964)
		(end 81.080864 -129.856992)
		(width 0.14224)
		(layer "In11.Cu")
		(net "M_K_CKE<1>")
	)
	(segment
		(start 82.250788 -126.28118)
		(end 81.431892 -127.100076)
		(width 0.14224)
		(layer "In11.Cu")
		(net "M_K_CKE<1>")
	)
	(segment
		(start 83.030568 -128.2446)
		(end 83.75142 -127.523748)
		(width 0.1651)
		(layer "F.Cu")
		(net "M_K_CKE<0>")
	)
	(segment
		(start 80.160368 -130.7084)
		(end 80.808068 -130.0607)
		(width 0.1651)
		(layer "F.Cu")
		(net "M_K_CKE<0>")
	)
	(segment
		(start 82.598768 -128.2446)
		(end 83.030568 -128.2446)
		(width 0.1651)
		(layer "F.Cu")
		(net "M_K_CKE<0>")
	)
	(segment
		(start 83.75142 -119.06631)
		(end 88.259666 -114.558064)
		(width 0.1651)
		(layer "F.Cu")
		(net "M_K_CKE<0>")
	)
	(segment
		(start 80.338168 -131.749546)
		(end 80.338168 -131.379468)
		(width 0.1651)
		(layer "F.Cu")
		(net "M_K_CKE<0>")
	)
	(segment
		(start 88.353392 -101.483922)
		(end 88.353392 -101.15804)
		(width 0.0889)
		(layer "F.Cu")
		(net "M_K_CKE<0>")
	)
	(segment
		(start 88.259666 -102.979728)
		(end 88.259666 -101.577648)
		(width 0.0889)
		(layer "F.Cu")
		(net "M_K_CKE<0>")
	)
	(segment
		(start 80.909668 -130.0607)
		(end 81.354168 -129.6162)
		(width 0.1651)
		(layer "F.Cu")
		(net "M_K_CKE<0>")
	)
	(segment
		(start 80.808068 -130.0607)
		(end 80.909668 -130.0607)
		(width 0.1651)
		(layer "F.Cu")
		(net "M_K_CKE<0>")
	)
	(segment
		(start 83.75142 -124.408692)
		(end 83.75142 -119.06631)
		(width 0.1651)
		(layer "F.Cu")
		(net "M_K_CKE<0>")
	)
	(segment
		(start 80.160368 -131.201668)
		(end 80.160368 -130.7084)
		(width 0.1651)
		(layer "F.Cu")
		(net "M_K_CKE<0>")
	)
	(segment
		(start 80.338168 -131.379468)
		(end 80.160368 -131.201668)
		(width 0.1651)
		(layer "F.Cu")
		(net "M_K_CKE<0>")
	)
	(segment
		(start 88.259666 -101.577648)
		(end 88.353392 -101.483922)
		(width 0.0889)
		(layer "F.Cu")
		(net "M_K_CKE<0>")
	)
	(segment
		(start 83.75142 -127.523748)
		(end 83.75142 -124.408692)
		(width 0.1651)
		(layer "F.Cu")
		(net "M_K_CKE<0>")
	)
	(segment
		(start 81.354168 -129.6162)
		(end 81.354168 -129.4892)
		(width 0.1651)
		(layer "F.Cu")
		(net "M_K_CKE<0>")
	)
	(segment
		(start 88.259666 -114.558064)
		(end 88.259666 -102.979728)
		(width 0.1651)
		(layer "F.Cu")
		(net "M_K_CKE<0>")
	)
	(segment
		(start 79.849472 -132.238242)
		(end 80.338168 -131.749546)
		(width 0.1651)
		(layer "F.Cu")
		(net "M_K_CKE<0>")
	)
	(segment
		(start 79.849472 -133.0706)
		(end 79.849472 -132.238242)
		(width 0.1651)
		(layer "F.Cu")
		(net "M_K_CKE<0>")
	)
	(segment
		(start 81.354168 -129.4892)
		(end 82.598768 -128.2446)
		(width 0.1651)
		(layer "F.Cu")
		(net "M_K_CKE<0>")
	)
	(via
		(at 83.75142 -124.408692)
		(size 0.508)
		(drill 0.254)
		(layers "F.Cu" "B.Cu")
		(net "M_K_CKE<0>")
	)
	(segment
		(start 111.299498 -136.387586)
		(end 111.300006 -136.387078)
		(width 0.10795)
		(layer "F.Cu")
		(net "M_K_C<2>")
	)
	(segment
		(start 111.299498 -137.67054)
		(end 111.299498 -136.387586)
		(width 0.10795)
		(layer "F.Cu")
		(net "M_K_C<2>")
	)
	(segment
		(start 101.230684 -97.690686)
		(end 100.659184 -97.690686)
		(width 0.1651)
		(layer "F.Cu")
		(net "M_K_C<2>")
	)
	(via
		(at 111.300006 -136.387078)
		(size 0.4572)
		(drill 0.2032)
		(layers "F.Cu" "B.Cu")
		(net "M_K_C<2>")
	)
	(via
		(at 100.659184 -97.690686)
		(size 0.508)
		(drill 0.254)
		(layers "F.Cu" "B.Cu")
		(net "M_K_C<2>")
	)
	(via
		(at 111.299498 -129.568956)
		(size 0.508)
		(drill 0.254)
		(layers "F.Cu" "B.Cu")
		(net "M_K_C<2>")
	)
	(segment
		(start 111.299498 -128.276096)
		(end 111.299498 -129.568956)
		(width 0.1651)
		(layer "B.Cu")
		(net "M_K_C<2>")
	)
	(segment
		(start 100.659184 -97.690686)
		(end 102.184454 -97.690686)
		(width 0.0889)
		(layer "In11.Cu")
		(net "M_K_C<2>")
	)
	(segment
		(start 111.656368 -134.6962)
		(end 111.656368 -136.030716)
		(width 0.14224)
		(layer "In11.Cu")
		(net "M_K_C<2>")
	)
	(segment
		(start 111.757968 -131.1656)
		(end 111.681768 -131.2418)
		(width 0.14224)
		(layer "In11.Cu")
		(net "M_K_C<2>")
	)
	(segment
		(start 104.493568 -101.676454)
		(end 104.493568 -102.014782)
		(width 0.0889)
		(layer "In11.Cu")
		(net "M_K_C<2>")
	)
	(segment
		(start 111.299498 -129.568956)
		(end 111.299498 -130.17373)
		(width 0.14224)
		(layer "In11.Cu")
		(net "M_K_C<2>")
	)
	(segment
		(start 102.867968 -100.050854)
		(end 104.493568 -101.676454)
		(width 0.0889)
		(layer "In11.Cu")
		(net "M_K_C<2>")
	)
	(segment
		(start 111.757968 -126.626112)
		(end 111.757968 -129.110486)
		(width 0.14224)
		(layer "In11.Cu")
		(net "M_K_C<2>")
	)
	(segment
		(start 102.867968 -98.3742)
		(end 102.867968 -100.050854)
		(width 0.0889)
		(layer "In11.Cu")
		(net "M_K_C<2>")
	)
	(segment
		(start 104.493568 -119.361712)
		(end 111.757968 -126.626112)
		(width 0.14224)
		(layer "In11.Cu")
		(net "M_K_C<2>")
	)
	(segment
		(start 104.493568 -102.014782)
		(end 104.493568 -119.361712)
		(width 0.14224)
		(layer "In11.Cu")
		(net "M_K_C<2>")
	)
	(segment
		(start 111.71555 -134.637018)
		(end 111.656368 -134.6962)
		(width 0.14224)
		(layer "In11.Cu")
		(net "M_K_C<2>")
	)
	(segment
		(start 111.299498 -130.17373)
		(end 111.757968 -130.6322)
		(width 0.14224)
		(layer "In11.Cu")
		(net "M_K_C<2>")
	)
	(segment
		(start 102.184454 -97.690686)
		(end 102.867968 -98.3742)
		(width 0.0889)
		(layer "In11.Cu")
		(net "M_K_C<2>")
	)
	(segment
		(start 111.757968 -130.6322)
		(end 111.757968 -131.1656)
		(width 0.14224)
		(layer "In11.Cu")
		(net "M_K_C<2>")
	)
	(segment
		(start 111.757968 -129.110486)
		(end 111.299498 -129.568956)
		(width 0.14224)
		(layer "In11.Cu")
		(net "M_K_C<2>")
	)
	(segment
		(start 111.71555 -131.885182)
		(end 111.71555 -134.637018)
		(width 0.14224)
		(layer "In11.Cu")
		(net "M_K_C<2>")
	)
	(segment
		(start 111.656368 -136.030716)
		(end 111.300006 -136.387078)
		(width 0.14224)
		(layer "In11.Cu")
		(net "M_K_C<2>")
	)
	(segment
		(start 111.681768 -131.2418)
		(end 111.681768 -131.8514)
		(width 0.14224)
		(layer "In11.Cu")
		(net "M_K_C<2>")
	)
	(segment
		(start 111.681768 -131.8514)
		(end 111.71555 -131.885182)
		(width 0.14224)
		(layer "In11.Cu")
		(net "M_K_C<2>")
	)
	(segment
		(start 88.353392 -98.18624)
		(end 87.781892 -98.18624)
		(width 0.1651)
		(layer "F.Cu")
		(net "M_K_BG<1>")
	)
	(segment
		(start 82.399378 -136.387078)
		(end 82.399378 -137.67054)
		(width 0.1651)
		(layer "F.Cu")
		(net "M_K_BG<1>")
	)
	(via
		(at 82.399378 -129.539746)
		(size 0.508)
		(drill 0.254)
		(layers "F.Cu" "B.Cu")
		(net "M_K_BG<1>")
	)
	(via
		(at 82.399378 -136.387078)
		(size 0.4572)
		(drill 0.2032)
		(layers "F.Cu" "B.Cu")
		(net "M_K_BG<1>")
	)
	(via
		(at 87.781892 -98.18624)
		(size 0.508)
		(drill 0.254)
		(layers "F.Cu" "B.Cu")
		(net "M_K_BG<1>")
	)
	(segment
		(start 82.399378 -128.276096)
		(end 82.399378 -129.539746)
		(width 0.1651)
		(layer "B.Cu")
		(net "M_K_BG<1>")
	)
	(segment
		(start 87.451946 -98.947986)
		(end 87.435182 -98.976688)
		(width 0.0889)
		(layer "In11.Cu")
		(net "M_K_BG<1>")
	)
	(segment
		(start 82.400902 -128.30937)
		(end 82.641948 -128.550416)
		(width 0.14224)
		(layer "In11.Cu")
		(net "M_K_BG<1>")
	)
	(segment
		(start 81.963768 -134.6962)
		(end 82.141568 -134.874)
		(width 0.14224)
		(layer "In11.Cu")
		(net "M_K_BG<1>")
	)
	(segment
		(start 83.538568 -124.146564)
		(end 83.538568 -127.859282)
		(width 0.14224)
		(layer "In11.Cu")
		(net "M_K_BG<1>")
	)
	(segment
		(start 82.641948 -128.769364)
		(end 82.399378 -129.011934)
		(width 0.14224)
		(layer "In11.Cu")
		(net "M_K_BG<1>")
	)
	(segment
		(start 86.957662 -101.463094)
		(end 86.957662 -101.894894)
		(width 0.0889)
		(layer "In11.Cu")
		(net "M_K_BG<1>")
	)
	(segment
		(start 86.957662 -101.894894)
		(end 86.957662 -102.155244)
		(width 0.14224)
		(layer "In11.Cu")
		(net "M_K_BG<1>")
	)
	(segment
		(start 83.025488 -128.139952)
		(end 82.793586 -127.90805)
		(width 0.14224)
		(layer "In11.Cu")
		(net "M_K_BG<1>")
	)
	(segment
		(start 86.957662 -102.155244)
		(end 86.957916 -102.155498)
		(width 0.14224)
		(layer "In11.Cu")
		(net "M_K_BG<1>")
	)
	(segment
		(start 83.538568 -127.859282)
		(end 83.257898 -128.139952)
		(width 0.14224)
		(layer "In11.Cu")
		(net "M_K_BG<1>")
	)
	(segment
		(start 82.400902 -128.086104)
		(end 82.400902 -128.30937)
		(width 0.14224)
		(layer "In11.Cu")
		(net "M_K_BG<1>")
	)
	(segment
		(start 82.641948 -128.550416)
		(end 82.641948 -128.769364)
		(width 0.14224)
		(layer "In11.Cu")
		(net "M_K_BG<1>")
	)
	(segment
		(start 81.963768 -131.953)
		(end 81.963768 -134.6962)
		(width 0.14224)
		(layer "In11.Cu")
		(net "M_K_BG<1>")
	)
	(segment
		(start 87.391494 -99.264978)
		(end 87.391494 -99.779074)
		(width 0.0889)
		(layer "In11.Cu")
		(net "M_K_BG<1>")
	)
	(segment
		(start 83.257898 -128.139952)
		(end 83.025488 -128.139952)
		(width 0.14224)
		(layer "In11.Cu")
		(net "M_K_BG<1>")
	)
	(segment
		(start 82.399378 -130.17119)
		(end 81.938368 -130.6322)
		(width 0.14224)
		(layer "In11.Cu")
		(net "M_K_BG<1>")
	)
	(segment
		(start 86.662768 -100.203)
		(end 86.434168 -100.4316)
		(width 0.0889)
		(layer "In11.Cu")
		(net "M_K_BG<1>")
	)
	(segment
		(start 82.793586 -127.90805)
		(end 82.578956 -127.90805)
		(width 0.14224)
		(layer "In11.Cu")
		(net "M_K_BG<1>")
	)
	(segment
		(start 82.399378 -129.011934)
		(end 82.399378 -129.539746)
		(width 0.14224)
		(layer "In11.Cu")
		(net "M_K_BG<1>")
	)
	(segment
		(start 82.141568 -134.874)
		(end 82.141568 -135.445246)
		(width 0.14224)
		(layer "In11.Cu")
		(net "M_K_BG<1>")
	)
	(segment
		(start 87.781892 -98.18624)
		(end 87.451946 -98.947986)
		(width 0.0889)
		(layer "In11.Cu")
		(net "M_K_BG<1>")
	)
	(segment
		(start 81.938368 -131.2164)
		(end 82.014568 -131.2926)
		(width 0.14224)
		(layer "In11.Cu")
		(net "M_K_BG<1>")
	)
	(segment
		(start 82.014568 -131.2926)
		(end 82.014568 -131.9022)
		(width 0.14224)
		(layer "In11.Cu")
		(net "M_K_BG<1>")
	)
	(segment
		(start 82.578956 -127.90805)
		(end 82.400902 -128.086104)
		(width 0.14224)
		(layer "In11.Cu")
		(net "M_K_BG<1>")
	)
	(segment
		(start 86.434168 -100.4316)
		(end 86.434168 -100.9396)
		(width 0.0889)
		(layer "In11.Cu")
		(net "M_K_BG<1>")
	)
	(segment
		(start 86.434168 -100.9396)
		(end 86.957662 -101.463094)
		(width 0.0889)
		(layer "In11.Cu")
		(net "M_K_BG<1>")
	)
	(segment
		(start 86.957916 -120.727216)
		(end 83.538568 -124.146564)
		(width 0.14224)
		(layer "In11.Cu")
		(net "M_K_BG<1>")
	)
	(segment
		(start 81.938368 -130.6322)
		(end 81.938368 -131.2164)
		(width 0.14224)
		(layer "In11.Cu")
		(net "M_K_BG<1>")
	)
	(segment
		(start 82.399378 -135.703056)
		(end 82.399378 -136.387078)
		(width 0.14224)
		(layer "In11.Cu")
		(net "M_K_BG<1>")
	)
	(segment
		(start 86.967568 -100.203)
		(end 86.662768 -100.203)
		(width 0.0889)
		(layer "In11.Cu")
		(net "M_K_BG<1>")
	)
	(segment
		(start 87.391494 -99.779074)
		(end 86.967568 -100.203)
		(width 0.0889)
		(layer "In11.Cu")
		(net "M_K_BG<1>")
	)
	(segment
		(start 82.141568 -135.445246)
		(end 82.399378 -135.703056)
		(width 0.14224)
		(layer "In11.Cu")
		(net "M_K_BG<1>")
	)
	(segment
		(start 82.399378 -129.539746)
		(end 82.399378 -130.17119)
		(width 0.14224)
		(layer "In11.Cu")
		(net "M_K_BG<1>")
	)
	(segment
		(start 82.014568 -131.9022)
		(end 81.963768 -131.953)
		(width 0.14224)
		(layer "In11.Cu")
		(net "M_K_BG<1>")
	)
	(segment
		(start 86.957916 -102.155498)
		(end 86.957916 -120.727216)
		(width 0.14224)
		(layer "In11.Cu")
		(net "M_K_BG<1>")
	)
	(arc
		(start 87.435182 -98.976688)
		(mid 87.386187 -99.116712)
		(end 87.391494 -99.264978)
		(width 0.0889)
		(layer "In11.Cu")
		(net "M_K_BG<1>")
	)
	(segment
		(start 85.448902 -125.316234)
		(end 85.287866 -125.47727)
		(width 0.1651)
		(layer "F.Cu")
		(net "M_K_BG<0>")
	)
	(segment
		(start 88.882474 -101.42347)
		(end 88.865202 -101.453188)
		(width 0.0889)
		(layer "F.Cu")
		(net "M_K_BG<0>")
	)
	(segment
		(start 83.249008 -130.902456)
		(end 82.399378 -130.902456)
		(width 0.1651)
		(layer "F.Cu")
		(net "M_K_BG<0>")
	)
	(segment
		(start 84.81822 -119.927878)
		(end 84.98332 -120.092978)
		(width 0.1651)
		(layer "F.Cu")
		(net "M_K_BG<0>")
	)
	(segment
		(start 85.448902 -124.973334)
		(end 85.448902 -125.316234)
		(width 0.1651)
		(layer "F.Cu")
		(net "M_K_BG<0>")
	)
	(segment
		(start 84.81822 -125.64237)
		(end 84.81822 -127.948436)
		(width 0.1651)
		(layer "F.Cu")
		(net "M_K_BG<0>")
	)
	(segment
		(start 89.323926 -114.992658)
		(end 84.81822 -119.498364)
		(width 0.1651)
		(layer "F.Cu")
		(net "M_K_BG<0>")
	)
	(segment
		(start 85.228684 -120.766078)
		(end 84.98332 -120.766078)
		(width 0.1651)
		(layer "F.Cu")
		(net "M_K_BG<0>")
	)
	(segment
		(start 85.279738 -124.80417)
		(end 85.448902 -124.973334)
		(width 0.1651)
		(layer "F.Cu")
		(net "M_K_BG<0>")
	)
	(segment
		(start 88.770968 -102.006654)
		(end 88.770968 -102.4636)
		(width 0.0889)
		(layer "F.Cu")
		(net "M_K_BG<0>")
	)
	(segment
		(start 85.049106 -128.179322)
		(end 85.049106 -128.730756)
		(width 0.1651)
		(layer "F.Cu")
		(net "M_K_BG<0>")
	)
	(segment
		(start 84.98332 -124.80417)
		(end 85.279738 -124.80417)
		(width 0.1651)
		(layer "F.Cu")
		(net "M_K_BG<0>")
	)
	(segment
		(start 84.681314 -129.098548)
		(end 83.87842 -129.098548)
		(width 0.1651)
		(layer "F.Cu")
		(net "M_K_BG<0>")
	)
	(segment
		(start 83.589368 -129.8194)
		(end 83.730084 -129.960116)
		(width 0.1651)
		(layer "F.Cu")
		(net "M_K_BG<0>")
	)
	(segment
		(start 89.323926 -103.016558)
		(end 89.323926 -103.473758)
		(width 0.0889)
		(layer "F.Cu")
		(net "M_K_BG<0>")
	)
	(segment
		(start 84.81822 -119.498364)
		(end 84.81822 -119.927878)
		(width 0.1651)
		(layer "F.Cu")
		(net "M_K_BG<0>")
	)
	(segment
		(start 88.811608 -101.966014)
		(end 88.770968 -102.006654)
		(width 0.0889)
		(layer "F.Cu")
		(net "M_K_BG<0>")
	)
	(segment
		(start 84.81822 -120.931178)
		(end 84.81822 -124.63907)
		(width 0.1651)
		(layer "F.Cu")
		(net "M_K_BG<0>")
	)
	(segment
		(start 84.98332 -125.47727)
		(end 84.81822 -125.64237)
		(width 0.1651)
		(layer "F.Cu")
		(net "M_K_BG<0>")
	)
	(segment
		(start 85.236812 -120.092978)
		(end 85.397848 -120.254014)
		(width 0.1651)
		(layer "F.Cu")
		(net "M_K_BG<0>")
	)
	(segment
		(start 84.98332 -120.092978)
		(end 85.236812 -120.092978)
		(width 0.1651)
		(layer "F.Cu")
		(net "M_K_BG<0>")
	)
	(segment
		(start 83.730084 -129.960116)
		(end 83.730084 -130.42138)
		(width 0.1651)
		(layer "F.Cu")
		(net "M_K_BG<0>")
	)
	(segment
		(start 89.211912 -100.662486)
		(end 88.882474 -101.42347)
		(width 0.0889)
		(layer "F.Cu")
		(net "M_K_BG<0>")
	)
	(segment
		(start 85.397848 -120.254014)
		(end 85.397848 -120.596914)
		(width 0.1651)
		(layer "F.Cu")
		(net "M_K_BG<0>")
	)
	(segment
		(start 84.81822 -124.63907)
		(end 84.98332 -124.80417)
		(width 0.1651)
		(layer "F.Cu")
		(net "M_K_BG<0>")
	)
	(segment
		(start 84.81822 -127.948436)
		(end 85.049106 -128.179322)
		(width 0.1651)
		(layer "F.Cu")
		(net "M_K_BG<0>")
	)
	(segment
		(start 83.730084 -130.42138)
		(end 83.249008 -130.902456)
		(width 0.1651)
		(layer "F.Cu")
		(net "M_K_BG<0>")
	)
	(segment
		(start 88.770968 -102.4636)
		(end 89.323926 -103.016558)
		(width 0.0889)
		(layer "F.Cu")
		(net "M_K_BG<0>")
	)
	(segment
		(start 85.287866 -125.47727)
		(end 84.98332 -125.47727)
		(width 0.1651)
		(layer "F.Cu")
		(net "M_K_BG<0>")
	)
	(segment
		(start 82.399378 -133.0706)
		(end 82.399378 -134.369556)
		(width 0.1651)
		(layer "F.Cu")
		(net "M_K_BG<0>")
	)
	(segment
		(start 88.813894 -101.650038)
		(end 88.811608 -101.966014)
		(width 0.0889)
		(layer "F.Cu")
		(net "M_K_BG<0>")
	)
	(segment
		(start 85.049106 -128.730756)
		(end 84.681314 -129.098548)
		(width 0.1651)
		(layer "F.Cu")
		(net "M_K_BG<0>")
	)
	(segment
		(start 89.323926 -103.473758)
		(end 89.323926 -114.992658)
		(width 0.1651)
		(layer "F.Cu")
		(net "M_K_BG<0>")
	)
	(segment
		(start 84.98332 -120.766078)
		(end 84.81822 -120.931178)
		(width 0.1651)
		(layer "F.Cu")
		(net "M_K_BG<0>")
	)
	(segment
		(start 83.589368 -129.3876)
		(end 83.589368 -129.8194)
		(width 0.1651)
		(layer "F.Cu")
		(net "M_K_BG<0>")
	)
	(segment
		(start 83.87842 -129.098548)
		(end 83.589368 -129.3876)
		(width 0.1651)
		(layer "F.Cu")
		(net "M_K_BG<0>")
	)
	(segment
		(start 85.397848 -120.596914)
		(end 85.228684 -120.766078)
		(width 0.1651)
		(layer "F.Cu")
		(net "M_K_BG<0>")
	)
	(via
		(at 82.399378 -130.902456)
		(size 0.508)
		(drill 0.254)
		(layers "F.Cu" "B.Cu")
		(net "M_K_BG<0>")
	)
	(via
		(at 82.399378 -134.369556)
		(size 0.4572)
		(drill 0.2032)
		(layers "F.Cu" "B.Cu")
		(net "M_K_BG<0>")
	)
	(arc
		(start 88.814148 -101.64699)
		(mid 88.814018 -101.648514)
		(end 88.813894 -101.650038)
		(width 0.0889)
		(layer "F.Cu")
		(net "M_K_BG<0>")
	)
	(arc
		(start 88.845898 -101.49713)
		(mid 88.822752 -101.570518)
		(end 88.814148 -101.64699)
		(width 0.0889)
		(layer "F.Cu")
		(net "M_K_BG<0>")
	)
	(arc
		(start 88.865202 -101.453188)
		(mid 88.854951 -101.474896)
		(end 88.845898 -101.49713)
		(width 0.0889)
		(layer "F.Cu")
		(net "M_K_BG<0>")
	)
	(segment
		(start 82.399378 -132.876036)
		(end 82.399378 -130.902456)
		(width 0.1651)
		(layer "B.Cu")
		(net "M_K_BG<0>")
	)
	(segment
		(start 82.399378 -130.902456)
		(end 82.399378 -134.369556)
		(width 0.14224)
		(layer "In9.Cu")
		(net "M_K_BG<0>")
	)
	(segment
		(start 101.949504 -137.67054)
		(end 101.949504 -136.387332)
		(width 0.1651)
		(layer "F.Cu")
		(net "M_K_BA<1>")
	)
	(segment
		(start 94.649798 -99.17684)
		(end 95.221298 -99.17684)
		(width 0.1651)
		(layer "F.Cu")
		(net "M_K_BA<1>")
	)
	(segment
		(start 101.949504 -136.387332)
		(end 101.949758 -136.387078)
		(width 0.1651)
		(layer "F.Cu")
		(net "M_K_BA<1>")
	)
	(via
		(at 101.94925 -130.249168)
		(size 0.508)
		(drill 0.254)
		(layers "F.Cu" "B.Cu")
		(net "M_K_BA<1>")
	)
	(via
		(at 101.949758 -136.387078)
		(size 0.4572)
		(drill 0.2032)
		(layers "F.Cu" "B.Cu")
		(net "M_K_BA<1>")
	)
	(via
		(at 94.649798 -99.17684)
		(size 0.508)
		(drill 0.254)
		(layers "F.Cu" "B.Cu")
		(net "M_K_BA<1>")
	)
	(segment
		(start 101.949504 -130.248914)
		(end 101.94925 -130.249168)
		(width 0.1651)
		(layer "B.Cu")
		(net "M_K_BA<1>")
	)
	(segment
		(start 101.949504 -128.276096)
		(end 101.949504 -130.248914)
		(width 0.1651)
		(layer "B.Cu")
		(net "M_K_BA<1>")
	)
	(segment
		(start 101.907848 -132.790692)
		(end 101.907848 -133.042152)
		(width 0.14224)
		(layer "In11.Cu")
		(net "M_K_BA<1>")
	)
	(segment
		(start 101.411278 -133.200648)
		(end 101.256338 -133.355588)
		(width 0.14224)
		(layer "In11.Cu")
		(net "M_K_BA<1>")
	)
	(segment
		(start 101.256338 -133.83387)
		(end 101.538786 -134.116318)
		(width 0.14224)
		(layer "In11.Cu")
		(net "M_K_BA<1>")
	)
	(segment
		(start 96.924368 -103.787956)
		(end 97.321116 -104.184704)
		(width 0.0889)
		(layer "In11.Cu")
		(net "M_K_BA<1>")
	)
	(segment
		(start 94.848172 -99.879404)
		(end 96.924368 -101.9556)
		(width 0.0889)
		(layer "In11.Cu")
		(net "M_K_BA<1>")
	)
	(segment
		(start 101.756464 -132.639308)
		(end 101.907848 -132.790692)
		(width 0.14224)
		(layer "In11.Cu")
		(net "M_K_BA<1>")
	)
	(segment
		(start 101.949504 -136.386824)
		(end 101.949758 -136.387078)
		(width 0.14224)
		(layer "In11.Cu")
		(net "M_K_BA<1>")
	)
	(segment
		(start 101.470968 -135.3058)
		(end 101.949504 -135.784336)
		(width 0.14224)
		(layer "In11.Cu")
		(net "M_K_BA<1>")
	)
	(segment
		(start 101.749352 -133.200648)
		(end 101.411278 -133.200648)
		(width 0.14224)
		(layer "In11.Cu")
		(net "M_K_BA<1>")
	)
	(segment
		(start 97.321116 -122.908314)
		(end 101.94925 -127.536448)
		(width 0.14224)
		(layer "In11.Cu")
		(net "M_K_BA<1>")
	)
	(segment
		(start 97.321116 -104.445816)
		(end 97.321116 -122.908314)
		(width 0.14224)
		(layer "In11.Cu")
		(net "M_K_BA<1>")
	)
	(segment
		(start 101.138736 -132.483606)
		(end 101.294438 -132.639308)
		(width 0.14224)
		(layer "In11.Cu")
		(net "M_K_BA<1>")
	)
	(segment
		(start 94.848172 -99.375214)
		(end 94.848172 -99.879404)
		(width 0.0889)
		(layer "In11.Cu")
		(net "M_K_BA<1>")
	)
	(segment
		(start 94.649798 -99.17684)
		(end 94.848172 -99.375214)
		(width 0.0889)
		(layer "In11.Cu")
		(net "M_K_BA<1>")
	)
	(segment
		(start 101.138736 -131.574032)
		(end 101.138736 -132.483606)
		(width 0.14224)
		(layer "In11.Cu")
		(net "M_K_BA<1>")
	)
	(segment
		(start 101.538786 -134.729982)
		(end 101.470968 -134.7978)
		(width 0.14224)
		(layer "In11.Cu")
		(net "M_K_BA<1>")
	)
	(segment
		(start 101.94925 -130.249168)
		(end 101.94925 -130.763518)
		(width 0.14224)
		(layer "In11.Cu")
		(net "M_K_BA<1>")
	)
	(segment
		(start 101.538786 -134.116318)
		(end 101.538786 -134.729982)
		(width 0.14224)
		(layer "In11.Cu")
		(net "M_K_BA<1>")
	)
	(segment
		(start 97.321116 -104.184704)
		(end 97.321116 -104.445816)
		(width 0.0889)
		(layer "In11.Cu")
		(net "M_K_BA<1>")
	)
	(segment
		(start 101.470968 -134.7978)
		(end 101.470968 -135.3058)
		(width 0.14224)
		(layer "In11.Cu")
		(net "M_K_BA<1>")
	)
	(segment
		(start 101.949504 -135.784336)
		(end 101.949504 -136.386824)
		(width 0.14224)
		(layer "In11.Cu")
		(net "M_K_BA<1>")
	)
	(segment
		(start 101.294438 -132.639308)
		(end 101.756464 -132.639308)
		(width 0.14224)
		(layer "In11.Cu")
		(net "M_K_BA<1>")
	)
	(segment
		(start 96.924368 -101.9556)
		(end 96.924368 -103.787956)
		(width 0.0889)
		(layer "In11.Cu")
		(net "M_K_BA<1>")
	)
	(segment
		(start 101.94925 -127.536448)
		(end 101.94925 -130.249168)
		(width 0.14224)
		(layer "In11.Cu")
		(net "M_K_BA<1>")
	)
	(segment
		(start 101.256338 -133.355588)
		(end 101.256338 -133.83387)
		(width 0.14224)
		(layer "In11.Cu")
		(net "M_K_BA<1>")
	)
	(segment
		(start 101.907848 -133.042152)
		(end 101.749352 -133.200648)
		(width 0.14224)
		(layer "In11.Cu")
		(net "M_K_BA<1>")
	)
	(segment
		(start 101.94925 -130.763518)
		(end 101.138736 -131.574032)
		(width 0.14224)
		(layer "In11.Cu")
		(net "M_K_BA<1>")
	)
	(segment
		(start 100.541836 -128.999996)
		(end 99.8601 -128.31826)
		(width 0.1651)
		(layer "F.Cu")
		(net "M_K_BA<0>")
	)
	(segment
		(start 102.799388 -134.371334)
		(end 102.799642 -134.371588)
		(width 0.1651)
		(layer "F.Cu")
		(net "M_K_BA<0>")
	)
	(segment
		(start 101.470968 -130.58394)
		(end 101.470968 -130.048)
		(width 0.1651)
		(layer "F.Cu")
		(net "M_K_BA<0>")
	)
	(segment
		(start 98.543618 -125.949202)
		(end 98.543618 -104.408224)
		(width 0.1651)
		(layer "F.Cu")
		(net "M_K_BA<0>")
	)
	(segment
		(start 98.543618 -103.95585)
		(end 96.938338 -102.35057)
		(width 0.0889)
		(layer "F.Cu")
		(net "M_K_BA<0>")
	)
	(segment
		(start 99.8601 -127.265684)
		(end 98.543618 -125.949202)
		(width 0.1651)
		(layer "F.Cu")
		(net "M_K_BA<0>")
	)
	(segment
		(start 101.789484 -130.902456)
		(end 101.470968 -130.58394)
		(width 0.1651)
		(layer "F.Cu")
		(net "M_K_BA<0>")
	)
	(segment
		(start 102.799388 -133.0706)
		(end 102.799388 -134.371334)
		(width 0.1651)
		(layer "F.Cu")
		(net "M_K_BA<0>")
	)
	(segment
		(start 101.470968 -130.048)
		(end 101.597968 -129.921)
		(width 0.1651)
		(layer "F.Cu")
		(net "M_K_BA<0>")
	)
	(segment
		(start 101.24694 -128.999996)
		(end 100.541836 -128.999996)
		(width 0.1651)
		(layer "F.Cu")
		(net "M_K_BA<0>")
	)
	(segment
		(start 96.938338 -102.35057)
		(end 96.938338 -101.15804)
		(width 0.0889)
		(layer "F.Cu")
		(net "M_K_BA<0>")
	)
	(segment
		(start 99.8601 -128.31826)
		(end 99.8601 -127.265684)
		(width 0.1651)
		(layer "F.Cu")
		(net "M_K_BA<0>")
	)
	(segment
		(start 101.597968 -129.921)
		(end 101.597968 -129.351024)
		(width 0.1651)
		(layer "F.Cu")
		(net "M_K_BA<0>")
	)
	(segment
		(start 102.799388 -130.902456)
		(end 101.789484 -130.902456)
		(width 0.1651)
		(layer "F.Cu")
		(net "M_K_BA<0>")
	)
	(segment
		(start 101.597968 -129.351024)
		(end 101.24694 -128.999996)
		(width 0.1651)
		(layer "F.Cu")
		(net "M_K_BA<0>")
	)
	(segment
		(start 98.543618 -104.408224)
		(end 98.543618 -103.95585)
		(width 0.0889)
		(layer "F.Cu")
		(net "M_K_BA<0>")
	)
	(via
		(at 102.799388 -130.902456)
		(size 0.508)
		(drill 0.254)
		(layers "F.Cu" "B.Cu")
		(net "M_K_BA<0>")
	)
	(via
		(at 102.799642 -134.371588)
		(size 0.4572)
		(drill 0.2032)
		(layers "F.Cu" "B.Cu")
		(net "M_K_BA<0>")
	)
	(segment
		(start 102.799388 -132.876036)
		(end 102.799388 -130.902456)
		(width 0.1651)
		(layer "B.Cu")
		(net "M_K_BA<0>")
	)
	(segment
		(start 102.799388 -134.371334)
		(end 102.799642 -134.371588)
		(width 0.14224)
		(layer "In9.Cu")
		(net "M_K_BA<0>")
	)
	(segment
		(start 102.799388 -130.902456)
		(end 102.799388 -134.371334)
		(width 0.14224)
		(layer "In9.Cu")
		(net "M_K_BA<0>")
	)
	(segment
		(start 87.494872 -100.662486)
		(end 86.8426 -100.662486)
		(width 0.1651)
		(layer "F.Cu")
		(net "M_K_ALERT_N")
	)
	(segment
		(start 83.249516 -136.387078)
		(end 83.249516 -137.67054)
		(width 0.1651)
		(layer "F.Cu")
		(net "M_K_ALERT_N")
	)
	(segment
		(start 86.8426 -100.662486)
		(end 86.840568 -100.660454)
		(width 0.1651)
		(layer "F.Cu")
		(net "M_K_ALERT_N")
	)
	(via
		(at 83.249516 -130.249168)
		(size 0.508)
		(drill 0.254)
		(layers "F.Cu" "B.Cu")
		(net "M_K_ALERT_N")
	)
	(via
		(at 83.249516 -136.387078)
		(size 0.4572)
		(drill 0.2032)
		(layers "F.Cu" "B.Cu")
		(net "M_K_ALERT_N")
	)
	(via
		(at 86.840568 -100.660454)
		(size 0.508)
		(drill 0.254)
		(layers "F.Cu" "B.Cu")
		(net "M_K_ALERT_N")
	)
	(segment
		(start 83.249516 -128.276096)
		(end 83.249516 -130.249168)
		(width 0.1651)
		(layer "B.Cu")
		(net "M_K_ALERT_N")
	)
	(segment
		(start 84.046568 -127.9652)
		(end 83.080098 -128.93167)
		(width 0.14224)
		(layer "In11.Cu")
		(net "M_K_ALERT_N")
	)
	(segment
		(start 83.249516 -135.733536)
		(end 83.249516 -136.387078)
		(width 0.14224)
		(layer "In11.Cu")
		(net "M_K_ALERT_N")
	)
	(segment
		(start 83.080098 -128.93167)
		(end 83.081368 -128.934718)
		(width 0.14224)
		(layer "In11.Cu")
		(net "M_K_ALERT_N")
	)
	(segment
		(start 83.081368 -128.934718)
		(end 83.081368 -130.08102)
		(width 0.14224)
		(layer "In11.Cu")
		(net "M_K_ALERT_N")
	)
	(segment
		(start 87.465916 -120.801892)
		(end 84.046568 -124.22124)
		(width 0.14224)
		(layer "In11.Cu")
		(net "M_K_ALERT_N")
	)
	(segment
		(start 83.081368 -130.08102)
		(end 83.249516 -130.249168)
		(width 0.14224)
		(layer "In11.Cu")
		(net "M_K_ALERT_N")
	)
	(segment
		(start 83.249516 -130.819652)
		(end 82.725768 -131.3434)
		(width 0.14224)
		(layer "In11.Cu")
		(net "M_K_ALERT_N")
	)
	(segment
		(start 82.816192 -131.941824)
		(end 82.816192 -135.300212)
		(width 0.14224)
		(layer "In11.Cu")
		(net "M_K_ALERT_N")
	)
	(segment
		(start 82.725768 -131.3434)
		(end 82.725768 -131.8514)
		(width 0.14224)
		(layer "In11.Cu")
		(net "M_K_ALERT_N")
	)
	(segment
		(start 83.249516 -130.249168)
		(end 83.249516 -130.819652)
		(width 0.14224)
		(layer "In11.Cu")
		(net "M_K_ALERT_N")
	)
	(segment
		(start 84.046568 -124.22124)
		(end 84.046568 -127.9652)
		(width 0.14224)
		(layer "In11.Cu")
		(net "M_K_ALERT_N")
	)
	(segment
		(start 87.465916 -101.285802)
		(end 87.465916 -120.801892)
		(width 0.14224)
		(layer "In11.Cu")
		(net "M_K_ALERT_N")
	)
	(segment
		(start 82.816192 -135.300212)
		(end 83.249516 -135.733536)
		(width 0.14224)
		(layer "In11.Cu")
		(net "M_K_ALERT_N")
	)
	(segment
		(start 82.725768 -131.8514)
		(end 82.816192 -131.941824)
		(width 0.14224)
		(layer "In11.Cu")
		(net "M_K_ALERT_N")
	)
	(segment
		(start 86.840568 -100.660454)
		(end 87.465916 -101.285802)
		(width 0.14224)
		(layer "In11.Cu")
		(net "M_K_ALERT_N")
	)
	(segment
		(start 88.791796 -102.789228)
		(end 88.791796 -103.15702)
		(width 0.0889)
		(layer "F.Cu")
		(net "M_K_ACT_N")
	)
	(segment
		(start 84.28482 -119.295164)
		(end 84.28482 -127.803148)
		(width 0.1651)
		(layer "F.Cu")
		(net "M_K_ACT_N")
	)
	(segment
		(start 88.791796 -103.15702)
		(end 88.791796 -114.788188)
		(width 0.1651)
		(layer "F.Cu")
		(net "M_K_ACT_N")
	)
	(segment
		(start 81.549494 -131.07035)
		(end 81.549494 -131.611878)
		(width 0.1651)
		(layer "F.Cu")
		(net "M_K_ACT_N")
	)
	(segment
		(start 84.28482 -127.803148)
		(end 82.992468 -129.0955)
		(width 0.1651)
		(layer "F.Cu")
		(net "M_K_ACT_N")
	)
	(segment
		(start 82.992468 -129.627376)
		(end 81.549494 -131.07035)
		(width 0.1651)
		(layer "F.Cu")
		(net "M_K_ACT_N")
	)
	(segment
		(start 88.542368 -102.5398)
		(end 88.791796 -102.789228)
		(width 0.0889)
		(layer "F.Cu")
		(net "M_K_ACT_N")
	)
	(segment
		(start 82.992468 -129.0955)
		(end 82.992468 -129.627376)
		(width 0.1651)
		(layer "F.Cu")
		(net "M_K_ACT_N")
	)
	(segment
		(start 88.542368 -101.944932)
		(end 88.542368 -102.5398)
		(width 0.0889)
		(layer "F.Cu")
		(net "M_K_ACT_N")
	)
	(segment
		(start 81.549494 -133.0706)
		(end 81.549494 -134.369556)
		(width 0.1651)
		(layer "F.Cu")
		(net "M_K_ACT_N")
	)
	(segment
		(start 88.791796 -114.788188)
		(end 84.28482 -119.295164)
		(width 0.1651)
		(layer "F.Cu")
		(net "M_K_ACT_N")
	)
	(via
		(at 81.549494 -134.369556)
		(size 0.4572)
		(drill 0.2032)
		(layers "F.Cu" "B.Cu")
		(net "M_K_ACT_N")
	)
	(via
		(at 81.549494 -131.611878)
		(size 0.508)
		(drill 0.254)
		(layers "F.Cu" "B.Cu")
		(net "M_K_ACT_N")
	)
	(arc
		(start 90.070178 -98.18624)
		(mid 89.674121 -98.847791)
		(end 89.607898 -99.616006)
		(width 0.0889)
		(layer "F.Cu")
		(net "M_K_ACT_N")
	)
	(arc
		(start 89.607898 -99.616006)
		(mid 89.604565 -99.748164)
		(end 89.558368 -99.872038)
		(width 0.0889)
		(layer "F.Cu")
		(net "M_K_ACT_N")
	)
	(arc
		(start 88.746584 -101.082856)
		(mid 88.748845 -101.219684)
		(end 88.704928 -101.349302)
		(width 0.0889)
		(layer "F.Cu")
		(net "M_K_ACT_N")
	)
	(arc
		(start 89.057734 -100.248212)
		(mid 88.785525 -100.62205)
		(end 88.746584 -101.082856)
		(width 0.0889)
		(layer "F.Cu")
		(net "M_K_ACT_N")
	)
	(arc
		(start 89.558368 -99.872038)
		(mid 89.346463 -100.111237)
		(end 89.057734 -100.248212)
		(width 0.0889)
		(layer "F.Cu")
		(net "M_K_ACT_N")
	)
	(arc
		(start 88.699848 -101.35743)
		(mid 88.582383 -101.640804)
		(end 88.542368 -101.944932)
		(width 0.0889)
		(layer "F.Cu")
		(net "M_K_ACT_N")
	)
	(arc
		(start 88.704928 -101.349302)
		(mid 88.702314 -101.35332)
		(end 88.699848 -101.35743)
		(width 0.0889)
		(layer "F.Cu")
		(net "M_K_ACT_N")
	)
	(segment
		(start 81.549494 -132.876036)
		(end 81.549494 -131.611878)
		(width 0.1651)
		(layer "B.Cu")
		(net "M_K_ACT_N")
	)
	(segment
		(start 81.549494 -131.611878)
		(end 81.549494 -134.369556)
		(width 0.14224)
		(layer "In9.Cu")
		(net "M_K_ACT_N")
	)
	(segment
		(start 78.14945 -154.111452)
		(end 78.271878 -154.23388)
		(width 0.10795)
		(layer "F.Cu")
		(net "M_KLM_RST_N")
	)
	(segment
		(start 78.14945 -142.6718)
		(end 78.14945 -143.874236)
		(width 0.10795)
		(layer "F.Cu")
		(net "M_KLM_RST_N")
	)
	(segment
		(start 78.14945 -143.874236)
		(end 78.227936 -143.952722)
		(width 0.10795)
		(layer "F.Cu")
		(net "M_KLM_RST_N")
	)
	(segment
		(start 78.14945 -152.273)
		(end 78.14945 -154.111452)
		(width 0.10795)
		(layer "F.Cu")
		(net "M_KLM_RST_N")
	)
	(segment
		(start 78.14945 -134.19836)
		(end 78.282292 -134.331202)
		(width 0.10795)
		(layer "F.Cu")
		(net "M_KLM_RST_N")
	)
	(segment
		(start 87.494872 -97.690686)
		(end 86.923372 -97.690686)
		(width 0.1016)
		(layer "F.Cu")
		(net "M_KLM_RST_N")
	)
	(segment
		(start 78.14945 -133.0706)
		(end 78.14945 -134.19836)
		(width 0.10795)
		(layer "F.Cu")
		(net "M_KLM_RST_N")
	)
	(via
		(at 78.14945 -131.586478)
		(size 0.508)
		(drill 0.254)
		(layers "F.Cu" "B.Cu")
		(net "M_KLM_RST_N")
	)
	(via
		(at 78.271878 -154.23388)
		(size 0.508)
		(drill 0.254)
		(layers "F.Cu" "B.Cu")
		(net "M_KLM_RST_N")
	)
	(via
		(at 78.14945 -150.788878)
		(size 0.4572)
		(drill 0.2032)
		(layers "F.Cu" "B.Cu")
		(net "M_KLM_RST_N")
	)
	(via
		(at 78.227936 -143.952722)
		(size 0.4572)
		(drill 0.2032)
		(layers "F.Cu" "B.Cu")
		(net "M_KLM_RST_N")
	)
	(via
		(at 78.14945 -141.187678)
		(size 0.4572)
		(drill 0.2032)
		(layers "F.Cu" "B.Cu")
		(net "M_KLM_RST_N")
	)
	(via
		(at 78.282292 -134.331202)
		(size 0.4572)
		(drill 0.2032)
		(layers "F.Cu" "B.Cu")
		(net "M_KLM_RST_N")
	)
	(via
		(at 86.923372 -97.690686)
		(size 0.508)
		(drill 0.254)
		(layers "F.Cu" "B.Cu")
		(net "M_KLM_RST_N")
	)
	(segment
		(start 78.14945 -142.477236)
		(end 78.14945 -141.187678)
		(width 0.10795)
		(layer "B.Cu")
		(net "M_KLM_RST_N")
	)
	(segment
		(start 78.14945 -152.078436)
		(end 78.14945 -150.788878)
		(width 0.10795)
		(layer "B.Cu")
		(net "M_KLM_RST_N")
	)
	(segment
		(start 78.14945 -132.876036)
		(end 78.14945 -131.586478)
		(width 0.10795)
		(layer "B.Cu")
		(net "M_KLM_RST_N")
	)
	(segment
		(start 78.458568 -130.7846)
		(end 78.458568 -131.27736)
		(width 0.089408)
		(layer "In11.Cu")
		(net "M_KLM_RST_N")
	)
	(segment
		(start 78.282292 -134.331202)
		(end 78.632812 -134.681722)
		(width 0.089408)
		(layer "In11.Cu")
		(net "M_KLM_RST_N")
	)
	(segment
		(start 86.830662 -99.08159)
		(end 86.159086 -99.753166)
		(width 0.0889)
		(layer "In11.Cu")
		(net "M_KLM_RST_N")
	)
	(segment
		(start 86.159086 -99.753166)
		(end 86.159086 -101.218492)
		(width 0.089408)
		(layer "In11.Cu")
		(net "M_KLM_RST_N")
	)
	(segment
		(start 86.159086 -101.218492)
		(end 86.230968 -101.290374)
		(width 0.089408)
		(layer "In11.Cu")
		(net "M_KLM_RST_N")
	)
	(segment
		(start 78.632812 -135.955024)
		(end 78.560168 -136.027668)
		(width 0.089408)
		(layer "In11.Cu")
		(net "M_KLM_RST_N")
	)
	(segment
		(start 79.601568 -129.6162)
		(end 79.017368 -130.2004)
		(width 0.089408)
		(layer "In11.Cu")
		(net "M_KLM_RST_N")
	)
	(segment
		(start 78.227936 -143.952722)
		(end 78.663038 -144.387824)
		(width 0.089408)
		(layer "In11.Cu")
		(net "M_KLM_RST_N")
	)
	(segment
		(start 86.928198 -99.08159)
		(end 86.830662 -99.08159)
		(width 0.0889)
		(layer "In11.Cu")
		(net "M_KLM_RST_N")
	)
	(segment
		(start 78.670404 -140.666724)
		(end 78.14945 -141.187678)
		(width 0.089408)
		(layer "In11.Cu")
		(net "M_KLM_RST_N")
	)
	(segment
		(start 86.923372 -97.690686)
		(end 87.25281 -98.45167)
		(width 0.0889)
		(layer "In11.Cu")
		(net "M_KLM_RST_N")
	)
	(segment
		(start 79.017368 -130.2258)
		(end 78.458568 -130.7846)
		(width 0.089408)
		(layer "In11.Cu")
		(net "M_KLM_RST_N")
	)
	(segment
		(start 78.585568 -149.0726)
		(end 78.655418 -149.14245)
		(width 0.089408)
		(layer "In11.Cu")
		(net "M_KLM_RST_N")
	)
	(segment
		(start 78.14945 -141.187678)
		(end 78.585568 -141.623796)
		(width 0.089408)
		(layer "In11.Cu")
		(net "M_KLM_RST_N")
	)
	(segment
		(start 86.129368 -120.381776)
		(end 79.601568 -126.909576)
		(width 0.089408)
		(layer "In11.Cu")
		(net "M_KLM_RST_N")
	)
	(segment
		(start 78.655418 -150.28291)
		(end 78.14945 -150.788878)
		(width 0.089408)
		(layer "In11.Cu")
		(net "M_KLM_RST_N")
	)
	(segment
		(start 78.585568 -153.92019)
		(end 78.271878 -154.23388)
		(width 0.089408)
		(layer "In11.Cu")
		(net "M_KLM_RST_N")
	)
	(segment
		(start 78.14945 -131.586478)
		(end 78.585568 -132.022596)
		(width 0.089408)
		(layer "In11.Cu")
		(net "M_KLM_RST_N")
	)
	(segment
		(start 78.585568 -143.59509)
		(end 78.227936 -143.952722)
		(width 0.089408)
		(layer "In11.Cu")
		(net "M_KLM_RST_N")
	)
	(segment
		(start 78.585568 -134.027926)
		(end 78.282292 -134.331202)
		(width 0.089408)
		(layer "In11.Cu")
		(net "M_KLM_RST_N")
	)
	(segment
		(start 78.585568 -151.224996)
		(end 78.585568 -153.92019)
		(width 0.089408)
		(layer "In11.Cu")
		(net "M_KLM_RST_N")
	)
	(segment
		(start 78.663038 -145.743676)
		(end 78.585568 -145.821146)
		(width 0.089408)
		(layer "In11.Cu")
		(net "M_KLM_RST_N")
	)
	(segment
		(start 78.560168 -136.027668)
		(end 78.560168 -139.5476)
		(width 0.089408)
		(layer "In11.Cu")
		(net "M_KLM_RST_N")
	)
	(segment
		(start 78.458568 -131.27736)
		(end 78.14945 -131.586478)
		(width 0.089408)
		(layer "In11.Cu")
		(net "M_KLM_RST_N")
	)
	(segment
		(start 78.655418 -149.14245)
		(end 78.655418 -150.28291)
		(width 0.089408)
		(layer "In11.Cu")
		(net "M_KLM_RST_N")
	)
	(segment
		(start 86.230968 -101.290374)
		(end 86.230968 -106.400854)
		(width 0.089408)
		(layer "In11.Cu")
		(net "M_KLM_RST_N")
	)
	(segment
		(start 78.670404 -139.657836)
		(end 78.670404 -140.666724)
		(width 0.089408)
		(layer "In11.Cu")
		(net "M_KLM_RST_N")
	)
	(segment
		(start 78.14945 -150.788878)
		(end 78.585568 -151.224996)
		(width 0.089408)
		(layer "In11.Cu")
		(net "M_KLM_RST_N")
	)
	(segment
		(start 78.585568 -145.821146)
		(end 78.585568 -149.0726)
		(width 0.089408)
		(layer "In11.Cu")
		(net "M_KLM_RST_N")
	)
	(segment
		(start 79.601568 -126.909576)
		(end 79.601568 -129.6162)
		(width 0.089408)
		(layer "In11.Cu")
		(net "M_KLM_RST_N")
	)
	(segment
		(start 78.585568 -141.623796)
		(end 78.585568 -143.59509)
		(width 0.089408)
		(layer "In11.Cu")
		(net "M_KLM_RST_N")
	)
	(segment
		(start 78.560168 -139.5476)
		(end 78.670404 -139.657836)
		(width 0.089408)
		(layer "In11.Cu")
		(net "M_KLM_RST_N")
	)
	(segment
		(start 86.230968 -106.400854)
		(end 86.129368 -106.502454)
		(width 0.089408)
		(layer "In11.Cu")
		(net "M_KLM_RST_N")
	)
	(segment
		(start 79.017368 -130.2004)
		(end 79.017368 -130.2258)
		(width 0.089408)
		(layer "In11.Cu")
		(net "M_KLM_RST_N")
	)
	(segment
		(start 86.129368 -106.502454)
		(end 86.129368 -120.381776)
		(width 0.089408)
		(layer "In11.Cu")
		(net "M_KLM_RST_N")
	)
	(segment
		(start 78.632812 -134.681722)
		(end 78.632812 -135.955024)
		(width 0.089408)
		(layer "In11.Cu")
		(net "M_KLM_RST_N")
	)
	(segment
		(start 78.663038 -144.387824)
		(end 78.663038 -145.743676)
		(width 0.089408)
		(layer "In11.Cu")
		(net "M_KLM_RST_N")
	)
	(segment
		(start 87.25281 -98.45167)
		(end 87.274908 -98.490024)
		(width 0.0889)
		(layer "In11.Cu")
		(net "M_KLM_RST_N")
	)
	(segment
		(start 78.585568 -132.022596)
		(end 78.585568 -134.027926)
		(width 0.089408)
		(layer "In11.Cu")
		(net "M_KLM_RST_N")
	)
	(arc
		(start 87.274908 -98.490024)
		(mid 87.26862 -98.883679)
		(end 86.928198 -99.08159)
		(width 0.0889)
		(layer "In11.Cu")
		(net "M_KLM_RST_N")
	)
	(segment
		(start 89.211912 -85.803486)
		(end 88.640412 -85.803486)
		(width 0.1016)
		(layer "F.Cu")
		(net "M_K_CPU_VREF")
	)
	(via
		(at 64.05118 -85.81644)
		(size 0.6604)
		(drill 0.3302)
		(layers "F.Cu" "B.Cu")
		(net "M_K_CPU_VREF")
	)
	(via
		(at 88.640412 -85.803486)
		(size 0.508)
		(drill 0.254)
		(layers "F.Cu" "B.Cu")
		(net "M_K_CPU_VREF")
	)
	(via
		(at 45.922946 -102.628446)
		(size 0.508)
		(drill 0.254)
		(layers "F.Cu" "B.Cu")
		(net "M_K_CPU_VREF")
	)
	(via
		(at 27.023568 -133.962902)
		(size 0.508)
		(drill 0.254)
		(layers "F.Cu" "B.Cu")
		(net "M_K_CPU_VREF")
	)
	(segment
		(start 72.14108 -83.887564)
		(end 71.685912 -84.342732)
		(width 0.1524)
		(layer "B.Cu")
		(net "M_K_CPU_VREF")
	)
	(segment
		(start 79.871062 -84.252562)
		(end 79.4131 -83.7946)
		(width 0.1524)
		(layer "B.Cu")
		(net "M_K_CPU_VREF")
	)
	(segment
		(start 70.799452 -83.887564)
		(end 70.296532 -83.887564)
		(width 0.1524)
		(layer "B.Cu")
		(net "M_K_CPU_VREF")
	)
	(segment
		(start 82.840322 -83.7819)
		(end 82.476848 -83.7819)
		(width 0.1524)
		(layer "B.Cu")
		(net "M_K_CPU_VREF")
	)
	(segment
		(start 81.593944 -83.39201)
		(end 81.204054 -83.7819)
		(width 0.1524)
		(layer "B.Cu")
		(net "M_K_CPU_VREF")
	)
	(segment
		(start 80.237838 -84.252562)
		(end 79.871062 -84.252562)
		(width 0.1524)
		(layer "B.Cu")
		(net "M_K_CPU_VREF")
	)
	(segment
		(start 68.68414 -83.8454)
		(end 68.276978 -84.252562)
		(width 0.1524)
		(layer "B.Cu")
		(net "M_K_CPU_VREF")
	)
	(segment
		(start 68.276978 -84.252562)
		(end 67.750182 -84.252562)
		(width 0.1524)
		(layer "B.Cu")
		(net "M_K_CPU_VREF")
	)
	(segment
		(start 71.685912 -84.342732)
		(end 71.25462 -84.342732)
		(width 0.1524)
		(layer "B.Cu")
		(net "M_K_CPU_VREF")
	)
	(segment
		(start 76.312522 -84.252562)
		(end 75.947524 -83.887564)
		(width 0.1524)
		(layer "B.Cu")
		(net "M_K_CPU_VREF")
	)
	(segment
		(start 75.947524 -83.887564)
		(end 75.584558 -83.887564)
		(width 0.1524)
		(layer "B.Cu")
		(net "M_K_CPU_VREF")
	)
	(segment
		(start 65.99428 -83.87334)
		(end 64.05118 -85.81644)
		(width 0.254)
		(layer "B.Cu")
		(net "M_K_CPU_VREF")
	)
	(segment
		(start 86.61273 -84.38261)
		(end 86.247224 -84.748116)
		(width 0.1524)
		(layer "B.Cu")
		(net "M_K_CPU_VREF")
	)
	(segment
		(start 71.25462 -84.342732)
		(end 70.799452 -83.887564)
		(width 0.1524)
		(layer "B.Cu")
		(net "M_K_CPU_VREF")
	)
	(segment
		(start 69.050662 -83.8454)
		(end 68.68414 -83.8454)
		(width 0.1524)
		(layer "B.Cu")
		(net "M_K_CPU_VREF")
	)
	(segment
		(start 70.296532 -83.887564)
		(end 69.931534 -84.252562)
		(width 0.1524)
		(layer "B.Cu")
		(net "M_K_CPU_VREF")
	)
	(segment
		(start 61.129926 -90.794332)
		(end 49.295812 -102.628446)
		(width 0.254)
		(layer "B.Cu")
		(net "M_K_CPU_VREF")
	)
	(segment
		(start 73.867518 -83.887564)
		(end 73.41235 -84.342732)
		(width 0.1524)
		(layer "B.Cu")
		(net "M_K_CPU_VREF")
	)
	(segment
		(start 69.457824 -84.252562)
		(end 69.050662 -83.8454)
		(width 0.1524)
		(layer "B.Cu")
		(net "M_K_CPU_VREF")
	)
	(segment
		(start 76.836778 -84.252562)
		(end 76.312522 -84.252562)
		(width 0.1524)
		(layer "B.Cu")
		(net "M_K_CPU_VREF")
	)
	(segment
		(start 74.233532 -83.887564)
		(end 73.867518 -83.887564)
		(width 0.1524)
		(layer "B.Cu")
		(net "M_K_CPU_VREF")
	)
	(segment
		(start 84.169504 -83.887564)
		(end 83.804506 -84.252562)
		(width 0.1524)
		(layer "B.Cu")
		(net "M_K_CPU_VREF")
	)
	(segment
		(start 87.5538 -84.76234)
		(end 87.17407 -84.38261)
		(width 0.1524)
		(layer "B.Cu")
		(net "M_K_CPU_VREF")
	)
	(segment
		(start 67.37096 -83.87334)
		(end 65.99428 -83.87334)
		(width 0.1524)
		(layer "B.Cu")
		(net "M_K_CPU_VREF")
	)
	(segment
		(start 85.35416 -84.29498)
		(end 85.004656 -84.29498)
		(width 0.1524)
		(layer "B.Cu")
		(net "M_K_CPU_VREF")
	)
	(segment
		(start 85.004656 -84.29498)
		(end 84.59724 -83.887564)
		(width 0.1524)
		(layer "B.Cu")
		(net "M_K_CPU_VREF")
	)
	(segment
		(start 83.804506 -84.252562)
		(end 83.310984 -84.252562)
		(width 0.1524)
		(layer "B.Cu")
		(net "M_K_CPU_VREF")
	)
	(segment
		(start 78.98384 -83.7946)
		(end 78.525878 -84.252562)
		(width 0.1524)
		(layer "B.Cu")
		(net "M_K_CPU_VREF")
	)
	(segment
		(start 69.931534 -84.252562)
		(end 69.457824 -84.252562)
		(width 0.1524)
		(layer "B.Cu")
		(net "M_K_CPU_VREF")
	)
	(segment
		(start 82.476848 -83.7819)
		(end 82.086958 -83.39201)
		(width 0.1524)
		(layer "B.Cu")
		(net "M_K_CPU_VREF")
	)
	(segment
		(start 87.17407 -84.38261)
		(end 86.61273 -84.38261)
		(width 0.1524)
		(layer "B.Cu")
		(net "M_K_CPU_VREF")
	)
	(segment
		(start 88.640412 -85.558376)
		(end 87.844376 -84.76234)
		(width 0.1524)
		(layer "B.Cu")
		(net "M_K_CPU_VREF")
	)
	(segment
		(start 27.912568 -134.874)
		(end 27.023568 -134.874)
		(width 0.254)
		(layer "B.Cu")
		(net "M_K_CPU_VREF")
	)
	(segment
		(start 77.658214 -83.887564)
		(end 77.201776 -83.887564)
		(width 0.1524)
		(layer "B.Cu")
		(net "M_K_CPU_VREF")
	)
	(segment
		(start 62.9412 -85.81644)
		(end 61.129926 -87.627714)
		(width 0.254)
		(layer "B.Cu")
		(net "M_K_CPU_VREF")
	)
	(segment
		(start 78.023212 -84.252562)
		(end 77.658214 -83.887564)
		(width 0.1524)
		(layer "B.Cu")
		(net "M_K_CPU_VREF")
	)
	(segment
		(start 86.247224 -84.748116)
		(end 85.807296 -84.748116)
		(width 0.1524)
		(layer "B.Cu")
		(net "M_K_CPU_VREF")
	)
	(segment
		(start 79.4131 -83.7946)
		(end 78.98384 -83.7946)
		(width 0.1524)
		(layer "B.Cu")
		(net "M_K_CPU_VREF")
	)
	(segment
		(start 61.129926 -87.627714)
		(end 61.129926 -90.794332)
		(width 0.254)
		(layer "B.Cu")
		(net "M_K_CPU_VREF")
	)
	(segment
		(start 88.640412 -85.803486)
		(end 88.640412 -85.558376)
		(width 0.1524)
		(layer "B.Cu")
		(net "M_K_CPU_VREF")
	)
	(segment
		(start 73.41235 -84.342732)
		(end 72.97166 -84.342732)
		(width 0.1524)
		(layer "B.Cu")
		(net "M_K_CPU_VREF")
	)
	(segment
		(start 75.584558 -83.887564)
		(end 75.12939 -84.342732)
		(width 0.1524)
		(layer "B.Cu")
		(net "M_K_CPU_VREF")
	)
	(segment
		(start 67.750182 -84.252562)
		(end 67.37096 -83.87334)
		(width 0.1524)
		(layer "B.Cu")
		(net "M_K_CPU_VREF")
	)
	(segment
		(start 84.59724 -83.887564)
		(end 84.169504 -83.887564)
		(width 0.1524)
		(layer "B.Cu")
		(net "M_K_CPU_VREF")
	)
	(segment
		(start 78.525878 -84.252562)
		(end 78.023212 -84.252562)
		(width 0.1524)
		(layer "B.Cu")
		(net "M_K_CPU_VREF")
	)
	(segment
		(start 80.7085 -83.7819)
		(end 80.237838 -84.252562)
		(width 0.1524)
		(layer "B.Cu")
		(net "M_K_CPU_VREF")
	)
	(segment
		(start 74.6887 -84.342732)
		(end 74.233532 -83.887564)
		(width 0.1524)
		(layer "B.Cu")
		(net "M_K_CPU_VREF")
	)
	(segment
		(start 77.201776 -83.887564)
		(end 76.836778 -84.252562)
		(width 0.1524)
		(layer "B.Cu")
		(net "M_K_CPU_VREF")
	)
	(segment
		(start 72.516492 -83.887564)
		(end 72.14108 -83.887564)
		(width 0.1524)
		(layer "B.Cu")
		(net "M_K_CPU_VREF")
	)
	(segment
		(start 49.295812 -102.628446)
		(end 45.922946 -102.628446)
		(width 0.254)
		(layer "B.Cu")
		(net "M_K_CPU_VREF")
	)
	(segment
		(start 64.05118 -85.81644)
		(end 62.9412 -85.81644)
		(width 0.254)
		(layer "B.Cu")
		(net "M_K_CPU_VREF")
	)
	(segment
		(start 75.12939 -84.342732)
		(end 74.6887 -84.342732)
		(width 0.1524)
		(layer "B.Cu")
		(net "M_K_CPU_VREF")
	)
	(segment
		(start 85.807296 -84.748116)
		(end 85.35416 -84.29498)
		(width 0.1524)
		(layer "B.Cu")
		(net "M_K_CPU_VREF")
	)
	(segment
		(start 27.023568 -134.874)
		(end 27.023568 -133.962902)
		(width 0.254)
		(layer "B.Cu")
		(net "M_K_CPU_VREF")
	)
	(segment
		(start 81.204054 -83.7819)
		(end 80.7085 -83.7819)
		(width 0.1524)
		(layer "B.Cu")
		(net "M_K_CPU_VREF")
	)
	(segment
		(start 83.310984 -84.252562)
		(end 82.840322 -83.7819)
		(width 0.1524)
		(layer "B.Cu")
		(net "M_K_CPU_VREF")
	)
	(segment
		(start 82.086958 -83.39201)
		(end 81.593944 -83.39201)
		(width 0.1524)
		(layer "B.Cu")
		(net "M_K_CPU_VREF")
	)
	(segment
		(start 87.844376 -84.76234)
		(end 87.5538 -84.76234)
		(width 0.1524)
		(layer "B.Cu")
		(net "M_K_CPU_VREF")
	)
	(segment
		(start 72.97166 -84.342732)
		(end 72.516492 -83.887564)
		(width 0.1524)
		(layer "B.Cu")
		(net "M_K_CPU_VREF")
	)
	(segment
		(start 37.51326 -108.5596)
		(end 39.34714 -106.72572)
		(width 0.254)
		(layer "In2.Cu")
		(net "M_K_CPU_VREF")
	)
	(segment
		(start 36.198556 -108.5596)
		(end 37.51326 -108.5596)
		(width 0.254)
		(layer "In2.Cu")
		(net "M_K_CPU_VREF")
	)
	(segment
		(start 27.651456 -128.605026)
		(end 29.589222 -126.66726)
		(width 0.254)
		(layer "In2.Cu")
		(net "M_K_CPU_VREF")
	)
	(segment
		(start 29.589222 -115.168934)
		(end 36.198556 -108.5596)
		(width 0.254)
		(layer "In2.Cu")
		(net "M_K_CPU_VREF")
	)
	(segment
		(start 39.34714 -104.79024)
		(end 43.09872 -101.03866)
		(width 0.254)
		(layer "In2.Cu")
		(net "M_K_CPU_VREF")
	)
	(segment
		(start 43.09872 -101.03866)
		(end 45.15866 -101.03866)
		(width 0.254)
		(layer "In2.Cu")
		(net "M_K_CPU_VREF")
	)
	(segment
		(start 27.651456 -131.926076)
		(end 27.651456 -128.605026)
		(width 0.254)
		(layer "In2.Cu")
		(net "M_K_CPU_VREF")
	)
	(segment
		(start 39.34714 -106.72572)
		(end 39.34714 -104.79024)
		(width 0.254)
		(layer "In2.Cu")
		(net "M_K_CPU_VREF")
	)
	(segment
		(start 45.922946 -101.802946)
		(end 45.922946 -102.628446)
		(width 0.254)
		(layer "In2.Cu")
		(net "M_K_CPU_VREF")
	)
	(segment
		(start 27.023568 -133.962902)
		(end 27.023568 -132.553964)
		(width 0.254)
		(layer "In2.Cu")
		(net "M_K_CPU_VREF")
	)
	(segment
		(start 27.023568 -132.553964)
		(end 27.651456 -131.926076)
		(width 0.254)
		(layer "In2.Cu")
		(net "M_K_CPU_VREF")
	)
	(segment
		(start 45.15866 -101.03866)
		(end 45.922946 -101.802946)
		(width 0.254)
		(layer "In2.Cu")
		(net "M_K_CPU_VREF")
	)
	(segment
		(start 29.589222 -126.66726)
		(end 29.589222 -115.168934)
		(width 0.254)
		(layer "In2.Cu")
		(net "M_K_CPU_VREF")
	)
	(segment
		(start 96.079818 -58.06694)
		(end 95.508318 -58.06694)
		(width 0.1651)
		(layer "F.Cu")
		(net "M_J_PAR")
	)
	(segment
		(start 100.249482 -0.821182)
		(end 100.249482 0.5588)
		(width 0.1651)
		(layer "F.Cu")
		(net "M_J_PAR")
	)
	(via
		(at 100.249228 -2.995168)
		(size 0.508)
		(drill 0.254)
		(layers "F.Cu" "B.Cu")
		(net "M_J_PAR")
	)
	(via
		(at 95.508318 -58.06694)
		(size 0.508)
		(drill 0.254)
		(layers "F.Cu" "B.Cu")
		(net "M_J_PAR")
	)
	(via
		(at 100.249482 0.5588)
		(size 0.508)
		(drill 0.254)
		(layers "F.Cu" "B.Cu")
		(net "M_J_PAR")
	)
	(segment
		(start 100.249482 -2.994914)
		(end 100.249228 -2.995168)
		(width 0.1651)
		(layer "B.Cu")
		(net "M_J_PAR")
	)
	(segment
		(start 100.249482 -1.021842)
		(end 100.249482 -2.994914)
		(width 0.1651)
		(layer "B.Cu")
		(net "M_J_PAR")
	)
	(segment
		(start 100.249482 0.5588)
		(end 100.249482 0.289814)
		(width 0.14224)
		(layer "In2.Cu")
		(net "M_J_PAR")
	)
	(segment
		(start 95.838264 -57.305194)
		(end 95.508318 -58.06694)
		(width 0.0889)
		(layer "In2.Cu")
		(net "M_J_PAR")
	)
	(segment
		(start 100.249228 -3.40614)
		(end 99.743768 -3.9116)
		(width 0.14224)
		(layer "In2.Cu")
		(net "M_J_PAR")
	)
	(segment
		(start 95.855028 -55.885588)
		(end 95.859854 -55.894224)
		(width 0.0889)
		(layer "In2.Cu")
		(net "M_J_PAR")
	)
	(segment
		(start 96.68002 -50.103786)
		(end 96.13646 -50.647346)
		(width 0.0889)
		(layer "In2.Cu")
		(net "M_J_PAR")
	)
	(segment
		(start 99.311968 -25.306528)
		(end 99.311968 -26.54554)
		(width 0.14224)
		(layer "In2.Cu")
		(net "M_J_PAR")
	)
	(segment
		(start 95.848678 -56.86552)
		(end 95.855028 -56.876188)
		(width 0.0889)
		(layer "In2.Cu")
		(net "M_J_PAR")
	)
	(segment
		(start 96.68002 -48.329342)
		(end 96.68002 -50.103786)
		(width 0.0889)
		(layer "In2.Cu")
		(net "M_J_PAR")
	)
	(segment
		(start 99.311968 -26.54554)
		(end 96.680528 -29.17698)
		(width 0.14224)
		(layer "In2.Cu")
		(net "M_J_PAR")
	)
	(segment
		(start 95.855028 -53.904388)
		(end 95.859854 -53.913024)
		(width 0.0889)
		(layer "In2.Cu")
		(net "M_J_PAR")
	)
	(segment
		(start 95.848678 -55.87492)
		(end 95.855028 -55.885588)
		(width 0.0889)
		(layer "In2.Cu")
		(net "M_J_PAR")
	)
	(segment
		(start 96.13646 -51.904138)
		(end 95.964756 -52.075588)
		(width 0.0889)
		(layer "In2.Cu")
		(net "M_J_PAR")
	)
	(segment
		(start 95.855028 -56.876188)
		(end 95.859854 -56.884824)
		(width 0.0889)
		(layer "In2.Cu")
		(net "M_J_PAR")
	)
	(segment
		(start 95.848678 -53.89372)
		(end 95.855028 -53.904388)
		(width 0.0889)
		(layer "In2.Cu")
		(net "M_J_PAR")
	)
	(segment
		(start 95.848678 -54.88432)
		(end 95.855028 -54.894988)
		(width 0.0889)
		(layer "In2.Cu")
		(net "M_J_PAR")
	)
	(segment
		(start 95.855028 -54.894988)
		(end 95.859854 -54.903624)
		(width 0.0889)
		(layer "In2.Cu")
		(net "M_J_PAR")
	)
	(segment
		(start 95.855028 -57.276238)
		(end 95.838264 -57.305194)
		(width 0.0889)
		(layer "In2.Cu")
		(net "M_J_PAR")
	)
	(segment
		(start 100.249228 0.28956)
		(end 100.249228 -2.995168)
		(width 0.14224)
		(layer "In2.Cu")
		(net "M_J_PAR")
	)
	(segment
		(start 96.680528 -48.328834)
		(end 96.68002 -48.329342)
		(width 0.14224)
		(layer "In2.Cu")
		(net "M_J_PAR")
	)
	(segment
		(start 99.743768 -3.9116)
		(end 99.743768 -24.874728)
		(width 0.14224)
		(layer "In2.Cu")
		(net "M_J_PAR")
	)
	(segment
		(start 95.964756 -52.075588)
		(end 95.943166 -52.097432)
		(width 0.0889)
		(layer "In2.Cu")
		(net "M_J_PAR")
	)
	(segment
		(start 96.680528 -29.17698)
		(end 96.680528 -48.328834)
		(width 0.14224)
		(layer "In2.Cu")
		(net "M_J_PAR")
	)
	(segment
		(start 100.249482 0.289814)
		(end 100.249228 0.28956)
		(width 0.14224)
		(layer "In2.Cu")
		(net "M_J_PAR")
	)
	(segment
		(start 99.743768 -24.874728)
		(end 99.311968 -25.306528)
		(width 0.14224)
		(layer "In2.Cu")
		(net "M_J_PAR")
	)
	(segment
		(start 95.855028 -52.913788)
		(end 95.859854 -52.922424)
		(width 0.0889)
		(layer "In2.Cu")
		(net "M_J_PAR")
	)
	(segment
		(start 100.249228 -2.995168)
		(end 100.249228 -3.40614)
		(width 0.14224)
		(layer "In2.Cu")
		(net "M_J_PAR")
	)
	(segment
		(start 95.855028 -52.323238)
		(end 95.848678 -52.333906)
		(width 0.0889)
		(layer "In2.Cu")
		(net "M_J_PAR")
	)
	(segment
		(start 96.13646 -50.647346)
		(end 96.13646 -51.904138)
		(width 0.0889)
		(layer "In2.Cu")
		(net "M_J_PAR")
	)
	(arc
		(start 95.855028 -53.313838)
		(mid 95.775806 -53.602956)
		(end 95.848678 -53.89372)
		(width 0.0889)
		(layer "In2.Cu")
		(net "M_J_PAR")
	)
	(arc
		(start 95.859854 -54.903624)
		(mid 95.908609 -55.099976)
		(end 95.855028 -55.295038)
		(width 0.0889)
		(layer "In2.Cu")
		(net "M_J_PAR")
	)
	(arc
		(start 95.855028 -54.304438)
		(mid 95.775806 -54.593556)
		(end 95.848678 -54.88432)
		(width 0.0889)
		(layer "In2.Cu")
		(net "M_J_PAR")
	)
	(arc
		(start 95.859854 -52.922424)
		(mid 95.908609 -53.118776)
		(end 95.855028 -53.313838)
		(width 0.0889)
		(layer "In2.Cu")
		(net "M_J_PAR")
	)
	(arc
		(start 95.848678 -52.333906)
		(mid 95.77588 -52.624669)
		(end 95.855028 -52.913788)
		(width 0.0889)
		(layer "In2.Cu")
		(net "M_J_PAR")
	)
	(arc
		(start 95.859854 -55.894224)
		(mid 95.908609 -56.090576)
		(end 95.855028 -56.285638)
		(width 0.0889)
		(layer "In2.Cu")
		(net "M_J_PAR")
	)
	(arc
		(start 95.943166 -52.097432)
		(mid 95.90839 -52.213961)
		(end 95.855028 -52.323238)
		(width 0.0889)
		(layer "In2.Cu")
		(net "M_J_PAR")
	)
	(arc
		(start 95.859854 -53.913024)
		(mid 95.908609 -54.109376)
		(end 95.855028 -54.304438)
		(width 0.0889)
		(layer "In2.Cu")
		(net "M_J_PAR")
	)
	(arc
		(start 95.859854 -56.884824)
		(mid 95.908609 -57.081176)
		(end 95.855028 -57.276238)
		(width 0.0889)
		(layer "In2.Cu")
		(net "M_J_PAR")
	)
	(arc
		(start 95.855028 -56.285638)
		(mid 95.775806 -56.574756)
		(end 95.848678 -56.86552)
		(width 0.0889)
		(layer "In2.Cu")
		(net "M_J_PAR")
	)
	(arc
		(start 95.855028 -55.295038)
		(mid 95.775806 -55.584156)
		(end 95.848678 -55.87492)
		(width 0.0889)
		(layer "In2.Cu")
		(net "M_J_PAR")
	)
	(segment
		(start 101.230684 -60.047886)
		(end 100.659184 -60.047886)
		(width 0.1016)
		(layer "F.Cu")
		(net "M_J_ODT<3>")
	)
	(via
		(at 111.299498 -4.332986)
		(size 0.4572)
		(drill 0.2032)
		(layers "F.Cu" "B.Cu")
		(net "M_J_ODT<3>")
	)
	(via
		(at 100.659184 -60.047886)
		(size 0.508)
		(drill 0.254)
		(layers "F.Cu" "B.Cu")
		(net "M_J_ODT<3>")
	)
	(segment
		(start 111.299498 -5.621782)
		(end 111.299498 -4.332986)
		(width 0.1651)
		(layer "B.Cu")
		(net "M_J_ODT<3>")
	)
	(segment
		(start 109.670342 -8.46455)
		(end 110.039912 -8.83412)
		(width 0.14224)
		(layer "In2.Cu")
		(net "M_J_ODT<3>")
	)
	(segment
		(start 109.663992 -12.54125)
		(end 109.663992 -13.32611)
		(width 0.14224)
		(layer "In2.Cu")
		(net "M_J_ODT<3>")
	)
	(segment
		(start 101.699568 -50.2412)
		(end 101.078792 -50.861976)
		(width 0.0889)
		(layer "In2.Cu")
		(net "M_J_ODT<3>")
	)
	(segment
		(start 109.663992 -13.32611)
		(end 110.008162 -13.67028)
		(width 0.14224)
		(layer "In2.Cu")
		(net "M_J_ODT<3>")
	)
	(segment
		(start 109.657642 -17.34439)
		(end 109.657642 -18.03019)
		(width 0.14224)
		(layer "In2.Cu")
		(net "M_J_ODT<3>")
	)
	(segment
		(start 102.776528 -32.672274)
		(end 102.776528 -48.330358)
		(width 0.14224)
		(layer "In2.Cu")
		(net "M_J_ODT<3>")
	)
	(segment
		(start 102.776528 -48.641)
		(end 101.699568 -49.71796)
		(width 0.0889)
		(layer "In2.Cu")
		(net "M_J_ODT<3>")
	)
	(segment
		(start 110.008162 -14.663674)
		(end 110.038388 -14.6939)
		(width 0.14224)
		(layer "In2.Cu")
		(net "M_J_ODT<3>")
	)
	(segment
		(start 110.04169 -7.359142)
		(end 109.670342 -7.73049)
		(width 0.14224)
		(layer "In2.Cu")
		(net "M_J_ODT<3>")
	)
	(segment
		(start 110.03534 -21.771102)
		(end 109.842046 -21.964396)
		(width 0.14224)
		(layer "In2.Cu")
		(net "M_J_ODT<3>")
	)
	(segment
		(start 111.299498 -4.332986)
		(end 110.04169 -5.590794)
		(width 0.14224)
		(layer "In2.Cu")
		(net "M_J_ODT<3>")
	)
	(segment
		(start 100.659184 -60.043822)
		(end 100.659184 -60.047886)
		(width 0.0889)
		(layer "In2.Cu")
		(net "M_J_ODT<3>")
	)
	(segment
		(start 109.852968 -23.426674)
		(end 109.852968 -24.282146)
		(width 0.14224)
		(layer "In2.Cu")
		(net "M_J_ODT<3>")
	)
	(segment
		(start 109.852968 -24.282146)
		(end 108.100368 -26.034746)
		(width 0.14224)
		(layer "In2.Cu")
		(net "M_J_ODT<3>")
	)
	(segment
		(start 108.100368 -27.348434)
		(end 102.776528 -32.672274)
		(width 0.14224)
		(layer "In2.Cu")
		(net "M_J_ODT<3>")
	)
	(segment
		(start 110.096046 -22.662896)
		(end 110.096046 -23.183596)
		(width 0.14224)
		(layer "In2.Cu")
		(net "M_J_ODT<3>")
	)
	(segment
		(start 110.039912 -12.16533)
		(end 109.663992 -12.54125)
		(width 0.14224)
		(layer "In2.Cu")
		(net "M_J_ODT<3>")
	)
	(segment
		(start 110.038388 -16.963644)
		(end 109.657642 -17.34439)
		(width 0.14224)
		(layer "In2.Cu")
		(net "M_J_ODT<3>")
	)
	(segment
		(start 110.008162 -13.67028)
		(end 110.008162 -14.663674)
		(width 0.14224)
		(layer "In2.Cu")
		(net "M_J_ODT<3>")
	)
	(segment
		(start 102.776528 -48.330358)
		(end 102.776528 -48.641)
		(width 0.0889)
		(layer "In2.Cu")
		(net "M_J_ODT<3>")
	)
	(segment
		(start 108.100368 -26.034746)
		(end 108.100368 -27.348434)
		(width 0.14224)
		(layer "In2.Cu")
		(net "M_J_ODT<3>")
	)
	(segment
		(start 101.699568 -49.71796)
		(end 101.699568 -50.2412)
		(width 0.0889)
		(layer "In2.Cu")
		(net "M_J_ODT<3>")
	)
	(segment
		(start 110.039912 -8.83412)
		(end 110.039912 -12.16533)
		(width 0.14224)
		(layer "In2.Cu")
		(net "M_J_ODT<3>")
	)
	(segment
		(start 110.038388 -14.6939)
		(end 110.038388 -16.963644)
		(width 0.14224)
		(layer "In2.Cu")
		(net "M_J_ODT<3>")
	)
	(segment
		(start 109.842046 -21.964396)
		(end 109.842046 -22.408896)
		(width 0.14224)
		(layer "In2.Cu")
		(net "M_J_ODT<3>")
	)
	(segment
		(start 110.03534 -18.407888)
		(end 110.03534 -21.771102)
		(width 0.14224)
		(layer "In2.Cu")
		(net "M_J_ODT<3>")
	)
	(segment
		(start 101.078792 -59.624214)
		(end 100.659184 -60.043822)
		(width 0.0889)
		(layer "In2.Cu")
		(net "M_J_ODT<3>")
	)
	(segment
		(start 109.842046 -22.408896)
		(end 110.096046 -22.662896)
		(width 0.14224)
		(layer "In2.Cu")
		(net "M_J_ODT<3>")
	)
	(segment
		(start 110.096046 -23.183596)
		(end 109.852968 -23.426674)
		(width 0.14224)
		(layer "In2.Cu")
		(net "M_J_ODT<3>")
	)
	(segment
		(start 109.657642 -18.03019)
		(end 110.03534 -18.407888)
		(width 0.14224)
		(layer "In2.Cu")
		(net "M_J_ODT<3>")
	)
	(segment
		(start 110.04169 -5.590794)
		(end 110.04169 -7.359142)
		(width 0.14224)
		(layer "In2.Cu")
		(net "M_J_ODT<3>")
	)
	(segment
		(start 101.078792 -50.861976)
		(end 101.078792 -59.624214)
		(width 0.0889)
		(layer "In2.Cu")
		(net "M_J_ODT<3>")
	)
	(segment
		(start 109.670342 -7.73049)
		(end 109.670342 -8.46455)
		(width 0.14224)
		(layer "In2.Cu")
		(net "M_J_ODT<3>")
	)
	(segment
		(start 99.513898 -58.06694)
		(end 98.942398 -58.06694)
		(width 0.1016)
		(layer "F.Cu")
		(net "M_J_ODT<2>")
	)
	(via
		(at 98.942398 -58.06694)
		(size 0.508)
		(drill 0.254)
		(layers "F.Cu" "B.Cu")
		(net "M_J_ODT<2>")
	)
	(via
		(at 107.899454 -4.328668)
		(size 0.4572)
		(drill 0.2032)
		(layers "F.Cu" "B.Cu")
		(net "M_J_ODT<2>")
	)
	(segment
		(start 107.899454 -5.621782)
		(end 107.899454 -4.328668)
		(width 0.1651)
		(layer "B.Cu")
		(net "M_J_ODT<2>")
	)
	(segment
		(start 106.442002 -24.086566)
		(end 106.442002 -23.437596)
		(width 0.14224)
		(layer "In2.Cu")
		(net "M_J_ODT<2>")
	)
	(segment
		(start 106.27106 -20.402042)
		(end 106.426 -20.247102)
		(width 0.14224)
		(layer "In2.Cu")
		(net "M_J_ODT<2>")
	)
	(segment
		(start 99.743768 -50.171096)
		(end 100.744528 -49.170336)
		(width 0.0889)
		(layer "In2.Cu")
		(net "M_J_ODT<2>")
	)
	(segment
		(start 99.288854 -54.894988)
		(end 99.279964 -54.879748)
		(width 0.0889)
		(layer "In2.Cu")
		(net "M_J_ODT<2>")
	)
	(segment
		(start 106.426 -20.247102)
		(end 106.745024 -20.247102)
		(width 0.14224)
		(layer "In2.Cu")
		(net "M_J_ODT<2>")
	)
	(segment
		(start 106.442002 -23.437596)
		(end 106.696002 -23.183596)
		(width 0.14224)
		(layer "In2.Cu")
		(net "M_J_ODT<2>")
	)
	(segment
		(start 106.633264 -5.864098)
		(end 107.70108 -4.796282)
		(width 0.14224)
		(layer "In2.Cu")
		(net "M_J_ODT<2>")
	)
	(segment
		(start 106.637074 -18.218658)
		(end 106.442002 -18.023586)
		(width 0.14224)
		(layer "In2.Cu")
		(net "M_J_ODT<2>")
	)
	(segment
		(start 106.363516 -8.51408)
		(end 106.363516 -7.637272)
		(width 0.14224)
		(layer "In2.Cu")
		(net "M_J_ODT<2>")
	)
	(segment
		(start 106.442002 -21.964396)
		(end 106.899964 -21.506434)
		(width 0.14224)
		(layer "In2.Cu")
		(net "M_J_ODT<2>")
	)
	(segment
		(start 106.899964 -19.472148)
		(end 106.637074 -19.209258)
		(width 0.14224)
		(layer "In2.Cu")
		(net "M_J_ODT<2>")
	)
	(segment
		(start 106.634534 -15.1257)
		(end 106.844338 -14.915896)
		(width 0.14224)
		(layer "In2.Cu")
		(net "M_J_ODT<2>")
	)
	(segment
		(start 106.899964 -20.092162)
		(end 106.899964 -19.472148)
		(width 0.14224)
		(layer "In2.Cu")
		(net "M_J_ODT<2>")
	)
	(segment
		(start 106.696002 -22.662896)
		(end 106.442002 -22.408896)
		(width 0.14224)
		(layer "In2.Cu")
		(net "M_J_ODT<2>")
	)
	(segment
		(start 107.70108 -4.527042)
		(end 107.899454 -4.328668)
		(width 0.14224)
		(layer "In2.Cu")
		(net "M_J_ODT<2>")
	)
	(segment
		(start 99.288854 -55.885588)
		(end 99.279964 -55.870348)
		(width 0.0889)
		(layer "In2.Cu")
		(net "M_J_ODT<2>")
	)
	(segment
		(start 99.389692 -51.458622)
		(end 99.743768 -51.104546)
		(width 0.0889)
		(layer "In2.Cu")
		(net "M_J_ODT<2>")
	)
	(segment
		(start 106.27106 -20.755102)
		(end 106.27106 -20.402042)
		(width 0.14224)
		(layer "In2.Cu")
		(net "M_J_ODT<2>")
	)
	(segment
		(start 106.363516 -7.637272)
		(end 106.633264 -7.367524)
		(width 0.14224)
		(layer "In2.Cu")
		(net "M_J_ODT<2>")
	)
	(segment
		(start 100.744528 -31.828994)
		(end 104.906826 -27.666696)
		(width 0.14224)
		(layer "In2.Cu")
		(net "M_J_ODT<2>")
	)
	(segment
		(start 106.696002 -23.183596)
		(end 106.696002 -22.662896)
		(width 0.14224)
		(layer "In2.Cu")
		(net "M_J_ODT<2>")
	)
	(segment
		(start 106.63428 -13.644118)
		(end 106.375708 -13.385546)
		(width 0.14224)
		(layer "In2.Cu")
		(net "M_J_ODT<2>")
	)
	(segment
		(start 106.638852 -11.406124)
		(end 106.424984 -11.192256)
		(width 0.14224)
		(layer "In2.Cu")
		(net "M_J_ODT<2>")
	)
	(segment
		(start 99.288854 -53.313584)
		(end 99.389692 -53.139086)
		(width 0.0889)
		(layer "In2.Cu")
		(net "M_J_ODT<2>")
	)
	(segment
		(start 106.638852 -10.529316)
		(end 106.638852 -8.789416)
		(width 0.14224)
		(layer "In2.Cu")
		(net "M_J_ODT<2>")
	)
	(segment
		(start 106.638852 -8.789416)
		(end 106.363516 -8.51408)
		(width 0.14224)
		(layer "In2.Cu")
		(net "M_J_ODT<2>")
	)
	(segment
		(start 106.424984 -10.743184)
		(end 106.638852 -10.529316)
		(width 0.14224)
		(layer "In2.Cu")
		(net "M_J_ODT<2>")
	)
	(segment
		(start 106.63428 -14.309344)
		(end 106.63428 -13.644118)
		(width 0.14224)
		(layer "In2.Cu")
		(net "M_J_ODT<2>")
	)
	(segment
		(start 106.633264 -7.367524)
		(end 106.633264 -5.864098)
		(width 0.14224)
		(layer "In2.Cu")
		(net "M_J_ODT<2>")
	)
	(segment
		(start 106.776266 -16.300196)
		(end 106.776266 -15.720568)
		(width 0.14224)
		(layer "In2.Cu")
		(net "M_J_ODT<2>")
	)
	(segment
		(start 106.375708 -13.385546)
		(end 106.375708 -12.42949)
		(width 0.14224)
		(layer "In2.Cu")
		(net "M_J_ODT<2>")
	)
	(segment
		(start 106.776266 -15.720568)
		(end 106.634534 -15.578836)
		(width 0.14224)
		(layer "In2.Cu")
		(net "M_J_ODT<2>")
	)
	(segment
		(start 106.426 -20.910042)
		(end 106.27106 -20.755102)
		(width 0.14224)
		(layer "In2.Cu")
		(net "M_J_ODT<2>")
	)
	(segment
		(start 106.375708 -12.42949)
		(end 106.638852 -12.166346)
		(width 0.14224)
		(layer "In2.Cu")
		(net "M_J_ODT<2>")
	)
	(segment
		(start 99.743768 -51.104546)
		(end 99.743768 -50.171096)
		(width 0.0889)
		(layer "In2.Cu")
		(net "M_J_ODT<2>")
	)
	(segment
		(start 106.634534 -15.578836)
		(end 106.634534 -15.1257)
		(width 0.14224)
		(layer "In2.Cu")
		(net "M_J_ODT<2>")
	)
	(segment
		(start 107.70108 -4.796282)
		(end 107.70108 -4.527042)
		(width 0.14224)
		(layer "In2.Cu")
		(net "M_J_ODT<2>")
	)
	(segment
		(start 106.63428 -16.967708)
		(end 106.63428 -16.442182)
		(width 0.14224)
		(layer "In2.Cu")
		(net "M_J_ODT<2>")
	)
	(segment
		(start 100.744528 -49.170336)
		(end 100.744528 -48.66259)
		(width 0.0889)
		(layer "In2.Cu")
		(net "M_J_ODT<2>")
	)
	(segment
		(start 99.288854 -53.904388)
		(end 99.279964 -53.889148)
		(width 0.0889)
		(layer "In2.Cu")
		(net "M_J_ODT<2>")
	)
	(segment
		(start 99.288854 -56.876188)
		(end 99.279964 -56.860948)
		(width 0.0889)
		(layer "In2.Cu")
		(net "M_J_ODT<2>")
	)
	(segment
		(start 100.744528 -48.66259)
		(end 100.744528 -31.828994)
		(width 0.14224)
		(layer "In2.Cu")
		(net "M_J_ODT<2>")
	)
	(segment
		(start 99.272852 -57.303162)
		(end 99.288854 -57.275984)
		(width 0.0889)
		(layer "In2.Cu")
		(net "M_J_ODT<2>")
	)
	(segment
		(start 106.442002 -22.408896)
		(end 106.442002 -21.964396)
		(width 0.14224)
		(layer "In2.Cu")
		(net "M_J_ODT<2>")
	)
	(segment
		(start 106.442002 -17.159986)
		(end 106.63428 -16.967708)
		(width 0.14224)
		(layer "In2.Cu")
		(net "M_J_ODT<2>")
	)
	(segment
		(start 106.745024 -20.247102)
		(end 106.899964 -20.092162)
		(width 0.14224)
		(layer "In2.Cu")
		(net "M_J_ODT<2>")
	)
	(segment
		(start 106.844338 -14.519402)
		(end 106.63428 -14.309344)
		(width 0.14224)
		(layer "In2.Cu")
		(net "M_J_ODT<2>")
	)
	(segment
		(start 104.906826 -25.621742)
		(end 106.442002 -24.086566)
		(width 0.14224)
		(layer "In2.Cu")
		(net "M_J_ODT<2>")
	)
	(segment
		(start 106.899964 -21.064982)
		(end 106.745024 -20.910042)
		(width 0.14224)
		(layer "In2.Cu")
		(net "M_J_ODT<2>")
	)
	(segment
		(start 104.906826 -27.666696)
		(end 104.906826 -25.621742)
		(width 0.14224)
		(layer "In2.Cu")
		(net "M_J_ODT<2>")
	)
	(segment
		(start 106.638852 -12.166346)
		(end 106.638852 -11.406124)
		(width 0.14224)
		(layer "In2.Cu")
		(net "M_J_ODT<2>")
	)
	(segment
		(start 106.745024 -20.910042)
		(end 106.426 -20.910042)
		(width 0.14224)
		(layer "In2.Cu")
		(net "M_J_ODT<2>")
	)
	(segment
		(start 106.899964 -21.506434)
		(end 106.899964 -21.064982)
		(width 0.14224)
		(layer "In2.Cu")
		(net "M_J_ODT<2>")
	)
	(segment
		(start 98.942398 -58.06694)
		(end 99.272852 -57.303162)
		(width 0.0889)
		(layer "In2.Cu")
		(net "M_J_ODT<2>")
	)
	(segment
		(start 106.637074 -19.209258)
		(end 106.637074 -18.218658)
		(width 0.14224)
		(layer "In2.Cu")
		(net "M_J_ODT<2>")
	)
	(segment
		(start 106.442002 -18.023586)
		(end 106.442002 -17.159986)
		(width 0.14224)
		(layer "In2.Cu")
		(net "M_J_ODT<2>")
	)
	(segment
		(start 99.389692 -53.139086)
		(end 99.389692 -51.458622)
		(width 0.0889)
		(layer "In2.Cu")
		(net "M_J_ODT<2>")
	)
	(segment
		(start 106.63428 -16.442182)
		(end 106.776266 -16.300196)
		(width 0.14224)
		(layer "In2.Cu")
		(net "M_J_ODT<2>")
	)
	(segment
		(start 106.844338 -14.915896)
		(end 106.844338 -14.519402)
		(width 0.14224)
		(layer "In2.Cu")
		(net "M_J_ODT<2>")
	)
	(segment
		(start 106.424984 -11.192256)
		(end 106.424984 -10.743184)
		(width 0.14224)
		(layer "In2.Cu")
		(net "M_J_ODT<2>")
	)
	(arc
		(start 99.288854 -57.275984)
		(mid 99.342387 -57.076086)
		(end 99.288854 -56.876188)
		(width 0.0889)
		(layer "In2.Cu")
		(net "M_J_ODT<2>")
	)
	(arc
		(start 99.279964 -56.860948)
		(mid 99.209567 -56.571997)
		(end 99.288854 -56.285384)
		(width 0.0889)
		(layer "In2.Cu")
		(net "M_J_ODT<2>")
	)
	(arc
		(start 99.279964 -55.870348)
		(mid 99.209567 -55.581397)
		(end 99.288854 -55.294784)
		(width 0.0889)
		(layer "In2.Cu")
		(net "M_J_ODT<2>")
	)
	(arc
		(start 99.288854 -54.304184)
		(mid 99.342387 -54.104286)
		(end 99.288854 -53.904388)
		(width 0.0889)
		(layer "In2.Cu")
		(net "M_J_ODT<2>")
	)
	(arc
		(start 99.288854 -55.294784)
		(mid 99.342387 -55.094886)
		(end 99.288854 -54.894988)
		(width 0.0889)
		(layer "In2.Cu")
		(net "M_J_ODT<2>")
	)
	(arc
		(start 99.288854 -56.285384)
		(mid 99.342387 -56.085486)
		(end 99.288854 -55.885588)
		(width 0.0889)
		(layer "In2.Cu")
		(net "M_J_ODT<2>")
	)
	(arc
		(start 99.279964 -54.879748)
		(mid 99.209567 -54.590797)
		(end 99.288854 -54.304184)
		(width 0.0889)
		(layer "In2.Cu")
		(net "M_J_ODT<2>")
	)
	(arc
		(start 99.279964 -53.889148)
		(mid 99.209567 -53.600197)
		(end 99.288854 -53.313584)
		(width 0.0889)
		(layer "In2.Cu")
		(net "M_J_ODT<2>")
	)
	(segment
		(start 111.299498 3.778758)
		(end 111.299498 2.485644)
		(width 0.1651)
		(layer "F.Cu")
		(net "M_J_ODT<1>")
	)
	(segment
		(start 100.372164 -59.55284)
		(end 99.800664 -59.55284)
		(width 0.1016)
		(layer "F.Cu")
		(net "M_J_ODT<1>")
	)
	(via
		(at 111.299498 2.485644)
		(size 0.508)
		(drill 0.254)
		(layers "F.Cu" "B.Cu")
		(net "M_J_ODT<1>")
	)
	(via
		(at 99.800664 -59.55284)
		(size 0.508)
		(drill 0.254)
		(layers "F.Cu" "B.Cu")
		(net "M_J_ODT<1>")
	)
	(segment
		(start 102.268528 -32.461454)
		(end 102.268528 -48.39208)
		(width 0.14224)
		(layer "In2.Cu")
		(net "M_J_ODT<1>")
	)
	(segment
		(start 109.189774 -14.548104)
		(end 109.163104 -14.574774)
		(width 0.14224)
		(layer "In2.Cu")
		(net "M_J_ODT<1>")
	)
	(segment
		(start 109.105446 -21.321268)
		(end 109.105446 -21.811996)
		(width 0.14224)
		(layer "In2.Cu")
		(net "M_J_ODT<1>")
	)
	(segment
		(start 111.299498 1.95453)
		(end 109.984032 0.639064)
		(width 0.14224)
		(layer "In2.Cu")
		(net "M_J_ODT<1>")
	)
	(segment
		(start 109.160056 -21.266658)
		(end 109.105446 -21.321268)
		(width 0.14224)
		(layer "In2.Cu")
		(net "M_J_ODT<1>")
	)
	(segment
		(start 100.735892 -52.461668)
		(end 100.352098 -52.845462)
		(width 0.0889)
		(layer "In2.Cu")
		(net "M_J_ODT<1>")
	)
	(segment
		(start 100.352098 -52.845462)
		(end 100.312474 -52.914296)
		(width 0.0889)
		(layer "In2.Cu")
		(net "M_J_ODT<1>")
	)
	(segment
		(start 107.566968 -27.163014)
		(end 102.268528 -32.461454)
		(width 0.14224)
		(layer "In2.Cu")
		(net "M_J_ODT<1>")
	)
	(segment
		(start 101.369368 -50.292)
		(end 100.735892 -50.925476)
		(width 0.0889)
		(layer "In2.Cu")
		(net "M_J_ODT<1>")
	)
	(segment
		(start 111.299498 2.485644)
		(end 111.299498 1.95453)
		(width 0.14224)
		(layer "In2.Cu")
		(net "M_J_ODT<1>")
	)
	(segment
		(start 109.160056 -18.459196)
		(end 109.160056 -21.266658)
		(width 0.14224)
		(layer "In2.Cu")
		(net "M_J_ODT<1>")
	)
	(segment
		(start 109.984032 0.639064)
		(end 109.984032 -0.080264)
		(width 0.14224)
		(layer "In2.Cu")
		(net "M_J_ODT<1>")
	)
	(segment
		(start 102.268528 -48.70704)
		(end 101.369368 -49.6062)
		(width 0.0889)
		(layer "In2.Cu")
		(net "M_J_ODT<1>")
	)
	(segment
		(start 109.054646 -23.132796)
		(end 109.24032 -23.31847)
		(width 0.14224)
		(layer "In2.Cu")
		(net "M_J_ODT<1>")
	)
	(segment
		(start 110.041182 -0.137414)
		(end 110.041182 -2.553208)
		(width 0.14224)
		(layer "In2.Cu")
		(net "M_J_ODT<1>")
	)
	(segment
		(start 109.105446 -17.769586)
		(end 109.105446 -18.404586)
		(width 0.14224)
		(layer "In2.Cu")
		(net "M_J_ODT<1>")
	)
	(segment
		(start 110.009178 -4.64439)
		(end 109.160056 -5.493512)
		(width 0.14224)
		(layer "In2.Cu")
		(net "M_J_ODT<1>")
	)
	(segment
		(start 110.009178 -4.13639)
		(end 110.009178 -4.64439)
		(width 0.14224)
		(layer "In2.Cu")
		(net "M_J_ODT<1>")
	)
	(segment
		(start 109.189774 -13.666724)
		(end 109.189774 -14.548104)
		(width 0.14224)
		(layer "In2.Cu")
		(net "M_J_ODT<1>")
	)
	(segment
		(start 109.984032 -0.080264)
		(end 110.041182 -0.137414)
		(width 0.14224)
		(layer "In2.Cu")
		(net "M_J_ODT<1>")
	)
	(segment
		(start 109.163104 -17.711928)
		(end 109.105446 -17.769586)
		(width 0.14224)
		(layer "In2.Cu")
		(net "M_J_ODT<1>")
	)
	(segment
		(start 109.105446 -18.404586)
		(end 109.160056 -18.459196)
		(width 0.14224)
		(layer "In2.Cu")
		(net "M_J_ODT<1>")
	)
	(segment
		(start 109.24032 -23.31847)
		(end 109.24032 -24.133048)
		(width 0.14224)
		(layer "In2.Cu")
		(net "M_J_ODT<1>")
	)
	(segment
		(start 109.163104 -14.574774)
		(end 109.163104 -17.711928)
		(width 0.14224)
		(layer "In2.Cu")
		(net "M_J_ODT<1>")
	)
	(segment
		(start 109.160056 -5.493512)
		(end 109.160056 -13.637006)
		(width 0.14224)
		(layer "In2.Cu")
		(net "M_J_ODT<1>")
	)
	(segment
		(start 107.566968 -25.8064)
		(end 107.566968 -27.163014)
		(width 0.14224)
		(layer "In2.Cu")
		(net "M_J_ODT<1>")
	)
	(segment
		(start 101.369368 -49.6062)
		(end 101.369368 -50.292)
		(width 0.0889)
		(layer "In2.Cu")
		(net "M_J_ODT<1>")
	)
	(segment
		(start 109.634782 -3.761994)
		(end 110.009178 -4.13639)
		(width 0.14224)
		(layer "In2.Cu")
		(net "M_J_ODT<1>")
	)
	(segment
		(start 109.232446 -21.938996)
		(end 109.232446 -22.421596)
		(width 0.14224)
		(layer "In2.Cu")
		(net "M_J_ODT<1>")
	)
	(segment
		(start 109.634782 -2.959608)
		(end 109.634782 -3.761994)
		(width 0.14224)
		(layer "In2.Cu")
		(net "M_J_ODT<1>")
	)
	(segment
		(start 109.105446 -21.811996)
		(end 109.232446 -21.938996)
		(width 0.14224)
		(layer "In2.Cu")
		(net "M_J_ODT<1>")
	)
	(segment
		(start 109.24032 -24.133048)
		(end 107.566968 -25.8064)
		(width 0.14224)
		(layer "In2.Cu")
		(net "M_J_ODT<1>")
	)
	(segment
		(start 100.735892 -50.925476)
		(end 100.735892 -52.461668)
		(width 0.0889)
		(layer "In2.Cu")
		(net "M_J_ODT<1>")
	)
	(segment
		(start 109.160056 -13.637006)
		(end 109.189774 -13.666724)
		(width 0.14224)
		(layer "In2.Cu")
		(net "M_J_ODT<1>")
	)
	(segment
		(start 100.23729 -58.960766)
		(end 99.800664 -59.55284)
		(width 0.0889)
		(layer "In2.Cu")
		(net "M_J_ODT<1>")
	)
	(segment
		(start 109.232446 -22.421596)
		(end 109.054646 -22.599396)
		(width 0.14224)
		(layer "In2.Cu")
		(net "M_J_ODT<1>")
	)
	(segment
		(start 110.041182 -2.553208)
		(end 109.634782 -2.959608)
		(width 0.14224)
		(layer "In2.Cu")
		(net "M_J_ODT<1>")
	)
	(segment
		(start 102.268528 -48.39208)
		(end 102.268528 -48.70704)
		(width 0.0889)
		(layer "In2.Cu")
		(net "M_J_ODT<1>")
	)
	(segment
		(start 109.054646 -22.599396)
		(end 109.054646 -23.132796)
		(width 0.14224)
		(layer "In2.Cu")
		(net "M_J_ODT<1>")
	)
	(arc
		(start 100.312474 -58.267092)
		(mid 100.388162 -58.6262)
		(end 100.23729 -58.960766)
		(width 0.0889)
		(layer "In2.Cu")
		(net "M_J_ODT<1>")
	)
	(arc
		(start 100.312474 -53.904896)
		(mid 100.258941 -54.104794)
		(end 100.312474 -54.304692)
		(width 0.0889)
		(layer "In2.Cu")
		(net "M_J_ODT<1>")
	)
	(arc
		(start 100.312474 -55.295292)
		(mid 100.391605 -55.590694)
		(end 100.312474 -55.886096)
		(width 0.0889)
		(layer "In2.Cu")
		(net "M_J_ODT<1>")
	)
	(arc
		(start 100.312474 -54.895496)
		(mid 100.258975 -55.095394)
		(end 100.312474 -55.295292)
		(width 0.0889)
		(layer "In2.Cu")
		(net "M_J_ODT<1>")
	)
	(arc
		(start 100.312474 -53.314092)
		(mid 100.391605 -53.609494)
		(end 100.312474 -53.904896)
		(width 0.0889)
		(layer "In2.Cu")
		(net "M_J_ODT<1>")
	)
	(arc
		(start 100.312474 -54.304692)
		(mid 100.391605 -54.600094)
		(end 100.312474 -54.895496)
		(width 0.0889)
		(layer "In2.Cu")
		(net "M_J_ODT<1>")
	)
	(arc
		(start 100.312474 -57.276492)
		(mid 100.391605 -57.571894)
		(end 100.312474 -57.867296)
		(width 0.0889)
		(layer "In2.Cu")
		(net "M_J_ODT<1>")
	)
	(arc
		(start 100.312474 -56.285892)
		(mid 100.391605 -56.581294)
		(end 100.312474 -56.876696)
		(width 0.0889)
		(layer "In2.Cu")
		(net "M_J_ODT<1>")
	)
	(arc
		(start 100.312474 -52.914296)
		(mid 100.258975 -53.114194)
		(end 100.312474 -53.314092)
		(width 0.0889)
		(layer "In2.Cu")
		(net "M_J_ODT<1>")
	)
	(arc
		(start 100.312474 -56.876696)
		(mid 100.258975 -57.076594)
		(end 100.312474 -57.276492)
		(width 0.0889)
		(layer "In2.Cu")
		(net "M_J_ODT<1>")
	)
	(arc
		(start 100.312474 -57.867296)
		(mid 100.258975 -58.067194)
		(end 100.312474 -58.267092)
		(width 0.0889)
		(layer "In2.Cu")
		(net "M_J_ODT<1>")
	)
	(arc
		(start 100.312474 -55.886096)
		(mid 100.258975 -56.085994)
		(end 100.312474 -56.285892)
		(width 0.0889)
		(layer "In2.Cu")
		(net "M_J_ODT<1>")
	)
	(segment
		(start 98.655378 -59.55284)
		(end 98.083878 -59.55284)
		(width 0.1016)
		(layer "F.Cu")
		(net "M_J_ODT<0>")
	)
	(segment
		(start 107.899454 3.778758)
		(end 107.899454 2.485644)
		(width 0.1651)
		(layer "F.Cu")
		(net "M_J_ODT<0>")
	)
	(via
		(at 107.899454 2.485644)
		(size 0.508)
		(drill 0.254)
		(layers "F.Cu" "B.Cu")
		(net "M_J_ODT<0>")
	)
	(via
		(at 98.083878 -59.55284)
		(size 0.508)
		(drill 0.254)
		(layers "F.Cu" "B.Cu")
		(net "M_J_ODT<0>")
	)
	(segment
		(start 98.590862 -55.894224)
		(end 98.595688 -55.885588)
		(width 0.0889)
		(layer "In2.Cu")
		(net "M_J_ODT<0>")
	)
	(segment
		(start 98.595688 -56.876188)
		(end 98.602038 -56.86552)
		(width 0.0889)
		(layer "In2.Cu")
		(net "M_J_ODT<0>")
	)
	(segment
		(start 107.460796 0.847852)
		(end 107.460796 1.519936)
		(width 0.14224)
		(layer "In2.Cu")
		(net "M_J_ODT<0>")
	)
	(segment
		(start 98.579178 -58.88609)
		(end 98.595688 -58.857388)
		(width 0.0889)
		(layer "In2.Cu")
		(net "M_J_ODT<0>")
	)
	(segment
		(start 104.398826 -27.455876)
		(end 104.398826 -25.393396)
		(width 0.14224)
		(layer "In2.Cu")
		(net "M_J_ODT<0>")
	)
	(segment
		(start 105.832402 -21.938996)
		(end 105.705402 -21.811996)
		(width 0.14224)
		(layer "In2.Cu")
		(net "M_J_ODT<0>")
	)
	(segment
		(start 105.760774 -8.113014)
		(end 105.75798 -8.11022)
		(width 0.14224)
		(layer "In2.Cu")
		(net "M_J_ODT<0>")
	)
	(segment
		(start 98.595688 -53.904388)
		(end 98.602038 -53.89372)
		(width 0.0889)
		(layer "In2.Cu")
		(net "M_J_ODT<0>")
	)
	(segment
		(start 105.72623 -22.527768)
		(end 105.832402 -22.421596)
		(width 0.14224)
		(layer "In2.Cu")
		(net "M_J_ODT<0>")
	)
	(segment
		(start 98.590862 -52.922424)
		(end 98.983292 -52.241958)
		(width 0.0889)
		(layer "In2.Cu")
		(net "M_J_ODT<0>")
	)
	(segment
		(start 107.198668 -2.7813)
		(end 107.460796 -2.519172)
		(width 0.14224)
		(layer "In2.Cu")
		(net "M_J_ODT<0>")
	)
	(segment
		(start 98.590862 -54.903624)
		(end 98.595688 -54.894988)
		(width 0.0889)
		(layer "In2.Cu")
		(net "M_J_ODT<0>")
	)
	(segment
		(start 100.236528 -31.618174)
		(end 100.521008 -31.33344)
		(width 0.14224)
		(layer "In2.Cu")
		(net "M_J_ODT<0>")
	)
	(segment
		(start 100.236528 -48.327564)
		(end 100.236528 -31.618174)
		(width 0.14224)
		(layer "In2.Cu")
		(net "M_J_ODT<0>")
	)
	(segment
		(start 107.460796 1.519936)
		(end 107.899454 1.958594)
		(width 0.14224)
		(layer "In2.Cu")
		(net "M_J_ODT<0>")
	)
	(segment
		(start 98.595688 -54.894988)
		(end 98.602038 -54.88432)
		(width 0.0889)
		(layer "In2.Cu")
		(net "M_J_ODT<0>")
	)
	(segment
		(start 105.840276 -23.951946)
		(end 105.840276 -23.31847)
		(width 0.14224)
		(layer "In2.Cu")
		(net "M_J_ODT<0>")
	)
	(segment
		(start 100.236528 -48.52035)
		(end 100.236528 -48.327564)
		(width 0.0889)
		(layer "In2.Cu")
		(net "M_J_ODT<0>")
	)
	(segment
		(start 104.398826 -25.393396)
		(end 105.840276 -23.951946)
		(width 0.14224)
		(layer "In2.Cu")
		(net "M_J_ODT<0>")
	)
	(segment
		(start 98.590862 -56.884824)
		(end 98.595688 -56.876188)
		(width 0.0889)
		(layer "In2.Cu")
		(net "M_J_ODT<0>")
	)
	(segment
		(start 105.760774 -19.230594)
		(end 105.760774 -8.113014)
		(width 0.14224)
		(layer "In2.Cu")
		(net "M_J_ODT<0>")
	)
	(segment
		(start 99.388168 -50.977546)
		(end 99.388168 -49.36871)
		(width 0.0889)
		(layer "In2.Cu")
		(net "M_J_ODT<0>")
	)
	(segment
		(start 105.705402 -19.285966)
		(end 105.760774 -19.230594)
		(width 0.14224)
		(layer "In2.Cu")
		(net "M_J_ODT<0>")
	)
	(segment
		(start 105.840276 -23.31847)
		(end 105.72623 -23.204424)
		(width 0.14224)
		(layer "In2.Cu")
		(net "M_J_ODT<0>")
	)
	(segment
		(start 106.88828 -2.7813)
		(end 107.198668 -2.7813)
		(width 0.14224)
		(layer "In2.Cu")
		(net "M_J_ODT<0>")
	)
	(segment
		(start 98.983292 -52.241958)
		(end 98.983292 -51.382422)
		(width 0.0889)
		(layer "In2.Cu")
		(net "M_J_ODT<0>")
	)
	(segment
		(start 98.983292 -51.382422)
		(end 99.388168 -50.977546)
		(width 0.0889)
		(layer "In2.Cu")
		(net "M_J_ODT<0>")
	)
	(segment
		(start 107.899454 1.958594)
		(end 107.899454 2.485644)
		(width 0.14224)
		(layer "In2.Cu")
		(net "M_J_ODT<0>")
	)
	(segment
		(start 105.72623 -23.204424)
		(end 105.72623 -22.527768)
		(width 0.14224)
		(layer "In2.Cu")
		(net "M_J_ODT<0>")
	)
	(segment
		(start 98.590862 -53.913024)
		(end 98.595688 -53.904388)
		(width 0.0889)
		(layer "In2.Cu")
		(net "M_J_ODT<0>")
	)
	(segment
		(start 99.388168 -49.36871)
		(end 100.236528 -48.52035)
		(width 0.0889)
		(layer "In2.Cu")
		(net "M_J_ODT<0>")
	)
	(segment
		(start 98.602038 -58.277506)
		(end 98.595688 -58.266838)
		(width 0.0889)
		(layer "In2.Cu")
		(net "M_J_ODT<0>")
	)
	(segment
		(start 107.566714 0.741934)
		(end 107.460796 0.847852)
		(width 0.14224)
		(layer "In2.Cu")
		(net "M_J_ODT<0>")
	)
	(segment
		(start 105.75798 -6.020816)
		(end 106.63301 -5.145786)
		(width 0.14224)
		(layer "In2.Cu")
		(net "M_J_ODT<0>")
	)
	(segment
		(start 107.460796 -2.519172)
		(end 107.460796 -0.434594)
		(width 0.14224)
		(layer "In2.Cu")
		(net "M_J_ODT<0>")
	)
	(segment
		(start 100.521008 -31.33344)
		(end 104.398826 -27.455876)
		(width 0.14224)
		(layer "In2.Cu")
		(net "M_J_ODT<0>")
	)
	(segment
		(start 106.63301 -5.145786)
		(end 106.63301 -3.795776)
		(width 0.14224)
		(layer "In2.Cu")
		(net "M_J_ODT<0>")
	)
	(segment
		(start 98.083878 -59.55284)
		(end 98.579178 -58.88609)
		(width 0.0889)
		(layer "In2.Cu")
		(net "M_J_ODT<0>")
	)
	(segment
		(start 106.502708 -3.665474)
		(end 106.502708 -3.166872)
		(width 0.14224)
		(layer "In2.Cu")
		(net "M_J_ODT<0>")
	)
	(segment
		(start 105.75798 -8.11022)
		(end 105.75798 -6.020816)
		(width 0.14224)
		(layer "In2.Cu")
		(net "M_J_ODT<0>")
	)
	(segment
		(start 105.705402 -21.811996)
		(end 105.705402 -19.285966)
		(width 0.14224)
		(layer "In2.Cu")
		(net "M_J_ODT<0>")
	)
	(segment
		(start 98.595688 -55.885588)
		(end 98.602038 -55.87492)
		(width 0.0889)
		(layer "In2.Cu")
		(net "M_J_ODT<0>")
	)
	(segment
		(start 105.832402 -22.421596)
		(end 105.832402 -21.938996)
		(width 0.14224)
		(layer "In2.Cu")
		(net "M_J_ODT<0>")
	)
	(segment
		(start 107.566714 -0.328676)
		(end 107.566714 0.741934)
		(width 0.14224)
		(layer "In2.Cu")
		(net "M_J_ODT<0>")
	)
	(segment
		(start 106.63301 -3.795776)
		(end 106.502708 -3.665474)
		(width 0.14224)
		(layer "In2.Cu")
		(net "M_J_ODT<0>")
	)
	(segment
		(start 106.502708 -3.166872)
		(end 106.88828 -2.7813)
		(width 0.14224)
		(layer "In2.Cu")
		(net "M_J_ODT<0>")
	)
	(segment
		(start 107.460796 -0.434594)
		(end 107.566714 -0.328676)
		(width 0.14224)
		(layer "In2.Cu")
		(net "M_J_ODT<0>")
	)
	(arc
		(start 98.602038 -54.88432)
		(mid 98.674836 -54.593557)
		(end 98.595688 -54.304438)
		(width 0.0889)
		(layer "In2.Cu")
		(net "M_J_ODT<0>")
	)
	(arc
		(start 98.595688 -56.285638)
		(mid 98.542218 -56.090575)
		(end 98.590862 -55.894224)
		(width 0.0889)
		(layer "In2.Cu")
		(net "M_J_ODT<0>")
	)
	(arc
		(start 98.595688 -55.295038)
		(mid 98.542218 -55.099975)
		(end 98.590862 -54.903624)
		(width 0.0889)
		(layer "In2.Cu")
		(net "M_J_ODT<0>")
	)
	(arc
		(start 98.595688 -58.857388)
		(mid 98.67491 -58.56827)
		(end 98.602038 -58.277506)
		(width 0.0889)
		(layer "In2.Cu")
		(net "M_J_ODT<0>")
	)
	(arc
		(start 98.602038 -56.86552)
		(mid 98.674836 -56.574757)
		(end 98.595688 -56.285638)
		(width 0.0889)
		(layer "In2.Cu")
		(net "M_J_ODT<0>")
	)
	(arc
		(start 98.602038 -53.89372)
		(mid 98.674836 -53.602957)
		(end 98.595688 -53.313838)
		(width 0.0889)
		(layer "In2.Cu")
		(net "M_J_ODT<0>")
	)
	(arc
		(start 98.595688 -53.313838)
		(mid 98.542218 -53.118775)
		(end 98.590862 -52.922424)
		(width 0.0889)
		(layer "In2.Cu")
		(net "M_J_ODT<0>")
	)
	(arc
		(start 98.595688 -58.266838)
		(mid 98.542189 -58.06694)
		(end 98.595688 -57.867042)
		(width 0.0889)
		(layer "In2.Cu")
		(net "M_J_ODT<0>")
	)
	(arc
		(start 98.595688 -57.867042)
		(mid 98.674819 -57.57164)
		(end 98.595688 -57.276238)
		(width 0.0889)
		(layer "In2.Cu")
		(net "M_J_ODT<0>")
	)
	(arc
		(start 98.602038 -55.87492)
		(mid 98.674836 -55.584157)
		(end 98.595688 -55.295038)
		(width 0.0889)
		(layer "In2.Cu")
		(net "M_J_ODT<0>")
	)
	(arc
		(start 98.595688 -57.276238)
		(mid 98.542218 -57.081175)
		(end 98.590862 -56.884824)
		(width 0.0889)
		(layer "In2.Cu")
		(net "M_J_ODT<0>")
	)
	(arc
		(start 98.595688 -54.304438)
		(mid 98.542218 -54.109375)
		(end 98.590862 -53.913024)
		(width 0.0889)
		(layer "In2.Cu")
		(net "M_J_ODT<0>")
	)
	(segment
		(start 91.787218 -62.52464)
		(end 91.215718 -62.52464)
		(width 0.0889)
		(layer "F.Cu")
		(net "M_J_MA<9>")
	)
	(segment
		(start 84.949538 3.778758)
		(end 84.949538 1.805432)
		(width 0.1651)
		(layer "F.Cu")
		(net "M_J_MA<9>")
	)
	(via
		(at 84.949538 1.805432)
		(size 0.508)
		(drill 0.254)
		(layers "F.Cu" "B.Cu")
		(net "M_J_MA<9>")
	)
	(via
		(at 91.215718 -62.52464)
		(size 0.508)
		(drill 0.254)
		(layers "F.Cu" "B.Cu")
		(net "M_J_MA<9>")
	)
	(via
		(at 84.949538 -4.332478)
		(size 0.4572)
		(drill 0.2032)
		(layers "F.Cu" "B.Cu")
		(net "M_J_MA<9>")
	)
	(segment
		(start 84.949538 -5.621782)
		(end 84.949538 -4.332478)
		(width 0.1651)
		(layer "B.Cu")
		(net "M_J_MA<9>")
	)
	(segment
		(start 84.41182 -2.989072)
		(end 84.41182 -3.4671)
		(width 0.14224)
		(layer "In11.Cu")
		(net "M_J_MA<9>")
	)
	(segment
		(start 84.41182 -3.4671)
		(end 84.949538 -4.004818)
		(width 0.14224)
		(layer "In11.Cu")
		(net "M_J_MA<9>")
	)
	(segment
		(start 84.949538 1.805432)
		(end 84.949538 1.36017)
		(width 0.14224)
		(layer "In11.Cu")
		(net "M_J_MA<9>")
	)
	(segment
		(start 89.634568 -8.7884)
		(end 89.634568 -9.62406)
		(width 0.14224)
		(layer "In11.Cu")
		(net "M_J_MA<9>")
	)
	(segment
		(start 92.671392 -13.4874)
		(end 93.646752 -13.4874)
		(width 0.14224)
		(layer "In11.Cu")
		(net "M_J_MA<9>")
	)
	(segment
		(start 86.868 -4.948682)
		(end 88.790018 -6.8707)
		(width 0.14224)
		(layer "In11.Cu")
		(net "M_J_MA<9>")
	)
	(segment
		(start 84.949538 1.36017)
		(end 84.478368 0.889)
		(width 0.14224)
		(layer "In11.Cu")
		(net "M_J_MA<9>")
	)
	(segment
		(start 92.422472 -51.009296)
		(end 92.326968 -51.1048)
		(width 0.0889)
		(layer "In11.Cu")
		(net "M_J_MA<9>")
	)
	(segment
		(start 84.949538 -4.004818)
		(end 84.949538 -4.332478)
		(width 0.14224)
		(layer "In11.Cu")
		(net "M_J_MA<9>")
	)
	(segment
		(start 84.533994 -2.036826)
		(end 84.533994 -2.866898)
		(width 0.14224)
		(layer "In11.Cu")
		(net "M_J_MA<9>")
	)
	(segment
		(start 92.422472 -50.457354)
		(end 92.422472 -51.009296)
		(width 0.0889)
		(layer "In11.Cu")
		(net "M_J_MA<9>")
	)
	(segment
		(start 93.646752 -13.4874)
		(end 93.927168 -13.767816)
		(width 0.14224)
		(layer "In11.Cu")
		(net "M_J_MA<9>")
	)
	(segment
		(start 89.634568 -9.62406)
		(end 91.336368 -11.32586)
		(width 0.14224)
		(layer "In11.Cu")
		(net "M_J_MA<9>")
	)
	(segment
		(start 91.336368 -11.32586)
		(end 91.336368 -12.152376)
		(width 0.14224)
		(layer "In11.Cu")
		(net "M_J_MA<9>")
	)
	(segment
		(start 92.085414 -60.448444)
		(end 92.084906 -60.447936)
		(width 0.0889)
		(layer "In11.Cu")
		(net "M_J_MA<9>")
	)
	(segment
		(start 84.533994 -2.866898)
		(end 84.41182 -2.989072)
		(width 0.14224)
		(layer "In11.Cu")
		(net "M_J_MA<9>")
	)
	(segment
		(start 93.698568 -19.088354)
		(end 93.698568 -20.509992)
		(width 0.14224)
		(layer "In11.Cu")
		(net "M_J_MA<9>")
	)
	(segment
		(start 93.927168 -13.767816)
		(end 93.927168 -18.859754)
		(width 0.14224)
		(layer "In11.Cu")
		(net "M_J_MA<9>")
	)
	(segment
		(start 92.084906 -60.447936)
		(end 92.056458 -60.447936)
		(width 0.0889)
		(layer "In11.Cu")
		(net "M_J_MA<9>")
	)
	(segment
		(start 92.422472 -25.372822)
		(end 92.422472 -50.457354)
		(width 0.14224)
		(layer "In11.Cu")
		(net "M_J_MA<9>")
	)
	(segment
		(start 94.124018 -23.669244)
		(end 92.422472 -25.372822)
		(width 0.14224)
		(layer "In11.Cu")
		(net "M_J_MA<9>")
	)
	(segment
		(start 92.474542 -52.016152)
		(end 92.474542 -54.10073)
		(width 0.0889)
		(layer "In11.Cu")
		(net "M_J_MA<9>")
	)
	(segment
		(start 92.326968 -51.76139)
		(end 92.474542 -52.016152)
		(width 0.0889)
		(layer "In11.Cu")
		(net "M_J_MA<9>")
	)
	(segment
		(start 88.790018 -7.94385)
		(end 89.634568 -8.7884)
		(width 0.14224)
		(layer "In11.Cu")
		(net "M_J_MA<9>")
	)
	(segment
		(start 93.698568 -20.509992)
		(end 93.927168 -20.738592)
		(width 0.14224)
		(layer "In11.Cu")
		(net "M_J_MA<9>")
	)
	(segment
		(start 85.565742 -4.948682)
		(end 86.868 -4.948682)
		(width 0.14224)
		(layer "In11.Cu")
		(net "M_J_MA<9>")
	)
	(segment
		(start 93.927168 -22.591014)
		(end 94.124018 -22.787864)
		(width 0.14224)
		(layer "In11.Cu")
		(net "M_J_MA<9>")
	)
	(segment
		(start 91.567254 -61.725302)
		(end 91.545156 -61.763656)
		(width 0.0889)
		(layer "In11.Cu")
		(net "M_J_MA<9>")
	)
	(segment
		(start 91.545156 -61.763656)
		(end 91.215718 -62.52464)
		(width 0.0889)
		(layer "In11.Cu")
		(net "M_J_MA<9>")
	)
	(segment
		(start 93.927168 -18.859754)
		(end 93.698568 -19.088354)
		(width 0.14224)
		(layer "In11.Cu")
		(net "M_J_MA<9>")
	)
	(segment
		(start 88.790018 -6.8707)
		(end 88.790018 -7.94385)
		(width 0.14224)
		(layer "In11.Cu")
		(net "M_J_MA<9>")
	)
	(segment
		(start 92.326968 -51.1048)
		(end 92.326968 -51.76139)
		(width 0.0889)
		(layer "In11.Cu")
		(net "M_J_MA<9>")
	)
	(segment
		(start 84.478368 -1.9812)
		(end 84.533994 -2.036826)
		(width 0.14224)
		(layer "In11.Cu")
		(net "M_J_MA<9>")
	)
	(segment
		(start 84.478368 0.889)
		(end 84.478368 -1.9812)
		(width 0.14224)
		(layer "In11.Cu")
		(net "M_J_MA<9>")
	)
	(segment
		(start 91.336368 -12.152376)
		(end 92.671392 -13.4874)
		(width 0.14224)
		(layer "In11.Cu")
		(net "M_J_MA<9>")
	)
	(segment
		(start 93.927168 -20.738592)
		(end 93.927168 -22.591014)
		(width 0.14224)
		(layer "In11.Cu")
		(net "M_J_MA<9>")
	)
	(segment
		(start 94.124018 -22.787864)
		(end 94.124018 -23.669244)
		(width 0.14224)
		(layer "In11.Cu")
		(net "M_J_MA<9>")
	)
	(segment
		(start 84.949538 -4.332478)
		(end 85.565742 -4.948682)
		(width 0.14224)
		(layer "In11.Cu")
		(net "M_J_MA<9>")
	)
	(arc
		(start 92.420948 -59.848496)
		(mid 92.423531 -60.243743)
		(end 92.085414 -60.448444)
		(width 0.0889)
		(layer "In11.Cu")
		(net "M_J_MA<9>")
	)
	(arc
		(start 92.420948 -58.857896)
		(mid 92.474447 -59.057794)
		(end 92.420948 -59.257692)
		(width 0.0889)
		(layer "In11.Cu")
		(net "M_J_MA<9>")
	)
	(arc
		(start 92.420948 -54.895496)
		(mid 92.474447 -55.095394)
		(end 92.420948 -55.295292)
		(width 0.0889)
		(layer "In11.Cu")
		(net "M_J_MA<9>")
	)
	(arc
		(start 92.420948 -58.267092)
		(mid 92.341817 -58.562494)
		(end 92.420948 -58.857896)
		(width 0.0889)
		(layer "In11.Cu")
		(net "M_J_MA<9>")
	)
	(arc
		(start 92.474542 -54.10073)
		(mid 92.46141 -54.206301)
		(end 92.420948 -54.304692)
		(width 0.0889)
		(layer "In11.Cu")
		(net "M_J_MA<9>")
	)
	(arc
		(start 92.420948 -57.276492)
		(mid 92.341817 -57.571894)
		(end 92.420948 -57.867296)
		(width 0.0889)
		(layer "In11.Cu")
		(net "M_J_MA<9>")
	)
	(arc
		(start 92.420948 -56.285892)
		(mid 92.341817 -56.581294)
		(end 92.420948 -56.876696)
		(width 0.0889)
		(layer "In11.Cu")
		(net "M_J_MA<9>")
	)
	(arc
		(start 92.420948 -55.295292)
		(mid 92.341817 -55.590694)
		(end 92.420948 -55.886096)
		(width 0.0889)
		(layer "In11.Cu")
		(net "M_J_MA<9>")
	)
	(arc
		(start 92.420948 -59.257692)
		(mid 92.341817 -59.553094)
		(end 92.420948 -59.848496)
		(width 0.0889)
		(layer "In11.Cu")
		(net "M_J_MA<9>")
	)
	(arc
		(start 92.420948 -55.886096)
		(mid 92.474447 -56.085994)
		(end 92.420948 -56.285892)
		(width 0.0889)
		(layer "In11.Cu")
		(net "M_J_MA<9>")
	)
	(arc
		(start 92.420948 -54.304692)
		(mid 92.341817 -54.600094)
		(end 92.420948 -54.895496)
		(width 0.0889)
		(layer "In11.Cu")
		(net "M_J_MA<9>")
	)
	(arc
		(start 92.056458 -60.447936)
		(mid 91.558207 -60.750776)
		(end 91.562428 -61.333888)
		(width 0.0889)
		(layer "In11.Cu")
		(net "M_J_MA<9>")
	)
	(arc
		(start 91.562428 -61.333888)
		(mid 91.615898 -61.528951)
		(end 91.567254 -61.725302)
		(width 0.0889)
		(layer "In11.Cu")
		(net "M_J_MA<9>")
	)
	(arc
		(start 92.420948 -57.867296)
		(mid 92.474447 -58.067194)
		(end 92.420948 -58.267092)
		(width 0.0889)
		(layer "In11.Cu")
		(net "M_J_MA<9>")
	)
	(arc
		(start 92.420948 -56.876696)
		(mid 92.474447 -57.076594)
		(end 92.420948 -57.276492)
		(width 0.0889)
		(layer "In11.Cu")
		(net "M_J_MA<9>")
	)
	(segment
		(start 86.64956 3.778758)
		(end 86.64956 1.805432)
		(width 0.1651)
		(layer "F.Cu")
		(net "M_J_MA<8>")
	)
	(segment
		(start 90.928698 -61.038486)
		(end 90.357198 -61.038486)
		(width 0.1016)
		(layer "F.Cu")
		(net "M_J_MA<8>")
	)
	(via
		(at 86.64956 -4.332478)
		(size 0.4572)
		(drill 0.2032)
		(layers "F.Cu" "B.Cu")
		(net "M_J_MA<8>")
	)
	(via
		(at 90.357198 -61.038486)
		(size 0.508)
		(drill 0.254)
		(layers "F.Cu" "B.Cu")
		(net "M_J_MA<8>")
	)
	(via
		(at 86.64956 1.805432)
		(size 0.508)
		(drill 0.254)
		(layers "F.Cu" "B.Cu")
		(net "M_J_MA<8>")
	)
	(segment
		(start 86.64956 -5.621782)
		(end 86.64956 -4.332478)
		(width 0.1651)
		(layer "B.Cu")
		(net "M_J_MA<8>")
	)
	(segment
		(start 85.367368 -12.2428)
		(end 85.367368 -8.18007)
		(width 0.14224)
		(layer "In2.Cu")
		(net "M_J_MA<8>")
	)
	(segment
		(start 86.332568 -1.5494)
		(end 86.332568 0.1016)
		(width 0.14224)
		(layer "In2.Cu")
		(net "M_J_MA<8>")
	)
	(segment
		(start 85.37702 -19.194018)
		(end 85.37702 -16.980154)
		(width 0.14224)
		(layer "In2.Cu")
		(net "M_J_MA<8>")
	)
	(segment
		(start 87.200994 -26.60904)
		(end 86.913212 -26.321258)
		(width 0.14224)
		(layer "In2.Cu")
		(net "M_J_MA<8>")
	)
	(segment
		(start 86.19236 0.241808)
		(end 86.19236 0.799592)
		(width 0.14224)
		(layer "In2.Cu")
		(net "M_J_MA<8>")
	)
	(segment
		(start 85.742272 -26.055574)
		(end 86.05139 -25.746456)
		(width 0.14224)
		(layer "In2.Cu")
		(net "M_J_MA<8>")
	)
	(segment
		(start 89.737692 -50.925222)
		(end 89.737692 -30.496002)
		(width 0.14224)
		(layer "In2.Cu")
		(net "M_J_MA<8>")
	)
	(segment
		(start 85.742272 -26.351738)
		(end 85.742272 -26.055574)
		(width 0.14224)
		(layer "In2.Cu")
		(net "M_J_MA<8>")
	)
	(segment
		(start 87.200994 -26.902918)
		(end 87.200994 -26.60904)
		(width 0.14224)
		(layer "In2.Cu")
		(net "M_J_MA<8>")
	)
	(segment
		(start 86.05139 -25.459436)
		(end 85.436964 -24.84501)
		(width 0.14224)
		(layer "In2.Cu")
		(net "M_J_MA<8>")
	)
	(segment
		(start 90.005662 -59.856624)
		(end 90.010488 -59.847988)
		(width 0.0889)
		(layer "In2.Cu")
		(net "M_J_MA<8>")
	)
	(segment
		(start 90.357198 -61.038486)
		(end 90.027252 -60.27674)
		(width 0.0889)
		(layer "In2.Cu")
		(net "M_J_MA<8>")
	)
	(segment
		(start 86.004146 -26.613612)
		(end 85.742272 -26.351738)
		(width 0.14224)
		(layer "In2.Cu")
		(net "M_J_MA<8>")
	)
	(segment
		(start 87.782908 -27.470862)
		(end 87.356442 -27.897328)
		(width 0.14224)
		(layer "In2.Cu")
		(net "M_J_MA<8>")
	)
	(segment
		(start 86.913212 -26.321258)
		(end 86.626446 -26.321258)
		(width 0.14224)
		(layer "In2.Cu")
		(net "M_J_MA<8>")
	)
	(segment
		(start 89.159842 -54.386988)
		(end 89.160096 -54.385718)
		(width 0.0889)
		(layer "In2.Cu")
		(net "M_J_MA<8>")
	)
	(segment
		(start 86.21649 -3.899408)
		(end 86.21649 -1.665478)
		(width 0.14224)
		(layer "In2.Cu")
		(net "M_J_MA<8>")
	)
	(segment
		(start 88.062816 -27.470862)
		(end 87.782908 -27.470862)
		(width 0.14224)
		(layer "In2.Cu")
		(net "M_J_MA<8>")
	)
	(segment
		(start 86.334092 -26.613612)
		(end 86.004146 -26.613612)
		(width 0.14224)
		(layer "In2.Cu")
		(net "M_J_MA<8>")
	)
	(segment
		(start 86.758526 -27.345386)
		(end 87.200994 -26.902918)
		(width 0.14224)
		(layer "In2.Cu")
		(net "M_J_MA<8>")
	)
	(segment
		(start 85.362288 -12.24788)
		(end 85.367368 -12.2428)
		(width 0.14224)
		(layer "In2.Cu")
		(net "M_J_MA<8>")
	)
	(segment
		(start 85.366352 -7.368286)
		(end 85.366352 -6.40207)
		(width 0.14224)
		(layer "In2.Cu")
		(net "M_J_MA<8>")
	)
	(segment
		(start 86.64956 -5.118862)
		(end 86.64956 -4.332478)
		(width 0.14224)
		(layer "In2.Cu")
		(net "M_J_MA<8>")
	)
	(segment
		(start 89.723976 -58.228992)
		(end 89.288112 -57.92089)
		(width 0.0889)
		(layer "In2.Cu")
		(net "M_J_MA<8>")
	)
	(segment
		(start 85.362288 -16.965422)
		(end 85.362288 -12.24788)
		(width 0.14224)
		(layer "In2.Cu")
		(net "M_J_MA<8>")
	)
	(segment
		(start 88.317578 -27.725624)
		(end 88.062816 -27.470862)
		(width 0.14224)
		(layer "In2.Cu")
		(net "M_J_MA<8>")
	)
	(segment
		(start 85.367368 -8.18007)
		(end 85.556852 -7.990586)
		(width 0.14224)
		(layer "In2.Cu")
		(net "M_J_MA<8>")
	)
	(segment
		(start 85.556852 -7.990586)
		(end 85.556852 -7.558786)
		(width 0.14224)
		(layer "In2.Cu")
		(net "M_J_MA<8>")
	)
	(segment
		(start 86.64956 -4.332478)
		(end 86.21649 -3.899408)
		(width 0.14224)
		(layer "In2.Cu")
		(net "M_J_MA<8>")
	)
	(segment
		(start 86.21649 -1.665478)
		(end 86.332568 -1.5494)
		(width 0.14224)
		(layer "In2.Cu")
		(net "M_J_MA<8>")
	)
	(segment
		(start 85.302852 -23.183596)
		(end 85.302852 -22.671024)
		(width 0.14224)
		(layer "In2.Cu")
		(net "M_J_MA<8>")
	)
	(segment
		(start 87.05723 -27.897328)
		(end 86.758526 -27.598624)
		(width 0.14224)
		(layer "In2.Cu")
		(net "M_J_MA<8>")
	)
	(segment
		(start 90.010488 -59.847988)
		(end 90.016838 -59.83732)
		(width 0.0889)
		(layer "In2.Cu")
		(net "M_J_MA<8>")
	)
	(segment
		(start 89.151714 -53.409088)
		(end 89.215468 -53.298598)
		(width 0.0889)
		(layer "In2.Cu")
		(net "M_J_MA<8>")
	)
	(segment
		(start 85.302852 -21.629624)
		(end 85.302852 -19.268186)
		(width 0.14224)
		(layer "In2.Cu")
		(net "M_J_MA<8>")
	)
	(segment
		(start 89.958418 -59.091322)
		(end 89.90965 -58.542936)
		(width 0.0889)
		(layer "In2.Cu")
		(net "M_J_MA<8>")
	)
	(segment
		(start 86.332568 0.1016)
		(end 86.19236 0.241808)
		(width 0.14224)
		(layer "In2.Cu")
		(net "M_J_MA<8>")
	)
	(segment
		(start 85.436964 -23.317708)
		(end 85.302852 -23.183596)
		(width 0.14224)
		(layer "In2.Cu")
		(net "M_J_MA<8>")
	)
	(segment
		(start 89.737692 -30.496002)
		(end 88.317578 -29.075888)
		(width 0.14224)
		(layer "In2.Cu")
		(net "M_J_MA<8>")
	)
	(segment
		(start 89.152222 -54.400196)
		(end 89.159842 -54.386988)
		(width 0.0889)
		(layer "In2.Cu")
		(net "M_J_MA<8>")
	)
	(segment
		(start 90.027252 -60.27674)
		(end 90.010488 -60.248038)
		(width 0.0889)
		(layer "In2.Cu")
		(net "M_J_MA<8>")
	)
	(segment
		(start 86.758526 -27.598624)
		(end 86.758526 -27.345386)
		(width 0.14224)
		(layer "In2.Cu")
		(net "M_J_MA<8>")
	)
	(segment
		(start 85.556852 -7.558786)
		(end 85.366352 -7.368286)
		(width 0.14224)
		(layer "In2.Cu")
		(net "M_J_MA<8>")
	)
	(segment
		(start 85.302852 -22.671024)
		(end 85.487002 -22.486874)
		(width 0.14224)
		(layer "In2.Cu")
		(net "M_J_MA<8>")
	)
	(segment
		(start 86.626446 -26.321258)
		(end 86.334092 -26.613612)
		(width 0.14224)
		(layer "In2.Cu")
		(net "M_J_MA<8>")
	)
	(segment
		(start 85.487002 -21.813774)
		(end 85.302852 -21.629624)
		(width 0.14224)
		(layer "In2.Cu")
		(net "M_J_MA<8>")
	)
	(segment
		(start 88.317578 -29.075888)
		(end 88.317578 -27.725624)
		(width 0.14224)
		(layer "In2.Cu")
		(net "M_J_MA<8>")
	)
	(segment
		(start 85.366352 -6.40207)
		(end 86.64956 -5.118862)
		(width 0.14224)
		(layer "In2.Cu")
		(net "M_J_MA<8>")
	)
	(segment
		(start 89.90965 -58.542936)
		(end 89.879932 -58.422032)
		(width 0.0889)
		(layer "In2.Cu")
		(net "M_J_MA<8>")
	)
	(segment
		(start 86.345268 0.9525)
		(end 86.345268 1.50114)
		(width 0.14224)
		(layer "In2.Cu")
		(net "M_J_MA<8>")
	)
	(segment
		(start 87.356442 -27.897328)
		(end 87.05723 -27.897328)
		(width 0.14224)
		(layer "In2.Cu")
		(net "M_J_MA<8>")
	)
	(segment
		(start 89.152222 -53.809138)
		(end 89.151968 -53.809138)
		(width 0.0889)
		(layer "In2.Cu")
		(net "M_J_MA<8>")
	)
	(segment
		(start 89.879932 -58.422032)
		(end 89.845388 -58.362088)
		(width 0.0889)
		(layer "In2.Cu")
		(net "M_J_MA<8>")
	)
	(segment
		(start 85.436964 -24.84501)
		(end 85.436964 -23.317708)
		(width 0.14224)
		(layer "In2.Cu")
		(net "M_J_MA<8>")
	)
	(segment
		(start 86.345268 1.50114)
		(end 86.64956 1.805432)
		(width 0.14224)
		(layer "In2.Cu")
		(net "M_J_MA<8>")
	)
	(segment
		(start 86.05139 -25.746456)
		(end 86.05139 -25.459436)
		(width 0.14224)
		(layer "In2.Cu")
		(net "M_J_MA<8>")
	)
	(segment
		(start 85.37702 -16.980154)
		(end 85.362288 -16.965422)
		(width 0.14224)
		(layer "In2.Cu")
		(net "M_J_MA<8>")
	)
	(segment
		(start 85.487002 -22.486874)
		(end 85.487002 -21.813774)
		(width 0.14224)
		(layer "In2.Cu")
		(net "M_J_MA<8>")
	)
	(segment
		(start 89.161112 -53.824378)
		(end 89.152222 -53.809138)
		(width 0.0889)
		(layer "In2.Cu")
		(net "M_J_MA<8>")
	)
	(segment
		(start 89.456768 -52.396136)
		(end 89.456768 -51.7144)
		(width 0.0889)
		(layer "In2.Cu")
		(net "M_J_MA<8>")
	)
	(segment
		(start 85.302852 -19.268186)
		(end 85.37702 -19.194018)
		(width 0.14224)
		(layer "In2.Cu")
		(net "M_J_MA<8>")
	)
	(segment
		(start 89.737692 -51.433476)
		(end 89.737692 -50.925222)
		(width 0.0889)
		(layer "In2.Cu")
		(net "M_J_MA<8>")
	)
	(segment
		(start 89.456768 -51.7144)
		(end 89.737692 -51.433476)
		(width 0.0889)
		(layer "In2.Cu")
		(net "M_J_MA<8>")
	)
	(segment
		(start 86.19236 0.799592)
		(end 86.345268 0.9525)
		(width 0.14224)
		(layer "In2.Cu")
		(net "M_J_MA<8>")
	)
	(arc
		(start 90.016838 -59.83732)
		(mid 90.089636 -59.546557)
		(end 90.010488 -59.257438)
		(width 0.0889)
		(layer "In2.Cu")
		(net "M_J_MA<8>")
	)
	(arc
		(start 89.215468 -53.298598)
		(mid 89.395429 -52.863223)
		(end 89.456768 -52.396136)
		(width 0.0889)
		(layer "In2.Cu")
		(net "M_J_MA<8>")
	)
	(arc
		(start 89.152222 -55.790592)
		(mid 89.098689 -55.590694)
		(end 89.152222 -55.390796)
		(width 0.0889)
		(layer "In2.Cu")
		(net "M_J_MA<8>")
	)
	(arc
		(start 89.288112 -57.92089)
		(mid 89.212066 -57.853722)
		(end 89.152222 -57.771792)
		(width 0.0889)
		(layer "In2.Cu")
		(net "M_J_MA<8>")
	)
	(arc
		(start 89.152222 -55.390796)
		(mid 89.231353 -55.095394)
		(end 89.152222 -54.799992)
		(width 0.0889)
		(layer "In2.Cu")
		(net "M_J_MA<8>")
	)
	(arc
		(start 90.010488 -59.257438)
		(mid 89.975311 -59.177246)
		(end 89.958418 -59.091322)
		(width 0.0889)
		(layer "In2.Cu")
		(net "M_J_MA<8>")
	)
	(arc
		(start 89.151968 -53.809138)
		(mid 89.148327 -53.802637)
		(end 89.144602 -53.796184)
		(width 0.0889)
		(layer "In2.Cu")
		(net "M_J_MA<8>")
	)
	(arc
		(start 89.144602 -53.796184)
		(mid 89.098228 -53.601707)
		(end 89.151714 -53.409088)
		(width 0.0889)
		(layer "In2.Cu")
		(net "M_J_MA<8>")
	)
	(arc
		(start 89.160096 -54.385718)
		(mid 89.231527 -54.105167)
		(end 89.161112 -53.824378)
		(width 0.0889)
		(layer "In2.Cu")
		(net "M_J_MA<8>")
	)
	(arc
		(start 89.152222 -56.781192)
		(mid 89.098689 -56.581294)
		(end 89.152222 -56.381396)
		(width 0.0889)
		(layer "In2.Cu")
		(net "M_J_MA<8>")
	)
	(arc
		(start 90.010488 -60.248038)
		(mid 89.957018 -60.052975)
		(end 90.005662 -59.856624)
		(width 0.0889)
		(layer "In2.Cu")
		(net "M_J_MA<8>")
	)
	(arc
		(start 89.152222 -56.381396)
		(mid 89.231353 -56.085994)
		(end 89.152222 -55.790592)
		(width 0.0889)
		(layer "In2.Cu")
		(net "M_J_MA<8>")
	)
	(arc
		(start 89.152222 -57.371996)
		(mid 89.231353 -57.076594)
		(end 89.152222 -56.781192)
		(width 0.0889)
		(layer "In2.Cu")
		(net "M_J_MA<8>")
	)
	(arc
		(start 89.845388 -58.362088)
		(mid 89.791899 -58.28896)
		(end 89.723976 -58.228992)
		(width 0.0889)
		(layer "In2.Cu")
		(net "M_J_MA<8>")
	)
	(arc
		(start 89.152222 -54.799992)
		(mid 89.098689 -54.600094)
		(end 89.152222 -54.400196)
		(width 0.0889)
		(layer "In2.Cu")
		(net "M_J_MA<8>")
	)
	(arc
		(start 89.152222 -57.771792)
		(mid 89.098689 -57.571894)
		(end 89.152222 -57.371996)
		(width 0.0889)
		(layer "In2.Cu")
		(net "M_J_MA<8>")
	)
	(segment
		(start 85.799422 -0.821182)
		(end 85.799422 1.152144)
		(width 0.1651)
		(layer "F.Cu")
		(net "M_J_MA<7>")
	)
	(segment
		(start 90.070178 -61.53404)
		(end 89.498678 -61.53404)
		(width 0.1016)
		(layer "F.Cu")
		(net "M_J_MA<7>")
	)
	(via
		(at 85.799422 -2.314956)
		(size 0.4572)
		(drill 0.2032)
		(layers "F.Cu" "B.Cu")
		(net "M_J_MA<7>")
	)
	(via
		(at 85.799422 1.152144)
		(size 0.508)
		(drill 0.254)
		(layers "F.Cu" "B.Cu")
		(net "M_J_MA<7>")
	)
	(via
		(at 89.498678 -61.53404)
		(size 0.508)
		(drill 0.254)
		(layers "F.Cu" "B.Cu")
		(net "M_J_MA<7>")
	)
	(segment
		(start 85.799422 -1.021842)
		(end 85.799422 -2.314956)
		(width 0.1651)
		(layer "B.Cu")
		(net "M_J_MA<7>")
	)
	(segment
		(start 85.799422 -0.080264)
		(end 85.621368 0.09779)
		(width 0.14224)
		(layer "In2.Cu")
		(net "M_J_MA<7>")
	)
	(segment
		(start 84.529168 -7.472426)
		(end 84.529168 -5.5626)
		(width 0.14224)
		(layer "In2.Cu")
		(net "M_J_MA<7>")
	)
	(segment
		(start 89.828116 -60.773056)
		(end 89.850214 -60.734702)
		(width 0.0889)
		(layer "In2.Cu")
		(net "M_J_MA<7>")
	)
	(segment
		(start 84.541868 -8.599678)
		(end 84.441284 -8.499094)
		(width 0.14224)
		(layer "In2.Cu")
		(net "M_J_MA<7>")
	)
	(segment
		(start 89.845388 -59.752738)
		(end 89.850214 -59.744102)
		(width 0.0889)
		(layer "In2.Cu")
		(net "M_J_MA<7>")
	)
	(segment
		(start 85.644482 -1.586992)
		(end 84.711794 -1.586992)
		(width 0.14224)
		(layer "In2.Cu")
		(net "M_J_MA<7>")
	)
	(segment
		(start 84.442808 -11.524996)
		(end 84.442808 -9.738106)
		(width 0.14224)
		(layer "In2.Cu")
		(net "M_J_MA<7>")
	)
	(segment
		(start 84.556854 -0.949452)
		(end 84.711794 -0.794512)
		(width 0.14224)
		(layer "In2.Cu")
		(net "M_J_MA<7>")
	)
	(segment
		(start 89.177368 -52.603146)
		(end 89.177368 -51.20132)
		(width 0.0889)
		(layer "In2.Cu")
		(net "M_J_MA<7>")
	)
	(segment
		(start 84.529168 -5.5626)
		(end 85.357208 -4.73456)
		(width 0.14224)
		(layer "In2.Cu")
		(net "M_J_MA<7>")
	)
	(segment
		(start 89.098628 -58.563764)
		(end 89.043256 -58.004456)
		(width 0.0889)
		(layer "In2.Cu")
		(net "M_J_MA<7>")
	)
	(segment
		(start 84.442808 -21.888196)
		(end 84.595208 -21.735796)
		(width 0.14224)
		(layer "In2.Cu")
		(net "M_J_MA<7>")
	)
	(segment
		(start 84.45119 -18.309336)
		(end 84.45119 -17.151604)
		(width 0.14224)
		(layer "In2.Cu")
		(net "M_J_MA<7>")
	)
	(segment
		(start 84.40674 -13.283692)
		(end 84.40674 -12.598908)
		(width 0.14224)
		(layer "In2.Cu")
		(net "M_J_MA<7>")
	)
	(segment
		(start 84.532724 -18.39087)
		(end 84.45119 -18.309336)
		(width 0.14224)
		(layer "In2.Cu")
		(net "M_J_MA<7>")
	)
	(segment
		(start 88.986868 -56.876188)
		(end 88.977978 -56.860948)
		(width 0.0889)
		(layer "In2.Cu")
		(net "M_J_MA<7>")
	)
	(segment
		(start 89.839038 -59.763406)
		(end 89.845388 -59.752738)
		(width 0.0889)
		(layer "In2.Cu")
		(net "M_J_MA<7>")
	)
	(segment
		(start 84.711794 -0.794512)
		(end 85.644482 -0.794512)
		(width 0.14224)
		(layer "In2.Cu")
		(net "M_J_MA<7>")
	)
	(segment
		(start 84.534248 -13.4112)
		(end 84.40674 -13.283692)
		(width 0.14224)
		(layer "In2.Cu")
		(net "M_J_MA<7>")
	)
	(segment
		(start 85.357208 -2.75717)
		(end 85.799422 -2.314956)
		(width 0.14224)
		(layer "In2.Cu")
		(net "M_J_MA<7>")
	)
	(segment
		(start 89.498678 -61.53404)
		(end 89.828116 -60.773056)
		(width 0.0889)
		(layer "In2.Cu")
		(net "M_J_MA<7>")
	)
	(segment
		(start 89.799922 -59.273948)
		(end 89.352374 -58.93435)
		(width 0.0889)
		(layer "In2.Cu")
		(net "M_J_MA<7>")
	)
	(segment
		(start 85.799422 -2.314956)
		(end 85.799422 -1.741932)
		(width 0.14224)
		(layer "In2.Cu")
		(net "M_J_MA<7>")
	)
	(segment
		(start 85.621368 0.417576)
		(end 85.214968 0.823976)
		(width 0.14224)
		(layer "In2.Cu")
		(net "M_J_MA<7>")
	)
	(segment
		(start 88.986868 -57.867042)
		(end 88.980518 -57.856374)
		(width 0.0889)
		(layer "In2.Cu")
		(net "M_J_MA<7>")
	)
	(segment
		(start 84.556854 -1.432052)
		(end 84.556854 -0.949452)
		(width 0.14224)
		(layer "In2.Cu")
		(net "M_J_MA<7>")
	)
	(segment
		(start 84.541868 -9.639046)
		(end 84.541868 -8.599678)
		(width 0.14224)
		(layer "In2.Cu")
		(net "M_J_MA<7>")
	)
	(segment
		(start 85.367368 1.3462)
		(end 85.605366 1.3462)
		(width 0.14224)
		(layer "In2.Cu")
		(net "M_J_MA<7>")
	)
	(segment
		(start 89.229692 -51.148996)
		(end 89.229692 -50.843942)
		(width 0.0889)
		(layer "In2.Cu")
		(net "M_J_MA<7>")
	)
	(segment
		(start 85.644482 -0.794512)
		(end 85.799422 -0.639572)
		(width 0.14224)
		(layer "In2.Cu")
		(net "M_J_MA<7>")
	)
	(segment
		(start 85.214968 1.1938)
		(end 85.367368 1.3462)
		(width 0.14224)
		(layer "In2.Cu")
		(net "M_J_MA<7>")
	)
	(segment
		(start 85.799422 -1.741932)
		(end 85.644482 -1.586992)
		(width 0.14224)
		(layer "In2.Cu")
		(net "M_J_MA<7>")
	)
	(segment
		(start 84.595208 -21.735796)
		(end 84.595208 -21.278596)
		(width 0.14224)
		(layer "In2.Cu")
		(net "M_J_MA<7>")
	)
	(segment
		(start 85.605366 1.3462)
		(end 85.799422 1.152144)
		(width 0.14224)
		(layer "In2.Cu")
		(net "M_J_MA<7>")
	)
	(segment
		(start 89.229692 -50.843942)
		(end 89.229692 -30.706568)
		(width 0.14224)
		(layer "In2.Cu")
		(net "M_J_MA<7>")
	)
	(segment
		(start 85.621368 0.09779)
		(end 85.621368 0.417576)
		(width 0.14224)
		(layer "In2.Cu")
		(net "M_J_MA<7>")
	)
	(segment
		(start 84.442808 -9.738106)
		(end 84.541868 -9.639046)
		(width 0.14224)
		(layer "In2.Cu")
		(net "M_J_MA<7>")
	)
	(segment
		(start 84.534248 -17.068546)
		(end 84.534248 -13.4112)
		(width 0.14224)
		(layer "In2.Cu")
		(net "M_J_MA<7>")
	)
	(segment
		(start 84.442808 -23.259796)
		(end 84.595208 -23.107396)
		(width 0.14224)
		(layer "In2.Cu")
		(net "M_J_MA<7>")
	)
	(segment
		(start 84.45119 -17.151604)
		(end 84.534248 -17.068546)
		(width 0.14224)
		(layer "In2.Cu")
		(net "M_J_MA<7>")
	)
	(segment
		(start 84.595208 -23.107396)
		(end 84.595208 -22.599396)
		(width 0.14224)
		(layer "In2.Cu")
		(net "M_J_MA<7>")
	)
	(segment
		(start 84.711794 -1.586992)
		(end 84.556854 -1.432052)
		(width 0.14224)
		(layer "In2.Cu")
		(net "M_J_MA<7>")
	)
	(segment
		(start 89.177368 -51.20132)
		(end 89.229692 -51.148996)
		(width 0.0889)
		(layer "In2.Cu")
		(net "M_J_MA<7>")
	)
	(segment
		(start 85.799422 -0.639572)
		(end 85.799422 -0.080264)
		(width 0.14224)
		(layer "In2.Cu")
		(net "M_J_MA<7>")
	)
	(segment
		(start 84.595208 -22.599396)
		(end 84.442808 -22.446996)
		(width 0.14224)
		(layer "In2.Cu")
		(net "M_J_MA<7>")
	)
	(segment
		(start 85.357208 -4.73456)
		(end 85.357208 -2.75717)
		(width 0.14224)
		(layer "In2.Cu")
		(net "M_J_MA<7>")
	)
	(segment
		(start 88.986868 -53.904388)
		(end 88.977978 -53.889148)
		(width 0.0889)
		(layer "In2.Cu")
		(net "M_J_MA<7>")
	)
	(segment
		(start 84.441284 -8.499094)
		(end 84.441284 -7.56031)
		(width 0.14224)
		(layer "In2.Cu")
		(net "M_J_MA<7>")
	)
	(segment
		(start 88.986868 -54.894988)
		(end 88.977978 -54.879748)
		(width 0.0889)
		(layer "In2.Cu")
		(net "M_J_MA<7>")
	)
	(segment
		(start 84.442808 -22.446996)
		(end 84.442808 -21.888196)
		(width 0.14224)
		(layer "In2.Cu")
		(net "M_J_MA<7>")
	)
	(segment
		(start 89.845388 -59.352688)
		(end 89.799922 -59.273948)
		(width 0.0889)
		(layer "In2.Cu")
		(net "M_J_MA<7>")
	)
	(segment
		(start 89.043256 -58.004456)
		(end 89.01557 -57.928002)
		(width 0.0889)
		(layer "In2.Cu")
		(net "M_J_MA<7>")
	)
	(segment
		(start 85.291168 -25.603454)
		(end 84.442808 -24.755094)
		(width 0.14224)
		(layer "In2.Cu")
		(net "M_J_MA<7>")
	)
	(segment
		(start 84.40674 -12.598908)
		(end 84.534248 -12.4714)
		(width 0.14224)
		(layer "In2.Cu")
		(net "M_J_MA<7>")
	)
	(segment
		(start 85.214968 0.823976)
		(end 85.214968 1.1938)
		(width 0.14224)
		(layer "In2.Cu")
		(net "M_J_MA<7>")
	)
	(segment
		(start 88.986868 -55.885588)
		(end 88.977978 -55.870348)
		(width 0.0889)
		(layer "In2.Cu")
		(net "M_J_MA<7>")
	)
	(segment
		(start 85.291168 -26.768044)
		(end 85.291168 -25.603454)
		(width 0.14224)
		(layer "In2.Cu")
		(net "M_J_MA<7>")
	)
	(segment
		(start 89.229692 -30.706568)
		(end 85.291168 -26.768044)
		(width 0.14224)
		(layer "In2.Cu")
		(net "M_J_MA<7>")
	)
	(segment
		(start 84.441284 -7.56031)
		(end 84.529168 -7.472426)
		(width 0.14224)
		(layer "In2.Cu")
		(net "M_J_MA<7>")
	)
	(segment
		(start 84.595208 -21.278596)
		(end 84.532724 -21.216112)
		(width 0.14224)
		(layer "In2.Cu")
		(net "M_J_MA<7>")
	)
	(segment
		(start 84.534248 -12.4714)
		(end 84.534248 -11.616436)
		(width 0.14224)
		(layer "In2.Cu")
		(net "M_J_MA<7>")
	)
	(segment
		(start 84.442808 -24.755094)
		(end 84.442808 -23.259796)
		(width 0.14224)
		(layer "In2.Cu")
		(net "M_J_MA<7>")
	)
	(segment
		(start 84.534248 -11.616436)
		(end 84.442808 -11.524996)
		(width 0.14224)
		(layer "In2.Cu")
		(net "M_J_MA<7>")
	)
	(segment
		(start 84.532724 -21.216112)
		(end 84.532724 -18.39087)
		(width 0.14224)
		(layer "In2.Cu")
		(net "M_J_MA<7>")
	)
	(arc
		(start 89.845388 -60.343288)
		(mid 89.766166 -60.05417)
		(end 89.839038 -59.763406)
		(width 0.0889)
		(layer "In2.Cu")
		(net "M_J_MA<7>")
	)
	(arc
		(start 88.977978 -54.879748)
		(mid 88.907581 -54.590797)
		(end 88.986868 -54.304184)
		(width 0.0889)
		(layer "In2.Cu")
		(net "M_J_MA<7>")
	)
	(arc
		(start 88.980518 -57.856374)
		(mid 88.907598 -57.565357)
		(end 88.986868 -57.275984)
		(width 0.0889)
		(layer "In2.Cu")
		(net "M_J_MA<7>")
	)
	(arc
		(start 88.986868 -56.285384)
		(mid 89.040401 -56.085486)
		(end 88.986868 -55.885588)
		(width 0.0889)
		(layer "In2.Cu")
		(net "M_J_MA<7>")
	)
	(arc
		(start 88.986868 -54.304184)
		(mid 89.040401 -54.104286)
		(end 88.986868 -53.904388)
		(width 0.0889)
		(layer "In2.Cu")
		(net "M_J_MA<7>")
	)
	(arc
		(start 88.977978 -53.889148)
		(mid 88.907581 -53.600197)
		(end 88.986868 -53.313584)
		(width 0.0889)
		(layer "In2.Cu")
		(net "M_J_MA<7>")
	)
	(arc
		(start 89.850214 -60.734702)
		(mid 89.898969 -60.53835)
		(end 89.845388 -60.343288)
		(width 0.0889)
		(layer "In2.Cu")
		(net "M_J_MA<7>")
	)
	(arc
		(start 88.977978 -56.860948)
		(mid 88.907581 -56.571997)
		(end 88.986868 -56.285384)
		(width 0.0889)
		(layer "In2.Cu")
		(net "M_J_MA<7>")
	)
	(arc
		(start 89.352374 -58.93435)
		(mid 89.16858 -58.788028)
		(end 89.098628 -58.563764)
		(width 0.0889)
		(layer "In2.Cu")
		(net "M_J_MA<7>")
	)
	(arc
		(start 88.977978 -55.870348)
		(mid 88.907581 -55.581397)
		(end 88.986868 -55.294784)
		(width 0.0889)
		(layer "In2.Cu")
		(net "M_J_MA<7>")
	)
	(arc
		(start 88.986868 -55.294784)
		(mid 89.040401 -55.094886)
		(end 88.986868 -54.894988)
		(width 0.0889)
		(layer "In2.Cu")
		(net "M_J_MA<7>")
	)
	(arc
		(start 89.850214 -59.744102)
		(mid 89.898969 -59.54775)
		(end 89.845388 -59.352688)
		(width 0.0889)
		(layer "In2.Cu")
		(net "M_J_MA<7>")
	)
	(arc
		(start 89.01557 -57.928002)
		(mid 89.002511 -57.896913)
		(end 88.986868 -57.867042)
		(width 0.0889)
		(layer "In2.Cu")
		(net "M_J_MA<7>")
	)
	(arc
		(start 88.986868 -57.275984)
		(mid 89.040401 -57.076086)
		(end 88.986868 -56.876188)
		(width 0.0889)
		(layer "In2.Cu")
		(net "M_J_MA<7>")
	)
	(arc
		(start 88.986868 -53.313584)
		(mid 89.128878 -52.970907)
		(end 89.177368 -52.603146)
		(width 0.0889)
		(layer "In2.Cu")
		(net "M_J_MA<7>")
	)
	(segment
		(start 90.928698 -60.047886)
		(end 90.357198 -60.047886)
		(width 0.1016)
		(layer "F.Cu")
		(net "M_J_MA<6>")
	)
	(segment
		(start 87.499444 3.778758)
		(end 87.499444 2.485644)
		(width 0.1651)
		(layer "F.Cu")
		(net "M_J_MA<6>")
	)
	(via
		(at 90.357198 -60.047886)
		(size 0.508)
		(drill 0.254)
		(layers "F.Cu" "B.Cu")
		(net "M_J_MA<6>")
	)
	(via
		(at 87.499444 -4.332478)
		(size 0.4572)
		(drill 0.2032)
		(layers "F.Cu" "B.Cu")
		(net "M_J_MA<6>")
	)
	(via
		(at 87.499444 2.485644)
		(size 0.508)
		(drill 0.254)
		(layers "F.Cu" "B.Cu")
		(net "M_J_MA<6>")
	)
	(segment
		(start 87.499444 -5.621782)
		(end 87.499444 -4.332478)
		(width 0.1651)
		(layer "B.Cu")
		(net "M_J_MA<6>")
	)
	(segment
		(start 87.119968 0.27432)
		(end 87.119968 0.7874)
		(width 0.14224)
		(layer "In2.Cu")
		(net "M_J_MA<6>")
	)
	(segment
		(start 89.839038 -53.819806)
		(end 89.845388 -53.809138)
		(width 0.0889)
		(layer "In2.Cu")
		(net "M_J_MA<6>")
	)
	(segment
		(start 89.957148 -58.076592)
		(end 89.941908 -57.923938)
		(width 0.0889)
		(layer "In2.Cu")
		(net "M_J_MA<6>")
	)
	(segment
		(start 86.344252 -23.132796)
		(end 86.344252 -22.599396)
		(width 0.14224)
		(layer "In2.Cu")
		(net "M_J_MA<6>")
	)
	(segment
		(start 86.166452 -21.938996)
		(end 86.293452 -21.811996)
		(width 0.14224)
		(layer "In2.Cu")
		(net "M_J_MA<6>")
	)
	(segment
		(start 90.245692 -48.44415)
		(end 90.245692 -30.285436)
		(width 0.14224)
		(layer "In2.Cu")
		(net "M_J_MA<6>")
	)
	(segment
		(start 90.245692 -51.281076)
		(end 90.245692 -48.44415)
		(width 0.0889)
		(layer "In2.Cu")
		(net "M_J_MA<6>")
	)
	(segment
		(start 86.207092 -8.082026)
		(end 86.24189 -8.047228)
		(width 0.14224)
		(layer "In2.Cu")
		(net "M_J_MA<6>")
	)
	(segment
		(start 87.119968 0.7874)
		(end 87.037164 0.870204)
		(width 0.14224)
		(layer "In2.Cu")
		(net "M_J_MA<6>")
	)
	(segment
		(start 86.158578 -24.848058)
		(end 86.158578 -23.31847)
		(width 0.14224)
		(layer "In2.Cu")
		(net "M_J_MA<6>")
	)
	(segment
		(start 89.845388 -55.790338)
		(end 89.850214 -55.781702)
		(width 0.0889)
		(layer "In2.Cu")
		(net "M_J_MA<6>")
	)
	(segment
		(start 86.208108 -11.062462)
		(end 86.207092 -11.061446)
		(width 0.14224)
		(layer "In2.Cu")
		(net "M_J_MA<6>")
	)
	(segment
		(start 89.73566 -51.791108)
		(end 90.245692 -51.281076)
		(width 0.0889)
		(layer "In2.Cu")
		(net "M_J_MA<6>")
	)
	(segment
		(start 87.087202 -3.337052)
		(end 87.087202 -2.090674)
		(width 0.14224)
		(layer "In2.Cu")
		(net "M_J_MA<6>")
	)
	(segment
		(start 87.037164 1.369568)
		(end 87.499444 2.485644)
		(width 0.14224)
		(layer "In2.Cu")
		(net "M_J_MA<6>")
	)
	(segment
		(start 90.245692 -30.285436)
		(end 88.825578 -28.865322)
		(width 0.14224)
		(layer "In2.Cu")
		(net "M_J_MA<6>")
	)
	(segment
		(start 89.845388 -53.409342)
		(end 89.73566 -53.21935)
		(width 0.0889)
		(layer "In2.Cu")
		(net "M_J_MA<6>")
	)
	(segment
		(start 87.087202 -2.090674)
		(end 86.899242 -1.902714)
		(width 0.14224)
		(layer "In2.Cu")
		(net "M_J_MA<6>")
	)
	(segment
		(start 86.20887 -20.649438)
		(end 86.20887 -17.769586)
		(width 0.14224)
		(layer "In2.Cu")
		(net "M_J_MA<6>")
	)
	(segment
		(start 90.051636 -58.338212)
		(end 90.010488 -58.266838)
		(width 0.0889)
		(layer "In2.Cu")
		(net "M_J_MA<6>")
	)
	(segment
		(start 90.54973 -58.706512)
		(end 90.22334 -58.494422)
		(width 0.0889)
		(layer "In2.Cu")
		(net "M_J_MA<6>")
	)
	(segment
		(start 89.839038 -56.791606)
		(end 89.845388 -56.780938)
		(width 0.0889)
		(layer "In2.Cu")
		(net "M_J_MA<6>")
	)
	(segment
		(start 89.839038 -55.801006)
		(end 89.845388 -55.790338)
		(width 0.0889)
		(layer "In2.Cu")
		(net "M_J_MA<6>")
	)
	(segment
		(start 87.499444 -5.030724)
		(end 87.499444 -4.332478)
		(width 0.14224)
		(layer "In2.Cu")
		(net "M_J_MA<6>")
	)
	(segment
		(start 86.20887 -17.769586)
		(end 86.236048 -17.742408)
		(width 0.14224)
		(layer "In2.Cu")
		(net "M_J_MA<6>")
	)
	(segment
		(start 86.24189 -6.288278)
		(end 87.499444 -5.030724)
		(width 0.14224)
		(layer "In2.Cu")
		(net "M_J_MA<6>")
	)
	(segment
		(start 86.208108 -12.862052)
		(end 86.208108 -11.062462)
		(width 0.14224)
		(layer "In2.Cu")
		(net "M_J_MA<6>")
	)
	(segment
		(start 90.687144 -59.28614)
		(end 90.703908 -59.257438)
		(width 0.0889)
		(layer "In2.Cu")
		(net "M_J_MA<6>")
	)
	(segment
		(start 87.037164 0.870204)
		(end 87.037164 1.369568)
		(width 0.14224)
		(layer "In2.Cu")
		(net "M_J_MA<6>")
	)
	(segment
		(start 89.941908 -57.923938)
		(end 89.898728 -57.580784)
		(width 0.0889)
		(layer "In2.Cu")
		(net "M_J_MA<6>")
	)
	(segment
		(start 86.158578 -23.31847)
		(end 86.344252 -23.132796)
		(width 0.14224)
		(layer "In2.Cu")
		(net "M_J_MA<6>")
	)
	(segment
		(start 88.825578 -27.515058)
		(end 86.158578 -24.848058)
		(width 0.14224)
		(layer "In2.Cu")
		(net "M_J_MA<6>")
	)
	(segment
		(start 86.236048 -17.742408)
		(end 86.236048 -12.889992)
		(width 0.14224)
		(layer "In2.Cu")
		(net "M_J_MA<6>")
	)
	(segment
		(start 86.293452 -21.811996)
		(end 86.293452 -20.73402)
		(width 0.14224)
		(layer "In2.Cu")
		(net "M_J_MA<6>")
	)
	(segment
		(start 86.24189 -8.047228)
		(end 86.24189 -6.288278)
		(width 0.14224)
		(layer "In2.Cu")
		(net "M_J_MA<6>")
	)
	(segment
		(start 90.357198 -60.047886)
		(end 90.687144 -59.28614)
		(width 0.0889)
		(layer "In2.Cu")
		(net "M_J_MA<6>")
	)
	(segment
		(start 86.166452 -22.421596)
		(end 86.166452 -21.938996)
		(width 0.14224)
		(layer "In2.Cu")
		(net "M_J_MA<6>")
	)
	(segment
		(start 89.839038 -54.810406)
		(end 89.845388 -54.799738)
		(width 0.0889)
		(layer "In2.Cu")
		(net "M_J_MA<6>")
	)
	(segment
		(start 89.845388 -53.809138)
		(end 89.850214 -53.800502)
		(width 0.0889)
		(layer "In2.Cu")
		(net "M_J_MA<6>")
	)
	(segment
		(start 86.899242 -1.902714)
		(end 86.899242 0.053594)
		(width 0.14224)
		(layer "In2.Cu")
		(net "M_J_MA<6>")
	)
	(segment
		(start 86.236048 -12.889992)
		(end 86.208108 -12.862052)
		(width 0.14224)
		(layer "In2.Cu")
		(net "M_J_MA<6>")
	)
	(segment
		(start 89.845388 -56.780938)
		(end 89.850214 -56.772302)
		(width 0.0889)
		(layer "In2.Cu")
		(net "M_J_MA<6>")
	)
	(segment
		(start 86.293452 -20.73402)
		(end 86.20887 -20.649438)
		(width 0.14224)
		(layer "In2.Cu")
		(net "M_J_MA<6>")
	)
	(segment
		(start 89.73566 -53.21935)
		(end 89.73566 -51.791108)
		(width 0.0889)
		(layer "In2.Cu")
		(net "M_J_MA<6>")
	)
	(segment
		(start 89.845388 -54.799738)
		(end 89.850214 -54.791102)
		(width 0.0889)
		(layer "In2.Cu")
		(net "M_J_MA<6>")
	)
	(segment
		(start 88.825578 -28.865322)
		(end 88.825578 -27.515058)
		(width 0.14224)
		(layer "In2.Cu")
		(net "M_J_MA<6>")
	)
	(segment
		(start 90.22334 -58.494422)
		(end 90.051636 -58.338212)
		(width 0.0889)
		(layer "In2.Cu")
		(net "M_J_MA<6>")
	)
	(segment
		(start 87.499444 -4.332478)
		(end 87.087202 -3.337052)
		(width 0.14224)
		(layer "In2.Cu")
		(net "M_J_MA<6>")
	)
	(segment
		(start 86.344252 -22.599396)
		(end 86.166452 -22.421596)
		(width 0.14224)
		(layer "In2.Cu")
		(net "M_J_MA<6>")
	)
	(segment
		(start 86.207092 -11.061446)
		(end 86.207092 -8.082026)
		(width 0.14224)
		(layer "In2.Cu")
		(net "M_J_MA<6>")
	)
	(segment
		(start 86.899242 0.053594)
		(end 87.119968 0.27432)
		(width 0.14224)
		(layer "In2.Cu")
		(net "M_J_MA<6>")
	)
	(arc
		(start 89.850214 -55.781702)
		(mid 89.898969 -55.58535)
		(end 89.845388 -55.390288)
		(width 0.0889)
		(layer "In2.Cu")
		(net "M_J_MA<6>")
	)
	(arc
		(start 90.703908 -59.257438)
		(mid 90.742579 -58.949613)
		(end 90.54973 -58.706512)
		(width 0.0889)
		(layer "In2.Cu")
		(net "M_J_MA<6>")
	)
	(arc
		(start 89.845388 -54.399688)
		(mid 89.766166 -54.11057)
		(end 89.839038 -53.819806)
		(width 0.0889)
		(layer "In2.Cu")
		(net "M_J_MA<6>")
	)
	(arc
		(start 89.898728 -57.580784)
		(mid 89.886422 -57.472479)
		(end 89.845388 -57.371488)
		(width 0.0889)
		(layer "In2.Cu")
		(net "M_J_MA<6>")
	)
	(arc
		(start 89.845388 -57.371488)
		(mid 89.766166 -57.08237)
		(end 89.839038 -56.791606)
		(width 0.0889)
		(layer "In2.Cu")
		(net "M_J_MA<6>")
	)
	(arc
		(start 89.845388 -56.380888)
		(mid 89.766166 -56.09177)
		(end 89.839038 -55.801006)
		(width 0.0889)
		(layer "In2.Cu")
		(net "M_J_MA<6>")
	)
	(arc
		(start 89.850214 -54.791102)
		(mid 89.898969 -54.59475)
		(end 89.845388 -54.399688)
		(width 0.0889)
		(layer "In2.Cu")
		(net "M_J_MA<6>")
	)
	(arc
		(start 90.010488 -58.266838)
		(mid 89.971871 -58.175062)
		(end 89.957148 -58.076592)
		(width 0.0889)
		(layer "In2.Cu")
		(net "M_J_MA<6>")
	)
	(arc
		(start 89.850214 -56.772302)
		(mid 89.898969 -56.57595)
		(end 89.845388 -56.380888)
		(width 0.0889)
		(layer "In2.Cu")
		(net "M_J_MA<6>")
	)
	(arc
		(start 89.850214 -53.800502)
		(mid 89.898846 -53.604294)
		(end 89.845388 -53.409342)
		(width 0.0889)
		(layer "In2.Cu")
		(net "M_J_MA<6>")
	)
	(arc
		(start 89.845388 -55.390288)
		(mid 89.766166 -55.10117)
		(end 89.839038 -54.810406)
		(width 0.0889)
		(layer "In2.Cu")
		(net "M_J_MA<6>")
	)
	(segment
		(start 87.499444 -0.821182)
		(end 87.499444 1.152144)
		(width 0.1651)
		(layer "F.Cu")
		(net "M_J_MA<5>")
	)
	(segment
		(start 90.928698 -58.06694)
		(end 90.357198 -58.06694)
		(width 0.1016)
		(layer "F.Cu")
		(net "M_J_MA<5>")
	)
	(via
		(at 90.357198 -58.06694)
		(size 0.508)
		(drill 0.254)
		(layers "F.Cu" "B.Cu")
		(net "M_J_MA<5>")
	)
	(via
		(at 87.499444 -2.316988)
		(size 0.4572)
		(drill 0.2032)
		(layers "F.Cu" "B.Cu")
		(net "M_J_MA<5>")
	)
	(via
		(at 87.499444 1.152144)
		(size 0.508)
		(drill 0.254)
		(layers "F.Cu" "B.Cu")
		(net "M_J_MA<5>")
	)
	(segment
		(start 87.499444 -1.021842)
		(end 87.499444 -2.316988)
		(width 0.1651)
		(layer "B.Cu")
		(net "M_J_MA<5>")
	)
	(segment
		(start 87.457788 -0.583946)
		(end 87.312754 -0.438912)
		(width 0.14224)
		(layer "In2.Cu")
		(net "M_J_MA<5>")
	)
	(segment
		(start 87.076788 -18.451322)
		(end 87.076788 -12.87526)
		(width 0.14224)
		(layer "In2.Cu")
		(net "M_J_MA<5>")
	)
	(segment
		(start 87.091774 -12.860274)
		(end 87.091774 -6.200394)
		(width 0.14224)
		(layer "In2.Cu")
		(net "M_J_MA<5>")
	)
	(segment
		(start 87.313008 -1.544828)
		(end 87.313008 -1.293368)
		(width 0.14224)
		(layer "In2.Cu")
		(net "M_J_MA<5>")
	)
	(segment
		(start 87.499444 -2.316988)
		(end 87.714328 -2.316988)
		(width 0.14224)
		(layer "In2.Cu")
		(net "M_J_MA<5>")
	)
	(segment
		(start 90.005662 -54.903624)
		(end 90.010488 -54.894988)
		(width 0.0889)
		(layer "In2.Cu")
		(net "M_J_MA<5>")
	)
	(segment
		(start 86.979252 -22.573996)
		(end 87.157052 -22.396196)
		(width 0.14224)
		(layer "In2.Cu")
		(net "M_J_MA<5>")
	)
	(segment
		(start 87.46109 -1.145286)
		(end 87.74684 -1.145286)
		(width 0.14224)
		(layer "In2.Cu")
		(net "M_J_MA<5>")
	)
	(segment
		(start 87.313008 -1.293368)
		(end 87.46109 -1.145286)
		(width 0.14224)
		(layer "In2.Cu")
		(net "M_J_MA<5>")
	)
	(segment
		(start 87.90178 -0.990346)
		(end 87.90178 -0.738886)
		(width 0.14224)
		(layer "In2.Cu")
		(net "M_J_MA<5>")
	)
	(segment
		(start 90.010488 -53.313838)
		(end 89.939368 -53.190648)
		(width 0.0889)
		(layer "In2.Cu")
		(net "M_J_MA<5>")
	)
	(segment
		(start 90.753692 -48.55845)
		(end 90.753692 -29.00553)
		(width 0.14224)
		(layer "In2.Cu")
		(net "M_J_MA<5>")
	)
	(segment
		(start 87.911432 0.681228)
		(end 88.201246 0.971042)
		(width 0.14224)
		(layer "In2.Cu")
		(net "M_J_MA<5>")
	)
	(segment
		(start 87.157052 -23.285196)
		(end 86.979252 -23.107396)
		(width 0.14224)
		(layer "In2.Cu")
		(net "M_J_MA<5>")
	)
	(segment
		(start 87.686642 -1.706626)
		(end 87.474806 -1.706626)
		(width 0.14224)
		(layer "In2.Cu")
		(net "M_J_MA<5>")
	)
	(segment
		(start 90.460576 -28.712414)
		(end 89.713308 -28.712414)
		(width 0.14224)
		(layer "In2.Cu")
		(net "M_J_MA<5>")
	)
	(segment
		(start 87.312754 -0.438912)
		(end 87.312754 -0.187452)
		(width 0.14224)
		(layer "In2.Cu")
		(net "M_J_MA<5>")
	)
	(segment
		(start 90.357198 -58.06694)
		(end 90.154252 -57.52465)
		(width 0.0889)
		(layer "In2.Cu")
		(net "M_J_MA<5>")
	)
	(segment
		(start 87.157052 -21.913596)
		(end 87.004652 -21.761196)
		(width 0.14224)
		(layer "In2.Cu")
		(net "M_J_MA<5>")
	)
	(segment
		(start 90.010488 -53.904388)
		(end 90.016838 -53.89372)
		(width 0.0889)
		(layer "In2.Cu")
		(net "M_J_MA<5>")
	)
	(segment
		(start 87.004652 -21.761196)
		(end 87.004652 -19.141186)
		(width 0.14224)
		(layer "In2.Cu")
		(net "M_J_MA<5>")
	)
	(segment
		(start 86.979252 -23.107396)
		(end 86.979252 -22.573996)
		(width 0.14224)
		(layer "In2.Cu")
		(net "M_J_MA<5>")
	)
	(segment
		(start 89.478612 -28.477718)
		(end 89.478612 -27.449526)
		(width 0.14224)
		(layer "In2.Cu")
		(net "M_J_MA<5>")
	)
	(segment
		(start 90.005662 -56.884824)
		(end 90.010488 -56.876188)
		(width 0.0889)
		(layer "In2.Cu")
		(net "M_J_MA<5>")
	)
	(segment
		(start 90.005662 -55.894224)
		(end 90.010488 -55.885588)
		(width 0.0889)
		(layer "In2.Cu")
		(net "M_J_MA<5>")
	)
	(segment
		(start 87.714328 -2.316988)
		(end 87.841582 -2.189734)
		(width 0.14224)
		(layer "In2.Cu")
		(net "M_J_MA<5>")
	)
	(segment
		(start 87.4776 -0.022606)
		(end 87.728298 -0.022606)
		(width 0.14224)
		(layer "In2.Cu")
		(net "M_J_MA<5>")
	)
	(segment
		(start 87.312754 -0.187452)
		(end 87.4776 -0.022606)
		(width 0.14224)
		(layer "In2.Cu")
		(net "M_J_MA<5>")
	)
	(segment
		(start 90.525092 -48.943514)
		(end 90.753692 -48.714914)
		(width 0.0889)
		(layer "In2.Cu")
		(net "M_J_MA<5>")
	)
	(segment
		(start 87.74684 -0.583946)
		(end 87.457788 -0.583946)
		(width 0.14224)
		(layer "In2.Cu")
		(net "M_J_MA<5>")
	)
	(segment
		(start 87.780368 1.433068)
		(end 87.499444 1.152144)
		(width 0.14224)
		(layer "In2.Cu")
		(net "M_J_MA<5>")
	)
	(segment
		(start 87.474806 -1.706626)
		(end 87.313008 -1.544828)
		(width 0.14224)
		(layer "In2.Cu")
		(net "M_J_MA<5>")
	)
	(segment
		(start 89.939368 -53.190648)
		(end 89.939368 -51.9176)
		(width 0.0889)
		(layer "In2.Cu")
		(net "M_J_MA<5>")
	)
	(segment
		(start 90.753692 -48.714914)
		(end 90.753692 -48.55845)
		(width 0.0889)
		(layer "In2.Cu")
		(net "M_J_MA<5>")
	)
	(segment
		(start 87.157052 -25.127966)
		(end 87.157052 -23.285196)
		(width 0.14224)
		(layer "In2.Cu")
		(net "M_J_MA<5>")
	)
	(segment
		(start 87.911432 0.160528)
		(end 87.911432 0.681228)
		(width 0.14224)
		(layer "In2.Cu")
		(net "M_J_MA<5>")
	)
	(segment
		(start 90.010488 -55.885588)
		(end 90.016838 -55.87492)
		(width 0.0889)
		(layer "In2.Cu")
		(net "M_J_MA<5>")
	)
	(segment
		(start 87.499444 -3.043428)
		(end 87.499444 -2.316988)
		(width 0.14224)
		(layer "In2.Cu")
		(net "M_J_MA<5>")
	)
	(segment
		(start 87.076788 -12.87526)
		(end 87.091774 -12.860274)
		(width 0.14224)
		(layer "In2.Cu")
		(net "M_J_MA<5>")
	)
	(segment
		(start 87.841582 -2.189734)
		(end 87.841582 -1.861566)
		(width 0.14224)
		(layer "In2.Cu")
		(net "M_J_MA<5>")
	)
	(segment
		(start 87.091774 -6.200394)
		(end 87.914734 -5.377434)
		(width 0.14224)
		(layer "In2.Cu")
		(net "M_J_MA<5>")
	)
	(segment
		(start 90.010488 -56.876188)
		(end 90.016838 -56.86552)
		(width 0.0889)
		(layer "In2.Cu")
		(net "M_J_MA<5>")
	)
	(segment
		(start 87.004652 -19.141186)
		(end 87.086948 -19.05889)
		(width 0.14224)
		(layer "In2.Cu")
		(net "M_J_MA<5>")
	)
	(segment
		(start 87.157052 -22.396196)
		(end 87.157052 -21.913596)
		(width 0.14224)
		(layer "In2.Cu")
		(net "M_J_MA<5>")
	)
	(segment
		(start 90.525092 -51.331876)
		(end 90.525092 -48.943514)
		(width 0.0889)
		(layer "In2.Cu")
		(net "M_J_MA<5>")
	)
	(segment
		(start 87.728298 -0.022606)
		(end 87.911432 0.160528)
		(width 0.14224)
		(layer "In2.Cu")
		(net "M_J_MA<5>")
	)
	(segment
		(start 89.713308 -28.712414)
		(end 89.478612 -28.477718)
		(width 0.14224)
		(layer "In2.Cu")
		(net "M_J_MA<5>")
	)
	(segment
		(start 87.99195 1.433068)
		(end 87.780368 1.433068)
		(width 0.14224)
		(layer "In2.Cu")
		(net "M_J_MA<5>")
	)
	(segment
		(start 88.201246 1.223772)
		(end 87.99195 1.433068)
		(width 0.14224)
		(layer "In2.Cu")
		(net "M_J_MA<5>")
	)
	(segment
		(start 87.914734 -3.458718)
		(end 87.499444 -3.043428)
		(width 0.14224)
		(layer "In2.Cu")
		(net "M_J_MA<5>")
	)
	(segment
		(start 90.753692 -29.00553)
		(end 90.460576 -28.712414)
		(width 0.14224)
		(layer "In2.Cu")
		(net "M_J_MA<5>")
	)
	(segment
		(start 89.939368 -51.9176)
		(end 90.525092 -51.331876)
		(width 0.0889)
		(layer "In2.Cu")
		(net "M_J_MA<5>")
	)
	(segment
		(start 87.086948 -18.461482)
		(end 87.076788 -18.451322)
		(width 0.14224)
		(layer "In2.Cu")
		(net "M_J_MA<5>")
	)
	(segment
		(start 90.154252 -57.52465)
		(end 90.010488 -57.276238)
		(width 0.0889)
		(layer "In2.Cu")
		(net "M_J_MA<5>")
	)
	(segment
		(start 88.201246 0.971042)
		(end 88.201246 1.223772)
		(width 0.14224)
		(layer "In2.Cu")
		(net "M_J_MA<5>")
	)
	(segment
		(start 87.914734 -5.377434)
		(end 87.914734 -3.458718)
		(width 0.14224)
		(layer "In2.Cu")
		(net "M_J_MA<5>")
	)
	(segment
		(start 87.90178 -0.738886)
		(end 87.74684 -0.583946)
		(width 0.14224)
		(layer "In2.Cu")
		(net "M_J_MA<5>")
	)
	(segment
		(start 87.086948 -19.05889)
		(end 87.086948 -18.461482)
		(width 0.14224)
		(layer "In2.Cu")
		(net "M_J_MA<5>")
	)
	(segment
		(start 87.841582 -1.861566)
		(end 87.686642 -1.706626)
		(width 0.14224)
		(layer "In2.Cu")
		(net "M_J_MA<5>")
	)
	(segment
		(start 87.74684 -1.145286)
		(end 87.90178 -0.990346)
		(width 0.14224)
		(layer "In2.Cu")
		(net "M_J_MA<5>")
	)
	(segment
		(start 90.010488 -54.894988)
		(end 90.016838 -54.88432)
		(width 0.0889)
		(layer "In2.Cu")
		(net "M_J_MA<5>")
	)
	(segment
		(start 90.005662 -53.913024)
		(end 90.010488 -53.904388)
		(width 0.0889)
		(layer "In2.Cu")
		(net "M_J_MA<5>")
	)
	(segment
		(start 89.478612 -27.449526)
		(end 87.157052 -25.127966)
		(width 0.14224)
		(layer "In2.Cu")
		(net "M_J_MA<5>")
	)
	(arc
		(start 90.016838 -55.87492)
		(mid 90.089636 -55.584157)
		(end 90.010488 -55.295038)
		(width 0.0889)
		(layer "In2.Cu")
		(net "M_J_MA<5>")
	)
	(arc
		(start 90.016838 -56.86552)
		(mid 90.089636 -56.574757)
		(end 90.010488 -56.285638)
		(width 0.0889)
		(layer "In2.Cu")
		(net "M_J_MA<5>")
	)
	(arc
		(start 90.016838 -53.89372)
		(mid 90.089636 -53.602957)
		(end 90.010488 -53.313838)
		(width 0.0889)
		(layer "In2.Cu")
		(net "M_J_MA<5>")
	)
	(arc
		(start 90.010488 -57.276238)
		(mid 89.957018 -57.081175)
		(end 90.005662 -56.884824)
		(width 0.0889)
		(layer "In2.Cu")
		(net "M_J_MA<5>")
	)
	(arc
		(start 90.016838 -54.88432)
		(mid 90.089636 -54.593557)
		(end 90.010488 -54.304438)
		(width 0.0889)
		(layer "In2.Cu")
		(net "M_J_MA<5>")
	)
	(arc
		(start 90.010488 -55.295038)
		(mid 89.957018 -55.099975)
		(end 90.005662 -54.903624)
		(width 0.0889)
		(layer "In2.Cu")
		(net "M_J_MA<5>")
	)
	(arc
		(start 90.010488 -54.304438)
		(mid 89.957018 -54.109375)
		(end 90.005662 -53.913024)
		(width 0.0889)
		(layer "In2.Cu")
		(net "M_J_MA<5>")
	)
	(arc
		(start 90.010488 -56.285638)
		(mid 89.957018 -56.090575)
		(end 90.005662 -55.894224)
		(width 0.0889)
		(layer "In2.Cu")
		(net "M_J_MA<5>")
	)
	(segment
		(start 91.787218 -59.55284)
		(end 91.215718 -59.55284)
		(width 0.1016)
		(layer "F.Cu")
		(net "M_J_MA<4>")
	)
	(segment
		(start 88.349582 -0.821182)
		(end 88.349582 0.442722)
		(width 0.1651)
		(layer "F.Cu")
		(net "M_J_MA<4>")
	)
	(via
		(at 91.215718 -59.55284)
		(size 0.508)
		(drill 0.254)
		(layers "F.Cu" "B.Cu")
		(net "M_J_MA<4>")
	)
	(via
		(at 88.349582 -2.316988)
		(size 0.4572)
		(drill 0.2032)
		(layers "F.Cu" "B.Cu")
		(net "M_J_MA<4>")
	)
	(via
		(at 88.349582 0.442722)
		(size 0.508)
		(drill 0.254)
		(layers "F.Cu" "B.Cu")
		(net "M_J_MA<4>")
	)
	(segment
		(start 88.349582 -1.021842)
		(end 88.349582 -2.316988)
		(width 0.1651)
		(layer "B.Cu")
		(net "M_J_MA<4>")
	)
	(segment
		(start 88.782652 -5.322316)
		(end 87.907368 -6.1976)
		(width 0.14224)
		(layer "In2.Cu")
		(net "M_J_MA<4>")
	)
	(segment
		(start 88.349582 -2.316988)
		(end 88.349582 -2.9972)
		(width 0.14224)
		(layer "In2.Cu")
		(net "M_J_MA<4>")
	)
	(segment
		(start 87.909908 -16.192246)
		(end 87.909908 -17.09293)
		(width 0.14224)
		(layer "In2.Cu")
		(net "M_J_MA<4>")
	)
	(segment
		(start 88.349582 -2.9972)
		(end 88.782652 -3.43027)
		(width 0.14224)
		(layer "In2.Cu")
		(net "M_J_MA<4>")
	)
	(segment
		(start 87.995252 -21.278596)
		(end 87.995252 -21.735796)
		(width 0.14224)
		(layer "In2.Cu")
		(net "M_J_MA<4>")
	)
	(segment
		(start 91.261692 -48.57115)
		(end 91.261692 -48.880014)
		(width 0.0889)
		(layer "In2.Cu")
		(net "M_J_MA<4>")
	)
	(segment
		(start 91.337892 -48.956214)
		(end 91.337892 -50.137314)
		(width 0.0889)
		(layer "In2.Cu")
		(net "M_J_MA<4>")
	)
	(segment
		(start 87.927688 -8.79475)
		(end 87.927688 -12.20216)
		(width 0.14224)
		(layer "In2.Cu")
		(net "M_J_MA<4>")
	)
	(segment
		(start 87.842852 -21.888196)
		(end 87.842852 -22.446996)
		(width 0.14224)
		(layer "In2.Cu")
		(net "M_J_MA<4>")
	)
	(segment
		(start 87.842852 -22.446996)
		(end 87.995252 -22.599396)
		(width 0.14224)
		(layer "In2.Cu")
		(net "M_J_MA<4>")
	)
	(segment
		(start 88.349582 0.442722)
		(end 88.349582 -2.316988)
		(width 0.14224)
		(layer "In2.Cu")
		(net "M_J_MA<4>")
	)
	(segment
		(start 87.907368 -8.77443)
		(end 87.927688 -8.79475)
		(width 0.14224)
		(layer "In2.Cu")
		(net "M_J_MA<4>")
	)
	(segment
		(start 87.795608 -23.30704)
		(end 87.795608 -24.407368)
		(width 0.14224)
		(layer "In2.Cu")
		(net "M_J_MA<4>")
	)
	(segment
		(start 88.428322 -25.420828)
		(end 88.428322 -25.68067)
		(width 0.14224)
		(layer "In2.Cu")
		(net "M_J_MA<4>")
	)
	(segment
		(start 90.33002 -27.582368)
		(end 90.828114 -27.582368)
		(width 0.14224)
		(layer "In2.Cu")
		(net "M_J_MA<4>")
	)
	(segment
		(start 87.93226 -18.391378)
		(end 87.93226 -21.215604)
		(width 0.14224)
		(layer "In2.Cu")
		(net "M_J_MA<4>")
	)
	(segment
		(start 91.337892 -50.137314)
		(end 90.770202 -50.705004)
		(width 0.0889)
		(layer "In2.Cu")
		(net "M_J_MA<4>")
	)
	(segment
		(start 90.949272 -58.897774)
		(end 91.215718 -59.55284)
		(width 0.0889)
		(layer "In2.Cu")
		(net "M_J_MA<4>")
	)
	(segment
		(start 87.995252 -21.735796)
		(end 87.842852 -21.888196)
		(width 0.14224)
		(layer "In2.Cu")
		(net "M_J_MA<4>")
	)
	(segment
		(start 90.770202 -50.705004)
		(end 90.770202 -53.066442)
		(width 0.0889)
		(layer "In2.Cu")
		(net "M_J_MA<4>")
	)
	(segment
		(start 87.93226 -21.215604)
		(end 87.995252 -21.278596)
		(width 0.14224)
		(layer "In2.Cu")
		(net "M_J_MA<4>")
	)
	(segment
		(start 90.828114 -27.582368)
		(end 91.261692 -28.015946)
		(width 0.14224)
		(layer "In2.Cu")
		(net "M_J_MA<4>")
	)
	(segment
		(start 87.792052 -17.210786)
		(end 87.792052 -17.566386)
		(width 0.14224)
		(layer "In2.Cu")
		(net "M_J_MA<4>")
	)
	(segment
		(start 91.261692 -28.015946)
		(end 91.261692 -48.57115)
		(width 0.14224)
		(layer "In2.Cu")
		(net "M_J_MA<4>")
	)
	(segment
		(start 88.161622 -15.399766)
		(end 88.161622 -15.940532)
		(width 0.14224)
		(layer "In2.Cu")
		(net "M_J_MA<4>")
	)
	(segment
		(start 88.161622 -15.940532)
		(end 87.909908 -16.192246)
		(width 0.14224)
		(layer "In2.Cu")
		(net "M_J_MA<4>")
	)
	(segment
		(start 90.869008 -58.762392)
		(end 90.949272 -58.897774)
		(width 0.0889)
		(layer "In2.Cu")
		(net "M_J_MA<4>")
	)
	(segment
		(start 87.995252 -23.107396)
		(end 87.795608 -23.30704)
		(width 0.14224)
		(layer "In2.Cu")
		(net "M_J_MA<4>")
	)
	(segment
		(start 87.927688 -12.20216)
		(end 87.909908 -12.21994)
		(width 0.14224)
		(layer "In2.Cu")
		(net "M_J_MA<4>")
	)
	(segment
		(start 88.726264 -25.122886)
		(end 88.428322 -25.420828)
		(width 0.14224)
		(layer "In2.Cu")
		(net "M_J_MA<4>")
	)
	(segment
		(start 87.909908 -12.21994)
		(end 87.909908 -15.148052)
		(width 0.14224)
		(layer "In2.Cu")
		(net "M_J_MA<4>")
	)
	(segment
		(start 88.782652 -3.43027)
		(end 88.782652 -5.322316)
		(width 0.14224)
		(layer "In2.Cu")
		(net "M_J_MA<4>")
	)
	(segment
		(start 87.909908 -17.09293)
		(end 87.792052 -17.210786)
		(width 0.14224)
		(layer "In2.Cu")
		(net "M_J_MA<4>")
	)
	(segment
		(start 87.907368 -6.1976)
		(end 87.907368 -8.77443)
		(width 0.14224)
		(layer "In2.Cu")
		(net "M_J_MA<4>")
	)
	(segment
		(start 87.950548 -24.562308)
		(end 88.384634 -24.562308)
		(width 0.14224)
		(layer "In2.Cu")
		(net "M_J_MA<4>")
	)
	(segment
		(start 88.384634 -24.562308)
		(end 88.726264 -24.903938)
		(width 0.14224)
		(layer "In2.Cu")
		(net "M_J_MA<4>")
	)
	(segment
		(start 87.909908 -15.148052)
		(end 88.161622 -15.399766)
		(width 0.14224)
		(layer "In2.Cu")
		(net "M_J_MA<4>")
	)
	(segment
		(start 88.726264 -24.903938)
		(end 88.726264 -25.122886)
		(width 0.14224)
		(layer "In2.Cu")
		(net "M_J_MA<4>")
	)
	(segment
		(start 87.995252 -22.599396)
		(end 87.995252 -23.107396)
		(width 0.14224)
		(layer "In2.Cu")
		(net "M_J_MA<4>")
	)
	(segment
		(start 88.428322 -25.68067)
		(end 90.33002 -27.582368)
		(width 0.14224)
		(layer "In2.Cu")
		(net "M_J_MA<4>")
	)
	(segment
		(start 87.792052 -17.566386)
		(end 87.995252 -17.769586)
		(width 0.14224)
		(layer "In2.Cu")
		(net "M_J_MA<4>")
	)
	(segment
		(start 87.995252 -17.769586)
		(end 87.995252 -18.328386)
		(width 0.14224)
		(layer "In2.Cu")
		(net "M_J_MA<4>")
	)
	(segment
		(start 87.995252 -18.328386)
		(end 87.93226 -18.391378)
		(width 0.14224)
		(layer "In2.Cu")
		(net "M_J_MA<4>")
	)
	(segment
		(start 91.261692 -48.880014)
		(end 91.337892 -48.956214)
		(width 0.0889)
		(layer "In2.Cu")
		(net "M_J_MA<4>")
	)
	(segment
		(start 87.795608 -24.407368)
		(end 87.950548 -24.562308)
		(width 0.14224)
		(layer "In2.Cu")
		(net "M_J_MA<4>")
	)
	(arc
		(start 90.703908 -54.895496)
		(mid 90.757407 -55.095394)
		(end 90.703908 -55.295292)
		(width 0.0889)
		(layer "In2.Cu")
		(net "M_J_MA<4>")
	)
	(arc
		(start 90.703908 -56.876696)
		(mid 90.757407 -57.076594)
		(end 90.703908 -57.276492)
		(width 0.0889)
		(layer "In2.Cu")
		(net "M_J_MA<4>")
	)
	(arc
		(start 90.770202 -53.066442)
		(mid 90.753345 -53.194629)
		(end 90.703908 -53.314092)
		(width 0.0889)
		(layer "In2.Cu")
		(net "M_J_MA<4>")
	)
	(arc
		(start 90.78468 -58.239406)
		(mid 90.817875 -58.375846)
		(end 90.818208 -58.516266)
		(width 0.0889)
		(layer "In2.Cu")
		(net "M_J_MA<4>")
	)
	(arc
		(start 90.703908 -55.295292)
		(mid 90.624777 -55.590694)
		(end 90.703908 -55.886096)
		(width 0.0889)
		(layer "In2.Cu")
		(net "M_J_MA<4>")
	)
	(arc
		(start 90.703908 -56.285892)
		(mid 90.624777 -56.581294)
		(end 90.703908 -56.876696)
		(width 0.0889)
		(layer "In2.Cu")
		(net "M_J_MA<4>")
	)
	(arc
		(start 90.703908 -57.867296)
		(mid 90.741528 -57.955781)
		(end 90.756994 -58.050684)
		(width 0.0889)
		(layer "In2.Cu")
		(net "M_J_MA<4>")
	)
	(arc
		(start 90.703908 -54.304692)
		(mid 90.624777 -54.600094)
		(end 90.703908 -54.895496)
		(width 0.0889)
		(layer "In2.Cu")
		(net "M_J_MA<4>")
	)
	(arc
		(start 90.703908 -57.276492)
		(mid 90.624777 -57.571894)
		(end 90.703908 -57.867296)
		(width 0.0889)
		(layer "In2.Cu")
		(net "M_J_MA<4>")
	)
	(arc
		(start 90.703908 -55.886096)
		(mid 90.757407 -56.085994)
		(end 90.703908 -56.285892)
		(width 0.0889)
		(layer "In2.Cu")
		(net "M_J_MA<4>")
	)
	(arc
		(start 90.703908 -53.904896)
		(mid 90.757441 -54.104794)
		(end 90.703908 -54.304692)
		(width 0.0889)
		(layer "In2.Cu")
		(net "M_J_MA<4>")
	)
	(arc
		(start 90.756994 -58.050684)
		(mid 90.765889 -58.14577)
		(end 90.78468 -58.239406)
		(width 0.0889)
		(layer "In2.Cu")
		(net "M_J_MA<4>")
	)
	(arc
		(start 90.818208 -58.516266)
		(mid 90.823796 -58.643417)
		(end 90.869008 -58.762392)
		(width 0.0889)
		(layer "In2.Cu")
		(net "M_J_MA<4>")
	)
	(arc
		(start 90.703908 -53.314092)
		(mid 90.624777 -53.609494)
		(end 90.703908 -53.904896)
		(width 0.0889)
		(layer "In2.Cu")
		(net "M_J_MA<4>")
	)
	(segment
		(start 89.199466 3.778758)
		(end 89.199466 2.514854)
		(width 0.1651)
		(layer "F.Cu")
		(net "M_J_MA<3>")
	)
	(segment
		(start 91.787218 -58.561986)
		(end 91.215718 -58.561986)
		(width 0.1016)
		(layer "F.Cu")
		(net "M_J_MA<3>")
	)
	(via
		(at 89.199466 -4.332478)
		(size 0.4572)
		(drill 0.2032)
		(layers "F.Cu" "B.Cu")
		(net "M_J_MA<3>")
	)
	(via
		(at 89.199466 2.514854)
		(size 0.508)
		(drill 0.254)
		(layers "F.Cu" "B.Cu")
		(net "M_J_MA<3>")
	)
	(via
		(at 91.215718 -58.561986)
		(size 0.508)
		(drill 0.254)
		(layers "F.Cu" "B.Cu")
		(net "M_J_MA<3>")
	)
	(segment
		(start 89.199466 -5.621782)
		(end 89.199466 -4.332478)
		(width 0.1651)
		(layer "B.Cu")
		(net "M_J_MA<3>")
	)
	(segment
		(start 88.702896 -20.131024)
		(end 88.702896 -19.268186)
		(width 0.14224)
		(layer "In2.Cu")
		(net "M_J_MA<3>")
	)
	(segment
		(start 88.975438 -8.66902)
		(end 88.975438 -7.82066)
		(width 0.14224)
		(layer "In2.Cu")
		(net "M_J_MA<3>")
	)
	(segment
		(start 88.956896 -22.408896)
		(end 88.956896 -21.964396)
		(width 0.14224)
		(layer "In2.Cu")
		(net "M_J_MA<3>")
	)
	(segment
		(start 88.702896 -21.710396)
		(end 88.702896 -21.181822)
		(width 0.14224)
		(layer "In2.Cu")
		(net "M_J_MA<3>")
	)
	(segment
		(start 88.783668 -13.663168)
		(end 88.671654 -13.551154)
		(width 0.14224)
		(layer "In2.Cu")
		(net "M_J_MA<3>")
	)
	(segment
		(start 91.034362 -52.792376)
		(end 91.034362 -50.974498)
		(width 0.0889)
		(layer "In2.Cu")
		(net "M_J_MA<3>")
	)
	(segment
		(start 88.671654 -13.551154)
		(end 88.671654 -13.092938)
		(width 0.14224)
		(layer "In2.Cu")
		(net "M_J_MA<3>")
	)
	(segment
		(start 89.199466 -3.019552)
		(end 88.763856 -2.583942)
		(width 0.14224)
		(layer "In2.Cu")
		(net "M_J_MA<3>")
	)
	(segment
		(start 88.783668 -15.183104)
		(end 88.783668 -13.663168)
		(width 0.14224)
		(layer "In2.Cu")
		(net "M_J_MA<3>")
	)
	(segment
		(start 88.791796 -7.637018)
		(end 88.791796 -6.329172)
		(width 0.14224)
		(layer "In2.Cu")
		(net "M_J_MA<3>")
	)
	(segment
		(start 88.760554 0.902208)
		(end 88.760554 1.462786)
		(width 0.14224)
		(layer "In2.Cu")
		(net "M_J_MA<3>")
	)
	(segment
		(start 88.999568 -1.6256)
		(end 88.999568 0.32512)
		(width 0.14224)
		(layer "In2.Cu")
		(net "M_J_MA<3>")
	)
	(segment
		(start 88.840564 -23.321264)
		(end 88.702896 -23.183596)
		(width 0.14224)
		(layer "In2.Cu")
		(net "M_J_MA<3>")
	)
	(segment
		(start 90.488516 -25.964134)
		(end 90.201242 -25.67686)
		(width 0.14224)
		(layer "In2.Cu")
		(net "M_J_MA<3>")
	)
	(segment
		(start 88.671654 -13.092938)
		(end 88.918542 -12.84605)
		(width 0.14224)
		(layer "In2.Cu")
		(net "M_J_MA<3>")
	)
	(segment
		(start 89.688162 -25.902412)
		(end 89.400634 -25.902412)
		(width 0.14224)
		(layer "In2.Cu")
		(net "M_J_MA<3>")
	)
	(segment
		(start 88.702896 -23.183596)
		(end 88.702896 -22.662896)
		(width 0.14224)
		(layer "In2.Cu")
		(net "M_J_MA<3>")
	)
	(segment
		(start 91.769692 -27.24531)
		(end 91.350846 -26.826464)
		(width 0.14224)
		(layer "In2.Cu")
		(net "M_J_MA<3>")
	)
	(segment
		(start 91.034362 -50.974498)
		(end 91.769692 -50.239168)
		(width 0.0889)
		(layer "In2.Cu")
		(net "M_J_MA<3>")
	)
	(segment
		(start 90.664538 -26.937716)
		(end 90.377264 -26.650442)
		(width 0.14224)
		(layer "In2.Cu")
		(net "M_J_MA<3>")
	)
	(segment
		(start 91.769692 -48.58385)
		(end 91.769692 -27.24531)
		(width 0.14224)
		(layer "In2.Cu")
		(net "M_J_MA<3>")
	)
	(segment
		(start 88.783668 -16.416782)
		(end 89.064338 -16.136112)
		(width 0.14224)
		(layer "In2.Cu")
		(net "M_J_MA<3>")
	)
	(segment
		(start 90.201242 -25.67686)
		(end 89.913714 -25.67686)
		(width 0.14224)
		(layer "In2.Cu")
		(net "M_J_MA<3>")
	)
	(segment
		(start 88.961214 -20.923504)
		(end 88.961214 -20.389342)
		(width 0.14224)
		(layer "In2.Cu")
		(net "M_J_MA<3>")
	)
	(segment
		(start 89.11336 -25.32761)
		(end 89.338912 -25.102058)
		(width 0.14224)
		(layer "In2.Cu")
		(net "M_J_MA<3>")
	)
	(segment
		(start 88.702896 -17.845786)
		(end 88.956896 -17.591786)
		(width 0.14224)
		(layer "In2.Cu")
		(net "M_J_MA<3>")
	)
	(segment
		(start 88.760808 -11.598656)
		(end 89.026238 -11.333226)
		(width 0.14224)
		(layer "In2.Cu")
		(net "M_J_MA<3>")
	)
	(segment
		(start 89.329768 -4.46278)
		(end 89.199466 -4.332478)
		(width 0.14224)
		(layer "In2.Cu")
		(net "M_J_MA<3>")
	)
	(segment
		(start 88.840564 -24.316182)
		(end 88.840564 -23.321264)
		(width 0.14224)
		(layer "In2.Cu")
		(net "M_J_MA<3>")
	)
	(segment
		(start 89.913714 -25.67686)
		(end 89.688162 -25.902412)
		(width 0.14224)
		(layer "In2.Cu")
		(net "M_J_MA<3>")
	)
	(segment
		(start 88.758522 -18.434812)
		(end 88.702896 -18.379186)
		(width 0.14224)
		(layer "In2.Cu")
		(net "M_J_MA<3>")
	)
	(segment
		(start 91.215718 -58.561986)
		(end 90.885518 -57.80024)
		(width 0.0889)
		(layer "In2.Cu")
		(net "M_J_MA<3>")
	)
	(segment
		(start 88.702896 -21.181822)
		(end 88.961214 -20.923504)
		(width 0.14224)
		(layer "In2.Cu")
		(net "M_J_MA<3>")
	)
	(segment
		(start 88.918542 -12.324842)
		(end 88.760808 -12.167108)
		(width 0.14224)
		(layer "In2.Cu")
		(net "M_J_MA<3>")
	)
	(segment
		(start 88.760554 1.462786)
		(end 89.195656 2.51333)
		(width 0.14224)
		(layer "In2.Cu")
		(net "M_J_MA<3>")
	)
	(segment
		(start 90.488516 -26.251662)
		(end 90.488516 -25.964134)
		(width 0.14224)
		(layer "In2.Cu")
		(net "M_J_MA<3>")
	)
	(segment
		(start 89.11336 -25.615138)
		(end 89.11336 -25.32761)
		(width 0.14224)
		(layer "In2.Cu")
		(net "M_J_MA<3>")
	)
	(segment
		(start 89.195656 2.51333)
		(end 89.199466 2.514854)
		(width 0.14224)
		(layer "In2.Cu")
		(net "M_J_MA<3>")
	)
	(segment
		(start 88.760808 -8.88365)
		(end 88.975438 -8.66902)
		(width 0.14224)
		(layer "In2.Cu")
		(net "M_J_MA<3>")
	)
	(segment
		(start 88.999568 0.32512)
		(end 88.760554 0.902208)
		(width 0.14224)
		(layer "In2.Cu")
		(net "M_J_MA<3>")
	)
	(segment
		(start 89.329768 -5.7912)
		(end 89.329768 -4.46278)
		(width 0.14224)
		(layer "In2.Cu")
		(net "M_J_MA<3>")
	)
	(segment
		(start 88.918542 -12.84605)
		(end 88.918542 -12.324842)
		(width 0.14224)
		(layer "In2.Cu")
		(net "M_J_MA<3>")
	)
	(segment
		(start 88.783668 -16.986758)
		(end 88.783668 -16.416782)
		(width 0.14224)
		(layer "In2.Cu")
		(net "M_J_MA<3>")
	)
	(segment
		(start 91.350846 -26.826464)
		(end 91.063318 -26.826464)
		(width 0.14224)
		(layer "In2.Cu")
		(net "M_J_MA<3>")
	)
	(segment
		(start 88.760808 -12.167108)
		(end 88.760808 -11.598656)
		(width 0.14224)
		(layer "In2.Cu")
		(net "M_J_MA<3>")
	)
	(segment
		(start 89.064338 -15.463774)
		(end 88.783668 -15.183104)
		(width 0.14224)
		(layer "In2.Cu")
		(net "M_J_MA<3>")
	)
	(segment
		(start 88.763856 -2.583942)
		(end 88.763856 -1.861312)
		(width 0.14224)
		(layer "In2.Cu")
		(net "M_J_MA<3>")
	)
	(segment
		(start 89.400634 -25.902412)
		(end 89.11336 -25.615138)
		(width 0.14224)
		(layer "In2.Cu")
		(net "M_J_MA<3>")
	)
	(segment
		(start 88.975438 -7.82066)
		(end 88.791796 -7.637018)
		(width 0.14224)
		(layer "In2.Cu")
		(net "M_J_MA<3>")
	)
	(segment
		(start 88.760808 -10.521696)
		(end 88.760808 -8.88365)
		(width 0.14224)
		(layer "In2.Cu")
		(net "M_J_MA<3>")
	)
	(segment
		(start 88.702896 -19.268186)
		(end 88.758522 -19.21256)
		(width 0.14224)
		(layer "In2.Cu")
		(net "M_J_MA<3>")
	)
	(segment
		(start 89.026238 -11.333226)
		(end 89.026238 -10.787126)
		(width 0.14224)
		(layer "In2.Cu")
		(net "M_J_MA<3>")
	)
	(segment
		(start 90.885518 -57.80024)
		(end 90.869008 -57.771792)
		(width 0.0889)
		(layer "In2.Cu")
		(net "M_J_MA<3>")
	)
	(segment
		(start 90.377264 -26.362914)
		(end 90.488516 -26.251662)
		(width 0.14224)
		(layer "In2.Cu")
		(net "M_J_MA<3>")
	)
	(segment
		(start 88.956896 -17.159986)
		(end 88.783668 -16.986758)
		(width 0.14224)
		(layer "In2.Cu")
		(net "M_J_MA<3>")
	)
	(segment
		(start 89.338912 -24.81453)
		(end 88.840564 -24.316182)
		(width 0.14224)
		(layer "In2.Cu")
		(net "M_J_MA<3>")
	)
	(segment
		(start 88.758522 -19.21256)
		(end 88.758522 -18.434812)
		(width 0.14224)
		(layer "In2.Cu")
		(net "M_J_MA<3>")
	)
	(segment
		(start 90.377264 -26.650442)
		(end 90.377264 -26.362914)
		(width 0.14224)
		(layer "In2.Cu")
		(net "M_J_MA<3>")
	)
	(segment
		(start 88.702896 -18.379186)
		(end 88.702896 -17.845786)
		(width 0.14224)
		(layer "In2.Cu")
		(net "M_J_MA<3>")
	)
	(segment
		(start 91.769692 -50.239168)
		(end 91.769692 -48.58385)
		(width 0.0889)
		(layer "In2.Cu")
		(net "M_J_MA<3>")
	)
	(segment
		(start 89.338912 -25.102058)
		(end 89.338912 -24.81453)
		(width 0.14224)
		(layer "In2.Cu")
		(net "M_J_MA<3>")
	)
	(segment
		(start 91.063318 -26.826464)
		(end 90.952066 -26.937716)
		(width 0.14224)
		(layer "In2.Cu")
		(net "M_J_MA<3>")
	)
	(segment
		(start 88.791796 -6.329172)
		(end 89.329768 -5.7912)
		(width 0.14224)
		(layer "In2.Cu")
		(net "M_J_MA<3>")
	)
	(segment
		(start 89.026238 -10.787126)
		(end 88.760808 -10.521696)
		(width 0.14224)
		(layer "In2.Cu")
		(net "M_J_MA<3>")
	)
	(segment
		(start 90.952066 -26.937716)
		(end 90.664538 -26.937716)
		(width 0.14224)
		(layer "In2.Cu")
		(net "M_J_MA<3>")
	)
	(segment
		(start 88.956896 -21.964396)
		(end 88.702896 -21.710396)
		(width 0.14224)
		(layer "In2.Cu")
		(net "M_J_MA<3>")
	)
	(segment
		(start 88.961214 -20.389342)
		(end 88.702896 -20.131024)
		(width 0.14224)
		(layer "In2.Cu")
		(net "M_J_MA<3>")
	)
	(segment
		(start 88.763856 -1.861312)
		(end 88.999568 -1.6256)
		(width 0.14224)
		(layer "In2.Cu")
		(net "M_J_MA<3>")
	)
	(segment
		(start 89.064338 -16.136112)
		(end 89.064338 -15.463774)
		(width 0.14224)
		(layer "In2.Cu")
		(net "M_J_MA<3>")
	)
	(segment
		(start 88.702896 -22.662896)
		(end 88.956896 -22.408896)
		(width 0.14224)
		(layer "In2.Cu")
		(net "M_J_MA<3>")
	)
	(segment
		(start 88.956896 -17.591786)
		(end 88.956896 -17.159986)
		(width 0.14224)
		(layer "In2.Cu")
		(net "M_J_MA<3>")
	)
	(segment
		(start 89.199466 -4.332478)
		(end 89.199466 -3.019552)
		(width 0.14224)
		(layer "In2.Cu")
		(net "M_J_MA<3>")
	)
	(arc
		(start 90.869008 -56.381396)
		(mid 90.948139 -56.085994)
		(end 90.869008 -55.790592)
		(width 0.0889)
		(layer "In2.Cu")
		(net "M_J_MA<3>")
	)
	(arc
		(start 90.869008 -55.390796)
		(mid 90.948139 -55.095394)
		(end 90.869008 -54.799992)
		(width 0.0889)
		(layer "In2.Cu")
		(net "M_J_MA<3>")
	)
	(arc
		(start 90.869008 -53.409596)
		(mid 90.992276 -53.111863)
		(end 91.034362 -52.792376)
		(width 0.0889)
		(layer "In2.Cu")
		(net "M_J_MA<3>")
	)
	(arc
		(start 90.869008 -57.371996)
		(mid 90.948139 -57.076594)
		(end 90.869008 -56.781192)
		(width 0.0889)
		(layer "In2.Cu")
		(net "M_J_MA<3>")
	)
	(arc
		(start 90.869008 -54.400196)
		(mid 90.948071 -54.104794)
		(end 90.869008 -53.809392)
		(width 0.0889)
		(layer "In2.Cu")
		(net "M_J_MA<3>")
	)
	(arc
		(start 90.869008 -54.799992)
		(mid 90.815509 -54.600094)
		(end 90.869008 -54.400196)
		(width 0.0889)
		(layer "In2.Cu")
		(net "M_J_MA<3>")
	)
	(arc
		(start 90.869008 -57.771792)
		(mid 90.815509 -57.571894)
		(end 90.869008 -57.371996)
		(width 0.0889)
		(layer "In2.Cu")
		(net "M_J_MA<3>")
	)
	(arc
		(start 90.869008 -56.781192)
		(mid 90.815509 -56.581294)
		(end 90.869008 -56.381396)
		(width 0.0889)
		(layer "In2.Cu")
		(net "M_J_MA<3>")
	)
	(arc
		(start 90.869008 -55.790592)
		(mid 90.815509 -55.590694)
		(end 90.869008 -55.390796)
		(width 0.0889)
		(layer "In2.Cu")
		(net "M_J_MA<3>")
	)
	(arc
		(start 90.869008 -53.809392)
		(mid 90.815509 -53.609494)
		(end 90.869008 -53.409596)
		(width 0.0889)
		(layer "In2.Cu")
		(net "M_J_MA<3>")
	)
	(segment
		(start 92.645738 -61.038486)
		(end 92.074238 -61.038486)
		(width 0.1016)
		(layer "F.Cu")
		(net "M_J_MA<2>")
	)
	(segment
		(start 90.04935 -0.821182)
		(end 90.04935 0.442468)
		(width 0.1651)
		(layer "F.Cu")
		(net "M_J_MA<2>")
	)
	(via
		(at 92.074238 -61.038486)
		(size 0.508)
		(drill 0.254)
		(layers "F.Cu" "B.Cu")
		(net "M_J_MA<2>")
	)
	(via
		(at 90.04935 -2.316988)
		(size 0.4572)
		(drill 0.2032)
		(layers "F.Cu" "B.Cu")
		(net "M_J_MA<2>")
	)
	(via
		(at 90.04935 0.442468)
		(size 0.508)
		(drill 0.254)
		(layers "F.Cu" "B.Cu")
		(net "M_J_MA<2>")
	)
	(segment
		(start 90.04935 -2.316988)
		(end 90.04935 -1.021842)
		(width 0.1651)
		(layer "B.Cu")
		(net "M_J_MA<2>")
	)
	(segment
		(start 90.45448 -21.81098)
		(end 90.45448 -24.492966)
		(width 0.14224)
		(layer "In2.Cu")
		(net "M_J_MA<2>")
	)
	(segment
		(start 90.404696 -19.141186)
		(end 90.404696 -21.761196)
		(width 0.14224)
		(layer "In2.Cu")
		(net "M_J_MA<2>")
	)
	(segment
		(start 90.466418 -11.56335)
		(end 90.466418 -12.200128)
		(width 0.14224)
		(layer "In2.Cu")
		(net "M_J_MA<2>")
	)
	(segment
		(start 90.088466 -2.277872)
		(end 90.04935 -2.316988)
		(width 0.14224)
		(layer "In2.Cu")
		(net "M_J_MA<2>")
	)
	(segment
		(start 90.142568 -2.410206)
		(end 90.142568 -3.784854)
		(width 0.14224)
		(layer "In2.Cu")
		(net "M_J_MA<2>")
	)
	(segment
		(start 90.244168 -7.5184)
		(end 90.244168 -8.6868)
		(width 0.14224)
		(layer "In2.Cu")
		(net "M_J_MA<2>")
	)
	(segment
		(start 92.785692 -50.320956)
		(end 91.671902 -51.434746)
		(width 0.0889)
		(layer "In2.Cu")
		(net "M_J_MA<2>")
	)
	(segment
		(start 90.462862 -13.748766)
		(end 90.462862 -16.92402)
		(width 0.14224)
		(layer "In2.Cu")
		(net "M_J_MA<2>")
	)
	(segment
		(start 90.33764 -18.424906)
		(end 90.476324 -18.56359)
		(width 0.14224)
		(layer "In2.Cu")
		(net "M_J_MA<2>")
	)
	(segment
		(start 90.04935 0.442468)
		(end 90.088466 0.403352)
		(width 0.14224)
		(layer "In2.Cu")
		(net "M_J_MA<2>")
	)
	(segment
		(start 91.744038 -60.27674)
		(end 92.074238 -61.038486)
		(width 0.0889)
		(layer "In2.Cu")
		(net "M_J_MA<2>")
	)
	(segment
		(start 90.466418 -12.200128)
		(end 90.404696 -12.26185)
		(width 0.14224)
		(layer "In2.Cu")
		(net "M_J_MA<2>")
	)
	(segment
		(start 90.404696 -13.6906)
		(end 90.462862 -13.748766)
		(width 0.14224)
		(layer "In2.Cu")
		(net "M_J_MA<2>")
	)
	(segment
		(start 92.785692 -26.824178)
		(end 92.785692 -49.86655)
		(width 0.14224)
		(layer "In2.Cu")
		(net "M_J_MA<2>")
	)
	(segment
		(start 90.574368 -11.4554)
		(end 90.466418 -11.56335)
		(width 0.14224)
		(layer "In2.Cu")
		(net "M_J_MA<2>")
	)
	(segment
		(start 91.727528 -60.248292)
		(end 91.744038 -60.27674)
		(width 0.0889)
		(layer "In2.Cu")
		(net "M_J_MA<2>")
	)
	(segment
		(start 90.142568 -3.784854)
		(end 90.458544 -4.10083)
		(width 0.14224)
		(layer "In2.Cu")
		(net "M_J_MA<2>")
	)
	(segment
		(start 90.458544 -7.304024)
		(end 90.244168 -7.5184)
		(width 0.14224)
		(layer "In2.Cu")
		(net "M_J_MA<2>")
	)
	(segment
		(start 91.671902 -51.434746)
		(end 91.671902 -53.10632)
		(width 0.0889)
		(layer "In2.Cu")
		(net "M_J_MA<2>")
	)
	(segment
		(start 90.458544 -4.10083)
		(end 90.458544 -7.304024)
		(width 0.14224)
		(layer "In2.Cu")
		(net "M_J_MA<2>")
	)
	(segment
		(start 90.574368 -9.017)
		(end 90.574368 -11.4554)
		(width 0.14224)
		(layer "In2.Cu")
		(net "M_J_MA<2>")
	)
	(segment
		(start 90.404696 -21.761196)
		(end 90.45448 -21.81098)
		(width 0.14224)
		(layer "In2.Cu")
		(net "M_J_MA<2>")
	)
	(segment
		(start 90.04935 -2.316988)
		(end 90.142568 -2.410206)
		(width 0.14224)
		(layer "In2.Cu")
		(net "M_J_MA<2>")
	)
	(segment
		(start 92.785692 -49.86655)
		(end 92.785692 -50.320956)
		(width 0.0889)
		(layer "In2.Cu")
		(net "M_J_MA<2>")
	)
	(segment
		(start 90.33764 -17.049242)
		(end 90.33764 -18.424906)
		(width 0.14224)
		(layer "In2.Cu")
		(net "M_J_MA<2>")
	)
	(segment
		(start 90.088466 0.403352)
		(end 90.088466 -2.277872)
		(width 0.14224)
		(layer "In2.Cu")
		(net "M_J_MA<2>")
	)
	(segment
		(start 90.404696 -12.26185)
		(end 90.404696 -13.6906)
		(width 0.14224)
		(layer "In2.Cu")
		(net "M_J_MA<2>")
	)
	(segment
		(start 90.476324 -19.069558)
		(end 90.404696 -19.141186)
		(width 0.14224)
		(layer "In2.Cu")
		(net "M_J_MA<2>")
	)
	(segment
		(start 90.45448 -24.492966)
		(end 92.785692 -26.824178)
		(width 0.14224)
		(layer "In2.Cu")
		(net "M_J_MA<2>")
	)
	(segment
		(start 90.462862 -16.92402)
		(end 90.33764 -17.049242)
		(width 0.14224)
		(layer "In2.Cu")
		(net "M_J_MA<2>")
	)
	(segment
		(start 90.476324 -18.56359)
		(end 90.476324 -19.069558)
		(width 0.14224)
		(layer "In2.Cu")
		(net "M_J_MA<2>")
	)
	(segment
		(start 90.244168 -8.6868)
		(end 90.574368 -9.017)
		(width 0.14224)
		(layer "In2.Cu")
		(net "M_J_MA<2>")
	)
	(arc
		(start 91.727528 -53.904896)
		(mid 91.674029 -54.104794)
		(end 91.727528 -54.304692)
		(width 0.0889)
		(layer "In2.Cu")
		(net "M_J_MA<2>")
	)
	(arc
		(start 91.727528 -56.876696)
		(mid 91.674029 -57.076594)
		(end 91.727528 -57.276492)
		(width 0.0889)
		(layer "In2.Cu")
		(net "M_J_MA<2>")
	)
	(arc
		(start 91.727528 -59.257692)
		(mid 91.806659 -59.553094)
		(end 91.727528 -59.848496)
		(width 0.0889)
		(layer "In2.Cu")
		(net "M_J_MA<2>")
	)
	(arc
		(start 91.727528 -55.295292)
		(mid 91.806659 -55.590694)
		(end 91.727528 -55.886096)
		(width 0.0889)
		(layer "In2.Cu")
		(net "M_J_MA<2>")
	)
	(arc
		(start 91.727528 -59.848496)
		(mid 91.674029 -60.048394)
		(end 91.727528 -60.248292)
		(width 0.0889)
		(layer "In2.Cu")
		(net "M_J_MA<2>")
	)
	(arc
		(start 91.671902 -53.10632)
		(mid 91.686043 -53.213868)
		(end 91.727528 -53.314092)
		(width 0.0889)
		(layer "In2.Cu")
		(net "M_J_MA<2>")
	)
	(arc
		(start 91.727528 -53.314092)
		(mid 91.806659 -53.609494)
		(end 91.727528 -53.904896)
		(width 0.0889)
		(layer "In2.Cu")
		(net "M_J_MA<2>")
	)
	(arc
		(start 91.727528 -56.285892)
		(mid 91.806659 -56.581294)
		(end 91.727528 -56.876696)
		(width 0.0889)
		(layer "In2.Cu")
		(net "M_J_MA<2>")
	)
	(arc
		(start 91.727528 -58.857896)
		(mid 91.674029 -59.057794)
		(end 91.727528 -59.257692)
		(width 0.0889)
		(layer "In2.Cu")
		(net "M_J_MA<2>")
	)
	(arc
		(start 91.727528 -57.276492)
		(mid 91.806659 -57.571894)
		(end 91.727528 -57.867296)
		(width 0.0889)
		(layer "In2.Cu")
		(net "M_J_MA<2>")
	)
	(arc
		(start 91.727528 -54.895496)
		(mid 91.674029 -55.095394)
		(end 91.727528 -55.295292)
		(width 0.0889)
		(layer "In2.Cu")
		(net "M_J_MA<2>")
	)
	(arc
		(start 91.727528 -55.886096)
		(mid 91.674029 -56.085994)
		(end 91.727528 -56.285892)
		(width 0.0889)
		(layer "In2.Cu")
		(net "M_J_MA<2>")
	)
	(arc
		(start 91.727528 -57.867296)
		(mid 91.674029 -58.067194)
		(end 91.727528 -58.267092)
		(width 0.0889)
		(layer "In2.Cu")
		(net "M_J_MA<2>")
	)
	(arc
		(start 91.727528 -58.267092)
		(mid 91.806659 -58.562494)
		(end 91.727528 -58.857896)
		(width 0.0889)
		(layer "In2.Cu")
		(net "M_J_MA<2>")
	)
	(arc
		(start 91.727528 -54.304692)
		(mid 91.806659 -54.600094)
		(end 91.727528 -54.895496)
		(width 0.0889)
		(layer "In2.Cu")
		(net "M_J_MA<2>")
	)
	(segment
		(start 90.04935 3.778758)
		(end 90.049604 3.778504)
		(width 0.1651)
		(layer "F.Cu")
		(net "M_J_MA<1>")
	)
	(segment
		(start 90.049604 3.778504)
		(end 90.049604 1.805432)
		(width 0.1651)
		(layer "F.Cu")
		(net "M_J_MA<1>")
	)
	(segment
		(start 91.787218 -61.53404)
		(end 91.215718 -61.53404)
		(width 0.1016)
		(layer "F.Cu")
		(net "M_J_MA<1>")
	)
	(via
		(at 90.049604 -4.332478)
		(size 0.4572)
		(drill 0.2032)
		(layers "F.Cu" "B.Cu")
		(net "M_J_MA<1>")
	)
	(via
		(at 90.049604 1.805432)
		(size 0.508)
		(drill 0.254)
		(layers "F.Cu" "B.Cu")
		(net "M_J_MA<1>")
	)
	(via
		(at 91.215718 -61.53404)
		(size 0.508)
		(drill 0.254)
		(layers "F.Cu" "B.Cu")
		(net "M_J_MA<1>")
	)
	(segment
		(start 90.04935 -5.621782)
		(end 90.04935 -4.358132)
		(width 0.1651)
		(layer "B.Cu")
		(net "M_J_MA<1>")
	)
	(segment
		(start 90.049604 -4.357878)
		(end 90.049604 -4.332478)
		(width 0.1651)
		(layer "B.Cu")
		(net "M_J_MA<1>")
	)
	(segment
		(start 90.04935 -4.358132)
		(end 90.049604 -4.357878)
		(width 0.1651)
		(layer "B.Cu")
		(net "M_J_MA<1>")
	)
	(segment
		(start 89.566496 -22.421596)
		(end 89.566496 -21.938996)
		(width 0.14224)
		(layer "In2.Cu")
		(net "M_J_MA<1>")
	)
	(segment
		(start 91.393772 -51.221894)
		(end 92.277692 -50.337974)
		(width 0.0889)
		(layer "In2.Cu")
		(net "M_J_MA<1>")
	)
	(segment
		(start 89.583768 -0.8128)
		(end 89.583768 0.7366)
		(width 0.14224)
		(layer "In2.Cu")
		(net "M_J_MA<1>")
	)
	(segment
		(start 89.639394 -17.715484)
		(end 89.616788 -17.692878)
		(width 0.14224)
		(layer "In2.Cu")
		(net "M_J_MA<1>")
	)
	(segment
		(start 89.634568 -6.8072)
		(end 90.049604 -6.392164)
		(width 0.14224)
		(layer "In2.Cu")
		(net "M_J_MA<1>")
	)
	(segment
		(start 89.639394 -21.866098)
		(end 89.639394 -17.715484)
		(width 0.14224)
		(layer "In2.Cu")
		(net "M_J_MA<1>")
	)
	(segment
		(start 89.558622 -23.31847)
		(end 89.744296 -23.132796)
		(width 0.14224)
		(layer "In2.Cu")
		(net "M_J_MA<1>")
	)
	(segment
		(start 89.64168 -3.924554)
		(end 89.64168 -0.870712)
		(width 0.14224)
		(layer "In2.Cu")
		(net "M_J_MA<1>")
	)
	(segment
		(start 91.215718 -61.53404)
		(end 91.545918 -60.77204)
		(width 0.0889)
		(layer "In2.Cu")
		(net "M_J_MA<1>")
	)
	(segment
		(start 89.616788 -12.287504)
		(end 89.634568 -12.269724)
		(width 0.14224)
		(layer "In2.Cu")
		(net "M_J_MA<1>")
	)
	(segment
		(start 91.545918 -60.77204)
		(end 91.562428 -60.743592)
		(width 0.0889)
		(layer "In2.Cu")
		(net "M_J_MA<1>")
	)
	(segment
		(start 89.64168 -0.870712)
		(end 89.583768 -0.8128)
		(width 0.14224)
		(layer "In2.Cu")
		(net "M_J_MA<1>")
	)
	(segment
		(start 89.566496 -21.938996)
		(end 89.639394 -21.866098)
		(width 0.14224)
		(layer "In2.Cu")
		(net "M_J_MA<1>")
	)
	(segment
		(start 92.277692 -50.337974)
		(end 92.277692 -49.87925)
		(width 0.0889)
		(layer "In2.Cu")
		(net "M_J_MA<1>")
	)
	(segment
		(start 90.049604 -4.332478)
		(end 89.64168 -3.924554)
		(width 0.14224)
		(layer "In2.Cu")
		(net "M_J_MA<1>")
	)
	(segment
		(start 89.583768 0.7366)
		(end 90.049604 1.202436)
		(width 0.14224)
		(layer "In2.Cu")
		(net "M_J_MA<1>")
	)
	(segment
		(start 89.558622 -24.315674)
		(end 89.558622 -23.31847)
		(width 0.14224)
		(layer "In2.Cu")
		(net "M_J_MA<1>")
	)
	(segment
		(start 92.277692 -49.87925)
		(end 92.277692 -27.034744)
		(width 0.14224)
		(layer "In2.Cu")
		(net "M_J_MA<1>")
	)
	(segment
		(start 90.049604 -6.392164)
		(end 90.049604 -4.332478)
		(width 0.14224)
		(layer "In2.Cu")
		(net "M_J_MA<1>")
	)
	(segment
		(start 91.393772 -52.77993)
		(end 91.393772 -51.221894)
		(width 0.0889)
		(layer "In2.Cu")
		(net "M_J_MA<1>")
	)
	(segment
		(start 89.744296 -23.132796)
		(end 89.744296 -22.599396)
		(width 0.14224)
		(layer "In2.Cu")
		(net "M_J_MA<1>")
	)
	(segment
		(start 90.049604 1.202436)
		(end 90.049604 1.805432)
		(width 0.14224)
		(layer "In2.Cu")
		(net "M_J_MA<1>")
	)
	(segment
		(start 92.277692 -27.034744)
		(end 89.558622 -24.315674)
		(width 0.14224)
		(layer "In2.Cu")
		(net "M_J_MA<1>")
	)
	(segment
		(start 89.616788 -17.692878)
		(end 89.616788 -12.287504)
		(width 0.14224)
		(layer "In2.Cu")
		(net "M_J_MA<1>")
	)
	(segment
		(start 89.744296 -22.599396)
		(end 89.566496 -22.421596)
		(width 0.14224)
		(layer "In2.Cu")
		(net "M_J_MA<1>")
	)
	(segment
		(start 89.634568 -12.269724)
		(end 89.634568 -6.8072)
		(width 0.14224)
		(layer "In2.Cu")
		(net "M_J_MA<1>")
	)
	(arc
		(start 91.562428 -59.353196)
		(mid 91.483297 -59.057794)
		(end 91.562428 -58.762392)
		(width 0.0889)
		(layer "In2.Cu")
		(net "M_J_MA<1>")
	)
	(arc
		(start 91.562428 -56.781192)
		(mid 91.615927 -56.581294)
		(end 91.562428 -56.381396)
		(width 0.0889)
		(layer "In2.Cu")
		(net "M_J_MA<1>")
	)
	(arc
		(start 91.562428 -53.409596)
		(mid 91.436651 -53.105864)
		(end 91.393772 -52.77993)
		(width 0.0889)
		(layer "In2.Cu")
		(net "M_J_MA<1>")
	)
	(arc
		(start 91.562428 -53.809392)
		(mid 91.615927 -53.609494)
		(end 91.562428 -53.409596)
		(width 0.0889)
		(layer "In2.Cu")
		(net "M_J_MA<1>")
	)
	(arc
		(start 91.562428 -60.743592)
		(mid 91.615927 -60.543694)
		(end 91.562428 -60.343796)
		(width 0.0889)
		(layer "In2.Cu")
		(net "M_J_MA<1>")
	)
	(arc
		(start 91.562428 -60.343796)
		(mid 91.483297 -60.048394)
		(end 91.562428 -59.752992)
		(width 0.0889)
		(layer "In2.Cu")
		(net "M_J_MA<1>")
	)
	(arc
		(start 91.562428 -54.400196)
		(mid 91.483297 -54.104794)
		(end 91.562428 -53.809392)
		(width 0.0889)
		(layer "In2.Cu")
		(net "M_J_MA<1>")
	)
	(arc
		(start 91.562428 -59.752992)
		(mid 91.615927 -59.553094)
		(end 91.562428 -59.353196)
		(width 0.0889)
		(layer "In2.Cu")
		(net "M_J_MA<1>")
	)
	(arc
		(start 91.562428 -56.381396)
		(mid 91.483297 -56.085994)
		(end 91.562428 -55.790592)
		(width 0.0889)
		(layer "In2.Cu")
		(net "M_J_MA<1>")
	)
	(arc
		(start 91.562428 -54.799992)
		(mid 91.615927 -54.600094)
		(end 91.562428 -54.400196)
		(width 0.0889)
		(layer "In2.Cu")
		(net "M_J_MA<1>")
	)
	(arc
		(start 91.562428 -58.762392)
		(mid 91.615927 -58.562494)
		(end 91.562428 -58.362596)
		(width 0.0889)
		(layer "In2.Cu")
		(net "M_J_MA<1>")
	)
	(arc
		(start 91.562428 -57.771792)
		(mid 91.615927 -57.571894)
		(end 91.562428 -57.371996)
		(width 0.0889)
		(layer "In2.Cu")
		(net "M_J_MA<1>")
	)
	(arc
		(start 91.562428 -58.362596)
		(mid 91.483297 -58.067194)
		(end 91.562428 -57.771792)
		(width 0.0889)
		(layer "In2.Cu")
		(net "M_J_MA<1>")
	)
	(arc
		(start 91.562428 -55.390796)
		(mid 91.483297 -55.095394)
		(end 91.562428 -54.799992)
		(width 0.0889)
		(layer "In2.Cu")
		(net "M_J_MA<1>")
	)
	(arc
		(start 91.562428 -57.371996)
		(mid 91.483297 -57.076594)
		(end 91.562428 -56.781192)
		(width 0.0889)
		(layer "In2.Cu")
		(net "M_J_MA<1>")
	)
	(arc
		(start 91.562428 -55.790592)
		(mid 91.615927 -55.590694)
		(end 91.562428 -55.390796)
		(width 0.0889)
		(layer "In2.Cu")
		(net "M_J_MA<1>")
	)
	(segment
		(start 110.44936 -0.821182)
		(end 110.44936 0.442722)
		(width 0.1651)
		(layer "F.Cu")
		(net "M_J_MA<17>")
	)
	(segment
		(start 102.089204 -60.54344)
		(end 101.517704 -60.54344)
		(width 0.1016)
		(layer "F.Cu")
		(net "M_J_MA<17>")
	)
	(via
		(at 101.517704 -60.54344)
		(size 0.508)
		(drill 0.254)
		(layers "F.Cu" "B.Cu")
		(net "M_J_MA<17>")
	)
	(via
		(at 110.44936 0.442722)
		(size 0.508)
		(drill 0.254)
		(layers "F.Cu" "B.Cu")
		(net "M_J_MA<17>")
	)
	(via
		(at 110.44936 -2.31648)
		(size 0.4572)
		(drill 0.2032)
		(layers "F.Cu" "B.Cu")
		(net "M_J_MA<17>")
	)
	(segment
		(start 110.44936 -2.31648)
		(end 110.44936 -1.021842)
		(width 0.1651)
		(layer "B.Cu")
		(net "M_J_MA<17>")
	)
	(segment
		(start 112.621568 -22.5044)
		(end 112.519968 -22.606)
		(width 0.14224)
		(layer "In11.Cu")
		(net "M_J_MA<17>")
	)
	(segment
		(start 110.885224 -7.395464)
		(end 111.478822 -7.989062)
		(width 0.14224)
		(layer "In11.Cu")
		(net "M_J_MA<17>")
	)
	(segment
		(start 110.44936 -2.779268)
		(end 110.885224 -3.215132)
		(width 0.14224)
		(layer "In11.Cu")
		(net "M_J_MA<17>")
	)
	(segment
		(start 110.44936 -2.31648)
		(end 110.449868 -2.316988)
		(width 0.14224)
		(layer "In11.Cu")
		(net "M_J_MA<17>")
	)
	(segment
		(start 110.44936 0.442722)
		(end 110.44936 -0.479806)
		(width 0.14224)
		(layer "In11.Cu")
		(net "M_J_MA<17>")
	)
	(segment
		(start 109.563662 -1.272286)
		(end 109.718602 -1.427226)
		(width 0.14224)
		(layer "In11.Cu")
		(net "M_J_MA<17>")
	)
	(segment
		(start 112.621568 -23.2156)
		(end 112.621568 -23.7236)
		(width 0.14224)
		(layer "In11.Cu")
		(net "M_J_MA<17>")
	)
	(segment
		(start 112.443768 -14.351)
		(end 112.443768 -15.533624)
		(width 0.14224)
		(layer "In11.Cu")
		(net "M_J_MA<17>")
	)
	(segment
		(start 112.519968 -22.606)
		(end 112.519968 -23.114)
		(width 0.14224)
		(layer "In11.Cu")
		(net "M_J_MA<17>")
	)
	(segment
		(start 112.621568 -21.9964)
		(end 112.621568 -22.5044)
		(width 0.14224)
		(layer "In11.Cu")
		(net "M_J_MA<17>")
	)
	(segment
		(start 112.586008 -8.92302)
		(end 112.586008 -9.43356)
		(width 0.14224)
		(layer "In11.Cu")
		(net "M_J_MA<17>")
	)
	(segment
		(start 110.44936 -1.582166)
		(end 110.44936 -2.31648)
		(width 0.14224)
		(layer "In11.Cu")
		(net "M_J_MA<17>")
	)
	(segment
		(start 110.885224 -3.215132)
		(end 110.885224 -7.395464)
		(width 0.14224)
		(layer "In11.Cu")
		(net "M_J_MA<17>")
	)
	(segment
		(start 112.591088 -15.680944)
		(end 112.591088 -18.95348)
		(width 0.14224)
		(layer "In11.Cu")
		(net "M_J_MA<17>")
	)
	(segment
		(start 110.29442 -0.634746)
		(end 109.718602 -0.634746)
		(width 0.14224)
		(layer "In11.Cu")
		(net "M_J_MA<17>")
	)
	(segment
		(start 112.519968 -19.0246)
		(end 112.519968 -21.8948)
		(width 0.14224)
		(layer "In11.Cu")
		(net "M_J_MA<17>")
	)
	(segment
		(start 112.418368 -9.6012)
		(end 112.418368 -10.957052)
		(width 0.14224)
		(layer "In11.Cu")
		(net "M_J_MA<17>")
	)
	(segment
		(start 112.621568 -23.7236)
		(end 112.570768 -23.7744)
		(width 0.14224)
		(layer "In11.Cu")
		(net "M_J_MA<17>")
	)
	(segment
		(start 104.496616 -35.896296)
		(end 104.496616 -49.337722)
		(width 0.14224)
		(layer "In11.Cu")
		(net "M_J_MA<17>")
	)
	(segment
		(start 112.418368 -10.957052)
		(end 112.583722 -11.122406)
		(width 0.14224)
		(layer "In11.Cu")
		(net "M_J_MA<17>")
	)
	(segment
		(start 112.591088 -18.95348)
		(end 112.519968 -19.0246)
		(width 0.14224)
		(layer "In11.Cu")
		(net "M_J_MA<17>")
	)
	(segment
		(start 110.29442 -1.427226)
		(end 110.44936 -1.582166)
		(width 0.14224)
		(layer "In11.Cu")
		(net "M_J_MA<17>")
	)
	(segment
		(start 111.478822 -7.989062)
		(end 111.65205 -7.989062)
		(width 0.14224)
		(layer "In11.Cu")
		(net "M_J_MA<17>")
	)
	(segment
		(start 112.443768 -15.533624)
		(end 112.591088 -15.680944)
		(width 0.14224)
		(layer "In11.Cu")
		(net "M_J_MA<17>")
	)
	(segment
		(start 112.519968 -23.114)
		(end 112.621568 -23.2156)
		(width 0.14224)
		(layer "In11.Cu")
		(net "M_J_MA<17>")
	)
	(segment
		(start 111.65205 -7.989062)
		(end 112.586008 -8.92302)
		(width 0.14224)
		(layer "In11.Cu")
		(net "M_J_MA<17>")
	)
	(segment
		(start 103.420672 -51.795934)
		(end 102.278434 -52.938172)
		(width 0.14224)
		(layer "In11.Cu")
		(net "M_J_MA<17>")
	)
	(segment
		(start 102.278434 -59.78271)
		(end 101.517704 -60.54344)
		(width 0.14224)
		(layer "In11.Cu")
		(net "M_J_MA<17>")
	)
	(segment
		(start 103.420672 -50.413666)
		(end 103.420672 -51.795934)
		(width 0.14224)
		(layer "In11.Cu")
		(net "M_J_MA<17>")
	)
	(segment
		(start 110.44936 -2.317496)
		(end 110.44936 -2.779268)
		(width 0.14224)
		(layer "In11.Cu")
		(net "M_J_MA<17>")
	)
	(segment
		(start 112.586008 -9.43356)
		(end 112.418368 -9.6012)
		(width 0.14224)
		(layer "In11.Cu")
		(net "M_J_MA<17>")
	)
	(segment
		(start 112.570768 -27.822144)
		(end 104.496616 -35.896296)
		(width 0.14224)
		(layer "In11.Cu")
		(net "M_J_MA<17>")
	)
	(segment
		(start 112.519968 -21.8948)
		(end 112.621568 -21.9964)
		(width 0.14224)
		(layer "In11.Cu")
		(net "M_J_MA<17>")
	)
	(segment
		(start 110.44936 -0.479806)
		(end 110.29442 -0.634746)
		(width 0.14224)
		(layer "In11.Cu")
		(net "M_J_MA<17>")
	)
	(segment
		(start 109.718602 -0.634746)
		(end 109.563662 -0.789686)
		(width 0.14224)
		(layer "In11.Cu")
		(net "M_J_MA<17>")
	)
	(segment
		(start 112.583722 -11.122406)
		(end 112.583722 -14.211046)
		(width 0.14224)
		(layer "In11.Cu")
		(net "M_J_MA<17>")
	)
	(segment
		(start 112.583722 -14.211046)
		(end 112.443768 -14.351)
		(width 0.14224)
		(layer "In11.Cu")
		(net "M_J_MA<17>")
	)
	(segment
		(start 109.563662 -0.789686)
		(end 109.563662 -1.272286)
		(width 0.14224)
		(layer "In11.Cu")
		(net "M_J_MA<17>")
	)
	(segment
		(start 110.449868 -2.316988)
		(end 110.44936 -2.317496)
		(width 0.14224)
		(layer "In11.Cu")
		(net "M_J_MA<17>")
	)
	(segment
		(start 104.496616 -49.337722)
		(end 103.420672 -50.413666)
		(width 0.14224)
		(layer "In11.Cu")
		(net "M_J_MA<17>")
	)
	(segment
		(start 112.570768 -23.7744)
		(end 112.570768 -27.822144)
		(width 0.14224)
		(layer "In11.Cu")
		(net "M_J_MA<17>")
	)
	(segment
		(start 102.278434 -52.938172)
		(end 102.278434 -59.78271)
		(width 0.14224)
		(layer "In11.Cu")
		(net "M_J_MA<17>")
	)
	(segment
		(start 109.718602 -1.427226)
		(end 110.29442 -1.427226)
		(width 0.14224)
		(layer "In11.Cu")
		(net "M_J_MA<17>")
	)
	(segment
		(start 96.938338 -59.55284)
		(end 96.366838 -59.55284)
		(width 0.1651)
		(layer "F.Cu")
		(net "M_J_MA<16>")
	)
	(segment
		(start 103.649526 1.805686)
		(end 103.649272 1.805432)
		(width 0.1651)
		(layer "F.Cu")
		(net "M_J_MA<16>")
	)
	(segment
		(start 103.649526 3.778758)
		(end 103.649526 1.805686)
		(width 0.1651)
		(layer "F.Cu")
		(net "M_J_MA<16>")
	)
	(via
		(at 103.649526 -4.328668)
		(size 0.4572)
		(drill 0.2032)
		(layers "F.Cu" "B.Cu")
		(net "M_J_MA<16>")
	)
	(via
		(at 103.649272 1.805432)
		(size 0.508)
		(drill 0.254)
		(layers "F.Cu" "B.Cu")
		(net "M_J_MA<16>")
	)
	(via
		(at 96.366838 -59.55284)
		(size 0.508)
		(drill 0.254)
		(layers "F.Cu" "B.Cu")
		(net "M_J_MA<16>")
	)
	(segment
		(start 103.649526 -5.621782)
		(end 103.649526 -4.328668)
		(width 0.1651)
		(layer "B.Cu")
		(net "M_J_MA<16>")
	)
	(segment
		(start 102.457758 -17.617186)
		(end 102.457758 -17.109186)
		(width 0.14224)
		(layer "In2.Cu")
		(net "M_J_MA<16>")
	)
	(segment
		(start 96.873822 -54.903624)
		(end 96.878648 -54.894988)
		(width 0.0889)
		(layer "In2.Cu")
		(net "M_J_MA<16>")
	)
	(segment
		(start 102.457758 -7.507986)
		(end 102.376224 -7.426452)
		(width 0.14224)
		(layer "In2.Cu")
		(net "M_J_MA<16>")
	)
	(segment
		(start 100.622608 -28.357068)
		(end 100.835968 -28.143708)
		(width 0.14224)
		(layer "In2.Cu")
		(net "M_J_MA<16>")
	)
	(segment
		(start 102.365556 -18.464784)
		(end 102.233222 -18.33245)
		(width 0.14224)
		(layer "In2.Cu")
		(net "M_J_MA<16>")
	)
	(segment
		(start 102.233222 -18.33245)
		(end 102.233222 -17.841722)
		(width 0.14224)
		(layer "In2.Cu")
		(net "M_J_MA<16>")
	)
	(segment
		(start 103.337868 1.494028)
		(end 103.649272 1.805432)
		(width 0.14224)
		(layer "In2.Cu")
		(net "M_J_MA<16>")
	)
	(segment
		(start 97.051368 -52.3748)
		(end 97.051368 -52.07)
		(width 0.0889)
		(layer "In2.Cu")
		(net "M_J_MA<16>")
	)
	(segment
		(start 102.17785 -8.675878)
		(end 102.17785 -8.295894)
		(width 0.14224)
		(layer "In2.Cu")
		(net "M_J_MA<16>")
	)
	(segment
		(start 102.233222 -17.841722)
		(end 102.457758 -17.617186)
		(width 0.14224)
		(layer "In2.Cu")
		(net "M_J_MA<16>")
	)
	(segment
		(start 102.227634 -22.62632)
		(end 102.432358 -22.421596)
		(width 0.14224)
		(layer "In2.Cu")
		(net "M_J_MA<16>")
	)
	(segment
		(start 102.432358 -21.938996)
		(end 102.305358 -21.811996)
		(width 0.14224)
		(layer "In2.Cu")
		(net "M_J_MA<16>")
	)
	(segment
		(start 102.376224 -7.426452)
		(end 102.376224 -5.60197)
		(width 0.14224)
		(layer "In2.Cu")
		(net "M_J_MA<16>")
	)
	(segment
		(start 99.564952 -28.736544)
		(end 99.564952 -28.449016)
		(width 0.14224)
		(layer "In2.Cu")
		(net "M_J_MA<16>")
	)
	(segment
		(start 96.825054 -59.094624)
		(end 96.825054 -58.064146)
		(width 0.0889)
		(layer "In2.Cu")
		(net "M_J_MA<16>")
	)
	(segment
		(start 97.725992 -51.395376)
		(end 97.725992 -50.811176)
		(width 0.0889)
		(layer "In2.Cu")
		(net "M_J_MA<16>")
	)
	(segment
		(start 102.432358 -12.337796)
		(end 102.386892 -12.29233)
		(width 0.14224)
		(layer "In2.Cu")
		(net "M_J_MA<16>")
	)
	(segment
		(start 102.386892 -8.88492)
		(end 102.17785 -8.675878)
		(width 0.14224)
		(layer "In2.Cu")
		(net "M_J_MA<16>")
	)
	(segment
		(start 99.564952 -28.449016)
		(end 99.852226 -28.161742)
		(width 0.14224)
		(layer "In2.Cu")
		(net "M_J_MA<16>")
	)
	(segment
		(start 102.305358 -19.58721)
		(end 102.365556 -19.527012)
		(width 0.14224)
		(layer "In2.Cu")
		(net "M_J_MA<16>")
	)
	(segment
		(start 102.440232 -24.334724)
		(end 102.440232 -23.31847)
		(width 0.14224)
		(layer "In2.Cu")
		(net "M_J_MA<16>")
	)
	(segment
		(start 99.852226 -28.161742)
		(end 100.139754 -28.161742)
		(width 0.14224)
		(layer "In2.Cu")
		(net "M_J_MA<16>")
	)
	(segment
		(start 96.878648 -53.904388)
		(end 96.884998 -53.89372)
		(width 0.0889)
		(layer "In2.Cu")
		(net "M_J_MA<16>")
	)
	(segment
		(start 98.204528 -48.525684)
		(end 98.204528 -48.302672)
		(width 0.0889)
		(layer "In2.Cu")
		(net "M_J_MA<16>")
	)
	(segment
		(start 103.172768 -3.85191)
		(end 103.172768 -2.5908)
		(width 0.14224)
		(layer "In2.Cu")
		(net "M_J_MA<16>")
	)
	(segment
		(start 99.760278 -28.93187)
		(end 99.564952 -28.736544)
		(width 0.14224)
		(layer "In2.Cu")
		(net "M_J_MA<16>")
	)
	(segment
		(start 96.873822 -55.894224)
		(end 96.878648 -55.885588)
		(width 0.0889)
		(layer "In2.Cu")
		(net "M_J_MA<16>")
	)
	(segment
		(start 102.389686 -13.666724)
		(end 102.196392 -13.47343)
		(width 0.14224)
		(layer "In2.Cu")
		(net "M_J_MA<16>")
	)
	(segment
		(start 102.457758 -8.015986)
		(end 102.457758 -7.507986)
		(width 0.14224)
		(layer "In2.Cu")
		(net "M_J_MA<16>")
	)
	(segment
		(start 103.216202 0.228854)
		(end 103.172768 0.272288)
		(width 0.14224)
		(layer "In2.Cu")
		(net "M_J_MA<16>")
	)
	(segment
		(start 102.457758 -17.109186)
		(end 102.389686 -17.041114)
		(width 0.14224)
		(layer "In2.Cu")
		(net "M_J_MA<16>")
	)
	(segment
		(start 97.725992 -50.811176)
		(end 97.914968 -50.6222)
		(width 0.0889)
		(layer "In2.Cu")
		(net "M_J_MA<16>")
	)
	(segment
		(start 97.051368 -52.07)
		(end 97.725992 -51.395376)
		(width 0.0889)
		(layer "In2.Cu")
		(net "M_J_MA<16>")
	)
	(segment
		(start 100.33508 -28.357068)
		(end 100.622608 -28.357068)
		(width 0.14224)
		(layer "In2.Cu")
		(net "M_J_MA<16>")
	)
	(segment
		(start 96.873822 -53.913024)
		(end 96.878648 -53.904388)
		(width 0.0889)
		(layer "In2.Cu")
		(net "M_J_MA<16>")
	)
	(segment
		(start 102.196392 -13.056362)
		(end 102.432358 -12.820396)
		(width 0.14224)
		(layer "In2.Cu")
		(net "M_J_MA<16>")
	)
	(segment
		(start 96.878648 -55.885588)
		(end 96.884998 -55.87492)
		(width 0.0889)
		(layer "In2.Cu")
		(net "M_J_MA<16>")
	)
	(segment
		(start 96.878648 -56.876188)
		(end 96.884998 -56.86552)
		(width 0.0889)
		(layer "In2.Cu")
		(net "M_J_MA<16>")
	)
	(segment
		(start 103.172768 0.272288)
		(end 103.172768 0.762)
		(width 0.14224)
		(layer "In2.Cu")
		(net "M_J_MA<16>")
	)
	(segment
		(start 103.216202 -2.547366)
		(end 103.216202 0.228854)
		(width 0.14224)
		(layer "In2.Cu")
		(net "M_J_MA<16>")
	)
	(segment
		(start 96.873822 -52.922424)
		(end 96.939354 -52.80533)
		(width 0.0889)
		(layer "In2.Cu")
		(net "M_J_MA<16>")
	)
	(segment
		(start 102.305358 -21.811996)
		(end 102.305358 -19.58721)
		(width 0.14224)
		(layer "In2.Cu")
		(net "M_J_MA<16>")
	)
	(segment
		(start 96.873822 -56.884824)
		(end 96.878648 -56.876188)
		(width 0.0889)
		(layer "In2.Cu")
		(net "M_J_MA<16>")
	)
	(segment
		(start 102.432358 -22.421596)
		(end 102.432358 -21.938996)
		(width 0.14224)
		(layer "In2.Cu")
		(net "M_J_MA<16>")
	)
	(segment
		(start 99.760278 -29.219398)
		(end 99.760278 -28.93187)
		(width 0.14224)
		(layer "In2.Cu")
		(net "M_J_MA<16>")
	)
	(segment
		(start 96.366838 -59.55284)
		(end 96.825054 -59.094624)
		(width 0.0889)
		(layer "In2.Cu")
		(net "M_J_MA<16>")
	)
	(segment
		(start 100.835968 -28.143708)
		(end 100.835968 -25.938988)
		(width 0.14224)
		(layer "In2.Cu")
		(net "M_J_MA<16>")
	)
	(segment
		(start 102.440232 -23.31847)
		(end 102.227634 -23.105872)
		(width 0.14224)
		(layer "In2.Cu")
		(net "M_J_MA<16>")
	)
	(segment
		(start 102.386892 -12.29233)
		(end 102.386892 -8.88492)
		(width 0.14224)
		(layer "In2.Cu")
		(net "M_J_MA<16>")
	)
	(segment
		(start 102.432358 -12.820396)
		(end 102.432358 -12.337796)
		(width 0.14224)
		(layer "In2.Cu")
		(net "M_J_MA<16>")
	)
	(segment
		(start 103.337868 0.9271)
		(end 103.337868 1.494028)
		(width 0.14224)
		(layer "In2.Cu")
		(net "M_J_MA<16>")
	)
	(segment
		(start 102.389686 -17.041114)
		(end 102.389686 -13.666724)
		(width 0.14224)
		(layer "In2.Cu")
		(net "M_J_MA<16>")
	)
	(segment
		(start 96.878648 -54.894988)
		(end 96.884998 -54.88432)
		(width 0.0889)
		(layer "In2.Cu")
		(net "M_J_MA<16>")
	)
	(segment
		(start 102.376224 -5.60197)
		(end 103.649526 -4.328668)
		(width 0.14224)
		(layer "In2.Cu")
		(net "M_J_MA<16>")
	)
	(segment
		(start 98.204528 -30.775148)
		(end 99.760278 -29.219398)
		(width 0.14224)
		(layer "In2.Cu")
		(net "M_J_MA<16>")
	)
	(segment
		(start 98.204528 -48.302672)
		(end 98.204528 -30.775148)
		(width 0.14224)
		(layer "In2.Cu")
		(net "M_J_MA<16>")
	)
	(segment
		(start 102.227634 -23.105872)
		(end 102.227634 -22.62632)
		(width 0.14224)
		(layer "In2.Cu")
		(net "M_J_MA<16>")
	)
	(segment
		(start 103.649526 -4.328668)
		(end 103.172768 -3.85191)
		(width 0.14224)
		(layer "In2.Cu")
		(net "M_J_MA<16>")
	)
	(segment
		(start 102.365556 -19.527012)
		(end 102.365556 -18.464784)
		(width 0.14224)
		(layer "In2.Cu")
		(net "M_J_MA<16>")
	)
	(segment
		(start 97.914968 -48.815244)
		(end 98.204528 -48.525684)
		(width 0.0889)
		(layer "In2.Cu")
		(net "M_J_MA<16>")
	)
	(segment
		(start 100.835968 -25.938988)
		(end 102.440232 -24.334724)
		(width 0.14224)
		(layer "In2.Cu")
		(net "M_J_MA<16>")
	)
	(segment
		(start 97.914968 -50.6222)
		(end 97.914968 -48.815244)
		(width 0.0889)
		(layer "In2.Cu")
		(net "M_J_MA<16>")
	)
	(segment
		(start 102.17785 -8.295894)
		(end 102.457758 -8.015986)
		(width 0.14224)
		(layer "In2.Cu")
		(net "M_J_MA<16>")
	)
	(segment
		(start 103.172768 -2.5908)
		(end 103.216202 -2.547366)
		(width 0.14224)
		(layer "In2.Cu")
		(net "M_J_MA<16>")
	)
	(segment
		(start 100.139754 -28.161742)
		(end 100.33508 -28.357068)
		(width 0.14224)
		(layer "In2.Cu")
		(net "M_J_MA<16>")
	)
	(segment
		(start 102.196392 -13.47343)
		(end 102.196392 -13.056362)
		(width 0.14224)
		(layer "In2.Cu")
		(net "M_J_MA<16>")
	)
	(segment
		(start 103.172768 0.762)
		(end 103.337868 0.9271)
		(width 0.14224)
		(layer "In2.Cu")
		(net "M_J_MA<16>")
	)
	(arc
		(start 96.878648 -54.304438)
		(mid 96.825178 -54.109375)
		(end 96.873822 -53.913024)
		(width 0.0889)
		(layer "In2.Cu")
		(net "M_J_MA<16>")
	)
	(arc
		(start 96.825054 -58.064146)
		(mid 96.839078 -57.962122)
		(end 96.878648 -57.867042)
		(width 0.0889)
		(layer "In2.Cu")
		(net "M_J_MA<16>")
	)
	(arc
		(start 96.939354 -52.80533)
		(mid 97.022915 -52.597236)
		(end 97.051368 -52.3748)
		(width 0.0889)
		(layer "In2.Cu")
		(net "M_J_MA<16>")
	)
	(arc
		(start 96.884998 -56.86552)
		(mid 96.957796 -56.574757)
		(end 96.878648 -56.285638)
		(width 0.0889)
		(layer "In2.Cu")
		(net "M_J_MA<16>")
	)
	(arc
		(start 96.878648 -57.276238)
		(mid 96.825178 -57.081175)
		(end 96.873822 -56.884824)
		(width 0.0889)
		(layer "In2.Cu")
		(net "M_J_MA<16>")
	)
	(arc
		(start 96.878648 -56.285638)
		(mid 96.825178 -56.090575)
		(end 96.873822 -55.894224)
		(width 0.0889)
		(layer "In2.Cu")
		(net "M_J_MA<16>")
	)
	(arc
		(start 96.878648 -55.295038)
		(mid 96.825178 -55.099975)
		(end 96.873822 -54.903624)
		(width 0.0889)
		(layer "In2.Cu")
		(net "M_J_MA<16>")
	)
	(arc
		(start 96.884998 -55.87492)
		(mid 96.957796 -55.584157)
		(end 96.878648 -55.295038)
		(width 0.0889)
		(layer "In2.Cu")
		(net "M_J_MA<16>")
	)
	(arc
		(start 96.884998 -54.88432)
		(mid 96.957796 -54.593557)
		(end 96.878648 -54.304438)
		(width 0.0889)
		(layer "In2.Cu")
		(net "M_J_MA<16>")
	)
	(arc
		(start 96.878648 -53.313838)
		(mid 96.825178 -53.118775)
		(end 96.873822 -52.922424)
		(width 0.0889)
		(layer "In2.Cu")
		(net "M_J_MA<16>")
	)
	(arc
		(start 96.878648 -57.867042)
		(mid 96.957779 -57.57164)
		(end 96.878648 -57.276238)
		(width 0.0889)
		(layer "In2.Cu")
		(net "M_J_MA<16>")
	)
	(arc
		(start 96.884998 -53.89372)
		(mid 96.957796 -53.602957)
		(end 96.878648 -53.313838)
		(width 0.0889)
		(layer "In2.Cu")
		(net "M_J_MA<16>")
	)
	(segment
		(start 107.04957 3.778758)
		(end 107.049316 3.778504)
		(width 0.1651)
		(layer "F.Cu")
		(net "M_J_MA<15>")
	)
	(segment
		(start 95.221298 -61.53404)
		(end 94.649798 -61.53404)
		(width 0.1016)
		(layer "F.Cu")
		(net "M_J_MA<15>")
	)
	(segment
		(start 107.049316 3.778504)
		(end 107.049316 1.805432)
		(width 0.1651)
		(layer "F.Cu")
		(net "M_J_MA<15>")
	)
	(via
		(at 94.649798 -61.53404)
		(size 0.508)
		(drill 0.254)
		(layers "F.Cu" "B.Cu")
		(net "M_J_MA<15>")
	)
	(via
		(at 107.049316 1.805432)
		(size 0.508)
		(drill 0.254)
		(layers "F.Cu" "B.Cu")
		(net "M_J_MA<15>")
	)
	(via
		(at 107.049824 -4.332478)
		(size 0.4572)
		(drill 0.2032)
		(layers "F.Cu" "B.Cu")
		(net "M_J_MA<15>")
	)
	(segment
		(start 107.04957 -4.332732)
		(end 107.049824 -4.332478)
		(width 0.10795)
		(layer "B.Cu")
		(net "M_J_MA<15>")
	)
	(segment
		(start 107.04957 -5.621782)
		(end 107.04957 -4.332732)
		(width 0.10795)
		(layer "B.Cu")
		(net "M_J_MA<15>")
	)
	(segment
		(start 106.576368 -2.7432)
		(end 106.638344 -2.681224)
		(width 0.14224)
		(layer "In11.Cu")
		(net "M_J_MA<15>")
	)
	(segment
		(start 103.452168 -19.2278)
		(end 103.214678 -18.99031)
		(width 0.14224)
		(layer "In11.Cu")
		(net "M_J_MA<15>")
	)
	(segment
		(start 97.667572 -49.920652)
		(end 97.667572 -49.453038)
		(width 0.0889)
		(layer "In11.Cu")
		(net "M_J_MA<15>")
	)
	(segment
		(start 99.239324 -30.83814)
		(end 99.239324 -30.619192)
		(width 0.14224)
		(layer "In11.Cu")
		(net "M_J_MA<15>")
	)
	(segment
		(start 97.865184 -31.487364)
		(end 97.865184 -31.268416)
		(width 0.14224)
		(layer "In11.Cu")
		(net "M_J_MA<15>")
	)
	(segment
		(start 94.649798 -61.53404)
		(end 95.076772 -60.629292)
		(width 0.0889)
		(layer "In11.Cu")
		(net "M_J_MA<15>")
	)
	(segment
		(start 95.593408 -53.594)
		(end 95.933768 -53.25364)
		(width 0.0889)
		(layer "In11.Cu")
		(net "M_J_MA<15>")
	)
	(segment
		(start 99.32797 -29.80563)
		(end 99.546918 -29.80563)
		(width 0.14224)
		(layer "In11.Cu")
		(net "M_J_MA<15>")
	)
	(segment
		(start 106.576368 -3.571494)
		(end 106.576368 -2.7432)
		(width 0.14224)
		(layer "In11.Cu")
		(net "M_J_MA<15>")
	)
	(segment
		(start 98.897694 -31.17977)
		(end 99.239324 -30.83814)
		(width 0.14224)
		(layer "In11.Cu")
		(net "M_J_MA<15>")
	)
	(segment
		(start 97.667572 -32.409892)
		(end 98.118168 -31.959296)
		(width 0.14224)
		(layer "In11.Cu")
		(net "M_J_MA<15>")
	)
	(segment
		(start 106.576368 0.679704)
		(end 107.049316 1.152652)
		(width 0.14224)
		(layer "In11.Cu")
		(net "M_J_MA<15>")
	)
	(segment
		(start 103.214678 -18.99031)
		(end 103.214678 -17.72031)
		(width 0.14224)
		(layer "In11.Cu")
		(net "M_J_MA<15>")
	)
	(segment
		(start 95.933768 -52.349146)
		(end 96.086168 -52.197)
		(width 0.0889)
		(layer "In11.Cu")
		(net "M_J_MA<15>")
	)
	(segment
		(start 103.172768 -21.971)
		(end 103.452168 -21.6916)
		(width 0.14224)
		(layer "In11.Cu")
		(net "M_J_MA<15>")
	)
	(segment
		(start 104.188768 -23.452836)
		(end 103.172768 -22.436836)
		(width 0.14224)
		(layer "In11.Cu")
		(net "M_J_MA<15>")
	)
	(segment
		(start 107.049824 -4.332478)
		(end 107.049824 -4.04495)
		(width 0.14224)
		(layer "In11.Cu")
		(net "M_J_MA<15>")
	)
	(segment
		(start 103.212646 -17.718278)
		(end 103.212646 -15.11173)
		(width 0.14224)
		(layer "In11.Cu")
		(net "M_J_MA<15>")
	)
	(segment
		(start 107.049824 -4.723638)
		(end 107.049824 -4.332478)
		(width 0.14224)
		(layer "In11.Cu")
		(net "M_J_MA<15>")
	)
	(segment
		(start 103.214678 -17.72031)
		(end 103.212646 -17.718278)
		(width 0.14224)
		(layer "In11.Cu")
		(net "M_J_MA<15>")
	)
	(segment
		(start 98.678746 -31.17977)
		(end 98.897694 -31.17977)
		(width 0.14224)
		(layer "In11.Cu")
		(net "M_J_MA<15>")
	)
	(segment
		(start 97.667572 -49.453038)
		(end 97.667572 -32.409892)
		(width 0.14224)
		(layer "In11.Cu")
		(net "M_J_MA<15>")
	)
	(segment
		(start 104.091232 -12.540234)
		(end 104.091232 -8.741664)
		(width 0.14224)
		(layer "In11.Cu")
		(net "M_J_MA<15>")
	)
	(segment
		(start 98.118168 -31.740348)
		(end 97.865184 -31.487364)
		(width 0.14224)
		(layer "In11.Cu")
		(net "M_J_MA<15>")
	)
	(segment
		(start 96.765364 -51.51755)
		(end 96.765364 -50.82286)
		(width 0.0889)
		(layer "In11.Cu")
		(net "M_J_MA<15>")
	)
	(segment
		(start 98.206814 -30.926786)
		(end 98.425762 -30.926786)
		(width 0.14224)
		(layer "In11.Cu")
		(net "M_J_MA<15>")
	)
	(segment
		(start 96.086168 -52.197)
		(end 96.765364 -51.51755)
		(width 0.0889)
		(layer "In11.Cu")
		(net "M_J_MA<15>")
	)
	(segment
		(start 99.546918 -29.80563)
		(end 99.799902 -30.058614)
		(width 0.14224)
		(layer "In11.Cu")
		(net "M_J_MA<15>")
	)
	(segment
		(start 106.638344 -1.992376)
		(end 106.576368 -1.9304)
		(width 0.14224)
		(layer "In11.Cu")
		(net "M_J_MA<15>")
	)
	(segment
		(start 102.197408 -27.880056)
		(end 103.304848 -27.880056)
		(width 0.14224)
		(layer "In11.Cu")
		(net "M_J_MA<15>")
	)
	(segment
		(start 107.049316 1.152652)
		(end 107.049316 1.805432)
		(width 0.14224)
		(layer "In11.Cu")
		(net "M_J_MA<15>")
	)
	(segment
		(start 106.638344 -2.681224)
		(end 106.638344 -1.992376)
		(width 0.14224)
		(layer "In11.Cu")
		(net "M_J_MA<15>")
	)
	(segment
		(start 104.188768 -26.996136)
		(end 104.188768 -23.452836)
		(width 0.14224)
		(layer "In11.Cu")
		(net "M_J_MA<15>")
	)
	(segment
		(start 97.865184 -31.268416)
		(end 98.206814 -30.926786)
		(width 0.14224)
		(layer "In11.Cu")
		(net "M_J_MA<15>")
	)
	(segment
		(start 98.425762 -30.926786)
		(end 98.678746 -31.17977)
		(width 0.14224)
		(layer "In11.Cu")
		(net "M_J_MA<15>")
	)
	(segment
		(start 104.158034 -12.607036)
		(end 104.091232 -12.540234)
		(width 0.14224)
		(layer "In11.Cu")
		(net "M_J_MA<15>")
	)
	(segment
		(start 103.452168 -21.6916)
		(end 103.452168 -19.2278)
		(width 0.14224)
		(layer "In11.Cu")
		(net "M_J_MA<15>")
	)
	(segment
		(start 104.061006 -13.41882)
		(end 104.158034 -13.321792)
		(width 0.14224)
		(layer "In11.Cu")
		(net "M_J_MA<15>")
	)
	(segment
		(start 98.98634 -30.366208)
		(end 98.98634 -30.14726)
		(width 0.14224)
		(layer "In11.Cu")
		(net "M_J_MA<15>")
	)
	(segment
		(start 104.091232 -8.741664)
		(end 104.919272 -7.913624)
		(width 0.14224)
		(layer "In11.Cu")
		(net "M_J_MA<15>")
	)
	(segment
		(start 96.765364 -50.82286)
		(end 97.667572 -49.920652)
		(width 0.0889)
		(layer "In11.Cu")
		(net "M_J_MA<15>")
	)
	(segment
		(start 104.917748 -6.855714)
		(end 107.049824 -4.723638)
		(width 0.14224)
		(layer "In11.Cu")
		(net "M_J_MA<15>")
	)
	(segment
		(start 98.98634 -30.14726)
		(end 99.32797 -29.80563)
		(width 0.14224)
		(layer "In11.Cu")
		(net "M_J_MA<15>")
	)
	(segment
		(start 104.158034 -13.321792)
		(end 104.158034 -12.607036)
		(width 0.14224)
		(layer "In11.Cu")
		(net "M_J_MA<15>")
	)
	(segment
		(start 95.4532 -53.594)
		(end 95.593408 -53.594)
		(width 0.0889)
		(layer "In11.Cu")
		(net "M_J_MA<15>")
	)
	(segment
		(start 104.919272 -7.524496)
		(end 104.917748 -7.522972)
		(width 0.14224)
		(layer "In11.Cu")
		(net "M_J_MA<15>")
	)
	(segment
		(start 100.01885 -30.058614)
		(end 102.197408 -27.880056)
		(width 0.14224)
		(layer "In11.Cu")
		(net "M_J_MA<15>")
	)
	(segment
		(start 104.917748 -7.522972)
		(end 104.917748 -6.855714)
		(width 0.14224)
		(layer "In11.Cu")
		(net "M_J_MA<15>")
	)
	(segment
		(start 103.212646 -15.11173)
		(end 104.061006 -14.26337)
		(width 0.14224)
		(layer "In11.Cu")
		(net "M_J_MA<15>")
	)
	(segment
		(start 104.919272 -7.913624)
		(end 104.919272 -7.524496)
		(width 0.14224)
		(layer "In11.Cu")
		(net "M_J_MA<15>")
	)
	(segment
		(start 106.576368 -1.9304)
		(end 106.576368 0.679704)
		(width 0.14224)
		(layer "In11.Cu")
		(net "M_J_MA<15>")
	)
	(segment
		(start 95.933768 -53.25364)
		(end 95.933768 -52.349146)
		(width 0.0889)
		(layer "In11.Cu")
		(net "M_J_MA<15>")
	)
	(segment
		(start 98.118168 -31.959296)
		(end 98.118168 -31.740348)
		(width 0.14224)
		(layer "In11.Cu")
		(net "M_J_MA<15>")
	)
	(segment
		(start 95.076772 -60.629292)
		(end 95.076772 -53.970428)
		(width 0.0889)
		(layer "In11.Cu")
		(net "M_J_MA<15>")
	)
	(segment
		(start 99.239324 -30.619192)
		(end 98.98634 -30.366208)
		(width 0.14224)
		(layer "In11.Cu")
		(net "M_J_MA<15>")
	)
	(segment
		(start 99.799902 -30.058614)
		(end 100.01885 -30.058614)
		(width 0.14224)
		(layer "In11.Cu")
		(net "M_J_MA<15>")
	)
	(segment
		(start 107.049824 -4.04495)
		(end 106.576368 -3.571494)
		(width 0.14224)
		(layer "In11.Cu")
		(net "M_J_MA<15>")
	)
	(segment
		(start 103.172768 -22.436836)
		(end 103.172768 -21.971)
		(width 0.14224)
		(layer "In11.Cu")
		(net "M_J_MA<15>")
	)
	(segment
		(start 103.304848 -27.880056)
		(end 104.188768 -26.996136)
		(width 0.14224)
		(layer "In11.Cu")
		(net "M_J_MA<15>")
	)
	(segment
		(start 95.076772 -53.970428)
		(end 95.4532 -53.594)
		(width 0.0889)
		(layer "In11.Cu")
		(net "M_J_MA<15>")
	)
	(segment
		(start 104.061006 -14.26337)
		(end 104.061006 -13.41882)
		(width 0.14224)
		(layer "In11.Cu")
		(net "M_J_MA<15>")
	)
	(segment
		(start 105.349548 -0.821182)
		(end 105.349548 0.442468)
		(width 0.1651)
		(layer "F.Cu")
		(net "M_J_MA<14>")
	)
	(segment
		(start 105.349548 0.442468)
		(end 105.349294 0.442722)
		(width 0.1651)
		(layer "F.Cu")
		(net "M_J_MA<14>")
	)
	(segment
		(start 98.655378 -58.561986)
		(end 98.083878 -58.561986)
		(width 0.1016)
		(layer "F.Cu")
		(net "M_J_MA<14>")
	)
	(via
		(at 105.349802 -2.316988)
		(size 0.4572)
		(drill 0.2032)
		(layers "F.Cu" "B.Cu")
		(net "M_J_MA<14>")
	)
	(via
		(at 98.083878 -58.561986)
		(size 0.508)
		(drill 0.254)
		(layers "F.Cu" "B.Cu")
		(net "M_J_MA<14>")
	)
	(via
		(at 105.349294 0.442722)
		(size 0.508)
		(drill 0.254)
		(layers "F.Cu" "B.Cu")
		(net "M_J_MA<14>")
	)
	(segment
		(start 105.349548 -1.021842)
		(end 105.349548 -2.316734)
		(width 0.1651)
		(layer "B.Cu")
		(net "M_J_MA<14>")
	)
	(segment
		(start 105.349548 -2.316734)
		(end 105.349802 -2.316988)
		(width 0.1651)
		(layer "B.Cu")
		(net "M_J_MA<14>")
	)
	(segment
		(start 105.349294 -1.079246)
		(end 105.349294 0.442722)
		(width 0.14224)
		(layer "In2.Cu")
		(net "M_J_MA<14>")
	)
	(segment
		(start 105.762044 -4.011676)
		(end 105.349294 -3.598926)
		(width 0.14224)
		(layer "In2.Cu")
		(net "M_J_MA<14>")
	)
	(segment
		(start 105.019602 -12.972796)
		(end 104.841802 -12.794996)
		(width 0.14224)
		(layer "In2.Cu")
		(net "M_J_MA<14>")
	)
	(segment
		(start 98.640392 -52.245514)
		(end 98.640392 -51.26863)
		(width 0.0889)
		(layer "In2.Cu")
		(net "M_J_MA<14>")
	)
	(segment
		(start 105.349802 -2.316988)
		(end 105.349294 -2.31648)
		(width 0.14224)
		(layer "In2.Cu")
		(net "M_J_MA<14>")
	)
	(segment
		(start 99.072192 -49.185576)
		(end 99.728528 -48.52924)
		(width 0.0889)
		(layer "In2.Cu")
		(net "M_J_MA<14>")
	)
	(segment
		(start 105.349294 -2.317496)
		(end 105.349802 -2.316988)
		(width 0.14224)
		(layer "In2.Cu")
		(net "M_J_MA<14>")
	)
	(segment
		(start 98.511614 -52.67325)
		(end 98.640392 -52.245514)
		(width 0.0889)
		(layer "In2.Cu")
		(net "M_J_MA<14>")
	)
	(segment
		(start 98.414078 -57.799986)
		(end 98.435414 -57.762902)
		(width 0.0889)
		(layer "In2.Cu")
		(net "M_J_MA<14>")
	)
	(segment
		(start 104.994202 -8.193786)
		(end 104.841802 -8.041386)
		(width 0.14224)
		(layer "In2.Cu")
		(net "M_J_MA<14>")
	)
	(segment
		(start 104.994202 -21.761196)
		(end 104.994202 -19.141186)
		(width 0.14224)
		(layer "In2.Cu")
		(net "M_J_MA<14>")
	)
	(segment
		(start 104.994202 -18.379186)
		(end 104.994202 -17.104614)
		(width 0.14224)
		(layer "In2.Cu")
		(net "M_J_MA<14>")
	)
	(segment
		(start 105.762044 -5.297932)
		(end 105.762044 -4.011676)
		(width 0.14224)
		(layer "In2.Cu")
		(net "M_J_MA<14>")
	)
	(segment
		(start 98.424238 -56.791606)
		(end 98.430588 -56.780938)
		(width 0.0889)
		(layer "In2.Cu")
		(net "M_J_MA<14>")
	)
	(segment
		(start 104.841802 -8.041386)
		(end 104.841802 -7.533386)
		(width 0.14224)
		(layer "In2.Cu")
		(net "M_J_MA<14>")
	)
	(segment
		(start 99.728528 -48.52924)
		(end 99.728528 -48.315372)
		(width 0.0889)
		(layer "In2.Cu")
		(net "M_J_MA<14>")
	)
	(segment
		(start 104.841802 -12.312396)
		(end 104.942132 -12.212066)
		(width 0.14224)
		(layer "In2.Cu")
		(net "M_J_MA<14>")
	)
	(segment
		(start 99.728528 -31.407608)
		(end 103.198168 -27.937968)
		(width 0.14224)
		(layer "In2.Cu")
		(net "M_J_MA<14>")
	)
	(segment
		(start 104.942132 -12.212066)
		(end 104.942132 -8.830056)
		(width 0.14224)
		(layer "In2.Cu")
		(net "M_J_MA<14>")
	)
	(segment
		(start 104.994202 -17.104614)
		(end 104.932988 -17.0434)
		(width 0.14224)
		(layer "In2.Cu")
		(net "M_J_MA<14>")
	)
	(segment
		(start 106.309922 0.132842)
		(end 106.058462 0.132842)
		(width 0.14224)
		(layer "In2.Cu")
		(net "M_J_MA<14>")
	)
	(segment
		(start 98.083878 -58.561986)
		(end 98.414078 -57.799986)
		(width 0.0889)
		(layer "In2.Cu")
		(net "M_J_MA<14>")
	)
	(segment
		(start 106.317034 -1.826006)
		(end 106.471974 -1.671066)
		(width 0.14224)
		(layer "In2.Cu")
		(net "M_J_MA<14>")
	)
	(segment
		(start 98.430588 -53.809138)
		(end 98.435414 -53.800502)
		(width 0.0889)
		(layer "In2.Cu")
		(net "M_J_MA<14>")
	)
	(segment
		(start 105.349294 -1.980946)
		(end 105.504234 -1.826006)
		(width 0.14224)
		(layer "In2.Cu")
		(net "M_J_MA<14>")
	)
	(segment
		(start 104.841802 -7.533386)
		(end 104.937052 -7.438136)
		(width 0.14224)
		(layer "In2.Cu")
		(net "M_J_MA<14>")
	)
	(segment
		(start 103.198168 -27.937968)
		(end 103.198168 -25.875488)
		(width 0.14224)
		(layer "In2.Cu")
		(net "M_J_MA<14>")
	)
	(segment
		(start 105.019602 -23.107396)
		(end 105.019602 -22.573996)
		(width 0.14224)
		(layer "In2.Cu")
		(net "M_J_MA<14>")
	)
	(segment
		(start 105.349294 -2.31648)
		(end 105.349294 -1.980946)
		(width 0.14224)
		(layer "In2.Cu")
		(net "M_J_MA<14>")
	)
	(segment
		(start 105.910634 -0.014986)
		(end 105.910634 -1.079246)
		(width 0.14224)
		(layer "In2.Cu")
		(net "M_J_MA<14>")
	)
	(segment
		(start 105.910634 -1.079246)
		(end 105.755694 -1.234186)
		(width 0.14224)
		(layer "In2.Cu")
		(net "M_J_MA<14>")
	)
	(segment
		(start 105.019602 -22.573996)
		(end 104.841802 -22.396196)
		(width 0.14224)
		(layer "In2.Cu")
		(net "M_J_MA<14>")
	)
	(segment
		(start 104.937052 -6.122924)
		(end 105.762044 -5.297932)
		(width 0.14224)
		(layer "In2.Cu")
		(net "M_J_MA<14>")
	)
	(segment
		(start 98.640392 -51.26863)
		(end 99.072192 -50.83683)
		(width 0.0889)
		(layer "In2.Cu")
		(net "M_J_MA<14>")
	)
	(segment
		(start 104.715564 -23.411434)
		(end 105.019602 -23.107396)
		(width 0.14224)
		(layer "In2.Cu")
		(net "M_J_MA<14>")
	)
	(segment
		(start 106.058462 0.132842)
		(end 105.910634 -0.014986)
		(width 0.14224)
		(layer "In2.Cu")
		(net "M_J_MA<14>")
	)
	(segment
		(start 104.994202 -8.777986)
		(end 104.994202 -8.193786)
		(width 0.14224)
		(layer "In2.Cu")
		(net "M_J_MA<14>")
	)
	(segment
		(start 98.430588 -54.799738)
		(end 98.435414 -54.791102)
		(width 0.0889)
		(layer "In2.Cu")
		(net "M_J_MA<14>")
	)
	(segment
		(start 105.504234 -1.234186)
		(end 105.349294 -1.079246)
		(width 0.14224)
		(layer "In2.Cu")
		(net "M_J_MA<14>")
	)
	(segment
		(start 104.932988 -13.59281)
		(end 105.019602 -13.506196)
		(width 0.14224)
		(layer "In2.Cu")
		(net "M_J_MA<14>")
	)
	(segment
		(start 99.728528 -48.315372)
		(end 99.728528 -31.407608)
		(width 0.14224)
		(layer "In2.Cu")
		(net "M_J_MA<14>")
	)
	(segment
		(start 104.942132 -8.830056)
		(end 104.994202 -8.777986)
		(width 0.14224)
		(layer "In2.Cu")
		(net "M_J_MA<14>")
	)
	(segment
		(start 99.072192 -50.83683)
		(end 99.072192 -49.185576)
		(width 0.0889)
		(layer "In2.Cu")
		(net "M_J_MA<14>")
	)
	(segment
		(start 104.932988 -17.0434)
		(end 104.932988 -13.59281)
		(width 0.14224)
		(layer "In2.Cu")
		(net "M_J_MA<14>")
	)
	(segment
		(start 105.019602 -13.506196)
		(end 105.019602 -12.972796)
		(width 0.14224)
		(layer "In2.Cu")
		(net "M_J_MA<14>")
	)
	(segment
		(start 98.424238 -54.810406)
		(end 98.430588 -54.799738)
		(width 0.0889)
		(layer "In2.Cu")
		(net "M_J_MA<14>")
	)
	(segment
		(start 104.909366 -19.05635)
		(end 104.909366 -18.464022)
		(width 0.14224)
		(layer "In2.Cu")
		(net "M_J_MA<14>")
	)
	(segment
		(start 98.424238 -53.819806)
		(end 98.430588 -53.809138)
		(width 0.0889)
		(layer "In2.Cu")
		(net "M_J_MA<14>")
	)
	(segment
		(start 98.430588 -52.818284)
		(end 98.511614 -52.67325)
		(width 0.0889)
		(layer "In2.Cu")
		(net "M_J_MA<14>")
	)
	(segment
		(start 98.430588 -55.790338)
		(end 98.435414 -55.781702)
		(width 0.0889)
		(layer "In2.Cu")
		(net "M_J_MA<14>")
	)
	(segment
		(start 104.715564 -24.358092)
		(end 104.715564 -23.411434)
		(width 0.14224)
		(layer "In2.Cu")
		(net "M_J_MA<14>")
	)
	(segment
		(start 104.994202 -19.141186)
		(end 104.909366 -19.05635)
		(width 0.14224)
		(layer "In2.Cu")
		(net "M_J_MA<14>")
	)
	(segment
		(start 98.430588 -56.780938)
		(end 98.435414 -56.772302)
		(width 0.0889)
		(layer "In2.Cu")
		(net "M_J_MA<14>")
	)
	(segment
		(start 106.471974 -1.671066)
		(end 106.471974 -0.02921)
		(width 0.14224)
		(layer "In2.Cu")
		(net "M_J_MA<14>")
	)
	(segment
		(start 106.471974 -0.02921)
		(end 106.309922 0.132842)
		(width 0.14224)
		(layer "In2.Cu")
		(net "M_J_MA<14>")
	)
	(segment
		(start 105.504234 -1.826006)
		(end 106.317034 -1.826006)
		(width 0.14224)
		(layer "In2.Cu")
		(net "M_J_MA<14>")
	)
	(segment
		(start 105.349294 -3.598926)
		(end 105.349294 -2.317496)
		(width 0.14224)
		(layer "In2.Cu")
		(net "M_J_MA<14>")
	)
	(segment
		(start 104.841802 -12.794996)
		(end 104.841802 -12.312396)
		(width 0.14224)
		(layer "In2.Cu")
		(net "M_J_MA<14>")
	)
	(segment
		(start 103.198168 -25.875488)
		(end 104.715564 -24.358092)
		(width 0.14224)
		(layer "In2.Cu")
		(net "M_J_MA<14>")
	)
	(segment
		(start 104.841802 -21.913596)
		(end 104.994202 -21.761196)
		(width 0.14224)
		(layer "In2.Cu")
		(net "M_J_MA<14>")
	)
	(segment
		(start 105.755694 -1.234186)
		(end 105.504234 -1.234186)
		(width 0.14224)
		(layer "In2.Cu")
		(net "M_J_MA<14>")
	)
	(segment
		(start 104.909366 -18.464022)
		(end 104.994202 -18.379186)
		(width 0.14224)
		(layer "In2.Cu")
		(net "M_J_MA<14>")
	)
	(segment
		(start 98.424238 -55.801006)
		(end 98.430588 -55.790338)
		(width 0.0889)
		(layer "In2.Cu")
		(net "M_J_MA<14>")
	)
	(segment
		(start 104.841802 -22.396196)
		(end 104.841802 -21.913596)
		(width 0.14224)
		(layer "In2.Cu")
		(net "M_J_MA<14>")
	)
	(segment
		(start 104.937052 -7.438136)
		(end 104.937052 -6.122924)
		(width 0.14224)
		(layer "In2.Cu")
		(net "M_J_MA<14>")
	)
	(arc
		(start 98.430588 -57.371488)
		(mid 98.351366 -57.08237)
		(end 98.424238 -56.791606)
		(width 0.0889)
		(layer "In2.Cu")
		(net "M_J_MA<14>")
	)
	(arc
		(start 98.435414 -55.781702)
		(mid 98.484169 -55.58535)
		(end 98.430588 -55.390288)
		(width 0.0889)
		(layer "In2.Cu")
		(net "M_J_MA<14>")
	)
	(arc
		(start 98.430588 -54.399688)
		(mid 98.351366 -54.11057)
		(end 98.424238 -53.819806)
		(width 0.0889)
		(layer "In2.Cu")
		(net "M_J_MA<14>")
	)
	(arc
		(start 98.435414 -56.772302)
		(mid 98.484169 -56.57595)
		(end 98.430588 -56.380888)
		(width 0.0889)
		(layer "In2.Cu")
		(net "M_J_MA<14>")
	)
	(arc
		(start 98.435414 -54.791102)
		(mid 98.484169 -54.59475)
		(end 98.430588 -54.399688)
		(width 0.0889)
		(layer "In2.Cu")
		(net "M_J_MA<14>")
	)
	(arc
		(start 98.435414 -57.762902)
		(mid 98.484169 -57.56655)
		(end 98.430588 -57.371488)
		(width 0.0889)
		(layer "In2.Cu")
		(net "M_J_MA<14>")
	)
	(arc
		(start 98.430588 -56.380888)
		(mid 98.351366 -56.09177)
		(end 98.424238 -55.801006)
		(width 0.0889)
		(layer "In2.Cu")
		(net "M_J_MA<14>")
	)
	(arc
		(start 98.430588 -55.390288)
		(mid 98.351366 -55.10117)
		(end 98.424238 -54.810406)
		(width 0.0889)
		(layer "In2.Cu")
		(net "M_J_MA<14>")
	)
	(arc
		(start 98.430588 -53.409088)
		(mid 98.351457 -53.113686)
		(end 98.430588 -52.818284)
		(width 0.0889)
		(layer "In2.Cu")
		(net "M_J_MA<14>")
	)
	(arc
		(start 98.435414 -53.800502)
		(mid 98.484169 -53.60415)
		(end 98.430588 -53.409088)
		(width 0.0889)
		(layer "In2.Cu")
		(net "M_J_MA<14>")
	)
	(segment
		(start 108.749338 -0.821182)
		(end 108.749338 0.442722)
		(width 0.1651)
		(layer "F.Cu")
		(net "M_J_MA<13>")
	)
	(segment
		(start 96.079818 -61.038486)
		(end 95.508318 -61.038486)
		(width 0.1016)
		(layer "F.Cu")
		(net "M_J_MA<13>")
	)
	(via
		(at 95.508318 -61.038486)
		(size 0.508)
		(drill 0.254)
		(layers "F.Cu" "B.Cu")
		(net "M_J_MA<13>")
	)
	(via
		(at 108.749338 -2.31648)
		(size 0.4572)
		(drill 0.2032)
		(layers "F.Cu" "B.Cu")
		(net "M_J_MA<13>")
	)
	(via
		(at 108.749338 0.442722)
		(size 0.508)
		(drill 0.254)
		(layers "F.Cu" "B.Cu")
		(net "M_J_MA<13>")
	)
	(segment
		(start 108.749338 -1.021842)
		(end 108.749338 -2.31648)
		(width 0.1651)
		(layer "B.Cu")
		(net "M_J_MA<13>")
	)
	(segment
		(start 104.084628 -18.207736)
		(end 104.203754 -18.08861)
		(width 0.14224)
		(layer "In11.Cu")
		(net "M_J_MA<13>")
	)
	(segment
		(start 97.686368 -50.47488)
		(end 98.175572 -49.985676)
		(width 0.0889)
		(layer "In11.Cu")
		(net "M_J_MA<13>")
	)
	(segment
		(start 98.175572 -49.985676)
		(end 98.175572 -49.539398)
		(width 0.0889)
		(layer "In11.Cu")
		(net "M_J_MA<13>")
	)
	(segment
		(start 104.010968 -21.675852)
		(end 104.010968 -19.1262)
		(width 0.14224)
		(layer "In11.Cu")
		(net "M_J_MA<13>")
	)
	(segment
		(start 108.188506 -1.621536)
		(end 108.033566 -1.776476)
		(width 0.14224)
		(layer "In11.Cu")
		(net "M_J_MA<13>")
	)
	(segment
		(start 108.749338 -0.493014)
		(end 108.605066 -0.348742)
		(width 0.14224)
		(layer "In11.Cu")
		(net "M_J_MA<13>")
	)
	(segment
		(start 104.696768 -23.4442)
		(end 104.976168 -23.1648)
		(width 0.14224)
		(layer "In11.Cu")
		(net "M_J_MA<13>")
	)
	(segment
		(start 104.203754 -18.08861)
		(end 104.203754 -17.300702)
		(width 0.14224)
		(layer "In11.Cu")
		(net "M_J_MA<13>")
	)
	(segment
		(start 104.280716 -21.9456)
		(end 104.010968 -21.675852)
		(width 0.14224)
		(layer "In11.Cu")
		(net "M_J_MA<13>")
	)
	(segment
		(start 108.749338 -2.662682)
		(end 108.749338 -2.31648)
		(width 0.14224)
		(layer "In11.Cu")
		(net "M_J_MA<13>")
	)
	(segment
		(start 104.09047 -16.379698)
		(end 104.943402 -15.526766)
		(width 0.14224)
		(layer "In11.Cu")
		(net "M_J_MA<13>")
	)
	(segment
		(start 104.93375 -14.33576)
		(end 104.93375 -11.692382)
		(width 0.14224)
		(layer "In11.Cu")
		(net "M_J_MA<13>")
	)
	(segment
		(start 95.933768 -60.613036)
		(end 95.933768 -53.9496)
		(width 0.0889)
		(layer "In11.Cu")
		(net "M_J_MA<13>")
	)
	(segment
		(start 107.474512 -3.937508)
		(end 108.749338 -2.662682)
		(width 0.14224)
		(layer "In11.Cu")
		(net "M_J_MA<13>")
	)
	(segment
		(start 104.772968 -11.5316)
		(end 104.772968 -9.758172)
		(width 0.14224)
		(layer "In11.Cu")
		(net "M_J_MA<13>")
	)
	(segment
		(start 95.933768 -53.9496)
		(end 96.766634 -53.116734)
		(width 0.0889)
		(layer "In11.Cu")
		(net "M_J_MA<13>")
	)
	(segment
		(start 107.474512 -5.161788)
		(end 107.474512 -3.937508)
		(width 0.14224)
		(layer "In11.Cu")
		(net "M_J_MA<13>")
	)
	(segment
		(start 107.925362 0.442722)
		(end 108.749338 0.442722)
		(width 0.14224)
		(layer "In11.Cu")
		(net "M_J_MA<13>")
	)
	(segment
		(start 104.976168 -22.6314)
		(end 104.290368 -21.9456)
		(width 0.14224)
		(layer "In11.Cu")
		(net "M_J_MA<13>")
	)
	(segment
		(start 97.686368 -51.482752)
		(end 97.686368 -50.47488)
		(width 0.0889)
		(layer "In11.Cu")
		(net "M_J_MA<13>")
	)
	(segment
		(start 96.766634 -52.402486)
		(end 97.686368 -51.482752)
		(width 0.0889)
		(layer "In11.Cu")
		(net "M_J_MA<13>")
	)
	(segment
		(start 108.033566 -1.776476)
		(end 107.782106 -1.776476)
		(width 0.14224)
		(layer "In11.Cu")
		(net "M_J_MA<13>")
	)
	(segment
		(start 104.09047 -17.187418)
		(end 104.09047 -16.379698)
		(width 0.14224)
		(layer "In11.Cu")
		(net "M_J_MA<13>")
	)
	(segment
		(start 107.627166 0.144526)
		(end 107.925362 0.442722)
		(width 0.14224)
		(layer "In11.Cu")
		(net "M_J_MA<13>")
	)
	(segment
		(start 96.766634 -53.116734)
		(end 96.766634 -52.402486)
		(width 0.0889)
		(layer "In11.Cu")
		(net "M_J_MA<13>")
	)
	(segment
		(start 104.943402 -14.345412)
		(end 104.93375 -14.33576)
		(width 0.14224)
		(layer "In11.Cu")
		(net "M_J_MA<13>")
	)
	(segment
		(start 104.939338 -9.591802)
		(end 104.939338 -8.79983)
		(width 0.14224)
		(layer "In11.Cu")
		(net "M_J_MA<13>")
	)
	(segment
		(start 95.508318 -61.038486)
		(end 95.933768 -60.613036)
		(width 0.0889)
		(layer "In11.Cu")
		(net "M_J_MA<13>")
	)
	(segment
		(start 105.763568 -7.9756)
		(end 105.763568 -6.872732)
		(width 0.14224)
		(layer "In11.Cu")
		(net "M_J_MA<13>")
	)
	(segment
		(start 104.976168 -23.1648)
		(end 104.976168 -22.6314)
		(width 0.14224)
		(layer "In11.Cu")
		(net "M_J_MA<13>")
	)
	(segment
		(start 98.175572 -32.448754)
		(end 102.23627 -28.388056)
		(width 0.14224)
		(layer "In11.Cu")
		(net "M_J_MA<13>")
	)
	(segment
		(start 104.203754 -17.300702)
		(end 104.09047 -17.187418)
		(width 0.14224)
		(layer "In11.Cu")
		(net "M_J_MA<13>")
	)
	(segment
		(start 104.010968 -19.1262)
		(end 104.084628 -19.05254)
		(width 0.14224)
		(layer "In11.Cu")
		(net "M_J_MA<13>")
	)
	(segment
		(start 107.782106 -1.776476)
		(end 107.627166 -1.621536)
		(width 0.14224)
		(layer "In11.Cu")
		(net "M_J_MA<13>")
	)
	(segment
		(start 105.763568 -6.872732)
		(end 107.474512 -5.161788)
		(width 0.14224)
		(layer "In11.Cu")
		(net "M_J_MA<13>")
	)
	(segment
		(start 108.188506 -0.513842)
		(end 108.188506 -1.621536)
		(width 0.14224)
		(layer "In11.Cu")
		(net "M_J_MA<13>")
	)
	(segment
		(start 104.772968 -9.758172)
		(end 104.939338 -9.591802)
		(width 0.14224)
		(layer "In11.Cu")
		(net "M_J_MA<13>")
	)
	(segment
		(start 108.749338 -2.31648)
		(end 108.749338 -0.493014)
		(width 0.14224)
		(layer "In11.Cu")
		(net "M_J_MA<13>")
	)
	(segment
		(start 104.084628 -19.05254)
		(end 104.084628 -18.207736)
		(width 0.14224)
		(layer "In11.Cu")
		(net "M_J_MA<13>")
	)
	(segment
		(start 104.943402 -15.526766)
		(end 104.943402 -14.345412)
		(width 0.14224)
		(layer "In11.Cu")
		(net "M_J_MA<13>")
	)
	(segment
		(start 107.627166 -1.621536)
		(end 107.627166 0.144526)
		(width 0.14224)
		(layer "In11.Cu")
		(net "M_J_MA<13>")
	)
	(segment
		(start 108.353606 -0.348742)
		(end 108.188506 -0.513842)
		(width 0.14224)
		(layer "In11.Cu")
		(net "M_J_MA<13>")
	)
	(segment
		(start 104.939338 -8.79983)
		(end 105.763568 -7.9756)
		(width 0.14224)
		(layer "In11.Cu")
		(net "M_J_MA<13>")
	)
	(segment
		(start 98.175572 -49.539398)
		(end 98.175572 -32.448754)
		(width 0.14224)
		(layer "In11.Cu")
		(net "M_J_MA<13>")
	)
	(segment
		(start 102.23627 -28.388056)
		(end 103.515414 -28.388056)
		(width 0.14224)
		(layer "In11.Cu")
		(net "M_J_MA<13>")
	)
	(segment
		(start 104.93375 -11.692382)
		(end 104.772968 -11.5316)
		(width 0.14224)
		(layer "In11.Cu")
		(net "M_J_MA<13>")
	)
	(segment
		(start 104.290368 -21.9456)
		(end 104.280716 -21.9456)
		(width 0.14224)
		(layer "In11.Cu")
		(net "M_J_MA<13>")
	)
	(segment
		(start 108.605066 -0.348742)
		(end 108.353606 -0.348742)
		(width 0.14224)
		(layer "In11.Cu")
		(net "M_J_MA<13>")
	)
	(segment
		(start 103.515414 -28.388056)
		(end 104.696768 -27.206702)
		(width 0.14224)
		(layer "In11.Cu")
		(net "M_J_MA<13>")
	)
	(segment
		(start 104.696768 -27.206702)
		(end 104.696768 -23.4442)
		(width 0.14224)
		(layer "In11.Cu")
		(net "M_J_MA<13>")
	)
	(segment
		(start 84.0994 3.778758)
		(end 84.0994 2.485644)
		(width 0.1651)
		(layer "F.Cu")
		(net "M_J_MA<12>")
	)
	(segment
		(start 88.353392 -62.52464)
		(end 87.781892 -62.52464)
		(width 0.0889)
		(layer "F.Cu")
		(net "M_J_MA<12>")
	)
	(via
		(at 87.781892 -62.52464)
		(size 0.508)
		(drill 0.254)
		(layers "F.Cu" "B.Cu")
		(net "M_J_MA<12>")
	)
	(via
		(at 84.0994 2.485644)
		(size 0.508)
		(drill 0.254)
		(layers "F.Cu" "B.Cu")
		(net "M_J_MA<12>")
	)
	(via
		(at 84.0994 -4.332478)
		(size 0.4572)
		(drill 0.2032)
		(layers "F.Cu" "B.Cu")
		(net "M_J_MA<12>")
	)
	(segment
		(start 84.0994 -5.621782)
		(end 84.0994 -4.332478)
		(width 0.1651)
		(layer "B.Cu")
		(net "M_J_MA<12>")
	)
	(segment
		(start 83.658964 -2.064004)
		(end 83.658964 -2.609596)
		(width 0.14224)
		(layer "In11.Cu")
		(net "M_J_MA<12>")
	)
	(segment
		(start 85.340952 -5.57403)
		(end 86.367366 -5.57403)
		(width 0.14224)
		(layer "In11.Cu")
		(net "M_J_MA<12>")
	)
	(segment
		(start 91.550998 -59.81319)
		(end 91.271852 -60.050426)
		(width 0.0889)
		(layer "In11.Cu")
		(net "M_J_MA<12>")
	)
	(segment
		(start 87.069168 -7.39648)
		(end 88.029288 -8.3566)
		(width 0.14224)
		(layer "In11.Cu")
		(net "M_J_MA<12>")
	)
	(segment
		(start 91.650058 -52.02682)
		(end 91.650058 -59.55792)
		(width 0.0889)
		(layer "In11.Cu")
		(net "M_J_MA<12>")
	)
	(segment
		(start 91.911932 -18.589752)
		(end 91.192604 -19.30908)
		(width 0.14224)
		(layer "In11.Cu")
		(net "M_J_MA<12>")
	)
	(segment
		(start 83.792568 -1.9304)
		(end 83.658964 -2.064004)
		(width 0.14224)
		(layer "In11.Cu")
		(net "M_J_MA<12>")
	)
	(segment
		(start 84.0994 1.889506)
		(end 83.6295 1.419606)
		(width 0.14224)
		(layer "In11.Cu")
		(net "M_J_MA<12>")
	)
	(segment
		(start 83.817968 -4.051046)
		(end 84.0994 -4.332478)
		(width 0.14224)
		(layer "In11.Cu")
		(net "M_J_MA<12>")
	)
	(segment
		(start 83.658964 -2.609596)
		(end 83.817968 -2.7686)
		(width 0.14224)
		(layer "In11.Cu")
		(net "M_J_MA<12>")
	)
	(segment
		(start 88.276938 -61.858652)
		(end 87.781892 -62.52464)
		(width 0.0889)
		(layer "In11.Cu")
		(net "M_J_MA<12>")
	)
	(segment
		(start 86.367366 -5.57403)
		(end 87.069168 -6.275832)
		(width 0.14224)
		(layer "In11.Cu")
		(net "M_J_MA<12>")
	)
	(segment
		(start 90.508328 -13.80236)
		(end 90.508328 -15.63116)
		(width 0.14224)
		(layer "In11.Cu")
		(net "M_J_MA<12>")
	)
	(segment
		(start 88.760808 -8.85444)
		(end 88.760808 -12.30884)
		(width 0.14224)
		(layer "In11.Cu")
		(net "M_J_MA<12>")
	)
	(segment
		(start 91.192604 -19.30908)
		(end 91.192604 -21.090636)
		(width 0.14224)
		(layer "In11.Cu")
		(net "M_J_MA<12>")
	)
	(segment
		(start 91.901772 -25.015444)
		(end 91.901772 -50.451258)
		(width 0.14224)
		(layer "In11.Cu")
		(net "M_J_MA<12>")
	)
	(segment
		(start 84.0994 -4.332478)
		(end 85.340952 -5.57403)
		(width 0.14224)
		(layer "In11.Cu")
		(net "M_J_MA<12>")
	)
	(segment
		(start 91.419172 -24.532844)
		(end 91.901772 -25.015444)
		(width 0.14224)
		(layer "In11.Cu")
		(net "M_J_MA<12>")
	)
	(segment
		(start 91.419172 -21.317204)
		(end 91.419172 -24.532844)
		(width 0.14224)
		(layer "In11.Cu")
		(net "M_J_MA<12>")
	)
	(segment
		(start 91.911932 -17.034764)
		(end 91.911932 -18.589752)
		(width 0.14224)
		(layer "In11.Cu")
		(net "M_J_MA<12>")
	)
	(segment
		(start 91.901772 -50.451258)
		(end 91.901772 -50.808382)
		(width 0.0889)
		(layer "In11.Cu")
		(net "M_J_MA<12>")
	)
	(segment
		(start 89.329768 -12.6238)
		(end 90.508328 -13.80236)
		(width 0.14224)
		(layer "In11.Cu")
		(net "M_J_MA<12>")
	)
	(segment
		(start 88.262968 -8.3566)
		(end 88.760808 -8.85444)
		(width 0.14224)
		(layer "In11.Cu")
		(net "M_J_MA<12>")
	)
	(segment
		(start 84.0994 2.485644)
		(end 84.0994 1.889506)
		(width 0.14224)
		(layer "In11.Cu")
		(net "M_J_MA<12>")
	)
	(segment
		(start 91.068398 -60.160154)
		(end 88.43772 -61.6839)
		(width 0.0889)
		(layer "In11.Cu")
		(net "M_J_MA<12>")
	)
	(segment
		(start 90.508328 -15.63116)
		(end 91.911932 -17.034764)
		(width 0.14224)
		(layer "In11.Cu")
		(net "M_J_MA<12>")
	)
	(segment
		(start 91.650058 -59.55792)
		(end 91.550998 -59.81319)
		(width 0.0889)
		(layer "In11.Cu")
		(net "M_J_MA<12>")
	)
	(segment
		(start 88.760808 -12.30884)
		(end 89.075768 -12.6238)
		(width 0.14224)
		(layer "In11.Cu")
		(net "M_J_MA<12>")
	)
	(segment
		(start 88.293702 -61.829188)
		(end 88.276938 -61.858652)
		(width 0.0889)
		(layer "In11.Cu")
		(net "M_J_MA<12>")
	)
	(segment
		(start 83.817968 -2.7686)
		(end 83.817968 -4.051046)
		(width 0.14224)
		(layer "In11.Cu")
		(net "M_J_MA<12>")
	)
	(segment
		(start 87.069168 -6.275832)
		(end 87.069168 -7.39648)
		(width 0.14224)
		(layer "In11.Cu")
		(net "M_J_MA<12>")
	)
	(segment
		(start 88.029288 -8.3566)
		(end 88.262968 -8.3566)
		(width 0.14224)
		(layer "In11.Cu")
		(net "M_J_MA<12>")
	)
	(segment
		(start 83.6295 1.419606)
		(end 83.6295 0.747268)
		(width 0.14224)
		(layer "In11.Cu")
		(net "M_J_MA<12>")
	)
	(segment
		(start 83.792568 0.5842)
		(end 83.792568 -1.9304)
		(width 0.14224)
		(layer "In11.Cu")
		(net "M_J_MA<12>")
	)
	(segment
		(start 89.075768 -12.6238)
		(end 89.329768 -12.6238)
		(width 0.14224)
		(layer "In11.Cu")
		(net "M_J_MA<12>")
	)
	(segment
		(start 83.6295 0.747268)
		(end 83.792568 0.5842)
		(width 0.14224)
		(layer "In11.Cu")
		(net "M_J_MA<12>")
	)
	(segment
		(start 91.901772 -50.808382)
		(end 91.650058 -52.02682)
		(width 0.0889)
		(layer "In11.Cu")
		(net "M_J_MA<12>")
	)
	(segment
		(start 91.192604 -21.090636)
		(end 91.419172 -21.317204)
		(width 0.14224)
		(layer "In11.Cu")
		(net "M_J_MA<12>")
	)
	(segment
		(start 91.271852 -60.050426)
		(end 91.068398 -60.160154)
		(width 0.0889)
		(layer "In11.Cu")
		(net "M_J_MA<12>")
	)
	(arc
		(start 88.43772 -61.6839)
		(mid 88.35627 -61.747185)
		(end 88.293702 -61.829188)
		(width 0.0889)
		(layer "In11.Cu")
		(net "M_J_MA<12>")
	)
	(segment
		(start 84.949538 -0.821182)
		(end 84.949538 0.442722)
		(width 0.1651)
		(layer "F.Cu")
		(net "M_J_MA<11>")
	)
	(segment
		(start 90.070178 -62.52464)
		(end 89.498678 -62.52464)
		(width 0.0889)
		(layer "F.Cu")
		(net "M_J_MA<11>")
	)
	(via
		(at 89.498678 -62.52464)
		(size 0.508)
		(drill 0.254)
		(layers "F.Cu" "B.Cu")
		(net "M_J_MA<11>")
	)
	(via
		(at 84.949538 0.442722)
		(size 0.508)
		(drill 0.254)
		(layers "F.Cu" "B.Cu")
		(net "M_J_MA<11>")
	)
	(via
		(at 84.949284 -2.314956)
		(size 0.4572)
		(drill 0.2032)
		(layers "F.Cu" "B.Cu")
		(net "M_J_MA<11>")
	)
	(segment
		(start 84.949538 -2.314702)
		(end 84.949284 -2.314956)
		(width 0.1651)
		(layer "B.Cu")
		(net "M_J_MA<11>")
	)
	(segment
		(start 84.949538 -1.021842)
		(end 84.949538 -2.314702)
		(width 0.1651)
		(layer "B.Cu")
		(net "M_J_MA<11>")
	)
	(segment
		(start 85.67166 -1.418336)
		(end 85.104224 -1.418336)
		(width 0.14224)
		(layer "In11.Cu")
		(net "M_J_MA<11>")
	)
	(segment
		(start 94.595442 -22.639274)
		(end 94.595442 -24.39035)
		(width 0.14224)
		(layer "In11.Cu")
		(net "M_J_MA<11>")
	)
	(segment
		(start 92.682568 -51.994562)
		(end 92.682568 -54.242716)
		(width 0.0889)
		(layer "In11.Cu")
		(net "M_J_MA<11>")
	)
	(segment
		(start 92.682568 -54.242716)
		(end 92.586048 -54.400196)
		(width 0.0889)
		(layer "In11.Cu")
		(net "M_J_MA<11>")
	)
	(segment
		(start 92.453714 -11.1252)
		(end 94.119192 -11.1252)
		(width 0.14224)
		(layer "In11.Cu")
		(net "M_J_MA<11>")
	)
	(segment
		(start 94.206568 -20.11045)
		(end 94.435168 -20.33905)
		(width 0.14224)
		(layer "In11.Cu")
		(net "M_J_MA<11>")
	)
	(segment
		(start 90.586052 -9.257538)
		(end 92.453714 -11.1252)
		(width 0.14224)
		(layer "In11.Cu")
		(net "M_J_MA<11>")
	)
	(segment
		(start 92.984066 -26.001726)
		(end 92.984066 -50.432716)
		(width 0.14224)
		(layer "In11.Cu")
		(net "M_J_MA<11>")
	)
	(segment
		(start 94.435168 -13.3096)
		(end 94.435168 -19.074384)
		(width 0.14224)
		(layer "In11.Cu")
		(net "M_J_MA<11>")
	)
	(segment
		(start 94.206568 -19.302984)
		(end 94.206568 -20.11045)
		(width 0.14224)
		(layer "In11.Cu")
		(net "M_J_MA<11>")
	)
	(segment
		(start 94.595442 -24.39035)
		(end 92.984066 -26.001726)
		(width 0.14224)
		(layer "In11.Cu")
		(net "M_J_MA<11>")
	)
	(segment
		(start 94.435168 -20.33905)
		(end 94.435168 -22.479)
		(width 0.14224)
		(layer "In11.Cu")
		(net "M_J_MA<11>")
	)
	(segment
		(start 85.104224 -0.625856)
		(end 85.67166 -0.625856)
		(width 0.14224)
		(layer "In11.Cu")
		(net "M_J_MA<11>")
	)
	(segment
		(start 91.387168 -62.9412)
		(end 90.929968 -62.9412)
		(width 0.0889)
		(layer "In11.Cu")
		(net "M_J_MA<11>")
	)
	(segment
		(start 84.949284 -0.470916)
		(end 85.104224 -0.625856)
		(width 0.14224)
		(layer "In11.Cu")
		(net "M_J_MA<11>")
	)
	(segment
		(start 94.435168 -19.074384)
		(end 94.206568 -19.302984)
		(width 0.14224)
		(layer "In11.Cu")
		(net "M_J_MA<11>")
	)
	(segment
		(start 84.949538 0.442722)
		(end 84.949284 0.442468)
		(width 0.14224)
		(layer "In11.Cu")
		(net "M_J_MA<11>")
	)
	(segment
		(start 84.949284 -2.314956)
		(end 85.809328 -3.175)
		(width 0.14224)
		(layer "In11.Cu")
		(net "M_J_MA<11>")
	)
	(segment
		(start 91.673934 -62.654434)
		(end 91.387168 -62.9412)
		(width 0.0889)
		(layer "In11.Cu")
		(net "M_J_MA<11>")
	)
	(segment
		(start 92.984066 -50.904902)
		(end 92.530168 -51.3588)
		(width 0.0889)
		(layer "In11.Cu")
		(net "M_J_MA<11>")
	)
	(segment
		(start 94.119192 -11.1252)
		(end 94.892368 -11.898376)
		(width 0.14224)
		(layer "In11.Cu")
		(net "M_J_MA<11>")
	)
	(segment
		(start 92.151962 -61.629036)
		(end 92.063062 -61.629036)
		(width 0.0889)
		(layer "In11.Cu")
		(net "M_J_MA<11>")
	)
	(segment
		(start 90.513408 -62.52464)
		(end 89.498678 -62.52464)
		(width 0.0889)
		(layer "In11.Cu")
		(net "M_J_MA<11>")
	)
	(segment
		(start 85.8266 -0.780796)
		(end 85.8266 -1.263396)
		(width 0.14224)
		(layer "In11.Cu")
		(net "M_J_MA<11>")
	)
	(segment
		(start 92.530168 -51.731672)
		(end 92.682568 -51.994562)
		(width 0.0889)
		(layer "In11.Cu")
		(net "M_J_MA<11>")
	)
	(segment
		(start 92.532708 -60.55487)
		(end 92.532708 -61.24829)
		(width 0.0889)
		(layer "In11.Cu")
		(net "M_J_MA<11>")
	)
	(segment
		(start 87.831168 -3.175)
		(end 88.115394 -3.459226)
		(width 0.14224)
		(layer "In11.Cu")
		(net "M_J_MA<11>")
	)
	(segment
		(start 85.67166 -0.625856)
		(end 85.8266 -0.780796)
		(width 0.14224)
		(layer "In11.Cu")
		(net "M_J_MA<11>")
	)
	(segment
		(start 94.435168 -22.479)
		(end 94.595442 -22.639274)
		(width 0.14224)
		(layer "In11.Cu")
		(net "M_J_MA<11>")
	)
	(segment
		(start 85.809328 -3.175)
		(end 87.831168 -3.175)
		(width 0.14224)
		(layer "In11.Cu")
		(net "M_J_MA<11>")
	)
	(segment
		(start 89.634568 -7.5946)
		(end 90.586052 -8.546084)
		(width 0.14224)
		(layer "In11.Cu")
		(net "M_J_MA<11>")
	)
	(segment
		(start 89.037922 -3.459226)
		(end 89.634568 -4.055872)
		(width 0.14224)
		(layer "In11.Cu")
		(net "M_J_MA<11>")
	)
	(segment
		(start 88.115394 -3.459226)
		(end 89.037922 -3.459226)
		(width 0.14224)
		(layer "In11.Cu")
		(net "M_J_MA<11>")
	)
	(segment
		(start 84.949284 -1.573276)
		(end 84.949284 -2.314956)
		(width 0.14224)
		(layer "In11.Cu")
		(net "M_J_MA<11>")
	)
	(segment
		(start 94.892368 -11.898376)
		(end 94.892368 -12.8524)
		(width 0.14224)
		(layer "In11.Cu")
		(net "M_J_MA<11>")
	)
	(segment
		(start 94.892368 -12.8524)
		(end 94.435168 -13.3096)
		(width 0.14224)
		(layer "In11.Cu")
		(net "M_J_MA<11>")
	)
	(segment
		(start 90.929968 -62.9412)
		(end 90.513408 -62.52464)
		(width 0.0889)
		(layer "In11.Cu")
		(net "M_J_MA<11>")
	)
	(segment
		(start 85.8266 -1.263396)
		(end 85.67166 -1.418336)
		(width 0.14224)
		(layer "In11.Cu")
		(net "M_J_MA<11>")
	)
	(segment
		(start 92.530168 -51.3588)
		(end 92.530168 -51.731672)
		(width 0.0889)
		(layer "In11.Cu")
		(net "M_J_MA<11>")
	)
	(segment
		(start 91.673934 -62.0268)
		(end 91.673934 -62.654434)
		(width 0.0889)
		(layer "In11.Cu")
		(net "M_J_MA<11>")
	)
	(segment
		(start 90.586052 -8.546084)
		(end 90.586052 -9.257538)
		(width 0.14224)
		(layer "In11.Cu")
		(net "M_J_MA<11>")
	)
	(segment
		(start 92.984066 -50.432716)
		(end 92.984066 -50.904902)
		(width 0.0889)
		(layer "In11.Cu")
		(net "M_J_MA<11>")
	)
	(segment
		(start 85.104224 -1.418336)
		(end 84.949284 -1.573276)
		(width 0.14224)
		(layer "In11.Cu")
		(net "M_J_MA<11>")
	)
	(segment
		(start 89.634568 -4.055872)
		(end 89.634568 -7.5946)
		(width 0.14224)
		(layer "In11.Cu")
		(net "M_J_MA<11>")
	)
	(segment
		(start 84.949284 0.442468)
		(end 84.949284 -0.470916)
		(width 0.14224)
		(layer "In11.Cu")
		(net "M_J_MA<11>")
	)
	(segment
		(start 92.532708 -61.24829)
		(end 92.151962 -61.629036)
		(width 0.0889)
		(layer "In11.Cu")
		(net "M_J_MA<11>")
	)
	(arc
		(start 92.586048 -58.762392)
		(mid 92.665179 -59.057794)
		(end 92.586048 -59.353196)
		(width 0.0889)
		(layer "In11.Cu")
		(net "M_J_MA<11>")
	)
	(arc
		(start 92.586048 -54.799992)
		(mid 92.665179 -55.095394)
		(end 92.586048 -55.390796)
		(width 0.0889)
		(layer "In11.Cu")
		(net "M_J_MA<11>")
	)
	(arc
		(start 92.063062 -61.629036)
		(mid 91.788123 -61.749259)
		(end 91.673934 -62.0268)
		(width 0.0889)
		(layer "In11.Cu")
		(net "M_J_MA<11>")
	)
	(arc
		(start 92.586048 -59.353196)
		(mid 92.532549 -59.553094)
		(end 92.586048 -59.752992)
		(width 0.0889)
		(layer "In11.Cu")
		(net "M_J_MA<11>")
	)
	(arc
		(start 92.586048 -56.381396)
		(mid 92.532549 -56.581294)
		(end 92.586048 -56.781192)
		(width 0.0889)
		(layer "In11.Cu")
		(net "M_J_MA<11>")
	)
	(arc
		(start 92.586048 -58.362596)
		(mid 92.532549 -58.562494)
		(end 92.586048 -58.762392)
		(width 0.0889)
		(layer "In11.Cu")
		(net "M_J_MA<11>")
	)
	(arc
		(start 92.586048 -54.400196)
		(mid 92.532549 -54.600094)
		(end 92.586048 -54.799992)
		(width 0.0889)
		(layer "In11.Cu")
		(net "M_J_MA<11>")
	)
	(arc
		(start 92.586048 -57.371996)
		(mid 92.532549 -57.571894)
		(end 92.586048 -57.771792)
		(width 0.0889)
		(layer "In11.Cu")
		(net "M_J_MA<11>")
	)
	(arc
		(start 92.586048 -60.343796)
		(mid 92.544748 -60.445636)
		(end 92.532708 -60.55487)
		(width 0.0889)
		(layer "In11.Cu")
		(net "M_J_MA<11>")
	)
	(arc
		(start 92.586048 -57.771792)
		(mid 92.665179 -58.067194)
		(end 92.586048 -58.362596)
		(width 0.0889)
		(layer "In11.Cu")
		(net "M_J_MA<11>")
	)
	(arc
		(start 92.586048 -56.781192)
		(mid 92.665179 -57.076594)
		(end 92.586048 -57.371996)
		(width 0.0889)
		(layer "In11.Cu")
		(net "M_J_MA<11>")
	)
	(arc
		(start 92.586048 -55.390796)
		(mid 92.532549 -55.590694)
		(end 92.586048 -55.790592)
		(width 0.0889)
		(layer "In11.Cu")
		(net "M_J_MA<11>")
	)
	(arc
		(start 92.586048 -59.752992)
		(mid 92.665179 -60.048394)
		(end 92.586048 -60.343796)
		(width 0.0889)
		(layer "In11.Cu")
		(net "M_J_MA<11>")
	)
	(arc
		(start 92.586048 -55.790592)
		(mid 92.665179 -56.085994)
		(end 92.586048 -56.381396)
		(width 0.0889)
		(layer "In11.Cu")
		(net "M_J_MA<11>")
	)
	(segment
		(start 94.362778 -61.038486)
		(end 93.791278 -61.038486)
		(width 0.1016)
		(layer "F.Cu")
		(net "M_J_MA<10>")
	)
	(segment
		(start 102.799388 -0.821182)
		(end 102.799388 1.152144)
		(width 0.1651)
		(layer "F.Cu")
		(net "M_J_MA<10>")
	)
	(via
		(at 102.799388 -2.316734)
		(size 0.4572)
		(drill 0.2032)
		(layers "F.Cu" "B.Cu")
		(net "M_J_MA<10>")
	)
	(via
		(at 93.791278 -61.038486)
		(size 0.508)
		(drill 0.254)
		(layers "F.Cu" "B.Cu")
		(net "M_J_MA<10>")
	)
	(via
		(at 102.799388 1.152144)
		(size 0.508)
		(drill 0.254)
		(layers "F.Cu" "B.Cu")
		(net "M_J_MA<10>")
	)
	(segment
		(start 102.799388 -1.021842)
		(end 102.799388 -2.316734)
		(width 0.1651)
		(layer "B.Cu")
		(net "M_J_MA<10>")
	)
	(segment
		(start 99.705668 -9.2837)
		(end 99.705668 -7.654036)
		(width 0.14224)
		(layer "In11.Cu")
		(net "M_J_MA<10>")
	)
	(segment
		(start 102.799642 -2.316988)
		(end 102.799388 -2.316734)
		(width 0.14224)
		(layer "In11.Cu")
		(net "M_J_MA<10>")
	)
	(segment
		(start 102.384352 -4.975352)
		(end 102.384352 -4.062984)
		(width 0.14224)
		(layer "In11.Cu")
		(net "M_J_MA<10>")
	)
	(segment
		(start 96.238568 -18.2626)
		(end 96.238568 -13.9827)
		(width 0.14224)
		(layer "In11.Cu")
		(net "M_J_MA<10>")
	)
	(segment
		(start 102.799388 1.152144)
		(end 102.799642 1.15189)
		(width 0.14224)
		(layer "In11.Cu")
		(net "M_J_MA<10>")
	)
	(segment
		(start 102.283768 -3.4036)
		(end 102.799642 -2.887726)
		(width 0.14224)
		(layer "In11.Cu")
		(net "M_J_MA<10>")
	)
	(segment
		(start 96.035368 -21.463)
		(end 96.035368 -18.4658)
		(width 0.14224)
		(layer "In11.Cu")
		(net "M_J_MA<10>")
	)
	(segment
		(start 94.009972 -26.746708)
		(end 95.857568 -24.899112)
		(width 0.14224)
		(layer "In11.Cu")
		(net "M_J_MA<10>")
	)
	(segment
		(start 96.035368 -18.4658)
		(end 96.238568 -18.2626)
		(width 0.14224)
		(layer "In11.Cu")
		(net "M_J_MA<10>")
	)
	(segment
		(start 102.384352 -4.062984)
		(end 102.283768 -3.9624)
		(width 0.14224)
		(layer "In11.Cu")
		(net "M_J_MA<10>")
	)
	(segment
		(start 99.760024 -10.397236)
		(end 99.285552 -9.922764)
		(width 0.14224)
		(layer "In11.Cu")
		(net "M_J_MA<10>")
	)
	(segment
		(start 98.724974 -10.483342)
		(end 99.192588 -10.950956)
		(width 0.14224)
		(layer "In11.Cu")
		(net "M_J_MA<10>")
	)
	(segment
		(start 99.192588 -10.950956)
		(end 99.386136 -10.950956)
		(width 0.14224)
		(layer "In11.Cu")
		(net "M_J_MA<10>")
	)
	(segment
		(start 93.391228 -53.901594)
		(end 93.571568 -53.721254)
		(width 0.0889)
		(layer "In11.Cu")
		(net "M_J_MA<10>")
	)
	(segment
		(start 94.009972 -50.793396)
		(end 94.009972 -50.432716)
		(width 0.0889)
		(layer "In11.Cu")
		(net "M_J_MA<10>")
	)
	(segment
		(start 93.571568 -53.721254)
		(end 93.571568 -51.2318)
		(width 0.0889)
		(layer "In11.Cu")
		(net "M_J_MA<10>")
	)
	(segment
		(start 96.238568 -13.9827)
		(end 97.457768 -12.7635)
		(width 0.14224)
		(layer "In11.Cu")
		(net "M_J_MA<10>")
	)
	(segment
		(start 93.571568 -51.2318)
		(end 94.009972 -50.793396)
		(width 0.0889)
		(layer "In11.Cu")
		(net "M_J_MA<10>")
	)
	(segment
		(start 93.791278 -61.038486)
		(end 93.461078 -60.27674)
		(width 0.0889)
		(layer "In11.Cu")
		(net "M_J_MA<10>")
	)
	(segment
		(start 94.009972 -50.432716)
		(end 94.009972 -26.746708)
		(width 0.14224)
		(layer "In11.Cu")
		(net "M_J_MA<10>")
	)
	(segment
		(start 102.799642 1.15189)
		(end 102.799642 -2.316988)
		(width 0.14224)
		(layer "In11.Cu")
		(net "M_J_MA<10>")
	)
	(segment
		(start 95.857568 -24.899112)
		(end 95.857568 -21.6408)
		(width 0.14224)
		(layer "In11.Cu")
		(net "M_J_MA<10>")
	)
	(segment
		(start 99.760024 -10.577068)
		(end 99.760024 -10.397236)
		(width 0.14224)
		(layer "In11.Cu")
		(net "M_J_MA<10>")
	)
	(segment
		(start 102.283768 -3.9624)
		(end 102.283768 -3.4036)
		(width 0.14224)
		(layer "In11.Cu")
		(net "M_J_MA<10>")
	)
	(segment
		(start 99.705668 -7.654036)
		(end 102.384352 -4.975352)
		(width 0.14224)
		(layer "In11.Cu")
		(net "M_J_MA<10>")
	)
	(segment
		(start 102.799642 -2.887726)
		(end 102.799642 -2.316988)
		(width 0.14224)
		(layer "In11.Cu")
		(net "M_J_MA<10>")
	)
	(segment
		(start 97.457768 -12.7635)
		(end 97.457768 -11.5316)
		(width 0.14224)
		(layer "In11.Cu")
		(net "M_J_MA<10>")
	)
	(segment
		(start 93.391228 -54.095396)
		(end 93.391228 -53.901594)
		(width 0.0889)
		(layer "In11.Cu")
		(net "M_J_MA<10>")
	)
	(segment
		(start 98.506026 -10.483342)
		(end 98.724974 -10.483342)
		(width 0.14224)
		(layer "In11.Cu")
		(net "M_J_MA<10>")
	)
	(segment
		(start 99.285552 -9.703816)
		(end 99.705668 -9.2837)
		(width 0.14224)
		(layer "In11.Cu")
		(net "M_J_MA<10>")
	)
	(segment
		(start 95.857568 -21.6408)
		(end 96.035368 -21.463)
		(width 0.14224)
		(layer "In11.Cu")
		(net "M_J_MA<10>")
	)
	(segment
		(start 93.461078 -60.27674)
		(end 93.444568 -60.248292)
		(width 0.0889)
		(layer "In11.Cu")
		(net "M_J_MA<10>")
	)
	(segment
		(start 97.457768 -11.5316)
		(end 98.506026 -10.483342)
		(width 0.14224)
		(layer "In11.Cu")
		(net "M_J_MA<10>")
	)
	(segment
		(start 99.285552 -9.922764)
		(end 99.285552 -9.703816)
		(width 0.14224)
		(layer "In11.Cu")
		(net "M_J_MA<10>")
	)
	(segment
		(start 99.386136 -10.950956)
		(end 99.760024 -10.577068)
		(width 0.14224)
		(layer "In11.Cu")
		(net "M_J_MA<10>")
	)
	(arc
		(start 93.444568 -58.857896)
		(mid 93.523699 -58.562494)
		(end 93.444568 -58.267092)
		(width 0.0889)
		(layer "In11.Cu")
		(net "M_J_MA<10>")
	)
	(arc
		(start 93.444568 -58.267092)
		(mid 93.391069 -58.067194)
		(end 93.444568 -57.867296)
		(width 0.0889)
		(layer "In11.Cu")
		(net "M_J_MA<10>")
	)
	(arc
		(start 93.444568 -54.304692)
		(mid 93.403487 -54.203713)
		(end 93.391228 -54.095396)
		(width 0.0889)
		(layer "In11.Cu")
		(net "M_J_MA<10>")
	)
	(arc
		(start 93.444568 -54.895496)
		(mid 93.523699 -54.600094)
		(end 93.444568 -54.304692)
		(width 0.0889)
		(layer "In11.Cu")
		(net "M_J_MA<10>")
	)
	(arc
		(start 93.444568 -55.886096)
		(mid 93.523699 -55.590694)
		(end 93.444568 -55.295292)
		(width 0.0889)
		(layer "In11.Cu")
		(net "M_J_MA<10>")
	)
	(arc
		(start 93.444568 -56.876696)
		(mid 93.523699 -56.581294)
		(end 93.444568 -56.285892)
		(width 0.0889)
		(layer "In11.Cu")
		(net "M_J_MA<10>")
	)
	(arc
		(start 93.444568 -57.276492)
		(mid 93.391069 -57.076594)
		(end 93.444568 -56.876696)
		(width 0.0889)
		(layer "In11.Cu")
		(net "M_J_MA<10>")
	)
	(arc
		(start 93.444568 -59.848496)
		(mid 93.523699 -59.553094)
		(end 93.444568 -59.257692)
		(width 0.0889)
		(layer "In11.Cu")
		(net "M_J_MA<10>")
	)
	(arc
		(start 93.444568 -57.867296)
		(mid 93.523699 -57.571894)
		(end 93.444568 -57.276492)
		(width 0.0889)
		(layer "In11.Cu")
		(net "M_J_MA<10>")
	)
	(arc
		(start 93.444568 -55.295292)
		(mid 93.391069 -55.095394)
		(end 93.444568 -54.895496)
		(width 0.0889)
		(layer "In11.Cu")
		(net "M_J_MA<10>")
	)
	(arc
		(start 93.444568 -60.248292)
		(mid 93.391069 -60.048394)
		(end 93.444568 -59.848496)
		(width 0.0889)
		(layer "In11.Cu")
		(net "M_J_MA<10>")
	)
	(arc
		(start 93.444568 -59.257692)
		(mid 93.391069 -59.057794)
		(end 93.444568 -58.857896)
		(width 0.0889)
		(layer "In11.Cu")
		(net "M_J_MA<10>")
	)
	(arc
		(start 93.444568 -56.285892)
		(mid 93.391069 -56.085994)
		(end 93.444568 -55.886096)
		(width 0.0889)
		(layer "In11.Cu")
		(net "M_J_MA<10>")
	)
	(segment
		(start 96.079818 -60.047886)
		(end 95.508318 -60.047886)
		(width 0.1016)
		(layer "F.Cu")
		(net "M_J_MA<0>")
	)
	(segment
		(start 101.099366 3.778758)
		(end 101.099366 2.514854)
		(width 0.1651)
		(layer "F.Cu")
		(net "M_J_MA<0>")
	)
	(via
		(at 95.508318 -60.047886)
		(size 0.508)
		(drill 0.254)
		(layers "F.Cu" "B.Cu")
		(net "M_J_MA<0>")
	)
	(via
		(at 101.099366 -4.328668)
		(size 0.4572)
		(drill 0.2032)
		(layers "F.Cu" "B.Cu")
		(net "M_J_MA<0>")
	)
	(via
		(at 101.099366 2.514854)
		(size 0.508)
		(drill 0.254)
		(layers "F.Cu" "B.Cu")
		(net "M_J_MA<0>")
	)
	(segment
		(start 101.099366 -5.621782)
		(end 101.099366 -4.328668)
		(width 0.1651)
		(layer "B.Cu")
		(net "M_J_MA<0>")
	)
	(segment
		(start 101.614478 0.85471)
		(end 101.614478 1.41097)
		(width 0.14224)
		(layer "In2.Cu")
		(net "M_J_MA<0>")
	)
	(segment
		(start 95.966788 -59.589416)
		(end 95.966788 -58.572146)
		(width 0.0889)
		(layer "In2.Cu")
		(net "M_J_MA<0>")
	)
	(segment
		(start 96.026478 -53.819806)
		(end 96.020128 -53.809138)
		(width 0.0889)
		(layer "In2.Cu")
		(net "M_J_MA<0>")
	)
	(segment
		(start 100.605336 -11.147806)
		(end 100.7491 -11.004042)
		(width 0.14224)
		(layer "In2.Cu")
		(net "M_J_MA<0>")
	)
	(segment
		(start 100.757736 -17.109186)
		(end 100.605336 -16.956786)
		(width 0.14224)
		(layer "In2.Cu")
		(net "M_J_MA<0>")
	)
	(segment
		(start 96.020128 -58.362088)
		(end 96.026478 -58.35142)
		(width 0.0889)
		(layer "In2.Cu")
		(net "M_J_MA<0>")
	)
	(segment
		(start 101.099366 -4.328668)
		(end 101.099366 -2.987802)
		(width 0.14224)
		(layer "In2.Cu")
		(net "M_J_MA<0>")
	)
	(segment
		(start 100.660962 -9.602216)
		(end 100.660962 -7.411212)
		(width 0.14224)
		(layer "In2.Cu")
		(net "M_J_MA<0>")
	)
	(segment
		(start 101.099366 1.926082)
		(end 101.099366 2.514854)
		(width 0.14224)
		(layer "In2.Cu")
		(net "M_J_MA<0>")
	)
	(segment
		(start 101.45395 -0.084582)
		(end 101.45395 0.694182)
		(width 0.14224)
		(layer "In2.Cu")
		(net "M_J_MA<0>")
	)
	(segment
		(start 100.732336 -12.820396)
		(end 100.732336 -12.337796)
		(width 0.14224)
		(layer "In2.Cu")
		(net "M_J_MA<0>")
	)
	(segment
		(start 100.937568 -4.490466)
		(end 101.099366 -4.328668)
		(width 0.14224)
		(layer "In2.Cu")
		(net "M_J_MA<0>")
	)
	(segment
		(start 99.819968 -25.517348)
		(end 100.74021 -24.597106)
		(width 0.14224)
		(layer "In2.Cu")
		(net "M_J_MA<0>")
	)
	(segment
		(start 96.020128 -56.780938)
		(end 96.015302 -56.772302)
		(width 0.0889)
		(layer "In2.Cu")
		(net "M_J_MA<0>")
	)
	(segment
		(start 97.188528 -29.3878)
		(end 99.819968 -26.75636)
		(width 0.14224)
		(layer "In2.Cu")
		(net "M_J_MA<0>")
	)
	(segment
		(start 100.732336 -21.938996)
		(end 100.605336 -21.811996)
		(width 0.14224)
		(layer "In2.Cu")
		(net "M_J_MA<0>")
	)
	(segment
		(start 101.45395 0.694182)
		(end 101.614478 0.85471)
		(width 0.14224)
		(layer "In2.Cu")
		(net "M_J_MA<0>")
	)
	(segment
		(start 96.020128 -53.809138)
		(end 96.015302 -53.800502)
		(width 0.0889)
		(layer "In2.Cu")
		(net "M_J_MA<0>")
	)
	(segment
		(start 100.7491 -11.004042)
		(end 100.7491 -9.690354)
		(width 0.14224)
		(layer "In2.Cu")
		(net "M_J_MA<0>")
	)
	(segment
		(start 100.554536 -23.132796)
		(end 100.554536 -22.599396)
		(width 0.14224)
		(layer "In2.Cu")
		(net "M_J_MA<0>")
	)
	(segment
		(start 100.554536 -22.599396)
		(end 100.732336 -22.421596)
		(width 0.14224)
		(layer "In2.Cu")
		(net "M_J_MA<0>")
	)
	(segment
		(start 100.605336 -6.910832)
		(end 100.937568 -6.5786)
		(width 0.14224)
		(layer "In2.Cu")
		(net "M_J_MA<0>")
	)
	(segment
		(start 100.732336 -22.421596)
		(end 100.732336 -21.938996)
		(width 0.14224)
		(layer "In2.Cu")
		(net "M_J_MA<0>")
	)
	(segment
		(start 96.020128 -55.790338)
		(end 96.015302 -55.781702)
		(width 0.0889)
		(layer "In2.Cu")
		(net "M_J_MA<0>")
	)
	(segment
		(start 100.74021 -23.31847)
		(end 100.554536 -23.132796)
		(width 0.14224)
		(layer "In2.Cu")
		(net "M_J_MA<0>")
	)
	(segment
		(start 100.605336 -16.105632)
		(end 100.64623 -16.064738)
		(width 0.14224)
		(layer "In2.Cu")
		(net "M_J_MA<0>")
	)
	(segment
		(start 96.015302 -52.427378)
		(end 96.020128 -52.418742)
		(width 0.0889)
		(layer "In2.Cu")
		(net "M_J_MA<0>")
	)
	(segment
		(start 95.508318 -60.047886)
		(end 95.966788 -59.589416)
		(width 0.0889)
		(layer "In2.Cu")
		(net "M_J_MA<0>")
	)
	(segment
		(start 100.605336 -7.355586)
		(end 100.605336 -6.910832)
		(width 0.14224)
		(layer "In2.Cu")
		(net "M_J_MA<0>")
	)
	(segment
		(start 97.188528 -48.35525)
		(end 97.188528 -29.3878)
		(width 0.14224)
		(layer "In2.Cu")
		(net "M_J_MA<0>")
	)
	(segment
		(start 100.64623 -16.064738)
		(end 100.64623 -12.906502)
		(width 0.14224)
		(layer "In2.Cu")
		(net "M_J_MA<0>")
	)
	(segment
		(start 100.74021 -24.597106)
		(end 100.74021 -23.31847)
		(width 0.14224)
		(layer "In2.Cu")
		(net "M_J_MA<0>")
	)
	(segment
		(start 100.605336 -12.210796)
		(end 100.605336 -11.147806)
		(width 0.14224)
		(layer "In2.Cu")
		(net "M_J_MA<0>")
	)
	(segment
		(start 100.937568 -6.5786)
		(end 100.937568 -4.490466)
		(width 0.14224)
		(layer "In2.Cu")
		(net "M_J_MA<0>")
	)
	(segment
		(start 96.026478 -55.801006)
		(end 96.020128 -55.790338)
		(width 0.0889)
		(layer "In2.Cu")
		(net "M_J_MA<0>")
	)
	(segment
		(start 97.188528 -50.104294)
		(end 97.188528 -48.35525)
		(width 0.0889)
		(layer "In2.Cu")
		(net "M_J_MA<0>")
	)
	(segment
		(start 96.441768 -50.851054)
		(end 97.188528 -50.104294)
		(width 0.0889)
		(layer "In2.Cu")
		(net "M_J_MA<0>")
	)
	(segment
		(start 100.605336 -16.956786)
		(end 100.605336 -16.105632)
		(width 0.14224)
		(layer "In2.Cu")
		(net "M_J_MA<0>")
	)
	(segment
		(start 96.441768 -51.922172)
		(end 96.441768 -50.851054)
		(width 0.0889)
		(layer "In2.Cu")
		(net "M_J_MA<0>")
	)
	(segment
		(start 101.534214 -0.164846)
		(end 101.45395 -0.084582)
		(width 0.14224)
		(layer "In2.Cu")
		(net "M_J_MA<0>")
	)
	(segment
		(start 100.732336 -12.337796)
		(end 100.605336 -12.210796)
		(width 0.14224)
		(layer "In2.Cu")
		(net "M_J_MA<0>")
	)
	(segment
		(start 100.7491 -9.690354)
		(end 100.660962 -9.602216)
		(width 0.14224)
		(layer "In2.Cu")
		(net "M_J_MA<0>")
	)
	(segment
		(start 100.757736 -17.617186)
		(end 100.757736 -17.109186)
		(width 0.14224)
		(layer "In2.Cu")
		(net "M_J_MA<0>")
	)
	(segment
		(start 96.026478 -54.810406)
		(end 96.020128 -54.799738)
		(width 0.0889)
		(layer "In2.Cu")
		(net "M_J_MA<0>")
	)
	(segment
		(start 101.099366 -2.987802)
		(end 101.534214 -2.552954)
		(width 0.14224)
		(layer "In2.Cu")
		(net "M_J_MA<0>")
	)
	(segment
		(start 101.534214 -2.552954)
		(end 101.534214 -0.164846)
		(width 0.14224)
		(layer "In2.Cu")
		(net "M_J_MA<0>")
	)
	(segment
		(start 101.614478 1.41097)
		(end 101.099366 1.926082)
		(width 0.14224)
		(layer "In2.Cu")
		(net "M_J_MA<0>")
	)
	(segment
		(start 100.605336 -21.811996)
		(end 100.605336 -17.769586)
		(width 0.14224)
		(layer "In2.Cu")
		(net "M_J_MA<0>")
	)
	(segment
		(start 96.020128 -57.771538)
		(end 96.015302 -57.762902)
		(width 0.0889)
		(layer "In2.Cu")
		(net "M_J_MA<0>")
	)
	(segment
		(start 96.020128 -54.799738)
		(end 96.015302 -54.791102)
		(width 0.0889)
		(layer "In2.Cu")
		(net "M_J_MA<0>")
	)
	(segment
		(start 96.026478 -56.791606)
		(end 96.020128 -56.780938)
		(width 0.0889)
		(layer "In2.Cu")
		(net "M_J_MA<0>")
	)
	(segment
		(start 99.819968 -26.75636)
		(end 99.819968 -25.517348)
		(width 0.14224)
		(layer "In2.Cu")
		(net "M_J_MA<0>")
	)
	(segment
		(start 96.08947 -52.27447)
		(end 96.441768 -51.922172)
		(width 0.0889)
		(layer "In2.Cu")
		(net "M_J_MA<0>")
	)
	(segment
		(start 100.660962 -7.411212)
		(end 100.605336 -7.355586)
		(width 0.14224)
		(layer "In2.Cu")
		(net "M_J_MA<0>")
	)
	(segment
		(start 100.605336 -17.769586)
		(end 100.757736 -17.617186)
		(width 0.14224)
		(layer "In2.Cu")
		(net "M_J_MA<0>")
	)
	(segment
		(start 100.64623 -12.906502)
		(end 100.732336 -12.820396)
		(width 0.14224)
		(layer "In2.Cu")
		(net "M_J_MA<0>")
	)
	(arc
		(start 96.020128 -52.818284)
		(mid 95.966785 -52.623475)
		(end 96.015302 -52.427378)
		(width 0.0889)
		(layer "In2.Cu")
		(net "M_J_MA<0>")
	)
	(arc
		(start 96.020128 -54.399688)
		(mid 96.09935 -54.11057)
		(end 96.026478 -53.819806)
		(width 0.0889)
		(layer "In2.Cu")
		(net "M_J_MA<0>")
	)
	(arc
		(start 96.015302 -56.772302)
		(mid 95.966547 -56.57595)
		(end 96.020128 -56.380888)
		(width 0.0889)
		(layer "In2.Cu")
		(net "M_J_MA<0>")
	)
	(arc
		(start 95.966788 -58.572146)
		(mid 95.978982 -58.463443)
		(end 96.020128 -58.362088)
		(width 0.0889)
		(layer "In2.Cu")
		(net "M_J_MA<0>")
	)
	(arc
		(start 96.020128 -53.409088)
		(mid 96.099259 -53.113686)
		(end 96.020128 -52.818284)
		(width 0.0889)
		(layer "In2.Cu")
		(net "M_J_MA<0>")
	)
	(arc
		(start 96.020128 -55.390288)
		(mid 96.09935 -55.10117)
		(end 96.026478 -54.810406)
		(width 0.0889)
		(layer "In2.Cu")
		(net "M_J_MA<0>")
	)
	(arc
		(start 96.020128 -56.380888)
		(mid 96.09935 -56.09177)
		(end 96.026478 -55.801006)
		(width 0.0889)
		(layer "In2.Cu")
		(net "M_J_MA<0>")
	)
	(arc
		(start 96.026478 -58.35142)
		(mid 96.099276 -58.060657)
		(end 96.020128 -57.771538)
		(width 0.0889)
		(layer "In2.Cu")
		(net "M_J_MA<0>")
	)
	(arc
		(start 96.020128 -57.371488)
		(mid 96.09935 -57.08237)
		(end 96.026478 -56.791606)
		(width 0.0889)
		(layer "In2.Cu")
		(net "M_J_MA<0>")
	)
	(arc
		(start 96.015302 -53.800502)
		(mid 95.966547 -53.60415)
		(end 96.020128 -53.409088)
		(width 0.0889)
		(layer "In2.Cu")
		(net "M_J_MA<0>")
	)
	(arc
		(start 96.020128 -52.418742)
		(mid 96.057897 -52.348095)
		(end 96.08947 -52.27447)
		(width 0.0889)
		(layer "In2.Cu")
		(net "M_J_MA<0>")
	)
	(arc
		(start 96.015302 -57.762902)
		(mid 95.966547 -57.56655)
		(end 96.020128 -57.371488)
		(width 0.0889)
		(layer "In2.Cu")
		(net "M_J_MA<0>")
	)
	(arc
		(start 96.015302 -55.781702)
		(mid 95.966547 -55.58535)
		(end 96.020128 -55.390288)
		(width 0.0889)
		(layer "In2.Cu")
		(net "M_J_MA<0>")
	)
	(arc
		(start 96.015302 -54.791102)
		(mid 95.966547 -54.59475)
		(end 96.020128 -54.399688)
		(width 0.0889)
		(layer "In2.Cu")
		(net "M_J_MA<0>")
	)
	(segment
		(start 81.485232 -69.45884)
		(end 80.913732 -69.45884)
		(width 0.1016)
		(layer "F.Cu")
		(net "M_J_ECC<7>")
	)
	(segment
		(start 74.749406 3.778758)
		(end 74.749406 2.514854)
		(width 0.1651)
		(layer "F.Cu")
		(net "M_J_ECC<7>")
	)
	(via
		(at 75.59929 -3.076956)
		(size 0.508)
		(drill 0.254)
		(layers "F.Cu" "B.Cu")
		(net "M_J_ECC<7>")
	)
	(via
		(at 80.913732 -69.45884)
		(size 0.508)
		(drill 0.254)
		(layers "F.Cu" "B.Cu")
		(net "M_J_ECC<7>")
	)
	(via
		(at 74.749406 2.514854)
		(size 0.508)
		(drill 0.254)
		(layers "F.Cu" "B.Cu")
		(net "M_J_ECC<7>")
	)
	(segment
		(start 75.59929 -1.022096)
		(end 75.59929 -3.076956)
		(width 0.1651)
		(layer "B.Cu")
		(net "M_J_ECC<7>")
	)
	(segment
		(start 75.599544 -1.021842)
		(end 75.59929 -1.022096)
		(width 0.1651)
		(layer "B.Cu")
		(net "M_J_ECC<7>")
	)
	(segment
		(start 81.420716 -56.884824)
		(end 81.425542 -56.876188)
		(width 0.0889)
		(layer "In4.Cu")
		(net "M_J_ECC<7>")
	)
	(segment
		(start 81.425542 -59.847988)
		(end 81.431892 -59.83732)
		(width 0.0889)
		(layer "In4.Cu")
		(net "M_J_ECC<7>")
	)
	(segment
		(start 81.504282 -55.201058)
		(end 81.444592 -55.141368)
		(width 0.0889)
		(layer "In4.Cu")
		(net "M_J_ECC<7>")
	)
	(segment
		(start 81.431892 -58.277506)
		(end 81.425542 -58.266838)
		(width 0.0889)
		(layer "In4.Cu")
		(net "M_J_ECC<7>")
	)
	(segment
		(start 76.180696 -17.093946)
		(end 75.977496 -16.890746)
		(width 0.14224)
		(layer "In4.Cu")
		(net "M_J_ECC<7>")
	)
	(segment
		(start 81.420716 -62.828424)
		(end 81.425542 -62.819788)
		(width 0.0889)
		(layer "In4.Cu")
		(net "M_J_ECC<7>")
	)
	(segment
		(start 81.425542 -65.791588)
		(end 81.431892 -65.78092)
		(width 0.0889)
		(layer "In4.Cu")
		(net "M_J_ECC<7>")
	)
	(segment
		(start 75.977496 -27.627072)
		(end 76.165964 -27.438604)
		(width 0.14224)
		(layer "In4.Cu")
		(net "M_J_ECC<7>")
	)
	(segment
		(start 76.155296 -13.516356)
		(end 76.155296 -12.373356)
		(width 0.14224)
		(layer "In4.Cu")
		(net "M_J_ECC<7>")
	)
	(segment
		(start 81.425542 -60.838588)
		(end 81.431892 -60.82792)
		(width 0.0889)
		(layer "In4.Cu")
		(net "M_J_ECC<7>")
	)
	(segment
		(start 81.420716 -61.837824)
		(end 81.425542 -61.829188)
		(width 0.0889)
		(layer "In4.Cu")
		(net "M_J_ECC<7>")
	)
	(segment
		(start 82.069686 -52.523136)
		(end 82.069686 -51.452526)
		(width 0.0889)
		(layer "In4.Cu")
		(net "M_J_ECC<7>")
	)
	(segment
		(start 81.420716 -59.856624)
		(end 81.425542 -59.847988)
		(width 0.0889)
		(layer "In4.Cu")
		(net "M_J_ECC<7>")
	)
	(segment
		(start 81.444592 -53.14823)
		(end 82.069686 -52.523136)
		(width 0.0889)
		(layer "In4.Cu")
		(net "M_J_ECC<7>")
	)
	(segment
		(start 81.420716 -64.809624)
		(end 81.425542 -64.800988)
		(width 0.0889)
		(layer "In4.Cu")
		(net "M_J_ECC<7>")
	)
	(segment
		(start 78.852268 -34.5313)
		(end 78.153768 -33.8328)
		(width 0.14224)
		(layer "In4.Cu")
		(net "M_J_ECC<7>")
	)
	(segment
		(start 81.431384 -45.568616)
		(end 81.057242 -45.568616)
		(width 0.14224)
		(layer "In4.Cu")
		(net "M_J_ECC<7>")
	)
	(segment
		(start 81.936844 -51.220624)
		(end 81.936844 -50.939954)
		(width 0.0889)
		(layer "In4.Cu")
		(net "M_J_ECC<7>")
	)
	(segment
		(start 80.913732 -69.45884)
		(end 81.213198 -68.771516)
		(width 0.0889)
		(layer "In4.Cu")
		(net "M_J_ECC<7>")
	)
	(segment
		(start 75.977496 -29.573728)
		(end 75.977496 -27.627072)
		(width 0.14224)
		(layer "In4.Cu")
		(net "M_J_ECC<7>")
	)
	(segment
		(start 75.977496 -6.375146)
		(end 75.977496 -4.844288)
		(width 0.14224)
		(layer "In4.Cu")
		(net "M_J_ECC<7>")
	)
	(segment
		(start 75.952096 -8.957818)
		(end 76.180696 -8.729218)
		(width 0.14224)
		(layer "In4.Cu")
		(net "M_J_ECC<7>")
	)
	(segment
		(start 82.714592 -49.949354)
		(end 82.770218 -49.893728)
		(width 0.14224)
		(layer "In4.Cu")
		(net "M_J_ECC<7>")
	)
	(segment
		(start 82.770218 -46.90745)
		(end 81.431384 -45.568616)
		(width 0.14224)
		(layer "In4.Cu")
		(net "M_J_ECC<7>")
	)
	(segment
		(start 75.962764 -26.358596)
		(end 75.962764 -23.310088)
		(width 0.14224)
		(layer "In4.Cu")
		(net "M_J_ECC<7>")
	)
	(segment
		(start 75.113896 -3.56235)
		(end 75.59929 -3.076956)
		(width 0.14224)
		(layer "In4.Cu")
		(net "M_J_ECC<7>")
	)
	(segment
		(start 75.901296 -6.451346)
		(end 75.977496 -6.375146)
		(width 0.14224)
		(layer "In4.Cu")
		(net "M_J_ECC<7>")
	)
	(segment
		(start 78.153768 -31.75)
		(end 75.977496 -29.573728)
		(width 0.14224)
		(layer "In4.Cu")
		(net "M_J_ECC<7>")
	)
	(segment
		(start 81.504282 -55.59298)
		(end 81.504282 -55.201058)
		(width 0.0889)
		(layer "In4.Cu")
		(net "M_J_ECC<7>")
	)
	(segment
		(start 75.901296 -7.213346)
		(end 75.901296 -6.451346)
		(width 0.14224)
		(layer "In4.Cu")
		(net "M_J_ECC<7>")
	)
	(segment
		(start 75.977496 -13.694156)
		(end 76.155296 -13.516356)
		(width 0.14224)
		(layer "In4.Cu")
		(net "M_J_ECC<7>")
	)
	(segment
		(start 82.069686 -51.452526)
		(end 81.936844 -51.220624)
		(width 0.0889)
		(layer "In4.Cu")
		(net "M_J_ECC<7>")
	)
	(segment
		(start 81.420716 -63.819024)
		(end 81.425542 -63.810388)
		(width 0.0889)
		(layer "In4.Cu")
		(net "M_J_ECC<7>")
	)
	(segment
		(start 81.057242 -45.568616)
		(end 78.852268 -43.363642)
		(width 0.14224)
		(layer "In4.Cu")
		(net "M_J_ECC<7>")
	)
	(segment
		(start 76.180696 -18.355818)
		(end 76.180696 -17.093946)
		(width 0.14224)
		(layer "In4.Cu")
		(net "M_J_ECC<7>")
	)
	(segment
		(start 81.425542 -62.819788)
		(end 81.431892 -62.80912)
		(width 0.0889)
		(layer "In4.Cu")
		(net "M_J_ECC<7>")
	)
	(segment
		(start 75.113896 -3.980688)
		(end 75.113896 -3.56235)
		(width 0.14224)
		(layer "In4.Cu")
		(net "M_J_ECC<7>")
	)
	(segment
		(start 81.425542 -56.285638)
		(end 81.425288 -56.285892)
		(width 0.0889)
		(layer "In4.Cu")
		(net "M_J_ECC<7>")
	)
	(segment
		(start 81.425542 -63.810388)
		(end 81.431892 -63.79972)
		(width 0.0889)
		(layer "In4.Cu")
		(net "M_J_ECC<7>")
	)
	(segment
		(start 81.444592 -55.141368)
		(end 81.444592 -53.14823)
		(width 0.0889)
		(layer "In4.Cu")
		(net "M_J_ECC<7>")
	)
	(segment
		(start 81.420716 -58.866024)
		(end 81.425542 -58.857388)
		(width 0.0889)
		(layer "In4.Cu")
		(net "M_J_ECC<7>")
	)
	(segment
		(start 75.952096 -18.584418)
		(end 76.180696 -18.355818)
		(width 0.14224)
		(layer "In4.Cu")
		(net "M_J_ECC<7>")
	)
	(segment
		(start 76.155296 -23.117556)
		(end 76.155296 -21.974556)
		(width 0.14224)
		(layer "In4.Cu")
		(net "M_J_ECC<7>")
	)
	(segment
		(start 81.425542 -56.876188)
		(end 81.431892 -56.86552)
		(width 0.0889)
		(layer "In4.Cu")
		(net "M_J_ECC<7>")
	)
	(segment
		(start 76.155296 -12.373356)
		(end 75.952096 -12.170156)
		(width 0.14224)
		(layer "In4.Cu")
		(net "M_J_ECC<7>")
	)
	(segment
		(start 75.962764 -23.310088)
		(end 76.155296 -23.117556)
		(width 0.14224)
		(layer "In4.Cu")
		(net "M_J_ECC<7>")
	)
	(segment
		(start 75.952096 -12.170156)
		(end 75.952096 -8.957818)
		(width 0.14224)
		(layer "In4.Cu")
		(net "M_J_ECC<7>")
	)
	(segment
		(start 82.463132 -50.200814)
		(end 82.714592 -49.949354)
		(width 0.0889)
		(layer "In4.Cu")
		(net "M_J_ECC<7>")
	)
	(segment
		(start 75.977496 -4.844288)
		(end 75.113896 -3.980688)
		(width 0.14224)
		(layer "In4.Cu")
		(net "M_J_ECC<7>")
	)
	(segment
		(start 81.936844 -50.939954)
		(end 82.463132 -50.413666)
		(width 0.0889)
		(layer "In4.Cu")
		(net "M_J_ECC<7>")
	)
	(segment
		(start 75.977496 -16.890746)
		(end 75.977496 -13.694156)
		(width 0.14224)
		(layer "In4.Cu")
		(net "M_J_ECC<7>")
	)
	(segment
		(start 76.180696 -7.492746)
		(end 75.901296 -7.213346)
		(width 0.14224)
		(layer "In4.Cu")
		(net "M_J_ECC<7>")
	)
	(segment
		(start 81.420716 -60.847224)
		(end 81.425542 -60.838588)
		(width 0.0889)
		(layer "In4.Cu")
		(net "M_J_ECC<7>")
	)
	(segment
		(start 78.153768 -33.8328)
		(end 78.153768 -31.75)
		(width 0.14224)
		(layer "In4.Cu")
		(net "M_J_ECC<7>")
	)
	(segment
		(start 76.155296 -21.974556)
		(end 75.952096 -21.771356)
		(width 0.14224)
		(layer "In4.Cu")
		(net "M_J_ECC<7>")
	)
	(segment
		(start 81.425542 -61.829188)
		(end 81.431892 -61.81852)
		(width 0.0889)
		(layer "In4.Cu")
		(net "M_J_ECC<7>")
	)
	(segment
		(start 75.952096 -21.771356)
		(end 75.952096 -18.584418)
		(width 0.14224)
		(layer "In4.Cu")
		(net "M_J_ECC<7>")
	)
	(segment
		(start 82.770218 -49.893728)
		(end 82.770218 -46.90745)
		(width 0.14224)
		(layer "In4.Cu")
		(net "M_J_ECC<7>")
	)
	(segment
		(start 82.463132 -50.413666)
		(end 82.463132 -50.200814)
		(width 0.0889)
		(layer "In4.Cu")
		(net "M_J_ECC<7>")
	)
	(segment
		(start 78.852268 -43.363642)
		(end 78.852268 -34.5313)
		(width 0.14224)
		(layer "In4.Cu")
		(net "M_J_ECC<7>")
	)
	(segment
		(start 81.425542 -64.800988)
		(end 81.431892 -64.79032)
		(width 0.0889)
		(layer "In4.Cu")
		(net "M_J_ECC<7>")
	)
	(segment
		(start 76.180696 -8.729218)
		(end 76.180696 -7.492746)
		(width 0.14224)
		(layer "In4.Cu")
		(net "M_J_ECC<7>")
	)
	(segment
		(start 81.420716 -65.800224)
		(end 81.425542 -65.791588)
		(width 0.0889)
		(layer "In4.Cu")
		(net "M_J_ECC<7>")
	)
	(segment
		(start 76.165964 -26.561796)
		(end 75.962764 -26.358596)
		(width 0.14224)
		(layer "In4.Cu")
		(net "M_J_ECC<7>")
	)
	(segment
		(start 76.165964 -27.438604)
		(end 76.165964 -26.561796)
		(width 0.14224)
		(layer "In4.Cu")
		(net "M_J_ECC<7>")
	)
	(arc
		(start 81.425542 -62.229238)
		(mid 81.372072 -62.034175)
		(end 81.420716 -61.837824)
		(width 0.0889)
		(layer "In4.Cu")
		(net "M_J_ECC<7>")
	)
	(arc
		(start 81.260442 -68.667884)
		(mid 81.307802 -68.537815)
		(end 81.30794 -68.399406)
		(width 0.0889)
		(layer "In4.Cu")
		(net "M_J_ECC<7>")
	)
	(arc
		(start 81.30794 -68.399406)
		(mid 81.313271 -68.07606)
		(end 81.425542 -67.772788)
		(width 0.0889)
		(layer "In4.Cu")
		(net "M_J_ECC<7>")
	)
	(arc
		(start 81.425288 -56.285892)
		(mid 81.371596 -56.090149)
		(end 81.420716 -55.893208)
		(width 0.0889)
		(layer "In4.Cu")
		(net "M_J_ECC<7>")
	)
	(arc
		(start 81.425542 -57.867042)
		(mid 81.504673 -57.57164)
		(end 81.425542 -57.276238)
		(width 0.0889)
		(layer "In4.Cu")
		(net "M_J_ECC<7>")
	)
	(arc
		(start 81.431892 -65.78092)
		(mid 81.50469 -65.490157)
		(end 81.425542 -65.201038)
		(width 0.0889)
		(layer "In4.Cu")
		(net "M_J_ECC<7>")
	)
	(arc
		(start 81.425542 -59.257438)
		(mid 81.372072 -59.062375)
		(end 81.420716 -58.866024)
		(width 0.0889)
		(layer "In4.Cu")
		(net "M_J_ECC<7>")
	)
	(arc
		(start 81.425542 -63.219838)
		(mid 81.372072 -63.024775)
		(end 81.420716 -62.828424)
		(width 0.0889)
		(layer "In4.Cu")
		(net "M_J_ECC<7>")
	)
	(arc
		(start 81.431892 -59.83732)
		(mid 81.50469 -59.546557)
		(end 81.425542 -59.257438)
		(width 0.0889)
		(layer "In4.Cu")
		(net "M_J_ECC<7>")
	)
	(arc
		(start 81.425542 -66.782188)
		(mid 81.504673 -66.486786)
		(end 81.425542 -66.191384)
		(width 0.0889)
		(layer "In4.Cu")
		(net "M_J_ECC<7>")
	)
	(arc
		(start 81.425542 -67.772788)
		(mid 81.504673 -67.477386)
		(end 81.425542 -67.181984)
		(width 0.0889)
		(layer "In4.Cu")
		(net "M_J_ECC<7>")
	)
	(arc
		(start 81.425542 -61.238638)
		(mid 81.372072 -61.043575)
		(end 81.420716 -60.847224)
		(width 0.0889)
		(layer "In4.Cu")
		(net "M_J_ECC<7>")
	)
	(arc
		(start 81.425542 -66.191384)
		(mid 81.372006 -65.996433)
		(end 81.420716 -65.800224)
		(width 0.0889)
		(layer "In4.Cu")
		(net "M_J_ECC<7>")
	)
	(arc
		(start 81.420716 -55.893208)
		(mid 81.447358 -55.844381)
		(end 81.468976 -55.793132)
		(width 0.0889)
		(layer "In4.Cu")
		(net "M_J_ECC<7>")
	)
	(arc
		(start 81.468976 -55.793132)
		(mid 81.495412 -55.694604)
		(end 81.504282 -55.59298)
		(width 0.0889)
		(layer "In4.Cu")
		(net "M_J_ECC<7>")
	)
	(arc
		(start 81.425542 -65.201038)
		(mid 81.372072 -65.005975)
		(end 81.420716 -64.809624)
		(width 0.0889)
		(layer "In4.Cu")
		(net "M_J_ECC<7>")
	)
	(arc
		(start 81.213198 -68.771516)
		(mid 81.234327 -68.718564)
		(end 81.260442 -68.667884)
		(width 0.0889)
		(layer "In4.Cu")
		(net "M_J_ECC<7>")
	)
	(arc
		(start 81.431892 -60.82792)
		(mid 81.50469 -60.537157)
		(end 81.425542 -60.248038)
		(width 0.0889)
		(layer "In4.Cu")
		(net "M_J_ECC<7>")
	)
	(arc
		(start 81.431892 -64.79032)
		(mid 81.50469 -64.499557)
		(end 81.425542 -64.210438)
		(width 0.0889)
		(layer "In4.Cu")
		(net "M_J_ECC<7>")
	)
	(arc
		(start 81.425542 -67.181984)
		(mid 81.372043 -66.982086)
		(end 81.425542 -66.782188)
		(width 0.0889)
		(layer "In4.Cu")
		(net "M_J_ECC<7>")
	)
	(arc
		(start 81.425542 -64.210438)
		(mid 81.372072 -64.015375)
		(end 81.420716 -63.819024)
		(width 0.0889)
		(layer "In4.Cu")
		(net "M_J_ECC<7>")
	)
	(arc
		(start 81.431892 -61.81852)
		(mid 81.50469 -61.527757)
		(end 81.425542 -61.238638)
		(width 0.0889)
		(layer "In4.Cu")
		(net "M_J_ECC<7>")
	)
	(arc
		(start 81.425542 -58.266838)
		(mid 81.372043 -58.06694)
		(end 81.425542 -57.867042)
		(width 0.0889)
		(layer "In4.Cu")
		(net "M_J_ECC<7>")
	)
	(arc
		(start 81.425542 -57.276238)
		(mid 81.372072 -57.081175)
		(end 81.420716 -56.884824)
		(width 0.0889)
		(layer "In4.Cu")
		(net "M_J_ECC<7>")
	)
	(arc
		(start 81.431892 -63.79972)
		(mid 81.50469 -63.508957)
		(end 81.425542 -63.219838)
		(width 0.0889)
		(layer "In4.Cu")
		(net "M_J_ECC<7>")
	)
	(arc
		(start 81.425542 -58.857388)
		(mid 81.504764 -58.56827)
		(end 81.431892 -58.277506)
		(width 0.0889)
		(layer "In4.Cu")
		(net "M_J_ECC<7>")
	)
	(arc
		(start 81.431892 -56.86552)
		(mid 81.50469 -56.574757)
		(end 81.425542 -56.285638)
		(width 0.0889)
		(layer "In4.Cu")
		(net "M_J_ECC<7>")
	)
	(arc
		(start 81.425542 -60.248038)
		(mid 81.372072 -60.052975)
		(end 81.420716 -59.856624)
		(width 0.0889)
		(layer "In4.Cu")
		(net "M_J_ECC<7>")
	)
	(arc
		(start 81.431892 -62.80912)
		(mid 81.50469 -62.518357)
		(end 81.425542 -62.229238)
		(width 0.0889)
		(layer "In4.Cu")
		(net "M_J_ECC<7>")
	)
	(segment
		(start 75.396344 1.5494)
		(end 75.066144 1.8796)
		(width 0.14224)
		(layer "In11.Cu")
		(net "M_J_ECC<7>")
	)
	(segment
		(start 75.066144 2.198116)
		(end 74.749406 2.514854)
		(width 0.14224)
		(layer "In11.Cu")
		(net "M_J_ECC<7>")
	)
	(segment
		(start 75.952096 0.581152)
		(end 76.107544 0.7366)
		(width 0.14224)
		(layer "In11.Cu")
		(net "M_J_ECC<7>")
	)
	(segment
		(start 75.650344 1.5494)
		(end 75.396344 1.5494)
		(width 0.14224)
		(layer "In11.Cu")
		(net "M_J_ECC<7>")
	)
	(segment
		(start 75.952096 -2.72415)
		(end 75.952096 0.581152)
		(width 0.14224)
		(layer "In11.Cu")
		(net "M_J_ECC<7>")
	)
	(segment
		(start 75.066144 1.8796)
		(end 75.066144 2.198116)
		(width 0.14224)
		(layer "In11.Cu")
		(net "M_J_ECC<7>")
	)
	(segment
		(start 75.59929 -3.076956)
		(end 75.952096 -2.72415)
		(width 0.14224)
		(layer "In11.Cu")
		(net "M_J_ECC<7>")
	)
	(segment
		(start 76.107544 1.0922)
		(end 75.650344 1.5494)
		(width 0.14224)
		(layer "In11.Cu")
		(net "M_J_ECC<7>")
	)
	(segment
		(start 76.107544 0.7366)
		(end 76.107544 1.0922)
		(width 0.14224)
		(layer "In11.Cu")
		(net "M_J_ECC<7>")
	)
	(segment
		(start 75.731624 0.28448)
		(end 75.731624 0.50292)
		(width 0.1651)
		(layer "F.Cu")
		(net "M_J_ECC<6>")
	)
	(segment
		(start 75.599544 -0.821182)
		(end 75.599544 0.1524)
		(width 0.1651)
		(layer "F.Cu")
		(net "M_J_ECC<6>")
	)
	(segment
		(start 81.485232 -67.47764)
		(end 80.913732 -67.47764)
		(width 0.0889)
		(layer "F.Cu")
		(net "M_J_ECC<6>")
	)
	(segment
		(start 75.731624 0.50292)
		(end 75.599544 0.635)
		(width 0.1651)
		(layer "F.Cu")
		(net "M_J_ECC<6>")
	)
	(segment
		(start 75.599544 0.1524)
		(end 75.731624 0.28448)
		(width 0.1651)
		(layer "F.Cu")
		(net "M_J_ECC<6>")
	)
	(segment
		(start 75.599544 0.635)
		(end 75.599544 0.939546)
		(width 0.1651)
		(layer "F.Cu")
		(net "M_J_ECC<6>")
	)
	(segment
		(start 75.599544 0.939546)
		(end 75.59929 0.9398)
		(width 0.1651)
		(layer "F.Cu")
		(net "M_J_ECC<6>")
	)
	(via
		(at 75.59929 0.9398)
		(size 0.508)
		(drill 0.254)
		(layers "F.Cu" "B.Cu")
		(net "M_J_ECC<6>")
	)
	(via
		(at 80.913732 -67.47764)
		(size 0.508)
		(drill 0.254)
		(layers "F.Cu" "B.Cu")
		(net "M_J_ECC<6>")
	)
	(via
		(at 74.749406 -4.357878)
		(size 0.508)
		(drill 0.254)
		(layers "F.Cu" "B.Cu")
		(net "M_J_ECC<6>")
	)
	(segment
		(start 74.749406 -5.621782)
		(end 74.749406 -4.357878)
		(width 0.1651)
		(layer "B.Cu")
		(net "M_J_ECC<6>")
	)
	(segment
		(start 77.711808 -35.546284)
		(end 78.047342 -35.546284)
		(width 0.14224)
		(layer "In4.Cu")
		(net "M_J_ECC<6>")
	)
	(segment
		(start 80.716628 -46.126146)
		(end 77.556868 -42.966386)
		(width 0.14224)
		(layer "In4.Cu")
		(net "M_J_ECC<6>")
	)
	(segment
		(start 77.711808 -34.926524)
		(end 77.556868 -34.771584)
		(width 0.14224)
		(layer "In4.Cu")
		(net "M_J_ECC<6>")
	)
	(segment
		(start 81.260442 -61.733938)
		(end 81.265268 -61.725302)
		(width 0.0889)
		(layer "In4.Cu")
		(net "M_J_ECC<6>")
	)
	(segment
		(start 75.113896 -18.422874)
		(end 75.113896 -16.992346)
		(width 0.14224)
		(layer "In4.Cu")
		(net "M_J_ECC<6>")
	)
	(segment
		(start 81.206848 -67.308476)
		(end 81.230724 -67.219068)
		(width 0.0889)
		(layer "In4.Cu")
		(net "M_J_ECC<6>")
	)
	(segment
		(start 75.359768 -27.813)
		(end 75.071732 -27.524964)
		(width 0.14224)
		(layer "In4.Cu")
		(net "M_J_ECC<6>")
	)
	(segment
		(start 81.254092 -53.06187)
		(end 81.879186 -52.436776)
		(width 0.0889)
		(layer "In4.Cu")
		(net "M_J_ECC<6>")
	)
	(segment
		(start 78.202282 -36.630864)
		(end 78.202282 -36.320984)
		(width 0.14224)
		(layer "In4.Cu")
		(net "M_J_ECC<6>")
	)
	(segment
		(start 75.113896 -23.168356)
		(end 75.113896 -21.974556)
		(width 0.14224)
		(layer "In4.Cu")
		(net "M_J_ECC<6>")
	)
	(segment
		(start 75.113896 -21.974556)
		(end 75.317096 -21.771356)
		(width 0.14224)
		(layer "In4.Cu")
		(net "M_J_ECC<6>")
	)
	(segment
		(start 77.556868 -34.771584)
		(end 77.556868 -32.020764)
		(width 0.14224)
		(layer "In4.Cu")
		(net "M_J_ECC<6>")
	)
	(segment
		(start 81.260442 -62.724538)
		(end 81.265268 -62.715902)
		(width 0.0889)
		(layer "In4.Cu")
		(net "M_J_ECC<6>")
	)
	(segment
		(start 81.260442 -63.715138)
		(end 81.265268 -63.706502)
		(width 0.0889)
		(layer "In4.Cu")
		(net "M_J_ECC<6>")
	)
	(segment
		(start 81.746344 -50.852578)
		(end 82.255868 -50.343054)
		(width 0.0889)
		(layer "In4.Cu")
		(net "M_J_ECC<6>")
	)
	(segment
		(start 81.260442 -59.752738)
		(end 81.265268 -59.744102)
		(width 0.0889)
		(layer "In4.Cu")
		(net "M_J_ECC<6>")
	)
	(segment
		(start 75.029568 -25.538938)
		(end 75.029568 -24.948134)
		(width 0.14224)
		(layer "In4.Cu")
		(net "M_J_ECC<6>")
	)
	(segment
		(start 75.251564 -23.306024)
		(end 75.113896 -23.168356)
		(width 0.14224)
		(layer "In4.Cu")
		(net "M_J_ECC<6>")
	)
	(segment
		(start 77.556868 -37.250624)
		(end 77.556868 -36.940744)
		(width 0.14224)
		(layer "In4.Cu")
		(net "M_J_ECC<6>")
	)
	(segment
		(start 81.313782 -55.285386)
		(end 81.254092 -55.225696)
		(width 0.0889)
		(layer "In4.Cu")
		(net "M_J_ECC<6>")
	)
	(segment
		(start 81.254092 -65.707006)
		(end 81.260442 -65.696338)
		(width 0.0889)
		(layer "In4.Cu")
		(net "M_J_ECC<6>")
	)
	(segment
		(start 81.254092 -55.225696)
		(end 81.254092 -53.06187)
		(width 0.0889)
		(layer "In4.Cu")
		(net "M_J_ECC<6>")
	)
	(segment
		(start 75.317096 -12.170156)
		(end 75.317096 -9.024874)
		(width 0.14224)
		(layer "In4.Cu")
		(net "M_J_ECC<6>")
	)
	(segment
		(start 80.913732 -67.47764)
		(end 81.206848 -67.308476)
		(width 0.0889)
		(layer "In4.Cu")
		(net "M_J_ECC<6>")
	)
	(segment
		(start 81.260442 -58.362088)
		(end 81.254092 -58.35142)
		(width 0.0889)
		(layer "In4.Cu")
		(net "M_J_ECC<6>")
	)
	(segment
		(start 77.556868 -36.011104)
		(end 77.556868 -35.701224)
		(width 0.14224)
		(layer "In4.Cu")
		(net "M_J_ECC<6>")
	)
	(segment
		(start 82.255868 -50.13579)
		(end 82.079592 -49.959514)
		(width 0.0889)
		(layer "In4.Cu")
		(net "M_J_ECC<6>")
	)
	(segment
		(start 78.047342 -38.025324)
		(end 78.202282 -37.870384)
		(width 0.14224)
		(layer "In4.Cu")
		(net "M_J_ECC<6>")
	)
	(segment
		(start 81.254092 -62.735206)
		(end 81.260442 -62.724538)
		(width 0.0889)
		(layer "In4.Cu")
		(net "M_J_ECC<6>")
	)
	(segment
		(start 78.047342 -36.785804)
		(end 78.202282 -36.630864)
		(width 0.14224)
		(layer "In4.Cu")
		(net "M_J_ECC<6>")
	)
	(segment
		(start 75.071732 -26.475436)
		(end 75.251564 -26.295604)
		(width 0.14224)
		(layer "In4.Cu")
		(net "M_J_ECC<6>")
	)
	(segment
		(start 81.254092 -61.744606)
		(end 81.260442 -61.733938)
		(width 0.0889)
		(layer "In4.Cu")
		(net "M_J_ECC<6>")
	)
	(segment
		(start 77.556868 -36.940744)
		(end 77.711808 -36.785804)
		(width 0.14224)
		(layer "In4.Cu")
		(net "M_J_ECC<6>")
	)
	(segment
		(start 75.251564 -26.295604)
		(end 75.251564 -25.760934)
		(width 0.14224)
		(layer "In4.Cu")
		(net "M_J_ECC<6>")
	)
	(segment
		(start 81.260442 -56.780938)
		(end 81.265268 -56.772302)
		(width 0.0889)
		(layer "In4.Cu")
		(net "M_J_ECC<6>")
	)
	(segment
		(start 81.254092 -64.716406)
		(end 81.260442 -64.705738)
		(width 0.0889)
		(layer "In4.Cu")
		(net "M_J_ECC<6>")
	)
	(segment
		(start 75.266296 -5.062728)
		(end 74.749406 -4.545838)
		(width 0.14224)
		(layer "In4.Cu")
		(net "M_J_ECC<6>")
	)
	(segment
		(start 77.711808 -36.166044)
		(end 77.556868 -36.011104)
		(width 0.14224)
		(layer "In4.Cu")
		(net "M_J_ECC<6>")
	)
	(segment
		(start 75.113896 -16.992346)
		(end 75.215496 -16.890746)
		(width 0.14224)
		(layer "In4.Cu")
		(net "M_J_ECC<6>")
	)
	(segment
		(start 81.313782 -55.592726)
		(end 81.313782 -55.285386)
		(width 0.0889)
		(layer "In4.Cu")
		(net "M_J_ECC<6>")
	)
	(segment
		(start 81.254092 -59.763406)
		(end 81.260442 -59.752738)
		(width 0.0889)
		(layer "In4.Cu")
		(net "M_J_ECC<6>")
	)
	(segment
		(start 78.202282 -36.320984)
		(end 78.047342 -36.166044)
		(width 0.14224)
		(layer "In4.Cu")
		(net "M_J_ECC<6>")
	)
	(segment
		(start 75.071732 -27.524964)
		(end 75.071732 -26.475436)
		(width 0.14224)
		(layer "In4.Cu")
		(net "M_J_ECC<6>")
	)
	(segment
		(start 74.749406 -4.545838)
		(end 74.749406 -4.357878)
		(width 0.14224)
		(layer "In4.Cu")
		(net "M_J_ECC<6>")
	)
	(segment
		(start 77.556868 -32.020764)
		(end 75.359768 -29.823664)
		(width 0.14224)
		(layer "In4.Cu")
		(net "M_J_ECC<6>")
	)
	(segment
		(start 75.317096 -18.626074)
		(end 75.113896 -18.422874)
		(width 0.14224)
		(layer "In4.Cu")
		(net "M_J_ECC<6>")
	)
	(segment
		(start 81.260442 -57.771538)
		(end 81.265268 -57.762902)
		(width 0.0889)
		(layer "In4.Cu")
		(net "M_J_ECC<6>")
	)
	(segment
		(start 78.047342 -37.405564)
		(end 77.711808 -37.405564)
		(width 0.14224)
		(layer "In4.Cu")
		(net "M_J_ECC<6>")
	)
	(segment
		(start 78.047342 -36.166044)
		(end 77.711808 -36.166044)
		(width 0.14224)
		(layer "In4.Cu")
		(net "M_J_ECC<6>")
	)
	(segment
		(start 81.254092 -60.754006)
		(end 81.260442 -60.743338)
		(width 0.0889)
		(layer "In4.Cu")
		(net "M_J_ECC<6>")
	)
	(segment
		(start 77.711808 -36.785804)
		(end 78.047342 -36.785804)
		(width 0.14224)
		(layer "In4.Cu")
		(net "M_J_ECC<6>")
	)
	(segment
		(start 78.202282 -35.391344)
		(end 78.202282 -35.081464)
		(width 0.14224)
		(layer "In4.Cu")
		(net "M_J_ECC<6>")
	)
	(segment
		(start 78.202282 -35.081464)
		(end 78.047342 -34.926524)
		(width 0.14224)
		(layer "In4.Cu")
		(net "M_J_ECC<6>")
	)
	(segment
		(start 75.215496 -16.890746)
		(end 75.215496 -13.668756)
		(width 0.14224)
		(layer "In4.Cu")
		(net "M_J_ECC<6>")
	)
	(segment
		(start 81.260442 -64.705738)
		(end 81.265268 -64.697102)
		(width 0.0889)
		(layer "In4.Cu")
		(net "M_J_ECC<6>")
	)
	(segment
		(start 75.029568 -24.948134)
		(end 75.251564 -24.726138)
		(width 0.14224)
		(layer "In4.Cu")
		(net "M_J_ECC<6>")
	)
	(segment
		(start 81.260442 -60.743338)
		(end 81.265268 -60.734702)
		(width 0.0889)
		(layer "In4.Cu")
		(net "M_J_ECC<6>")
	)
	(segment
		(start 75.113896 -12.373356)
		(end 75.317096 -12.170156)
		(width 0.14224)
		(layer "In4.Cu")
		(net "M_J_ECC<6>")
	)
	(segment
		(start 82.065368 -46.9646)
		(end 81.226914 -46.126146)
		(width 0.14224)
		(layer "In4.Cu")
		(net "M_J_ECC<6>")
	)
	(segment
		(start 81.226914 -46.126146)
		(end 80.716628 -46.126146)
		(width 0.14224)
		(layer "In4.Cu")
		(net "M_J_ECC<6>")
	)
	(segment
		(start 78.047342 -34.926524)
		(end 77.711808 -34.926524)
		(width 0.14224)
		(layer "In4.Cu")
		(net "M_J_ECC<6>")
	)
	(segment
		(start 75.215496 -13.668756)
		(end 75.113896 -13.567156)
		(width 0.14224)
		(layer "In4.Cu")
		(net "M_J_ECC<6>")
	)
	(segment
		(start 75.251564 -25.760934)
		(end 75.029568 -25.538938)
		(width 0.14224)
		(layer "In4.Cu")
		(net "M_J_ECC<6>")
	)
	(segment
		(start 75.113896 -7.391146)
		(end 75.266296 -7.238746)
		(width 0.14224)
		(layer "In4.Cu")
		(net "M_J_ECC<6>")
	)
	(segment
		(start 81.260442 -65.696338)
		(end 81.265268 -65.687702)
		(width 0.0889)
		(layer "In4.Cu")
		(net "M_J_ECC<6>")
	)
	(segment
		(start 75.317096 -9.024874)
		(end 75.113896 -8.821674)
		(width 0.14224)
		(layer "In4.Cu")
		(net "M_J_ECC<6>")
	)
	(segment
		(start 81.254092 -63.725806)
		(end 81.260442 -63.715138)
		(width 0.0889)
		(layer "In4.Cu")
		(net "M_J_ECC<6>")
	)
	(segment
		(start 77.711808 -38.025324)
		(end 78.047342 -38.025324)
		(width 0.14224)
		(layer "In4.Cu")
		(net "M_J_ECC<6>")
	)
	(segment
		(start 78.202282 -37.560504)
		(end 78.047342 -37.405564)
		(width 0.14224)
		(layer "In4.Cu")
		(net "M_J_ECC<6>")
	)
	(segment
		(start 77.556868 -35.701224)
		(end 77.711808 -35.546284)
		(width 0.14224)
		(layer "In4.Cu")
		(net "M_J_ECC<6>")
	)
	(segment
		(start 82.079592 -49.959514)
		(end 82.065368 -49.94529)
		(width 0.14224)
		(layer "In4.Cu")
		(net "M_J_ECC<6>")
	)
	(segment
		(start 75.359768 -29.823664)
		(end 75.359768 -27.813)
		(width 0.14224)
		(layer "In4.Cu")
		(net "M_J_ECC<6>")
	)
	(segment
		(start 78.047342 -35.546284)
		(end 78.202282 -35.391344)
		(width 0.14224)
		(layer "In4.Cu")
		(net "M_J_ECC<6>")
	)
	(segment
		(start 77.711808 -37.405564)
		(end 77.556868 -37.250624)
		(width 0.14224)
		(layer "In4.Cu")
		(net "M_J_ECC<6>")
	)
	(segment
		(start 81.879186 -51.511454)
		(end 81.746344 -51.279552)
		(width 0.0889)
		(layer "In4.Cu")
		(net "M_J_ECC<6>")
	)
	(segment
		(start 77.556868 -42.966386)
		(end 77.556868 -38.180264)
		(width 0.14224)
		(layer "In4.Cu")
		(net "M_J_ECC<6>")
	)
	(segment
		(start 75.317096 -21.771356)
		(end 75.317096 -18.626074)
		(width 0.14224)
		(layer "In4.Cu")
		(net "M_J_ECC<6>")
	)
	(segment
		(start 81.254092 -56.791606)
		(end 81.260442 -56.780938)
		(width 0.0889)
		(layer "In4.Cu")
		(net "M_J_ECC<6>")
	)
	(segment
		(start 78.202282 -37.870384)
		(end 78.202282 -37.560504)
		(width 0.14224)
		(layer "In4.Cu")
		(net "M_J_ECC<6>")
	)
	(segment
		(start 75.251564 -24.726138)
		(end 75.251564 -23.306024)
		(width 0.14224)
		(layer "In4.Cu")
		(net "M_J_ECC<6>")
	)
	(segment
		(start 81.746344 -51.279552)
		(end 81.746344 -50.852578)
		(width 0.0889)
		(layer "In4.Cu")
		(net "M_J_ECC<6>")
	)
	(segment
		(start 75.266296 -7.238746)
		(end 75.266296 -5.062728)
		(width 0.14224)
		(layer "In4.Cu")
		(net "M_J_ECC<6>")
	)
	(segment
		(start 77.556868 -38.180264)
		(end 77.711808 -38.025324)
		(width 0.14224)
		(layer "In4.Cu")
		(net "M_J_ECC<6>")
	)
	(segment
		(start 82.255868 -50.343054)
		(end 82.255868 -50.13579)
		(width 0.0889)
		(layer "In4.Cu")
		(net "M_J_ECC<6>")
	)
	(segment
		(start 75.113896 -13.567156)
		(end 75.113896 -12.373356)
		(width 0.14224)
		(layer "In4.Cu")
		(net "M_J_ECC<6>")
	)
	(segment
		(start 81.879186 -52.436776)
		(end 81.879186 -51.511454)
		(width 0.0889)
		(layer "In4.Cu")
		(net "M_J_ECC<6>")
	)
	(segment
		(start 75.113896 -8.821674)
		(end 75.113896 -7.391146)
		(width 0.14224)
		(layer "In4.Cu")
		(net "M_J_ECC<6>")
	)
	(segment
		(start 82.065368 -49.94529)
		(end 82.065368 -46.9646)
		(width 0.14224)
		(layer "In4.Cu")
		(net "M_J_ECC<6>")
	)
	(arc
		(start 81.260442 -59.352688)
		(mid 81.181311 -59.057286)
		(end 81.260442 -58.761884)
		(width 0.0889)
		(layer "In4.Cu")
		(net "M_J_ECC<6>")
	)
	(arc
		(start 81.254092 -58.35142)
		(mid 81.181294 -58.060657)
		(end 81.260442 -57.771538)
		(width 0.0889)
		(layer "In4.Cu")
		(net "M_J_ECC<6>")
	)
	(arc
		(start 81.265268 -63.706502)
		(mid 81.314023 -63.51015)
		(end 81.260442 -63.315088)
		(width 0.0889)
		(layer "In4.Cu")
		(net "M_J_ECC<6>")
	)
	(arc
		(start 81.265268 -59.744102)
		(mid 81.314023 -59.54775)
		(end 81.260442 -59.352688)
		(width 0.0889)
		(layer "In4.Cu")
		(net "M_J_ECC<6>")
	)
	(arc
		(start 81.260442 -61.333888)
		(mid 81.18122 -61.04477)
		(end 81.254092 -60.754006)
		(width 0.0889)
		(layer "In4.Cu")
		(net "M_J_ECC<6>")
	)
	(arc
		(start 81.265268 -60.734702)
		(mid 81.314023 -60.53835)
		(end 81.260442 -60.343288)
		(width 0.0889)
		(layer "In4.Cu")
		(net "M_J_ECC<6>")
	)
	(arc
		(start 81.260442 -66.286888)
		(mid 81.181322 -65.99777)
		(end 81.254092 -65.707006)
		(width 0.0889)
		(layer "In4.Cu")
		(net "M_J_ECC<6>")
	)
	(arc
		(start 81.265268 -56.772302)
		(mid 81.314023 -56.57595)
		(end 81.260442 -56.380888)
		(width 0.0889)
		(layer "In4.Cu")
		(net "M_J_ECC<6>")
	)
	(arc
		(start 81.265268 -61.725302)
		(mid 81.314023 -61.52895)
		(end 81.260442 -61.333888)
		(width 0.0889)
		(layer "In4.Cu")
		(net "M_J_ECC<6>")
	)
	(arc
		(start 81.265268 -62.715902)
		(mid 81.314023 -62.51955)
		(end 81.260442 -62.324488)
		(width 0.0889)
		(layer "In4.Cu")
		(net "M_J_ECC<6>")
	)
	(arc
		(start 81.230724 -67.219068)
		(mid 81.181712 -66.955619)
		(end 81.254092 -66.697606)
		(width 0.0889)
		(layer "In4.Cu")
		(net "M_J_ECC<6>")
	)
	(arc
		(start 81.260442 -58.761884)
		(mid 81.313941 -58.561986)
		(end 81.260442 -58.362088)
		(width 0.0889)
		(layer "In4.Cu")
		(net "M_J_ECC<6>")
	)
	(arc
		(start 81.28889 -55.73014)
		(mid 81.307512 -55.662552)
		(end 81.313782 -55.592726)
		(width 0.0889)
		(layer "In4.Cu")
		(net "M_J_ECC<6>")
	)
	(arc
		(start 81.260442 -65.296288)
		(mid 81.18122 -65.00717)
		(end 81.254092 -64.716406)
		(width 0.0889)
		(layer "In4.Cu")
		(net "M_J_ECC<6>")
	)
	(arc
		(start 81.254092 -55.801006)
		(mid 81.273217 -55.766421)
		(end 81.28889 -55.73014)
		(width 0.0889)
		(layer "In4.Cu")
		(net "M_J_ECC<6>")
	)
	(arc
		(start 81.254092 -66.697606)
		(mid 81.2572 -66.692106)
		(end 81.260442 -66.686684)
		(width 0.0889)
		(layer "In4.Cu")
		(net "M_J_ECC<6>")
	)
	(arc
		(start 81.265268 -65.687702)
		(mid 81.314023 -65.49135)
		(end 81.260442 -65.296288)
		(width 0.0889)
		(layer "In4.Cu")
		(net "M_J_ECC<6>")
	)
	(arc
		(start 81.260442 -57.371488)
		(mid 81.18122 -57.08237)
		(end 81.254092 -56.791606)
		(width 0.0889)
		(layer "In4.Cu")
		(net "M_J_ECC<6>")
	)
	(arc
		(start 81.260442 -62.324488)
		(mid 81.18122 -62.03537)
		(end 81.254092 -61.744606)
		(width 0.0889)
		(layer "In4.Cu")
		(net "M_J_ECC<6>")
	)
	(arc
		(start 81.265268 -57.762902)
		(mid 81.314023 -57.56655)
		(end 81.260442 -57.371488)
		(width 0.0889)
		(layer "In4.Cu")
		(net "M_J_ECC<6>")
	)
	(arc
		(start 81.260442 -66.686684)
		(mid 81.313941 -66.486786)
		(end 81.260442 -66.286888)
		(width 0.0889)
		(layer "In4.Cu")
		(net "M_J_ECC<6>")
	)
	(arc
		(start 81.265268 -64.697102)
		(mid 81.314023 -64.50075)
		(end 81.260442 -64.305688)
		(width 0.0889)
		(layer "In4.Cu")
		(net "M_J_ECC<6>")
	)
	(arc
		(start 81.260442 -60.343288)
		(mid 81.18122 -60.05417)
		(end 81.254092 -59.763406)
		(width 0.0889)
		(layer "In4.Cu")
		(net "M_J_ECC<6>")
	)
	(arc
		(start 81.260442 -63.315088)
		(mid 81.18122 -63.02597)
		(end 81.254092 -62.735206)
		(width 0.0889)
		(layer "In4.Cu")
		(net "M_J_ECC<6>")
	)
	(arc
		(start 81.260442 -64.305688)
		(mid 81.18122 -64.01657)
		(end 81.254092 -63.725806)
		(width 0.0889)
		(layer "In4.Cu")
		(net "M_J_ECC<6>")
	)
	(arc
		(start 81.260442 -56.380888)
		(mid 81.18122 -56.09177)
		(end 81.254092 -55.801006)
		(width 0.0889)
		(layer "In4.Cu")
		(net "M_J_ECC<6>")
	)
	(segment
		(start 74.431144 -4.039616)
		(end 74.431144 -3.5941)
		(width 0.14224)
		(layer "In11.Cu")
		(net "M_J_ECC<6>")
	)
	(segment
		(start 74.749406 -4.357878)
		(end 74.431144 -4.039616)
		(width 0.14224)
		(layer "In11.Cu")
		(net "M_J_ECC<6>")
	)
	(segment
		(start 75.193144 -2.8321)
		(end 75.193144 0.533654)
		(width 0.14224)
		(layer "In11.Cu")
		(net "M_J_ECC<6>")
	)
	(segment
		(start 75.193144 0.533654)
		(end 75.59929 0.9398)
		(width 0.14224)
		(layer "In11.Cu")
		(net "M_J_ECC<6>")
	)
	(segment
		(start 74.431144 -3.5941)
		(end 75.193144 -2.8321)
		(width 0.14224)
		(layer "In11.Cu")
		(net "M_J_ECC<6>")
	)
	(segment
		(start 78.909672 -68.963286)
		(end 78.338172 -68.963286)
		(width 0.1016)
		(layer "F.Cu")
		(net "M_J_ECC<5>")
	)
	(segment
		(start 68.799456 3.778758)
		(end 68.799456 2.514854)
		(width 0.1651)
		(layer "F.Cu")
		(net "M_J_ECC<5>")
	)
	(via
		(at 69.57314 -3.076956)
		(size 0.508)
		(drill 0.254)
		(layers "F.Cu" "B.Cu")
		(net "M_J_ECC<5>")
	)
	(via
		(at 68.799456 2.514854)
		(size 0.508)
		(drill 0.254)
		(layers "F.Cu" "B.Cu")
		(net "M_J_ECC<5>")
	)
	(via
		(at 78.338172 -68.963286)
		(size 0.508)
		(drill 0.254)
		(layers "F.Cu" "B.Cu")
		(net "M_J_ECC<5>")
	)
	(segment
		(start 69.64934 -1.021842)
		(end 69.64934 -3.000756)
		(width 0.1651)
		(layer "B.Cu")
		(net "M_J_ECC<5>")
	)
	(segment
		(start 69.64934 -3.000756)
		(end 69.57314 -3.076956)
		(width 0.1651)
		(layer "B.Cu")
		(net "M_J_ECC<5>")
	)
	(segment
		(start 69.983096 -7.264146)
		(end 69.983096 -6.662928)
		(width 0.14224)
		(layer "In4.Cu")
		(net "M_J_ECC<5>")
	)
	(segment
		(start 70.044564 -26.841196)
		(end 69.957696 -26.754328)
		(width 0.14224)
		(layer "In4.Cu")
		(net "M_J_ECC<5>")
	)
	(segment
		(start 78.070964 -53.60924)
		(end 78.07071 -53.298598)
		(width 0.0889)
		(layer "In4.Cu")
		(net "M_J_ECC<5>")
	)
	(segment
		(start 77.991716 -62.819788)
		(end 78.000606 -62.804548)
		(width 0.0889)
		(layer "In4.Cu")
		(net "M_J_ECC<5>")
	)
	(segment
		(start 77.991716 -57.867042)
		(end 77.998066 -57.856374)
		(width 0.0889)
		(layer "In4.Cu")
		(net "M_J_ECC<5>")
	)
	(segment
		(start 72.921368 -36.6268)
		(end 72.210168 -35.9156)
		(width 0.14224)
		(layer "In4.Cu")
		(net "M_J_ECC<5>")
	)
	(segment
		(start 72.210168 -35.9156)
		(end 72.210168 -32.588454)
		(width 0.14224)
		(layer "In4.Cu")
		(net "M_J_ECC<5>")
	)
	(segment
		(start 72.210168 -42.807636)
		(end 72.210168 -42.441876)
		(width 0.14224)
		(layer "In4.Cu")
		(net "M_J_ECC<5>")
	)
	(segment
		(start 69.957696 -8.991346)
		(end 70.046596 -8.902446)
		(width 0.14224)
		(layer "In4.Cu")
		(net "M_J_ECC<5>")
	)
	(segment
		(start 70.076568 -30.454854)
		(end 70.076568 -28.871672)
		(width 0.14224)
		(layer "In4.Cu")
		(net "M_J_ECC<5>")
	)
	(segment
		(start 72.779128 -42.299636)
		(end 72.921368 -42.157396)
		(width 0.14224)
		(layer "In4.Cu")
		(net "M_J_ECC<5>")
	)
	(segment
		(start 69.644768 -4.5212)
		(end 69.085968 -3.9624)
		(width 0.14224)
		(layer "In4.Cu")
		(net "M_J_ECC<5>")
	)
	(segment
		(start 77.998066 -58.277506)
		(end 77.991716 -58.266838)
		(width 0.0889)
		(layer "In4.Cu")
		(net "M_J_ECC<5>")
	)
	(segment
		(start 72.352408 -42.299636)
		(end 72.779128 -42.299636)
		(width 0.14224)
		(layer "In4.Cu")
		(net "M_J_ECC<5>")
	)
	(segment
		(start 70.046596 -13.617956)
		(end 70.046596 -12.360656)
		(width 0.14224)
		(layer "In4.Cu")
		(net "M_J_ECC<5>")
	)
	(segment
		(start 77.991716 -61.829188)
		(end 78.000606 -61.813948)
		(width 0.0889)
		(layer "In4.Cu")
		(net "M_J_ECC<5>")
	)
	(segment
		(start 77.991716 -59.847988)
		(end 78.000606 -59.832748)
		(width 0.0889)
		(layer "In4.Cu")
		(net "M_J_ECC<5>")
	)
	(segment
		(start 72.210168 -32.588454)
		(end 70.076568 -30.454854)
		(width 0.14224)
		(layer "In4.Cu")
		(net "M_J_ECC<5>")
	)
	(segment
		(start 77.710792 -48.731424)
		(end 72.921368 -43.942)
		(width 0.14224)
		(layer "In4.Cu")
		(net "M_J_ECC<5>")
	)
	(segment
		(start 70.046596 -18.503646)
		(end 70.046596 -16.928846)
		(width 0.14224)
		(layer "In4.Cu")
		(net "M_J_ECC<5>")
	)
	(segment
		(start 69.957696 -21.872956)
		(end 69.957696 -18.592546)
		(width 0.14224)
		(layer "In4.Cu")
		(net "M_J_ECC<5>")
	)
	(segment
		(start 69.644768 -6.3246)
		(end 69.644768 -4.5212)
		(width 0.14224)
		(layer "In4.Cu")
		(net "M_J_ECC<5>")
	)
	(segment
		(start 77.991716 -63.810388)
		(end 78.000606 -63.795148)
		(width 0.0889)
		(layer "In4.Cu")
		(net "M_J_ECC<5>")
	)
	(segment
		(start 69.957696 -28.212796)
		(end 70.044564 -28.125928)
		(width 0.14224)
		(layer "In4.Cu")
		(net "M_J_ECC<5>")
	)
	(segment
		(start 69.983096 -13.681456)
		(end 70.046596 -13.617956)
		(width 0.14224)
		(layer "In4.Cu")
		(net "M_J_ECC<5>")
	)
	(segment
		(start 77.710792 -50.124614)
		(end 77.710792 -48.731424)
		(width 0.14224)
		(layer "In4.Cu")
		(net "M_J_ECC<5>")
	)
	(segment
		(start 77.991716 -54.894988)
		(end 78.000606 -54.879748)
		(width 0.0889)
		(layer "In4.Cu")
		(net "M_J_ECC<5>")
	)
	(segment
		(start 70.046596 -12.360656)
		(end 69.957696 -12.271756)
		(width 0.14224)
		(layer "In4.Cu")
		(net "M_J_ECC<5>")
	)
	(segment
		(start 70.046596 -23.219156)
		(end 70.046596 -21.961856)
		(width 0.14224)
		(layer "In4.Cu")
		(net "M_J_ECC<5>")
	)
	(segment
		(start 77.991716 -56.876188)
		(end 78.000606 -56.860948)
		(width 0.0889)
		(layer "In4.Cu")
		(net "M_J_ECC<5>")
	)
	(segment
		(start 70.046596 -21.961856)
		(end 69.957696 -21.872956)
		(width 0.14224)
		(layer "In4.Cu")
		(net "M_J_ECC<5>")
	)
	(segment
		(start 70.046596 -8.902446)
		(end 70.046596 -7.327646)
		(width 0.14224)
		(layer "In4.Cu")
		(net "M_J_ECC<5>")
	)
	(segment
		(start 72.921368 -43.092116)
		(end 72.779128 -42.949876)
		(width 0.14224)
		(layer "In4.Cu")
		(net "M_J_ECC<5>")
	)
	(segment
		(start 70.046596 -7.327646)
		(end 69.983096 -7.264146)
		(width 0.14224)
		(layer "In4.Cu")
		(net "M_J_ECC<5>")
	)
	(segment
		(start 69.983096 -6.662928)
		(end 69.644768 -6.3246)
		(width 0.14224)
		(layer "In4.Cu")
		(net "M_J_ECC<5>")
	)
	(segment
		(start 72.921368 -42.157396)
		(end 72.921368 -36.6268)
		(width 0.14224)
		(layer "In4.Cu")
		(net "M_J_ECC<5>")
	)
	(segment
		(start 77.991716 -64.800988)
		(end 78.000606 -64.785748)
		(width 0.0889)
		(layer "In4.Cu")
		(net "M_J_ECC<5>")
	)
	(segment
		(start 78.492604 -67.599052)
		(end 78.490318 -67.59829)
		(width 0.0889)
		(layer "In4.Cu")
		(net "M_J_ECC<5>")
	)
	(segment
		(start 72.779128 -42.949876)
		(end 72.352408 -42.949876)
		(width 0.14224)
		(layer "In4.Cu")
		(net "M_J_ECC<5>")
	)
	(segment
		(start 78.07071 -53.298598)
		(end 78.07071 -51.61026)
		(width 0.0889)
		(layer "In4.Cu")
		(net "M_J_ECC<5>")
	)
	(segment
		(start 69.085968 -3.9624)
		(end 69.085968 -3.564128)
		(width 0.14224)
		(layer "In4.Cu")
		(net "M_J_ECC<5>")
	)
	(segment
		(start 77.991716 -60.838588)
		(end 78.000606 -60.823348)
		(width 0.0889)
		(layer "In4.Cu")
		(net "M_J_ECC<5>")
	)
	(segment
		(start 70.044564 -28.125928)
		(end 70.044564 -26.841196)
		(width 0.14224)
		(layer "In4.Cu")
		(net "M_J_ECC<5>")
	)
	(segment
		(start 69.085968 -3.564128)
		(end 69.57314 -3.076956)
		(width 0.14224)
		(layer "In4.Cu")
		(net "M_J_ECC<5>")
	)
	(segment
		(start 69.957696 -26.754328)
		(end 69.957696 -23.308056)
		(width 0.14224)
		(layer "In4.Cu")
		(net "M_J_ECC<5>")
	)
	(segment
		(start 72.921368 -43.942)
		(end 72.921368 -43.092116)
		(width 0.14224)
		(layer "In4.Cu")
		(net "M_J_ECC<5>")
	)
	(segment
		(start 69.957696 -12.271756)
		(end 69.957696 -8.991346)
		(width 0.14224)
		(layer "In4.Cu")
		(net "M_J_ECC<5>")
	)
	(segment
		(start 72.210168 -42.441876)
		(end 72.352408 -42.299636)
		(width 0.14224)
		(layer "In4.Cu")
		(net "M_J_ECC<5>")
	)
	(segment
		(start 77.489304 -50.346102)
		(end 77.710792 -50.124614)
		(width 0.0889)
		(layer "In4.Cu")
		(net "M_J_ECC<5>")
	)
	(segment
		(start 77.991716 -55.885588)
		(end 78.000606 -55.870348)
		(width 0.0889)
		(layer "In4.Cu")
		(net "M_J_ECC<5>")
	)
	(segment
		(start 69.957696 -23.308056)
		(end 70.046596 -23.219156)
		(width 0.14224)
		(layer "In4.Cu")
		(net "M_J_ECC<5>")
	)
	(segment
		(start 69.957696 -18.592546)
		(end 70.046596 -18.503646)
		(width 0.14224)
		(layer "In4.Cu")
		(net "M_J_ECC<5>")
	)
	(segment
		(start 72.352408 -42.949876)
		(end 72.210168 -42.807636)
		(width 0.14224)
		(layer "In4.Cu")
		(net "M_J_ECC<5>")
	)
	(segment
		(start 77.489304 -51.028854)
		(end 77.489304 -50.346102)
		(width 0.0889)
		(layer "In4.Cu")
		(net "M_J_ECC<5>")
	)
	(segment
		(start 77.991716 -65.791588)
		(end 78.000606 -65.776348)
		(width 0.0889)
		(layer "In4.Cu")
		(net "M_J_ECC<5>")
	)
	(segment
		(start 78.07071 -51.61026)
		(end 77.489304 -51.028854)
		(width 0.0889)
		(layer "In4.Cu")
		(net "M_J_ECC<5>")
	)
	(segment
		(start 77.991716 -53.904388)
		(end 78.000606 -53.889148)
		(width 0.0889)
		(layer "In4.Cu")
		(net "M_J_ECC<5>")
	)
	(segment
		(start 69.957696 -28.7528)
		(end 69.957696 -28.212796)
		(width 0.14224)
		(layer "In4.Cu")
		(net "M_J_ECC<5>")
	)
	(segment
		(start 70.046596 -16.928846)
		(end 69.983096 -16.865346)
		(width 0.14224)
		(layer "In4.Cu")
		(net "M_J_ECC<5>")
	)
	(segment
		(start 70.076568 -28.871672)
		(end 69.957696 -28.7528)
		(width 0.14224)
		(layer "In4.Cu")
		(net "M_J_ECC<5>")
	)
	(segment
		(start 69.983096 -16.865346)
		(end 69.983096 -13.681456)
		(width 0.14224)
		(layer "In4.Cu")
		(net "M_J_ECC<5>")
	)
	(segment
		(start 78.338172 -68.963286)
		(end 78.612492 -68.264024)
		(width 0.0889)
		(layer "In4.Cu")
		(net "M_J_ECC<5>")
	)
	(arc
		(start 78.000606 -55.870348)
		(mid 78.071003 -55.581397)
		(end 77.991716 -55.294784)
		(width 0.0889)
		(layer "In4.Cu")
		(net "M_J_ECC<5>")
	)
	(arc
		(start 77.991716 -66.782188)
		(mid 78.070847 -66.486786)
		(end 77.991716 -66.191384)
		(width 0.0889)
		(layer "In4.Cu")
		(net "M_J_ECC<5>")
	)
	(arc
		(start 77.991716 -61.238384)
		(mid 77.938183 -61.038486)
		(end 77.991716 -60.838588)
		(width 0.0889)
		(layer "In4.Cu")
		(net "M_J_ECC<5>")
	)
	(arc
		(start 78.000606 -56.860948)
		(mid 78.071003 -56.571997)
		(end 77.991716 -56.285384)
		(width 0.0889)
		(layer "In4.Cu")
		(net "M_J_ECC<5>")
	)
	(arc
		(start 77.991716 -57.275984)
		(mid 77.938183 -57.076086)
		(end 77.991716 -56.876188)
		(width 0.0889)
		(layer "In4.Cu")
		(net "M_J_ECC<5>")
	)
	(arc
		(start 78.000606 -60.823348)
		(mid 78.071003 -60.534397)
		(end 77.991716 -60.247784)
		(width 0.0889)
		(layer "In4.Cu")
		(net "M_J_ECC<5>")
	)
	(arc
		(start 77.991716 -56.285384)
		(mid 77.938183 -56.085486)
		(end 77.991716 -55.885588)
		(width 0.0889)
		(layer "In4.Cu")
		(net "M_J_ECC<5>")
	)
	(arc
		(start 77.991716 -58.266838)
		(mid 77.938183 -58.06694)
		(end 77.991716 -57.867042)
		(width 0.0889)
		(layer "In4.Cu")
		(net "M_J_ECC<5>")
	)
	(arc
		(start 78.000606 -59.832748)
		(mid 78.071003 -59.543797)
		(end 77.991716 -59.257184)
		(width 0.0889)
		(layer "In4.Cu")
		(net "M_J_ECC<5>")
	)
	(arc
		(start 78.000606 -54.879748)
		(mid 78.071003 -54.590797)
		(end 77.991716 -54.304184)
		(width 0.0889)
		(layer "In4.Cu")
		(net "M_J_ECC<5>")
	)
	(arc
		(start 78.612492 -68.264024)
		(mid 78.73277 -67.899091)
		(end 78.492604 -67.599052)
		(width 0.0889)
		(layer "In4.Cu")
		(net "M_J_ECC<5>")
	)
	(arc
		(start 77.991716 -64.210184)
		(mid 77.938183 -64.010286)
		(end 77.991716 -63.810388)
		(width 0.0889)
		(layer "In4.Cu")
		(net "M_J_ECC<5>")
	)
	(arc
		(start 77.991716 -55.294784)
		(mid 77.938183 -55.094886)
		(end 77.991716 -54.894988)
		(width 0.0889)
		(layer "In4.Cu")
		(net "M_J_ECC<5>")
	)
	(arc
		(start 78.490318 -67.59829)
		(mid 78.203043 -67.435609)
		(end 77.991716 -67.181984)
		(width 0.0889)
		(layer "In4.Cu")
		(net "M_J_ECC<5>")
	)
	(arc
		(start 77.991716 -60.247784)
		(mid 77.938183 -60.047886)
		(end 77.991716 -59.847988)
		(width 0.0889)
		(layer "In4.Cu")
		(net "M_J_ECC<5>")
	)
	(arc
		(start 78.000606 -53.889148)
		(mid 78.053126 -53.753554)
		(end 78.070964 -53.60924)
		(width 0.0889)
		(layer "In4.Cu")
		(net "M_J_ECC<5>")
	)
	(arc
		(start 77.991716 -66.191384)
		(mid 77.938183 -65.991486)
		(end 77.991716 -65.791588)
		(width 0.0889)
		(layer "In4.Cu")
		(net "M_J_ECC<5>")
	)
	(arc
		(start 78.000606 -61.813948)
		(mid 78.071003 -61.524997)
		(end 77.991716 -61.238384)
		(width 0.0889)
		(layer "In4.Cu")
		(net "M_J_ECC<5>")
	)
	(arc
		(start 77.991716 -62.228984)
		(mid 77.938183 -62.029086)
		(end 77.991716 -61.829188)
		(width 0.0889)
		(layer "In4.Cu")
		(net "M_J_ECC<5>")
	)
	(arc
		(start 77.991716 -65.200784)
		(mid 77.938183 -65.000886)
		(end 77.991716 -64.800988)
		(width 0.0889)
		(layer "In4.Cu")
		(net "M_J_ECC<5>")
	)
	(arc
		(start 78.000606 -62.804548)
		(mid 78.071003 -62.515597)
		(end 77.991716 -62.228984)
		(width 0.0889)
		(layer "In4.Cu")
		(net "M_J_ECC<5>")
	)
	(arc
		(start 78.000606 -63.795148)
		(mid 78.071003 -63.506197)
		(end 77.991716 -63.219584)
		(width 0.0889)
		(layer "In4.Cu")
		(net "M_J_ECC<5>")
	)
	(arc
		(start 78.000606 -65.776348)
		(mid 78.071003 -65.487397)
		(end 77.991716 -65.200784)
		(width 0.0889)
		(layer "In4.Cu")
		(net "M_J_ECC<5>")
	)
	(arc
		(start 77.998066 -57.856374)
		(mid 78.070986 -57.565357)
		(end 77.991716 -57.275984)
		(width 0.0889)
		(layer "In4.Cu")
		(net "M_J_ECC<5>")
	)
	(arc
		(start 77.991716 -63.219584)
		(mid 77.938183 -63.019686)
		(end 77.991716 -62.819788)
		(width 0.0889)
		(layer "In4.Cu")
		(net "M_J_ECC<5>")
	)
	(arc
		(start 77.991716 -58.857388)
		(mid 78.070938 -58.56827)
		(end 77.998066 -58.277506)
		(width 0.0889)
		(layer "In4.Cu")
		(net "M_J_ECC<5>")
	)
	(arc
		(start 77.991716 -54.304184)
		(mid 77.938183 -54.104286)
		(end 77.991716 -53.904388)
		(width 0.0889)
		(layer "In4.Cu")
		(net "M_J_ECC<5>")
	)
	(arc
		(start 77.991716 -59.257184)
		(mid 77.938183 -59.057286)
		(end 77.991716 -58.857388)
		(width 0.0889)
		(layer "In4.Cu")
		(net "M_J_ECC<5>")
	)
	(arc
		(start 78.000606 -64.785748)
		(mid 78.071003 -64.496797)
		(end 77.991716 -64.210184)
		(width 0.0889)
		(layer "In4.Cu")
		(net "M_J_ECC<5>")
	)
	(arc
		(start 77.991716 -67.181984)
		(mid 77.938183 -66.982086)
		(end 77.991716 -66.782188)
		(width 0.0889)
		(layer "In4.Cu")
		(net "M_J_ECC<5>")
	)
	(segment
		(start 70.081394 0.7366)
		(end 70.081394 1.149096)
		(width 0.14224)
		(layer "In11.Cu")
		(net "M_J_ECC<5>")
	)
	(segment
		(start 69.884544 -2.765552)
		(end 69.884544 0.53975)
		(width 0.14224)
		(layer "In11.Cu")
		(net "M_J_ECC<5>")
	)
	(segment
		(start 69.68109 1.5494)
		(end 69.370194 1.5494)
		(width 0.14224)
		(layer "In11.Cu")
		(net "M_J_ECC<5>")
	)
	(segment
		(start 70.081394 1.149096)
		(end 69.68109 1.5494)
		(width 0.14224)
		(layer "In11.Cu")
		(net "M_J_ECC<5>")
	)
	(segment
		(start 69.57314 -3.076956)
		(end 69.884544 -2.765552)
		(width 0.14224)
		(layer "In11.Cu")
		(net "M_J_ECC<5>")
	)
	(segment
		(start 69.370194 1.5494)
		(end 68.799456 2.120138)
		(width 0.14224)
		(layer "In11.Cu")
		(net "M_J_ECC<5>")
	)
	(segment
		(start 69.884544 0.53975)
		(end 70.081394 0.7366)
		(width 0.14224)
		(layer "In11.Cu")
		(net "M_J_ECC<5>")
	)
	(segment
		(start 68.799456 2.120138)
		(end 68.799456 2.514854)
		(width 0.14224)
		(layer "In11.Cu")
		(net "M_J_ECC<5>")
	)
	(segment
		(start 69.64934 0.510032)
		(end 69.551296 1.0414)
		(width 0.1651)
		(layer "F.Cu")
		(net "M_J_ECC<4>")
	)
	(segment
		(start 69.64934 -0.821182)
		(end 69.64934 0.510032)
		(width 0.1651)
		(layer "F.Cu")
		(net "M_J_ECC<4>")
	)
	(segment
		(start 78.909672 -67.972686)
		(end 78.338172 -67.972686)
		(width 0.0889)
		(layer "F.Cu")
		(net "M_J_ECC<4>")
	)
	(via
		(at 78.338172 -67.972686)
		(size 0.508)
		(drill 0.254)
		(layers "F.Cu" "B.Cu")
		(net "M_J_ECC<4>")
	)
	(via
		(at 69.551296 1.0414)
		(size 0.508)
		(drill 0.254)
		(layers "F.Cu" "B.Cu")
		(net "M_J_ECC<4>")
	)
	(via
		(at 68.799456 -4.357878)
		(size 0.508)
		(drill 0.254)
		(layers "F.Cu" "B.Cu")
		(net "M_J_ECC<4>")
	)
	(segment
		(start 68.799456 -5.621782)
		(end 68.799456 -4.357878)
		(width 0.1651)
		(layer "B.Cu")
		(net "M_J_ECC<4>")
	)
	(segment
		(start 69.322696 -18.567146)
		(end 69.068696 -18.313146)
		(width 0.14224)
		(layer "In4.Cu")
		(net "M_J_ECC<4>")
	)
	(segment
		(start 69.297296 -28.365196)
		(end 69.053964 -28.121864)
		(width 0.14224)
		(layer "In4.Cu")
		(net "M_J_ECC<4>")
	)
	(segment
		(start 78.338172 -67.972686)
		(end 78.279498 -67.90944)
		(width 0.0889)
		(layer "In4.Cu")
		(net "M_J_ECC<4>")
	)
	(segment
		(start 69.441568 -29.1338)
		(end 69.297296 -28.989528)
		(width 0.14224)
		(layer "In4.Cu")
		(net "M_J_ECC<4>")
	)
	(segment
		(start 69.068696 -8.711946)
		(end 69.068696 -7.433818)
		(width 0.14224)
		(layer "In4.Cu")
		(net "M_J_ECC<4>")
	)
	(segment
		(start 71.511668 -33.019746)
		(end 69.441568 -30.949646)
		(width 0.14224)
		(layer "In4.Cu")
		(net "M_J_ECC<4>")
	)
	(segment
		(start 69.297296 -16.22679)
		(end 69.085968 -16.015462)
		(width 0.14224)
		(layer "In4.Cu")
		(net "M_J_ECC<4>")
	)
	(segment
		(start 69.322696 -19.907758)
		(end 69.322696 -18.567146)
		(width 0.14224)
		(layer "In4.Cu")
		(net "M_J_ECC<4>")
	)
	(segment
		(start 69.111368 -20.119086)
		(end 69.322696 -19.907758)
		(width 0.14224)
		(layer "In4.Cu")
		(net "M_J_ECC<4>")
	)
	(segment
		(start 77.817472 -56.796178)
		(end 77.826362 -56.780938)
		(width 0.0889)
		(layer "In4.Cu")
		(net "M_J_ECC<4>")
	)
	(segment
		(start 71.676768 -36.524946)
		(end 71.511668 -36.359846)
		(width 0.14224)
		(layer "In4.Cu")
		(net "M_J_ECC<4>")
	)
	(segment
		(start 71.676768 -40.459914)
		(end 71.676768 -40.094154)
		(width 0.14224)
		(layer "In4.Cu")
		(net "M_J_ECC<4>")
	)
	(segment
		(start 69.068696 -13.567156)
		(end 69.068696 -12.347956)
		(width 0.14224)
		(layer "In4.Cu")
		(net "M_J_ECC<4>")
	)
	(segment
		(start 69.085968 -25.284176)
		(end 69.297296 -25.072848)
		(width 0.14224)
		(layer "In4.Cu")
		(net "M_J_ECC<4>")
	)
	(segment
		(start 77.298804 -51.108102)
		(end 77.298804 -50.347626)
		(width 0.0889)
		(layer "In4.Cu")
		(net "M_J_ECC<4>")
	)
	(segment
		(start 72.311768 -39.443914)
		(end 72.169528 -39.301674)
		(width 0.14224)
		(layer "In4.Cu")
		(net "M_J_ECC<4>")
	)
	(segment
		(start 72.311768 -40.744394)
		(end 72.169528 -40.602154)
		(width 0.14224)
		(layer "In4.Cu")
		(net "M_J_ECC<4>")
	)
	(segment
		(start 71.819008 -41.252394)
		(end 72.169528 -41.252394)
		(width 0.14224)
		(layer "In4.Cu")
		(net "M_J_ECC<4>")
	)
	(segment
		(start 69.322696 -20.931886)
		(end 69.111368 -20.720558)
		(width 0.14224)
		(layer "In4.Cu")
		(net "M_J_ECC<4>")
	)
	(segment
		(start 69.297296 -28.989528)
		(end 69.297296 -28.365196)
		(width 0.14224)
		(layer "In4.Cu")
		(net "M_J_ECC<4>")
	)
	(segment
		(start 69.068696 -21.949156)
		(end 69.322696 -21.695156)
		(width 0.14224)
		(layer "In4.Cu")
		(net "M_J_ECC<4>")
	)
	(segment
		(start 72.169528 -39.951914)
		(end 72.311768 -39.809674)
		(width 0.14224)
		(layer "In4.Cu")
		(net "M_J_ECC<4>")
	)
	(segment
		(start 69.297296 -26.096976)
		(end 69.085968 -25.885648)
		(width 0.14224)
		(layer "In4.Cu")
		(net "M_J_ECC<4>")
	)
	(segment
		(start 71.511668 -36.359846)
		(end 71.511668 -33.019746)
		(width 0.14224)
		(layer "In4.Cu")
		(net "M_J_ECC<4>")
	)
	(segment
		(start 69.263768 -6.8834)
		(end 68.799456 -6.419088)
		(width 0.14224)
		(layer "In4.Cu")
		(net "M_J_ECC<4>")
	)
	(segment
		(start 69.441568 -30.949646)
		(end 69.441568 -29.1338)
		(width 0.14224)
		(layer "In4.Cu")
		(net "M_J_ECC<4>")
	)
	(segment
		(start 69.068696 -7.433818)
		(end 69.263768 -7.238746)
		(width 0.14224)
		(layer "In4.Cu")
		(net "M_J_ECC<4>")
	)
	(segment
		(start 77.099668 -49.0474)
		(end 71.676768 -43.6245)
		(width 0.14224)
		(layer "In4.Cu")
		(net "M_J_ECC<4>")
	)
	(segment
		(start 77.830426 -67.2846)
		(end 77.826362 -67.277488)
		(width 0.0889)
		(layer "In4.Cu")
		(net "M_J_ECC<4>")
	)
	(segment
		(start 71.676768 -41.394634)
		(end 71.819008 -41.252394)
		(width 0.14224)
		(layer "In4.Cu")
		(net "M_J_ECC<4>")
	)
	(segment
		(start 69.322696 -11.433556)
		(end 69.085968 -11.196828)
		(width 0.14224)
		(layer "In4.Cu")
		(net "M_J_ECC<4>")
	)
	(segment
		(start 69.068696 -12.347956)
		(end 69.322696 -12.093956)
		(width 0.14224)
		(layer "In4.Cu")
		(net "M_J_ECC<4>")
	)
	(segment
		(start 77.817472 -64.720978)
		(end 77.826362 -64.705738)
		(width 0.0889)
		(layer "In4.Cu")
		(net "M_J_ECC<4>")
	)
	(segment
		(start 69.068696 -23.168356)
		(end 69.068696 -21.949156)
		(width 0.14224)
		(layer "In4.Cu")
		(net "M_J_ECC<4>")
	)
	(segment
		(start 77.879956 -51.689254)
		(end 77.298804 -51.108102)
		(width 0.0889)
		(layer "In4.Cu")
		(net "M_J_ECC<4>")
	)
	(segment
		(start 71.819008 -39.951914)
		(end 72.169528 -39.951914)
		(width 0.14224)
		(layer "In4.Cu")
		(net "M_J_ECC<4>")
	)
	(segment
		(start 69.068696 -18.313146)
		(end 69.068696 -17.060418)
		(width 0.14224)
		(layer "In4.Cu")
		(net "M_J_ECC<4>")
	)
	(segment
		(start 77.879956 -53.60924)
		(end 77.879956 -51.689254)
		(width 0.0889)
		(layer "In4.Cu")
		(net "M_J_ECC<4>")
	)
	(segment
		(start 77.817472 -62.739778)
		(end 77.826362 -62.724538)
		(width 0.0889)
		(layer "In4.Cu")
		(net "M_J_ECC<4>")
	)
	(segment
		(start 69.085968 -10.620756)
		(end 69.322696 -10.384028)
		(width 0.14224)
		(layer "In4.Cu")
		(net "M_J_ECC<4>")
	)
	(segment
		(start 69.297296 -15.202662)
		(end 69.297296 -13.795756)
		(width 0.14224)
		(layer "In4.Cu")
		(net "M_J_ECC<4>")
	)
	(segment
		(start 77.817472 -65.711578)
		(end 77.826362 -65.696338)
		(width 0.0889)
		(layer "In4.Cu")
		(net "M_J_ECC<4>")
	)
	(segment
		(start 77.817472 -55.805578)
		(end 77.826362 -55.790338)
		(width 0.0889)
		(layer "In4.Cu")
		(net "M_J_ECC<4>")
	)
	(segment
		(start 77.817472 -63.730378)
		(end 77.826362 -63.715138)
		(width 0.0889)
		(layer "In4.Cu")
		(net "M_J_ECC<4>")
	)
	(segment
		(start 69.085968 -16.015462)
		(end 69.085968 -15.41399)
		(width 0.14224)
		(layer "In4.Cu")
		(net "M_J_ECC<4>")
	)
	(segment
		(start 68.799456 -6.419088)
		(end 68.799456 -4.357878)
		(width 0.14224)
		(layer "In4.Cu")
		(net "M_J_ECC<4>")
	)
	(segment
		(start 69.297296 -16.831818)
		(end 69.297296 -16.22679)
		(width 0.14224)
		(layer "In4.Cu")
		(net "M_J_ECC<4>")
	)
	(segment
		(start 69.085968 -25.885648)
		(end 69.085968 -25.284176)
		(width 0.14224)
		(layer "In4.Cu")
		(net "M_J_ECC<4>")
	)
	(segment
		(start 69.297296 -23.396956)
		(end 69.068696 -23.168356)
		(width 0.14224)
		(layer "In4.Cu")
		(net "M_J_ECC<4>")
	)
	(segment
		(start 77.826362 -58.362088)
		(end 77.820012 -58.35142)
		(width 0.0889)
		(layer "In4.Cu")
		(net "M_J_ECC<4>")
	)
	(segment
		(start 69.085968 -11.196828)
		(end 69.085968 -10.620756)
		(width 0.14224)
		(layer "In4.Cu")
		(net "M_J_ECC<4>")
	)
	(segment
		(start 69.322696 -10.384028)
		(end 69.322696 -8.965946)
		(width 0.14224)
		(layer "In4.Cu")
		(net "M_J_ECC<4>")
	)
	(segment
		(start 72.311768 -39.809674)
		(end 72.311768 -39.443914)
		(width 0.14224)
		(layer "In4.Cu")
		(net "M_J_ECC<4>")
	)
	(segment
		(start 69.322696 -12.093956)
		(end 69.322696 -11.433556)
		(width 0.14224)
		(layer "In4.Cu")
		(net "M_J_ECC<4>")
	)
	(segment
		(start 77.298804 -50.347626)
		(end 77.075792 -50.124614)
		(width 0.0889)
		(layer "In4.Cu")
		(net "M_J_ECC<4>")
	)
	(segment
		(start 71.676768 -39.159434)
		(end 71.676768 -36.524946)
		(width 0.14224)
		(layer "In4.Cu")
		(net "M_J_ECC<4>")
	)
	(segment
		(start 69.068696 -17.060418)
		(end 69.297296 -16.831818)
		(width 0.14224)
		(layer "In4.Cu")
		(net "M_J_ECC<4>")
	)
	(segment
		(start 71.819008 -40.602154)
		(end 71.676768 -40.459914)
		(width 0.14224)
		(layer "In4.Cu")
		(net "M_J_ECC<4>")
	)
	(segment
		(start 69.085968 -15.41399)
		(end 69.297296 -15.202662)
		(width 0.14224)
		(layer "In4.Cu")
		(net "M_J_ECC<4>")
	)
	(segment
		(start 77.820012 -58.772552)
		(end 77.826362 -58.761884)
		(width 0.0889)
		(layer "In4.Cu")
		(net "M_J_ECC<4>")
	)
	(segment
		(start 77.817472 -59.767978)
		(end 77.826362 -59.752738)
		(width 0.0889)
		(layer "In4.Cu")
		(net "M_J_ECC<4>")
	)
	(segment
		(start 69.322696 -21.695156)
		(end 69.322696 -20.931886)
		(width 0.14224)
		(layer "In4.Cu")
		(net "M_J_ECC<4>")
	)
	(segment
		(start 72.169528 -41.252394)
		(end 72.311768 -41.110154)
		(width 0.14224)
		(layer "In4.Cu")
		(net "M_J_ECC<4>")
	)
	(segment
		(start 69.111368 -20.720558)
		(end 69.111368 -20.119086)
		(width 0.14224)
		(layer "In4.Cu")
		(net "M_J_ECC<4>")
	)
	(segment
		(start 69.297296 -13.795756)
		(end 69.068696 -13.567156)
		(width 0.14224)
		(layer "In4.Cu")
		(net "M_J_ECC<4>")
	)
	(segment
		(start 77.817472 -60.758578)
		(end 77.826362 -60.743338)
		(width 0.0889)
		(layer "In4.Cu")
		(net "M_J_ECC<4>")
	)
	(segment
		(start 69.263768 -7.238746)
		(end 69.263768 -6.8834)
		(width 0.14224)
		(layer "In4.Cu")
		(net "M_J_ECC<4>")
	)
	(segment
		(start 77.075792 -50.124614)
		(end 77.099668 -50.100738)
		(width 0.14224)
		(layer "In4.Cu")
		(net "M_J_ECC<4>")
	)
	(segment
		(start 77.817472 -54.814978)
		(end 77.826362 -54.799738)
		(width 0.0889)
		(layer "In4.Cu")
		(net "M_J_ECC<4>")
	)
	(segment
		(start 72.311768 -41.110154)
		(end 72.311768 -40.744394)
		(width 0.14224)
		(layer "In4.Cu")
		(net "M_J_ECC<4>")
	)
	(segment
		(start 71.676768 -43.6245)
		(end 71.676768 -41.394634)
		(width 0.14224)
		(layer "In4.Cu")
		(net "M_J_ECC<4>")
	)
	(segment
		(start 77.817472 -53.824378)
		(end 77.826362 -53.809138)
		(width 0.0889)
		(layer "In4.Cu")
		(net "M_J_ECC<4>")
	)
	(segment
		(start 72.169528 -39.301674)
		(end 71.819008 -39.301674)
		(width 0.14224)
		(layer "In4.Cu")
		(net "M_J_ECC<4>")
	)
	(segment
		(start 69.053964 -26.993596)
		(end 69.297296 -26.750264)
		(width 0.14224)
		(layer "In4.Cu")
		(net "M_J_ECC<4>")
	)
	(segment
		(start 69.053964 -28.121864)
		(end 69.053964 -26.993596)
		(width 0.14224)
		(layer "In4.Cu")
		(net "M_J_ECC<4>")
	)
	(segment
		(start 77.099668 -50.100738)
		(end 77.099668 -49.0474)
		(width 0.14224)
		(layer "In4.Cu")
		(net "M_J_ECC<4>")
	)
	(segment
		(start 77.817472 -61.749178)
		(end 77.826362 -61.733938)
		(width 0.0889)
		(layer "In4.Cu")
		(net "M_J_ECC<4>")
	)
	(segment
		(start 69.297296 -26.750264)
		(end 69.297296 -26.096976)
		(width 0.14224)
		(layer "In4.Cu")
		(net "M_J_ECC<4>")
	)
	(segment
		(start 71.819008 -39.301674)
		(end 71.676768 -39.159434)
		(width 0.14224)
		(layer "In4.Cu")
		(net "M_J_ECC<4>")
	)
	(segment
		(start 69.297296 -25.072848)
		(end 69.297296 -23.396956)
		(width 0.14224)
		(layer "In4.Cu")
		(net "M_J_ECC<4>")
	)
	(segment
		(start 71.676768 -40.094154)
		(end 71.819008 -39.951914)
		(width 0.14224)
		(layer "In4.Cu")
		(net "M_J_ECC<4>")
	)
	(segment
		(start 72.169528 -40.602154)
		(end 71.819008 -40.602154)
		(width 0.14224)
		(layer "In4.Cu")
		(net "M_J_ECC<4>")
	)
	(segment
		(start 69.322696 -8.965946)
		(end 69.068696 -8.711946)
		(width 0.14224)
		(layer "In4.Cu")
		(net "M_J_ECC<4>")
	)
	(arc
		(start 77.826362 -57.371742)
		(mid 77.747173 -57.085127)
		(end 77.817472 -56.796178)
		(width 0.0889)
		(layer "In4.Cu")
		(net "M_J_ECC<4>")
	)
	(arc
		(start 77.826362 -54.399942)
		(mid 77.747173 -54.113327)
		(end 77.817472 -53.824378)
		(width 0.0889)
		(layer "In4.Cu")
		(net "M_J_ECC<4>")
	)
	(arc
		(start 77.826362 -53.809138)
		(mid 77.86628 -53.712711)
		(end 77.879956 -53.60924)
		(width 0.0889)
		(layer "In4.Cu")
		(net "M_J_ECC<4>")
	)
	(arc
		(start 77.826362 -56.780938)
		(mid 77.879895 -56.58104)
		(end 77.826362 -56.381142)
		(width 0.0889)
		(layer "In4.Cu")
		(net "M_J_ECC<4>")
	)
	(arc
		(start 77.826362 -64.305942)
		(mid 77.747173 -64.019327)
		(end 77.817472 -63.730378)
		(width 0.0889)
		(layer "In4.Cu")
		(net "M_J_ECC<4>")
	)
	(arc
		(start 77.826362 -65.696338)
		(mid 77.879895 -65.49644)
		(end 77.826362 -65.296542)
		(width 0.0889)
		(layer "In4.Cu")
		(net "M_J_ECC<4>")
	)
	(arc
		(start 77.826362 -58.761884)
		(mid 77.879895 -58.561986)
		(end 77.826362 -58.362088)
		(width 0.0889)
		(layer "In4.Cu")
		(net "M_J_ECC<4>")
	)
	(arc
		(start 77.826362 -64.705738)
		(mid 77.879895 -64.50584)
		(end 77.826362 -64.305942)
		(width 0.0889)
		(layer "In4.Cu")
		(net "M_J_ECC<4>")
	)
	(arc
		(start 77.826362 -63.315342)
		(mid 77.747173 -63.028727)
		(end 77.817472 -62.739778)
		(width 0.0889)
		(layer "In4.Cu")
		(net "M_J_ECC<4>")
	)
	(arc
		(start 77.826362 -65.296542)
		(mid 77.747173 -65.009927)
		(end 77.817472 -64.720978)
		(width 0.0889)
		(layer "In4.Cu")
		(net "M_J_ECC<4>")
	)
	(arc
		(start 77.826362 -55.390542)
		(mid 77.747173 -55.103927)
		(end 77.817472 -54.814978)
		(width 0.0889)
		(layer "In4.Cu")
		(net "M_J_ECC<4>")
	)
	(arc
		(start 78.279498 -67.90944)
		(mid 78.039351 -67.608239)
		(end 77.830426 -67.2846)
		(width 0.0889)
		(layer "In4.Cu")
		(net "M_J_ECC<4>")
	)
	(arc
		(start 77.826362 -62.324742)
		(mid 77.747173 -62.038127)
		(end 77.817472 -61.749178)
		(width 0.0889)
		(layer "In4.Cu")
		(net "M_J_ECC<4>")
	)
	(arc
		(start 77.826362 -57.771538)
		(mid 77.879895 -57.57164)
		(end 77.826362 -57.371742)
		(width 0.0889)
		(layer "In4.Cu")
		(net "M_J_ECC<4>")
	)
	(arc
		(start 77.826362 -59.352942)
		(mid 77.747013 -59.06357)
		(end 77.820012 -58.772552)
		(width 0.0889)
		(layer "In4.Cu")
		(net "M_J_ECC<4>")
	)
	(arc
		(start 77.826362 -61.334142)
		(mid 77.747173 -61.047527)
		(end 77.817472 -60.758578)
		(width 0.0889)
		(layer "In4.Cu")
		(net "M_J_ECC<4>")
	)
	(arc
		(start 77.826362 -66.286888)
		(mid 77.747242 -66.000385)
		(end 77.817472 -65.711578)
		(width 0.0889)
		(layer "In4.Cu")
		(net "M_J_ECC<4>")
	)
	(arc
		(start 77.826362 -60.343542)
		(mid 77.747173 -60.056927)
		(end 77.817472 -59.767978)
		(width 0.0889)
		(layer "In4.Cu")
		(net "M_J_ECC<4>")
	)
	(arc
		(start 77.826362 -54.799738)
		(mid 77.879895 -54.59984)
		(end 77.826362 -54.399942)
		(width 0.0889)
		(layer "In4.Cu")
		(net "M_J_ECC<4>")
	)
	(arc
		(start 77.826362 -62.724538)
		(mid 77.879895 -62.52464)
		(end 77.826362 -62.324742)
		(width 0.0889)
		(layer "In4.Cu")
		(net "M_J_ECC<4>")
	)
	(arc
		(start 77.826362 -55.790338)
		(mid 77.879895 -55.59044)
		(end 77.826362 -55.390542)
		(width 0.0889)
		(layer "In4.Cu")
		(net "M_J_ECC<4>")
	)
	(arc
		(start 77.826362 -56.381142)
		(mid 77.747173 -56.094527)
		(end 77.817472 -55.805578)
		(width 0.0889)
		(layer "In4.Cu")
		(net "M_J_ECC<4>")
	)
	(arc
		(start 77.826362 -63.715138)
		(mid 77.879895 -63.51524)
		(end 77.826362 -63.315342)
		(width 0.0889)
		(layer "In4.Cu")
		(net "M_J_ECC<4>")
	)
	(arc
		(start 77.820012 -58.35142)
		(mid 77.747214 -58.060657)
		(end 77.826362 -57.771538)
		(width 0.0889)
		(layer "In4.Cu")
		(net "M_J_ECC<4>")
	)
	(arc
		(start 77.826362 -66.686684)
		(mid 77.879895 -66.486786)
		(end 77.826362 -66.286888)
		(width 0.0889)
		(layer "In4.Cu")
		(net "M_J_ECC<4>")
	)
	(arc
		(start 77.826362 -67.277488)
		(mid 77.747231 -66.982086)
		(end 77.826362 -66.686684)
		(width 0.0889)
		(layer "In4.Cu")
		(net "M_J_ECC<4>")
	)
	(arc
		(start 77.826362 -60.743338)
		(mid 77.879895 -60.54344)
		(end 77.826362 -60.343542)
		(width 0.0889)
		(layer "In4.Cu")
		(net "M_J_ECC<4>")
	)
	(arc
		(start 77.826362 -61.733938)
		(mid 77.879895 -61.53404)
		(end 77.826362 -61.334142)
		(width 0.0889)
		(layer "In4.Cu")
		(net "M_J_ECC<4>")
	)
	(arc
		(start 77.826362 -59.752738)
		(mid 77.879895 -59.55284)
		(end 77.826362 -59.352942)
		(width 0.0889)
		(layer "In4.Cu")
		(net "M_J_ECC<4>")
	)
	(segment
		(start 68.563744 -4.122166)
		(end 68.563744 -3.327654)
		(width 0.14224)
		(layer "In11.Cu")
		(net "M_J_ECC<4>")
	)
	(segment
		(start 68.799456 -4.357878)
		(end 68.563744 -4.122166)
		(width 0.14224)
		(layer "In11.Cu")
		(net "M_J_ECC<4>")
	)
	(segment
		(start 69.274944 -2.616454)
		(end 69.274944 0.765048)
		(width 0.14224)
		(layer "In11.Cu")
		(net "M_J_ECC<4>")
	)
	(segment
		(start 69.274944 0.765048)
		(end 69.551296 1.0414)
		(width 0.14224)
		(layer "In11.Cu")
		(net "M_J_ECC<4>")
	)
	(segment
		(start 68.563744 -3.327654)
		(end 69.274944 -2.616454)
		(width 0.14224)
		(layer "In11.Cu")
		(net "M_J_ECC<4>")
	)
	(segment
		(start 82.343752 -68.963286)
		(end 81.772252 -68.963286)
		(width 0.0889)
		(layer "F.Cu")
		(net "M_J_ECC<3>")
	)
	(segment
		(start 76.449428 3.778758)
		(end 76.449428 2.514854)
		(width 0.1651)
		(layer "F.Cu")
		(net "M_J_ECC<3>")
	)
	(via
		(at 76.449428 2.514854)
		(size 0.508)
		(drill 0.254)
		(layers "F.Cu" "B.Cu")
		(net "M_J_ECC<3>")
	)
	(via
		(at 77.299312 -3.076956)
		(size 0.508)
		(drill 0.254)
		(layers "F.Cu" "B.Cu")
		(net "M_J_ECC<3>")
	)
	(via
		(at 81.772252 -68.963286)
		(size 0.508)
		(drill 0.254)
		(layers "F.Cu" "B.Cu")
		(net "M_J_ECC<3>")
	)
	(segment
		(start 77.299566 -1.021842)
		(end 77.299312 -1.022096)
		(width 0.1651)
		(layer "B.Cu")
		(net "M_J_ECC<3>")
	)
	(segment
		(start 77.299312 -1.022096)
		(end 77.299312 -3.076956)
		(width 0.1651)
		(layer "B.Cu")
		(net "M_J_ECC<3>")
	)
	(segment
		(start 77.816964 -26.383996)
		(end 77.679296 -26.246328)
		(width 0.14224)
		(layer "In4.Cu")
		(net "M_J_ECC<3>")
	)
	(segment
		(start 82.290412 -62.735206)
		(end 82.284062 -62.724538)
		(width 0.0889)
		(layer "In4.Cu")
		(net "M_J_ECC<3>")
	)
	(segment
		(start 77.679296 -23.335996)
		(end 77.780896 -23.234396)
		(width 0.14224)
		(layer "In4.Cu")
		(net "M_J_ECC<3>")
	)
	(segment
		(start 77.666596 -4.796028)
		(end 76.815696 -3.945128)
		(width 0.14224)
		(layer "In4.Cu")
		(net "M_J_ECC<3>")
	)
	(segment
		(start 82.093562 -68.290948)
		(end 82.230976 -68.153534)
		(width 0.0889)
		(layer "In4.Cu")
		(net "M_J_ECC<3>")
	)
	(segment
		(start 80.414368 -43.031156)
		(end 80.414368 -31.2039)
		(width 0.14224)
		(layer "In4.Cu")
		(net "M_J_ECC<3>")
	)
	(segment
		(start 81.772252 -68.963286)
		(end 82.093562 -68.290948)
		(width 0.0889)
		(layer "In4.Cu")
		(net "M_J_ECC<3>")
	)
	(segment
		(start 81.848706 -44.465494)
		(end 80.414368 -43.031156)
		(width 0.14224)
		(layer "In4.Cu")
		(net "M_J_ECC<3>")
	)
	(segment
		(start 82.211926 -53.460396)
		(end 83.145376 -52.526946)
		(width 0.0889)
		(layer "In4.Cu")
		(net "M_J_ECC<3>")
	)
	(segment
		(start 80.414368 -31.2039)
		(end 77.816964 -28.606496)
		(width 0.14224)
		(layer "In4.Cu")
		(net "M_J_ECC<3>")
	)
	(segment
		(start 82.290412 -56.791606)
		(end 82.284062 -56.780938)
		(width 0.0889)
		(layer "In4.Cu")
		(net "M_J_ECC<3>")
	)
	(segment
		(start 82.230976 -68.153534)
		(end 82.230976 -67.472052)
		(width 0.0889)
		(layer "In4.Cu")
		(net "M_J_ECC<3>")
	)
	(segment
		(start 83.984592 -50.111914)
		(end 83.983068 -50.11039)
		(width 0.14224)
		(layer "In4.Cu")
		(net "M_J_ECC<3>")
	)
	(segment
		(start 82.284062 -62.724538)
		(end 82.279236 -62.715902)
		(width 0.0889)
		(layer "In4.Cu")
		(net "M_J_ECC<3>")
	)
	(segment
		(start 77.653896 -18.559018)
		(end 77.793596 -18.419318)
		(width 0.14224)
		(layer "In4.Cu")
		(net "M_J_ECC<3>")
	)
	(segment
		(start 82.284062 -64.705738)
		(end 82.279236 -64.697102)
		(width 0.0889)
		(layer "In4.Cu")
		(net "M_J_ECC<3>")
	)
	(segment
		(start 83.983068 -50.11039)
		(end 83.983068 -46.4185)
		(width 0.14224)
		(layer "In4.Cu")
		(net "M_J_ECC<3>")
	)
	(segment
		(start 77.78369 -13.577062)
		(end 77.78369 -12.33805)
		(width 0.14224)
		(layer "In4.Cu")
		(net "M_J_ECC<3>")
	)
	(segment
		(start 83.743292 -50.468022)
		(end 83.743292 -50.353214)
		(width 0.0889)
		(layer "In4.Cu")
		(net "M_J_ECC<3>")
	)
	(segment
		(start 82.290412 -61.744606)
		(end 82.284062 -61.733938)
		(width 0.0889)
		(layer "In4.Cu")
		(net "M_J_ECC<3>")
	)
	(segment
		(start 77.780896 -21.949156)
		(end 77.653896 -21.822156)
		(width 0.14224)
		(layer "In4.Cu")
		(net "M_J_ECC<3>")
	)
	(segment
		(start 77.666596 -7.289546)
		(end 77.666596 -4.796028)
		(width 0.14224)
		(layer "In4.Cu")
		(net "M_J_ECC<3>")
	)
	(segment
		(start 77.666596 -16.890746)
		(end 77.666596 -13.694156)
		(width 0.14224)
		(layer "In4.Cu")
		(net "M_J_ECC<3>")
	)
	(segment
		(start 82.290412 -63.725806)
		(end 82.284062 -63.715138)
		(width 0.0889)
		(layer "In4.Cu")
		(net "M_J_ECC<3>")
	)
	(segment
		(start 82.284062 -59.752738)
		(end 82.279236 -59.744102)
		(width 0.0889)
		(layer "In4.Cu")
		(net "M_J_ECC<3>")
	)
	(segment
		(start 77.78369 -12.33805)
		(end 77.653896 -12.208256)
		(width 0.14224)
		(layer "In4.Cu")
		(net "M_J_ECC<3>")
	)
	(segment
		(start 82.290412 -64.716406)
		(end 82.284062 -64.705738)
		(width 0.0889)
		(layer "In4.Cu")
		(net "M_J_ECC<3>")
	)
	(segment
		(start 77.793596 -17.017746)
		(end 77.666596 -16.890746)
		(width 0.14224)
		(layer "In4.Cu")
		(net "M_J_ECC<3>")
	)
	(segment
		(start 82.290412 -65.707006)
		(end 82.284062 -65.696338)
		(width 0.0889)
		(layer "In4.Cu")
		(net "M_J_ECC<3>")
	)
	(segment
		(start 83.983068 -46.4185)
		(end 82.030062 -44.465494)
		(width 0.14224)
		(layer "In4.Cu")
		(net "M_J_ECC<3>")
	)
	(segment
		(start 82.36331 -56.085486)
		(end 82.36331 -55.771796)
		(width 0.0889)
		(layer "In4.Cu")
		(net "M_J_ECC<3>")
	)
	(segment
		(start 77.780896 -23.234396)
		(end 77.780896 -21.949156)
		(width 0.14224)
		(layer "In4.Cu")
		(net "M_J_ECC<3>")
	)
	(segment
		(start 77.806296 -8.831326)
		(end 77.806296 -7.429246)
		(width 0.14224)
		(layer "In4.Cu")
		(net "M_J_ECC<3>")
	)
	(segment
		(start 82.284062 -58.362088)
		(end 82.290412 -58.35142)
		(width 0.0889)
		(layer "In4.Cu")
		(net "M_J_ECC<3>")
	)
	(segment
		(start 82.36331 -55.771796)
		(end 82.211926 -55.620412)
		(width 0.0889)
		(layer "In4.Cu")
		(net "M_J_ECC<3>")
	)
	(segment
		(start 76.815696 -3.560572)
		(end 77.299312 -3.076956)
		(width 0.14224)
		(layer "In4.Cu")
		(net "M_J_ECC<3>")
	)
	(segment
		(start 82.284062 -66.686938)
		(end 82.279236 -66.678302)
		(width 0.0889)
		(layer "In4.Cu")
		(net "M_J_ECC<3>")
	)
	(segment
		(start 82.290412 -59.763406)
		(end 82.284062 -59.752738)
		(width 0.0889)
		(layer "In4.Cu")
		(net "M_J_ECC<3>")
	)
	(segment
		(start 82.284062 -65.696338)
		(end 82.279236 -65.687702)
		(width 0.0889)
		(layer "In4.Cu")
		(net "M_J_ECC<3>")
	)
	(segment
		(start 82.284062 -57.771538)
		(end 82.279236 -57.762902)
		(width 0.0889)
		(layer "In4.Cu")
		(net "M_J_ECC<3>")
	)
	(segment
		(start 83.145376 -51.065938)
		(end 83.743292 -50.468022)
		(width 0.0889)
		(layer "In4.Cu")
		(net "M_J_ECC<3>")
	)
	(segment
		(start 82.284062 -61.733938)
		(end 82.279236 -61.725302)
		(width 0.0889)
		(layer "In4.Cu")
		(net "M_J_ECC<3>")
	)
	(segment
		(start 77.653896 -8.983726)
		(end 77.806296 -8.831326)
		(width 0.14224)
		(layer "In4.Cu")
		(net "M_J_ECC<3>")
	)
	(segment
		(start 82.290412 -60.754006)
		(end 82.284062 -60.743338)
		(width 0.0889)
		(layer "In4.Cu")
		(net "M_J_ECC<3>")
	)
	(segment
		(start 76.815696 -3.945128)
		(end 76.815696 -3.560572)
		(width 0.14224)
		(layer "In4.Cu")
		(net "M_J_ECC<3>")
	)
	(segment
		(start 77.679296 -26.246328)
		(end 77.679296 -23.335996)
		(width 0.14224)
		(layer "In4.Cu")
		(net "M_J_ECC<3>")
	)
	(segment
		(start 82.211926 -55.620412)
		(end 82.211926 -53.460396)
		(width 0.0889)
		(layer "In4.Cu")
		(net "M_J_ECC<3>")
	)
	(segment
		(start 77.793596 -18.419318)
		(end 77.793596 -17.017746)
		(width 0.14224)
		(layer "In4.Cu")
		(net "M_J_ECC<3>")
	)
	(segment
		(start 77.653896 -21.822156)
		(end 77.653896 -18.559018)
		(width 0.14224)
		(layer "In4.Cu")
		(net "M_J_ECC<3>")
	)
	(segment
		(start 82.290412 -66.697606)
		(end 82.284062 -66.686938)
		(width 0.0889)
		(layer "In4.Cu")
		(net "M_J_ECC<3>")
	)
	(segment
		(start 82.284062 -60.743338)
		(end 82.279236 -60.734702)
		(width 0.0889)
		(layer "In4.Cu")
		(net "M_J_ECC<3>")
	)
	(segment
		(start 82.284062 -63.715138)
		(end 82.279236 -63.706502)
		(width 0.0889)
		(layer "In4.Cu")
		(net "M_J_ECC<3>")
	)
	(segment
		(start 82.030062 -44.465494)
		(end 81.848706 -44.465494)
		(width 0.14224)
		(layer "In4.Cu")
		(net "M_J_ECC<3>")
	)
	(segment
		(start 77.653896 -12.208256)
		(end 77.653896 -8.983726)
		(width 0.14224)
		(layer "In4.Cu")
		(net "M_J_ECC<3>")
	)
	(segment
		(start 77.806296 -7.429246)
		(end 77.666596 -7.289546)
		(width 0.14224)
		(layer "In4.Cu")
		(net "M_J_ECC<3>")
	)
	(segment
		(start 77.666596 -13.694156)
		(end 77.78369 -13.577062)
		(width 0.14224)
		(layer "In4.Cu")
		(net "M_J_ECC<3>")
	)
	(segment
		(start 83.145376 -52.526946)
		(end 83.145376 -51.065938)
		(width 0.0889)
		(layer "In4.Cu")
		(net "M_J_ECC<3>")
	)
	(segment
		(start 83.743292 -50.353214)
		(end 83.984592 -50.111914)
		(width 0.0889)
		(layer "In4.Cu")
		(net "M_J_ECC<3>")
	)
	(segment
		(start 82.284062 -56.780938)
		(end 82.279236 -56.772302)
		(width 0.0889)
		(layer "In4.Cu")
		(net "M_J_ECC<3>")
	)
	(segment
		(start 77.816964 -28.606496)
		(end 77.816964 -26.383996)
		(width 0.14224)
		(layer "In4.Cu")
		(net "M_J_ECC<3>")
	)
	(arc
		(start 82.230976 -67.472052)
		(mid 82.245135 -67.371389)
		(end 82.284062 -67.277488)
		(width 0.0889)
		(layer "In4.Cu")
		(net "M_J_ECC<3>")
	)
	(arc
		(start 82.279236 -66.678302)
		(mid 82.230481 -66.48195)
		(end 82.284062 -66.286888)
		(width 0.0889)
		(layer "In4.Cu")
		(net "M_J_ECC<3>")
	)
	(arc
		(start 82.284062 -61.333888)
		(mid 82.363284 -61.04477)
		(end 82.290412 -60.754006)
		(width 0.0889)
		(layer "In4.Cu")
		(net "M_J_ECC<3>")
	)
	(arc
		(start 82.290412 -58.35142)
		(mid 82.36321 -58.060657)
		(end 82.284062 -57.771538)
		(width 0.0889)
		(layer "In4.Cu")
		(net "M_J_ECC<3>")
	)
	(arc
		(start 82.284062 -60.343288)
		(mid 82.363284 -60.05417)
		(end 82.290412 -59.763406)
		(width 0.0889)
		(layer "In4.Cu")
		(net "M_J_ECC<3>")
	)
	(arc
		(start 82.279236 -62.715902)
		(mid 82.230481 -62.51955)
		(end 82.284062 -62.324488)
		(width 0.0889)
		(layer "In4.Cu")
		(net "M_J_ECC<3>")
	)
	(arc
		(start 82.284062 -59.352688)
		(mid 82.363193 -59.057286)
		(end 82.284062 -58.761884)
		(width 0.0889)
		(layer "In4.Cu")
		(net "M_J_ECC<3>")
	)
	(arc
		(start 82.284062 -65.296288)
		(mid 82.363284 -65.00717)
		(end 82.290412 -64.716406)
		(width 0.0889)
		(layer "In4.Cu")
		(net "M_J_ECC<3>")
	)
	(arc
		(start 82.284062 -56.380888)
		(mid 82.343129 -56.238402)
		(end 82.36331 -56.085486)
		(width 0.0889)
		(layer "In4.Cu")
		(net "M_J_ECC<3>")
	)
	(arc
		(start 82.284062 -63.315088)
		(mid 82.363284 -63.02597)
		(end 82.290412 -62.735206)
		(width 0.0889)
		(layer "In4.Cu")
		(net "M_J_ECC<3>")
	)
	(arc
		(start 82.279236 -57.762902)
		(mid 82.230481 -57.56655)
		(end 82.284062 -57.371488)
		(width 0.0889)
		(layer "In4.Cu")
		(net "M_J_ECC<3>")
	)
	(arc
		(start 82.284062 -62.324488)
		(mid 82.363284 -62.03537)
		(end 82.290412 -61.744606)
		(width 0.0889)
		(layer "In4.Cu")
		(net "M_J_ECC<3>")
	)
	(arc
		(start 82.279236 -59.744102)
		(mid 82.230481 -59.54775)
		(end 82.284062 -59.352688)
		(width 0.0889)
		(layer "In4.Cu")
		(net "M_J_ECC<3>")
	)
	(arc
		(start 82.284062 -67.277488)
		(mid 82.363284 -66.98837)
		(end 82.290412 -66.697606)
		(width 0.0889)
		(layer "In4.Cu")
		(net "M_J_ECC<3>")
	)
	(arc
		(start 82.279236 -60.734702)
		(mid 82.230481 -60.53835)
		(end 82.284062 -60.343288)
		(width 0.0889)
		(layer "In4.Cu")
		(net "M_J_ECC<3>")
	)
	(arc
		(start 82.279236 -64.697102)
		(mid 82.230481 -64.50075)
		(end 82.284062 -64.305688)
		(width 0.0889)
		(layer "In4.Cu")
		(net "M_J_ECC<3>")
	)
	(arc
		(start 82.279236 -65.687702)
		(mid 82.230481 -65.49135)
		(end 82.284062 -65.296288)
		(width 0.0889)
		(layer "In4.Cu")
		(net "M_J_ECC<3>")
	)
	(arc
		(start 82.284062 -57.371488)
		(mid 82.363284 -57.08237)
		(end 82.290412 -56.791606)
		(width 0.0889)
		(layer "In4.Cu")
		(net "M_J_ECC<3>")
	)
	(arc
		(start 82.279236 -61.725302)
		(mid 82.230481 -61.52895)
		(end 82.284062 -61.333888)
		(width 0.0889)
		(layer "In4.Cu")
		(net "M_J_ECC<3>")
	)
	(arc
		(start 82.284062 -58.761884)
		(mid 82.230563 -58.561986)
		(end 82.284062 -58.362088)
		(width 0.0889)
		(layer "In4.Cu")
		(net "M_J_ECC<3>")
	)
	(arc
		(start 82.279236 -56.772302)
		(mid 82.230481 -56.57595)
		(end 82.284062 -56.380888)
		(width 0.0889)
		(layer "In4.Cu")
		(net "M_J_ECC<3>")
	)
	(arc
		(start 82.279236 -63.706502)
		(mid 82.230481 -63.51015)
		(end 82.284062 -63.315088)
		(width 0.0889)
		(layer "In4.Cu")
		(net "M_J_ECC<3>")
	)
	(arc
		(start 82.284062 -64.305688)
		(mid 82.363284 -64.01657)
		(end 82.290412 -63.725806)
		(width 0.0889)
		(layer "In4.Cu")
		(net "M_J_ECC<3>")
	)
	(arc
		(start 82.284062 -66.286888)
		(mid 82.363284 -65.99777)
		(end 82.290412 -65.707006)
		(width 0.0889)
		(layer "In4.Cu")
		(net "M_J_ECC<3>")
	)
	(segment
		(start 77.807566 1.0922)
		(end 77.350366 1.5494)
		(width 0.14224)
		(layer "In11.Cu")
		(net "M_J_ECC<3>")
	)
	(segment
		(start 77.096366 1.5494)
		(end 76.766166 1.8796)
		(width 0.14224)
		(layer "In11.Cu")
		(net "M_J_ECC<3>")
	)
	(segment
		(start 77.299312 -3.076956)
		(end 77.652118 -2.72415)
		(width 0.14224)
		(layer "In11.Cu")
		(net "M_J_ECC<3>")
	)
	(segment
		(start 77.807566 0.7366)
		(end 77.807566 1.0922)
		(width 0.14224)
		(layer "In11.Cu")
		(net "M_J_ECC<3>")
	)
	(segment
		(start 76.766166 1.8796)
		(end 76.766166 2.198116)
		(width 0.14224)
		(layer "In11.Cu")
		(net "M_J_ECC<3>")
	)
	(segment
		(start 77.350366 1.5494)
		(end 77.096366 1.5494)
		(width 0.14224)
		(layer "In11.Cu")
		(net "M_J_ECC<3>")
	)
	(segment
		(start 77.652118 0.581152)
		(end 77.807566 0.7366)
		(width 0.14224)
		(layer "In11.Cu")
		(net "M_J_ECC<3>")
	)
	(segment
		(start 76.766166 2.198116)
		(end 76.449428 2.514854)
		(width 0.14224)
		(layer "In11.Cu")
		(net "M_J_ECC<3>")
	)
	(segment
		(start 77.652118 -2.72415)
		(end 77.652118 0.581152)
		(width 0.14224)
		(layer "In11.Cu")
		(net "M_J_ECC<3>")
	)
	(segment
		(start 77.299312 0.662432)
		(end 77.299312 0.9398)
		(width 0.1651)
		(layer "F.Cu")
		(net "M_J_ECC<2>")
	)
	(segment
		(start 77.299566 -0.821182)
		(end 77.299312 -0.820928)
		(width 0.1651)
		(layer "F.Cu")
		(net "M_J_ECC<2>")
	)
	(segment
		(start 82.343752 -67.972686)
		(end 81.772252 -67.972686)
		(width 0.1016)
		(layer "F.Cu")
		(net "M_J_ECC<2>")
	)
	(segment
		(start 77.299312 -0.820928)
		(end 77.299312 0.175768)
		(width 0.1651)
		(layer "F.Cu")
		(net "M_J_ECC<2>")
	)
	(segment
		(start 77.299312 0.175768)
		(end 77.430884 0.30734)
		(width 0.1651)
		(layer "F.Cu")
		(net "M_J_ECC<2>")
	)
	(segment
		(start 77.430884 0.53086)
		(end 77.299312 0.662432)
		(width 0.1651)
		(layer "F.Cu")
		(net "M_J_ECC<2>")
	)
	(segment
		(start 77.430884 0.30734)
		(end 77.430884 0.53086)
		(width 0.1651)
		(layer "F.Cu")
		(net "M_J_ECC<2>")
	)
	(via
		(at 81.772252 -67.972686)
		(size 0.508)
		(drill 0.254)
		(layers "F.Cu" "B.Cu")
		(net "M_J_ECC<2>")
	)
	(via
		(at 77.299312 0.9398)
		(size 0.508)
		(drill 0.254)
		(layers "F.Cu" "B.Cu")
		(net "M_J_ECC<2>")
	)
	(via
		(at 76.449428 -4.357878)
		(size 0.508)
		(drill 0.254)
		(layers "F.Cu" "B.Cu")
		(net "M_J_ECC<2>")
	)
	(segment
		(start 76.449428 -5.621782)
		(end 76.449428 -4.357878)
		(width 0.1651)
		(layer "B.Cu")
		(net "M_J_ECC<2>")
	)
	(segment
		(start 79.738728 -33.5661)
		(end 79.880968 -33.42386)
		(width 0.14224)
		(layer "In4.Cu")
		(net "M_J_ECC<2>")
	)
	(segment
		(start 79.409798 -42.944288)
		(end 79.409798 -38.91026)
		(width 0.14224)
		(layer "In4.Cu")
		(net "M_J_ECC<2>")
	)
	(segment
		(start 81.772252 -67.972686)
		(end 82.102198 -67.21094)
		(width 0.0889)
		(layer "In4.Cu")
		(net "M_J_ECC<2>")
	)
	(segment
		(start 79.880968 -36.95954)
		(end 79.738728 -36.8173)
		(width 0.14224)
		(layer "In4.Cu")
		(net "M_J_ECC<2>")
	)
	(segment
		(start 79.738728 -34.21634)
		(end 79.552038 -34.21634)
		(width 0.14224)
		(layer "In4.Cu")
		(net "M_J_ECC<2>")
	)
	(segment
		(start 79.409798 -35.37458)
		(end 79.409798 -35.00882)
		(width 0.14224)
		(layer "In4.Cu")
		(net "M_J_ECC<2>")
	)
	(segment
		(start 82.118962 -56.876188)
		(end 82.112612 -56.86552)
		(width 0.0889)
		(layer "In4.Cu")
		(net "M_J_ECC<2>")
	)
	(segment
		(start 82.123788 -61.837824)
		(end 82.118962 -61.829188)
		(width 0.0889)
		(layer "In4.Cu")
		(net "M_J_ECC<2>")
	)
	(segment
		(start 79.880968 -33.0581)
		(end 79.738728 -32.91586)
		(width 0.14224)
		(layer "In4.Cu")
		(net "M_J_ECC<2>")
	)
	(segment
		(start 79.552038 -33.5661)
		(end 79.738728 -33.5661)
		(width 0.14224)
		(layer "In4.Cu")
		(net "M_J_ECC<2>")
	)
	(segment
		(start 79.880968 -34.72434)
		(end 79.880968 -34.35858)
		(width 0.14224)
		(layer "In4.Cu")
		(net "M_J_ECC<2>")
	)
	(segment
		(start 82.123788 -58.866024)
		(end 82.118962 -58.857388)
		(width 0.0889)
		(layer "In4.Cu")
		(net "M_J_ECC<2>")
	)
	(segment
		(start 79.738728 -32.91586)
		(end 79.552038 -32.91586)
		(width 0.14224)
		(layer "In4.Cu")
		(net "M_J_ECC<2>")
	)
	(segment
		(start 79.738728 -38.11778)
		(end 79.552038 -38.11778)
		(width 0.14224)
		(layer "In4.Cu")
		(net "M_J_ECC<2>")
	)
	(segment
		(start 81.534762 -45.069252)
		(end 79.409798 -42.944288)
		(width 0.14224)
		(layer "In4.Cu")
		(net "M_J_ECC<2>")
	)
	(segment
		(start 79.552038 -37.46754)
		(end 79.738728 -37.46754)
		(width 0.14224)
		(layer "In4.Cu")
		(net "M_J_ECC<2>")
	)
	(segment
		(start 79.738728 -34.86658)
		(end 79.880968 -34.72434)
		(width 0.14224)
		(layer "In4.Cu")
		(net "M_J_ECC<2>")
	)
	(segment
		(start 82.021172 -53.371242)
		(end 82.954876 -52.437538)
		(width 0.0889)
		(layer "In4.Cu")
		(net "M_J_ECC<2>")
	)
	(segment
		(start 77.044296 -23.409656)
		(end 76.790296 -23.155656)
		(width 0.14224)
		(layer "In4.Cu")
		(net "M_J_ECC<2>")
	)
	(segment
		(start 82.118962 -63.810388)
		(end 82.112612 -63.79972)
		(width 0.0889)
		(layer "In4.Cu")
		(net "M_J_ECC<2>")
	)
	(segment
		(start 79.552038 -32.91586)
		(end 79.409798 -32.77362)
		(width 0.14224)
		(layer "In4.Cu")
		(net "M_J_ECC<2>")
	)
	(segment
		(start 82.123788 -62.828424)
		(end 82.118962 -62.819788)
		(width 0.0889)
		(layer "In4.Cu")
		(net "M_J_ECC<2>")
	)
	(segment
		(start 76.934568 -29.4894)
		(end 76.934568 -27.686)
		(width 0.14224)
		(layer "In4.Cu")
		(net "M_J_ECC<2>")
	)
	(segment
		(start 82.123788 -66.790824)
		(end 82.118962 -66.782188)
		(width 0.0889)
		(layer "In4.Cu")
		(net "M_J_ECC<2>")
	)
	(segment
		(start 82.123788 -60.847224)
		(end 82.118962 -60.838588)
		(width 0.0889)
		(layer "In4.Cu")
		(net "M_J_ECC<2>")
	)
	(segment
		(start 79.738728 -38.76802)
		(end 79.880968 -38.62578)
		(width 0.14224)
		(layer "In4.Cu")
		(net "M_J_ECC<2>")
	)
	(segment
		(start 77.031596 -13.783056)
		(end 76.790296 -13.541756)
		(width 0.14224)
		(layer "In4.Cu")
		(net "M_J_ECC<2>")
	)
	(segment
		(start 79.409798 -37.60978)
		(end 79.552038 -37.46754)
		(width 0.14224)
		(layer "In4.Cu")
		(net "M_J_ECC<2>")
	)
	(segment
		(start 76.790296 -13.541756)
		(end 76.790296 -12.347956)
		(width 0.14224)
		(layer "In4.Cu")
		(net "M_J_ECC<2>")
	)
	(segment
		(start 82.172556 -55.869078)
		(end 82.021172 -55.717694)
		(width 0.0889)
		(layer "In4.Cu")
		(net "M_J_ECC<2>")
	)
	(segment
		(start 79.552038 -38.11778)
		(end 79.409798 -37.97554)
		(width 0.14224)
		(layer "In4.Cu")
		(net "M_J_ECC<2>")
	)
	(segment
		(start 76.942696 -18.575274)
		(end 76.815696 -18.448274)
		(width 0.14224)
		(layer "In4.Cu")
		(net "M_J_ECC<2>")
	)
	(segment
		(start 79.552038 -36.8173)
		(end 79.409798 -36.67506)
		(width 0.14224)
		(layer "In4.Cu")
		(net "M_J_ECC<2>")
	)
	(segment
		(start 76.790296 -12.347956)
		(end 76.942696 -12.195556)
		(width 0.14224)
		(layer "In4.Cu")
		(net "M_J_ECC<2>")
	)
	(segment
		(start 79.738728 -36.8173)
		(end 79.552038 -36.8173)
		(width 0.14224)
		(layer "In4.Cu")
		(net "M_J_ECC<2>")
	)
	(segment
		(start 82.112612 -58.277506)
		(end 82.118962 -58.266838)
		(width 0.0889)
		(layer "In4.Cu")
		(net "M_J_ECC<2>")
	)
	(segment
		(start 79.880968 -38.62578)
		(end 79.880968 -38.26002)
		(width 0.14224)
		(layer "In4.Cu")
		(net "M_J_ECC<2>")
	)
	(segment
		(start 82.118962 -64.800988)
		(end 82.112612 -64.79032)
		(width 0.0889)
		(layer "In4.Cu")
		(net "M_J_ECC<2>")
	)
	(segment
		(start 77.031596 -16.751046)
		(end 77.031596 -13.783056)
		(width 0.14224)
		(layer "In4.Cu")
		(net "M_J_ECC<2>")
	)
	(segment
		(start 79.552038 -35.51682)
		(end 79.409798 -35.37458)
		(width 0.14224)
		(layer "In4.Cu")
		(net "M_J_ECC<2>")
	)
	(segment
		(start 79.880968 -34.35858)
		(end 79.738728 -34.21634)
		(width 0.14224)
		(layer "In4.Cu")
		(net "M_J_ECC<2>")
	)
	(segment
		(start 79.738728 -36.16706)
		(end 79.880968 -36.02482)
		(width 0.14224)
		(layer "In4.Cu")
		(net "M_J_ECC<2>")
	)
	(segment
		(start 76.815696 -8.847074)
		(end 76.815696 -7.365746)
		(width 0.14224)
		(layer "In4.Cu")
		(net "M_J_ECC<2>")
	)
	(segment
		(start 82.118962 -66.782188)
		(end 82.112612 -66.77152)
		(width 0.0889)
		(layer "In4.Cu")
		(net "M_J_ECC<2>")
	)
	(segment
		(start 82.172556 -56.085486)
		(end 82.172556 -55.869078)
		(width 0.0889)
		(layer "In4.Cu")
		(net "M_J_ECC<2>")
	)
	(segment
		(start 82.954876 -52.437538)
		(end 82.954876 -50.97653)
		(width 0.0889)
		(layer "In4.Cu")
		(net "M_J_ECC<2>")
	)
	(segment
		(start 82.123788 -59.856624)
		(end 82.118962 -59.847988)
		(width 0.0889)
		(layer "In4.Cu")
		(net "M_J_ECC<2>")
	)
	(segment
		(start 79.738728 -35.51682)
		(end 79.552038 -35.51682)
		(width 0.14224)
		(layer "In4.Cu")
		(net "M_J_ECC<2>")
	)
	(segment
		(start 77.018896 -4.927346)
		(end 76.449428 -4.357878)
		(width 0.14224)
		(layer "In4.Cu")
		(net "M_J_ECC<2>")
	)
	(segment
		(start 79.552038 -36.16706)
		(end 79.738728 -36.16706)
		(width 0.14224)
		(layer "In4.Cu")
		(net "M_J_ECC<2>")
	)
	(segment
		(start 76.815696 -16.966946)
		(end 77.031596 -16.751046)
		(width 0.14224)
		(layer "In4.Cu")
		(net "M_J_ECC<2>")
	)
	(segment
		(start 79.738728 -37.46754)
		(end 79.880968 -37.3253)
		(width 0.14224)
		(layer "In4.Cu")
		(net "M_J_ECC<2>")
	)
	(segment
		(start 79.552038 -34.21634)
		(end 79.409798 -34.0741)
		(width 0.14224)
		(layer "In4.Cu")
		(net "M_J_ECC<2>")
	)
	(segment
		(start 82.118962 -60.838588)
		(end 82.112612 -60.82792)
		(width 0.0889)
		(layer "In4.Cu")
		(net "M_J_ECC<2>")
	)
	(segment
		(start 83.349592 -46.699424)
		(end 81.71942 -45.069252)
		(width 0.14224)
		(layer "In4.Cu")
		(net "M_J_ECC<2>")
	)
	(segment
		(start 76.815696 -18.448274)
		(end 76.815696 -16.966946)
		(width 0.14224)
		(layer "In4.Cu")
		(net "M_J_ECC<2>")
	)
	(segment
		(start 82.123788 -63.819024)
		(end 82.118962 -63.810388)
		(width 0.0889)
		(layer "In4.Cu")
		(net "M_J_ECC<2>")
	)
	(segment
		(start 82.118962 -65.791588)
		(end 82.112612 -65.78092)
		(width 0.0889)
		(layer "In4.Cu")
		(net "M_J_ECC<2>")
	)
	(segment
		(start 76.942696 -8.974074)
		(end 76.815696 -8.847074)
		(width 0.14224)
		(layer "In4.Cu")
		(net "M_J_ECC<2>")
	)
	(segment
		(start 76.800964 -26.448004)
		(end 77.044296 -26.204672)
		(width 0.14224)
		(layer "In4.Cu")
		(net "M_J_ECC<2>")
	)
	(segment
		(start 82.118962 -61.829188)
		(end 82.112612 -61.81852)
		(width 0.0889)
		(layer "In4.Cu")
		(net "M_J_ECC<2>")
	)
	(segment
		(start 79.409798 -34.0741)
		(end 79.409798 -33.70834)
		(width 0.14224)
		(layer "In4.Cu")
		(net "M_J_ECC<2>")
	)
	(segment
		(start 79.409798 -38.91026)
		(end 79.552038 -38.76802)
		(width 0.14224)
		(layer "In4.Cu")
		(net "M_J_ECC<2>")
	)
	(segment
		(start 82.118962 -59.847988)
		(end 82.112612 -59.83732)
		(width 0.0889)
		(layer "In4.Cu")
		(net "M_J_ECC<2>")
	)
	(segment
		(start 83.552792 -50.378614)
		(end 83.552792 -50.315114)
		(width 0.0889)
		(layer "In4.Cu")
		(net "M_J_ECC<2>")
	)
	(segment
		(start 77.018896 -7.162546)
		(end 77.018896 -4.927346)
		(width 0.14224)
		(layer "In4.Cu")
		(net "M_J_ECC<2>")
	)
	(segment
		(start 82.123788 -64.809624)
		(end 82.118962 -64.800988)
		(width 0.0889)
		(layer "In4.Cu")
		(net "M_J_ECC<2>")
	)
	(segment
		(start 76.800964 -27.552396)
		(end 76.800964 -26.448004)
		(width 0.14224)
		(layer "In4.Cu")
		(net "M_J_ECC<2>")
	)
	(segment
		(start 79.409798 -31.96463)
		(end 76.934568 -29.4894)
		(width 0.14224)
		(layer "In4.Cu")
		(net "M_J_ECC<2>")
	)
	(segment
		(start 83.349592 -50.111914)
		(end 83.349592 -46.699424)
		(width 0.14224)
		(layer "In4.Cu")
		(net "M_J_ECC<2>")
	)
	(segment
		(start 79.409798 -36.67506)
		(end 79.409798 -36.3093)
		(width 0.14224)
		(layer "In4.Cu")
		(net "M_J_ECC<2>")
	)
	(segment
		(start 79.409798 -35.00882)
		(end 79.552038 -34.86658)
		(width 0.14224)
		(layer "In4.Cu")
		(net "M_J_ECC<2>")
	)
	(segment
		(start 82.102198 -67.21094)
		(end 82.118962 -67.182238)
		(width 0.0889)
		(layer "In4.Cu")
		(net "M_J_ECC<2>")
	)
	(segment
		(start 79.409798 -36.3093)
		(end 79.552038 -36.16706)
		(width 0.14224)
		(layer "In4.Cu")
		(net "M_J_ECC<2>")
	)
	(segment
		(start 79.880968 -38.26002)
		(end 79.738728 -38.11778)
		(width 0.14224)
		(layer "In4.Cu")
		(net "M_J_ECC<2>")
	)
	(segment
		(start 76.790296 -23.155656)
		(end 76.790296 -21.949156)
		(width 0.14224)
		(layer "In4.Cu")
		(net "M_J_ECC<2>")
	)
	(segment
		(start 82.118962 -62.819788)
		(end 82.112612 -62.80912)
		(width 0.0889)
		(layer "In4.Cu")
		(net "M_J_ECC<2>")
	)
	(segment
		(start 76.942696 -21.796756)
		(end 76.942696 -18.575274)
		(width 0.14224)
		(layer "In4.Cu")
		(net "M_J_ECC<2>")
	)
	(segment
		(start 82.123788 -65.800224)
		(end 82.118962 -65.791588)
		(width 0.0889)
		(layer "In4.Cu")
		(net "M_J_ECC<2>")
	)
	(segment
		(start 76.934568 -27.686)
		(end 76.800964 -27.552396)
		(width 0.14224)
		(layer "In4.Cu")
		(net "M_J_ECC<2>")
	)
	(segment
		(start 83.552792 -50.315114)
		(end 83.349592 -50.111914)
		(width 0.0889)
		(layer "In4.Cu")
		(net "M_J_ECC<2>")
	)
	(segment
		(start 77.044296 -26.204672)
		(end 77.044296 -23.409656)
		(width 0.14224)
		(layer "In4.Cu")
		(net "M_J_ECC<2>")
	)
	(segment
		(start 79.552038 -38.76802)
		(end 79.738728 -38.76802)
		(width 0.14224)
		(layer "In4.Cu")
		(net "M_J_ECC<2>")
	)
	(segment
		(start 76.942696 -12.195556)
		(end 76.942696 -8.974074)
		(width 0.14224)
		(layer "In4.Cu")
		(net "M_J_ECC<2>")
	)
	(segment
		(start 79.552038 -34.86658)
		(end 79.738728 -34.86658)
		(width 0.14224)
		(layer "In4.Cu")
		(net "M_J_ECC<2>")
	)
	(segment
		(start 82.123788 -56.884824)
		(end 82.118962 -56.876188)
		(width 0.0889)
		(layer "In4.Cu")
		(net "M_J_ECC<2>")
	)
	(segment
		(start 81.71942 -45.069252)
		(end 81.534762 -45.069252)
		(width 0.14224)
		(layer "In4.Cu")
		(net "M_J_ECC<2>")
	)
	(segment
		(start 82.954876 -50.97653)
		(end 83.552792 -50.378614)
		(width 0.0889)
		(layer "In4.Cu")
		(net "M_J_ECC<2>")
	)
	(segment
		(start 82.021172 -55.717694)
		(end 82.021172 -53.371242)
		(width 0.0889)
		(layer "In4.Cu")
		(net "M_J_ECC<2>")
	)
	(segment
		(start 79.409798 -37.97554)
		(end 79.409798 -37.60978)
		(width 0.14224)
		(layer "In4.Cu")
		(net "M_J_ECC<2>")
	)
	(segment
		(start 79.880968 -36.02482)
		(end 79.880968 -35.65906)
		(width 0.14224)
		(layer "In4.Cu")
		(net "M_J_ECC<2>")
	)
	(segment
		(start 79.880968 -35.65906)
		(end 79.738728 -35.51682)
		(width 0.14224)
		(layer "In4.Cu")
		(net "M_J_ECC<2>")
	)
	(segment
		(start 76.790296 -21.949156)
		(end 76.942696 -21.796756)
		(width 0.14224)
		(layer "In4.Cu")
		(net "M_J_ECC<2>")
	)
	(segment
		(start 79.409798 -32.77362)
		(end 79.409798 -31.96463)
		(width 0.14224)
		(layer "In4.Cu")
		(net "M_J_ECC<2>")
	)
	(segment
		(start 79.880968 -33.42386)
		(end 79.880968 -33.0581)
		(width 0.14224)
		(layer "In4.Cu")
		(net "M_J_ECC<2>")
	)
	(segment
		(start 76.815696 -7.365746)
		(end 77.018896 -7.162546)
		(width 0.14224)
		(layer "In4.Cu")
		(net "M_J_ECC<2>")
	)
	(segment
		(start 79.409798 -33.70834)
		(end 79.552038 -33.5661)
		(width 0.14224)
		(layer "In4.Cu")
		(net "M_J_ECC<2>")
	)
	(segment
		(start 79.880968 -37.3253)
		(end 79.880968 -36.95954)
		(width 0.14224)
		(layer "In4.Cu")
		(net "M_J_ECC<2>")
	)
	(arc
		(start 82.118962 -62.229238)
		(mid 82.172432 -62.034175)
		(end 82.123788 -61.837824)
		(width 0.0889)
		(layer "In4.Cu")
		(net "M_J_ECC<2>")
	)
	(arc
		(start 82.118962 -60.248038)
		(mid 82.172432 -60.052975)
		(end 82.123788 -59.856624)
		(width 0.0889)
		(layer "In4.Cu")
		(net "M_J_ECC<2>")
	)
	(arc
		(start 82.118962 -58.857388)
		(mid 82.03974 -58.56827)
		(end 82.112612 -58.277506)
		(width 0.0889)
		(layer "In4.Cu")
		(net "M_J_ECC<2>")
	)
	(arc
		(start 82.118962 -57.867042)
		(mid 82.039831 -57.57164)
		(end 82.118962 -57.276238)
		(width 0.0889)
		(layer "In4.Cu")
		(net "M_J_ECC<2>")
	)
	(arc
		(start 82.118962 -61.238638)
		(mid 82.172432 -61.043575)
		(end 82.123788 -60.847224)
		(width 0.0889)
		(layer "In4.Cu")
		(net "M_J_ECC<2>")
	)
	(arc
		(start 82.112612 -59.83732)
		(mid 82.039814 -59.546557)
		(end 82.118962 -59.257438)
		(width 0.0889)
		(layer "In4.Cu")
		(net "M_J_ECC<2>")
	)
	(arc
		(start 82.118962 -65.201038)
		(mid 82.172432 -65.005975)
		(end 82.123788 -64.809624)
		(width 0.0889)
		(layer "In4.Cu")
		(net "M_J_ECC<2>")
	)
	(arc
		(start 82.112612 -66.77152)
		(mid 82.039814 -66.480757)
		(end 82.118962 -66.191638)
		(width 0.0889)
		(layer "In4.Cu")
		(net "M_J_ECC<2>")
	)
	(arc
		(start 82.118962 -64.210438)
		(mid 82.172432 -64.015375)
		(end 82.123788 -63.819024)
		(width 0.0889)
		(layer "In4.Cu")
		(net "M_J_ECC<2>")
	)
	(arc
		(start 82.118962 -67.182238)
		(mid 82.172432 -66.987175)
		(end 82.123788 -66.790824)
		(width 0.0889)
		(layer "In4.Cu")
		(net "M_J_ECC<2>")
	)
	(arc
		(start 82.118962 -56.285638)
		(mid 82.158924 -56.189087)
		(end 82.172556 -56.085486)
		(width 0.0889)
		(layer "In4.Cu")
		(net "M_J_ECC<2>")
	)
	(arc
		(start 82.112612 -63.79972)
		(mid 82.039814 -63.508957)
		(end 82.118962 -63.219838)
		(width 0.0889)
		(layer "In4.Cu")
		(net "M_J_ECC<2>")
	)
	(arc
		(start 82.112612 -60.82792)
		(mid 82.039814 -60.537157)
		(end 82.118962 -60.248038)
		(width 0.0889)
		(layer "In4.Cu")
		(net "M_J_ECC<2>")
	)
	(arc
		(start 82.118962 -63.219838)
		(mid 82.172432 -63.024775)
		(end 82.123788 -62.828424)
		(width 0.0889)
		(layer "In4.Cu")
		(net "M_J_ECC<2>")
	)
	(arc
		(start 82.118962 -59.257438)
		(mid 82.172432 -59.062375)
		(end 82.123788 -58.866024)
		(width 0.0889)
		(layer "In4.Cu")
		(net "M_J_ECC<2>")
	)
	(arc
		(start 82.118962 -58.266838)
		(mid 82.172461 -58.06694)
		(end 82.118962 -57.867042)
		(width 0.0889)
		(layer "In4.Cu")
		(net "M_J_ECC<2>")
	)
	(arc
		(start 82.112612 -64.79032)
		(mid 82.039814 -64.499557)
		(end 82.118962 -64.210438)
		(width 0.0889)
		(layer "In4.Cu")
		(net "M_J_ECC<2>")
	)
	(arc
		(start 82.112612 -65.78092)
		(mid 82.039814 -65.490157)
		(end 82.118962 -65.201038)
		(width 0.0889)
		(layer "In4.Cu")
		(net "M_J_ECC<2>")
	)
	(arc
		(start 82.112612 -62.80912)
		(mid 82.039814 -62.518357)
		(end 82.118962 -62.229238)
		(width 0.0889)
		(layer "In4.Cu")
		(net "M_J_ECC<2>")
	)
	(arc
		(start 82.118962 -57.276238)
		(mid 82.172432 -57.081175)
		(end 82.123788 -56.884824)
		(width 0.0889)
		(layer "In4.Cu")
		(net "M_J_ECC<2>")
	)
	(arc
		(start 82.112612 -56.86552)
		(mid 82.039814 -56.574757)
		(end 82.118962 -56.285638)
		(width 0.0889)
		(layer "In4.Cu")
		(net "M_J_ECC<2>")
	)
	(arc
		(start 82.112612 -61.81852)
		(mid 82.039814 -61.527757)
		(end 82.118962 -61.238638)
		(width 0.0889)
		(layer "In4.Cu")
		(net "M_J_ECC<2>")
	)
	(arc
		(start 82.118962 -66.191638)
		(mid 82.172432 -65.996575)
		(end 82.123788 -65.800224)
		(width 0.0889)
		(layer "In4.Cu")
		(net "M_J_ECC<2>")
	)
	(segment
		(start 76.893166 0.533654)
		(end 77.299312 0.9398)
		(width 0.14224)
		(layer "In11.Cu")
		(net "M_J_ECC<2>")
	)
	(segment
		(start 76.449428 -4.357878)
		(end 76.132944 -4.041394)
		(width 0.14224)
		(layer "In11.Cu")
		(net "M_J_ECC<2>")
	)
	(segment
		(start 76.893166 -2.719324)
		(end 76.893166 0.533654)
		(width 0.14224)
		(layer "In11.Cu")
		(net "M_J_ECC<2>")
	)
	(segment
		(start 76.132944 -3.479546)
		(end 76.893166 -2.719324)
		(width 0.14224)
		(layer "In11.Cu")
		(net "M_J_ECC<2>")
	)
	(segment
		(start 76.132944 -4.041394)
		(end 76.132944 -3.479546)
		(width 0.14224)
		(layer "In11.Cu")
		(net "M_J_ECC<2>")
	)
	(segment
		(start 70.499478 3.778758)
		(end 70.499478 2.514854)
		(width 0.1651)
		(layer "F.Cu")
		(net "M_J_ECC<1>")
	)
	(segment
		(start 79.768192 -69.45884)
		(end 79.196692 -69.45884)
		(width 0.1016)
		(layer "F.Cu")
		(net "M_J_ECC<1>")
	)
	(via
		(at 79.196692 -69.45884)
		(size 0.508)
		(drill 0.254)
		(layers "F.Cu" "B.Cu")
		(net "M_J_ECC<1>")
	)
	(via
		(at 71.171562 -3.076956)
		(size 0.508)
		(drill 0.254)
		(layers "F.Cu" "B.Cu")
		(net "M_J_ECC<1>")
	)
	(via
		(at 70.499478 2.514854)
		(size 0.508)
		(drill 0.254)
		(layers "F.Cu" "B.Cu")
		(net "M_J_ECC<1>")
	)
	(segment
		(start 71.171562 -2.573782)
		(end 71.171562 -3.076956)
		(width 0.1651)
		(layer "B.Cu")
		(net "M_J_ECC<1>")
	)
	(segment
		(start 71.349362 -1.021842)
		(end 71.349362 -2.395982)
		(width 0.1651)
		(layer "B.Cu")
		(net "M_J_ECC<1>")
	)
	(segment
		(start 71.349362 -2.395982)
		(end 71.171562 -2.573782)
		(width 0.1651)
		(layer "B.Cu")
		(net "M_J_ECC<1>")
	)
	(segment
		(start 79.196692 -69.45884)
		(end 78.849982 -68.667884)
		(width 0.0889)
		(layer "In4.Cu")
		(net "M_J_ECC<1>")
	)
	(segment
		(start 78.849982 -65.696338)
		(end 78.845156 -65.687702)
		(width 0.0889)
		(layer "In4.Cu")
		(net "M_J_ECC<1>")
	)
	(segment
		(start 78.849982 -62.724538)
		(end 78.845156 -62.715902)
		(width 0.0889)
		(layer "In4.Cu")
		(net "M_J_ECC<1>")
	)
	(segment
		(start 78.930754 -51.413664)
		(end 78.930754 -50.71364)
		(width 0.0889)
		(layer "In4.Cu")
		(net "M_J_ECC<1>")
	)
	(segment
		(start 78.856332 -55.801006)
		(end 78.849982 -55.790338)
		(width 0.0889)
		(layer "In4.Cu")
		(net "M_J_ECC<1>")
	)
	(segment
		(start 78.849982 -53.409088)
		(end 78.88732 -53.344318)
		(width 0.0889)
		(layer "In4.Cu")
		(net "M_J_ECC<1>")
	)
	(segment
		(start 73.378568 -31.9024)
		(end 71.659496 -30.183328)
		(width 0.14224)
		(layer "In4.Cu")
		(net "M_J_ECC<1>")
	)
	(segment
		(start 78.849982 -57.771538)
		(end 78.845156 -57.762902)
		(width 0.0889)
		(layer "In4.Cu")
		(net "M_J_ECC<1>")
	)
	(segment
		(start 78.856332 -53.819806)
		(end 78.849982 -53.809138)
		(width 0.0889)
		(layer "In4.Cu")
		(net "M_J_ECC<1>")
	)
	(segment
		(start 78.849982 -60.743338)
		(end 78.845156 -60.734702)
		(width 0.0889)
		(layer "In4.Cu")
		(net "M_J_ECC<1>")
	)
	(segment
		(start 78.856332 -59.763406)
		(end 78.849982 -59.752738)
		(width 0.0889)
		(layer "In4.Cu")
		(net "M_J_ECC<1>")
	)
	(segment
		(start 78.856332 -60.754006)
		(end 78.849982 -60.743338)
		(width 0.0889)
		(layer "In4.Cu")
		(net "M_J_ECC<1>")
	)
	(segment
		(start 74.864468 -36.194746)
		(end 73.378568 -34.708846)
		(width 0.14224)
		(layer "In4.Cu")
		(net "M_J_ECC<1>")
	)
	(segment
		(start 78.980792 -50.124614)
		(end 78.980792 -48.055022)
		(width 0.14224)
		(layer "In4.Cu")
		(net "M_J_ECC<1>")
	)
	(segment
		(start 70.64502 -3.603498)
		(end 71.171562 -3.076956)
		(width 0.14224)
		(layer "In4.Cu")
		(net "M_J_ECC<1>")
	)
	(segment
		(start 78.757272 -50.540158)
		(end 78.757272 -50.348134)
		(width 0.0889)
		(layer "In4.Cu")
		(net "M_J_ECC<1>")
	)
	(segment
		(start 71.659496 -6.612382)
		(end 71.024496 -5.977382)
		(width 0.14224)
		(layer "In4.Cu")
		(net "M_J_ECC<1>")
	)
	(segment
		(start 78.849982 -53.809138)
		(end 78.845156 -53.800502)
		(width 0.0889)
		(layer "In4.Cu")
		(net "M_J_ECC<1>")
	)
	(segment
		(start 71.024496 -5.977382)
		(end 71.024496 -4.249928)
		(width 0.14224)
		(layer "In4.Cu")
		(net "M_J_ECC<1>")
	)
	(segment
		(start 78.856332 -61.744606)
		(end 78.849982 -61.733938)
		(width 0.0889)
		(layer "In4.Cu")
		(net "M_J_ECC<1>")
	)
	(segment
		(start 78.757272 -50.348134)
		(end 78.980792 -50.124614)
		(width 0.0889)
		(layer "In4.Cu")
		(net "M_J_ECC<1>")
	)
	(segment
		(start 78.849982 -64.705738)
		(end 78.845156 -64.697102)
		(width 0.0889)
		(layer "In4.Cu")
		(net "M_J_ECC<1>")
	)
	(segment
		(start 70.64502 -3.870452)
		(end 70.64502 -3.603498)
		(width 0.14224)
		(layer "In4.Cu")
		(net "M_J_ECC<1>")
	)
	(segment
		(start 78.930754 -50.71364)
		(end 78.757272 -50.540158)
		(width 0.0889)
		(layer "In4.Cu")
		(net "M_J_ECC<1>")
	)
	(segment
		(start 78.849982 -55.790338)
		(end 78.845156 -55.781702)
		(width 0.0889)
		(layer "In4.Cu")
		(net "M_J_ECC<1>")
	)
	(segment
		(start 78.856332 -56.791606)
		(end 78.849982 -56.780938)
		(width 0.0889)
		(layer "In4.Cu")
		(net "M_J_ECC<1>")
	)
	(segment
		(start 78.849982 -63.715138)
		(end 78.845156 -63.706502)
		(width 0.0889)
		(layer "In4.Cu")
		(net "M_J_ECC<1>")
	)
	(segment
		(start 78.849982 -54.799738)
		(end 78.845156 -54.791102)
		(width 0.0889)
		(layer "In4.Cu")
		(net "M_J_ECC<1>")
	)
	(segment
		(start 78.849982 -61.733938)
		(end 78.845156 -61.725302)
		(width 0.0889)
		(layer "In4.Cu")
		(net "M_J_ECC<1>")
	)
	(segment
		(start 78.88732 -51.457098)
		(end 78.930754 -51.413664)
		(width 0.0889)
		(layer "In4.Cu")
		(net "M_J_ECC<1>")
	)
	(segment
		(start 78.849982 -59.752738)
		(end 78.845156 -59.744102)
		(width 0.0889)
		(layer "In4.Cu")
		(net "M_J_ECC<1>")
	)
	(segment
		(start 78.856332 -62.735206)
		(end 78.849982 -62.724538)
		(width 0.0889)
		(layer "In4.Cu")
		(net "M_J_ECC<1>")
	)
	(segment
		(start 78.856332 -65.707006)
		(end 78.849982 -65.696338)
		(width 0.0889)
		(layer "In4.Cu")
		(net "M_J_ECC<1>")
	)
	(segment
		(start 78.980792 -48.055022)
		(end 74.864468 -43.938698)
		(width 0.14224)
		(layer "In4.Cu")
		(net "M_J_ECC<1>")
	)
	(segment
		(start 78.849982 -56.780938)
		(end 78.845156 -56.772302)
		(width 0.0889)
		(layer "In4.Cu")
		(net "M_J_ECC<1>")
	)
	(segment
		(start 78.88732 -53.344318)
		(end 78.88732 -51.457098)
		(width 0.0889)
		(layer "In4.Cu")
		(net "M_J_ECC<1>")
	)
	(segment
		(start 78.856332 -54.810406)
		(end 78.849982 -54.799738)
		(width 0.0889)
		(layer "In4.Cu")
		(net "M_J_ECC<1>")
	)
	(segment
		(start 74.864468 -43.938698)
		(end 74.864468 -36.194746)
		(width 0.14224)
		(layer "In4.Cu")
		(net "M_J_ECC<1>")
	)
	(segment
		(start 78.856332 -63.725806)
		(end 78.849982 -63.715138)
		(width 0.0889)
		(layer "In4.Cu")
		(net "M_J_ECC<1>")
	)
	(segment
		(start 71.024496 -4.249928)
		(end 70.64502 -3.870452)
		(width 0.14224)
		(layer "In4.Cu")
		(net "M_J_ECC<1>")
	)
	(segment
		(start 73.378568 -34.708846)
		(end 73.378568 -31.9024)
		(width 0.14224)
		(layer "In4.Cu")
		(net "M_J_ECC<1>")
	)
	(segment
		(start 78.856332 -64.716406)
		(end 78.849982 -64.705738)
		(width 0.0889)
		(layer "In4.Cu")
		(net "M_J_ECC<1>")
	)
	(segment
		(start 78.849982 -58.362088)
		(end 78.856332 -58.35142)
		(width 0.0889)
		(layer "In4.Cu")
		(net "M_J_ECC<1>")
	)
	(segment
		(start 71.659496 -30.183328)
		(end 71.659496 -6.612382)
		(width 0.14224)
		(layer "In4.Cu")
		(net "M_J_ECC<1>")
	)
	(arc
		(start 78.845156 -60.734702)
		(mid 78.796401 -60.53835)
		(end 78.849982 -60.343288)
		(width 0.0889)
		(layer "In4.Cu")
		(net "M_J_ECC<1>")
	)
	(arc
		(start 79.514192 -67.720972)
		(mid 79.582187 -67.369988)
		(end 79.342488 -67.104768)
		(width 0.0889)
		(layer "In4.Cu")
		(net "M_J_ECC<1>")
	)
	(arc
		(start 78.845156 -62.715902)
		(mid 78.796401 -62.51955)
		(end 78.849982 -62.324488)
		(width 0.0889)
		(layer "In4.Cu")
		(net "M_J_ECC<1>")
	)
	(arc
		(start 78.856332 -58.35142)
		(mid 78.92913 -58.060657)
		(end 78.849982 -57.771538)
		(width 0.0889)
		(layer "In4.Cu")
		(net "M_J_ECC<1>")
	)
	(arc
		(start 78.845156 -55.781702)
		(mid 78.796401 -55.58535)
		(end 78.849982 -55.390288)
		(width 0.0889)
		(layer "In4.Cu")
		(net "M_J_ECC<1>")
	)
	(arc
		(start 78.849982 -59.352688)
		(mid 78.929113 -59.057286)
		(end 78.849982 -58.761884)
		(width 0.0889)
		(layer "In4.Cu")
		(net "M_J_ECC<1>")
	)
	(arc
		(start 78.845156 -63.706502)
		(mid 78.796401 -63.51015)
		(end 78.849982 -63.315088)
		(width 0.0889)
		(layer "In4.Cu")
		(net "M_J_ECC<1>")
	)
	(arc
		(start 78.845156 -61.725302)
		(mid 78.796401 -61.52895)
		(end 78.849982 -61.333888)
		(width 0.0889)
		(layer "In4.Cu")
		(net "M_J_ECC<1>")
	)
	(arc
		(start 78.845156 -57.762902)
		(mid 78.796401 -57.56655)
		(end 78.849982 -57.371488)
		(width 0.0889)
		(layer "In4.Cu")
		(net "M_J_ECC<1>")
	)
	(arc
		(start 78.849982 -60.343288)
		(mid 78.929204 -60.05417)
		(end 78.856332 -59.763406)
		(width 0.0889)
		(layer "In4.Cu")
		(net "M_J_ECC<1>")
	)
	(arc
		(start 78.849982 -64.305688)
		(mid 78.929204 -64.01657)
		(end 78.856332 -63.725806)
		(width 0.0889)
		(layer "In4.Cu")
		(net "M_J_ECC<1>")
	)
	(arc
		(start 78.845156 -64.697102)
		(mid 78.796401 -64.50075)
		(end 78.849982 -64.305688)
		(width 0.0889)
		(layer "In4.Cu")
		(net "M_J_ECC<1>")
	)
	(arc
		(start 78.849982 -66.286888)
		(mid 78.929102 -65.99777)
		(end 78.856332 -65.707006)
		(width 0.0889)
		(layer "In4.Cu")
		(net "M_J_ECC<1>")
	)
	(arc
		(start 78.849982 -54.399688)
		(mid 78.929204 -54.11057)
		(end 78.856332 -53.819806)
		(width 0.0889)
		(layer "In4.Cu")
		(net "M_J_ECC<1>")
	)
	(arc
		(start 78.845156 -54.791102)
		(mid 78.796401 -54.59475)
		(end 78.849982 -54.399688)
		(width 0.0889)
		(layer "In4.Cu")
		(net "M_J_ECC<1>")
	)
	(arc
		(start 78.849982 -66.686684)
		(mid 78.796483 -66.486786)
		(end 78.849982 -66.286888)
		(width 0.0889)
		(layer "In4.Cu")
		(net "M_J_ECC<1>")
	)
	(arc
		(start 78.849982 -68.667884)
		(mid 78.817711 -68.339377)
		(end 79.043276 -68.098416)
		(width 0.0889)
		(layer "In4.Cu")
		(net "M_J_ECC<1>")
	)
	(arc
		(start 78.845156 -53.800502)
		(mid 78.796401 -53.60415)
		(end 78.849982 -53.409088)
		(width 0.0889)
		(layer "In4.Cu")
		(net "M_J_ECC<1>")
	)
	(arc
		(start 78.849982 -57.371488)
		(mid 78.929204 -57.08237)
		(end 78.856332 -56.791606)
		(width 0.0889)
		(layer "In4.Cu")
		(net "M_J_ECC<1>")
	)
	(arc
		(start 78.845156 -59.744102)
		(mid 78.796401 -59.54775)
		(end 78.849982 -59.352688)
		(width 0.0889)
		(layer "In4.Cu")
		(net "M_J_ECC<1>")
	)
	(arc
		(start 79.043276 -68.098416)
		(mid 79.305517 -67.943117)
		(end 79.514192 -67.720972)
		(width 0.0889)
		(layer "In4.Cu")
		(net "M_J_ECC<1>")
	)
	(arc
		(start 78.849982 -58.761884)
		(mid 78.796483 -58.561986)
		(end 78.849982 -58.362088)
		(width 0.0889)
		(layer "In4.Cu")
		(net "M_J_ECC<1>")
	)
	(arc
		(start 78.849982 -61.333888)
		(mid 78.929204 -61.04477)
		(end 78.856332 -60.754006)
		(width 0.0889)
		(layer "In4.Cu")
		(net "M_J_ECC<1>")
	)
	(arc
		(start 78.849982 -65.296288)
		(mid 78.929204 -65.00717)
		(end 78.856332 -64.716406)
		(width 0.0889)
		(layer "In4.Cu")
		(net "M_J_ECC<1>")
	)
	(arc
		(start 78.849982 -56.380888)
		(mid 78.929204 -56.09177)
		(end 78.856332 -55.801006)
		(width 0.0889)
		(layer "In4.Cu")
		(net "M_J_ECC<1>")
	)
	(arc
		(start 78.845156 -65.687702)
		(mid 78.796401 -65.49135)
		(end 78.849982 -65.296288)
		(width 0.0889)
		(layer "In4.Cu")
		(net "M_J_ECC<1>")
	)
	(arc
		(start 79.342488 -67.104768)
		(mid 79.059905 -66.938515)
		(end 78.849982 -66.686684)
		(width 0.0889)
		(layer "In4.Cu")
		(net "M_J_ECC<1>")
	)
	(arc
		(start 78.849982 -55.390288)
		(mid 78.929204 -55.10117)
		(end 78.856332 -54.810406)
		(width 0.0889)
		(layer "In4.Cu")
		(net "M_J_ECC<1>")
	)
	(arc
		(start 78.845156 -56.772302)
		(mid 78.796401 -56.57595)
		(end 78.849982 -56.380888)
		(width 0.0889)
		(layer "In4.Cu")
		(net "M_J_ECC<1>")
	)
	(arc
		(start 78.849982 -62.324488)
		(mid 78.929204 -62.03537)
		(end 78.856332 -61.744606)
		(width 0.0889)
		(layer "In4.Cu")
		(net "M_J_ECC<1>")
	)
	(arc
		(start 78.849982 -63.315088)
		(mid 78.929204 -63.02597)
		(end 78.856332 -62.735206)
		(width 0.0889)
		(layer "In4.Cu")
		(net "M_J_ECC<1>")
	)
	(segment
		(start 71.545704 -2.702814)
		(end 71.545704 0.630936)
		(width 0.14224)
		(layer "In11.Cu")
		(net "M_J_ECC<1>")
	)
	(segment
		(start 71.702168 0.7874)
		(end 71.702168 1.128776)
		(width 0.14224)
		(layer "In11.Cu")
		(net "M_J_ECC<1>")
	)
	(segment
		(start 71.171562 -3.076956)
		(end 71.545704 -2.702814)
		(width 0.14224)
		(layer "In11.Cu")
		(net "M_J_ECC<1>")
	)
	(segment
		(start 71.545704 0.630936)
		(end 71.702168 0.7874)
		(width 0.14224)
		(layer "In11.Cu")
		(net "M_J_ECC<1>")
	)
	(segment
		(start 71.332344 1.4986)
		(end 70.976744 1.4986)
		(width 0.14224)
		(layer "In11.Cu")
		(net "M_J_ECC<1>")
	)
	(segment
		(start 71.702168 1.128776)
		(end 71.332344 1.4986)
		(width 0.14224)
		(layer "In11.Cu")
		(net "M_J_ECC<1>")
	)
	(segment
		(start 70.499478 1.975866)
		(end 70.499478 2.514854)
		(width 0.14224)
		(layer "In11.Cu")
		(net "M_J_ECC<1>")
	)
	(segment
		(start 70.976744 1.4986)
		(end 70.499478 1.975866)
		(width 0.14224)
		(layer "In11.Cu")
		(net "M_J_ECC<1>")
	)
	(segment
		(start 79.768192 -67.47764)
		(end 79.196692 -67.47764)
		(width 0.0889)
		(layer "F.Cu")
		(net "M_J_ECC<0>")
	)
	(segment
		(start 71.349362 -0.821182)
		(end 71.171562 1.0414)
		(width 0.1651)
		(layer "F.Cu")
		(net "M_J_ECC<0>")
	)
	(via
		(at 70.499478 -4.357878)
		(size 0.508)
		(drill 0.254)
		(layers "F.Cu" "B.Cu")
		(net "M_J_ECC<0>")
	)
	(via
		(at 71.171562 1.0414)
		(size 0.508)
		(drill 0.254)
		(layers "F.Cu" "B.Cu")
		(net "M_J_ECC<0>")
	)
	(via
		(at 79.196692 -67.47764)
		(size 0.508)
		(drill 0.254)
		(layers "F.Cu" "B.Cu")
		(net "M_J_ECC<0>")
	)
	(segment
		(start 70.499478 -5.621782)
		(end 70.499478 -4.357878)
		(width 0.1651)
		(layer "B.Cu")
		(net "M_J_ECC<0>")
	)
	(segment
		(start 72.768968 -35.242246)
		(end 72.768968 -32.182054)
		(width 0.14224)
		(layer "In4.Cu")
		(net "M_J_ECC<0>")
	)
	(segment
		(start 73.962768 -40.54983)
		(end 73.962768 -40.11041)
		(width 0.14224)
		(layer "In4.Cu")
		(net "M_J_ECC<0>")
	)
	(segment
		(start 78.689708 -60.847224)
		(end 78.684882 -60.838588)
		(width 0.0889)
		(layer "In4.Cu")
		(net "M_J_ECC<0>")
	)
	(segment
		(start 78.69682 -53.29301)
		(end 78.69682 -51.378866)
		(width 0.0889)
		(layer "In4.Cu")
		(net "M_J_ECC<0>")
	)
	(segment
		(start 74.229468 -44.3992)
		(end 74.229468 -40.81653)
		(width 0.14224)
		(layer "In4.Cu")
		(net "M_J_ECC<0>")
	)
	(segment
		(start 78.684882 -56.876188)
		(end 78.678532 -56.86552)
		(width 0.0889)
		(layer "In4.Cu")
		(net "M_J_ECC<0>")
	)
	(segment
		(start 78.689708 -63.819024)
		(end 78.684882 -63.810388)
		(width 0.0889)
		(layer "In4.Cu")
		(net "M_J_ECC<0>")
	)
	(segment
		(start 78.689708 -64.809624)
		(end 78.684882 -64.800988)
		(width 0.0889)
		(layer "In4.Cu")
		(net "M_J_ECC<0>")
	)
	(segment
		(start 70.681596 -8.682482)
		(end 70.681596 -7.522718)
		(width 0.14224)
		(layer "In4.Cu")
		(net "M_J_ECC<0>")
	)
	(segment
		(start 71.016368 -30.429454)
		(end 71.016368 -28.357068)
		(width 0.14224)
		(layer "In4.Cu")
		(net "M_J_ECC<0>")
	)
	(segment
		(start 78.684882 -53.904388)
		(end 78.678532 -53.89372)
		(width 0.0889)
		(layer "In4.Cu")
		(net "M_J_ECC<0>")
	)
	(segment
		(start 70.679564 -26.968196)
		(end 71.024496 -26.623264)
		(width 0.14224)
		(layer "In4.Cu")
		(net "M_J_ECC<0>")
	)
	(segment
		(start 71.024496 -16.781018)
		(end 71.024496 -13.851128)
		(width 0.14224)
		(layer "In4.Cu")
		(net "M_J_ECC<0>")
	)
	(segment
		(start 78.689708 -54.903624)
		(end 78.684882 -54.894988)
		(width 0.0889)
		(layer "In4.Cu")
		(net "M_J_ECC<0>")
	)
	(segment
		(start 74.229468 -39.84371)
		(end 74.229468 -39.49065)
		(width 0.14224)
		(layer "In4.Cu")
		(net "M_J_ECC<0>")
	)
	(segment
		(start 70.389496 -6.180582)
		(end 70.389496 -4.46786)
		(width 0.14224)
		(layer "In4.Cu")
		(net "M_J_ECC<0>")
	)
	(segment
		(start 74.074528 -37.34689)
		(end 74.229468 -37.19195)
		(width 0.14224)
		(layer "In4.Cu")
		(net "M_J_ECC<0>")
	)
	(segment
		(start 70.681596 -7.522718)
		(end 70.973696 -7.230618)
		(width 0.14224)
		(layer "In4.Cu")
		(net "M_J_ECC<0>")
	)
	(segment
		(start 73.467468 -37.50183)
		(end 73.622408 -37.34689)
		(width 0.14224)
		(layer "In4.Cu")
		(net "M_J_ECC<0>")
	)
	(segment
		(start 74.074528 -39.33571)
		(end 73.622408 -39.33571)
		(width 0.14224)
		(layer "In4.Cu")
		(net "M_J_ECC<0>")
	)
	(segment
		(start 70.973696 -7.230618)
		(end 70.973696 -6.764782)
		(width 0.14224)
		(layer "In4.Cu")
		(net "M_J_ECC<0>")
	)
	(segment
		(start 78.684882 -60.838588)
		(end 78.678532 -60.82792)
		(width 0.0889)
		(layer "In4.Cu")
		(net "M_J_ECC<0>")
	)
	(segment
		(start 78.689708 -61.837824)
		(end 78.684882 -61.829188)
		(width 0.0889)
		(layer "In4.Cu")
		(net "M_J_ECC<0>")
	)
	(segment
		(start 70.681596 -18.309082)
		(end 70.681596 -17.123918)
		(width 0.14224)
		(layer "In4.Cu")
		(net "M_J_ECC<0>")
	)
	(segment
		(start 71.024496 -21.682456)
		(end 71.024496 -18.651982)
		(width 0.14224)
		(layer "In4.Cu")
		(net "M_J_ECC<0>")
	)
	(segment
		(start 78.689708 -62.828424)
		(end 78.684882 -62.819788)
		(width 0.0889)
		(layer "In4.Cu")
		(net "M_J_ECC<0>")
	)
	(segment
		(start 73.467468 -38.82771)
		(end 73.622408 -38.67277)
		(width 0.14224)
		(layer "In4.Cu")
		(net "M_J_ECC<0>")
	)
	(segment
		(start 73.467468 -37.85489)
		(end 73.467468 -37.50183)
		(width 0.14224)
		(layer "In4.Cu")
		(net "M_J_ECC<0>")
	)
	(segment
		(start 78.688946 -66.7893)
		(end 78.684882 -66.782188)
		(width 0.0889)
		(layer "In4.Cu")
		(net "M_J_ECC<0>")
	)
	(segment
		(start 74.229468 -38.51783)
		(end 74.229468 -38.16477)
		(width 0.14224)
		(layer "In4.Cu")
		(net "M_J_ECC<0>")
	)
	(segment
		(start 70.389496 -4.46786)
		(end 70.499478 -4.357878)
		(width 0.14224)
		(layer "In4.Cu")
		(net "M_J_ECC<0>")
	)
	(segment
		(start 74.229468 -40.81653)
		(end 73.962768 -40.54983)
		(width 0.14224)
		(layer "In4.Cu")
		(net "M_J_ECC<0>")
	)
	(segment
		(start 78.69682 -51.378866)
		(end 78.740254 -51.335432)
		(width 0.0889)
		(layer "In4.Cu")
		(net "M_J_ECC<0>")
	)
	(segment
		(start 70.681596 -12.424156)
		(end 71.024496 -12.081256)
		(width 0.14224)
		(layer "In4.Cu")
		(net "M_J_ECC<0>")
	)
	(segment
		(start 74.229468 -37.19195)
		(end 74.229468 -36.702746)
		(width 0.14224)
		(layer "In4.Cu")
		(net "M_J_ECC<0>")
	)
	(segment
		(start 78.345792 -48.515524)
		(end 74.229468 -44.3992)
		(width 0.14224)
		(layer "In4.Cu")
		(net "M_J_ECC<0>")
	)
	(segment
		(start 70.681596 -23.109428)
		(end 70.681596 -22.025356)
		(width 0.14224)
		(layer "In4.Cu")
		(net "M_J_ECC<0>")
	)
	(segment
		(start 73.962768 -40.11041)
		(end 74.229468 -39.84371)
		(width 0.14224)
		(layer "In4.Cu")
		(net "M_J_ECC<0>")
	)
	(segment
		(start 74.074528 -38.67277)
		(end 74.229468 -38.51783)
		(width 0.14224)
		(layer "In4.Cu")
		(net "M_J_ECC<0>")
	)
	(segment
		(start 71.024496 -9.025382)
		(end 70.681596 -8.682482)
		(width 0.14224)
		(layer "In4.Cu")
		(net "M_J_ECC<0>")
	)
	(segment
		(start 78.689708 -65.800224)
		(end 78.684882 -65.791588)
		(width 0.0889)
		(layer "In4.Cu")
		(net "M_J_ECC<0>")
	)
	(segment
		(start 74.229468 -38.16477)
		(end 74.074528 -38.00983)
		(width 0.14224)
		(layer "In4.Cu")
		(net "M_J_ECC<0>")
	)
	(segment
		(start 71.024496 -26.623264)
		(end 71.024496 -23.452328)
		(width 0.14224)
		(layer "In4.Cu")
		(net "M_J_ECC<0>")
	)
	(segment
		(start 72.768968 -32.182054)
		(end 71.016368 -30.429454)
		(width 0.14224)
		(layer "In4.Cu")
		(net "M_J_ECC<0>")
	)
	(segment
		(start 78.345792 -50.124614)
		(end 78.345792 -48.515524)
		(width 0.14224)
		(layer "In4.Cu")
		(net "M_J_ECC<0>")
	)
	(segment
		(start 78.684882 -62.819788)
		(end 78.678532 -62.80912)
		(width 0.0889)
		(layer "In4.Cu")
		(net "M_J_ECC<0>")
	)
	(segment
		(start 78.684882 -53.313838)
		(end 78.69682 -53.29301)
		(width 0.0889)
		(layer "In4.Cu")
		(net "M_J_ECC<0>")
	)
	(segment
		(start 71.024496 -13.851128)
		(end 70.681596 -13.508228)
		(width 0.14224)
		(layer "In4.Cu")
		(net "M_J_ECC<0>")
	)
	(segment
		(start 78.740254 -51.335432)
		(end 78.740254 -50.798476)
		(width 0.0889)
		(layer "In4.Cu")
		(net "M_J_ECC<0>")
	)
	(segment
		(start 78.684882 -64.800988)
		(end 78.678532 -64.79032)
		(width 0.0889)
		(layer "In4.Cu")
		(net "M_J_ECC<0>")
	)
	(segment
		(start 78.678532 -58.277506)
		(end 78.684882 -58.266838)
		(width 0.0889)
		(layer "In4.Cu")
		(net "M_J_ECC<0>")
	)
	(segment
		(start 78.689708 -58.866024)
		(end 78.684882 -58.857388)
		(width 0.0889)
		(layer "In4.Cu")
		(net "M_J_ECC<0>")
	)
	(segment
		(start 74.229468 -39.49065)
		(end 74.074528 -39.33571)
		(width 0.14224)
		(layer "In4.Cu")
		(net "M_J_ECC<0>")
	)
	(segment
		(start 78.684882 -63.810388)
		(end 78.678532 -63.79972)
		(width 0.0889)
		(layer "In4.Cu")
		(net "M_J_ECC<0>")
	)
	(segment
		(start 70.973696 -6.764782)
		(end 70.389496 -6.180582)
		(width 0.14224)
		(layer "In4.Cu")
		(net "M_J_ECC<0>")
	)
	(segment
		(start 78.684882 -61.829188)
		(end 78.678532 -61.81852)
		(width 0.0889)
		(layer "In4.Cu")
		(net "M_J_ECC<0>")
	)
	(segment
		(start 73.622408 -38.00983)
		(end 73.467468 -37.85489)
		(width 0.14224)
		(layer "In4.Cu")
		(net "M_J_ECC<0>")
	)
	(segment
		(start 71.024496 -18.651982)
		(end 70.681596 -18.309082)
		(width 0.14224)
		(layer "In4.Cu")
		(net "M_J_ECC<0>")
	)
	(segment
		(start 73.622408 -37.34689)
		(end 74.074528 -37.34689)
		(width 0.14224)
		(layer "In4.Cu")
		(net "M_J_ECC<0>")
	)
	(segment
		(start 70.679564 -28.020264)
		(end 70.679564 -26.968196)
		(width 0.14224)
		(layer "In4.Cu")
		(net "M_J_ECC<0>")
	)
	(segment
		(start 71.024496 -23.452328)
		(end 70.681596 -23.109428)
		(width 0.14224)
		(layer "In4.Cu")
		(net "M_J_ECC<0>")
	)
	(segment
		(start 70.681596 -13.508228)
		(end 70.681596 -12.424156)
		(width 0.14224)
		(layer "In4.Cu")
		(net "M_J_ECC<0>")
	)
	(segment
		(start 73.467468 -39.18077)
		(end 73.467468 -38.82771)
		(width 0.14224)
		(layer "In4.Cu")
		(net "M_J_ECC<0>")
	)
	(segment
		(start 78.684882 -65.791588)
		(end 78.678532 -65.78092)
		(width 0.0889)
		(layer "In4.Cu")
		(net "M_J_ECC<0>")
	)
	(segment
		(start 78.689708 -56.884824)
		(end 78.684882 -56.876188)
		(width 0.0889)
		(layer "In4.Cu")
		(net "M_J_ECC<0>")
	)
	(segment
		(start 74.074528 -38.00983)
		(end 73.622408 -38.00983)
		(width 0.14224)
		(layer "In4.Cu")
		(net "M_J_ECC<0>")
	)
	(segment
		(start 78.566772 -50.345594)
		(end 78.345792 -50.124614)
		(width 0.0889)
		(layer "In4.Cu")
		(net "M_J_ECC<0>")
	)
	(segment
		(start 74.229468 -36.702746)
		(end 72.768968 -35.242246)
		(width 0.14224)
		(layer "In4.Cu")
		(net "M_J_ECC<0>")
	)
	(segment
		(start 78.740254 -50.798476)
		(end 78.566772 -50.624994)
		(width 0.0889)
		(layer "In4.Cu")
		(net "M_J_ECC<0>")
	)
	(segment
		(start 78.689708 -53.913024)
		(end 78.684882 -53.904388)
		(width 0.0889)
		(layer "In4.Cu")
		(net "M_J_ECC<0>")
	)
	(segment
		(start 70.681596 -22.025356)
		(end 71.024496 -21.682456)
		(width 0.14224)
		(layer "In4.Cu")
		(net "M_J_ECC<0>")
	)
	(segment
		(start 78.684882 -59.847988)
		(end 78.678532 -59.83732)
		(width 0.0889)
		(layer "In4.Cu")
		(net "M_J_ECC<0>")
	)
	(segment
		(start 78.566772 -50.624994)
		(end 78.566772 -50.345594)
		(width 0.0889)
		(layer "In4.Cu")
		(net "M_J_ECC<0>")
	)
	(segment
		(start 71.024496 -12.081256)
		(end 71.024496 -9.025382)
		(width 0.14224)
		(layer "In4.Cu")
		(net "M_J_ECC<0>")
	)
	(segment
		(start 78.684882 -54.894988)
		(end 78.678532 -54.88432)
		(width 0.0889)
		(layer "In4.Cu")
		(net "M_J_ECC<0>")
	)
	(segment
		(start 78.689708 -55.894224)
		(end 78.684882 -55.885588)
		(width 0.0889)
		(layer "In4.Cu")
		(net "M_J_ECC<0>")
	)
	(segment
		(start 71.016368 -28.357068)
		(end 70.679564 -28.020264)
		(width 0.14224)
		(layer "In4.Cu")
		(net "M_J_ECC<0>")
	)
	(segment
		(start 70.681596 -17.123918)
		(end 71.024496 -16.781018)
		(width 0.14224)
		(layer "In4.Cu")
		(net "M_J_ECC<0>")
	)
	(segment
		(start 78.684882 -55.885588)
		(end 78.678532 -55.87492)
		(width 0.0889)
		(layer "In4.Cu")
		(net "M_J_ECC<0>")
	)
	(segment
		(start 78.689708 -59.856624)
		(end 78.684882 -59.847988)
		(width 0.0889)
		(layer "In4.Cu")
		(net "M_J_ECC<0>")
	)
	(segment
		(start 73.622408 -38.67277)
		(end 74.074528 -38.67277)
		(width 0.14224)
		(layer "In4.Cu")
		(net "M_J_ECC<0>")
	)
	(segment
		(start 73.622408 -39.33571)
		(end 73.467468 -39.18077)
		(width 0.14224)
		(layer "In4.Cu")
		(net "M_J_ECC<0>")
	)
	(arc
		(start 78.96606 -67.20459)
		(mid 78.820785 -67.001428)
		(end 78.688946 -66.7893)
		(width 0.0889)
		(layer "In4.Cu")
		(net "M_J_ECC<0>")
	)
	(arc
		(start 78.678532 -63.79972)
		(mid 78.605734 -63.508957)
		(end 78.684882 -63.219838)
		(width 0.0889)
		(layer "In4.Cu")
		(net "M_J_ECC<0>")
	)
	(arc
		(start 78.684882 -66.782188)
		(mid 78.605751 -66.486786)
		(end 78.684882 -66.191384)
		(width 0.0889)
		(layer "In4.Cu")
		(net "M_J_ECC<0>")
	)
	(arc
		(start 78.684882 -58.857388)
		(mid 78.60566 -58.56827)
		(end 78.678532 -58.277506)
		(width 0.0889)
		(layer "In4.Cu")
		(net "M_J_ECC<0>")
	)
	(arc
		(start 78.684882 -64.210438)
		(mid 78.738352 -64.015375)
		(end 78.689708 -63.819024)
		(width 0.0889)
		(layer "In4.Cu")
		(net "M_J_ECC<0>")
	)
	(arc
		(start 78.678532 -53.89372)
		(mid 78.605734 -53.602957)
		(end 78.684882 -53.313838)
		(width 0.0889)
		(layer "In4.Cu")
		(net "M_J_ECC<0>")
	)
	(arc
		(start 78.684882 -55.295038)
		(mid 78.738352 -55.099975)
		(end 78.689708 -54.903624)
		(width 0.0889)
		(layer "In4.Cu")
		(net "M_J_ECC<0>")
	)
	(arc
		(start 78.678532 -64.79032)
		(mid 78.605734 -64.499557)
		(end 78.684882 -64.210438)
		(width 0.0889)
		(layer "In4.Cu")
		(net "M_J_ECC<0>")
	)
	(arc
		(start 78.684882 -62.229238)
		(mid 78.738352 -62.034175)
		(end 78.689708 -61.837824)
		(width 0.0889)
		(layer "In4.Cu")
		(net "M_J_ECC<0>")
	)
	(arc
		(start 78.684882 -63.219838)
		(mid 78.738352 -63.024775)
		(end 78.689708 -62.828424)
		(width 0.0889)
		(layer "In4.Cu")
		(net "M_J_ECC<0>")
	)
	(arc
		(start 78.678532 -54.88432)
		(mid 78.605734 -54.593557)
		(end 78.684882 -54.304438)
		(width 0.0889)
		(layer "In4.Cu")
		(net "M_J_ECC<0>")
	)
	(arc
		(start 78.684882 -58.266838)
		(mid 78.738381 -58.06694)
		(end 78.684882 -57.867042)
		(width 0.0889)
		(layer "In4.Cu")
		(net "M_J_ECC<0>")
	)
	(arc
		(start 78.678532 -62.80912)
		(mid 78.605734 -62.518357)
		(end 78.684882 -62.229238)
		(width 0.0889)
		(layer "In4.Cu")
		(net "M_J_ECC<0>")
	)
	(arc
		(start 78.684882 -56.285638)
		(mid 78.738352 -56.090575)
		(end 78.689708 -55.894224)
		(width 0.0889)
		(layer "In4.Cu")
		(net "M_J_ECC<0>")
	)
	(arc
		(start 79.196692 -67.47764)
		(mid 79.078082 -67.343898)
		(end 78.96606 -67.20459)
		(width 0.0889)
		(layer "In4.Cu")
		(net "M_J_ECC<0>")
	)
	(arc
		(start 78.684882 -57.867042)
		(mid 78.605751 -57.57164)
		(end 78.684882 -57.276238)
		(width 0.0889)
		(layer "In4.Cu")
		(net "M_J_ECC<0>")
	)
	(arc
		(start 78.678532 -60.82792)
		(mid 78.605734 -60.537157)
		(end 78.684882 -60.248038)
		(width 0.0889)
		(layer "In4.Cu")
		(net "M_J_ECC<0>")
	)
	(arc
		(start 78.684882 -54.304438)
		(mid 78.738352 -54.109375)
		(end 78.689708 -53.913024)
		(width 0.0889)
		(layer "In4.Cu")
		(net "M_J_ECC<0>")
	)
	(arc
		(start 78.684882 -59.257438)
		(mid 78.738352 -59.062375)
		(end 78.689708 -58.866024)
		(width 0.0889)
		(layer "In4.Cu")
		(net "M_J_ECC<0>")
	)
	(arc
		(start 78.684882 -60.248038)
		(mid 78.738352 -60.052975)
		(end 78.689708 -59.856624)
		(width 0.0889)
		(layer "In4.Cu")
		(net "M_J_ECC<0>")
	)
	(arc
		(start 78.678532 -61.81852)
		(mid 78.605734 -61.527757)
		(end 78.684882 -61.238638)
		(width 0.0889)
		(layer "In4.Cu")
		(net "M_J_ECC<0>")
	)
	(arc
		(start 78.684882 -61.238638)
		(mid 78.738352 -61.043575)
		(end 78.689708 -60.847224)
		(width 0.0889)
		(layer "In4.Cu")
		(net "M_J_ECC<0>")
	)
	(arc
		(start 78.678532 -65.78092)
		(mid 78.605734 -65.490157)
		(end 78.684882 -65.201038)
		(width 0.0889)
		(layer "In4.Cu")
		(net "M_J_ECC<0>")
	)
	(arc
		(start 78.684882 -66.191384)
		(mid 78.738418 -65.996433)
		(end 78.689708 -65.800224)
		(width 0.0889)
		(layer "In4.Cu")
		(net "M_J_ECC<0>")
	)
	(arc
		(start 78.684882 -57.276238)
		(mid 78.738352 -57.081175)
		(end 78.689708 -56.884824)
		(width 0.0889)
		(layer "In4.Cu")
		(net "M_J_ECC<0>")
	)
	(arc
		(start 78.678532 -55.87492)
		(mid 78.605734 -55.584157)
		(end 78.684882 -55.295038)
		(width 0.0889)
		(layer "In4.Cu")
		(net "M_J_ECC<0>")
	)
	(arc
		(start 78.678532 -59.83732)
		(mid 78.605734 -59.546557)
		(end 78.684882 -59.257438)
		(width 0.0889)
		(layer "In4.Cu")
		(net "M_J_ECC<0>")
	)
	(arc
		(start 78.678532 -56.86552)
		(mid 78.605734 -56.574757)
		(end 78.684882 -56.285638)
		(width 0.0889)
		(layer "In4.Cu")
		(net "M_J_ECC<0>")
	)
	(arc
		(start 78.684882 -65.201038)
		(mid 78.738352 -65.005975)
		(end 78.689708 -64.809624)
		(width 0.0889)
		(layer "In4.Cu")
		(net "M_J_ECC<0>")
	)
	(segment
		(start 70.214744 -4.073144)
		(end 70.214744 -3.3274)
		(width 0.14224)
		(layer "In11.Cu")
		(net "M_J_ECC<0>")
	)
	(segment
		(start 70.214744 -3.3274)
		(end 70.951344 -2.5908)
		(width 0.14224)
		(layer "In11.Cu")
		(net "M_J_ECC<0>")
	)
	(segment
		(start 70.951344 -2.5908)
		(end 70.951344 0.821182)
		(width 0.14224)
		(layer "In11.Cu")
		(net "M_J_ECC<0>")
	)
	(segment
		(start 70.499478 -4.357878)
		(end 70.214744 -4.073144)
		(width 0.14224)
		(layer "In11.Cu")
		(net "M_J_ECC<0>")
	)
	(segment
		(start 70.951344 0.821182)
		(end 71.171562 1.0414)
		(width 0.14224)
		(layer "In11.Cu")
		(net "M_J_ECC<0>")
	)
	(segment
		(start 34.278824 2.542032)
		(end 34.278824 1.723898)
		(width 0.1651)
		(layer "F.Cu")
		(net "M_J_DQS_DP<9>")
	)
	(segment
		(start 34.360358 1.499616)
		(end 34.74212 1.117854)
		(width 0.1651)
		(layer "F.Cu")
		(net "M_J_DQS_DP<9>")
	)
	(segment
		(start 34.799524 3.778758)
		(end 34.799524 3.162046)
		(width 0.1651)
		(layer "F.Cu")
		(net "M_J_DQS_DP<9>")
	)
	(segment
		(start 34.799524 3.162046)
		(end 34.363406 2.725928)
		(width 0.1651)
		(layer "F.Cu")
		(net "M_J_DQS_DP<9>")
	)
	(segment
		(start 34.278824 1.723898)
		(end 34.360358 1.499616)
		(width 0.1651)
		(layer "F.Cu")
		(net "M_J_DQS_DP<9>")
	)
	(segment
		(start 76.334366 -65.49644)
		(end 75.762866 -65.49644)
		(width 0.0889)
		(layer "F.Cu")
		(net "M_J_DQS_DP<9>")
	)
	(segment
		(start 34.363406 2.725928)
		(end 34.278824 2.542032)
		(width 0.1651)
		(layer "F.Cu")
		(net "M_J_DQS_DP<9>")
	)
	(via
		(at 34.74212 -2.9718)
		(size 0.508)
		(drill 0.254)
		(layers "F.Cu" "B.Cu")
		(net "M_J_DQS_DP<9>")
	)
	(via
		(at 34.74212 1.117854)
		(size 0.508)
		(drill 0.254)
		(layers "F.Cu" "B.Cu")
		(net "M_J_DQS_DP<9>")
	)
	(via
		(at 75.762866 -65.49644)
		(size 0.508)
		(drill 0.254)
		(layers "F.Cu" "B.Cu")
		(net "M_J_DQS_DP<9>")
	)
	(segment
		(start 34.266124 -3.519932)
		(end 34.3535 -3.36042)
		(width 0.1651)
		(layer "B.Cu")
		(net "M_J_DQS_DP<9>")
	)
	(segment
		(start 34.799524 -5.004054)
		(end 34.34334 -4.54787)
		(width 0.1651)
		(layer "B.Cu")
		(net "M_J_DQS_DP<9>")
	)
	(segment
		(start 34.3535 -3.36042)
		(end 34.74212 -2.9718)
		(width 0.1651)
		(layer "B.Cu")
		(net "M_J_DQS_DP<9>")
	)
	(segment
		(start 34.799524 -5.621782)
		(end 34.799524 -5.004054)
		(width 0.1651)
		(layer "B.Cu")
		(net "M_J_DQS_DP<9>")
	)
	(segment
		(start 34.266124 -4.415536)
		(end 34.266124 -3.519932)
		(width 0.1651)
		(layer "B.Cu")
		(net "M_J_DQS_DP<9>")
	)
	(segment
		(start 34.34334 -4.54787)
		(end 34.266124 -4.415536)
		(width 0.1651)
		(layer "B.Cu")
		(net "M_J_DQS_DP<9>")
	)
	(segment
		(start 34.770568 -1.346708)
		(end 34.770568 -1.685036)
		(width 0.14224)
		(layer "In11.Cu")
		(net "M_J_DQS_DP<9>")
	)
	(segment
		(start 35.2552 -20.060666)
		(end 35.486848 -20.292314)
		(width 0.14224)
		(layer "In11.Cu")
		(net "M_J_DQS_DP<9>")
	)
	(segment
		(start 35.053524 -0.5842)
		(end 35.261804 -0.79248)
		(width 0.14224)
		(layer "In11.Cu")
		(net "M_J_DQS_DP<9>")
	)
	(segment
		(start 37.340032 -40.860472)
		(end 37.751004 -41.271444)
		(width 0.14224)
		(layer "In11.Cu")
		(net "M_J_DQS_DP<9>")
	)
	(segment
		(start 34.774124 -0.1778)
		(end 34.774124 -0.4318)
		(width 0.14224)
		(layer "In11.Cu")
		(net "M_J_DQS_DP<9>")
	)
	(segment
		(start 35.021266 -2.9718)
		(end 34.74212 -2.9718)
		(width 0.14224)
		(layer "In11.Cu")
		(net "M_J_DQS_DP<9>")
	)
	(segment
		(start 35.08121 1.32588)
		(end 35.261804 1.145286)
		(width 0.14224)
		(layer "In11.Cu")
		(net "M_J_DQS_DP<9>")
	)
	(segment
		(start 34.445448 -25.183592)
		(end 34.445448 -32.788352)
		(width 0.14224)
		(layer "In11.Cu")
		(net "M_J_DQS_DP<9>")
	)
	(segment
		(start 35.162236 -39.098728)
		(end 36.846764 -39.098728)
		(width 0.14224)
		(layer "In11.Cu")
		(net "M_J_DQS_DP<9>")
	)
	(segment
		(start 35.078924 -1.2192)
		(end 34.898076 -1.2192)
		(width 0.14224)
		(layer "In11.Cu")
		(net "M_J_DQS_DP<9>")
	)
	(segment
		(start 34.927032 -1.8415)
		(end 35.015424 -1.8415)
		(width 0.14224)
		(layer "In11.Cu")
		(net "M_J_DQS_DP<9>")
	)
	(segment
		(start 34.770568 -1.685036)
		(end 34.927032 -1.8415)
		(width 0.14224)
		(layer "In11.Cu")
		(net "M_J_DQS_DP<9>")
	)
	(segment
		(start 34.898076 -1.2192)
		(end 34.770568 -1.346708)
		(width 0.14224)
		(layer "In11.Cu")
		(net "M_J_DQS_DP<9>")
	)
	(segment
		(start 34.787078 -33.129982)
		(end 34.787078 -33.63849)
		(width 0.14224)
		(layer "In11.Cu")
		(net "M_J_DQS_DP<9>")
	)
	(segment
		(start 35.261804 -2.08788)
		(end 35.261804 -2.731262)
		(width 0.14224)
		(layer "In11.Cu")
		(net "M_J_DQS_DP<9>")
	)
	(segment
		(start 35.015424 -1.8415)
		(end 35.261804 -2.08788)
		(width 0.14224)
		(layer "In11.Cu")
		(net "M_J_DQS_DP<9>")
	)
	(segment
		(start 75.26782 -66.162174)
		(end 75.762866 -65.49644)
		(width 0.0889)
		(layer "In11.Cu")
		(net "M_J_DQS_DP<9>")
	)
	(segment
		(start 69.752464 -64.60109)
		(end 69.753988 -64.60109)
		(width 0.0889)
		(layer "In11.Cu")
		(net "M_J_DQS_DP<9>")
	)
	(segment
		(start 35.486848 -20.292314)
		(end 35.486848 -20.954238)
		(width 0.14224)
		(layer "In11.Cu")
		(net "M_J_DQS_DP<9>")
	)
	(segment
		(start 34.787078 -33.63849)
		(end 34.445448 -33.98012)
		(width 0.14224)
		(layer "In11.Cu")
		(net "M_J_DQS_DP<9>")
	)
	(segment
		(start 34.950146 1.32588)
		(end 35.08121 1.32588)
		(width 0.14224)
		(layer "In11.Cu")
		(net "M_J_DQS_DP<9>")
	)
	(segment
		(start 74.045318 -67.07759)
		(end 74.046334 -67.07759)
		(width 0.0889)
		(layer "In11.Cu")
		(net "M_J_DQS_DP<9>")
	)
	(segment
		(start 68.035424 -64.60109)
		(end 68.036948 -64.60109)
		(width 0.0889)
		(layer "In11.Cu")
		(net "M_J_DQS_DP<9>")
	)
	(segment
		(start 39.247064 -43.316652)
		(end 61.066172 -65.13576)
		(width 0.14224)
		(layer "In11.Cu")
		(net "M_J_DQS_DP<9>")
	)
	(segment
		(start 35.128962 -36.382706)
		(end 35.413442 -36.667186)
		(width 0.14224)
		(layer "In11.Cu")
		(net "M_J_DQS_DP<9>")
	)
	(segment
		(start 38.856158 -41.271444)
		(end 39.247064 -41.66235)
		(width 0.14224)
		(layer "In11.Cu")
		(net "M_J_DQS_DP<9>")
	)
	(segment
		(start 68.89369 -65.096136)
		(end 68.895722 -65.096136)
		(width 0.0889)
		(layer "In11.Cu")
		(net "M_J_DQS_DP<9>")
	)
	(segment
		(start 70.59803 -65.09639)
		(end 70.626732 -65.09639)
		(width 0.0889)
		(layer "In11.Cu")
		(net "M_J_DQS_DP<9>")
	)
	(segment
		(start 34.445448 -32.788352)
		(end 34.787078 -33.129982)
		(width 0.14224)
		(layer "In11.Cu")
		(net "M_J_DQS_DP<9>")
	)
	(segment
		(start 34.445448 -36.003738)
		(end 34.824416 -36.382706)
		(width 0.14224)
		(layer "In11.Cu")
		(net "M_J_DQS_DP<9>")
	)
	(segment
		(start 73.165716 -66.582036)
		(end 73.198482 -66.582036)
		(width 0.0889)
		(layer "In11.Cu")
		(net "M_J_DQS_DP<9>")
	)
	(segment
		(start 34.926524 -0.5842)
		(end 35.053524 -0.5842)
		(width 0.14224)
		(layer "In11.Cu")
		(net "M_J_DQS_DP<9>")
	)
	(segment
		(start 34.875724 -37.680392)
		(end 34.875724 -38.812216)
		(width 0.14224)
		(layer "In11.Cu")
		(net "M_J_DQS_DP<9>")
	)
	(segment
		(start 71.448676 -65.591436)
		(end 71.481442 -65.591436)
		(width 0.0889)
		(layer "In11.Cu")
		(net "M_J_DQS_DP<9>")
	)
	(segment
		(start 75.251056 -66.191638)
		(end 75.26782 -66.162174)
		(width 0.0889)
		(layer "In11.Cu")
		(net "M_J_DQS_DP<9>")
	)
	(segment
		(start 35.261804 -1.03632)
		(end 35.078924 -1.2192)
		(width 0.14224)
		(layer "In11.Cu")
		(net "M_J_DQS_DP<9>")
	)
	(segment
		(start 37.340032 -39.591996)
		(end 37.340032 -40.860472)
		(width 0.14224)
		(layer "In11.Cu")
		(net "M_J_DQS_DP<9>")
	)
	(segment
		(start 35.261804 -2.731262)
		(end 35.021266 -2.9718)
		(width 0.14224)
		(layer "In11.Cu")
		(net "M_J_DQS_DP<9>")
	)
	(segment
		(start 74.648568 -66.674238)
		(end 74.798936 -66.488056)
		(width 0.0889)
		(layer "In11.Cu")
		(net "M_J_DQS_DP<9>")
	)
	(segment
		(start 34.74212 1.117854)
		(end 34.950146 1.32588)
		(width 0.14224)
		(layer "In11.Cu")
		(net "M_J_DQS_DP<9>")
	)
	(segment
		(start 39.247064 -41.66235)
		(end 39.247064 -43.316652)
		(width 0.14224)
		(layer "In11.Cu")
		(net "M_J_DQS_DP<9>")
	)
	(segment
		(start 35.261804 0.30988)
		(end 34.774124 -0.1778)
		(width 0.14224)
		(layer "In11.Cu")
		(net "M_J_DQS_DP<9>")
	)
	(segment
		(start 35.2552 -24.37384)
		(end 34.445448 -25.183592)
		(width 0.14224)
		(layer "In11.Cu")
		(net "M_J_DQS_DP<9>")
	)
	(segment
		(start 36.846764 -39.098728)
		(end 37.340032 -39.591996)
		(width 0.14224)
		(layer "In11.Cu")
		(net "M_J_DQS_DP<9>")
	)
	(segment
		(start 35.261804 1.145286)
		(end 35.261804 0.30988)
		(width 0.14224)
		(layer "In11.Cu")
		(net "M_J_DQS_DP<9>")
	)
	(segment
		(start 34.74212 -2.9718)
		(end 34.271204 -3.442716)
		(width 0.14224)
		(layer "In11.Cu")
		(net "M_J_DQS_DP<9>")
	)
	(segment
		(start 34.875724 -38.812216)
		(end 35.162236 -39.098728)
		(width 0.14224)
		(layer "In11.Cu")
		(net "M_J_DQS_DP<9>")
	)
	(segment
		(start 65.733168 -65.13576)
		(end 65.772538 -65.09639)
		(width 0.0889)
		(layer "In11.Cu")
		(net "M_J_DQS_DP<9>")
	)
	(segment
		(start 34.271204 -3.442716)
		(end 34.271204 -5.367274)
		(width 0.14224)
		(layer "In11.Cu")
		(net "M_J_DQS_DP<9>")
	)
	(segment
		(start 35.486848 -20.954238)
		(end 35.2552 -21.185886)
		(width 0.14224)
		(layer "In11.Cu")
		(net "M_J_DQS_DP<9>")
	)
	(segment
		(start 35.2552 -21.185886)
		(end 35.2552 -24.37384)
		(width 0.14224)
		(layer "In11.Cu")
		(net "M_J_DQS_DP<9>")
	)
	(segment
		(start 34.774124 -0.4318)
		(end 34.926524 -0.5842)
		(width 0.14224)
		(layer "In11.Cu")
		(net "M_J_DQS_DP<9>")
	)
	(segment
		(start 35.413442 -37.142674)
		(end 34.875724 -37.680392)
		(width 0.14224)
		(layer "In11.Cu")
		(net "M_J_DQS_DP<9>")
	)
	(segment
		(start 72.311006 -66.08699)
		(end 72.343772 -66.08699)
		(width 0.0889)
		(layer "In11.Cu")
		(net "M_J_DQS_DP<9>")
	)
	(segment
		(start 65.772538 -65.09639)
		(end 67.191382 -65.09639)
		(width 0.0889)
		(layer "In11.Cu")
		(net "M_J_DQS_DP<9>")
	)
	(segment
		(start 61.066172 -65.13576)
		(end 65.733168 -65.13576)
		(width 0.14224)
		(layer "In11.Cu")
		(net "M_J_DQS_DP<9>")
	)
	(segment
		(start 34.445448 -33.98012)
		(end 34.445448 -36.003738)
		(width 0.14224)
		(layer "In11.Cu")
		(net "M_J_DQS_DP<9>")
	)
	(segment
		(start 34.824416 -36.382706)
		(end 35.128962 -36.382706)
		(width 0.14224)
		(layer "In11.Cu")
		(net "M_J_DQS_DP<9>")
	)
	(segment
		(start 35.2552 -6.35127)
		(end 35.2552 -20.060666)
		(width 0.14224)
		(layer "In11.Cu")
		(net "M_J_DQS_DP<9>")
	)
	(segment
		(start 34.271204 -5.367274)
		(end 35.2552 -6.35127)
		(width 0.14224)
		(layer "In11.Cu")
		(net "M_J_DQS_DP<9>")
	)
	(segment
		(start 35.261804 -0.79248)
		(end 35.261804 -1.03632)
		(width 0.14224)
		(layer "In11.Cu")
		(net "M_J_DQS_DP<9>")
	)
	(segment
		(start 35.413442 -36.667186)
		(end 35.413442 -37.142674)
		(width 0.14224)
		(layer "In11.Cu")
		(net "M_J_DQS_DP<9>")
	)
	(segment
		(start 37.751004 -41.271444)
		(end 38.856158 -41.271444)
		(width 0.14224)
		(layer "In11.Cu")
		(net "M_J_DQS_DP<9>")
	)
	(arc
		(start 74.798936 -66.488056)
		(mid 74.850688 -66.429255)
		(end 74.919332 -66.391536)
		(width 0.0889)
		(layer "In11.Cu")
		(net "M_J_DQS_DP<9>")
	)
	(arc
		(start 73.198482 -66.582036)
		(mid 73.392332 -66.638386)
		(end 73.534016 -66.782188)
		(width 0.0889)
		(layer "In11.Cu")
		(net "M_J_DQS_DP<9>")
	)
	(arc
		(start 67.191382 -65.09639)
		(mid 67.479069 -65.013869)
		(end 67.689476 -64.800988)
		(width 0.0889)
		(layer "In11.Cu")
		(net "M_J_DQS_DP<9>")
	)
	(arc
		(start 69.406516 -64.800988)
		(mid 69.552688 -64.654653)
		(end 69.752464 -64.60109)
		(width 0.0889)
		(layer "In11.Cu")
		(net "M_J_DQS_DP<9>")
	)
	(arc
		(start 73.534016 -66.782188)
		(mid 73.750079 -66.998397)
		(end 74.045318 -67.07759)
		(width 0.0889)
		(layer "In11.Cu")
		(net "M_J_DQS_DP<9>")
	)
	(arc
		(start 71.481442 -65.591436)
		(mid 71.675292 -65.647786)
		(end 71.816976 -65.791588)
		(width 0.0889)
		(layer "In11.Cu")
		(net "M_J_DQS_DP<9>")
	)
	(arc
		(start 74.046334 -67.07759)
		(mid 74.341597 -66.998439)
		(end 74.557636 -66.782188)
		(width 0.0889)
		(layer "In11.Cu")
		(net "M_J_DQS_DP<9>")
	)
	(arc
		(start 70.958456 -65.296288)
		(mid 71.16546 -65.507152)
		(end 71.448676 -65.591436)
		(width 0.0889)
		(layer "In11.Cu")
		(net "M_J_DQS_DP<9>")
	)
	(arc
		(start 70.099936 -64.800988)
		(mid 70.310289 -65.01396)
		(end 70.59803 -65.09639)
		(width 0.0889)
		(layer "In11.Cu")
		(net "M_J_DQS_DP<9>")
	)
	(arc
		(start 74.919332 -66.391536)
		(mid 75.110974 -66.33437)
		(end 75.251056 -66.191638)
		(width 0.0889)
		(layer "In11.Cu")
		(net "M_J_DQS_DP<9>")
	)
	(arc
		(start 67.689476 -64.800988)
		(mid 67.835648 -64.654653)
		(end 68.035424 -64.60109)
		(width 0.0889)
		(layer "In11.Cu")
		(net "M_J_DQS_DP<9>")
	)
	(arc
		(start 74.61885 -66.701416)
		(mid 74.633365 -66.687451)
		(end 74.648568 -66.674238)
		(width 0.0889)
		(layer "In11.Cu")
		(net "M_J_DQS_DP<9>")
	)
	(arc
		(start 68.895722 -65.096136)
		(mid 69.190716 -65.017062)
		(end 69.406516 -64.800988)
		(width 0.0889)
		(layer "In11.Cu")
		(net "M_J_DQS_DP<9>")
	)
	(arc
		(start 68.382896 -64.800988)
		(mid 68.59875 -65.016969)
		(end 68.89369 -65.096136)
		(width 0.0889)
		(layer "In11.Cu")
		(net "M_J_DQS_DP<9>")
	)
	(arc
		(start 71.816976 -65.791588)
		(mid 72.025584 -66.00352)
		(end 72.311006 -66.08699)
		(width 0.0889)
		(layer "In11.Cu")
		(net "M_J_DQS_DP<9>")
	)
	(arc
		(start 70.626732 -65.09639)
		(mid 70.818374 -65.153556)
		(end 70.958456 -65.296288)
		(width 0.0889)
		(layer "In11.Cu")
		(net "M_J_DQS_DP<9>")
	)
	(arc
		(start 72.343772 -66.08699)
		(mid 72.535414 -66.144156)
		(end 72.675496 -66.286888)
		(width 0.0889)
		(layer "In11.Cu")
		(net "M_J_DQS_DP<9>")
	)
	(arc
		(start 69.753988 -64.60109)
		(mid 69.953761 -64.654659)
		(end 70.099936 -64.800988)
		(width 0.0889)
		(layer "In11.Cu")
		(net "M_J_DQS_DP<9>")
	)
	(arc
		(start 74.557636 -66.782188)
		(mid 74.585677 -66.739858)
		(end 74.61885 -66.701416)
		(width 0.0889)
		(layer "In11.Cu")
		(net "M_J_DQS_DP<9>")
	)
	(arc
		(start 68.036948 -64.60109)
		(mid 68.236721 -64.654659)
		(end 68.382896 -64.800988)
		(width 0.0889)
		(layer "In11.Cu")
		(net "M_J_DQS_DP<9>")
	)
	(arc
		(start 72.675496 -66.286888)
		(mid 72.8825 -66.497752)
		(end 73.165716 -66.582036)
		(width 0.0889)
		(layer "In11.Cu")
		(net "M_J_DQS_DP<9>")
	)
	(segment
		(start 80.626712 -68.963286)
		(end 80.055212 -68.963286)
		(width 0.0889)
		(layer "F.Cu")
		(net "M_J_DQS_DP<8>")
	)
	(segment
		(start 73.899268 -0.820928)
		(end 73.899268 0.277368)
		(width 0.1651)
		(layer "F.Cu")
		(net "M_J_DQS_DP<8>")
	)
	(segment
		(start 73.711308 1.455166)
		(end 73.437496 1.181354)
		(width 0.1651)
		(layer "F.Cu")
		(net "M_J_DQS_DP<8>")
	)
	(segment
		(start 73.899522 -0.821182)
		(end 73.899268 -0.820928)
		(width 0.1651)
		(layer "F.Cu")
		(net "M_J_DQS_DP<8>")
	)
	(segment
		(start 74.12101 1.241298)
		(end 73.907142 1.455166)
		(width 0.1651)
		(layer "F.Cu")
		(net "M_J_DQS_DP<8>")
	)
	(segment
		(start 73.899268 0.277368)
		(end 74.12101 0.49911)
		(width 0.1651)
		(layer "F.Cu")
		(net "M_J_DQS_DP<8>")
	)
	(segment
		(start 74.12101 0.49911)
		(end 74.12101 1.241298)
		(width 0.1651)
		(layer "F.Cu")
		(net "M_J_DQS_DP<8>")
	)
	(segment
		(start 73.907142 1.455166)
		(end 73.711308 1.455166)
		(width 0.1651)
		(layer "F.Cu")
		(net "M_J_DQS_DP<8>")
	)
	(via
		(at 73.437496 1.181354)
		(size 0.508)
		(drill 0.254)
		(layers "F.Cu" "B.Cu")
		(net "M_J_DQS_DP<8>")
	)
	(via
		(at 73.437496 -3.026156)
		(size 0.508)
		(drill 0.254)
		(layers "F.Cu" "B.Cu")
		(net "M_J_DQS_DP<8>")
	)
	(via
		(at 80.055212 -68.963286)
		(size 0.508)
		(drill 0.254)
		(layers "F.Cu" "B.Cu")
		(net "M_J_DQS_DP<8>")
	)
	(segment
		(start 73.899268 -2.537968)
		(end 74.0791 -2.7178)
		(width 0.1651)
		(layer "B.Cu")
		(net "M_J_DQS_DP<8>")
	)
	(segment
		(start 73.899522 -1.021842)
		(end 73.899522 -2.537714)
		(width 0.1651)
		(layer "B.Cu")
		(net "M_J_DQS_DP<8>")
	)
	(segment
		(start 74.0791 -3.16738)
		(end 73.9394 -3.30708)
		(width 0.1651)
		(layer "B.Cu")
		(net "M_J_DQS_DP<8>")
	)
	(segment
		(start 73.9394 -3.30708)
		(end 73.71842 -3.30708)
		(width 0.1651)
		(layer "B.Cu")
		(net "M_J_DQS_DP<8>")
	)
	(segment
		(start 73.899522 -2.537714)
		(end 73.899268 -2.537968)
		(width 0.1651)
		(layer "B.Cu")
		(net "M_J_DQS_DP<8>")
	)
	(segment
		(start 74.0791 -2.7178)
		(end 74.0791 -3.16738)
		(width 0.1651)
		(layer "B.Cu")
		(net "M_J_DQS_DP<8>")
	)
	(segment
		(start 73.71842 -3.30708)
		(end 73.437496 -3.026156)
		(width 0.1651)
		(layer "B.Cu")
		(net "M_J_DQS_DP<8>")
	)
	(segment
		(start 72.9996 -3.464052)
		(end 73.437496 -3.026156)
		(width 0.14224)
		(layer "In4.Cu")
		(net "M_J_DQS_DP<8>")
	)
	(segment
		(start 80.406748 -60.847224)
		(end 80.401922 -60.838588)
		(width 0.0889)
		(layer "In4.Cu")
		(net "M_J_DQS_DP<8>")
	)
	(segment
		(start 80.888332 -52.340002)
		(end 80.888332 -50.647092)
		(width 0.0889)
		(layer "In4.Cu")
		(net "M_J_DQS_DP<8>")
	)
	(segment
		(start 80.487012 -55.147972)
		(end 80.487012 -52.741322)
		(width 0.0889)
		(layer "In4.Cu")
		(net "M_J_DQS_DP<8>")
	)
	(segment
		(start 80.406748 -56.884824)
		(end 80.401922 -56.876188)
		(width 0.0889)
		(layer "In4.Cu")
		(net "M_J_DQS_DP<8>")
	)
	(segment
		(start 81.122774 -47.203106)
		(end 80.937608 -47.01794)
		(width 0.14224)
		(layer "In4.Cu")
		(net "M_J_DQS_DP<8>")
	)
	(segment
		(start 80.401922 -56.876188)
		(end 80.395572 -56.86552)
		(width 0.0889)
		(layer "In4.Cu")
		(net "M_J_DQS_DP<8>")
	)
	(segment
		(start 80.2513 -47.01794)
		(end 76.538328 -43.304968)
		(width 0.14224)
		(layer "In4.Cu")
		(net "M_J_DQS_DP<8>")
	)
	(segment
		(start 80.401922 -62.819788)
		(end 80.395572 -62.80912)
		(width 0.0889)
		(layer "In4.Cu")
		(net "M_J_DQS_DP<8>")
	)
	(segment
		(start 80.401922 -63.810388)
		(end 80.395572 -63.79972)
		(width 0.0889)
		(layer "In4.Cu")
		(net "M_J_DQS_DP<8>")
	)
	(segment
		(start 76.538328 -32.26562)
		(end 73.950576 -29.677868)
		(width 0.14224)
		(layer "In4.Cu")
		(net "M_J_DQS_DP<8>")
	)
	(segment
		(start 80.937608 -47.01794)
		(end 80.2513 -47.01794)
		(width 0.14224)
		(layer "In4.Cu")
		(net "M_J_DQS_DP<8>")
	)
	(segment
		(start 80.406748 -67.781424)
		(end 80.401922 -67.772788)
		(width 0.0889)
		(layer "In4.Cu")
		(net "M_J_DQS_DP<8>")
	)
	(segment
		(start 80.888332 -50.647092)
		(end 81.162144 -50.37328)
		(width 0.0889)
		(layer "In4.Cu")
		(net "M_J_DQS_DP<8>")
	)
	(segment
		(start 73.950576 -29.677868)
		(end 73.950576 -6.22427)
		(width 0.14224)
		(layer "In4.Cu")
		(net "M_J_DQS_DP<8>")
	)
	(segment
		(start 80.406748 -68.772024)
		(end 80.401922 -68.763388)
		(width 0.0889)
		(layer "In4.Cu")
		(net "M_J_DQS_DP<8>")
	)
	(segment
		(start 80.401922 -55.295292)
		(end 80.487012 -55.147972)
		(width 0.0889)
		(layer "In4.Cu")
		(net "M_J_DQS_DP<8>")
	)
	(segment
		(start 80.406748 -64.809624)
		(end 80.401922 -64.800988)
		(width 0.0889)
		(layer "In4.Cu")
		(net "M_J_DQS_DP<8>")
	)
	(segment
		(start 76.538328 -43.304968)
		(end 76.538328 -32.26562)
		(width 0.14224)
		(layer "In4.Cu")
		(net "M_J_DQS_DP<8>")
	)
	(segment
		(start 72.9996 -4.574286)
		(end 72.9996 -3.464052)
		(width 0.14224)
		(layer "In4.Cu")
		(net "M_J_DQS_DP<8>")
	)
	(segment
		(start 73.11898 -4.693666)
		(end 72.9996 -4.574286)
		(width 0.14224)
		(layer "In4.Cu")
		(net "M_J_DQS_DP<8>")
	)
	(segment
		(start 80.406748 -61.837824)
		(end 80.401922 -61.829188)
		(width 0.0889)
		(layer "In4.Cu")
		(net "M_J_DQS_DP<8>")
	)
	(segment
		(start 80.406748 -62.828424)
		(end 80.401922 -62.819788)
		(width 0.0889)
		(layer "In4.Cu")
		(net "M_J_DQS_DP<8>")
	)
	(segment
		(start 80.055212 -69.30136)
		(end 80.113124 -69.359272)
		(width 0.0889)
		(layer "In4.Cu")
		(net "M_J_DQS_DP<8>")
	)
	(segment
		(start 81.162144 -50.00117)
		(end 81.122774 -49.9618)
		(width 0.0889)
		(layer "In4.Cu")
		(net "M_J_DQS_DP<8>")
	)
	(segment
		(start 73.950576 -6.22427)
		(end 73.11898 -5.392674)
		(width 0.14224)
		(layer "In4.Cu")
		(net "M_J_DQS_DP<8>")
	)
	(segment
		(start 80.406748 -59.856624)
		(end 80.401922 -59.847988)
		(width 0.0889)
		(layer "In4.Cu")
		(net "M_J_DQS_DP<8>")
	)
	(segment
		(start 80.406748 -63.819024)
		(end 80.401922 -63.810388)
		(width 0.0889)
		(layer "In4.Cu")
		(net "M_J_DQS_DP<8>")
	)
	(segment
		(start 80.406748 -55.894224)
		(end 80.401922 -55.885588)
		(width 0.0889)
		(layer "In4.Cu")
		(net "M_J_DQS_DP<8>")
	)
	(segment
		(start 81.162144 -50.37328)
		(end 81.162144 -50.00117)
		(width 0.0889)
		(layer "In4.Cu")
		(net "M_J_DQS_DP<8>")
	)
	(segment
		(start 80.055212 -68.963286)
		(end 80.055212 -69.30136)
		(width 0.0889)
		(layer "In4.Cu")
		(net "M_J_DQS_DP<8>")
	)
	(segment
		(start 80.401922 -65.791588)
		(end 80.395572 -65.78092)
		(width 0.0889)
		(layer "In4.Cu")
		(net "M_J_DQS_DP<8>")
	)
	(segment
		(start 80.487012 -52.741322)
		(end 80.888332 -52.340002)
		(width 0.0889)
		(layer "In4.Cu")
		(net "M_J_DQS_DP<8>")
	)
	(segment
		(start 80.395572 -58.277506)
		(end 80.401922 -58.266838)
		(width 0.0889)
		(layer "In4.Cu")
		(net "M_J_DQS_DP<8>")
	)
	(segment
		(start 80.406748 -65.800224)
		(end 80.401922 -65.791588)
		(width 0.0889)
		(layer "In4.Cu")
		(net "M_J_DQS_DP<8>")
	)
	(segment
		(start 80.401922 -67.772788)
		(end 80.395572 -67.76212)
		(width 0.0889)
		(layer "In4.Cu")
		(net "M_J_DQS_DP<8>")
	)
	(segment
		(start 81.122774 -49.939702)
		(end 81.122774 -47.203106)
		(width 0.14224)
		(layer "In4.Cu")
		(net "M_J_DQS_DP<8>")
	)
	(segment
		(start 80.401922 -64.800988)
		(end 80.395572 -64.79032)
		(width 0.0889)
		(layer "In4.Cu")
		(net "M_J_DQS_DP<8>")
	)
	(segment
		(start 81.122774 -49.9618)
		(end 81.122774 -49.939702)
		(width 0.0889)
		(layer "In4.Cu")
		(net "M_J_DQS_DP<8>")
	)
	(segment
		(start 80.406748 -58.866024)
		(end 80.401922 -58.857388)
		(width 0.0889)
		(layer "In4.Cu")
		(net "M_J_DQS_DP<8>")
	)
	(segment
		(start 80.401922 -68.763388)
		(end 80.395572 -68.75272)
		(width 0.0889)
		(layer "In4.Cu")
		(net "M_J_DQS_DP<8>")
	)
	(segment
		(start 73.11898 -5.392674)
		(end 73.11898 -4.693666)
		(width 0.14224)
		(layer "In4.Cu")
		(net "M_J_DQS_DP<8>")
	)
	(segment
		(start 80.401922 -60.838588)
		(end 80.395572 -60.82792)
		(width 0.0889)
		(layer "In4.Cu")
		(net "M_J_DQS_DP<8>")
	)
	(segment
		(start 80.401922 -59.847988)
		(end 80.395572 -59.83732)
		(width 0.0889)
		(layer "In4.Cu")
		(net "M_J_DQS_DP<8>")
	)
	(segment
		(start 80.401922 -61.829188)
		(end 80.395572 -61.81852)
		(width 0.0889)
		(layer "In4.Cu")
		(net "M_J_DQS_DP<8>")
	)
	(arc
		(start 80.395572 -68.75272)
		(mid 80.322774 -68.461957)
		(end 80.401922 -68.172838)
		(width 0.0889)
		(layer "In4.Cu")
		(net "M_J_DQS_DP<8>")
	)
	(arc
		(start 80.401922 -55.885588)
		(mid 80.322917 -55.59044)
		(end 80.401922 -55.295292)
		(width 0.0889)
		(layer "In4.Cu")
		(net "M_J_DQS_DP<8>")
	)
	(arc
		(start 80.395572 -67.76212)
		(mid 80.322682 -67.471213)
		(end 80.401922 -67.181984)
		(width 0.0889)
		(layer "In4.Cu")
		(net "M_J_DQS_DP<8>")
	)
	(arc
		(start 80.401922 -59.257438)
		(mid 80.455392 -59.062375)
		(end 80.406748 -58.866024)
		(width 0.0889)
		(layer "In4.Cu")
		(net "M_J_DQS_DP<8>")
	)
	(arc
		(start 80.401922 -62.229238)
		(mid 80.455392 -62.034175)
		(end 80.406748 -61.837824)
		(width 0.0889)
		(layer "In4.Cu")
		(net "M_J_DQS_DP<8>")
	)
	(arc
		(start 80.401922 -66.782188)
		(mid 80.322791 -66.486786)
		(end 80.401922 -66.191384)
		(width 0.0889)
		(layer "In4.Cu")
		(net "M_J_DQS_DP<8>")
	)
	(arc
		(start 80.395572 -56.86552)
		(mid 80.322774 -56.574757)
		(end 80.401922 -56.285638)
		(width 0.0889)
		(layer "In4.Cu")
		(net "M_J_DQS_DP<8>")
	)
	(arc
		(start 80.401922 -58.266838)
		(mid 80.455421 -58.06694)
		(end 80.401922 -57.867042)
		(width 0.0889)
		(layer "In4.Cu")
		(net "M_J_DQS_DP<8>")
	)
	(arc
		(start 80.113124 -69.359272)
		(mid 80.41316 -69.14226)
		(end 80.406748 -68.772024)
		(width 0.0889)
		(layer "In4.Cu")
		(net "M_J_DQS_DP<8>")
	)
	(arc
		(start 80.401922 -64.210438)
		(mid 80.455392 -64.015375)
		(end 80.406748 -63.819024)
		(width 0.0889)
		(layer "In4.Cu")
		(net "M_J_DQS_DP<8>")
	)
	(arc
		(start 80.395572 -62.80912)
		(mid 80.322774 -62.518357)
		(end 80.401922 -62.229238)
		(width 0.0889)
		(layer "In4.Cu")
		(net "M_J_DQS_DP<8>")
	)
	(arc
		(start 80.401922 -60.248038)
		(mid 80.455392 -60.052975)
		(end 80.406748 -59.856624)
		(width 0.0889)
		(layer "In4.Cu")
		(net "M_J_DQS_DP<8>")
	)
	(arc
		(start 80.395572 -65.78092)
		(mid 80.322774 -65.490157)
		(end 80.401922 -65.201038)
		(width 0.0889)
		(layer "In4.Cu")
		(net "M_J_DQS_DP<8>")
	)
	(arc
		(start 80.401922 -68.172838)
		(mid 80.455392 -67.977775)
		(end 80.406748 -67.781424)
		(width 0.0889)
		(layer "In4.Cu")
		(net "M_J_DQS_DP<8>")
	)
	(arc
		(start 80.395572 -63.79972)
		(mid 80.322774 -63.508957)
		(end 80.401922 -63.219838)
		(width 0.0889)
		(layer "In4.Cu")
		(net "M_J_DQS_DP<8>")
	)
	(arc
		(start 80.401922 -57.867042)
		(mid 80.322791 -57.57164)
		(end 80.401922 -57.276238)
		(width 0.0889)
		(layer "In4.Cu")
		(net "M_J_DQS_DP<8>")
	)
	(arc
		(start 80.401922 -63.219838)
		(mid 80.455392 -63.024775)
		(end 80.406748 -62.828424)
		(width 0.0889)
		(layer "In4.Cu")
		(net "M_J_DQS_DP<8>")
	)
	(arc
		(start 80.395572 -64.79032)
		(mid 80.322774 -64.499557)
		(end 80.401922 -64.210438)
		(width 0.0889)
		(layer "In4.Cu")
		(net "M_J_DQS_DP<8>")
	)
	(arc
		(start 80.395572 -60.82792)
		(mid 80.322774 -60.537157)
		(end 80.401922 -60.248038)
		(width 0.0889)
		(layer "In4.Cu")
		(net "M_J_DQS_DP<8>")
	)
	(arc
		(start 80.401922 -58.857388)
		(mid 80.3227 -58.56827)
		(end 80.395572 -58.277506)
		(width 0.0889)
		(layer "In4.Cu")
		(net "M_J_DQS_DP<8>")
	)
	(arc
		(start 80.401922 -65.201038)
		(mid 80.455392 -65.005975)
		(end 80.406748 -64.809624)
		(width 0.0889)
		(layer "In4.Cu")
		(net "M_J_DQS_DP<8>")
	)
	(arc
		(start 80.395572 -61.81852)
		(mid 80.322774 -61.527757)
		(end 80.401922 -61.238638)
		(width 0.0889)
		(layer "In4.Cu")
		(net "M_J_DQS_DP<8>")
	)
	(arc
		(start 80.401922 -57.276238)
		(mid 80.455392 -57.081175)
		(end 80.406748 -56.884824)
		(width 0.0889)
		(layer "In4.Cu")
		(net "M_J_DQS_DP<8>")
	)
	(arc
		(start 80.401922 -67.181984)
		(mid 80.455421 -66.982086)
		(end 80.401922 -66.782188)
		(width 0.0889)
		(layer "In4.Cu")
		(net "M_J_DQS_DP<8>")
	)
	(arc
		(start 80.395572 -59.83732)
		(mid 80.322774 -59.546557)
		(end 80.401922 -59.257438)
		(width 0.0889)
		(layer "In4.Cu")
		(net "M_J_DQS_DP<8>")
	)
	(arc
		(start 80.401922 -61.238638)
		(mid 80.455392 -61.043575)
		(end 80.406748 -60.847224)
		(width 0.0889)
		(layer "In4.Cu")
		(net "M_J_DQS_DP<8>")
	)
	(arc
		(start 80.401922 -56.285638)
		(mid 80.455392 -56.090575)
		(end 80.406748 -55.894224)
		(width 0.0889)
		(layer "In4.Cu")
		(net "M_J_DQS_DP<8>")
	)
	(arc
		(start 80.401922 -66.191384)
		(mid 80.455458 -65.996433)
		(end 80.406748 -65.800224)
		(width 0.0889)
		(layer "In4.Cu")
		(net "M_J_DQS_DP<8>")
	)
	(segment
		(start 73.437496 1.181354)
		(end 73.719182 1.181354)
		(width 0.14224)
		(layer "In11.Cu")
		(net "M_J_DQS_DP<8>")
	)
	(segment
		(start 73.491344 -1.7018)
		(end 73.669144 -1.8796)
		(width 0.14224)
		(layer "In11.Cu")
		(net "M_J_DQS_DP<8>")
	)
	(segment
		(start 73.979024 -2.763774)
		(end 73.716388 -3.02641)
		(width 0.14224)
		(layer "In11.Cu")
		(net "M_J_DQS_DP<8>")
	)
	(segment
		(start 73.774046 -0.5334)
		(end 73.979024 -0.738378)
		(width 0.14224)
		(layer "In11.Cu")
		(net "M_J_DQS_DP<8>")
	)
	(segment
		(start 73.799446 0.0762)
		(end 73.596754 0.0762)
		(width 0.14224)
		(layer "In11.Cu")
		(net "M_J_DQS_DP<8>")
	)
	(segment
		(start 73.491344 -1.4478)
		(end 73.491344 -1.7018)
		(width 0.14224)
		(layer "In11.Cu")
		(net "M_J_DQS_DP<8>")
	)
	(segment
		(start 73.4441 -0.076454)
		(end 73.4441 -0.380746)
		(width 0.14224)
		(layer "In11.Cu")
		(net "M_J_DQS_DP<8>")
	)
	(segment
		(start 73.669144 -1.8796)
		(end 73.7997 -1.8796)
		(width 0.14224)
		(layer "In11.Cu")
		(net "M_J_DQS_DP<8>")
	)
	(segment
		(start 73.7997 -1.8796)
		(end 73.979024 -2.058924)
		(width 0.14224)
		(layer "In11.Cu")
		(net "M_J_DQS_DP<8>")
	)
	(segment
		(start 73.979024 0.255778)
		(end 73.799446 0.0762)
		(width 0.14224)
		(layer "In11.Cu")
		(net "M_J_DQS_DP<8>")
	)
	(segment
		(start 73.979024 -2.058924)
		(end 73.979024 -2.763774)
		(width 0.14224)
		(layer "In11.Cu")
		(net "M_J_DQS_DP<8>")
	)
	(segment
		(start 73.979024 0.921512)
		(end 73.979024 0.255778)
		(width 0.14224)
		(layer "In11.Cu")
		(net "M_J_DQS_DP<8>")
	)
	(segment
		(start 73.596754 -0.5334)
		(end 73.774046 -0.5334)
		(width 0.14224)
		(layer "In11.Cu")
		(net "M_J_DQS_DP<8>")
	)
	(segment
		(start 73.719182 1.181354)
		(end 73.979024 0.921512)
		(width 0.14224)
		(layer "In11.Cu")
		(net "M_J_DQS_DP<8>")
	)
	(segment
		(start 73.437496 -3.02641)
		(end 73.437496 -3.026156)
		(width 0.14224)
		(layer "In11.Cu")
		(net "M_J_DQS_DP<8>")
	)
	(segment
		(start 73.796144 -1.27)
		(end 73.669144 -1.27)
		(width 0.14224)
		(layer "In11.Cu")
		(net "M_J_DQS_DP<8>")
	)
	(segment
		(start 73.979024 -0.738378)
		(end 73.979024 -1.08712)
		(width 0.14224)
		(layer "In11.Cu")
		(net "M_J_DQS_DP<8>")
	)
	(segment
		(start 73.596754 0.0762)
		(end 73.4441 -0.076454)
		(width 0.14224)
		(layer "In11.Cu")
		(net "M_J_DQS_DP<8>")
	)
	(segment
		(start 73.716388 -3.02641)
		(end 73.437496 -3.02641)
		(width 0.14224)
		(layer "In11.Cu")
		(net "M_J_DQS_DP<8>")
	)
	(segment
		(start 73.669144 -1.27)
		(end 73.491344 -1.4478)
		(width 0.14224)
		(layer "In11.Cu")
		(net "M_J_DQS_DP<8>")
	)
	(segment
		(start 73.979024 -1.08712)
		(end 73.796144 -1.27)
		(width 0.14224)
		(layer "In11.Cu")
		(net "M_J_DQS_DP<8>")
	)
	(segment
		(start 73.4441 -0.380746)
		(end 73.596754 -0.5334)
		(width 0.14224)
		(layer "In11.Cu")
		(net "M_J_DQS_DP<8>")
	)
	(segment
		(start 147.85721 1.455166)
		(end 147.661376 1.455166)
		(width 0.1651)
		(layer "F.Cu")
		(net "M_J_DQS_DP<7>")
	)
	(segment
		(start 147.849336 -0.821182)
		(end 147.849336 0.277368)
		(width 0.1651)
		(layer "F.Cu")
		(net "M_J_DQS_DP<7>")
	)
	(segment
		(start 147.661376 1.455166)
		(end 147.387564 1.181354)
		(width 0.1651)
		(layer "F.Cu")
		(net "M_J_DQS_DP<7>")
	)
	(segment
		(start 148.071078 0.49911)
		(end 148.071078 1.241298)
		(width 0.1651)
		(layer "F.Cu")
		(net "M_J_DQS_DP<7>")
	)
	(segment
		(start 147.849336 0.277368)
		(end 148.071078 0.49911)
		(width 0.1651)
		(layer "F.Cu")
		(net "M_J_DQS_DP<7>")
	)
	(segment
		(start 148.071078 1.241298)
		(end 147.85721 1.455166)
		(width 0.1651)
		(layer "F.Cu")
		(net "M_J_DQS_DP<7>")
	)
	(segment
		(start 122.504708 -64.324738)
		(end 121.933208 -64.324738)
		(width 0.0889)
		(layer "F.Cu")
		(net "M_J_DQS_DP<7>")
	)
	(via
		(at 147.387564 -3.026156)
		(size 0.508)
		(drill 0.254)
		(layers "F.Cu" "B.Cu")
		(net "M_J_DQS_DP<7>")
	)
	(via
		(at 147.387564 1.181354)
		(size 0.508)
		(drill 0.254)
		(layers "F.Cu" "B.Cu")
		(net "M_J_DQS_DP<7>")
	)
	(via
		(at 121.933208 -64.324738)
		(size 0.508)
		(drill 0.254)
		(layers "F.Cu" "B.Cu")
		(net "M_J_DQS_DP<7>")
	)
	(segment
		(start 148.029168 -2.7178)
		(end 148.029168 -3.16738)
		(width 0.1651)
		(layer "B.Cu")
		(net "M_J_DQS_DP<7>")
	)
	(segment
		(start 147.849336 -2.537968)
		(end 148.029168 -2.7178)
		(width 0.1651)
		(layer "B.Cu")
		(net "M_J_DQS_DP<7>")
	)
	(segment
		(start 148.029168 -3.16738)
		(end 147.889468 -3.30708)
		(width 0.1651)
		(layer "B.Cu")
		(net "M_J_DQS_DP<7>")
	)
	(segment
		(start 147.889468 -3.30708)
		(end 147.668488 -3.30708)
		(width 0.1651)
		(layer "B.Cu")
		(net "M_J_DQS_DP<7>")
	)
	(segment
		(start 147.849336 -1.021842)
		(end 147.849336 -2.537968)
		(width 0.1651)
		(layer "B.Cu")
		(net "M_J_DQS_DP<7>")
	)
	(segment
		(start 147.668488 -3.30708)
		(end 147.387564 -3.026156)
		(width 0.1651)
		(layer "B.Cu")
		(net "M_J_DQS_DP<7>")
	)
	(segment
		(start 147.069048 -5.392674)
		(end 147.069048 -4.754626)
		(width 0.14224)
		(layer "In11.Cu")
		(net "M_J_DQS_DP<7>")
	)
	(segment
		(start 122.273568 -61.563504)
		(end 122.279918 -61.552836)
		(width 0.0889)
		(layer "In11.Cu")
		(net "M_J_DQS_DP<7>")
	)
	(segment
		(start 147.666456 -3.02641)
		(end 147.929092 -2.763774)
		(width 0.14224)
		(layer "In11.Cu")
		(net "M_J_DQS_DP<7>")
	)
	(segment
		(start 126.91364 -48.18253)
		(end 127.02794 -48.29683)
		(width 0.14224)
		(layer "In11.Cu")
		(net "M_J_DQS_DP<7>")
	)
	(segment
		(start 135.710168 -41.783)
		(end 136.624568 -41.783)
		(width 0.14224)
		(layer "In11.Cu")
		(net "M_J_DQS_DP<7>")
	)
	(segment
		(start 126.65964 -48.18253)
		(end 126.91364 -48.18253)
		(width 0.14224)
		(layer "In11.Cu")
		(net "M_J_DQS_DP<7>")
	)
	(segment
		(start 121.933208 -64.324738)
		(end 121.933208 -64.662812)
		(width 0.0889)
		(layer "In11.Cu")
		(net "M_J_DQS_DP<7>")
	)
	(segment
		(start 122.273568 -56.610504)
		(end 122.279918 -56.599836)
		(width 0.0889)
		(layer "In11.Cu")
		(net "M_J_DQS_DP<7>")
	)
	(segment
		(start 147.069048 -4.754626)
		(end 146.949668 -4.635246)
		(width 0.14224)
		(layer "In11.Cu")
		(net "M_J_DQS_DP<7>")
	)
	(segment
		(start 129.196338 -48.29683)
		(end 135.710168 -41.783)
		(width 0.14224)
		(layer "In11.Cu")
		(net "M_J_DQS_DP<7>")
	)
	(segment
		(start 147.929092 -0.738378)
		(end 147.724114 -0.5334)
		(width 0.14224)
		(layer "In11.Cu")
		(net "M_J_DQS_DP<7>")
	)
	(segment
		(start 147.900644 -30.506924)
		(end 147.900644 -6.22427)
		(width 0.14224)
		(layer "In11.Cu")
		(net "M_J_DQS_DP<7>")
	)
	(segment
		(start 147.394168 -0.380746)
		(end 147.394168 -0.076454)
		(width 0.14224)
		(layer "In11.Cu")
		(net "M_J_DQS_DP<7>")
	)
	(segment
		(start 147.546822 0.0762)
		(end 147.749514 0.0762)
		(width 0.14224)
		(layer "In11.Cu")
		(net "M_J_DQS_DP<7>")
	)
	(segment
		(start 147.546822 -0.5334)
		(end 147.394168 -0.380746)
		(width 0.14224)
		(layer "In11.Cu")
		(net "M_J_DQS_DP<7>")
	)
	(segment
		(start 147.619212 -1.27)
		(end 147.746212 -1.27)
		(width 0.14224)
		(layer "In11.Cu")
		(net "M_J_DQS_DP<7>")
	)
	(segment
		(start 122.401838 -53.416962)
		(end 122.401838 -51.40833)
		(width 0.0889)
		(layer "In11.Cu")
		(net "M_J_DQS_DP<7>")
	)
	(segment
		(start 147.900644 -6.22427)
		(end 147.069048 -5.392674)
		(width 0.14224)
		(layer "In11.Cu")
		(net "M_J_DQS_DP<7>")
	)
	(segment
		(start 146.949668 -4.635246)
		(end 146.949668 -3.464052)
		(width 0.14224)
		(layer "In11.Cu")
		(net "M_J_DQS_DP<7>")
	)
	(segment
		(start 147.724114 -0.5334)
		(end 147.546822 -0.5334)
		(width 0.14224)
		(layer "In11.Cu")
		(net "M_J_DQS_DP<7>")
	)
	(segment
		(start 122.279918 -57.590436)
		(end 122.284744 -57.5818)
		(width 0.0889)
		(layer "In11.Cu")
		(net "M_J_DQS_DP<7>")
	)
	(segment
		(start 147.929092 -1.08712)
		(end 147.929092 -0.738378)
		(width 0.14224)
		(layer "In11.Cu")
		(net "M_J_DQS_DP<7>")
	)
	(segment
		(start 122.279918 -59.171586)
		(end 122.273568 -59.160918)
		(width 0.0889)
		(layer "In11.Cu")
		(net "M_J_DQS_DP<7>")
	)
	(segment
		(start 147.441412 -1.4478)
		(end 147.619212 -1.27)
		(width 0.14224)
		(layer "In11.Cu")
		(net "M_J_DQS_DP<7>")
	)
	(segment
		(start 122.279918 -63.534036)
		(end 122.284744 -63.5254)
		(width 0.0889)
		(layer "In11.Cu")
		(net "M_J_DQS_DP<7>")
	)
	(segment
		(start 122.401838 -51.40833)
		(end 122.895868 -50.9143)
		(width 0.0889)
		(layer "In11.Cu")
		(net "M_J_DQS_DP<7>")
	)
	(segment
		(start 122.279918 -60.562236)
		(end 122.284744 -60.5536)
		(width 0.0889)
		(layer "In11.Cu")
		(net "M_J_DQS_DP<7>")
	)
	(segment
		(start 123.708668 -50.7111)
		(end 126.122938 -48.29683)
		(width 0.14224)
		(layer "In11.Cu")
		(net "M_J_DQS_DP<7>")
	)
	(segment
		(start 147.929092 -2.763774)
		(end 147.929092 -2.058924)
		(width 0.14224)
		(layer "In11.Cu")
		(net "M_J_DQS_DP<7>")
	)
	(segment
		(start 127.494538 -48.29683)
		(end 127.608838 -48.18253)
		(width 0.14224)
		(layer "In11.Cu")
		(net "M_J_DQS_DP<7>")
	)
	(segment
		(start 127.862838 -48.18253)
		(end 127.977138 -48.29683)
		(width 0.14224)
		(layer "In11.Cu")
		(net "M_J_DQS_DP<7>")
	)
	(segment
		(start 122.279918 -62.543436)
		(end 122.284744 -62.5348)
		(width 0.0889)
		(layer "In11.Cu")
		(net "M_J_DQS_DP<7>")
	)
	(segment
		(start 122.273568 -55.619904)
		(end 122.279918 -55.609236)
		(width 0.0889)
		(layer "In11.Cu")
		(net "M_J_DQS_DP<7>")
	)
	(segment
		(start 147.441412 -1.7018)
		(end 147.441412 -1.4478)
		(width 0.14224)
		(layer "In11.Cu")
		(net "M_J_DQS_DP<7>")
	)
	(segment
		(start 147.929092 0.921512)
		(end 147.66925 1.181354)
		(width 0.14224)
		(layer "In11.Cu")
		(net "M_J_DQS_DP<7>")
	)
	(segment
		(start 127.02794 -48.29683)
		(end 127.494538 -48.29683)
		(width 0.14224)
		(layer "In11.Cu")
		(net "M_J_DQS_DP<7>")
	)
	(segment
		(start 122.273568 -57.601104)
		(end 122.279918 -57.590436)
		(width 0.0889)
		(layer "In11.Cu")
		(net "M_J_DQS_DP<7>")
	)
	(segment
		(start 123.708668 -50.767234)
		(end 123.708668 -50.7111)
		(width 0.0889)
		(layer "In11.Cu")
		(net "M_J_DQS_DP<7>")
	)
	(segment
		(start 122.279918 -58.581036)
		(end 122.284744 -58.5724)
		(width 0.0889)
		(layer "In11.Cu")
		(net "M_J_DQS_DP<7>")
	)
	(segment
		(start 126.122938 -48.29683)
		(end 126.54534 -48.29683)
		(width 0.14224)
		(layer "In11.Cu")
		(net "M_J_DQS_DP<7>")
	)
	(segment
		(start 147.619212 -1.8796)
		(end 147.441412 -1.7018)
		(width 0.14224)
		(layer "In11.Cu")
		(net "M_J_DQS_DP<7>")
	)
	(segment
		(start 147.394168 -0.076454)
		(end 147.546822 0.0762)
		(width 0.14224)
		(layer "In11.Cu")
		(net "M_J_DQS_DP<7>")
	)
	(segment
		(start 127.977138 -48.29683)
		(end 129.196338 -48.29683)
		(width 0.14224)
		(layer "In11.Cu")
		(net "M_J_DQS_DP<7>")
	)
	(segment
		(start 147.929092 0.255778)
		(end 147.929092 0.921512)
		(width 0.14224)
		(layer "In11.Cu")
		(net "M_J_DQS_DP<7>")
	)
	(segment
		(start 136.624568 -41.783)
		(end 147.900644 -30.506924)
		(width 0.14224)
		(layer "In11.Cu")
		(net "M_J_DQS_DP<7>")
	)
	(segment
		(start 123.561602 -50.9143)
		(end 123.708668 -50.767234)
		(width 0.0889)
		(layer "In11.Cu")
		(net "M_J_DQS_DP<7>")
	)
	(segment
		(start 122.895868 -50.9143)
		(end 123.561602 -50.9143)
		(width 0.0889)
		(layer "In11.Cu")
		(net "M_J_DQS_DP<7>")
	)
	(segment
		(start 147.929092 -2.058924)
		(end 147.749768 -1.8796)
		(width 0.14224)
		(layer "In11.Cu")
		(net "M_J_DQS_DP<7>")
	)
	(segment
		(start 122.273568 -54.629304)
		(end 122.279918 -54.618636)
		(width 0.0889)
		(layer "In11.Cu")
		(net "M_J_DQS_DP<7>")
	)
	(segment
		(start 122.273568 -60.572904)
		(end 122.279918 -60.562236)
		(width 0.0889)
		(layer "In11.Cu")
		(net "M_J_DQS_DP<7>")
	)
	(segment
		(start 146.949668 -3.464052)
		(end 147.387564 -3.026156)
		(width 0.14224)
		(layer "In11.Cu")
		(net "M_J_DQS_DP<7>")
	)
	(segment
		(start 147.749514 0.0762)
		(end 147.929092 0.255778)
		(width 0.14224)
		(layer "In11.Cu")
		(net "M_J_DQS_DP<7>")
	)
	(segment
		(start 122.279918 -53.627782)
		(end 122.401838 -53.416962)
		(width 0.0889)
		(layer "In11.Cu")
		(net "M_J_DQS_DP<7>")
	)
	(segment
		(start 127.608838 -48.18253)
		(end 127.862838 -48.18253)
		(width 0.14224)
		(layer "In11.Cu")
		(net "M_J_DQS_DP<7>")
	)
	(segment
		(start 122.279918 -54.618636)
		(end 122.284744 -54.61)
		(width 0.0889)
		(layer "In11.Cu")
		(net "M_J_DQS_DP<7>")
	)
	(segment
		(start 122.279918 -56.599836)
		(end 122.284744 -56.5912)
		(width 0.0889)
		(layer "In11.Cu")
		(net "M_J_DQS_DP<7>")
	)
	(segment
		(start 126.54534 -48.29683)
		(end 126.65964 -48.18253)
		(width 0.14224)
		(layer "In11.Cu")
		(net "M_J_DQS_DP<7>")
	)
	(segment
		(start 122.273568 -62.554104)
		(end 122.279918 -62.543436)
		(width 0.0889)
		(layer "In11.Cu")
		(net "M_J_DQS_DP<7>")
	)
	(segment
		(start 122.279918 -55.609236)
		(end 122.284744 -55.6006)
		(width 0.0889)
		(layer "In11.Cu")
		(net "M_J_DQS_DP<7>")
	)
	(segment
		(start 122.279918 -61.552836)
		(end 122.284744 -61.5442)
		(width 0.0889)
		(layer "In11.Cu")
		(net "M_J_DQS_DP<7>")
	)
	(segment
		(start 122.273568 -63.544704)
		(end 122.279918 -63.534036)
		(width 0.0889)
		(layer "In11.Cu")
		(net "M_J_DQS_DP<7>")
	)
	(segment
		(start 121.933208 -64.662812)
		(end 121.99112 -64.720724)
		(width 0.0889)
		(layer "In11.Cu")
		(net "M_J_DQS_DP<7>")
	)
	(segment
		(start 147.66925 1.181354)
		(end 147.387564 1.181354)
		(width 0.14224)
		(layer "In11.Cu")
		(net "M_J_DQS_DP<7>")
	)
	(segment
		(start 147.746212 -1.27)
		(end 147.929092 -1.08712)
		(width 0.14224)
		(layer "In11.Cu")
		(net "M_J_DQS_DP<7>")
	)
	(segment
		(start 147.749768 -1.8796)
		(end 147.619212 -1.8796)
		(width 0.14224)
		(layer "In11.Cu")
		(net "M_J_DQS_DP<7>")
	)
	(segment
		(start 147.387564 -3.026156)
		(end 147.387564 -3.02641)
		(width 0.14224)
		(layer "In11.Cu")
		(net "M_J_DQS_DP<7>")
	)
	(segment
		(start 147.387564 -3.02641)
		(end 147.666456 -3.02641)
		(width 0.14224)
		(layer "In11.Cu")
		(net "M_J_DQS_DP<7>")
	)
	(arc
		(start 122.279918 -58.180986)
		(mid 122.200696 -57.891868)
		(end 122.273568 -57.601104)
		(width 0.0889)
		(layer "In11.Cu")
		(net "M_J_DQS_DP<7>")
	)
	(arc
		(start 122.279918 -63.133986)
		(mid 122.200696 -62.844868)
		(end 122.273568 -62.554104)
		(width 0.0889)
		(layer "In11.Cu")
		(net "M_J_DQS_DP<7>")
	)
	(arc
		(start 122.279918 -60.162186)
		(mid 122.200787 -59.866784)
		(end 122.279918 -59.571382)
		(width 0.0889)
		(layer "In11.Cu")
		(net "M_J_DQS_DP<7>")
	)
	(arc
		(start 122.279918 -55.209186)
		(mid 122.200696 -54.920068)
		(end 122.273568 -54.629304)
		(width 0.0889)
		(layer "In11.Cu")
		(net "M_J_DQS_DP<7>")
	)
	(arc
		(start 122.284744 -62.5348)
		(mid 122.333499 -62.338448)
		(end 122.279918 -62.143386)
		(width 0.0889)
		(layer "In11.Cu")
		(net "M_J_DQS_DP<7>")
	)
	(arc
		(start 122.284744 -57.5818)
		(mid 122.333499 -57.385448)
		(end 122.279918 -57.190386)
		(width 0.0889)
		(layer "In11.Cu")
		(net "M_J_DQS_DP<7>")
	)
	(arc
		(start 122.279918 -57.190386)
		(mid 122.200696 -56.901268)
		(end 122.273568 -56.610504)
		(width 0.0889)
		(layer "In11.Cu")
		(net "M_J_DQS_DP<7>")
	)
	(arc
		(start 122.284744 -56.5912)
		(mid 122.333499 -56.394848)
		(end 122.279918 -56.199786)
		(width 0.0889)
		(layer "In11.Cu")
		(net "M_J_DQS_DP<7>")
	)
	(arc
		(start 122.284744 -60.5536)
		(mid 122.333499 -60.357248)
		(end 122.279918 -60.162186)
		(width 0.0889)
		(layer "In11.Cu")
		(net "M_J_DQS_DP<7>")
	)
	(arc
		(start 122.279918 -56.199786)
		(mid 122.200696 -55.910668)
		(end 122.273568 -55.619904)
		(width 0.0889)
		(layer "In11.Cu")
		(net "M_J_DQS_DP<7>")
	)
	(arc
		(start 122.284744 -63.5254)
		(mid 122.333499 -63.329048)
		(end 122.279918 -63.133986)
		(width 0.0889)
		(layer "In11.Cu")
		(net "M_J_DQS_DP<7>")
	)
	(arc
		(start 122.279918 -64.124586)
		(mid 122.200696 -63.835468)
		(end 122.273568 -63.544704)
		(width 0.0889)
		(layer "In11.Cu")
		(net "M_J_DQS_DP<7>")
	)
	(arc
		(start 122.284744 -61.5442)
		(mid 122.333499 -61.347848)
		(end 122.279918 -61.152786)
		(width 0.0889)
		(layer "In11.Cu")
		(net "M_J_DQS_DP<7>")
	)
	(arc
		(start 122.284744 -55.6006)
		(mid 122.333499 -55.404248)
		(end 122.279918 -55.209186)
		(width 0.0889)
		(layer "In11.Cu")
		(net "M_J_DQS_DP<7>")
	)
	(arc
		(start 122.279918 -61.152786)
		(mid 122.200696 -60.863668)
		(end 122.273568 -60.572904)
		(width 0.0889)
		(layer "In11.Cu")
		(net "M_J_DQS_DP<7>")
	)
	(arc
		(start 122.279918 -54.218586)
		(mid 122.200787 -53.923184)
		(end 122.279918 -53.627782)
		(width 0.0889)
		(layer "In11.Cu")
		(net "M_J_DQS_DP<7>")
	)
	(arc
		(start 122.284744 -58.5724)
		(mid 122.333499 -58.376048)
		(end 122.279918 -58.180986)
		(width 0.0889)
		(layer "In11.Cu")
		(net "M_J_DQS_DP<7>")
	)
	(arc
		(start 121.99112 -64.720724)
		(mid 122.293389 -64.499175)
		(end 122.279918 -64.124586)
		(width 0.0889)
		(layer "In11.Cu")
		(net "M_J_DQS_DP<7>")
	)
	(arc
		(start 122.284744 -54.61)
		(mid 122.333499 -54.413648)
		(end 122.279918 -54.218586)
		(width 0.0889)
		(layer "In11.Cu")
		(net "M_J_DQS_DP<7>")
	)
	(arc
		(start 122.273568 -59.160918)
		(mid 122.20077 -58.870155)
		(end 122.279918 -58.581036)
		(width 0.0889)
		(layer "In11.Cu")
		(net "M_J_DQS_DP<7>")
	)
	(arc
		(start 122.279918 -62.143386)
		(mid 122.200696 -61.854268)
		(end 122.273568 -61.563504)
		(width 0.0889)
		(layer "In11.Cu")
		(net "M_J_DQS_DP<7>")
	)
	(arc
		(start 122.279918 -59.571382)
		(mid 122.333417 -59.371484)
		(end 122.279918 -59.171586)
		(width 0.0889)
		(layer "In11.Cu")
		(net "M_J_DQS_DP<7>")
	)
	(segment
		(start 138.507216 1.455166)
		(end 138.311382 1.455166)
		(width 0.1651)
		(layer "F.Cu")
		(net "M_J_DQS_DP<6>")
	)
	(segment
		(start 117.353842 -64.324738)
		(end 116.782342 -64.324738)
		(width 0.0889)
		(layer "F.Cu")
		(net "M_J_DQS_DP<6>")
	)
	(segment
		(start 138.721084 0.49911)
		(end 138.721084 1.241298)
		(width 0.1651)
		(layer "F.Cu")
		(net "M_J_DQS_DP<6>")
	)
	(segment
		(start 138.499342 -0.821182)
		(end 138.499342 0.277368)
		(width 0.1651)
		(layer "F.Cu")
		(net "M_J_DQS_DP<6>")
	)
	(segment
		(start 138.721084 1.241298)
		(end 138.507216 1.455166)
		(width 0.1651)
		(layer "F.Cu")
		(net "M_J_DQS_DP<6>")
	)
	(segment
		(start 138.311382 1.455166)
		(end 138.03757 1.181354)
		(width 0.1651)
		(layer "F.Cu")
		(net "M_J_DQS_DP<6>")
	)
	(segment
		(start 138.499342 0.277368)
		(end 138.721084 0.49911)
		(width 0.1651)
		(layer "F.Cu")
		(net "M_J_DQS_DP<6>")
	)
	(via
		(at 116.782342 -64.324738)
		(size 0.508)
		(drill 0.254)
		(layers "F.Cu" "B.Cu")
		(net "M_J_DQS_DP<6>")
	)
	(via
		(at 138.03757 -3.026156)
		(size 0.508)
		(drill 0.254)
		(layers "F.Cu" "B.Cu")
		(net "M_J_DQS_DP<6>")
	)
	(via
		(at 138.03757 1.181354)
		(size 0.508)
		(drill 0.254)
		(layers "F.Cu" "B.Cu")
		(net "M_J_DQS_DP<6>")
	)
	(segment
		(start 138.318494 -3.30708)
		(end 138.03757 -3.026156)
		(width 0.1651)
		(layer "B.Cu")
		(net "M_J_DQS_DP<6>")
	)
	(segment
		(start 138.679174 -3.16738)
		(end 138.539474 -3.30708)
		(width 0.1651)
		(layer "B.Cu")
		(net "M_J_DQS_DP<6>")
	)
	(segment
		(start 138.679174 -2.7178)
		(end 138.679174 -3.16738)
		(width 0.1651)
		(layer "B.Cu")
		(net "M_J_DQS_DP<6>")
	)
	(segment
		(start 138.539474 -3.30708)
		(end 138.318494 -3.30708)
		(width 0.1651)
		(layer "B.Cu")
		(net "M_J_DQS_DP<6>")
	)
	(segment
		(start 138.499342 -2.537968)
		(end 138.679174 -2.7178)
		(width 0.1651)
		(layer "B.Cu")
		(net "M_J_DQS_DP<6>")
	)
	(segment
		(start 138.499342 -1.021842)
		(end 138.499342 -2.537968)
		(width 0.1651)
		(layer "B.Cu")
		(net "M_J_DQS_DP<6>")
	)
	(segment
		(start 120.484138 -43.876468)
		(end 121.172986 -43.18762)
		(width 0.14224)
		(layer "In11.Cu")
		(net "M_J_DQS_DP<6>")
	)
	(segment
		(start 117.122702 -61.563504)
		(end 117.129052 -61.552836)
		(width 0.0889)
		(layer "In11.Cu")
		(net "M_J_DQS_DP<6>")
	)
	(segment
		(start 119.6086 -44.590462)
		(end 119.788432 -44.41063)
		(width 0.14224)
		(layer "In11.Cu")
		(net "M_J_DQS_DP<6>")
	)
	(segment
		(start 117.129052 -61.552836)
		(end 117.133878 -61.5442)
		(width 0.0889)
		(layer "In11.Cu")
		(net "M_J_DQS_DP<6>")
	)
	(segment
		(start 117.122702 -62.554104)
		(end 117.129052 -62.543436)
		(width 0.0889)
		(layer "In11.Cu")
		(net "M_J_DQS_DP<6>")
	)
	(segment
		(start 138.269218 -1.27)
		(end 138.396218 -1.27)
		(width 0.14224)
		(layer "In11.Cu")
		(net "M_J_DQS_DP<6>")
	)
	(segment
		(start 117.122702 -63.544704)
		(end 117.129052 -63.534036)
		(width 0.0889)
		(layer "In11.Cu")
		(net "M_J_DQS_DP<6>")
	)
	(segment
		(start 138.585448 -29.450792)
		(end 138.585448 -6.337046)
		(width 0.14224)
		(layer "In11.Cu")
		(net "M_J_DQS_DP<6>")
	)
	(segment
		(start 117.129052 -57.590436)
		(end 117.133878 -57.5818)
		(width 0.0889)
		(layer "In11.Cu")
		(net "M_J_DQS_DP<6>")
	)
	(segment
		(start 117.794786 -46.56582)
		(end 118.394734 -45.965872)
		(width 0.14224)
		(layer "In11.Cu")
		(net "M_J_DQS_DP<6>")
	)
	(segment
		(start 138.579098 -2.763774)
		(end 138.579098 -2.058924)
		(width 0.14224)
		(layer "In11.Cu")
		(net "M_J_DQS_DP<6>")
	)
	(segment
		(start 116.955316 -51.12131)
		(end 116.955316 -50.907696)
		(width 0.0889)
		(layer "In11.Cu")
		(net "M_J_DQS_DP<6>")
	)
	(segment
		(start 119.788432 -44.41063)
		(end 119.949976 -44.41063)
		(width 0.14224)
		(layer "In11.Cu")
		(net "M_J_DQS_DP<6>")
	)
	(segment
		(start 117.122702 -55.619904)
		(end 117.129052 -55.609236)
		(width 0.0889)
		(layer "In11.Cu")
		(net "M_J_DQS_DP<6>")
	)
	(segment
		(start 120.142762 -44.217844)
		(end 120.142762 -44.0563)
		(width 0.14224)
		(layer "In11.Cu")
		(net "M_J_DQS_DP<6>")
	)
	(segment
		(start 138.39952 0.0762)
		(end 138.579098 0.255778)
		(width 0.14224)
		(layer "In11.Cu")
		(net "M_J_DQS_DP<6>")
	)
	(segment
		(start 117.129052 -62.543436)
		(end 117.133878 -62.5348)
		(width 0.0889)
		(layer "In11.Cu")
		(net "M_J_DQS_DP<6>")
	)
	(segment
		(start 138.579098 -2.058924)
		(end 138.399774 -1.8796)
		(width 0.14224)
		(layer "In11.Cu")
		(net "M_J_DQS_DP<6>")
	)
	(segment
		(start 119.016018 -45.344588)
		(end 119.016018 -45.18279)
		(width 0.14224)
		(layer "In11.Cu")
		(net "M_J_DQS_DP<6>")
	)
	(segment
		(start 138.044174 -0.380746)
		(end 138.044174 -0.076454)
		(width 0.14224)
		(layer "In11.Cu")
		(net "M_J_DQS_DP<6>")
	)
	(segment
		(start 124.609606 -35.92068)
		(end 132.11556 -35.92068)
		(width 0.14224)
		(layer "In11.Cu")
		(net "M_J_DQS_DP<6>")
	)
	(segment
		(start 138.579098 0.921512)
		(end 138.319256 1.181354)
		(width 0.14224)
		(layer "In11.Cu")
		(net "M_J_DQS_DP<6>")
	)
	(segment
		(start 118.736364 -45.624242)
		(end 119.016018 -45.344588)
		(width 0.14224)
		(layer "In11.Cu")
		(net "M_J_DQS_DP<6>")
	)
	(segment
		(start 118.394734 -45.804074)
		(end 118.574566 -45.624242)
		(width 0.14224)
		(layer "In11.Cu")
		(net "M_J_DQS_DP<6>")
	)
	(segment
		(start 138.319256 1.181354)
		(end 138.03757 1.181354)
		(width 0.14224)
		(layer "In11.Cu")
		(net "M_J_DQS_DP<6>")
	)
	(segment
		(start 138.396218 -1.27)
		(end 138.579098 -1.08712)
		(width 0.14224)
		(layer "In11.Cu")
		(net "M_J_DQS_DP<6>")
	)
	(segment
		(start 138.03757 -3.026156)
		(end 138.03757 -3.02641)
		(width 0.14224)
		(layer "In11.Cu")
		(net "M_J_DQS_DP<6>")
	)
	(segment
		(start 116.782342 -64.662812)
		(end 116.840254 -64.720724)
		(width 0.0889)
		(layer "In11.Cu")
		(net "M_J_DQS_DP<6>")
	)
	(segment
		(start 117.129052 -56.599836)
		(end 117.133878 -56.5912)
		(width 0.0889)
		(layer "In11.Cu")
		(net "M_J_DQS_DP<6>")
	)
	(segment
		(start 138.03757 -3.02641)
		(end 138.316462 -3.02641)
		(width 0.14224)
		(layer "In11.Cu")
		(net "M_J_DQS_DP<6>")
	)
	(segment
		(start 117.122702 -56.610504)
		(end 117.129052 -56.599836)
		(width 0.0889)
		(layer "In11.Cu")
		(net "M_J_DQS_DP<6>")
	)
	(segment
		(start 119.357648 -45.002958)
		(end 119.6086 -44.752006)
		(width 0.14224)
		(layer "In11.Cu")
		(net "M_J_DQS_DP<6>")
	)
	(segment
		(start 137.592054 -3.471672)
		(end 138.03757 -3.026156)
		(width 0.14224)
		(layer "In11.Cu")
		(net "M_J_DQS_DP<6>")
	)
	(segment
		(start 138.091418 -1.7018)
		(end 138.091418 -1.4478)
		(width 0.14224)
		(layer "In11.Cu")
		(net "M_J_DQS_DP<6>")
	)
	(segment
		(start 138.091418 -1.4478)
		(end 138.269218 -1.27)
		(width 0.14224)
		(layer "In11.Cu")
		(net "M_J_DQS_DP<6>")
	)
	(segment
		(start 117.794786 -47.221902)
		(end 117.794786 -46.56582)
		(width 0.14224)
		(layer "In11.Cu")
		(net "M_J_DQS_DP<6>")
	)
	(segment
		(start 117.129052 -60.562236)
		(end 117.133878 -60.5536)
		(width 0.0889)
		(layer "In11.Cu")
		(net "M_J_DQS_DP<6>")
	)
	(segment
		(start 116.782342 -64.324738)
		(end 116.782342 -64.662812)
		(width 0.0889)
		(layer "In11.Cu")
		(net "M_J_DQS_DP<6>")
	)
	(segment
		(start 138.316462 -3.02641)
		(end 138.579098 -2.763774)
		(width 0.14224)
		(layer "In11.Cu")
		(net "M_J_DQS_DP<6>")
	)
	(segment
		(start 138.399774 -1.8796)
		(end 138.269218 -1.8796)
		(width 0.14224)
		(layer "In11.Cu")
		(net "M_J_DQS_DP<6>")
	)
	(segment
		(start 138.579098 -0.738378)
		(end 138.37412 -0.5334)
		(width 0.14224)
		(layer "In11.Cu")
		(net "M_J_DQS_DP<6>")
	)
	(segment
		(start 117.834156 -48.212502)
		(end 117.834156 -47.28337)
		(width 0.0889)
		(layer "In11.Cu")
		(net "M_J_DQS_DP<6>")
	)
	(segment
		(start 138.196828 -0.5334)
		(end 138.044174 -0.380746)
		(width 0.14224)
		(layer "In11.Cu")
		(net "M_J_DQS_DP<6>")
	)
	(segment
		(start 132.11556 -35.92068)
		(end 138.585448 -29.450792)
		(width 0.14224)
		(layer "In11.Cu")
		(net "M_J_DQS_DP<6>")
	)
	(segment
		(start 116.763292 -49.283366)
		(end 117.834156 -48.212502)
		(width 0.0889)
		(layer "In11.Cu")
		(net "M_J_DQS_DP<6>")
	)
	(segment
		(start 120.142762 -44.0563)
		(end 120.322594 -43.876468)
		(width 0.14224)
		(layer "In11.Cu")
		(net "M_J_DQS_DP<6>")
	)
	(segment
		(start 138.585448 -6.337046)
		(end 137.592054 -5.343652)
		(width 0.14224)
		(layer "In11.Cu")
		(net "M_J_DQS_DP<6>")
	)
	(segment
		(start 121.172986 -39.3573)
		(end 124.609606 -35.92068)
		(width 0.14224)
		(layer "In11.Cu")
		(net "M_J_DQS_DP<6>")
	)
	(segment
		(start 138.196828 0.0762)
		(end 138.39952 0.0762)
		(width 0.14224)
		(layer "In11.Cu")
		(net "M_J_DQS_DP<6>")
	)
	(segment
		(start 119.016018 -45.18279)
		(end 119.19585 -45.002958)
		(width 0.14224)
		(layer "In11.Cu")
		(net "M_J_DQS_DP<6>")
	)
	(segment
		(start 118.394734 -45.965872)
		(end 118.394734 -45.804074)
		(width 0.14224)
		(layer "In11.Cu")
		(net "M_J_DQS_DP<6>")
	)
	(segment
		(start 119.6086 -44.752006)
		(end 119.6086 -44.590462)
		(width 0.14224)
		(layer "In11.Cu")
		(net "M_J_DQS_DP<6>")
	)
	(segment
		(start 118.574566 -45.624242)
		(end 118.736364 -45.624242)
		(width 0.14224)
		(layer "In11.Cu")
		(net "M_J_DQS_DP<6>")
	)
	(segment
		(start 117.122702 -60.572904)
		(end 117.129052 -60.562236)
		(width 0.0889)
		(layer "In11.Cu")
		(net "M_J_DQS_DP<6>")
	)
	(segment
		(start 138.37412 -0.5334)
		(end 138.196828 -0.5334)
		(width 0.14224)
		(layer "In11.Cu")
		(net "M_J_DQS_DP<6>")
	)
	(segment
		(start 138.579098 -1.08712)
		(end 138.579098 -0.738378)
		(width 0.14224)
		(layer "In11.Cu")
		(net "M_J_DQS_DP<6>")
	)
	(segment
		(start 117.122702 -54.629304)
		(end 117.214904 -54.469792)
		(width 0.0889)
		(layer "In11.Cu")
		(net "M_J_DQS_DP<6>")
	)
	(segment
		(start 137.592054 -5.343652)
		(end 137.592054 -3.471672)
		(width 0.14224)
		(layer "In11.Cu")
		(net "M_J_DQS_DP<6>")
	)
	(segment
		(start 117.122702 -57.601104)
		(end 117.129052 -57.590436)
		(width 0.0889)
		(layer "In11.Cu")
		(net "M_J_DQS_DP<6>")
	)
	(segment
		(start 138.044174 -0.076454)
		(end 138.196828 0.0762)
		(width 0.14224)
		(layer "In11.Cu")
		(net "M_J_DQS_DP<6>")
	)
	(segment
		(start 117.091206 -51.2572)
		(end 116.955316 -51.12131)
		(width 0.0889)
		(layer "In11.Cu")
		(net "M_J_DQS_DP<6>")
	)
	(segment
		(start 138.579098 0.255778)
		(end 138.579098 0.921512)
		(width 0.14224)
		(layer "In11.Cu")
		(net "M_J_DQS_DP<6>")
	)
	(segment
		(start 119.19585 -45.002958)
		(end 119.357648 -45.002958)
		(width 0.14224)
		(layer "In11.Cu")
		(net "M_J_DQS_DP<6>")
	)
	(segment
		(start 119.949976 -44.41063)
		(end 120.142762 -44.217844)
		(width 0.14224)
		(layer "In11.Cu")
		(net "M_J_DQS_DP<6>")
	)
	(segment
		(start 116.763292 -50.523648)
		(end 116.763292 -49.283366)
		(width 0.0889)
		(layer "In11.Cu")
		(net "M_J_DQS_DP<6>")
	)
	(segment
		(start 117.091206 -54.084728)
		(end 117.091206 -51.2572)
		(width 0.0889)
		(layer "In11.Cu")
		(net "M_J_DQS_DP<6>")
	)
	(segment
		(start 117.129052 -59.171586)
		(end 117.122702 -59.160918)
		(width 0.0889)
		(layer "In11.Cu")
		(net "M_J_DQS_DP<6>")
	)
	(segment
		(start 117.214904 -54.208426)
		(end 117.091206 -54.084728)
		(width 0.0889)
		(layer "In11.Cu")
		(net "M_J_DQS_DP<6>")
	)
	(segment
		(start 117.834156 -47.28337)
		(end 117.794786 -47.244)
		(width 0.0889)
		(layer "In11.Cu")
		(net "M_J_DQS_DP<6>")
	)
	(segment
		(start 117.129052 -55.609236)
		(end 117.133878 -55.6006)
		(width 0.0889)
		(layer "In11.Cu")
		(net "M_J_DQS_DP<6>")
	)
	(segment
		(start 138.269218 -1.8796)
		(end 138.091418 -1.7018)
		(width 0.14224)
		(layer "In11.Cu")
		(net "M_J_DQS_DP<6>")
	)
	(segment
		(start 120.322594 -43.876468)
		(end 120.484138 -43.876468)
		(width 0.14224)
		(layer "In11.Cu")
		(net "M_J_DQS_DP<6>")
	)
	(segment
		(start 117.794786 -47.244)
		(end 117.794786 -47.221902)
		(width 0.0889)
		(layer "In11.Cu")
		(net "M_J_DQS_DP<6>")
	)
	(segment
		(start 117.129052 -63.534036)
		(end 117.133878 -63.5254)
		(width 0.0889)
		(layer "In11.Cu")
		(net "M_J_DQS_DP<6>")
	)
	(segment
		(start 117.214904 -54.469792)
		(end 117.214904 -54.208426)
		(width 0.0889)
		(layer "In11.Cu")
		(net "M_J_DQS_DP<6>")
	)
	(segment
		(start 116.955316 -50.907696)
		(end 116.763292 -50.523648)
		(width 0.0889)
		(layer "In11.Cu")
		(net "M_J_DQS_DP<6>")
	)
	(segment
		(start 121.172986 -43.18762)
		(end 121.172986 -39.3573)
		(width 0.14224)
		(layer "In11.Cu")
		(net "M_J_DQS_DP<6>")
	)
	(segment
		(start 117.129052 -58.581036)
		(end 117.133878 -58.5724)
		(width 0.0889)
		(layer "In11.Cu")
		(net "M_J_DQS_DP<6>")
	)
	(arc
		(start 117.129052 -63.133986)
		(mid 117.04983 -62.844868)
		(end 117.122702 -62.554104)
		(width 0.0889)
		(layer "In11.Cu")
		(net "M_J_DQS_DP<6>")
	)
	(arc
		(start 117.129052 -56.199786)
		(mid 117.04983 -55.910668)
		(end 117.122702 -55.619904)
		(width 0.0889)
		(layer "In11.Cu")
		(net "M_J_DQS_DP<6>")
	)
	(arc
		(start 117.129052 -57.190386)
		(mid 117.04983 -56.901268)
		(end 117.122702 -56.610504)
		(width 0.0889)
		(layer "In11.Cu")
		(net "M_J_DQS_DP<6>")
	)
	(arc
		(start 117.133878 -61.5442)
		(mid 117.182633 -61.347848)
		(end 117.129052 -61.152786)
		(width 0.0889)
		(layer "In11.Cu")
		(net "M_J_DQS_DP<6>")
	)
	(arc
		(start 116.840254 -64.720724)
		(mid 117.142523 -64.499175)
		(end 117.129052 -64.124586)
		(width 0.0889)
		(layer "In11.Cu")
		(net "M_J_DQS_DP<6>")
	)
	(arc
		(start 117.133878 -55.6006)
		(mid 117.182633 -55.404248)
		(end 117.129052 -55.209186)
		(width 0.0889)
		(layer "In11.Cu")
		(net "M_J_DQS_DP<6>")
	)
	(arc
		(start 117.133878 -58.5724)
		(mid 117.182633 -58.376048)
		(end 117.129052 -58.180986)
		(width 0.0889)
		(layer "In11.Cu")
		(net "M_J_DQS_DP<6>")
	)
	(arc
		(start 117.133878 -57.5818)
		(mid 117.182633 -57.385448)
		(end 117.129052 -57.190386)
		(width 0.0889)
		(layer "In11.Cu")
		(net "M_J_DQS_DP<6>")
	)
	(arc
		(start 117.133878 -62.5348)
		(mid 117.182633 -62.338448)
		(end 117.129052 -62.143386)
		(width 0.0889)
		(layer "In11.Cu")
		(net "M_J_DQS_DP<6>")
	)
	(arc
		(start 117.129052 -55.209186)
		(mid 117.04983 -54.920068)
		(end 117.122702 -54.629304)
		(width 0.0889)
		(layer "In11.Cu")
		(net "M_J_DQS_DP<6>")
	)
	(arc
		(start 117.129052 -58.180986)
		(mid 117.04983 -57.891868)
		(end 117.122702 -57.601104)
		(width 0.0889)
		(layer "In11.Cu")
		(net "M_J_DQS_DP<6>")
	)
	(arc
		(start 117.122702 -59.160918)
		(mid 117.049904 -58.870155)
		(end 117.129052 -58.581036)
		(width 0.0889)
		(layer "In11.Cu")
		(net "M_J_DQS_DP<6>")
	)
	(arc
		(start 117.129052 -60.162186)
		(mid 117.049921 -59.866784)
		(end 117.129052 -59.571382)
		(width 0.0889)
		(layer "In11.Cu")
		(net "M_J_DQS_DP<6>")
	)
	(arc
		(start 117.129052 -59.571382)
		(mid 117.182551 -59.371484)
		(end 117.129052 -59.171586)
		(width 0.0889)
		(layer "In11.Cu")
		(net "M_J_DQS_DP<6>")
	)
	(arc
		(start 117.129052 -64.124586)
		(mid 117.04983 -63.835468)
		(end 117.122702 -63.544704)
		(width 0.0889)
		(layer "In11.Cu")
		(net "M_J_DQS_DP<6>")
	)
	(arc
		(start 117.133878 -63.5254)
		(mid 117.182633 -63.329048)
		(end 117.129052 -63.133986)
		(width 0.0889)
		(layer "In11.Cu")
		(net "M_J_DQS_DP<6>")
	)
	(arc
		(start 117.129052 -61.152786)
		(mid 117.04983 -60.863668)
		(end 117.122702 -60.572904)
		(width 0.0889)
		(layer "In11.Cu")
		(net "M_J_DQS_DP<6>")
	)
	(arc
		(start 117.133878 -56.5912)
		(mid 117.182633 -56.394848)
		(end 117.129052 -56.199786)
		(width 0.0889)
		(layer "In11.Cu")
		(net "M_J_DQS_DP<6>")
	)
	(arc
		(start 117.129052 -62.143386)
		(mid 117.04983 -61.854268)
		(end 117.122702 -61.563504)
		(width 0.0889)
		(layer "In11.Cu")
		(net "M_J_DQS_DP<6>")
	)
	(arc
		(start 117.133878 -60.5536)
		(mid 117.182633 -60.357248)
		(end 117.129052 -60.162186)
		(width 0.0889)
		(layer "In11.Cu")
		(net "M_J_DQS_DP<6>")
	)
	(segment
		(start 129.157222 1.455166)
		(end 128.961388 1.455166)
		(width 0.1651)
		(layer "F.Cu")
		(net "M_J_DQS_DP<5>")
	)
	(segment
		(start 129.149348 -0.821182)
		(end 129.149348 0.277368)
		(width 0.1651)
		(layer "F.Cu")
		(net "M_J_DQS_DP<5>")
	)
	(segment
		(start 128.961388 1.455166)
		(end 128.687576 1.181354)
		(width 0.1651)
		(layer "F.Cu")
		(net "M_J_DQS_DP<5>")
	)
	(segment
		(start 114.778282 -60.857384)
		(end 114.206782 -60.857384)
		(width 0.0889)
		(layer "F.Cu")
		(net "M_J_DQS_DP<5>")
	)
	(segment
		(start 129.37109 0.49911)
		(end 129.37109 1.241298)
		(width 0.1651)
		(layer "F.Cu")
		(net "M_J_DQS_DP<5>")
	)
	(segment
		(start 129.149348 0.277368)
		(end 129.37109 0.49911)
		(width 0.1651)
		(layer "F.Cu")
		(net "M_J_DQS_DP<5>")
	)
	(segment
		(start 129.37109 1.241298)
		(end 129.157222 1.455166)
		(width 0.1651)
		(layer "F.Cu")
		(net "M_J_DQS_DP<5>")
	)
	(via
		(at 114.206782 -60.857384)
		(size 0.508)
		(drill 0.254)
		(layers "F.Cu" "B.Cu")
		(net "M_J_DQS_DP<5>")
	)
	(via
		(at 128.687576 1.181354)
		(size 0.508)
		(drill 0.254)
		(layers "F.Cu" "B.Cu")
		(net "M_J_DQS_DP<5>")
	)
	(via
		(at 128.687576 -3.026156)
		(size 0.508)
		(drill 0.254)
		(layers "F.Cu" "B.Cu")
		(net "M_J_DQS_DP<5>")
	)
	(segment
		(start 129.32918 -2.7178)
		(end 129.32918 -3.16738)
		(width 0.1651)
		(layer "B.Cu")
		(net "M_J_DQS_DP<5>")
	)
	(segment
		(start 129.149348 -1.021842)
		(end 129.149348 -2.537968)
		(width 0.1651)
		(layer "B.Cu")
		(net "M_J_DQS_DP<5>")
	)
	(segment
		(start 128.9685 -3.30708)
		(end 128.687576 -3.026156)
		(width 0.1651)
		(layer "B.Cu")
		(net "M_J_DQS_DP<5>")
	)
	(segment
		(start 129.149348 -2.537968)
		(end 129.32918 -2.7178)
		(width 0.1651)
		(layer "B.Cu")
		(net "M_J_DQS_DP<5>")
	)
	(segment
		(start 129.18948 -3.30708)
		(end 128.9685 -3.30708)
		(width 0.1651)
		(layer "B.Cu")
		(net "M_J_DQS_DP<5>")
	)
	(segment
		(start 129.32918 -3.16738)
		(end 129.18948 -3.30708)
		(width 0.1651)
		(layer "B.Cu")
		(net "M_J_DQS_DP<5>")
	)
	(segment
		(start 129.242566 -28.826714)
		(end 129.035048 -29.034232)
		(width 0.14224)
		(layer "In4.Cu")
		(net "M_J_DQS_DP<5>")
	)
	(segment
		(start 129.242566 -6.26618)
		(end 129.242566 -28.826714)
		(width 0.14224)
		(layer "In4.Cu")
		(net "M_J_DQS_DP<5>")
	)
	(segment
		(start 117.780816 -42.473118)
		(end 117.780816 -47.275496)
		(width 0.14224)
		(layer "In4.Cu")
		(net "M_J_DQS_DP<5>")
	)
	(segment
		(start 114.606832 -53.396642)
		(end 114.606832 -53.912262)
		(width 0.0889)
		(layer "In4.Cu")
		(net "M_J_DQS_DP<5>")
	)
	(segment
		(start 128.36906 -5.392674)
		(end 129.242566 -6.26618)
		(width 0.14224)
		(layer "In4.Cu")
		(net "M_J_DQS_DP<5>")
	)
	(segment
		(start 114.553492 -59.076336)
		(end 114.547142 -59.087004)
		(width 0.0889)
		(layer "In4.Cu")
		(net "M_J_DQS_DP<5>")
	)
	(segment
		(start 129.035048 -31.218886)
		(end 117.780816 -42.473118)
		(width 0.14224)
		(layer "In4.Cu")
		(net "M_J_DQS_DP<5>")
	)
	(segment
		(start 128.36906 -4.825746)
		(end 128.36906 -5.392674)
		(width 0.14224)
		(layer "In4.Cu")
		(net "M_J_DQS_DP<5>")
	)
	(segment
		(start 114.547142 -55.693818)
		(end 114.553492 -55.704486)
		(width 0.0889)
		(layer "In4.Cu")
		(net "M_J_DQS_DP<5>")
	)
	(segment
		(start 114.553492 -57.685686)
		(end 114.558318 -57.694322)
		(width 0.0889)
		(layer "In4.Cu")
		(net "M_J_DQS_DP<5>")
	)
	(segment
		(start 115.872768 -51.376326)
		(end 114.93246 -52.316634)
		(width 0.0889)
		(layer "In4.Cu")
		(net "M_J_DQS_DP<5>")
	)
	(segment
		(start 114.547142 -54.703218)
		(end 114.553492 -54.713886)
		(width 0.0889)
		(layer "In4.Cu")
		(net "M_J_DQS_DP<5>")
	)
	(segment
		(start 128.24968 -3.464052)
		(end 128.24968 -4.706366)
		(width 0.14224)
		(layer "In4.Cu")
		(net "M_J_DQS_DP<5>")
	)
	(segment
		(start 114.264694 -61.25337)
		(end 114.206782 -61.195458)
		(width 0.0889)
		(layer "In4.Cu")
		(net "M_J_DQS_DP<5>")
	)
	(segment
		(start 129.035048 -29.034232)
		(end 129.035048 -31.218886)
		(width 0.14224)
		(layer "In4.Cu")
		(net "M_J_DQS_DP<5>")
	)
	(segment
		(start 114.553492 -55.704486)
		(end 114.558318 -55.713122)
		(width 0.0889)
		(layer "In4.Cu")
		(net "M_J_DQS_DP<5>")
	)
	(segment
		(start 114.553492 -60.657486)
		(end 114.558318 -60.666122)
		(width 0.0889)
		(layer "In4.Cu")
		(net "M_J_DQS_DP<5>")
	)
	(segment
		(start 114.547142 -56.684418)
		(end 114.553492 -56.695086)
		(width 0.0889)
		(layer "In4.Cu")
		(net "M_J_DQS_DP<5>")
	)
	(segment
		(start 114.553492 -54.713886)
		(end 114.558318 -54.722522)
		(width 0.0889)
		(layer "In4.Cu")
		(net "M_J_DQS_DP<5>")
	)
	(segment
		(start 114.553492 -59.666886)
		(end 114.558318 -59.675522)
		(width 0.0889)
		(layer "In4.Cu")
		(net "M_J_DQS_DP<5>")
	)
	(segment
		(start 128.687576 -3.026156)
		(end 128.24968 -3.464052)
		(width 0.14224)
		(layer "In4.Cu")
		(net "M_J_DQS_DP<5>")
	)
	(segment
		(start 114.547142 -60.646818)
		(end 114.553492 -60.657486)
		(width 0.0889)
		(layer "In4.Cu")
		(net "M_J_DQS_DP<5>")
	)
	(segment
		(start 128.24968 -4.706366)
		(end 128.36906 -4.825746)
		(width 0.14224)
		(layer "In4.Cu")
		(net "M_J_DQS_DP<5>")
	)
	(segment
		(start 114.553492 -56.695086)
		(end 114.558318 -56.703722)
		(width 0.0889)
		(layer "In4.Cu")
		(net "M_J_DQS_DP<5>")
	)
	(segment
		(start 114.93246 -53.071014)
		(end 114.606832 -53.396642)
		(width 0.0889)
		(layer "In4.Cu")
		(net "M_J_DQS_DP<5>")
	)
	(segment
		(start 117.780816 -47.275496)
		(end 117.780816 -47.297594)
		(width 0.0889)
		(layer "In4.Cu")
		(net "M_J_DQS_DP<5>")
	)
	(segment
		(start 114.547142 -57.675018)
		(end 114.553492 -57.685686)
		(width 0.0889)
		(layer "In4.Cu")
		(net "M_J_DQS_DP<5>")
	)
	(segment
		(start 115.872768 -50.665126)
		(end 115.872768 -51.376326)
		(width 0.0889)
		(layer "In4.Cu")
		(net "M_J_DQS_DP<5>")
	)
	(segment
		(start 114.93246 -52.316634)
		(end 114.93246 -53.071014)
		(width 0.0889)
		(layer "In4.Cu")
		(net "M_J_DQS_DP<5>")
	)
	(segment
		(start 117.780816 -47.297594)
		(end 117.820186 -47.336964)
		(width 0.0889)
		(layer "In4.Cu")
		(net "M_J_DQS_DP<5>")
	)
	(segment
		(start 117.820186 -48.717708)
		(end 115.872768 -50.665126)
		(width 0.0889)
		(layer "In4.Cu")
		(net "M_J_DQS_DP<5>")
	)
	(segment
		(start 114.206782 -61.195458)
		(end 114.206782 -60.857384)
		(width 0.0889)
		(layer "In4.Cu")
		(net "M_J_DQS_DP<5>")
	)
	(segment
		(start 117.820186 -47.336964)
		(end 117.820186 -48.717708)
		(width 0.0889)
		(layer "In4.Cu")
		(net "M_J_DQS_DP<5>")
	)
	(arc
		(start 114.553492 -57.095136)
		(mid 114.47427 -57.384254)
		(end 114.547142 -57.675018)
		(width 0.0889)
		(layer "In4.Cu")
		(net "M_J_DQS_DP<5>")
	)
	(arc
		(start 114.558318 -55.713122)
		(mid 114.607073 -55.909474)
		(end 114.553492 -56.104536)
		(width 0.0889)
		(layer "In4.Cu")
		(net "M_J_DQS_DP<5>")
	)
	(arc
		(start 114.553238 -61.057536)
		(mid 114.431431 -61.188574)
		(end 114.264694 -61.25337)
		(width 0.0889)
		(layer "In4.Cu")
		(net "M_J_DQS_DP<5>")
	)
	(arc
		(start 114.558318 -57.694322)
		(mid 114.607073 -57.890674)
		(end 114.553492 -58.085736)
		(width 0.0889)
		(layer "In4.Cu")
		(net "M_J_DQS_DP<5>")
	)
	(arc
		(start 114.553492 -54.123336)
		(mid 114.47427 -54.412454)
		(end 114.547142 -54.703218)
		(width 0.0889)
		(layer "In4.Cu")
		(net "M_J_DQS_DP<5>")
	)
	(arc
		(start 114.553492 -56.104536)
		(mid 114.47427 -56.393654)
		(end 114.547142 -56.684418)
		(width 0.0889)
		(layer "In4.Cu")
		(net "M_J_DQS_DP<5>")
	)
	(arc
		(start 114.553492 -58.67654)
		(mid 114.606991 -58.876438)
		(end 114.553492 -59.076336)
		(width 0.0889)
		(layer "In4.Cu")
		(net "M_J_DQS_DP<5>")
	)
	(arc
		(start 114.558318 -59.675522)
		(mid 114.607073 -59.871874)
		(end 114.553492 -60.066936)
		(width 0.0889)
		(layer "In4.Cu")
		(net "M_J_DQS_DP<5>")
	)
	(arc
		(start 114.558318 -56.703722)
		(mid 114.607073 -56.900074)
		(end 114.553492 -57.095136)
		(width 0.0889)
		(layer "In4.Cu")
		(net "M_J_DQS_DP<5>")
	)
	(arc
		(start 114.547142 -59.087004)
		(mid 114.474344 -59.377767)
		(end 114.553492 -59.666886)
		(width 0.0889)
		(layer "In4.Cu")
		(net "M_J_DQS_DP<5>")
	)
	(arc
		(start 114.558318 -54.722522)
		(mid 114.607073 -54.918874)
		(end 114.553492 -55.113936)
		(width 0.0889)
		(layer "In4.Cu")
		(net "M_J_DQS_DP<5>")
	)
	(arc
		(start 114.558318 -60.666122)
		(mid 114.606948 -60.862504)
		(end 114.553238 -61.057536)
		(width 0.0889)
		(layer "In4.Cu")
		(net "M_J_DQS_DP<5>")
	)
	(arc
		(start 114.606832 -53.912262)
		(mid 114.594789 -54.021495)
		(end 114.553492 -54.123336)
		(width 0.0889)
		(layer "In4.Cu")
		(net "M_J_DQS_DP<5>")
	)
	(arc
		(start 114.553492 -55.113936)
		(mid 114.47427 -55.403054)
		(end 114.547142 -55.693818)
		(width 0.0889)
		(layer "In4.Cu")
		(net "M_J_DQS_DP<5>")
	)
	(arc
		(start 114.553492 -60.066936)
		(mid 114.47427 -60.356054)
		(end 114.547142 -60.646818)
		(width 0.0889)
		(layer "In4.Cu")
		(net "M_J_DQS_DP<5>")
	)
	(arc
		(start 114.553492 -58.085736)
		(mid 114.474361 -58.381138)
		(end 114.553492 -58.67654)
		(width 0.0889)
		(layer "In4.Cu")
		(net "M_J_DQS_DP<5>")
	)
	(segment
		(start 129.229104 -2.763774)
		(end 129.229104 -2.058924)
		(width 0.14224)
		(layer "In11.Cu")
		(net "M_J_DQS_DP<5>")
	)
	(segment
		(start 128.846834 0.0762)
		(end 129.049526 0.0762)
		(width 0.14224)
		(layer "In11.Cu")
		(net "M_J_DQS_DP<5>")
	)
	(segment
		(start 129.229104 -2.058924)
		(end 129.04978 -1.8796)
		(width 0.14224)
		(layer "In11.Cu")
		(net "M_J_DQS_DP<5>")
	)
	(segment
		(start 129.229104 0.255778)
		(end 129.229104 0.921512)
		(width 0.14224)
		(layer "In11.Cu")
		(net "M_J_DQS_DP<5>")
	)
	(segment
		(start 128.919224 -1.8796)
		(end 128.741424 -1.7018)
		(width 0.14224)
		(layer "In11.Cu")
		(net "M_J_DQS_DP<5>")
	)
	(segment
		(start 128.687576 -3.026156)
		(end 128.687576 -3.02641)
		(width 0.14224)
		(layer "In11.Cu")
		(net "M_J_DQS_DP<5>")
	)
	(segment
		(start 129.049526 0.0762)
		(end 129.229104 0.255778)
		(width 0.14224)
		(layer "In11.Cu")
		(net "M_J_DQS_DP<5>")
	)
	(segment
		(start 128.69418 -0.076454)
		(end 128.846834 0.0762)
		(width 0.14224)
		(layer "In11.Cu")
		(net "M_J_DQS_DP<5>")
	)
	(segment
		(start 128.741424 -1.4478)
		(end 128.919224 -1.27)
		(width 0.14224)
		(layer "In11.Cu")
		(net "M_J_DQS_DP<5>")
	)
	(segment
		(start 128.919224 -1.27)
		(end 129.046224 -1.27)
		(width 0.14224)
		(layer "In11.Cu")
		(net "M_J_DQS_DP<5>")
	)
	(segment
		(start 129.229104 -1.08712)
		(end 129.229104 -0.738378)
		(width 0.14224)
		(layer "In11.Cu")
		(net "M_J_DQS_DP<5>")
	)
	(segment
		(start 129.229104 0.921512)
		(end 128.969262 1.181354)
		(width 0.14224)
		(layer "In11.Cu")
		(net "M_J_DQS_DP<5>")
	)
	(segment
		(start 129.024126 -0.5334)
		(end 128.846834 -0.5334)
		(width 0.14224)
		(layer "In11.Cu")
		(net "M_J_DQS_DP<5>")
	)
	(segment
		(start 128.966468 -3.02641)
		(end 129.229104 -2.763774)
		(width 0.14224)
		(layer "In11.Cu")
		(net "M_J_DQS_DP<5>")
	)
	(segment
		(start 128.969262 1.181354)
		(end 128.687576 1.181354)
		(width 0.14224)
		(layer "In11.Cu")
		(net "M_J_DQS_DP<5>")
	)
	(segment
		(start 128.69418 -0.380746)
		(end 128.69418 -0.076454)
		(width 0.14224)
		(layer "In11.Cu")
		(net "M_J_DQS_DP<5>")
	)
	(segment
		(start 129.229104 -0.738378)
		(end 129.024126 -0.5334)
		(width 0.14224)
		(layer "In11.Cu")
		(net "M_J_DQS_DP<5>")
	)
	(segment
		(start 129.04978 -1.8796)
		(end 128.919224 -1.8796)
		(width 0.14224)
		(layer "In11.Cu")
		(net "M_J_DQS_DP<5>")
	)
	(segment
		(start 128.846834 -0.5334)
		(end 128.69418 -0.380746)
		(width 0.14224)
		(layer "In11.Cu")
		(net "M_J_DQS_DP<5>")
	)
	(segment
		(start 129.046224 -1.27)
		(end 129.229104 -1.08712)
		(width 0.14224)
		(layer "In11.Cu")
		(net "M_J_DQS_DP<5>")
	)
	(segment
		(start 128.687576 -3.02641)
		(end 128.966468 -3.02641)
		(width 0.14224)
		(layer "In11.Cu")
		(net "M_J_DQS_DP<5>")
	)
	(segment
		(start 128.741424 -1.7018)
		(end 128.741424 -1.4478)
		(width 0.14224)
		(layer "In11.Cu")
		(net "M_J_DQS_DP<5>")
	)
	(segment
		(start 119.7991 0.277368)
		(end 120.020842 0.49911)
		(width 0.1651)
		(layer "F.Cu")
		(net "M_J_DQS_DP<4>")
	)
	(segment
		(start 109.627416 -60.857384)
		(end 109.055916 -60.857384)
		(width 0.0889)
		(layer "F.Cu")
		(net "M_J_DQS_DP<4>")
	)
	(segment
		(start 119.799354 -0.821182)
		(end 119.7991 -0.820928)
		(width 0.1651)
		(layer "F.Cu")
		(net "M_J_DQS_DP<4>")
	)
	(segment
		(start 119.7991 -0.820928)
		(end 119.7991 0.277368)
		(width 0.1651)
		(layer "F.Cu")
		(net "M_J_DQS_DP<4>")
	)
	(segment
		(start 120.020842 1.241298)
		(end 119.806974 1.455166)
		(width 0.1651)
		(layer "F.Cu")
		(net "M_J_DQS_DP<4>")
	)
	(segment
		(start 119.61114 1.455166)
		(end 119.337328 1.181354)
		(width 0.1651)
		(layer "F.Cu")
		(net "M_J_DQS_DP<4>")
	)
	(segment
		(start 119.806974 1.455166)
		(end 119.61114 1.455166)
		(width 0.1651)
		(layer "F.Cu")
		(net "M_J_DQS_DP<4>")
	)
	(segment
		(start 120.020842 0.49911)
		(end 120.020842 1.241298)
		(width 0.1651)
		(layer "F.Cu")
		(net "M_J_DQS_DP<4>")
	)
	(via
		(at 119.337328 1.181354)
		(size 0.508)
		(drill 0.254)
		(layers "F.Cu" "B.Cu")
		(net "M_J_DQS_DP<4>")
	)
	(via
		(at 119.337328 -3.026156)
		(size 0.508)
		(drill 0.254)
		(layers "F.Cu" "B.Cu")
		(net "M_J_DQS_DP<4>")
	)
	(via
		(at 109.055916 -60.857384)
		(size 0.508)
		(drill 0.254)
		(layers "F.Cu" "B.Cu")
		(net "M_J_DQS_DP<4>")
	)
	(segment
		(start 119.978932 -2.7178)
		(end 119.978932 -3.16738)
		(width 0.1651)
		(layer "B.Cu")
		(net "M_J_DQS_DP<4>")
	)
	(segment
		(start 119.618252 -3.30708)
		(end 119.337328 -3.026156)
		(width 0.1651)
		(layer "B.Cu")
		(net "M_J_DQS_DP<4>")
	)
	(segment
		(start 119.7991 -1.021842)
		(end 119.7991 -2.537968)
		(width 0.1651)
		(layer "B.Cu")
		(net "M_J_DQS_DP<4>")
	)
	(segment
		(start 119.799354 -1.021842)
		(end 119.7991 -1.021842)
		(width 0.1651)
		(layer "B.Cu")
		(net "M_J_DQS_DP<4>")
	)
	(segment
		(start 119.978932 -3.16738)
		(end 119.839232 -3.30708)
		(width 0.1651)
		(layer "B.Cu")
		(net "M_J_DQS_DP<4>")
	)
	(segment
		(start 119.839232 -3.30708)
		(end 119.618252 -3.30708)
		(width 0.1651)
		(layer "B.Cu")
		(net "M_J_DQS_DP<4>")
	)
	(segment
		(start 119.7991 -2.537968)
		(end 119.978932 -2.7178)
		(width 0.1651)
		(layer "B.Cu")
		(net "M_J_DQS_DP<4>")
	)
	(segment
		(start 119.391176 -1.7018)
		(end 119.391176 -1.4478)
		(width 0.14224)
		(layer "In11.Cu")
		(net "M_J_DQS_DP<4>")
	)
	(segment
		(start 110.276132 -43.74134)
		(end 110.390432 -43.62704)
		(width 0.14224)
		(layer "In11.Cu")
		(net "M_J_DQS_DP<4>")
	)
	(segment
		(start 109.402372 -60.657486)
		(end 109.393482 -60.642246)
		(width 0.0889)
		(layer "In11.Cu")
		(net "M_J_DQS_DP<4>")
	)
	(segment
		(start 109.511846 -52.941982)
		(end 109.511846 -52.461922)
		(width 0.0889)
		(layer "In11.Cu")
		(net "M_J_DQS_DP<4>")
	)
	(segment
		(start 110.276132 -44.756578)
		(end 110.390432 -44.642278)
		(width 0.14224)
		(layer "In11.Cu")
		(net "M_J_DQS_DP<4>")
	)
	(segment
		(start 119.391176 -1.4478)
		(end 119.568976 -1.27)
		(width 0.14224)
		(layer "In11.Cu")
		(net "M_J_DQS_DP<4>")
	)
	(segment
		(start 109.055916 -60.857384)
		(end 109.055916 -61.195458)
		(width 0.0889)
		(layer "In11.Cu")
		(net "M_J_DQS_DP<4>")
	)
	(segment
		(start 110.219998 -47.348902)
		(end 110.219998 -46.783244)
		(width 0.14224)
		(layer "In11.Cu")
		(net "M_J_DQS_DP<4>")
	)
	(segment
		(start 119.61622 -3.02641)
		(end 119.878856 -2.763774)
		(width 0.14224)
		(layer "In11.Cu")
		(net "M_J_DQS_DP<4>")
	)
	(segment
		(start 110.259368 -48.140366)
		(end 110.259368 -47.41037)
		(width 0.0889)
		(layer "In11.Cu")
		(net "M_J_DQS_DP<4>")
	)
	(segment
		(start 119.496586 0.0762)
		(end 119.699278 0.0762)
		(width 0.14224)
		(layer "In11.Cu")
		(net "M_J_DQS_DP<4>")
	)
	(segment
		(start 119.878856 -2.763774)
		(end 119.878856 -2.058924)
		(width 0.14224)
		(layer "In11.Cu")
		(net "M_J_DQS_DP<4>")
	)
	(segment
		(start 119.863616 -30.090618)
		(end 119.863616 -6.237478)
		(width 0.14224)
		(layer "In11.Cu")
		(net "M_J_DQS_DP<4>")
	)
	(segment
		(start 118.899432 -3.464052)
		(end 119.337328 -3.026156)
		(width 0.14224)
		(layer "In11.Cu")
		(net "M_J_DQS_DP<4>")
	)
	(segment
		(start 119.337328 -3.02641)
		(end 119.61622 -3.02641)
		(width 0.14224)
		(layer "In11.Cu")
		(net "M_J_DQS_DP<4>")
	)
	(segment
		(start 119.568976 -1.27)
		(end 119.695976 -1.27)
		(width 0.14224)
		(layer "In11.Cu")
		(net "M_J_DQS_DP<4>")
	)
	(segment
		(start 110.276132 -42.76725)
		(end 110.390432 -42.65295)
		(width 0.14224)
		(layer "In11.Cu")
		(net "M_J_DQS_DP<4>")
	)
	(segment
		(start 110.390432 -44.10964)
		(end 110.276132 -43.99534)
		(width 0.14224)
		(layer "In11.Cu")
		(net "M_J_DQS_DP<4>")
	)
	(segment
		(start 118.899432 -4.627118)
		(end 118.899432 -3.464052)
		(width 0.14224)
		(layer "In11.Cu")
		(net "M_J_DQS_DP<4>")
	)
	(segment
		(start 110.259368 -47.41037)
		(end 110.219998 -47.371)
		(width 0.0889)
		(layer "In11.Cu")
		(net "M_J_DQS_DP<4>")
	)
	(segment
		(start 119.863616 -6.237478)
		(end 119.018812 -5.392674)
		(width 0.14224)
		(layer "In11.Cu")
		(net "M_J_DQS_DP<4>")
	)
	(segment
		(start 110.390432 -46.61281)
		(end 110.390432 -46.214538)
		(width 0.14224)
		(layer "In11.Cu")
		(net "M_J_DQS_DP<4>")
	)
	(segment
		(start 119.343932 -0.076454)
		(end 119.496586 0.0762)
		(width 0.14224)
		(layer "In11.Cu")
		(net "M_J_DQS_DP<4>")
	)
	(segment
		(start 110.219998 -47.371)
		(end 110.219998 -47.348902)
		(width 0.0889)
		(layer "In11.Cu")
		(net "M_J_DQS_DP<4>")
	)
	(segment
		(start 109.402372 -54.123336)
		(end 109.407198 -54.1147)
		(width 0.0889)
		(layer "In11.Cu")
		(net "M_J_DQS_DP<4>")
	)
	(segment
		(start 110.390432 -45.731938)
		(end 110.390432 -45.124878)
		(width 0.14224)
		(layer "In11.Cu")
		(net "M_J_DQS_DP<4>")
	)
	(segment
		(start 119.337328 -3.026156)
		(end 119.337328 -3.02641)
		(width 0.14224)
		(layer "In11.Cu")
		(net "M_J_DQS_DP<4>")
	)
	(segment
		(start 110.390432 -43.13555)
		(end 110.276132 -43.02125)
		(width 0.14224)
		(layer "In11.Cu")
		(net "M_J_DQS_DP<4>")
	)
	(segment
		(start 119.878856 -0.738378)
		(end 119.673878 -0.5334)
		(width 0.14224)
		(layer "In11.Cu")
		(net "M_J_DQS_DP<4>")
	)
	(segment
		(start 109.80674 -48.592994)
		(end 110.259368 -48.140366)
		(width 0.0889)
		(layer "In11.Cu")
		(net "M_J_DQS_DP<4>")
	)
	(segment
		(start 109.80674 -52.167028)
		(end 109.80674 -48.592994)
		(width 0.0889)
		(layer "In11.Cu")
		(net "M_J_DQS_DP<4>")
	)
	(segment
		(start 110.276132 -43.99534)
		(end 110.276132 -43.74134)
		(width 0.14224)
		(layer "In11.Cu")
		(net "M_J_DQS_DP<4>")
	)
	(segment
		(start 110.219998 -46.783244)
		(end 110.390432 -46.61281)
		(width 0.14224)
		(layer "In11.Cu")
		(net "M_J_DQS_DP<4>")
	)
	(segment
		(start 119.018812 -4.746498)
		(end 118.899432 -4.627118)
		(width 0.14224)
		(layer "In11.Cu")
		(net "M_J_DQS_DP<4>")
	)
	(segment
		(start 119.619014 1.181354)
		(end 119.337328 1.181354)
		(width 0.14224)
		(layer "In11.Cu")
		(net "M_J_DQS_DP<4>")
	)
	(segment
		(start 109.402372 -56.695086)
		(end 109.393482 -56.679846)
		(width 0.0889)
		(layer "In11.Cu")
		(net "M_J_DQS_DP<4>")
	)
	(segment
		(start 119.878856 -2.058924)
		(end 119.699532 -1.8796)
		(width 0.14224)
		(layer "In11.Cu")
		(net "M_J_DQS_DP<4>")
	)
	(segment
		(start 119.699532 -1.8796)
		(end 119.568976 -1.8796)
		(width 0.14224)
		(layer "In11.Cu")
		(net "M_J_DQS_DP<4>")
	)
	(segment
		(start 119.018812 -5.392674)
		(end 119.018812 -4.746498)
		(width 0.14224)
		(layer "In11.Cu")
		(net "M_J_DQS_DP<4>")
	)
	(segment
		(start 110.276132 -43.02125)
		(end 110.276132 -42.76725)
		(width 0.14224)
		(layer "In11.Cu")
		(net "M_J_DQS_DP<4>")
	)
	(segment
		(start 109.402372 -54.713886)
		(end 109.396022 -54.703218)
		(width 0.0889)
		(layer "In11.Cu")
		(net "M_J_DQS_DP<4>")
	)
	(segment
		(start 109.511846 -52.461922)
		(end 109.80674 -52.167028)
		(width 0.0889)
		(layer "In11.Cu")
		(net "M_J_DQS_DP<4>")
	)
	(segment
		(start 110.390432 -42.65295)
		(end 110.390432 -39.563802)
		(width 0.14224)
		(layer "In11.Cu")
		(net "M_J_DQS_DP<4>")
	)
	(segment
		(start 110.276132 -45.846238)
		(end 110.390432 -45.731938)
		(width 0.14224)
		(layer "In11.Cu")
		(net "M_J_DQS_DP<4>")
	)
	(segment
		(start 110.390432 -44.642278)
		(end 110.390432 -44.10964)
		(width 0.14224)
		(layer "In11.Cu")
		(net "M_J_DQS_DP<4>")
	)
	(segment
		(start 119.673878 -0.5334)
		(end 119.496586 -0.5334)
		(width 0.14224)
		(layer "In11.Cu")
		(net "M_J_DQS_DP<4>")
	)
	(segment
		(start 110.390432 -39.563802)
		(end 119.863616 -30.090618)
		(width 0.14224)
		(layer "In11.Cu")
		(net "M_J_DQS_DP<4>")
	)
	(segment
		(start 109.402372 -58.67654)
		(end 109.396022 -58.665872)
		(width 0.0889)
		(layer "In11.Cu")
		(net "M_J_DQS_DP<4>")
	)
	(segment
		(start 110.390432 -43.62704)
		(end 110.390432 -43.13555)
		(width 0.14224)
		(layer "In11.Cu")
		(net "M_J_DQS_DP<4>")
	)
	(segment
		(start 109.402372 -55.704486)
		(end 109.393482 -55.689246)
		(width 0.0889)
		(layer "In11.Cu")
		(net "M_J_DQS_DP<4>")
	)
	(segment
		(start 110.390432 -46.214538)
		(end 110.276132 -46.100238)
		(width 0.14224)
		(layer "In11.Cu")
		(net "M_J_DQS_DP<4>")
	)
	(segment
		(start 119.878856 0.921512)
		(end 119.619014 1.181354)
		(width 0.14224)
		(layer "In11.Cu")
		(net "M_J_DQS_DP<4>")
	)
	(segment
		(start 119.878856 -1.08712)
		(end 119.878856 -0.738378)
		(width 0.14224)
		(layer "In11.Cu")
		(net "M_J_DQS_DP<4>")
	)
	(segment
		(start 119.695976 -1.27)
		(end 119.878856 -1.08712)
		(width 0.14224)
		(layer "In11.Cu")
		(net "M_J_DQS_DP<4>")
	)
	(segment
		(start 109.055916 -61.195458)
		(end 109.113574 -61.253116)
		(width 0.0889)
		(layer "In11.Cu")
		(net "M_J_DQS_DP<4>")
	)
	(segment
		(start 109.402372 -57.685686)
		(end 109.393482 -57.670446)
		(width 0.0889)
		(layer "In11.Cu")
		(net "M_J_DQS_DP<4>")
	)
	(segment
		(start 119.343932 -0.380746)
		(end 119.343932 -0.076454)
		(width 0.14224)
		(layer "In11.Cu")
		(net "M_J_DQS_DP<4>")
	)
	(segment
		(start 119.568976 -1.8796)
		(end 119.391176 -1.7018)
		(width 0.14224)
		(layer "In11.Cu")
		(net "M_J_DQS_DP<4>")
	)
	(segment
		(start 109.396022 -59.087004)
		(end 109.402372 -59.076336)
		(width 0.0889)
		(layer "In11.Cu")
		(net "M_J_DQS_DP<4>")
	)
	(segment
		(start 119.699278 0.0762)
		(end 119.878856 0.255778)
		(width 0.14224)
		(layer "In11.Cu")
		(net "M_J_DQS_DP<4>")
	)
	(segment
		(start 110.390432 -45.124878)
		(end 110.276132 -45.010578)
		(width 0.14224)
		(layer "In11.Cu")
		(net "M_J_DQS_DP<4>")
	)
	(segment
		(start 109.393482 -53.146706)
		(end 109.511846 -52.941982)
		(width 0.0889)
		(layer "In11.Cu")
		(net "M_J_DQS_DP<4>")
	)
	(segment
		(start 119.496586 -0.5334)
		(end 119.343932 -0.380746)
		(width 0.14224)
		(layer "In11.Cu")
		(net "M_J_DQS_DP<4>")
	)
	(segment
		(start 110.276132 -46.100238)
		(end 110.276132 -45.846238)
		(width 0.14224)
		(layer "In11.Cu")
		(net "M_J_DQS_DP<4>")
	)
	(segment
		(start 110.276132 -45.010578)
		(end 110.276132 -44.756578)
		(width 0.14224)
		(layer "In11.Cu")
		(net "M_J_DQS_DP<4>")
	)
	(segment
		(start 119.878856 0.255778)
		(end 119.878856 0.921512)
		(width 0.14224)
		(layer "In11.Cu")
		(net "M_J_DQS_DP<4>")
	)
	(arc
		(start 109.407198 -54.1147)
		(mid 109.456074 -53.918094)
		(end 109.402372 -53.722778)
		(width 0.0889)
		(layer "In11.Cu")
		(net "M_J_DQS_DP<4>")
	)
	(arc
		(start 109.402372 -59.666886)
		(mid 109.32315 -59.377768)
		(end 109.396022 -59.087004)
		(width 0.0889)
		(layer "In11.Cu")
		(net "M_J_DQS_DP<4>")
	)
	(arc
		(start 109.113574 -61.253116)
		(mid 109.415771 -61.031834)
		(end 109.402372 -60.657486)
		(width 0.0889)
		(layer "In11.Cu")
		(net "M_J_DQS_DP<4>")
	)
	(arc
		(start 109.396022 -54.703218)
		(mid 109.323224 -54.412455)
		(end 109.402372 -54.123336)
		(width 0.0889)
		(layer "In11.Cu")
		(net "M_J_DQS_DP<4>")
	)
	(arc
		(start 109.402372 -55.113682)
		(mid 109.455905 -54.913784)
		(end 109.402372 -54.713886)
		(width 0.0889)
		(layer "In11.Cu")
		(net "M_J_DQS_DP<4>")
	)
	(arc
		(start 109.402372 -57.094882)
		(mid 109.455905 -56.894984)
		(end 109.402372 -56.695086)
		(width 0.0889)
		(layer "In11.Cu")
		(net "M_J_DQS_DP<4>")
	)
	(arc
		(start 109.402372 -58.085482)
		(mid 109.455905 -57.885584)
		(end 109.402372 -57.685686)
		(width 0.0889)
		(layer "In11.Cu")
		(net "M_J_DQS_DP<4>")
	)
	(arc
		(start 109.393482 -57.670446)
		(mid 109.323085 -57.381495)
		(end 109.402372 -57.094882)
		(width 0.0889)
		(layer "In11.Cu")
		(net "M_J_DQS_DP<4>")
	)
	(arc
		(start 109.396022 -58.665872)
		(mid 109.323102 -58.374855)
		(end 109.402372 -58.085482)
		(width 0.0889)
		(layer "In11.Cu")
		(net "M_J_DQS_DP<4>")
	)
	(arc
		(start 109.402372 -56.104282)
		(mid 109.455905 -55.904384)
		(end 109.402372 -55.704486)
		(width 0.0889)
		(layer "In11.Cu")
		(net "M_J_DQS_DP<4>")
	)
	(arc
		(start 109.402372 -59.076336)
		(mid 109.455905 -58.876438)
		(end 109.402372 -58.67654)
		(width 0.0889)
		(layer "In11.Cu")
		(net "M_J_DQS_DP<4>")
	)
	(arc
		(start 109.393482 -60.642246)
		(mid 109.323085 -60.353295)
		(end 109.402372 -60.066682)
		(width 0.0889)
		(layer "In11.Cu")
		(net "M_J_DQS_DP<4>")
	)
	(arc
		(start 109.393482 -55.689246)
		(mid 109.323085 -55.400295)
		(end 109.402372 -55.113682)
		(width 0.0889)
		(layer "In11.Cu")
		(net "M_J_DQS_DP<4>")
	)
	(arc
		(start 109.402372 -60.066682)
		(mid 109.455905 -59.866784)
		(end 109.402372 -59.666886)
		(width 0.0889)
		(layer "In11.Cu")
		(net "M_J_DQS_DP<4>")
	)
	(arc
		(start 109.402372 -53.722778)
		(mid 109.323056 -53.435909)
		(end 109.393482 -53.146706)
		(width 0.0889)
		(layer "In11.Cu")
		(net "M_J_DQS_DP<4>")
	)
	(arc
		(start 109.393482 -56.679846)
		(mid 109.323085 -56.390895)
		(end 109.402372 -56.104282)
		(width 0.0889)
		(layer "In11.Cu")
		(net "M_J_DQS_DP<4>")
	)
	(segment
		(start 64.771016 0.49911)
		(end 64.771016 1.241298)
		(width 0.1651)
		(layer "F.Cu")
		(net "M_J_DQS_DP<3>")
	)
	(segment
		(start 64.771016 1.241298)
		(end 64.557148 1.455166)
		(width 0.1651)
		(layer "F.Cu")
		(net "M_J_DQS_DP<3>")
	)
	(segment
		(start 64.549528 0.277622)
		(end 64.771016 0.49911)
		(width 0.1651)
		(layer "F.Cu")
		(net "M_J_DQS_DP<3>")
	)
	(segment
		(start 64.361314 1.455166)
		(end 64.087502 1.181354)
		(width 0.1651)
		(layer "F.Cu")
		(net "M_J_DQS_DP<3>")
	)
	(segment
		(start 64.557148 1.455166)
		(end 64.361314 1.455166)
		(width 0.1651)
		(layer "F.Cu")
		(net "M_J_DQS_DP<3>")
	)
	(segment
		(start 84.919312 -66.48704)
		(end 84.347812 -66.48704)
		(width 0.1016)
		(layer "F.Cu")
		(net "M_J_DQS_DP<3>")
	)
	(segment
		(start 64.549528 -0.821182)
		(end 64.549528 0.277622)
		(width 0.1651)
		(layer "F.Cu")
		(net "M_J_DQS_DP<3>")
	)
	(via
		(at 64.087502 1.181354)
		(size 0.508)
		(drill 0.254)
		(layers "F.Cu" "B.Cu")
		(net "M_J_DQS_DP<3>")
	)
	(via
		(at 84.347812 -66.48704)
		(size 0.508)
		(drill 0.254)
		(layers "F.Cu" "B.Cu")
		(net "M_J_DQS_DP<3>")
	)
	(via
		(at 64.087502 -3.026156)
		(size 0.508)
		(drill 0.254)
		(layers "F.Cu" "B.Cu")
		(net "M_J_DQS_DP<3>")
	)
	(segment
		(start 64.589406 -3.30708)
		(end 64.368426 -3.30708)
		(width 0.1651)
		(layer "B.Cu")
		(net "M_J_DQS_DP<3>")
	)
	(segment
		(start 64.729106 -3.16738)
		(end 64.589406 -3.30708)
		(width 0.1651)
		(layer "B.Cu")
		(net "M_J_DQS_DP<3>")
	)
	(segment
		(start 64.549528 -1.021842)
		(end 64.549528 -2.538222)
		(width 0.1651)
		(layer "B.Cu")
		(net "M_J_DQS_DP<3>")
	)
	(segment
		(start 64.549528 -2.538222)
		(end 64.729106 -2.7178)
		(width 0.1651)
		(layer "B.Cu")
		(net "M_J_DQS_DP<3>")
	)
	(segment
		(start 64.368426 -3.30708)
		(end 64.087502 -3.026156)
		(width 0.1651)
		(layer "B.Cu")
		(net "M_J_DQS_DP<3>")
	)
	(segment
		(start 64.729106 -2.7178)
		(end 64.729106 -3.16738)
		(width 0.1651)
		(layer "B.Cu")
		(net "M_J_DQS_DP<3>")
	)
	(segment
		(start 83.928204 -52.935886)
		(end 83.928204 -54.188106)
		(width 0.0889)
		(layer "In11.Cu")
		(net "M_J_DQS_DP<3>")
	)
	(segment
		(start 64.62903 0.255778)
		(end 64.449452 0.0762)
		(width 0.14224)
		(layer "In11.Cu")
		(net "M_J_DQS_DP<3>")
	)
	(segment
		(start 64.094106 -0.380746)
		(end 64.24676 -0.5334)
		(width 0.14224)
		(layer "In11.Cu")
		(net "M_J_DQS_DP<3>")
	)
	(segment
		(start 84.688172 -58.35142)
		(end 84.694522 -58.362088)
		(width 0.0889)
		(layer "In11.Cu")
		(net "M_J_DQS_DP<3>")
	)
	(segment
		(start 64.449452 0.0762)
		(end 64.24676 0.0762)
		(width 0.14224)
		(layer "In11.Cu")
		(net "M_J_DQS_DP<3>")
	)
	(segment
		(start 84.699348 -63.706502)
		(end 84.694522 -63.715138)
		(width 0.0889)
		(layer "In11.Cu")
		(net "M_J_DQS_DP<3>")
	)
	(segment
		(start 64.62903 -2.058924)
		(end 64.62903 -2.763774)
		(width 0.14224)
		(layer "In11.Cu")
		(net "M_J_DQS_DP<3>")
	)
	(segment
		(start 64.449706 -1.8796)
		(end 64.62903 -2.058924)
		(width 0.14224)
		(layer "In11.Cu")
		(net "M_J_DQS_DP<3>")
	)
	(segment
		(start 84.668106 -55.344568)
		(end 84.694522 -55.390288)
		(width 0.0889)
		(layer "In11.Cu")
		(net "M_J_DQS_DP<3>")
	)
	(segment
		(start 80.69199 -47.591472)
		(end 80.69199 -47.75327)
		(width 0.14224)
		(layer "In11.Cu")
		(net "M_J_DQS_DP<3>")
	)
	(segment
		(start 81.869788 -49.337722)
		(end 82.049366 -49.5173)
		(width 0.14224)
		(layer "In11.Cu")
		(net "M_J_DQS_DP<3>")
	)
	(segment
		(start 64.31915 -1.8796)
		(end 64.449706 -1.8796)
		(width 0.14224)
		(layer "In11.Cu")
		(net "M_J_DQS_DP<3>")
	)
	(segment
		(start 84.192872 -54.452774)
		(end 84.192872 -54.869334)
		(width 0.0889)
		(layer "In11.Cu")
		(net "M_J_DQS_DP<3>")
	)
	(segment
		(start 70.45325 -37.352732)
		(end 80.69199 -47.591472)
		(width 0.14224)
		(layer "In11.Cu")
		(net "M_J_DQS_DP<3>")
	)
	(segment
		(start 84.405724 -66.883026)
		(end 84.347812 -66.825114)
		(width 0.0889)
		(layer "In11.Cu")
		(net "M_J_DQS_DP<3>")
	)
	(segment
		(start 64.62903 -1.08712)
		(end 64.44615 -1.27)
		(width 0.14224)
		(layer "In11.Cu")
		(net "M_J_DQS_DP<3>")
	)
	(segment
		(start 64.31915 -1.27)
		(end 64.14135 -1.4478)
		(width 0.14224)
		(layer "In11.Cu")
		(net "M_J_DQS_DP<3>")
	)
	(segment
		(start 84.699348 -60.734702)
		(end 84.694522 -60.743338)
		(width 0.0889)
		(layer "In11.Cu")
		(net "M_J_DQS_DP<3>")
	)
	(segment
		(start 83.928204 -54.188106)
		(end 84.192872 -54.452774)
		(width 0.0889)
		(layer "In11.Cu")
		(net "M_J_DQS_DP<3>")
	)
	(segment
		(start 80.69199 -47.75327)
		(end 80.871822 -47.933102)
		(width 0.14224)
		(layer "In11.Cu")
		(net "M_J_DQS_DP<3>")
	)
	(segment
		(start 63.768986 -5.392674)
		(end 64.600582 -6.22427)
		(width 0.14224)
		(layer "In11.Cu")
		(net "M_J_DQS_DP<3>")
	)
	(segment
		(start 64.369188 1.181354)
		(end 64.62903 0.921512)
		(width 0.14224)
		(layer "In11.Cu")
		(net "M_J_DQS_DP<3>")
	)
	(segment
		(start 63.649606 -4.596638)
		(end 63.768986 -4.716018)
		(width 0.14224)
		(layer "In11.Cu")
		(net "M_J_DQS_DP<3>")
	)
	(segment
		(start 64.087502 -3.02641)
		(end 64.087502 -3.026156)
		(width 0.14224)
		(layer "In11.Cu")
		(net "M_J_DQS_DP<3>")
	)
	(segment
		(start 64.62903 -0.738378)
		(end 64.62903 -1.08712)
		(width 0.14224)
		(layer "In11.Cu")
		(net "M_J_DQS_DP<3>")
	)
	(segment
		(start 63.649606 -3.464052)
		(end 63.649606 -4.596638)
		(width 0.14224)
		(layer "In11.Cu")
		(net "M_J_DQS_DP<3>")
	)
	(segment
		(start 64.600582 -6.22427)
		(end 64.600582 -29.136086)
		(width 0.14224)
		(layer "In11.Cu")
		(net "M_J_DQS_DP<3>")
	)
	(segment
		(start 84.694522 -64.705738)
		(end 84.688172 -64.716406)
		(width 0.0889)
		(layer "In11.Cu")
		(net "M_J_DQS_DP<3>")
	)
	(segment
		(start 84.694522 -55.790338)
		(end 84.688172 -55.801006)
		(width 0.0889)
		(layer "In11.Cu")
		(net "M_J_DQS_DP<3>")
	)
	(segment
		(start 81.313528 -48.21301)
		(end 81.313528 -48.374554)
		(width 0.14224)
		(layer "In11.Cu")
		(net "M_J_DQS_DP<3>")
	)
	(segment
		(start 81.869788 -48.76927)
		(end 81.869788 -49.337722)
		(width 0.14224)
		(layer "In11.Cu")
		(net "M_J_DQS_DP<3>")
	)
	(segment
		(start 84.699348 -65.687702)
		(end 84.694522 -65.696338)
		(width 0.0889)
		(layer "In11.Cu")
		(net "M_J_DQS_DP<3>")
	)
	(segment
		(start 64.62903 0.921512)
		(end 64.62903 0.255778)
		(width 0.14224)
		(layer "In11.Cu")
		(net "M_J_DQS_DP<3>")
	)
	(segment
		(start 64.094106 -0.076454)
		(end 64.094106 -0.380746)
		(width 0.14224)
		(layer "In11.Cu")
		(net "M_J_DQS_DP<3>")
	)
	(segment
		(start 84.699348 -62.715902)
		(end 84.694522 -62.724538)
		(width 0.0889)
		(layer "In11.Cu")
		(net "M_J_DQS_DP<3>")
	)
	(segment
		(start 82.648806 -50.061114)
		(end 82.74685 -50.159158)
		(width 0.0889)
		(layer "In11.Cu")
		(net "M_J_DQS_DP<3>")
	)
	(segment
		(start 64.087502 -3.026156)
		(end 63.649606 -3.464052)
		(width 0.14224)
		(layer "In11.Cu")
		(net "M_J_DQS_DP<3>")
	)
	(segment
		(start 82.74685 -51.754532)
		(end 83.928204 -52.935886)
		(width 0.0889)
		(layer "In11.Cu")
		(net "M_J_DQS_DP<3>")
	)
	(segment
		(start 82.049366 -49.5173)
		(end 82.049366 -49.678844)
		(width 0.14224)
		(layer "In11.Cu")
		(net "M_J_DQS_DP<3>")
	)
	(segment
		(start 64.24676 0.0762)
		(end 64.094106 -0.076454)
		(width 0.14224)
		(layer "In11.Cu")
		(net "M_J_DQS_DP<3>")
	)
	(segment
		(start 70.45325 -34.988754)
		(end 70.45325 -37.352732)
		(width 0.14224)
		(layer "In11.Cu")
		(net "M_J_DQS_DP<3>")
	)
	(segment
		(start 81.03362 -47.933102)
		(end 81.313528 -48.21301)
		(width 0.14224)
		(layer "In11.Cu")
		(net "M_J_DQS_DP<3>")
	)
	(segment
		(start 84.694522 -56.780938)
		(end 84.688172 -56.791606)
		(width 0.0889)
		(layer "In11.Cu")
		(net "M_J_DQS_DP<3>")
	)
	(segment
		(start 84.694522 -65.696338)
		(end 84.688172 -65.707006)
		(width 0.0889)
		(layer "In11.Cu")
		(net "M_J_DQS_DP<3>")
	)
	(segment
		(start 84.699348 -57.762902)
		(end 84.694522 -57.771538)
		(width 0.0889)
		(layer "In11.Cu")
		(net "M_J_DQS_DP<3>")
	)
	(segment
		(start 64.24676 -0.5334)
		(end 64.424052 -0.5334)
		(width 0.14224)
		(layer "In11.Cu")
		(net "M_J_DQS_DP<3>")
	)
	(segment
		(start 81.49336 -48.554386)
		(end 81.654904 -48.554386)
		(width 0.14224)
		(layer "In11.Cu")
		(net "M_J_DQS_DP<3>")
	)
	(segment
		(start 64.14135 -1.7018)
		(end 64.31915 -1.8796)
		(width 0.14224)
		(layer "In11.Cu")
		(net "M_J_DQS_DP<3>")
	)
	(segment
		(start 84.694522 -63.715138)
		(end 84.688172 -63.725806)
		(width 0.0889)
		(layer "In11.Cu")
		(net "M_J_DQS_DP<3>")
	)
	(segment
		(start 82.229198 -49.858676)
		(end 82.390742 -49.858676)
		(width 0.14224)
		(layer "In11.Cu")
		(net "M_J_DQS_DP<3>")
	)
	(segment
		(start 64.424052 -0.5334)
		(end 64.62903 -0.738378)
		(width 0.14224)
		(layer "In11.Cu")
		(net "M_J_DQS_DP<3>")
	)
	(segment
		(start 84.699348 -55.781702)
		(end 84.694522 -55.790338)
		(width 0.0889)
		(layer "In11.Cu")
		(net "M_J_DQS_DP<3>")
	)
	(segment
		(start 82.049366 -49.678844)
		(end 82.229198 -49.858676)
		(width 0.14224)
		(layer "In11.Cu")
		(net "M_J_DQS_DP<3>")
	)
	(segment
		(start 84.694522 -60.743338)
		(end 84.688172 -60.754006)
		(width 0.0889)
		(layer "In11.Cu")
		(net "M_J_DQS_DP<3>")
	)
	(segment
		(start 64.14135 -1.4478)
		(end 64.14135 -1.7018)
		(width 0.14224)
		(layer "In11.Cu")
		(net "M_J_DQS_DP<3>")
	)
	(segment
		(start 82.57794 -50.04562)
		(end 82.593434 -50.061114)
		(width 0.0889)
		(layer "In11.Cu")
		(net "M_J_DQS_DP<3>")
	)
	(segment
		(start 82.593434 -50.061114)
		(end 82.648806 -50.061114)
		(width 0.0889)
		(layer "In11.Cu")
		(net "M_J_DQS_DP<3>")
	)
	(segment
		(start 82.74685 -50.159158)
		(end 82.74685 -51.754532)
		(width 0.0889)
		(layer "In11.Cu")
		(net "M_J_DQS_DP<3>")
	)
	(segment
		(start 64.44615 -1.27)
		(end 64.31915 -1.27)
		(width 0.14224)
		(layer "In11.Cu")
		(net "M_J_DQS_DP<3>")
	)
	(segment
		(start 80.871822 -47.933102)
		(end 81.03362 -47.933102)
		(width 0.14224)
		(layer "In11.Cu")
		(net "M_J_DQS_DP<3>")
	)
	(segment
		(start 64.600582 -29.136086)
		(end 70.45325 -34.988754)
		(width 0.14224)
		(layer "In11.Cu")
		(net "M_J_DQS_DP<3>")
	)
	(segment
		(start 64.087502 1.181354)
		(end 64.369188 1.181354)
		(width 0.14224)
		(layer "In11.Cu")
		(net "M_J_DQS_DP<3>")
	)
	(segment
		(start 81.654904 -48.554386)
		(end 81.869788 -48.76927)
		(width 0.14224)
		(layer "In11.Cu")
		(net "M_J_DQS_DP<3>")
	)
	(segment
		(start 81.313528 -48.374554)
		(end 81.49336 -48.554386)
		(width 0.14224)
		(layer "In11.Cu")
		(net "M_J_DQS_DP<3>")
	)
	(segment
		(start 64.366394 -3.02641)
		(end 64.087502 -3.02641)
		(width 0.14224)
		(layer "In11.Cu")
		(net "M_J_DQS_DP<3>")
	)
	(segment
		(start 84.694522 -61.733938)
		(end 84.688172 -61.744606)
		(width 0.0889)
		(layer "In11.Cu")
		(net "M_J_DQS_DP<3>")
	)
	(segment
		(start 64.62903 -2.763774)
		(end 64.366394 -3.02641)
		(width 0.14224)
		(layer "In11.Cu")
		(net "M_J_DQS_DP<3>")
	)
	(segment
		(start 82.390742 -49.858676)
		(end 82.57794 -50.045874)
		(width 0.14224)
		(layer "In11.Cu")
		(net "M_J_DQS_DP<3>")
	)
	(segment
		(start 84.192872 -54.869334)
		(end 84.668106 -55.344568)
		(width 0.0889)
		(layer "In11.Cu")
		(net "M_J_DQS_DP<3>")
	)
	(segment
		(start 84.694522 -59.752738)
		(end 84.688172 -59.763406)
		(width 0.0889)
		(layer "In11.Cu")
		(net "M_J_DQS_DP<3>")
	)
	(segment
		(start 82.57794 -50.045874)
		(end 82.57794 -50.04562)
		(width 0.0889)
		(layer "In11.Cu")
		(net "M_J_DQS_DP<3>")
	)
	(segment
		(start 84.699348 -59.744102)
		(end 84.694522 -59.752738)
		(width 0.0889)
		(layer "In11.Cu")
		(net "M_J_DQS_DP<3>")
	)
	(segment
		(start 84.699348 -56.772302)
		(end 84.694522 -56.780938)
		(width 0.0889)
		(layer "In11.Cu")
		(net "M_J_DQS_DP<3>")
	)
	(segment
		(start 84.699348 -64.697102)
		(end 84.694522 -64.705738)
		(width 0.0889)
		(layer "In11.Cu")
		(net "M_J_DQS_DP<3>")
	)
	(segment
		(start 84.694522 -62.724538)
		(end 84.688172 -62.735206)
		(width 0.0889)
		(layer "In11.Cu")
		(net "M_J_DQS_DP<3>")
	)
	(segment
		(start 63.768986 -4.716018)
		(end 63.768986 -5.392674)
		(width 0.14224)
		(layer "In11.Cu")
		(net "M_J_DQS_DP<3>")
	)
	(segment
		(start 84.347812 -66.825114)
		(end 84.347812 -66.48704)
		(width 0.0889)
		(layer "In11.Cu")
		(net "M_J_DQS_DP<3>")
	)
	(segment
		(start 84.699348 -61.725302)
		(end 84.694522 -61.733938)
		(width 0.0889)
		(layer "In11.Cu")
		(net "M_J_DQS_DP<3>")
	)
	(arc
		(start 84.694522 -62.324488)
		(mid 84.747992 -62.519551)
		(end 84.699348 -62.715902)
		(width 0.0889)
		(layer "In11.Cu")
		(net "M_J_DQS_DP<3>")
	)
	(arc
		(start 84.694522 -56.380888)
		(mid 84.747992 -56.575951)
		(end 84.699348 -56.772302)
		(width 0.0889)
		(layer "In11.Cu")
		(net "M_J_DQS_DP<3>")
	)
	(arc
		(start 84.694522 -55.390288)
		(mid 84.747992 -55.585351)
		(end 84.699348 -55.781702)
		(width 0.0889)
		(layer "In11.Cu")
		(net "M_J_DQS_DP<3>")
	)
	(arc
		(start 84.694522 -65.296288)
		(mid 84.747992 -65.491351)
		(end 84.699348 -65.687702)
		(width 0.0889)
		(layer "In11.Cu")
		(net "M_J_DQS_DP<3>")
	)
	(arc
		(start 84.694522 -61.333888)
		(mid 84.747992 -61.528951)
		(end 84.699348 -61.725302)
		(width 0.0889)
		(layer "In11.Cu")
		(net "M_J_DQS_DP<3>")
	)
	(arc
		(start 84.694522 -60.343288)
		(mid 84.747992 -60.538351)
		(end 84.699348 -60.734702)
		(width 0.0889)
		(layer "In11.Cu")
		(net "M_J_DQS_DP<3>")
	)
	(arc
		(start 84.688172 -60.754006)
		(mid 84.615374 -61.044769)
		(end 84.694522 -61.333888)
		(width 0.0889)
		(layer "In11.Cu")
		(net "M_J_DQS_DP<3>")
	)
	(arc
		(start 84.694522 -57.371488)
		(mid 84.747992 -57.566551)
		(end 84.699348 -57.762902)
		(width 0.0889)
		(layer "In11.Cu")
		(net "M_J_DQS_DP<3>")
	)
	(arc
		(start 84.688172 -55.801006)
		(mid 84.615374 -56.091769)
		(end 84.694522 -56.380888)
		(width 0.0889)
		(layer "In11.Cu")
		(net "M_J_DQS_DP<3>")
	)
	(arc
		(start 84.694522 -66.286888)
		(mid 84.708117 -66.661537)
		(end 84.405724 -66.883026)
		(width 0.0889)
		(layer "In11.Cu")
		(net "M_J_DQS_DP<3>")
	)
	(arc
		(start 84.694522 -63.315088)
		(mid 84.747992 -63.510151)
		(end 84.699348 -63.706502)
		(width 0.0889)
		(layer "In11.Cu")
		(net "M_J_DQS_DP<3>")
	)
	(arc
		(start 84.688172 -61.744606)
		(mid 84.615374 -62.035369)
		(end 84.694522 -62.324488)
		(width 0.0889)
		(layer "In11.Cu")
		(net "M_J_DQS_DP<3>")
	)
	(arc
		(start 84.694522 -57.771538)
		(mid 84.6153 -58.060656)
		(end 84.688172 -58.35142)
		(width 0.0889)
		(layer "In11.Cu")
		(net "M_J_DQS_DP<3>")
	)
	(arc
		(start 84.694522 -58.761884)
		(mid 84.615391 -59.057286)
		(end 84.694522 -59.352688)
		(width 0.0889)
		(layer "In11.Cu")
		(net "M_J_DQS_DP<3>")
	)
	(arc
		(start 84.694522 -64.305688)
		(mid 84.747992 -64.500751)
		(end 84.699348 -64.697102)
		(width 0.0889)
		(layer "In11.Cu")
		(net "M_J_DQS_DP<3>")
	)
	(arc
		(start 84.688172 -63.725806)
		(mid 84.615374 -64.016569)
		(end 84.694522 -64.305688)
		(width 0.0889)
		(layer "In11.Cu")
		(net "M_J_DQS_DP<3>")
	)
	(arc
		(start 84.688172 -64.716406)
		(mid 84.615374 -65.007169)
		(end 84.694522 -65.296288)
		(width 0.0889)
		(layer "In11.Cu")
		(net "M_J_DQS_DP<3>")
	)
	(arc
		(start 84.694522 -58.362088)
		(mid 84.748021 -58.561986)
		(end 84.694522 -58.761884)
		(width 0.0889)
		(layer "In11.Cu")
		(net "M_J_DQS_DP<3>")
	)
	(arc
		(start 84.688172 -62.735206)
		(mid 84.615374 -63.025969)
		(end 84.694522 -63.315088)
		(width 0.0889)
		(layer "In11.Cu")
		(net "M_J_DQS_DP<3>")
	)
	(arc
		(start 84.688172 -59.763406)
		(mid 84.615374 -60.054169)
		(end 84.694522 -60.343288)
		(width 0.0889)
		(layer "In11.Cu")
		(net "M_J_DQS_DP<3>")
	)
	(arc
		(start 84.688172 -65.707006)
		(mid 84.615374 -65.997769)
		(end 84.694522 -66.286888)
		(width 0.0889)
		(layer "In11.Cu")
		(net "M_J_DQS_DP<3>")
	)
	(arc
		(start 84.694522 -59.352688)
		(mid 84.747992 -59.547751)
		(end 84.699348 -59.744102)
		(width 0.0889)
		(layer "In11.Cu")
		(net "M_J_DQS_DP<3>")
	)
	(arc
		(start 84.688172 -56.791606)
		(mid 84.615374 -57.082369)
		(end 84.694522 -57.371488)
		(width 0.0889)
		(layer "In11.Cu")
		(net "M_J_DQS_DP<3>")
	)
	(segment
		(start 55.421022 1.241298)
		(end 55.207154 1.455166)
		(width 0.1651)
		(layer "F.Cu")
		(net "M_J_DQS_DP<2>")
	)
	(segment
		(start 55.199534 0.277622)
		(end 55.421022 0.49911)
		(width 0.1651)
		(layer "F.Cu")
		(net "M_J_DQS_DP<2>")
	)
	(segment
		(start 55.207154 1.455166)
		(end 55.01132 1.455166)
		(width 0.1651)
		(layer "F.Cu")
		(net "M_J_DQS_DP<2>")
	)
	(segment
		(start 81.485232 -58.561986)
		(end 80.913732 -58.561986)
		(width 0.0889)
		(layer "F.Cu")
		(net "M_J_DQS_DP<2>")
	)
	(segment
		(start 55.199534 -0.821182)
		(end 55.199534 0.277622)
		(width 0.1651)
		(layer "F.Cu")
		(net "M_J_DQS_DP<2>")
	)
	(segment
		(start 55.421022 0.49911)
		(end 55.421022 1.241298)
		(width 0.1651)
		(layer "F.Cu")
		(net "M_J_DQS_DP<2>")
	)
	(segment
		(start 55.01132 1.455166)
		(end 54.737508 1.181354)
		(width 0.1651)
		(layer "F.Cu")
		(net "M_J_DQS_DP<2>")
	)
	(via
		(at 54.737508 1.181354)
		(size 0.508)
		(drill 0.254)
		(layers "F.Cu" "B.Cu")
		(net "M_J_DQS_DP<2>")
	)
	(via
		(at 80.913732 -58.561986)
		(size 0.508)
		(drill 0.254)
		(layers "F.Cu" "B.Cu")
		(net "M_J_DQS_DP<2>")
	)
	(via
		(at 54.737508 -3.026156)
		(size 0.508)
		(drill 0.254)
		(layers "F.Cu" "B.Cu")
		(net "M_J_DQS_DP<2>")
	)
	(segment
		(start 55.199534 -1.021842)
		(end 55.199534 -2.538222)
		(width 0.1651)
		(layer "B.Cu")
		(net "M_J_DQS_DP<2>")
	)
	(segment
		(start 55.239412 -3.30708)
		(end 55.018432 -3.30708)
		(width 0.1651)
		(layer "B.Cu")
		(net "M_J_DQS_DP<2>")
	)
	(segment
		(start 55.199534 -2.538222)
		(end 55.379112 -2.7178)
		(width 0.1651)
		(layer "B.Cu")
		(net "M_J_DQS_DP<2>")
	)
	(segment
		(start 55.018432 -3.30708)
		(end 54.737508 -3.026156)
		(width 0.1651)
		(layer "B.Cu")
		(net "M_J_DQS_DP<2>")
	)
	(segment
		(start 55.379112 -3.16738)
		(end 55.239412 -3.30708)
		(width 0.1651)
		(layer "B.Cu")
		(net "M_J_DQS_DP<2>")
	)
	(segment
		(start 55.379112 -2.7178)
		(end 55.379112 -3.16738)
		(width 0.1651)
		(layer "B.Cu")
		(net "M_J_DQS_DP<2>")
	)
	(segment
		(start 54.744112 -0.380746)
		(end 54.896766 -0.5334)
		(width 0.14224)
		(layer "In11.Cu")
		(net "M_J_DQS_DP<2>")
	)
	(segment
		(start 71.289164 -50.274474)
		(end 71.652384 -50.637694)
		(width 0.0889)
		(layer "In11.Cu")
		(net "M_J_DQS_DP<2>")
	)
	(segment
		(start 81.285588 -58.70956)
		(end 81.206848 -58.730896)
		(width 0.0889)
		(layer "In11.Cu")
		(net "M_J_DQS_DP<2>")
	)
	(segment
		(start 55.250588 -33.613598)
		(end 67.427856 -45.790866)
		(width 0.14224)
		(layer "In11.Cu")
		(net "M_J_DQS_DP<2>")
	)
	(segment
		(start 54.418992 -4.76377)
		(end 54.418992 -5.392674)
		(width 0.14224)
		(layer "In11.Cu")
		(net "M_J_DQS_DP<2>")
	)
	(segment
		(start 54.737508 1.181354)
		(end 55.019194 1.181354)
		(width 0.14224)
		(layer "In11.Cu")
		(net "M_J_DQS_DP<2>")
	)
	(segment
		(start 54.299612 -3.464052)
		(end 54.299612 -4.64439)
		(width 0.14224)
		(layer "In11.Cu")
		(net "M_J_DQS_DP<2>")
	)
	(segment
		(start 69.12229 -48.472344)
		(end 70.711822 -49.753012)
		(width 0.14224)
		(layer "In11.Cu")
		(net "M_J_DQS_DP<2>")
	)
	(segment
		(start 55.099712 -1.8796)
		(end 55.279036 -2.058924)
		(width 0.14224)
		(layer "In11.Cu")
		(net "M_J_DQS_DP<2>")
	)
	(segment
		(start 55.279036 0.255778)
		(end 55.099458 0.0762)
		(width 0.14224)
		(layer "In11.Cu")
		(net "M_J_DQS_DP<2>")
	)
	(segment
		(start 74.028046 -54.19979)
		(end 74.060812 -54.19979)
		(width 0.0889)
		(layer "In11.Cu")
		(net "M_J_DQS_DP<2>")
	)
	(segment
		(start 72.315832 -53.20919)
		(end 72.343772 -53.20919)
		(width 0.0889)
		(layer "In11.Cu")
		(net "M_J_DQS_DP<2>")
	)
	(segment
		(start 71.652384 -50.637694)
		(end 71.821548 -50.940462)
		(width 0.0889)
		(layer "In11.Cu")
		(net "M_J_DQS_DP<2>")
	)
	(segment
		(start 54.299612 -4.64439)
		(end 54.418992 -4.76377)
		(width 0.14224)
		(layer "In11.Cu")
		(net "M_J_DQS_DP<2>")
	)
	(segment
		(start 54.737508 -3.026156)
		(end 54.299612 -3.464052)
		(width 0.14224)
		(layer "In11.Cu")
		(net "M_J_DQS_DP<2>")
	)
	(segment
		(start 55.279036 -0.738378)
		(end 55.279036 -1.08712)
		(width 0.14224)
		(layer "In11.Cu")
		(net "M_J_DQS_DP<2>")
	)
	(segment
		(start 77.82306 -56.3753)
		(end 77.826362 -56.381142)
		(width 0.0889)
		(layer "In11.Cu")
		(net "M_J_DQS_DP<2>")
	)
	(segment
		(start 54.896766 -0.5334)
		(end 55.074058 -0.5334)
		(width 0.14224)
		(layer "In11.Cu")
		(net "M_J_DQS_DP<2>")
	)
	(segment
		(start 70.711822 -49.753012)
		(end 71.217536 -50.258726)
		(width 0.14224)
		(layer "In11.Cu")
		(net "M_J_DQS_DP<2>")
	)
	(segment
		(start 73.165716 -53.704236)
		(end 73.198482 -53.704236)
		(width 0.0889)
		(layer "In11.Cu")
		(net "M_J_DQS_DP<2>")
	)
	(segment
		(start 54.744112 -0.076454)
		(end 54.744112 -0.380746)
		(width 0.14224)
		(layer "In11.Cu")
		(net "M_J_DQS_DP<2>")
	)
	(segment
		(start 55.279036 -1.08712)
		(end 55.096156 -1.27)
		(width 0.14224)
		(layer "In11.Cu")
		(net "M_J_DQS_DP<2>")
	)
	(segment
		(start 55.0164 -3.02641)
		(end 54.737508 -3.02641)
		(width 0.14224)
		(layer "In11.Cu")
		(net "M_J_DQS_DP<2>")
	)
	(segment
		(start 71.233284 -50.274474)
		(end 71.289164 -50.274474)
		(width 0.0889)
		(layer "In11.Cu")
		(net "M_J_DQS_DP<2>")
	)
	(segment
		(start 54.791356 -1.7018)
		(end 54.969156 -1.8796)
		(width 0.14224)
		(layer "In11.Cu")
		(net "M_J_DQS_DP<2>")
	)
	(segment
		(start 55.096156 -1.27)
		(end 54.969156 -1.27)
		(width 0.14224)
		(layer "In11.Cu")
		(net "M_J_DQS_DP<2>")
	)
	(segment
		(start 54.896766 0.0762)
		(end 54.744112 -0.076454)
		(width 0.14224)
		(layer "In11.Cu")
		(net "M_J_DQS_DP<2>")
	)
	(segment
		(start 55.019194 1.181354)
		(end 55.279036 0.921512)
		(width 0.14224)
		(layer "In11.Cu")
		(net "M_J_DQS_DP<2>")
	)
	(segment
		(start 77.462126 -56.18099)
		(end 77.479906 -56.18099)
		(width 0.0889)
		(layer "In11.Cu")
		(net "M_J_DQS_DP<2>")
	)
	(segment
		(start 55.279036 -2.058924)
		(end 55.279036 -2.763774)
		(width 0.14224)
		(layer "In11.Cu")
		(net "M_J_DQS_DP<2>")
	)
	(segment
		(start 78.31328 -56.676036)
		(end 78.349348 -56.676036)
		(width 0.0889)
		(layer "In11.Cu")
		(net "M_J_DQS_DP<2>")
	)
	(segment
		(start 75.745086 -55.19039)
		(end 75.777852 -55.19039)
		(width 0.0889)
		(layer "In11.Cu")
		(net "M_J_DQS_DP<2>")
	)
	(segment
		(start 81.206848 -58.730896)
		(end 80.913732 -58.561986)
		(width 0.0889)
		(layer "In11.Cu")
		(net "M_J_DQS_DP<2>")
	)
	(segment
		(start 55.279036 -2.763774)
		(end 55.0164 -3.02641)
		(width 0.14224)
		(layer "In11.Cu")
		(net "M_J_DQS_DP<2>")
	)
	(segment
		(start 74.882756 -54.694836)
		(end 74.915522 -54.694836)
		(width 0.0889)
		(layer "In11.Cu")
		(net "M_J_DQS_DP<2>")
	)
	(segment
		(start 79.178912 -57.17159)
		(end 79.211678 -57.17159)
		(width 0.0889)
		(layer "In11.Cu")
		(net "M_J_DQS_DP<2>")
	)
	(segment
		(start 54.969156 -1.8796)
		(end 55.099712 -1.8796)
		(width 0.14224)
		(layer "In11.Cu")
		(net "M_J_DQS_DP<2>")
	)
	(segment
		(start 54.737508 -3.02641)
		(end 54.737508 -3.026156)
		(width 0.14224)
		(layer "In11.Cu")
		(net "M_J_DQS_DP<2>")
	)
	(segment
		(start 54.969156 -1.27)
		(end 54.791356 -1.4478)
		(width 0.14224)
		(layer "In11.Cu")
		(net "M_J_DQS_DP<2>")
	)
	(segment
		(start 71.217536 -50.258726)
		(end 71.233284 -50.274474)
		(width 0.0889)
		(layer "In11.Cu")
		(net "M_J_DQS_DP<2>")
	)
	(segment
		(start 55.099458 0.0762)
		(end 54.896766 0.0762)
		(width 0.14224)
		(layer "In11.Cu")
		(net "M_J_DQS_DP<2>")
	)
	(segment
		(start 54.418992 -5.392674)
		(end 55.250588 -6.22427)
		(width 0.14224)
		(layer "In11.Cu")
		(net "M_J_DQS_DP<2>")
	)
	(segment
		(start 67.427856 -46.77791)
		(end 69.12229 -48.472344)
		(width 0.14224)
		(layer "In11.Cu")
		(net "M_J_DQS_DP<2>")
	)
	(segment
		(start 67.427856 -45.790866)
		(end 67.427856 -46.77791)
		(width 0.14224)
		(layer "In11.Cu")
		(net "M_J_DQS_DP<2>")
	)
	(segment
		(start 55.074058 -0.5334)
		(end 55.279036 -0.738378)
		(width 0.14224)
		(layer "In11.Cu")
		(net "M_J_DQS_DP<2>")
	)
	(segment
		(start 76.599796 -55.685436)
		(end 76.632562 -55.685436)
		(width 0.0889)
		(layer "In11.Cu")
		(net "M_J_DQS_DP<2>")
	)
	(segment
		(start 80.042258 -57.66689)
		(end 80.066388 -57.66689)
		(width 0.0889)
		(layer "In11.Cu")
		(net "M_J_DQS_DP<2>")
	)
	(segment
		(start 71.816976 -52.323238)
		(end 71.810626 -52.333906)
		(width 0.0889)
		(layer "In11.Cu")
		(net "M_J_DQS_DP<2>")
	)
	(segment
		(start 80.892142 -58.16219)
		(end 80.931766 -58.16219)
		(width 0.0889)
		(layer "In11.Cu")
		(net "M_J_DQS_DP<2>")
	)
	(segment
		(start 55.250588 -6.22427)
		(end 55.250588 -33.613598)
		(width 0.14224)
		(layer "In11.Cu")
		(net "M_J_DQS_DP<2>")
	)
	(segment
		(start 54.791356 -1.4478)
		(end 54.791356 -1.7018)
		(width 0.14224)
		(layer "In11.Cu")
		(net "M_J_DQS_DP<2>")
	)
	(segment
		(start 55.279036 0.921512)
		(end 55.279036 0.255778)
		(width 0.14224)
		(layer "In11.Cu")
		(net "M_J_DQS_DP<2>")
	)
	(arc
		(start 74.060812 -54.19979)
		(mid 74.252454 -54.256956)
		(end 74.392536 -54.399688)
		(width 0.0889)
		(layer "In11.Cu")
		(net "M_J_DQS_DP<2>")
	)
	(arc
		(start 73.534016 -53.904388)
		(mid 73.742624 -54.11632)
		(end 74.028046 -54.19979)
		(width 0.0889)
		(layer "In11.Cu")
		(net "M_J_DQS_DP<2>")
	)
	(arc
		(start 76.632562 -55.685436)
		(mid 76.826412 -55.741786)
		(end 76.968096 -55.885588)
		(width 0.0889)
		(layer "In11.Cu")
		(net "M_J_DQS_DP<2>")
	)
	(arc
		(start 80.066388 -57.66689)
		(mid 80.260238 -57.72324)
		(end 80.401922 -57.867042)
		(width 0.0889)
		(layer "In11.Cu")
		(net "M_J_DQS_DP<2>")
	)
	(arc
		(start 75.251056 -54.894988)
		(mid 75.459664 -55.10692)
		(end 75.745086 -55.19039)
		(width 0.0889)
		(layer "In11.Cu")
		(net "M_J_DQS_DP<2>")
	)
	(arc
		(start 73.198482 -53.704236)
		(mid 73.392332 -53.760586)
		(end 73.534016 -53.904388)
		(width 0.0889)
		(layer "In11.Cu")
		(net "M_J_DQS_DP<2>")
	)
	(arc
		(start 72.343772 -53.20919)
		(mid 72.535414 -53.266356)
		(end 72.675496 -53.409088)
		(width 0.0889)
		(layer "In11.Cu")
		(net "M_J_DQS_DP<2>")
	)
	(arc
		(start 79.543402 -57.371488)
		(mid 79.754115 -57.584567)
		(end 80.042258 -57.66689)
		(width 0.0889)
		(layer "In11.Cu")
		(net "M_J_DQS_DP<2>")
	)
	(arc
		(start 79.211678 -57.17159)
		(mid 79.40332 -57.228756)
		(end 79.543402 -57.371488)
		(width 0.0889)
		(layer "In11.Cu")
		(net "M_J_DQS_DP<2>")
	)
	(arc
		(start 80.931766 -58.16219)
		(mid 81.249805 -58.344691)
		(end 81.285588 -58.70956)
		(width 0.0889)
		(layer "In11.Cu")
		(net "M_J_DQS_DP<2>")
	)
	(arc
		(start 77.479906 -56.18099)
		(mid 77.677067 -56.232949)
		(end 77.82306 -56.3753)
		(width 0.0889)
		(layer "In11.Cu")
		(net "M_J_DQS_DP<2>")
	)
	(arc
		(start 72.675496 -53.409088)
		(mid 72.8825 -53.619952)
		(end 73.165716 -53.704236)
		(width 0.0889)
		(layer "In11.Cu")
		(net "M_J_DQS_DP<2>")
	)
	(arc
		(start 77.826362 -56.381142)
		(mid 78.031983 -56.591065)
		(end 78.31328 -56.676036)
		(width 0.0889)
		(layer "In11.Cu")
		(net "M_J_DQS_DP<2>")
	)
	(arc
		(start 74.915522 -54.694836)
		(mid 75.109372 -54.751186)
		(end 75.251056 -54.894988)
		(width 0.0889)
		(layer "In11.Cu")
		(net "M_J_DQS_DP<2>")
	)
	(arc
		(start 71.821548 -50.940462)
		(mid 71.870579 -51.137149)
		(end 71.816976 -51.332638)
		(width 0.0889)
		(layer "In11.Cu")
		(net "M_J_DQS_DP<2>")
	)
	(arc
		(start 76.109576 -55.390288)
		(mid 76.31658 -55.601152)
		(end 76.599796 -55.685436)
		(width 0.0889)
		(layer "In11.Cu")
		(net "M_J_DQS_DP<2>")
	)
	(arc
		(start 74.392536 -54.399688)
		(mid 74.59954 -54.610552)
		(end 74.882756 -54.694836)
		(width 0.0889)
		(layer "In11.Cu")
		(net "M_J_DQS_DP<2>")
	)
	(arc
		(start 78.349348 -56.676036)
		(mid 78.543198 -56.732386)
		(end 78.684882 -56.876188)
		(width 0.0889)
		(layer "In11.Cu")
		(net "M_J_DQS_DP<2>")
	)
	(arc
		(start 71.816976 -51.923442)
		(mid 71.870475 -52.12334)
		(end 71.816976 -52.323238)
		(width 0.0889)
		(layer "In11.Cu")
		(net "M_J_DQS_DP<2>")
	)
	(arc
		(start 78.684882 -56.876188)
		(mid 78.89349 -57.08812)
		(end 79.178912 -57.17159)
		(width 0.0889)
		(layer "In11.Cu")
		(net "M_J_DQS_DP<2>")
	)
	(arc
		(start 75.777852 -55.19039)
		(mid 75.969494 -55.247556)
		(end 76.109576 -55.390288)
		(width 0.0889)
		(layer "In11.Cu")
		(net "M_J_DQS_DP<2>")
	)
	(arc
		(start 76.968096 -55.885588)
		(mid 77.176704 -56.09752)
		(end 77.462126 -56.18099)
		(width 0.0889)
		(layer "In11.Cu")
		(net "M_J_DQS_DP<2>")
	)
	(arc
		(start 71.816976 -51.332638)
		(mid 71.737845 -51.62804)
		(end 71.816976 -51.923442)
		(width 0.0889)
		(layer "In11.Cu")
		(net "M_J_DQS_DP<2>")
	)
	(arc
		(start 71.810626 -52.333906)
		(mid 71.816803 -52.913838)
		(end 72.315832 -53.20919)
		(width 0.0889)
		(layer "In11.Cu")
		(net "M_J_DQS_DP<2>")
	)
	(arc
		(start 80.401922 -57.867042)
		(mid 80.608926 -58.077906)
		(end 80.892142 -58.16219)
		(width 0.0889)
		(layer "In11.Cu")
		(net "M_J_DQS_DP<2>")
	)
	(segment
		(start 45.84954 0.277622)
		(end 46.071028 0.49911)
		(width 0.1651)
		(layer "F.Cu")
		(net "M_J_DQS_DP<1>")
	)
	(segment
		(start 45.661326 1.455166)
		(end 45.387514 1.181354)
		(width 0.1651)
		(layer "F.Cu")
		(net "M_J_DQS_DP<1>")
	)
	(segment
		(start 46.071028 1.241298)
		(end 45.85716 1.455166)
		(width 0.1651)
		(layer "F.Cu")
		(net "M_J_DQS_DP<1>")
	)
	(segment
		(start 46.071028 0.49911)
		(end 46.071028 1.241298)
		(width 0.1651)
		(layer "F.Cu")
		(net "M_J_DQS_DP<1>")
	)
	(segment
		(start 45.84954 -0.821182)
		(end 45.84954 0.277622)
		(width 0.1651)
		(layer "F.Cu")
		(net "M_J_DQS_DP<1>")
	)
	(segment
		(start 77.192886 -60.047886)
		(end 76.621386 -60.047886)
		(width 0.0889)
		(layer "F.Cu")
		(net "M_J_DQS_DP<1>")
	)
	(segment
		(start 45.85716 1.455166)
		(end 45.661326 1.455166)
		(width 0.1651)
		(layer "F.Cu")
		(net "M_J_DQS_DP<1>")
	)
	(via
		(at 76.621386 -60.047886)
		(size 0.508)
		(drill 0.254)
		(layers "F.Cu" "B.Cu")
		(net "M_J_DQS_DP<1>")
	)
	(via
		(at 45.387514 1.181354)
		(size 0.508)
		(drill 0.254)
		(layers "F.Cu" "B.Cu")
		(net "M_J_DQS_DP<1>")
	)
	(via
		(at 45.387514 -3.026156)
		(size 0.508)
		(drill 0.254)
		(layers "F.Cu" "B.Cu")
		(net "M_J_DQS_DP<1>")
	)
	(segment
		(start 46.029118 -3.16738)
		(end 45.889418 -3.30708)
		(width 0.1651)
		(layer "B.Cu")
		(net "M_J_DQS_DP<1>")
	)
	(segment
		(start 45.889418 -3.30708)
		(end 45.668438 -3.30708)
		(width 0.1651)
		(layer "B.Cu")
		(net "M_J_DQS_DP<1>")
	)
	(segment
		(start 46.029118 -2.7178)
		(end 46.029118 -3.16738)
		(width 0.1651)
		(layer "B.Cu")
		(net "M_J_DQS_DP<1>")
	)
	(segment
		(start 45.84954 -1.021842)
		(end 45.84954 -2.538222)
		(width 0.1651)
		(layer "B.Cu")
		(net "M_J_DQS_DP<1>")
	)
	(segment
		(start 45.84954 -2.538222)
		(end 46.029118 -2.7178)
		(width 0.1651)
		(layer "B.Cu")
		(net "M_J_DQS_DP<1>")
	)
	(segment
		(start 45.668438 -3.30708)
		(end 45.387514 -3.026156)
		(width 0.1651)
		(layer "B.Cu")
		(net "M_J_DQS_DP<1>")
	)
	(segment
		(start 45.697648 -31.075122)
		(end 45.697648 -31.69539)
		(width 0.14224)
		(layer "In11.Cu")
		(net "M_J_DQS_DP<1>")
	)
	(segment
		(start 44.808648 -32.284924)
		(end 44.808648 -33.060386)
		(width 0.14224)
		(layer "In11.Cu")
		(net "M_J_DQS_DP<1>")
	)
	(segment
		(start 45.900594 -6.22427)
		(end 45.900594 -25.911048)
		(width 0.14224)
		(layer "In11.Cu")
		(net "M_J_DQS_DP<1>")
	)
	(segment
		(start 74.028046 -60.14339)
		(end 74.060812 -60.14339)
		(width 0.0889)
		(layer "In11.Cu")
		(net "M_J_DQS_DP<1>")
	)
	(segment
		(start 45.619162 -1.8796)
		(end 45.749718 -1.8796)
		(width 0.14224)
		(layer "In11.Cu")
		(net "M_J_DQS_DP<1>")
	)
	(segment
		(start 44.808648 -33.060386)
		(end 45.773848 -34.025586)
		(width 0.14224)
		(layer "In11.Cu")
		(net "M_J_DQS_DP<1>")
	)
	(segment
		(start 73.165716 -59.647836)
		(end 73.198482 -59.647836)
		(width 0.0889)
		(layer "In11.Cu")
		(net "M_J_DQS_DP<1>")
	)
	(segment
		(start 44.949618 -4.64185)
		(end 45.068998 -4.76123)
		(width 0.14224)
		(layer "In11.Cu")
		(net "M_J_DQS_DP<1>")
	)
	(segment
		(start 45.929042 -1.08712)
		(end 45.746162 -1.27)
		(width 0.14224)
		(layer "In11.Cu")
		(net "M_J_DQS_DP<1>")
	)
	(segment
		(start 48.756062 -39.48684)
		(end 49.848262 -39.48684)
		(width 0.14224)
		(layer "In11.Cu")
		(net "M_J_DQS_DP<1>")
	)
	(segment
		(start 45.136054 -30.828996)
		(end 45.451522 -30.828996)
		(width 0.14224)
		(layer "In11.Cu")
		(net "M_J_DQS_DP<1>")
	)
	(segment
		(start 45.546772 0.0762)
		(end 45.394118 -0.076454)
		(width 0.14224)
		(layer "In11.Cu")
		(net "M_J_DQS_DP<1>")
	)
	(segment
		(start 50.849276 -40.884094)
		(end 53.52034 -43.555158)
		(width 0.14224)
		(layer "In11.Cu")
		(net "M_J_DQS_DP<1>")
	)
	(segment
		(start 45.441362 -1.7018)
		(end 45.619162 -1.8796)
		(width 0.14224)
		(layer "In11.Cu")
		(net "M_J_DQS_DP<1>")
	)
	(segment
		(start 45.929042 -2.763774)
		(end 45.666406 -3.02641)
		(width 0.14224)
		(layer "In11.Cu")
		(net "M_J_DQS_DP<1>")
	)
	(segment
		(start 53.52034 -44.548044)
		(end 65.164208 -56.191912)
		(width 0.14224)
		(layer "In11.Cu")
		(net "M_J_DQS_DP<1>")
	)
	(segment
		(start 65.45834 -56.191912)
		(end 65.493138 -56.157114)
		(width 0.0889)
		(layer "In11.Cu")
		(net "M_J_DQS_DP<1>")
	)
	(segment
		(start 45.394118 -0.380746)
		(end 45.546772 -0.5334)
		(width 0.14224)
		(layer "In11.Cu")
		(net "M_J_DQS_DP<1>")
	)
	(segment
		(start 45.900594 -25.911048)
		(end 44.757848 -27.053794)
		(width 0.14224)
		(layer "In11.Cu")
		(net "M_J_DQS_DP<1>")
	)
	(segment
		(start 65.164208 -56.191912)
		(end 65.45834 -56.191912)
		(width 0.14224)
		(layer "In11.Cu")
		(net "M_J_DQS_DP<1>")
	)
	(segment
		(start 67.440556 -56.157114)
		(end 68.950332 -57.66689)
		(width 0.0889)
		(layer "In11.Cu")
		(net "M_J_DQS_DP<1>")
	)
	(segment
		(start 45.394118 -0.076454)
		(end 45.394118 -0.380746)
		(width 0.14224)
		(layer "In11.Cu")
		(net "M_J_DQS_DP<1>")
	)
	(segment
		(start 45.6692 1.181354)
		(end 45.929042 0.921512)
		(width 0.14224)
		(layer "In11.Cu")
		(net "M_J_DQS_DP<1>")
	)
	(segment
		(start 50.849276 -40.487854)
		(end 50.849276 -40.884094)
		(width 0.14224)
		(layer "In11.Cu")
		(net "M_J_DQS_DP<1>")
	)
	(segment
		(start 44.757848 -27.053794)
		(end 44.757848 -30.45079)
		(width 0.14224)
		(layer "In11.Cu")
		(net "M_J_DQS_DP<1>")
	)
	(segment
		(start 45.749464 0.0762)
		(end 45.546772 0.0762)
		(width 0.14224)
		(layer "In11.Cu")
		(net "M_J_DQS_DP<1>")
	)
	(segment
		(start 45.697648 -31.69539)
		(end 45.487082 -31.905956)
		(width 0.14224)
		(layer "In11.Cu")
		(net "M_J_DQS_DP<1>")
	)
	(segment
		(start 45.387514 -3.02641)
		(end 45.387514 -3.026156)
		(width 0.14224)
		(layer "In11.Cu")
		(net "M_J_DQS_DP<1>")
	)
	(segment
		(start 45.487082 -31.905956)
		(end 45.187616 -31.905956)
		(width 0.14224)
		(layer "In11.Cu")
		(net "M_J_DQS_DP<1>")
	)
	(segment
		(start 45.929042 -0.738378)
		(end 45.929042 -1.08712)
		(width 0.14224)
		(layer "In11.Cu")
		(net "M_J_DQS_DP<1>")
	)
	(segment
		(start 76.914502 -59.878976)
		(end 76.830174 -59.92749)
		(width 0.0889)
		(layer "In11.Cu")
		(net "M_J_DQS_DP<1>")
	)
	(segment
		(start 45.773848 -34.025586)
		(end 45.773848 -36.504626)
		(width 0.14224)
		(layer "In11.Cu")
		(net "M_J_DQS_DP<1>")
	)
	(segment
		(start 45.187616 -31.905956)
		(end 44.808648 -32.284924)
		(width 0.14224)
		(layer "In11.Cu")
		(net "M_J_DQS_DP<1>")
	)
	(segment
		(start 45.666406 -3.02641)
		(end 45.387514 -3.02641)
		(width 0.14224)
		(layer "In11.Cu")
		(net "M_J_DQS_DP<1>")
	)
	(segment
		(start 76.830174 -59.92749)
		(end 76.621386 -60.047886)
		(width 0.0889)
		(layer "In11.Cu")
		(net "M_J_DQS_DP<1>")
	)
	(segment
		(start 68.950332 -57.66689)
		(end 69.764402 -57.66689)
		(width 0.0889)
		(layer "In11.Cu")
		(net "M_J_DQS_DP<1>")
	)
	(segment
		(start 45.546772 -0.5334)
		(end 45.724064 -0.5334)
		(width 0.14224)
		(layer "In11.Cu")
		(net "M_J_DQS_DP<1>")
	)
	(segment
		(start 45.746162 -1.27)
		(end 45.619162 -1.27)
		(width 0.14224)
		(layer "In11.Cu")
		(net "M_J_DQS_DP<1>")
	)
	(segment
		(start 45.724064 -0.5334)
		(end 45.929042 -0.738378)
		(width 0.14224)
		(layer "In11.Cu")
		(net "M_J_DQS_DP<1>")
	)
	(segment
		(start 45.387514 -3.026156)
		(end 44.949618 -3.464052)
		(width 0.14224)
		(layer "In11.Cu")
		(net "M_J_DQS_DP<1>")
	)
	(segment
		(start 45.068998 -5.392674)
		(end 45.900594 -6.22427)
		(width 0.14224)
		(layer "In11.Cu")
		(net "M_J_DQS_DP<1>")
	)
	(segment
		(start 45.929042 -2.058924)
		(end 45.929042 -2.763774)
		(width 0.14224)
		(layer "In11.Cu")
		(net "M_J_DQS_DP<1>")
	)
	(segment
		(start 45.068998 -4.76123)
		(end 45.068998 -5.392674)
		(width 0.14224)
		(layer "In11.Cu")
		(net "M_J_DQS_DP<1>")
	)
	(segment
		(start 45.773848 -36.504626)
		(end 48.756062 -39.48684)
		(width 0.14224)
		(layer "In11.Cu")
		(net "M_J_DQS_DP<1>")
	)
	(segment
		(start 70.590156 -58.16219)
		(end 70.62978 -58.16219)
		(width 0.0889)
		(layer "In11.Cu")
		(net "M_J_DQS_DP<1>")
	)
	(segment
		(start 44.757848 -30.45079)
		(end 45.136054 -30.828996)
		(width 0.14224)
		(layer "In11.Cu")
		(net "M_J_DQS_DP<1>")
	)
	(segment
		(start 45.929042 0.255778)
		(end 45.749464 0.0762)
		(width 0.14224)
		(layer "In11.Cu")
		(net "M_J_DQS_DP<1>")
	)
	(segment
		(start 76.935584 -59.800236)
		(end 76.935838 -59.799982)
		(width 0.0889)
		(layer "In11.Cu")
		(net "M_J_DQS_DP<1>")
	)
	(segment
		(start 53.52034 -43.555158)
		(end 53.52034 -44.548044)
		(width 0.14224)
		(layer "In11.Cu")
		(net "M_J_DQS_DP<1>")
	)
	(segment
		(start 49.848262 -39.48684)
		(end 50.849276 -40.487854)
		(width 0.14224)
		(layer "In11.Cu")
		(net "M_J_DQS_DP<1>")
	)
	(segment
		(start 72.315832 -59.15279)
		(end 72.343772 -59.15279)
		(width 0.0889)
		(layer "In11.Cu")
		(net "M_J_DQS_DP<1>")
	)
	(segment
		(start 45.441362 -1.4478)
		(end 45.441362 -1.7018)
		(width 0.14224)
		(layer "In11.Cu")
		(net "M_J_DQS_DP<1>")
	)
	(segment
		(start 65.493138 -56.157114)
		(end 67.440556 -56.157114)
		(width 0.0889)
		(layer "In11.Cu")
		(net "M_J_DQS_DP<1>")
	)
	(segment
		(start 45.451522 -30.828996)
		(end 45.697648 -31.075122)
		(width 0.14224)
		(layer "In11.Cu")
		(net "M_J_DQS_DP<1>")
	)
	(segment
		(start 74.882756 -60.638436)
		(end 74.925936 -60.638436)
		(width 0.0889)
		(layer "In11.Cu")
		(net "M_J_DQS_DP<1>")
	)
	(segment
		(start 45.387514 1.181354)
		(end 45.6692 1.181354)
		(width 0.14224)
		(layer "In11.Cu")
		(net "M_J_DQS_DP<1>")
	)
	(segment
		(start 45.749718 -1.8796)
		(end 45.929042 -2.058924)
		(width 0.14224)
		(layer "In11.Cu")
		(net "M_J_DQS_DP<1>")
	)
	(segment
		(start 45.619162 -1.27)
		(end 45.441362 -1.4478)
		(width 0.14224)
		(layer "In11.Cu")
		(net "M_J_DQS_DP<1>")
	)
	(segment
		(start 71.452486 -58.65749)
		(end 71.4883 -58.65749)
		(width 0.0889)
		(layer "In11.Cu")
		(net "M_J_DQS_DP<1>")
	)
	(segment
		(start 45.929042 0.921512)
		(end 45.929042 0.255778)
		(width 0.14224)
		(layer "In11.Cu")
		(net "M_J_DQS_DP<1>")
	)
	(segment
		(start 76.935838 -59.799982)
		(end 76.914502 -59.878976)
		(width 0.0889)
		(layer "In11.Cu")
		(net "M_J_DQS_DP<1>")
	)
	(segment
		(start 44.949618 -3.464052)
		(end 44.949618 -4.64185)
		(width 0.14224)
		(layer "In11.Cu")
		(net "M_J_DQS_DP<1>")
	)
	(segment
		(start 75.74788 -60.14339)
		(end 75.780646 -60.14339)
		(width 0.0889)
		(layer "In11.Cu")
		(net "M_J_DQS_DP<1>")
	)
	(arc
		(start 69.764402 -57.66689)
		(mid 69.958252 -57.72324)
		(end 70.099936 -57.867042)
		(width 0.0889)
		(layer "In11.Cu")
		(net "M_J_DQS_DP<1>")
	)
	(arc
		(start 71.4883 -58.65749)
		(mid 71.678229 -58.71536)
		(end 71.816976 -58.857388)
		(width 0.0889)
		(layer "In11.Cu")
		(net "M_J_DQS_DP<1>")
	)
	(arc
		(start 70.099936 -57.867042)
		(mid 70.30694 -58.077906)
		(end 70.590156 -58.16219)
		(width 0.0889)
		(layer "In11.Cu")
		(net "M_J_DQS_DP<1>")
	)
	(arc
		(start 75.780646 -60.14339)
		(mid 76.06607 -60.059923)
		(end 76.274676 -59.847988)
		(width 0.0889)
		(layer "In11.Cu")
		(net "M_J_DQS_DP<1>")
	)
	(arc
		(start 74.392536 -60.343288)
		(mid 74.59954 -60.554152)
		(end 74.882756 -60.638436)
		(width 0.0889)
		(layer "In11.Cu")
		(net "M_J_DQS_DP<1>")
	)
	(arc
		(start 70.958456 -58.362088)
		(mid 71.167064 -58.57402)
		(end 71.452486 -58.65749)
		(width 0.0889)
		(layer "In11.Cu")
		(net "M_J_DQS_DP<1>")
	)
	(arc
		(start 73.198482 -59.647836)
		(mid 73.392332 -59.704186)
		(end 73.534016 -59.847988)
		(width 0.0889)
		(layer "In11.Cu")
		(net "M_J_DQS_DP<1>")
	)
	(arc
		(start 70.62978 -58.16219)
		(mid 70.819709 -58.22006)
		(end 70.958456 -58.362088)
		(width 0.0889)
		(layer "In11.Cu")
		(net "M_J_DQS_DP<1>")
	)
	(arc
		(start 74.060812 -60.14339)
		(mid 74.252454 -60.200556)
		(end 74.392536 -60.343288)
		(width 0.0889)
		(layer "In11.Cu")
		(net "M_J_DQS_DP<1>")
	)
	(arc
		(start 75.416156 -60.343288)
		(mid 75.556235 -60.200552)
		(end 75.74788 -60.14339)
		(width 0.0889)
		(layer "In11.Cu")
		(net "M_J_DQS_DP<1>")
	)
	(arc
		(start 72.675496 -59.352688)
		(mid 72.8825 -59.563552)
		(end 73.165716 -59.647836)
		(width 0.0889)
		(layer "In11.Cu")
		(net "M_J_DQS_DP<1>")
	)
	(arc
		(start 73.534016 -59.847988)
		(mid 73.742624 -60.05992)
		(end 74.028046 -60.14339)
		(width 0.0889)
		(layer "In11.Cu")
		(net "M_J_DQS_DP<1>")
	)
	(arc
		(start 76.274676 -59.847988)
		(mid 76.592496 -59.648721)
		(end 76.935584 -59.800236)
		(width 0.0889)
		(layer "In11.Cu")
		(net "M_J_DQS_DP<1>")
	)
	(arc
		(start 74.925936 -60.638436)
		(mid 75.209153 -60.554155)
		(end 75.416156 -60.343288)
		(width 0.0889)
		(layer "In11.Cu")
		(net "M_J_DQS_DP<1>")
	)
	(arc
		(start 71.816976 -58.857388)
		(mid 72.027689 -59.070467)
		(end 72.315832 -59.15279)
		(width 0.0889)
		(layer "In11.Cu")
		(net "M_J_DQS_DP<1>")
	)
	(arc
		(start 72.343772 -59.15279)
		(mid 72.535414 -59.209956)
		(end 72.675496 -59.352688)
		(width 0.0889)
		(layer "In11.Cu")
		(net "M_J_DQS_DP<1>")
	)
	(segment
		(start 71.6788 1.723898)
		(end 71.760334 1.499616)
		(width 0.1651)
		(layer "F.Cu")
		(net "M_J_DQS_DP<17>")
	)
	(segment
		(start 72.1995 3.162046)
		(end 71.763382 2.725928)
		(width 0.1651)
		(layer "F.Cu")
		(net "M_J_DQS_DP<17>")
	)
	(segment
		(start 71.760334 1.499616)
		(end 72.142096 1.117854)
		(width 0.1651)
		(layer "F.Cu")
		(net "M_J_DQS_DP<17>")
	)
	(segment
		(start 72.1995 3.778758)
		(end 72.1995 3.162046)
		(width 0.1651)
		(layer "F.Cu")
		(net "M_J_DQS_DP<17>")
	)
	(segment
		(start 71.6788 2.542032)
		(end 71.6788 1.723898)
		(width 0.1651)
		(layer "F.Cu")
		(net "M_J_DQS_DP<17>")
	)
	(segment
		(start 80.626712 -67.972686)
		(end 80.055212 -67.972686)
		(width 0.0889)
		(layer "F.Cu")
		(net "M_J_DQS_DP<17>")
	)
	(segment
		(start 71.763382 2.725928)
		(end 71.6788 2.542032)
		(width 0.1651)
		(layer "F.Cu")
		(net "M_J_DQS_DP<17>")
	)
	(via
		(at 72.142096 1.117854)
		(size 0.508)
		(drill 0.254)
		(layers "F.Cu" "B.Cu")
		(net "M_J_DQS_DP<17>")
	)
	(via
		(at 80.055212 -67.972686)
		(size 0.508)
		(drill 0.254)
		(layers "F.Cu" "B.Cu")
		(net "M_J_DQS_DP<17>")
	)
	(via
		(at 72.142096 -2.9718)
		(size 0.508)
		(drill 0.254)
		(layers "F.Cu" "B.Cu")
		(net "M_J_DQS_DP<17>")
	)
	(segment
		(start 72.1995 -5.004054)
		(end 71.743316 -4.54787)
		(width 0.1651)
		(layer "B.Cu")
		(net "M_J_DQS_DP<17>")
	)
	(segment
		(start 71.743316 -4.54787)
		(end 71.6661 -4.415536)
		(width 0.1651)
		(layer "B.Cu")
		(net "M_J_DQS_DP<17>")
	)
	(segment
		(start 71.6661 -4.415536)
		(end 71.6661 -3.519932)
		(width 0.1651)
		(layer "B.Cu")
		(net "M_J_DQS_DP<17>")
	)
	(segment
		(start 71.753476 -3.36042)
		(end 72.142096 -2.9718)
		(width 0.1651)
		(layer "B.Cu")
		(net "M_J_DQS_DP<17>")
	)
	(segment
		(start 71.6661 -3.519932)
		(end 71.753476 -3.36042)
		(width 0.1651)
		(layer "B.Cu")
		(net "M_J_DQS_DP<17>")
	)
	(segment
		(start 72.1995 -5.621782)
		(end 72.1995 -5.004054)
		(width 0.1651)
		(layer "B.Cu")
		(net "M_J_DQS_DP<17>")
	)
	(segment
		(start 79.463392 -52.783994)
		(end 79.881222 -52.366164)
		(width 0.0889)
		(layer "In4.Cu")
		(net "M_J_DQS_DP<17>")
	)
	(segment
		(start 79.537052 -54.810406)
		(end 79.543402 -54.799738)
		(width 0.0889)
		(layer "In4.Cu")
		(net "M_J_DQS_DP<17>")
	)
	(segment
		(start 79.881222 -51.949604)
		(end 79.773272 -51.841654)
		(width 0.0889)
		(layer "In4.Cu")
		(net "M_J_DQS_DP<17>")
	)
	(segment
		(start 75.435968 -34.920428)
		(end 75.31608 -34.80054)
		(width 0.14224)
		(layer "In4.Cu")
		(net "M_J_DQS_DP<17>")
	)
	(segment
		(start 79.543402 -59.752738)
		(end 79.548228 -59.744102)
		(width 0.0889)
		(layer "In4.Cu")
		(net "M_J_DQS_DP<17>")
	)
	(segment
		(start 74.064368 -33.856168)
		(end 74.341736 -33.5788)
		(width 0.14224)
		(layer "In4.Cu")
		(net "M_J_DQS_DP<17>")
	)
	(segment
		(start 79.733902 -48.087534)
		(end 75.435968 -43.7896)
		(width 0.14224)
		(layer "In4.Cu")
		(net "M_J_DQS_DP<17>")
	)
	(segment
		(start 75.31608 -34.80054)
		(end 74.341736 -34.80054)
		(width 0.14224)
		(layer "In4.Cu")
		(net "M_J_DQS_DP<17>")
	)
	(segment
		(start 79.733902 -49.361598)
		(end 79.733902 -49.3395)
		(width 0.0889)
		(layer "In4.Cu")
		(net "M_J_DQS_DP<17>")
	)
	(segment
		(start 75.435968 -32.68472)
		(end 72.655176 -29.903928)
		(width 0.14224)
		(layer "In4.Cu")
		(net "M_J_DQS_DP<17>")
	)
	(segment
		(start 80.055212 -67.972686)
		(end 80.053434 -67.968876)
		(width 0.0889)
		(layer "In4.Cu")
		(net "M_J_DQS_DP<17>")
	)
	(segment
		(start 74.064368 -34.523172)
		(end 74.064368 -33.856168)
		(width 0.14224)
		(layer "In4.Cu")
		(net "M_J_DQS_DP<17>")
	)
	(segment
		(start 79.773272 -49.400968)
		(end 79.733902 -49.361598)
		(width 0.0889)
		(layer "In4.Cu")
		(net "M_J_DQS_DP<17>")
	)
	(segment
		(start 79.543402 -58.362088)
		(end 79.537052 -58.35142)
		(width 0.0889)
		(layer "In4.Cu")
		(net "M_J_DQS_DP<17>")
	)
	(segment
		(start 79.543402 -62.724538)
		(end 79.548228 -62.715902)
		(width 0.0889)
		(layer "In4.Cu")
		(net "M_J_DQS_DP<17>")
	)
	(segment
		(start 72.655176 -29.903928)
		(end 72.655176 -6.57479)
		(width 0.14224)
		(layer "In4.Cu")
		(net "M_J_DQS_DP<17>")
	)
	(segment
		(start 72.655176 -6.57479)
		(end 71.67118 -5.590794)
		(width 0.14224)
		(layer "In4.Cu")
		(net "M_J_DQS_DP<17>")
	)
	(segment
		(start 74.341736 -33.5788)
		(end 75.31608 -33.5788)
		(width 0.14224)
		(layer "In4.Cu")
		(net "M_J_DQS_DP<17>")
	)
	(segment
		(start 79.537052 -62.735206)
		(end 79.543402 -62.724538)
		(width 0.0889)
		(layer "In4.Cu")
		(net "M_J_DQS_DP<17>")
	)
	(segment
		(start 79.537052 -56.791606)
		(end 79.543402 -56.780938)
		(width 0.0889)
		(layer "In4.Cu")
		(net "M_J_DQS_DP<17>")
	)
	(segment
		(start 79.543402 -56.780938)
		(end 79.548228 -56.772302)
		(width 0.0889)
		(layer "In4.Cu")
		(net "M_J_DQS_DP<17>")
	)
	(segment
		(start 79.543402 -65.696338)
		(end 79.548228 -65.687702)
		(width 0.0889)
		(layer "In4.Cu")
		(net "M_J_DQS_DP<17>")
	)
	(segment
		(start 79.543402 -60.743338)
		(end 79.548228 -60.734702)
		(width 0.0889)
		(layer "In4.Cu")
		(net "M_J_DQS_DP<17>")
	)
	(segment
		(start 79.543402 -54.799738)
		(end 79.548228 -54.791102)
		(width 0.0889)
		(layer "In4.Cu")
		(net "M_J_DQS_DP<17>")
	)
	(segment
		(start 75.31608 -33.5788)
		(end 75.435968 -33.458912)
		(width 0.14224)
		(layer "In4.Cu")
		(net "M_J_DQS_DP<17>")
	)
	(segment
		(start 79.537052 -59.763406)
		(end 79.543402 -59.752738)
		(width 0.0889)
		(layer "In4.Cu")
		(net "M_J_DQS_DP<17>")
	)
	(segment
		(start 71.67118 -5.590794)
		(end 71.67118 -3.442716)
		(width 0.14224)
		(layer "In4.Cu")
		(net "M_J_DQS_DP<17>")
	)
	(segment
		(start 79.543402 -53.809138)
		(end 79.548228 -53.800502)
		(width 0.0889)
		(layer "In4.Cu")
		(net "M_J_DQS_DP<17>")
	)
	(segment
		(start 79.543402 -61.733938)
		(end 79.548228 -61.725302)
		(width 0.0889)
		(layer "In4.Cu")
		(net "M_J_DQS_DP<17>")
	)
	(segment
		(start 79.463392 -53.270404)
		(end 79.463392 -52.783994)
		(width 0.0889)
		(layer "In4.Cu")
		(net "M_J_DQS_DP<17>")
	)
	(segment
		(start 79.543402 -57.771538)
		(end 79.548228 -57.762902)
		(width 0.0889)
		(layer "In4.Cu")
		(net "M_J_DQS_DP<17>")
	)
	(segment
		(start 74.341736 -34.80054)
		(end 74.064368 -34.523172)
		(width 0.14224)
		(layer "In4.Cu")
		(net "M_J_DQS_DP<17>")
	)
	(segment
		(start 75.435968 -33.458912)
		(end 75.435968 -32.68472)
		(width 0.14224)
		(layer "In4.Cu")
		(net "M_J_DQS_DP<17>")
	)
	(segment
		(start 79.543402 -55.790338)
		(end 79.548228 -55.781702)
		(width 0.0889)
		(layer "In4.Cu")
		(net "M_J_DQS_DP<17>")
	)
	(segment
		(start 79.543402 -53.409088)
		(end 79.463392 -53.270404)
		(width 0.0889)
		(layer "In4.Cu")
		(net "M_J_DQS_DP<17>")
	)
	(segment
		(start 79.537052 -53.819806)
		(end 79.543402 -53.809138)
		(width 0.0889)
		(layer "In4.Cu")
		(net "M_J_DQS_DP<17>")
	)
	(segment
		(start 79.773272 -51.841654)
		(end 79.773272 -49.400968)
		(width 0.0889)
		(layer "In4.Cu")
		(net "M_J_DQS_DP<17>")
	)
	(segment
		(start 79.537052 -63.725806)
		(end 79.543402 -63.715138)
		(width 0.0889)
		(layer "In4.Cu")
		(net "M_J_DQS_DP<17>")
	)
	(segment
		(start 79.537052 -64.716406)
		(end 79.543402 -64.705738)
		(width 0.0889)
		(layer "In4.Cu")
		(net "M_J_DQS_DP<17>")
	)
	(segment
		(start 79.543402 -64.705738)
		(end 79.548228 -64.697102)
		(width 0.0889)
		(layer "In4.Cu")
		(net "M_J_DQS_DP<17>")
	)
	(segment
		(start 79.537052 -55.801006)
		(end 79.543402 -55.790338)
		(width 0.0889)
		(layer "In4.Cu")
		(net "M_J_DQS_DP<17>")
	)
	(segment
		(start 79.537052 -60.754006)
		(end 79.543402 -60.743338)
		(width 0.0889)
		(layer "In4.Cu")
		(net "M_J_DQS_DP<17>")
	)
	(segment
		(start 71.67118 -3.442716)
		(end 72.142096 -2.9718)
		(width 0.14224)
		(layer "In4.Cu")
		(net "M_J_DQS_DP<17>")
	)
	(segment
		(start 79.881222 -52.366164)
		(end 79.881222 -51.949604)
		(width 0.0889)
		(layer "In4.Cu")
		(net "M_J_DQS_DP<17>")
	)
	(segment
		(start 79.543402 -63.715138)
		(end 79.548228 -63.706502)
		(width 0.0889)
		(layer "In4.Cu")
		(net "M_J_DQS_DP<17>")
	)
	(segment
		(start 79.537052 -65.707006)
		(end 79.543402 -65.696338)
		(width 0.0889)
		(layer "In4.Cu")
		(net "M_J_DQS_DP<17>")
	)
	(segment
		(start 79.537052 -61.744606)
		(end 79.543402 -61.733938)
		(width 0.0889)
		(layer "In4.Cu")
		(net "M_J_DQS_DP<17>")
	)
	(segment
		(start 79.733902 -49.3395)
		(end 79.733902 -48.087534)
		(width 0.14224)
		(layer "In4.Cu")
		(net "M_J_DQS_DP<17>")
	)
	(segment
		(start 75.435968 -43.7896)
		(end 75.435968 -34.920428)
		(width 0.14224)
		(layer "In4.Cu")
		(net "M_J_DQS_DP<17>")
	)
	(arc
		(start 79.543402 -58.761884)
		(mid 79.596901 -58.561986)
		(end 79.543402 -58.362088)
		(width 0.0889)
		(layer "In4.Cu")
		(net "M_J_DQS_DP<17>")
	)
	(arc
		(start 79.548228 -60.734702)
		(mid 79.596983 -60.53835)
		(end 79.543402 -60.343288)
		(width 0.0889)
		(layer "In4.Cu")
		(net "M_J_DQS_DP<17>")
	)
	(arc
		(start 79.548228 -57.762902)
		(mid 79.596983 -57.56655)
		(end 79.543402 -57.371488)
		(width 0.0889)
		(layer "In4.Cu")
		(net "M_J_DQS_DP<17>")
	)
	(arc
		(start 79.548228 -59.744102)
		(mid 79.596983 -59.54775)
		(end 79.543402 -59.352688)
		(width 0.0889)
		(layer "In4.Cu")
		(net "M_J_DQS_DP<17>")
	)
	(arc
		(start 79.548228 -63.706502)
		(mid 79.596983 -63.51015)
		(end 79.543402 -63.315088)
		(width 0.0889)
		(layer "In4.Cu")
		(net "M_J_DQS_DP<17>")
	)
	(arc
		(start 79.548228 -53.800502)
		(mid 79.596983 -53.60415)
		(end 79.543402 -53.409088)
		(width 0.0889)
		(layer "In4.Cu")
		(net "M_J_DQS_DP<17>")
	)
	(arc
		(start 79.543402 -60.343288)
		(mid 79.46418 -60.05417)
		(end 79.537052 -59.763406)
		(width 0.0889)
		(layer "In4.Cu")
		(net "M_J_DQS_DP<17>")
	)
	(arc
		(start 79.543402 -56.380888)
		(mid 79.46418 -56.09177)
		(end 79.537052 -55.801006)
		(width 0.0889)
		(layer "In4.Cu")
		(net "M_J_DQS_DP<17>")
	)
	(arc
		(start 79.537052 -58.35142)
		(mid 79.464254 -58.060657)
		(end 79.543402 -57.771538)
		(width 0.0889)
		(layer "In4.Cu")
		(net "M_J_DQS_DP<17>")
	)
	(arc
		(start 79.548228 -61.725302)
		(mid 79.596983 -61.52895)
		(end 79.543402 -61.333888)
		(width 0.0889)
		(layer "In4.Cu")
		(net "M_J_DQS_DP<17>")
	)
	(arc
		(start 79.548228 -64.697102)
		(mid 79.596983 -64.50075)
		(end 79.543402 -64.305688)
		(width 0.0889)
		(layer "In4.Cu")
		(net "M_J_DQS_DP<17>")
	)
	(arc
		(start 79.548228 -62.715902)
		(mid 79.596983 -62.51955)
		(end 79.543402 -62.324488)
		(width 0.0889)
		(layer "In4.Cu")
		(net "M_J_DQS_DP<17>")
	)
	(arc
		(start 79.543402 -63.315088)
		(mid 79.46418 -63.02597)
		(end 79.537052 -62.735206)
		(width 0.0889)
		(layer "In4.Cu")
		(net "M_J_DQS_DP<17>")
	)
	(arc
		(start 79.543402 -61.333888)
		(mid 79.46418 -61.04477)
		(end 79.537052 -60.754006)
		(width 0.0889)
		(layer "In4.Cu")
		(net "M_J_DQS_DP<17>")
	)
	(arc
		(start 79.708502 -67.181984)
		(mid 79.658687 -67.036259)
		(end 79.667608 -66.882518)
		(width 0.0889)
		(layer "In4.Cu")
		(net "M_J_DQS_DP<17>")
	)
	(arc
		(start 79.543402 -54.399688)
		(mid 79.46418 -54.11057)
		(end 79.537052 -53.819806)
		(width 0.0889)
		(layer "In4.Cu")
		(net "M_J_DQS_DP<17>")
	)
	(arc
		(start 79.548228 -56.772302)
		(mid 79.596983 -56.57595)
		(end 79.543402 -56.380888)
		(width 0.0889)
		(layer "In4.Cu")
		(net "M_J_DQS_DP<17>")
	)
	(arc
		(start 79.667608 -66.882518)
		(mid 79.65321 -66.57476)
		(end 79.543402 -66.286888)
		(width 0.0889)
		(layer "In4.Cu")
		(net "M_J_DQS_DP<17>")
	)
	(arc
		(start 79.548228 -54.791102)
		(mid 79.596983 -54.59475)
		(end 79.543402 -54.399688)
		(width 0.0889)
		(layer "In4.Cu")
		(net "M_J_DQS_DP<17>")
	)
	(arc
		(start 79.548228 -55.781702)
		(mid 79.596983 -55.58535)
		(end 79.543402 -55.390288)
		(width 0.0889)
		(layer "In4.Cu")
		(net "M_J_DQS_DP<17>")
	)
	(arc
		(start 79.543402 -59.352688)
		(mid 79.464271 -59.057286)
		(end 79.543402 -58.761884)
		(width 0.0889)
		(layer "In4.Cu")
		(net "M_J_DQS_DP<17>")
	)
	(arc
		(start 79.543402 -64.305688)
		(mid 79.46418 -64.01657)
		(end 79.537052 -63.725806)
		(width 0.0889)
		(layer "In4.Cu")
		(net "M_J_DQS_DP<17>")
	)
	(arc
		(start 79.543402 -65.296288)
		(mid 79.46418 -65.00717)
		(end 79.537052 -64.716406)
		(width 0.0889)
		(layer "In4.Cu")
		(net "M_J_DQS_DP<17>")
	)
	(arc
		(start 79.543402 -66.286888)
		(mid 79.464214 -65.99777)
		(end 79.537052 -65.707006)
		(width 0.0889)
		(layer "In4.Cu")
		(net "M_J_DQS_DP<17>")
	)
	(arc
		(start 80.053434 -67.968876)
		(mid 79.902616 -67.56594)
		(end 79.708502 -67.181984)
		(width 0.0889)
		(layer "In4.Cu")
		(net "M_J_DQS_DP<17>")
	)
	(arc
		(start 79.543402 -57.371488)
		(mid 79.46418 -57.08237)
		(end 79.537052 -56.791606)
		(width 0.0889)
		(layer "In4.Cu")
		(net "M_J_DQS_DP<17>")
	)
	(arc
		(start 79.543402 -55.390288)
		(mid 79.46418 -55.10117)
		(end 79.537052 -54.810406)
		(width 0.0889)
		(layer "In4.Cu")
		(net "M_J_DQS_DP<17>")
	)
	(arc
		(start 79.548228 -65.687702)
		(mid 79.596983 -65.49135)
		(end 79.543402 -65.296288)
		(width 0.0889)
		(layer "In4.Cu")
		(net "M_J_DQS_DP<17>")
	)
	(arc
		(start 79.543402 -62.324488)
		(mid 79.46418 -62.03537)
		(end 79.537052 -61.744606)
		(width 0.0889)
		(layer "In4.Cu")
		(net "M_J_DQS_DP<17>")
	)
	(segment
		(start 72.3265 -0.5842)
		(end 72.4535 -0.5842)
		(width 0.14224)
		(layer "In11.Cu")
		(net "M_J_DQS_DP<17>")
	)
	(segment
		(start 72.170544 -1.346708)
		(end 72.170544 -1.685036)
		(width 0.14224)
		(layer "In11.Cu")
		(net "M_J_DQS_DP<17>")
	)
	(segment
		(start 72.298052 -1.2192)
		(end 72.170544 -1.346708)
		(width 0.14224)
		(layer "In11.Cu")
		(net "M_J_DQS_DP<17>")
	)
	(segment
		(start 72.481186 1.32588)
		(end 72.66178 1.145286)
		(width 0.14224)
		(layer "In11.Cu")
		(net "M_J_DQS_DP<17>")
	)
	(segment
		(start 72.66178 -0.79248)
		(end 72.66178 -1.03632)
		(width 0.14224)
		(layer "In11.Cu")
		(net "M_J_DQS_DP<17>")
	)
	(segment
		(start 72.170544 -1.685036)
		(end 72.327008 -1.8415)
		(width 0.14224)
		(layer "In11.Cu")
		(net "M_J_DQS_DP<17>")
	)
	(segment
		(start 72.327008 -1.8415)
		(end 72.4154 -1.8415)
		(width 0.14224)
		(layer "In11.Cu")
		(net "M_J_DQS_DP<17>")
	)
	(segment
		(start 72.1741 -0.4318)
		(end 72.3265 -0.5842)
		(width 0.14224)
		(layer "In11.Cu")
		(net "M_J_DQS_DP<17>")
	)
	(segment
		(start 72.142096 1.117854)
		(end 72.350122 1.32588)
		(width 0.14224)
		(layer "In11.Cu")
		(net "M_J_DQS_DP<17>")
	)
	(segment
		(start 72.66178 0.30988)
		(end 72.1741 -0.1778)
		(width 0.14224)
		(layer "In11.Cu")
		(net "M_J_DQS_DP<17>")
	)
	(segment
		(start 72.4789 -1.2192)
		(end 72.298052 -1.2192)
		(width 0.14224)
		(layer "In11.Cu")
		(net "M_J_DQS_DP<17>")
	)
	(segment
		(start 72.1741 -0.1778)
		(end 72.1741 -0.4318)
		(width 0.14224)
		(layer "In11.Cu")
		(net "M_J_DQS_DP<17>")
	)
	(segment
		(start 72.66178 1.145286)
		(end 72.66178 0.30988)
		(width 0.14224)
		(layer "In11.Cu")
		(net "M_J_DQS_DP<17>")
	)
	(segment
		(start 72.66178 -2.08788)
		(end 72.66178 -2.731262)
		(width 0.14224)
		(layer "In11.Cu")
		(net "M_J_DQS_DP<17>")
	)
	(segment
		(start 72.4535 -0.5842)
		(end 72.66178 -0.79248)
		(width 0.14224)
		(layer "In11.Cu")
		(net "M_J_DQS_DP<17>")
	)
	(segment
		(start 72.66178 -1.03632)
		(end 72.4789 -1.2192)
		(width 0.14224)
		(layer "In11.Cu")
		(net "M_J_DQS_DP<17>")
	)
	(segment
		(start 72.4154 -1.8415)
		(end 72.66178 -2.08788)
		(width 0.14224)
		(layer "In11.Cu")
		(net "M_J_DQS_DP<17>")
	)
	(segment
		(start 72.421242 -2.9718)
		(end 72.142096 -2.9718)
		(width 0.14224)
		(layer "In11.Cu")
		(net "M_J_DQS_DP<17>")
	)
	(segment
		(start 72.350122 1.32588)
		(end 72.481186 1.32588)
		(width 0.14224)
		(layer "In11.Cu")
		(net "M_J_DQS_DP<17>")
	)
	(segment
		(start 72.66178 -2.731262)
		(end 72.421242 -2.9718)
		(width 0.14224)
		(layer "In11.Cu")
		(net "M_J_DQS_DP<17>")
	)
	(segment
		(start 146.149568 3.162046)
		(end 145.71345 2.725928)
		(width 0.1651)
		(layer "F.Cu")
		(net "M_J_DQS_DP<16>")
	)
	(segment
		(start 145.71345 2.725928)
		(end 145.628868 2.542032)
		(width 0.1651)
		(layer "F.Cu")
		(net "M_J_DQS_DP<16>")
	)
	(segment
		(start 145.628868 1.723898)
		(end 145.710402 1.499616)
		(width 0.1651)
		(layer "F.Cu")
		(net "M_J_DQS_DP<16>")
	)
	(segment
		(start 145.628868 2.542032)
		(end 145.628868 1.723898)
		(width 0.1651)
		(layer "F.Cu")
		(net "M_J_DQS_DP<16>")
	)
	(segment
		(start 146.149568 3.778758)
		(end 146.149568 3.162046)
		(width 0.1651)
		(layer "F.Cu")
		(net "M_J_DQS_DP<16>")
	)
	(segment
		(start 145.710402 1.499616)
		(end 146.092164 1.117854)
		(width 0.1651)
		(layer "F.Cu")
		(net "M_J_DQS_DP<16>")
	)
	(segment
		(start 122.504708 -63.334138)
		(end 121.933208 -63.334138)
		(width 0.0889)
		(layer "F.Cu")
		(net "M_J_DQS_DP<16>")
	)
	(via
		(at 121.933208 -63.334138)
		(size 0.508)
		(drill 0.254)
		(layers "F.Cu" "B.Cu")
		(net "M_J_DQS_DP<16>")
	)
	(via
		(at 146.092164 -2.9718)
		(size 0.508)
		(drill 0.254)
		(layers "F.Cu" "B.Cu")
		(net "M_J_DQS_DP<16>")
	)
	(via
		(at 146.092164 1.117854)
		(size 0.508)
		(drill 0.254)
		(layers "F.Cu" "B.Cu")
		(net "M_J_DQS_DP<16>")
	)
	(segment
		(start 145.616168 -3.519932)
		(end 145.703544 -3.36042)
		(width 0.1651)
		(layer "B.Cu")
		(net "M_J_DQS_DP<16>")
	)
	(segment
		(start 145.693384 -4.54787)
		(end 145.616168 -4.415536)
		(width 0.1651)
		(layer "B.Cu")
		(net "M_J_DQS_DP<16>")
	)
	(segment
		(start 146.149568 -5.004054)
		(end 145.693384 -4.54787)
		(width 0.1651)
		(layer "B.Cu")
		(net "M_J_DQS_DP<16>")
	)
	(segment
		(start 146.149568 -5.621782)
		(end 146.149568 -5.004054)
		(width 0.1651)
		(layer "B.Cu")
		(net "M_J_DQS_DP<16>")
	)
	(segment
		(start 145.616168 -4.415536)
		(end 145.616168 -3.519932)
		(width 0.1651)
		(layer "B.Cu")
		(net "M_J_DQS_DP<16>")
	)
	(segment
		(start 145.703544 -3.36042)
		(end 146.092164 -2.9718)
		(width 0.1651)
		(layer "B.Cu")
		(net "M_J_DQS_DP<16>")
	)
	(segment
		(start 147.038568 -28.42387)
		(end 146.81708 -28.202382)
		(width 0.14224)
		(layer "In11.Cu")
		(net "M_J_DQS_DP<16>")
	)
	(segment
		(start 146.81708 -29.279342)
		(end 147.038568 -29.057854)
		(width 0.14224)
		(layer "In11.Cu")
		(net "M_J_DQS_DP<16>")
	)
	(segment
		(start 146.611848 -1.03632)
		(end 146.611848 -0.79248)
		(width 0.14224)
		(layer "In11.Cu")
		(net "M_J_DQS_DP<16>")
	)
	(segment
		(start 130.494278 -45.728382)
		(end 135.319008 -40.90416)
		(width 0.14224)
		(layer "In11.Cu")
		(net "M_J_DQS_DP<16>")
	)
	(segment
		(start 146.380454 -25.555956)
		(end 146.380454 -24.888698)
		(width 0.14224)
		(layer "In11.Cu")
		(net "M_J_DQS_DP<16>")
	)
	(segment
		(start 146.380454 -26.586942)
		(end 146.66976 -26.586942)
		(width 0.14224)
		(layer "In11.Cu")
		(net "M_J_DQS_DP<16>")
	)
	(segment
		(start 121.426224 -54.722522)
		(end 121.421398 -54.713886)
		(width 0.0889)
		(layer "In11.Cu")
		(net "M_J_DQS_DP<16>")
	)
	(segment
		(start 121.879868 -51.483006)
		(end 121.879868 -50.837846)
		(width 0.0889)
		(layer "In11.Cu")
		(net "M_J_DQS_DP<16>")
	)
	(segment
		(start 121.421398 -56.695086)
		(end 121.415048 -56.684418)
		(width 0.0889)
		(layer "In11.Cu")
		(net "M_J_DQS_DP<16>")
	)
	(segment
		(start 123.37542 -49.652428)
		(end 123.37542 -49.596548)
		(width 0.0889)
		(layer "In11.Cu")
		(net "M_J_DQS_DP<16>")
	)
	(segment
		(start 121.421398 -57.685686)
		(end 121.415048 -57.675018)
		(width 0.0889)
		(layer "In11.Cu")
		(net "M_J_DQS_DP<16>")
	)
	(segment
		(start 123.391168 -49.5808)
		(end 125.981968 -46.99)
		(width 0.14224)
		(layer "In11.Cu")
		(net "M_J_DQS_DP<16>")
	)
	(segment
		(start 121.426224 -59.675522)
		(end 121.421398 -59.666886)
		(width 0.0889)
		(layer "In11.Cu")
		(net "M_J_DQS_DP<16>")
	)
	(segment
		(start 146.605244 -6.35127)
		(end 145.621248 -5.367274)
		(width 0.14224)
		(layer "In11.Cu")
		(net "M_J_DQS_DP<16>")
	)
	(segment
		(start 146.611848 1.145286)
		(end 146.431254 1.32588)
		(width 0.14224)
		(layer "In11.Cu")
		(net "M_J_DQS_DP<16>")
	)
	(segment
		(start 146.66976 -26.586942)
		(end 146.916648 -26.340054)
		(width 0.14224)
		(layer "In11.Cu")
		(net "M_J_DQS_DP<16>")
	)
	(segment
		(start 146.276568 -0.5842)
		(end 146.124168 -0.4318)
		(width 0.14224)
		(layer "In11.Cu")
		(net "M_J_DQS_DP<16>")
	)
	(segment
		(start 121.342912 -53.601366)
		(end 121.342912 -52.019962)
		(width 0.0889)
		(layer "In11.Cu")
		(net "M_J_DQS_DP<16>")
	)
	(segment
		(start 146.916648 -26.340054)
		(end 146.916648 -26.09215)
		(width 0.14224)
		(layer "In11.Cu")
		(net "M_J_DQS_DP<16>")
	)
	(segment
		(start 146.611848 0.30988)
		(end 146.611848 1.145286)
		(width 0.14224)
		(layer "In11.Cu")
		(net "M_J_DQS_DP<16>")
	)
	(segment
		(start 129.233168 -46.99)
		(end 130.494278 -45.72889)
		(width 0.14224)
		(layer "In11.Cu")
		(net "M_J_DQS_DP<16>")
	)
	(segment
		(start 121.342912 -52.019962)
		(end 121.879868 -51.483006)
		(width 0.0889)
		(layer "In11.Cu")
		(net "M_J_DQS_DP<16>")
	)
	(segment
		(start 146.916648 -26.09215)
		(end 146.380454 -25.555956)
		(width 0.14224)
		(layer "In11.Cu")
		(net "M_J_DQS_DP<16>")
	)
	(segment
		(start 146.092164 -2.9718)
		(end 146.37131 -2.9718)
		(width 0.14224)
		(layer "In11.Cu")
		(net "M_J_DQS_DP<16>")
	)
	(segment
		(start 146.888708 -24.201374)
		(end 146.605244 -23.91791)
		(width 0.14224)
		(layer "In11.Cu")
		(net "M_J_DQS_DP<16>")
	)
	(segment
		(start 146.120612 -1.346708)
		(end 146.24812 -1.2192)
		(width 0.14224)
		(layer "In11.Cu")
		(net "M_J_DQS_DP<16>")
	)
	(segment
		(start 121.426224 -57.694322)
		(end 121.421398 -57.685686)
		(width 0.0889)
		(layer "In11.Cu")
		(net "M_J_DQS_DP<16>")
	)
	(segment
		(start 122.862848 -50.165)
		(end 123.37542 -49.652428)
		(width 0.0889)
		(layer "In11.Cu")
		(net "M_J_DQS_DP<16>")
	)
	(segment
		(start 125.981968 -46.99)
		(end 129.233168 -46.99)
		(width 0.14224)
		(layer "In11.Cu")
		(net "M_J_DQS_DP<16>")
	)
	(segment
		(start 121.410222 -53.705506)
		(end 121.410222 -53.705252)
		(width 0.0889)
		(layer "In11.Cu")
		(net "M_J_DQS_DP<16>")
	)
	(segment
		(start 121.421398 -60.657486)
		(end 121.415048 -60.646818)
		(width 0.0889)
		(layer "In11.Cu")
		(net "M_J_DQS_DP<16>")
	)
	(segment
		(start 135.319008 -40.90416)
		(end 136.385808 -40.90416)
		(width 0.14224)
		(layer "In11.Cu")
		(net "M_J_DQS_DP<16>")
	)
	(segment
		(start 146.277076 -1.8415)
		(end 146.120612 -1.685036)
		(width 0.14224)
		(layer "In11.Cu")
		(net "M_J_DQS_DP<16>")
	)
	(segment
		(start 146.611848 -2.731262)
		(end 146.611848 -2.08788)
		(width 0.14224)
		(layer "In11.Cu")
		(net "M_J_DQS_DP<16>")
	)
	(segment
		(start 122.552714 -50.165)
		(end 122.862848 -50.165)
		(width 0.0889)
		(layer "In11.Cu")
		(net "M_J_DQS_DP<16>")
	)
	(segment
		(start 121.933208 -63.334138)
		(end 121.93143 -63.330328)
		(width 0.0889)
		(layer "In11.Cu")
		(net "M_J_DQS_DP<16>")
	)
	(segment
		(start 130.494278 -45.72889)
		(end 130.494278 -45.728382)
		(width 0.14224)
		(layer "In11.Cu")
		(net "M_J_DQS_DP<16>")
	)
	(segment
		(start 147.038568 -29.057854)
		(end 147.038568 -28.42387)
		(width 0.14224)
		(layer "In11.Cu")
		(net "M_J_DQS_DP<16>")
	)
	(segment
		(start 146.428968 -1.2192)
		(end 146.611848 -1.03632)
		(width 0.14224)
		(layer "In11.Cu")
		(net "M_J_DQS_DP<16>")
	)
	(segment
		(start 146.888708 -24.380444)
		(end 146.888708 -24.201374)
		(width 0.14224)
		(layer "In11.Cu")
		(net "M_J_DQS_DP<16>")
	)
	(segment
		(start 123.37542 -49.596548)
		(end 123.391168 -49.5808)
		(width 0.0889)
		(layer "In11.Cu")
		(net "M_J_DQS_DP<16>")
	)
	(segment
		(start 121.421398 -54.713886)
		(end 121.415048 -54.703218)
		(width 0.0889)
		(layer "In11.Cu")
		(net "M_J_DQS_DP<16>")
	)
	(segment
		(start 121.426224 -60.666122)
		(end 121.421398 -60.657486)
		(width 0.0889)
		(layer "In11.Cu")
		(net "M_J_DQS_DP<16>")
	)
	(segment
		(start 146.431254 1.32588)
		(end 146.30019 1.32588)
		(width 0.14224)
		(layer "In11.Cu")
		(net "M_J_DQS_DP<16>")
	)
	(segment
		(start 146.002248 -27.824176)
		(end 146.002248 -26.965148)
		(width 0.14224)
		(layer "In11.Cu")
		(net "M_J_DQS_DP<16>")
	)
	(segment
		(start 146.403568 -0.5842)
		(end 146.276568 -0.5842)
		(width 0.14224)
		(layer "In11.Cu")
		(net "M_J_DQS_DP<16>")
	)
	(segment
		(start 146.81708 -28.202382)
		(end 146.380454 -28.202382)
		(width 0.14224)
		(layer "In11.Cu")
		(net "M_J_DQS_DP<16>")
	)
	(segment
		(start 121.415048 -59.087004)
		(end 121.421398 -59.076336)
		(width 0.0889)
		(layer "In11.Cu")
		(net "M_J_DQS_DP<16>")
	)
	(segment
		(start 146.605244 -23.91791)
		(end 146.605244 -6.35127)
		(width 0.14224)
		(layer "In11.Cu")
		(net "M_J_DQS_DP<16>")
	)
	(segment
		(start 146.380454 -24.888698)
		(end 146.888708 -24.380444)
		(width 0.14224)
		(layer "In11.Cu")
		(net "M_J_DQS_DP<16>")
	)
	(segment
		(start 146.24812 -1.2192)
		(end 146.428968 -1.2192)
		(width 0.14224)
		(layer "In11.Cu")
		(net "M_J_DQS_DP<16>")
	)
	(segment
		(start 146.124168 -0.4318)
		(end 146.124168 -0.1778)
		(width 0.14224)
		(layer "In11.Cu")
		(net "M_J_DQS_DP<16>")
	)
	(segment
		(start 146.120612 -1.685036)
		(end 146.120612 -1.346708)
		(width 0.14224)
		(layer "In11.Cu")
		(net "M_J_DQS_DP<16>")
	)
	(segment
		(start 121.426224 -55.713122)
		(end 121.421398 -55.704486)
		(width 0.0889)
		(layer "In11.Cu")
		(net "M_J_DQS_DP<16>")
	)
	(segment
		(start 146.405854 -29.279342)
		(end 146.81708 -29.279342)
		(width 0.14224)
		(layer "In11.Cu")
		(net "M_J_DQS_DP<16>")
	)
	(segment
		(start 146.027648 -29.657548)
		(end 146.405854 -29.279342)
		(width 0.14224)
		(layer "In11.Cu")
		(net "M_J_DQS_DP<16>")
	)
	(segment
		(start 146.002248 -26.965148)
		(end 146.380454 -26.586942)
		(width 0.14224)
		(layer "In11.Cu")
		(net "M_J_DQS_DP<16>")
	)
	(segment
		(start 146.365468 -1.8415)
		(end 146.277076 -1.8415)
		(width 0.14224)
		(layer "In11.Cu")
		(net "M_J_DQS_DP<16>")
	)
	(segment
		(start 146.611848 -0.79248)
		(end 146.403568 -0.5842)
		(width 0.14224)
		(layer "In11.Cu")
		(net "M_J_DQS_DP<16>")
	)
	(segment
		(start 146.380454 -28.202382)
		(end 146.002248 -27.824176)
		(width 0.14224)
		(layer "In11.Cu")
		(net "M_J_DQS_DP<16>")
	)
	(segment
		(start 121.879868 -50.837846)
		(end 122.552714 -50.165)
		(width 0.0889)
		(layer "In11.Cu")
		(net "M_J_DQS_DP<16>")
	)
	(segment
		(start 146.30019 1.32588)
		(end 146.092164 1.117854)
		(width 0.14224)
		(layer "In11.Cu")
		(net "M_J_DQS_DP<16>")
	)
	(segment
		(start 146.37131 -2.9718)
		(end 146.611848 -2.731262)
		(width 0.14224)
		(layer "In11.Cu")
		(net "M_J_DQS_DP<16>")
	)
	(segment
		(start 146.027648 -31.26232)
		(end 146.027648 -29.657548)
		(width 0.14224)
		(layer "In11.Cu")
		(net "M_J_DQS_DP<16>")
	)
	(segment
		(start 121.421398 -55.704486)
		(end 121.415048 -55.693818)
		(width 0.0889)
		(layer "In11.Cu")
		(net "M_J_DQS_DP<16>")
	)
	(segment
		(start 146.611848 -2.08788)
		(end 146.365468 -1.8415)
		(width 0.14224)
		(layer "In11.Cu")
		(net "M_J_DQS_DP<16>")
	)
	(segment
		(start 136.385808 -40.90416)
		(end 146.027648 -31.26232)
		(width 0.14224)
		(layer "In11.Cu")
		(net "M_J_DQS_DP<16>")
	)
	(segment
		(start 145.621248 -3.442716)
		(end 146.092164 -2.9718)
		(width 0.14224)
		(layer "In11.Cu")
		(net "M_J_DQS_DP<16>")
	)
	(segment
		(start 121.421398 -54.123336)
		(end 121.421652 -54.123082)
		(width 0.0889)
		(layer "In11.Cu")
		(net "M_J_DQS_DP<16>")
	)
	(segment
		(start 121.410222 -53.705252)
		(end 121.342912 -53.601366)
		(width 0.0889)
		(layer "In11.Cu")
		(net "M_J_DQS_DP<16>")
	)
	(segment
		(start 145.621248 -5.367274)
		(end 145.621248 -3.442716)
		(width 0.14224)
		(layer "In11.Cu")
		(net "M_J_DQS_DP<16>")
	)
	(segment
		(start 121.426224 -56.703722)
		(end 121.421398 -56.695086)
		(width 0.0889)
		(layer "In11.Cu")
		(net "M_J_DQS_DP<16>")
	)
	(segment
		(start 146.124168 -0.1778)
		(end 146.611848 0.30988)
		(width 0.14224)
		(layer "In11.Cu")
		(net "M_J_DQS_DP<16>")
	)
	(arc
		(start 121.421398 -55.113936)
		(mid 121.474868 -54.918873)
		(end 121.426224 -54.722522)
		(width 0.0889)
		(layer "In11.Cu")
		(net "M_J_DQS_DP<16>")
	)
	(arc
		(start 121.415048 -56.684418)
		(mid 121.34225 -56.393655)
		(end 121.421398 -56.104536)
		(width 0.0889)
		(layer "In11.Cu")
		(net "M_J_DQS_DP<16>")
	)
	(arc
		(start 121.545604 -62.24397)
		(mid 121.531206 -61.936212)
		(end 121.421398 -61.64834)
		(width 0.0889)
		(layer "In11.Cu")
		(net "M_J_DQS_DP<16>")
	)
	(arc
		(start 121.421652 -54.123082)
		(mid 121.474814 -53.912694)
		(end 121.410222 -53.705506)
		(width 0.0889)
		(layer "In11.Cu")
		(net "M_J_DQS_DP<16>")
	)
	(arc
		(start 121.421398 -56.104536)
		(mid 121.474868 -55.909473)
		(end 121.426224 -55.713122)
		(width 0.0889)
		(layer "In11.Cu")
		(net "M_J_DQS_DP<16>")
	)
	(arc
		(start 121.421398 -58.085736)
		(mid 121.474868 -57.890673)
		(end 121.426224 -57.694322)
		(width 0.0889)
		(layer "In11.Cu")
		(net "M_J_DQS_DP<16>")
	)
	(arc
		(start 121.415048 -57.675018)
		(mid 121.34225 -57.384255)
		(end 121.421398 -57.095136)
		(width 0.0889)
		(layer "In11.Cu")
		(net "M_J_DQS_DP<16>")
	)
	(arc
		(start 121.421398 -60.066936)
		(mid 121.474868 -59.871873)
		(end 121.426224 -59.675522)
		(width 0.0889)
		(layer "In11.Cu")
		(net "M_J_DQS_DP<16>")
	)
	(arc
		(start 121.586498 -62.543436)
		(mid 121.536683 -62.397711)
		(end 121.545604 -62.24397)
		(width 0.0889)
		(layer "In11.Cu")
		(net "M_J_DQS_DP<16>")
	)
	(arc
		(start 121.421398 -58.67654)
		(mid 121.342267 -58.381138)
		(end 121.421398 -58.085736)
		(width 0.0889)
		(layer "In11.Cu")
		(net "M_J_DQS_DP<16>")
	)
	(arc
		(start 121.421398 -57.095136)
		(mid 121.474868 -56.900073)
		(end 121.426224 -56.703722)
		(width 0.0889)
		(layer "In11.Cu")
		(net "M_J_DQS_DP<16>")
	)
	(arc
		(start 121.415048 -54.703218)
		(mid 121.34225 -54.412455)
		(end 121.421398 -54.123336)
		(width 0.0889)
		(layer "In11.Cu")
		(net "M_J_DQS_DP<16>")
	)
	(arc
		(start 121.93143 -63.330328)
		(mid 121.780612 -62.927392)
		(end 121.586498 -62.543436)
		(width 0.0889)
		(layer "In11.Cu")
		(net "M_J_DQS_DP<16>")
	)
	(arc
		(start 121.415048 -60.646818)
		(mid 121.34225 -60.356055)
		(end 121.421398 -60.066936)
		(width 0.0889)
		(layer "In11.Cu")
		(net "M_J_DQS_DP<16>")
	)
	(arc
		(start 121.421398 -59.076336)
		(mid 121.474897 -58.876438)
		(end 121.421398 -58.67654)
		(width 0.0889)
		(layer "In11.Cu")
		(net "M_J_DQS_DP<16>")
	)
	(arc
		(start 121.421398 -59.666886)
		(mid 121.342176 -59.377768)
		(end 121.415048 -59.087004)
		(width 0.0889)
		(layer "In11.Cu")
		(net "M_J_DQS_DP<16>")
	)
	(arc
		(start 121.415048 -55.693818)
		(mid 121.34225 -55.403055)
		(end 121.421398 -55.113936)
		(width 0.0889)
		(layer "In11.Cu")
		(net "M_J_DQS_DP<16>")
	)
	(arc
		(start 121.421398 -61.64834)
		(mid 121.342267 -61.352938)
		(end 121.421398 -61.057536)
		(width 0.0889)
		(layer "In11.Cu")
		(net "M_J_DQS_DP<16>")
	)
	(arc
		(start 121.421398 -61.057536)
		(mid 121.474868 -60.862473)
		(end 121.426224 -60.666122)
		(width 0.0889)
		(layer "In11.Cu")
		(net "M_J_DQS_DP<16>")
	)
	(segment
		(start 136.278874 2.542032)
		(end 136.278874 1.723898)
		(width 0.1651)
		(layer "F.Cu")
		(net "M_J_DQS_DP<15>")
	)
	(segment
		(start 136.360408 1.499616)
		(end 136.74217 1.117854)
		(width 0.1651)
		(layer "F.Cu")
		(net "M_J_DQS_DP<15>")
	)
	(segment
		(start 136.278874 1.723898)
		(end 136.360408 1.499616)
		(width 0.1651)
		(layer "F.Cu")
		(net "M_J_DQS_DP<15>")
	)
	(segment
		(start 136.799574 3.778758)
		(end 136.799574 3.162046)
		(width 0.1651)
		(layer "F.Cu")
		(net "M_J_DQS_DP<15>")
	)
	(segment
		(start 117.353842 -63.334138)
		(end 116.782342 -63.334138)
		(width 0.0889)
		(layer "F.Cu")
		(net "M_J_DQS_DP<15>")
	)
	(segment
		(start 136.363456 2.725928)
		(end 136.278874 2.542032)
		(width 0.1651)
		(layer "F.Cu")
		(net "M_J_DQS_DP<15>")
	)
	(segment
		(start 136.799574 3.162046)
		(end 136.363456 2.725928)
		(width 0.1651)
		(layer "F.Cu")
		(net "M_J_DQS_DP<15>")
	)
	(via
		(at 136.74217 1.117854)
		(size 0.508)
		(drill 0.254)
		(layers "F.Cu" "B.Cu")
		(net "M_J_DQS_DP<15>")
	)
	(via
		(at 136.74217 -2.9718)
		(size 0.508)
		(drill 0.254)
		(layers "F.Cu" "B.Cu")
		(net "M_J_DQS_DP<15>")
	)
	(via
		(at 116.782342 -63.334138)
		(size 0.508)
		(drill 0.254)
		(layers "F.Cu" "B.Cu")
		(net "M_J_DQS_DP<15>")
	)
	(segment
		(start 136.34339 -4.54787)
		(end 136.266174 -4.415536)
		(width 0.1651)
		(layer "B.Cu")
		(net "M_J_DQS_DP<15>")
	)
	(segment
		(start 136.266174 -4.415536)
		(end 136.266174 -3.519932)
		(width 0.1651)
		(layer "B.Cu")
		(net "M_J_DQS_DP<15>")
	)
	(segment
		(start 136.799574 -5.004054)
		(end 136.34339 -4.54787)
		(width 0.1651)
		(layer "B.Cu")
		(net "M_J_DQS_DP<15>")
	)
	(segment
		(start 136.35355 -3.36042)
		(end 136.74217 -2.9718)
		(width 0.1651)
		(layer "B.Cu")
		(net "M_J_DQS_DP<15>")
	)
	(segment
		(start 136.266174 -3.519932)
		(end 136.35355 -3.36042)
		(width 0.1651)
		(layer "B.Cu")
		(net "M_J_DQS_DP<15>")
	)
	(segment
		(start 136.799574 -5.621782)
		(end 136.799574 -5.004054)
		(width 0.1651)
		(layer "B.Cu")
		(net "M_J_DQS_DP<15>")
	)
	(segment
		(start 137.078974 -1.2192)
		(end 137.261854 -1.03632)
		(width 0.14224)
		(layer "In11.Cu")
		(net "M_J_DQS_DP<15>")
	)
	(segment
		(start 116.782342 -63.334138)
		(end 116.782342 -63.332106)
		(width 0.0889)
		(layer "In11.Cu")
		(net "M_J_DQS_DP<15>")
	)
	(segment
		(start 129.1844 -34.733992)
		(end 129.1844 -34.343086)
		(width 0.14224)
		(layer "In11.Cu")
		(net "M_J_DQS_DP<15>")
	)
	(segment
		(start 119.72671 -39.432484)
		(end 124.203206 -34.95548)
		(width 0.14224)
		(layer "In11.Cu")
		(net "M_J_DQS_DP<15>")
	)
	(segment
		(start 128.962912 -34.95548)
		(end 129.1844 -34.733992)
		(width 0.14224)
		(layer "In11.Cu")
		(net "M_J_DQS_DP<15>")
	)
	(segment
		(start 116.829332 -45.863002)
		(end 119.72671 -42.965624)
		(width 0.14224)
		(layer "In11.Cu")
		(net "M_J_DQS_DP<15>")
	)
	(segment
		(start 137.25525 -29.308552)
		(end 137.25525 -6.541262)
		(width 0.14224)
		(layer "In11.Cu")
		(net "M_J_DQS_DP<15>")
	)
	(segment
		(start 128.328928 -34.95548)
		(end 128.962912 -34.95548)
		(width 0.14224)
		(layer "In11.Cu")
		(net "M_J_DQS_DP<15>")
	)
	(segment
		(start 116.275358 -54.722522)
		(end 116.270532 -54.713886)
		(width 0.0889)
		(layer "In11.Cu")
		(net "M_J_DQS_DP<15>")
	)
	(segment
		(start 116.782342 -63.332106)
		(end 116.780564 -63.330328)
		(width 0.0889)
		(layer "In11.Cu")
		(net "M_J_DQS_DP<15>")
	)
	(segment
		(start 130.51536 -33.96488)
		(end 130.79984 -34.24936)
		(width 0.14224)
		(layer "In11.Cu")
		(net "M_J_DQS_DP<15>")
	)
	(segment
		(start 124.203206 -34.95548)
		(end 126.138432 -34.95548)
		(width 0.14224)
		(layer "In11.Cu")
		(net "M_J_DQS_DP<15>")
	)
	(segment
		(start 116.270532 -60.657486)
		(end 116.264182 -60.646818)
		(width 0.0889)
		(layer "In11.Cu")
		(net "M_J_DQS_DP<15>")
	)
	(segment
		(start 116.829332 -46.732698)
		(end 116.829332 -46.7106)
		(width 0.0889)
		(layer "In11.Cu")
		(net "M_J_DQS_DP<15>")
	)
	(segment
		(start 137.021316 -2.9718)
		(end 137.261854 -2.731262)
		(width 0.14224)
		(layer "In11.Cu")
		(net "M_J_DQS_DP<15>")
	)
	(segment
		(start 136.770618 -1.346708)
		(end 136.898126 -1.2192)
		(width 0.14224)
		(layer "In11.Cu")
		(net "M_J_DQS_DP<15>")
	)
	(segment
		(start 128.10744 -34.733992)
		(end 128.328928 -34.95548)
		(width 0.14224)
		(layer "In11.Cu")
		(net "M_J_DQS_DP<15>")
	)
	(segment
		(start 136.926574 -0.5842)
		(end 136.774174 -0.4318)
		(width 0.14224)
		(layer "In11.Cu")
		(net "M_J_DQS_DP<15>")
	)
	(segment
		(start 126.299976 -34.793936)
		(end 126.299976 -34.408364)
		(width 0.14224)
		(layer "In11.Cu")
		(net "M_J_DQS_DP<15>")
	)
	(segment
		(start 137.261854 1.145286)
		(end 137.08126 1.32588)
		(width 0.14224)
		(layer "In11.Cu")
		(net "M_J_DQS_DP<15>")
	)
	(segment
		(start 130.79984 -34.828226)
		(end 130.927094 -34.95548)
		(width 0.14224)
		(layer "In11.Cu")
		(net "M_J_DQS_DP<15>")
	)
	(segment
		(start 116.324126 -51.633628)
		(end 115.899692 -51.209194)
		(width 0.0889)
		(layer "In11.Cu")
		(net "M_J_DQS_DP<15>")
	)
	(segment
		(start 116.264182 -59.087004)
		(end 116.270532 -59.076336)
		(width 0.0889)
		(layer "In11.Cu")
		(net "M_J_DQS_DP<15>")
	)
	(segment
		(start 137.261854 -1.03632)
		(end 137.261854 -0.79248)
		(width 0.14224)
		(layer "In11.Cu")
		(net "M_J_DQS_DP<15>")
	)
	(segment
		(start 136.271254 -5.557266)
		(end 136.271254 -3.442716)
		(width 0.14224)
		(layer "In11.Cu")
		(net "M_J_DQS_DP<15>")
	)
	(segment
		(start 119.72671 -42.965624)
		(end 119.72671 -39.432484)
		(width 0.14224)
		(layer "In11.Cu")
		(net "M_J_DQS_DP<15>")
	)
	(segment
		(start 126.74346 -33.96488)
		(end 127.729234 -33.96488)
		(width 0.14224)
		(layer "In11.Cu")
		(net "M_J_DQS_DP<15>")
	)
	(segment
		(start 128.10744 -34.343086)
		(end 128.10744 -34.733992)
		(width 0.14224)
		(layer "In11.Cu")
		(net "M_J_DQS_DP<15>")
	)
	(segment
		(start 136.74217 -2.9718)
		(end 137.021316 -2.9718)
		(width 0.14224)
		(layer "In11.Cu")
		(net "M_J_DQS_DP<15>")
	)
	(segment
		(start 136.774174 -0.4318)
		(end 136.774174 -0.1778)
		(width 0.14224)
		(layer "In11.Cu")
		(net "M_J_DQS_DP<15>")
	)
	(segment
		(start 115.899692 -50.741326)
		(end 116.041932 -50.368962)
		(width 0.0889)
		(layer "In11.Cu")
		(net "M_J_DQS_DP<15>")
	)
	(segment
		(start 137.08126 1.32588)
		(end 136.950196 1.32588)
		(width 0.14224)
		(layer "In11.Cu")
		(net "M_J_DQS_DP<15>")
	)
	(segment
		(start 136.770618 -1.685036)
		(end 136.770618 -1.346708)
		(width 0.14224)
		(layer "In11.Cu")
		(net "M_J_DQS_DP<15>")
	)
	(segment
		(start 116.270532 -54.713886)
		(end 116.264182 -54.703218)
		(width 0.0889)
		(layer "In11.Cu")
		(net "M_J_DQS_DP<15>")
	)
	(segment
		(start 130.79984 -34.24936)
		(end 130.79984 -34.828226)
		(width 0.14224)
		(layer "In11.Cu")
		(net "M_J_DQS_DP<15>")
	)
	(segment
		(start 116.868702 -47.458884)
		(end 116.868702 -46.772068)
		(width 0.0889)
		(layer "In11.Cu")
		(net "M_J_DQS_DP<15>")
	)
	(segment
		(start 116.868702 -46.772068)
		(end 116.829332 -46.732698)
		(width 0.0889)
		(layer "In11.Cu")
		(net "M_J_DQS_DP<15>")
	)
	(segment
		(start 136.898126 -1.2192)
		(end 137.078974 -1.2192)
		(width 0.14224)
		(layer "In11.Cu")
		(net "M_J_DQS_DP<15>")
	)
	(segment
		(start 116.275358 -60.666122)
		(end 116.270532 -60.657486)
		(width 0.0889)
		(layer "In11.Cu")
		(net "M_J_DQS_DP<15>")
	)
	(segment
		(start 127.729234 -33.96488)
		(end 128.10744 -34.343086)
		(width 0.14224)
		(layer "In11.Cu")
		(net "M_J_DQS_DP<15>")
	)
	(segment
		(start 137.053574 -0.5842)
		(end 136.926574 -0.5842)
		(width 0.14224)
		(layer "In11.Cu")
		(net "M_J_DQS_DP<15>")
	)
	(segment
		(start 129.1844 -34.343086)
		(end 129.562606 -33.96488)
		(width 0.14224)
		(layer "In11.Cu")
		(net "M_J_DQS_DP<15>")
	)
	(segment
		(start 116.324126 -53.921152)
		(end 116.324126 -51.633628)
		(width 0.0889)
		(layer "In11.Cu")
		(net "M_J_DQS_DP<15>")
	)
	(segment
		(start 116.270532 -56.695086)
		(end 116.264182 -56.684418)
		(width 0.0889)
		(layer "In11.Cu")
		(net "M_J_DQS_DP<15>")
	)
	(segment
		(start 116.275358 -56.703722)
		(end 116.270532 -56.695086)
		(width 0.0889)
		(layer "In11.Cu")
		(net "M_J_DQS_DP<15>")
	)
	(segment
		(start 137.261854 -2.731262)
		(end 137.261854 -2.08788)
		(width 0.14224)
		(layer "In11.Cu")
		(net "M_J_DQS_DP<15>")
	)
	(segment
		(start 126.299976 -34.408364)
		(end 126.74346 -33.96488)
		(width 0.14224)
		(layer "In11.Cu")
		(net "M_J_DQS_DP<15>")
	)
	(segment
		(start 131.608322 -34.95548)
		(end 137.25525 -29.308552)
		(width 0.14224)
		(layer "In11.Cu")
		(net "M_J_DQS_DP<15>")
	)
	(segment
		(start 116.270532 -55.704486)
		(end 116.264182 -55.693818)
		(width 0.0889)
		(layer "In11.Cu")
		(net "M_J_DQS_DP<15>")
	)
	(segment
		(start 116.270532 -57.685686)
		(end 116.264182 -57.675018)
		(width 0.0889)
		(layer "In11.Cu")
		(net "M_J_DQS_DP<15>")
	)
	(segment
		(start 136.774174 -0.1778)
		(end 137.261854 0.30988)
		(width 0.14224)
		(layer "In11.Cu")
		(net "M_J_DQS_DP<15>")
	)
	(segment
		(start 136.271254 -3.442716)
		(end 136.74217 -2.9718)
		(width 0.14224)
		(layer "In11.Cu")
		(net "M_J_DQS_DP<15>")
	)
	(segment
		(start 137.261854 -0.79248)
		(end 137.053574 -0.5842)
		(width 0.14224)
		(layer "In11.Cu")
		(net "M_J_DQS_DP<15>")
	)
	(segment
		(start 116.275358 -57.694322)
		(end 116.270532 -57.685686)
		(width 0.0889)
		(layer "In11.Cu")
		(net "M_J_DQS_DP<15>")
	)
	(segment
		(start 136.950196 1.32588)
		(end 136.74217 1.117854)
		(width 0.14224)
		(layer "In11.Cu")
		(net "M_J_DQS_DP<15>")
	)
	(segment
		(start 137.261854 -2.08788)
		(end 137.015474 -1.8415)
		(width 0.14224)
		(layer "In11.Cu")
		(net "M_J_DQS_DP<15>")
	)
	(segment
		(start 115.899692 -51.209194)
		(end 115.899692 -50.741326)
		(width 0.0889)
		(layer "In11.Cu")
		(net "M_J_DQS_DP<15>")
	)
	(segment
		(start 137.25525 -6.541262)
		(end 136.271254 -5.557266)
		(width 0.14224)
		(layer "In11.Cu")
		(net "M_J_DQS_DP<15>")
	)
	(segment
		(start 116.041932 -48.285654)
		(end 116.868702 -47.458884)
		(width 0.0889)
		(layer "In11.Cu")
		(net "M_J_DQS_DP<15>")
	)
	(segment
		(start 116.041932 -50.368962)
		(end 116.041932 -48.285654)
		(width 0.0889)
		(layer "In11.Cu")
		(net "M_J_DQS_DP<15>")
	)
	(segment
		(start 116.275358 -55.713122)
		(end 116.270532 -55.704486)
		(width 0.0889)
		(layer "In11.Cu")
		(net "M_J_DQS_DP<15>")
	)
	(segment
		(start 136.927082 -1.8415)
		(end 136.770618 -1.685036)
		(width 0.14224)
		(layer "In11.Cu")
		(net "M_J_DQS_DP<15>")
	)
	(segment
		(start 126.138432 -34.95548)
		(end 126.299976 -34.793936)
		(width 0.14224)
		(layer "In11.Cu")
		(net "M_J_DQS_DP<15>")
	)
	(segment
		(start 130.927094 -34.95548)
		(end 131.608322 -34.95548)
		(width 0.14224)
		(layer "In11.Cu")
		(net "M_J_DQS_DP<15>")
	)
	(segment
		(start 116.829332 -46.7106)
		(end 116.829332 -45.863002)
		(width 0.14224)
		(layer "In11.Cu")
		(net "M_J_DQS_DP<15>")
	)
	(segment
		(start 129.562606 -33.96488)
		(end 130.51536 -33.96488)
		(width 0.14224)
		(layer "In11.Cu")
		(net "M_J_DQS_DP<15>")
	)
	(segment
		(start 116.275358 -59.675522)
		(end 116.270532 -59.666886)
		(width 0.0889)
		(layer "In11.Cu")
		(net "M_J_DQS_DP<15>")
	)
	(segment
		(start 137.261854 0.30988)
		(end 137.261854 1.145286)
		(width 0.14224)
		(layer "In11.Cu")
		(net "M_J_DQS_DP<15>")
	)
	(segment
		(start 137.015474 -1.8415)
		(end 136.927082 -1.8415)
		(width 0.14224)
		(layer "In11.Cu")
		(net "M_J_DQS_DP<15>")
	)
	(segment
		(start 116.270532 -54.123336)
		(end 116.270786 -54.123082)
		(width 0.0889)
		(layer "In11.Cu")
		(net "M_J_DQS_DP<15>")
	)
	(arc
		(start 116.270786 -54.123082)
		(mid 116.310867 -54.025662)
		(end 116.324126 -53.921152)
		(width 0.0889)
		(layer "In11.Cu")
		(net "M_J_DQS_DP<15>")
	)
	(arc
		(start 116.270532 -55.113936)
		(mid 116.324002 -54.918873)
		(end 116.275358 -54.722522)
		(width 0.0889)
		(layer "In11.Cu")
		(net "M_J_DQS_DP<15>")
	)
	(arc
		(start 116.780564 -63.330328)
		(mid 116.629746 -62.927392)
		(end 116.435632 -62.543436)
		(width 0.0889)
		(layer "In11.Cu")
		(net "M_J_DQS_DP<15>")
	)
	(arc
		(start 116.264182 -55.693818)
		(mid 116.191384 -55.403055)
		(end 116.270532 -55.113936)
		(width 0.0889)
		(layer "In11.Cu")
		(net "M_J_DQS_DP<15>")
	)
	(arc
		(start 116.264182 -60.646818)
		(mid 116.191384 -60.356055)
		(end 116.270532 -60.066936)
		(width 0.0889)
		(layer "In11.Cu")
		(net "M_J_DQS_DP<15>")
	)
	(arc
		(start 116.270532 -60.066936)
		(mid 116.324002 -59.871873)
		(end 116.275358 -59.675522)
		(width 0.0889)
		(layer "In11.Cu")
		(net "M_J_DQS_DP<15>")
	)
	(arc
		(start 116.270532 -59.666886)
		(mid 116.19131 -59.377768)
		(end 116.264182 -59.087004)
		(width 0.0889)
		(layer "In11.Cu")
		(net "M_J_DQS_DP<15>")
	)
	(arc
		(start 116.270532 -61.057536)
		(mid 116.324002 -60.862473)
		(end 116.275358 -60.666122)
		(width 0.0889)
		(layer "In11.Cu")
		(net "M_J_DQS_DP<15>")
	)
	(arc
		(start 116.264182 -57.675018)
		(mid 116.191384 -57.384255)
		(end 116.270532 -57.095136)
		(width 0.0889)
		(layer "In11.Cu")
		(net "M_J_DQS_DP<15>")
	)
	(arc
		(start 116.394738 -62.24397)
		(mid 116.38034 -61.936212)
		(end 116.270532 -61.64834)
		(width 0.0889)
		(layer "In11.Cu")
		(net "M_J_DQS_DP<15>")
	)
	(arc
		(start 116.270532 -58.085736)
		(mid 116.324002 -57.890673)
		(end 116.275358 -57.694322)
		(width 0.0889)
		(layer "In11.Cu")
		(net "M_J_DQS_DP<15>")
	)
	(arc
		(start 116.264182 -54.703218)
		(mid 116.191384 -54.412455)
		(end 116.270532 -54.123336)
		(width 0.0889)
		(layer "In11.Cu")
		(net "M_J_DQS_DP<15>")
	)
	(arc
		(start 116.264182 -56.684418)
		(mid 116.191384 -56.393655)
		(end 116.270532 -56.104536)
		(width 0.0889)
		(layer "In11.Cu")
		(net "M_J_DQS_DP<15>")
	)
	(arc
		(start 116.270532 -56.104536)
		(mid 116.324002 -55.909473)
		(end 116.275358 -55.713122)
		(width 0.0889)
		(layer "In11.Cu")
		(net "M_J_DQS_DP<15>")
	)
	(arc
		(start 116.435632 -62.543436)
		(mid 116.385817 -62.397711)
		(end 116.394738 -62.24397)
		(width 0.0889)
		(layer "In11.Cu")
		(net "M_J_DQS_DP<15>")
	)
	(arc
		(start 116.270532 -61.64834)
		(mid 116.191401 -61.352938)
		(end 116.270532 -61.057536)
		(width 0.0889)
		(layer "In11.Cu")
		(net "M_J_DQS_DP<15>")
	)
	(arc
		(start 116.270532 -59.076336)
		(mid 116.324031 -58.876438)
		(end 116.270532 -58.67654)
		(width 0.0889)
		(layer "In11.Cu")
		(net "M_J_DQS_DP<15>")
	)
	(arc
		(start 116.270532 -57.095136)
		(mid 116.324002 -56.900073)
		(end 116.275358 -56.703722)
		(width 0.0889)
		(layer "In11.Cu")
		(net "M_J_DQS_DP<15>")
	)
	(arc
		(start 116.270532 -58.67654)
		(mid 116.191401 -58.381138)
		(end 116.270532 -58.085736)
		(width 0.0889)
		(layer "In11.Cu")
		(net "M_J_DQS_DP<15>")
	)
	(segment
		(start 127.44958 3.778758)
		(end 127.44958 3.162046)
		(width 0.1651)
		(layer "F.Cu")
		(net "M_J_DQS_DP<14>")
	)
	(segment
		(start 127.010414 1.499616)
		(end 127.392176 1.117854)
		(width 0.1651)
		(layer "F.Cu")
		(net "M_J_DQS_DP<14>")
	)
	(segment
		(start 126.92888 1.723898)
		(end 127.010414 1.499616)
		(width 0.1651)
		(layer "F.Cu")
		(net "M_J_DQS_DP<14>")
	)
	(segment
		(start 127.013462 2.725928)
		(end 126.92888 2.542032)
		(width 0.1651)
		(layer "F.Cu")
		(net "M_J_DQS_DP<14>")
	)
	(segment
		(start 126.92888 2.542032)
		(end 126.92888 1.723898)
		(width 0.1651)
		(layer "F.Cu")
		(net "M_J_DQS_DP<14>")
	)
	(segment
		(start 114.778282 -59.866784)
		(end 114.206782 -59.866784)
		(width 0.0889)
		(layer "F.Cu")
		(net "M_J_DQS_DP<14>")
	)
	(segment
		(start 127.44958 3.162046)
		(end 127.013462 2.725928)
		(width 0.1651)
		(layer "F.Cu")
		(net "M_J_DQS_DP<14>")
	)
	(via
		(at 127.392176 -2.9718)
		(size 0.508)
		(drill 0.254)
		(layers "F.Cu" "B.Cu")
		(net "M_J_DQS_DP<14>")
	)
	(via
		(at 127.392176 1.117854)
		(size 0.508)
		(drill 0.254)
		(layers "F.Cu" "B.Cu")
		(net "M_J_DQS_DP<14>")
	)
	(via
		(at 114.206782 -59.866784)
		(size 0.508)
		(drill 0.254)
		(layers "F.Cu" "B.Cu")
		(net "M_J_DQS_DP<14>")
	)
	(segment
		(start 126.91618 -3.519932)
		(end 127.003556 -3.36042)
		(width 0.1651)
		(layer "B.Cu")
		(net "M_J_DQS_DP<14>")
	)
	(segment
		(start 127.003556 -3.36042)
		(end 127.392176 -2.9718)
		(width 0.1651)
		(layer "B.Cu")
		(net "M_J_DQS_DP<14>")
	)
	(segment
		(start 126.993396 -4.54787)
		(end 126.91618 -4.415536)
		(width 0.1651)
		(layer "B.Cu")
		(net "M_J_DQS_DP<14>")
	)
	(segment
		(start 127.44958 -5.004054)
		(end 126.993396 -4.54787)
		(width 0.1651)
		(layer "B.Cu")
		(net "M_J_DQS_DP<14>")
	)
	(segment
		(start 127.44958 -5.621782)
		(end 127.44958 -5.004054)
		(width 0.1651)
		(layer "B.Cu")
		(net "M_J_DQS_DP<14>")
	)
	(segment
		(start 126.91618 -4.415536)
		(end 126.91618 -3.519932)
		(width 0.1651)
		(layer "B.Cu")
		(net "M_J_DQS_DP<14>")
	)
	(segment
		(start 114.206528 -51.975766)
		(end 114.206528 -52.777644)
		(width 0.0889)
		(layer "In4.Cu")
		(net "M_J_DQS_DP<14>")
	)
	(segment
		(start 126.772162 -30.652212)
		(end 126.284228 -30.652212)
		(width 0.14224)
		(layer "In4.Cu")
		(net "M_J_DQS_DP<14>")
	)
	(segment
		(start 126.18974 -32.354774)
		(end 126.18974 -32.693356)
		(width 0.14224)
		(layer "In4.Cu")
		(net "M_J_DQS_DP<14>")
	)
	(segment
		(start 127.392176 -2.9718)
		(end 126.92126 -3.442716)
		(width 0.14224)
		(layer "In4.Cu")
		(net "M_J_DQS_DP<14>")
	)
	(segment
		(start 127.905256 -30.261052)
		(end 128.04902 -30.404816)
		(width 0.14224)
		(layer "In4.Cu")
		(net "M_J_DQS_DP<14>")
	)
	(segment
		(start 113.699798 -54.61)
		(end 113.694972 -54.618636)
		(width 0.0889)
		(layer "In4.Cu")
		(net "M_J_DQS_DP<14>")
	)
	(segment
		(start 113.699798 -55.6006)
		(end 113.694972 -55.609236)
		(width 0.0889)
		(layer "In4.Cu")
		(net "M_J_DQS_DP<14>")
	)
	(segment
		(start 115.021868 -49.989994)
		(end 115.021868 -51.160426)
		(width 0.0889)
		(layer "In4.Cu")
		(net "M_J_DQS_DP<14>")
	)
	(segment
		(start 113.694972 -55.609236)
		(end 113.688622 -55.619904)
		(width 0.0889)
		(layer "In4.Cu")
		(net "M_J_DQS_DP<14>")
	)
	(segment
		(start 114.206528 -52.777644)
		(end 113.74882 -53.235352)
		(width 0.0889)
		(layer "In4.Cu")
		(net "M_J_DQS_DP<14>")
	)
	(segment
		(start 113.699798 -57.5818)
		(end 113.694972 -57.590436)
		(width 0.0889)
		(layer "In4.Cu")
		(net "M_J_DQS_DP<14>")
	)
	(segment
		(start 126.18974 -32.693356)
		(end 116.78793 -42.095166)
		(width 0.14224)
		(layer "In4.Cu")
		(net "M_J_DQS_DP<14>")
	)
	(segment
		(start 128.04902 -30.7467)
		(end 127.62865 -31.16707)
		(width 0.14224)
		(layer "In4.Cu")
		(net "M_J_DQS_DP<14>")
	)
	(segment
		(start 113.74882 -53.429408)
		(end 113.748566 -53.429662)
		(width 0.0889)
		(layer "In4.Cu")
		(net "M_J_DQS_DP<14>")
	)
	(segment
		(start 113.694972 -54.618636)
		(end 113.688622 -54.629304)
		(width 0.0889)
		(layer "In4.Cu")
		(net "M_J_DQS_DP<14>")
	)
	(segment
		(start 126.92126 -3.442716)
		(end 126.92126 -5.367274)
		(width 0.14224)
		(layer "In4.Cu")
		(net "M_J_DQS_DP<14>")
	)
	(segment
		(start 127.905256 -6.35127)
		(end 127.905256 -30.261052)
		(width 0.14224)
		(layer "In4.Cu")
		(net "M_J_DQS_DP<14>")
	)
	(segment
		(start 113.843308 -59.046872)
		(end 113.957862 -59.248294)
		(width 0.0889)
		(layer "In4.Cu")
		(net "M_J_DQS_DP<14>")
	)
	(segment
		(start 127.62865 -31.16707)
		(end 127.28702 -31.16707)
		(width 0.14224)
		(layer "In4.Cu")
		(net "M_J_DQS_DP<14>")
	)
	(segment
		(start 116.8273 -47.336964)
		(end 116.8273 -48.184562)
		(width 0.0889)
		(layer "In4.Cu")
		(net "M_J_DQS_DP<14>")
	)
	(segment
		(start 116.78793 -47.275496)
		(end 116.78793 -47.297594)
		(width 0.0889)
		(layer "In4.Cu")
		(net "M_J_DQS_DP<14>")
	)
	(segment
		(start 113.957862 -59.248294)
		(end 114.11712 -59.528202)
		(width 0.0889)
		(layer "In4.Cu")
		(net "M_J_DQS_DP<14>")
	)
	(segment
		(start 126.92126 -5.367274)
		(end 127.905256 -6.35127)
		(width 0.14224)
		(layer "In4.Cu")
		(net "M_J_DQS_DP<14>")
	)
	(segment
		(start 113.694972 -57.590436)
		(end 113.688622 -57.601104)
		(width 0.0889)
		(layer "In4.Cu")
		(net "M_J_DQS_DP<14>")
	)
	(segment
		(start 113.699798 -56.5912)
		(end 113.694972 -56.599836)
		(width 0.0889)
		(layer "In4.Cu")
		(net "M_J_DQS_DP<14>")
	)
	(segment
		(start 116.78793 -47.297594)
		(end 116.8273 -47.336964)
		(width 0.0889)
		(layer "In4.Cu")
		(net "M_J_DQS_DP<14>")
	)
	(segment
		(start 127.28702 -31.16707)
		(end 126.772162 -30.652212)
		(width 0.14224)
		(layer "In4.Cu")
		(net "M_J_DQS_DP<14>")
	)
	(segment
		(start 125.653546 -31.81858)
		(end 126.18974 -32.354774)
		(width 0.14224)
		(layer "In4.Cu")
		(net "M_J_DQS_DP<14>")
	)
	(segment
		(start 113.74882 -53.235352)
		(end 113.74882 -53.429408)
		(width 0.0889)
		(layer "In4.Cu")
		(net "M_J_DQS_DP<14>")
	)
	(segment
		(start 126.284228 -30.652212)
		(end 125.653546 -31.282894)
		(width 0.14224)
		(layer "In4.Cu")
		(net "M_J_DQS_DP<14>")
	)
	(segment
		(start 116.8273 -48.184562)
		(end 115.021868 -49.989994)
		(width 0.0889)
		(layer "In4.Cu")
		(net "M_J_DQS_DP<14>")
	)
	(segment
		(start 125.653546 -31.282894)
		(end 125.653546 -31.81858)
		(width 0.14224)
		(layer "In4.Cu")
		(net "M_J_DQS_DP<14>")
	)
	(segment
		(start 128.04902 -30.404816)
		(end 128.04902 -30.7467)
		(width 0.14224)
		(layer "In4.Cu")
		(net "M_J_DQS_DP<14>")
	)
	(segment
		(start 113.694972 -56.599836)
		(end 113.688622 -56.610504)
		(width 0.0889)
		(layer "In4.Cu")
		(net "M_J_DQS_DP<14>")
	)
	(segment
		(start 116.78793 -42.095166)
		(end 116.78793 -47.275496)
		(width 0.14224)
		(layer "In4.Cu")
		(net "M_J_DQS_DP<14>")
	)
	(segment
		(start 115.021868 -51.160426)
		(end 114.206528 -51.975766)
		(width 0.0889)
		(layer "In4.Cu")
		(net "M_J_DQS_DP<14>")
	)
	(arc
		(start 113.688622 -56.610504)
		(mid 113.615824 -56.901267)
		(end 113.694972 -57.190386)
		(width 0.0889)
		(layer "In4.Cu")
		(net "M_J_DQS_DP<14>")
	)
	(arc
		(start 113.688622 -55.619904)
		(mid 113.615824 -55.910667)
		(end 113.694972 -56.199786)
		(width 0.0889)
		(layer "In4.Cu")
		(net "M_J_DQS_DP<14>")
	)
	(arc
		(start 113.694972 -54.218586)
		(mid 113.748442 -54.413649)
		(end 113.699798 -54.61)
		(width 0.0889)
		(layer "In4.Cu")
		(net "M_J_DQS_DP<14>")
	)
	(arc
		(start 113.725706 -58.247534)
		(mid 113.745002 -58.327558)
		(end 113.74755 -58.40984)
		(width 0.0889)
		(layer "In4.Cu")
		(net "M_J_DQS_DP<14>")
	)
	(arc
		(start 114.11712 -59.528202)
		(mid 114.183946 -59.691665)
		(end 114.206782 -59.866784)
		(width 0.0889)
		(layer "In4.Cu")
		(net "M_J_DQS_DP<14>")
	)
	(arc
		(start 113.694972 -58.180986)
		(mid 113.711868 -58.213554)
		(end 113.725706 -58.247534)
		(width 0.0889)
		(layer "In4.Cu")
		(net "M_J_DQS_DP<14>")
	)
	(arc
		(start 113.694972 -53.627782)
		(mid 113.615841 -53.923184)
		(end 113.694972 -54.218586)
		(width 0.0889)
		(layer "In4.Cu")
		(net "M_J_DQS_DP<14>")
	)
	(arc
		(start 113.694972 -56.199786)
		(mid 113.748442 -56.394849)
		(end 113.699798 -56.5912)
		(width 0.0889)
		(layer "In4.Cu")
		(net "M_J_DQS_DP<14>")
	)
	(arc
		(start 113.748566 -53.429662)
		(mid 113.734669 -53.53221)
		(end 113.694972 -53.627782)
		(width 0.0889)
		(layer "In4.Cu")
		(net "M_J_DQS_DP<14>")
	)
	(arc
		(start 113.688622 -54.629304)
		(mid 113.615824 -54.920067)
		(end 113.694972 -55.209186)
		(width 0.0889)
		(layer "In4.Cu")
		(net "M_J_DQS_DP<14>")
	)
	(arc
		(start 113.74755 -58.40984)
		(mid 113.760087 -58.73367)
		(end 113.843308 -59.046872)
		(width 0.0889)
		(layer "In4.Cu")
		(net "M_J_DQS_DP<14>")
	)
	(arc
		(start 113.694972 -57.190386)
		(mid 113.748442 -57.385449)
		(end 113.699798 -57.5818)
		(width 0.0889)
		(layer "In4.Cu")
		(net "M_J_DQS_DP<14>")
	)
	(arc
		(start 113.688622 -57.601104)
		(mid 113.615824 -57.891867)
		(end 113.694972 -58.180986)
		(width 0.0889)
		(layer "In4.Cu")
		(net "M_J_DQS_DP<14>")
	)
	(arc
		(start 113.694972 -55.209186)
		(mid 113.748442 -55.404249)
		(end 113.699798 -55.6006)
		(width 0.0889)
		(layer "In4.Cu")
		(net "M_J_DQS_DP<14>")
	)
	(segment
		(start 127.91186 0.30988)
		(end 127.91186 1.145286)
		(width 0.14224)
		(layer "In11.Cu")
		(net "M_J_DQS_DP<14>")
	)
	(segment
		(start 127.392176 -2.9718)
		(end 127.671322 -2.9718)
		(width 0.14224)
		(layer "In11.Cu")
		(net "M_J_DQS_DP<14>")
	)
	(segment
		(start 127.731266 1.32588)
		(end 127.600202 1.32588)
		(width 0.14224)
		(layer "In11.Cu")
		(net "M_J_DQS_DP<14>")
	)
	(segment
		(start 127.91186 -1.03632)
		(end 127.91186 -0.79248)
		(width 0.14224)
		(layer "In11.Cu")
		(net "M_J_DQS_DP<14>")
	)
	(segment
		(start 127.600202 1.32588)
		(end 127.392176 1.117854)
		(width 0.14224)
		(layer "In11.Cu")
		(net "M_J_DQS_DP<14>")
	)
	(segment
		(start 127.420624 -1.685036)
		(end 127.420624 -1.346708)
		(width 0.14224)
		(layer "In11.Cu")
		(net "M_J_DQS_DP<14>")
	)
	(segment
		(start 127.577088 -1.8415)
		(end 127.420624 -1.685036)
		(width 0.14224)
		(layer "In11.Cu")
		(net "M_J_DQS_DP<14>")
	)
	(segment
		(start 127.70358 -0.5842)
		(end 127.57658 -0.5842)
		(width 0.14224)
		(layer "In11.Cu")
		(net "M_J_DQS_DP<14>")
	)
	(segment
		(start 127.548132 -1.2192)
		(end 127.72898 -1.2192)
		(width 0.14224)
		(layer "In11.Cu")
		(net "M_J_DQS_DP<14>")
	)
	(segment
		(start 127.72898 -1.2192)
		(end 127.91186 -1.03632)
		(width 0.14224)
		(layer "In11.Cu")
		(net "M_J_DQS_DP<14>")
	)
	(segment
		(start 127.42418 -0.1778)
		(end 127.91186 0.30988)
		(width 0.14224)
		(layer "In11.Cu")
		(net "M_J_DQS_DP<14>")
	)
	(segment
		(start 127.420624 -1.346708)
		(end 127.548132 -1.2192)
		(width 0.14224)
		(layer "In11.Cu")
		(net "M_J_DQS_DP<14>")
	)
	(segment
		(start 127.57658 -0.5842)
		(end 127.42418 -0.4318)
		(width 0.14224)
		(layer "In11.Cu")
		(net "M_J_DQS_DP<14>")
	)
	(segment
		(start 127.42418 -0.4318)
		(end 127.42418 -0.1778)
		(width 0.14224)
		(layer "In11.Cu")
		(net "M_J_DQS_DP<14>")
	)
	(segment
		(start 127.91186 -2.731262)
		(end 127.91186 -2.08788)
		(width 0.14224)
		(layer "In11.Cu")
		(net "M_J_DQS_DP<14>")
	)
	(segment
		(start 127.91186 1.145286)
		(end 127.731266 1.32588)
		(width 0.14224)
		(layer "In11.Cu")
		(net "M_J_DQS_DP<14>")
	)
	(segment
		(start 127.91186 -0.79248)
		(end 127.70358 -0.5842)
		(width 0.14224)
		(layer "In11.Cu")
		(net "M_J_DQS_DP<14>")
	)
	(segment
		(start 127.671322 -2.9718)
		(end 127.91186 -2.731262)
		(width 0.14224)
		(layer "In11.Cu")
		(net "M_J_DQS_DP<14>")
	)
	(segment
		(start 127.66548 -1.8415)
		(end 127.577088 -1.8415)
		(width 0.14224)
		(layer "In11.Cu")
		(net "M_J_DQS_DP<14>")
	)
	(segment
		(start 127.91186 -2.08788)
		(end 127.66548 -1.8415)
		(width 0.14224)
		(layer "In11.Cu")
		(net "M_J_DQS_DP<14>")
	)
	(segment
		(start 118.099332 3.778758)
		(end 118.099332 3.161792)
		(width 0.1651)
		(layer "F.Cu")
		(net "M_J_DQS_DP<13>")
	)
	(segment
		(start 117.578632 2.542032)
		(end 117.578632 1.723898)
		(width 0.1651)
		(layer "F.Cu")
		(net "M_J_DQS_DP<13>")
	)
	(segment
		(start 118.099332 3.161792)
		(end 117.663214 2.725674)
		(width 0.1651)
		(layer "F.Cu")
		(net "M_J_DQS_DP<13>")
	)
	(segment
		(start 117.663214 2.725674)
		(end 117.578632 2.542032)
		(width 0.1651)
		(layer "F.Cu")
		(net "M_J_DQS_DP<13>")
	)
	(segment
		(start 117.578632 1.723898)
		(end 117.660166 1.499616)
		(width 0.1651)
		(layer "F.Cu")
		(net "M_J_DQS_DP<13>")
	)
	(segment
		(start 109.055916 -59.866784)
		(end 109.627416 -59.866784)
		(width 0.0889)
		(layer "F.Cu")
		(net "M_J_DQS_DP<13>")
	)
	(segment
		(start 117.660166 1.499616)
		(end 118.041928 1.117854)
		(width 0.1651)
		(layer "F.Cu")
		(net "M_J_DQS_DP<13>")
	)
	(via
		(at 118.041928 -2.9718)
		(size 0.508)
		(drill 0.254)
		(layers "F.Cu" "B.Cu")
		(net "M_J_DQS_DP<13>")
	)
	(via
		(at 109.055916 -59.866784)
		(size 0.508)
		(drill 0.254)
		(layers "F.Cu" "B.Cu")
		(net "M_J_DQS_DP<13>")
	)
	(via
		(at 118.041928 1.117854)
		(size 0.508)
		(drill 0.254)
		(layers "F.Cu" "B.Cu")
		(net "M_J_DQS_DP<13>")
	)
	(segment
		(start 117.653308 -3.36042)
		(end 118.041928 -2.9718)
		(width 0.1651)
		(layer "B.Cu")
		(net "M_J_DQS_DP<13>")
	)
	(segment
		(start 117.565932 -4.415536)
		(end 117.565932 -3.519932)
		(width 0.1651)
		(layer "B.Cu")
		(net "M_J_DQS_DP<13>")
	)
	(segment
		(start 117.643148 -4.54787)
		(end 117.565932 -4.415536)
		(width 0.1651)
		(layer "B.Cu")
		(net "M_J_DQS_DP<13>")
	)
	(segment
		(start 118.099332 -5.621782)
		(end 118.099332 -5.004054)
		(width 0.1651)
		(layer "B.Cu")
		(net "M_J_DQS_DP<13>")
	)
	(segment
		(start 118.099332 -5.004054)
		(end 117.643148 -4.54787)
		(width 0.1651)
		(layer "B.Cu")
		(net "M_J_DQS_DP<13>")
	)
	(segment
		(start 117.565932 -3.519932)
		(end 117.653308 -3.36042)
		(width 0.1651)
		(layer "B.Cu")
		(net "M_J_DQS_DP<13>")
	)
	(segment
		(start 109.039914 -51.71567)
		(end 109.039914 -48.005492)
		(width 0.0889)
		(layer "In11.Cu")
		(net "M_J_DQS_DP<13>")
	)
	(segment
		(start 109.280198 -47.2694)
		(end 109.280198 -47.247302)
		(width 0.0889)
		(layer "In11.Cu")
		(net "M_J_DQS_DP<13>")
	)
	(segment
		(start 117.452648 -27.870658)
		(end 117.857016 -27.46629)
		(width 0.14224)
		(layer "In11.Cu")
		(net "M_J_DQS_DP<13>")
	)
	(segment
		(start 118.875048 -25.523952)
		(end 118.555262 -25.204166)
		(width 0.14224)
		(layer "In11.Cu")
		(net "M_J_DQS_DP<13>")
	)
	(segment
		(start 108.446062 -52.93995)
		(end 108.647738 -52.738274)
		(width 0.0889)
		(layer "In11.Cu")
		(net "M_J_DQS_DP<13>")
	)
	(segment
		(start 118.22684 -1.8415)
		(end 118.070376 -1.685036)
		(width 0.14224)
		(layer "In11.Cu")
		(net "M_J_DQS_DP<13>")
	)
	(segment
		(start 108.647738 -52.738274)
		(end 108.647738 -52.107846)
		(width 0.0889)
		(layer "In11.Cu")
		(net "M_J_DQS_DP<13>")
	)
	(segment
		(start 109.319568 -47.30877)
		(end 109.280198 -47.2694)
		(width 0.0889)
		(layer "In11.Cu")
		(net "M_J_DQS_DP<13>")
	)
	(segment
		(start 118.561612 0.30988)
		(end 118.561612 1.145286)
		(width 0.14224)
		(layer "In11.Cu")
		(net "M_J_DQS_DP<13>")
	)
	(segment
		(start 109.280198 -47.247302)
		(end 109.280198 -39.26205)
		(width 0.14224)
		(layer "In11.Cu")
		(net "M_J_DQS_DP<13>")
	)
	(segment
		(start 108.647738 -52.107846)
		(end 109.039914 -51.71567)
		(width 0.0889)
		(layer "In11.Cu")
		(net "M_J_DQS_DP<13>")
	)
	(segment
		(start 118.561612 1.145286)
		(end 118.381018 1.32588)
		(width 0.14224)
		(layer "In11.Cu")
		(net "M_J_DQS_DP<13>")
	)
	(segment
		(start 118.315232 -1.8415)
		(end 118.22684 -1.8415)
		(width 0.14224)
		(layer "In11.Cu")
		(net "M_J_DQS_DP<13>")
	)
	(segment
		(start 118.321074 -2.9718)
		(end 118.561612 -2.731262)
		(width 0.14224)
		(layer "In11.Cu")
		(net "M_J_DQS_DP<13>")
	)
	(segment
		(start 109.280198 -39.26205)
		(end 118.875048 -29.6672)
		(width 0.14224)
		(layer "In11.Cu")
		(net "M_J_DQS_DP<13>")
	)
	(segment
		(start 118.747794 -27.46629)
		(end 118.875048 -27.339036)
		(width 0.14224)
		(layer "In11.Cu")
		(net "M_J_DQS_DP<13>")
	)
	(segment
		(start 118.555262 -6.351524)
		(end 117.571012 -5.367274)
		(width 0.14224)
		(layer "In11.Cu")
		(net "M_J_DQS_DP<13>")
	)
	(segment
		(start 117.857016 -27.46629)
		(end 118.747794 -27.46629)
		(width 0.14224)
		(layer "In11.Cu")
		(net "M_J_DQS_DP<13>")
	)
	(segment
		(start 117.452648 -28.703524)
		(end 117.452648 -27.870658)
		(width 0.14224)
		(layer "In11.Cu")
		(net "M_J_DQS_DP<13>")
	)
	(segment
		(start 109.055916 -59.864752)
		(end 109.054138 -59.862974)
		(width 0.0889)
		(layer "In11.Cu")
		(net "M_J_DQS_DP<13>")
	)
	(segment
		(start 118.561612 -2.731262)
		(end 118.561612 -2.08788)
		(width 0.14224)
		(layer "In11.Cu")
		(net "M_J_DQS_DP<13>")
	)
	(segment
		(start 108.446062 -55.039006)
		(end 108.446062 -52.93995)
		(width 0.0889)
		(layer "In11.Cu")
		(net "M_J_DQS_DP<13>")
	)
	(segment
		(start 118.381018 1.32588)
		(end 118.249954 1.32588)
		(width 0.14224)
		(layer "In11.Cu")
		(net "M_J_DQS_DP<13>")
	)
	(segment
		(start 118.65356 -29.08173)
		(end 117.830854 -29.08173)
		(width 0.14224)
		(layer "In11.Cu")
		(net "M_J_DQS_DP<13>")
	)
	(segment
		(start 108.544106 -55.20944)
		(end 108.544106 -55.209186)
		(width 0.0889)
		(layer "In11.Cu")
		(net "M_J_DQS_DP<13>")
	)
	(segment
		(start 108.537756 -56.610504)
		(end 108.544106 -56.599836)
		(width 0.0889)
		(layer "In11.Cu")
		(net "M_J_DQS_DP<13>")
	)
	(segment
		(start 118.073932 -0.4318)
		(end 118.073932 -0.1778)
		(width 0.14224)
		(layer "In11.Cu")
		(net "M_J_DQS_DP<13>")
	)
	(segment
		(start 108.537756 -57.601104)
		(end 108.544106 -57.590436)
		(width 0.0889)
		(layer "In11.Cu")
		(net "M_J_DQS_DP<13>")
	)
	(segment
		(start 118.353332 -0.5842)
		(end 118.226332 -0.5842)
		(width 0.14224)
		(layer "In11.Cu")
		(net "M_J_DQS_DP<13>")
	)
	(segment
		(start 118.561612 -1.03632)
		(end 118.561612 -0.79248)
		(width 0.14224)
		(layer "In11.Cu")
		(net "M_J_DQS_DP<13>")
	)
	(segment
		(start 118.561612 -0.79248)
		(end 118.353332 -0.5842)
		(width 0.14224)
		(layer "In11.Cu")
		(net "M_J_DQS_DP<13>")
	)
	(segment
		(start 109.319568 -47.725838)
		(end 109.319568 -47.30877)
		(width 0.0889)
		(layer "In11.Cu")
		(net "M_J_DQS_DP<13>")
	)
	(segment
		(start 118.561612 -2.08788)
		(end 118.315232 -1.8415)
		(width 0.14224)
		(layer "In11.Cu")
		(net "M_J_DQS_DP<13>")
	)
	(segment
		(start 118.226332 -0.5842)
		(end 118.073932 -0.4318)
		(width 0.14224)
		(layer "In11.Cu")
		(net "M_J_DQS_DP<13>")
	)
	(segment
		(start 118.875048 -29.6672)
		(end 118.875048 -29.303218)
		(width 0.14224)
		(layer "In11.Cu")
		(net "M_J_DQS_DP<13>")
	)
	(segment
		(start 109.055916 -59.866784)
		(end 109.055916 -59.864752)
		(width 0.0889)
		(layer "In11.Cu")
		(net "M_J_DQS_DP<13>")
	)
	(segment
		(start 117.571012 -3.442716)
		(end 118.041928 -2.9718)
		(width 0.14224)
		(layer "In11.Cu")
		(net "M_J_DQS_DP<13>")
	)
	(segment
		(start 118.875048 -27.339036)
		(end 118.875048 -25.523952)
		(width 0.14224)
		(layer "In11.Cu")
		(net "M_J_DQS_DP<13>")
	)
	(segment
		(start 118.197884 -1.2192)
		(end 118.378732 -1.2192)
		(width 0.14224)
		(layer "In11.Cu")
		(net "M_J_DQS_DP<13>")
	)
	(segment
		(start 108.544106 -55.209186)
		(end 108.446062 -55.039006)
		(width 0.0889)
		(layer "In11.Cu")
		(net "M_J_DQS_DP<13>")
	)
	(segment
		(start 117.571012 -5.367274)
		(end 117.571012 -3.442716)
		(width 0.14224)
		(layer "In11.Cu")
		(net "M_J_DQS_DP<13>")
	)
	(segment
		(start 108.544106 -57.590436)
		(end 108.548932 -57.5818)
		(width 0.0889)
		(layer "In11.Cu")
		(net "M_J_DQS_DP<13>")
	)
	(segment
		(start 118.073932 -0.1778)
		(end 118.561612 0.30988)
		(width 0.14224)
		(layer "In11.Cu")
		(net "M_J_DQS_DP<13>")
	)
	(segment
		(start 118.070376 -1.346708)
		(end 118.197884 -1.2192)
		(width 0.14224)
		(layer "In11.Cu")
		(net "M_J_DQS_DP<13>")
	)
	(segment
		(start 118.875048 -29.303218)
		(end 118.65356 -29.08173)
		(width 0.14224)
		(layer "In11.Cu")
		(net "M_J_DQS_DP<13>")
	)
	(segment
		(start 118.378732 -1.2192)
		(end 118.561612 -1.03632)
		(width 0.14224)
		(layer "In11.Cu")
		(net "M_J_DQS_DP<13>")
	)
	(segment
		(start 108.544106 -56.599836)
		(end 108.548932 -56.5912)
		(width 0.0889)
		(layer "In11.Cu")
		(net "M_J_DQS_DP<13>")
	)
	(segment
		(start 108.537756 -55.619904)
		(end 108.549948 -55.599584)
		(width 0.0889)
		(layer "In11.Cu")
		(net "M_J_DQS_DP<13>")
	)
	(segment
		(start 118.249954 1.32588)
		(end 118.041928 1.117854)
		(width 0.14224)
		(layer "In11.Cu")
		(net "M_J_DQS_DP<13>")
	)
	(segment
		(start 109.039914 -48.005492)
		(end 109.319568 -47.725838)
		(width 0.0889)
		(layer "In11.Cu")
		(net "M_J_DQS_DP<13>")
	)
	(segment
		(start 118.070376 -1.685036)
		(end 118.070376 -1.346708)
		(width 0.14224)
		(layer "In11.Cu")
		(net "M_J_DQS_DP<13>")
	)
	(segment
		(start 118.555262 -25.204166)
		(end 118.555262 -6.351524)
		(width 0.14224)
		(layer "In11.Cu")
		(net "M_J_DQS_DP<13>")
	)
	(segment
		(start 117.830854 -29.08173)
		(end 117.452648 -28.703524)
		(width 0.14224)
		(layer "In11.Cu")
		(net "M_J_DQS_DP<13>")
	)
	(segment
		(start 118.041928 -2.9718)
		(end 118.321074 -2.9718)
		(width 0.14224)
		(layer "In11.Cu")
		(net "M_J_DQS_DP<13>")
	)
	(arc
		(start 108.709206 -59.076082)
		(mid 108.659391 -58.930357)
		(end 108.668312 -58.776616)
		(width 0.0889)
		(layer "In11.Cu")
		(net "M_J_DQS_DP<13>")
	)
	(arc
		(start 108.549948 -55.599584)
		(mid 108.597716 -55.403765)
		(end 108.544106 -55.20944)
		(width 0.0889)
		(layer "In11.Cu")
		(net "M_J_DQS_DP<13>")
	)
	(arc
		(start 108.548932 -56.5912)
		(mid 108.597687 -56.394848)
		(end 108.544106 -56.199786)
		(width 0.0889)
		(layer "In11.Cu")
		(net "M_J_DQS_DP<13>")
	)
	(arc
		(start 109.054138 -59.862974)
		(mid 108.90332 -59.460038)
		(end 108.709206 -59.076082)
		(width 0.0889)
		(layer "In11.Cu")
		(net "M_J_DQS_DP<13>")
	)
	(arc
		(start 108.544106 -58.180986)
		(mid 108.464884 -57.891868)
		(end 108.537756 -57.601104)
		(width 0.0889)
		(layer "In11.Cu")
		(net "M_J_DQS_DP<13>")
	)
	(arc
		(start 108.544106 -56.199786)
		(mid 108.464884 -55.910668)
		(end 108.537756 -55.619904)
		(width 0.0889)
		(layer "In11.Cu")
		(net "M_J_DQS_DP<13>")
	)
	(arc
		(start 108.668312 -58.776616)
		(mid 108.653914 -58.468858)
		(end 108.544106 -58.180986)
		(width 0.0889)
		(layer "In11.Cu")
		(net "M_J_DQS_DP<13>")
	)
	(arc
		(start 108.544106 -57.190386)
		(mid 108.464884 -56.901268)
		(end 108.537756 -56.610504)
		(width 0.0889)
		(layer "In11.Cu")
		(net "M_J_DQS_DP<13>")
	)
	(arc
		(start 108.548932 -57.5818)
		(mid 108.597687 -57.385448)
		(end 108.544106 -57.190386)
		(width 0.0889)
		(layer "In11.Cu")
		(net "M_J_DQS_DP<13>")
	)
	(segment
		(start 62.41034 1.499616)
		(end 62.792102 1.117854)
		(width 0.1651)
		(layer "F.Cu")
		(net "M_J_DQS_DP<12>")
	)
	(segment
		(start 62.328806 1.723898)
		(end 62.41034 1.499616)
		(width 0.1651)
		(layer "F.Cu")
		(net "M_J_DQS_DP<12>")
	)
	(segment
		(start 62.849506 3.162046)
		(end 62.413388 2.725928)
		(width 0.1651)
		(layer "F.Cu")
		(net "M_J_DQS_DP<12>")
	)
	(segment
		(start 84.919312 -65.49644)
		(end 84.347812 -65.49644)
		(width 0.0889)
		(layer "F.Cu")
		(net "M_J_DQS_DP<12>")
	)
	(segment
		(start 62.328806 2.542032)
		(end 62.328806 1.723898)
		(width 0.1651)
		(layer "F.Cu")
		(net "M_J_DQS_DP<12>")
	)
	(segment
		(start 62.413388 2.725928)
		(end 62.328806 2.542032)
		(width 0.1651)
		(layer "F.Cu")
		(net "M_J_DQS_DP<12>")
	)
	(segment
		(start 62.849506 3.778758)
		(end 62.849506 3.162046)
		(width 0.1651)
		(layer "F.Cu")
		(net "M_J_DQS_DP<12>")
	)
	(via
		(at 62.792102 1.117854)
		(size 0.508)
		(drill 0.254)
		(layers "F.Cu" "B.Cu")
		(net "M_J_DQS_DP<12>")
	)
	(via
		(at 62.792102 -2.9718)
		(size 0.508)
		(drill 0.254)
		(layers "F.Cu" "B.Cu")
		(net "M_J_DQS_DP<12>")
	)
	(via
		(at 84.347812 -65.49644)
		(size 0.508)
		(drill 0.254)
		(layers "F.Cu" "B.Cu")
		(net "M_J_DQS_DP<12>")
	)
	(segment
		(start 62.316106 -4.415536)
		(end 62.316106 -3.519932)
		(width 0.1651)
		(layer "B.Cu")
		(net "M_J_DQS_DP<12>")
	)
	(segment
		(start 62.849506 -5.621782)
		(end 62.849506 -5.004054)
		(width 0.1651)
		(layer "B.Cu")
		(net "M_J_DQS_DP<12>")
	)
	(segment
		(start 62.403482 -3.36042)
		(end 62.792102 -2.9718)
		(width 0.1651)
		(layer "B.Cu")
		(net "M_J_DQS_DP<12>")
	)
	(segment
		(start 62.393322 -4.54787)
		(end 62.316106 -4.415536)
		(width 0.1651)
		(layer "B.Cu")
		(net "M_J_DQS_DP<12>")
	)
	(segment
		(start 62.316106 -3.519932)
		(end 62.403482 -3.36042)
		(width 0.1651)
		(layer "B.Cu")
		(net "M_J_DQS_DP<12>")
	)
	(segment
		(start 62.849506 -5.004054)
		(end 62.393322 -4.54787)
		(width 0.1651)
		(layer "B.Cu")
		(net "M_J_DQS_DP<12>")
	)
	(segment
		(start 62.792102 -2.9718)
		(end 62.321186 -3.442716)
		(width 0.14224)
		(layer "In11.Cu")
		(net "M_J_DQS_DP<12>")
	)
	(segment
		(start 69.291962 -37.567616)
		(end 79.652368 -47.928022)
		(width 0.14224)
		(layer "In11.Cu")
		(net "M_J_DQS_DP<12>")
	)
	(segment
		(start 83.829652 -62.80912)
		(end 83.836002 -62.819788)
		(width 0.0889)
		(layer "In11.Cu")
		(net "M_J_DQS_DP<12>")
	)
	(segment
		(start 84.347812 -65.494408)
		(end 84.347812 -65.49644)
		(width 0.0889)
		(layer "In11.Cu")
		(net "M_J_DQS_DP<12>")
	)
	(segment
		(start 62.792102 1.117854)
		(end 63.000128 1.32588)
		(width 0.14224)
		(layer "In11.Cu")
		(net "M_J_DQS_DP<12>")
	)
	(segment
		(start 83.383374 -55.07609)
		(end 83.840574 -55.893462)
		(width 0.0889)
		(layer "In11.Cu")
		(net "M_J_DQS_DP<12>")
	)
	(segment
		(start 63.131192 1.32588)
		(end 63.311786 1.145286)
		(width 0.14224)
		(layer "In11.Cu")
		(net "M_J_DQS_DP<12>")
	)
	(segment
		(start 81.082388 -50.6222)
		(end 81.75498 -51.294792)
		(width 0.0889)
		(layer "In11.Cu")
		(net "M_J_DQS_DP<12>")
	)
	(segment
		(start 62.977014 -1.8415)
		(end 63.065406 -1.8415)
		(width 0.14224)
		(layer "In11.Cu")
		(net "M_J_DQS_DP<12>")
	)
	(segment
		(start 83.834986 -63.809118)
		(end 83.836002 -63.810642)
		(width 0.0889)
		(layer "In11.Cu")
		(net "M_J_DQS_DP<12>")
	)
	(segment
		(start 83.829652 -59.83732)
		(end 83.836002 -59.847988)
		(width 0.0889)
		(layer "In11.Cu")
		(net "M_J_DQS_DP<12>")
	)
	(segment
		(start 83.836002 -59.847988)
		(end 83.840828 -59.856624)
		(width 0.0889)
		(layer "In11.Cu")
		(net "M_J_DQS_DP<12>")
	)
	(segment
		(start 69.291962 -35.199066)
		(end 69.291962 -37.567616)
		(width 0.14224)
		(layer "In11.Cu")
		(net "M_J_DQS_DP<12>")
	)
	(segment
		(start 63.065406 -1.8415)
		(end 63.311786 -2.08788)
		(width 0.14224)
		(layer "In11.Cu")
		(net "M_J_DQS_DP<12>")
	)
	(segment
		(start 79.652368 -47.928022)
		(end 79.652368 -49.247552)
		(width 0.14224)
		(layer "In11.Cu")
		(net "M_J_DQS_DP<12>")
	)
	(segment
		(start 83.836256 -56.285384)
		(end 83.836002 -56.285638)
		(width 0.0889)
		(layer "In11.Cu")
		(net "M_J_DQS_DP<12>")
	)
	(segment
		(start 79.652368 -49.247552)
		(end 81.011268 -50.606452)
		(width 0.14224)
		(layer "In11.Cu")
		(net "M_J_DQS_DP<12>")
	)
	(segment
		(start 63.305182 -6.45287)
		(end 63.305182 -29.212286)
		(width 0.14224)
		(layer "In11.Cu")
		(net "M_J_DQS_DP<12>")
	)
	(segment
		(start 83.120992 -54.813708)
		(end 83.383374 -55.07609)
		(width 0.0889)
		(layer "In11.Cu")
		(net "M_J_DQS_DP<12>")
	)
	(segment
		(start 62.976506 -0.5842)
		(end 63.103506 -0.5842)
		(width 0.14224)
		(layer "In11.Cu")
		(net "M_J_DQS_DP<12>")
	)
	(segment
		(start 63.311786 1.145286)
		(end 63.311786 0.30988)
		(width 0.14224)
		(layer "In11.Cu")
		(net "M_J_DQS_DP<12>")
	)
	(segment
		(start 81.75498 -51.294792)
		(end 81.894172 -51.535838)
		(width 0.0889)
		(layer "In11.Cu")
		(net "M_J_DQS_DP<12>")
	)
	(segment
		(start 63.311786 -0.79248)
		(end 63.311786 -1.03632)
		(width 0.14224)
		(layer "In11.Cu")
		(net "M_J_DQS_DP<12>")
	)
	(segment
		(start 83.836002 -56.876188)
		(end 83.840828 -56.884824)
		(width 0.0889)
		(layer "In11.Cu")
		(net "M_J_DQS_DP<12>")
	)
	(segment
		(start 62.824106 -0.1778)
		(end 62.824106 -0.4318)
		(width 0.14224)
		(layer "In11.Cu")
		(net "M_J_DQS_DP<12>")
	)
	(segment
		(start 64.530478 -32.466026)
		(end 65.170558 -33.106106)
		(width 0.14224)
		(layer "In11.Cu")
		(net "M_J_DQS_DP<12>")
	)
	(segment
		(start 62.948058 -1.2192)
		(end 62.82055 -1.346708)
		(width 0.14224)
		(layer "In11.Cu")
		(net "M_J_DQS_DP<12>")
	)
	(segment
		(start 66.287396 -32.507428)
		(end 66.600324 -32.507428)
		(width 0.14224)
		(layer "In11.Cu")
		(net "M_J_DQS_DP<12>")
	)
	(segment
		(start 64.530478 -31.978346)
		(end 64.530478 -32.466026)
		(width 0.14224)
		(layer "In11.Cu")
		(net "M_J_DQS_DP<12>")
	)
	(segment
		(start 63.305182 -29.212286)
		(end 65.144396 -31.0515)
		(width 0.14224)
		(layer "In11.Cu")
		(net "M_J_DQS_DP<12>")
	)
	(segment
		(start 62.82055 -1.685036)
		(end 62.977014 -1.8415)
		(width 0.14224)
		(layer "In11.Cu")
		(net "M_J_DQS_DP<12>")
	)
	(segment
		(start 81.011268 -50.606452)
		(end 81.027016 -50.6222)
		(width 0.0889)
		(layer "In11.Cu")
		(net "M_J_DQS_DP<12>")
	)
	(segment
		(start 83.836002 -61.829188)
		(end 83.840828 -61.837824)
		(width 0.0889)
		(layer "In11.Cu")
		(net "M_J_DQS_DP<12>")
	)
	(segment
		(start 83.836002 -58.857388)
		(end 83.840828 -58.866024)
		(width 0.0889)
		(layer "In11.Cu")
		(net "M_J_DQS_DP<12>")
	)
	(segment
		(start 66.600324 -32.507428)
		(end 69.291962 -35.199066)
		(width 0.14224)
		(layer "In11.Cu")
		(net "M_J_DQS_DP<12>")
	)
	(segment
		(start 63.103506 -0.5842)
		(end 63.311786 -0.79248)
		(width 0.14224)
		(layer "In11.Cu")
		(net "M_J_DQS_DP<12>")
	)
	(segment
		(start 83.829652 -56.86552)
		(end 83.836002 -56.876188)
		(width 0.0889)
		(layer "In11.Cu")
		(net "M_J_DQS_DP<12>")
	)
	(segment
		(start 81.894172 -52.090574)
		(end 83.120992 -53.317394)
		(width 0.0889)
		(layer "In11.Cu")
		(net "M_J_DQS_DP<12>")
	)
	(segment
		(start 62.321186 -3.442716)
		(end 62.321186 -5.468874)
		(width 0.14224)
		(layer "In11.Cu")
		(net "M_J_DQS_DP<12>")
	)
	(segment
		(start 63.000128 1.32588)
		(end 63.131192 1.32588)
		(width 0.14224)
		(layer "In11.Cu")
		(net "M_J_DQS_DP<12>")
	)
	(segment
		(start 65.688718 -33.106106)
		(end 66.287396 -32.507428)
		(width 0.14224)
		(layer "In11.Cu")
		(net "M_J_DQS_DP<12>")
	)
	(segment
		(start 83.829652 -61.81852)
		(end 83.836002 -61.829188)
		(width 0.0889)
		(layer "In11.Cu")
		(net "M_J_DQS_DP<12>")
	)
	(segment
		(start 65.144396 -31.364428)
		(end 64.530478 -31.978346)
		(width 0.14224)
		(layer "In11.Cu")
		(net "M_J_DQS_DP<12>")
	)
	(segment
		(start 63.128906 -1.2192)
		(end 62.948058 -1.2192)
		(width 0.14224)
		(layer "In11.Cu")
		(net "M_J_DQS_DP<12>")
	)
	(segment
		(start 83.836002 -62.819788)
		(end 83.840828 -62.828424)
		(width 0.0889)
		(layer "In11.Cu")
		(net "M_J_DQS_DP<12>")
	)
	(segment
		(start 63.311786 0.30988)
		(end 62.824106 -0.1778)
		(width 0.14224)
		(layer "In11.Cu")
		(net "M_J_DQS_DP<12>")
	)
	(segment
		(start 83.120992 -53.317394)
		(end 83.120992 -54.813708)
		(width 0.0889)
		(layer "In11.Cu")
		(net "M_J_DQS_DP<12>")
	)
	(segment
		(start 84.346034 -65.49263)
		(end 84.347812 -65.494408)
		(width 0.0889)
		(layer "In11.Cu")
		(net "M_J_DQS_DP<12>")
	)
	(segment
		(start 65.144396 -31.0515)
		(end 65.144396 -31.364428)
		(width 0.14224)
		(layer "In11.Cu")
		(net "M_J_DQS_DP<12>")
	)
	(segment
		(start 83.829652 -63.79972)
		(end 83.834986 -63.809118)
		(width 0.0889)
		(layer "In11.Cu")
		(net "M_J_DQS_DP<12>")
	)
	(segment
		(start 81.894172 -51.535838)
		(end 81.894172 -52.090574)
		(width 0.0889)
		(layer "In11.Cu")
		(net "M_J_DQS_DP<12>")
	)
	(segment
		(start 83.836002 -58.266838)
		(end 83.829652 -58.277506)
		(width 0.0889)
		(layer "In11.Cu")
		(net "M_J_DQS_DP<12>")
	)
	(segment
		(start 63.311786 -2.08788)
		(end 63.311786 -2.731262)
		(width 0.14224)
		(layer "In11.Cu")
		(net "M_J_DQS_DP<12>")
	)
	(segment
		(start 63.311786 -1.03632)
		(end 63.128906 -1.2192)
		(width 0.14224)
		(layer "In11.Cu")
		(net "M_J_DQS_DP<12>")
	)
	(segment
		(start 83.836002 -60.838588)
		(end 83.840828 -60.847224)
		(width 0.0889)
		(layer "In11.Cu")
		(net "M_J_DQS_DP<12>")
	)
	(segment
		(start 62.824106 -0.4318)
		(end 62.976506 -0.5842)
		(width 0.14224)
		(layer "In11.Cu")
		(net "M_J_DQS_DP<12>")
	)
	(segment
		(start 81.027016 -50.6222)
		(end 81.082388 -50.6222)
		(width 0.0889)
		(layer "In11.Cu")
		(net "M_J_DQS_DP<12>")
	)
	(segment
		(start 63.311786 -2.731262)
		(end 63.071248 -2.9718)
		(width 0.14224)
		(layer "In11.Cu")
		(net "M_J_DQS_DP<12>")
	)
	(segment
		(start 65.170558 -33.106106)
		(end 65.688718 -33.106106)
		(width 0.14224)
		(layer "In11.Cu")
		(net "M_J_DQS_DP<12>")
	)
	(segment
		(start 83.829652 -60.82792)
		(end 83.836002 -60.838588)
		(width 0.0889)
		(layer "In11.Cu")
		(net "M_J_DQS_DP<12>")
	)
	(segment
		(start 62.82055 -1.346708)
		(end 62.82055 -1.685036)
		(width 0.14224)
		(layer "In11.Cu")
		(net "M_J_DQS_DP<12>")
	)
	(segment
		(start 63.071248 -2.9718)
		(end 62.792102 -2.9718)
		(width 0.14224)
		(layer "In11.Cu")
		(net "M_J_DQS_DP<12>")
	)
	(segment
		(start 62.321186 -5.468874)
		(end 63.305182 -6.45287)
		(width 0.14224)
		(layer "In11.Cu")
		(net "M_J_DQS_DP<12>")
	)
	(arc
		(start 84.001102 -64.705738)
		(mid 84.195197 -65.089702)
		(end 84.346034 -65.49263)
		(width 0.0889)
		(layer "In11.Cu")
		(net "M_J_DQS_DP<12>")
	)
	(arc
		(start 83.836002 -56.285638)
		(mid 83.75678 -56.574756)
		(end 83.829652 -56.86552)
		(width 0.0889)
		(layer "In11.Cu")
		(net "M_J_DQS_DP<12>")
	)
	(arc
		(start 83.840828 -58.866024)
		(mid 83.889583 -59.062376)
		(end 83.836002 -59.257438)
		(width 0.0889)
		(layer "In11.Cu")
		(net "M_J_DQS_DP<12>")
	)
	(arc
		(start 83.840828 -62.828424)
		(mid 83.889583 -63.024776)
		(end 83.836002 -63.219838)
		(width 0.0889)
		(layer "In11.Cu")
		(net "M_J_DQS_DP<12>")
	)
	(arc
		(start 83.840828 -56.884824)
		(mid 83.889583 -57.081176)
		(end 83.836002 -57.276238)
		(width 0.0889)
		(layer "In11.Cu")
		(net "M_J_DQS_DP<12>")
	)
	(arc
		(start 83.840574 -55.893462)
		(mid 83.889607 -56.089975)
		(end 83.836256 -56.285384)
		(width 0.0889)
		(layer "In11.Cu")
		(net "M_J_DQS_DP<12>")
	)
	(arc
		(start 83.829652 -58.277506)
		(mid 83.756854 -58.568269)
		(end 83.836002 -58.857388)
		(width 0.0889)
		(layer "In11.Cu")
		(net "M_J_DQS_DP<12>")
	)
	(arc
		(start 83.836002 -59.257438)
		(mid 83.75678 -59.546556)
		(end 83.829652 -59.83732)
		(width 0.0889)
		(layer "In11.Cu")
		(net "M_J_DQS_DP<12>")
	)
	(arc
		(start 83.836002 -57.276238)
		(mid 83.756871 -57.57164)
		(end 83.836002 -57.867042)
		(width 0.0889)
		(layer "In11.Cu")
		(net "M_J_DQS_DP<12>")
	)
	(arc
		(start 83.836002 -62.229238)
		(mid 83.75678 -62.518356)
		(end 83.829652 -62.80912)
		(width 0.0889)
		(layer "In11.Cu")
		(net "M_J_DQS_DP<12>")
	)
	(arc
		(start 83.840828 -61.837824)
		(mid 83.889583 -62.034176)
		(end 83.836002 -62.229238)
		(width 0.0889)
		(layer "In11.Cu")
		(net "M_J_DQS_DP<12>")
	)
	(arc
		(start 83.836002 -63.810642)
		(mid 83.945872 -64.098501)
		(end 83.960208 -64.406272)
		(width 0.0889)
		(layer "In11.Cu")
		(net "M_J_DQS_DP<12>")
	)
	(arc
		(start 83.960208 -64.406272)
		(mid 83.951307 -64.560011)
		(end 84.001102 -64.705738)
		(width 0.0889)
		(layer "In11.Cu")
		(net "M_J_DQS_DP<12>")
	)
	(arc
		(start 83.840828 -60.847224)
		(mid 83.889583 -61.043576)
		(end 83.836002 -61.238638)
		(width 0.0889)
		(layer "In11.Cu")
		(net "M_J_DQS_DP<12>")
	)
	(arc
		(start 83.836002 -63.219838)
		(mid 83.75678 -63.508956)
		(end 83.829652 -63.79972)
		(width 0.0889)
		(layer "In11.Cu")
		(net "M_J_DQS_DP<12>")
	)
	(arc
		(start 83.836002 -57.867042)
		(mid 83.889501 -58.06694)
		(end 83.836002 -58.266838)
		(width 0.0889)
		(layer "In11.Cu")
		(net "M_J_DQS_DP<12>")
	)
	(arc
		(start 83.836002 -61.238638)
		(mid 83.75678 -61.527756)
		(end 83.829652 -61.81852)
		(width 0.0889)
		(layer "In11.Cu")
		(net "M_J_DQS_DP<12>")
	)
	(arc
		(start 83.840828 -59.856624)
		(mid 83.889583 -60.052976)
		(end 83.836002 -60.248038)
		(width 0.0889)
		(layer "In11.Cu")
		(net "M_J_DQS_DP<12>")
	)
	(arc
		(start 83.836002 -60.248038)
		(mid 83.75678 -60.537156)
		(end 83.829652 -60.82792)
		(width 0.0889)
		(layer "In11.Cu")
		(net "M_J_DQS_DP<12>")
	)
	(segment
		(start 52.978812 1.723898)
		(end 53.060346 1.499616)
		(width 0.1651)
		(layer "F.Cu")
		(net "M_J_DQS_DP<11>")
	)
	(segment
		(start 52.978812 2.542032)
		(end 52.978812 1.723898)
		(width 0.1651)
		(layer "F.Cu")
		(net "M_J_DQS_DP<11>")
	)
	(segment
		(start 53.499512 3.778758)
		(end 53.499512 3.162046)
		(width 0.1651)
		(layer "F.Cu")
		(net "M_J_DQS_DP<11>")
	)
	(segment
		(start 80.626712 -58.06694)
		(end 80.055212 -58.06694)
		(width 0.0889)
		(layer "F.Cu")
		(net "M_J_DQS_DP<11>")
	)
	(segment
		(start 53.499512 3.162046)
		(end 53.063394 2.725928)
		(width 0.1651)
		(layer "F.Cu")
		(net "M_J_DQS_DP<11>")
	)
	(segment
		(start 53.060346 1.499616)
		(end 53.442108 1.117854)
		(width 0.1651)
		(layer "F.Cu")
		(net "M_J_DQS_DP<11>")
	)
	(segment
		(start 53.063394 2.725928)
		(end 52.978812 2.542032)
		(width 0.1651)
		(layer "F.Cu")
		(net "M_J_DQS_DP<11>")
	)
	(via
		(at 53.442108 -2.9718)
		(size 0.508)
		(drill 0.254)
		(layers "F.Cu" "B.Cu")
		(net "M_J_DQS_DP<11>")
	)
	(via
		(at 53.442108 1.117854)
		(size 0.508)
		(drill 0.254)
		(layers "F.Cu" "B.Cu")
		(net "M_J_DQS_DP<11>")
	)
	(via
		(at 80.055212 -58.06694)
		(size 0.508)
		(drill 0.254)
		(layers "F.Cu" "B.Cu")
		(net "M_J_DQS_DP<11>")
	)
	(segment
		(start 53.499512 -5.004054)
		(end 53.043328 -4.54787)
		(width 0.1651)
		(layer "B.Cu")
		(net "M_J_DQS_DP<11>")
	)
	(segment
		(start 53.053488 -3.36042)
		(end 53.442108 -2.9718)
		(width 0.1651)
		(layer "B.Cu")
		(net "M_J_DQS_DP<11>")
	)
	(segment
		(start 52.966112 -4.415536)
		(end 52.966112 -3.519932)
		(width 0.1651)
		(layer "B.Cu")
		(net "M_J_DQS_DP<11>")
	)
	(segment
		(start 52.966112 -3.519932)
		(end 53.053488 -3.36042)
		(width 0.1651)
		(layer "B.Cu")
		(net "M_J_DQS_DP<11>")
	)
	(segment
		(start 53.043328 -4.54787)
		(end 52.966112 -4.415536)
		(width 0.1651)
		(layer "B.Cu")
		(net "M_J_DQS_DP<11>")
	)
	(segment
		(start 53.499512 -5.621782)
		(end 53.499512 -5.004054)
		(width 0.1651)
		(layer "B.Cu")
		(net "M_J_DQS_DP<11>")
	)
	(segment
		(start 74.063352 -55.19039)
		(end 74.03211 -55.19039)
		(width 0.0889)
		(layer "In11.Cu")
		(net "M_J_DQS_DP<11>")
	)
	(segment
		(start 77.830172 -57.377584)
		(end 77.826108 -57.370726)
		(width 0.0889)
		(layer "In11.Cu")
		(net "M_J_DQS_DP<11>")
	)
	(segment
		(start 66.53022 -47.245778)
		(end 66.53022 -46.28642)
		(width 0.14224)
		(layer "In11.Cu")
		(net "M_J_DQS_DP<11>")
	)
	(segment
		(start 53.721254 -2.9718)
		(end 53.961792 -2.731262)
		(width 0.14224)
		(layer "In11.Cu")
		(net "M_J_DQS_DP<11>")
	)
	(segment
		(start 53.961792 -0.79248)
		(end 53.753512 -0.5842)
		(width 0.14224)
		(layer "In11.Cu")
		(net "M_J_DQS_DP<11>")
	)
	(segment
		(start 69.715634 -50.250598)
		(end 69.662294 -50.235866)
		(width 0.0889)
		(layer "In11.Cu")
		(net "M_J_DQS_DP<11>")
	)
	(segment
		(start 69.444616 -49.85131)
		(end 68.629276 -49.344834)
		(width 0.14224)
		(layer "In11.Cu")
		(net "M_J_DQS_DP<11>")
	)
	(segment
		(start 53.470556 -1.685036)
		(end 53.470556 -1.346708)
		(width 0.14224)
		(layer "In11.Cu")
		(net "M_J_DQS_DP<11>")
	)
	(segment
		(start 53.961792 -2.731262)
		(end 53.961792 -2.08788)
		(width 0.14224)
		(layer "In11.Cu")
		(net "M_J_DQS_DP<11>")
	)
	(segment
		(start 54.06136 -26.863548)
		(end 53.901086 -26.863548)
		(width 0.14224)
		(layer "In11.Cu")
		(net "M_J_DQS_DP<11>")
	)
	(segment
		(start 72.346312 -54.19979)
		(end 72.31507 -54.19979)
		(width 0.0889)
		(layer "In11.Cu")
		(net "M_J_DQS_DP<11>")
	)
	(segment
		(start 77.500226 -57.17159)
		(end 77.46619 -57.17159)
		(width 0.0889)
		(layer "In11.Cu")
		(net "M_J_DQS_DP<11>")
	)
	(segment
		(start 68.629276 -49.344834)
		(end 66.53022 -47.245778)
		(width 0.14224)
		(layer "In11.Cu")
		(net "M_J_DQS_DP<11>")
	)
	(segment
		(start 53.715412 -1.8415)
		(end 53.62702 -1.8415)
		(width 0.14224)
		(layer "In11.Cu")
		(net "M_J_DQS_DP<11>")
	)
	(segment
		(start 53.961792 -1.03632)
		(end 53.961792 -0.79248)
		(width 0.14224)
		(layer "In11.Cu")
		(net "M_J_DQS_DP<11>")
	)
	(segment
		(start 53.62702 -1.8415)
		(end 53.470556 -1.685036)
		(width 0.14224)
		(layer "In11.Cu")
		(net "M_J_DQS_DP<11>")
	)
	(segment
		(start 70.626224 -52.218336)
		(end 70.589648 -52.218336)
		(width 0.0889)
		(layer "In11.Cu")
		(net "M_J_DQS_DP<11>")
	)
	(segment
		(start 52.971192 -5.367274)
		(end 52.971192 -3.442716)
		(width 0.14224)
		(layer "In11.Cu")
		(net "M_J_DQS_DP<11>")
	)
	(segment
		(start 53.778912 -1.2192)
		(end 53.961792 -1.03632)
		(width 0.14224)
		(layer "In11.Cu")
		(net "M_J_DQS_DP<11>")
	)
	(segment
		(start 69.662294 -50.235866)
		(end 69.651372 -50.216562)
		(width 0.0889)
		(layer "In11.Cu")
		(net "M_J_DQS_DP<11>")
	)
	(segment
		(start 76.635864 -56.676036)
		(end 76.603098 -56.676036)
		(width 0.0889)
		(layer "In11.Cu")
		(net "M_J_DQS_DP<11>")
	)
	(segment
		(start 53.474112 -0.4318)
		(end 53.474112 -0.1778)
		(width 0.14224)
		(layer "In11.Cu")
		(net "M_J_DQS_DP<11>")
	)
	(segment
		(start 53.474112 -0.1778)
		(end 53.961792 0.30988)
		(width 0.14224)
		(layer "In11.Cu")
		(net "M_J_DQS_DP<11>")
	)
	(segment
		(start 53.961792 1.145286)
		(end 53.781198 1.32588)
		(width 0.14224)
		(layer "In11.Cu")
		(net "M_J_DQS_DP<11>")
	)
	(segment
		(start 53.955188 -6.35127)
		(end 52.971192 -5.367274)
		(width 0.14224)
		(layer "In11.Cu")
		(net "M_J_DQS_DP<11>")
	)
	(segment
		(start 53.781198 1.32588)
		(end 53.650134 1.32588)
		(width 0.14224)
		(layer "In11.Cu")
		(net "M_J_DQS_DP<11>")
	)
	(segment
		(start 78.34884 -57.666636)
		(end 78.338172 -57.666636)
		(width 0.0889)
		(layer "In11.Cu")
		(net "M_J_DQS_DP<11>")
	)
	(segment
		(start 54.282848 -27.085036)
		(end 54.06136 -26.863548)
		(width 0.14224)
		(layer "In11.Cu")
		(net "M_J_DQS_DP<11>")
	)
	(segment
		(start 75.780392 -56.18099)
		(end 75.74915 -56.18099)
		(width 0.0889)
		(layer "In11.Cu")
		(net "M_J_DQS_DP<11>")
	)
	(segment
		(start 69.651372 -50.216562)
		(end 69.444616 -49.85131)
		(width 0.14224)
		(layer "In11.Cu")
		(net "M_J_DQS_DP<11>")
	)
	(segment
		(start 53.343048 -26.30551)
		(end 53.343048 -25.441402)
		(width 0.14224)
		(layer "In11.Cu")
		(net "M_J_DQS_DP<11>")
	)
	(segment
		(start 54.282848 -34.039048)
		(end 54.282848 -27.085036)
		(width 0.14224)
		(layer "In11.Cu")
		(net "M_J_DQS_DP<11>")
	)
	(segment
		(start 71.484744 -53.704236)
		(end 71.451978 -53.704236)
		(width 0.0889)
		(layer "In11.Cu")
		(net "M_J_DQS_DP<11>")
	)
	(segment
		(start 53.598064 -1.2192)
		(end 53.778912 -1.2192)
		(width 0.14224)
		(layer "In11.Cu")
		(net "M_J_DQS_DP<11>")
	)
	(segment
		(start 53.626512 -0.5842)
		(end 53.474112 -0.4318)
		(width 0.14224)
		(layer "In11.Cu")
		(net "M_J_DQS_DP<11>")
	)
	(segment
		(start 66.53022 -46.28642)
		(end 54.282848 -34.039048)
		(width 0.14224)
		(layer "In11.Cu")
		(net "M_J_DQS_DP<11>")
	)
	(segment
		(start 53.753512 -0.5842)
		(end 53.626512 -0.5842)
		(width 0.14224)
		(layer "In11.Cu")
		(net "M_J_DQS_DP<11>")
	)
	(segment
		(start 78.943454 -57.94502)
		(end 78.815692 -57.909714)
		(width 0.0889)
		(layer "In11.Cu")
		(net "M_J_DQS_DP<11>")
	)
	(segment
		(start 52.971192 -3.442716)
		(end 53.442108 -2.9718)
		(width 0.14224)
		(layer "In11.Cu")
		(net "M_J_DQS_DP<11>")
	)
	(segment
		(start 70.104762 -50.941224)
		(end 69.715634 -50.250598)
		(width 0.0889)
		(layer "In11.Cu")
		(net "M_J_DQS_DP<11>")
	)
	(segment
		(start 53.955188 -24.829262)
		(end 53.955188 -6.35127)
		(width 0.14224)
		(layer "In11.Cu")
		(net "M_J_DQS_DP<11>")
	)
	(segment
		(start 53.343048 -25.441402)
		(end 53.955188 -24.829262)
		(width 0.14224)
		(layer "In11.Cu")
		(net "M_J_DQS_DP<11>")
	)
	(segment
		(start 53.961792 -2.08788)
		(end 53.715412 -1.8415)
		(width 0.14224)
		(layer "In11.Cu")
		(net "M_J_DQS_DP<11>")
	)
	(segment
		(start 53.470556 -1.346708)
		(end 53.598064 -1.2192)
		(width 0.14224)
		(layer "In11.Cu")
		(net "M_J_DQS_DP<11>")
	)
	(segment
		(start 73.201784 -54.694836)
		(end 73.169018 -54.694836)
		(width 0.0889)
		(layer "In11.Cu")
		(net "M_J_DQS_DP<11>")
	)
	(segment
		(start 74.918824 -55.685436)
		(end 74.886058 -55.685436)
		(width 0.0889)
		(layer "In11.Cu")
		(net "M_J_DQS_DP<11>")
	)
	(segment
		(start 70.951852 -52.830222)
		(end 70.957694 -52.819554)
		(width 0.0889)
		(layer "In11.Cu")
		(net "M_J_DQS_DP<11>")
	)
	(segment
		(start 80.055212 -58.06694)
		(end 79.33944 -57.971944)
		(width 0.0889)
		(layer "In11.Cu")
		(net "M_J_DQS_DP<11>")
	)
	(segment
		(start 70.957694 -52.819554)
		(end 70.958456 -52.818538)
		(width 0.0889)
		(layer "In11.Cu")
		(net "M_J_DQS_DP<11>")
	)
	(segment
		(start 53.650134 1.32588)
		(end 53.442108 1.117854)
		(width 0.14224)
		(layer "In11.Cu")
		(net "M_J_DQS_DP<11>")
	)
	(segment
		(start 53.901086 -26.863548)
		(end 53.343048 -26.30551)
		(width 0.14224)
		(layer "In11.Cu")
		(net "M_J_DQS_DP<11>")
	)
	(segment
		(start 79.115412 -57.971944)
		(end 78.943454 -57.94502)
		(width 0.0889)
		(layer "In11.Cu")
		(net "M_J_DQS_DP<11>")
	)
	(segment
		(start 79.33944 -57.971944)
		(end 79.115412 -57.971944)
		(width 0.0889)
		(layer "In11.Cu")
		(net "M_J_DQS_DP<11>")
	)
	(segment
		(start 53.442108 -2.9718)
		(end 53.721254 -2.9718)
		(width 0.14224)
		(layer "In11.Cu")
		(net "M_J_DQS_DP<11>")
	)
	(segment
		(start 53.961792 0.30988)
		(end 53.961792 1.145286)
		(width 0.14224)
		(layer "In11.Cu")
		(net "M_J_DQS_DP<11>")
	)
	(arc
		(start 70.099936 -51.332638)
		(mid 70.153406 -51.137575)
		(end 70.104762 -50.941224)
		(width 0.0889)
		(layer "In11.Cu")
		(net "M_J_DQS_DP<11>")
	)
	(arc
		(start 73.169018 -54.694836)
		(mid 72.883971 -54.611308)
		(end 72.675496 -54.399688)
		(width 0.0889)
		(layer "In11.Cu")
		(net "M_J_DQS_DP<11>")
	)
	(arc
		(start 75.251056 -55.885588)
		(mid 75.110788 -55.742632)
		(end 74.918824 -55.685436)
		(width 0.0889)
		(layer "In11.Cu")
		(net "M_J_DQS_DP<11>")
	)
	(arc
		(start 74.03211 -55.19039)
		(mid 73.744423 -55.107869)
		(end 73.534016 -54.894988)
		(width 0.0889)
		(layer "In11.Cu")
		(net "M_J_DQS_DP<11>")
	)
	(arc
		(start 76.603098 -56.676036)
		(mid 76.318051 -56.592508)
		(end 76.109576 -56.380888)
		(width 0.0889)
		(layer "In11.Cu")
		(net "M_J_DQS_DP<11>")
	)
	(arc
		(start 78.815692 -57.909714)
		(mid 78.724039 -57.871102)
		(end 78.645258 -57.8104)
		(width 0.0889)
		(layer "In11.Cu")
		(net "M_J_DQS_DP<11>")
	)
	(arc
		(start 71.451978 -53.704236)
		(mid 70.957451 -53.407121)
		(end 70.951852 -52.830222)
		(width 0.0889)
		(layer "In11.Cu")
		(net "M_J_DQS_DP<11>")
	)
	(arc
		(start 76.968096 -56.876188)
		(mid 76.827828 -56.733232)
		(end 76.635864 -56.676036)
		(width 0.0889)
		(layer "In11.Cu")
		(net "M_J_DQS_DP<11>")
	)
	(arc
		(start 75.74915 -56.18099)
		(mid 75.461463 -56.098469)
		(end 75.251056 -55.885588)
		(width 0.0889)
		(layer "In11.Cu")
		(net "M_J_DQS_DP<11>")
	)
	(arc
		(start 73.534016 -54.894988)
		(mid 73.393748 -54.752032)
		(end 73.201784 -54.694836)
		(width 0.0889)
		(layer "In11.Cu")
		(net "M_J_DQS_DP<11>")
	)
	(arc
		(start 74.392536 -55.390288)
		(mid 74.253543 -55.248208)
		(end 74.063352 -55.19039)
		(width 0.0889)
		(layer "In11.Cu")
		(net "M_J_DQS_DP<11>")
	)
	(arc
		(start 72.31507 -54.19979)
		(mid 72.027383 -54.117269)
		(end 71.816976 -53.904388)
		(width 0.0889)
		(layer "In11.Cu")
		(net "M_J_DQS_DP<11>")
	)
	(arc
		(start 70.589648 -52.218336)
		(mid 70.094545 -51.913858)
		(end 70.099936 -51.332638)
		(width 0.0889)
		(layer "In11.Cu")
		(net "M_J_DQS_DP<11>")
	)
	(arc
		(start 71.816976 -53.904388)
		(mid 71.676708 -53.761432)
		(end 71.484744 -53.704236)
		(width 0.0889)
		(layer "In11.Cu")
		(net "M_J_DQS_DP<11>")
	)
	(arc
		(start 78.645258 -57.8104)
		(mid 78.512526 -57.706613)
		(end 78.34884 -57.666636)
		(width 0.0889)
		(layer "In11.Cu")
		(net "M_J_DQS_DP<11>")
	)
	(arc
		(start 72.675496 -54.399688)
		(mid 72.536503 -54.257608)
		(end 72.346312 -54.19979)
		(width 0.0889)
		(layer "In11.Cu")
		(net "M_J_DQS_DP<11>")
	)
	(arc
		(start 77.826108 -57.370726)
		(mid 77.688417 -57.229857)
		(end 77.500226 -57.17159)
		(width 0.0889)
		(layer "In11.Cu")
		(net "M_J_DQS_DP<11>")
	)
	(arc
		(start 70.958456 -52.818538)
		(mid 70.962006 -52.424513)
		(end 70.626224 -52.218336)
		(width 0.0889)
		(layer "In11.Cu")
		(net "M_J_DQS_DP<11>")
	)
	(arc
		(start 77.46619 -57.17159)
		(mid 77.178503 -57.089069)
		(end 76.968096 -56.876188)
		(width 0.0889)
		(layer "In11.Cu")
		(net "M_J_DQS_DP<11>")
	)
	(arc
		(start 74.886058 -55.685436)
		(mid 74.601011 -55.601908)
		(end 74.392536 -55.390288)
		(width 0.0889)
		(layer "In11.Cu")
		(net "M_J_DQS_DP<11>")
	)
	(arc
		(start 78.338172 -57.666636)
		(mid 78.045947 -57.589305)
		(end 77.830172 -57.377584)
		(width 0.0889)
		(layer "In11.Cu")
		(net "M_J_DQS_DP<11>")
	)
	(arc
		(start 76.109576 -56.380888)
		(mid 75.970583 -56.238808)
		(end 75.780392 -56.18099)
		(width 0.0889)
		(layer "In11.Cu")
		(net "M_J_DQS_DP<11>")
	)
	(segment
		(start 43.710352 1.499616)
		(end 44.092114 1.117854)
		(width 0.1651)
		(layer "F.Cu")
		(net "M_J_DQS_DP<10>")
	)
	(segment
		(start 76.334366 -60.54344)
		(end 75.762866 -60.54344)
		(width 0.0889)
		(layer "F.Cu")
		(net "M_J_DQS_DP<10>")
	)
	(segment
		(start 43.628818 1.723898)
		(end 43.710352 1.499616)
		(width 0.1651)
		(layer "F.Cu")
		(net "M_J_DQS_DP<10>")
	)
	(segment
		(start 44.149518 3.778758)
		(end 44.149518 3.162046)
		(width 0.1651)
		(layer "F.Cu")
		(net "M_J_DQS_DP<10>")
	)
	(segment
		(start 43.628818 2.542032)
		(end 43.628818 1.723898)
		(width 0.1651)
		(layer "F.Cu")
		(net "M_J_DQS_DP<10>")
	)
	(segment
		(start 43.7134 2.725928)
		(end 43.628818 2.542032)
		(width 0.1651)
		(layer "F.Cu")
		(net "M_J_DQS_DP<10>")
	)
	(segment
		(start 44.149518 3.162046)
		(end 43.7134 2.725928)
		(width 0.1651)
		(layer "F.Cu")
		(net "M_J_DQS_DP<10>")
	)
	(via
		(at 75.762866 -60.54344)
		(size 0.508)
		(drill 0.254)
		(layers "F.Cu" "B.Cu")
		(net "M_J_DQS_DP<10>")
	)
	(via
		(at 44.092114 1.117854)
		(size 0.508)
		(drill 0.254)
		(layers "F.Cu" "B.Cu")
		(net "M_J_DQS_DP<10>")
	)
	(via
		(at 44.092114 -2.9718)
		(size 0.508)
		(drill 0.254)
		(layers "F.Cu" "B.Cu")
		(net "M_J_DQS_DP<10>")
	)
	(segment
		(start 43.616118 -4.415536)
		(end 43.616118 -3.519932)
		(width 0.1651)
		(layer "B.Cu")
		(net "M_J_DQS_DP<10>")
	)
	(segment
		(start 43.616118 -3.519932)
		(end 43.703494 -3.36042)
		(width 0.1651)
		(layer "B.Cu")
		(net "M_J_DQS_DP<10>")
	)
	(segment
		(start 43.693334 -4.54787)
		(end 43.616118 -4.415536)
		(width 0.1651)
		(layer "B.Cu")
		(net "M_J_DQS_DP<10>")
	)
	(segment
		(start 44.149518 -5.004054)
		(end 43.693334 -4.54787)
		(width 0.1651)
		(layer "B.Cu")
		(net "M_J_DQS_DP<10>")
	)
	(segment
		(start 43.703494 -3.36042)
		(end 44.092114 -2.9718)
		(width 0.1651)
		(layer "B.Cu")
		(net "M_J_DQS_DP<10>")
	)
	(segment
		(start 44.149518 -5.621782)
		(end 44.149518 -5.004054)
		(width 0.1651)
		(layer "B.Cu")
		(net "M_J_DQS_DP<10>")
	)
	(segment
		(start 44.6786 -34.378392)
		(end 44.6786 -35.201352)
		(width 0.14224)
		(layer "In11.Cu")
		(net "M_J_DQS_DP<10>")
	)
	(segment
		(start 44.6786 -35.201352)
		(end 44.5516 -35.328352)
		(width 0.14224)
		(layer "In11.Cu")
		(net "M_J_DQS_DP<10>")
	)
	(segment
		(start 51.865784 -44.315888)
		(end 64.760856 -57.21096)
		(width 0.14224)
		(layer "In11.Cu")
		(net "M_J_DQS_DP<10>")
	)
	(segment
		(start 44.092114 1.117854)
		(end 44.30014 1.32588)
		(width 0.14224)
		(layer "In11.Cu")
		(net "M_J_DQS_DP<10>")
	)
	(segment
		(start 71.448676 -59.647836)
		(end 71.481442 -59.647836)
		(width 0.0889)
		(layer "In11.Cu")
		(net "M_J_DQS_DP<10>")
	)
	(segment
		(start 44.30014 1.32588)
		(end 44.431204 1.32588)
		(width 0.14224)
		(layer "In11.Cu")
		(net "M_J_DQS_DP<10>")
	)
	(segment
		(start 65.543938 -57.17159)
		(end 67.369944 -57.17159)
		(width 0.0889)
		(layer "In11.Cu")
		(net "M_J_DQS_DP<10>")
	)
	(segment
		(start 44.5516 -35.328352)
		(end 44.120816 -35.328352)
		(width 0.14224)
		(layer "In11.Cu")
		(net "M_J_DQS_DP<10>")
	)
	(segment
		(start 44.611798 1.145286)
		(end 44.611798 0.30988)
		(width 0.14224)
		(layer "In11.Cu")
		(net "M_J_DQS_DP<10>")
	)
	(segment
		(start 67.369944 -57.17159)
		(end 68.85559 -58.657236)
		(width 0.0889)
		(layer "In11.Cu")
		(net "M_J_DQS_DP<10>")
	)
	(segment
		(start 44.611798 0.30988)
		(end 44.124118 -0.1778)
		(width 0.14224)
		(layer "In11.Cu")
		(net "M_J_DQS_DP<10>")
	)
	(segment
		(start 68.85559 -58.657236)
		(end 69.767958 -58.657236)
		(width 0.0889)
		(layer "In11.Cu")
		(net "M_J_DQS_DP<10>")
	)
	(segment
		(start 70.099936 -58.857134)
		(end 70.099936 -58.857388)
		(width 0.0889)
		(layer "In11.Cu")
		(net "M_J_DQS_DP<10>")
	)
	(segment
		(start 48.509936 -40.96004)
		(end 49.47412 -40.96004)
		(width 0.14224)
		(layer "In11.Cu")
		(net "M_J_DQS_DP<10>")
	)
	(segment
		(start 75.301602 -61.149738)
		(end 75.751182 -60.545218)
		(width 0.0889)
		(layer "In11.Cu")
		(net "M_J_DQS_DP<10>")
	)
	(segment
		(start 44.611798 -0.79248)
		(end 44.611798 -1.03632)
		(width 0.14224)
		(layer "In11.Cu")
		(net "M_J_DQS_DP<10>")
	)
	(segment
		(start 74.839068 -61.439044)
		(end 74.919332 -61.438536)
		(width 0.0889)
		(layer "In11.Cu")
		(net "M_J_DQS_DP<10>")
	)
	(segment
		(start 44.120816 -35.328352)
		(end 43.767248 -35.68192)
		(width 0.14224)
		(layer "In11.Cu")
		(net "M_J_DQS_DP<10>")
	)
	(segment
		(start 44.170854 -34.251392)
		(end 44.5516 -34.251392)
		(width 0.14224)
		(layer "In11.Cu")
		(net "M_J_DQS_DP<10>")
	)
	(segment
		(start 44.124118 -0.1778)
		(end 44.124118 -0.4318)
		(width 0.14224)
		(layer "In11.Cu")
		(net "M_J_DQS_DP<10>")
	)
	(segment
		(start 43.792648 -26.519886)
		(end 43.792648 -33.873186)
		(width 0.14224)
		(layer "In11.Cu")
		(net "M_J_DQS_DP<10>")
	)
	(segment
		(start 44.605194 -6.35127)
		(end 44.605194 -25.70734)
		(width 0.14224)
		(layer "In11.Cu")
		(net "M_J_DQS_DP<10>")
	)
	(segment
		(start 73.165716 -60.638436)
		(end 73.198482 -60.638436)
		(width 0.0889)
		(layer "In11.Cu")
		(net "M_J_DQS_DP<10>")
	)
	(segment
		(start 44.611798 -2.08788)
		(end 44.611798 -2.731262)
		(width 0.14224)
		(layer "In11.Cu")
		(net "M_J_DQS_DP<10>")
	)
	(segment
		(start 44.5516 -34.251392)
		(end 44.6786 -34.378392)
		(width 0.14224)
		(layer "In11.Cu")
		(net "M_J_DQS_DP<10>")
	)
	(segment
		(start 44.277026 -1.8415)
		(end 44.365418 -1.8415)
		(width 0.14224)
		(layer "In11.Cu")
		(net "M_J_DQS_DP<10>")
	)
	(segment
		(start 64.760856 -57.21096)
		(end 65.504568 -57.21096)
		(width 0.14224)
		(layer "In11.Cu")
		(net "M_J_DQS_DP<10>")
	)
	(segment
		(start 43.767248 -36.217352)
		(end 48.509936 -40.96004)
		(width 0.14224)
		(layer "In11.Cu")
		(net "M_J_DQS_DP<10>")
	)
	(segment
		(start 43.792648 -33.873186)
		(end 44.170854 -34.251392)
		(width 0.14224)
		(layer "In11.Cu")
		(net "M_J_DQS_DP<10>")
	)
	(segment
		(start 44.120562 -1.685036)
		(end 44.277026 -1.8415)
		(width 0.14224)
		(layer "In11.Cu")
		(net "M_J_DQS_DP<10>")
	)
	(segment
		(start 43.621198 -5.367274)
		(end 44.605194 -6.35127)
		(width 0.14224)
		(layer "In11.Cu")
		(net "M_J_DQS_DP<10>")
	)
	(segment
		(start 44.611798 -2.731262)
		(end 44.37126 -2.9718)
		(width 0.14224)
		(layer "In11.Cu")
		(net "M_J_DQS_DP<10>")
	)
	(segment
		(start 44.403518 -0.5842)
		(end 44.611798 -0.79248)
		(width 0.14224)
		(layer "In11.Cu")
		(net "M_J_DQS_DP<10>")
	)
	(segment
		(start 44.428918 -1.2192)
		(end 44.24807 -1.2192)
		(width 0.14224)
		(layer "In11.Cu")
		(net "M_J_DQS_DP<10>")
	)
	(segment
		(start 44.276518 -0.5842)
		(end 44.403518 -0.5842)
		(width 0.14224)
		(layer "In11.Cu")
		(net "M_J_DQS_DP<10>")
	)
	(segment
		(start 75.251056 -61.238638)
		(end 75.301602 -61.149738)
		(width 0.0889)
		(layer "In11.Cu")
		(net "M_J_DQS_DP<10>")
	)
	(segment
		(start 44.092114 -2.9718)
		(end 43.621198 -3.442716)
		(width 0.14224)
		(layer "In11.Cu")
		(net "M_J_DQS_DP<10>")
	)
	(segment
		(start 70.598792 -59.15279)
		(end 70.626732 -59.15279)
		(width 0.0889)
		(layer "In11.Cu")
		(net "M_J_DQS_DP<10>")
	)
	(segment
		(start 44.605194 -25.70734)
		(end 43.792648 -26.519886)
		(width 0.14224)
		(layer "In11.Cu")
		(net "M_J_DQS_DP<10>")
	)
	(segment
		(start 65.504568 -57.21096)
		(end 65.543938 -57.17159)
		(width 0.0889)
		(layer "In11.Cu")
		(net "M_J_DQS_DP<10>")
	)
	(segment
		(start 44.37126 -2.9718)
		(end 44.092114 -2.9718)
		(width 0.14224)
		(layer "In11.Cu")
		(net "M_J_DQS_DP<10>")
	)
	(segment
		(start 44.365418 -1.8415)
		(end 44.611798 -2.08788)
		(width 0.14224)
		(layer "In11.Cu")
		(net "M_J_DQS_DP<10>")
	)
	(segment
		(start 51.865784 -43.351704)
		(end 51.865784 -44.315888)
		(width 0.14224)
		(layer "In11.Cu")
		(net "M_J_DQS_DP<10>")
	)
	(segment
		(start 44.24807 -1.2192)
		(end 44.120562 -1.346708)
		(width 0.14224)
		(layer "In11.Cu")
		(net "M_J_DQS_DP<10>")
	)
	(segment
		(start 74.028046 -61.13399)
		(end 74.060812 -61.13399)
		(width 0.0889)
		(layer "In11.Cu")
		(net "M_J_DQS_DP<10>")
	)
	(segment
		(start 75.751182 -60.545218)
		(end 75.762866 -60.54344)
		(width 0.0889)
		(layer "In11.Cu")
		(net "M_J_DQS_DP<10>")
	)
	(segment
		(start 43.621198 -3.442716)
		(end 43.621198 -5.367274)
		(width 0.14224)
		(layer "In11.Cu")
		(net "M_J_DQS_DP<10>")
	)
	(segment
		(start 44.120562 -1.346708)
		(end 44.120562 -1.685036)
		(width 0.14224)
		(layer "In11.Cu")
		(net "M_J_DQS_DP<10>")
	)
	(segment
		(start 74.237088 -61.18225)
		(end 74.585576 -61.290454)
		(width 0.0889)
		(layer "In11.Cu")
		(net "M_J_DQS_DP<10>")
	)
	(segment
		(start 44.611798 -1.03632)
		(end 44.428918 -1.2192)
		(width 0.14224)
		(layer "In11.Cu")
		(net "M_J_DQS_DP<10>")
	)
	(segment
		(start 49.47412 -40.96004)
		(end 51.865784 -43.351704)
		(width 0.14224)
		(layer "In11.Cu")
		(net "M_J_DQS_DP<10>")
	)
	(segment
		(start 44.124118 -0.4318)
		(end 44.276518 -0.5842)
		(width 0.14224)
		(layer "In11.Cu")
		(net "M_J_DQS_DP<10>")
	)
	(segment
		(start 44.431204 1.32588)
		(end 44.611798 1.145286)
		(width 0.14224)
		(layer "In11.Cu")
		(net "M_J_DQS_DP<10>")
	)
	(segment
		(start 43.767248 -35.68192)
		(end 43.767248 -36.217352)
		(width 0.14224)
		(layer "In11.Cu")
		(net "M_J_DQS_DP<10>")
	)
	(segment
		(start 72.311006 -60.14339)
		(end 72.343772 -60.14339)
		(width 0.0889)
		(layer "In11.Cu")
		(net "M_J_DQS_DP<10>")
	)
	(arc
		(start 70.099936 -58.857388)
		(mid 70.310649 -59.070467)
		(end 70.598792 -59.15279)
		(width 0.0889)
		(layer "In11.Cu")
		(net "M_J_DQS_DP<10>")
	)
	(arc
		(start 74.192384 -61.161422)
		(mid 74.21506 -61.171142)
		(end 74.237088 -61.18225)
		(width 0.0889)
		(layer "In11.Cu")
		(net "M_J_DQS_DP<10>")
	)
	(arc
		(start 73.198482 -60.638436)
		(mid 73.392332 -60.694786)
		(end 73.534016 -60.838588)
		(width 0.0889)
		(layer "In11.Cu")
		(net "M_J_DQS_DP<10>")
	)
	(arc
		(start 71.481442 -59.647836)
		(mid 71.675292 -59.704186)
		(end 71.816976 -59.847988)
		(width 0.0889)
		(layer "In11.Cu")
		(net "M_J_DQS_DP<10>")
	)
	(arc
		(start 72.343772 -60.14339)
		(mid 72.535414 -60.200556)
		(end 72.675496 -60.343288)
		(width 0.0889)
		(layer "In11.Cu")
		(net "M_J_DQS_DP<10>")
	)
	(arc
		(start 70.626732 -59.15279)
		(mid 70.818374 -59.209956)
		(end 70.958456 -59.352688)
		(width 0.0889)
		(layer "In11.Cu")
		(net "M_J_DQS_DP<10>")
	)
	(arc
		(start 69.767958 -58.657236)
		(mid 69.959741 -58.714345)
		(end 70.099936 -58.857134)
		(width 0.0889)
		(layer "In11.Cu")
		(net "M_J_DQS_DP<10>")
	)
	(arc
		(start 71.816976 -59.847988)
		(mid 72.025584 -60.05992)
		(end 72.311006 -60.14339)
		(width 0.0889)
		(layer "In11.Cu")
		(net "M_J_DQS_DP<10>")
	)
	(arc
		(start 74.060812 -61.13399)
		(mid 74.127759 -61.14214)
		(end 74.192384 -61.161422)
		(width 0.0889)
		(layer "In11.Cu")
		(net "M_J_DQS_DP<10>")
	)
	(arc
		(start 74.585576 -61.290454)
		(mid 74.692159 -61.399139)
		(end 74.839068 -61.439044)
		(width 0.0889)
		(layer "In11.Cu")
		(net "M_J_DQS_DP<10>")
	)
	(arc
		(start 72.675496 -60.343288)
		(mid 72.8825 -60.554152)
		(end 73.165716 -60.638436)
		(width 0.0889)
		(layer "In11.Cu")
		(net "M_J_DQS_DP<10>")
	)
	(arc
		(start 73.534016 -60.838588)
		(mid 73.742624 -61.05052)
		(end 74.028046 -61.13399)
		(width 0.0889)
		(layer "In11.Cu")
		(net "M_J_DQS_DP<10>")
	)
	(arc
		(start 70.958456 -59.352688)
		(mid 71.16546 -59.563552)
		(end 71.448676 -59.647836)
		(width 0.0889)
		(layer "In11.Cu")
		(net "M_J_DQS_DP<10>")
	)
	(arc
		(start 74.919332 -61.438536)
		(mid 75.110974 -61.38137)
		(end 75.251056 -61.238638)
		(width 0.0889)
		(layer "In11.Cu")
		(net "M_J_DQS_DP<10>")
	)
	(segment
		(start 36.311332 1.455166)
		(end 36.03752 1.181354)
		(width 0.1651)
		(layer "F.Cu")
		(net "M_J_DQS_DP<0>")
	)
	(segment
		(start 36.721034 0.49911)
		(end 36.721034 1.241298)
		(width 0.1651)
		(layer "F.Cu")
		(net "M_J_DQS_DP<0>")
	)
	(segment
		(start 77.192886 -65.000886)
		(end 76.621386 -65.000886)
		(width 0.0889)
		(layer "F.Cu")
		(net "M_J_DQS_DP<0>")
	)
	(segment
		(start 36.721034 1.241298)
		(end 36.507166 1.455166)
		(width 0.1651)
		(layer "F.Cu")
		(net "M_J_DQS_DP<0>")
	)
	(segment
		(start 36.499546 -0.821182)
		(end 36.499546 0.277622)
		(width 0.1651)
		(layer "F.Cu")
		(net "M_J_DQS_DP<0>")
	)
	(segment
		(start 36.507166 1.455166)
		(end 36.311332 1.455166)
		(width 0.1651)
		(layer "F.Cu")
		(net "M_J_DQS_DP<0>")
	)
	(segment
		(start 36.499546 0.277622)
		(end 36.721034 0.49911)
		(width 0.1651)
		(layer "F.Cu")
		(net "M_J_DQS_DP<0>")
	)
	(via
		(at 36.03752 1.181354)
		(size 0.508)
		(drill 0.254)
		(layers "F.Cu" "B.Cu")
		(net "M_J_DQS_DP<0>")
	)
	(via
		(at 36.03752 -3.026156)
		(size 0.508)
		(drill 0.254)
		(layers "F.Cu" "B.Cu")
		(net "M_J_DQS_DP<0>")
	)
	(via
		(at 76.621386 -65.000886)
		(size 0.508)
		(drill 0.254)
		(layers "F.Cu" "B.Cu")
		(net "M_J_DQS_DP<0>")
	)
	(segment
		(start 36.318444 -3.30708)
		(end 36.03752 -3.026156)
		(width 0.1651)
		(layer "B.Cu")
		(net "M_J_DQS_DP<0>")
	)
	(segment
		(start 36.679124 -2.7178)
		(end 36.679124 -3.16738)
		(width 0.1651)
		(layer "B.Cu")
		(net "M_J_DQS_DP<0>")
	)
	(segment
		(start 36.539424 -3.30708)
		(end 36.318444 -3.30708)
		(width 0.1651)
		(layer "B.Cu")
		(net "M_J_DQS_DP<0>")
	)
	(segment
		(start 36.679124 -3.16738)
		(end 36.539424 -3.30708)
		(width 0.1651)
		(layer "B.Cu")
		(net "M_J_DQS_DP<0>")
	)
	(segment
		(start 36.499546 -1.021842)
		(end 36.499546 -2.538222)
		(width 0.1651)
		(layer "B.Cu")
		(net "M_J_DQS_DP<0>")
	)
	(segment
		(start 36.499546 -2.538222)
		(end 36.679124 -2.7178)
		(width 0.1651)
		(layer "B.Cu")
		(net "M_J_DQS_DP<0>")
	)
	(segment
		(start 76.914502 -64.831976)
		(end 76.830174 -64.88049)
		(width 0.0889)
		(layer "In11.Cu")
		(net "M_J_DQS_DP<0>")
	)
	(segment
		(start 36.5506 -35.583114)
		(end 36.5506 -37.676328)
		(width 0.14224)
		(layer "In11.Cu")
		(net "M_J_DQS_DP<0>")
	)
	(segment
		(start 76.61021 -64.600836)
		(end 76.632562 -64.600836)
		(width 0.0889)
		(layer "In11.Cu")
		(net "M_J_DQS_DP<0>")
	)
	(segment
		(start 36.319206 1.181354)
		(end 36.579048 0.921512)
		(width 0.14224)
		(layer "In11.Cu")
		(net "M_J_DQS_DP<0>")
	)
	(segment
		(start 35.410648 -32.355028)
		(end 35.788854 -32.733234)
		(width 0.14224)
		(layer "In11.Cu")
		(net "M_J_DQS_DP<0>")
	)
	(segment
		(start 71.448676 -64.600836)
		(end 71.481442 -64.600836)
		(width 0.0889)
		(layer "In11.Cu")
		(net "M_J_DQS_DP<0>")
	)
	(segment
		(start 36.37407 -0.5334)
		(end 36.579048 -0.738378)
		(width 0.14224)
		(layer "In11.Cu")
		(net "M_J_DQS_DP<0>")
	)
	(segment
		(start 76.830174 -64.88049)
		(end 76.621386 -65.000886)
		(width 0.0889)
		(layer "In11.Cu")
		(net "M_J_DQS_DP<0>")
	)
	(segment
		(start 75.74788 -65.09639)
		(end 75.780646 -65.09639)
		(width 0.0889)
		(layer "In11.Cu")
		(net "M_J_DQS_DP<0>")
	)
	(segment
		(start 74.045318 -66.08699)
		(end 74.046334 -66.08699)
		(width 0.0889)
		(layer "In11.Cu")
		(net "M_J_DQS_DP<0>")
	)
	(segment
		(start 36.579048 -1.08712)
		(end 36.396168 -1.27)
		(width 0.14224)
		(layer "In11.Cu")
		(net "M_J_DQS_DP<0>")
	)
	(segment
		(start 36.044124 -0.076454)
		(end 36.044124 -0.380746)
		(width 0.14224)
		(layer "In11.Cu")
		(net "M_J_DQS_DP<0>")
	)
	(segment
		(start 36.579048 -2.058924)
		(end 36.579048 -2.763774)
		(width 0.14224)
		(layer "In11.Cu")
		(net "M_J_DQS_DP<0>")
	)
	(segment
		(start 36.269168 -1.8796)
		(end 36.399724 -1.8796)
		(width 0.14224)
		(layer "In11.Cu")
		(net "M_J_DQS_DP<0>")
	)
	(segment
		(start 61.45784 -64.14516)
		(end 66.297556 -64.14516)
		(width 0.14224)
		(layer "In11.Cu")
		(net "M_J_DQS_DP<0>")
	)
	(segment
		(start 74.89317 -65.591436)
		(end 74.925936 -65.591436)
		(width 0.0889)
		(layer "In11.Cu")
		(net "M_J_DQS_DP<0>")
	)
	(segment
		(start 68.035424 -63.61049)
		(end 68.036948 -63.61049)
		(width 0.0889)
		(layer "In11.Cu")
		(net "M_J_DQS_DP<0>")
	)
	(segment
		(start 40.210994 -42.898314)
		(end 61.45784 -64.14516)
		(width 0.14224)
		(layer "In11.Cu")
		(net "M_J_DQS_DP<0>")
	)
	(segment
		(start 37.065712 -32.954722)
		(end 37.065712 -33.563306)
		(width 0.14224)
		(layer "In11.Cu")
		(net "M_J_DQS_DP<0>")
	)
	(segment
		(start 37.065712 -33.563306)
		(end 36.818824 -33.810194)
		(width 0.14224)
		(layer "In11.Cu")
		(net "M_J_DQS_DP<0>")
	)
	(segment
		(start 36.044124 -0.380746)
		(end 36.196778 -0.5334)
		(width 0.14224)
		(layer "In11.Cu")
		(net "M_J_DQS_DP<0>")
	)
	(segment
		(start 36.5506 -24.88184)
		(end 35.410648 -26.021792)
		(width 0.14224)
		(layer "In11.Cu")
		(net "M_J_DQS_DP<0>")
	)
	(segment
		(start 35.788854 -32.733234)
		(end 36.844224 -32.733234)
		(width 0.14224)
		(layer "In11.Cu")
		(net "M_J_DQS_DP<0>")
	)
	(segment
		(start 36.03752 -3.026156)
		(end 35.599624 -3.464052)
		(width 0.14224)
		(layer "In11.Cu")
		(net "M_J_DQS_DP<0>")
	)
	(segment
		(start 35.599624 -3.464052)
		(end 35.599624 -4.66471)
		(width 0.14224)
		(layer "In11.Cu")
		(net "M_J_DQS_DP<0>")
	)
	(segment
		(start 36.269168 -1.27)
		(end 36.091368 -1.4478)
		(width 0.14224)
		(layer "In11.Cu")
		(net "M_J_DQS_DP<0>")
	)
	(segment
		(start 35.46094 -34.329116)
		(end 35.46094 -35.042094)
		(width 0.14224)
		(layer "In11.Cu")
		(net "M_J_DQS_DP<0>")
	)
	(segment
		(start 36.196778 -0.5334)
		(end 36.37407 -0.5334)
		(width 0.14224)
		(layer "In11.Cu")
		(net "M_J_DQS_DP<0>")
	)
	(segment
		(start 68.89369 -64.105536)
		(end 68.895722 -64.105536)
		(width 0.0889)
		(layer "In11.Cu")
		(net "M_J_DQS_DP<0>")
	)
	(segment
		(start 36.396168 -1.27)
		(end 36.269168 -1.27)
		(width 0.14224)
		(layer "In11.Cu")
		(net "M_J_DQS_DP<0>")
	)
	(segment
		(start 35.846766 -35.42792)
		(end 36.395406 -35.42792)
		(width 0.14224)
		(layer "In11.Cu")
		(net "M_J_DQS_DP<0>")
	)
	(segment
		(start 66.297556 -64.14516)
		(end 66.319654 -64.14516)
		(width 0.0889)
		(layer "In11.Cu")
		(net "M_J_DQS_DP<0>")
	)
	(segment
		(start 36.39947 0.0762)
		(end 36.196778 0.0762)
		(width 0.14224)
		(layer "In11.Cu")
		(net "M_J_DQS_DP<0>")
	)
	(segment
		(start 35.719004 -4.78409)
		(end 35.719004 -5.392674)
		(width 0.14224)
		(layer "In11.Cu")
		(net "M_J_DQS_DP<0>")
	)
	(segment
		(start 36.579048 0.255778)
		(end 36.39947 0.0762)
		(width 0.14224)
		(layer "In11.Cu")
		(net "M_J_DQS_DP<0>")
	)
	(segment
		(start 36.395406 -35.42792)
		(end 36.5506 -35.583114)
		(width 0.14224)
		(layer "In11.Cu")
		(net "M_J_DQS_DP<0>")
	)
	(segment
		(start 36.03752 1.181354)
		(end 36.319206 1.181354)
		(width 0.14224)
		(layer "In11.Cu")
		(net "M_J_DQS_DP<0>")
	)
	(segment
		(start 35.599624 -4.66471)
		(end 35.719004 -4.78409)
		(width 0.14224)
		(layer "In11.Cu")
		(net "M_J_DQS_DP<0>")
	)
	(segment
		(start 70.59803 -64.10579)
		(end 70.626732 -64.10579)
		(width 0.0889)
		(layer "In11.Cu")
		(net "M_J_DQS_DP<0>")
	)
	(segment
		(start 40.210994 -41.336722)
		(end 40.210994 -42.898314)
		(width 0.14224)
		(layer "In11.Cu")
		(net "M_J_DQS_DP<0>")
	)
	(segment
		(start 66.359024 -64.10579)
		(end 67.191382 -64.10579)
		(width 0.0889)
		(layer "In11.Cu")
		(net "M_J_DQS_DP<0>")
	)
	(segment
		(start 36.03752 -3.02641)
		(end 36.03752 -3.026156)
		(width 0.14224)
		(layer "In11.Cu")
		(net "M_J_DQS_DP<0>")
	)
	(segment
		(start 66.319654 -64.14516)
		(end 66.359024 -64.10579)
		(width 0.0889)
		(layer "In11.Cu")
		(net "M_J_DQS_DP<0>")
	)
	(segment
		(start 35.719004 -5.392674)
		(end 36.5506 -6.22427)
		(width 0.14224)
		(layer "In11.Cu")
		(net "M_J_DQS_DP<0>")
	)
	(segment
		(start 36.5506 -6.22427)
		(end 36.5506 -24.88184)
		(width 0.14224)
		(layer "In11.Cu")
		(net "M_J_DQS_DP<0>")
	)
	(segment
		(start 36.579048 -2.763774)
		(end 36.316412 -3.02641)
		(width 0.14224)
		(layer "In11.Cu")
		(net "M_J_DQS_DP<0>")
	)
	(segment
		(start 36.399724 -1.8796)
		(end 36.579048 -2.058924)
		(width 0.14224)
		(layer "In11.Cu")
		(net "M_J_DQS_DP<0>")
	)
	(segment
		(start 69.752464 -63.61049)
		(end 69.753988 -63.61049)
		(width 0.0889)
		(layer "In11.Cu")
		(net "M_J_DQS_DP<0>")
	)
	(segment
		(start 73.165716 -65.591436)
		(end 73.198482 -65.591436)
		(width 0.0889)
		(layer "In11.Cu")
		(net "M_J_DQS_DP<0>")
	)
	(segment
		(start 36.818824 -33.810194)
		(end 35.979862 -33.810194)
		(width 0.14224)
		(layer "In11.Cu")
		(net "M_J_DQS_DP<0>")
	)
	(segment
		(start 36.196778 0.0762)
		(end 36.044124 -0.076454)
		(width 0.14224)
		(layer "In11.Cu")
		(net "M_J_DQS_DP<0>")
	)
	(segment
		(start 36.316412 -3.02641)
		(end 36.03752 -3.02641)
		(width 0.14224)
		(layer "In11.Cu")
		(net "M_J_DQS_DP<0>")
	)
	(segment
		(start 76.935584 -64.753236)
		(end 76.914502 -64.831976)
		(width 0.0889)
		(layer "In11.Cu")
		(net "M_J_DQS_DP<0>")
	)
	(segment
		(start 36.579048 -0.738378)
		(end 36.579048 -1.08712)
		(width 0.14224)
		(layer "In11.Cu")
		(net "M_J_DQS_DP<0>")
	)
	(segment
		(start 36.091368 -1.4478)
		(end 36.091368 -1.7018)
		(width 0.14224)
		(layer "In11.Cu")
		(net "M_J_DQS_DP<0>")
	)
	(segment
		(start 36.579048 0.921512)
		(end 36.579048 0.255778)
		(width 0.14224)
		(layer "In11.Cu")
		(net "M_J_DQS_DP<0>")
	)
	(segment
		(start 35.979862 -33.810194)
		(end 35.46094 -34.329116)
		(width 0.14224)
		(layer "In11.Cu")
		(net "M_J_DQS_DP<0>")
	)
	(segment
		(start 35.46094 -35.042094)
		(end 35.846766 -35.42792)
		(width 0.14224)
		(layer "In11.Cu")
		(net "M_J_DQS_DP<0>")
	)
	(segment
		(start 36.5506 -37.676328)
		(end 40.210994 -41.336722)
		(width 0.14224)
		(layer "In11.Cu")
		(net "M_J_DQS_DP<0>")
	)
	(segment
		(start 36.091368 -1.7018)
		(end 36.269168 -1.8796)
		(width 0.14224)
		(layer "In11.Cu")
		(net "M_J_DQS_DP<0>")
	)
	(segment
		(start 35.410648 -26.021792)
		(end 35.410648 -32.355028)
		(width 0.14224)
		(layer "In11.Cu")
		(net "M_J_DQS_DP<0>")
	)
	(segment
		(start 72.311006 -65.09639)
		(end 72.343772 -65.09639)
		(width 0.0889)
		(layer "In11.Cu")
		(net "M_J_DQS_DP<0>")
	)
	(segment
		(start 36.844224 -32.733234)
		(end 37.065712 -32.954722)
		(width 0.14224)
		(layer "In11.Cu")
		(net "M_J_DQS_DP<0>")
	)
	(arc
		(start 70.099936 -63.810388)
		(mid 70.310289 -64.02336)
		(end 70.59803 -64.10579)
		(width 0.0889)
		(layer "In11.Cu")
		(net "M_J_DQS_DP<0>")
	)
	(arc
		(start 68.036948 -63.61049)
		(mid 68.236721 -63.664059)
		(end 68.382896 -63.810388)
		(width 0.0889)
		(layer "In11.Cu")
		(net "M_J_DQS_DP<0>")
	)
	(arc
		(start 68.382896 -63.810388)
		(mid 68.59875 -64.026369)
		(end 68.89369 -64.105536)
		(width 0.0889)
		(layer "In11.Cu")
		(net "M_J_DQS_DP<0>")
	)
	(arc
		(start 74.046334 -66.08699)
		(mid 74.341597 -66.007839)
		(end 74.557636 -65.791588)
		(width 0.0889)
		(layer "In11.Cu")
		(net "M_J_DQS_DP<0>")
	)
	(arc
		(start 71.816976 -64.800988)
		(mid 72.025584 -65.01292)
		(end 72.311006 -65.09639)
		(width 0.0889)
		(layer "In11.Cu")
		(net "M_J_DQS_DP<0>")
	)
	(arc
		(start 67.689476 -63.810388)
		(mid 67.835648 -63.664053)
		(end 68.035424 -63.61049)
		(width 0.0889)
		(layer "In11.Cu")
		(net "M_J_DQS_DP<0>")
	)
	(arc
		(start 71.481442 -64.600836)
		(mid 71.675292 -64.657186)
		(end 71.816976 -64.800988)
		(width 0.0889)
		(layer "In11.Cu")
		(net "M_J_DQS_DP<0>")
	)
	(arc
		(start 72.343772 -65.09639)
		(mid 72.535414 -65.153556)
		(end 72.675496 -65.296288)
		(width 0.0889)
		(layer "In11.Cu")
		(net "M_J_DQS_DP<0>")
	)
	(arc
		(start 73.198482 -65.591436)
		(mid 73.392332 -65.647786)
		(end 73.534016 -65.791588)
		(width 0.0889)
		(layer "In11.Cu")
		(net "M_J_DQS_DP<0>")
	)
	(arc
		(start 74.557636 -65.791588)
		(mid 74.699319 -65.647784)
		(end 74.89317 -65.591436)
		(width 0.0889)
		(layer "In11.Cu")
		(net "M_J_DQS_DP<0>")
	)
	(arc
		(start 76.274676 -64.800988)
		(mid 76.416359 -64.657184)
		(end 76.61021 -64.600836)
		(width 0.0889)
		(layer "In11.Cu")
		(net "M_J_DQS_DP<0>")
	)
	(arc
		(start 74.925936 -65.591436)
		(mid 75.209153 -65.507155)
		(end 75.416156 -65.296288)
		(width 0.0889)
		(layer "In11.Cu")
		(net "M_J_DQS_DP<0>")
	)
	(arc
		(start 73.534016 -65.791588)
		(mid 73.750079 -66.007797)
		(end 74.045318 -66.08699)
		(width 0.0889)
		(layer "In11.Cu")
		(net "M_J_DQS_DP<0>")
	)
	(arc
		(start 70.626732 -64.10579)
		(mid 70.818374 -64.162956)
		(end 70.958456 -64.305688)
		(width 0.0889)
		(layer "In11.Cu")
		(net "M_J_DQS_DP<0>")
	)
	(arc
		(start 67.191382 -64.10579)
		(mid 67.479069 -64.023269)
		(end 67.689476 -63.810388)
		(width 0.0889)
		(layer "In11.Cu")
		(net "M_J_DQS_DP<0>")
	)
	(arc
		(start 75.416156 -65.296288)
		(mid 75.556235 -65.153552)
		(end 75.74788 -65.09639)
		(width 0.0889)
		(layer "In11.Cu")
		(net "M_J_DQS_DP<0>")
	)
	(arc
		(start 75.780646 -65.09639)
		(mid 76.06607 -65.012923)
		(end 76.274676 -64.800988)
		(width 0.0889)
		(layer "In11.Cu")
		(net "M_J_DQS_DP<0>")
	)
	(arc
		(start 69.753988 -63.61049)
		(mid 69.953761 -63.664059)
		(end 70.099936 -63.810388)
		(width 0.0889)
		(layer "In11.Cu")
		(net "M_J_DQS_DP<0>")
	)
	(arc
		(start 76.632562 -64.600836)
		(mid 76.800999 -64.643369)
		(end 76.935584 -64.753236)
		(width 0.0889)
		(layer "In11.Cu")
		(net "M_J_DQS_DP<0>")
	)
	(arc
		(start 72.675496 -65.296288)
		(mid 72.8825 -65.507152)
		(end 73.165716 -65.591436)
		(width 0.0889)
		(layer "In11.Cu")
		(net "M_J_DQS_DP<0>")
	)
	(arc
		(start 69.406516 -63.810388)
		(mid 69.552688 -63.664053)
		(end 69.752464 -63.61049)
		(width 0.0889)
		(layer "In11.Cu")
		(net "M_J_DQS_DP<0>")
	)
	(arc
		(start 68.895722 -64.105536)
		(mid 69.190716 -64.026462)
		(end 69.406516 -63.810388)
		(width 0.0889)
		(layer "In11.Cu")
		(net "M_J_DQS_DP<0>")
	)
	(arc
		(start 70.958456 -64.305688)
		(mid 71.16546 -64.516552)
		(end 71.448676 -64.600836)
		(width 0.0889)
		(layer "In11.Cu")
		(net "M_J_DQS_DP<0>")
	)
	(segment
		(start 34.767774 1.7907)
		(end 34.748724 1.7907)
		(width 0.1651)
		(layer "F.Cu")
		(net "M_J_DQS_DN<9>")
	)
	(segment
		(start 35.231324 2.286)
		(end 35.417252 2.100072)
		(width 0.1651)
		(layer "F.Cu")
		(net "M_J_DQS_DN<9>")
	)
	(segment
		(start 75.475846 -65.991486)
		(end 74.904346 -65.991486)
		(width 0.0889)
		(layer "F.Cu")
		(net "M_J_DQS_DN<9>")
	)
	(segment
		(start 35.417252 1.853438)
		(end 35.165284 1.60147)
		(width 0.1651)
		(layer "F.Cu")
		(net "M_J_DQS_DN<9>")
	)
	(segment
		(start 35.417252 2.100072)
		(end 35.417252 1.853438)
		(width 0.1651)
		(layer "F.Cu")
		(net "M_J_DQS_DN<9>")
	)
	(segment
		(start 35.165284 1.60147)
		(end 34.957004 1.60147)
		(width 0.1651)
		(layer "F.Cu")
		(net "M_J_DQS_DN<9>")
	)
	(segment
		(start 35.231324 2.518156)
		(end 35.231324 2.286)
		(width 0.1651)
		(layer "F.Cu")
		(net "M_J_DQS_DN<9>")
	)
	(segment
		(start 34.957004 1.60147)
		(end 34.767774 1.7907)
		(width 0.1651)
		(layer "F.Cu")
		(net "M_J_DQS_DN<9>")
	)
	(segment
		(start 35.649408 3.778758)
		(end 35.649408 2.93624)
		(width 0.1651)
		(layer "F.Cu")
		(net "M_J_DQS_DN<9>")
	)
	(segment
		(start 35.649408 2.93624)
		(end 35.231324 2.518156)
		(width 0.1651)
		(layer "F.Cu")
		(net "M_J_DQS_DN<9>")
	)
	(via
		(at 74.904346 -65.991486)
		(size 0.508)
		(drill 0.254)
		(layers "F.Cu" "B.Cu")
		(net "M_J_DQS_DN<9>")
	)
	(via
		(at 34.748724 1.7907)
		(size 0.508)
		(drill 0.254)
		(layers "F.Cu" "B.Cu")
		(net "M_J_DQS_DN<9>")
	)
	(via
		(at 34.74212 -3.6322)
		(size 0.508)
		(drill 0.254)
		(layers "F.Cu" "B.Cu")
		(net "M_J_DQS_DN<9>")
	)
	(segment
		(start 35.16376 -3.437636)
		(end 34.936684 -3.437636)
		(width 0.1651)
		(layer "B.Cu")
		(net "M_J_DQS_DN<9>")
	)
	(segment
		(start 35.205924 -4.521454)
		(end 35.205924 -4.1656)
		(width 0.1651)
		(layer "B.Cu")
		(net "M_J_DQS_DN<9>")
	)
	(segment
		(start 35.649408 -4.964938)
		(end 35.205924 -4.521454)
		(width 0.1651)
		(layer "B.Cu")
		(net "M_J_DQS_DN<9>")
	)
	(segment
		(start 35.205924 -4.1656)
		(end 35.383724 -3.9878)
		(width 0.1651)
		(layer "B.Cu")
		(net "M_J_DQS_DN<9>")
	)
	(segment
		(start 34.936684 -3.437636)
		(end 34.74212 -3.6322)
		(width 0.1651)
		(layer "B.Cu")
		(net "M_J_DQS_DN<9>")
	)
	(segment
		(start 35.383724 -3.9878)
		(end 35.383724 -3.6576)
		(width 0.1651)
		(layer "B.Cu")
		(net "M_J_DQS_DN<9>")
	)
	(segment
		(start 35.649408 -5.621782)
		(end 35.649408 -4.964938)
		(width 0.1651)
		(layer "B.Cu")
		(net "M_J_DQS_DN<9>")
	)
	(segment
		(start 35.383724 -3.6576)
		(end 35.16376 -3.437636)
		(width 0.1651)
		(layer "B.Cu")
		(net "M_J_DQS_DN<9>")
	)
	(segment
		(start 58.778902 -62.305946)
		(end 58.778902 -62.46749)
		(width 0.14224)
		(layer "In11.Cu")
		(net "M_J_DQS_DN<9>")
	)
	(segment
		(start 35.52444 -11.12012)
		(end 35.682936 -11.278616)
		(width 0.14224)
		(layer "In11.Cu")
		(net "M_J_DQS_DN<9>")
	)
	(segment
		(start 34.714688 -34.09188)
		(end 34.714688 -35.891978)
		(width 0.14224)
		(layer "In11.Cu")
		(net "M_J_DQS_DN<9>")
	)
	(segment
		(start 58.59907 -62.126114)
		(end 58.778902 -62.305946)
		(width 0.14224)
		(layer "In11.Cu")
		(net "M_J_DQS_DN<9>")
	)
	(segment
		(start 34.936176 -36.113466)
		(end 35.240722 -36.113466)
		(width 0.14224)
		(layer "In11.Cu")
		(net "M_J_DQS_DN<9>")
	)
	(segment
		(start 59.30011 -62.8269)
		(end 59.30011 -62.988698)
		(width 0.14224)
		(layer "In11.Cu")
		(net "M_J_DQS_DN<9>")
	)
	(segment
		(start 60.421012 -64.1096)
		(end 60.656978 -64.345566)
		(width 0.14224)
		(layer "In11.Cu")
		(net "M_J_DQS_DN<9>")
	)
	(segment
		(start 58.778902 -62.46749)
		(end 58.95848 -62.647068)
		(width 0.14224)
		(layer "In11.Cu")
		(net "M_J_DQS_DN<9>")
	)
	(segment
		(start 62.502542 -64.86652)
		(end 62.616842 -64.75222)
		(width 0.14224)
		(layer "In11.Cu")
		(net "M_J_DQS_DN<9>")
	)
	(segment
		(start 58.95848 -62.647068)
		(end 59.120278 -62.647068)
		(width 0.14224)
		(layer "In11.Cu")
		(net "M_J_DQS_DN<9>")
	)
	(segment
		(start 35.193732 1.59512)
		(end 35.531044 1.257808)
		(width 0.14224)
		(layer "In11.Cu")
		(net "M_J_DQS_DN<9>")
	)
	(segment
		(start 60.998354 -64.525398)
		(end 60.998354 -64.686942)
		(width 0.14224)
		(layer "In11.Cu")
		(net "M_J_DQS_DN<9>")
	)
	(segment
		(start 35.682936 -10.006584)
		(end 35.52444 -10.16508)
		(width 0.14224)
		(layer "In11.Cu")
		(net "M_J_DQS_DN<9>")
	)
	(segment
		(start 34.540444 -5.254752)
		(end 35.52444 -6.238748)
		(width 0.14224)
		(layer "In11.Cu")
		(net "M_J_DQS_DN<9>")
	)
	(segment
		(start 60.998354 -64.686942)
		(end 61.177932 -64.86652)
		(width 0.14224)
		(layer "In11.Cu")
		(net "M_J_DQS_DN<9>")
	)
	(segment
		(start 35.056318 -33.018222)
		(end 35.056318 -33.75025)
		(width 0.14224)
		(layer "In11.Cu")
		(net "M_J_DQS_DN<9>")
	)
	(segment
		(start 35.756088 -20.179792)
		(end 35.756088 -21.06676)
		(width 0.14224)
		(layer "In11.Cu")
		(net "M_J_DQS_DN<9>")
	)
	(segment
		(start 34.714688 -29.295344)
		(end 34.714688 -29.92755)
		(width 0.14224)
		(layer "In11.Cu")
		(net "M_J_DQS_DN<9>")
	)
	(segment
		(start 34.714688 -31.652972)
		(end 34.714688 -32.676592)
		(width 0.14224)
		(layer "In11.Cu")
		(net "M_J_DQS_DN<9>")
	)
	(segment
		(start 65.733168 -64.86652)
		(end 65.772538 -64.90589)
		(width 0.0889)
		(layer "In11.Cu")
		(net "M_J_DQS_DN<9>")
	)
	(segment
		(start 34.540444 -4.98348)
		(end 34.540444 -5.254752)
		(width 0.14224)
		(layer "In11.Cu")
		(net "M_J_DQS_DN<9>")
	)
	(segment
		(start 35.682936 -9.754616)
		(end 35.682936 -10.006584)
		(width 0.14224)
		(layer "In11.Cu")
		(net "M_J_DQS_DN<9>")
	)
	(segment
		(start 35.52444 -24.486362)
		(end 34.714688 -25.296114)
		(width 0.14224)
		(layer "In11.Cu")
		(net "M_J_DQS_DN<9>")
	)
	(segment
		(start 60.421012 -63.947802)
		(end 60.421012 -64.1096)
		(width 0.14224)
		(layer "In11.Cu")
		(net "M_J_DQS_DN<9>")
	)
	(segment
		(start 74.511154 -66.541142)
		(end 74.519536 -66.530728)
		(width 0.0889)
		(layer "In11.Cu")
		(net "M_J_DQS_DN<9>")
	)
	(segment
		(start 35.683698 -36.556442)
		(end 35.683698 -37.253418)
		(width 0.14224)
		(layer "In11.Cu")
		(net "M_J_DQS_DN<9>")
	)
	(segment
		(start 34.714688 -32.676592)
		(end 35.056318 -33.018222)
		(width 0.14224)
		(layer "In11.Cu")
		(net "M_J_DQS_DN<9>")
	)
	(segment
		(start 35.52444 -10.16508)
		(end 35.52444 -10.35812)
		(width 0.14224)
		(layer "In11.Cu")
		(net "M_J_DQS_DN<9>")
	)
	(segment
		(start 69.752718 -64.41059)
		(end 69.753988 -64.41059)
		(width 0.0889)
		(layer "In11.Cu")
		(net "M_J_DQS_DN<9>")
	)
	(segment
		(start 35.682936 -10.768584)
		(end 35.52444 -10.92708)
		(width 0.14224)
		(layer "In11.Cu")
		(net "M_J_DQS_DN<9>")
	)
	(segment
		(start 59.822842 -63.51143)
		(end 60.079382 -63.76797)
		(width 0.14224)
		(layer "In11.Cu")
		(net "M_J_DQS_DN<9>")
	)
	(segment
		(start 59.481212 -63.1698)
		(end 59.64301 -63.1698)
		(width 0.14224)
		(layer "In11.Cu")
		(net "M_J_DQS_DN<9>")
	)
	(segment
		(start 64.996568 -64.86652)
		(end 65.110868 -64.75222)
		(width 0.14224)
		(layer "In11.Cu")
		(net "M_J_DQS_DN<9>")
	)
	(segment
		(start 72.314308 -65.89649)
		(end 72.347074 -65.89649)
		(width 0.0889)
		(layer "In11.Cu")
		(net "M_J_DQS_DN<9>")
	)
	(segment
		(start 35.144964 -37.792152)
		(end 35.144964 -38.700456)
		(width 0.14224)
		(layer "In11.Cu")
		(net "M_J_DQS_DN<9>")
	)
	(segment
		(start 62.195456 -64.86652)
		(end 62.502542 -64.86652)
		(width 0.14224)
		(layer "In11.Cu")
		(net "M_J_DQS_DN<9>")
	)
	(segment
		(start 36.958524 -38.829488)
		(end 37.609272 -39.480236)
		(width 0.14224)
		(layer "In11.Cu")
		(net "M_J_DQS_DN<9>")
	)
	(segment
		(start 63.6905 -64.75222)
		(end 63.8048 -64.86652)
		(width 0.14224)
		(layer "In11.Cu")
		(net "M_J_DQS_DN<9>")
	)
	(segment
		(start 35.52444 -9.59612)
		(end 35.682936 -9.754616)
		(width 0.14224)
		(layer "In11.Cu")
		(net "M_J_DQS_DN<9>")
	)
	(segment
		(start 35.683698 -37.253418)
		(end 35.144964 -37.792152)
		(width 0.14224)
		(layer "In11.Cu")
		(net "M_J_DQS_DN<9>")
	)
	(segment
		(start 34.828988 -28.356306)
		(end 34.714688 -28.470606)
		(width 0.14224)
		(layer "In11.Cu")
		(net "M_J_DQS_DN<9>")
	)
	(segment
		(start 60.24118 -63.76797)
		(end 60.421012 -63.947802)
		(width 0.14224)
		(layer "In11.Cu")
		(net "M_J_DQS_DN<9>")
	)
	(segment
		(start 34.828988 -31.284672)
		(end 34.828988 -31.538672)
		(width 0.14224)
		(layer "In11.Cu")
		(net "M_J_DQS_DN<9>")
	)
	(segment
		(start 35.52444 -10.35812)
		(end 35.682936 -10.516616)
		(width 0.14224)
		(layer "In11.Cu")
		(net "M_J_DQS_DN<9>")
	)
	(segment
		(start 70.60057 -64.90589)
		(end 70.630034 -64.90589)
		(width 0.0889)
		(layer "In11.Cu")
		(net "M_J_DQS_DN<9>")
	)
	(segment
		(start 65.479168 -64.86652)
		(end 65.733168 -64.86652)
		(width 0.14224)
		(layer "In11.Cu")
		(net "M_J_DQS_DN<9>")
	)
	(segment
		(start 59.30011 -62.988698)
		(end 59.481212 -63.1698)
		(width 0.14224)
		(layer "In11.Cu")
		(net "M_J_DQS_DN<9>")
	)
	(segment
		(start 39.516304 -41.55059)
		(end 39.516304 -43.204892)
		(width 0.14224)
		(layer "In11.Cu")
		(net "M_J_DQS_DN<9>")
	)
	(segment
		(start 34.74212 -3.6322)
		(end 35.180524 -4.070604)
		(width 0.14224)
		(layer "In11.Cu")
		(net "M_J_DQS_DN<9>")
	)
	(segment
		(start 34.828988 -30.29585)
		(end 34.714688 -30.41015)
		(width 0.14224)
		(layer "In11.Cu")
		(net "M_J_DQS_DN<9>")
	)
	(segment
		(start 37.862764 -41.002204)
		(end 38.967918 -41.002204)
		(width 0.14224)
		(layer "In11.Cu")
		(net "M_J_DQS_DN<9>")
	)
	(segment
		(start 34.714688 -31.170372)
		(end 34.828988 -31.284672)
		(width 0.14224)
		(layer "In11.Cu")
		(net "M_J_DQS_DN<9>")
	)
	(segment
		(start 39.516304 -43.204892)
		(end 58.437526 -62.126114)
		(width 0.14224)
		(layer "In11.Cu")
		(net "M_J_DQS_DN<9>")
	)
	(segment
		(start 34.748724 1.7907)
		(end 34.944304 1.59512)
		(width 0.14224)
		(layer "In11.Cu")
		(net "M_J_DQS_DN<9>")
	)
	(segment
		(start 35.682936 -14.301216)
		(end 35.682936 -14.553184)
		(width 0.14224)
		(layer "In11.Cu")
		(net "M_J_DQS_DN<9>")
	)
	(segment
		(start 63.4365 -64.75222)
		(end 63.6905 -64.75222)
		(width 0.14224)
		(layer "In11.Cu")
		(net "M_J_DQS_DN<9>")
	)
	(segment
		(start 35.52444 -11.68908)
		(end 35.52444 -14.14272)
		(width 0.14224)
		(layer "In11.Cu")
		(net "M_J_DQS_DN<9>")
	)
	(segment
		(start 63.3222 -64.86652)
		(end 63.4365 -64.75222)
		(width 0.14224)
		(layer "In11.Cu")
		(net "M_J_DQS_DN<9>")
	)
	(segment
		(start 34.828988 -29.181044)
		(end 34.714688 -29.295344)
		(width 0.14224)
		(layer "In11.Cu")
		(net "M_J_DQS_DN<9>")
	)
	(segment
		(start 65.364868 -64.75222)
		(end 65.479168 -64.86652)
		(width 0.14224)
		(layer "In11.Cu")
		(net "M_J_DQS_DN<9>")
	)
	(segment
		(start 34.714688 -28.812744)
		(end 34.828988 -28.927044)
		(width 0.14224)
		(layer "In11.Cu")
		(net "M_J_DQS_DN<9>")
	)
	(segment
		(start 35.682936 -10.516616)
		(end 35.682936 -10.768584)
		(width 0.14224)
		(layer "In11.Cu")
		(net "M_J_DQS_DN<9>")
	)
	(segment
		(start 62.985142 -64.86652)
		(end 63.3222 -64.86652)
		(width 0.14224)
		(layer "In11.Cu")
		(net "M_J_DQS_DN<9>")
	)
	(segment
		(start 37.609272 -40.748712)
		(end 37.862764 -41.002204)
		(width 0.14224)
		(layer "In11.Cu")
		(net "M_J_DQS_DN<9>")
	)
	(segment
		(start 62.616842 -64.75222)
		(end 62.870842 -64.75222)
		(width 0.14224)
		(layer "In11.Cu")
		(net "M_J_DQS_DN<9>")
	)
	(segment
		(start 37.609272 -39.480236)
		(end 37.609272 -40.748712)
		(width 0.14224)
		(layer "In11.Cu")
		(net "M_J_DQS_DN<9>")
	)
	(segment
		(start 60.818522 -64.345566)
		(end 60.998354 -64.525398)
		(width 0.14224)
		(layer "In11.Cu")
		(net "M_J_DQS_DN<9>")
	)
	(segment
		(start 62.081156 -64.75222)
		(end 62.195456 -64.86652)
		(width 0.14224)
		(layer "In11.Cu")
		(net "M_J_DQS_DN<9>")
	)
	(segment
		(start 35.144964 -38.700456)
		(end 35.273996 -38.829488)
		(width 0.14224)
		(layer "In11.Cu")
		(net "M_J_DQS_DN<9>")
	)
	(segment
		(start 34.977324 -4.8006)
		(end 34.723324 -4.8006)
		(width 0.14224)
		(layer "In11.Cu")
		(net "M_J_DQS_DN<9>")
	)
	(segment
		(start 59.64301 -63.1698)
		(end 59.822842 -63.349632)
		(width 0.14224)
		(layer "In11.Cu")
		(net "M_J_DQS_DN<9>")
	)
	(segment
		(start 35.52444 -14.71168)
		(end 35.52444 -19.948144)
		(width 0.14224)
		(layer "In11.Cu")
		(net "M_J_DQS_DN<9>")
	)
	(segment
		(start 60.079382 -63.76797)
		(end 60.24118 -63.76797)
		(width 0.14224)
		(layer "In11.Cu")
		(net "M_J_DQS_DN<9>")
	)
	(segment
		(start 35.531044 1.257808)
		(end 35.531044 -2.843276)
		(width 0.14224)
		(layer "In11.Cu")
		(net "M_J_DQS_DN<9>")
	)
	(segment
		(start 58.437526 -62.126114)
		(end 58.59907 -62.126114)
		(width 0.14224)
		(layer "In11.Cu")
		(net "M_J_DQS_DN<9>")
	)
	(segment
		(start 34.714688 -30.41015)
		(end 34.714688 -31.170372)
		(width 0.14224)
		(layer "In11.Cu")
		(net "M_J_DQS_DN<9>")
	)
	(segment
		(start 35.056318 -33.75025)
		(end 34.714688 -34.09188)
		(width 0.14224)
		(layer "In11.Cu")
		(net "M_J_DQS_DN<9>")
	)
	(segment
		(start 34.828988 -28.927044)
		(end 34.828988 -29.181044)
		(width 0.14224)
		(layer "In11.Cu")
		(net "M_J_DQS_DN<9>")
	)
	(segment
		(start 63.8048 -64.86652)
		(end 64.0588 -64.86652)
		(width 0.14224)
		(layer "In11.Cu")
		(net "M_J_DQS_DN<9>")
	)
	(segment
		(start 68.035678 -64.41059)
		(end 68.036948 -64.41059)
		(width 0.0889)
		(layer "In11.Cu")
		(net "M_J_DQS_DN<9>")
	)
	(segment
		(start 74.519536 -66.530728)
		(end 74.904346 -65.991486)
		(width 0.0889)
		(layer "In11.Cu")
		(net "M_J_DQS_DN<9>")
	)
	(segment
		(start 71.45274 -65.400936)
		(end 71.483982 -65.400936)
		(width 0.0889)
		(layer "In11.Cu")
		(net "M_J_DQS_DN<9>")
	)
	(segment
		(start 35.180524 -4.5974)
		(end 34.977324 -4.8006)
		(width 0.14224)
		(layer "In11.Cu")
		(net "M_J_DQS_DN<9>")
	)
	(segment
		(start 34.714688 -35.891978)
		(end 34.936176 -36.113466)
		(width 0.14224)
		(layer "In11.Cu")
		(net "M_J_DQS_DN<9>")
	)
	(segment
		(start 59.120278 -62.647068)
		(end 59.30011 -62.8269)
		(width 0.14224)
		(layer "In11.Cu")
		(net "M_J_DQS_DN<9>")
	)
	(segment
		(start 68.893944 -64.905636)
		(end 68.895468 -64.905636)
		(width 0.0889)
		(layer "In11.Cu")
		(net "M_J_DQS_DN<9>")
	)
	(segment
		(start 35.52444 -19.948144)
		(end 35.756088 -20.179792)
		(width 0.14224)
		(layer "In11.Cu")
		(net "M_J_DQS_DN<9>")
	)
	(segment
		(start 65.772538 -64.90589)
		(end 67.188842 -64.90589)
		(width 0.0889)
		(layer "In11.Cu")
		(net "M_J_DQS_DN<9>")
	)
	(segment
		(start 65.110868 -64.75222)
		(end 65.364868 -64.75222)
		(width 0.14224)
		(layer "In11.Cu")
		(net "M_J_DQS_DN<9>")
	)
	(segment
		(start 61.177932 -64.86652)
		(end 61.712856 -64.86652)
		(width 0.14224)
		(layer "In11.Cu")
		(net "M_J_DQS_DN<9>")
	)
	(segment
		(start 64.4271 -64.75222)
		(end 64.5414 -64.86652)
		(width 0.14224)
		(layer "In11.Cu")
		(net "M_J_DQS_DN<9>")
	)
	(segment
		(start 64.5414 -64.86652)
		(end 64.996568 -64.86652)
		(width 0.14224)
		(layer "In11.Cu")
		(net "M_J_DQS_DN<9>")
	)
	(segment
		(start 35.240722 -36.113466)
		(end 35.683698 -36.556442)
		(width 0.14224)
		(layer "In11.Cu")
		(net "M_J_DQS_DN<9>")
	)
	(segment
		(start 35.52444 -10.92708)
		(end 35.52444 -11.12012)
		(width 0.14224)
		(layer "In11.Cu")
		(net "M_J_DQS_DN<9>")
	)
	(segment
		(start 34.828988 -30.04185)
		(end 34.828988 -30.29585)
		(width 0.14224)
		(layer "In11.Cu")
		(net "M_J_DQS_DN<9>")
	)
	(segment
		(start 35.180524 -4.070604)
		(end 35.180524 -4.5974)
		(width 0.14224)
		(layer "In11.Cu")
		(net "M_J_DQS_DN<9>")
	)
	(segment
		(start 34.714688 -25.296114)
		(end 34.714688 -27.988006)
		(width 0.14224)
		(layer "In11.Cu")
		(net "M_J_DQS_DN<9>")
	)
	(segment
		(start 59.822842 -63.349632)
		(end 59.822842 -63.51143)
		(width 0.14224)
		(layer "In11.Cu")
		(net "M_J_DQS_DN<9>")
	)
	(segment
		(start 62.870842 -64.75222)
		(end 62.985142 -64.86652)
		(width 0.14224)
		(layer "In11.Cu")
		(net "M_J_DQS_DN<9>")
	)
	(segment
		(start 61.827156 -64.75222)
		(end 62.081156 -64.75222)
		(width 0.14224)
		(layer "In11.Cu")
		(net "M_J_DQS_DN<9>")
	)
	(segment
		(start 34.828988 -28.102306)
		(end 34.828988 -28.356306)
		(width 0.14224)
		(layer "In11.Cu")
		(net "M_J_DQS_DN<9>")
	)
	(segment
		(start 35.756088 -21.06676)
		(end 35.52444 -21.298408)
		(width 0.14224)
		(layer "In11.Cu")
		(net "M_J_DQS_DN<9>")
	)
	(segment
		(start 35.682936 -11.278616)
		(end 35.682936 -11.530584)
		(width 0.14224)
		(layer "In11.Cu")
		(net "M_J_DQS_DN<9>")
	)
	(segment
		(start 34.714688 -29.92755)
		(end 34.828988 -30.04185)
		(width 0.14224)
		(layer "In11.Cu")
		(net "M_J_DQS_DN<9>")
	)
	(segment
		(start 35.273996 -38.829488)
		(end 36.958524 -38.829488)
		(width 0.14224)
		(layer "In11.Cu")
		(net "M_J_DQS_DN<9>")
	)
	(segment
		(start 34.714688 -28.470606)
		(end 34.714688 -28.812744)
		(width 0.14224)
		(layer "In11.Cu")
		(net "M_J_DQS_DN<9>")
	)
	(segment
		(start 61.712856 -64.86652)
		(end 61.827156 -64.75222)
		(width 0.14224)
		(layer "In11.Cu")
		(net "M_J_DQS_DN<9>")
	)
	(segment
		(start 35.531044 -2.843276)
		(end 34.74212 -3.6322)
		(width 0.14224)
		(layer "In11.Cu")
		(net "M_J_DQS_DN<9>")
	)
	(segment
		(start 35.52444 -6.238748)
		(end 35.52444 -9.59612)
		(width 0.14224)
		(layer "In11.Cu")
		(net "M_J_DQS_DN<9>")
	)
	(segment
		(start 35.52444 -14.14272)
		(end 35.682936 -14.301216)
		(width 0.14224)
		(layer "In11.Cu")
		(net "M_J_DQS_DN<9>")
	)
	(segment
		(start 60.656978 -64.345566)
		(end 60.818522 -64.345566)
		(width 0.14224)
		(layer "In11.Cu")
		(net "M_J_DQS_DN<9>")
	)
	(segment
		(start 34.944304 1.59512)
		(end 35.193732 1.59512)
		(width 0.14224)
		(layer "In11.Cu")
		(net "M_J_DQS_DN<9>")
	)
	(segment
		(start 34.723324 -4.8006)
		(end 34.540444 -4.98348)
		(width 0.14224)
		(layer "In11.Cu")
		(net "M_J_DQS_DN<9>")
	)
	(segment
		(start 64.1731 -64.75222)
		(end 64.4271 -64.75222)
		(width 0.14224)
		(layer "In11.Cu")
		(net "M_J_DQS_DN<9>")
	)
	(segment
		(start 34.714688 -27.988006)
		(end 34.828988 -28.102306)
		(width 0.14224)
		(layer "In11.Cu")
		(net "M_J_DQS_DN<9>")
	)
	(segment
		(start 35.682936 -11.530584)
		(end 35.52444 -11.68908)
		(width 0.14224)
		(layer "In11.Cu")
		(net "M_J_DQS_DN<9>")
	)
	(segment
		(start 34.828988 -31.538672)
		(end 34.714688 -31.652972)
		(width 0.14224)
		(layer "In11.Cu")
		(net "M_J_DQS_DN<9>")
	)
	(segment
		(start 64.0588 -64.86652)
		(end 64.1731 -64.75222)
		(width 0.14224)
		(layer "In11.Cu")
		(net "M_J_DQS_DN<9>")
	)
	(segment
		(start 38.967918 -41.002204)
		(end 39.516304 -41.55059)
		(width 0.14224)
		(layer "In11.Cu")
		(net "M_J_DQS_DN<9>")
	)
	(segment
		(start 73.16978 -66.391536)
		(end 73.201022 -66.391536)
		(width 0.0889)
		(layer "In11.Cu")
		(net "M_J_DQS_DN<9>")
	)
	(segment
		(start 74.045572 -66.88709)
		(end 74.04608 -66.88709)
		(width 0.0889)
		(layer "In11.Cu")
		(net "M_J_DQS_DN<9>")
	)
	(segment
		(start 35.682936 -14.553184)
		(end 35.52444 -14.71168)
		(width 0.14224)
		(layer "In11.Cu")
		(net "M_J_DQS_DN<9>")
	)
	(segment
		(start 35.52444 -21.298408)
		(end 35.52444 -24.486362)
		(width 0.14224)
		(layer "In11.Cu")
		(net "M_J_DQS_DN<9>")
	)
	(arc
		(start 71.483982 -65.400936)
		(mid 71.771669 -65.483457)
		(end 71.982076 -65.696338)
		(width 0.0889)
		(layer "In11.Cu")
		(net "M_J_DQS_DN<9>")
	)
	(arc
		(start 68.547996 -64.705738)
		(mid 68.694168 -64.852073)
		(end 68.893944 -64.905636)
		(width 0.0889)
		(layer "In11.Cu")
		(net "M_J_DQS_DN<9>")
	)
	(arc
		(start 73.201022 -66.391536)
		(mid 73.488709 -66.474057)
		(end 73.699116 -66.686938)
		(width 0.0889)
		(layer "In11.Cu")
		(net "M_J_DQS_DN<9>")
	)
	(arc
		(start 70.265036 -64.705738)
		(mid 70.406719 -64.849542)
		(end 70.60057 -64.90589)
		(width 0.0889)
		(layer "In11.Cu")
		(net "M_J_DQS_DN<9>")
	)
	(arc
		(start 72.840596 -66.191638)
		(mid 72.979589 -66.333718)
		(end 73.16978 -66.391536)
		(width 0.0889)
		(layer "In11.Cu")
		(net "M_J_DQS_DN<9>")
	)
	(arc
		(start 74.48296 -66.567558)
		(mid 74.496843 -66.554122)
		(end 74.511154 -66.541142)
		(width 0.0889)
		(layer "In11.Cu")
		(net "M_J_DQS_DN<9>")
	)
	(arc
		(start 70.630034 -64.90589)
		(mid 70.915081 -64.989418)
		(end 71.123556 -65.201038)
		(width 0.0889)
		(layer "In11.Cu")
		(net "M_J_DQS_DN<9>")
	)
	(arc
		(start 74.04608 -66.88709)
		(mid 74.246066 -66.833476)
		(end 74.392282 -66.686938)
		(width 0.0889)
		(layer "In11.Cu")
		(net "M_J_DQS_DN<9>")
	)
	(arc
		(start 68.895468 -64.905636)
		(mid 69.095241 -64.852067)
		(end 69.241416 -64.705738)
		(width 0.0889)
		(layer "In11.Cu")
		(net "M_J_DQS_DN<9>")
	)
	(arc
		(start 71.123556 -65.201038)
		(mid 71.262549 -65.343118)
		(end 71.45274 -65.400936)
		(width 0.0889)
		(layer "In11.Cu")
		(net "M_J_DQS_DN<9>")
	)
	(arc
		(start 67.524376 -64.705738)
		(mid 67.740449 -64.48963)
		(end 68.035678 -64.41059)
		(width 0.0889)
		(layer "In11.Cu")
		(net "M_J_DQS_DN<9>")
	)
	(arc
		(start 73.699116 -66.686938)
		(mid 73.845498 -66.833502)
		(end 74.045572 -66.88709)
		(width 0.0889)
		(layer "In11.Cu")
		(net "M_J_DQS_DN<9>")
	)
	(arc
		(start 71.982076 -65.696338)
		(mid 72.122344 -65.839294)
		(end 72.314308 -65.89649)
		(width 0.0889)
		(layer "In11.Cu")
		(net "M_J_DQS_DN<9>")
	)
	(arc
		(start 69.753988 -64.41059)
		(mid 70.049126 -64.489601)
		(end 70.265036 -64.705738)
		(width 0.0889)
		(layer "In11.Cu")
		(net "M_J_DQS_DN<9>")
	)
	(arc
		(start 72.347074 -65.89649)
		(mid 72.632121 -65.980018)
		(end 72.840596 -66.191638)
		(width 0.0889)
		(layer "In11.Cu")
		(net "M_J_DQS_DN<9>")
	)
	(arc
		(start 68.036948 -64.41059)
		(mid 68.332086 -64.489601)
		(end 68.547996 -64.705738)
		(width 0.0889)
		(layer "In11.Cu")
		(net "M_J_DQS_DN<9>")
	)
	(arc
		(start 67.188842 -64.90589)
		(mid 67.382692 -64.84954)
		(end 67.524376 -64.705738)
		(width 0.0889)
		(layer "In11.Cu")
		(net "M_J_DQS_DN<9>")
	)
	(arc
		(start 69.241416 -64.705738)
		(mid 69.457489 -64.48963)
		(end 69.752718 -64.41059)
		(width 0.0889)
		(layer "In11.Cu")
		(net "M_J_DQS_DN<9>")
	)
	(arc
		(start 74.392282 -66.686938)
		(mid 74.433825 -66.624365)
		(end 74.48296 -66.567558)
		(width 0.0889)
		(layer "In11.Cu")
		(net "M_J_DQS_DN<9>")
	)
	(segment
		(start 80.626712 -69.953886)
		(end 80.055212 -69.953886)
		(width 0.0889)
		(layer "F.Cu")
		(net "M_J_DQS_DN<8>")
	)
	(segment
		(start 72.7837 1.190244)
		(end 73.437496 1.84404)
		(width 0.1651)
		(layer "F.Cu")
		(net "M_J_DQS_DN<8>")
	)
	(segment
		(start 73.049384 0.19177)
		(end 72.7837 0.457454)
		(width 0.1651)
		(layer "F.Cu")
		(net "M_J_DQS_DN<8>")
	)
	(segment
		(start 73.049384 -0.821182)
		(end 73.049384 0.19177)
		(width 0.1651)
		(layer "F.Cu")
		(net "M_J_DQS_DN<8>")
	)
	(segment
		(start 72.7837 0.457454)
		(end 72.7837 1.190244)
		(width 0.1651)
		(layer "F.Cu")
		(net "M_J_DQS_DN<8>")
	)
	(via
		(at 73.437496 -3.686556)
		(size 0.508)
		(drill 0.254)
		(layers "F.Cu" "B.Cu")
		(net "M_J_DQS_DN<8>")
	)
	(via
		(at 73.437496 1.84404)
		(size 0.508)
		(drill 0.254)
		(layers "F.Cu" "B.Cu")
		(net "M_J_DQS_DN<8>")
	)
	(via
		(at 80.055212 -69.953886)
		(size 0.508)
		(drill 0.254)
		(layers "F.Cu" "B.Cu")
		(net "M_J_DQS_DN<8>")
	)
	(segment
		(start 73.049384 -1.021842)
		(end 73.049384 -1.91897)
		(width 0.1651)
		(layer "B.Cu")
		(net "M_J_DQS_DN<8>")
	)
	(segment
		(start 72.7964 -2.171954)
		(end 72.7964 -3.04546)
		(width 0.1651)
		(layer "B.Cu")
		(net "M_J_DQS_DN<8>")
	)
	(segment
		(start 73.049384 -1.91897)
		(end 72.7964 -2.171954)
		(width 0.1651)
		(layer "B.Cu")
		(net "M_J_DQS_DN<8>")
	)
	(segment
		(start 72.7964 -3.04546)
		(end 73.437496 -3.686556)
		(width 0.1651)
		(layer "B.Cu")
		(net "M_J_DQS_DN<8>")
	)
	(segment
		(start 80.567022 -62.724538)
		(end 80.562196 -62.715902)
		(width 0.0889)
		(layer "In4.Cu")
		(net "M_J_DQS_DN<8>")
	)
	(segment
		(start 80.573372 -68.678806)
		(end 80.567022 -68.668138)
		(width 0.0889)
		(layer "In4.Cu")
		(net "M_J_DQS_DN<8>")
	)
	(segment
		(start 80.567022 -56.780938)
		(end 80.562196 -56.772302)
		(width 0.0889)
		(layer "In4.Cu")
		(net "M_J_DQS_DN<8>")
	)
	(segment
		(start 73.9013 -4.5466)
		(end 73.9013 -4.15036)
		(width 0.14224)
		(layer "In4.Cu")
		(net "M_J_DQS_DN<8>")
	)
	(segment
		(start 80.573372 -59.763406)
		(end 80.567022 -59.752738)
		(width 0.0889)
		(layer "In4.Cu")
		(net "M_J_DQS_DN<8>")
	)
	(segment
		(start 73.38822 -5.05968)
		(end 73.9013 -4.5466)
		(width 0.14224)
		(layer "In4.Cu")
		(net "M_J_DQS_DN<8>")
	)
	(segment
		(start 80.567022 -68.668138)
		(end 80.562196 -68.659502)
		(width 0.0889)
		(layer "In4.Cu")
		(net "M_J_DQS_DN<8>")
	)
	(segment
		(start 76.807568 -43.193208)
		(end 76.807568 -32.15386)
		(width 0.14224)
		(layer "In4.Cu")
		(net "M_J_DQS_DN<8>")
	)
	(segment
		(start 80.567022 -60.743338)
		(end 80.562196 -60.734702)
		(width 0.0889)
		(layer "In4.Cu")
		(net "M_J_DQS_DN<8>")
	)
	(segment
		(start 81.392014 -47.091346)
		(end 81.049368 -46.7487)
		(width 0.14224)
		(layer "In4.Cu")
		(net "M_J_DQS_DN<8>")
	)
	(segment
		(start 80.573372 -65.707006)
		(end 80.567022 -65.696338)
		(width 0.0889)
		(layer "In4.Cu")
		(net "M_J_DQS_DN<8>")
	)
	(segment
		(start 76.807568 -32.15386)
		(end 74.219816 -29.566108)
		(width 0.14224)
		(layer "In4.Cu")
		(net "M_J_DQS_DN<8>")
	)
	(segment
		(start 80.567022 -63.715138)
		(end 80.562196 -63.706502)
		(width 0.0889)
		(layer "In4.Cu")
		(net "M_J_DQS_DN<8>")
	)
	(segment
		(start 80.567022 -67.677538)
		(end 80.562196 -67.668902)
		(width 0.0889)
		(layer "In4.Cu")
		(net "M_J_DQS_DN<8>")
	)
	(segment
		(start 80.677512 -52.820316)
		(end 81.078832 -52.418996)
		(width 0.0889)
		(layer "In4.Cu")
		(net "M_J_DQS_DN<8>")
	)
	(segment
		(start 80.055212 -69.953886)
		(end 80.055212 -69.615812)
		(width 0.0889)
		(layer "In4.Cu")
		(net "M_J_DQS_DN<8>")
	)
	(segment
		(start 73.38822 -5.280152)
		(end 73.38822 -5.05968)
		(width 0.14224)
		(layer "In4.Cu")
		(net "M_J_DQS_DN<8>")
	)
	(segment
		(start 80.677512 -55.199026)
		(end 80.677512 -52.820316)
		(width 0.0889)
		(layer "In4.Cu")
		(net "M_J_DQS_DN<8>")
	)
	(segment
		(start 80.567022 -64.705738)
		(end 80.562196 -64.697102)
		(width 0.0889)
		(layer "In4.Cu")
		(net "M_J_DQS_DN<8>")
	)
	(segment
		(start 73.635616 -5.527548)
		(end 73.38822 -5.280152)
		(width 0.14224)
		(layer "In4.Cu")
		(net "M_J_DQS_DN<8>")
	)
	(segment
		(start 80.573372 -67.688206)
		(end 80.567022 -67.677538)
		(width 0.0889)
		(layer "In4.Cu")
		(net "M_J_DQS_DN<8>")
	)
	(segment
		(start 74.037952 -5.929884)
		(end 74.037952 -5.70738)
		(width 0.14224)
		(layer "In4.Cu")
		(net "M_J_DQS_DN<8>")
	)
	(segment
		(start 81.392014 -49.9618)
		(end 81.392014 -49.939702)
		(width 0.0889)
		(layer "In4.Cu")
		(net "M_J_DQS_DN<8>")
	)
	(segment
		(start 80.567022 -59.752738)
		(end 80.562196 -59.744102)
		(width 0.0889)
		(layer "In4.Cu")
		(net "M_J_DQS_DN<8>")
	)
	(segment
		(start 80.567022 -61.733938)
		(end 80.562196 -61.725302)
		(width 0.0889)
		(layer "In4.Cu")
		(net "M_J_DQS_DN<8>")
	)
	(segment
		(start 81.352644 -50.452274)
		(end 81.352644 -50.00117)
		(width 0.0889)
		(layer "In4.Cu")
		(net "M_J_DQS_DN<8>")
	)
	(segment
		(start 80.573372 -62.735206)
		(end 80.567022 -62.724538)
		(width 0.0889)
		(layer "In4.Cu")
		(net "M_J_DQS_DN<8>")
	)
	(segment
		(start 80.567022 -55.390542)
		(end 80.677512 -55.199026)
		(width 0.0889)
		(layer "In4.Cu")
		(net "M_J_DQS_DN<8>")
	)
	(segment
		(start 80.573372 -60.754006)
		(end 80.567022 -60.743338)
		(width 0.0889)
		(layer "In4.Cu")
		(net "M_J_DQS_DN<8>")
	)
	(segment
		(start 74.037952 -5.70738)
		(end 73.85812 -5.527548)
		(width 0.14224)
		(layer "In4.Cu")
		(net "M_J_DQS_DN<8>")
	)
	(segment
		(start 73.9013 -4.15036)
		(end 73.437496 -3.686556)
		(width 0.14224)
		(layer "In4.Cu")
		(net "M_J_DQS_DN<8>")
	)
	(segment
		(start 80.573372 -61.744606)
		(end 80.567022 -61.733938)
		(width 0.0889)
		(layer "In4.Cu")
		(net "M_J_DQS_DN<8>")
	)
	(segment
		(start 80.567022 -65.696338)
		(end 80.562196 -65.687702)
		(width 0.0889)
		(layer "In4.Cu")
		(net "M_J_DQS_DN<8>")
	)
	(segment
		(start 80.567022 -57.771538)
		(end 80.562196 -57.762902)
		(width 0.0889)
		(layer "In4.Cu")
		(net "M_J_DQS_DN<8>")
	)
	(segment
		(start 80.567022 -58.362088)
		(end 80.573372 -58.35142)
		(width 0.0889)
		(layer "In4.Cu")
		(net "M_J_DQS_DN<8>")
	)
	(segment
		(start 80.573372 -63.725806)
		(end 80.567022 -63.715138)
		(width 0.0889)
		(layer "In4.Cu")
		(net "M_J_DQS_DN<8>")
	)
	(segment
		(start 80.573372 -55.801006)
		(end 80.567022 -55.790338)
		(width 0.0889)
		(layer "In4.Cu")
		(net "M_J_DQS_DN<8>")
	)
	(segment
		(start 74.219816 -29.566108)
		(end 74.219816 -6.111748)
		(width 0.14224)
		(layer "In4.Cu")
		(net "M_J_DQS_DN<8>")
	)
	(segment
		(start 80.055212 -69.615812)
		(end 80.120236 -69.550788)
		(width 0.0889)
		(layer "In4.Cu")
		(net "M_J_DQS_DN<8>")
	)
	(segment
		(start 81.049368 -46.7487)
		(end 80.36306 -46.7487)
		(width 0.14224)
		(layer "In4.Cu")
		(net "M_J_DQS_DN<8>")
	)
	(segment
		(start 81.352644 -50.00117)
		(end 81.392014 -49.9618)
		(width 0.0889)
		(layer "In4.Cu")
		(net "M_J_DQS_DN<8>")
	)
	(segment
		(start 81.078832 -50.726086)
		(end 81.352644 -50.452274)
		(width 0.0889)
		(layer "In4.Cu")
		(net "M_J_DQS_DN<8>")
	)
	(segment
		(start 80.573372 -64.716406)
		(end 80.567022 -64.705738)
		(width 0.0889)
		(layer "In4.Cu")
		(net "M_J_DQS_DN<8>")
	)
	(segment
		(start 74.219816 -6.111748)
		(end 74.037952 -5.929884)
		(width 0.14224)
		(layer "In4.Cu")
		(net "M_J_DQS_DN<8>")
	)
	(segment
		(start 81.078832 -52.418996)
		(end 81.078832 -50.726086)
		(width 0.0889)
		(layer "In4.Cu")
		(net "M_J_DQS_DN<8>")
	)
	(segment
		(start 73.85812 -5.527548)
		(end 73.635616 -5.527548)
		(width 0.14224)
		(layer "In4.Cu")
		(net "M_J_DQS_DN<8>")
	)
	(segment
		(start 81.392014 -49.939702)
		(end 81.392014 -47.091346)
		(width 0.14224)
		(layer "In4.Cu")
		(net "M_J_DQS_DN<8>")
	)
	(segment
		(start 80.573372 -56.791606)
		(end 80.567022 -56.780938)
		(width 0.0889)
		(layer "In4.Cu")
		(net "M_J_DQS_DN<8>")
	)
	(segment
		(start 80.36306 -46.7487)
		(end 76.807568 -43.193208)
		(width 0.14224)
		(layer "In4.Cu")
		(net "M_J_DQS_DN<8>")
	)
	(arc
		(start 80.567022 -64.305688)
		(mid 80.646244 -64.01657)
		(end 80.573372 -63.725806)
		(width 0.0889)
		(layer "In4.Cu")
		(net "M_J_DQS_DN<8>")
	)
	(arc
		(start 80.562196 -61.725302)
		(mid 80.513441 -61.52895)
		(end 80.567022 -61.333888)
		(width 0.0889)
		(layer "In4.Cu")
		(net "M_J_DQS_DN<8>")
	)
	(arc
		(start 80.562196 -63.706502)
		(mid 80.513441 -63.51015)
		(end 80.567022 -63.315088)
		(width 0.0889)
		(layer "In4.Cu")
		(net "M_J_DQS_DN<8>")
	)
	(arc
		(start 80.562196 -65.687702)
		(mid 80.513441 -65.49135)
		(end 80.567022 -65.296288)
		(width 0.0889)
		(layer "In4.Cu")
		(net "M_J_DQS_DN<8>")
	)
	(arc
		(start 80.562196 -60.734702)
		(mid 80.513441 -60.53835)
		(end 80.567022 -60.343288)
		(width 0.0889)
		(layer "In4.Cu")
		(net "M_J_DQS_DN<8>")
	)
	(arc
		(start 80.567022 -65.296288)
		(mid 80.646244 -65.00717)
		(end 80.573372 -64.716406)
		(width 0.0889)
		(layer "In4.Cu")
		(net "M_J_DQS_DN<8>")
	)
	(arc
		(start 80.567022 -57.371488)
		(mid 80.646244 -57.08237)
		(end 80.573372 -56.791606)
		(width 0.0889)
		(layer "In4.Cu")
		(net "M_J_DQS_DN<8>")
	)
	(arc
		(start 80.120236 -69.550788)
		(mid 80.579713 -69.235839)
		(end 80.573372 -68.678806)
		(width 0.0889)
		(layer "In4.Cu")
		(net "M_J_DQS_DN<8>")
	)
	(arc
		(start 80.567022 -66.286888)
		(mid 80.646142 -65.99777)
		(end 80.573372 -65.707006)
		(width 0.0889)
		(layer "In4.Cu")
		(net "M_J_DQS_DN<8>")
	)
	(arc
		(start 80.567022 -55.790338)
		(mid 80.513523 -55.59044)
		(end 80.567022 -55.390542)
		(width 0.0889)
		(layer "In4.Cu")
		(net "M_J_DQS_DN<8>")
	)
	(arc
		(start 80.562196 -68.659502)
		(mid 80.513441 -68.46315)
		(end 80.567022 -68.268088)
		(width 0.0889)
		(layer "In4.Cu")
		(net "M_J_DQS_DN<8>")
	)
	(arc
		(start 80.562196 -57.762902)
		(mid 80.513441 -57.56655)
		(end 80.567022 -57.371488)
		(width 0.0889)
		(layer "In4.Cu")
		(net "M_J_DQS_DN<8>")
	)
	(arc
		(start 80.567022 -60.343288)
		(mid 80.646244 -60.05417)
		(end 80.573372 -59.763406)
		(width 0.0889)
		(layer "In4.Cu")
		(net "M_J_DQS_DN<8>")
	)
	(arc
		(start 80.567022 -62.324488)
		(mid 80.646244 -62.03537)
		(end 80.573372 -61.744606)
		(width 0.0889)
		(layer "In4.Cu")
		(net "M_J_DQS_DN<8>")
	)
	(arc
		(start 80.567022 -68.268088)
		(mid 80.646244 -67.97897)
		(end 80.573372 -67.688206)
		(width 0.0889)
		(layer "In4.Cu")
		(net "M_J_DQS_DN<8>")
	)
	(arc
		(start 80.567022 -56.380888)
		(mid 80.646244 -56.09177)
		(end 80.573372 -55.801006)
		(width 0.0889)
		(layer "In4.Cu")
		(net "M_J_DQS_DN<8>")
	)
	(arc
		(start 80.567022 -59.352688)
		(mid 80.646153 -59.057286)
		(end 80.567022 -58.761884)
		(width 0.0889)
		(layer "In4.Cu")
		(net "M_J_DQS_DN<8>")
	)
	(arc
		(start 80.562196 -56.772302)
		(mid 80.513441 -56.57595)
		(end 80.567022 -56.380888)
		(width 0.0889)
		(layer "In4.Cu")
		(net "M_J_DQS_DN<8>")
	)
	(arc
		(start 80.562196 -59.744102)
		(mid 80.513441 -59.54775)
		(end 80.567022 -59.352688)
		(width 0.0889)
		(layer "In4.Cu")
		(net "M_J_DQS_DN<8>")
	)
	(arc
		(start 80.562196 -67.668902)
		(mid 80.513441 -67.47255)
		(end 80.567022 -67.277488)
		(width 0.0889)
		(layer "In4.Cu")
		(net "M_J_DQS_DN<8>")
	)
	(arc
		(start 80.562196 -62.715902)
		(mid 80.513441 -62.51955)
		(end 80.567022 -62.324488)
		(width 0.0889)
		(layer "In4.Cu")
		(net "M_J_DQS_DN<8>")
	)
	(arc
		(start 80.567022 -66.686684)
		(mid 80.513523 -66.486786)
		(end 80.567022 -66.286888)
		(width 0.0889)
		(layer "In4.Cu")
		(net "M_J_DQS_DN<8>")
	)
	(arc
		(start 80.567022 -63.315088)
		(mid 80.646244 -63.02597)
		(end 80.573372 -62.735206)
		(width 0.0889)
		(layer "In4.Cu")
		(net "M_J_DQS_DN<8>")
	)
	(arc
		(start 80.567022 -67.277488)
		(mid 80.646153 -66.982086)
		(end 80.567022 -66.686684)
		(width 0.0889)
		(layer "In4.Cu")
		(net "M_J_DQS_DN<8>")
	)
	(arc
		(start 80.567022 -61.333888)
		(mid 80.646244 -61.04477)
		(end 80.573372 -60.754006)
		(width 0.0889)
		(layer "In4.Cu")
		(net "M_J_DQS_DN<8>")
	)
	(arc
		(start 80.567022 -58.761884)
		(mid 80.513523 -58.561986)
		(end 80.567022 -58.362088)
		(width 0.0889)
		(layer "In4.Cu")
		(net "M_J_DQS_DN<8>")
	)
	(arc
		(start 80.573372 -58.35142)
		(mid 80.64617 -58.060657)
		(end 80.567022 -57.771538)
		(width 0.0889)
		(layer "In4.Cu")
		(net "M_J_DQS_DN<8>")
	)
	(arc
		(start 80.562196 -64.697102)
		(mid 80.513441 -64.50075)
		(end 80.567022 -64.305688)
		(width 0.0889)
		(layer "In4.Cu")
		(net "M_J_DQS_DN<8>")
	)
	(segment
		(start 74.248264 1.033272)
		(end 74.248264 -2.875788)
		(width 0.14224)
		(layer "In11.Cu")
		(net "M_J_DQS_DN<8>")
	)
	(segment
		(start 73.437496 1.84404)
		(end 74.248264 1.033272)
		(width 0.14224)
		(layer "In11.Cu")
		(net "M_J_DQS_DN<8>")
	)
	(segment
		(start 74.248264 -2.875788)
		(end 73.437496 -3.686556)
		(width 0.14224)
		(layer "In11.Cu")
		(net "M_J_DQS_DN<8>")
	)
	(segment
		(start 146.999452 0.19177)
		(end 146.733768 0.457454)
		(width 0.1651)
		(layer "F.Cu")
		(net "M_J_DQS_DN<7>")
	)
	(segment
		(start 146.733768 0.457454)
		(end 146.733768 1.190244)
		(width 0.1651)
		(layer "F.Cu")
		(net "M_J_DQS_DN<7>")
	)
	(segment
		(start 146.733768 1.190244)
		(end 147.387564 1.84404)
		(width 0.1651)
		(layer "F.Cu")
		(net "M_J_DQS_DN<7>")
	)
	(segment
		(start 122.504708 -65.315338)
		(end 121.933208 -65.315338)
		(width 0.0889)
		(layer "F.Cu")
		(net "M_J_DQS_DN<7>")
	)
	(segment
		(start 146.999452 -0.821182)
		(end 146.999452 0.19177)
		(width 0.1651)
		(layer "F.Cu")
		(net "M_J_DQS_DN<7>")
	)
	(via
		(at 121.933208 -65.315338)
		(size 0.508)
		(drill 0.254)
		(layers "F.Cu" "B.Cu")
		(net "M_J_DQS_DN<7>")
	)
	(via
		(at 147.387564 -3.686556)
		(size 0.508)
		(drill 0.254)
		(layers "F.Cu" "B.Cu")
		(net "M_J_DQS_DN<7>")
	)
	(via
		(at 147.387564 1.84404)
		(size 0.508)
		(drill 0.254)
		(layers "F.Cu" "B.Cu")
		(net "M_J_DQS_DN<7>")
	)
	(segment
		(start 146.746468 -3.04546)
		(end 147.387564 -3.686556)
		(width 0.1651)
		(layer "B.Cu")
		(net "M_J_DQS_DN<7>")
	)
	(segment
		(start 146.746468 -2.171954)
		(end 146.746468 -3.04546)
		(width 0.1651)
		(layer "B.Cu")
		(net "M_J_DQS_DN<7>")
	)
	(segment
		(start 146.999452 -1.021842)
		(end 146.999452 -1.91897)
		(width 0.1651)
		(layer "B.Cu")
		(net "M_J_DQS_DN<7>")
	)
	(segment
		(start 146.999452 -1.91897)
		(end 146.746468 -2.171954)
		(width 0.1651)
		(layer "B.Cu")
		(net "M_J_DQS_DN<7>")
	)
	(segment
		(start 147.585684 -5.527548)
		(end 147.338288 -5.280152)
		(width 0.14224)
		(layer "In11.Cu")
		(net "M_J_DQS_DN<7>")
	)
	(segment
		(start 121.933208 -64.977264)
		(end 121.998486 -64.911986)
		(width 0.0889)
		(layer "In11.Cu")
		(net "M_J_DQS_DN<7>")
	)
	(segment
		(start 122.440192 -53.731922)
		(end 122.592338 -53.46827)
		(width 0.0889)
		(layer "In11.Cu")
		(net "M_J_DQS_DN<7>")
	)
	(segment
		(start 122.451368 -59.087004)
		(end 122.445018 -59.076336)
		(width 0.0889)
		(layer "In11.Cu")
		(net "M_J_DQS_DN<7>")
	)
	(segment
		(start 122.445018 -56.695086)
		(end 122.451368 -56.684418)
		(width 0.0889)
		(layer "In11.Cu")
		(net "M_J_DQS_DN<7>")
	)
	(segment
		(start 147.338288 -5.05968)
		(end 147.851368 -4.5466)
		(width 0.14224)
		(layer "In11.Cu")
		(net "M_J_DQS_DN<7>")
	)
	(segment
		(start 122.592338 -51.487324)
		(end 122.974862 -51.1048)
		(width 0.0889)
		(layer "In11.Cu")
		(net "M_J_DQS_DN<7>")
	)
	(segment
		(start 147.851368 -4.15036)
		(end 147.387564 -3.686556)
		(width 0.14224)
		(layer "In11.Cu")
		(net "M_J_DQS_DN<7>")
	)
	(segment
		(start 123.88342 -50.917348)
		(end 123.899168 -50.9016)
		(width 0.0889)
		(layer "In11.Cu")
		(net "M_J_DQS_DN<7>")
	)
	(segment
		(start 122.440192 -63.637922)
		(end 122.445018 -63.629286)
		(width 0.0889)
		(layer "In11.Cu")
		(net "M_J_DQS_DN<7>")
	)
	(segment
		(start 147.387564 -3.686556)
		(end 148.198332 -2.875788)
		(width 0.14224)
		(layer "In11.Cu")
		(net "M_J_DQS_DN<7>")
	)
	(segment
		(start 147.851368 -4.5466)
		(end 147.851368 -4.15036)
		(width 0.14224)
		(layer "In11.Cu")
		(net "M_J_DQS_DN<7>")
	)
	(segment
		(start 122.440192 -61.656722)
		(end 122.445018 -61.648086)
		(width 0.0889)
		(layer "In11.Cu")
		(net "M_J_DQS_DN<7>")
	)
	(segment
		(start 122.445018 -54.713886)
		(end 122.451368 -54.703218)
		(width 0.0889)
		(layer "In11.Cu")
		(net "M_J_DQS_DN<7>")
	)
	(segment
		(start 136.736328 -42.05224)
		(end 148.169884 -30.618684)
		(width 0.14224)
		(layer "In11.Cu")
		(net "M_J_DQS_DN<7>")
	)
	(segment
		(start 122.440192 -62.647322)
		(end 122.445018 -62.638686)
		(width 0.0889)
		(layer "In11.Cu")
		(net "M_J_DQS_DN<7>")
	)
	(segment
		(start 148.327364 -6.269228)
		(end 147.98802 -5.929884)
		(width 0.14224)
		(layer "In11.Cu")
		(net "M_J_DQS_DN<7>")
	)
	(segment
		(start 122.440192 -60.666122)
		(end 122.445018 -60.657486)
		(width 0.0889)
		(layer "In11.Cu")
		(net "M_J_DQS_DN<7>")
	)
	(segment
		(start 148.169884 -30.618684)
		(end 148.169884 -6.638036)
		(width 0.14224)
		(layer "In11.Cu")
		(net "M_J_DQS_DN<7>")
	)
	(segment
		(start 147.98802 -5.929884)
		(end 147.98802 -5.70738)
		(width 0.14224)
		(layer "In11.Cu")
		(net "M_J_DQS_DN<7>")
	)
	(segment
		(start 122.445018 -62.638686)
		(end 122.451368 -62.628018)
		(width 0.0889)
		(layer "In11.Cu")
		(net "M_J_DQS_DN<7>")
	)
	(segment
		(start 122.592338 -53.46827)
		(end 122.592338 -51.487324)
		(width 0.0889)
		(layer "In11.Cu")
		(net "M_J_DQS_DN<7>")
	)
	(segment
		(start 122.440192 -55.713122)
		(end 122.445018 -55.704486)
		(width 0.0889)
		(layer "In11.Cu")
		(net "M_J_DQS_DN<7>")
	)
	(segment
		(start 147.808188 -5.527548)
		(end 147.585684 -5.527548)
		(width 0.14224)
		(layer "In11.Cu")
		(net "M_J_DQS_DN<7>")
	)
	(segment
		(start 147.338288 -5.280152)
		(end 147.338288 -5.05968)
		(width 0.14224)
		(layer "In11.Cu")
		(net "M_J_DQS_DN<7>")
	)
	(segment
		(start 126.234698 -48.56607)
		(end 129.308098 -48.56607)
		(width 0.14224)
		(layer "In11.Cu")
		(net "M_J_DQS_DN<7>")
	)
	(segment
		(start 122.445018 -60.657486)
		(end 122.451368 -60.646818)
		(width 0.0889)
		(layer "In11.Cu")
		(net "M_J_DQS_DN<7>")
	)
	(segment
		(start 147.98802 -5.70738)
		(end 147.808188 -5.527548)
		(width 0.14224)
		(layer "In11.Cu")
		(net "M_J_DQS_DN<7>")
	)
	(segment
		(start 122.440192 -57.694322)
		(end 122.445018 -57.685686)
		(width 0.0889)
		(layer "In11.Cu")
		(net "M_J_DQS_DN<7>")
	)
	(segment
		(start 122.974862 -51.1048)
		(end 123.640596 -51.1048)
		(width 0.0889)
		(layer "In11.Cu")
		(net "M_J_DQS_DN<7>")
	)
	(segment
		(start 122.445018 -57.685686)
		(end 122.451368 -57.675018)
		(width 0.0889)
		(layer "In11.Cu")
		(net "M_J_DQS_DN<7>")
	)
	(segment
		(start 122.440192 -56.703722)
		(end 122.445018 -56.695086)
		(width 0.0889)
		(layer "In11.Cu")
		(net "M_J_DQS_DN<7>")
	)
	(segment
		(start 123.828048 -50.917348)
		(end 123.88342 -50.917348)
		(width 0.0889)
		(layer "In11.Cu")
		(net "M_J_DQS_DN<7>")
	)
	(segment
		(start 148.198332 1.033272)
		(end 147.387564 1.84404)
		(width 0.14224)
		(layer "In11.Cu")
		(net "M_J_DQS_DN<7>")
	)
	(segment
		(start 122.440192 -54.722522)
		(end 122.445018 -54.713886)
		(width 0.0889)
		(layer "In11.Cu")
		(net "M_J_DQS_DN<7>")
	)
	(segment
		(start 122.440192 -59.675522)
		(end 122.445018 -59.666886)
		(width 0.0889)
		(layer "In11.Cu")
		(net "M_J_DQS_DN<7>")
	)
	(segment
		(start 122.445018 -55.704486)
		(end 122.451368 -55.693818)
		(width 0.0889)
		(layer "In11.Cu")
		(net "M_J_DQS_DN<7>")
	)
	(segment
		(start 123.899168 -50.9016)
		(end 126.234698 -48.56607)
		(width 0.14224)
		(layer "In11.Cu")
		(net "M_J_DQS_DN<7>")
	)
	(segment
		(start 148.198332 -2.875788)
		(end 148.198332 1.033272)
		(width 0.14224)
		(layer "In11.Cu")
		(net "M_J_DQS_DN<7>")
	)
	(segment
		(start 135.821928 -42.05224)
		(end 136.736328 -42.05224)
		(width 0.14224)
		(layer "In11.Cu")
		(net "M_J_DQS_DN<7>")
	)
	(segment
		(start 121.933208 -65.315338)
		(end 121.933208 -64.977264)
		(width 0.0889)
		(layer "In11.Cu")
		(net "M_J_DQS_DN<7>")
	)
	(segment
		(start 122.445018 -63.629286)
		(end 122.451368 -63.618618)
		(width 0.0889)
		(layer "In11.Cu")
		(net "M_J_DQS_DN<7>")
	)
	(segment
		(start 129.308098 -48.56607)
		(end 135.821928 -42.05224)
		(width 0.14224)
		(layer "In11.Cu")
		(net "M_J_DQS_DN<7>")
	)
	(segment
		(start 123.640596 -51.1048)
		(end 123.828048 -50.917348)
		(width 0.0889)
		(layer "In11.Cu")
		(net "M_J_DQS_DN<7>")
	)
	(segment
		(start 148.327364 -6.480556)
		(end 148.327364 -6.269228)
		(width 0.14224)
		(layer "In11.Cu")
		(net "M_J_DQS_DN<7>")
	)
	(segment
		(start 148.169884 -6.638036)
		(end 148.327364 -6.480556)
		(width 0.14224)
		(layer "In11.Cu")
		(net "M_J_DQS_DN<7>")
	)
	(segment
		(start 122.445018 -61.648086)
		(end 122.451368 -61.637418)
		(width 0.0889)
		(layer "In11.Cu")
		(net "M_J_DQS_DN<7>")
	)
	(arc
		(start 122.445018 -62.048136)
		(mid 122.391548 -61.853073)
		(end 122.440192 -61.656722)
		(width 0.0889)
		(layer "In11.Cu")
		(net "M_J_DQS_DN<7>")
	)
	(arc
		(start 121.998486 -64.911986)
		(mid 122.460455 -64.591444)
		(end 122.445018 -64.029336)
		(width 0.0889)
		(layer "In11.Cu")
		(net "M_J_DQS_DN<7>")
	)
	(arc
		(start 122.445018 -61.057536)
		(mid 122.391548 -60.862473)
		(end 122.440192 -60.666122)
		(width 0.0889)
		(layer "In11.Cu")
		(net "M_J_DQS_DN<7>")
	)
	(arc
		(start 122.445018 -59.666886)
		(mid 122.52424 -59.377768)
		(end 122.451368 -59.087004)
		(width 0.0889)
		(layer "In11.Cu")
		(net "M_J_DQS_DN<7>")
	)
	(arc
		(start 122.445018 -56.104536)
		(mid 122.391548 -55.909473)
		(end 122.440192 -55.713122)
		(width 0.0889)
		(layer "In11.Cu")
		(net "M_J_DQS_DN<7>")
	)
	(arc
		(start 122.445018 -59.076336)
		(mid 122.391519 -58.876438)
		(end 122.445018 -58.67654)
		(width 0.0889)
		(layer "In11.Cu")
		(net "M_J_DQS_DN<7>")
	)
	(arc
		(start 122.451368 -55.693818)
		(mid 122.524166 -55.403055)
		(end 122.445018 -55.113936)
		(width 0.0889)
		(layer "In11.Cu")
		(net "M_J_DQS_DN<7>")
	)
	(arc
		(start 122.451368 -56.684418)
		(mid 122.524166 -56.393655)
		(end 122.445018 -56.104536)
		(width 0.0889)
		(layer "In11.Cu")
		(net "M_J_DQS_DN<7>")
	)
	(arc
		(start 122.445018 -54.123336)
		(mid 122.391548 -53.928273)
		(end 122.440192 -53.731922)
		(width 0.0889)
		(layer "In11.Cu")
		(net "M_J_DQS_DN<7>")
	)
	(arc
		(start 122.445018 -63.038736)
		(mid 122.391548 -62.843673)
		(end 122.440192 -62.647322)
		(width 0.0889)
		(layer "In11.Cu")
		(net "M_J_DQS_DN<7>")
	)
	(arc
		(start 122.451368 -54.703218)
		(mid 122.524166 -54.412455)
		(end 122.445018 -54.123336)
		(width 0.0889)
		(layer "In11.Cu")
		(net "M_J_DQS_DN<7>")
	)
	(arc
		(start 122.445018 -55.113936)
		(mid 122.391548 -54.918873)
		(end 122.440192 -54.722522)
		(width 0.0889)
		(layer "In11.Cu")
		(net "M_J_DQS_DN<7>")
	)
	(arc
		(start 122.451368 -57.675018)
		(mid 122.524166 -57.384255)
		(end 122.445018 -57.095136)
		(width 0.0889)
		(layer "In11.Cu")
		(net "M_J_DQS_DN<7>")
	)
	(arc
		(start 122.445018 -60.066936)
		(mid 122.391548 -59.871873)
		(end 122.440192 -59.675522)
		(width 0.0889)
		(layer "In11.Cu")
		(net "M_J_DQS_DN<7>")
	)
	(arc
		(start 122.451368 -63.618618)
		(mid 122.524166 -63.327855)
		(end 122.445018 -63.038736)
		(width 0.0889)
		(layer "In11.Cu")
		(net "M_J_DQS_DN<7>")
	)
	(arc
		(start 122.445018 -57.095136)
		(mid 122.391548 -56.900073)
		(end 122.440192 -56.703722)
		(width 0.0889)
		(layer "In11.Cu")
		(net "M_J_DQS_DN<7>")
	)
	(arc
		(start 122.445018 -58.67654)
		(mid 122.524149 -58.381138)
		(end 122.445018 -58.085736)
		(width 0.0889)
		(layer "In11.Cu")
		(net "M_J_DQS_DN<7>")
	)
	(arc
		(start 122.445018 -64.029336)
		(mid 122.391548 -63.834273)
		(end 122.440192 -63.637922)
		(width 0.0889)
		(layer "In11.Cu")
		(net "M_J_DQS_DN<7>")
	)
	(arc
		(start 122.451368 -60.646818)
		(mid 122.524166 -60.356055)
		(end 122.445018 -60.066936)
		(width 0.0889)
		(layer "In11.Cu")
		(net "M_J_DQS_DN<7>")
	)
	(arc
		(start 122.445018 -58.085736)
		(mid 122.391548 -57.890673)
		(end 122.440192 -57.694322)
		(width 0.0889)
		(layer "In11.Cu")
		(net "M_J_DQS_DN<7>")
	)
	(arc
		(start 122.451368 -61.637418)
		(mid 122.524166 -61.346655)
		(end 122.445018 -61.057536)
		(width 0.0889)
		(layer "In11.Cu")
		(net "M_J_DQS_DN<7>")
	)
	(arc
		(start 122.451368 -62.628018)
		(mid 122.524166 -62.337255)
		(end 122.445018 -62.048136)
		(width 0.0889)
		(layer "In11.Cu")
		(net "M_J_DQS_DN<7>")
	)
	(segment
		(start 137.383774 0.457454)
		(end 137.383774 1.190244)
		(width 0.1651)
		(layer "F.Cu")
		(net "M_J_DQS_DN<6>")
	)
	(segment
		(start 137.383774 1.190244)
		(end 138.03757 1.84404)
		(width 0.1651)
		(layer "F.Cu")
		(net "M_J_DQS_DN<6>")
	)
	(segment
		(start 116.782342 -65.315338)
		(end 117.353842 -65.315338)
		(width 0.0889)
		(layer "F.Cu")
		(net "M_J_DQS_DN<6>")
	)
	(segment
		(start 137.649458 0.19177)
		(end 137.383774 0.457454)
		(width 0.1651)
		(layer "F.Cu")
		(net "M_J_DQS_DN<6>")
	)
	(segment
		(start 137.649458 -0.821182)
		(end 137.649458 0.19177)
		(width 0.1651)
		(layer "F.Cu")
		(net "M_J_DQS_DN<6>")
	)
	(via
		(at 116.782342 -65.315338)
		(size 0.508)
		(drill 0.254)
		(layers "F.Cu" "B.Cu")
		(net "M_J_DQS_DN<6>")
	)
	(via
		(at 138.03757 1.84404)
		(size 0.508)
		(drill 0.254)
		(layers "F.Cu" "B.Cu")
		(net "M_J_DQS_DN<6>")
	)
	(via
		(at 138.03757 -3.686556)
		(size 0.508)
		(drill 0.254)
		(layers "F.Cu" "B.Cu")
		(net "M_J_DQS_DN<6>")
	)
	(segment
		(start 137.649458 -1.021842)
		(end 137.649458 -1.91897)
		(width 0.1651)
		(layer "B.Cu")
		(net "M_J_DQS_DN<6>")
	)
	(segment
		(start 137.649458 -1.91897)
		(end 137.396474 -2.171954)
		(width 0.1651)
		(layer "B.Cu")
		(net "M_J_DQS_DN<6>")
	)
	(segment
		(start 137.396474 -2.171954)
		(end 137.396474 -3.04546)
		(width 0.1651)
		(layer "B.Cu")
		(net "M_J_DQS_DN<6>")
	)
	(segment
		(start 137.396474 -3.04546)
		(end 138.03757 -3.686556)
		(width 0.1651)
		(layer "B.Cu")
		(net "M_J_DQS_DN<6>")
	)
	(segment
		(start 138.521948 -5.670042)
		(end 138.299444 -5.670042)
		(width 0.14224)
		(layer "In11.Cu")
		(net "M_J_DQS_DN<6>")
	)
	(segment
		(start 116.782342 -64.977264)
		(end 116.84762 -64.911986)
		(width 0.0889)
		(layer "In11.Cu")
		(net "M_J_DQS_DN<6>")
	)
	(segment
		(start 138.854688 -8.03148)
		(end 138.986768 -7.8994)
		(width 0.14224)
		(layer "In11.Cu")
		(net "M_J_DQS_DN<6>")
	)
	(segment
		(start 138.352022 -4.826)
		(end 138.501374 -4.676648)
		(width 0.14224)
		(layer "In11.Cu")
		(net "M_J_DQS_DN<6>")
	)
	(segment
		(start 117.294152 -55.113936)
		(end 117.293898 -55.113682)
		(width 0.0889)
		(layer "In11.Cu")
		(net "M_J_DQS_DN<6>")
	)
	(segment
		(start 117.294152 -61.648086)
		(end 117.300502 -61.637418)
		(width 0.0889)
		(layer "In11.Cu")
		(net "M_J_DQS_DN<6>")
	)
	(segment
		(start 117.289326 -57.694322)
		(end 117.294152 -57.685686)
		(width 0.0889)
		(layer "In11.Cu")
		(net "M_J_DQS_DN<6>")
	)
	(segment
		(start 121.442226 -43.29938)
		(end 121.442226 -39.46906)
		(width 0.14224)
		(layer "In11.Cu")
		(net "M_J_DQS_DN<6>")
	)
	(segment
		(start 117.289326 -62.647322)
		(end 117.294152 -62.638686)
		(width 0.0889)
		(layer "In11.Cu")
		(net "M_J_DQS_DN<6>")
	)
	(segment
		(start 118.024656 -47.28337)
		(end 118.064026 -47.244)
		(width 0.0889)
		(layer "In11.Cu")
		(net "M_J_DQS_DN<6>")
	)
	(segment
		(start 117.145816 -51.042316)
		(end 117.145816 -50.862484)
		(width 0.0889)
		(layer "In11.Cu")
		(net "M_J_DQS_DN<6>")
	)
	(segment
		(start 116.782342 -65.315338)
		(end 116.782342 -64.977264)
		(width 0.0889)
		(layer "In11.Cu")
		(net "M_J_DQS_DN<6>")
	)
	(segment
		(start 118.064026 -47.221902)
		(end 118.064026 -46.67758)
		(width 0.14224)
		(layer "In11.Cu")
		(net "M_J_DQS_DN<6>")
	)
	(segment
		(start 138.299444 -5.670042)
		(end 137.861294 -5.231892)
		(width 0.14224)
		(layer "In11.Cu")
		(net "M_J_DQS_DN<6>")
	)
	(segment
		(start 117.294152 -57.685686)
		(end 117.300502 -57.675018)
		(width 0.0889)
		(layer "In11.Cu")
		(net "M_J_DQS_DN<6>")
	)
	(segment
		(start 117.300502 -59.087004)
		(end 117.294152 -59.076336)
		(width 0.0889)
		(layer "In11.Cu")
		(net "M_J_DQS_DN<6>")
	)
	(segment
		(start 117.294152 -60.657486)
		(end 117.300502 -60.646818)
		(width 0.0889)
		(layer "In11.Cu")
		(net "M_J_DQS_DN<6>")
	)
	(segment
		(start 117.281706 -54.005734)
		(end 117.281706 -51.178206)
		(width 0.0889)
		(layer "In11.Cu")
		(net "M_J_DQS_DN<6>")
	)
	(segment
		(start 117.294152 -63.629286)
		(end 117.300502 -63.618618)
		(width 0.0889)
		(layer "In11.Cu")
		(net "M_J_DQS_DN<6>")
	)
	(segment
		(start 138.701526 -5.84962)
		(end 138.521948 -5.670042)
		(width 0.14224)
		(layer "In11.Cu")
		(net "M_J_DQS_DN<6>")
	)
	(segment
		(start 138.501374 -4.676648)
		(end 138.501374 -4.15036)
		(width 0.14224)
		(layer "In11.Cu")
		(net "M_J_DQS_DN<6>")
	)
	(segment
		(start 138.986768 -7.8994)
		(end 138.986768 -7.5946)
		(width 0.14224)
		(layer "In11.Cu")
		(net "M_J_DQS_DN<6>")
	)
	(segment
		(start 138.848338 -2.875788)
		(end 138.848338 1.033272)
		(width 0.14224)
		(layer "In11.Cu")
		(net "M_J_DQS_DN<6>")
	)
	(segment
		(start 116.953792 -49.36236)
		(end 118.024656 -48.291496)
		(width 0.0889)
		(layer "In11.Cu")
		(net "M_J_DQS_DN<6>")
	)
	(segment
		(start 124.721366 -36.18992)
		(end 132.228082 -36.18992)
		(width 0.14224)
		(layer "In11.Cu")
		(net "M_J_DQS_DN<6>")
	)
	(segment
		(start 138.501374 -4.15036)
		(end 138.03757 -3.686556)
		(width 0.14224)
		(layer "In11.Cu")
		(net "M_J_DQS_DN<6>")
	)
	(segment
		(start 121.442226 -39.46906)
		(end 124.721366 -36.18992)
		(width 0.14224)
		(layer "In11.Cu")
		(net "M_J_DQS_DN<6>")
	)
	(segment
		(start 117.405404 -54.5211)
		(end 117.405404 -54.129432)
		(width 0.0889)
		(layer "In11.Cu")
		(net "M_J_DQS_DN<6>")
	)
	(segment
		(start 118.064026 -47.244)
		(end 118.064026 -47.221902)
		(width 0.0889)
		(layer "In11.Cu")
		(net "M_J_DQS_DN<6>")
	)
	(segment
		(start 116.953792 -50.478436)
		(end 116.953792 -49.36236)
		(width 0.0889)
		(layer "In11.Cu")
		(net "M_J_DQS_DN<6>")
	)
	(segment
		(start 132.228082 -36.18992)
		(end 138.854688 -29.563314)
		(width 0.14224)
		(layer "In11.Cu")
		(net "M_J_DQS_DN<6>")
	)
	(segment
		(start 117.294152 -56.695086)
		(end 117.300502 -56.684418)
		(width 0.0889)
		(layer "In11.Cu")
		(net "M_J_DQS_DN<6>")
	)
	(segment
		(start 137.861294 -5.231892)
		(end 137.861294 -4.953254)
		(width 0.14224)
		(layer "In11.Cu")
		(net "M_J_DQS_DN<6>")
	)
	(segment
		(start 117.294152 -55.704486)
		(end 117.300502 -55.693818)
		(width 0.0889)
		(layer "In11.Cu")
		(net "M_J_DQS_DN<6>")
	)
	(segment
		(start 138.986768 -7.5946)
		(end 138.854688 -7.46252)
		(width 0.14224)
		(layer "In11.Cu")
		(net "M_J_DQS_DN<6>")
	)
	(segment
		(start 138.854688 -7.46252)
		(end 138.854688 -6.225286)
		(width 0.14224)
		(layer "In11.Cu")
		(net "M_J_DQS_DN<6>")
	)
	(segment
		(start 117.289326 -61.656722)
		(end 117.294152 -61.648086)
		(width 0.0889)
		(layer "In11.Cu")
		(net "M_J_DQS_DN<6>")
	)
	(segment
		(start 117.289326 -63.637922)
		(end 117.294152 -63.629286)
		(width 0.0889)
		(layer "In11.Cu")
		(net "M_J_DQS_DN<6>")
	)
	(segment
		(start 117.294152 -62.638686)
		(end 117.300502 -62.628018)
		(width 0.0889)
		(layer "In11.Cu")
		(net "M_J_DQS_DN<6>")
	)
	(segment
		(start 117.289326 -56.703722)
		(end 117.294152 -56.695086)
		(width 0.0889)
		(layer "In11.Cu")
		(net "M_J_DQS_DN<6>")
	)
	(segment
		(start 138.854688 -29.563314)
		(end 138.854688 -8.03148)
		(width 0.14224)
		(layer "In11.Cu")
		(net "M_J_DQS_DN<6>")
	)
	(segment
		(start 117.289326 -60.666122)
		(end 117.294152 -60.657486)
		(width 0.0889)
		(layer "In11.Cu")
		(net "M_J_DQS_DN<6>")
	)
	(segment
		(start 117.405404 -54.129432)
		(end 117.281706 -54.005734)
		(width 0.0889)
		(layer "In11.Cu")
		(net "M_J_DQS_DN<6>")
	)
	(segment
		(start 138.701526 -6.072124)
		(end 138.701526 -5.84962)
		(width 0.14224)
		(layer "In11.Cu")
		(net "M_J_DQS_DN<6>")
	)
	(segment
		(start 117.145816 -50.862484)
		(end 116.953792 -50.478436)
		(width 0.0889)
		(layer "In11.Cu")
		(net "M_J_DQS_DN<6>")
	)
	(segment
		(start 118.064026 -46.67758)
		(end 121.442226 -43.29938)
		(width 0.14224)
		(layer "In11.Cu")
		(net "M_J_DQS_DN<6>")
	)
	(segment
		(start 117.281706 -51.178206)
		(end 117.145816 -51.042316)
		(width 0.0889)
		(layer "In11.Cu")
		(net "M_J_DQS_DN<6>")
	)
	(segment
		(start 117.289326 -59.675522)
		(end 117.294152 -59.666886)
		(width 0.0889)
		(layer "In11.Cu")
		(net "M_J_DQS_DN<6>")
	)
	(segment
		(start 117.289326 -55.713122)
		(end 117.294152 -55.704486)
		(width 0.0889)
		(layer "In11.Cu")
		(net "M_J_DQS_DN<6>")
	)
	(segment
		(start 138.854688 -6.225286)
		(end 138.701526 -6.072124)
		(width 0.14224)
		(layer "In11.Cu")
		(net "M_J_DQS_DN<6>")
	)
	(segment
		(start 137.861294 -4.953254)
		(end 137.988548 -4.826)
		(width 0.14224)
		(layer "In11.Cu")
		(net "M_J_DQS_DN<6>")
	)
	(segment
		(start 117.289072 -54.722776)
		(end 117.405404 -54.5211)
		(width 0.0889)
		(layer "In11.Cu")
		(net "M_J_DQS_DN<6>")
	)
	(segment
		(start 138.03757 -3.686556)
		(end 138.848338 -2.875788)
		(width 0.14224)
		(layer "In11.Cu")
		(net "M_J_DQS_DN<6>")
	)
	(segment
		(start 118.024656 -48.291496)
		(end 118.024656 -47.28337)
		(width 0.0889)
		(layer "In11.Cu")
		(net "M_J_DQS_DN<6>")
	)
	(segment
		(start 138.848338 1.033272)
		(end 138.03757 1.84404)
		(width 0.14224)
		(layer "In11.Cu")
		(net "M_J_DQS_DN<6>")
	)
	(segment
		(start 137.988548 -4.826)
		(end 138.352022 -4.826)
		(width 0.14224)
		(layer "In11.Cu")
		(net "M_J_DQS_DN<6>")
	)
	(arc
		(start 117.294152 -61.057536)
		(mid 117.240682 -60.862473)
		(end 117.289326 -60.666122)
		(width 0.0889)
		(layer "In11.Cu")
		(net "M_J_DQS_DN<6>")
	)
	(arc
		(start 117.300502 -57.675018)
		(mid 117.3733 -57.384255)
		(end 117.294152 -57.095136)
		(width 0.0889)
		(layer "In11.Cu")
		(net "M_J_DQS_DN<6>")
	)
	(arc
		(start 117.294152 -58.67654)
		(mid 117.373283 -58.381138)
		(end 117.294152 -58.085736)
		(width 0.0889)
		(layer "In11.Cu")
		(net "M_J_DQS_DN<6>")
	)
	(arc
		(start 117.300502 -61.637418)
		(mid 117.3733 -61.346655)
		(end 117.294152 -61.057536)
		(width 0.0889)
		(layer "In11.Cu")
		(net "M_J_DQS_DN<6>")
	)
	(arc
		(start 116.84762 -64.911986)
		(mid 117.309589 -64.591444)
		(end 117.294152 -64.029336)
		(width 0.0889)
		(layer "In11.Cu")
		(net "M_J_DQS_DN<6>")
	)
	(arc
		(start 117.294152 -62.048136)
		(mid 117.240682 -61.853073)
		(end 117.289326 -61.656722)
		(width 0.0889)
		(layer "In11.Cu")
		(net "M_J_DQS_DN<6>")
	)
	(arc
		(start 117.300502 -56.684418)
		(mid 117.3733 -56.393655)
		(end 117.294152 -56.104536)
		(width 0.0889)
		(layer "In11.Cu")
		(net "M_J_DQS_DN<6>")
	)
	(arc
		(start 117.294152 -57.095136)
		(mid 117.240682 -56.900073)
		(end 117.289326 -56.703722)
		(width 0.0889)
		(layer "In11.Cu")
		(net "M_J_DQS_DN<6>")
	)
	(arc
		(start 117.294152 -59.666886)
		(mid 117.373374 -59.377768)
		(end 117.300502 -59.087004)
		(width 0.0889)
		(layer "In11.Cu")
		(net "M_J_DQS_DN<6>")
	)
	(arc
		(start 117.294152 -60.066936)
		(mid 117.240682 -59.871873)
		(end 117.289326 -59.675522)
		(width 0.0889)
		(layer "In11.Cu")
		(net "M_J_DQS_DN<6>")
	)
	(arc
		(start 117.294152 -56.104536)
		(mid 117.240682 -55.909473)
		(end 117.289326 -55.713122)
		(width 0.0889)
		(layer "In11.Cu")
		(net "M_J_DQS_DN<6>")
	)
	(arc
		(start 117.300502 -63.618618)
		(mid 117.3733 -63.327855)
		(end 117.294152 -63.038736)
		(width 0.0889)
		(layer "In11.Cu")
		(net "M_J_DQS_DN<6>")
	)
	(arc
		(start 117.300502 -55.693818)
		(mid 117.3733 -55.403055)
		(end 117.294152 -55.113936)
		(width 0.0889)
		(layer "In11.Cu")
		(net "M_J_DQS_DN<6>")
	)
	(arc
		(start 117.300502 -62.628018)
		(mid 117.3733 -62.337255)
		(end 117.294152 -62.048136)
		(width 0.0889)
		(layer "In11.Cu")
		(net "M_J_DQS_DN<6>")
	)
	(arc
		(start 117.294152 -58.085736)
		(mid 117.240682 -57.890673)
		(end 117.289326 -57.694322)
		(width 0.0889)
		(layer "In11.Cu")
		(net "M_J_DQS_DN<6>")
	)
	(arc
		(start 117.300502 -60.646818)
		(mid 117.3733 -60.356055)
		(end 117.294152 -60.066936)
		(width 0.0889)
		(layer "In11.Cu")
		(net "M_J_DQS_DN<6>")
	)
	(arc
		(start 117.293898 -55.113682)
		(mid 117.240589 -54.918873)
		(end 117.289072 -54.722776)
		(width 0.0889)
		(layer "In11.Cu")
		(net "M_J_DQS_DN<6>")
	)
	(arc
		(start 117.294152 -63.038736)
		(mid 117.240682 -62.843673)
		(end 117.289326 -62.647322)
		(width 0.0889)
		(layer "In11.Cu")
		(net "M_J_DQS_DN<6>")
	)
	(arc
		(start 117.294152 -59.076336)
		(mid 117.240653 -58.876438)
		(end 117.294152 -58.67654)
		(width 0.0889)
		(layer "In11.Cu")
		(net "M_J_DQS_DN<6>")
	)
	(arc
		(start 117.294152 -64.029336)
		(mid 117.240682 -63.834273)
		(end 117.289326 -63.637922)
		(width 0.0889)
		(layer "In11.Cu")
		(net "M_J_DQS_DN<6>")
	)
	(segment
		(start 128.03378 1.190244)
		(end 128.687576 1.84404)
		(width 0.1651)
		(layer "F.Cu")
		(net "M_J_DQS_DN<5>")
	)
	(segment
		(start 114.778282 -61.847984)
		(end 114.206782 -61.847984)
		(width 0.0889)
		(layer "F.Cu")
		(net "M_J_DQS_DN<5>")
	)
	(segment
		(start 128.299464 0.19177)
		(end 128.03378 0.457454)
		(width 0.1651)
		(layer "F.Cu")
		(net "M_J_DQS_DN<5>")
	)
	(segment
		(start 128.03378 0.457454)
		(end 128.03378 1.190244)
		(width 0.1651)
		(layer "F.Cu")
		(net "M_J_DQS_DN<5>")
	)
	(segment
		(start 128.299464 -0.821182)
		(end 128.299464 0.19177)
		(width 0.1651)
		(layer "F.Cu")
		(net "M_J_DQS_DN<5>")
	)
	(via
		(at 114.206782 -61.847984)
		(size 0.508)
		(drill 0.254)
		(layers "F.Cu" "B.Cu")
		(net "M_J_DQS_DN<5>")
	)
	(via
		(at 128.687576 -3.686556)
		(size 0.508)
		(drill 0.254)
		(layers "F.Cu" "B.Cu")
		(net "M_J_DQS_DN<5>")
	)
	(via
		(at 128.687576 1.84404)
		(size 0.508)
		(drill 0.254)
		(layers "F.Cu" "B.Cu")
		(net "M_J_DQS_DN<5>")
	)
	(segment
		(start 128.04648 -2.171954)
		(end 128.04648 -3.04546)
		(width 0.1651)
		(layer "B.Cu")
		(net "M_J_DQS_DN<5>")
	)
	(segment
		(start 128.04648 -3.04546)
		(end 128.687576 -3.686556)
		(width 0.1651)
		(layer "B.Cu")
		(net "M_J_DQS_DN<5>")
	)
	(segment
		(start 128.299464 -1.91897)
		(end 128.04648 -2.171954)
		(width 0.1651)
		(layer "B.Cu")
		(net "M_J_DQS_DN<5>")
	)
	(segment
		(start 128.299464 -1.021842)
		(end 128.299464 -1.91897)
		(width 0.1651)
		(layer "B.Cu")
		(net "M_J_DQS_DN<5>")
	)
	(segment
		(start 129.511806 -28.939236)
		(end 129.304288 -29.146754)
		(width 0.14224)
		(layer "In4.Cu")
		(net "M_J_DQS_DN<5>")
	)
	(segment
		(start 116.063268 -51.45532)
		(end 115.12296 -52.395628)
		(width 0.0889)
		(layer "In4.Cu")
		(net "M_J_DQS_DN<5>")
	)
	(segment
		(start 114.713766 -55.6006)
		(end 114.718592 -55.609236)
		(width 0.0889)
		(layer "In4.Cu")
		(net "M_J_DQS_DN<5>")
	)
	(segment
		(start 114.718592 -61.152786)
		(end 114.652298 -61.26734)
		(width 0.0889)
		(layer "In4.Cu")
		(net "M_J_DQS_DN<5>")
	)
	(segment
		(start 129.511806 -9.41832)
		(end 129.669286 -9.5758)
		(width 0.14224)
		(layer "In4.Cu")
		(net "M_J_DQS_DN<5>")
	)
	(segment
		(start 114.797332 -53.475636)
		(end 114.797332 -53.906928)
		(width 0.0889)
		(layer "In4.Cu")
		(net "M_J_DQS_DN<5>")
	)
	(segment
		(start 114.718592 -55.609236)
		(end 114.724942 -55.619904)
		(width 0.0889)
		(layer "In4.Cu")
		(net "M_J_DQS_DN<5>")
	)
	(segment
		(start 118.050056 -47.297594)
		(end 118.010686 -47.336964)
		(width 0.0889)
		(layer "In4.Cu")
		(net "M_J_DQS_DN<5>")
	)
	(segment
		(start 114.713766 -54.61)
		(end 114.718592 -54.618636)
		(width 0.0889)
		(layer "In4.Cu")
		(net "M_J_DQS_DN<5>")
	)
	(segment
		(start 114.797332 -53.906928)
		(end 114.797586 -53.907182)
		(width 0.0889)
		(layer "In4.Cu")
		(net "M_J_DQS_DN<5>")
	)
	(segment
		(start 115.12296 -53.150008)
		(end 114.797332 -53.475636)
		(width 0.0889)
		(layer "In4.Cu")
		(net "M_J_DQS_DN<5>")
	)
	(segment
		(start 128.6383 -5.280152)
		(end 128.885696 -5.527548)
		(width 0.14224)
		(layer "In4.Cu")
		(net "M_J_DQS_DN<5>")
	)
	(segment
		(start 129.15138 -4.5466)
		(end 128.6383 -5.05968)
		(width 0.14224)
		(layer "In4.Cu")
		(net "M_J_DQS_DN<5>")
	)
	(segment
		(start 129.304288 -31.331408)
		(end 118.050056 -42.58564)
		(width 0.14224)
		(layer "In4.Cu")
		(net "M_J_DQS_DN<5>")
	)
	(segment
		(start 114.718592 -60.562236)
		(end 114.724942 -60.572904)
		(width 0.0889)
		(layer "In4.Cu")
		(net "M_J_DQS_DN<5>")
	)
	(segment
		(start 118.050056 -47.275496)
		(end 118.050056 -47.297594)
		(width 0.0889)
		(layer "In4.Cu")
		(net "M_J_DQS_DN<5>")
	)
	(segment
		(start 129.304288 -29.146754)
		(end 129.304288 -31.331408)
		(width 0.14224)
		(layer "In4.Cu")
		(net "M_J_DQS_DN<5>")
	)
	(segment
		(start 129.669286 -9.8298)
		(end 129.511806 -9.98728)
		(width 0.14224)
		(layer "In4.Cu")
		(net "M_J_DQS_DN<5>")
	)
	(segment
		(start 129.511806 -6.153658)
		(end 129.511806 -9.41832)
		(width 0.14224)
		(layer "In4.Cu")
		(net "M_J_DQS_DN<5>")
	)
	(segment
		(start 118.010686 -48.796702)
		(end 116.063268 -50.74412)
		(width 0.0889)
		(layer "In4.Cu")
		(net "M_J_DQS_DN<5>")
	)
	(segment
		(start 114.713766 -56.5912)
		(end 114.718592 -56.599836)
		(width 0.0889)
		(layer "In4.Cu")
		(net "M_J_DQS_DN<5>")
	)
	(segment
		(start 114.718592 -56.599836)
		(end 114.724942 -56.610504)
		(width 0.0889)
		(layer "In4.Cu")
		(net "M_J_DQS_DN<5>")
	)
	(segment
		(start 118.010686 -47.336964)
		(end 118.010686 -48.796702)
		(width 0.0889)
		(layer "In4.Cu")
		(net "M_J_DQS_DN<5>")
	)
	(segment
		(start 129.15138 -4.15036)
		(end 129.15138 -4.5466)
		(width 0.14224)
		(layer "In4.Cu")
		(net "M_J_DQS_DN<5>")
	)
	(segment
		(start 114.713766 -57.5818)
		(end 114.718592 -57.590436)
		(width 0.0889)
		(layer "In4.Cu")
		(net "M_J_DQS_DN<5>")
	)
	(segment
		(start 114.713766 -58.5724)
		(end 114.718592 -58.581036)
		(width 0.0889)
		(layer "In4.Cu")
		(net "M_J_DQS_DN<5>")
	)
	(segment
		(start 128.885696 -5.527548)
		(end 129.1082 -5.527548)
		(width 0.14224)
		(layer "In4.Cu")
		(net "M_J_DQS_DN<5>")
	)
	(segment
		(start 128.687576 -3.686556)
		(end 129.15138 -4.15036)
		(width 0.14224)
		(layer "In4.Cu")
		(net "M_J_DQS_DN<5>")
	)
	(segment
		(start 114.724942 -59.160918)
		(end 114.718592 -59.171586)
		(width 0.0889)
		(layer "In4.Cu")
		(net "M_J_DQS_DN<5>")
	)
	(segment
		(start 129.669286 -9.5758)
		(end 129.669286 -9.8298)
		(width 0.14224)
		(layer "In4.Cu")
		(net "M_J_DQS_DN<5>")
	)
	(segment
		(start 129.288032 -5.929884)
		(end 129.511806 -6.153658)
		(width 0.14224)
		(layer "In4.Cu")
		(net "M_J_DQS_DN<5>")
	)
	(segment
		(start 118.050056 -42.58564)
		(end 118.050056 -47.275496)
		(width 0.14224)
		(layer "In4.Cu")
		(net "M_J_DQS_DN<5>")
	)
	(segment
		(start 116.063268 -50.74412)
		(end 116.063268 -51.45532)
		(width 0.0889)
		(layer "In4.Cu")
		(net "M_J_DQS_DN<5>")
	)
	(segment
		(start 114.718592 -57.590436)
		(end 114.724942 -57.601104)
		(width 0.0889)
		(layer "In4.Cu")
		(net "M_J_DQS_DN<5>")
	)
	(segment
		(start 114.718592 -54.618636)
		(end 114.724942 -54.629304)
		(width 0.0889)
		(layer "In4.Cu")
		(net "M_J_DQS_DN<5>")
	)
	(segment
		(start 128.6383 -5.05968)
		(end 128.6383 -5.280152)
		(width 0.14224)
		(layer "In4.Cu")
		(net "M_J_DQS_DN<5>")
	)
	(segment
		(start 115.12296 -52.395628)
		(end 115.12296 -53.150008)
		(width 0.0889)
		(layer "In4.Cu")
		(net "M_J_DQS_DN<5>")
	)
	(segment
		(start 129.288032 -5.70738)
		(end 129.288032 -5.929884)
		(width 0.14224)
		(layer "In4.Cu")
		(net "M_J_DQS_DN<5>")
	)
	(segment
		(start 114.713766 -60.5536)
		(end 114.718592 -60.562236)
		(width 0.0889)
		(layer "In4.Cu")
		(net "M_J_DQS_DN<5>")
	)
	(segment
		(start 129.511806 -9.98728)
		(end 129.511806 -28.939236)
		(width 0.14224)
		(layer "In4.Cu")
		(net "M_J_DQS_DN<5>")
	)
	(segment
		(start 129.1082 -5.527548)
		(end 129.288032 -5.70738)
		(width 0.14224)
		(layer "In4.Cu")
		(net "M_J_DQS_DN<5>")
	)
	(arc
		(start 114.718592 -57.190386)
		(mid 114.665122 -57.385449)
		(end 114.713766 -57.5818)
		(width 0.0889)
		(layer "In4.Cu")
		(net "M_J_DQS_DN<5>")
	)
	(arc
		(start 114.718592 -58.581036)
		(mid 114.797814 -58.870154)
		(end 114.724942 -59.160918)
		(width 0.0889)
		(layer "In4.Cu")
		(net "M_J_DQS_DN<5>")
	)
	(arc
		(start 114.724942 -54.629304)
		(mid 114.79774 -54.920067)
		(end 114.718592 -55.209186)
		(width 0.0889)
		(layer "In4.Cu")
		(net "M_J_DQS_DN<5>")
	)
	(arc
		(start 114.718592 -54.218586)
		(mid 114.665122 -54.413649)
		(end 114.713766 -54.61)
		(width 0.0889)
		(layer "In4.Cu")
		(net "M_J_DQS_DN<5>")
	)
	(arc
		(start 114.797586 -53.907182)
		(mid 114.779628 -54.068344)
		(end 114.718592 -54.218586)
		(width 0.0889)
		(layer "In4.Cu")
		(net "M_J_DQS_DN<5>")
	)
	(arc
		(start 114.718592 -56.199786)
		(mid 114.665122 -56.394849)
		(end 114.713766 -56.5912)
		(width 0.0889)
		(layer "In4.Cu")
		(net "M_J_DQS_DN<5>")
	)
	(arc
		(start 114.718592 -59.171586)
		(mid 114.665093 -59.371484)
		(end 114.718592 -59.571382)
		(width 0.0889)
		(layer "In4.Cu")
		(net "M_J_DQS_DN<5>")
	)
	(arc
		(start 114.718592 -59.571382)
		(mid 114.797723 -59.866784)
		(end 114.718592 -60.162186)
		(width 0.0889)
		(layer "In4.Cu")
		(net "M_J_DQS_DN<5>")
	)
	(arc
		(start 114.724942 -55.619904)
		(mid 114.79774 -55.910667)
		(end 114.718592 -56.199786)
		(width 0.0889)
		(layer "In4.Cu")
		(net "M_J_DQS_DN<5>")
	)
	(arc
		(start 114.718592 -58.180986)
		(mid 114.665122 -58.376049)
		(end 114.713766 -58.5724)
		(width 0.0889)
		(layer "In4.Cu")
		(net "M_J_DQS_DN<5>")
	)
	(arc
		(start 114.724942 -60.572904)
		(mid 114.79774 -60.863667)
		(end 114.718592 -61.152786)
		(width 0.0889)
		(layer "In4.Cu")
		(net "M_J_DQS_DN<5>")
	)
	(arc
		(start 114.724942 -57.601104)
		(mid 114.79774 -57.891867)
		(end 114.718592 -58.180986)
		(width 0.0889)
		(layer "In4.Cu")
		(net "M_J_DQS_DN<5>")
	)
	(arc
		(start 114.718592 -55.209186)
		(mid 114.665122 -55.404249)
		(end 114.713766 -55.6006)
		(width 0.0889)
		(layer "In4.Cu")
		(net "M_J_DQS_DN<5>")
	)
	(arc
		(start 114.718592 -60.162186)
		(mid 114.665122 -60.357249)
		(end 114.713766 -60.5536)
		(width 0.0889)
		(layer "In4.Cu")
		(net "M_J_DQS_DN<5>")
	)
	(arc
		(start 114.652298 -61.26734)
		(mid 114.448551 -61.572249)
		(end 114.206782 -61.847984)
		(width 0.0889)
		(layer "In4.Cu")
		(net "M_J_DQS_DN<5>")
	)
	(arc
		(start 114.724942 -56.610504)
		(mid 114.79774 -56.901267)
		(end 114.718592 -57.190386)
		(width 0.0889)
		(layer "In4.Cu")
		(net "M_J_DQS_DN<5>")
	)
	(segment
		(start 129.498344 1.033272)
		(end 128.687576 1.84404)
		(width 0.14224)
		(layer "In11.Cu")
		(net "M_J_DQS_DN<5>")
	)
	(segment
		(start 128.687576 -3.686556)
		(end 129.498344 -2.875788)
		(width 0.14224)
		(layer "In11.Cu")
		(net "M_J_DQS_DN<5>")
	)
	(segment
		(start 129.498344 -2.875788)
		(end 129.498344 1.033272)
		(width 0.14224)
		(layer "In11.Cu")
		(net "M_J_DQS_DN<5>")
	)
	(segment
		(start 118.683532 1.190244)
		(end 119.337328 1.84404)
		(width 0.1651)
		(layer "F.Cu")
		(net "M_J_DQS_DN<4>")
	)
	(segment
		(start 118.94947 -0.821182)
		(end 118.949216 -0.820928)
		(width 0.1651)
		(layer "F.Cu")
		(net "M_J_DQS_DN<4>")
	)
	(segment
		(start 109.627416 -61.847984)
		(end 109.055916 -61.847984)
		(width 0.0889)
		(layer "F.Cu")
		(net "M_J_DQS_DN<4>")
	)
	(segment
		(start 118.949216 -0.820928)
		(end 118.949216 0.19177)
		(width 0.1651)
		(layer "F.Cu")
		(net "M_J_DQS_DN<4>")
	)
	(segment
		(start 118.683532 0.457454)
		(end 118.683532 1.190244)
		(width 0.1651)
		(layer "F.Cu")
		(net "M_J_DQS_DN<4>")
	)
	(segment
		(start 118.949216 0.19177)
		(end 118.683532 0.457454)
		(width 0.1651)
		(layer "F.Cu")
		(net "M_J_DQS_DN<4>")
	)
	(via
		(at 109.055916 -61.847984)
		(size 0.508)
		(drill 0.254)
		(layers "F.Cu" "B.Cu")
		(net "M_J_DQS_DN<4>")
	)
	(via
		(at 119.337328 1.84404)
		(size 0.508)
		(drill 0.254)
		(layers "F.Cu" "B.Cu")
		(net "M_J_DQS_DN<4>")
	)
	(via
		(at 119.337328 -3.686556)
		(size 0.508)
		(drill 0.254)
		(layers "F.Cu" "B.Cu")
		(net "M_J_DQS_DN<4>")
	)
	(segment
		(start 118.94947 -1.918716)
		(end 118.696232 -2.171954)
		(width 0.1651)
		(layer "B.Cu")
		(net "M_J_DQS_DN<4>")
	)
	(segment
		(start 118.696232 -2.171954)
		(end 118.696232 -3.04546)
		(width 0.1651)
		(layer "B.Cu")
		(net "M_J_DQS_DN<4>")
	)
	(segment
		(start 118.94947 -1.021842)
		(end 118.94947 -1.918716)
		(width 0.1651)
		(layer "B.Cu")
		(net "M_J_DQS_DN<4>")
	)
	(segment
		(start 118.696232 -3.04546)
		(end 119.337328 -3.686556)
		(width 0.1651)
		(layer "B.Cu")
		(net "M_J_DQS_DN<4>")
	)
	(segment
		(start 119.937784 -5.929884)
		(end 119.937784 -5.70738)
		(width 0.14224)
		(layer "In11.Cu")
		(net "M_J_DQS_DN<4>")
	)
	(segment
		(start 120.148096 1.033272)
		(end 119.337328 1.84404)
		(width 0.14224)
		(layer "In11.Cu")
		(net "M_J_DQS_DN<4>")
	)
	(segment
		(start 110.489238 -46.895004)
		(end 110.659672 -46.72457)
		(width 0.14224)
		(layer "In11.Cu")
		(net "M_J_DQS_DN<4>")
	)
	(segment
		(start 109.567472 -54.218586)
		(end 109.576362 -54.203346)
		(width 0.0889)
		(layer "In11.Cu")
		(net "M_J_DQS_DN<4>")
	)
	(segment
		(start 119.288052 -5.280152)
		(end 119.288052 -5.05968)
		(width 0.14224)
		(layer "In11.Cu")
		(net "M_J_DQS_DN<4>")
	)
	(segment
		(start 109.560106 -53.239162)
		(end 109.702346 -52.99329)
		(width 0.0889)
		(layer "In11.Cu")
		(net "M_J_DQS_DN<4>")
	)
	(segment
		(start 120.132856 -6.336284)
		(end 120.132856 -6.124956)
		(width 0.14224)
		(layer "In11.Cu")
		(net "M_J_DQS_DN<4>")
	)
	(segment
		(start 120.132856 -6.905244)
		(end 120.290336 -6.747764)
		(width 0.14224)
		(layer "In11.Cu")
		(net "M_J_DQS_DN<4>")
	)
	(segment
		(start 119.757952 -5.527548)
		(end 119.535448 -5.527548)
		(width 0.14224)
		(layer "In11.Cu")
		(net "M_J_DQS_DN<4>")
	)
	(segment
		(start 109.576616 -60.577476)
		(end 109.567726 -60.562236)
		(width 0.0889)
		(layer "In11.Cu")
		(net "M_J_DQS_DN<4>")
	)
	(segment
		(start 119.801132 -4.5466)
		(end 119.801132 -4.15036)
		(width 0.14224)
		(layer "In11.Cu")
		(net "M_J_DQS_DN<4>")
	)
	(segment
		(start 109.576616 -56.615076)
		(end 109.567726 -56.599836)
		(width 0.0889)
		(layer "In11.Cu")
		(net "M_J_DQS_DN<4>")
	)
	(segment
		(start 109.702346 -52.99329)
		(end 109.702346 -52.540916)
		(width 0.0889)
		(layer "In11.Cu")
		(net "M_J_DQS_DN<4>")
	)
	(segment
		(start 109.055916 -61.847984)
		(end 109.055916 -61.50991)
		(width 0.0889)
		(layer "In11.Cu")
		(net "M_J_DQS_DN<4>")
	)
	(segment
		(start 120.132856 -30.202378)
		(end 120.132856 -10.80008)
		(width 0.14224)
		(layer "In11.Cu")
		(net "M_J_DQS_DN<4>")
	)
	(segment
		(start 110.489238 -47.348902)
		(end 110.489238 -46.895004)
		(width 0.14224)
		(layer "In11.Cu")
		(net "M_J_DQS_DN<4>")
	)
	(segment
		(start 110.659672 -39.675562)
		(end 120.132856 -30.202378)
		(width 0.14224)
		(layer "In11.Cu")
		(net "M_J_DQS_DN<4>")
	)
	(segment
		(start 119.337328 -3.686556)
		(end 120.148096 -2.875788)
		(width 0.14224)
		(layer "In11.Cu")
		(net "M_J_DQS_DN<4>")
	)
	(segment
		(start 110.659672 -46.72457)
		(end 110.659672 -39.675562)
		(width 0.14224)
		(layer "In11.Cu")
		(net "M_J_DQS_DN<4>")
	)
	(segment
		(start 110.489238 -47.371)
		(end 110.489238 -47.348902)
		(width 0.0889)
		(layer "In11.Cu")
		(net "M_J_DQS_DN<4>")
	)
	(segment
		(start 119.937784 -5.70738)
		(end 119.757952 -5.527548)
		(width 0.14224)
		(layer "In11.Cu")
		(net "M_J_DQS_DN<4>")
	)
	(segment
		(start 110.449868 -48.21936)
		(end 110.449868 -47.41037)
		(width 0.0889)
		(layer "In11.Cu")
		(net "M_J_DQS_DN<4>")
	)
	(segment
		(start 109.567726 -59.171586)
		(end 109.574076 -59.160918)
		(width 0.0889)
		(layer "In11.Cu")
		(net "M_J_DQS_DN<4>")
	)
	(segment
		(start 120.290336 -9.6266)
		(end 120.132856 -9.46912)
		(width 0.14224)
		(layer "In11.Cu")
		(net "M_J_DQS_DN<4>")
	)
	(segment
		(start 109.574076 -59.58205)
		(end 109.567726 -59.571382)
		(width 0.0889)
		(layer "In11.Cu")
		(net "M_J_DQS_DN<4>")
	)
	(segment
		(start 119.535448 -5.527548)
		(end 119.288052 -5.280152)
		(width 0.14224)
		(layer "In11.Cu")
		(net "M_J_DQS_DN<4>")
	)
	(segment
		(start 120.290336 -10.6426)
		(end 120.290336 -10.3886)
		(width 0.14224)
		(layer "In11.Cu")
		(net "M_J_DQS_DN<4>")
	)
	(segment
		(start 109.576616 -55.624476)
		(end 109.567726 -55.609236)
		(width 0.0889)
		(layer "In11.Cu")
		(net "M_J_DQS_DN<4>")
	)
	(segment
		(start 119.801132 -4.15036)
		(end 119.337328 -3.686556)
		(width 0.14224)
		(layer "In11.Cu")
		(net "M_J_DQS_DN<4>")
	)
	(segment
		(start 120.132856 -6.124956)
		(end 119.937784 -5.929884)
		(width 0.14224)
		(layer "In11.Cu")
		(net "M_J_DQS_DN<4>")
	)
	(segment
		(start 120.132856 -9.46912)
		(end 120.132856 -6.905244)
		(width 0.14224)
		(layer "In11.Cu")
		(net "M_J_DQS_DN<4>")
	)
	(segment
		(start 119.288052 -5.05968)
		(end 119.801132 -4.5466)
		(width 0.14224)
		(layer "In11.Cu")
		(net "M_J_DQS_DN<4>")
	)
	(segment
		(start 120.290336 -6.493764)
		(end 120.132856 -6.336284)
		(width 0.14224)
		(layer "In11.Cu")
		(net "M_J_DQS_DN<4>")
	)
	(segment
		(start 120.132856 -10.23112)
		(end 120.132856 -10.03808)
		(width 0.14224)
		(layer "In11.Cu")
		(net "M_J_DQS_DN<4>")
	)
	(segment
		(start 110.449868 -47.41037)
		(end 110.489238 -47.371)
		(width 0.0889)
		(layer "In11.Cu")
		(net "M_J_DQS_DN<4>")
	)
	(segment
		(start 120.132856 -10.03808)
		(end 120.290336 -9.8806)
		(width 0.14224)
		(layer "In11.Cu")
		(net "M_J_DQS_DN<4>")
	)
	(segment
		(start 109.99724 -48.671988)
		(end 110.449868 -48.21936)
		(width 0.0889)
		(layer "In11.Cu")
		(net "M_J_DQS_DN<4>")
	)
	(segment
		(start 120.148096 -2.875788)
		(end 120.148096 1.033272)
		(width 0.14224)
		(layer "In11.Cu")
		(net "M_J_DQS_DN<4>")
	)
	(segment
		(start 109.702346 -52.540916)
		(end 109.99724 -52.246022)
		(width 0.0889)
		(layer "In11.Cu")
		(net "M_J_DQS_DN<4>")
	)
	(segment
		(start 109.576616 -57.605676)
		(end 109.567726 -57.590436)
		(width 0.0889)
		(layer "In11.Cu")
		(net "M_J_DQS_DN<4>")
	)
	(segment
		(start 120.290336 -9.8806)
		(end 120.290336 -9.6266)
		(width 0.14224)
		(layer "In11.Cu")
		(net "M_J_DQS_DN<4>")
	)
	(segment
		(start 109.576616 -54.633876)
		(end 109.559598 -54.604412)
		(width 0.0889)
		(layer "In11.Cu")
		(net "M_J_DQS_DN<4>")
	)
	(segment
		(start 109.055916 -61.50991)
		(end 109.12094 -61.444886)
		(width 0.0889)
		(layer "In11.Cu")
		(net "M_J_DQS_DN<4>")
	)
	(segment
		(start 109.99724 -52.246022)
		(end 109.99724 -48.671988)
		(width 0.0889)
		(layer "In11.Cu")
		(net "M_J_DQS_DN<4>")
	)
	(segment
		(start 120.290336 -6.747764)
		(end 120.290336 -6.493764)
		(width 0.14224)
		(layer "In11.Cu")
		(net "M_J_DQS_DN<4>")
	)
	(segment
		(start 120.132856 -10.80008)
		(end 120.290336 -10.6426)
		(width 0.14224)
		(layer "In11.Cu")
		(net "M_J_DQS_DN<4>")
	)
	(segment
		(start 120.290336 -10.3886)
		(end 120.132856 -10.23112)
		(width 0.14224)
		(layer "In11.Cu")
		(net "M_J_DQS_DN<4>")
	)
	(arc
		(start 109.567472 -53.627274)
		(mid 109.51384 -53.4367)
		(end 109.558074 -53.243734)
		(width 0.0889)
		(layer "In11.Cu")
		(net "M_J_DQS_DN<4>")
	)
	(arc
		(start 109.567726 -57.19064)
		(mid 109.646915 -56.904025)
		(end 109.576616 -56.615076)
		(width 0.0889)
		(layer "In11.Cu")
		(net "M_J_DQS_DN<4>")
	)
	(arc
		(start 109.558074 -53.243734)
		(mid 109.559083 -53.241445)
		(end 109.560106 -53.239162)
		(width 0.0889)
		(layer "In11.Cu")
		(net "M_J_DQS_DN<4>")
	)
	(arc
		(start 109.567726 -56.20004)
		(mid 109.646915 -55.913425)
		(end 109.576616 -55.624476)
		(width 0.0889)
		(layer "In11.Cu")
		(net "M_J_DQS_DN<4>")
	)
	(arc
		(start 109.567726 -55.20944)
		(mid 109.646915 -54.922825)
		(end 109.576616 -54.633876)
		(width 0.0889)
		(layer "In11.Cu")
		(net "M_J_DQS_DN<4>")
	)
	(arc
		(start 109.567726 -60.562236)
		(mid 109.514193 -60.362338)
		(end 109.567726 -60.16244)
		(width 0.0889)
		(layer "In11.Cu")
		(net "M_J_DQS_DN<4>")
	)
	(arc
		(start 109.567726 -58.581036)
		(mid 109.514193 -58.381138)
		(end 109.567726 -58.18124)
		(width 0.0889)
		(layer "In11.Cu")
		(net "M_J_DQS_DN<4>")
	)
	(arc
		(start 109.576362 -54.203346)
		(mid 109.646879 -53.914141)
		(end 109.567472 -53.627274)
		(width 0.0889)
		(layer "In11.Cu")
		(net "M_J_DQS_DN<4>")
	)
	(arc
		(start 109.567726 -58.18124)
		(mid 109.646915 -57.894625)
		(end 109.576616 -57.605676)
		(width 0.0889)
		(layer "In11.Cu")
		(net "M_J_DQS_DN<4>")
	)
	(arc
		(start 109.559598 -54.604412)
		(mid 109.514011 -54.410499)
		(end 109.567472 -54.218586)
		(width 0.0889)
		(layer "In11.Cu")
		(net "M_J_DQS_DN<4>")
	)
	(arc
		(start 109.567726 -60.16244)
		(mid 109.647075 -59.873068)
		(end 109.574076 -59.58205)
		(width 0.0889)
		(layer "In11.Cu")
		(net "M_J_DQS_DN<4>")
	)
	(arc
		(start 109.567726 -55.609236)
		(mid 109.514193 -55.409338)
		(end 109.567726 -55.20944)
		(width 0.0889)
		(layer "In11.Cu")
		(net "M_J_DQS_DN<4>")
	)
	(arc
		(start 109.12094 -61.444886)
		(mid 109.579206 -61.132255)
		(end 109.576616 -60.577476)
		(width 0.0889)
		(layer "In11.Cu")
		(net "M_J_DQS_DN<4>")
	)
	(arc
		(start 109.574076 -59.160918)
		(mid 109.646874 -58.870155)
		(end 109.567726 -58.581036)
		(width 0.0889)
		(layer "In11.Cu")
		(net "M_J_DQS_DN<4>")
	)
	(arc
		(start 109.567726 -59.571382)
		(mid 109.514193 -59.371484)
		(end 109.567726 -59.171586)
		(width 0.0889)
		(layer "In11.Cu")
		(net "M_J_DQS_DN<4>")
	)
	(arc
		(start 109.567726 -57.590436)
		(mid 109.514193 -57.390538)
		(end 109.567726 -57.19064)
		(width 0.0889)
		(layer "In11.Cu")
		(net "M_J_DQS_DN<4>")
	)
	(arc
		(start 109.567726 -56.599836)
		(mid 109.514193 -56.399938)
		(end 109.567726 -56.20004)
		(width 0.0889)
		(layer "In11.Cu")
		(net "M_J_DQS_DN<4>")
	)
	(segment
		(start 84.919312 -67.47764)
		(end 84.347812 -67.47764)
		(width 0.1016)
		(layer "F.Cu")
		(net "M_J_DQS_DN<3>")
	)
	(segment
		(start 63.69939 0.19177)
		(end 63.433706 0.457454)
		(width 0.1651)
		(layer "F.Cu")
		(net "M_J_DQS_DN<3>")
	)
	(segment
		(start 63.69939 -0.821182)
		(end 63.69939 0.19177)
		(width 0.1651)
		(layer "F.Cu")
		(net "M_J_DQS_DN<3>")
	)
	(segment
		(start 63.433706 1.190244)
		(end 64.087502 1.84404)
		(width 0.1651)
		(layer "F.Cu")
		(net "M_J_DQS_DN<3>")
	)
	(segment
		(start 63.433706 0.457454)
		(end 63.433706 1.190244)
		(width 0.1651)
		(layer "F.Cu")
		(net "M_J_DQS_DN<3>")
	)
	(via
		(at 84.347812 -67.47764)
		(size 0.508)
		(drill 0.254)
		(layers "F.Cu" "B.Cu")
		(net "M_J_DQS_DN<3>")
	)
	(via
		(at 64.087502 1.84404)
		(size 0.508)
		(drill 0.254)
		(layers "F.Cu" "B.Cu")
		(net "M_J_DQS_DN<3>")
	)
	(via
		(at 64.087502 -3.686556)
		(size 0.508)
		(drill 0.254)
		(layers "F.Cu" "B.Cu")
		(net "M_J_DQS_DN<3>")
	)
	(segment
		(start 63.69939 -1.021842)
		(end 63.69939 -1.91897)
		(width 0.1651)
		(layer "B.Cu")
		(net "M_J_DQS_DN<3>")
	)
	(segment
		(start 63.446406 -3.04546)
		(end 64.087502 -3.686556)
		(width 0.1651)
		(layer "B.Cu")
		(net "M_J_DQS_DN<3>")
	)
	(segment
		(start 63.69939 -1.91897)
		(end 63.446406 -2.171954)
		(width 0.1651)
		(layer "B.Cu")
		(net "M_J_DQS_DN<3>")
	)
	(segment
		(start 63.446406 -2.171954)
		(end 63.446406 -3.04546)
		(width 0.1651)
		(layer "B.Cu")
		(net "M_J_DQS_DN<3>")
	)
	(segment
		(start 84.859622 -64.800988)
		(end 84.854796 -64.809624)
		(width 0.0889)
		(layer "In11.Cu")
		(net "M_J_DQS_DN<3>")
	)
	(segment
		(start 82.784188 -49.927002)
		(end 82.93735 -50.080164)
		(width 0.0889)
		(layer "In11.Cu")
		(net "M_J_DQS_DN<3>")
	)
	(segment
		(start 65.021968 -8.407146)
		(end 65.021968 -8.610854)
		(width 0.14224)
		(layer "In11.Cu")
		(net "M_J_DQS_DN<3>")
	)
	(segment
		(start 70.72249 -37.240972)
		(end 82.139028 -48.65751)
		(width 0.14224)
		(layer "In11.Cu")
		(net "M_J_DQS_DN<3>")
	)
	(segment
		(start 84.347812 -67.139566)
		(end 84.347812 -67.47764)
		(width 0.0889)
		(layer "In11.Cu")
		(net "M_J_DQS_DN<3>")
	)
	(segment
		(start 84.820506 -55.227474)
		(end 84.859622 -55.295038)
		(width 0.0889)
		(layer "In11.Cu")
		(net "M_J_DQS_DN<3>")
	)
	(segment
		(start 64.285622 -5.527548)
		(end 64.508126 -5.527548)
		(width 0.14224)
		(layer "In11.Cu")
		(net "M_J_DQS_DN<3>")
	)
	(segment
		(start 84.859622 -65.791588)
		(end 84.854796 -65.800224)
		(width 0.0889)
		(layer "In11.Cu")
		(net "M_J_DQS_DN<3>")
	)
	(segment
		(start 84.865972 -65.78092)
		(end 84.859622 -65.791588)
		(width 0.0889)
		(layer "In11.Cu")
		(net "M_J_DQS_DN<3>")
	)
	(segment
		(start 84.865972 -56.86552)
		(end 84.859622 -56.876188)
		(width 0.0889)
		(layer "In11.Cu")
		(net "M_J_DQS_DN<3>")
	)
	(segment
		(start 64.869822 -29.024326)
		(end 70.72249 -34.876994)
		(width 0.14224)
		(layer "In11.Cu")
		(net "M_J_DQS_DN<3>")
	)
	(segment
		(start 82.93735 -50.080164)
		(end 82.93735 -51.675538)
		(width 0.0889)
		(layer "In11.Cu")
		(net "M_J_DQS_DN<3>")
	)
	(segment
		(start 65.027302 -10.5664)
		(end 64.869822 -10.72388)
		(width 0.14224)
		(layer "In11.Cu")
		(net "M_J_DQS_DN<3>")
	)
	(segment
		(start 64.869822 -10.15492)
		(end 65.027302 -10.3124)
		(width 0.14224)
		(layer "In11.Cu")
		(net "M_J_DQS_DN<3>")
	)
	(segment
		(start 64.087502 1.84404)
		(end 64.89827 1.033272)
		(width 0.14224)
		(layer "In11.Cu")
		(net "M_J_DQS_DN<3>")
	)
	(segment
		(start 64.89827 -2.875788)
		(end 64.087502 -3.686556)
		(width 0.14224)
		(layer "In11.Cu")
		(net "M_J_DQS_DN<3>")
	)
	(segment
		(start 84.865972 -64.79032)
		(end 84.859622 -64.800988)
		(width 0.0889)
		(layer "In11.Cu")
		(net "M_J_DQS_DN<3>")
	)
	(segment
		(start 82.93735 -51.675538)
		(end 84.118704 -52.856892)
		(width 0.0889)
		(layer "In11.Cu")
		(net "M_J_DQS_DN<3>")
	)
	(segment
		(start 70.72249 -34.876994)
		(end 70.72249 -37.240972)
		(width 0.14224)
		(layer "In11.Cu")
		(net "M_J_DQS_DN<3>")
	)
	(segment
		(start 84.383372 -54.79034)
		(end 84.820506 -55.227474)
		(width 0.0889)
		(layer "In11.Cu")
		(net "M_J_DQS_DN<3>")
	)
	(segment
		(start 84.859622 -56.876188)
		(end 84.854796 -56.884824)
		(width 0.0889)
		(layer "In11.Cu")
		(net "M_J_DQS_DN<3>")
	)
	(segment
		(start 64.551306 -4.5466)
		(end 64.038226 -5.05968)
		(width 0.14224)
		(layer "In11.Cu")
		(net "M_J_DQS_DN<3>")
	)
	(segment
		(start 64.087502 -3.686556)
		(end 64.551306 -4.15036)
		(width 0.14224)
		(layer "In11.Cu")
		(net "M_J_DQS_DN<3>")
	)
	(segment
		(start 84.859622 -55.885588)
		(end 84.854796 -55.894224)
		(width 0.0889)
		(layer "In11.Cu")
		(net "M_J_DQS_DN<3>")
	)
	(segment
		(start 84.383372 -54.37378)
		(end 84.383372 -54.79034)
		(width 0.0889)
		(layer "In11.Cu")
		(net "M_J_DQS_DN<3>")
	)
	(segment
		(start 84.859622 -59.847988)
		(end 84.854796 -59.856624)
		(width 0.0889)
		(layer "In11.Cu")
		(net "M_J_DQS_DN<3>")
	)
	(segment
		(start 84.118704 -54.109112)
		(end 84.383372 -54.37378)
		(width 0.0889)
		(layer "In11.Cu")
		(net "M_J_DQS_DN<3>")
	)
	(segment
		(start 84.865972 -60.82792)
		(end 84.859622 -60.838588)
		(width 0.0889)
		(layer "In11.Cu")
		(net "M_J_DQS_DN<3>")
	)
	(segment
		(start 64.687958 -5.929884)
		(end 64.869822 -6.111748)
		(width 0.14224)
		(layer "In11.Cu")
		(net "M_J_DQS_DN<3>")
	)
	(segment
		(start 64.038226 -5.280152)
		(end 64.285622 -5.527548)
		(width 0.14224)
		(layer "In11.Cu")
		(net "M_J_DQS_DN<3>")
	)
	(segment
		(start 82.139028 -49.225962)
		(end 82.76844 -49.855374)
		(width 0.14224)
		(layer "In11.Cu")
		(net "M_J_DQS_DN<3>")
	)
	(segment
		(start 84.859622 -58.266838)
		(end 84.865972 -58.277506)
		(width 0.0889)
		(layer "In11.Cu")
		(net "M_J_DQS_DN<3>")
	)
	(segment
		(start 84.865972 -61.81852)
		(end 84.859622 -61.829188)
		(width 0.0889)
		(layer "In11.Cu")
		(net "M_J_DQS_DN<3>")
	)
	(segment
		(start 65.021968 -8.610854)
		(end 64.869822 -8.763)
		(width 0.14224)
		(layer "In11.Cu")
		(net "M_J_DQS_DN<3>")
	)
	(segment
		(start 64.687958 -5.70738)
		(end 64.687958 -5.929884)
		(width 0.14224)
		(layer "In11.Cu")
		(net "M_J_DQS_DN<3>")
	)
	(segment
		(start 64.551306 -4.15036)
		(end 64.551306 -4.5466)
		(width 0.14224)
		(layer "In11.Cu")
		(net "M_J_DQS_DN<3>")
	)
	(segment
		(start 64.869822 -9.96188)
		(end 64.869822 -10.15492)
		(width 0.14224)
		(layer "In11.Cu")
		(net "M_J_DQS_DN<3>")
	)
	(segment
		(start 84.859622 -62.819788)
		(end 84.854796 -62.828424)
		(width 0.0889)
		(layer "In11.Cu")
		(net "M_J_DQS_DN<3>")
	)
	(segment
		(start 84.865972 -59.83732)
		(end 84.859622 -59.847988)
		(width 0.0889)
		(layer "In11.Cu")
		(net "M_J_DQS_DN<3>")
	)
	(segment
		(start 64.89827 1.033272)
		(end 64.89827 -2.875788)
		(width 0.14224)
		(layer "In11.Cu")
		(net "M_J_DQS_DN<3>")
	)
	(segment
		(start 64.869822 -10.72388)
		(end 64.869822 -29.024326)
		(width 0.14224)
		(layer "In11.Cu")
		(net "M_J_DQS_DN<3>")
	)
	(segment
		(start 64.508126 -5.527548)
		(end 64.687958 -5.70738)
		(width 0.14224)
		(layer "In11.Cu")
		(net "M_J_DQS_DN<3>")
	)
	(segment
		(start 84.859622 -58.857388)
		(end 84.854796 -58.866024)
		(width 0.0889)
		(layer "In11.Cu")
		(net "M_J_DQS_DN<3>")
	)
	(segment
		(start 64.869822 -8.763)
		(end 64.869822 -9.39292)
		(width 0.14224)
		(layer "In11.Cu")
		(net "M_J_DQS_DN<3>")
	)
	(segment
		(start 82.76844 -49.855374)
		(end 82.784188 -49.871122)
		(width 0.0889)
		(layer "In11.Cu")
		(net "M_J_DQS_DN<3>")
	)
	(segment
		(start 84.859622 -60.838588)
		(end 84.854796 -60.847224)
		(width 0.0889)
		(layer "In11.Cu")
		(net "M_J_DQS_DN<3>")
	)
	(segment
		(start 65.027302 -9.8044)
		(end 64.869822 -9.96188)
		(width 0.14224)
		(layer "In11.Cu")
		(net "M_J_DQS_DN<3>")
	)
	(segment
		(start 65.027302 -9.5504)
		(end 65.027302 -9.8044)
		(width 0.14224)
		(layer "In11.Cu")
		(net "M_J_DQS_DN<3>")
	)
	(segment
		(start 65.027302 -10.3124)
		(end 65.027302 -10.5664)
		(width 0.14224)
		(layer "In11.Cu")
		(net "M_J_DQS_DN<3>")
	)
	(segment
		(start 82.784188 -49.871122)
		(end 82.784188 -49.927002)
		(width 0.0889)
		(layer "In11.Cu")
		(net "M_J_DQS_DN<3>")
	)
	(segment
		(start 64.869822 -8.255)
		(end 65.021968 -8.407146)
		(width 0.14224)
		(layer "In11.Cu")
		(net "M_J_DQS_DN<3>")
	)
	(segment
		(start 84.865972 -63.79972)
		(end 84.859622 -63.810388)
		(width 0.0889)
		(layer "In11.Cu")
		(net "M_J_DQS_DN<3>")
	)
	(segment
		(start 84.859622 -61.829188)
		(end 84.854796 -61.837824)
		(width 0.0889)
		(layer "In11.Cu")
		(net "M_J_DQS_DN<3>")
	)
	(segment
		(start 84.865972 -55.87492)
		(end 84.859622 -55.885588)
		(width 0.0889)
		(layer "In11.Cu")
		(net "M_J_DQS_DN<3>")
	)
	(segment
		(start 84.865972 -62.80912)
		(end 84.859622 -62.819788)
		(width 0.0889)
		(layer "In11.Cu")
		(net "M_J_DQS_DN<3>")
	)
	(segment
		(start 64.869822 -6.111748)
		(end 64.869822 -8.255)
		(width 0.14224)
		(layer "In11.Cu")
		(net "M_J_DQS_DN<3>")
	)
	(segment
		(start 82.139028 -48.65751)
		(end 82.139028 -49.225962)
		(width 0.14224)
		(layer "In11.Cu")
		(net "M_J_DQS_DN<3>")
	)
	(segment
		(start 84.118704 -52.856892)
		(end 84.118704 -54.109112)
		(width 0.0889)
		(layer "In11.Cu")
		(net "M_J_DQS_DN<3>")
	)
	(segment
		(start 64.038226 -5.05968)
		(end 64.038226 -5.280152)
		(width 0.14224)
		(layer "In11.Cu")
		(net "M_J_DQS_DN<3>")
	)
	(segment
		(start 84.859622 -63.810388)
		(end 84.854796 -63.819024)
		(width 0.0889)
		(layer "In11.Cu")
		(net "M_J_DQS_DN<3>")
	)
	(segment
		(start 64.869822 -9.39292)
		(end 65.027302 -9.5504)
		(width 0.14224)
		(layer "In11.Cu")
		(net "M_J_DQS_DN<3>")
	)
	(segment
		(start 84.41309 -67.074288)
		(end 84.347812 -67.139566)
		(width 0.0889)
		(layer "In11.Cu")
		(net "M_J_DQS_DN<3>")
	)
	(arc
		(start 84.854796 -64.809624)
		(mid 84.806041 -65.005976)
		(end 84.859622 -65.201038)
		(width 0.0889)
		(layer "In11.Cu")
		(net "M_J_DQS_DN<3>")
	)
	(arc
		(start 84.859622 -60.248038)
		(mid 84.938844 -60.537156)
		(end 84.865972 -60.82792)
		(width 0.0889)
		(layer "In11.Cu")
		(net "M_J_DQS_DN<3>")
	)
	(arc
		(start 84.854796 -63.819024)
		(mid 84.806041 -64.015376)
		(end 84.859622 -64.210438)
		(width 0.0889)
		(layer "In11.Cu")
		(net "M_J_DQS_DN<3>")
	)
	(arc
		(start 84.854796 -62.828424)
		(mid 84.806041 -63.024776)
		(end 84.859622 -63.219838)
		(width 0.0889)
		(layer "In11.Cu")
		(net "M_J_DQS_DN<3>")
	)
	(arc
		(start 84.859622 -65.201038)
		(mid 84.938844 -65.490156)
		(end 84.865972 -65.78092)
		(width 0.0889)
		(layer "In11.Cu")
		(net "M_J_DQS_DN<3>")
	)
	(arc
		(start 84.859622 -57.276238)
		(mid 84.938753 -57.57164)
		(end 84.859622 -57.867042)
		(width 0.0889)
		(layer "In11.Cu")
		(net "M_J_DQS_DN<3>")
	)
	(arc
		(start 84.859622 -63.219838)
		(mid 84.938844 -63.508956)
		(end 84.865972 -63.79972)
		(width 0.0889)
		(layer "In11.Cu")
		(net "M_J_DQS_DN<3>")
	)
	(arc
		(start 84.865972 -58.277506)
		(mid 84.93877 -58.568269)
		(end 84.859622 -58.857388)
		(width 0.0889)
		(layer "In11.Cu")
		(net "M_J_DQS_DN<3>")
	)
	(arc
		(start 84.859622 -66.191638)
		(mid 84.875127 -66.75378)
		(end 84.41309 -67.074288)
		(width 0.0889)
		(layer "In11.Cu")
		(net "M_J_DQS_DN<3>")
	)
	(arc
		(start 84.854796 -65.800224)
		(mid 84.806041 -65.996576)
		(end 84.859622 -66.191638)
		(width 0.0889)
		(layer "In11.Cu")
		(net "M_J_DQS_DN<3>")
	)
	(arc
		(start 84.854796 -55.894224)
		(mid 84.806041 -56.090576)
		(end 84.859622 -56.285638)
		(width 0.0889)
		(layer "In11.Cu")
		(net "M_J_DQS_DN<3>")
	)
	(arc
		(start 84.859622 -56.285638)
		(mid 84.938844 -56.574756)
		(end 84.865972 -56.86552)
		(width 0.0889)
		(layer "In11.Cu")
		(net "M_J_DQS_DN<3>")
	)
	(arc
		(start 84.854796 -58.866024)
		(mid 84.806041 -59.062376)
		(end 84.859622 -59.257438)
		(width 0.0889)
		(layer "In11.Cu")
		(net "M_J_DQS_DN<3>")
	)
	(arc
		(start 84.859622 -61.238638)
		(mid 84.938844 -61.527756)
		(end 84.865972 -61.81852)
		(width 0.0889)
		(layer "In11.Cu")
		(net "M_J_DQS_DN<3>")
	)
	(arc
		(start 84.859622 -62.229238)
		(mid 84.938844 -62.518356)
		(end 84.865972 -62.80912)
		(width 0.0889)
		(layer "In11.Cu")
		(net "M_J_DQS_DN<3>")
	)
	(arc
		(start 84.854796 -61.837824)
		(mid 84.806041 -62.034176)
		(end 84.859622 -62.229238)
		(width 0.0889)
		(layer "In11.Cu")
		(net "M_J_DQS_DN<3>")
	)
	(arc
		(start 84.859622 -59.257438)
		(mid 84.938844 -59.546556)
		(end 84.865972 -59.83732)
		(width 0.0889)
		(layer "In11.Cu")
		(net "M_J_DQS_DN<3>")
	)
	(arc
		(start 84.859622 -57.867042)
		(mid 84.806123 -58.06694)
		(end 84.859622 -58.266838)
		(width 0.0889)
		(layer "In11.Cu")
		(net "M_J_DQS_DN<3>")
	)
	(arc
		(start 84.859622 -55.295038)
		(mid 84.938844 -55.584156)
		(end 84.865972 -55.87492)
		(width 0.0889)
		(layer "In11.Cu")
		(net "M_J_DQS_DN<3>")
	)
	(arc
		(start 84.854796 -56.884824)
		(mid 84.806041 -57.081176)
		(end 84.859622 -57.276238)
		(width 0.0889)
		(layer "In11.Cu")
		(net "M_J_DQS_DN<3>")
	)
	(arc
		(start 84.854796 -59.856624)
		(mid 84.806041 -60.052976)
		(end 84.859622 -60.248038)
		(width 0.0889)
		(layer "In11.Cu")
		(net "M_J_DQS_DN<3>")
	)
	(arc
		(start 84.854796 -60.847224)
		(mid 84.806041 -61.043576)
		(end 84.859622 -61.238638)
		(width 0.0889)
		(layer "In11.Cu")
		(net "M_J_DQS_DN<3>")
	)
	(arc
		(start 84.859622 -64.210438)
		(mid 84.938844 -64.499556)
		(end 84.865972 -64.79032)
		(width 0.0889)
		(layer "In11.Cu")
		(net "M_J_DQS_DN<3>")
	)
	(segment
		(start 82.343752 -59.057286)
		(end 81.772252 -59.057286)
		(width 0.0889)
		(layer "F.Cu")
		(net "M_J_DQS_DN<2>")
	)
	(segment
		(start 54.349396 0.19177)
		(end 54.083712 0.457454)
		(width 0.1651)
		(layer "F.Cu")
		(net "M_J_DQS_DN<2>")
	)
	(segment
		(start 54.349396 -0.821182)
		(end 54.349396 0.19177)
		(width 0.1651)
		(layer "F.Cu")
		(net "M_J_DQS_DN<2>")
	)
	(segment
		(start 54.083712 0.457454)
		(end 54.083712 1.190244)
		(width 0.1651)
		(layer "F.Cu")
		(net "M_J_DQS_DN<2>")
	)
	(segment
		(start 54.083712 1.190244)
		(end 54.737508 1.84404)
		(width 0.1651)
		(layer "F.Cu")
		(net "M_J_DQS_DN<2>")
	)
	(via
		(at 54.737508 1.84404)
		(size 0.508)
		(drill 0.254)
		(layers "F.Cu" "B.Cu")
		(net "M_J_DQS_DN<2>")
	)
	(via
		(at 81.772252 -59.057286)
		(size 0.508)
		(drill 0.254)
		(layers "F.Cu" "B.Cu")
		(net "M_J_DQS_DN<2>")
	)
	(via
		(at 54.737508 -3.686556)
		(size 0.508)
		(drill 0.254)
		(layers "F.Cu" "B.Cu")
		(net "M_J_DQS_DN<2>")
	)
	(segment
		(start 54.096412 -2.171954)
		(end 54.096412 -3.04546)
		(width 0.1651)
		(layer "B.Cu")
		(net "M_J_DQS_DN<2>")
	)
	(segment
		(start 54.096412 -3.04546)
		(end 54.737508 -3.686556)
		(width 0.1651)
		(layer "B.Cu")
		(net "M_J_DQS_DN<2>")
	)
	(segment
		(start 54.349396 -1.021842)
		(end 54.349396 -1.91897)
		(width 0.1651)
		(layer "B.Cu")
		(net "M_J_DQS_DN<2>")
	)
	(segment
		(start 54.349396 -1.91897)
		(end 54.096412 -2.171954)
		(width 0.1651)
		(layer "B.Cu")
		(net "M_J_DQS_DN<2>")
	)
	(segment
		(start 55.677308 -6.480556)
		(end 55.519828 -6.638036)
		(width 0.14224)
		(layer "In11.Cu")
		(net "M_J_DQS_DN<2>")
	)
	(segment
		(start 72.31761 -53.018436)
		(end 72.34174 -53.018436)
		(width 0.0889)
		(layer "In11.Cu")
		(net "M_J_DQS_DN<2>")
	)
	(segment
		(start 55.158132 -5.527548)
		(end 55.337964 -5.70738)
		(width 0.14224)
		(layer "In11.Cu")
		(net "M_J_DQS_DN<2>")
	)
	(segment
		(start 55.519828 -6.638036)
		(end 55.519828 -33.501838)
		(width 0.14224)
		(layer "In11.Cu")
		(net "M_J_DQS_DN<2>")
	)
	(segment
		(start 67.990974 -46.960028)
		(end 68.152772 -46.960028)
		(width 0.14224)
		(layer "In11.Cu")
		(net "M_J_DQS_DN<2>")
	)
	(segment
		(start 78.338172 -56.485536)
		(end 78.355952 -56.485536)
		(width 0.0889)
		(layer "In11.Cu")
		(net "M_J_DQS_DN<2>")
	)
	(segment
		(start 81.479136 -58.888376)
		(end 81.772252 -59.057286)
		(width 0.0889)
		(layer "In11.Cu")
		(net "M_J_DQS_DN<2>")
	)
	(segment
		(start 68.332604 -47.301658)
		(end 68.664582 -47.633636)
		(width 0.14224)
		(layer "In11.Cu")
		(net "M_J_DQS_DN<2>")
	)
	(segment
		(start 71.42353 -50.083974)
		(end 71.42353 -50.139346)
		(width 0.0889)
		(layer "In11.Cu")
		(net "M_J_DQS_DN<2>")
	)
	(segment
		(start 68.664582 -47.633636)
		(end 68.82638 -47.633636)
		(width 0.14224)
		(layer "In11.Cu")
		(net "M_J_DQS_DN<2>")
	)
	(segment
		(start 68.152772 -46.960028)
		(end 68.332604 -47.13986)
		(width 0.14224)
		(layer "In11.Cu")
		(net "M_J_DQS_DN<2>")
	)
	(segment
		(start 55.201312 -4.15036)
		(end 55.201312 -4.5466)
		(width 0.14224)
		(layer "In11.Cu")
		(net "M_J_DQS_DN<2>")
	)
	(segment
		(start 76.6064 -55.494936)
		(end 76.639166 -55.494936)
		(width 0.0889)
		(layer "In11.Cu")
		(net "M_J_DQS_DN<2>")
	)
	(segment
		(start 75.75169 -54.99989)
		(end 75.784456 -54.99989)
		(width 0.0889)
		(layer "In11.Cu")
		(net "M_J_DQS_DN<2>")
	)
	(segment
		(start 71.988426 -52.40782)
		(end 71.982076 -52.418488)
		(width 0.0889)
		(layer "In11.Cu")
		(net "M_J_DQS_DN<2>")
	)
	(segment
		(start 73.17232 -53.513736)
		(end 73.205086 -53.513736)
		(width 0.0889)
		(layer "In11.Cu")
		(net "M_J_DQS_DN<2>")
	)
	(segment
		(start 54.688232 -5.05968)
		(end 54.688232 -5.280152)
		(width 0.14224)
		(layer "In11.Cu")
		(net "M_J_DQS_DN<2>")
	)
	(segment
		(start 69.006212 -47.975266)
		(end 69.30263 -48.271684)
		(width 0.14224)
		(layer "In11.Cu")
		(net "M_J_DQS_DN<2>")
	)
	(segment
		(start 55.548276 1.033272)
		(end 55.548276 -2.875788)
		(width 0.14224)
		(layer "In11.Cu")
		(net "M_J_DQS_DN<2>")
	)
	(segment
		(start 74.88936 -54.504336)
		(end 74.922126 -54.504336)
		(width 0.0889)
		(layer "In11.Cu")
		(net "M_J_DQS_DN<2>")
	)
	(segment
		(start 69.30263 -48.271684)
		(end 70.892162 -49.552352)
		(width 0.14224)
		(layer "In11.Cu")
		(net "M_J_DQS_DN<2>")
	)
	(segment
		(start 55.201312 -4.5466)
		(end 54.688232 -5.05968)
		(width 0.14224)
		(layer "In11.Cu")
		(net "M_J_DQS_DN<2>")
	)
	(segment
		(start 71.42353 -50.139346)
		(end 71.8058 -50.521616)
		(width 0.0889)
		(layer "In11.Cu")
		(net "M_J_DQS_DN<2>")
	)
	(segment
		(start 55.337964 -5.70738)
		(end 55.337964 -5.929884)
		(width 0.14224)
		(layer "In11.Cu")
		(net "M_J_DQS_DN<2>")
	)
	(segment
		(start 71.8058 -50.521616)
		(end 71.988426 -50.848006)
		(width 0.0889)
		(layer "In11.Cu")
		(net "M_J_DQS_DN<2>")
	)
	(segment
		(start 55.548276 -2.875788)
		(end 54.737508 -3.686556)
		(width 0.14224)
		(layer "In11.Cu")
		(net "M_J_DQS_DN<2>")
	)
	(segment
		(start 81.45526 -58.798968)
		(end 81.479136 -58.888376)
		(width 0.0889)
		(layer "In11.Cu")
		(net "M_J_DQS_DN<2>")
	)
	(segment
		(start 54.688232 -5.280152)
		(end 54.935628 -5.527548)
		(width 0.14224)
		(layer "In11.Cu")
		(net "M_J_DQS_DN<2>")
	)
	(segment
		(start 71.97725 -51.819302)
		(end 71.982076 -51.827938)
		(width 0.0889)
		(layer "In11.Cu")
		(net "M_J_DQS_DN<2>")
	)
	(segment
		(start 69.006212 -47.813468)
		(end 69.006212 -47.975266)
		(width 0.14224)
		(layer "In11.Cu")
		(net "M_J_DQS_DN<2>")
	)
	(segment
		(start 80.895698 -57.971436)
		(end 80.931512 -57.971436)
		(width 0.0889)
		(layer "In11.Cu")
		(net "M_J_DQS_DN<2>")
	)
	(segment
		(start 68.82638 -47.633636)
		(end 69.006212 -47.813468)
		(width 0.14224)
		(layer "In11.Cu")
		(net "M_J_DQS_DN<2>")
	)
	(segment
		(start 77.991716 -56.285384)
		(end 77.995018 -56.291226)
		(width 0.0889)
		(layer "In11.Cu")
		(net "M_J_DQS_DN<2>")
	)
	(segment
		(start 68.332604 -47.13986)
		(end 68.332604 -47.301658)
		(width 0.14224)
		(layer "In11.Cu")
		(net "M_J_DQS_DN<2>")
	)
	(segment
		(start 55.337964 -5.929884)
		(end 55.677308 -6.269228)
		(width 0.14224)
		(layer "In11.Cu")
		(net "M_J_DQS_DN<2>")
	)
	(segment
		(start 54.737508 1.84404)
		(end 55.548276 1.033272)
		(width 0.14224)
		(layer "In11.Cu")
		(net "M_J_DQS_DN<2>")
	)
	(segment
		(start 79.185516 -56.98109)
		(end 79.218282 -56.98109)
		(width 0.0889)
		(layer "In11.Cu")
		(net "M_J_DQS_DN<2>")
	)
	(segment
		(start 55.519828 -33.501838)
		(end 67.697096 -45.679106)
		(width 0.14224)
		(layer "In11.Cu")
		(net "M_J_DQS_DN<2>")
	)
	(segment
		(start 80.040226 -57.476136)
		(end 80.068166 -57.476136)
		(width 0.0889)
		(layer "In11.Cu")
		(net "M_J_DQS_DN<2>")
	)
	(segment
		(start 55.677308 -6.269228)
		(end 55.677308 -6.480556)
		(width 0.14224)
		(layer "In11.Cu")
		(net "M_J_DQS_DN<2>")
	)
	(segment
		(start 67.697096 -46.66615)
		(end 67.990974 -46.960028)
		(width 0.14224)
		(layer "In11.Cu")
		(net "M_J_DQS_DN<2>")
	)
	(segment
		(start 71.407782 -50.068226)
		(end 71.42353 -50.083974)
		(width 0.0889)
		(layer "In11.Cu")
		(net "M_J_DQS_DN<2>")
	)
	(segment
		(start 77.46873 -55.99049)
		(end 77.504798 -55.99049)
		(width 0.0889)
		(layer "In11.Cu")
		(net "M_J_DQS_DN<2>")
	)
	(segment
		(start 74.03465 -54.00929)
		(end 74.067416 -54.00929)
		(width 0.0889)
		(layer "In11.Cu")
		(net "M_J_DQS_DN<2>")
	)
	(segment
		(start 54.737508 -3.686556)
		(end 55.201312 -4.15036)
		(width 0.14224)
		(layer "In11.Cu")
		(net "M_J_DQS_DN<2>")
	)
	(segment
		(start 54.935628 -5.527548)
		(end 55.158132 -5.527548)
		(width 0.14224)
		(layer "In11.Cu")
		(net "M_J_DQS_DN<2>")
	)
	(segment
		(start 70.892162 -49.552352)
		(end 71.407782 -50.068226)
		(width 0.14224)
		(layer "In11.Cu")
		(net "M_J_DQS_DN<2>")
	)
	(segment
		(start 67.697096 -45.679106)
		(end 67.697096 -46.66615)
		(width 0.14224)
		(layer "In11.Cu")
		(net "M_J_DQS_DN<2>")
	)
	(arc
		(start 76.274676 -55.295038)
		(mid 76.414755 -55.437774)
		(end 76.6064 -55.494936)
		(width 0.0889)
		(layer "In11.Cu")
		(net "M_J_DQS_DN<2>")
	)
	(arc
		(start 80.931512 -57.971436)
		(mid 81.413223 -58.246045)
		(end 81.45526 -58.798968)
		(width 0.0889)
		(layer "In11.Cu")
		(net "M_J_DQS_DN<2>")
	)
	(arc
		(start 72.34174 -53.018436)
		(mid 72.629885 -53.100755)
		(end 72.840596 -53.313838)
		(width 0.0889)
		(layer "In11.Cu")
		(net "M_J_DQS_DN<2>")
	)
	(arc
		(start 80.567022 -57.771538)
		(mid 80.705766 -57.913571)
		(end 80.895698 -57.971436)
		(width 0.0889)
		(layer "In11.Cu")
		(net "M_J_DQS_DN<2>")
	)
	(arc
		(start 77.504798 -55.99049)
		(mid 77.786098 -56.075456)
		(end 77.991716 -56.285384)
		(width 0.0889)
		(layer "In11.Cu")
		(net "M_J_DQS_DN<2>")
	)
	(arc
		(start 71.982076 -51.827938)
		(mid 72.061298 -52.117056)
		(end 71.988426 -52.40782)
		(width 0.0889)
		(layer "In11.Cu")
		(net "M_J_DQS_DN<2>")
	)
	(arc
		(start 78.355952 -56.485536)
		(mid 78.641376 -56.569003)
		(end 78.849982 -56.780938)
		(width 0.0889)
		(layer "In11.Cu")
		(net "M_J_DQS_DN<2>")
	)
	(arc
		(start 77.133196 -55.790338)
		(mid 77.274879 -55.934142)
		(end 77.46873 -55.99049)
		(width 0.0889)
		(layer "In11.Cu")
		(net "M_J_DQS_DN<2>")
	)
	(arc
		(start 73.699116 -53.809138)
		(mid 73.840799 -53.952942)
		(end 74.03465 -54.00929)
		(width 0.0889)
		(layer "In11.Cu")
		(net "M_J_DQS_DN<2>")
	)
	(arc
		(start 74.557636 -54.304438)
		(mid 74.697715 -54.447174)
		(end 74.88936 -54.504336)
		(width 0.0889)
		(layer "In11.Cu")
		(net "M_J_DQS_DN<2>")
	)
	(arc
		(start 71.982076 -51.427888)
		(mid 71.928606 -51.622951)
		(end 71.97725 -51.819302)
		(width 0.0889)
		(layer "In11.Cu")
		(net "M_J_DQS_DN<2>")
	)
	(arc
		(start 76.639166 -55.494936)
		(mid 76.92459 -55.578403)
		(end 77.133196 -55.790338)
		(width 0.0889)
		(layer "In11.Cu")
		(net "M_J_DQS_DN<2>")
	)
	(arc
		(start 74.067416 -54.00929)
		(mid 74.350633 -54.093571)
		(end 74.557636 -54.304438)
		(width 0.0889)
		(layer "In11.Cu")
		(net "M_J_DQS_DN<2>")
	)
	(arc
		(start 79.708502 -57.276238)
		(mid 79.848581 -57.418974)
		(end 80.040226 -57.476136)
		(width 0.0889)
		(layer "In11.Cu")
		(net "M_J_DQS_DN<2>")
	)
	(arc
		(start 75.784456 -54.99989)
		(mid 76.067673 -55.084171)
		(end 76.274676 -55.295038)
		(width 0.0889)
		(layer "In11.Cu")
		(net "M_J_DQS_DN<2>")
	)
	(arc
		(start 72.840596 -53.313838)
		(mid 72.980675 -53.456574)
		(end 73.17232 -53.513736)
		(width 0.0889)
		(layer "In11.Cu")
		(net "M_J_DQS_DN<2>")
	)
	(arc
		(start 78.849982 -56.780938)
		(mid 78.991665 -56.924742)
		(end 79.185516 -56.98109)
		(width 0.0889)
		(layer "In11.Cu")
		(net "M_J_DQS_DN<2>")
	)
	(arc
		(start 77.995018 -56.291226)
		(mid 78.140984 -56.433625)
		(end 78.338172 -56.485536)
		(width 0.0889)
		(layer "In11.Cu")
		(net "M_J_DQS_DN<2>")
	)
	(arc
		(start 71.988426 -50.848006)
		(mid 72.061224 -51.138769)
		(end 71.982076 -51.427888)
		(width 0.0889)
		(layer "In11.Cu")
		(net "M_J_DQS_DN<2>")
	)
	(arc
		(start 74.922126 -54.504336)
		(mid 75.20755 -54.587803)
		(end 75.416156 -54.799738)
		(width 0.0889)
		(layer "In11.Cu")
		(net "M_J_DQS_DN<2>")
	)
	(arc
		(start 73.205086 -53.513736)
		(mid 73.49051 -53.597203)
		(end 73.699116 -53.809138)
		(width 0.0889)
		(layer "In11.Cu")
		(net "M_J_DQS_DN<2>")
	)
	(arc
		(start 79.218282 -56.98109)
		(mid 79.501499 -57.065371)
		(end 79.708502 -57.276238)
		(width 0.0889)
		(layer "In11.Cu")
		(net "M_J_DQS_DN<2>")
	)
	(arc
		(start 80.068166 -57.476136)
		(mid 80.356311 -57.558455)
		(end 80.567022 -57.771538)
		(width 0.0889)
		(layer "In11.Cu")
		(net "M_J_DQS_DN<2>")
	)
	(arc
		(start 71.982076 -52.418488)
		(mid 71.979493 -52.813735)
		(end 72.31761 -53.018436)
		(width 0.0889)
		(layer "In11.Cu")
		(net "M_J_DQS_DN<2>")
	)
	(arc
		(start 75.416156 -54.799738)
		(mid 75.557839 -54.943542)
		(end 75.75169 -54.99989)
		(width 0.0889)
		(layer "In11.Cu")
		(net "M_J_DQS_DN<2>")
	)
	(segment
		(start 44.999402 0.19177)
		(end 44.733718 0.457454)
		(width 0.1651)
		(layer "F.Cu")
		(net "M_J_DQS_DN<1>")
	)
	(segment
		(start 44.733718 1.190244)
		(end 45.387514 1.84404)
		(width 0.1651)
		(layer "F.Cu")
		(net "M_J_DQS_DN<1>")
	)
	(segment
		(start 44.999402 -0.821182)
		(end 44.999402 0.19177)
		(width 0.1651)
		(layer "F.Cu")
		(net "M_J_DQS_DN<1>")
	)
	(segment
		(start 78.051406 -59.55284)
		(end 77.479906 -59.55284)
		(width 0.0889)
		(layer "F.Cu")
		(net "M_J_DQS_DN<1>")
	)
	(segment
		(start 44.733718 0.457454)
		(end 44.733718 1.190244)
		(width 0.1651)
		(layer "F.Cu")
		(net "M_J_DQS_DN<1>")
	)
	(via
		(at 45.387514 -3.686556)
		(size 0.508)
		(drill 0.254)
		(layers "F.Cu" "B.Cu")
		(net "M_J_DQS_DN<1>")
	)
	(via
		(at 45.387514 1.84404)
		(size 0.508)
		(drill 0.254)
		(layers "F.Cu" "B.Cu")
		(net "M_J_DQS_DN<1>")
	)
	(via
		(at 77.479906 -59.55284)
		(size 0.508)
		(drill 0.254)
		(layers "F.Cu" "B.Cu")
		(net "M_J_DQS_DN<1>")
	)
	(segment
		(start 44.999402 -1.91897)
		(end 44.746418 -2.171954)
		(width 0.1651)
		(layer "B.Cu")
		(net "M_J_DQS_DN<1>")
	)
	(segment
		(start 44.746418 -2.171954)
		(end 44.746418 -3.04546)
		(width 0.1651)
		(layer "B.Cu")
		(net "M_J_DQS_DN<1>")
	)
	(segment
		(start 44.999402 -1.021842)
		(end 44.999402 -1.91897)
		(width 0.1651)
		(layer "B.Cu")
		(net "M_J_DQS_DN<1>")
	)
	(segment
		(start 44.746418 -3.04546)
		(end 45.387514 -3.686556)
		(width 0.1651)
		(layer "B.Cu")
		(net "M_J_DQS_DN<1>")
	)
	(segment
		(start 62.606936 -53.092096)
		(end 62.786768 -53.271928)
		(width 0.14224)
		(layer "In11.Cu")
		(net "M_J_DQS_DN<1>")
	)
	(segment
		(start 61.561726 -52.046886)
		(end 61.741558 -52.226718)
		(width 0.14224)
		(layer "In11.Cu")
		(net "M_J_DQS_DN<1>")
	)
	(segment
		(start 45.585634 -5.527548)
		(end 45.808138 -5.527548)
		(width 0.14224)
		(layer "In11.Cu")
		(net "M_J_DQS_DN<1>")
	)
	(segment
		(start 46.198282 -2.875788)
		(end 45.387514 -3.686556)
		(width 0.14224)
		(layer "In11.Cu")
		(net "M_J_DQS_DN<1>")
	)
	(segment
		(start 65.480692 -55.954168)
		(end 65.493138 -55.966614)
		(width 0.0889)
		(layer "In11.Cu")
		(net "M_J_DQS_DN<1>")
	)
	(segment
		(start 45.077888 -32.948626)
		(end 46.043088 -33.913826)
		(width 0.14224)
		(layer "In11.Cu")
		(net "M_J_DQS_DN<1>")
	)
	(segment
		(start 51.118516 -40.376094)
		(end 51.118516 -40.772334)
		(width 0.14224)
		(layer "In11.Cu")
		(net "M_J_DQS_DN<1>")
	)
	(segment
		(start 64.052958 -54.537864)
		(end 64.23279 -54.717696)
		(width 0.14224)
		(layer "In11.Cu")
		(net "M_J_DQS_DN<1>")
	)
	(segment
		(start 45.98797 -5.929884)
		(end 46.327314 -6.269228)
		(width 0.14224)
		(layer "In11.Cu")
		(net "M_J_DQS_DN<1>")
	)
	(segment
		(start 49.960022 -39.2176)
		(end 51.118516 -40.376094)
		(width 0.14224)
		(layer "In11.Cu")
		(net "M_J_DQS_DN<1>")
	)
	(segment
		(start 45.248576 -30.559756)
		(end 45.563282 -30.559756)
		(width 0.14224)
		(layer "In11.Cu")
		(net "M_J_DQS_DN<1>")
	)
	(segment
		(start 77.097382 -59.69762)
		(end 77.18679 -59.72175)
		(width 0.0889)
		(layer "In11.Cu")
		(net "M_J_DQS_DN<1>")
	)
	(segment
		(start 63.350394 -53.8353)
		(end 63.530226 -54.015132)
		(width 0.14224)
		(layer "In11.Cu")
		(net "M_J_DQS_DN<1>")
	)
	(segment
		(start 65.480692 -55.933848)
		(end 65.480692 -55.954168)
		(width 0.0889)
		(layer "In11.Cu")
		(net "M_J_DQS_DN<1>")
	)
	(segment
		(start 45.338238 -5.280152)
		(end 45.585634 -5.527548)
		(width 0.14224)
		(layer "In11.Cu")
		(net "M_J_DQS_DN<1>")
	)
	(segment
		(start 61.92266 -52.569364)
		(end 62.084458 -52.569364)
		(width 0.14224)
		(layer "In11.Cu")
		(net "M_J_DQS_DN<1>")
	)
	(segment
		(start 77.18679 -59.72175)
		(end 77.479906 -59.55284)
		(width 0.0889)
		(layer "In11.Cu")
		(net "M_J_DQS_DN<1>")
	)
	(segment
		(start 69.029326 -57.47639)
		(end 69.766688 -57.47639)
		(width 0.0889)
		(layer "In11.Cu")
		(net "M_J_DQS_DN<1>")
	)
	(segment
		(start 74.88936 -60.447936)
		(end 74.919332 -60.447936)
		(width 0.0889)
		(layer "In11.Cu")
		(net "M_J_DQS_DN<1>")
	)
	(segment
		(start 62.084458 -52.569364)
		(end 62.26429 -52.749196)
		(width 0.14224)
		(layer "In11.Cu")
		(net "M_J_DQS_DN<1>")
	)
	(segment
		(start 46.043088 -36.392866)
		(end 48.867822 -39.2176)
		(width 0.14224)
		(layer "In11.Cu")
		(net "M_J_DQS_DN<1>")
	)
	(segment
		(start 53.78958 -43.443398)
		(end 53.78958 -44.436284)
		(width 0.14224)
		(layer "In11.Cu")
		(net "M_J_DQS_DN<1>")
	)
	(segment
		(start 45.387514 1.84404)
		(end 46.198282 1.033272)
		(width 0.14224)
		(layer "In11.Cu")
		(net "M_J_DQS_DN<1>")
	)
	(segment
		(start 46.327314 -6.269228)
		(end 46.327314 -6.480556)
		(width 0.14224)
		(layer "In11.Cu")
		(net "M_J_DQS_DN<1>")
	)
	(segment
		(start 62.26429 -52.749196)
		(end 62.26429 -52.910994)
		(width 0.14224)
		(layer "In11.Cu")
		(net "M_J_DQS_DN<1>")
	)
	(segment
		(start 61.741558 -52.226718)
		(end 61.741558 -52.388262)
		(width 0.14224)
		(layer "In11.Cu")
		(net "M_J_DQS_DN<1>")
	)
	(segment
		(start 61.400182 -52.046886)
		(end 61.561726 -52.046886)
		(width 0.14224)
		(layer "In11.Cu")
		(net "M_J_DQS_DN<1>")
	)
	(segment
		(start 46.169834 -26.022808)
		(end 45.027088 -27.165554)
		(width 0.14224)
		(layer "In11.Cu")
		(net "M_J_DQS_DN<1>")
	)
	(segment
		(start 74.03465 -59.95289)
		(end 74.067416 -59.95289)
		(width 0.0889)
		(layer "In11.Cu")
		(net "M_J_DQS_DN<1>")
	)
	(segment
		(start 62.26429 -52.910994)
		(end 62.445392 -53.092096)
		(width 0.14224)
		(layer "In11.Cu")
		(net "M_J_DQS_DN<1>")
	)
	(segment
		(start 65.45834 -55.922672)
		(end 65.469516 -55.922672)
		(width 0.0889)
		(layer "In11.Cu")
		(net "M_J_DQS_DN<1>")
	)
	(segment
		(start 45.077888 -32.396684)
		(end 45.077888 -32.948626)
		(width 0.14224)
		(layer "In11.Cu")
		(net "M_J_DQS_DN<1>")
	)
	(segment
		(start 71.452232 -58.466736)
		(end 71.491856 -58.466736)
		(width 0.0889)
		(layer "In11.Cu")
		(net "M_J_DQS_DN<1>")
	)
	(segment
		(start 75.741276 -59.95289)
		(end 75.774042 -59.95289)
		(width 0.0889)
		(layer "In11.Cu")
		(net "M_J_DQS_DN<1>")
	)
	(segment
		(start 45.027088 -27.165554)
		(end 45.027088 -30.338268)
		(width 0.14224)
		(layer "In11.Cu")
		(net "M_J_DQS_DN<1>")
	)
	(segment
		(start 45.966888 -30.963362)
		(end 45.966888 -31.80715)
		(width 0.14224)
		(layer "In11.Cu")
		(net "M_J_DQS_DN<1>")
	)
	(segment
		(start 45.338238 -5.05968)
		(end 45.338238 -5.280152)
		(width 0.14224)
		(layer "In11.Cu")
		(net "M_J_DQS_DN<1>")
	)
	(segment
		(start 45.299376 -32.175196)
		(end 45.077888 -32.396684)
		(width 0.14224)
		(layer "In11.Cu")
		(net "M_J_DQS_DN<1>")
	)
	(segment
		(start 46.327314 -6.480556)
		(end 46.169834 -6.638036)
		(width 0.14224)
		(layer "In11.Cu")
		(net "M_J_DQS_DN<1>")
	)
	(segment
		(start 46.198282 1.033272)
		(end 46.198282 -2.875788)
		(width 0.14224)
		(layer "In11.Cu")
		(net "M_J_DQS_DN<1>")
	)
	(segment
		(start 65.469516 -55.922672)
		(end 65.480692 -55.933848)
		(width 0.0889)
		(layer "In11.Cu")
		(net "M_J_DQS_DN<1>")
	)
	(segment
		(start 72.31761 -58.962036)
		(end 72.34174 -58.962036)
		(width 0.0889)
		(layer "In11.Cu")
		(net "M_J_DQS_DN<1>")
	)
	(segment
		(start 46.169834 -6.638036)
		(end 46.169834 -26.022808)
		(width 0.14224)
		(layer "In11.Cu")
		(net "M_J_DQS_DN<1>")
	)
	(segment
		(start 45.563282 -30.559756)
		(end 45.966888 -30.963362)
		(width 0.14224)
		(layer "In11.Cu")
		(net "M_J_DQS_DN<1>")
	)
	(segment
		(start 46.043088 -33.913826)
		(end 46.043088 -36.392866)
		(width 0.14224)
		(layer "In11.Cu")
		(net "M_J_DQS_DN<1>")
	)
	(segment
		(start 63.530226 -54.015132)
		(end 63.530226 -54.17693)
		(width 0.14224)
		(layer "In11.Cu")
		(net "M_J_DQS_DN<1>")
	)
	(segment
		(start 63.89116 -54.537864)
		(end 64.052958 -54.537864)
		(width 0.14224)
		(layer "In11.Cu")
		(net "M_J_DQS_DN<1>")
	)
	(segment
		(start 53.78958 -44.436284)
		(end 61.400182 -52.046886)
		(width 0.14224)
		(layer "In11.Cu")
		(net "M_J_DQS_DN<1>")
	)
	(segment
		(start 65.493138 -55.966614)
		(end 67.51955 -55.966614)
		(width 0.0889)
		(layer "In11.Cu")
		(net "M_J_DQS_DN<1>")
	)
	(segment
		(start 63.188596 -53.8353)
		(end 63.350394 -53.8353)
		(width 0.14224)
		(layer "In11.Cu")
		(net "M_J_DQS_DN<1>")
	)
	(segment
		(start 45.966888 -31.80715)
		(end 45.598842 -32.175196)
		(width 0.14224)
		(layer "In11.Cu")
		(net "M_J_DQS_DN<1>")
	)
	(segment
		(start 73.17232 -59.457336)
		(end 73.205086 -59.457336)
		(width 0.0889)
		(layer "In11.Cu")
		(net "M_J_DQS_DN<1>")
	)
	(segment
		(start 69.766688 -57.47639)
		(end 69.76618 -57.476136)
		(width 0.0889)
		(layer "In11.Cu")
		(net "M_J_DQS_DN<1>")
	)
	(segment
		(start 45.808138 -5.527548)
		(end 45.98797 -5.70738)
		(width 0.14224)
		(layer "In11.Cu")
		(net "M_J_DQS_DN<1>")
	)
	(segment
		(start 45.027088 -30.338268)
		(end 45.248576 -30.559756)
		(width 0.14224)
		(layer "In11.Cu")
		(net "M_J_DQS_DN<1>")
	)
	(segment
		(start 45.98797 -5.70738)
		(end 45.98797 -5.929884)
		(width 0.14224)
		(layer "In11.Cu")
		(net "M_J_DQS_DN<1>")
	)
	(segment
		(start 65.275968 -55.922672)
		(end 65.45834 -55.922672)
		(width 0.14224)
		(layer "In11.Cu")
		(net "M_J_DQS_DN<1>")
	)
	(segment
		(start 51.118516 -40.772334)
		(end 53.78958 -43.443398)
		(width 0.14224)
		(layer "In11.Cu")
		(net "M_J_DQS_DN<1>")
	)
	(segment
		(start 62.445392 -53.092096)
		(end 62.606936 -53.092096)
		(width 0.14224)
		(layer "In11.Cu")
		(net "M_J_DQS_DN<1>")
	)
	(segment
		(start 70.593712 -57.971436)
		(end 70.629526 -57.971436)
		(width 0.0889)
		(layer "In11.Cu")
		(net "M_J_DQS_DN<1>")
	)
	(segment
		(start 48.867822 -39.2176)
		(end 49.960022 -39.2176)
		(width 0.14224)
		(layer "In11.Cu")
		(net "M_J_DQS_DN<1>")
	)
	(segment
		(start 61.741558 -52.388262)
		(end 61.92266 -52.569364)
		(width 0.14224)
		(layer "In11.Cu")
		(net "M_J_DQS_DN<1>")
	)
	(segment
		(start 64.23279 -54.879494)
		(end 65.275968 -55.922672)
		(width 0.14224)
		(layer "In11.Cu")
		(net "M_J_DQS_DN<1>")
	)
	(segment
		(start 62.786768 -53.271928)
		(end 62.786768 -53.433472)
		(width 0.14224)
		(layer "In11.Cu")
		(net "M_J_DQS_DN<1>")
	)
	(segment
		(start 45.851318 -4.5466)
		(end 45.338238 -5.05968)
		(width 0.14224)
		(layer "In11.Cu")
		(net "M_J_DQS_DN<1>")
	)
	(segment
		(start 62.786768 -53.433472)
		(end 63.188596 -53.8353)
		(width 0.14224)
		(layer "In11.Cu")
		(net "M_J_DQS_DN<1>")
	)
	(segment
		(start 45.598842 -32.175196)
		(end 45.299376 -32.175196)
		(width 0.14224)
		(layer "In11.Cu")
		(net "M_J_DQS_DN<1>")
	)
	(segment
		(start 64.23279 -54.717696)
		(end 64.23279 -54.879494)
		(width 0.14224)
		(layer "In11.Cu")
		(net "M_J_DQS_DN<1>")
	)
	(segment
		(start 67.51955 -55.966614)
		(end 69.029326 -57.47639)
		(width 0.0889)
		(layer "In11.Cu")
		(net "M_J_DQS_DN<1>")
	)
	(segment
		(start 63.530226 -54.17693)
		(end 63.89116 -54.537864)
		(width 0.14224)
		(layer "In11.Cu")
		(net "M_J_DQS_DN<1>")
	)
	(segment
		(start 45.387514 -3.686556)
		(end 45.851318 -4.15036)
		(width 0.14224)
		(layer "In11.Cu")
		(net "M_J_DQS_DN<1>")
	)
	(segment
		(start 45.851318 -4.15036)
		(end 45.851318 -4.5466)
		(width 0.14224)
		(layer "In11.Cu")
		(net "M_J_DQS_DN<1>")
	)
	(arc
		(start 75.251056 -60.248038)
		(mid 75.45806 -60.037174)
		(end 75.741276 -59.95289)
		(width 0.0889)
		(layer "In11.Cu")
		(net "M_J_DQS_DN<1>")
	)
	(arc
		(start 70.629526 -57.971436)
		(mid 70.91495 -58.054903)
		(end 71.123556 -58.266838)
		(width 0.0889)
		(layer "In11.Cu")
		(net "M_J_DQS_DN<1>")
	)
	(arc
		(start 71.982076 -58.761884)
		(mid 72.123759 -58.905688)
		(end 72.31761 -58.962036)
		(width 0.0889)
		(layer "In11.Cu")
		(net "M_J_DQS_DN<1>")
	)
	(arc
		(start 72.840596 -59.257438)
		(mid 72.980675 -59.400174)
		(end 73.17232 -59.457336)
		(width 0.0889)
		(layer "In11.Cu")
		(net "M_J_DQS_DN<1>")
	)
	(arc
		(start 74.067416 -59.95289)
		(mid 74.350633 -60.037171)
		(end 74.557636 -60.248038)
		(width 0.0889)
		(layer "In11.Cu")
		(net "M_J_DQS_DN<1>")
	)
	(arc
		(start 74.919332 -60.447936)
		(mid 75.110974 -60.39077)
		(end 75.251056 -60.248038)
		(width 0.0889)
		(layer "In11.Cu")
		(net "M_J_DQS_DN<1>")
	)
	(arc
		(start 71.123556 -58.266838)
		(mid 71.2623 -58.408871)
		(end 71.452232 -58.466736)
		(width 0.0889)
		(layer "In11.Cu")
		(net "M_J_DQS_DN<1>")
	)
	(arc
		(start 69.76618 -57.476136)
		(mid 70.054325 -57.558455)
		(end 70.265036 -57.771538)
		(width 0.0889)
		(layer "In11.Cu")
		(net "M_J_DQS_DN<1>")
	)
	(arc
		(start 73.205086 -59.457336)
		(mid 73.49051 -59.540803)
		(end 73.699116 -59.752738)
		(width 0.0889)
		(layer "In11.Cu")
		(net "M_J_DQS_DN<1>")
	)
	(arc
		(start 72.34174 -58.962036)
		(mid 72.629885 -59.044355)
		(end 72.840596 -59.257438)
		(width 0.0889)
		(layer "In11.Cu")
		(net "M_J_DQS_DN<1>")
	)
	(arc
		(start 75.774042 -59.95289)
		(mid 75.967892 -59.89654)
		(end 76.109576 -59.752738)
		(width 0.0889)
		(layer "In11.Cu")
		(net "M_J_DQS_DN<1>")
	)
	(arc
		(start 73.699116 -59.752738)
		(mid 73.840799 -59.896542)
		(end 74.03465 -59.95289)
		(width 0.0889)
		(layer "In11.Cu")
		(net "M_J_DQS_DN<1>")
	)
	(arc
		(start 70.265036 -57.771538)
		(mid 70.40378 -57.913571)
		(end 70.593712 -57.971436)
		(width 0.0889)
		(layer "In11.Cu")
		(net "M_J_DQS_DN<1>")
	)
	(arc
		(start 74.557636 -60.248038)
		(mid 74.697715 -60.390774)
		(end 74.88936 -60.447936)
		(width 0.0889)
		(layer "In11.Cu")
		(net "M_J_DQS_DN<1>")
	)
	(arc
		(start 76.109576 -59.752738)
		(mid 76.588525 -59.457986)
		(end 77.097382 -59.69762)
		(width 0.0889)
		(layer "In11.Cu")
		(net "M_J_DQS_DN<1>")
	)
	(arc
		(start 71.491856 -58.466736)
		(mid 71.775073 -58.551017)
		(end 71.982076 -58.761884)
		(width 0.0889)
		(layer "In11.Cu")
		(net "M_J_DQS_DN<1>")
	)
	(segment
		(start 73.049384 3.778758)
		(end 73.049384 2.93624)
		(width 0.1651)
		(layer "F.Cu")
		(net "M_J_DQS_DN<17>")
	)
	(segment
		(start 72.6313 2.286)
		(end 72.817228 2.100072)
		(width 0.1651)
		(layer "F.Cu")
		(net "M_J_DQS_DN<17>")
	)
	(segment
		(start 72.817228 2.100072)
		(end 72.817228 1.853438)
		(width 0.1651)
		(layer "F.Cu")
		(net "M_J_DQS_DN<17>")
	)
	(segment
		(start 72.817228 1.853438)
		(end 72.56526 1.60147)
		(width 0.1651)
		(layer "F.Cu")
		(net "M_J_DQS_DN<17>")
	)
	(segment
		(start 72.56526 1.60147)
		(end 72.35698 1.60147)
		(width 0.1651)
		(layer "F.Cu")
		(net "M_J_DQS_DN<17>")
	)
	(segment
		(start 80.626712 -66.982086)
		(end 80.055212 -66.982086)
		(width 0.0889)
		(layer "F.Cu")
		(net "M_J_DQS_DN<17>")
	)
	(segment
		(start 72.35698 1.60147)
		(end 72.16775 1.7907)
		(width 0.1651)
		(layer "F.Cu")
		(net "M_J_DQS_DN<17>")
	)
	(segment
		(start 72.6313 2.518156)
		(end 72.6313 2.286)
		(width 0.1651)
		(layer "F.Cu")
		(net "M_J_DQS_DN<17>")
	)
	(segment
		(start 72.16775 1.7907)
		(end 72.1487 1.7907)
		(width 0.1651)
		(layer "F.Cu")
		(net "M_J_DQS_DN<17>")
	)
	(segment
		(start 73.049384 2.93624)
		(end 72.6313 2.518156)
		(width 0.1651)
		(layer "F.Cu")
		(net "M_J_DQS_DN<17>")
	)
	(via
		(at 72.1487 1.7907)
		(size 0.508)
		(drill 0.254)
		(layers "F.Cu" "B.Cu")
		(net "M_J_DQS_DN<17>")
	)
	(via
		(at 72.142096 -3.6322)
		(size 0.508)
		(drill 0.254)
		(layers "F.Cu" "B.Cu")
		(net "M_J_DQS_DN<17>")
	)
	(via
		(at 80.055212 -66.982086)
		(size 0.508)
		(drill 0.254)
		(layers "F.Cu" "B.Cu")
		(net "M_J_DQS_DN<17>")
	)
	(segment
		(start 72.7837 -3.6576)
		(end 72.563736 -3.437636)
		(width 0.1651)
		(layer "B.Cu")
		(net "M_J_DQS_DN<17>")
	)
	(segment
		(start 72.7837 -3.9878)
		(end 72.7837 -3.6576)
		(width 0.1651)
		(layer "B.Cu")
		(net "M_J_DQS_DN<17>")
	)
	(segment
		(start 72.563736 -3.437636)
		(end 72.33666 -3.437636)
		(width 0.1651)
		(layer "B.Cu")
		(net "M_J_DQS_DN<17>")
	)
	(segment
		(start 72.6059 -4.521454)
		(end 72.6059 -4.1656)
		(width 0.1651)
		(layer "B.Cu")
		(net "M_J_DQS_DN<17>")
	)
	(segment
		(start 73.049384 -5.621782)
		(end 73.049384 -4.964938)
		(width 0.1651)
		(layer "B.Cu")
		(net "M_J_DQS_DN<17>")
	)
	(segment
		(start 72.33666 -3.437636)
		(end 72.142096 -3.6322)
		(width 0.1651)
		(layer "B.Cu")
		(net "M_J_DQS_DN<17>")
	)
	(segment
		(start 72.6059 -4.1656)
		(end 72.7837 -3.9878)
		(width 0.1651)
		(layer "B.Cu")
		(net "M_J_DQS_DN<17>")
	)
	(segment
		(start 73.049384 -4.964938)
		(end 72.6059 -4.521454)
		(width 0.1651)
		(layer "B.Cu")
		(net "M_J_DQS_DN<17>")
	)
	(segment
		(start 79.708502 -60.838588)
		(end 79.714852 -60.82792)
		(width 0.0889)
		(layer "In4.Cu")
		(net "M_J_DQS_DN<17>")
	)
	(segment
		(start 80.003142 -47.975774)
		(end 79.841598 -47.81423)
		(width 0.14224)
		(layer "In4.Cu")
		(net "M_J_DQS_DN<17>")
	)
	(segment
		(start 74.333608 -34.411412)
		(end 74.333608 -33.967928)
		(width 0.14224)
		(layer "In4.Cu")
		(net "M_J_DQS_DN<17>")
	)
	(segment
		(start 79.703676 -59.856624)
		(end 79.708502 -59.847988)
		(width 0.0889)
		(layer "In4.Cu")
		(net "M_J_DQS_DN<17>")
	)
	(segment
		(start 77.97419 -45.946822)
		(end 77.803756 -45.776388)
		(width 0.14224)
		(layer "In4.Cu")
		(net "M_J_DQS_DN<17>")
	)
	(segment
		(start 73.081896 -15.0622)
		(end 72.924416 -14.90472)
		(width 0.14224)
		(layer "In4.Cu")
		(net "M_J_DQS_DN<17>")
	)
	(segment
		(start 80.003142 -49.3395)
		(end 80.003142 -49.0347)
		(width 0.14224)
		(layer "In4.Cu")
		(net "M_J_DQS_DN<17>")
	)
	(segment
		(start 79.703676 -64.809624)
		(end 79.708502 -64.800988)
		(width 0.0889)
		(layer "In4.Cu")
		(net "M_J_DQS_DN<17>")
	)
	(segment
		(start 72.924416 -15.47368)
		(end 73.081896 -15.3162)
		(width 0.14224)
		(layer "In4.Cu")
		(net "M_J_DQS_DN<17>")
	)
	(segment
		(start 80.003142 -49.361598)
		(end 80.003142 -49.3395)
		(width 0.0889)
		(layer "In4.Cu")
		(net "M_J_DQS_DN<17>")
	)
	(segment
		(start 78.818486 -46.611286)
		(end 78.656942 -46.449742)
		(width 0.14224)
		(layer "In4.Cu")
		(net "M_J_DQS_DN<17>")
	)
	(segment
		(start 79.953612 -52.683156)
		(end 80.071722 -52.565046)
		(width 0.0889)
		(layer "In4.Cu")
		(net "M_J_DQS_DN<17>")
	)
	(segment
		(start 79.708502 -62.819788)
		(end 79.714852 -62.80912)
		(width 0.0889)
		(layer "In4.Cu")
		(net "M_J_DQS_DN<17>")
	)
	(segment
		(start 79.500222 -47.472854)
		(end 79.321406 -47.294038)
		(width 0.14224)
		(layer "In4.Cu")
		(net "M_J_DQS_DN<17>")
	)
	(segment
		(start 79.708502 -59.847988)
		(end 79.714852 -59.83732)
		(width 0.0889)
		(layer "In4.Cu")
		(net "M_J_DQS_DN<17>")
	)
	(segment
		(start 77.803756 -45.596556)
		(end 77.642212 -45.435012)
		(width 0.14224)
		(layer "In4.Cu")
		(net "M_J_DQS_DN<17>")
	)
	(segment
		(start 79.708502 -61.829188)
		(end 79.714852 -61.81852)
		(width 0.0889)
		(layer "In4.Cu")
		(net "M_J_DQS_DN<17>")
	)
	(segment
		(start 75.705208 -43.67784)
		(end 75.705208 -34.808668)
		(width 0.14224)
		(layer "In4.Cu")
		(net "M_J_DQS_DN<17>")
	)
	(segment
		(start 72.3773 -4.8006)
		(end 72.5805 -4.5974)
		(width 0.14224)
		(layer "In4.Cu")
		(net "M_J_DQS_DN<17>")
	)
	(segment
		(start 71.94042 -4.98348)
		(end 72.1233 -4.8006)
		(width 0.14224)
		(layer "In4.Cu")
		(net "M_J_DQS_DN<17>")
	)
	(segment
		(start 72.5805 -4.5974)
		(end 72.5805 -4.070604)
		(width 0.14224)
		(layer "In4.Cu")
		(net "M_J_DQS_DN<17>")
	)
	(segment
		(start 80.130142 -48.9077)
		(end 80.130142 -48.6791)
		(width 0.14224)
		(layer "In4.Cu")
		(net "M_J_DQS_DN<17>")
	)
	(segment
		(start 74.453496 -33.84804)
		(end 75.42784 -33.84804)
		(width 0.14224)
		(layer "In4.Cu")
		(net "M_J_DQS_DN<17>")
	)
	(segment
		(start 79.963772 -51.76266)
		(end 79.963772 -49.400968)
		(width 0.0889)
		(layer "In4.Cu")
		(net "M_J_DQS_DN<17>")
	)
	(segment
		(start 79.703676 -54.903624)
		(end 79.708502 -54.894988)
		(width 0.0889)
		(layer "In4.Cu")
		(net "M_J_DQS_DN<17>")
	)
	(segment
		(start 79.703676 -63.819024)
		(end 79.708502 -63.810388)
		(width 0.0889)
		(layer "In4.Cu")
		(net "M_J_DQS_DN<17>")
	)
	(segment
		(start 76.95946 -44.932092)
		(end 76.797916 -44.770548)
		(width 0.14224)
		(layer "In4.Cu")
		(net "M_J_DQS_DN<17>")
	)
	(segment
		(start 79.653892 -52.862988)
		(end 79.833724 -52.683156)
		(width 0.0889)
		(layer "In4.Cu")
		(net "M_J_DQS_DN<17>")
	)
	(segment
		(start 78.47711 -46.449742)
		(end 78.315566 -46.288198)
		(width 0.14224)
		(layer "In4.Cu")
		(net "M_J_DQS_DN<17>")
	)
	(segment
		(start 78.315566 -46.288198)
		(end 78.315566 -46.108366)
		(width 0.14224)
		(layer "In4.Cu")
		(net "M_J_DQS_DN<17>")
	)
	(segment
		(start 78.154022 -45.946822)
		(end 77.97419 -45.946822)
		(width 0.14224)
		(layer "In4.Cu")
		(net "M_J_DQS_DN<17>")
	)
	(segment
		(start 79.708502 -65.791588)
		(end 79.714852 -65.78092)
		(width 0.0889)
		(layer "In4.Cu")
		(net "M_J_DQS_DN<17>")
	)
	(segment
		(start 78.818486 -46.791118)
		(end 78.818486 -46.611286)
		(width 0.14224)
		(layer "In4.Cu")
		(net "M_J_DQS_DN<17>")
	)
	(segment
		(start 72.1233 -4.8006)
		(end 72.3773 -4.8006)
		(width 0.14224)
		(layer "In4.Cu")
		(net "M_J_DQS_DN<17>")
	)
	(segment
		(start 80.071722 -51.87061)
		(end 79.963772 -51.76266)
		(width 0.0889)
		(layer "In4.Cu")
		(net "M_J_DQS_DN<17>")
	)
	(segment
		(start 73.081896 -14.3002)
		(end 72.924416 -14.14272)
		(width 0.14224)
		(layer "In4.Cu")
		(net "M_J_DQS_DN<17>")
	)
	(segment
		(start 79.321406 -47.114206)
		(end 79.159862 -46.952662)
		(width 0.14224)
		(layer "In4.Cu")
		(net "M_J_DQS_DN<17>")
	)
	(segment
		(start 79.708502 -53.313838)
		(end 79.653892 -53.219096)
		(width 0.0889)
		(layer "In4.Cu")
		(net "M_J_DQS_DN<17>")
	)
	(segment
		(start 71.94042 -5.478272)
		(end 71.94042 -4.98348)
		(width 0.14224)
		(layer "In4.Cu")
		(net "M_J_DQS_DN<17>")
	)
	(segment
		(start 72.924416 -14.14272)
		(end 72.924416 -6.462268)
		(width 0.14224)
		(layer "In4.Cu")
		(net "M_J_DQS_DN<17>")
	)
	(segment
		(start 77.803756 -45.776388)
		(end 77.803756 -45.596556)
		(width 0.14224)
		(layer "In4.Cu")
		(net "M_J_DQS_DN<17>")
	)
	(segment
		(start 80.071722 -52.565046)
		(end 80.071722 -51.87061)
		(width 0.0889)
		(layer "In4.Cu")
		(net "M_J_DQS_DN<17>")
	)
	(segment
		(start 79.703676 -60.847224)
		(end 79.708502 -60.838588)
		(width 0.0889)
		(layer "In4.Cu")
		(net "M_J_DQS_DN<17>")
	)
	(segment
		(start 79.159862 -46.952662)
		(end 78.98003 -46.952662)
		(width 0.14224)
		(layer "In4.Cu")
		(net "M_J_DQS_DN<17>")
	)
	(segment
		(start 75.705208 -34.808668)
		(end 75.42784 -34.5313)
		(width 0.14224)
		(layer "In4.Cu")
		(net "M_J_DQS_DN<17>")
	)
	(segment
		(start 80.055212 -66.982086)
		(end 80.053434 -66.978276)
		(width 0.0889)
		(layer "In4.Cu")
		(net "M_J_DQS_DN<17>")
	)
	(segment
		(start 77.46238 -45.435012)
		(end 77.300836 -45.273468)
		(width 0.14224)
		(layer "In4.Cu")
		(net "M_J_DQS_DN<17>")
	)
	(segment
		(start 80.130142 -48.6791)
		(end 80.003142 -48.5521)
		(width 0.14224)
		(layer "In4.Cu")
		(net "M_J_DQS_DN<17>")
	)
	(segment
		(start 75.42784 -33.84804)
		(end 75.705208 -33.570672)
		(width 0.14224)
		(layer "In4.Cu")
		(net "M_J_DQS_DN<17>")
	)
	(segment
		(start 79.653892 -53.219096)
		(end 79.653892 -52.862988)
		(width 0.0889)
		(layer "In4.Cu")
		(net "M_J_DQS_DN<17>")
	)
	(segment
		(start 79.708502 -56.876188)
		(end 79.714852 -56.86552)
		(width 0.0889)
		(layer "In4.Cu")
		(net "M_J_DQS_DN<17>")
	)
	(segment
		(start 80.003142 -48.5521)
		(end 80.003142 -47.975774)
		(width 0.14224)
		(layer "In4.Cu")
		(net "M_J_DQS_DN<17>")
	)
	(segment
		(start 77.300836 -45.273468)
		(end 77.300836 -45.093636)
		(width 0.14224)
		(layer "In4.Cu")
		(net "M_J_DQS_DN<17>")
	)
	(segment
		(start 78.315566 -46.108366)
		(end 78.154022 -45.946822)
		(width 0.14224)
		(layer "In4.Cu")
		(net "M_J_DQS_DN<17>")
	)
	(segment
		(start 79.708502 -54.894988)
		(end 79.714852 -54.88432)
		(width 0.0889)
		(layer "In4.Cu")
		(net "M_J_DQS_DN<17>")
	)
	(segment
		(start 79.708502 -55.885588)
		(end 79.714852 -55.87492)
		(width 0.0889)
		(layer "In4.Cu")
		(net "M_J_DQS_DN<17>")
	)
	(segment
		(start 79.680054 -47.472854)
		(end 79.500222 -47.472854)
		(width 0.14224)
		(layer "In4.Cu")
		(net "M_J_DQS_DN<17>")
	)
	(segment
		(start 79.841598 -47.81423)
		(end 79.841598 -47.634398)
		(width 0.14224)
		(layer "In4.Cu")
		(net "M_J_DQS_DN<17>")
	)
	(segment
		(start 80.003142 -49.0347)
		(end 80.130142 -48.9077)
		(width 0.14224)
		(layer "In4.Cu")
		(net "M_J_DQS_DN<17>")
	)
	(segment
		(start 76.45654 -44.429172)
		(end 76.294996 -44.267628)
		(width 0.14224)
		(layer "In4.Cu")
		(net "M_J_DQS_DN<17>")
	)
	(segment
		(start 79.703676 -58.866024)
		(end 79.708502 -58.857388)
		(width 0.0889)
		(layer "In4.Cu")
		(net "M_J_DQS_DN<17>")
	)
	(segment
		(start 74.333608 -33.967928)
		(end 74.453496 -33.84804)
		(width 0.14224)
		(layer "In4.Cu")
		(net "M_J_DQS_DN<17>")
	)
	(segment
		(start 79.703676 -61.837824)
		(end 79.708502 -61.829188)
		(width 0.0889)
		(layer "In4.Cu")
		(net "M_J_DQS_DN<17>")
	)
	(segment
		(start 79.703676 -62.828424)
		(end 79.708502 -62.819788)
		(width 0.0889)
		(layer "In4.Cu")
		(net "M_J_DQS_DN<17>")
	)
	(segment
		(start 72.924416 -14.90472)
		(end 72.924416 -14.71168)
		(width 0.14224)
		(layer "In4.Cu")
		(net "M_J_DQS_DN<17>")
	)
	(segment
		(start 72.924416 -29.792168)
		(end 72.924416 -15.47368)
		(width 0.14224)
		(layer "In4.Cu")
		(net "M_J_DQS_DN<17>")
	)
	(segment
		(start 75.42784 -34.5313)
		(end 74.453496 -34.5313)
		(width 0.14224)
		(layer "In4.Cu")
		(net "M_J_DQS_DN<17>")
	)
	(segment
		(start 79.963772 -49.400968)
		(end 80.003142 -49.361598)
		(width 0.0889)
		(layer "In4.Cu")
		(net "M_J_DQS_DN<17>")
	)
	(segment
		(start 75.705208 -33.570672)
		(end 75.705208 -32.57296)
		(width 0.14224)
		(layer "In4.Cu")
		(net "M_J_DQS_DN<17>")
	)
	(segment
		(start 73.081896 -15.3162)
		(end 73.081896 -15.0622)
		(width 0.14224)
		(layer "In4.Cu")
		(net "M_J_DQS_DN<17>")
	)
	(segment
		(start 75.95362 -43.926252)
		(end 75.705208 -43.67784)
		(width 0.14224)
		(layer "In4.Cu")
		(net "M_J_DQS_DN<17>")
	)
	(segment
		(start 78.98003 -46.952662)
		(end 78.818486 -46.791118)
		(width 0.14224)
		(layer "In4.Cu")
		(net "M_J_DQS_DN<17>")
	)
	(segment
		(start 72.5805 -4.070604)
		(end 72.142096 -3.6322)
		(width 0.14224)
		(layer "In4.Cu")
		(net "M_J_DQS_DN<17>")
	)
	(segment
		(start 76.294996 -44.087796)
		(end 76.133452 -43.926252)
		(width 0.14224)
		(layer "In4.Cu")
		(net "M_J_DQS_DN<17>")
	)
	(segment
		(start 76.294996 -44.267628)
		(end 76.294996 -44.087796)
		(width 0.14224)
		(layer "In4.Cu")
		(net "M_J_DQS_DN<17>")
	)
	(segment
		(start 76.133452 -43.926252)
		(end 75.95362 -43.926252)
		(width 0.14224)
		(layer "In4.Cu")
		(net "M_J_DQS_DN<17>")
	)
	(segment
		(start 79.841598 -47.634398)
		(end 79.680054 -47.472854)
		(width 0.14224)
		(layer "In4.Cu")
		(net "M_J_DQS_DN<17>")
	)
	(segment
		(start 79.714852 -58.277506)
		(end 79.708502 -58.266838)
		(width 0.0889)
		(layer "In4.Cu")
		(net "M_J_DQS_DN<17>")
	)
	(segment
		(start 78.656942 -46.449742)
		(end 78.47711 -46.449742)
		(width 0.14224)
		(layer "In4.Cu")
		(net "M_J_DQS_DN<17>")
	)
	(segment
		(start 74.453496 -34.5313)
		(end 74.333608 -34.411412)
		(width 0.14224)
		(layer "In4.Cu")
		(net "M_J_DQS_DN<17>")
	)
	(segment
		(start 79.708502 -53.904388)
		(end 79.714852 -53.89372)
		(width 0.0889)
		(layer "In4.Cu")
		(net "M_J_DQS_DN<17>")
	)
	(segment
		(start 79.708502 -64.800988)
		(end 79.714852 -64.79032)
		(width 0.0889)
		(layer "In4.Cu")
		(net "M_J_DQS_DN<17>")
	)
	(segment
		(start 76.797916 -44.770548)
		(end 76.797916 -44.590716)
		(width 0.14224)
		(layer "In4.Cu")
		(net "M_J_DQS_DN<17>")
	)
	(segment
		(start 79.703676 -65.800224)
		(end 79.708502 -65.791588)
		(width 0.0889)
		(layer "In4.Cu")
		(net "M_J_DQS_DN<17>")
	)
	(segment
		(start 72.924416 -14.71168)
		(end 73.081896 -14.5542)
		(width 0.14224)
		(layer "In4.Cu")
		(net "M_J_DQS_DN<17>")
	)
	(segment
		(start 77.139292 -44.932092)
		(end 76.95946 -44.932092)
		(width 0.14224)
		(layer "In4.Cu")
		(net "M_J_DQS_DN<17>")
	)
	(segment
		(start 75.705208 -32.57296)
		(end 72.924416 -29.792168)
		(width 0.14224)
		(layer "In4.Cu")
		(net "M_J_DQS_DN<17>")
	)
	(segment
		(start 79.703676 -55.894224)
		(end 79.708502 -55.885588)
		(width 0.0889)
		(layer "In4.Cu")
		(net "M_J_DQS_DN<17>")
	)
	(segment
		(start 77.642212 -45.435012)
		(end 77.46238 -45.435012)
		(width 0.14224)
		(layer "In4.Cu")
		(net "M_J_DQS_DN<17>")
	)
	(segment
		(start 76.797916 -44.590716)
		(end 76.636372 -44.429172)
		(width 0.14224)
		(layer "In4.Cu")
		(net "M_J_DQS_DN<17>")
	)
	(segment
		(start 79.703676 -53.913024)
		(end 79.708502 -53.904388)
		(width 0.0889)
		(layer "In4.Cu")
		(net "M_J_DQS_DN<17>")
	)
	(segment
		(start 73.081896 -14.5542)
		(end 73.081896 -14.3002)
		(width 0.14224)
		(layer "In4.Cu")
		(net "M_J_DQS_DN<17>")
	)
	(segment
		(start 79.703676 -56.884824)
		(end 79.708502 -56.876188)
		(width 0.0889)
		(layer "In4.Cu")
		(net "M_J_DQS_DN<17>")
	)
	(segment
		(start 72.924416 -6.462268)
		(end 71.94042 -5.478272)
		(width 0.14224)
		(layer "In4.Cu")
		(net "M_J_DQS_DN<17>")
	)
	(segment
		(start 79.708502 -63.810388)
		(end 79.714852 -63.79972)
		(width 0.0889)
		(layer "In4.Cu")
		(net "M_J_DQS_DN<17>")
	)
	(segment
		(start 77.300836 -45.093636)
		(end 77.139292 -44.932092)
		(width 0.14224)
		(layer "In4.Cu")
		(net "M_J_DQS_DN<17>")
	)
	(segment
		(start 79.833724 -52.683156)
		(end 79.953612 -52.683156)
		(width 0.0889)
		(layer "In4.Cu")
		(net "M_J_DQS_DN<17>")
	)
	(segment
		(start 79.321406 -47.294038)
		(end 79.321406 -47.114206)
		(width 0.14224)
		(layer "In4.Cu")
		(net "M_J_DQS_DN<17>")
	)
	(segment
		(start 76.636372 -44.429172)
		(end 76.45654 -44.429172)
		(width 0.14224)
		(layer "In4.Cu")
		(net "M_J_DQS_DN<17>")
	)
	(arc
		(start 79.708502 -62.229238)
		(mid 79.655032 -62.034175)
		(end 79.703676 -61.837824)
		(width 0.0889)
		(layer "In4.Cu")
		(net "M_J_DQS_DN<17>")
	)
	(arc
		(start 79.714852 -56.86552)
		(mid 79.78765 -56.574757)
		(end 79.708502 -56.285638)
		(width 0.0889)
		(layer "In4.Cu")
		(net "M_J_DQS_DN<17>")
	)
	(arc
		(start 79.708502 -54.304438)
		(mid 79.655032 -54.109375)
		(end 79.703676 -53.913024)
		(width 0.0889)
		(layer "In4.Cu")
		(net "M_J_DQS_DN<17>")
	)
	(arc
		(start 79.708502 -61.238638)
		(mid 79.655032 -61.043575)
		(end 79.703676 -60.847224)
		(width 0.0889)
		(layer "In4.Cu")
		(net "M_J_DQS_DN<17>")
	)
	(arc
		(start 79.714852 -59.83732)
		(mid 79.78765 -59.546557)
		(end 79.708502 -59.257438)
		(width 0.0889)
		(layer "In4.Cu")
		(net "M_J_DQS_DN<17>")
	)
	(arc
		(start 79.714852 -60.82792)
		(mid 79.78765 -60.537157)
		(end 79.708502 -60.248038)
		(width 0.0889)
		(layer "In4.Cu")
		(net "M_J_DQS_DN<17>")
	)
	(arc
		(start 79.708502 -60.248038)
		(mid 79.655032 -60.052975)
		(end 79.703676 -59.856624)
		(width 0.0889)
		(layer "In4.Cu")
		(net "M_J_DQS_DN<17>")
	)
	(arc
		(start 79.714852 -64.79032)
		(mid 79.78765 -64.499557)
		(end 79.708502 -64.210438)
		(width 0.0889)
		(layer "In4.Cu")
		(net "M_J_DQS_DN<17>")
	)
	(arc
		(start 79.708502 -56.285638)
		(mid 79.655032 -56.090575)
		(end 79.703676 -55.894224)
		(width 0.0889)
		(layer "In4.Cu")
		(net "M_J_DQS_DN<17>")
	)
	(arc
		(start 79.714852 -62.80912)
		(mid 79.78765 -62.518357)
		(end 79.708502 -62.229238)
		(width 0.0889)
		(layer "In4.Cu")
		(net "M_J_DQS_DN<17>")
	)
	(arc
		(start 79.714852 -61.81852)
		(mid 79.78765 -61.527757)
		(end 79.708502 -61.238638)
		(width 0.0889)
		(layer "In4.Cu")
		(net "M_J_DQS_DN<17>")
	)
	(arc
		(start 79.714852 -54.88432)
		(mid 79.78765 -54.593557)
		(end 79.708502 -54.304438)
		(width 0.0889)
		(layer "In4.Cu")
		(net "M_J_DQS_DN<17>")
	)
	(arc
		(start 79.708502 -58.266838)
		(mid 79.655003 -58.06694)
		(end 79.708502 -57.867042)
		(width 0.0889)
		(layer "In4.Cu")
		(net "M_J_DQS_DN<17>")
	)
	(arc
		(start 79.708502 -64.210438)
		(mid 79.655032 -64.015375)
		(end 79.703676 -63.819024)
		(width 0.0889)
		(layer "In4.Cu")
		(net "M_J_DQS_DN<17>")
	)
	(arc
		(start 79.708502 -57.867042)
		(mid 79.787633 -57.57164)
		(end 79.708502 -57.276238)
		(width 0.0889)
		(layer "In4.Cu")
		(net "M_J_DQS_DN<17>")
	)
	(arc
		(start 79.708502 -66.191384)
		(mid 79.655034 -65.996433)
		(end 79.703676 -65.800224)
		(width 0.0889)
		(layer "In4.Cu")
		(net "M_J_DQS_DN<17>")
	)
	(arc
		(start 79.708502 -59.257438)
		(mid 79.655032 -59.062375)
		(end 79.703676 -58.866024)
		(width 0.0889)
		(layer "In4.Cu")
		(net "M_J_DQS_DN<17>")
	)
	(arc
		(start 80.053434 -66.978276)
		(mid 79.902616 -66.57534)
		(end 79.708502 -66.191384)
		(width 0.0889)
		(layer "In4.Cu")
		(net "M_J_DQS_DN<17>")
	)
	(arc
		(start 79.714852 -65.78092)
		(mid 79.78765 -65.490157)
		(end 79.708502 -65.201038)
		(width 0.0889)
		(layer "In4.Cu")
		(net "M_J_DQS_DN<17>")
	)
	(arc
		(start 79.708502 -63.219838)
		(mid 79.655032 -63.024775)
		(end 79.703676 -62.828424)
		(width 0.0889)
		(layer "In4.Cu")
		(net "M_J_DQS_DN<17>")
	)
	(arc
		(start 79.708502 -55.295038)
		(mid 79.655032 -55.099975)
		(end 79.703676 -54.903624)
		(width 0.0889)
		(layer "In4.Cu")
		(net "M_J_DQS_DN<17>")
	)
	(arc
		(start 79.708502 -57.276238)
		(mid 79.655032 -57.081175)
		(end 79.703676 -56.884824)
		(width 0.0889)
		(layer "In4.Cu")
		(net "M_J_DQS_DN<17>")
	)
	(arc
		(start 79.708502 -65.201038)
		(mid 79.655032 -65.005975)
		(end 79.703676 -64.809624)
		(width 0.0889)
		(layer "In4.Cu")
		(net "M_J_DQS_DN<17>")
	)
	(arc
		(start 79.714852 -55.87492)
		(mid 79.78765 -55.584157)
		(end 79.708502 -55.295038)
		(width 0.0889)
		(layer "In4.Cu")
		(net "M_J_DQS_DN<17>")
	)
	(arc
		(start 79.714852 -53.89372)
		(mid 79.78765 -53.602957)
		(end 79.708502 -53.313838)
		(width 0.0889)
		(layer "In4.Cu")
		(net "M_J_DQS_DN<17>")
	)
	(arc
		(start 79.714852 -63.79972)
		(mid 79.78765 -63.508957)
		(end 79.708502 -63.219838)
		(width 0.0889)
		(layer "In4.Cu")
		(net "M_J_DQS_DN<17>")
	)
	(arc
		(start 79.708502 -58.857388)
		(mid 79.787724 -58.56827)
		(end 79.714852 -58.277506)
		(width 0.0889)
		(layer "In4.Cu")
		(net "M_J_DQS_DN<17>")
	)
	(segment
		(start 72.34428 1.59512)
		(end 72.593708 1.59512)
		(width 0.14224)
		(layer "In11.Cu")
		(net "M_J_DQS_DN<17>")
	)
	(segment
		(start 72.1487 1.7907)
		(end 72.34428 1.59512)
		(width 0.14224)
		(layer "In11.Cu")
		(net "M_J_DQS_DN<17>")
	)
	(segment
		(start 72.93102 1.257808)
		(end 72.93102 -2.843276)
		(width 0.14224)
		(layer "In11.Cu")
		(net "M_J_DQS_DN<17>")
	)
	(segment
		(start 72.593708 1.59512)
		(end 72.93102 1.257808)
		(width 0.14224)
		(layer "In11.Cu")
		(net "M_J_DQS_DN<17>")
	)
	(segment
		(start 72.93102 -2.843276)
		(end 72.142096 -3.6322)
		(width 0.14224)
		(layer "In11.Cu")
		(net "M_J_DQS_DN<17>")
	)
	(segment
		(start 146.307048 1.60147)
		(end 146.117818 1.7907)
		(width 0.1651)
		(layer "F.Cu")
		(net "M_J_DQS_DN<16>")
	)
	(segment
		(start 146.999452 2.93624)
		(end 146.581368 2.518156)
		(width 0.1651)
		(layer "F.Cu")
		(net "M_J_DQS_DN<16>")
	)
	(segment
		(start 146.999452 3.778758)
		(end 146.999452 2.93624)
		(width 0.1651)
		(layer "F.Cu")
		(net "M_J_DQS_DN<16>")
	)
	(segment
		(start 146.515328 1.60147)
		(end 146.307048 1.60147)
		(width 0.1651)
		(layer "F.Cu")
		(net "M_J_DQS_DN<16>")
	)
	(segment
		(start 146.581368 2.286)
		(end 146.767296 2.100072)
		(width 0.1651)
		(layer "F.Cu")
		(net "M_J_DQS_DN<16>")
	)
	(segment
		(start 122.504708 -62.343538)
		(end 121.933208 -62.343538)
		(width 0.0889)
		(layer "F.Cu")
		(net "M_J_DQS_DN<16>")
	)
	(segment
		(start 146.117818 1.7907)
		(end 146.098768 1.7907)
		(width 0.1651)
		(layer "F.Cu")
		(net "M_J_DQS_DN<16>")
	)
	(segment
		(start 146.767296 1.853438)
		(end 146.515328 1.60147)
		(width 0.1651)
		(layer "F.Cu")
		(net "M_J_DQS_DN<16>")
	)
	(segment
		(start 146.767296 2.100072)
		(end 146.767296 1.853438)
		(width 0.1651)
		(layer "F.Cu")
		(net "M_J_DQS_DN<16>")
	)
	(segment
		(start 146.581368 2.518156)
		(end 146.581368 2.286)
		(width 0.1651)
		(layer "F.Cu")
		(net "M_J_DQS_DN<16>")
	)
	(via
		(at 146.098768 1.7907)
		(size 0.508)
		(drill 0.254)
		(layers "F.Cu" "B.Cu")
		(net "M_J_DQS_DN<16>")
	)
	(via
		(at 146.092164 -3.6322)
		(size 0.508)
		(drill 0.254)
		(layers "F.Cu" "B.Cu")
		(net "M_J_DQS_DN<16>")
	)
	(via
		(at 121.933208 -62.343538)
		(size 0.508)
		(drill 0.254)
		(layers "F.Cu" "B.Cu")
		(net "M_J_DQS_DN<16>")
	)
	(segment
		(start 146.733768 -3.9878)
		(end 146.733768 -3.6576)
		(width 0.1651)
		(layer "B.Cu")
		(net "M_J_DQS_DN<16>")
	)
	(segment
		(start 146.733768 -3.6576)
		(end 146.513804 -3.437636)
		(width 0.1651)
		(layer "B.Cu")
		(net "M_J_DQS_DN<16>")
	)
	(segment
		(start 146.999452 -5.621782)
		(end 146.999452 -4.964938)
		(width 0.1651)
		(layer "B.Cu")
		(net "M_J_DQS_DN<16>")
	)
	(segment
		(start 146.999452 -4.964938)
		(end 146.555968 -4.521454)
		(width 0.1651)
		(layer "B.Cu")
		(net "M_J_DQS_DN<16>")
	)
	(segment
		(start 146.555968 -4.1656)
		(end 146.733768 -3.9878)
		(width 0.1651)
		(layer "B.Cu")
		(net "M_J_DQS_DN<16>")
	)
	(segment
		(start 146.513804 -3.437636)
		(end 146.286728 -3.437636)
		(width 0.1651)
		(layer "B.Cu")
		(net "M_J_DQS_DN<16>")
	)
	(segment
		(start 146.286728 -3.437636)
		(end 146.092164 -3.6322)
		(width 0.1651)
		(layer "B.Cu")
		(net "M_J_DQS_DN<16>")
	)
	(segment
		(start 146.555968 -4.521454)
		(end 146.555968 -4.1656)
		(width 0.1651)
		(layer "B.Cu")
		(net "M_J_DQS_DN<16>")
	)
	(segment
		(start 146.874484 -10.799572)
		(end 146.874484 -10.446004)
		(width 0.14224)
		(layer "In11.Cu")
		(net "M_J_DQS_DN<16>")
	)
	(segment
		(start 124.138436 -49.214532)
		(end 124.318014 -49.034954)
		(width 0.14224)
		(layer "In11.Cu")
		(net "M_J_DQS_DN<16>")
	)
	(segment
		(start 126.728728 -47.38624)
		(end 126.855728 -47.25924)
		(width 0.14224)
		(layer "In11.Cu")
		(net "M_J_DQS_DN<16>")
	)
	(segment
		(start 125.575568 -47.956978)
		(end 125.7554 -47.7774)
		(width 0.14224)
		(layer "In11.Cu")
		(net "M_J_DQS_DN<16>")
	)
	(segment
		(start 121.586498 -58.581036)
		(end 121.581672 -58.5724)
		(width 0.0889)
		(layer "In11.Cu")
		(net "M_J_DQS_DN<16>")
	)
	(segment
		(start 121.592848 -54.629304)
		(end 121.586498 -54.618636)
		(width 0.0889)
		(layer "In11.Cu")
		(net "M_J_DQS_DN<16>")
	)
	(segment
		(start 146.327368 -4.8006)
		(end 146.530568 -4.5974)
		(width 0.14224)
		(layer "In11.Cu")
		(net "M_J_DQS_DN<16>")
	)
	(segment
		(start 146.517614 -29.548582)
		(end 146.92884 -29.548582)
		(width 0.14224)
		(layer "In11.Cu")
		(net "M_J_DQS_DN<16>")
	)
	(segment
		(start 146.874484 -10.446004)
		(end 146.988784 -10.331704)
		(width 0.14224)
		(layer "In11.Cu")
		(net "M_J_DQS_DN<16>")
	)
	(segment
		(start 146.874484 -12.246102)
		(end 146.988784 -12.131802)
		(width 0.14224)
		(layer "In11.Cu")
		(net "M_J_DQS_DN<16>")
	)
	(segment
		(start 146.988784 -10.331704)
		(end 146.988784 -10.077704)
		(width 0.14224)
		(layer "In11.Cu")
		(net "M_J_DQS_DN<16>")
	)
	(segment
		(start 121.586498 -56.599836)
		(end 121.581672 -56.5912)
		(width 0.0889)
		(layer "In11.Cu")
		(net "M_J_DQS_DN<16>")
	)
	(segment
		(start 121.586498 -54.618636)
		(end 121.581672 -54.61)
		(width 0.0889)
		(layer "In11.Cu")
		(net "M_J_DQS_DN<16>")
	)
	(segment
		(start 130.5052 -46.2788)
		(end 130.5052 -46.098968)
		(width 0.14224)
		(layer "In11.Cu")
		(net "M_J_DQS_DN<16>")
	)
	(segment
		(start 125.39599 -47.956978)
		(end 125.575568 -47.956978)
		(width 0.14224)
		(layer "In11.Cu")
		(net "M_J_DQS_DN<16>")
	)
	(segment
		(start 121.533412 -53.544978)
		(end 121.533412 -52.098956)
		(width 0.0889)
		(layer "In11.Cu")
		(net "M_J_DQS_DN<16>")
	)
	(segment
		(start 147.157948 -24.492204)
		(end 147.157948 -24.089614)
		(width 0.14224)
		(layer "In11.Cu")
		(net "M_J_DQS_DN<16>")
	)
	(segment
		(start 127.124968 -47.25924)
		(end 127.251968 -47.38624)
		(width 0.14224)
		(layer "In11.Cu")
		(net "M_J_DQS_DN<16>")
	)
	(segment
		(start 129.344928 -47.25924)
		(end 129.574036 -47.030132)
		(width 0.14224)
		(layer "In11.Cu")
		(net "M_J_DQS_DN<16>")
	)
	(segment
		(start 147.185888 -26.451814)
		(end 147.185888 -25.98039)
		(width 0.14224)
		(layer "In11.Cu")
		(net "M_J_DQS_DN<16>")
	)
	(segment
		(start 145.890488 -5.254752)
		(end 145.890488 -4.98348)
		(width 0.14224)
		(layer "In11.Cu")
		(net "M_J_DQS_DN<16>")
	)
	(segment
		(start 146.874484 -6.238748)
		(end 145.890488 -5.254752)
		(width 0.14224)
		(layer "In11.Cu")
		(net "M_J_DQS_DN<16>")
	)
	(segment
		(start 121.592848 -57.601104)
		(end 121.586498 -57.590436)
		(width 0.0889)
		(layer "In11.Cu")
		(net "M_J_DQS_DN<16>")
	)
	(segment
		(start 146.92884 -29.548582)
		(end 147.307808 -29.169614)
		(width 0.14224)
		(layer "In11.Cu")
		(net "M_J_DQS_DN<16>")
	)
	(segment
		(start 146.874484 -11.763502)
		(end 146.874484 -11.282172)
		(width 0.14224)
		(layer "In11.Cu")
		(net "M_J_DQS_DN<16>")
	)
	(segment
		(start 121.592848 -60.572904)
		(end 121.586498 -60.562236)
		(width 0.0889)
		(layer "In11.Cu")
		(net "M_J_DQS_DN<16>")
	)
	(segment
		(start 125.216412 -48.316388)
		(end 125.216412 -48.136556)
		(width 0.14224)
		(layer "In11.Cu")
		(net "M_J_DQS_DN<16>")
	)
	(segment
		(start 146.294348 1.59512)
		(end 146.098768 1.7907)
		(width 0.14224)
		(layer "In11.Cu")
		(net "M_J_DQS_DN<16>")
	)
	(segment
		(start 123.958604 -49.556162)
		(end 124.138436 -49.37633)
		(width 0.14224)
		(layer "In11.Cu")
		(net "M_J_DQS_DN<16>")
	)
	(segment
		(start 130.5052 -46.098968)
		(end 130.684778 -45.91939)
		(width 0.14224)
		(layer "In11.Cu")
		(net "M_J_DQS_DN<16>")
	)
	(segment
		(start 123.510548 -49.787048)
		(end 123.56592 -49.787048)
		(width 0.0889)
		(layer "In11.Cu")
		(net "M_J_DQS_DN<16>")
	)
	(segment
		(start 121.592848 -56.610504)
		(end 121.586498 -56.599836)
		(width 0.0889)
		(layer "In11.Cu")
		(net "M_J_DQS_DN<16>")
	)
	(segment
		(start 127.632968 -47.25924)
		(end 128.013968 -47.25924)
		(width 0.14224)
		(layer "In11.Cu")
		(net "M_J_DQS_DN<16>")
	)
	(segment
		(start 128.013968 -47.25924)
		(end 128.140968 -47.38624)
		(width 0.14224)
		(layer "In11.Cu")
		(net "M_J_DQS_DN<16>")
	)
	(segment
		(start 125.7554 -47.7774)
		(end 125.7554 -47.597568)
		(width 0.14224)
		(layer "In11.Cu")
		(net "M_J_DQS_DN<16>")
	)
	(segment
		(start 146.092164 -3.6322)
		(end 146.881088 -2.843276)
		(width 0.14224)
		(layer "In11.Cu")
		(net "M_J_DQS_DN<16>")
	)
	(segment
		(start 126.093728 -47.25924)
		(end 126.347728 -47.25924)
		(width 0.14224)
		(layer "In11.Cu")
		(net "M_J_DQS_DN<16>")
	)
	(segment
		(start 124.138436 -49.37633)
		(end 124.138436 -49.214532)
		(width 0.14224)
		(layer "In11.Cu")
		(net "M_J_DQS_DN<16>")
	)
	(segment
		(start 125.7554 -47.597568)
		(end 126.093728 -47.25924)
		(width 0.14224)
		(layer "In11.Cu")
		(net "M_J_DQS_DN<16>")
	)
	(segment
		(start 126.347728 -47.25924)
		(end 126.474728 -47.38624)
		(width 0.14224)
		(layer "In11.Cu")
		(net "M_J_DQS_DN<16>")
	)
	(segment
		(start 121.533412 -52.098956)
		(end 122.070368 -51.562)
		(width 0.0889)
		(layer "In11.Cu")
		(net "M_J_DQS_DN<16>")
	)
	(segment
		(start 127.505968 -47.38624)
		(end 127.632968 -47.25924)
		(width 0.14224)
		(layer "In11.Cu")
		(net "M_J_DQS_DN<16>")
	)
	(segment
		(start 130.684778 -45.918882)
		(end 135.430768 -41.1734)
		(width 0.14224)
		(layer "In11.Cu")
		(net "M_J_DQS_DN<16>")
	)
	(segment
		(start 146.649694 -25.444196)
		(end 146.649694 -25.000458)
		(width 0.14224)
		(layer "In11.Cu")
		(net "M_J_DQS_DN<16>")
	)
	(segment
		(start 146.874484 -23.80615)
		(end 146.874484 -12.246102)
		(width 0.14224)
		(layer "In11.Cu")
		(net "M_J_DQS_DN<16>")
	)
	(segment
		(start 124.677424 -48.675544)
		(end 124.857002 -48.495966)
		(width 0.14224)
		(layer "In11.Cu")
		(net "M_J_DQS_DN<16>")
	)
	(segment
		(start 126.855728 -47.25924)
		(end 127.124968 -47.25924)
		(width 0.14224)
		(layer "In11.Cu")
		(net "M_J_DQS_DN<16>")
	)
	(segment
		(start 146.874484 -11.282172)
		(end 146.988784 -11.167872)
		(width 0.14224)
		(layer "In11.Cu")
		(net "M_J_DQS_DN<16>")
	)
	(segment
		(start 122.070368 -50.91684)
		(end 122.631708 -50.3555)
		(width 0.0889)
		(layer "In11.Cu")
		(net "M_J_DQS_DN<16>")
	)
	(segment
		(start 146.296888 -29.769308)
		(end 146.517614 -29.548582)
		(width 0.14224)
		(layer "In11.Cu")
		(net "M_J_DQS_DN<16>")
	)
	(segment
		(start 146.988784 -10.913872)
		(end 146.874484 -10.799572)
		(width 0.14224)
		(layer "In11.Cu")
		(net "M_J_DQS_DN<16>")
	)
	(segment
		(start 130.145536 -46.458632)
		(end 130.325368 -46.458632)
		(width 0.14224)
		(layer "In11.Cu")
		(net "M_J_DQS_DN<16>")
	)
	(segment
		(start 121.586498 -60.562236)
		(end 121.581672 -60.5536)
		(width 0.0889)
		(layer "In11.Cu")
		(net "M_J_DQS_DN<16>")
	)
	(segment
		(start 146.271488 -27.712416)
		(end 146.271488 -27.07767)
		(width 0.14224)
		(layer "In11.Cu")
		(net "M_J_DQS_DN<16>")
	)
	(segment
		(start 136.497568 -41.1734)
		(end 146.296888 -31.37408)
		(width 0.14224)
		(layer "In11.Cu")
		(net "M_J_DQS_DN<16>")
	)
	(segment
		(start 146.988784 -11.167872)
		(end 146.988784 -10.913872)
		(width 0.14224)
		(layer "In11.Cu")
		(net "M_J_DQS_DN<16>")
	)
	(segment
		(start 147.157948 -24.089614)
		(end 146.874484 -23.80615)
		(width 0.14224)
		(layer "In11.Cu")
		(net "M_J_DQS_DN<16>")
	)
	(segment
		(start 146.988784 -10.077704)
		(end 146.874484 -9.963404)
		(width 0.14224)
		(layer "In11.Cu")
		(net "M_J_DQS_DN<16>")
	)
	(segment
		(start 122.942096 -50.3555)
		(end 123.510548 -49.787048)
		(width 0.0889)
		(layer "In11.Cu")
		(net "M_J_DQS_DN<16>")
	)
	(segment
		(start 147.307808 -29.169614)
		(end 147.307808 -28.31211)
		(width 0.14224)
		(layer "In11.Cu")
		(net "M_J_DQS_DN<16>")
	)
	(segment
		(start 129.574036 -47.030132)
		(end 129.753868 -47.030132)
		(width 0.14224)
		(layer "In11.Cu")
		(net "M_J_DQS_DN<16>")
	)
	(segment
		(start 146.073368 -4.8006)
		(end 146.327368 -4.8006)
		(width 0.14224)
		(layer "In11.Cu")
		(net "M_J_DQS_DN<16>")
	)
	(segment
		(start 123.581668 -49.7713)
		(end 123.796806 -49.556162)
		(width 0.14224)
		(layer "In11.Cu")
		(net "M_J_DQS_DN<16>")
	)
	(segment
		(start 129.9337 -46.8503)
		(end 129.9337 -46.670468)
		(width 0.14224)
		(layer "In11.Cu")
		(net "M_J_DQS_DN<16>")
	)
	(segment
		(start 146.492976 -26.856182)
		(end 146.78152 -26.856182)
		(width 0.14224)
		(layer "In11.Cu")
		(net "M_J_DQS_DN<16>")
	)
	(segment
		(start 146.492214 -27.933142)
		(end 146.271488 -27.712416)
		(width 0.14224)
		(layer "In11.Cu")
		(net "M_J_DQS_DN<16>")
	)
	(segment
		(start 130.684778 -45.91939)
		(end 130.684778 -45.918882)
		(width 0.14224)
		(layer "In11.Cu")
		(net "M_J_DQS_DN<16>")
	)
	(segment
		(start 128.394968 -47.38624)
		(end 128.521968 -47.25924)
		(width 0.14224)
		(layer "In11.Cu")
		(net "M_J_DQS_DN<16>")
	)
	(segment
		(start 146.296888 -31.37408)
		(end 146.296888 -29.769308)
		(width 0.14224)
		(layer "In11.Cu")
		(net "M_J_DQS_DN<16>")
	)
	(segment
		(start 124.497592 -49.034954)
		(end 124.677424 -48.855376)
		(width 0.14224)
		(layer "In11.Cu")
		(net "M_J_DQS_DN<16>")
	)
	(segment
		(start 121.586498 -59.171586)
		(end 121.592848 -59.160918)
		(width 0.0889)
		(layer "In11.Cu")
		(net "M_J_DQS_DN<16>")
	)
	(segment
		(start 146.530568 -4.5974)
		(end 146.530568 -4.070604)
		(width 0.14224)
		(layer "In11.Cu")
		(net "M_J_DQS_DN<16>")
	)
	(segment
		(start 121.586498 -55.609236)
		(end 121.581672 -55.6006)
		(width 0.0889)
		(layer "In11.Cu")
		(net "M_J_DQS_DN<16>")
	)
	(segment
		(start 128.140968 -47.38624)
		(end 128.394968 -47.38624)
		(width 0.14224)
		(layer "In11.Cu")
		(net "M_J_DQS_DN<16>")
	)
	(segment
		(start 147.185888 -25.98039)
		(end 146.649694 -25.444196)
		(width 0.14224)
		(layer "In11.Cu")
		(net "M_J_DQS_DN<16>")
	)
	(segment
		(start 129.9337 -46.670468)
		(end 130.145536 -46.458632)
		(width 0.14224)
		(layer "In11.Cu")
		(net "M_J_DQS_DN<16>")
	)
	(segment
		(start 129.753868 -47.030132)
		(end 129.9337 -46.8503)
		(width 0.14224)
		(layer "In11.Cu")
		(net "M_J_DQS_DN<16>")
	)
	(segment
		(start 122.070368 -51.562)
		(end 122.070368 -50.91684)
		(width 0.0889)
		(layer "In11.Cu")
		(net "M_J_DQS_DN<16>")
	)
	(segment
		(start 146.78152 -26.856182)
		(end 147.185888 -26.451814)
		(width 0.14224)
		(layer "In11.Cu")
		(net "M_J_DQS_DN<16>")
	)
	(segment
		(start 121.586498 -57.590436)
		(end 121.581672 -57.5818)
		(width 0.0889)
		(layer "In11.Cu")
		(net "M_J_DQS_DN<16>")
	)
	(segment
		(start 122.631708 -50.3555)
		(end 122.942096 -50.3555)
		(width 0.0889)
		(layer "In11.Cu")
		(net "M_J_DQS_DN<16>")
	)
	(segment
		(start 124.318014 -49.034954)
		(end 124.497592 -49.034954)
		(width 0.14224)
		(layer "In11.Cu")
		(net "M_J_DQS_DN<16>")
	)
	(segment
		(start 146.988784 -11.877802)
		(end 146.874484 -11.763502)
		(width 0.14224)
		(layer "In11.Cu")
		(net "M_J_DQS_DN<16>")
	)
	(segment
		(start 123.56592 -49.787048)
		(end 123.581668 -49.7713)
		(width 0.0889)
		(layer "In11.Cu")
		(net "M_J_DQS_DN<16>")
	)
	(segment
		(start 127.251968 -47.38624)
		(end 127.505968 -47.38624)
		(width 0.14224)
		(layer "In11.Cu")
		(net "M_J_DQS_DN<16>")
	)
	(segment
		(start 146.881088 -2.843276)
		(end 146.881088 1.257808)
		(width 0.14224)
		(layer "In11.Cu")
		(net "M_J_DQS_DN<16>")
	)
	(segment
		(start 124.857002 -48.495966)
		(end 125.03658 -48.495966)
		(width 0.14224)
		(layer "In11.Cu")
		(net "M_J_DQS_DN<16>")
	)
	(segment
		(start 146.649694 -25.000458)
		(end 147.157948 -24.492204)
		(width 0.14224)
		(layer "In11.Cu")
		(net "M_J_DQS_DN<16>")
	)
	(segment
		(start 146.881088 1.257808)
		(end 146.543776 1.59512)
		(width 0.14224)
		(layer "In11.Cu")
		(net "M_J_DQS_DN<16>")
	)
	(segment
		(start 125.216412 -48.136556)
		(end 125.39599 -47.956978)
		(width 0.14224)
		(layer "In11.Cu")
		(net "M_J_DQS_DN<16>")
	)
	(segment
		(start 124.677424 -48.855376)
		(end 124.677424 -48.675544)
		(width 0.14224)
		(layer "In11.Cu")
		(net "M_J_DQS_DN<16>")
	)
	(segment
		(start 123.796806 -49.556162)
		(end 123.958604 -49.556162)
		(width 0.14224)
		(layer "In11.Cu")
		(net "M_J_DQS_DN<16>")
	)
	(segment
		(start 145.890488 -4.98348)
		(end 146.073368 -4.8006)
		(width 0.14224)
		(layer "In11.Cu")
		(net "M_J_DQS_DN<16>")
	)
	(segment
		(start 146.92884 -27.933142)
		(end 146.492214 -27.933142)
		(width 0.14224)
		(layer "In11.Cu")
		(net "M_J_DQS_DN<16>")
	)
	(segment
		(start 146.271488 -27.07767)
		(end 146.492976 -26.856182)
		(width 0.14224)
		(layer "In11.Cu")
		(net "M_J_DQS_DN<16>")
	)
	(segment
		(start 146.543776 1.59512)
		(end 146.294348 1.59512)
		(width 0.14224)
		(layer "In11.Cu")
		(net "M_J_DQS_DN<16>")
	)
	(segment
		(start 125.03658 -48.495966)
		(end 125.216412 -48.316388)
		(width 0.14224)
		(layer "In11.Cu")
		(net "M_J_DQS_DN<16>")
	)
	(segment
		(start 121.569988 -53.601366)
		(end 121.533412 -53.544978)
		(width 0.0889)
		(layer "In11.Cu")
		(net "M_J_DQS_DN<16>")
	)
	(segment
		(start 128.521968 -47.25924)
		(end 129.344928 -47.25924)
		(width 0.14224)
		(layer "In11.Cu")
		(net "M_J_DQS_DN<16>")
	)
	(segment
		(start 147.307808 -28.31211)
		(end 146.92884 -27.933142)
		(width 0.14224)
		(layer "In11.Cu")
		(net "M_J_DQS_DN<16>")
	)
	(segment
		(start 146.988784 -12.131802)
		(end 146.988784 -11.877802)
		(width 0.14224)
		(layer "In11.Cu")
		(net "M_J_DQS_DN<16>")
	)
	(segment
		(start 121.592848 -55.619904)
		(end 121.586498 -55.609236)
		(width 0.0889)
		(layer "In11.Cu")
		(net "M_J_DQS_DN<16>")
	)
	(segment
		(start 121.933208 -62.343538)
		(end 121.93143 -62.339728)
		(width 0.0889)
		(layer "In11.Cu")
		(net "M_J_DQS_DN<16>")
	)
	(segment
		(start 146.530568 -4.070604)
		(end 146.092164 -3.6322)
		(width 0.14224)
		(layer "In11.Cu")
		(net "M_J_DQS_DN<16>")
	)
	(segment
		(start 135.430768 -41.1734)
		(end 136.497568 -41.1734)
		(width 0.14224)
		(layer "In11.Cu")
		(net "M_J_DQS_DN<16>")
	)
	(segment
		(start 130.325368 -46.458632)
		(end 130.5052 -46.2788)
		(width 0.14224)
		(layer "In11.Cu")
		(net "M_J_DQS_DN<16>")
	)
	(segment
		(start 146.874484 -9.963404)
		(end 146.874484 -6.238748)
		(width 0.14224)
		(layer "In11.Cu")
		(net "M_J_DQS_DN<16>")
	)
	(segment
		(start 126.474728 -47.38624)
		(end 126.728728 -47.38624)
		(width 0.14224)
		(layer "In11.Cu")
		(net "M_J_DQS_DN<16>")
	)
	(arc
		(start 121.586498 -61.552836)
		(mid 121.533033 -61.352828)
		(end 121.586498 -61.152786)
		(width 0.0889)
		(layer "In11.Cu")
		(net "M_J_DQS_DN<16>")
	)
	(arc
		(start 121.592848 -59.160918)
		(mid 121.665646 -58.870155)
		(end 121.586498 -58.581036)
		(width 0.0889)
		(layer "In11.Cu")
		(net "M_J_DQS_DN<16>")
	)
	(arc
		(start 121.581672 -57.5818)
		(mid 121.532917 -57.385448)
		(end 121.586498 -57.190386)
		(width 0.0889)
		(layer "In11.Cu")
		(net "M_J_DQS_DN<16>")
	)
	(arc
		(start 121.586498 -56.199786)
		(mid 121.66572 -55.910668)
		(end 121.592848 -55.619904)
		(width 0.0889)
		(layer "In11.Cu")
		(net "M_J_DQS_DN<16>")
	)
	(arc
		(start 121.581672 -58.5724)
		(mid 121.532917 -58.376048)
		(end 121.586498 -58.180986)
		(width 0.0889)
		(layer "In11.Cu")
		(net "M_J_DQS_DN<16>")
	)
	(arc
		(start 121.586498 -61.152786)
		(mid 121.66572 -60.863668)
		(end 121.592848 -60.572904)
		(width 0.0889)
		(layer "In11.Cu")
		(net "M_J_DQS_DN<16>")
	)
	(arc
		(start 121.586498 -58.180986)
		(mid 121.66572 -57.891868)
		(end 121.592848 -57.601104)
		(width 0.0889)
		(layer "In11.Cu")
		(net "M_J_DQS_DN<16>")
	)
	(arc
		(start 121.586498 -60.162186)
		(mid 121.665629 -59.866784)
		(end 121.586498 -59.571382)
		(width 0.0889)
		(layer "In11.Cu")
		(net "M_J_DQS_DN<16>")
	)
	(arc
		(start 121.581672 -56.5912)
		(mid 121.532917 -56.394848)
		(end 121.586498 -56.199786)
		(width 0.0889)
		(layer "In11.Cu")
		(net "M_J_DQS_DN<16>")
	)
	(arc
		(start 121.581672 -54.61)
		(mid 121.532917 -54.413648)
		(end 121.586498 -54.218586)
		(width 0.0889)
		(layer "In11.Cu")
		(net "M_J_DQS_DN<16>")
	)
	(arc
		(start 121.581672 -60.5536)
		(mid 121.532917 -60.357248)
		(end 121.586498 -60.162186)
		(width 0.0889)
		(layer "In11.Cu")
		(net "M_J_DQS_DN<16>")
	)
	(arc
		(start 121.581672 -55.6006)
		(mid 121.532917 -55.404248)
		(end 121.586498 -55.209186)
		(width 0.0889)
		(layer "In11.Cu")
		(net "M_J_DQS_DN<16>")
	)
	(arc
		(start 121.93143 -62.339728)
		(mid 121.780612 -61.936792)
		(end 121.586498 -61.552836)
		(width 0.0889)
		(layer "In11.Cu")
		(net "M_J_DQS_DN<16>")
	)
	(arc
		(start 121.586498 -54.218586)
		(mid 121.665393 -53.907647)
		(end 121.569988 -53.601366)
		(width 0.0889)
		(layer "In11.Cu")
		(net "M_J_DQS_DN<16>")
	)
	(arc
		(start 121.586498 -55.209186)
		(mid 121.66572 -54.920068)
		(end 121.592848 -54.629304)
		(width 0.0889)
		(layer "In11.Cu")
		(net "M_J_DQS_DN<16>")
	)
	(arc
		(start 121.586498 -59.571382)
		(mid 121.532999 -59.371484)
		(end 121.586498 -59.171586)
		(width 0.0889)
		(layer "In11.Cu")
		(net "M_J_DQS_DN<16>")
	)
	(arc
		(start 121.586498 -57.190386)
		(mid 121.66572 -56.901268)
		(end 121.592848 -56.610504)
		(width 0.0889)
		(layer "In11.Cu")
		(net "M_J_DQS_DN<16>")
	)
	(segment
		(start 137.417302 2.100072)
		(end 137.417302 1.853438)
		(width 0.1651)
		(layer "F.Cu")
		(net "M_J_DQS_DN<15>")
	)
	(segment
		(start 137.649458 3.778758)
		(end 137.649458 2.93624)
		(width 0.1651)
		(layer "F.Cu")
		(net "M_J_DQS_DN<15>")
	)
	(segment
		(start 137.231374 2.286)
		(end 137.417302 2.100072)
		(width 0.1651)
		(layer "F.Cu")
		(net "M_J_DQS_DN<15>")
	)
	(segment
		(start 117.353842 -62.343538)
		(end 116.782342 -62.343538)
		(width 0.0889)
		(layer "F.Cu")
		(net "M_J_DQS_DN<15>")
	)
	(segment
		(start 136.957054 1.60147)
		(end 136.767824 1.7907)
		(width 0.1651)
		(layer "F.Cu")
		(net "M_J_DQS_DN<15>")
	)
	(segment
		(start 136.767824 1.7907)
		(end 136.748774 1.7907)
		(width 0.1651)
		(layer "F.Cu")
		(net "M_J_DQS_DN<15>")
	)
	(segment
		(start 137.165334 1.60147)
		(end 136.957054 1.60147)
		(width 0.1651)
		(layer "F.Cu")
		(net "M_J_DQS_DN<15>")
	)
	(segment
		(start 137.417302 1.853438)
		(end 137.165334 1.60147)
		(width 0.1651)
		(layer "F.Cu")
		(net "M_J_DQS_DN<15>")
	)
	(segment
		(start 137.649458 2.93624)
		(end 137.231374 2.518156)
		(width 0.1651)
		(layer "F.Cu")
		(net "M_J_DQS_DN<15>")
	)
	(segment
		(start 137.231374 2.518156)
		(end 137.231374 2.286)
		(width 0.1651)
		(layer "F.Cu")
		(net "M_J_DQS_DN<15>")
	)
	(via
		(at 136.74217 -3.6322)
		(size 0.508)
		(drill 0.254)
		(layers "F.Cu" "B.Cu")
		(net "M_J_DQS_DN<15>")
	)
	(via
		(at 136.748774 1.7907)
		(size 0.508)
		(drill 0.254)
		(layers "F.Cu" "B.Cu")
		(net "M_J_DQS_DN<15>")
	)
	(via
		(at 116.782342 -62.343538)
		(size 0.508)
		(drill 0.254)
		(layers "F.Cu" "B.Cu")
		(net "M_J_DQS_DN<15>")
	)
	(segment
		(start 137.16381 -3.437636)
		(end 136.936734 -3.437636)
		(width 0.1651)
		(layer "B.Cu")
		(net "M_J_DQS_DN<15>")
	)
	(segment
		(start 137.383774 -3.6576)
		(end 137.16381 -3.437636)
		(width 0.1651)
		(layer "B.Cu")
		(net "M_J_DQS_DN<15>")
	)
	(segment
		(start 137.649458 -5.621782)
		(end 137.649458 -4.964938)
		(width 0.1651)
		(layer "B.Cu")
		(net "M_J_DQS_DN<15>")
	)
	(segment
		(start 137.649458 -4.964938)
		(end 137.205974 -4.521454)
		(width 0.1651)
		(layer "B.Cu")
		(net "M_J_DQS_DN<15>")
	)
	(segment
		(start 137.383774 -3.9878)
		(end 137.383774 -3.6576)
		(width 0.1651)
		(layer "B.Cu")
		(net "M_J_DQS_DN<15>")
	)
	(segment
		(start 137.205974 -4.521454)
		(end 137.205974 -4.1656)
		(width 0.1651)
		(layer "B.Cu")
		(net "M_J_DQS_DN<15>")
	)
	(segment
		(start 136.936734 -3.437636)
		(end 136.74217 -3.6322)
		(width 0.1651)
		(layer "B.Cu")
		(net "M_J_DQS_DN<15>")
	)
	(segment
		(start 137.205974 -4.1656)
		(end 137.383774 -3.9878)
		(width 0.1651)
		(layer "B.Cu")
		(net "M_J_DQS_DN<15>")
	)
	(segment
		(start 116.232432 -50.404268)
		(end 116.232432 -48.364648)
		(width 0.0889)
		(layer "In11.Cu")
		(net "M_J_DQS_DN<15>")
	)
	(segment
		(start 137.68197 -9.7028)
		(end 137.68197 -9.4488)
		(width 0.14224)
		(layer "In11.Cu")
		(net "M_J_DQS_DN<15>")
	)
	(segment
		(start 137.68197 -10.9728)
		(end 137.52449 -10.81532)
		(width 0.14224)
		(layer "In11.Cu")
		(net "M_J_DQS_DN<15>")
	)
	(segment
		(start 137.52449 -10.62228)
		(end 137.68197 -10.4648)
		(width 0.14224)
		(layer "In11.Cu")
		(net "M_J_DQS_DN<15>")
	)
	(segment
		(start 137.531094 -2.843276)
		(end 137.531094 1.257808)
		(width 0.14224)
		(layer "In11.Cu")
		(net "M_J_DQS_DN<15>")
	)
	(segment
		(start 137.52449 -9.29132)
		(end 137.52449 -6.42874)
		(width 0.14224)
		(layer "In11.Cu")
		(net "M_J_DQS_DN<15>")
	)
	(segment
		(start 119.361966 -43.711368)
		(end 119.52351 -43.711368)
		(width 0.14224)
		(layer "In11.Cu")
		(net "M_J_DQS_DN<15>")
	)
	(segment
		(start 116.090192 -50.776632)
		(end 116.232432 -50.404268)
		(width 0.0889)
		(layer "In11.Cu")
		(net "M_J_DQS_DN<15>")
	)
	(segment
		(start 116.514626 -51.554634)
		(end 116.090192 -51.1302)
		(width 0.0889)
		(layer "In11.Cu")
		(net "M_J_DQS_DN<15>")
	)
	(segment
		(start 116.430806 -58.5724)
		(end 116.435632 -58.581036)
		(width 0.0889)
		(layer "In11.Cu")
		(net "M_J_DQS_DN<15>")
	)
	(segment
		(start 116.232432 -48.364648)
		(end 117.059202 -47.537878)
		(width 0.0889)
		(layer "In11.Cu")
		(net "M_J_DQS_DN<15>")
	)
	(segment
		(start 116.430806 -54.61)
		(end 116.435632 -54.618636)
		(width 0.0889)
		(layer "In11.Cu")
		(net "M_J_DQS_DN<15>")
	)
	(segment
		(start 129.45364 -34.455608)
		(end 129.675128 -34.23412)
		(width 0.14224)
		(layer "In11.Cu")
		(net "M_J_DQS_DN<15>")
	)
	(segment
		(start 127.8382 -34.846514)
		(end 128.216406 -35.22472)
		(width 0.14224)
		(layer "In11.Cu")
		(net "M_J_DQS_DN<15>")
	)
	(segment
		(start 117.799104 -45.27423)
		(end 117.960648 -45.27423)
		(width 0.14224)
		(layer "In11.Cu")
		(net "M_J_DQS_DN<15>")
	)
	(segment
		(start 126.85522 -34.23412)
		(end 127.617474 -34.23412)
		(width 0.14224)
		(layer "In11.Cu")
		(net "M_J_DQS_DN<15>")
	)
	(segment
		(start 118.661434 -44.573444)
		(end 118.661434 -44.4119)
		(width 0.14224)
		(layer "In11.Cu")
		(net "M_J_DQS_DN<15>")
	)
	(segment
		(start 117.098572 -45.974762)
		(end 117.27815 -45.795184)
		(width 0.14224)
		(layer "In11.Cu")
		(net "M_J_DQS_DN<15>")
	)
	(segment
		(start 119.99595 -42.053764)
		(end 120.11025 -41.939464)
		(width 0.14224)
		(layer "In11.Cu")
		(net "M_J_DQS_DN<15>")
	)
	(segment
		(start 126.250192 -35.22472)
		(end 126.569216 -34.905696)
		(width 0.14224)
		(layer "In11.Cu")
		(net "M_J_DQS_DN<15>")
	)
	(segment
		(start 116.430806 -60.5536)
		(end 116.435632 -60.562236)
		(width 0.0889)
		(layer "In11.Cu")
		(net "M_J_DQS_DN<15>")
	)
	(segment
		(start 129.45364 -34.846514)
		(end 129.45364 -34.455608)
		(width 0.14224)
		(layer "In11.Cu")
		(net "M_J_DQS_DN<15>")
	)
	(segment
		(start 137.52449 -10.81532)
		(end 137.52449 -10.62228)
		(width 0.14224)
		(layer "In11.Cu")
		(net "M_J_DQS_DN<15>")
	)
	(segment
		(start 117.439694 -45.795184)
		(end 117.619526 -45.615352)
		(width 0.14224)
		(layer "In11.Cu")
		(net "M_J_DQS_DN<15>")
	)
	(segment
		(start 119.182388 -43.890946)
		(end 119.361966 -43.711368)
		(width 0.14224)
		(layer "In11.Cu")
		(net "M_J_DQS_DN<15>")
	)
	(segment
		(start 119.002556 -44.232322)
		(end 119.182388 -44.05249)
		(width 0.14224)
		(layer "In11.Cu")
		(net "M_J_DQS_DN<15>")
	)
	(segment
		(start 116.441982 -59.160918)
		(end 116.435632 -59.171586)
		(width 0.0889)
		(layer "In11.Cu")
		(net "M_J_DQS_DN<15>")
	)
	(segment
		(start 120.11025 -41.939464)
		(end 120.11025 -41.685464)
		(width 0.14224)
		(layer "In11.Cu")
		(net "M_J_DQS_DN<15>")
	)
	(segment
		(start 119.99595 -42.307764)
		(end 119.99595 -42.053764)
		(width 0.14224)
		(layer "In11.Cu")
		(net "M_J_DQS_DN<15>")
	)
	(segment
		(start 119.99595 -42.790364)
		(end 120.11025 -42.676064)
		(width 0.14224)
		(layer "In11.Cu")
		(net "M_J_DQS_DN<15>")
	)
	(segment
		(start 120.11025 -42.676064)
		(end 120.11025 -42.422064)
		(width 0.14224)
		(layer "In11.Cu")
		(net "M_J_DQS_DN<15>")
	)
	(segment
		(start 124.314966 -35.22472)
		(end 126.250192 -35.22472)
		(width 0.14224)
		(layer "In11.Cu")
		(net "M_J_DQS_DN<15>")
	)
	(segment
		(start 137.52449 -9.86028)
		(end 137.68197 -9.7028)
		(width 0.14224)
		(layer "In11.Cu")
		(net "M_J_DQS_DN<15>")
	)
	(segment
		(start 119.99595 -40.580564)
		(end 120.11025 -40.466264)
		(width 0.14224)
		(layer "In11.Cu")
		(net "M_J_DQS_DN<15>")
	)
	(segment
		(start 116.780564 -62.339728)
		(end 116.782342 -62.341506)
		(width 0.0889)
		(layer "In11.Cu")
		(net "M_J_DQS_DN<15>")
	)
	(segment
		(start 116.430806 -56.5912)
		(end 116.435632 -56.599836)
		(width 0.0889)
		(layer "In11.Cu")
		(net "M_J_DQS_DN<15>")
	)
	(segment
		(start 116.435632 -56.599836)
		(end 116.441982 -56.610504)
		(width 0.0889)
		(layer "In11.Cu")
		(net "M_J_DQS_DN<15>")
	)
	(segment
		(start 127.617474 -34.23412)
		(end 127.8382 -34.454846)
		(width 0.14224)
		(layer "In11.Cu")
		(net "M_J_DQS_DN<15>")
	)
	(segment
		(start 137.68197 -9.4488)
		(end 137.52449 -9.29132)
		(width 0.14224)
		(layer "In11.Cu")
		(net "M_J_DQS_DN<15>")
	)
	(segment
		(start 118.481602 -44.753276)
		(end 118.661434 -44.573444)
		(width 0.14224)
		(layer "In11.Cu")
		(net "M_J_DQS_DN<15>")
	)
	(segment
		(start 137.193782 1.59512)
		(end 136.944354 1.59512)
		(width 0.14224)
		(layer "In11.Cu")
		(net "M_J_DQS_DN<15>")
	)
	(segment
		(start 130.5306 -34.939986)
		(end 130.815334 -35.22472)
		(width 0.14224)
		(layer "In11.Cu")
		(net "M_J_DQS_DN<15>")
	)
	(segment
		(start 137.68197 -10.2108)
		(end 137.52449 -10.05332)
		(width 0.14224)
		(layer "In11.Cu")
		(net "M_J_DQS_DN<15>")
	)
	(segment
		(start 126.569216 -34.520124)
		(end 126.85522 -34.23412)
		(width 0.14224)
		(layer "In11.Cu")
		(net "M_J_DQS_DN<15>")
	)
	(segment
		(start 127.8382 -34.454846)
		(end 127.8382 -34.846514)
		(width 0.14224)
		(layer "In11.Cu")
		(net "M_J_DQS_DN<15>")
	)
	(segment
		(start 116.430806 -55.6006)
		(end 116.435632 -55.609236)
		(width 0.0889)
		(layer "In11.Cu")
		(net "M_J_DQS_DN<15>")
	)
	(segment
		(start 137.52449 -6.42874)
		(end 136.540494 -5.444744)
		(width 0.14224)
		(layer "In11.Cu")
		(net "M_J_DQS_DN<15>")
	)
	(segment
		(start 117.059202 -46.772068)
		(end 117.098572 -46.732698)
		(width 0.0889)
		(layer "In11.Cu")
		(net "M_J_DQS_DN<15>")
	)
	(segment
		(start 117.27815 -45.795184)
		(end 117.439694 -45.795184)
		(width 0.14224)
		(layer "In11.Cu")
		(net "M_J_DQS_DN<15>")
	)
	(segment
		(start 116.435632 -60.562236)
		(end 116.441982 -60.572904)
		(width 0.0889)
		(layer "In11.Cu")
		(net "M_J_DQS_DN<15>")
	)
	(segment
		(start 116.782342 -62.341506)
		(end 116.782342 -62.343538)
		(width 0.0889)
		(layer "In11.Cu")
		(net "M_J_DQS_DN<15>")
	)
	(segment
		(start 136.944354 1.59512)
		(end 136.748774 1.7907)
		(width 0.14224)
		(layer "In11.Cu")
		(net "M_J_DQS_DN<15>")
	)
	(segment
		(start 118.320058 -44.753276)
		(end 118.481602 -44.753276)
		(width 0.14224)
		(layer "In11.Cu")
		(net "M_J_DQS_DN<15>")
	)
	(segment
		(start 137.52449 -29.420312)
		(end 137.52449 -11.38428)
		(width 0.14224)
		(layer "In11.Cu")
		(net "M_J_DQS_DN<15>")
	)
	(segment
		(start 116.514626 -53.92039)
		(end 116.514626 -51.554634)
		(width 0.0889)
		(layer "In11.Cu")
		(net "M_J_DQS_DN<15>")
	)
	(segment
		(start 120.11025 -40.948864)
		(end 119.99595 -40.834564)
		(width 0.14224)
		(layer "In11.Cu")
		(net "M_J_DQS_DN<15>")
	)
	(segment
		(start 130.4036 -34.23412)
		(end 130.5306 -34.36112)
		(width 0.14224)
		(layer "In11.Cu")
		(net "M_J_DQS_DN<15>")
	)
	(segment
		(start 118.14048 -45.094398)
		(end 118.14048 -44.932854)
		(width 0.14224)
		(layer "In11.Cu")
		(net "M_J_DQS_DN<15>")
	)
	(segment
		(start 120.11025 -42.422064)
		(end 119.99595 -42.307764)
		(width 0.14224)
		(layer "In11.Cu")
		(net "M_J_DQS_DN<15>")
	)
	(segment
		(start 118.14048 -44.932854)
		(end 118.320058 -44.753276)
		(width 0.14224)
		(layer "In11.Cu")
		(net "M_J_DQS_DN<15>")
	)
	(segment
		(start 137.52449 -10.05332)
		(end 137.52449 -9.86028)
		(width 0.14224)
		(layer "In11.Cu")
		(net "M_J_DQS_DN<15>")
	)
	(segment
		(start 137.68197 -10.4648)
		(end 137.68197 -10.2108)
		(width 0.14224)
		(layer "In11.Cu")
		(net "M_J_DQS_DN<15>")
	)
	(segment
		(start 137.52449 -11.38428)
		(end 137.68197 -11.2268)
		(width 0.14224)
		(layer "In11.Cu")
		(net "M_J_DQS_DN<15>")
	)
	(segment
		(start 136.723374 -4.8006)
		(end 136.977374 -4.8006)
		(width 0.14224)
		(layer "In11.Cu")
		(net "M_J_DQS_DN<15>")
	)
	(segment
		(start 116.435886 -54.218332)
		(end 116.435632 -54.218586)
		(width 0.0889)
		(layer "In11.Cu")
		(net "M_J_DQS_DN<15>")
	)
	(segment
		(start 116.430806 -57.5818)
		(end 116.435632 -57.590436)
		(width 0.0889)
		(layer "In11.Cu")
		(net "M_J_DQS_DN<15>")
	)
	(segment
		(start 136.977374 -4.8006)
		(end 137.180574 -4.5974)
		(width 0.14224)
		(layer "In11.Cu")
		(net "M_J_DQS_DN<15>")
	)
	(segment
		(start 119.703342 -43.369992)
		(end 119.99595 -43.077384)
		(width 0.14224)
		(layer "In11.Cu")
		(net "M_J_DQS_DN<15>")
	)
	(segment
		(start 117.059202 -47.537878)
		(end 117.059202 -46.772068)
		(width 0.0889)
		(layer "In11.Cu")
		(net "M_J_DQS_DN<15>")
	)
	(segment
		(start 119.99595 -40.097964)
		(end 119.99595 -39.544244)
		(width 0.14224)
		(layer "In11.Cu")
		(net "M_J_DQS_DN<15>")
	)
	(segment
		(start 128.216406 -35.22472)
		(end 129.075434 -35.22472)
		(width 0.14224)
		(layer "In11.Cu")
		(net "M_J_DQS_DN<15>")
	)
	(segment
		(start 136.74217 -3.6322)
		(end 137.531094 -2.843276)
		(width 0.14224)
		(layer "In11.Cu")
		(net "M_J_DQS_DN<15>")
	)
	(segment
		(start 116.435632 -57.590436)
		(end 116.441982 -57.601104)
		(width 0.0889)
		(layer "In11.Cu")
		(net "M_J_DQS_DN<15>")
	)
	(segment
		(start 126.569216 -34.905696)
		(end 126.569216 -34.520124)
		(width 0.14224)
		(layer "In11.Cu")
		(net "M_J_DQS_DN<15>")
	)
	(segment
		(start 117.960648 -45.27423)
		(end 118.14048 -45.094398)
		(width 0.14224)
		(layer "In11.Cu")
		(net "M_J_DQS_DN<15>")
	)
	(segment
		(start 130.815334 -35.22472)
		(end 131.720082 -35.22472)
		(width 0.14224)
		(layer "In11.Cu")
		(net "M_J_DQS_DN<15>")
	)
	(segment
		(start 131.720082 -35.22472)
		(end 137.52449 -29.420312)
		(width 0.14224)
		(layer "In11.Cu")
		(net "M_J_DQS_DN<15>")
	)
	(segment
		(start 129.675128 -34.23412)
		(end 130.4036 -34.23412)
		(width 0.14224)
		(layer "In11.Cu")
		(net "M_J_DQS_DN<15>")
	)
	(segment
		(start 129.075434 -35.22472)
		(end 129.45364 -34.846514)
		(width 0.14224)
		(layer "In11.Cu")
		(net "M_J_DQS_DN<15>")
	)
	(segment
		(start 117.098572 -46.7106)
		(end 117.098572 -45.974762)
		(width 0.14224)
		(layer "In11.Cu")
		(net "M_J_DQS_DN<15>")
	)
	(segment
		(start 120.11025 -40.466264)
		(end 120.11025 -40.212264)
		(width 0.14224)
		(layer "In11.Cu")
		(net "M_J_DQS_DN<15>")
	)
	(segment
		(start 119.99595 -43.077384)
		(end 119.99595 -42.790364)
		(width 0.14224)
		(layer "In11.Cu")
		(net "M_J_DQS_DN<15>")
	)
	(segment
		(start 119.703342 -43.531536)
		(end 119.703342 -43.369992)
		(width 0.14224)
		(layer "In11.Cu")
		(net "M_J_DQS_DN<15>")
	)
	(segment
		(start 136.540494 -5.444744)
		(end 136.540494 -4.98348)
		(width 0.14224)
		(layer "In11.Cu")
		(net "M_J_DQS_DN<15>")
	)
	(segment
		(start 119.52351 -43.711368)
		(end 119.703342 -43.531536)
		(width 0.14224)
		(layer "In11.Cu")
		(net "M_J_DQS_DN<15>")
	)
	(segment
		(start 120.11025 -41.202864)
		(end 120.11025 -40.948864)
		(width 0.14224)
		(layer "In11.Cu")
		(net "M_J_DQS_DN<15>")
	)
	(segment
		(start 137.531094 1.257808)
		(end 137.193782 1.59512)
		(width 0.14224)
		(layer "In11.Cu")
		(net "M_J_DQS_DN<15>")
	)
	(segment
		(start 118.661434 -44.4119)
		(end 118.841012 -44.232322)
		(width 0.14224)
		(layer "In11.Cu")
		(net "M_J_DQS_DN<15>")
	)
	(segment
		(start 136.540494 -4.98348)
		(end 136.723374 -4.8006)
		(width 0.14224)
		(layer "In11.Cu")
		(net "M_J_DQS_DN<15>")
	)
	(segment
		(start 119.99595 -41.571164)
		(end 119.99595 -41.317164)
		(width 0.14224)
		(layer "In11.Cu")
		(net "M_J_DQS_DN<15>")
	)
	(segment
		(start 119.99595 -39.544244)
		(end 124.314966 -35.22472)
		(width 0.14224)
		(layer "In11.Cu")
		(net "M_J_DQS_DN<15>")
	)
	(segment
		(start 117.619526 -45.453808)
		(end 117.799104 -45.27423)
		(width 0.14224)
		(layer "In11.Cu")
		(net "M_J_DQS_DN<15>")
	)
	(segment
		(start 130.5306 -34.36112)
		(end 130.5306 -34.939986)
		(width 0.14224)
		(layer "In11.Cu")
		(net "M_J_DQS_DN<15>")
	)
	(segment
		(start 117.619526 -45.615352)
		(end 117.619526 -45.453808)
		(width 0.14224)
		(layer "In11.Cu")
		(net "M_J_DQS_DN<15>")
	)
	(segment
		(start 137.180574 -4.5974)
		(end 137.180574 -4.070604)
		(width 0.14224)
		(layer "In11.Cu")
		(net "M_J_DQS_DN<15>")
	)
	(segment
		(start 137.68197 -11.2268)
		(end 137.68197 -10.9728)
		(width 0.14224)
		(layer "In11.Cu")
		(net "M_J_DQS_DN<15>")
	)
	(segment
		(start 116.435632 -55.609236)
		(end 116.441982 -55.619904)
		(width 0.0889)
		(layer "In11.Cu")
		(net "M_J_DQS_DN<15>")
	)
	(segment
		(start 116.435632 -54.618636)
		(end 116.441982 -54.629304)
		(width 0.0889)
		(layer "In11.Cu")
		(net "M_J_DQS_DN<15>")
	)
	(segment
		(start 137.180574 -4.070604)
		(end 136.74217 -3.6322)
		(width 0.14224)
		(layer "In11.Cu")
		(net "M_J_DQS_DN<15>")
	)
	(segment
		(start 118.841012 -44.232322)
		(end 119.002556 -44.232322)
		(width 0.14224)
		(layer "In11.Cu")
		(net "M_J_DQS_DN<15>")
	)
	(segment
		(start 119.182388 -44.05249)
		(end 119.182388 -43.890946)
		(width 0.14224)
		(layer "In11.Cu")
		(net "M_J_DQS_DN<15>")
	)
	(segment
		(start 120.11025 -40.212264)
		(end 119.99595 -40.097964)
		(width 0.14224)
		(layer "In11.Cu")
		(net "M_J_DQS_DN<15>")
	)
	(segment
		(start 119.99595 -41.317164)
		(end 120.11025 -41.202864)
		(width 0.14224)
		(layer "In11.Cu")
		(net "M_J_DQS_DN<15>")
	)
	(segment
		(start 117.098572 -46.732698)
		(end 117.098572 -46.7106)
		(width 0.0889)
		(layer "In11.Cu")
		(net "M_J_DQS_DN<15>")
	)
	(segment
		(start 116.090192 -51.1302)
		(end 116.090192 -50.776632)
		(width 0.0889)
		(layer "In11.Cu")
		(net "M_J_DQS_DN<15>")
	)
	(segment
		(start 120.11025 -41.685464)
		(end 119.99595 -41.571164)
		(width 0.14224)
		(layer "In11.Cu")
		(net "M_J_DQS_DN<15>")
	)
	(segment
		(start 119.99595 -40.834564)
		(end 119.99595 -40.580564)
		(width 0.14224)
		(layer "In11.Cu")
		(net "M_J_DQS_DN<15>")
	)
	(arc
		(start 116.514626 -53.92039)
		(mid 116.495079 -54.074604)
		(end 116.435886 -54.218332)
		(width 0.0889)
		(layer "In11.Cu")
		(net "M_J_DQS_DN<15>")
	)
	(arc
		(start 116.435632 -55.209186)
		(mid 116.382162 -55.404249)
		(end 116.430806 -55.6006)
		(width 0.0889)
		(layer "In11.Cu")
		(net "M_J_DQS_DN<15>")
	)
	(arc
		(start 116.435632 -57.190386)
		(mid 116.382162 -57.385449)
		(end 116.430806 -57.5818)
		(width 0.0889)
		(layer "In11.Cu")
		(net "M_J_DQS_DN<15>")
	)
	(arc
		(start 116.435632 -56.199786)
		(mid 116.382162 -56.394849)
		(end 116.430806 -56.5912)
		(width 0.0889)
		(layer "In11.Cu")
		(net "M_J_DQS_DN<15>")
	)
	(arc
		(start 116.435632 -58.180986)
		(mid 116.382162 -58.376049)
		(end 116.430806 -58.5724)
		(width 0.0889)
		(layer "In11.Cu")
		(net "M_J_DQS_DN<15>")
	)
	(arc
		(start 116.435632 -59.571382)
		(mid 116.514763 -59.866784)
		(end 116.435632 -60.162186)
		(width 0.0889)
		(layer "In11.Cu")
		(net "M_J_DQS_DN<15>")
	)
	(arc
		(start 116.435632 -59.171586)
		(mid 116.382133 -59.371484)
		(end 116.435632 -59.571382)
		(width 0.0889)
		(layer "In11.Cu")
		(net "M_J_DQS_DN<15>")
	)
	(arc
		(start 116.441982 -55.619904)
		(mid 116.51478 -55.910667)
		(end 116.435632 -56.199786)
		(width 0.0889)
		(layer "In11.Cu")
		(net "M_J_DQS_DN<15>")
	)
	(arc
		(start 116.441982 -57.601104)
		(mid 116.51478 -57.891867)
		(end 116.435632 -58.180986)
		(width 0.0889)
		(layer "In11.Cu")
		(net "M_J_DQS_DN<15>")
	)
	(arc
		(start 116.435632 -60.162186)
		(mid 116.382162 -60.357249)
		(end 116.430806 -60.5536)
		(width 0.0889)
		(layer "In11.Cu")
		(net "M_J_DQS_DN<15>")
	)
	(arc
		(start 116.441982 -60.572904)
		(mid 116.51478 -60.863667)
		(end 116.435632 -61.152786)
		(width 0.0889)
		(layer "In11.Cu")
		(net "M_J_DQS_DN<15>")
	)
	(arc
		(start 116.441982 -56.610504)
		(mid 116.51478 -56.901267)
		(end 116.435632 -57.190386)
		(width 0.0889)
		(layer "In11.Cu")
		(net "M_J_DQS_DN<15>")
	)
	(arc
		(start 116.435632 -54.218586)
		(mid 116.382162 -54.413649)
		(end 116.430806 -54.61)
		(width 0.0889)
		(layer "In11.Cu")
		(net "M_J_DQS_DN<15>")
	)
	(arc
		(start 116.435632 -61.552836)
		(mid 116.629727 -61.9368)
		(end 116.780564 -62.339728)
		(width 0.0889)
		(layer "In11.Cu")
		(net "M_J_DQS_DN<15>")
	)
	(arc
		(start 116.435632 -58.581036)
		(mid 116.514854 -58.870154)
		(end 116.441982 -59.160918)
		(width 0.0889)
		(layer "In11.Cu")
		(net "M_J_DQS_DN<15>")
	)
	(arc
		(start 116.435632 -61.152786)
		(mid 116.38204 -61.352828)
		(end 116.435632 -61.552836)
		(width 0.0889)
		(layer "In11.Cu")
		(net "M_J_DQS_DN<15>")
	)
	(arc
		(start 116.441982 -54.629304)
		(mid 116.51478 -54.920067)
		(end 116.435632 -55.209186)
		(width 0.0889)
		(layer "In11.Cu")
		(net "M_J_DQS_DN<15>")
	)
	(segment
		(start 127.60706 1.60147)
		(end 127.41783 1.7907)
		(width 0.1651)
		(layer "F.Cu")
		(net "M_J_DQS_DN<14>")
	)
	(segment
		(start 114.778282 -58.876438)
		(end 114.206782 -58.876438)
		(width 0.0889)
		(layer "F.Cu")
		(net "M_J_DQS_DN<14>")
	)
	(segment
		(start 128.299464 2.93624)
		(end 127.88138 2.518156)
		(width 0.1651)
		(layer "F.Cu")
		(net "M_J_DQS_DN<14>")
	)
	(segment
		(start 127.88138 2.518156)
		(end 127.88138 2.286)
		(width 0.1651)
		(layer "F.Cu")
		(net "M_J_DQS_DN<14>")
	)
	(segment
		(start 128.067308 2.100072)
		(end 128.067308 1.853438)
		(width 0.1651)
		(layer "F.Cu")
		(net "M_J_DQS_DN<14>")
	)
	(segment
		(start 128.299464 3.778758)
		(end 128.299464 2.93624)
		(width 0.1651)
		(layer "F.Cu")
		(net "M_J_DQS_DN<14>")
	)
	(segment
		(start 127.41783 1.7907)
		(end 127.39878 1.7907)
		(width 0.1651)
		(layer "F.Cu")
		(net "M_J_DQS_DN<14>")
	)
	(segment
		(start 128.067308 1.853438)
		(end 127.81534 1.60147)
		(width 0.1651)
		(layer "F.Cu")
		(net "M_J_DQS_DN<14>")
	)
	(segment
		(start 127.81534 1.60147)
		(end 127.60706 1.60147)
		(width 0.1651)
		(layer "F.Cu")
		(net "M_J_DQS_DN<14>")
	)
	(segment
		(start 127.88138 2.286)
		(end 128.067308 2.100072)
		(width 0.1651)
		(layer "F.Cu")
		(net "M_J_DQS_DN<14>")
	)
	(via
		(at 127.392176 -3.6322)
		(size 0.508)
		(drill 0.254)
		(layers "F.Cu" "B.Cu")
		(net "M_J_DQS_DN<14>")
	)
	(via
		(at 127.39878 1.7907)
		(size 0.508)
		(drill 0.254)
		(layers "F.Cu" "B.Cu")
		(net "M_J_DQS_DN<14>")
	)
	(via
		(at 114.206782 -58.876438)
		(size 0.508)
		(drill 0.254)
		(layers "F.Cu" "B.Cu")
		(net "M_J_DQS_DN<14>")
	)
	(segment
		(start 128.03378 -3.6576)
		(end 127.813816 -3.437636)
		(width 0.1651)
		(layer "B.Cu")
		(net "M_J_DQS_DN<14>")
	)
	(segment
		(start 128.03378 -3.9878)
		(end 128.03378 -3.6576)
		(width 0.1651)
		(layer "B.Cu")
		(net "M_J_DQS_DN<14>")
	)
	(segment
		(start 127.58674 -3.437636)
		(end 127.392176 -3.6322)
		(width 0.1651)
		(layer "B.Cu")
		(net "M_J_DQS_DN<14>")
	)
	(segment
		(start 128.299464 -4.964938)
		(end 127.85598 -4.521454)
		(width 0.1651)
		(layer "B.Cu")
		(net "M_J_DQS_DN<14>")
	)
	(segment
		(start 127.85598 -4.1656)
		(end 128.03378 -3.9878)
		(width 0.1651)
		(layer "B.Cu")
		(net "M_J_DQS_DN<14>")
	)
	(segment
		(start 127.85598 -4.521454)
		(end 127.85598 -4.1656)
		(width 0.1651)
		(layer "B.Cu")
		(net "M_J_DQS_DN<14>")
	)
	(segment
		(start 128.299464 -5.621782)
		(end 128.299464 -4.964938)
		(width 0.1651)
		(layer "B.Cu")
		(net "M_J_DQS_DN<14>")
	)
	(segment
		(start 127.813816 -3.437636)
		(end 127.58674 -3.437636)
		(width 0.1651)
		(layer "B.Cu")
		(net "M_J_DQS_DN<14>")
	)
	(segment
		(start 113.860072 -53.723286)
		(end 113.855246 -53.731922)
		(width 0.0889)
		(layer "In4.Cu")
		(net "M_J_DQS_DN<14>")
	)
	(segment
		(start 128.31826 -30.85846)
		(end 127.74041 -31.43631)
		(width 0.14224)
		(layer "In4.Cu")
		(net "M_J_DQS_DN<14>")
	)
	(segment
		(start 117.17147 -46.374558)
		(end 117.17147 -46.628558)
		(width 0.14224)
		(layer "In4.Cu")
		(net "M_J_DQS_DN<14>")
	)
	(segment
		(start 119.47017 -39.793926)
		(end 119.290592 -39.973504)
		(width 0.14224)
		(layer "In4.Cu")
		(net "M_J_DQS_DN<14>")
	)
	(segment
		(start 127.1905 -5.254752)
		(end 128.174496 -6.238748)
		(width 0.14224)
		(layer "In4.Cu")
		(net "M_J_DQS_DN<14>")
	)
	(segment
		(start 117.0178 -48.263556)
		(end 115.212368 -50.068988)
		(width 0.0889)
		(layer "In4.Cu")
		(net "M_J_DQS_DN<14>")
	)
	(segment
		(start 118.712742 -40.551354)
		(end 118.712742 -40.712898)
		(width 0.14224)
		(layer "In4.Cu")
		(net "M_J_DQS_DN<14>")
	)
	(segment
		(start 117.17147 -43.576748)
		(end 117.05717 -43.691048)
		(width 0.14224)
		(layer "In4.Cu")
		(net "M_J_DQS_DN<14>")
	)
	(segment
		(start 128.174496 -10.62228)
		(end 128.174496 -30.14853)
		(width 0.14224)
		(layer "In4.Cu")
		(net "M_J_DQS_DN<14>")
	)
	(segment
		(start 113.993676 -58.663332)
		(end 114.206782 -58.876438)
		(width 0.0889)
		(layer "In4.Cu")
		(net "M_J_DQS_DN<14>")
	)
	(segment
		(start 117.17147 -43.322748)
		(end 117.17147 -43.576748)
		(width 0.14224)
		(layer "In4.Cu")
		(net "M_J_DQS_DN<14>")
	)
	(segment
		(start 119.631714 -39.793926)
		(end 119.47017 -39.793926)
		(width 0.14224)
		(layer "In4.Cu")
		(net "M_J_DQS_DN<14>")
	)
	(segment
		(start 127.62738 -4.8006)
		(end 127.37338 -4.8006)
		(width 0.14224)
		(layer "In4.Cu")
		(net "M_J_DQS_DN<14>")
	)
	(segment
		(start 128.174496 -9.86028)
		(end 128.174496 -10.05332)
		(width 0.14224)
		(layer "In4.Cu")
		(net "M_J_DQS_DN<14>")
	)
	(segment
		(start 115.212368 -51.23942)
		(end 114.397028 -52.05476)
		(width 0.0889)
		(layer "In4.Cu")
		(net "M_J_DQS_DN<14>")
	)
	(segment
		(start 126.45898 -32.805116)
		(end 119.811546 -39.45255)
		(width 0.14224)
		(layer "In4.Cu")
		(net "M_J_DQS_DN<14>")
	)
	(segment
		(start 113.860072 -57.685686)
		(end 113.855246 -57.694322)
		(width 0.0889)
		(layer "In4.Cu")
		(net "M_J_DQS_DN<14>")
	)
	(segment
		(start 128.174496 -9.29132)
		(end 128.331976 -9.4488)
		(width 0.14224)
		(layer "In4.Cu")
		(net "M_J_DQS_DN<14>")
	)
	(segment
		(start 128.331976 -10.4648)
		(end 128.174496 -10.62228)
		(width 0.14224)
		(layer "In4.Cu")
		(net "M_J_DQS_DN<14>")
	)
	(segment
		(start 118.184422 -41.241218)
		(end 118.00459 -41.42105)
		(width 0.14224)
		(layer "In4.Cu")
		(net "M_J_DQS_DN<14>")
	)
	(segment
		(start 117.17147 -44.313348)
		(end 117.05717 -44.427648)
		(width 0.14224)
		(layer "In4.Cu")
		(net "M_J_DQS_DN<14>")
	)
	(segment
		(start 117.17147 -46.628558)
		(end 117.05717 -46.742858)
		(width 0.14224)
		(layer "In4.Cu")
		(net "M_J_DQS_DN<14>")
	)
	(segment
		(start 117.578124 -41.847516)
		(end 117.398292 -42.027348)
		(width 0.14224)
		(layer "In4.Cu")
		(net "M_J_DQS_DN<14>")
	)
	(segment
		(start 113.93932 -53.314346)
		(end 113.93932 -53.430424)
		(width 0.0889)
		(layer "In4.Cu")
		(net "M_J_DQS_DN<14>")
	)
	(segment
		(start 117.05717 -45.418248)
		(end 117.17147 -45.532548)
		(width 0.14224)
		(layer "In4.Cu")
		(net "M_J_DQS_DN<14>")
	)
	(segment
		(start 119.290592 -39.973504)
		(end 119.290592 -40.135048)
		(width 0.14224)
		(layer "In4.Cu")
		(net "M_J_DQS_DN<14>")
	)
	(segment
		(start 119.11076 -40.31488)
		(end 118.949216 -40.31488)
		(width 0.14224)
		(layer "In4.Cu")
		(net "M_J_DQS_DN<14>")
	)
	(segment
		(start 126.395988 -30.921452)
		(end 125.922786 -31.394654)
		(width 0.14224)
		(layer "In4.Cu")
		(net "M_J_DQS_DN<14>")
	)
	(segment
		(start 128.174496 -6.238748)
		(end 128.174496 -9.29132)
		(width 0.14224)
		(layer "In4.Cu")
		(net "M_J_DQS_DN<14>")
	)
	(segment
		(start 117.236748 -42.027348)
		(end 117.05717 -42.206926)
		(width 0.14224)
		(layer "In4.Cu")
		(net "M_J_DQS_DN<14>")
	)
	(segment
		(start 128.331976 -9.7028)
		(end 128.174496 -9.86028)
		(width 0.14224)
		(layer "In4.Cu")
		(net "M_J_DQS_DN<14>")
	)
	(segment
		(start 117.05717 -43.945048)
		(end 117.17147 -44.059348)
		(width 0.14224)
		(layer "In4.Cu")
		(net "M_J_DQS_DN<14>")
	)
	(segment
		(start 119.811546 -39.45255)
		(end 119.811546 -39.614094)
		(width 0.14224)
		(layer "In4.Cu")
		(net "M_J_DQS_DN<14>")
	)
	(segment
		(start 114.397028 -52.05476)
		(end 114.397028 -52.856638)
		(width 0.0889)
		(layer "In4.Cu")
		(net "M_J_DQS_DN<14>")
	)
	(segment
		(start 118.53291 -40.89273)
		(end 118.371366 -40.89273)
		(width 0.14224)
		(layer "In4.Cu")
		(net "M_J_DQS_DN<14>")
	)
	(segment
		(start 128.331976 -9.4488)
		(end 128.331976 -9.7028)
		(width 0.14224)
		(layer "In4.Cu")
		(net "M_J_DQS_DN<14>")
	)
	(segment
		(start 126.660402 -30.921452)
		(end 126.395988 -30.921452)
		(width 0.14224)
		(layer "In4.Cu")
		(net "M_J_DQS_DN<14>")
	)
	(segment
		(start 113.934748 -58.50128)
		(end 113.934748 -58.521092)
		(width 0.0889)
		(layer "In4.Cu")
		(net "M_J_DQS_DN<14>")
	)
	(segment
		(start 113.866422 -56.684418)
		(end 113.860072 -56.695086)
		(width 0.0889)
		(layer "In4.Cu")
		(net "M_J_DQS_DN<14>")
	)
	(segment
		(start 115.212368 -50.068988)
		(end 115.212368 -51.23942)
		(width 0.0889)
		(layer "In4.Cu")
		(net "M_J_DQS_DN<14>")
	)
	(segment
		(start 128.31826 -30.292294)
		(end 128.31826 -30.85846)
		(width 0.14224)
		(layer "In4.Cu")
		(net "M_J_DQS_DN<14>")
	)
	(segment
		(start 113.937796 -58.423556)
		(end 113.935002 -58.489342)
		(width 0.0889)
		(layer "In4.Cu")
		(net "M_J_DQS_DN<14>")
	)
	(segment
		(start 118.184422 -41.079674)
		(end 118.184422 -41.241218)
		(width 0.14224)
		(layer "In4.Cu")
		(net "M_J_DQS_DN<14>")
	)
	(segment
		(start 127.392176 -3.6322)
		(end 127.83058 -4.070604)
		(width 0.14224)
		(layer "In4.Cu")
		(net "M_J_DQS_DN<14>")
	)
	(segment
		(start 127.74041 -31.43631)
		(end 127.17526 -31.43631)
		(width 0.14224)
		(layer "In4.Cu")
		(net "M_J_DQS_DN<14>")
	)
	(segment
		(start 113.860072 -55.704486)
		(end 113.855246 -55.713122)
		(width 0.0889)
		(layer "In4.Cu")
		(net "M_J_DQS_DN<14>")
	)
	(segment
		(start 113.866422 -57.675018)
		(end 113.860072 -57.685686)
		(width 0.0889)
		(layer "In4.Cu")
		(net "M_J_DQS_DN<14>")
	)
	(segment
		(start 128.174496 -30.14853)
		(end 128.31826 -30.292294)
		(width 0.14224)
		(layer "In4.Cu")
		(net "M_J_DQS_DN<14>")
	)
	(segment
		(start 114.397028 -52.856638)
		(end 113.93932 -53.314346)
		(width 0.0889)
		(layer "In4.Cu")
		(net "M_J_DQS_DN<14>")
	)
	(segment
		(start 127.37338 -4.8006)
		(end 127.1905 -4.98348)
		(width 0.14224)
		(layer "In4.Cu")
		(net "M_J_DQS_DN<14>")
	)
	(segment
		(start 117.05717 -45.900848)
		(end 117.05717 -46.260258)
		(width 0.14224)
		(layer "In4.Cu")
		(net "M_J_DQS_DN<14>")
	)
	(segment
		(start 117.0178 -47.336964)
		(end 117.0178 -48.263556)
		(width 0.0889)
		(layer "In4.Cu")
		(net "M_J_DQS_DN<14>")
	)
	(segment
		(start 117.05717 -47.297594)
		(end 117.0178 -47.336964)
		(width 0.0889)
		(layer "In4.Cu")
		(net "M_J_DQS_DN<14>")
	)
	(segment
		(start 117.05717 -45.164248)
		(end 117.05717 -45.418248)
		(width 0.14224)
		(layer "In4.Cu")
		(net "M_J_DQS_DN<14>")
	)
	(segment
		(start 117.05717 -43.691048)
		(end 117.05717 -43.945048)
		(width 0.14224)
		(layer "In4.Cu")
		(net "M_J_DQS_DN<14>")
	)
	(segment
		(start 127.83058 -4.070604)
		(end 127.83058 -4.5974)
		(width 0.14224)
		(layer "In4.Cu")
		(net "M_J_DQS_DN<14>")
	)
	(segment
		(start 117.17147 -45.532548)
		(end 117.17147 -45.786548)
		(width 0.14224)
		(layer "In4.Cu")
		(net "M_J_DQS_DN<14>")
	)
	(segment
		(start 117.05717 -46.742858)
		(end 117.05717 -47.275496)
		(width 0.14224)
		(layer "In4.Cu")
		(net "M_J_DQS_DN<14>")
	)
	(segment
		(start 127.83058 -4.5974)
		(end 127.62738 -4.8006)
		(width 0.14224)
		(layer "In4.Cu")
		(net "M_J_DQS_DN<14>")
	)
	(segment
		(start 117.17147 -44.795948)
		(end 117.17147 -45.049948)
		(width 0.14224)
		(layer "In4.Cu")
		(net "M_J_DQS_DN<14>")
	)
	(segment
		(start 125.922786 -31.70682)
		(end 126.45898 -32.243014)
		(width 0.14224)
		(layer "In4.Cu")
		(net "M_J_DQS_DN<14>")
	)
	(segment
		(start 117.398292 -42.027348)
		(end 117.236748 -42.027348)
		(width 0.14224)
		(layer "In4.Cu")
		(net "M_J_DQS_DN<14>")
	)
	(segment
		(start 118.949216 -40.31488)
		(end 118.712742 -40.551354)
		(width 0.14224)
		(layer "In4.Cu")
		(net "M_J_DQS_DN<14>")
	)
	(segment
		(start 119.290592 -40.135048)
		(end 119.11076 -40.31488)
		(width 0.14224)
		(layer "In4.Cu")
		(net "M_J_DQS_DN<14>")
	)
	(segment
		(start 117.05717 -44.427648)
		(end 117.05717 -44.681648)
		(width 0.14224)
		(layer "In4.Cu")
		(net "M_J_DQS_DN<14>")
	)
	(segment
		(start 113.860072 -56.695086)
		(end 113.855246 -56.703722)
		(width 0.0889)
		(layer "In4.Cu")
		(net "M_J_DQS_DN<14>")
	)
	(segment
		(start 117.05717 -43.208448)
		(end 117.17147 -43.322748)
		(width 0.14224)
		(layer "In4.Cu")
		(net "M_J_DQS_DN<14>")
	)
	(segment
		(start 127.17526 -31.43631)
		(end 126.660402 -30.921452)
		(width 0.14224)
		(layer "In4.Cu")
		(net "M_J_DQS_DN<14>")
	)
	(segment
		(start 118.712742 -40.712898)
		(end 118.53291 -40.89273)
		(width 0.14224)
		(layer "In4.Cu")
		(net "M_J_DQS_DN<14>")
	)
	(segment
		(start 118.00459 -41.42105)
		(end 117.843046 -41.42105)
		(width 0.14224)
		(layer "In4.Cu")
		(net "M_J_DQS_DN<14>")
	)
	(segment
		(start 128.331976 -10.2108)
		(end 128.331976 -10.4648)
		(width 0.14224)
		(layer "In4.Cu")
		(net "M_J_DQS_DN<14>")
	)
	(segment
		(start 113.866422 -54.703218)
		(end 113.860072 -54.713886)
		(width 0.0889)
		(layer "In4.Cu")
		(net "M_J_DQS_DN<14>")
	)
	(segment
		(start 117.05717 -46.260258)
		(end 117.17147 -46.374558)
		(width 0.14224)
		(layer "In4.Cu")
		(net "M_J_DQS_DN<14>")
	)
	(segment
		(start 128.174496 -10.05332)
		(end 128.331976 -10.2108)
		(width 0.14224)
		(layer "In4.Cu")
		(net "M_J_DQS_DN<14>")
	)
	(segment
		(start 113.866422 -55.693818)
		(end 113.860072 -55.704486)
		(width 0.0889)
		(layer "In4.Cu")
		(net "M_J_DQS_DN<14>")
	)
	(segment
		(start 117.05717 -47.275496)
		(end 117.05717 -47.297594)
		(width 0.0889)
		(layer "In4.Cu")
		(net "M_J_DQS_DN<14>")
	)
	(segment
		(start 117.843046 -41.42105)
		(end 117.578124 -41.685972)
		(width 0.14224)
		(layer "In4.Cu")
		(net "M_J_DQS_DN<14>")
	)
	(segment
		(start 113.860072 -54.713886)
		(end 113.855246 -54.722522)
		(width 0.0889)
		(layer "In4.Cu")
		(net "M_J_DQS_DN<14>")
	)
	(segment
		(start 125.922786 -31.394654)
		(end 125.922786 -31.70682)
		(width 0.14224)
		(layer "In4.Cu")
		(net "M_J_DQS_DN<14>")
	)
	(segment
		(start 119.811546 -39.614094)
		(end 119.631714 -39.793926)
		(width 0.14224)
		(layer "In4.Cu")
		(net "M_J_DQS_DN<14>")
	)
	(segment
		(start 118.371366 -40.89273)
		(end 118.184422 -41.079674)
		(width 0.14224)
		(layer "In4.Cu")
		(net "M_J_DQS_DN<14>")
	)
	(segment
		(start 117.05717 -44.681648)
		(end 117.17147 -44.795948)
		(width 0.14224)
		(layer "In4.Cu")
		(net "M_J_DQS_DN<14>")
	)
	(segment
		(start 117.17147 -44.059348)
		(end 117.17147 -44.313348)
		(width 0.14224)
		(layer "In4.Cu")
		(net "M_J_DQS_DN<14>")
	)
	(segment
		(start 117.17147 -45.049948)
		(end 117.05717 -45.164248)
		(width 0.14224)
		(layer "In4.Cu")
		(net "M_J_DQS_DN<14>")
	)
	(segment
		(start 127.1905 -4.98348)
		(end 127.1905 -5.254752)
		(width 0.14224)
		(layer "In4.Cu")
		(net "M_J_DQS_DN<14>")
	)
	(segment
		(start 117.578124 -41.685972)
		(end 117.578124 -41.847516)
		(width 0.14224)
		(layer "In4.Cu")
		(net "M_J_DQS_DN<14>")
	)
	(segment
		(start 126.45898 -32.243014)
		(end 126.45898 -32.805116)
		(width 0.14224)
		(layer "In4.Cu")
		(net "M_J_DQS_DN<14>")
	)
	(segment
		(start 117.05717 -42.206926)
		(end 117.05717 -43.208448)
		(width 0.14224)
		(layer "In4.Cu")
		(net "M_J_DQS_DN<14>")
	)
	(segment
		(start 117.17147 -45.786548)
		(end 117.05717 -45.900848)
		(width 0.14224)
		(layer "In4.Cu")
		(net "M_J_DQS_DN<14>")
	)
	(arc
		(start 113.855246 -53.731922)
		(mid 113.806491 -53.928274)
		(end 113.860072 -54.123336)
		(width 0.0889)
		(layer "In4.Cu")
		(net "M_J_DQS_DN<14>")
	)
	(arc
		(start 113.860072 -56.104536)
		(mid 113.939294 -56.393654)
		(end 113.866422 -56.684418)
		(width 0.0889)
		(layer "In4.Cu")
		(net "M_J_DQS_DN<14>")
	)
	(arc
		(start 113.93932 -53.430424)
		(mid 113.918805 -53.582026)
		(end 113.860072 -53.723286)
		(width 0.0889)
		(layer "In4.Cu")
		(net "M_J_DQS_DN<14>")
	)
	(arc
		(start 113.905538 -58.18378)
		(mid 113.934081 -58.301999)
		(end 113.937796 -58.423556)
		(width 0.0889)
		(layer "In4.Cu")
		(net "M_J_DQS_DN<14>")
	)
	(arc
		(start 113.855246 -56.703722)
		(mid 113.806491 -56.900074)
		(end 113.860072 -57.095136)
		(width 0.0889)
		(layer "In4.Cu")
		(net "M_J_DQS_DN<14>")
	)
	(arc
		(start 113.860072 -57.095136)
		(mid 113.939294 -57.384254)
		(end 113.866422 -57.675018)
		(width 0.0889)
		(layer "In4.Cu")
		(net "M_J_DQS_DN<14>")
	)
	(arc
		(start 113.855246 -54.722522)
		(mid 113.806491 -54.918874)
		(end 113.860072 -55.113936)
		(width 0.0889)
		(layer "In4.Cu")
		(net "M_J_DQS_DN<14>")
	)
	(arc
		(start 113.860072 -54.123336)
		(mid 113.939294 -54.412454)
		(end 113.866422 -54.703218)
		(width 0.0889)
		(layer "In4.Cu")
		(net "M_J_DQS_DN<14>")
	)
	(arc
		(start 113.934748 -58.521092)
		(mid 113.950061 -58.598076)
		(end 113.993676 -58.663332)
		(width 0.0889)
		(layer "In4.Cu")
		(net "M_J_DQS_DN<14>")
	)
	(arc
		(start 113.860072 -55.113936)
		(mid 113.939294 -55.403054)
		(end 113.866422 -55.693818)
		(width 0.0889)
		(layer "In4.Cu")
		(net "M_J_DQS_DN<14>")
	)
	(arc
		(start 113.860072 -58.085736)
		(mid 113.88505 -58.133717)
		(end 113.905538 -58.18378)
		(width 0.0889)
		(layer "In4.Cu")
		(net "M_J_DQS_DN<14>")
	)
	(arc
		(start 113.935002 -58.489342)
		(mid 113.934812 -58.49531)
		(end 113.934748 -58.50128)
		(width 0.0889)
		(layer "In4.Cu")
		(net "M_J_DQS_DN<14>")
	)
	(arc
		(start 113.855246 -55.713122)
		(mid 113.806491 -55.909474)
		(end 113.860072 -56.104536)
		(width 0.0889)
		(layer "In4.Cu")
		(net "M_J_DQS_DN<14>")
	)
	(arc
		(start 113.855246 -57.694322)
		(mid 113.806491 -57.890674)
		(end 113.860072 -58.085736)
		(width 0.0889)
		(layer "In4.Cu")
		(net "M_J_DQS_DN<14>")
	)
	(segment
		(start 127.59436 1.59512)
		(end 127.39878 1.7907)
		(width 0.14224)
		(layer "In11.Cu")
		(net "M_J_DQS_DN<14>")
	)
	(segment
		(start 127.392176 -3.6322)
		(end 128.1811 -2.843276)
		(width 0.14224)
		(layer "In11.Cu")
		(net "M_J_DQS_DN<14>")
	)
	(segment
		(start 128.1811 -2.843276)
		(end 128.1811 1.257808)
		(width 0.14224)
		(layer "In11.Cu")
		(net "M_J_DQS_DN<14>")
	)
	(segment
		(start 127.843788 1.59512)
		(end 127.59436 1.59512)
		(width 0.14224)
		(layer "In11.Cu")
		(net "M_J_DQS_DN<14>")
	)
	(segment
		(start 128.1811 1.257808)
		(end 127.843788 1.59512)
		(width 0.14224)
		(layer "In11.Cu")
		(net "M_J_DQS_DN<14>")
	)
	(segment
		(start 118.256812 1.60147)
		(end 118.067582 1.7907)
		(width 0.1651)
		(layer "F.Cu")
		(net "M_J_DQS_DN<13>")
	)
	(segment
		(start 118.94947 3.778758)
		(end 118.94947 2.936494)
		(width 0.1651)
		(layer "F.Cu")
		(net "M_J_DQS_DN<13>")
	)
	(segment
		(start 118.71706 1.853438)
		(end 118.465092 1.60147)
		(width 0.1651)
		(layer "F.Cu")
		(net "M_J_DQS_DN<13>")
	)
	(segment
		(start 118.531132 2.518156)
		(end 118.531132 2.286)
		(width 0.1651)
		(layer "F.Cu")
		(net "M_J_DQS_DN<13>")
	)
	(segment
		(start 118.531132 2.286)
		(end 118.71706 2.100072)
		(width 0.1651)
		(layer "F.Cu")
		(net "M_J_DQS_DN<13>")
	)
	(segment
		(start 118.71706 2.100072)
		(end 118.71706 1.853438)
		(width 0.1651)
		(layer "F.Cu")
		(net "M_J_DQS_DN<13>")
	)
	(segment
		(start 118.067582 1.7907)
		(end 118.048532 1.7907)
		(width 0.1651)
		(layer "F.Cu")
		(net "M_J_DQS_DN<13>")
	)
	(segment
		(start 109.627416 -58.876438)
		(end 109.055916 -58.876438)
		(width 0.0889)
		(layer "F.Cu")
		(net "M_J_DQS_DN<13>")
	)
	(segment
		(start 118.465092 1.60147)
		(end 118.256812 1.60147)
		(width 0.1651)
		(layer "F.Cu")
		(net "M_J_DQS_DN<13>")
	)
	(segment
		(start 118.94947 2.936494)
		(end 118.531132 2.518156)
		(width 0.1651)
		(layer "F.Cu")
		(net "M_J_DQS_DN<13>")
	)
	(via
		(at 118.041928 -3.6322)
		(size 0.508)
		(drill 0.254)
		(layers "F.Cu" "B.Cu")
		(net "M_J_DQS_DN<13>")
	)
	(via
		(at 118.048532 1.7907)
		(size 0.508)
		(drill 0.254)
		(layers "F.Cu" "B.Cu")
		(net "M_J_DQS_DN<13>")
	)
	(via
		(at 109.055916 -58.876438)
		(size 0.508)
		(drill 0.254)
		(layers "F.Cu" "B.Cu")
		(net "M_J_DQS_DN<13>")
	)
	(segment
		(start 118.505732 -4.521454)
		(end 118.505732 -4.1656)
		(width 0.1651)
		(layer "B.Cu")
		(net "M_J_DQS_DN<13>")
	)
	(segment
		(start 118.94947 -5.621782)
		(end 118.94947 -4.965192)
		(width 0.1651)
		(layer "B.Cu")
		(net "M_J_DQS_DN<13>")
	)
	(segment
		(start 118.505732 -4.1656)
		(end 118.683532 -3.9878)
		(width 0.1651)
		(layer "B.Cu")
		(net "M_J_DQS_DN<13>")
	)
	(segment
		(start 118.683532 -3.6576)
		(end 118.463568 -3.437636)
		(width 0.1651)
		(layer "B.Cu")
		(net "M_J_DQS_DN<13>")
	)
	(segment
		(start 118.683532 -3.9878)
		(end 118.683532 -3.6576)
		(width 0.1651)
		(layer "B.Cu")
		(net "M_J_DQS_DN<13>")
	)
	(segment
		(start 118.236492 -3.437636)
		(end 118.041928 -3.6322)
		(width 0.1651)
		(layer "B.Cu")
		(net "M_J_DQS_DN<13>")
	)
	(segment
		(start 118.94947 -4.965192)
		(end 118.505732 -4.521454)
		(width 0.1651)
		(layer "B.Cu")
		(net "M_J_DQS_DN<13>")
	)
	(segment
		(start 118.463568 -3.437636)
		(end 118.236492 -3.437636)
		(width 0.1651)
		(layer "B.Cu")
		(net "M_J_DQS_DN<13>")
	)
	(segment
		(start 110.070392 -38.852856)
		(end 110.257844 -38.665404)
		(width 0.14224)
		(layer "In11.Cu")
		(net "M_J_DQS_DN<13>")
	)
	(segment
		(start 109.055916 -58.874406)
		(end 109.054138 -58.872628)
		(width 0.0889)
		(layer "In11.Cu")
		(net "M_J_DQS_DN<13>")
	)
	(segment
		(start 110.070392 -39.0144)
		(end 110.070392 -38.852856)
		(width 0.14224)
		(layer "In11.Cu")
		(net "M_J_DQS_DN<13>")
	)
	(segment
		(start 109.510068 -47.804832)
		(end 109.510068 -47.30877)
		(width 0.0889)
		(layer "In11.Cu")
		(net "M_J_DQS_DN<13>")
	)
	(segment
		(start 109.055916 -58.876438)
		(end 109.055916 -58.874406)
		(width 0.0889)
		(layer "In11.Cu")
		(net "M_J_DQS_DN<13>")
	)
	(segment
		(start 118.830852 1.257808)
		(end 118.49354 1.59512)
		(width 0.14224)
		(layer "In11.Cu")
		(net "M_J_DQS_DN<13>")
	)
	(segment
		(start 118.49354 1.59512)
		(end 118.244112 1.59512)
		(width 0.14224)
		(layer "In11.Cu")
		(net "M_J_DQS_DN<13>")
	)
	(segment
		(start 109.549438 -47.247302)
		(end 109.549438 -46.486826)
		(width 0.14224)
		(layer "In11.Cu")
		(net "M_J_DQS_DN<13>")
	)
	(segment
		(start 109.549438 -42.931588)
		(end 109.549438 -42.677588)
		(width 0.14224)
		(layer "In11.Cu")
		(net "M_J_DQS_DN<13>")
	)
	(segment
		(start 117.943376 -28.81249)
		(end 117.721888 -28.591002)
		(width 0.14224)
		(layer "In11.Cu")
		(net "M_J_DQS_DN<13>")
	)
	(segment
		(start 109.549438 -40.6781)
		(end 109.549438 -40.4241)
		(width 0.14224)
		(layer "In11.Cu")
		(net "M_J_DQS_DN<13>")
	)
	(segment
		(start 108.838238 -52.18684)
		(end 109.230414 -51.794664)
		(width 0.0889)
		(layer "In11.Cu")
		(net "M_J_DQS_DN<13>")
	)
	(segment
		(start 109.549438 -44.901866)
		(end 109.663738 -44.787566)
		(width 0.14224)
		(layer "In11.Cu")
		(net "M_J_DQS_DN<13>")
	)
	(segment
		(start 109.549438 -39.9415)
		(end 109.549438 -39.37381)
		(width 0.14224)
		(layer "In11.Cu")
		(net "M_J_DQS_DN<13>")
	)
	(segment
		(start 109.663738 -44.787566)
		(end 109.663738 -44.533566)
		(width 0.14224)
		(layer "In11.Cu")
		(net "M_J_DQS_DN<13>")
	)
	(segment
		(start 108.70438 -55.713122)
		(end 108.709206 -55.704486)
		(width 0.0889)
		(layer "In11.Cu")
		(net "M_J_DQS_DN<13>")
	)
	(segment
		(start 109.729016 -39.194232)
		(end 109.89056 -39.194232)
		(width 0.14224)
		(layer "In11.Cu")
		(net "M_J_DQS_DN<13>")
	)
	(segment
		(start 118.830852 -2.843276)
		(end 118.830852 1.257808)
		(width 0.14224)
		(layer "In11.Cu")
		(net "M_J_DQS_DN<13>")
	)
	(segment
		(start 109.510068 -47.30877)
		(end 109.549438 -47.2694)
		(width 0.0889)
		(layer "In11.Cu")
		(net "M_J_DQS_DN<13>")
	)
	(segment
		(start 110.419388 -38.665404)
		(end 110.59922 -38.485572)
		(width 0.14224)
		(layer "In11.Cu")
		(net "M_J_DQS_DN<13>")
	)
	(segment
		(start 108.838238 -52.817268)
		(end 108.838238 -52.18684)
		(width 0.0889)
		(layer "In11.Cu")
		(net "M_J_DQS_DN<13>")
	)
	(segment
		(start 118.824502 -15.44828)
		(end 118.981982 -15.2908)
		(width 0.14224)
		(layer "In11.Cu")
		(net "M_J_DQS_DN<13>")
	)
	(segment
		(start 109.663738 -44.533566)
		(end 109.549438 -44.419266)
		(width 0.14224)
		(layer "In11.Cu")
		(net "M_J_DQS_DN<13>")
	)
	(segment
		(start 109.663738 -43.782488)
		(end 109.549438 -43.668188)
		(width 0.14224)
		(layer "In11.Cu")
		(net "M_J_DQS_DN<13>")
	)
	(segment
		(start 118.277132 -4.8006)
		(end 118.480332 -4.5974)
		(width 0.14224)
		(layer "In11.Cu")
		(net "M_J_DQS_DN<13>")
	)
	(segment
		(start 108.70438 -56.703722)
		(end 108.709206 -56.695086)
		(width 0.0889)
		(layer "In11.Cu")
		(net "M_J_DQS_DN<13>")
	)
	(segment
		(start 109.549438 -45.267626)
		(end 109.549438 -44.901866)
		(width 0.14224)
		(layer "In11.Cu")
		(net "M_J_DQS_DN<13>")
	)
	(segment
		(start 109.663738 -46.372526)
		(end 109.663738 -46.118526)
		(width 0.14224)
		(layer "In11.Cu")
		(net "M_J_DQS_DN<13>")
	)
	(segment
		(start 117.968776 -27.73553)
		(end 118.859554 -27.73553)
		(width 0.14224)
		(layer "In11.Cu")
		(net "M_J_DQS_DN<13>")
	)
	(segment
		(start 109.663738 -40.3098)
		(end 109.663738 -40.0558)
		(width 0.14224)
		(layer "In11.Cu")
		(net "M_J_DQS_DN<13>")
	)
	(segment
		(start 109.663738 -41.783)
		(end 109.663738 -41.529)
		(width 0.14224)
		(layer "In11.Cu")
		(net "M_J_DQS_DN<13>")
	)
	(segment
		(start 109.663738 -41.0464)
		(end 109.663738 -40.7924)
		(width 0.14224)
		(layer "In11.Cu")
		(net "M_J_DQS_DN<13>")
	)
	(segment
		(start 108.70438 -57.694322)
		(end 108.709206 -57.685686)
		(width 0.0889)
		(layer "In11.Cu")
		(net "M_J_DQS_DN<13>")
	)
	(segment
		(start 119.144288 -27.450796)
		(end 119.144288 -25.412192)
		(width 0.14224)
		(layer "In11.Cu")
		(net "M_J_DQS_DN<13>")
	)
	(segment
		(start 109.549438 -43.414188)
		(end 109.663738 -43.299888)
		(width 0.14224)
		(layer "In11.Cu")
		(net "M_J_DQS_DN<13>")
	)
	(segment
		(start 118.244112 1.59512)
		(end 118.048532 1.7907)
		(width 0.14224)
		(layer "In11.Cu")
		(net "M_J_DQS_DN<13>")
	)
	(segment
		(start 109.549438 -42.677588)
		(end 109.663738 -42.563288)
		(width 0.14224)
		(layer "In11.Cu")
		(net "M_J_DQS_DN<13>")
	)
	(segment
		(start 109.549438 -40.4241)
		(end 109.663738 -40.3098)
		(width 0.14224)
		(layer "In11.Cu")
		(net "M_J_DQS_DN<13>")
	)
	(segment
		(start 108.636562 -54.987952)
		(end 108.636562 -53.018944)
		(width 0.0889)
		(layer "In11.Cu")
		(net "M_J_DQS_DN<13>")
	)
	(segment
		(start 109.663738 -45.381926)
		(end 109.549438 -45.267626)
		(width 0.14224)
		(layer "In11.Cu")
		(net "M_J_DQS_DN<13>")
	)
	(segment
		(start 117.840252 -4.98348)
		(end 118.023132 -4.8006)
		(width 0.14224)
		(layer "In11.Cu")
		(net "M_J_DQS_DN<13>")
	)
	(segment
		(start 109.549438 -43.668188)
		(end 109.549438 -43.414188)
		(width 0.14224)
		(layer "In11.Cu")
		(net "M_J_DQS_DN<13>")
	)
	(segment
		(start 109.549438 -41.4147)
		(end 109.549438 -41.1607)
		(width 0.14224)
		(layer "In11.Cu")
		(net "M_J_DQS_DN<13>")
	)
	(segment
		(start 117.840252 -5.254752)
		(end 117.840252 -4.98348)
		(width 0.14224)
		(layer "In11.Cu")
		(net "M_J_DQS_DN<13>")
	)
	(segment
		(start 118.981982 -14.5288)
		(end 118.981982 -14.2748)
		(width 0.14224)
		(layer "In11.Cu")
		(net "M_J_DQS_DN<13>")
	)
	(segment
		(start 109.663738 -46.118526)
		(end 109.549438 -46.004226)
		(width 0.14224)
		(layer "In11.Cu")
		(net "M_J_DQS_DN<13>")
	)
	(segment
		(start 109.549438 -46.486826)
		(end 109.663738 -46.372526)
		(width 0.14224)
		(layer "In11.Cu")
		(net "M_J_DQS_DN<13>")
	)
	(segment
		(start 118.824502 -6.239002)
		(end 117.840252 -5.254752)
		(width 0.14224)
		(layer "In11.Cu")
		(net "M_J_DQS_DN<13>")
	)
	(segment
		(start 110.59922 -38.324028)
		(end 119.144288 -29.77896)
		(width 0.14224)
		(layer "In11.Cu")
		(net "M_J_DQS_DN<13>")
	)
	(segment
		(start 108.709206 -55.113936)
		(end 108.636562 -54.987952)
		(width 0.0889)
		(layer "In11.Cu")
		(net "M_J_DQS_DN<13>")
	)
	(segment
		(start 109.89056 -39.194232)
		(end 110.070392 -39.0144)
		(width 0.14224)
		(layer "In11.Cu")
		(net "M_J_DQS_DN<13>")
	)
	(segment
		(start 118.023132 -4.8006)
		(end 118.277132 -4.8006)
		(width 0.14224)
		(layer "In11.Cu")
		(net "M_J_DQS_DN<13>")
	)
	(segment
		(start 108.709206 -56.695086)
		(end 108.715556 -56.684418)
		(width 0.0889)
		(layer "In11.Cu")
		(net "M_J_DQS_DN<13>")
	)
	(segment
		(start 110.257844 -38.665404)
		(end 110.419388 -38.665404)
		(width 0.14224)
		(layer "In11.Cu")
		(net "M_J_DQS_DN<13>")
	)
	(segment
		(start 109.663738 -41.529)
		(end 109.549438 -41.4147)
		(width 0.14224)
		(layer "In11.Cu")
		(net "M_J_DQS_DN<13>")
	)
	(segment
		(start 118.480332 -4.070604)
		(end 118.041928 -3.6322)
		(width 0.14224)
		(layer "In11.Cu")
		(net "M_J_DQS_DN<13>")
	)
	(segment
		(start 109.549438 -47.2694)
		(end 109.549438 -47.247302)
		(width 0.0889)
		(layer "In11.Cu")
		(net "M_J_DQS_DN<13>")
	)
	(segment
		(start 109.663738 -42.563288)
		(end 109.663738 -42.309288)
		(width 0.14224)
		(layer "In11.Cu")
		(net "M_J_DQS_DN<13>")
	)
	(segment
		(start 108.709206 -57.685686)
		(end 108.715556 -57.675018)
		(width 0.0889)
		(layer "In11.Cu")
		(net "M_J_DQS_DN<13>")
	)
	(segment
		(start 109.549438 -45.750226)
		(end 109.663738 -45.635926)
		(width 0.14224)
		(layer "In11.Cu")
		(net "M_J_DQS_DN<13>")
	)
	(segment
		(start 118.824502 -14.68628)
		(end 118.981982 -14.5288)
		(width 0.14224)
		(layer "In11.Cu")
		(net "M_J_DQS_DN<13>")
	)
	(segment
		(start 118.981982 -15.0368)
		(end 118.824502 -14.87932)
		(width 0.14224)
		(layer "In11.Cu")
		(net "M_J_DQS_DN<13>")
	)
	(segment
		(start 118.041928 -3.6322)
		(end 118.830852 -2.843276)
		(width 0.14224)
		(layer "In11.Cu")
		(net "M_J_DQS_DN<13>")
	)
	(segment
		(start 108.636562 -53.018944)
		(end 108.838238 -52.817268)
		(width 0.0889)
		(layer "In11.Cu")
		(net "M_J_DQS_DN<13>")
	)
	(segment
		(start 119.144288 -29.77896)
		(end 119.144288 -29.190696)
		(width 0.14224)
		(layer "In11.Cu")
		(net "M_J_DQS_DN<13>")
	)
	(segment
		(start 109.663738 -45.635926)
		(end 109.663738 -45.381926)
		(width 0.14224)
		(layer "In11.Cu")
		(net "M_J_DQS_DN<13>")
	)
	(segment
		(start 109.663738 -40.0558)
		(end 109.549438 -39.9415)
		(width 0.14224)
		(layer "In11.Cu")
		(net "M_J_DQS_DN<13>")
	)
	(segment
		(start 109.663738 -40.7924)
		(end 109.549438 -40.6781)
		(width 0.14224)
		(layer "In11.Cu")
		(net "M_J_DQS_DN<13>")
	)
	(segment
		(start 118.824502 -25.092406)
		(end 118.824502 -15.44828)
		(width 0.14224)
		(layer "In11.Cu")
		(net "M_J_DQS_DN<13>")
	)
	(segment
		(start 119.144288 -29.190696)
		(end 118.766082 -28.81249)
		(width 0.14224)
		(layer "In11.Cu")
		(net "M_J_DQS_DN<13>")
	)
	(segment
		(start 109.549438 -41.1607)
		(end 109.663738 -41.0464)
		(width 0.14224)
		(layer "In11.Cu")
		(net "M_J_DQS_DN<13>")
	)
	(segment
		(start 109.663738 -42.309288)
		(end 109.549438 -42.194988)
		(width 0.14224)
		(layer "In11.Cu")
		(net "M_J_DQS_DN<13>")
	)
	(segment
		(start 118.824502 -14.87932)
		(end 118.824502 -14.68628)
		(width 0.14224)
		(layer "In11.Cu")
		(net "M_J_DQS_DN<13>")
	)
	(segment
		(start 118.981982 -15.2908)
		(end 118.981982 -15.0368)
		(width 0.14224)
		(layer "In11.Cu")
		(net "M_J_DQS_DN<13>")
	)
	(segment
		(start 109.663738 -43.045888)
		(end 109.549438 -42.931588)
		(width 0.14224)
		(layer "In11.Cu")
		(net "M_J_DQS_DN<13>")
	)
	(segment
		(start 118.480332 -4.5974)
		(end 118.480332 -4.070604)
		(width 0.14224)
		(layer "In11.Cu")
		(net "M_J_DQS_DN<13>")
	)
	(segment
		(start 109.549438 -42.194988)
		(end 109.549438 -41.8973)
		(width 0.14224)
		(layer "In11.Cu")
		(net "M_J_DQS_DN<13>")
	)
	(segment
		(start 109.549438 -46.004226)
		(end 109.549438 -45.750226)
		(width 0.14224)
		(layer "In11.Cu")
		(net "M_J_DQS_DN<13>")
	)
	(segment
		(start 110.59922 -38.485572)
		(end 110.59922 -38.324028)
		(width 0.14224)
		(layer "In11.Cu")
		(net "M_J_DQS_DN<13>")
	)
	(segment
		(start 117.721888 -27.982418)
		(end 117.968776 -27.73553)
		(width 0.14224)
		(layer "In11.Cu")
		(net "M_J_DQS_DN<13>")
	)
	(segment
		(start 109.663738 -44.036488)
		(end 109.663738 -43.782488)
		(width 0.14224)
		(layer "In11.Cu")
		(net "M_J_DQS_DN<13>")
	)
	(segment
		(start 117.721888 -28.591002)
		(end 117.721888 -27.982418)
		(width 0.14224)
		(layer "In11.Cu")
		(net "M_J_DQS_DN<13>")
	)
	(segment
		(start 109.549438 -39.37381)
		(end 109.729016 -39.194232)
		(width 0.14224)
		(layer "In11.Cu")
		(net "M_J_DQS_DN<13>")
	)
	(segment
		(start 118.824502 -14.11732)
		(end 118.824502 -6.239002)
		(width 0.14224)
		(layer "In11.Cu")
		(net "M_J_DQS_DN<13>")
	)
	(segment
		(start 118.766082 -28.81249)
		(end 117.943376 -28.81249)
		(width 0.14224)
		(layer "In11.Cu")
		(net "M_J_DQS_DN<13>")
	)
	(segment
		(start 109.549438 -44.419266)
		(end 109.549438 -44.150788)
		(width 0.14224)
		(layer "In11.Cu")
		(net "M_J_DQS_DN<13>")
	)
	(segment
		(start 109.230414 -48.084486)
		(end 109.510068 -47.804832)
		(width 0.0889)
		(layer "In11.Cu")
		(net "M_J_DQS_DN<13>")
	)
	(segment
		(start 118.981982 -14.2748)
		(end 118.824502 -14.11732)
		(width 0.14224)
		(layer "In11.Cu")
		(net "M_J_DQS_DN<13>")
	)
	(segment
		(start 109.549438 -44.150788)
		(end 109.663738 -44.036488)
		(width 0.14224)
		(layer "In11.Cu")
		(net "M_J_DQS_DN<13>")
	)
	(segment
		(start 108.709206 -55.704486)
		(end 108.715556 -55.693818)
		(width 0.0889)
		(layer "In11.Cu")
		(net "M_J_DQS_DN<13>")
	)
	(segment
		(start 109.549438 -41.8973)
		(end 109.663738 -41.783)
		(width 0.14224)
		(layer "In11.Cu")
		(net "M_J_DQS_DN<13>")
	)
	(segment
		(start 109.663738 -43.299888)
		(end 109.663738 -43.045888)
		(width 0.14224)
		(layer "In11.Cu")
		(net "M_J_DQS_DN<13>")
	)
	(segment
		(start 109.230414 -51.794664)
		(end 109.230414 -48.084486)
		(width 0.0889)
		(layer "In11.Cu")
		(net "M_J_DQS_DN<13>")
	)
	(segment
		(start 119.144288 -25.412192)
		(end 118.824502 -25.092406)
		(width 0.14224)
		(layer "In11.Cu")
		(net "M_J_DQS_DN<13>")
	)
	(segment
		(start 118.859554 -27.73553)
		(end 119.144288 -27.450796)
		(width 0.14224)
		(layer "In11.Cu")
		(net "M_J_DQS_DN<13>")
	)
	(arc
		(start 108.715556 -55.693818)
		(mid 108.788354 -55.403055)
		(end 108.709206 -55.113936)
		(width 0.0889)
		(layer "In11.Cu")
		(net "M_J_DQS_DN<13>")
	)
	(arc
		(start 108.715556 -57.675018)
		(mid 108.788354 -57.384255)
		(end 108.709206 -57.095136)
		(width 0.0889)
		(layer "In11.Cu")
		(net "M_J_DQS_DN<13>")
	)
	(arc
		(start 108.709206 -58.085736)
		(mid 108.655736 -57.890673)
		(end 108.70438 -57.694322)
		(width 0.0889)
		(layer "In11.Cu")
		(net "M_J_DQS_DN<13>")
	)
	(arc
		(start 108.709206 -56.104536)
		(mid 108.655736 -55.909473)
		(end 108.70438 -55.713122)
		(width 0.0889)
		(layer "In11.Cu")
		(net "M_J_DQS_DN<13>")
	)
	(arc
		(start 109.054138 -58.872628)
		(mid 108.90332 -58.469692)
		(end 108.709206 -58.085736)
		(width 0.0889)
		(layer "In11.Cu")
		(net "M_J_DQS_DN<13>")
	)
	(arc
		(start 108.715556 -56.684418)
		(mid 108.788354 -56.393655)
		(end 108.709206 -56.104536)
		(width 0.0889)
		(layer "In11.Cu")
		(net "M_J_DQS_DN<13>")
	)
	(arc
		(start 108.709206 -57.095136)
		(mid 108.655736 -56.900073)
		(end 108.70438 -56.703722)
		(width 0.0889)
		(layer "In11.Cu")
		(net "M_J_DQS_DN<13>")
	)
	(segment
		(start 63.69939 2.93624)
		(end 63.281306 2.518156)
		(width 0.1651)
		(layer "F.Cu")
		(net "M_J_DQS_DN<12>")
	)
	(segment
		(start 62.817756 1.7907)
		(end 62.798706 1.7907)
		(width 0.1651)
		(layer "F.Cu")
		(net "M_J_DQS_DN<12>")
	)
	(segment
		(start 63.281306 2.518156)
		(end 63.281306 2.286)
		(width 0.1651)
		(layer "F.Cu")
		(net "M_J_DQS_DN<12>")
	)
	(segment
		(start 63.467234 2.100072)
		(end 63.467234 1.853438)
		(width 0.1651)
		(layer "F.Cu")
		(net "M_J_DQS_DN<12>")
	)
	(segment
		(start 63.467234 1.853438)
		(end 63.215266 1.60147)
		(width 0.1651)
		(layer "F.Cu")
		(net "M_J_DQS_DN<12>")
	)
	(segment
		(start 63.69939 3.778758)
		(end 63.69939 2.93624)
		(width 0.1651)
		(layer "F.Cu")
		(net "M_J_DQS_DN<12>")
	)
	(segment
		(start 63.281306 2.286)
		(end 63.467234 2.100072)
		(width 0.1651)
		(layer "F.Cu")
		(net "M_J_DQS_DN<12>")
	)
	(segment
		(start 63.215266 1.60147)
		(end 63.006986 1.60147)
		(width 0.1651)
		(layer "F.Cu")
		(net "M_J_DQS_DN<12>")
	)
	(segment
		(start 63.006986 1.60147)
		(end 62.817756 1.7907)
		(width 0.1651)
		(layer "F.Cu")
		(net "M_J_DQS_DN<12>")
	)
	(segment
		(start 84.919312 -64.50584)
		(end 84.347812 -64.50584)
		(width 0.1651)
		(layer "F.Cu")
		(net "M_J_DQS_DN<12>")
	)
	(via
		(at 84.347812 -64.50584)
		(size 0.508)
		(drill 0.254)
		(layers "F.Cu" "B.Cu")
		(net "M_J_DQS_DN<12>")
	)
	(via
		(at 62.792102 -3.6322)
		(size 0.508)
		(drill 0.254)
		(layers "F.Cu" "B.Cu")
		(net "M_J_DQS_DN<12>")
	)
	(via
		(at 62.798706 1.7907)
		(size 0.508)
		(drill 0.254)
		(layers "F.Cu" "B.Cu")
		(net "M_J_DQS_DN<12>")
	)
	(segment
		(start 62.986666 -3.437636)
		(end 62.792102 -3.6322)
		(width 0.1651)
		(layer "B.Cu")
		(net "M_J_DQS_DN<12>")
	)
	(segment
		(start 63.213742 -3.437636)
		(end 62.986666 -3.437636)
		(width 0.1651)
		(layer "B.Cu")
		(net "M_J_DQS_DN<12>")
	)
	(segment
		(start 63.69939 -5.621782)
		(end 63.69939 -4.964938)
		(width 0.1651)
		(layer "B.Cu")
		(net "M_J_DQS_DN<12>")
	)
	(segment
		(start 63.69939 -4.964938)
		(end 63.255906 -4.521454)
		(width 0.1651)
		(layer "B.Cu")
		(net "M_J_DQS_DN<12>")
	)
	(segment
		(start 63.255906 -4.521454)
		(end 63.255906 -4.1656)
		(width 0.1651)
		(layer "B.Cu")
		(net "M_J_DQS_DN<12>")
	)
	(segment
		(start 63.255906 -4.1656)
		(end 63.433706 -3.9878)
		(width 0.1651)
		(layer "B.Cu")
		(net "M_J_DQS_DN<12>")
	)
	(segment
		(start 63.433706 -3.6576)
		(end 63.213742 -3.437636)
		(width 0.1651)
		(layer "B.Cu")
		(net "M_J_DQS_DN<12>")
	)
	(segment
		(start 63.433706 -3.9878)
		(end 63.433706 -3.6576)
		(width 0.1651)
		(layer "B.Cu")
		(net "M_J_DQS_DN<12>")
	)
	(segment
		(start 65.413636 -30.93974)
		(end 65.413636 -31.476188)
		(width 0.14224)
		(layer "In11.Cu")
		(net "M_J_DQS_DN<12>")
	)
	(segment
		(start 63.574422 -10.86612)
		(end 63.731902 -11.0236)
		(width 0.14224)
		(layer "In11.Cu")
		(net "M_J_DQS_DN<12>")
	)
	(segment
		(start 78.297532 -46.192186)
		(end 78.459076 -46.192186)
		(width 0.14224)
		(layer "In11.Cu")
		(net "M_J_DQS_DN<12>")
	)
	(segment
		(start 65.282318 -32.836866)
		(end 65.576958 -32.836866)
		(width 0.14224)
		(layer "In11.Cu")
		(net "M_J_DQS_DN<12>")
	)
	(segment
		(start 83.997546 -63.708788)
		(end 83.998054 -63.70955)
		(width 0.0889)
		(layer "In11.Cu")
		(net "M_J_DQS_DN<12>")
	)
	(segment
		(start 83.998816 -63.71082)
		(end 84.00034 -63.713868)
		(width 0.0889)
		(layer "In11.Cu")
		(net "M_J_DQS_DN<12>")
	)
	(segment
		(start 83.996276 -60.734702)
		(end 84.001102 -60.743338)
		(width 0.0889)
		(layer "In11.Cu")
		(net "M_J_DQS_DN<12>")
	)
	(segment
		(start 79.921608 -48.829722)
		(end 79.921608 -49.135792)
		(width 0.14224)
		(layer "In11.Cu")
		(net "M_J_DQS_DN<12>")
	)
	(segment
		(start 83.996276 -63.706502)
		(end 83.997038 -63.707772)
		(width 0.0889)
		(layer "In11.Cu")
		(net "M_J_DQS_DN<12>")
	)
	(segment
		(start 63.581026 -2.843276)
		(end 62.792102 -3.6322)
		(width 0.14224)
		(layer "In11.Cu")
		(net "M_J_DQS_DN<12>")
	)
	(segment
		(start 84.131658 -63.979298)
		(end 84.357718 -64.501522)
		(width 0.0889)
		(layer "In11.Cu")
		(net "M_J_DQS_DN<12>")
	)
	(segment
		(start 75.579986 -43.47464)
		(end 75.74153 -43.47464)
		(width 0.14224)
		(layer "In11.Cu")
		(net "M_J_DQS_DN<12>")
	)
	(segment
		(start 83.998054 -63.70955)
		(end 83.998816 -63.71082)
		(width 0.0889)
		(layer "In11.Cu")
		(net "M_J_DQS_DN<12>")
	)
	(segment
		(start 75.921362 -43.654472)
		(end 75.921362 -43.816016)
		(width 0.14224)
		(layer "In11.Cu")
		(net "M_J_DQS_DN<12>")
	)
	(segment
		(start 64.799718 -32.090106)
		(end 64.799718 -32.354266)
		(width 0.14224)
		(layer "In11.Cu")
		(net "M_J_DQS_DN<12>")
	)
	(segment
		(start 63.581026 1.257808)
		(end 63.581026 -2.843276)
		(width 0.14224)
		(layer "In11.Cu")
		(net "M_J_DQS_DN<12>")
	)
	(segment
		(start 62.994286 1.59512)
		(end 63.243714 1.59512)
		(width 0.14224)
		(layer "In11.Cu")
		(net "M_J_DQS_DN<12>")
	)
	(segment
		(start 76.10094 -43.995594)
		(end 76.262484 -43.995594)
		(width 0.14224)
		(layer "In11.Cu")
		(net "M_J_DQS_DN<12>")
	)
	(segment
		(start 83.996276 -61.725302)
		(end 84.001102 -61.733938)
		(width 0.0889)
		(layer "In11.Cu")
		(net "M_J_DQS_DN<12>")
	)
	(segment
		(start 79.921608 -47.816262)
		(end 79.921608 -48.347122)
		(width 0.14224)
		(layer "In11.Cu")
		(net "M_J_DQS_DN<12>")
	)
	(segment
		(start 78.091538 -45.824394)
		(end 78.091538 -45.986192)
		(width 0.14224)
		(layer "In11.Cu")
		(net "M_J_DQS_DN<12>")
	)
	(segment
		(start 81.907634 -51.177698)
		(end 82.084672 -51.484784)
		(width 0.0889)
		(layer "In11.Cu")
		(net "M_J_DQS_DN<12>")
	)
	(segment
		(start 79.921608 -49.135792)
		(end 81.201768 -50.415952)
		(width 0.14224)
		(layer "In11.Cu")
		(net "M_J_DQS_DN<12>")
	)
	(segment
		(start 78.091538 -45.986192)
		(end 78.297532 -46.192186)
		(width 0.14224)
		(layer "In11.Cu")
		(net "M_J_DQS_DN<12>")
	)
	(segment
		(start 63.574422 -10.67308)
		(end 63.574422 -10.86612)
		(width 0.14224)
		(layer "In11.Cu")
		(net "M_J_DQS_DN<12>")
	)
	(segment
		(start 63.731902 -14.605)
		(end 63.574422 -14.76248)
		(width 0.14224)
		(layer "In11.Cu")
		(net "M_J_DQS_DN<12>")
	)
	(segment
		(start 76.442316 -44.33697)
		(end 76.64069 -44.535344)
		(width 0.14224)
		(layer "In11.Cu")
		(net "M_J_DQS_DN<12>")
	)
	(segment
		(start 63.731902 -11.2776)
		(end 63.574422 -11.43508)
		(width 0.14224)
		(layer "In11.Cu")
		(net "M_J_DQS_DN<12>")
	)
	(segment
		(start 63.731902 -11.0236)
		(end 63.731902 -11.2776)
		(width 0.14224)
		(layer "In11.Cu")
		(net "M_J_DQS_DN<12>")
	)
	(segment
		(start 63.574422 -14.19352)
		(end 63.731902 -14.351)
		(width 0.14224)
		(layer "In11.Cu")
		(net "M_J_DQS_DN<12>")
	)
	(segment
		(start 84.001102 -61.733938)
		(end 84.007452 -61.744606)
		(width 0.0889)
		(layer "In11.Cu")
		(net "M_J_DQS_DN<12>")
	)
	(segment
		(start 63.731902 -10.5156)
		(end 63.574422 -10.67308)
		(width 0.14224)
		(layer "In11.Cu")
		(net "M_J_DQS_DN<12>")
	)
	(segment
		(start 78.638908 -46.372018)
		(end 78.638908 -46.533562)
		(width 0.14224)
		(layer "In11.Cu")
		(net "M_J_DQS_DN<12>")
	)
	(segment
		(start 78.638908 -46.533562)
		(end 78.818486 -46.71314)
		(width 0.14224)
		(layer "In11.Cu")
		(net "M_J_DQS_DN<12>")
	)
	(segment
		(start 79.159862 -47.054516)
		(end 79.393288 -47.287942)
		(width 0.14224)
		(layer "In11.Cu")
		(net "M_J_DQS_DN<12>")
	)
	(segment
		(start 62.590426 -4.98348)
		(end 62.590426 -5.356352)
		(width 0.14224)
		(layer "In11.Cu")
		(net "M_J_DQS_DN<12>")
	)
	(segment
		(start 76.442316 -44.175426)
		(end 76.442316 -44.33697)
		(width 0.14224)
		(layer "In11.Cu")
		(net "M_J_DQS_DN<12>")
	)
	(segment
		(start 76.64069 -44.535344)
		(end 76.802488 -44.535344)
		(width 0.14224)
		(layer "In11.Cu")
		(net "M_J_DQS_DN<12>")
	)
	(segment
		(start 80.035908 -48.715422)
		(end 79.921608 -48.829722)
		(width 0.14224)
		(layer "In11.Cu")
		(net "M_J_DQS_DN<12>")
	)
	(segment
		(start 77.57033 -45.464984)
		(end 77.749908 -45.644562)
		(width 0.14224)
		(layer "In11.Cu")
		(net "M_J_DQS_DN<12>")
	)
	(segment
		(start 84.357718 -64.501522)
		(end 84.347812 -64.50584)
		(width 0.0889)
		(layer "In11.Cu")
		(net "M_J_DQS_DN<12>")
	)
	(segment
		(start 84.001102 -62.724538)
		(end 84.007452 -62.735206)
		(width 0.0889)
		(layer "In11.Cu")
		(net "M_J_DQS_DN<12>")
	)
	(segment
		(start 81.217516 -50.4317)
		(end 81.217516 -50.48758)
		(width 0.0889)
		(layer "In11.Cu")
		(net "M_J_DQS_DN<12>")
	)
	(segment
		(start 75.74153 -43.47464)
		(end 75.921362 -43.654472)
		(width 0.14224)
		(layer "In11.Cu")
		(net "M_J_DQS_DN<12>")
	)
	(segment
		(start 82.084672 -52.01158)
		(end 83.311492 -53.2384)
		(width 0.0889)
		(layer "In11.Cu")
		(net "M_J_DQS_DN<12>")
	)
	(segment
		(start 83.996276 -59.744102)
		(end 84.001102 -59.752738)
		(width 0.0889)
		(layer "In11.Cu")
		(net "M_J_DQS_DN<12>")
	)
	(segment
		(start 63.243714 1.59512)
		(end 63.581026 1.257808)
		(width 0.14224)
		(layer "In11.Cu")
		(net "M_J_DQS_DN<12>")
	)
	(segment
		(start 64.799718 -32.354266)
		(end 65.282318 -32.836866)
		(width 0.14224)
		(layer "In11.Cu")
		(net "M_J_DQS_DN<12>")
	)
	(segment
		(start 63.574422 -14.76248)
		(end 63.574422 -29.100526)
		(width 0.14224)
		(layer "In11.Cu")
		(net "M_J_DQS_DN<12>")
	)
	(segment
		(start 69.561202 -37.455856)
		(end 75.579986 -43.47464)
		(width 0.14224)
		(layer "In11.Cu")
		(net "M_J_DQS_DN<12>")
	)
	(segment
		(start 63.731902 -14.351)
		(end 63.731902 -14.605)
		(width 0.14224)
		(layer "In11.Cu")
		(net "M_J_DQS_DN<12>")
	)
	(segment
		(start 63.574422 -9.34212)
		(end 63.731902 -9.4996)
		(width 0.14224)
		(layer "In11.Cu")
		(net "M_J_DQS_DN<12>")
	)
	(segment
		(start 62.938914 -4.8006)
		(end 62.773306 -4.8006)
		(width 0.14224)
		(layer "In11.Cu")
		(net "M_J_DQS_DN<12>")
	)
	(segment
		(start 63.230506 -4.070604)
		(end 63.230506 -4.509008)
		(width 0.14224)
		(layer "In11.Cu")
		(net "M_J_DQS_DN<12>")
	)
	(segment
		(start 63.574422 -6.340348)
		(end 63.574422 -9.34212)
		(width 0.14224)
		(layer "In11.Cu")
		(net "M_J_DQS_DN<12>")
	)
	(segment
		(start 83.997038 -63.707772)
		(end 83.997546 -63.708788)
		(width 0.0889)
		(layer "In11.Cu")
		(net "M_J_DQS_DN<12>")
	)
	(segment
		(start 76.802488 -44.535344)
		(end 76.98232 -44.715176)
		(width 0.14224)
		(layer "In11.Cu")
		(net "M_J_DQS_DN<12>")
	)
	(segment
		(start 83.311492 -53.2384)
		(end 83.311492 -54.734714)
		(width 0.0889)
		(layer "In11.Cu")
		(net "M_J_DQS_DN<12>")
	)
	(segment
		(start 82.084672 -51.484784)
		(end 82.084672 -52.01158)
		(width 0.0889)
		(layer "In11.Cu")
		(net "M_J_DQS_DN<12>")
	)
	(segment
		(start 79.734918 -47.629572)
		(end 79.921608 -47.816262)
		(width 0.14224)
		(layer "In11.Cu")
		(net "M_J_DQS_DN<12>")
	)
	(segment
		(start 63.230506 -4.509008)
		(end 62.938914 -4.8006)
		(width 0.14224)
		(layer "In11.Cu")
		(net "M_J_DQS_DN<12>")
	)
	(segment
		(start 78.98003 -46.71314)
		(end 79.159862 -46.892972)
		(width 0.14224)
		(layer "In11.Cu")
		(net "M_J_DQS_DN<12>")
	)
	(segment
		(start 84.001102 -60.743338)
		(end 84.007452 -60.754006)
		(width 0.0889)
		(layer "In11.Cu")
		(net "M_J_DQS_DN<12>")
	)
	(segment
		(start 62.792102 -3.6322)
		(end 63.230506 -4.070604)
		(width 0.14224)
		(layer "In11.Cu")
		(net "M_J_DQS_DN<12>")
	)
	(segment
		(start 63.731902 -9.7536)
		(end 63.574422 -9.91108)
		(width 0.14224)
		(layer "In11.Cu")
		(net "M_J_DQS_DN<12>")
	)
	(segment
		(start 83.996276 -56.772302)
		(end 84.001102 -56.780938)
		(width 0.0889)
		(layer "In11.Cu")
		(net "M_J_DQS_DN<12>")
	)
	(segment
		(start 76.262484 -43.995594)
		(end 76.442316 -44.175426)
		(width 0.14224)
		(layer "In11.Cu")
		(net "M_J_DQS_DN<12>")
	)
	(segment
		(start 79.393288 -47.287942)
		(end 79.555086 -47.287942)
		(width 0.14224)
		(layer "In11.Cu")
		(net "M_J_DQS_DN<12>")
	)
	(segment
		(start 81.217516 -50.48758)
		(end 81.907634 -51.177698)
		(width 0.0889)
		(layer "In11.Cu")
		(net "M_J_DQS_DN<12>")
	)
	(segment
		(start 79.921608 -48.347122)
		(end 80.035908 -48.461422)
		(width 0.14224)
		(layer "In11.Cu")
		(net "M_J_DQS_DN<12>")
	)
	(segment
		(start 63.574422 -11.43508)
		(end 63.574422 -14.19352)
		(width 0.14224)
		(layer "In11.Cu")
		(net "M_J_DQS_DN<12>")
	)
	(segment
		(start 76.98232 -44.876974)
		(end 77.228954 -45.123608)
		(width 0.14224)
		(layer "In11.Cu")
		(net "M_J_DQS_DN<12>")
	)
	(segment
		(start 76.98232 -44.715176)
		(end 76.98232 -44.876974)
		(width 0.14224)
		(layer "In11.Cu")
		(net "M_J_DQS_DN<12>")
	)
	(segment
		(start 84.00034 -63.713868)
		(end 84.007452 -63.725806)
		(width 0.0889)
		(layer "In11.Cu")
		(net "M_J_DQS_DN<12>")
	)
	(segment
		(start 77.749908 -45.644562)
		(end 77.911706 -45.644562)
		(width 0.14224)
		(layer "In11.Cu")
		(net "M_J_DQS_DN<12>")
	)
	(segment
		(start 63.574422 -9.91108)
		(end 63.574422 -10.10412)
		(width 0.14224)
		(layer "In11.Cu")
		(net "M_J_DQS_DN<12>")
	)
	(segment
		(start 75.921362 -43.816016)
		(end 76.10094 -43.995594)
		(width 0.14224)
		(layer "In11.Cu")
		(net "M_J_DQS_DN<12>")
	)
	(segment
		(start 81.201768 -50.415952)
		(end 81.217516 -50.4317)
		(width 0.0889)
		(layer "In11.Cu")
		(net "M_J_DQS_DN<12>")
	)
	(segment
		(start 63.731902 -10.2616)
		(end 63.731902 -10.5156)
		(width 0.14224)
		(layer "In11.Cu")
		(net "M_J_DQS_DN<12>")
	)
	(segment
		(start 77.911706 -45.644562)
		(end 78.091538 -45.824394)
		(width 0.14224)
		(layer "In11.Cu")
		(net "M_J_DQS_DN<12>")
	)
	(segment
		(start 62.773306 -4.8006)
		(end 62.590426 -4.98348)
		(width 0.14224)
		(layer "In11.Cu")
		(net "M_J_DQS_DN<12>")
	)
	(segment
		(start 79.159862 -46.892972)
		(end 79.159862 -47.054516)
		(width 0.14224)
		(layer "In11.Cu")
		(net "M_J_DQS_DN<12>")
	)
	(segment
		(start 69.561202 -35.087306)
		(end 69.561202 -37.455856)
		(width 0.14224)
		(layer "In11.Cu")
		(net "M_J_DQS_DN<12>")
	)
	(segment
		(start 66.175636 -32.238188)
		(end 66.712084 -32.238188)
		(width 0.14224)
		(layer "In11.Cu")
		(net "M_J_DQS_DN<12>")
	)
	(segment
		(start 65.413636 -31.476188)
		(end 64.799718 -32.090106)
		(width 0.14224)
		(layer "In11.Cu")
		(net "M_J_DQS_DN<12>")
	)
	(segment
		(start 63.574422 -29.100526)
		(end 65.413636 -30.93974)
		(width 0.14224)
		(layer "In11.Cu")
		(net "M_J_DQS_DN<12>")
	)
	(segment
		(start 78.818486 -46.71314)
		(end 78.98003 -46.71314)
		(width 0.14224)
		(layer "In11.Cu")
		(net "M_J_DQS_DN<12>")
	)
	(segment
		(start 83.53679 -54.960012)
		(end 84.007452 -55.801006)
		(width 0.0889)
		(layer "In11.Cu")
		(net "M_J_DQS_DN<12>")
	)
	(segment
		(start 84.001102 -59.752738)
		(end 84.007452 -59.763406)
		(width 0.0889)
		(layer "In11.Cu")
		(net "M_J_DQS_DN<12>")
	)
	(segment
		(start 62.590426 -5.356352)
		(end 63.574422 -6.340348)
		(width 0.14224)
		(layer "In11.Cu")
		(net "M_J_DQS_DN<12>")
	)
	(segment
		(start 63.731902 -9.4996)
		(end 63.731902 -9.7536)
		(width 0.14224)
		(layer "In11.Cu")
		(net "M_J_DQS_DN<12>")
	)
	(segment
		(start 83.996276 -57.762902)
		(end 84.001102 -57.771538)
		(width 0.0889)
		(layer "In11.Cu")
		(net "M_J_DQS_DN<12>")
	)
	(segment
		(start 84.001102 -56.780938)
		(end 84.007452 -56.791606)
		(width 0.0889)
		(layer "In11.Cu")
		(net "M_J_DQS_DN<12>")
	)
	(segment
		(start 65.576958 -32.836866)
		(end 66.175636 -32.238188)
		(width 0.14224)
		(layer "In11.Cu")
		(net "M_J_DQS_DN<12>")
	)
	(segment
		(start 79.555086 -47.287942)
		(end 79.734918 -47.467774)
		(width 0.14224)
		(layer "In11.Cu")
		(net "M_J_DQS_DN<12>")
	)
	(segment
		(start 77.390498 -45.123608)
		(end 77.57033 -45.30344)
		(width 0.14224)
		(layer "In11.Cu")
		(net "M_J_DQS_DN<12>")
	)
	(segment
		(start 63.574422 -10.10412)
		(end 63.731902 -10.2616)
		(width 0.14224)
		(layer "In11.Cu")
		(net "M_J_DQS_DN<12>")
	)
	(segment
		(start 83.996276 -62.715902)
		(end 84.001102 -62.724538)
		(width 0.0889)
		(layer "In11.Cu")
		(net "M_J_DQS_DN<12>")
	)
	(segment
		(start 62.798706 1.7907)
		(end 62.994286 1.59512)
		(width 0.14224)
		(layer "In11.Cu")
		(net "M_J_DQS_DN<12>")
	)
	(segment
		(start 77.228954 -45.123608)
		(end 77.390498 -45.123608)
		(width 0.14224)
		(layer "In11.Cu")
		(net "M_J_DQS_DN<12>")
	)
	(segment
		(start 78.459076 -46.192186)
		(end 78.638908 -46.372018)
		(width 0.14224)
		(layer "In11.Cu")
		(net "M_J_DQS_DN<12>")
	)
	(segment
		(start 79.734918 -47.467774)
		(end 79.734918 -47.629572)
		(width 0.14224)
		(layer "In11.Cu")
		(net "M_J_DQS_DN<12>")
	)
	(segment
		(start 80.035908 -48.461422)
		(end 80.035908 -48.715422)
		(width 0.14224)
		(layer "In11.Cu")
		(net "M_J_DQS_DN<12>")
	)
	(segment
		(start 83.311492 -54.734714)
		(end 83.53679 -54.960012)
		(width 0.0889)
		(layer "In11.Cu")
		(net "M_J_DQS_DN<12>")
	)
	(segment
		(start 66.712084 -32.238188)
		(end 69.561202 -35.087306)
		(width 0.14224)
		(layer "In11.Cu")
		(net "M_J_DQS_DN<12>")
	)
	(segment
		(start 77.57033 -45.30344)
		(end 77.57033 -45.464984)
		(width 0.14224)
		(layer "In11.Cu")
		(net "M_J_DQS_DN<12>")
	)
	(segment
		(start 84.007452 -58.35142)
		(end 84.001102 -58.362088)
		(width 0.0889)
		(layer "In11.Cu")
		(net "M_J_DQS_DN<12>")
	)
	(arc
		(start 84.001102 -56.380888)
		(mid 83.947632 -56.575951)
		(end 83.996276 -56.772302)
		(width 0.0889)
		(layer "In11.Cu")
		(net "M_J_DQS_DN<12>")
	)
	(arc
		(start 84.007452 -59.763406)
		(mid 84.08025 -60.054169)
		(end 84.001102 -60.343288)
		(width 0.0889)
		(layer "In11.Cu")
		(net "M_J_DQS_DN<12>")
	)
	(arc
		(start 84.001102 -57.771538)
		(mid 84.080324 -58.060656)
		(end 84.007452 -58.35142)
		(width 0.0889)
		(layer "In11.Cu")
		(net "M_J_DQS_DN<12>")
	)
	(arc
		(start 84.007452 -55.801006)
		(mid 84.08025 -56.091769)
		(end 84.001102 -56.380888)
		(width 0.0889)
		(layer "In11.Cu")
		(net "M_J_DQS_DN<12>")
	)
	(arc
		(start 84.001102 -61.333888)
		(mid 83.947632 -61.528951)
		(end 83.996276 -61.725302)
		(width 0.0889)
		(layer "In11.Cu")
		(net "M_J_DQS_DN<12>")
	)
	(arc
		(start 84.007452 -63.725806)
		(mid 84.072534 -63.851092)
		(end 84.131658 -63.979298)
		(width 0.0889)
		(layer "In11.Cu")
		(net "M_J_DQS_DN<12>")
	)
	(arc
		(start 84.001102 -58.362088)
		(mid 83.947603 -58.561986)
		(end 84.001102 -58.761884)
		(width 0.0889)
		(layer "In11.Cu")
		(net "M_J_DQS_DN<12>")
	)
	(arc
		(start 84.001102 -57.371488)
		(mid 83.947632 -57.566551)
		(end 83.996276 -57.762902)
		(width 0.0889)
		(layer "In11.Cu")
		(net "M_J_DQS_DN<12>")
	)
	(arc
		(start 84.007452 -60.754006)
		(mid 84.08025 -61.044769)
		(end 84.001102 -61.333888)
		(width 0.0889)
		(layer "In11.Cu")
		(net "M_J_DQS_DN<12>")
	)
	(arc
		(start 84.001102 -63.315088)
		(mid 83.947632 -63.510151)
		(end 83.996276 -63.706502)
		(width 0.0889)
		(layer "In11.Cu")
		(net "M_J_DQS_DN<12>")
	)
	(arc
		(start 84.001102 -60.343288)
		(mid 83.947632 -60.538351)
		(end 83.996276 -60.734702)
		(width 0.0889)
		(layer "In11.Cu")
		(net "M_J_DQS_DN<12>")
	)
	(arc
		(start 84.001102 -59.352688)
		(mid 83.947632 -59.547751)
		(end 83.996276 -59.744102)
		(width 0.0889)
		(layer "In11.Cu")
		(net "M_J_DQS_DN<12>")
	)
	(arc
		(start 84.007452 -61.744606)
		(mid 84.08025 -62.035369)
		(end 84.001102 -62.324488)
		(width 0.0889)
		(layer "In11.Cu")
		(net "M_J_DQS_DN<12>")
	)
	(arc
		(start 84.007452 -56.791606)
		(mid 84.08025 -57.082369)
		(end 84.001102 -57.371488)
		(width 0.0889)
		(layer "In11.Cu")
		(net "M_J_DQS_DN<12>")
	)
	(arc
		(start 84.007452 -62.735206)
		(mid 84.08025 -63.025969)
		(end 84.001102 -63.315088)
		(width 0.0889)
		(layer "In11.Cu")
		(net "M_J_DQS_DN<12>")
	)
	(arc
		(start 84.001102 -62.324488)
		(mid 83.947632 -62.519551)
		(end 83.996276 -62.715902)
		(width 0.0889)
		(layer "In11.Cu")
		(net "M_J_DQS_DN<12>")
	)
	(arc
		(start 84.001102 -58.761884)
		(mid 84.080233 -59.057286)
		(end 84.001102 -59.352688)
		(width 0.0889)
		(layer "In11.Cu")
		(net "M_J_DQS_DN<12>")
	)
	(segment
		(start 53.656992 1.60147)
		(end 53.467762 1.7907)
		(width 0.1651)
		(layer "F.Cu")
		(net "M_J_DQS_DN<11>")
	)
	(segment
		(start 79.768192 -57.57164)
		(end 79.196692 -57.57164)
		(width 0.0889)
		(layer "F.Cu")
		(net "M_J_DQS_DN<11>")
	)
	(segment
		(start 54.349396 2.93624)
		(end 53.931312 2.518156)
		(width 0.1651)
		(layer "F.Cu")
		(net "M_J_DQS_DN<11>")
	)
	(segment
		(start 54.11724 1.853438)
		(end 53.865272 1.60147)
		(width 0.1651)
		(layer "F.Cu")
		(net "M_J_DQS_DN<11>")
	)
	(segment
		(start 53.865272 1.60147)
		(end 53.656992 1.60147)
		(width 0.1651)
		(layer "F.Cu")
		(net "M_J_DQS_DN<11>")
	)
	(segment
		(start 53.467762 1.7907)
		(end 53.448712 1.7907)
		(width 0.1651)
		(layer "F.Cu")
		(net "M_J_DQS_DN<11>")
	)
	(segment
		(start 53.931312 2.286)
		(end 54.11724 2.100072)
		(width 0.1651)
		(layer "F.Cu")
		(net "M_J_DQS_DN<11>")
	)
	(segment
		(start 53.931312 2.518156)
		(end 53.931312 2.286)
		(width 0.1651)
		(layer "F.Cu")
		(net "M_J_DQS_DN<11>")
	)
	(segment
		(start 54.11724 2.100072)
		(end 54.11724 1.853438)
		(width 0.1651)
		(layer "F.Cu")
		(net "M_J_DQS_DN<11>")
	)
	(segment
		(start 54.349396 3.778758)
		(end 54.349396 2.93624)
		(width 0.1651)
		(layer "F.Cu")
		(net "M_J_DQS_DN<11>")
	)
	(via
		(at 79.196692 -57.57164)
		(size 0.508)
		(drill 0.254)
		(layers "F.Cu" "B.Cu")
		(net "M_J_DQS_DN<11>")
	)
	(via
		(at 53.442108 -3.6322)
		(size 0.508)
		(drill 0.254)
		(layers "F.Cu" "B.Cu")
		(net "M_J_DQS_DN<11>")
	)
	(via
		(at 53.448712 1.7907)
		(size 0.508)
		(drill 0.254)
		(layers "F.Cu" "B.Cu")
		(net "M_J_DQS_DN<11>")
	)
	(segment
		(start 53.863748 -3.437636)
		(end 53.636672 -3.437636)
		(width 0.1651)
		(layer "B.Cu")
		(net "M_J_DQS_DN<11>")
	)
	(segment
		(start 53.636672 -3.437636)
		(end 53.442108 -3.6322)
		(width 0.1651)
		(layer "B.Cu")
		(net "M_J_DQS_DN<11>")
	)
	(segment
		(start 54.349396 -5.621782)
		(end 54.349396 -4.964938)
		(width 0.1651)
		(layer "B.Cu")
		(net "M_J_DQS_DN<11>")
	)
	(segment
		(start 53.905912 -4.521454)
		(end 53.905912 -4.1656)
		(width 0.1651)
		(layer "B.Cu")
		(net "M_J_DQS_DN<11>")
	)
	(segment
		(start 54.083712 -3.9878)
		(end 54.083712 -3.6576)
		(width 0.1651)
		(layer "B.Cu")
		(net "M_J_DQS_DN<11>")
	)
	(segment
		(start 54.083712 -3.6576)
		(end 53.863748 -3.437636)
		(width 0.1651)
		(layer "B.Cu")
		(net "M_J_DQS_DN<11>")
	)
	(segment
		(start 54.349396 -4.964938)
		(end 53.905912 -4.521454)
		(width 0.1651)
		(layer "B.Cu")
		(net "M_J_DQS_DN<11>")
	)
	(segment
		(start 53.905912 -4.1656)
		(end 54.083712 -3.9878)
		(width 0.1651)
		(layer "B.Cu")
		(net "M_J_DQS_DN<11>")
	)
	(segment
		(start 53.677312 -4.8006)
		(end 53.880512 -4.5974)
		(width 0.14224)
		(layer "In11.Cu")
		(net "M_J_DQS_DN<11>")
	)
	(segment
		(start 64.053212 -43.428412)
		(end 63.873634 -43.248834)
		(width 0.14224)
		(layer "In11.Cu")
		(net "M_J_DQS_DN<11>")
	)
	(segment
		(start 66.79946 -47.134018)
		(end 66.79946 -46.17466)
		(width 0.14224)
		(layer "In11.Cu")
		(net "M_J_DQS_DN<11>")
	)
	(segment
		(start 54.381908 -11.2776)
		(end 54.381908 -11.0236)
		(width 0.14224)
		(layer "In11.Cu")
		(net "M_J_DQS_DN<11>")
	)
	(segment
		(start 54.381908 -9.7536)
		(end 54.381908 -9.4996)
		(width 0.14224)
		(layer "In11.Cu")
		(net "M_J_DQS_DN<11>")
	)
	(segment
		(start 53.423312 -4.8006)
		(end 53.677312 -4.8006)
		(width 0.14224)
		(layer "In11.Cu")
		(net "M_J_DQS_DN<11>")
	)
	(segment
		(start 65.957704 -45.332904)
		(end 65.957704 -45.171106)
		(width 0.14224)
		(layer "In11.Cu")
		(net "M_J_DQS_DN<11>")
	)
	(segment
		(start 77.504798 -56.98109)
		(end 77.46873 -56.98109)
		(width 0.0889)
		(layer "In11.Cu")
		(net "M_J_DQS_DN<11>")
	)
	(segment
		(start 64.915542 -44.290742)
		(end 64.915542 -44.129198)
		(width 0.14224)
		(layer "In11.Cu")
		(net "M_J_DQS_DN<11>")
	)
	(segment
		(start 54.224428 -9.91108)
		(end 54.381908 -9.7536)
		(width 0.14224)
		(layer "In11.Cu")
		(net "M_J_DQS_DN<11>")
	)
	(segment
		(start 54.552088 -26.973276)
		(end 54.17312 -26.594308)
		(width 0.14224)
		(layer "In11.Cu")
		(net "M_J_DQS_DN<11>")
	)
	(segment
		(start 66.42227 -45.635926)
		(end 66.260726 -45.635926)
		(width 0.14224)
		(layer "In11.Cu")
		(net "M_J_DQS_DN<11>")
	)
	(segment
		(start 62.07887 -41.292526)
		(end 61.917326 -41.292526)
		(width 0.14224)
		(layer "In11.Cu")
		(net "M_J_DQS_DN<11>")
	)
	(segment
		(start 54.224428 -9.34212)
		(end 54.224428 -6.238748)
		(width 0.14224)
		(layer "In11.Cu")
		(net "M_J_DQS_DN<11>")
	)
	(segment
		(start 74.922126 -55.494936)
		(end 74.88936 -55.494936)
		(width 0.0889)
		(layer "In11.Cu")
		(net "M_J_DQS_DN<11>")
	)
	(segment
		(start 71.488046 -53.513736)
		(end 71.45528 -53.513736)
		(width 0.0889)
		(layer "In11.Cu")
		(net "M_J_DQS_DN<11>")
	)
	(segment
		(start 63.873634 -43.08729)
		(end 63.693802 -42.907458)
		(width 0.14224)
		(layer "In11.Cu")
		(net "M_J_DQS_DN<11>")
	)
	(segment
		(start 54.012846 -26.594308)
		(end 53.612288 -26.19375)
		(width 0.14224)
		(layer "In11.Cu")
		(net "M_J_DQS_DN<11>")
	)
	(segment
		(start 65.777872 -44.991274)
		(end 65.616074 -44.991274)
		(width 0.14224)
		(layer "In11.Cu")
		(net "M_J_DQS_DN<11>")
	)
	(segment
		(start 54.224428 -10.10412)
		(end 54.224428 -9.91108)
		(width 0.14224)
		(layer "In11.Cu")
		(net "M_J_DQS_DN<11>")
	)
	(segment
		(start 62.49035 -41.86555)
		(end 62.258702 -41.633902)
		(width 0.14224)
		(layer "In11.Cu")
		(net "M_J_DQS_DN<11>")
	)
	(segment
		(start 68.166742 -48.339248)
		(end 67.98691 -48.159416)
		(width 0.14224)
		(layer "In11.Cu")
		(net "M_J_DQS_DN<11>")
	)
	(segment
		(start 54.224428 -6.238748)
		(end 53.240432 -5.254752)
		(width 0.14224)
		(layer "In11.Cu")
		(net "M_J_DQS_DN<11>")
	)
	(segment
		(start 73.205086 -54.504336)
		(end 73.17232 -54.504336)
		(width 0.0889)
		(layer "In11.Cu")
		(net "M_J_DQS_DN<11>")
	)
	(segment
		(start 62.258702 -41.633902)
		(end 62.258702 -41.472358)
		(width 0.14224)
		(layer "In11.Cu")
		(net "M_J_DQS_DN<11>")
	)
	(segment
		(start 54.224428 -10.67308)
		(end 54.381908 -10.5156)
		(width 0.14224)
		(layer "In11.Cu")
		(net "M_J_DQS_DN<11>")
	)
	(segment
		(start 54.381908 -9.4996)
		(end 54.224428 -9.34212)
		(width 0.14224)
		(layer "In11.Cu")
		(net "M_J_DQS_DN<11>")
	)
	(segment
		(start 54.381908 -14.3764)
		(end 54.224428 -14.21892)
		(width 0.14224)
		(layer "In11.Cu")
		(net "M_J_DQS_DN<11>")
	)
	(segment
		(start 67.545458 -47.879762)
		(end 67.545458 -47.717964)
		(width 0.14224)
		(layer "In11.Cu")
		(net "M_J_DQS_DN<11>")
	)
	(segment
		(start 65.256664 -44.47032)
		(end 65.09512 -44.47032)
		(width 0.14224)
		(layer "In11.Cu")
		(net "M_J_DQS_DN<11>")
	)
	(segment
		(start 64.915542 -44.129198)
		(end 64.73571 -43.949366)
		(width 0.14224)
		(layer "In11.Cu")
		(net "M_J_DQS_DN<11>")
	)
	(segment
		(start 54.552088 -33.927288)
		(end 54.552088 -26.973276)
		(width 0.14224)
		(layer "In11.Cu")
		(net "M_J_DQS_DN<11>")
	)
	(segment
		(start 65.616074 -44.991274)
		(end 65.436496 -44.811696)
		(width 0.14224)
		(layer "In11.Cu")
		(net "M_J_DQS_DN<11>")
	)
	(segment
		(start 64.394588 -43.608244)
		(end 64.214756 -43.428412)
		(width 0.14224)
		(layer "In11.Cu")
		(net "M_J_DQS_DN<11>")
	)
	(segment
		(start 54.231032 1.257808)
		(end 53.89372 1.59512)
		(width 0.14224)
		(layer "In11.Cu")
		(net "M_J_DQS_DN<11>")
	)
	(segment
		(start 62.651894 -41.86555)
		(end 62.49035 -41.86555)
		(width 0.14224)
		(layer "In11.Cu")
		(net "M_J_DQS_DN<11>")
	)
	(segment
		(start 78.351126 -57.476136)
		(end 78.338172 -57.476136)
		(width 0.0889)
		(layer "In11.Cu")
		(net "M_J_DQS_DN<11>")
	)
	(segment
		(start 54.231032 -2.843276)
		(end 54.231032 1.257808)
		(width 0.14224)
		(layer "In11.Cu")
		(net "M_J_DQS_DN<11>")
	)
	(segment
		(start 54.224428 -11.43508)
		(end 54.381908 -11.2776)
		(width 0.14224)
		(layer "In11.Cu")
		(net "M_J_DQS_DN<11>")
	)
	(segment
		(start 63.532258 -42.907458)
		(end 63.35268 -42.72788)
		(width 0.14224)
		(layer "In11.Cu")
		(net "M_J_DQS_DN<11>")
	)
	(segment
		(start 54.224428 -10.86612)
		(end 54.224428 -10.67308)
		(width 0.14224)
		(layer "In11.Cu")
		(net "M_J_DQS_DN<11>")
	)
	(segment
		(start 76.639166 -56.485536)
		(end 76.6064 -56.485536)
		(width 0.0889)
		(layer "In11.Cu")
		(net "M_J_DQS_DN<11>")
	)
	(segment
		(start 64.574166 -43.949366)
		(end 64.394588 -43.769788)
		(width 0.14224)
		(layer "In11.Cu")
		(net "M_J_DQS_DN<11>")
	)
	(segment
		(start 70.629526 -52.027836)
		(end 70.593712 -52.027836)
		(width 0.0889)
		(layer "In11.Cu")
		(net "M_J_DQS_DN<11>")
	)
	(segment
		(start 53.612288 -25.553162)
		(end 54.224428 -24.941022)
		(width 0.14224)
		(layer "In11.Cu")
		(net "M_J_DQS_DN<11>")
	)
	(segment
		(start 53.89372 1.59512)
		(end 53.644292 1.59512)
		(width 0.14224)
		(layer "In11.Cu")
		(net "M_J_DQS_DN<11>")
	)
	(segment
		(start 63.35268 -42.566336)
		(end 63.172848 -42.386504)
		(width 0.14224)
		(layer "In11.Cu")
		(net "M_J_DQS_DN<11>")
	)
	(segment
		(start 70.271386 -50.848768)
		(end 69.88175 -50.157126)
		(width 0.0889)
		(layer "In11.Cu")
		(net "M_J_DQS_DN<11>")
	)
	(segment
		(start 54.381908 -11.0236)
		(end 54.224428 -10.86612)
		(width 0.14224)
		(layer "In11.Cu")
		(net "M_J_DQS_DN<11>")
	)
	(segment
		(start 54.17312 -26.594308)
		(end 54.012846 -26.594308)
		(width 0.14224)
		(layer "In11.Cu")
		(net "M_J_DQS_DN<11>")
	)
	(segment
		(start 53.442108 -3.6322)
		(end 54.231032 -2.843276)
		(width 0.14224)
		(layer "In11.Cu")
		(net "M_J_DQS_DN<11>")
	)
	(segment
		(start 53.880512 -4.070604)
		(end 53.442108 -3.6322)
		(width 0.14224)
		(layer "In11.Cu")
		(net "M_J_DQS_DN<11>")
	)
	(segment
		(start 68.797932 -49.132236)
		(end 68.166742 -48.501046)
		(width 0.14224)
		(layer "In11.Cu")
		(net "M_J_DQS_DN<11>")
	)
	(segment
		(start 53.612288 -26.19375)
		(end 53.612288 -25.553162)
		(width 0.14224)
		(layer "In11.Cu")
		(net "M_J_DQS_DN<11>")
	)
	(segment
		(start 66.602102 -45.815758)
		(end 66.42227 -45.635926)
		(width 0.14224)
		(layer "In11.Cu")
		(net "M_J_DQS_DN<11>")
	)
	(segment
		(start 66.602102 -45.977302)
		(end 66.602102 -45.815758)
		(width 0.14224)
		(layer "In11.Cu")
		(net "M_J_DQS_DN<11>")
	)
	(segment
		(start 77.995018 -57.281826)
		(end 77.991716 -57.275984)
		(width 0.0889)
		(layer "In11.Cu")
		(net "M_J_DQS_DN<11>")
	)
	(segment
		(start 63.873634 -43.248834)
		(end 63.873634 -43.08729)
		(width 0.14224)
		(layer "In11.Cu")
		(net "M_J_DQS_DN<11>")
	)
	(segment
		(start 67.365626 -47.538132)
		(end 67.203574 -47.538132)
		(width 0.14224)
		(layer "In11.Cu")
		(net "M_J_DQS_DN<11>")
	)
	(segment
		(start 66.260726 -45.635926)
		(end 65.957704 -45.332904)
		(width 0.14224)
		(layer "In11.Cu")
		(net "M_J_DQS_DN<11>")
	)
	(segment
		(start 54.224428 -14.21892)
		(end 54.224428 -11.43508)
		(width 0.14224)
		(layer "In11.Cu")
		(net "M_J_DQS_DN<11>")
	)
	(segment
		(start 72.350376 -54.00929)
		(end 72.31761 -54.00929)
		(width 0.0889)
		(layer "In11.Cu")
		(net "M_J_DQS_DN<11>")
	)
	(segment
		(start 63.35268 -42.72788)
		(end 63.35268 -42.566336)
		(width 0.14224)
		(layer "In11.Cu")
		(net "M_J_DQS_DN<11>")
	)
	(segment
		(start 69.88175 -50.157126)
		(end 69.896736 -50.103278)
		(width 0.0889)
		(layer "In11.Cu")
		(net "M_J_DQS_DN<11>")
	)
	(segment
		(start 53.644292 1.59512)
		(end 53.448712 1.7907)
		(width 0.14224)
		(layer "In11.Cu")
		(net "M_J_DQS_DN<11>")
	)
	(segment
		(start 62.258702 -41.472358)
		(end 62.07887 -41.292526)
		(width 0.14224)
		(layer "In11.Cu")
		(net "M_J_DQS_DN<11>")
	)
	(segment
		(start 65.957704 -45.171106)
		(end 65.777872 -44.991274)
		(width 0.14224)
		(layer "In11.Cu")
		(net "M_J_DQS_DN<11>")
	)
	(segment
		(start 64.73571 -43.949366)
		(end 64.574166 -43.949366)
		(width 0.14224)
		(layer "In11.Cu")
		(net "M_J_DQS_DN<11>")
	)
	(segment
		(start 65.436496 -44.650152)
		(end 65.256664 -44.47032)
		(width 0.14224)
		(layer "In11.Cu")
		(net "M_J_DQS_DN<11>")
	)
	(segment
		(start 67.825112 -48.159416)
		(end 67.545458 -47.879762)
		(width 0.14224)
		(layer "In11.Cu")
		(net "M_J_DQS_DN<11>")
	)
	(segment
		(start 63.011304 -42.386504)
		(end 62.831726 -42.206926)
		(width 0.14224)
		(layer "In11.Cu")
		(net "M_J_DQS_DN<11>")
	)
	(segment
		(start 79.196692 -57.57164)
		(end 78.464664 -57.489598)
		(width 0.0889)
		(layer "In11.Cu")
		(net "M_J_DQS_DN<11>")
	)
	(segment
		(start 66.79946 -46.17466)
		(end 66.602102 -45.977302)
		(width 0.14224)
		(layer "In11.Cu")
		(net "M_J_DQS_DN<11>")
	)
	(segment
		(start 54.224428 -24.941022)
		(end 54.224428 -14.78788)
		(width 0.14224)
		(layer "In11.Cu")
		(net "M_J_DQS_DN<11>")
	)
	(segment
		(start 54.381908 -10.2616)
		(end 54.224428 -10.10412)
		(width 0.14224)
		(layer "In11.Cu")
		(net "M_J_DQS_DN<11>")
	)
	(segment
		(start 67.545458 -47.717964)
		(end 67.365626 -47.538132)
		(width 0.14224)
		(layer "In11.Cu")
		(net "M_J_DQS_DN<11>")
	)
	(segment
		(start 69.896736 -50.103278)
		(end 69.885814 -50.083974)
		(width 0.0889)
		(layer "In11.Cu")
		(net "M_J_DQS_DN<11>")
	)
	(segment
		(start 67.98691 -48.159416)
		(end 67.825112 -48.159416)
		(width 0.14224)
		(layer "In11.Cu")
		(net "M_J_DQS_DN<11>")
	)
	(segment
		(start 67.203574 -47.538132)
		(end 66.79946 -47.134018)
		(width 0.14224)
		(layer "In11.Cu")
		(net "M_J_DQS_DN<11>")
	)
	(segment
		(start 69.645276 -49.658778)
		(end 68.797932 -49.132236)
		(width 0.14224)
		(layer "In11.Cu")
		(net "M_J_DQS_DN<11>")
	)
	(segment
		(start 62.831726 -42.045382)
		(end 62.651894 -41.86555)
		(width 0.14224)
		(layer "In11.Cu")
		(net "M_J_DQS_DN<11>")
	)
	(segment
		(start 64.394588 -43.769788)
		(end 64.394588 -43.608244)
		(width 0.14224)
		(layer "In11.Cu")
		(net "M_J_DQS_DN<11>")
	)
	(segment
		(start 75.784456 -55.99049)
		(end 75.75169 -55.99049)
		(width 0.0889)
		(layer "In11.Cu")
		(net "M_J_DQS_DN<11>")
	)
	(segment
		(start 53.240432 -4.98348)
		(end 53.423312 -4.8006)
		(width 0.14224)
		(layer "In11.Cu")
		(net "M_J_DQS_DN<11>")
	)
	(segment
		(start 53.240432 -5.254752)
		(end 53.240432 -4.98348)
		(width 0.14224)
		(layer "In11.Cu")
		(net "M_J_DQS_DN<11>")
	)
	(segment
		(start 65.436496 -44.811696)
		(end 65.436496 -44.650152)
		(width 0.14224)
		(layer "In11.Cu")
		(net "M_J_DQS_DN<11>")
	)
	(segment
		(start 54.381908 -14.6304)
		(end 54.381908 -14.3764)
		(width 0.14224)
		(layer "In11.Cu")
		(net "M_J_DQS_DN<11>")
	)
	(segment
		(start 61.917326 -41.292526)
		(end 54.552088 -33.927288)
		(width 0.14224)
		(layer "In11.Cu")
		(net "M_J_DQS_DN<11>")
	)
	(segment
		(start 69.885814 -50.083974)
		(end 69.645276 -49.658778)
		(width 0.14224)
		(layer "In11.Cu")
		(net "M_J_DQS_DN<11>")
	)
	(segment
		(start 63.693802 -42.907458)
		(end 63.532258 -42.907458)
		(width 0.14224)
		(layer "In11.Cu")
		(net "M_J_DQS_DN<11>")
	)
	(segment
		(start 74.067416 -54.99989)
		(end 74.03465 -54.99989)
		(width 0.0889)
		(layer "In11.Cu")
		(net "M_J_DQS_DN<11>")
	)
	(segment
		(start 53.880512 -4.5974)
		(end 53.880512 -4.070604)
		(width 0.14224)
		(layer "In11.Cu")
		(net "M_J_DQS_DN<11>")
	)
	(segment
		(start 65.09512 -44.47032)
		(end 64.915542 -44.290742)
		(width 0.14224)
		(layer "In11.Cu")
		(net "M_J_DQS_DN<11>")
	)
	(segment
		(start 68.166742 -48.501046)
		(end 68.166742 -48.339248)
		(width 0.14224)
		(layer "In11.Cu")
		(net "M_J_DQS_DN<11>")
	)
	(segment
		(start 54.381908 -10.5156)
		(end 54.381908 -10.2616)
		(width 0.14224)
		(layer "In11.Cu")
		(net "M_J_DQS_DN<11>")
	)
	(segment
		(start 63.172848 -42.386504)
		(end 63.011304 -42.386504)
		(width 0.14224)
		(layer "In11.Cu")
		(net "M_J_DQS_DN<11>")
	)
	(segment
		(start 54.224428 -14.78788)
		(end 54.381908 -14.6304)
		(width 0.14224)
		(layer "In11.Cu")
		(net "M_J_DQS_DN<11>")
	)
	(segment
		(start 64.214756 -43.428412)
		(end 64.053212 -43.428412)
		(width 0.14224)
		(layer "In11.Cu")
		(net "M_J_DQS_DN<11>")
	)
	(segment
		(start 62.831726 -42.206926)
		(end 62.831726 -42.045382)
		(width 0.14224)
		(layer "In11.Cu")
		(net "M_J_DQS_DN<11>")
	)
	(segment
		(start 71.11873 -52.922424)
		(end 71.123556 -52.913788)
		(width 0.0889)
		(layer "In11.Cu")
		(net "M_J_DQS_DN<11>")
	)
	(arc
		(start 70.593712 -52.027836)
		(mid 70.260743 -51.820288)
		(end 70.265036 -51.427888)
		(width 0.0889)
		(layer "In11.Cu")
		(net "M_J_DQS_DN<11>")
	)
	(arc
		(start 74.557636 -55.295038)
		(mid 74.350632 -55.084174)
		(end 74.067416 -54.99989)
		(width 0.0889)
		(layer "In11.Cu")
		(net "M_J_DQS_DN<11>")
	)
	(arc
		(start 73.699116 -54.799738)
		(mid 73.490508 -54.587806)
		(end 73.205086 -54.504336)
		(width 0.0889)
		(layer "In11.Cu")
		(net "M_J_DQS_DN<11>")
	)
	(arc
		(start 78.464664 -57.489598)
		(mid 78.408221 -57.480118)
		(end 78.351126 -57.476136)
		(width 0.0889)
		(layer "In11.Cu")
		(net "M_J_DQS_DN<11>")
	)
	(arc
		(start 74.88936 -55.494936)
		(mid 74.697718 -55.43777)
		(end 74.557636 -55.295038)
		(width 0.0889)
		(layer "In11.Cu")
		(net "M_J_DQS_DN<11>")
	)
	(arc
		(start 77.46873 -56.98109)
		(mid 77.27488 -56.92474)
		(end 77.133196 -56.780938)
		(width 0.0889)
		(layer "In11.Cu")
		(net "M_J_DQS_DN<11>")
	)
	(arc
		(start 78.338172 -57.476136)
		(mid 78.141011 -57.424177)
		(end 77.995018 -57.281826)
		(width 0.0889)
		(layer "In11.Cu")
		(net "M_J_DQS_DN<11>")
	)
	(arc
		(start 75.75169 -55.99049)
		(mid 75.55784 -55.93414)
		(end 75.416156 -55.790338)
		(width 0.0889)
		(layer "In11.Cu")
		(net "M_J_DQS_DN<11>")
	)
	(arc
		(start 72.31761 -54.00929)
		(mid 72.12376 -53.95294)
		(end 71.982076 -53.809138)
		(width 0.0889)
		(layer "In11.Cu")
		(net "M_J_DQS_DN<11>")
	)
	(arc
		(start 71.45528 -53.513736)
		(mid 71.122362 -53.311745)
		(end 71.11873 -52.922424)
		(width 0.0889)
		(layer "In11.Cu")
		(net "M_J_DQS_DN<11>")
	)
	(arc
		(start 76.6064 -56.485536)
		(mid 76.414758 -56.42837)
		(end 76.274676 -56.285638)
		(width 0.0889)
		(layer "In11.Cu")
		(net "M_J_DQS_DN<11>")
	)
	(arc
		(start 72.840596 -54.304438)
		(mid 72.633592 -54.093574)
		(end 72.350376 -54.00929)
		(width 0.0889)
		(layer "In11.Cu")
		(net "M_J_DQS_DN<11>")
	)
	(arc
		(start 73.17232 -54.504336)
		(mid 72.980678 -54.44717)
		(end 72.840596 -54.304438)
		(width 0.0889)
		(layer "In11.Cu")
		(net "M_J_DQS_DN<11>")
	)
	(arc
		(start 71.982076 -53.809138)
		(mid 71.773468 -53.597206)
		(end 71.488046 -53.513736)
		(width 0.0889)
		(layer "In11.Cu")
		(net "M_J_DQS_DN<11>")
	)
	(arc
		(start 77.991716 -57.275984)
		(mid 77.786095 -57.066061)
		(end 77.504798 -56.98109)
		(width 0.0889)
		(layer "In11.Cu")
		(net "M_J_DQS_DN<11>")
	)
	(arc
		(start 74.03465 -54.99989)
		(mid 73.8408 -54.94354)
		(end 73.699116 -54.799738)
		(width 0.0889)
		(layer "In11.Cu")
		(net "M_J_DQS_DN<11>")
	)
	(arc
		(start 71.123556 -52.913788)
		(mid 71.127885 -52.330616)
		(end 70.629526 -52.027836)
		(width 0.0889)
		(layer "In11.Cu")
		(net "M_J_DQS_DN<11>")
	)
	(arc
		(start 70.265036 -51.427888)
		(mid 70.344006 -51.139167)
		(end 70.271386 -50.848768)
		(width 0.0889)
		(layer "In11.Cu")
		(net "M_J_DQS_DN<11>")
	)
	(arc
		(start 75.416156 -55.790338)
		(mid 75.207548 -55.578406)
		(end 74.922126 -55.494936)
		(width 0.0889)
		(layer "In11.Cu")
		(net "M_J_DQS_DN<11>")
	)
	(arc
		(start 76.274676 -56.285638)
		(mid 76.067672 -56.074774)
		(end 75.784456 -55.99049)
		(width 0.0889)
		(layer "In11.Cu")
		(net "M_J_DQS_DN<11>")
	)
	(arc
		(start 77.133196 -56.780938)
		(mid 76.924588 -56.569006)
		(end 76.639166 -56.485536)
		(width 0.0889)
		(layer "In11.Cu")
		(net "M_J_DQS_DN<11>")
	)
	(segment
		(start 44.999402 3.778758)
		(end 44.999402 2.93624)
		(width 0.1651)
		(layer "F.Cu")
		(net "M_J_DQS_DN<10>")
	)
	(segment
		(start 75.475846 -61.038486)
		(end 74.904346 -61.038486)
		(width 0.0889)
		(layer "F.Cu")
		(net "M_J_DQS_DN<10>")
	)
	(segment
		(start 44.767246 2.100072)
		(end 44.767246 1.853438)
		(width 0.1651)
		(layer "F.Cu")
		(net "M_J_DQS_DN<10>")
	)
	(segment
		(start 44.306998 1.60147)
		(end 44.117768 1.7907)
		(width 0.1651)
		(layer "F.Cu")
		(net "M_J_DQS_DN<10>")
	)
	(segment
		(start 44.581318 2.286)
		(end 44.767246 2.100072)
		(width 0.1651)
		(layer "F.Cu")
		(net "M_J_DQS_DN<10>")
	)
	(segment
		(start 44.117768 1.7907)
		(end 44.098718 1.7907)
		(width 0.1651)
		(layer "F.Cu")
		(net "M_J_DQS_DN<10>")
	)
	(segment
		(start 44.581318 2.518156)
		(end 44.581318 2.286)
		(width 0.1651)
		(layer "F.Cu")
		(net "M_J_DQS_DN<10>")
	)
	(segment
		(start 44.999402 2.93624)
		(end 44.581318 2.518156)
		(width 0.1651)
		(layer "F.Cu")
		(net "M_J_DQS_DN<10>")
	)
	(segment
		(start 44.767246 1.853438)
		(end 44.515278 1.60147)
		(width 0.1651)
		(layer "F.Cu")
		(net "M_J_DQS_DN<10>")
	)
	(segment
		(start 44.515278 1.60147)
		(end 44.306998 1.60147)
		(width 0.1651)
		(layer "F.Cu")
		(net "M_J_DQS_DN<10>")
	)
	(via
		(at 44.098718 1.7907)
		(size 0.508)
		(drill 0.254)
		(layers "F.Cu" "B.Cu")
		(net "M_J_DQS_DN<10>")
	)
	(via
		(at 44.092114 -3.6322)
		(size 0.508)
		(drill 0.254)
		(layers "F.Cu" "B.Cu")
		(net "M_J_DQS_DN<10>")
	)
	(via
		(at 74.904346 -61.038486)
		(size 0.508)
		(drill 0.254)
		(layers "F.Cu" "B.Cu")
		(net "M_J_DQS_DN<10>")
	)
	(segment
		(start 44.513754 -3.437636)
		(end 44.286678 -3.437636)
		(width 0.1651)
		(layer "B.Cu")
		(net "M_J_DQS_DN<10>")
	)
	(segment
		(start 44.999402 -4.964938)
		(end 44.555918 -4.521454)
		(width 0.1651)
		(layer "B.Cu")
		(net "M_J_DQS_DN<10>")
	)
	(segment
		(start 44.733718 -3.9878)
		(end 44.733718 -3.6576)
		(width 0.1651)
		(layer "B.Cu")
		(net "M_J_DQS_DN<10>")
	)
	(segment
		(start 44.555918 -4.521454)
		(end 44.555918 -4.1656)
		(width 0.1651)
		(layer "B.Cu")
		(net "M_J_DQS_DN<10>")
	)
	(segment
		(start 44.733718 -3.6576)
		(end 44.513754 -3.437636)
		(width 0.1651)
		(layer "B.Cu")
		(net "M_J_DQS_DN<10>")
	)
	(segment
		(start 44.555918 -4.1656)
		(end 44.733718 -3.9878)
		(width 0.1651)
		(layer "B.Cu")
		(net "M_J_DQS_DN<10>")
	)
	(segment
		(start 44.286678 -3.437636)
		(end 44.092114 -3.6322)
		(width 0.1651)
		(layer "B.Cu")
		(net "M_J_DQS_DN<10>")
	)
	(segment
		(start 44.999402 -5.621782)
		(end 44.999402 -4.964938)
		(width 0.1651)
		(layer "B.Cu")
		(net "M_J_DQS_DN<10>")
	)
	(segment
		(start 63.544704 -55.613808)
		(end 63.706248 -55.613808)
		(width 0.14224)
		(layer "In11.Cu")
		(net "M_J_DQS_DN<10>")
	)
	(segment
		(start 63.706248 -55.613808)
		(end 63.88608 -55.79364)
		(width 0.14224)
		(layer "In11.Cu")
		(net "M_J_DQS_DN<10>")
	)
	(segment
		(start 45.001434 -6.365748)
		(end 45.001434 -6.761988)
		(width 0.14224)
		(layer "In11.Cu")
		(net "M_J_DQS_DN<10>")
	)
	(segment
		(start 44.283376 -33.982152)
		(end 44.66336 -33.982152)
		(width 0.14224)
		(layer "In11.Cu")
		(net "M_J_DQS_DN<10>")
	)
	(segment
		(start 44.098718 1.7907)
		(end 44.294298 1.59512)
		(width 0.14224)
		(layer "In11.Cu")
		(net "M_J_DQS_DN<10>")
	)
	(segment
		(start 58.269124 -50.338228)
		(end 58.607198 -50.676302)
		(width 0.14224)
		(layer "In11.Cu")
		(net "M_J_DQS_DN<10>")
	)
	(segment
		(start 44.874434 -10.20572)
		(end 45.031914 -10.3632)
		(width 0.14224)
		(layer "In11.Cu")
		(net "M_J_DQS_DN<10>")
	)
	(segment
		(start 44.092114 -3.6322)
		(end 44.530518 -4.070604)
		(width 0.14224)
		(layer "In11.Cu")
		(net "M_J_DQS_DN<10>")
	)
	(segment
		(start 44.874434 -10.96772)
		(end 45.031914 -11.1252)
		(width 0.14224)
		(layer "In11.Cu")
		(net "M_J_DQS_DN<10>")
	)
	(segment
		(start 49.58588 -40.6908)
		(end 52.135024 -43.239944)
		(width 0.14224)
		(layer "In11.Cu")
		(net "M_J_DQS_DN<10>")
	)
	(segment
		(start 43.890438 -4.98348)
		(end 43.890438 -5.254752)
		(width 0.14224)
		(layer "In11.Cu")
		(net "M_J_DQS_DN<10>")
	)
	(segment
		(start 44.874434 -11.53668)
		(end 44.874434 -25.819862)
		(width 0.14224)
		(layer "In11.Cu")
		(net "M_J_DQS_DN<10>")
	)
	(segment
		(start 64.227456 -56.134762)
		(end 64.407288 -56.314594)
		(width 0.14224)
		(layer "In11.Cu")
		(net "M_J_DQS_DN<10>")
	)
	(segment
		(start 43.890438 -5.254752)
		(end 45.001434 -6.365748)
		(width 0.14224)
		(layer "In11.Cu")
		(net "M_J_DQS_DN<10>")
	)
	(segment
		(start 65.52692 -56.952896)
		(end 65.52692 -56.964072)
		(width 0.0889)
		(layer "In11.Cu")
		(net "M_J_DQS_DN<10>")
	)
	(segment
		(start 57.659524 -49.728628)
		(end 57.927748 -49.996852)
		(width 0.14224)
		(layer "In11.Cu")
		(net "M_J_DQS_DN<10>")
	)
	(segment
		(start 62.787022 -54.856126)
		(end 62.968124 -55.037228)
		(width 0.14224)
		(layer "In11.Cu")
		(net "M_J_DQS_DN<10>")
	)
	(segment
		(start 62.968124 -55.037228)
		(end 63.129922 -55.037228)
		(width 0.14224)
		(layer "In11.Cu")
		(net "M_J_DQS_DN<10>")
	)
	(segment
		(start 57.107836 -49.17694)
		(end 57.317894 -49.386998)
		(width 0.14224)
		(layer "In11.Cu")
		(net "M_J_DQS_DN<10>")
	)
	(segment
		(start 56.34736 -48.25492)
		(end 56.527192 -48.434752)
		(width 0.14224)
		(layer "In11.Cu")
		(net "M_J_DQS_DN<10>")
	)
	(segment
		(start 58.768742 -50.676302)
		(end 58.948574 -50.856134)
		(width 0.14224)
		(layer "In11.Cu")
		(net "M_J_DQS_DN<10>")
	)
	(segment
		(start 71.45528 -59.457336)
		(end 71.488046 -59.457336)
		(width 0.0889)
		(layer "In11.Cu")
		(net "M_J_DQS_DN<10>")
	)
	(segment
		(start 55.575962 -47.645066)
		(end 55.73776 -47.645066)
		(width 0.14224)
		(layer "In11.Cu")
		(net "M_J_DQS_DN<10>")
	)
	(segment
		(start 56.766206 -48.83531)
		(end 56.928004 -48.83531)
		(width 0.14224)
		(layer "In11.Cu")
		(net "M_J_DQS_DN<10>")
	)
	(segment
		(start 44.036488 -35.79368)
		(end 44.036488 -36.105592)
		(width 0.14224)
		(layer "In11.Cu")
		(net "M_J_DQS_DN<10>")
	)
	(segment
		(start 57.107836 -49.015142)
		(end 57.107836 -49.17694)
		(width 0.14224)
		(layer "In11.Cu")
		(net "M_J_DQS_DN<10>")
	)
	(segment
		(start 65.52692 -56.964072)
		(end 65.543938 -56.98109)
		(width 0.0889)
		(layer "In11.Cu")
		(net "M_J_DQS_DN<10>")
	)
	(segment
		(start 44.66336 -35.597592)
		(end 44.232576 -35.597592)
		(width 0.14224)
		(layer "In11.Cu")
		(net "M_J_DQS_DN<10>")
	)
	(segment
		(start 61.133736 -53.20284)
		(end 61.313314 -53.382418)
		(width 0.14224)
		(layer "In11.Cu")
		(net "M_J_DQS_DN<10>")
	)
	(segment
		(start 64.872616 -56.94172)
		(end 65.504568 -56.94172)
		(width 0.14224)
		(layer "In11.Cu")
		(net "M_J_DQS_DN<10>")
	)
	(segment
		(start 44.874434 -10.01268)
		(end 44.874434 -10.20572)
		(width 0.14224)
		(layer "In11.Cu")
		(net "M_J_DQS_DN<10>")
	)
	(segment
		(start 58.607198 -50.676302)
		(end 58.768742 -50.676302)
		(width 0.14224)
		(layer "In11.Cu")
		(net "M_J_DQS_DN<10>")
	)
	(segment
		(start 61.474858 -53.382418)
		(end 61.65469 -53.56225)
		(width 0.14224)
		(layer "In11.Cu")
		(net "M_J_DQS_DN<10>")
	)
	(segment
		(start 61.313314 -53.382418)
		(end 61.474858 -53.382418)
		(width 0.14224)
		(layer "In11.Cu")
		(net "M_J_DQS_DN<10>")
	)
	(segment
		(start 44.543726 1.59512)
		(end 44.881038 1.257808)
		(width 0.14224)
		(layer "In11.Cu")
		(net "M_J_DQS_DN<10>")
	)
	(segment
		(start 74.262234 -60.98413)
		(end 74.904346 -61.038486)
		(width 0.0889)
		(layer "In11.Cu")
		(net "M_J_DQS_DN<10>")
	)
	(segment
		(start 55.917592 -47.824898)
		(end 55.917592 -47.986696)
		(width 0.14224)
		(layer "In11.Cu")
		(net "M_J_DQS_DN<10>")
	)
	(segment
		(start 59.222894 -51.291998)
		(end 59.384438 -51.291998)
		(width 0.14224)
		(layer "In11.Cu")
		(net "M_J_DQS_DN<10>")
	)
	(segment
		(start 44.66336 -33.982152)
		(end 44.94784 -34.266632)
		(width 0.14224)
		(layer "In11.Cu")
		(net "M_J_DQS_DN<10>")
	)
	(segment
		(start 55.73776 -47.645066)
		(end 55.917592 -47.824898)
		(width 0.14224)
		(layer "In11.Cu")
		(net "M_J_DQS_DN<10>")
	)
	(segment
		(start 57.479692 -49.386998)
		(end 57.659524 -49.56683)
		(width 0.14224)
		(layer "In11.Cu")
		(net "M_J_DQS_DN<10>")
	)
	(segment
		(start 44.881038 -2.843276)
		(end 44.092114 -3.6322)
		(width 0.14224)
		(layer "In11.Cu")
		(net "M_J_DQS_DN<10>")
	)
	(segment
		(start 44.874434 -6.888988)
		(end 44.874434 -9.44372)
		(width 0.14224)
		(layer "In11.Cu")
		(net "M_J_DQS_DN<10>")
	)
	(segment
		(start 60.087002 -51.994308)
		(end 60.087002 -52.156106)
		(width 0.14224)
		(layer "In11.Cu")
		(net "M_J_DQS_DN<10>")
	)
	(segment
		(start 60.79236 -52.861464)
		(end 60.953904 -52.861464)
		(width 0.14224)
		(layer "In11.Cu")
		(net "M_J_DQS_DN<10>")
	)
	(segment
		(start 57.317894 -49.386998)
		(end 57.479692 -49.386998)
		(width 0.14224)
		(layer "In11.Cu")
		(net "M_J_DQS_DN<10>")
	)
	(segment
		(start 55.01259 -47.081694)
		(end 55.174388 -47.081694)
		(width 0.14224)
		(layer "In11.Cu")
		(net "M_J_DQS_DN<10>")
	)
	(segment
		(start 44.874434 -10.77468)
		(end 44.874434 -10.96772)
		(width 0.14224)
		(layer "In11.Cu")
		(net "M_J_DQS_DN<10>")
	)
	(segment
		(start 60.43295 -52.34051)
		(end 60.612782 -52.520342)
		(width 0.14224)
		(layer "In11.Cu")
		(net "M_J_DQS_DN<10>")
	)
	(segment
		(start 72.31761 -59.95289)
		(end 72.350376 -59.95289)
		(width 0.0889)
		(layer "In11.Cu")
		(net "M_J_DQS_DN<10>")
	)
	(segment
		(start 44.881038 1.257808)
		(end 44.881038 -2.843276)
		(width 0.14224)
		(layer "In11.Cu")
		(net "M_J_DQS_DN<10>")
	)
	(segment
		(start 58.269124 -50.176684)
		(end 58.269124 -50.338228)
		(width 0.14224)
		(layer "In11.Cu")
		(net "M_J_DQS_DN<10>")
	)
	(segment
		(start 48.621696 -40.6908)
		(end 49.58588 -40.6908)
		(width 0.14224)
		(layer "In11.Cu")
		(net "M_J_DQS_DN<10>")
	)
	(segment
		(start 56.527192 -48.596296)
		(end 56.766206 -48.83531)
		(width 0.14224)
		(layer "In11.Cu")
		(net "M_J_DQS_DN<10>")
	)
	(segment
		(start 56.185816 -48.25492)
		(end 56.34736 -48.25492)
		(width 0.14224)
		(layer "In11.Cu")
		(net "M_J_DQS_DN<10>")
	)
	(segment
		(start 56.928004 -48.83531)
		(end 57.107836 -49.015142)
		(width 0.14224)
		(layer "In11.Cu")
		(net "M_J_DQS_DN<10>")
	)
	(segment
		(start 45.031914 -10.6172)
		(end 44.874434 -10.77468)
		(width 0.14224)
		(layer "In11.Cu")
		(net "M_J_DQS_DN<10>")
	)
	(segment
		(start 60.087002 -52.156106)
		(end 60.271406 -52.34051)
		(width 0.14224)
		(layer "In11.Cu")
		(net "M_J_DQS_DN<10>")
	)
	(segment
		(start 62.787022 -54.694582)
		(end 62.787022 -54.856126)
		(width 0.14224)
		(layer "In11.Cu")
		(net "M_J_DQS_DN<10>")
	)
	(segment
		(start 65.543938 -56.98109)
		(end 67.448938 -56.98109)
		(width 0.0889)
		(layer "In11.Cu")
		(net "M_J_DQS_DN<10>")
	)
	(segment
		(start 44.036488 -36.105592)
		(end 48.621696 -40.6908)
		(width 0.14224)
		(layer "In11.Cu")
		(net "M_J_DQS_DN<10>")
	)
	(segment
		(start 55.35422 -47.261526)
		(end 55.35422 -47.423324)
		(width 0.14224)
		(layer "In11.Cu")
		(net "M_J_DQS_DN<10>")
	)
	(segment
		(start 60.271406 -52.34051)
		(end 60.43295 -52.34051)
		(width 0.14224)
		(layer "In11.Cu")
		(net "M_J_DQS_DN<10>")
	)
	(segment
		(start 60.953904 -52.861464)
		(end 61.133736 -53.041296)
		(width 0.14224)
		(layer "In11.Cu")
		(net "M_J_DQS_DN<10>")
	)
	(segment
		(start 52.135024 -44.204128)
		(end 55.01259 -47.081694)
		(width 0.14224)
		(layer "In11.Cu")
		(net "M_J_DQS_DN<10>")
	)
	(segment
		(start 56.527192 -48.434752)
		(end 56.527192 -48.596296)
		(width 0.14224)
		(layer "In11.Cu")
		(net "M_J_DQS_DN<10>")
	)
	(segment
		(start 62.223904 -54.13121)
		(end 62.223904 -54.293008)
		(width 0.14224)
		(layer "In11.Cu")
		(net "M_J_DQS_DN<10>")
	)
	(segment
		(start 45.031914 -10.3632)
		(end 45.031914 -10.6172)
		(width 0.14224)
		(layer "In11.Cu")
		(net "M_J_DQS_DN<10>")
	)
	(segment
		(start 45.031914 -11.3792)
		(end 44.874434 -11.53668)
		(width 0.14224)
		(layer "In11.Cu")
		(net "M_J_DQS_DN<10>")
	)
	(segment
		(start 62.60719 -54.51475)
		(end 62.787022 -54.694582)
		(width 0.14224)
		(layer "In11.Cu")
		(net "M_J_DQS_DN<10>")
	)
	(segment
		(start 63.129922 -55.037228)
		(end 63.309754 -55.21706)
		(width 0.14224)
		(layer "In11.Cu")
		(net "M_J_DQS_DN<10>")
	)
	(segment
		(start 59.56427 -51.633374)
		(end 59.745372 -51.814476)
		(width 0.14224)
		(layer "In11.Cu")
		(net "M_J_DQS_DN<10>")
	)
	(segment
		(start 59.384438 -51.291998)
		(end 59.56427 -51.47183)
		(width 0.14224)
		(layer "In11.Cu")
		(net "M_J_DQS_DN<10>")
	)
	(segment
		(start 44.061888 -33.760664)
		(end 44.283376 -33.982152)
		(width 0.14224)
		(layer "In11.Cu")
		(net "M_J_DQS_DN<10>")
	)
	(segment
		(start 60.612782 -52.520342)
		(end 60.612782 -52.681886)
		(width 0.14224)
		(layer "In11.Cu")
		(net "M_J_DQS_DN<10>")
	)
	(segment
		(start 44.530518 -4.5974)
		(end 44.327318 -4.8006)
		(width 0.14224)
		(layer "In11.Cu")
		(net "M_J_DQS_DN<10>")
	)
	(segment
		(start 63.88608 -55.955184)
		(end 64.065658 -56.134762)
		(width 0.14224)
		(layer "In11.Cu")
		(net "M_J_DQS_DN<10>")
	)
	(segment
		(start 44.874434 -9.44372)
		(end 45.031914 -9.6012)
		(width 0.14224)
		(layer "In11.Cu")
		(net "M_J_DQS_DN<10>")
	)
	(segment
		(start 68.934584 -58.466736)
		(end 69.774816 -58.466736)
		(width 0.0889)
		(layer "In11.Cu")
		(net "M_J_DQS_DN<10>")
	)
	(segment
		(start 62.044072 -53.951378)
		(end 62.223904 -54.13121)
		(width 0.14224)
		(layer "In11.Cu")
		(net "M_J_DQS_DN<10>")
	)
	(segment
		(start 59.90717 -51.814476)
		(end 60.087002 -51.994308)
		(width 0.14224)
		(layer "In11.Cu")
		(net "M_J_DQS_DN<10>")
	)
	(segment
		(start 64.065658 -56.134762)
		(end 64.227456 -56.134762)
		(width 0.14224)
		(layer "In11.Cu")
		(net "M_J_DQS_DN<10>")
	)
	(segment
		(start 44.94784 -34.266632)
		(end 44.94784 -35.313112)
		(width 0.14224)
		(layer "In11.Cu")
		(net "M_J_DQS_DN<10>")
	)
	(segment
		(start 44.232576 -35.597592)
		(end 44.036488 -35.79368)
		(width 0.14224)
		(layer "In11.Cu")
		(net "M_J_DQS_DN<10>")
	)
	(segment
		(start 45.031914 -9.6012)
		(end 45.031914 -9.8552)
		(width 0.14224)
		(layer "In11.Cu")
		(net "M_J_DQS_DN<10>")
	)
	(segment
		(start 73.17232 -60.447936)
		(end 73.205086 -60.447936)
		(width 0.0889)
		(layer "In11.Cu")
		(net "M_J_DQS_DN<10>")
	)
	(segment
		(start 64.407288 -56.314594)
		(end 64.407288 -56.476392)
		(width 0.14224)
		(layer "In11.Cu")
		(net "M_J_DQS_DN<10>")
	)
	(segment
		(start 44.874434 -25.819862)
		(end 44.061888 -26.632408)
		(width 0.14224)
		(layer "In11.Cu")
		(net "M_J_DQS_DN<10>")
	)
	(segment
		(start 44.061888 -26.632408)
		(end 44.061888 -33.760664)
		(width 0.14224)
		(layer "In11.Cu")
		(net "M_J_DQS_DN<10>")
	)
	(segment
		(start 58.948574 -51.017678)
		(end 59.222894 -51.291998)
		(width 0.14224)
		(layer "In11.Cu")
		(net "M_J_DQS_DN<10>")
	)
	(segment
		(start 52.135024 -43.239944)
		(end 52.135024 -44.204128)
		(width 0.14224)
		(layer "In11.Cu")
		(net "M_J_DQS_DN<10>")
	)
	(segment
		(start 44.327318 -4.8006)
		(end 44.073318 -4.8006)
		(width 0.14224)
		(layer "In11.Cu")
		(net "M_J_DQS_DN<10>")
	)
	(segment
		(start 60.612782 -52.681886)
		(end 60.79236 -52.861464)
		(width 0.14224)
		(layer "In11.Cu")
		(net "M_J_DQS_DN<10>")
	)
	(segment
		(start 61.133736 -53.041296)
		(end 61.133736 -53.20284)
		(width 0.14224)
		(layer "In11.Cu")
		(net "M_J_DQS_DN<10>")
	)
	(segment
		(start 70.60057 -58.962036)
		(end 70.6247 -58.962036)
		(width 0.0889)
		(layer "In11.Cu")
		(net "M_J_DQS_DN<10>")
	)
	(segment
		(start 55.174388 -47.081694)
		(end 55.35422 -47.261526)
		(width 0.14224)
		(layer "In11.Cu")
		(net "M_J_DQS_DN<10>")
	)
	(segment
		(start 65.504568 -56.94172)
		(end 65.515744 -56.94172)
		(width 0.0889)
		(layer "In11.Cu")
		(net "M_J_DQS_DN<10>")
	)
	(segment
		(start 44.530518 -4.070604)
		(end 44.530518 -4.5974)
		(width 0.14224)
		(layer "In11.Cu")
		(net "M_J_DQS_DN<10>")
	)
	(segment
		(start 63.88608 -55.79364)
		(end 63.88608 -55.955184)
		(width 0.14224)
		(layer "In11.Cu")
		(net "M_J_DQS_DN<10>")
	)
	(segment
		(start 44.073318 -4.8006)
		(end 43.890438 -4.98348)
		(width 0.14224)
		(layer "In11.Cu")
		(net "M_J_DQS_DN<10>")
	)
	(segment
		(start 44.294298 1.59512)
		(end 44.543726 1.59512)
		(width 0.14224)
		(layer "In11.Cu")
		(net "M_J_DQS_DN<10>")
	)
	(segment
		(start 59.745372 -51.814476)
		(end 59.90717 -51.814476)
		(width 0.14224)
		(layer "In11.Cu")
		(net "M_J_DQS_DN<10>")
	)
	(segment
		(start 61.882274 -53.951378)
		(end 62.044072 -53.951378)
		(width 0.14224)
		(layer "In11.Cu")
		(net "M_J_DQS_DN<10>")
	)
	(segment
		(start 65.515744 -56.94172)
		(end 65.52692 -56.952896)
		(width 0.0889)
		(layer "In11.Cu")
		(net "M_J_DQS_DN<10>")
	)
	(segment
		(start 64.407288 -56.476392)
		(end 64.872616 -56.94172)
		(width 0.14224)
		(layer "In11.Cu")
		(net "M_J_DQS_DN<10>")
	)
	(segment
		(start 63.309754 -55.378858)
		(end 63.544704 -55.613808)
		(width 0.14224)
		(layer "In11.Cu")
		(net "M_J_DQS_DN<10>")
	)
	(segment
		(start 45.001434 -6.761988)
		(end 44.874434 -6.888988)
		(width 0.14224)
		(layer "In11.Cu")
		(net "M_J_DQS_DN<10>")
	)
	(segment
		(start 61.65469 -53.56225)
		(end 61.65469 -53.723794)
		(width 0.14224)
		(layer "In11.Cu")
		(net "M_J_DQS_DN<10>")
	)
	(segment
		(start 57.927748 -49.996852)
		(end 58.089292 -49.996852)
		(width 0.14224)
		(layer "In11.Cu")
		(net "M_J_DQS_DN<10>")
	)
	(segment
		(start 44.94784 -35.313112)
		(end 44.66336 -35.597592)
		(width 0.14224)
		(layer "In11.Cu")
		(net "M_J_DQS_DN<10>")
	)
	(segment
		(start 57.659524 -49.56683)
		(end 57.659524 -49.728628)
		(width 0.14224)
		(layer "In11.Cu")
		(net "M_J_DQS_DN<10>")
	)
	(segment
		(start 55.917592 -47.986696)
		(end 56.185816 -48.25492)
		(width 0.14224)
		(layer "In11.Cu")
		(net "M_J_DQS_DN<10>")
	)
	(segment
		(start 62.445646 -54.51475)
		(end 62.60719 -54.51475)
		(width 0.14224)
		(layer "In11.Cu")
		(net "M_J_DQS_DN<10>")
	)
	(segment
		(start 63.309754 -55.21706)
		(end 63.309754 -55.378858)
		(width 0.14224)
		(layer "In11.Cu")
		(net "M_J_DQS_DN<10>")
	)
	(segment
		(start 61.65469 -53.723794)
		(end 61.882274 -53.951378)
		(width 0.14224)
		(layer "In11.Cu")
		(net "M_J_DQS_DN<10>")
	)
	(segment
		(start 45.031914 -9.8552)
		(end 44.874434 -10.01268)
		(width 0.14224)
		(layer "In11.Cu")
		(net "M_J_DQS_DN<10>")
	)
	(segment
		(start 58.948574 -50.856134)
		(end 58.948574 -51.017678)
		(width 0.14224)
		(layer "In11.Cu")
		(net "M_J_DQS_DN<10>")
	)
	(segment
		(start 62.223904 -54.293008)
		(end 62.445646 -54.51475)
		(width 0.14224)
		(layer "In11.Cu")
		(net "M_J_DQS_DN<10>")
	)
	(segment
		(start 67.448938 -56.98109)
		(end 68.934584 -58.466736)
		(width 0.0889)
		(layer "In11.Cu")
		(net "M_J_DQS_DN<10>")
	)
	(segment
		(start 55.35422 -47.423324)
		(end 55.575962 -47.645066)
		(width 0.14224)
		(layer "In11.Cu")
		(net "M_J_DQS_DN<10>")
	)
	(segment
		(start 45.031914 -11.1252)
		(end 45.031914 -11.3792)
		(width 0.14224)
		(layer "In11.Cu")
		(net "M_J_DQS_DN<10>")
	)
	(segment
		(start 74.03465 -60.94349)
		(end 74.067416 -60.94349)
		(width 0.0889)
		(layer "In11.Cu")
		(net "M_J_DQS_DN<10>")
	)
	(segment
		(start 59.56427 -51.47183)
		(end 59.56427 -51.633374)
		(width 0.14224)
		(layer "In11.Cu")
		(net "M_J_DQS_DN<10>")
	)
	(segment
		(start 58.089292 -49.996852)
		(end 58.269124 -50.176684)
		(width 0.14224)
		(layer "In11.Cu")
		(net "M_J_DQS_DN<10>")
	)
	(arc
		(start 70.6247 -58.962036)
		(mid 70.912845 -59.044355)
		(end 71.123556 -59.257438)
		(width 0.0889)
		(layer "In11.Cu")
		(net "M_J_DQS_DN<10>")
	)
	(arc
		(start 69.774816 -58.466736)
		(mid 70.058033 -58.551017)
		(end 70.265036 -58.761884)
		(width 0.0889)
		(layer "In11.Cu")
		(net "M_J_DQS_DN<10>")
	)
	(arc
		(start 71.123556 -59.257438)
		(mid 71.263635 -59.400174)
		(end 71.45528 -59.457336)
		(width 0.0889)
		(layer "In11.Cu")
		(net "M_J_DQS_DN<10>")
	)
	(arc
		(start 73.205086 -60.447936)
		(mid 73.49051 -60.531403)
		(end 73.699116 -60.743338)
		(width 0.0889)
		(layer "In11.Cu")
		(net "M_J_DQS_DN<10>")
	)
	(arc
		(start 71.982076 -59.752738)
		(mid 72.123759 -59.896542)
		(end 72.31761 -59.95289)
		(width 0.0889)
		(layer "In11.Cu")
		(net "M_J_DQS_DN<10>")
	)
	(arc
		(start 72.350376 -59.95289)
		(mid 72.633593 -60.037171)
		(end 72.840596 -60.248038)
		(width 0.0889)
		(layer "In11.Cu")
		(net "M_J_DQS_DN<10>")
	)
	(arc
		(start 70.265036 -58.761884)
		(mid 70.406719 -58.905688)
		(end 70.60057 -58.962036)
		(width 0.0889)
		(layer "In11.Cu")
		(net "M_J_DQS_DN<10>")
	)
	(arc
		(start 71.488046 -59.457336)
		(mid 71.77347 -59.540803)
		(end 71.982076 -59.752738)
		(width 0.0889)
		(layer "In11.Cu")
		(net "M_J_DQS_DN<10>")
	)
	(arc
		(start 72.840596 -60.248038)
		(mid 72.980675 -60.390774)
		(end 73.17232 -60.447936)
		(width 0.0889)
		(layer "In11.Cu")
		(net "M_J_DQS_DN<10>")
	)
	(arc
		(start 74.067416 -60.94349)
		(mid 74.166546 -60.955557)
		(end 74.262234 -60.98413)
		(width 0.0889)
		(layer "In11.Cu")
		(net "M_J_DQS_DN<10>")
	)
	(arc
		(start 73.699116 -60.743338)
		(mid 73.840799 -60.887142)
		(end 74.03465 -60.94349)
		(width 0.0889)
		(layer "In11.Cu")
		(net "M_J_DQS_DN<10>")
	)
	(segment
		(start 35.649408 -0.821182)
		(end 35.649408 0.19177)
		(width 0.1651)
		(layer "F.Cu")
		(net "M_J_DQS_DN<0>")
	)
	(segment
		(start 35.383724 0.457454)
		(end 35.383724 1.190244)
		(width 0.1651)
		(layer "F.Cu")
		(net "M_J_DQS_DN<0>")
	)
	(segment
		(start 78.051406 -64.50584)
		(end 77.479906 -64.50584)
		(width 0.0889)
		(layer "F.Cu")
		(net "M_J_DQS_DN<0>")
	)
	(segment
		(start 35.649408 0.19177)
		(end 35.383724 0.457454)
		(width 0.1651)
		(layer "F.Cu")
		(net "M_J_DQS_DN<0>")
	)
	(segment
		(start 35.383724 1.190244)
		(end 36.03752 1.84404)
		(width 0.1651)
		(layer "F.Cu")
		(net "M_J_DQS_DN<0>")
	)
	(via
		(at 36.03752 1.84404)
		(size 0.508)
		(drill 0.254)
		(layers "F.Cu" "B.Cu")
		(net "M_J_DQS_DN<0>")
	)
	(via
		(at 77.479906 -64.50584)
		(size 0.508)
		(drill 0.254)
		(layers "F.Cu" "B.Cu")
		(net "M_J_DQS_DN<0>")
	)
	(via
		(at 36.03752 -3.686556)
		(size 0.508)
		(drill 0.254)
		(layers "F.Cu" "B.Cu")
		(net "M_J_DQS_DN<0>")
	)
	(segment
		(start 35.396424 -3.04546)
		(end 36.03752 -3.686556)
		(width 0.1651)
		(layer "B.Cu")
		(net "M_J_DQS_DN<0>")
	)
	(segment
		(start 35.649408 -1.91897)
		(end 35.396424 -2.171954)
		(width 0.1651)
		(layer "B.Cu")
		(net "M_J_DQS_DN<0>")
	)
	(segment
		(start 35.649408 -1.021842)
		(end 35.649408 -1.91897)
		(width 0.1651)
		(layer "B.Cu")
		(net "M_J_DQS_DN<0>")
	)
	(segment
		(start 35.396424 -2.171954)
		(end 35.396424 -3.04546)
		(width 0.1651)
		(layer "B.Cu")
		(net "M_J_DQS_DN<0>")
	)
	(segment
		(start 61.048646 -63.354966)
		(end 61.21019 -63.354966)
		(width 0.14224)
		(layer "In11.Cu")
		(net "M_J_DQS_DN<0>")
	)
	(segment
		(start 60.026042 -62.170818)
		(end 60.026042 -62.332362)
		(width 0.14224)
		(layer "In11.Cu")
		(net "M_J_DQS_DN<0>")
	)
	(segment
		(start 76.603606 -64.410336)
		(end 76.639166 -64.410336)
		(width 0.0889)
		(layer "In11.Cu")
		(net "M_J_DQS_DN<0>")
	)
	(segment
		(start 75.741276 -64.90589)
		(end 75.774042 -64.90589)
		(width 0.0889)
		(layer "In11.Cu")
		(net "M_J_DQS_DN<0>")
	)
	(segment
		(start 61.390022 -63.534798)
		(end 61.390022 -63.696342)
		(width 0.14224)
		(layer "In11.Cu")
		(net "M_J_DQS_DN<0>")
	)
	(segment
		(start 35.73018 -34.440876)
		(end 35.73018 -34.930334)
		(width 0.14224)
		(layer "In11.Cu")
		(net "M_J_DQS_DN<0>")
	)
	(segment
		(start 64.29756 -63.87592)
		(end 64.871854 -63.87592)
		(width 0.14224)
		(layer "In11.Cu")
		(net "M_J_DQS_DN<0>")
	)
	(segment
		(start 36.81984 -24.994362)
		(end 35.679888 -26.134314)
		(width 0.14224)
		(layer "In11.Cu")
		(net "M_J_DQS_DN<0>")
	)
	(segment
		(start 36.81984 -37.564568)
		(end 40.480234 -41.224962)
		(width 0.14224)
		(layer "In11.Cu")
		(net "M_J_DQS_DN<0>")
	)
	(segment
		(start 35.958526 -35.15868)
		(end 36.507166 -35.15868)
		(width 0.14224)
		(layer "In11.Cu")
		(net "M_J_DQS_DN<0>")
	)
	(segment
		(start 63.036958 -63.87592)
		(end 63.151258 -63.76162)
		(width 0.14224)
		(layer "In11.Cu")
		(net "M_J_DQS_DN<0>")
	)
	(segment
		(start 59.445398 -61.590174)
		(end 59.445398 -61.751718)
		(width 0.14224)
		(layer "In11.Cu")
		(net "M_J_DQS_DN<0>")
	)
	(segment
		(start 37.334952 -33.675066)
		(end 36.930584 -34.079434)
		(width 0.14224)
		(layer "In11.Cu")
		(net "M_J_DQS_DN<0>")
	)
	(segment
		(start 68.03517 -63.41999)
		(end 68.036948 -63.41999)
		(width 0.0889)
		(layer "In11.Cu")
		(net "M_J_DQS_DN<0>")
	)
	(segment
		(start 36.501324 -4.5466)
		(end 35.988244 -5.05968)
		(width 0.14224)
		(layer "In11.Cu")
		(net "M_J_DQS_DN<0>")
	)
	(segment
		(start 61.21019 -63.354966)
		(end 61.390022 -63.534798)
		(width 0.14224)
		(layer "In11.Cu")
		(net "M_J_DQS_DN<0>")
	)
	(segment
		(start 60.490862 -62.635384)
		(end 60.670694 -62.815216)
		(width 0.14224)
		(layer "In11.Cu")
		(net "M_J_DQS_DN<0>")
	)
	(segment
		(start 63.81496 -63.87592)
		(end 63.92926 -63.76162)
		(width 0.14224)
		(layer "In11.Cu")
		(net "M_J_DQS_DN<0>")
	)
	(segment
		(start 40.480234 -41.224962)
		(end 40.480234 -42.786554)
		(width 0.14224)
		(layer "In11.Cu")
		(net "M_J_DQS_DN<0>")
	)
	(segment
		(start 77.18679 -64.67475)
		(end 77.479906 -64.50584)
		(width 0.0889)
		(layer "In11.Cu")
		(net "M_J_DQS_DN<0>")
	)
	(segment
		(start 35.988244 -5.280152)
		(end 36.81984 -6.111748)
		(width 0.14224)
		(layer "In11.Cu")
		(net "M_J_DQS_DN<0>")
	)
	(segment
		(start 35.901376 -32.463994)
		(end 36.955984 -32.463994)
		(width 0.14224)
		(layer "In11.Cu")
		(net "M_J_DQS_DN<0>")
	)
	(segment
		(start 36.507166 -35.15868)
		(end 36.81984 -35.471354)
		(width 0.14224)
		(layer "In11.Cu")
		(net "M_J_DQS_DN<0>")
	)
	(segment
		(start 72.31761 -64.90589)
		(end 72.350376 -64.90589)
		(width 0.0889)
		(layer "In11.Cu")
		(net "M_J_DQS_DN<0>")
	)
	(segment
		(start 77.097382 -64.65062)
		(end 77.18679 -64.67475)
		(width 0.0889)
		(layer "In11.Cu")
		(net "M_J_DQS_DN<0>")
	)
	(segment
		(start 59.104022 -61.410342)
		(end 59.265566 -61.410342)
		(width 0.14224)
		(layer "In11.Cu")
		(net "M_J_DQS_DN<0>")
	)
	(segment
		(start 62.258702 -63.87592)
		(end 62.373002 -63.76162)
		(width 0.14224)
		(layer "In11.Cu")
		(net "M_J_DQS_DN<0>")
	)
	(segment
		(start 64.986154 -63.76162)
		(end 65.240154 -63.76162)
		(width 0.14224)
		(layer "In11.Cu")
		(net "M_J_DQS_DN<0>")
	)
	(segment
		(start 61.390022 -63.696342)
		(end 61.5696 -63.87592)
		(width 0.14224)
		(layer "In11.Cu")
		(net "M_J_DQS_DN<0>")
	)
	(segment
		(start 59.84621 -61.990986)
		(end 60.026042 -62.170818)
		(width 0.14224)
		(layer "In11.Cu")
		(net "M_J_DQS_DN<0>")
	)
	(segment
		(start 36.501324 -4.15036)
		(end 36.501324 -4.5466)
		(width 0.14224)
		(layer "In11.Cu")
		(net "M_J_DQS_DN<0>")
	)
	(segment
		(start 36.81984 -35.471354)
		(end 36.81984 -37.564568)
		(width 0.14224)
		(layer "In11.Cu")
		(net "M_J_DQS_DN<0>")
	)
	(segment
		(start 74.045572 -65.89649)
		(end 74.04608 -65.89649)
		(width 0.0889)
		(layer "In11.Cu")
		(net "M_J_DQS_DN<0>")
	)
	(segment
		(start 36.930584 -34.079434)
		(end 36.091622 -34.079434)
		(width 0.14224)
		(layer "In11.Cu")
		(net "M_J_DQS_DN<0>")
	)
	(segment
		(start 66.359024 -63.91529)
		(end 67.188842 -63.91529)
		(width 0.0889)
		(layer "In11.Cu")
		(net "M_J_DQS_DN<0>")
	)
	(segment
		(start 70.60057 -63.91529)
		(end 70.633336 -63.91529)
		(width 0.0889)
		(layer "In11.Cu")
		(net "M_J_DQS_DN<0>")
	)
	(segment
		(start 60.670694 -62.815216)
		(end 60.670694 -62.977014)
		(width 0.14224)
		(layer "In11.Cu")
		(net "M_J_DQS_DN<0>")
	)
	(segment
		(start 35.73018 -34.930334)
		(end 35.958526 -35.15868)
		(width 0.14224)
		(layer "In11.Cu")
		(net "M_J_DQS_DN<0>")
	)
	(segment
		(start 63.92926 -63.76162)
		(end 64.18326 -63.76162)
		(width 0.14224)
		(layer "In11.Cu")
		(net "M_J_DQS_DN<0>")
	)
	(segment
		(start 69.752718 -63.41999)
		(end 69.754242 -63.41999)
		(width 0.0889)
		(layer "In11.Cu")
		(net "M_J_DQS_DN<0>")
	)
	(segment
		(start 36.81984 -6.111748)
		(end 36.81984 -24.994362)
		(width 0.14224)
		(layer "In11.Cu")
		(net "M_J_DQS_DN<0>")
	)
	(segment
		(start 73.17232 -65.400936)
		(end 73.201022 -65.400936)
		(width 0.0889)
		(layer "In11.Cu")
		(net "M_J_DQS_DN<0>")
	)
	(segment
		(start 59.445398 -61.751718)
		(end 59.684666 -61.990986)
		(width 0.14224)
		(layer "In11.Cu")
		(net "M_J_DQS_DN<0>")
	)
	(segment
		(start 60.329064 -62.635384)
		(end 60.490862 -62.635384)
		(width 0.14224)
		(layer "In11.Cu")
		(net "M_J_DQS_DN<0>")
	)
	(segment
		(start 60.026042 -62.332362)
		(end 60.329064 -62.635384)
		(width 0.14224)
		(layer "In11.Cu")
		(net "M_J_DQS_DN<0>")
	)
	(segment
		(start 63.519558 -63.87592)
		(end 63.81496 -63.87592)
		(width 0.14224)
		(layer "In11.Cu")
		(net "M_J_DQS_DN<0>")
	)
	(segment
		(start 74.89063 -65.400936)
		(end 74.919332 -65.400936)
		(width 0.0889)
		(layer "In11.Cu")
		(net "M_J_DQS_DN<0>")
	)
	(segment
		(start 36.848288 1.033272)
		(end 36.848288 -2.875788)
		(width 0.14224)
		(layer "In11.Cu")
		(net "M_J_DQS_DN<0>")
	)
	(segment
		(start 71.45528 -64.410336)
		(end 71.488046 -64.410336)
		(width 0.0889)
		(layer "In11.Cu")
		(net "M_J_DQS_DN<0>")
	)
	(segment
		(start 36.955984 -32.463994)
		(end 37.334952 -32.842962)
		(width 0.14224)
		(layer "In11.Cu")
		(net "M_J_DQS_DN<0>")
	)
	(segment
		(start 36.03752 -3.686556)
		(end 36.501324 -4.15036)
		(width 0.14224)
		(layer "In11.Cu")
		(net "M_J_DQS_DN<0>")
	)
	(segment
		(start 59.684666 -61.990986)
		(end 59.84621 -61.990986)
		(width 0.14224)
		(layer "In11.Cu")
		(net "M_J_DQS_DN<0>")
	)
	(segment
		(start 35.679888 -26.134314)
		(end 35.679888 -32.242506)
		(width 0.14224)
		(layer "In11.Cu")
		(net "M_J_DQS_DN<0>")
	)
	(segment
		(start 35.679888 -32.242506)
		(end 35.901376 -32.463994)
		(width 0.14224)
		(layer "In11.Cu")
		(net "M_J_DQS_DN<0>")
	)
	(segment
		(start 65.354454 -63.87592)
		(end 66.297556 -63.87592)
		(width 0.14224)
		(layer "In11.Cu")
		(net "M_J_DQS_DN<0>")
	)
	(segment
		(start 62.741302 -63.87592)
		(end 63.036958 -63.87592)
		(width 0.14224)
		(layer "In11.Cu")
		(net "M_J_DQS_DN<0>")
	)
	(segment
		(start 40.480234 -42.786554)
		(end 59.104022 -61.410342)
		(width 0.14224)
		(layer "In11.Cu")
		(net "M_J_DQS_DN<0>")
	)
	(segment
		(start 66.297556 -63.87592)
		(end 66.319654 -63.87592)
		(width 0.0889)
		(layer "In11.Cu")
		(net "M_J_DQS_DN<0>")
	)
	(segment
		(start 63.405258 -63.76162)
		(end 63.519558 -63.87592)
		(width 0.14224)
		(layer "In11.Cu")
		(net "M_J_DQS_DN<0>")
	)
	(segment
		(start 66.319654 -63.87592)
		(end 66.359024 -63.91529)
		(width 0.0889)
		(layer "In11.Cu")
		(net "M_J_DQS_DN<0>")
	)
	(segment
		(start 64.871854 -63.87592)
		(end 64.986154 -63.76162)
		(width 0.14224)
		(layer "In11.Cu")
		(net "M_J_DQS_DN<0>")
	)
	(segment
		(start 36.03752 1.84404)
		(end 36.848288 1.033272)
		(width 0.14224)
		(layer "In11.Cu")
		(net "M_J_DQS_DN<0>")
	)
	(segment
		(start 62.373002 -63.76162)
		(end 62.627002 -63.76162)
		(width 0.14224)
		(layer "In11.Cu")
		(net "M_J_DQS_DN<0>")
	)
	(segment
		(start 36.091622 -34.079434)
		(end 35.73018 -34.440876)
		(width 0.14224)
		(layer "In11.Cu")
		(net "M_J_DQS_DN<0>")
	)
	(segment
		(start 63.151258 -63.76162)
		(end 63.405258 -63.76162)
		(width 0.14224)
		(layer "In11.Cu")
		(net "M_J_DQS_DN<0>")
	)
	(segment
		(start 68.893944 -63.915036)
		(end 68.895468 -63.915036)
		(width 0.0889)
		(layer "In11.Cu")
		(net "M_J_DQS_DN<0>")
	)
	(segment
		(start 36.848288 -2.875788)
		(end 36.03752 -3.686556)
		(width 0.14224)
		(layer "In11.Cu")
		(net "M_J_DQS_DN<0>")
	)
	(segment
		(start 60.670694 -62.977014)
		(end 61.048646 -63.354966)
		(width 0.14224)
		(layer "In11.Cu")
		(net "M_J_DQS_DN<0>")
	)
	(segment
		(start 62.627002 -63.76162)
		(end 62.741302 -63.87592)
		(width 0.14224)
		(layer "In11.Cu")
		(net "M_J_DQS_DN<0>")
	)
	(segment
		(start 64.18326 -63.76162)
		(end 64.29756 -63.87592)
		(width 0.14224)
		(layer "In11.Cu")
		(net "M_J_DQS_DN<0>")
	)
	(segment
		(start 61.5696 -63.87592)
		(end 62.258702 -63.87592)
		(width 0.14224)
		(layer "In11.Cu")
		(net "M_J_DQS_DN<0>")
	)
	(segment
		(start 35.988244 -5.05968)
		(end 35.988244 -5.280152)
		(width 0.14224)
		(layer "In11.Cu")
		(net "M_J_DQS_DN<0>")
	)
	(segment
		(start 65.240154 -63.76162)
		(end 65.354454 -63.87592)
		(width 0.14224)
		(layer "In11.Cu")
		(net "M_J_DQS_DN<0>")
	)
	(segment
		(start 59.265566 -61.410342)
		(end 59.445398 -61.590174)
		(width 0.14224)
		(layer "In11.Cu")
		(net "M_J_DQS_DN<0>")
	)
	(segment
		(start 37.334952 -32.842962)
		(end 37.334952 -33.675066)
		(width 0.14224)
		(layer "In11.Cu")
		(net "M_J_DQS_DN<0>")
	)
	(arc
		(start 72.350376 -64.90589)
		(mid 72.633593 -64.990171)
		(end 72.840596 -65.201038)
		(width 0.0889)
		(layer "In11.Cu")
		(net "M_J_DQS_DN<0>")
	)
	(arc
		(start 74.919332 -65.400936)
		(mid 75.110974 -65.34377)
		(end 75.251056 -65.201038)
		(width 0.0889)
		(layer "In11.Cu")
		(net "M_J_DQS_DN<0>")
	)
	(arc
		(start 73.699116 -65.696338)
		(mid 73.845498 -65.842902)
		(end 74.045572 -65.89649)
		(width 0.0889)
		(layer "In11.Cu")
		(net "M_J_DQS_DN<0>")
	)
	(arc
		(start 71.123556 -64.210438)
		(mid 71.263635 -64.353174)
		(end 71.45528 -64.410336)
		(width 0.0889)
		(layer "In11.Cu")
		(net "M_J_DQS_DN<0>")
	)
	(arc
		(start 75.251056 -65.201038)
		(mid 75.45806 -64.990174)
		(end 75.741276 -64.90589)
		(width 0.0889)
		(layer "In11.Cu")
		(net "M_J_DQS_DN<0>")
	)
	(arc
		(start 74.392536 -65.696338)
		(mid 74.602889 -65.483366)
		(end 74.89063 -65.400936)
		(width 0.0889)
		(layer "In11.Cu")
		(net "M_J_DQS_DN<0>")
	)
	(arc
		(start 71.982076 -64.705738)
		(mid 72.123759 -64.849542)
		(end 72.31761 -64.90589)
		(width 0.0889)
		(layer "In11.Cu")
		(net "M_J_DQS_DN<0>")
	)
	(arc
		(start 72.840596 -65.201038)
		(mid 72.980675 -65.343774)
		(end 73.17232 -65.400936)
		(width 0.0889)
		(layer "In11.Cu")
		(net "M_J_DQS_DN<0>")
	)
	(arc
		(start 74.04608 -65.89649)
		(mid 74.246121 -65.842845)
		(end 74.392536 -65.696338)
		(width 0.0889)
		(layer "In11.Cu")
		(net "M_J_DQS_DN<0>")
	)
	(arc
		(start 67.524376 -63.715138)
		(mid 67.74023 -63.499157)
		(end 68.03517 -63.41999)
		(width 0.0889)
		(layer "In11.Cu")
		(net "M_J_DQS_DN<0>")
	)
	(arc
		(start 69.754242 -63.41999)
		(mid 70.049236 -63.499064)
		(end 70.265036 -63.715138)
		(width 0.0889)
		(layer "In11.Cu")
		(net "M_J_DQS_DN<0>")
	)
	(arc
		(start 70.633336 -63.91529)
		(mid 70.916553 -63.999571)
		(end 71.123556 -64.210438)
		(width 0.0889)
		(layer "In11.Cu")
		(net "M_J_DQS_DN<0>")
	)
	(arc
		(start 67.188842 -63.91529)
		(mid 67.382692 -63.85894)
		(end 67.524376 -63.715138)
		(width 0.0889)
		(layer "In11.Cu")
		(net "M_J_DQS_DN<0>")
	)
	(arc
		(start 71.488046 -64.410336)
		(mid 71.77347 -64.493803)
		(end 71.982076 -64.705738)
		(width 0.0889)
		(layer "In11.Cu")
		(net "M_J_DQS_DN<0>")
	)
	(arc
		(start 68.036948 -63.41999)
		(mid 68.332086 -63.499001)
		(end 68.547996 -63.715138)
		(width 0.0889)
		(layer "In11.Cu")
		(net "M_J_DQS_DN<0>")
	)
	(arc
		(start 75.774042 -64.90589)
		(mid 75.967892 -64.84954)
		(end 76.109576 -64.705738)
		(width 0.0889)
		(layer "In11.Cu")
		(net "M_J_DQS_DN<0>")
	)
	(arc
		(start 73.201022 -65.400936)
		(mid 73.488709 -65.483457)
		(end 73.699116 -65.696338)
		(width 0.0889)
		(layer "In11.Cu")
		(net "M_J_DQS_DN<0>")
	)
	(arc
		(start 68.895468 -63.915036)
		(mid 69.095241 -63.861467)
		(end 69.241416 -63.715138)
		(width 0.0889)
		(layer "In11.Cu")
		(net "M_J_DQS_DN<0>")
	)
	(arc
		(start 76.109576 -64.705738)
		(mid 76.318184 -64.493806)
		(end 76.603606 -64.410336)
		(width 0.0889)
		(layer "In11.Cu")
		(net "M_J_DQS_DN<0>")
	)
	(arc
		(start 70.265036 -63.715138)
		(mid 70.406719 -63.858942)
		(end 70.60057 -63.91529)
		(width 0.0889)
		(layer "In11.Cu")
		(net "M_J_DQS_DN<0>")
	)
	(arc
		(start 76.639166 -64.410336)
		(mid 76.895988 -64.477637)
		(end 77.097382 -64.65062)
		(width 0.0889)
		(layer "In11.Cu")
		(net "M_J_DQS_DN<0>")
	)
	(arc
		(start 69.241416 -63.715138)
		(mid 69.457489 -63.49903)
		(end 69.752718 -63.41999)
		(width 0.0889)
		(layer "In11.Cu")
		(net "M_J_DQS_DN<0>")
	)
	(arc
		(start 68.547996 -63.715138)
		(mid 68.694168 -63.861473)
		(end 68.893944 -63.915036)
		(width 0.0889)
		(layer "In11.Cu")
		(net "M_J_DQS_DN<0>")
	)
	(segment
		(start 78.051406 -60.54344)
		(end 77.479906 -60.54344)
		(width 0.0889)
		(layer "F.Cu")
		(net "M_J_DQ<9>")
	)
	(segment
		(start 42.449496 3.778758)
		(end 42.449496 2.514854)
		(width 0.1651)
		(layer "F.Cu")
		(net "M_J_DQ<9>")
	)
	(via
		(at 43.12158 -3.076956)
		(size 0.508)
		(drill 0.254)
		(layers "F.Cu" "B.Cu")
		(net "M_J_DQ<9>")
	)
	(via
		(at 77.479906 -60.54344)
		(size 0.508)
		(drill 0.254)
		(layers "F.Cu" "B.Cu")
		(net "M_J_DQ<9>")
	)
	(via
		(at 42.449496 2.514854)
		(size 0.508)
		(drill 0.254)
		(layers "F.Cu" "B.Cu")
		(net "M_J_DQ<9>")
	)
	(segment
		(start 43.29938 -1.021842)
		(end 43.29938 -2.395982)
		(width 0.1651)
		(layer "B.Cu")
		(net "M_J_DQ<9>")
	)
	(segment
		(start 43.29938 -2.395982)
		(end 43.12158 -2.573782)
		(width 0.1651)
		(layer "B.Cu")
		(net "M_J_DQ<9>")
	)
	(segment
		(start 43.12158 -2.573782)
		(end 43.12158 -3.076956)
		(width 0.1651)
		(layer "B.Cu")
		(net "M_J_DQ<9>")
	)
	(segment
		(start 43.609514 -18.998946)
		(end 43.762168 -19.1516)
		(width 0.14224)
		(layer "In11.Cu")
		(net "M_J_DQ<9>")
	)
	(segment
		(start 75.848972 -61.13399)
		(end 76.400406 -61.372496)
		(width 0.0889)
		(layer "In11.Cu")
		(net "M_J_DQ<9>")
	)
	(segment
		(start 43.495722 -2.702814)
		(end 43.12158 -3.076956)
		(width 0.14224)
		(layer "In11.Cu")
		(net "M_J_DQ<9>")
	)
	(segment
		(start 43.609514 -21.2852)
		(end 43.609514 -25.785064)
		(width 0.14224)
		(layer "In11.Cu")
		(net "M_J_DQ<9>")
	)
	(segment
		(start 64.784986 -58.176668)
		(end 65.310512 -58.176668)
		(width 0.14224)
		(layer "In11.Cu")
		(net "M_J_DQ<9>")
	)
	(segment
		(start 48.213518 -41.6052)
		(end 49.199038 -41.6052)
		(width 0.14224)
		(layer "In11.Cu")
		(net "M_J_DQ<9>")
	)
	(segment
		(start 43.652186 1.128776)
		(end 43.652186 0.7874)
		(width 0.14224)
		(layer "In11.Cu")
		(net "M_J_DQ<9>")
	)
	(segment
		(start 42.595038 -3.603498)
		(end 42.595038 -3.861816)
		(width 0.14224)
		(layer "In11.Cu")
		(net "M_J_DQ<9>")
	)
	(segment
		(start 74.03465 -61.93409)
		(end 74.236072 -61.93409)
		(width 0.0889)
		(layer "In11.Cu")
		(net "M_J_DQ<9>")
	)
	(segment
		(start 43.762168 -11.5951)
		(end 43.609514 -11.747754)
		(width 0.14224)
		(layer "In11.Cu")
		(net "M_J_DQ<9>")
	)
	(segment
		(start 51.014884 -43.421046)
		(end 51.014884 -44.406566)
		(width 0.14224)
		(layer "In11.Cu")
		(net "M_J_DQ<9>")
	)
	(segment
		(start 43.244262 -36.635944)
		(end 48.213518 -41.6052)
		(width 0.14224)
		(layer "In11.Cu")
		(net "M_J_DQ<9>")
	)
	(segment
		(start 68.766436 -59.457336)
		(end 69.771006 -59.457336)
		(width 0.0889)
		(layer "In11.Cu")
		(net "M_J_DQ<9>")
	)
	(segment
		(start 76.968096 -61.238638)
		(end 76.98486 -61.209174)
		(width 0.0889)
		(layer "In11.Cu")
		(net "M_J_DQ<9>")
	)
	(segment
		(start 74.236072 -61.93409)
		(end 74.627486 -61.740034)
		(width 0.0889)
		(layer "In11.Cu")
		(net "M_J_DQ<9>")
	)
	(segment
		(start 67.721734 -58.412634)
		(end 68.766436 -59.457336)
		(width 0.0889)
		(layer "In11.Cu")
		(net "M_J_DQ<9>")
	)
	(segment
		(start 43.762168 -9.601454)
		(end 43.762168 -11.5951)
		(width 0.14224)
		(layer "In11.Cu")
		(net "M_J_DQ<9>")
	)
	(segment
		(start 43.609514 -25.785064)
		(end 43.244262 -26.150316)
		(width 0.14224)
		(layer "In11.Cu")
		(net "M_J_DQ<9>")
	)
	(segment
		(start 43.244262 -26.150316)
		(end 43.244262 -36.635944)
		(width 0.14224)
		(layer "In11.Cu")
		(net "M_J_DQ<9>")
	)
	(segment
		(start 42.595038 -3.861816)
		(end 42.974514 -4.241292)
		(width 0.14224)
		(layer "In11.Cu")
		(net "M_J_DQ<9>")
	)
	(segment
		(start 73.17232 -61.438536)
		(end 73.205086 -61.438536)
		(width 0.0889)
		(layer "In11.Cu")
		(net "M_J_DQ<9>")
	)
	(segment
		(start 42.974514 -5.841746)
		(end 43.609514 -6.476746)
		(width 0.14224)
		(layer "In11.Cu")
		(net "M_J_DQ<9>")
	)
	(segment
		(start 51.014884 -44.406566)
		(end 64.784986 -58.176668)
		(width 0.14224)
		(layer "In11.Cu")
		(net "M_J_DQ<9>")
	)
	(segment
		(start 71.45528 -60.447936)
		(end 71.488046 -60.447936)
		(width 0.0889)
		(layer "In11.Cu")
		(net "M_J_DQ<9>")
	)
	(segment
		(start 42.926762 1.4986)
		(end 43.282362 1.4986)
		(width 0.14224)
		(layer "In11.Cu")
		(net "M_J_DQ<9>")
	)
	(segment
		(start 65.546478 -58.412634)
		(end 67.721734 -58.412634)
		(width 0.0889)
		(layer "In11.Cu")
		(net "M_J_DQ<9>")
	)
	(segment
		(start 70.60057 -59.95289)
		(end 70.633336 -59.95289)
		(width 0.0889)
		(layer "In11.Cu")
		(net "M_J_DQ<9>")
	)
	(segment
		(start 65.310512 -58.176668)
		(end 65.546478 -58.412634)
		(width 0.0889)
		(layer "In11.Cu")
		(net "M_J_DQ<9>")
	)
	(segment
		(start 42.449496 2.514854)
		(end 42.449496 1.975866)
		(width 0.14224)
		(layer "In11.Cu")
		(net "M_J_DQ<9>")
	)
	(segment
		(start 43.609514 -9.4488)
		(end 43.762168 -9.601454)
		(width 0.14224)
		(layer "In11.Cu")
		(net "M_J_DQ<9>")
	)
	(segment
		(start 43.609514 -6.476746)
		(end 43.609514 -9.4488)
		(width 0.14224)
		(layer "In11.Cu")
		(net "M_J_DQ<9>")
	)
	(segment
		(start 43.762168 -19.1516)
		(end 43.762168 -21.132546)
		(width 0.14224)
		(layer "In11.Cu")
		(net "M_J_DQ<9>")
	)
	(segment
		(start 75.74788 -61.13399)
		(end 75.848972 -61.13399)
		(width 0.0889)
		(layer "In11.Cu")
		(net "M_J_DQ<9>")
	)
	(segment
		(start 43.282362 1.4986)
		(end 43.652186 1.128776)
		(width 0.14224)
		(layer "In11.Cu")
		(net "M_J_DQ<9>")
	)
	(segment
		(start 42.449496 1.975866)
		(end 42.926762 1.4986)
		(width 0.14224)
		(layer "In11.Cu")
		(net "M_J_DQ<9>")
	)
	(segment
		(start 43.609514 -11.747754)
		(end 43.609514 -18.998946)
		(width 0.14224)
		(layer "In11.Cu")
		(net "M_J_DQ<9>")
	)
	(segment
		(start 43.12158 -3.076956)
		(end 42.595038 -3.603498)
		(width 0.14224)
		(layer "In11.Cu")
		(net "M_J_DQ<9>")
	)
	(segment
		(start 43.762168 -21.132546)
		(end 43.609514 -21.2852)
		(width 0.14224)
		(layer "In11.Cu")
		(net "M_J_DQ<9>")
	)
	(segment
		(start 49.199038 -41.6052)
		(end 51.014884 -43.421046)
		(width 0.14224)
		(layer "In11.Cu")
		(net "M_J_DQ<9>")
	)
	(segment
		(start 42.974514 -4.241292)
		(end 42.974514 -5.841746)
		(width 0.14224)
		(layer "In11.Cu")
		(net "M_J_DQ<9>")
	)
	(segment
		(start 43.652186 0.7874)
		(end 43.495722 0.630936)
		(width 0.14224)
		(layer "In11.Cu")
		(net "M_J_DQ<9>")
	)
	(segment
		(start 72.31761 -60.94349)
		(end 72.350376 -60.94349)
		(width 0.0889)
		(layer "In11.Cu")
		(net "M_J_DQ<9>")
	)
	(segment
		(start 76.6064 -61.438536)
		(end 76.636372 -61.438536)
		(width 0.0889)
		(layer "In11.Cu")
		(net "M_J_DQ<9>")
	)
	(segment
		(start 76.98486 -61.209174)
		(end 77.479906 -60.54344)
		(width 0.0889)
		(layer "In11.Cu")
		(net "M_J_DQ<9>")
	)
	(segment
		(start 74.89317 -61.629036)
		(end 74.925936 -61.629036)
		(width 0.0889)
		(layer "In11.Cu")
		(net "M_J_DQ<9>")
	)
	(segment
		(start 43.495722 0.630936)
		(end 43.495722 -2.702814)
		(width 0.14224)
		(layer "In11.Cu")
		(net "M_J_DQ<9>")
	)
	(arc
		(start 71.123556 -60.248038)
		(mid 71.263635 -60.390774)
		(end 71.45528 -60.447936)
		(width 0.0889)
		(layer "In11.Cu")
		(net "M_J_DQ<9>")
	)
	(arc
		(start 69.771006 -59.457336)
		(mid 70.05643 -59.540803)
		(end 70.265036 -59.752738)
		(width 0.0889)
		(layer "In11.Cu")
		(net "M_J_DQ<9>")
	)
	(arc
		(start 73.205086 -61.438536)
		(mid 73.49051 -61.522003)
		(end 73.699116 -61.733938)
		(width 0.0889)
		(layer "In11.Cu")
		(net "M_J_DQ<9>")
	)
	(arc
		(start 75.416156 -61.333888)
		(mid 75.556235 -61.191152)
		(end 75.74788 -61.13399)
		(width 0.0889)
		(layer "In11.Cu")
		(net "M_J_DQ<9>")
	)
	(arc
		(start 71.488046 -60.447936)
		(mid 71.77347 -60.531403)
		(end 71.982076 -60.743338)
		(width 0.0889)
		(layer "In11.Cu")
		(net "M_J_DQ<9>")
	)
	(arc
		(start 72.840596 -61.238638)
		(mid 72.980675 -61.381374)
		(end 73.17232 -61.438536)
		(width 0.0889)
		(layer "In11.Cu")
		(net "M_J_DQ<9>")
	)
	(arc
		(start 70.265036 -59.752738)
		(mid 70.406719 -59.896542)
		(end 70.60057 -59.95289)
		(width 0.0889)
		(layer "In11.Cu")
		(net "M_J_DQ<9>")
	)
	(arc
		(start 76.400406 -61.372496)
		(mid 76.498855 -61.419709)
		(end 76.6064 -61.438536)
		(width 0.0889)
		(layer "In11.Cu")
		(net "M_J_DQ<9>")
	)
	(arc
		(start 76.636372 -61.438536)
		(mid 76.828014 -61.38137)
		(end 76.968096 -61.238638)
		(width 0.0889)
		(layer "In11.Cu")
		(net "M_J_DQ<9>")
	)
	(arc
		(start 74.627486 -61.740034)
		(mid 74.749995 -61.659792)
		(end 74.89317 -61.629036)
		(width 0.0889)
		(layer "In11.Cu")
		(net "M_J_DQ<9>")
	)
	(arc
		(start 74.925936 -61.629036)
		(mid 75.209153 -61.544755)
		(end 75.416156 -61.333888)
		(width 0.0889)
		(layer "In11.Cu")
		(net "M_J_DQ<9>")
	)
	(arc
		(start 71.982076 -60.743338)
		(mid 72.123759 -60.887142)
		(end 72.31761 -60.94349)
		(width 0.0889)
		(layer "In11.Cu")
		(net "M_J_DQ<9>")
	)
	(arc
		(start 73.699116 -61.733938)
		(mid 73.840799 -61.877742)
		(end 74.03465 -61.93409)
		(width 0.0889)
		(layer "In11.Cu")
		(net "M_J_DQ<9>")
	)
	(arc
		(start 70.633336 -59.95289)
		(mid 70.916553 -60.037171)
		(end 71.123556 -60.248038)
		(width 0.0889)
		(layer "In11.Cu")
		(net "M_J_DQ<9>")
	)
	(arc
		(start 72.350376 -60.94349)
		(mid 72.633593 -61.027771)
		(end 72.840596 -61.238638)
		(width 0.0889)
		(layer "In11.Cu")
		(net "M_J_DQ<9>")
	)
	(segment
		(start 43.29938 -0.821182)
		(end 43.12158 1.0414)
		(width 0.1651)
		(layer "F.Cu")
		(net "M_J_DQ<8>")
	)
	(segment
		(start 76.334366 -61.53404)
		(end 75.762866 -61.53404)
		(width 0.0889)
		(layer "F.Cu")
		(net "M_J_DQ<8>")
	)
	(via
		(at 43.12158 1.0414)
		(size 0.508)
		(drill 0.254)
		(layers "F.Cu" "B.Cu")
		(net "M_J_DQ<8>")
	)
	(via
		(at 42.449496 -4.357878)
		(size 0.508)
		(drill 0.254)
		(layers "F.Cu" "B.Cu")
		(net "M_J_DQ<8>")
	)
	(via
		(at 75.762866 -61.53404)
		(size 0.508)
		(drill 0.254)
		(layers "F.Cu" "B.Cu")
		(net "M_J_DQ<8>")
	)
	(segment
		(start 42.449496 -5.621782)
		(end 42.449496 -4.357878)
		(width 0.1651)
		(layer "B.Cu")
		(net "M_J_DQ<8>")
	)
	(segment
		(start 42.449496 -6.281928)
		(end 42.923714 -6.756146)
		(width 0.14224)
		(layer "In11.Cu")
		(net "M_J_DQ<8>")
	)
	(segment
		(start 42.974514 -18.668746)
		(end 42.974514 -18.948654)
		(width 0.14224)
		(layer "In11.Cu")
		(net "M_J_DQ<8>")
	)
	(segment
		(start 42.733214 -37.02304)
		(end 48.47971 -42.769536)
		(width 0.14224)
		(layer "In11.Cu")
		(net "M_J_DQ<8>")
	)
	(segment
		(start 49.137062 -43.207686)
		(end 49.137062 -43.426888)
		(width 0.14224)
		(layer "In11.Cu")
		(net "M_J_DQ<8>")
	)
	(segment
		(start 42.923714 -7.226554)
		(end 42.631614 -7.518654)
		(width 0.14224)
		(layer "In11.Cu")
		(net "M_J_DQ<8>")
	)
	(segment
		(start 42.82948 -1.0795)
		(end 42.51198 -1.397)
		(width 0.14224)
		(layer "In11.Cu")
		(net "M_J_DQ<8>")
	)
	(segment
		(start 42.733214 -25.709626)
		(end 42.733214 -37.02304)
		(width 0.14224)
		(layer "In11.Cu")
		(net "M_J_DQ<8>")
	)
	(segment
		(start 49.246028 -42.44086)
		(end 49.465484 -42.660316)
		(width 0.14224)
		(layer "In11.Cu")
		(net "M_J_DQ<8>")
	)
	(segment
		(start 42.901362 -2.090928)
		(end 42.901362 -2.5908)
		(width 0.14224)
		(layer "In11.Cu")
		(net "M_J_DQ<8>")
	)
	(segment
		(start 74.028046 -62.12459)
		(end 74.210672 -62.12459)
		(width 0.0889)
		(layer "In11.Cu")
		(net "M_J_DQ<8>")
	)
	(segment
		(start 67.64274 -58.603134)
		(end 68.687442 -59.647836)
		(width 0.0889)
		(layer "In11.Cu")
		(net "M_J_DQ<8>")
	)
	(segment
		(start 42.631614 -18.325846)
		(end 42.974514 -18.668746)
		(width 0.14224)
		(layer "In11.Cu")
		(net "M_J_DQ<8>")
	)
	(segment
		(start 42.631614 -12.424156)
		(end 42.631614 -13.524992)
		(width 0.14224)
		(layer "In11.Cu")
		(net "M_J_DQ<8>")
	)
	(segment
		(start 50.354992 -43.743626)
		(end 50.01387 -44.084748)
		(width 0.14224)
		(layer "In11.Cu")
		(net "M_J_DQ<8>")
	)
	(segment
		(start 48.698658 -42.769536)
		(end 49.027334 -42.44086)
		(width 0.14224)
		(layer "In11.Cu")
		(net "M_J_DQ<8>")
	)
	(segment
		(start 42.901362 0.236728)
		(end 42.48658 -0.178054)
		(width 0.14224)
		(layer "In11.Cu")
		(net "M_J_DQ<8>")
	)
	(segment
		(start 42.164762 -4.073144)
		(end 42.449496 -4.357878)
		(width 0.14224)
		(layer "In11.Cu")
		(net "M_J_DQ<8>")
	)
	(segment
		(start 42.771568 -11.557)
		(end 42.974514 -11.759946)
		(width 0.14224)
		(layer "In11.Cu")
		(net "M_J_DQ<8>")
	)
	(segment
		(start 68.687442 -59.647836)
		(end 69.764402 -59.647836)
		(width 0.0889)
		(layer "In11.Cu")
		(net "M_J_DQ<8>")
	)
	(segment
		(start 42.631614 -13.524992)
		(end 42.974514 -13.867892)
		(width 0.14224)
		(layer "In11.Cu")
		(net "M_J_DQ<8>")
	)
	(segment
		(start 42.923714 -6.756146)
		(end 42.923714 -7.226554)
		(width 0.14224)
		(layer "In11.Cu")
		(net "M_J_DQ<8>")
	)
	(segment
		(start 48.47971 -42.769536)
		(end 48.698658 -42.769536)
		(width 0.14224)
		(layer "In11.Cu")
		(net "M_J_DQ<8>")
	)
	(segment
		(start 49.916588 -43.304968)
		(end 50.135536 -43.304968)
		(width 0.14224)
		(layer "In11.Cu")
		(net "M_J_DQ<8>")
	)
	(segment
		(start 42.82948 -0.8509)
		(end 42.82948 -1.0795)
		(width 0.14224)
		(layer "In11.Cu")
		(net "M_J_DQ<8>")
	)
	(segment
		(start 50.135536 -43.304968)
		(end 50.354992 -43.524424)
		(width 0.14224)
		(layer "In11.Cu")
		(net "M_J_DQ<8>")
	)
	(segment
		(start 73.165716 -61.629036)
		(end 73.198482 -61.629036)
		(width 0.0889)
		(layer "In11.Cu")
		(net "M_J_DQ<8>")
	)
	(segment
		(start 42.796968 -19.1262)
		(end 42.796968 -21.234654)
		(width 0.14224)
		(layer "In11.Cu")
		(net "M_J_DQ<8>")
	)
	(segment
		(start 70.593966 -60.14339)
		(end 70.626732 -60.14339)
		(width 0.0889)
		(layer "In11.Cu")
		(net "M_J_DQ<8>")
	)
	(segment
		(start 50.354992 -43.524424)
		(end 50.354992 -43.743626)
		(width 0.14224)
		(layer "In11.Cu")
		(net "M_J_DQ<8>")
	)
	(segment
		(start 50.01387 -44.084748)
		(end 50.01387 -44.303696)
		(width 0.14224)
		(layer "In11.Cu")
		(net "M_J_DQ<8>")
	)
	(segment
		(start 75.251056 -62.229238)
		(end 75.26782 -62.199774)
		(width 0.0889)
		(layer "In11.Cu")
		(net "M_J_DQ<8>")
	)
	(segment
		(start 49.465484 -42.660316)
		(end 49.465484 -42.879264)
		(width 0.14224)
		(layer "In11.Cu")
		(net "M_J_DQ<8>")
	)
	(segment
		(start 42.48658 -0.508)
		(end 42.82948 -0.8509)
		(width 0.14224)
		(layer "In11.Cu")
		(net "M_J_DQ<8>")
	)
	(segment
		(start 42.923968 -23.405846)
		(end 42.923968 -25.518872)
		(width 0.14224)
		(layer "In11.Cu")
		(net "M_J_DQ<8>")
	)
	(segment
		(start 74.88936 -62.429136)
		(end 74.919332 -62.429136)
		(width 0.0889)
		(layer "In11.Cu")
		(net "M_J_DQ<8>")
	)
	(segment
		(start 42.164762 -3.3274)
		(end 42.164762 -4.073144)
		(width 0.14224)
		(layer "In11.Cu")
		(net "M_J_DQ<8>")
	)
	(segment
		(start 65.519046 -58.603134)
		(end 67.64274 -58.603134)
		(width 0.0889)
		(layer "In11.Cu")
		(net "M_J_DQ<8>")
	)
	(segment
		(start 42.974514 -9.3472)
		(end 42.771568 -9.550146)
		(width 0.14224)
		(layer "In11.Cu")
		(net "M_J_DQ<8>")
	)
	(segment
		(start 42.631614 -23.113492)
		(end 42.923968 -23.405846)
		(width 0.14224)
		(layer "In11.Cu")
		(net "M_J_DQ<8>")
	)
	(segment
		(start 42.974514 -21.4122)
		(end 42.974514 -21.682456)
		(width 0.14224)
		(layer "In11.Cu")
		(net "M_J_DQ<8>")
	)
	(segment
		(start 42.974514 -12.081256)
		(end 42.631614 -12.424156)
		(width 0.14224)
		(layer "In11.Cu")
		(net "M_J_DQ<8>")
	)
	(segment
		(start 42.974514 -11.759946)
		(end 42.974514 -12.081256)
		(width 0.14224)
		(layer "In11.Cu")
		(net "M_J_DQ<8>")
	)
	(segment
		(start 43.12158 1.0414)
		(end 42.901362 0.821182)
		(width 0.14224)
		(layer "In11.Cu")
		(net "M_J_DQ<8>")
	)
	(segment
		(start 49.137062 -43.426888)
		(end 49.356518 -43.646344)
		(width 0.14224)
		(layer "In11.Cu")
		(net "M_J_DQ<8>")
	)
	(segment
		(start 74.210672 -62.12459)
		(end 74.665586 -62.350396)
		(width 0.0889)
		(layer "In11.Cu")
		(net "M_J_DQ<8>")
	)
	(segment
		(start 42.631614 -22.025356)
		(end 42.631614 -23.113492)
		(width 0.14224)
		(layer "In11.Cu")
		(net "M_J_DQ<8>")
	)
	(segment
		(start 42.51198 -1.701546)
		(end 42.901362 -2.090928)
		(width 0.14224)
		(layer "In11.Cu")
		(net "M_J_DQ<8>")
	)
	(segment
		(start 42.974514 -21.682456)
		(end 42.631614 -22.025356)
		(width 0.14224)
		(layer "In11.Cu")
		(net "M_J_DQ<8>")
	)
	(segment
		(start 42.631614 -8.699246)
		(end 42.974514 -9.042146)
		(width 0.14224)
		(layer "In11.Cu")
		(net "M_J_DQ<8>")
	)
	(segment
		(start 42.51198 -1.397)
		(end 42.51198 -1.701546)
		(width 0.14224)
		(layer "In11.Cu")
		(net "M_J_DQ<8>")
	)
	(segment
		(start 65.310512 -58.811668)
		(end 65.519046 -58.603134)
		(width 0.0889)
		(layer "In11.Cu")
		(net "M_J_DQ<8>")
	)
	(segment
		(start 49.465484 -42.879264)
		(end 49.137062 -43.207686)
		(width 0.14224)
		(layer "In11.Cu")
		(net "M_J_DQ<8>")
	)
	(segment
		(start 42.771568 -9.550146)
		(end 42.771568 -11.557)
		(width 0.14224)
		(layer "In11.Cu")
		(net "M_J_DQ<8>")
	)
	(segment
		(start 49.575212 -43.646344)
		(end 49.916588 -43.304968)
		(width 0.14224)
		(layer "In11.Cu")
		(net "M_J_DQ<8>")
	)
	(segment
		(start 42.796968 -21.234654)
		(end 42.974514 -21.4122)
		(width 0.14224)
		(layer "In11.Cu")
		(net "M_J_DQ<8>")
	)
	(segment
		(start 42.48658 -0.178054)
		(end 42.48658 -0.508)
		(width 0.14224)
		(layer "In11.Cu")
		(net "M_J_DQ<8>")
	)
	(segment
		(start 42.974514 -9.042146)
		(end 42.974514 -9.3472)
		(width 0.14224)
		(layer "In11.Cu")
		(net "M_J_DQ<8>")
	)
	(segment
		(start 42.923968 -25.518872)
		(end 42.733214 -25.709626)
		(width 0.14224)
		(layer "In11.Cu")
		(net "M_J_DQ<8>")
	)
	(segment
		(start 42.901362 0.821182)
		(end 42.901362 0.236728)
		(width 0.14224)
		(layer "In11.Cu")
		(net "M_J_DQ<8>")
	)
	(segment
		(start 42.901362 -2.5908)
		(end 42.164762 -3.3274)
		(width 0.14224)
		(layer "In11.Cu")
		(net "M_J_DQ<8>")
	)
	(segment
		(start 42.631614 -17.119854)
		(end 42.631614 -18.325846)
		(width 0.14224)
		(layer "In11.Cu")
		(net "M_J_DQ<8>")
	)
	(segment
		(start 42.449496 -4.357878)
		(end 42.449496 -6.281928)
		(width 0.14224)
		(layer "In11.Cu")
		(net "M_J_DQ<8>")
	)
	(segment
		(start 42.631614 -7.518654)
		(end 42.631614 -8.699246)
		(width 0.14224)
		(layer "In11.Cu")
		(net "M_J_DQ<8>")
	)
	(segment
		(start 64.521842 -58.811668)
		(end 65.310512 -58.811668)
		(width 0.14224)
		(layer "In11.Cu")
		(net "M_J_DQ<8>")
	)
	(segment
		(start 75.26782 -62.199774)
		(end 75.762866 -61.53404)
		(width 0.0889)
		(layer "In11.Cu")
		(net "M_J_DQ<8>")
	)
	(segment
		(start 42.974514 -16.776954)
		(end 42.631614 -17.119854)
		(width 0.14224)
		(layer "In11.Cu")
		(net "M_J_DQ<8>")
	)
	(segment
		(start 72.311006 -61.13399)
		(end 72.343772 -61.13399)
		(width 0.0889)
		(layer "In11.Cu")
		(net "M_J_DQ<8>")
	)
	(segment
		(start 42.974514 -13.867892)
		(end 42.974514 -16.776954)
		(width 0.14224)
		(layer "In11.Cu")
		(net "M_J_DQ<8>")
	)
	(segment
		(start 71.448676 -60.638436)
		(end 71.481442 -60.638436)
		(width 0.0889)
		(layer "In11.Cu")
		(net "M_J_DQ<8>")
	)
	(segment
		(start 49.356518 -43.646344)
		(end 49.575212 -43.646344)
		(width 0.14224)
		(layer "In11.Cu")
		(net "M_J_DQ<8>")
	)
	(segment
		(start 42.974514 -18.948654)
		(end 42.796968 -19.1262)
		(width 0.14224)
		(layer "In11.Cu")
		(net "M_J_DQ<8>")
	)
	(segment
		(start 49.027334 -42.44086)
		(end 49.246028 -42.44086)
		(width 0.14224)
		(layer "In11.Cu")
		(net "M_J_DQ<8>")
	)
	(segment
		(start 50.01387 -44.303696)
		(end 64.521842 -58.811668)
		(width 0.14224)
		(layer "In11.Cu")
		(net "M_J_DQ<8>")
	)
	(arc
		(start 71.481442 -60.638436)
		(mid 71.675292 -60.694786)
		(end 71.816976 -60.838588)
		(width 0.0889)
		(layer "In11.Cu")
		(net "M_J_DQ<8>")
	)
	(arc
		(start 69.764402 -59.647836)
		(mid 69.958252 -59.704186)
		(end 70.099936 -59.847988)
		(width 0.0889)
		(layer "In11.Cu")
		(net "M_J_DQ<8>")
	)
	(arc
		(start 74.665586 -62.350396)
		(mid 74.771509 -62.406711)
		(end 74.88936 -62.429136)
		(width 0.0889)
		(layer "In11.Cu")
		(net "M_J_DQ<8>")
	)
	(arc
		(start 71.816976 -60.838588)
		(mid 72.025584 -61.05052)
		(end 72.311006 -61.13399)
		(width 0.0889)
		(layer "In11.Cu")
		(net "M_J_DQ<8>")
	)
	(arc
		(start 74.919332 -62.429136)
		(mid 75.110974 -62.37197)
		(end 75.251056 -62.229238)
		(width 0.0889)
		(layer "In11.Cu")
		(net "M_J_DQ<8>")
	)
	(arc
		(start 70.099936 -59.847988)
		(mid 70.308544 -60.05992)
		(end 70.593966 -60.14339)
		(width 0.0889)
		(layer "In11.Cu")
		(net "M_J_DQ<8>")
	)
	(arc
		(start 70.626732 -60.14339)
		(mid 70.818374 -60.200556)
		(end 70.958456 -60.343288)
		(width 0.0889)
		(layer "In11.Cu")
		(net "M_J_DQ<8>")
	)
	(arc
		(start 73.534016 -61.829188)
		(mid 73.742624 -62.04112)
		(end 74.028046 -62.12459)
		(width 0.0889)
		(layer "In11.Cu")
		(net "M_J_DQ<8>")
	)
	(arc
		(start 73.198482 -61.629036)
		(mid 73.392332 -61.685386)
		(end 73.534016 -61.829188)
		(width 0.0889)
		(layer "In11.Cu")
		(net "M_J_DQ<8>")
	)
	(arc
		(start 70.958456 -60.343288)
		(mid 71.16546 -60.554152)
		(end 71.448676 -60.638436)
		(width 0.0889)
		(layer "In11.Cu")
		(net "M_J_DQ<8>")
	)
	(arc
		(start 72.675496 -61.333888)
		(mid 72.8825 -61.544752)
		(end 73.165716 -61.629036)
		(width 0.0889)
		(layer "In11.Cu")
		(net "M_J_DQ<8>")
	)
	(arc
		(start 72.343772 -61.13399)
		(mid 72.535414 -61.191156)
		(end 72.675496 -61.333888)
		(width 0.0889)
		(layer "In11.Cu")
		(net "M_J_DQ<8>")
	)
	(segment
		(start 37.34943 3.778758)
		(end 37.34943 2.514854)
		(width 0.1651)
		(layer "F.Cu")
		(net "M_J_DQ<7>")
	)
	(segment
		(start 77.192886 -64.010286)
		(end 76.621386 -64.010286)
		(width 0.0889)
		(layer "F.Cu")
		(net "M_J_DQ<7>")
	)
	(via
		(at 76.621386 -64.010286)
		(size 0.508)
		(drill 0.254)
		(layers "F.Cu" "B.Cu")
		(net "M_J_DQ<7>")
	)
	(via
		(at 38.199314 -3.076956)
		(size 0.508)
		(drill 0.254)
		(layers "F.Cu" "B.Cu")
		(net "M_J_DQ<7>")
	)
	(via
		(at 37.34943 2.514854)
		(size 0.508)
		(drill 0.254)
		(layers "F.Cu" "B.Cu")
		(net "M_J_DQ<7>")
	)
	(segment
		(start 38.199314 -1.022096)
		(end 38.199314 -3.076956)
		(width 0.1651)
		(layer "B.Cu")
		(net "M_J_DQ<7>")
	)
	(segment
		(start 38.199568 -1.021842)
		(end 38.199314 -1.022096)
		(width 0.1651)
		(layer "B.Cu")
		(net "M_J_DQ<7>")
	)
	(segment
		(start 38.682168 -19.1262)
		(end 38.682168 -21.180552)
		(width 0.14224)
		(layer "In11.Cu")
		(net "M_J_DQ<7>")
	)
	(segment
		(start 37.729668 -3.546602)
		(end 37.729668 -3.9751)
		(width 0.14224)
		(layer "In11.Cu")
		(net "M_J_DQ<7>")
	)
	(segment
		(start 45.05579 -45.163486)
		(end 45.60316 -44.616116)
		(width 0.14224)
		(layer "In11.Cu")
		(net "M_J_DQ<7>")
	)
	(segment
		(start 44.617386 -44.725082)
		(end 44.617386 -44.94403)
		(width 0.14224)
		(layer "In11.Cu")
		(net "M_J_DQ<7>")
	)
	(segment
		(start 74.886566 -64.410336)
		(end 74.919332 -64.410336)
		(width 0.0889)
		(layer "In11.Cu")
		(net "M_J_DQ<7>")
	)
	(segment
		(start 69.735446 -62.429136)
		(end 69.771006 -62.429136)
		(width 0.0889)
		(layer "In11.Cu")
		(net "M_J_DQ<7>")
	)
	(segment
		(start 44.726352 -43.739308)
		(end 44.9453 -43.739308)
		(width 0.14224)
		(layer "In11.Cu")
		(net "M_J_DQ<7>")
	)
	(segment
		(start 38.504368 -37.25418)
		(end 38.646608 -37.39642)
		(width 0.14224)
		(layer "In11.Cu")
		(net "M_J_DQ<7>")
	)
	(segment
		(start 38.504368 -35.58794)
		(end 38.504368 -35.9537)
		(width 0.14224)
		(layer "In11.Cu")
		(net "M_J_DQ<7>")
	)
	(segment
		(start 38.45052 -26.6954)
		(end 37.183568 -26.6954)
		(width 0.14224)
		(layer "In11.Cu")
		(net "M_J_DQ<7>")
	)
	(segment
		(start 38.55212 -21.771356)
		(end 38.75532 -21.974556)
		(width 0.14224)
		(layer "In11.Cu")
		(net "M_J_DQ<7>")
	)
	(segment
		(start 44.178982 -44.286678)
		(end 44.726352 -43.739308)
		(width 0.14224)
		(layer "In11.Cu")
		(net "M_J_DQ<7>")
	)
	(segment
		(start 38.55212 -11.763248)
		(end 38.55212 -12.170156)
		(width 0.14224)
		(layer "In11.Cu")
		(net "M_J_DQ<7>")
	)
	(segment
		(start 39.083742 -36.09594)
		(end 39.225982 -36.23818)
		(width 0.14224)
		(layer "In11.Cu")
		(net "M_J_DQ<7>")
	)
	(segment
		(start 38.504368 -35.9537)
		(end 38.646608 -36.09594)
		(width 0.14224)
		(layer "In11.Cu")
		(net "M_J_DQ<7>")
	)
	(segment
		(start 38.646608 -37.39642)
		(end 39.083742 -37.39642)
		(width 0.14224)
		(layer "In11.Cu")
		(net "M_J_DQ<7>")
	)
	(segment
		(start 59.503056 -59.31916)
		(end 62.662816 -62.47892)
		(width 0.14224)
		(layer "In11.Cu")
		(net "M_J_DQ<7>")
	)
	(segment
		(start 43.740578 -44.067222)
		(end 43.960034 -44.286678)
		(width 0.14224)
		(layer "In11.Cu")
		(net "M_J_DQ<7>")
	)
	(segment
		(start 39.225982 -34.808414)
		(end 39.225982 -35.30346)
		(width 0.14224)
		(layer "In11.Cu")
		(net "M_J_DQ<7>")
	)
	(segment
		(start 39.083742 -35.4457)
		(end 38.646608 -35.4457)
		(width 0.14224)
		(layer "In11.Cu")
		(net "M_J_DQ<7>")
	)
	(segment
		(start 43.960034 -44.286678)
		(end 44.178982 -44.286678)
		(width 0.14224)
		(layer "In11.Cu")
		(net "M_J_DQ<7>")
	)
	(segment
		(start 62.662816 -62.47892)
		(end 65.474088 -62.47892)
		(width 0.14224)
		(layer "In11.Cu")
		(net "M_J_DQ<7>")
	)
	(segment
		(start 39.225982 -36.60394)
		(end 39.083742 -36.74618)
		(width 0.14224)
		(layer "In11.Cu")
		(net "M_J_DQ<7>")
	)
	(segment
		(start 38.57752 -23.295356)
		(end 38.57752 -26.5684)
		(width 0.14224)
		(layer "In11.Cu")
		(net "M_J_DQ<7>")
	)
	(segment
		(start 75.79995 -63.91529)
		(end 76.621386 -64.010286)
		(width 0.0889)
		(layer "In11.Cu")
		(net "M_J_DQ<7>")
	)
	(segment
		(start 58.8518 -59.31916)
		(end 59.503056 -59.31916)
		(width 0.14224)
		(layer "In11.Cu")
		(net "M_J_DQ<7>")
	)
	(segment
		(start 38.78072 -7.438898)
		(end 38.78072 -8.791194)
		(width 0.14224)
		(layer "In11.Cu")
		(net "M_J_DQ<7>")
	)
	(segment
		(start 38.504368 -34.0868)
		(end 39.225982 -34.808414)
		(width 0.14224)
		(layer "In11.Cu")
		(net "M_J_DQ<7>")
	)
	(segment
		(start 38.199314 -3.076956)
		(end 37.729668 -3.546602)
		(width 0.14224)
		(layer "In11.Cu")
		(net "M_J_DQ<7>")
	)
	(segment
		(start 44.287948 -43.300904)
		(end 43.740578 -43.848274)
		(width 0.14224)
		(layer "In11.Cu")
		(net "M_J_DQ<7>")
	)
	(segment
		(start 72.31761 -63.91529)
		(end 72.350376 -63.91529)
		(width 0.0889)
		(layer "In11.Cu")
		(net "M_J_DQ<7>")
	)
	(segment
		(start 45.164756 -44.177712)
		(end 44.617386 -44.725082)
		(width 0.14224)
		(layer "In11.Cu")
		(net "M_J_DQ<7>")
	)
	(segment
		(start 43.740578 -43.848274)
		(end 43.740578 -44.067222)
		(width 0.14224)
		(layer "In11.Cu")
		(net "M_J_DQ<7>")
	)
	(segment
		(start 39.083742 -37.39642)
		(end 39.225982 -37.53866)
		(width 0.14224)
		(layer "In11.Cu")
		(net "M_J_DQ<7>")
	)
	(segment
		(start 75.741276 -63.91529)
		(end 75.79995 -63.91529)
		(width 0.0889)
		(layer "In11.Cu")
		(net "M_J_DQ<7>")
	)
	(segment
		(start 44.287948 -43.081956)
		(end 44.287948 -43.300904)
		(width 0.14224)
		(layer "In11.Cu")
		(net "M_J_DQ<7>")
	)
	(segment
		(start 39.225982 -36.23818)
		(end 39.225982 -36.60394)
		(width 0.14224)
		(layer "In11.Cu")
		(net "M_J_DQ<7>")
	)
	(segment
		(start 45.164756 -43.958764)
		(end 45.164756 -44.177712)
		(width 0.14224)
		(layer "In11.Cu")
		(net "M_J_DQ<7>")
	)
	(segment
		(start 38.707568 0.7366)
		(end 38.55212 0.581152)
		(width 0.14224)
		(layer "In11.Cu")
		(net "M_J_DQ<7>")
	)
	(segment
		(start 71.45528 -63.419736)
		(end 71.488046 -63.419736)
		(width 0.0889)
		(layer "In11.Cu")
		(net "M_J_DQ<7>")
	)
	(segment
		(start 38.707568 1.0922)
		(end 38.707568 0.7366)
		(width 0.14224)
		(layer "In11.Cu")
		(net "M_J_DQ<7>")
	)
	(segment
		(start 39.225982 -38.01999)
		(end 44.287948 -43.081956)
		(width 0.14224)
		(layer "In11.Cu")
		(net "M_J_DQ<7>")
	)
	(segment
		(start 38.55212 -2.72415)
		(end 38.199314 -3.076956)
		(width 0.14224)
		(layer "In11.Cu")
		(net "M_J_DQ<7>")
	)
	(segment
		(start 38.55212 -9.3726)
		(end 38.732968 -9.553448)
		(width 0.14224)
		(layer "In11.Cu")
		(net "M_J_DQ<7>")
	)
	(segment
		(start 38.646608 -35.4457)
		(end 38.504368 -35.58794)
		(width 0.14224)
		(layer "In11.Cu")
		(net "M_J_DQ<7>")
	)
	(segment
		(start 65.474088 -62.47892)
		(end 65.919858 -62.92469)
		(width 0.0889)
		(layer "In11.Cu")
		(net "M_J_DQ<7>")
	)
	(segment
		(start 37.666168 1.8796)
		(end 37.996368 1.5494)
		(width 0.14224)
		(layer "In11.Cu")
		(net "M_J_DQ<7>")
	)
	(segment
		(start 37.666168 2.198116)
		(end 37.666168 1.8796)
		(width 0.14224)
		(layer "In11.Cu")
		(net "M_J_DQ<7>")
	)
	(segment
		(start 38.55212 0.581152)
		(end 38.55212 -2.72415)
		(width 0.14224)
		(layer "In11.Cu")
		(net "M_J_DQ<7>")
	)
	(segment
		(start 38.504368 -27.52344)
		(end 38.504368 -34.0868)
		(width 0.14224)
		(layer "In11.Cu")
		(net "M_J_DQ<7>")
	)
	(segment
		(start 44.836842 -45.163486)
		(end 45.05579 -45.163486)
		(width 0.14224)
		(layer "In11.Cu")
		(net "M_J_DQ<7>")
	)
	(segment
		(start 38.57752 -13.694156)
		(end 38.57752 -16.890746)
		(width 0.14224)
		(layer "In11.Cu")
		(net "M_J_DQ<7>")
	)
	(segment
		(start 38.75532 -23.117556)
		(end 38.57752 -23.295356)
		(width 0.14224)
		(layer "In11.Cu")
		(net "M_J_DQ<7>")
	)
	(segment
		(start 38.732968 -9.553448)
		(end 38.732968 -11.5824)
		(width 0.14224)
		(layer "In11.Cu")
		(net "M_J_DQ<7>")
	)
	(segment
		(start 46.17085 -46.63821)
		(end 58.8518 -59.31916)
		(width 0.14224)
		(layer "In11.Cu")
		(net "M_J_DQ<7>")
	)
	(segment
		(start 38.732968 -11.5824)
		(end 38.55212 -11.763248)
		(width 0.14224)
		(layer "In11.Cu")
		(net "M_J_DQ<7>")
	)
	(segment
		(start 70.60057 -62.92469)
		(end 70.633336 -62.92469)
		(width 0.0889)
		(layer "In11.Cu")
		(net "M_J_DQ<7>")
	)
	(segment
		(start 37.19449 -27.3812)
		(end 38.362128 -27.3812)
		(width 0.14224)
		(layer "In11.Cu")
		(net "M_J_DQ<7>")
	)
	(segment
		(start 38.75532 -21.974556)
		(end 38.75532 -23.117556)
		(width 0.14224)
		(layer "In11.Cu")
		(net "M_J_DQ<7>")
	)
	(segment
		(start 38.57752 -16.890746)
		(end 38.78072 -17.093946)
		(width 0.14224)
		(layer "In11.Cu")
		(net "M_J_DQ<7>")
	)
	(segment
		(start 38.362128 -27.3812)
		(end 38.504368 -27.52344)
		(width 0.14224)
		(layer "In11.Cu")
		(net "M_J_DQ<7>")
	)
	(segment
		(start 38.646608 -36.09594)
		(end 39.083742 -36.09594)
		(width 0.14224)
		(layer "In11.Cu")
		(net "M_J_DQ<7>")
	)
	(segment
		(start 36.980368 -26.8986)
		(end 36.980368 -27.167078)
		(width 0.14224)
		(layer "In11.Cu")
		(net "M_J_DQ<7>")
	)
	(segment
		(start 37.34943 2.514854)
		(end 37.666168 2.198116)
		(width 0.14224)
		(layer "In11.Cu")
		(net "M_J_DQ<7>")
	)
	(segment
		(start 38.250368 1.5494)
		(end 38.707568 1.0922)
		(width 0.14224)
		(layer "In11.Cu")
		(net "M_J_DQ<7>")
	)
	(segment
		(start 38.55212 -12.170156)
		(end 38.75532 -12.373356)
		(width 0.14224)
		(layer "In11.Cu")
		(net "M_J_DQ<7>")
	)
	(segment
		(start 38.580568 -7.238746)
		(end 38.78072 -7.438898)
		(width 0.14224)
		(layer "In11.Cu")
		(net "M_J_DQ<7>")
	)
	(segment
		(start 38.580568 -4.826)
		(end 38.580568 -7.238746)
		(width 0.14224)
		(layer "In11.Cu")
		(net "M_J_DQ<7>")
	)
	(segment
		(start 38.57752 -26.5684)
		(end 38.45052 -26.6954)
		(width 0.14224)
		(layer "In11.Cu")
		(net "M_J_DQ<7>")
	)
	(segment
		(start 38.504368 -36.88842)
		(end 38.504368 -37.25418)
		(width 0.14224)
		(layer "In11.Cu")
		(net "M_J_DQ<7>")
	)
	(segment
		(start 37.183568 -26.6954)
		(end 36.980368 -26.8986)
		(width 0.14224)
		(layer "In11.Cu")
		(net "M_J_DQ<7>")
	)
	(segment
		(start 38.646608 -36.74618)
		(end 38.504368 -36.88842)
		(width 0.14224)
		(layer "In11.Cu")
		(net "M_J_DQ<7>")
	)
	(segment
		(start 73.17232 -64.410336)
		(end 73.205086 -64.410336)
		(width 0.0889)
		(layer "In11.Cu")
		(net "M_J_DQ<7>")
	)
	(segment
		(start 38.55212 -21.3106)
		(end 38.55212 -21.771356)
		(width 0.14224)
		(layer "In11.Cu")
		(net "M_J_DQ<7>")
	)
	(segment
		(start 38.78072 -18.341594)
		(end 38.55212 -18.570194)
		(width 0.14224)
		(layer "In11.Cu")
		(net "M_J_DQ<7>")
	)
	(segment
		(start 38.78072 -17.093946)
		(end 38.78072 -18.341594)
		(width 0.14224)
		(layer "In11.Cu")
		(net "M_J_DQ<7>")
	)
	(segment
		(start 46.17085 -44.964858)
		(end 46.17085 -46.63821)
		(width 0.14224)
		(layer "In11.Cu")
		(net "M_J_DQ<7>")
	)
	(segment
		(start 38.682168 -21.180552)
		(end 38.55212 -21.3106)
		(width 0.14224)
		(layer "In11.Cu")
		(net "M_J_DQ<7>")
	)
	(segment
		(start 37.729668 -3.9751)
		(end 38.580568 -4.826)
		(width 0.14224)
		(layer "In11.Cu")
		(net "M_J_DQ<7>")
	)
	(segment
		(start 68.018406 -62.429136)
		(end 68.053966 -62.429136)
		(width 0.0889)
		(layer "In11.Cu")
		(net "M_J_DQ<7>")
	)
	(segment
		(start 38.55212 -18.570194)
		(end 38.55212 -18.996152)
		(width 0.14224)
		(layer "In11.Cu")
		(net "M_J_DQ<7>")
	)
	(segment
		(start 38.78072 -8.791194)
		(end 38.55212 -9.019794)
		(width 0.14224)
		(layer "In11.Cu")
		(net "M_J_DQ<7>")
	)
	(segment
		(start 38.55212 -18.996152)
		(end 38.682168 -19.1262)
		(width 0.14224)
		(layer "In11.Cu")
		(net "M_J_DQ<7>")
	)
	(segment
		(start 45.822108 -44.616116)
		(end 46.17085 -44.964858)
		(width 0.14224)
		(layer "In11.Cu")
		(net "M_J_DQ<7>")
	)
	(segment
		(start 39.225982 -35.30346)
		(end 39.083742 -35.4457)
		(width 0.14224)
		(layer "In11.Cu")
		(net "M_J_DQ<7>")
	)
	(segment
		(start 38.55212 -9.019794)
		(end 38.55212 -9.3726)
		(width 0.14224)
		(layer "In11.Cu")
		(net "M_J_DQ<7>")
	)
	(segment
		(start 39.225982 -37.53866)
		(end 39.225982 -38.01999)
		(width 0.14224)
		(layer "In11.Cu")
		(net "M_J_DQ<7>")
	)
	(segment
		(start 38.75532 -13.516356)
		(end 38.57752 -13.694156)
		(width 0.14224)
		(layer "In11.Cu")
		(net "M_J_DQ<7>")
	)
	(segment
		(start 45.60316 -44.616116)
		(end 45.822108 -44.616116)
		(width 0.14224)
		(layer "In11.Cu")
		(net "M_J_DQ<7>")
	)
	(segment
		(start 65.919858 -62.92469)
		(end 67.188842 -62.92469)
		(width 0.0889)
		(layer "In11.Cu")
		(net "M_J_DQ<7>")
	)
	(segment
		(start 37.996368 1.5494)
		(end 38.250368 1.5494)
		(width 0.14224)
		(layer "In11.Cu")
		(net "M_J_DQ<7>")
	)
	(segment
		(start 36.980368 -27.167078)
		(end 37.19449 -27.3812)
		(width 0.14224)
		(layer "In11.Cu")
		(net "M_J_DQ<7>")
	)
	(segment
		(start 39.083742 -36.74618)
		(end 38.646608 -36.74618)
		(width 0.14224)
		(layer "In11.Cu")
		(net "M_J_DQ<7>")
	)
	(segment
		(start 44.617386 -44.94403)
		(end 44.836842 -45.163486)
		(width 0.14224)
		(layer "In11.Cu")
		(net "M_J_DQ<7>")
	)
	(segment
		(start 38.75532 -12.373356)
		(end 38.75532 -13.516356)
		(width 0.14224)
		(layer "In11.Cu")
		(net "M_J_DQ<7>")
	)
	(segment
		(start 44.9453 -43.739308)
		(end 45.164756 -43.958764)
		(width 0.14224)
		(layer "In11.Cu")
		(net "M_J_DQ<7>")
	)
	(arc
		(start 69.241416 -62.724538)
		(mid 69.450024 -62.512606)
		(end 69.735446 -62.429136)
		(width 0.0889)
		(layer "In11.Cu")
		(net "M_J_DQ<7>")
	)
	(arc
		(start 73.699116 -64.705738)
		(mid 74.045826 -64.906049)
		(end 74.392536 -64.705738)
		(width 0.0889)
		(layer "In11.Cu")
		(net "M_J_DQ<7>")
	)
	(arc
		(start 71.488046 -63.419736)
		(mid 71.77347 -63.503203)
		(end 71.982076 -63.715138)
		(width 0.0889)
		(layer "In11.Cu")
		(net "M_J_DQ<7>")
	)
	(arc
		(start 71.123556 -63.219838)
		(mid 71.263635 -63.362574)
		(end 71.45528 -63.419736)
		(width 0.0889)
		(layer "In11.Cu")
		(net "M_J_DQ<7>")
	)
	(arc
		(start 70.633336 -62.92469)
		(mid 70.916553 -63.008971)
		(end 71.123556 -63.219838)
		(width 0.0889)
		(layer "In11.Cu")
		(net "M_J_DQ<7>")
	)
	(arc
		(start 75.251056 -64.210438)
		(mid 75.45806 -63.999574)
		(end 75.741276 -63.91529)
		(width 0.0889)
		(layer "In11.Cu")
		(net "M_J_DQ<7>")
	)
	(arc
		(start 72.350376 -63.91529)
		(mid 72.633593 -63.999571)
		(end 72.840596 -64.210438)
		(width 0.0889)
		(layer "In11.Cu")
		(net "M_J_DQ<7>")
	)
	(arc
		(start 72.840596 -64.210438)
		(mid 72.980675 -64.353174)
		(end 73.17232 -64.410336)
		(width 0.0889)
		(layer "In11.Cu")
		(net "M_J_DQ<7>")
	)
	(arc
		(start 68.547996 -62.724538)
		(mid 68.894706 -62.924849)
		(end 69.241416 -62.724538)
		(width 0.0889)
		(layer "In11.Cu")
		(net "M_J_DQ<7>")
	)
	(arc
		(start 70.265036 -62.724538)
		(mid 70.406719 -62.868342)
		(end 70.60057 -62.92469)
		(width 0.0889)
		(layer "In11.Cu")
		(net "M_J_DQ<7>")
	)
	(arc
		(start 67.524376 -62.724538)
		(mid 67.732984 -62.512606)
		(end 68.018406 -62.429136)
		(width 0.0889)
		(layer "In11.Cu")
		(net "M_J_DQ<7>")
	)
	(arc
		(start 71.982076 -63.715138)
		(mid 72.123759 -63.858942)
		(end 72.31761 -63.91529)
		(width 0.0889)
		(layer "In11.Cu")
		(net "M_J_DQ<7>")
	)
	(arc
		(start 69.771006 -62.429136)
		(mid 70.05643 -62.512603)
		(end 70.265036 -62.724538)
		(width 0.0889)
		(layer "In11.Cu")
		(net "M_J_DQ<7>")
	)
	(arc
		(start 74.392536 -64.705738)
		(mid 74.601144 -64.493806)
		(end 74.886566 -64.410336)
		(width 0.0889)
		(layer "In11.Cu")
		(net "M_J_DQ<7>")
	)
	(arc
		(start 74.919332 -64.410336)
		(mid 75.110974 -64.35317)
		(end 75.251056 -64.210438)
		(width 0.0889)
		(layer "In11.Cu")
		(net "M_J_DQ<7>")
	)
	(arc
		(start 68.053966 -62.429136)
		(mid 68.33939 -62.512603)
		(end 68.547996 -62.724538)
		(width 0.0889)
		(layer "In11.Cu")
		(net "M_J_DQ<7>")
	)
	(arc
		(start 67.188842 -62.92469)
		(mid 67.382692 -62.86834)
		(end 67.524376 -62.724538)
		(width 0.0889)
		(layer "In11.Cu")
		(net "M_J_DQ<7>")
	)
	(arc
		(start 73.205086 -64.410336)
		(mid 73.49051 -64.493803)
		(end 73.699116 -64.705738)
		(width 0.0889)
		(layer "In11.Cu")
		(net "M_J_DQ<7>")
	)
	(segment
		(start 38.331648 0.28448)
		(end 38.331648 0.50292)
		(width 0.1651)
		(layer "F.Cu")
		(net "M_J_DQ<6>")
	)
	(segment
		(start 38.199568 0.1524)
		(end 38.331648 0.28448)
		(width 0.1651)
		(layer "F.Cu")
		(net "M_J_DQ<6>")
	)
	(segment
		(start 38.199568 0.939546)
		(end 38.199314 0.9398)
		(width 0.1651)
		(layer "F.Cu")
		(net "M_J_DQ<6>")
	)
	(segment
		(start 38.331648 0.50292)
		(end 38.199568 0.635)
		(width 0.1651)
		(layer "F.Cu")
		(net "M_J_DQ<6>")
	)
	(segment
		(start 38.199568 -0.821182)
		(end 38.199568 0.1524)
		(width 0.1651)
		(layer "F.Cu")
		(net "M_J_DQ<6>")
	)
	(segment
		(start 75.475846 -65.000886)
		(end 74.904346 -65.000886)
		(width 0.0889)
		(layer "F.Cu")
		(net "M_J_DQ<6>")
	)
	(segment
		(start 38.199568 0.635)
		(end 38.199568 0.939546)
		(width 0.1651)
		(layer "F.Cu")
		(net "M_J_DQ<6>")
	)
	(via
		(at 74.904346 -65.000886)
		(size 0.508)
		(drill 0.254)
		(layers "F.Cu" "B.Cu")
		(net "M_J_DQ<6>")
	)
	(via
		(at 37.34943 -4.357878)
		(size 0.508)
		(drill 0.254)
		(layers "F.Cu" "B.Cu")
		(net "M_J_DQ<6>")
	)
	(via
		(at 38.199314 0.9398)
		(size 0.508)
		(drill 0.254)
		(layers "F.Cu" "B.Cu")
		(net "M_J_DQ<6>")
	)
	(segment
		(start 37.34943 -5.621782)
		(end 37.34943 -4.357878)
		(width 0.1651)
		(layer "B.Cu")
		(net "M_J_DQ<6>")
	)
	(segment
		(start 41.19118 -42.632884)
		(end 41.410636 -42.85234)
		(width 0.14224)
		(layer "In11.Cu")
		(net "M_J_DQ<6>")
	)
	(segment
		(start 37.841936 -0.768096)
		(end 37.841936 -1.111504)
		(width 0.14224)
		(layer "In11.Cu")
		(net "M_J_DQ<6>")
	)
	(segment
		(start 37.71392 -21.974556)
		(end 37.71392 -23.168356)
		(width 0.14224)
		(layer "In11.Cu")
		(net "M_J_DQ<6>")
	)
	(segment
		(start 58.743596 -60.1091)
		(end 59.224672 -60.1091)
		(width 0.14224)
		(layer "In11.Cu")
		(net "M_J_DQ<6>")
	)
	(segment
		(start 37.81552 -25.098248)
		(end 36.345368 -26.5684)
		(width 0.14224)
		(layer "In11.Cu")
		(net "M_J_DQ<6>")
	)
	(segment
		(start 37.460936 -1.492504)
		(end 37.460936 -1.777746)
		(width 0.14224)
		(layer "In11.Cu")
		(net "M_J_DQ<6>")
	)
	(segment
		(start 37.460936 -0.076454)
		(end 37.460936 -0.387096)
		(width 0.14224)
		(layer "In11.Cu")
		(net "M_J_DQ<6>")
	)
	(segment
		(start 37.91712 -18.976848)
		(end 37.716968 -19.177)
		(width 0.14224)
		(layer "In11.Cu")
		(net "M_J_DQ<6>")
	)
	(segment
		(start 72.311006 -64.10579)
		(end 72.343772 -64.10579)
		(width 0.0889)
		(layer "In11.Cu")
		(net "M_J_DQ<6>")
	)
	(segment
		(start 37.460936 -0.387096)
		(end 37.841936 -0.768096)
		(width 0.14224)
		(layer "In11.Cu")
		(net "M_J_DQ<6>")
	)
	(segment
		(start 37.91712 -11.7602)
		(end 37.91712 -12.170156)
		(width 0.14224)
		(layer "In11.Cu")
		(net "M_J_DQ<6>")
	)
	(segment
		(start 65.660524 -63.11519)
		(end 67.195446 -63.11519)
		(width 0.0889)
		(layer "In11.Cu")
		(net "M_J_DQ<6>")
	)
	(segment
		(start 37.91712 -21.3614)
		(end 37.91712 -21.771356)
		(width 0.14224)
		(layer "In11.Cu")
		(net "M_J_DQ<6>")
	)
	(segment
		(start 41.629584 -42.85234)
		(end 42.246804 -42.23512)
		(width 0.14224)
		(layer "In11.Cu")
		(net "M_J_DQ<6>")
	)
	(segment
		(start 42.919142 -42.68851)
		(end 42.919142 -44.284646)
		(width 0.14224)
		(layer "In11.Cu")
		(net "M_J_DQ<6>")
	)
	(segment
		(start 37.91712 -18.665698)
		(end 37.91712 -18.976848)
		(width 0.14224)
		(layer "In11.Cu")
		(net "M_J_DQ<6>")
	)
	(segment
		(start 42.465752 -42.23512)
		(end 42.919142 -42.68851)
		(width 0.14224)
		(layer "In11.Cu")
		(net "M_J_DQ<6>")
	)
	(segment
		(start 71.448676 -63.610236)
		(end 71.481442 -63.610236)
		(width 0.0889)
		(layer "In11.Cu")
		(net "M_J_DQ<6>")
	)
	(segment
		(start 41.19118 -42.413936)
		(end 41.19118 -42.632884)
		(width 0.14224)
		(layer "In11.Cu")
		(net "M_J_DQ<6>")
	)
	(segment
		(start 36.954968 -31.7754)
		(end 37.158168 -31.5722)
		(width 0.14224)
		(layer "In11.Cu")
		(net "M_J_DQ<6>")
	)
	(segment
		(start 42.246804 -42.23512)
		(end 42.465752 -42.23512)
		(width 0.14224)
		(layer "In11.Cu")
		(net "M_J_DQ<6>")
	)
	(segment
		(start 37.71392 -7.343394)
		(end 37.71392 -8.912098)
		(width 0.14224)
		(layer "In11.Cu")
		(net "M_J_DQ<6>")
	)
	(segment
		(start 59.224672 -60.1091)
		(end 62.230762 -63.11519)
		(width 0.14224)
		(layer "In11.Cu")
		(net "M_J_DQ<6>")
	)
	(segment
		(start 37.113718 -3.327654)
		(end 37.113718 -4.122166)
		(width 0.14224)
		(layer "In11.Cu")
		(net "M_J_DQ<6>")
	)
	(segment
		(start 37.71392 -8.912098)
		(end 37.91712 -9.115298)
		(width 0.14224)
		(layer "In11.Cu")
		(net "M_J_DQ<6>")
	)
	(segment
		(start 37.970968 -28.3972)
		(end 37.970968 -37.740336)
		(width 0.14224)
		(layer "In11.Cu")
		(net "M_J_DQ<6>")
	)
	(segment
		(start 68.876926 -63.11519)
		(end 68.912486 -63.11519)
		(width 0.0889)
		(layer "In11.Cu")
		(net "M_J_DQ<6>")
	)
	(segment
		(start 37.886386 -2.203196)
		(end 37.886386 -2.554986)
		(width 0.14224)
		(layer "In11.Cu")
		(net "M_J_DQ<6>")
	)
	(segment
		(start 37.767768 -9.5504)
		(end 37.767768 -11.610848)
		(width 0.14224)
		(layer "In11.Cu")
		(net "M_J_DQ<6>")
	)
	(segment
		(start 70.593966 -63.11519)
		(end 70.626732 -63.11519)
		(width 0.0889)
		(layer "In11.Cu")
		(net "M_J_DQ<6>")
	)
	(segment
		(start 37.81552 -16.890746)
		(end 37.71392 -16.992346)
		(width 0.14224)
		(layer "In11.Cu")
		(net "M_J_DQ<6>")
	)
	(segment
		(start 37.716968 -21.161248)
		(end 37.91712 -21.3614)
		(width 0.14224)
		(layer "In11.Cu")
		(net "M_J_DQ<6>")
	)
	(segment
		(start 37.158168 -28.4226)
		(end 37.386768 -28.194)
		(width 0.14224)
		(layer "In11.Cu")
		(net "M_J_DQ<6>")
	)
	(segment
		(start 37.86632 -7.190994)
		(end 37.71392 -7.343394)
		(width 0.14224)
		(layer "In11.Cu")
		(net "M_J_DQ<6>")
	)
	(segment
		(start 37.91712 -9.115298)
		(end 37.91712 -9.401048)
		(width 0.14224)
		(layer "In11.Cu")
		(net "M_J_DQ<6>")
	)
	(segment
		(start 37.71392 -12.373356)
		(end 37.71392 -13.567156)
		(width 0.14224)
		(layer "In11.Cu")
		(net "M_J_DQ<6>")
	)
	(segment
		(start 37.460936 -1.777746)
		(end 37.886386 -2.203196)
		(width 0.14224)
		(layer "In11.Cu")
		(net "M_J_DQ<6>")
	)
	(segment
		(start 38.199314 0.9398)
		(end 37.824918 0.565404)
		(width 0.14224)
		(layer "In11.Cu")
		(net "M_J_DQ<6>")
	)
	(segment
		(start 37.386768 -28.194)
		(end 37.767768 -28.194)
		(width 0.14224)
		(layer "In11.Cu")
		(net "M_J_DQ<6>")
	)
	(segment
		(start 37.71392 -13.567156)
		(end 37.81552 -13.668756)
		(width 0.14224)
		(layer "In11.Cu")
		(net "M_J_DQ<6>")
	)
	(segment
		(start 37.158168 -31.5722)
		(end 37.158168 -28.4226)
		(width 0.14224)
		(layer "In11.Cu")
		(net "M_J_DQ<6>")
	)
	(segment
		(start 37.71392 -23.168356)
		(end 37.81552 -23.269956)
		(width 0.14224)
		(layer "In11.Cu")
		(net "M_J_DQ<6>")
	)
	(segment
		(start 62.230762 -63.11519)
		(end 65.660524 -63.11519)
		(width 0.14224)
		(layer "In11.Cu")
		(net "M_J_DQ<6>")
	)
	(segment
		(start 37.71392 -18.462498)
		(end 37.91712 -18.665698)
		(width 0.14224)
		(layer "In11.Cu")
		(net "M_J_DQ<6>")
	)
	(segment
		(start 37.91712 -9.401048)
		(end 37.767768 -9.5504)
		(width 0.14224)
		(layer "In11.Cu")
		(net "M_J_DQ<6>")
	)
	(segment
		(start 37.34943 -4.357878)
		(end 37.86632 -4.874768)
		(width 0.14224)
		(layer "In11.Cu")
		(net "M_J_DQ<6>")
	)
	(segment
		(start 37.81552 -23.269956)
		(end 37.81552 -25.098248)
		(width 0.14224)
		(layer "In11.Cu")
		(net "M_J_DQ<6>")
	)
	(segment
		(start 42.919142 -44.284646)
		(end 58.743596 -60.1091)
		(width 0.14224)
		(layer "In11.Cu")
		(net "M_J_DQ<6>")
	)
	(segment
		(start 41.8084 -41.577768)
		(end 41.8084 -41.796716)
		(width 0.14224)
		(layer "In11.Cu")
		(net "M_J_DQ<6>")
	)
	(segment
		(start 37.886386 -2.554986)
		(end 37.113718 -3.327654)
		(width 0.14224)
		(layer "In11.Cu")
		(net "M_J_DQ<6>")
	)
	(segment
		(start 37.970968 -37.740336)
		(end 41.8084 -41.577768)
		(width 0.14224)
		(layer "In11.Cu")
		(net "M_J_DQ<6>")
	)
	(segment
		(start 73.165716 -64.600836)
		(end 73.198482 -64.600836)
		(width 0.0889)
		(layer "In11.Cu")
		(net "M_J_DQ<6>")
	)
	(segment
		(start 37.716968 -19.177)
		(end 37.716968 -21.161248)
		(width 0.14224)
		(layer "In11.Cu")
		(net "M_J_DQ<6>")
	)
	(segment
		(start 37.824918 0.565404)
		(end 37.824918 0.287528)
		(width 0.14224)
		(layer "In11.Cu")
		(net "M_J_DQ<6>")
	)
	(segment
		(start 37.71392 -16.992346)
		(end 37.71392 -18.462498)
		(width 0.14224)
		(layer "In11.Cu")
		(net "M_J_DQ<6>")
	)
	(segment
		(start 37.767768 -28.194)
		(end 37.970968 -28.3972)
		(width 0.14224)
		(layer "In11.Cu")
		(net "M_J_DQ<6>")
	)
	(segment
		(start 37.824918 0.287528)
		(end 37.460936 -0.076454)
		(width 0.14224)
		(layer "In11.Cu")
		(net "M_J_DQ<6>")
	)
	(segment
		(start 74.028046 -65.09639)
		(end 74.081894 -65.09639)
		(width 0.0889)
		(layer "In11.Cu")
		(net "M_J_DQ<6>")
	)
	(segment
		(start 37.113718 -4.122166)
		(end 37.34943 -4.357878)
		(width 0.14224)
		(layer "In11.Cu")
		(net "M_J_DQ<6>")
	)
	(segment
		(start 37.91712 -21.771356)
		(end 37.71392 -21.974556)
		(width 0.14224)
		(layer "In11.Cu")
		(net "M_J_DQ<6>")
	)
	(segment
		(start 36.548568 -31.7754)
		(end 36.954968 -31.7754)
		(width 0.14224)
		(layer "In11.Cu")
		(net "M_J_DQ<6>")
	)
	(segment
		(start 41.8084 -41.796716)
		(end 41.19118 -42.413936)
		(width 0.14224)
		(layer "In11.Cu")
		(net "M_J_DQ<6>")
	)
	(segment
		(start 37.841936 -1.111504)
		(end 37.460936 -1.492504)
		(width 0.14224)
		(layer "In11.Cu")
		(net "M_J_DQ<6>")
	)
	(segment
		(start 36.345368 -26.5684)
		(end 36.345368 -31.5722)
		(width 0.14224)
		(layer "In11.Cu")
		(net "M_J_DQ<6>")
	)
	(segment
		(start 37.86632 -4.874768)
		(end 37.86632 -7.190994)
		(width 0.14224)
		(layer "In11.Cu")
		(net "M_J_DQ<6>")
	)
	(segment
		(start 37.767768 -11.610848)
		(end 37.91712 -11.7602)
		(width 0.14224)
		(layer "In11.Cu")
		(net "M_J_DQ<6>")
	)
	(segment
		(start 37.91712 -12.170156)
		(end 37.71392 -12.373356)
		(width 0.14224)
		(layer "In11.Cu")
		(net "M_J_DQ<6>")
	)
	(segment
		(start 37.81552 -13.668756)
		(end 37.81552 -16.890746)
		(width 0.14224)
		(layer "In11.Cu")
		(net "M_J_DQ<6>")
	)
	(segment
		(start 74.081894 -65.09639)
		(end 74.904346 -65.000886)
		(width 0.0889)
		(layer "In11.Cu")
		(net "M_J_DQ<6>")
	)
	(segment
		(start 41.410636 -42.85234)
		(end 41.629584 -42.85234)
		(width 0.14224)
		(layer "In11.Cu")
		(net "M_J_DQ<6>")
	)
	(segment
		(start 36.345368 -31.5722)
		(end 36.548568 -31.7754)
		(width 0.14224)
		(layer "In11.Cu")
		(net "M_J_DQ<6>")
	)
	(arc
		(start 69.406516 -62.819788)
		(mid 69.753226 -62.619477)
		(end 70.099936 -62.819788)
		(width 0.0889)
		(layer "In11.Cu")
		(net "M_J_DQ<6>")
	)
	(arc
		(start 67.689476 -62.819788)
		(mid 68.036186 -62.619477)
		(end 68.382896 -62.819788)
		(width 0.0889)
		(layer "In11.Cu")
		(net "M_J_DQ<6>")
	)
	(arc
		(start 73.534016 -64.800988)
		(mid 73.742624 -65.01292)
		(end 74.028046 -65.09639)
		(width 0.0889)
		(layer "In11.Cu")
		(net "M_J_DQ<6>")
	)
	(arc
		(start 68.382896 -62.819788)
		(mid 68.591504 -63.03172)
		(end 68.876926 -63.11519)
		(width 0.0889)
		(layer "In11.Cu")
		(net "M_J_DQ<6>")
	)
	(arc
		(start 72.343772 -64.10579)
		(mid 72.535414 -64.162956)
		(end 72.675496 -64.305688)
		(width 0.0889)
		(layer "In11.Cu")
		(net "M_J_DQ<6>")
	)
	(arc
		(start 73.198482 -64.600836)
		(mid 73.392332 -64.657186)
		(end 73.534016 -64.800988)
		(width 0.0889)
		(layer "In11.Cu")
		(net "M_J_DQ<6>")
	)
	(arc
		(start 71.481442 -63.610236)
		(mid 71.675292 -63.666586)
		(end 71.816976 -63.810388)
		(width 0.0889)
		(layer "In11.Cu")
		(net "M_J_DQ<6>")
	)
	(arc
		(start 67.195446 -63.11519)
		(mid 67.48087 -63.031723)
		(end 67.689476 -62.819788)
		(width 0.0889)
		(layer "In11.Cu")
		(net "M_J_DQ<6>")
	)
	(arc
		(start 70.626732 -63.11519)
		(mid 70.818374 -63.172356)
		(end 70.958456 -63.315088)
		(width 0.0889)
		(layer "In11.Cu")
		(net "M_J_DQ<6>")
	)
	(arc
		(start 68.912486 -63.11519)
		(mid 69.19791 -63.031723)
		(end 69.406516 -62.819788)
		(width 0.0889)
		(layer "In11.Cu")
		(net "M_J_DQ<6>")
	)
	(arc
		(start 72.675496 -64.305688)
		(mid 72.8825 -64.516552)
		(end 73.165716 -64.600836)
		(width 0.0889)
		(layer "In11.Cu")
		(net "M_J_DQ<6>")
	)
	(arc
		(start 70.099936 -62.819788)
		(mid 70.308544 -63.03172)
		(end 70.593966 -63.11519)
		(width 0.0889)
		(layer "In11.Cu")
		(net "M_J_DQ<6>")
	)
	(arc
		(start 70.958456 -63.315088)
		(mid 71.16546 -63.525952)
		(end 71.448676 -63.610236)
		(width 0.0889)
		(layer "In11.Cu")
		(net "M_J_DQ<6>")
	)
	(arc
		(start 71.816976 -63.810388)
		(mid 72.025584 -64.02232)
		(end 72.311006 -64.10579)
		(width 0.0889)
		(layer "In11.Cu")
		(net "M_J_DQ<6>")
	)
	(segment
		(start 123.363228 -64.819784)
		(end 122.791728 -64.819784)
		(width 0.0889)
		(layer "F.Cu")
		(net "M_J_DQ<63>")
	)
	(segment
		(start 148.699474 3.778758)
		(end 148.699474 2.514854)
		(width 0.1651)
		(layer "F.Cu")
		(net "M_J_DQ<63>")
	)
	(via
		(at 149.549358 -3.076956)
		(size 0.508)
		(drill 0.254)
		(layers "F.Cu" "B.Cu")
		(net "M_J_DQ<63>")
	)
	(via
		(at 122.791728 -64.819784)
		(size 0.508)
		(drill 0.254)
		(layers "F.Cu" "B.Cu")
		(net "M_J_DQ<63>")
	)
	(via
		(at 148.699474 2.514854)
		(size 0.508)
		(drill 0.254)
		(layers "F.Cu" "B.Cu")
		(net "M_J_DQ<63>")
	)
	(segment
		(start 149.549358 -1.021842)
		(end 149.549358 -3.076956)
		(width 0.1651)
		(layer "B.Cu")
		(net "M_J_DQ<63>")
	)
	(segment
		(start 150.081742 -23.183596)
		(end 150.081742 -21.999956)
		(width 0.14224)
		(layer "In11.Cu")
		(net "M_J_DQ<63>")
	)
	(segment
		(start 149.929342 -23.793196)
		(end 149.929342 -23.335996)
		(width 0.14224)
		(layer "In11.Cu")
		(net "M_J_DQ<63>")
	)
	(segment
		(start 149.929342 -23.335996)
		(end 150.081742 -23.183596)
		(width 0.14224)
		(layer "In11.Cu")
		(net "M_J_DQ<63>")
	)
	(segment
		(start 150.056342 -17.030446)
		(end 149.916642 -16.890746)
		(width 0.14224)
		(layer "In11.Cu")
		(net "M_J_DQ<63>")
	)
	(segment
		(start 149.902164 -2.72415)
		(end 149.902164 0.581152)
		(width 0.14224)
		(layer "In11.Cu")
		(net "M_J_DQ<63>")
	)
	(segment
		(start 149.903942 -19.017996)
		(end 149.903942 -18.574258)
		(width 0.14224)
		(layer "In11.Cu")
		(net "M_J_DQ<63>")
	)
	(segment
		(start 123.309888 -60.572904)
		(end 123.303538 -60.562236)
		(width 0.0889)
		(layer "In11.Cu")
		(net "M_J_DQ<63>")
	)
	(segment
		(start 129.867914 -49.6824)
		(end 135.964168 -43.586146)
		(width 0.14224)
		(layer "In11.Cu")
		(net "M_J_DQ<63>")
	)
	(segment
		(start 150.111968 -23.975822)
		(end 149.929342 -23.793196)
		(width 0.14224)
		(layer "In11.Cu")
		(net "M_J_DQ<63>")
	)
	(segment
		(start 123.303538 -57.590436)
		(end 123.298712 -57.5818)
		(width 0.0889)
		(layer "In11.Cu")
		(net "M_J_DQ<63>")
	)
	(segment
		(start 123.303538 -55.609236)
		(end 123.298712 -55.6006)
		(width 0.0889)
		(layer "In11.Cu")
		(net "M_J_DQ<63>")
	)
	(segment
		(start 149.016212 2.198116)
		(end 148.699474 2.514854)
		(width 0.14224)
		(layer "In11.Cu")
		(net "M_J_DQ<63>")
	)
	(segment
		(start 122.791728 -64.819784)
		(end 123.138438 -64.029336)
		(width 0.0889)
		(layer "In11.Cu")
		(net "M_J_DQ<63>")
	)
	(segment
		(start 136.929368 -43.586146)
		(end 150.111968 -30.403546)
		(width 0.14224)
		(layer "In11.Cu")
		(net "M_J_DQ<63>")
	)
	(segment
		(start 123.303538 -60.562236)
		(end 123.298712 -60.5536)
		(width 0.0889)
		(layer "In11.Cu")
		(net "M_J_DQ<63>")
	)
	(segment
		(start 149.916642 -13.681456)
		(end 150.081742 -13.516356)
		(width 0.14224)
		(layer "In11.Cu")
		(net "M_J_DQ<63>")
	)
	(segment
		(start 150.057612 0.7366)
		(end 150.057612 1.0922)
		(width 0.14224)
		(layer "In11.Cu")
		(net "M_J_DQ<63>")
	)
	(segment
		(start 149.903942 -11.741404)
		(end 150.113746 -11.5316)
		(width 0.14224)
		(layer "In11.Cu")
		(net "M_J_DQ<63>")
	)
	(segment
		(start 149.903942 -8.947658)
		(end 150.056342 -8.795258)
		(width 0.14224)
		(layer "In11.Cu")
		(net "M_J_DQ<63>")
	)
	(segment
		(start 150.111968 -30.403546)
		(end 150.111968 -23.975822)
		(width 0.14224)
		(layer "In11.Cu")
		(net "M_J_DQ<63>")
	)
	(segment
		(start 149.016212 1.8796)
		(end 149.016212 2.198116)
		(width 0.14224)
		(layer "In11.Cu")
		(net "M_J_DQ<63>")
	)
	(segment
		(start 149.916642 -7.289546)
		(end 149.916642 -4.816856)
		(width 0.14224)
		(layer "In11.Cu")
		(net "M_J_DQ<63>")
	)
	(segment
		(start 149.903942 -21.822156)
		(end 149.903942 -21.3614)
		(width 0.14224)
		(layer "In11.Cu")
		(net "M_J_DQ<63>")
	)
	(segment
		(start 149.916642 -4.816856)
		(end 149.065742 -3.965956)
		(width 0.14224)
		(layer "In11.Cu")
		(net "M_J_DQ<63>")
	)
	(segment
		(start 150.056342 -7.429246)
		(end 149.916642 -7.289546)
		(width 0.14224)
		(layer "In11.Cu")
		(net "M_J_DQ<63>")
	)
	(segment
		(start 149.903942 -18.574258)
		(end 150.056342 -18.421858)
		(width 0.14224)
		(layer "In11.Cu")
		(net "M_J_DQ<63>")
	)
	(segment
		(start 123.309888 -56.610504)
		(end 123.303538 -56.599836)
		(width 0.0889)
		(layer "In11.Cu")
		(net "M_J_DQ<63>")
	)
	(segment
		(start 149.346412 1.5494)
		(end 149.016212 1.8796)
		(width 0.14224)
		(layer "In11.Cu")
		(net "M_J_DQ<63>")
	)
	(segment
		(start 149.065742 -3.965956)
		(end 149.065742 -3.560572)
		(width 0.14224)
		(layer "In11.Cu")
		(net "M_J_DQ<63>")
	)
	(segment
		(start 150.113746 -9.582404)
		(end 149.903942 -9.3726)
		(width 0.14224)
		(layer "In11.Cu")
		(net "M_J_DQ<63>")
	)
	(segment
		(start 149.549358 -3.076956)
		(end 149.902164 -2.72415)
		(width 0.14224)
		(layer "In11.Cu")
		(net "M_J_DQ<63>")
	)
	(segment
		(start 149.902164 0.581152)
		(end 150.057612 0.7366)
		(width 0.14224)
		(layer "In11.Cu")
		(net "M_J_DQ<63>")
	)
	(segment
		(start 124.591572 -51.5112)
		(end 125.118368 -51.5112)
		(width 0.0889)
		(layer "In11.Cu")
		(net "M_J_DQ<63>")
	)
	(segment
		(start 123.626372 -52.4764)
		(end 124.591572 -51.5112)
		(width 0.0889)
		(layer "In11.Cu")
		(net "M_J_DQ<63>")
	)
	(segment
		(start 149.903942 -9.3726)
		(end 149.903942 -8.947658)
		(width 0.14224)
		(layer "In11.Cu")
		(net "M_J_DQ<63>")
	)
	(segment
		(start 150.056342 -8.795258)
		(end 150.056342 -7.429246)
		(width 0.14224)
		(layer "In11.Cu")
		(net "M_J_DQ<63>")
	)
	(segment
		(start 150.037546 -21.227796)
		(end 150.037546 -19.1516)
		(width 0.14224)
		(layer "In11.Cu")
		(net "M_J_DQ<63>")
	)
	(segment
		(start 150.037546 -19.1516)
		(end 149.903942 -19.017996)
		(width 0.14224)
		(layer "In11.Cu")
		(net "M_J_DQ<63>")
	)
	(segment
		(start 126.947168 -49.6824)
		(end 129.867914 -49.6824)
		(width 0.14224)
		(layer "In11.Cu")
		(net "M_J_DQ<63>")
	)
	(segment
		(start 149.903942 -12.176252)
		(end 149.903942 -11.741404)
		(width 0.14224)
		(layer "In11.Cu")
		(net "M_J_DQ<63>")
	)
	(segment
		(start 149.065742 -3.560572)
		(end 149.549358 -3.076956)
		(width 0.14224)
		(layer "In11.Cu")
		(net "M_J_DQ<63>")
	)
	(segment
		(start 150.056342 -18.421858)
		(end 150.056342 -17.030446)
		(width 0.14224)
		(layer "In11.Cu")
		(net "M_J_DQ<63>")
	)
	(segment
		(start 149.916642 -16.890746)
		(end 149.916642 -13.681456)
		(width 0.14224)
		(layer "In11.Cu")
		(net "M_J_DQ<63>")
	)
	(segment
		(start 150.081742 -21.999956)
		(end 149.903942 -21.822156)
		(width 0.14224)
		(layer "In11.Cu")
		(net "M_J_DQ<63>")
	)
	(segment
		(start 150.057612 1.0922)
		(end 149.600412 1.5494)
		(width 0.14224)
		(layer "In11.Cu")
		(net "M_J_DQ<63>")
	)
	(segment
		(start 150.113746 -11.5316)
		(end 150.113746 -9.582404)
		(width 0.14224)
		(layer "In11.Cu")
		(net "M_J_DQ<63>")
	)
	(segment
		(start 123.309888 -54.629304)
		(end 123.303538 -54.618636)
		(width 0.0889)
		(layer "In11.Cu")
		(net "M_J_DQ<63>")
	)
	(segment
		(start 149.903942 -21.3614)
		(end 150.037546 -21.227796)
		(width 0.14224)
		(layer "In11.Cu")
		(net "M_J_DQ<63>")
	)
	(segment
		(start 123.303538 -58.581036)
		(end 123.298712 -58.5724)
		(width 0.0889)
		(layer "In11.Cu")
		(net "M_J_DQ<63>")
	)
	(segment
		(start 125.118368 -51.5112)
		(end 126.947168 -49.6824)
		(width 0.14224)
		(layer "In11.Cu")
		(net "M_J_DQ<63>")
	)
	(segment
		(start 123.303538 -59.171586)
		(end 123.309888 -59.160918)
		(width 0.0889)
		(layer "In11.Cu")
		(net "M_J_DQ<63>")
	)
	(segment
		(start 150.081742 -12.354052)
		(end 149.903942 -12.176252)
		(width 0.14224)
		(layer "In11.Cu")
		(net "M_J_DQ<63>")
	)
	(segment
		(start 149.600412 1.5494)
		(end 149.346412 1.5494)
		(width 0.14224)
		(layer "In11.Cu")
		(net "M_J_DQ<63>")
	)
	(segment
		(start 123.309888 -55.619904)
		(end 123.303538 -55.609236)
		(width 0.0889)
		(layer "In11.Cu")
		(net "M_J_DQ<63>")
	)
	(segment
		(start 150.081742 -13.516356)
		(end 150.081742 -12.354052)
		(width 0.14224)
		(layer "In11.Cu")
		(net "M_J_DQ<63>")
	)
	(segment
		(start 123.626372 -52.656994)
		(end 123.626372 -52.4764)
		(width 0.0889)
		(layer "In11.Cu")
		(net "M_J_DQ<63>")
	)
	(segment
		(start 135.964168 -43.586146)
		(end 136.929368 -43.586146)
		(width 0.14224)
		(layer "In11.Cu")
		(net "M_J_DQ<63>")
	)
	(segment
		(start 123.303538 -54.618636)
		(end 123.298712 -54.61)
		(width 0.0889)
		(layer "In11.Cu")
		(net "M_J_DQ<63>")
	)
	(segment
		(start 123.303538 -56.599836)
		(end 123.298712 -56.5912)
		(width 0.0889)
		(layer "In11.Cu")
		(net "M_J_DQ<63>")
	)
	(segment
		(start 123.303538 -53.227732)
		(end 123.30303 -53.227478)
		(width 0.0889)
		(layer "In11.Cu")
		(net "M_J_DQ<63>")
	)
	(segment
		(start 123.309888 -57.601104)
		(end 123.303538 -57.590436)
		(width 0.0889)
		(layer "In11.Cu")
		(net "M_J_DQ<63>")
	)
	(arc
		(start 123.303538 -54.218586)
		(mid 123.382669 -53.923184)
		(end 123.303538 -53.627782)
		(width 0.0889)
		(layer "In11.Cu")
		(net "M_J_DQ<63>")
	)
	(arc
		(start 123.303538 -62.543436)
		(mid 123.250039 -62.343538)
		(end 123.303538 -62.14364)
		(width 0.0889)
		(layer "In11.Cu")
		(net "M_J_DQ<63>")
	)
	(arc
		(start 123.403868 -53.112162)
		(mid 123.568334 -52.910585)
		(end 123.626372 -52.656994)
		(width 0.0889)
		(layer "In11.Cu")
		(net "M_J_DQ<63>")
	)
	(arc
		(start 123.303538 -56.199786)
		(mid 123.38276 -55.910668)
		(end 123.309888 -55.619904)
		(width 0.0889)
		(layer "In11.Cu")
		(net "M_J_DQ<63>")
	)
	(arc
		(start 123.303538 -62.14364)
		(mid 123.382669 -61.848238)
		(end 123.303538 -61.552836)
		(width 0.0889)
		(layer "In11.Cu")
		(net "M_J_DQ<63>")
	)
	(arc
		(start 123.303538 -61.152786)
		(mid 123.38276 -60.863668)
		(end 123.309888 -60.572904)
		(width 0.0889)
		(layer "In11.Cu")
		(net "M_J_DQ<63>")
	)
	(arc
		(start 123.138438 -64.029336)
		(mid 123.185798 -63.899267)
		(end 123.185936 -63.760858)
		(width 0.0889)
		(layer "In11.Cu")
		(net "M_J_DQ<63>")
	)
	(arc
		(start 123.303538 -55.209186)
		(mid 123.38276 -54.920068)
		(end 123.309888 -54.629304)
		(width 0.0889)
		(layer "In11.Cu")
		(net "M_J_DQ<63>")
	)
	(arc
		(start 123.298712 -58.5724)
		(mid 123.249957 -58.376048)
		(end 123.303538 -58.180986)
		(width 0.0889)
		(layer "In11.Cu")
		(net "M_J_DQ<63>")
	)
	(arc
		(start 123.303538 -63.13424)
		(mid 123.382669 -62.838838)
		(end 123.303538 -62.543436)
		(width 0.0889)
		(layer "In11.Cu")
		(net "M_J_DQ<63>")
	)
	(arc
		(start 123.30303 -53.227478)
		(mid 123.347825 -53.164905)
		(end 123.403868 -53.112162)
		(width 0.0889)
		(layer "In11.Cu")
		(net "M_J_DQ<63>")
	)
	(arc
		(start 123.298712 -60.5536)
		(mid 123.249957 -60.357248)
		(end 123.303538 -60.162186)
		(width 0.0889)
		(layer "In11.Cu")
		(net "M_J_DQ<63>")
	)
	(arc
		(start 123.185936 -63.760858)
		(mid 123.191267 -63.437512)
		(end 123.303538 -63.13424)
		(width 0.0889)
		(layer "In11.Cu")
		(net "M_J_DQ<63>")
	)
	(arc
		(start 123.303538 -60.162186)
		(mid 123.382669 -59.866784)
		(end 123.303538 -59.571382)
		(width 0.0889)
		(layer "In11.Cu")
		(net "M_J_DQ<63>")
	)
	(arc
		(start 123.303538 -61.552836)
		(mid 123.250005 -61.352828)
		(end 123.303538 -61.152786)
		(width 0.0889)
		(layer "In11.Cu")
		(net "M_J_DQ<63>")
	)
	(arc
		(start 123.298712 -54.61)
		(mid 123.249957 -54.413648)
		(end 123.303538 -54.218586)
		(width 0.0889)
		(layer "In11.Cu")
		(net "M_J_DQ<63>")
	)
	(arc
		(start 123.309888 -59.160918)
		(mid 123.382686 -58.870155)
		(end 123.303538 -58.581036)
		(width 0.0889)
		(layer "In11.Cu")
		(net "M_J_DQ<63>")
	)
	(arc
		(start 123.298712 -56.5912)
		(mid 123.249957 -56.394848)
		(end 123.303538 -56.199786)
		(width 0.0889)
		(layer "In11.Cu")
		(net "M_J_DQ<63>")
	)
	(arc
		(start 123.303538 -57.190386)
		(mid 123.38276 -56.901268)
		(end 123.309888 -56.610504)
		(width 0.0889)
		(layer "In11.Cu")
		(net "M_J_DQ<63>")
	)
	(arc
		(start 123.298712 -57.5818)
		(mid 123.249957 -57.385448)
		(end 123.303538 -57.190386)
		(width 0.0889)
		(layer "In11.Cu")
		(net "M_J_DQ<63>")
	)
	(arc
		(start 123.298712 -55.6006)
		(mid 123.249957 -55.404248)
		(end 123.303538 -55.209186)
		(width 0.0889)
		(layer "In11.Cu")
		(net "M_J_DQ<63>")
	)
	(arc
		(start 123.303538 -59.571382)
		(mid 123.250039 -59.371484)
		(end 123.303538 -59.171586)
		(width 0.0889)
		(layer "In11.Cu")
		(net "M_J_DQ<63>")
	)
	(arc
		(start 123.303538 -58.180986)
		(mid 123.38276 -57.891868)
		(end 123.309888 -57.601104)
		(width 0.0889)
		(layer "In11.Cu")
		(net "M_J_DQ<63>")
	)
	(arc
		(start 123.303538 -53.627782)
		(mid 123.250005 -53.427774)
		(end 123.303538 -53.227732)
		(width 0.0889)
		(layer "In11.Cu")
		(net "M_J_DQ<63>")
	)
	(segment
		(start 149.549612 0.939546)
		(end 149.549358 0.9398)
		(width 0.1651)
		(layer "F.Cu")
		(net "M_J_DQ<62>")
	)
	(segment
		(start 149.549612 0.635)
		(end 149.549612 0.939546)
		(width 0.1651)
		(layer "F.Cu")
		(net "M_J_DQ<62>")
	)
	(segment
		(start 149.681692 0.50292)
		(end 149.549612 0.635)
		(width 0.1651)
		(layer "F.Cu")
		(net "M_J_DQ<62>")
	)
	(segment
		(start 149.681692 0.28448)
		(end 149.681692 0.50292)
		(width 0.1651)
		(layer "F.Cu")
		(net "M_J_DQ<62>")
	)
	(segment
		(start 123.363228 -62.838584)
		(end 122.791728 -62.838584)
		(width 0.0889)
		(layer "F.Cu")
		(net "M_J_DQ<62>")
	)
	(segment
		(start 149.549612 -0.820928)
		(end 149.549612 0.1524)
		(width 0.1651)
		(layer "F.Cu")
		(net "M_J_DQ<62>")
	)
	(segment
		(start 149.549612 0.1524)
		(end 149.681692 0.28448)
		(width 0.1651)
		(layer "F.Cu")
		(net "M_J_DQ<62>")
	)
	(segment
		(start 149.549358 -0.821182)
		(end 149.549612 -0.820928)
		(width 0.1651)
		(layer "F.Cu")
		(net "M_J_DQ<62>")
	)
	(via
		(at 122.791728 -62.838584)
		(size 0.508)
		(drill 0.254)
		(layers "F.Cu" "B.Cu")
		(net "M_J_DQ<62>")
	)
	(via
		(at 149.549358 0.9398)
		(size 0.508)
		(drill 0.254)
		(layers "F.Cu" "B.Cu")
		(net "M_J_DQ<62>")
	)
	(via
		(at 148.699474 -4.357878)
		(size 0.508)
		(drill 0.254)
		(layers "F.Cu" "B.Cu")
		(net "M_J_DQ<62>")
	)
	(segment
		(start 148.699474 -5.621782)
		(end 148.699474 -4.357878)
		(width 0.1651)
		(layer "B.Cu")
		(net "M_J_DQ<62>")
	)
	(segment
		(start 149.121368 -19.177)
		(end 149.267164 -19.031204)
		(width 0.14224)
		(layer "In11.Cu")
		(net "M_J_DQ<62>")
	)
	(segment
		(start 148.977604 -26.725118)
		(end 148.835364 -26.582878)
		(width 0.14224)
		(layer "In11.Cu")
		(net "M_J_DQ<62>")
	)
	(segment
		(start 149.267164 -21.771356)
		(end 149.267164 -21.3614)
		(width 0.14224)
		(layer "In11.Cu")
		(net "M_J_DQ<62>")
	)
	(segment
		(start 149.174962 0.565404)
		(end 149.549358 0.9398)
		(width 0.14224)
		(layer "In11.Cu")
		(net "M_J_DQ<62>")
	)
	(segment
		(start 149.216364 -4.874768)
		(end 148.699474 -4.357878)
		(width 0.14224)
		(layer "In11.Cu")
		(net "M_J_DQ<62>")
	)
	(segment
		(start 123.084844 -62.669674)
		(end 123.10872 -62.58052)
		(width 0.0889)
		(layer "In11.Cu")
		(net "M_J_DQ<62>")
	)
	(segment
		(start 148.977604 -29.976318)
		(end 149.461728 -29.976318)
		(width 0.14224)
		(layer "In11.Cu")
		(net "M_J_DQ<62>")
	)
	(segment
		(start 149.603968 -27.233118)
		(end 149.603968 -26.867358)
		(width 0.14224)
		(layer "In11.Cu")
		(net "M_J_DQ<62>")
	)
	(segment
		(start 149.461728 -27.375358)
		(end 149.603968 -27.233118)
		(width 0.14224)
		(layer "In11.Cu")
		(net "M_J_DQ<62>")
	)
	(segment
		(start 149.461728 -28.025598)
		(end 148.977604 -28.025598)
		(width 0.14224)
		(layer "In11.Cu")
		(net "M_J_DQ<62>")
	)
	(segment
		(start 149.603968 -29.468318)
		(end 149.461728 -29.326078)
		(width 0.14224)
		(layer "In11.Cu")
		(net "M_J_DQ<62>")
	)
	(segment
		(start 149.165564 -25.610058)
		(end 149.165564 -23.269956)
		(width 0.14224)
		(layer "In11.Cu")
		(net "M_J_DQ<62>")
	)
	(segment
		(start 123.138438 -54.713886)
		(end 123.132088 -54.703218)
		(width 0.0889)
		(layer "In11.Cu")
		(net "M_J_DQ<62>")
	)
	(segment
		(start 149.165564 -13.668756)
		(end 149.063964 -13.567156)
		(width 0.14224)
		(layer "In11.Cu")
		(net "M_J_DQ<62>")
	)
	(segment
		(start 149.063964 -12.373356)
		(end 149.267164 -12.170156)
		(width 0.14224)
		(layer "In11.Cu")
		(net "M_J_DQ<62>")
	)
	(segment
		(start 148.463762 -4.122166)
		(end 148.463762 -3.327654)
		(width 0.14224)
		(layer "In11.Cu")
		(net "M_J_DQ<62>")
	)
	(segment
		(start 123.434856 -52.396898)
		(end 124.917454 -50.9143)
		(width 0.0889)
		(layer "In11.Cu")
		(net "M_J_DQ<62>")
	)
	(segment
		(start 149.23643 -2.203196)
		(end 148.81098 -1.777746)
		(width 0.14224)
		(layer "In11.Cu")
		(net "M_J_DQ<62>")
	)
	(segment
		(start 149.063964 -23.168356)
		(end 149.063964 -21.974556)
		(width 0.14224)
		(layer "In11.Cu")
		(net "M_J_DQ<62>")
	)
	(segment
		(start 148.977604 -27.375358)
		(end 149.461728 -27.375358)
		(width 0.14224)
		(layer "In11.Cu")
		(net "M_J_DQ<62>")
	)
	(segment
		(start 122.791728 -62.838584)
		(end 123.084844 -62.669674)
		(width 0.0889)
		(layer "In11.Cu")
		(net "M_J_DQ<62>")
	)
	(segment
		(start 149.461728 -28.675838)
		(end 149.603968 -28.533598)
		(width 0.14224)
		(layer "In11.Cu")
		(net "M_J_DQ<62>")
	)
	(segment
		(start 148.835364 -30.893004)
		(end 148.835364 -30.118558)
		(width 0.14224)
		(layer "In11.Cu")
		(net "M_J_DQ<62>")
	)
	(segment
		(start 148.977604 -28.025598)
		(end 148.835364 -27.883358)
		(width 0.14224)
		(layer "In11.Cu")
		(net "M_J_DQ<62>")
	)
	(segment
		(start 129.614168 -49.0728)
		(end 136.02462 -42.662348)
		(width 0.14224)
		(layer "In11.Cu")
		(net "M_J_DQ<62>")
	)
	(segment
		(start 123.143264 -60.666122)
		(end 123.138438 -60.657486)
		(width 0.0889)
		(layer "In11.Cu")
		(net "M_J_DQ<62>")
	)
	(segment
		(start 149.165564 -16.91005)
		(end 149.165564 -13.668756)
		(width 0.14224)
		(layer "In11.Cu")
		(net "M_J_DQ<62>")
	)
	(segment
		(start 148.977604 -29.326078)
		(end 148.835364 -29.183838)
		(width 0.14224)
		(layer "In11.Cu")
		(net "M_J_DQ<62>")
	)
	(segment
		(start 149.070568 -11.589004)
		(end 149.070568 -9.5504)
		(width 0.14224)
		(layer "In11.Cu")
		(net "M_J_DQ<62>")
	)
	(segment
		(start 123.143264 -55.713122)
		(end 123.138438 -55.704486)
		(width 0.0889)
		(layer "In11.Cu")
		(net "M_J_DQ<62>")
	)
	(segment
		(start 149.603968 -26.867358)
		(end 149.461728 -26.725118)
		(width 0.14224)
		(layer "In11.Cu")
		(net "M_J_DQ<62>")
	)
	(segment
		(start 149.19198 -0.768096)
		(end 148.81098 -0.387096)
		(width 0.14224)
		(layer "In11.Cu")
		(net "M_J_DQ<62>")
	)
	(segment
		(start 149.267164 -19.031204)
		(end 149.267164 -18.63725)
		(width 0.14224)
		(layer "In11.Cu")
		(net "M_J_DQ<62>")
	)
	(segment
		(start 149.19198 -1.111504)
		(end 149.19198 -0.768096)
		(width 0.14224)
		(layer "In11.Cu")
		(net "M_J_DQ<62>")
	)
	(segment
		(start 149.267164 -18.63725)
		(end 149.063964 -18.43405)
		(width 0.14224)
		(layer "In11.Cu")
		(net "M_J_DQ<62>")
	)
	(segment
		(start 148.81098 -0.387096)
		(end 148.81098 -0.076454)
		(width 0.14224)
		(layer "In11.Cu")
		(net "M_J_DQ<62>")
	)
	(segment
		(start 123.138438 -55.704486)
		(end 123.132088 -55.693818)
		(width 0.0889)
		(layer "In11.Cu")
		(net "M_J_DQ<62>")
	)
	(segment
		(start 149.603968 -28.167838)
		(end 149.461728 -28.025598)
		(width 0.14224)
		(layer "In11.Cu")
		(net "M_J_DQ<62>")
	)
	(segment
		(start 148.81098 -1.777746)
		(end 148.81098 -1.492504)
		(width 0.14224)
		(layer "In11.Cu")
		(net "M_J_DQ<62>")
	)
	(segment
		(start 148.977604 -28.675838)
		(end 149.461728 -28.675838)
		(width 0.14224)
		(layer "In11.Cu")
		(net "M_J_DQ<62>")
	)
	(segment
		(start 148.835364 -30.118558)
		(end 148.977604 -29.976318)
		(width 0.14224)
		(layer "In11.Cu")
		(net "M_J_DQ<62>")
	)
	(segment
		(start 149.23643 -2.554986)
		(end 149.23643 -2.203196)
		(width 0.14224)
		(layer "In11.Cu")
		(net "M_J_DQ<62>")
	)
	(segment
		(start 148.81098 -0.076454)
		(end 149.174962 0.287528)
		(width 0.14224)
		(layer "In11.Cu")
		(net "M_J_DQ<62>")
	)
	(segment
		(start 123.132088 -59.087004)
		(end 123.138438 -59.076336)
		(width 0.0889)
		(layer "In11.Cu")
		(net "M_J_DQ<62>")
	)
	(segment
		(start 149.063964 -8.788654)
		(end 149.063964 -7.391146)
		(width 0.14224)
		(layer "In11.Cu")
		(net "M_J_DQ<62>")
	)
	(segment
		(start 149.070568 -9.5504)
		(end 149.267164 -9.353804)
		(width 0.14224)
		(layer "In11.Cu")
		(net "M_J_DQ<62>")
	)
	(segment
		(start 123.138438 -56.695086)
		(end 123.132088 -56.684418)
		(width 0.0889)
		(layer "In11.Cu")
		(net "M_J_DQ<62>")
	)
	(segment
		(start 137.06602 -42.662348)
		(end 148.835364 -30.893004)
		(width 0.14224)
		(layer "In11.Cu")
		(net "M_J_DQ<62>")
	)
	(segment
		(start 149.063964 -18.43405)
		(end 149.063964 -17.01165)
		(width 0.14224)
		(layer "In11.Cu")
		(net "M_J_DQ<62>")
	)
	(segment
		(start 149.174962 0.287528)
		(end 149.174962 0.565404)
		(width 0.14224)
		(layer "In11.Cu")
		(net "M_J_DQ<62>")
	)
	(segment
		(start 149.063964 -13.567156)
		(end 149.063964 -12.373356)
		(width 0.14224)
		(layer "In11.Cu")
		(net "M_J_DQ<62>")
	)
	(segment
		(start 149.063964 -21.974556)
		(end 149.267164 -21.771356)
		(width 0.14224)
		(layer "In11.Cu")
		(net "M_J_DQ<62>")
	)
	(segment
		(start 149.165564 -23.269956)
		(end 149.063964 -23.168356)
		(width 0.14224)
		(layer "In11.Cu")
		(net "M_J_DQ<62>")
	)
	(segment
		(start 149.267164 -11.7856)
		(end 149.070568 -11.589004)
		(width 0.14224)
		(layer "In11.Cu")
		(net "M_J_DQ<62>")
	)
	(segment
		(start 149.461728 -29.976318)
		(end 149.603968 -29.834078)
		(width 0.14224)
		(layer "In11.Cu")
		(net "M_J_DQ<62>")
	)
	(segment
		(start 148.835364 -27.883358)
		(end 148.835364 -27.517598)
		(width 0.14224)
		(layer "In11.Cu")
		(net "M_J_DQ<62>")
	)
	(segment
		(start 148.835364 -26.582878)
		(end 148.835364 -25.940258)
		(width 0.14224)
		(layer "In11.Cu")
		(net "M_J_DQ<62>")
	)
	(segment
		(start 123.138438 -57.685686)
		(end 123.132088 -57.675018)
		(width 0.0889)
		(layer "In11.Cu")
		(net "M_J_DQ<62>")
	)
	(segment
		(start 123.434856 -52.656994)
		(end 123.434856 -52.396898)
		(width 0.0889)
		(layer "In11.Cu")
		(net "M_J_DQ<62>")
	)
	(segment
		(start 124.927868 -50.9143)
		(end 126.769368 -49.0728)
		(width 0.14224)
		(layer "In11.Cu")
		(net "M_J_DQ<62>")
	)
	(segment
		(start 148.835364 -29.183838)
		(end 148.835364 -28.818078)
		(width 0.14224)
		(layer "In11.Cu")
		(net "M_J_DQ<62>")
	)
	(segment
		(start 124.917454 -50.9143)
		(end 124.927868 -50.9143)
		(width 0.0889)
		(layer "In11.Cu")
		(net "M_J_DQ<62>")
	)
	(segment
		(start 149.603968 -29.834078)
		(end 149.603968 -29.468318)
		(width 0.14224)
		(layer "In11.Cu")
		(net "M_J_DQ<62>")
	)
	(segment
		(start 148.835364 -25.940258)
		(end 149.165564 -25.610058)
		(width 0.14224)
		(layer "In11.Cu")
		(net "M_J_DQ<62>")
	)
	(segment
		(start 149.267164 -8.991854)
		(end 149.063964 -8.788654)
		(width 0.14224)
		(layer "In11.Cu")
		(net "M_J_DQ<62>")
	)
	(segment
		(start 148.81098 -1.492504)
		(end 149.19198 -1.111504)
		(width 0.14224)
		(layer "In11.Cu")
		(net "M_J_DQ<62>")
	)
	(segment
		(start 149.063964 -7.391146)
		(end 149.216364 -7.238746)
		(width 0.14224)
		(layer "In11.Cu")
		(net "M_J_DQ<62>")
	)
	(segment
		(start 149.216364 -7.238746)
		(end 149.216364 -4.874768)
		(width 0.14224)
		(layer "In11.Cu")
		(net "M_J_DQ<62>")
	)
	(segment
		(start 149.267164 -12.170156)
		(end 149.267164 -11.7856)
		(width 0.14224)
		(layer "In11.Cu")
		(net "M_J_DQ<62>")
	)
	(segment
		(start 149.267164 -21.3614)
		(end 149.121368 -21.215604)
		(width 0.14224)
		(layer "In11.Cu")
		(net "M_J_DQ<62>")
	)
	(segment
		(start 123.143264 -54.722522)
		(end 123.138438 -54.713886)
		(width 0.0889)
		(layer "In11.Cu")
		(net "M_J_DQ<62>")
	)
	(segment
		(start 126.769368 -49.0728)
		(end 129.614168 -49.0728)
		(width 0.14224)
		(layer "In11.Cu")
		(net "M_J_DQ<62>")
	)
	(segment
		(start 123.143264 -56.703722)
		(end 123.138438 -56.695086)
		(width 0.0889)
		(layer "In11.Cu")
		(net "M_J_DQ<62>")
	)
	(segment
		(start 123.143264 -57.694322)
		(end 123.138438 -57.685686)
		(width 0.0889)
		(layer "In11.Cu")
		(net "M_J_DQ<62>")
	)
	(segment
		(start 123.138438 -60.657486)
		(end 123.132088 -60.646818)
		(width 0.0889)
		(layer "In11.Cu")
		(net "M_J_DQ<62>")
	)
	(segment
		(start 149.461728 -29.326078)
		(end 148.977604 -29.326078)
		(width 0.14224)
		(layer "In11.Cu")
		(net "M_J_DQ<62>")
	)
	(segment
		(start 123.143264 -59.675522)
		(end 123.138438 -59.666886)
		(width 0.0889)
		(layer "In11.Cu")
		(net "M_J_DQ<62>")
	)
	(segment
		(start 149.603968 -28.533598)
		(end 149.603968 -28.167838)
		(width 0.14224)
		(layer "In11.Cu")
		(net "M_J_DQ<62>")
	)
	(segment
		(start 148.699474 -4.357878)
		(end 148.463762 -4.122166)
		(width 0.14224)
		(layer "In11.Cu")
		(net "M_J_DQ<62>")
	)
	(segment
		(start 149.267164 -9.353804)
		(end 149.267164 -8.991854)
		(width 0.14224)
		(layer "In11.Cu")
		(net "M_J_DQ<62>")
	)
	(segment
		(start 149.063964 -17.01165)
		(end 149.165564 -16.91005)
		(width 0.14224)
		(layer "In11.Cu")
		(net "M_J_DQ<62>")
	)
	(segment
		(start 148.835364 -27.517598)
		(end 148.977604 -27.375358)
		(width 0.14224)
		(layer "In11.Cu")
		(net "M_J_DQ<62>")
	)
	(segment
		(start 148.463762 -3.327654)
		(end 149.23643 -2.554986)
		(width 0.14224)
		(layer "In11.Cu")
		(net "M_J_DQ<62>")
	)
	(segment
		(start 149.121368 -21.215604)
		(end 149.121368 -19.177)
		(width 0.14224)
		(layer "In11.Cu")
		(net "M_J_DQ<62>")
	)
	(segment
		(start 149.461728 -26.725118)
		(end 148.977604 -26.725118)
		(width 0.14224)
		(layer "In11.Cu")
		(net "M_J_DQ<62>")
	)
	(segment
		(start 148.835364 -28.818078)
		(end 148.977604 -28.675838)
		(width 0.14224)
		(layer "In11.Cu")
		(net "M_J_DQ<62>")
	)
	(segment
		(start 136.02462 -42.662348)
		(end 137.06602 -42.662348)
		(width 0.14224)
		(layer "In11.Cu")
		(net "M_J_DQ<62>")
	)
	(arc
		(start 123.138438 -61.64834)
		(mid 123.059375 -61.352938)
		(end 123.138438 -61.057536)
		(width 0.0889)
		(layer "In11.Cu")
		(net "M_J_DQ<62>")
	)
	(arc
		(start 123.138438 -54.123336)
		(mid 123.191908 -53.928273)
		(end 123.143264 -53.731922)
		(width 0.0889)
		(layer "In11.Cu")
		(net "M_J_DQ<62>")
	)
	(arc
		(start 123.138438 -59.666886)
		(mid 123.059216 -59.377768)
		(end 123.132088 -59.087004)
		(width 0.0889)
		(layer "In11.Cu")
		(net "M_J_DQ<62>")
	)
	(arc
		(start 123.132088 -57.675018)
		(mid 123.05929 -57.384255)
		(end 123.138438 -57.095136)
		(width 0.0889)
		(layer "In11.Cu")
		(net "M_J_DQ<62>")
	)
	(arc
		(start 123.138438 -56.104536)
		(mid 123.191908 -55.909473)
		(end 123.143264 -55.713122)
		(width 0.0889)
		(layer "In11.Cu")
		(net "M_J_DQ<62>")
	)
	(arc
		(start 123.10872 -62.58052)
		(mid 123.06016 -62.310795)
		(end 123.138438 -62.048136)
		(width 0.0889)
		(layer "In11.Cu")
		(net "M_J_DQ<62>")
	)
	(arc
		(start 123.138438 -53.132482)
		(mid 123.203896 -53.040641)
		(end 123.285758 -52.963064)
		(width 0.0889)
		(layer "In11.Cu")
		(net "M_J_DQ<62>")
	)
	(arc
		(start 123.132088 -55.693818)
		(mid 123.05929 -55.403055)
		(end 123.138438 -55.113936)
		(width 0.0889)
		(layer "In11.Cu")
		(net "M_J_DQ<62>")
	)
	(arc
		(start 123.132088 -54.703218)
		(mid 123.05929 -54.412455)
		(end 123.138438 -54.123336)
		(width 0.0889)
		(layer "In11.Cu")
		(net "M_J_DQ<62>")
	)
	(arc
		(start 123.138438 -59.076336)
		(mid 123.191937 -58.876438)
		(end 123.138438 -58.67654)
		(width 0.0889)
		(layer "In11.Cu")
		(net "M_J_DQ<62>")
	)
	(arc
		(start 123.132088 -60.646818)
		(mid 123.05929 -60.356055)
		(end 123.138438 -60.066936)
		(width 0.0889)
		(layer "In11.Cu")
		(net "M_J_DQ<62>")
	)
	(arc
		(start 123.138438 -58.085736)
		(mid 123.191908 -57.890673)
		(end 123.143264 -57.694322)
		(width 0.0889)
		(layer "In11.Cu")
		(net "M_J_DQ<62>")
	)
	(arc
		(start 123.138438 -62.048136)
		(mid 123.191937 -61.848238)
		(end 123.138438 -61.64834)
		(width 0.0889)
		(layer "In11.Cu")
		(net "M_J_DQ<62>")
	)
	(arc
		(start 123.138438 -55.113936)
		(mid 123.191908 -54.918873)
		(end 123.143264 -54.722522)
		(width 0.0889)
		(layer "In11.Cu")
		(net "M_J_DQ<62>")
	)
	(arc
		(start 123.138438 -58.67654)
		(mid 123.059307 -58.381138)
		(end 123.138438 -58.085736)
		(width 0.0889)
		(layer "In11.Cu")
		(net "M_J_DQ<62>")
	)
	(arc
		(start 123.138438 -57.095136)
		(mid 123.191908 -56.900073)
		(end 123.143264 -56.703722)
		(width 0.0889)
		(layer "In11.Cu")
		(net "M_J_DQ<62>")
	)
	(arc
		(start 123.138438 -61.057536)
		(mid 123.191908 -60.862473)
		(end 123.143264 -60.666122)
		(width 0.0889)
		(layer "In11.Cu")
		(net "M_J_DQ<62>")
	)
	(arc
		(start 123.132088 -56.684418)
		(mid 123.05929 -56.393655)
		(end 123.138438 -56.104536)
		(width 0.0889)
		(layer "In11.Cu")
		(net "M_J_DQ<62>")
	)
	(arc
		(start 123.143264 -53.731922)
		(mid 123.05938 -53.432864)
		(end 123.138438 -53.132482)
		(width 0.0889)
		(layer "In11.Cu")
		(net "M_J_DQ<62>")
	)
	(arc
		(start 123.285758 -52.963064)
		(mid 123.395839 -52.827323)
		(end 123.434856 -52.656994)
		(width 0.0889)
		(layer "In11.Cu")
		(net "M_J_DQ<62>")
	)
	(arc
		(start 123.138438 -60.066936)
		(mid 123.191908 -59.871873)
		(end 123.143264 -59.675522)
		(width 0.0889)
		(layer "In11.Cu")
		(net "M_J_DQ<62>")
	)
	(segment
		(start 142.749524 3.778758)
		(end 142.749524 2.514854)
		(width 0.1651)
		(layer "F.Cu")
		(net "M_J_DQ<61>")
	)
	(segment
		(start 120.787668 -64.324738)
		(end 120.216168 -64.324738)
		(width 0.0889)
		(layer "F.Cu")
		(net "M_J_DQ<61>")
	)
	(via
		(at 142.749524 2.514854)
		(size 0.508)
		(drill 0.254)
		(layers "F.Cu" "B.Cu")
		(net "M_J_DQ<61>")
	)
	(via
		(at 120.216168 -64.324738)
		(size 0.508)
		(drill 0.254)
		(layers "F.Cu" "B.Cu")
		(net "M_J_DQ<61>")
	)
	(via
		(at 143.523208 -3.076956)
		(size 0.508)
		(drill 0.254)
		(layers "F.Cu" "B.Cu")
		(net "M_J_DQ<61>")
	)
	(segment
		(start 143.599408 -1.021842)
		(end 143.599408 -3.000756)
		(width 0.1651)
		(layer "B.Cu")
		(net "M_J_DQ<61>")
	)
	(segment
		(start 143.599408 -3.000756)
		(end 143.523208 -3.076956)
		(width 0.1651)
		(layer "B.Cu")
		(net "M_J_DQ<61>")
	)
	(segment
		(start 142.57655 -32.098996)
		(end 142.77721 -32.09925)
		(width 0.14224)
		(layer "In11.Cu")
		(net "M_J_DQ<61>")
	)
	(segment
		(start 144.031462 1.149096)
		(end 143.631158 1.5494)
		(width 0.14224)
		(layer "In11.Cu")
		(net "M_J_DQ<61>")
	)
	(segment
		(start 144.098264 -9.632696)
		(end 143.954246 -9.488678)
		(width 0.14224)
		(layer "In11.Cu")
		(net "M_J_DQ<61>")
	)
	(segment
		(start 143.956278 -30.719014)
		(end 143.6624 -30.425136)
		(width 0.14224)
		(layer "In11.Cu")
		(net "M_J_DQ<61>")
	)
	(segment
		(start 119.878602 -60.577476)
		(end 119.869712 -60.562236)
		(width 0.0889)
		(layer "In11.Cu")
		(net "M_J_DQ<61>")
	)
	(segment
		(start 143.990568 -17.11071)
		(end 143.990568 -13.624052)
		(width 0.14224)
		(layer "In11.Cu")
		(net "M_J_DQ<61>")
	)
	(segment
		(start 144.098264 -11.551158)
		(end 144.098264 -9.632696)
		(width 0.14224)
		(layer "In11.Cu")
		(net "M_J_DQ<61>")
	)
	(segment
		(start 144.041368 -23.024592)
		(end 144.041368 -21.9456)
		(width 0.14224)
		(layer "In11.Cu")
		(net "M_J_DQ<61>")
	)
	(segment
		(start 141.542262 -32.725106)
		(end 141.82217 -32.445198)
		(width 0.14224)
		(layer "In11.Cu")
		(net "M_J_DQ<61>")
	)
	(segment
		(start 141.161516 -32.725106)
		(end 141.542262 -32.725106)
		(width 0.14224)
		(layer "In11.Cu")
		(net "M_J_DQ<61>")
	)
	(segment
		(start 143.963136 -25.931368)
		(end 143.963136 -23.102824)
		(width 0.14224)
		(layer "In11.Cu")
		(net "M_J_DQ<61>")
	)
	(segment
		(start 143.963136 -23.102824)
		(end 144.041368 -23.024592)
		(width 0.14224)
		(layer "In11.Cu")
		(net "M_J_DQ<61>")
	)
	(segment
		(start 143.914368 -7.24535)
		(end 143.914368 -4.83616)
		(width 0.14224)
		(layer "In11.Cu")
		(net "M_J_DQ<61>")
	)
	(segment
		(start 143.956278 -30.920182)
		(end 143.956278 -30.719014)
		(width 0.14224)
		(layer "In11.Cu")
		(net "M_J_DQ<61>")
	)
	(segment
		(start 144.039336 -12.403328)
		(end 143.954246 -12.318238)
		(width 0.14224)
		(layer "In11.Cu")
		(net "M_J_DQ<61>")
	)
	(segment
		(start 120.432068 -62.99073)
		(end 120.080278 -62.767464)
		(width 0.0889)
		(layer "In11.Cu")
		(net "M_J_DQ<61>")
	)
	(segment
		(start 143.939768 -19.05)
		(end 143.939768 -18.478246)
		(width 0.14224)
		(layer "In11.Cu")
		(net "M_J_DQ<61>")
	)
	(segment
		(start 119.949214 -52.907438)
		(end 119.99976 -52.856892)
		(width 0.0889)
		(layer "In11.Cu")
		(net "M_J_DQ<61>")
	)
	(segment
		(start 143.001492 -30.88513)
		(end 143.20266 -30.88513)
		(width 0.14224)
		(layer "In11.Cu")
		(net "M_J_DQ<61>")
	)
	(segment
		(start 120.45442 -63.012574)
		(end 120.432068 -62.99073)
		(width 0.0889)
		(layer "In11.Cu")
		(net "M_J_DQ<61>")
	)
	(segment
		(start 122.007376 -48.653192)
		(end 122.210068 -48.4505)
		(width 0.0889)
		(layer "In11.Cu")
		(net "M_J_DQ<61>")
	)
	(segment
		(start 143.939768 -21.844)
		(end 143.939768 -21.3106)
		(width 0.14224)
		(layer "In11.Cu")
		(net "M_J_DQ<61>")
	)
	(segment
		(start 144.039336 -18.378678)
		(end 144.039336 -17.159478)
		(width 0.14224)
		(layer "In11.Cu")
		(net "M_J_DQ<61>")
	)
	(segment
		(start 144.092168 -21.1582)
		(end 144.092168 -19.2024)
		(width 0.14224)
		(layer "In11.Cu")
		(net "M_J_DQ<61>")
	)
	(segment
		(start 143.834612 -2.765552)
		(end 143.834612 0.53975)
		(width 0.14224)
		(layer "In11.Cu")
		(net "M_J_DQ<61>")
	)
	(segment
		(start 119.878602 -55.624476)
		(end 119.869712 -55.609236)
		(width 0.0889)
		(layer "In11.Cu")
		(net "M_J_DQ<61>")
	)
	(segment
		(start 119.878602 -57.605676)
		(end 119.869712 -57.590436)
		(width 0.0889)
		(layer "In11.Cu")
		(net "M_J_DQ<61>")
	)
	(segment
		(start 143.496538 -31.179008)
		(end 143.697198 -31.179262)
		(width 0.14224)
		(layer "In11.Cu")
		(net "M_J_DQ<61>")
	)
	(segment
		(start 143.048736 -3.551428)
		(end 143.523208 -3.076956)
		(width 0.14224)
		(layer "In11.Cu")
		(net "M_J_DQ<61>")
	)
	(segment
		(start 142.742412 -31.345124)
		(end 142.742666 -31.143956)
		(width 0.14224)
		(layer "In11.Cu")
		(net "M_J_DQ<61>")
	)
	(segment
		(start 143.03629 -31.639002)
		(end 142.742412 -31.345124)
		(width 0.14224)
		(layer "In11.Cu")
		(net "M_J_DQ<61>")
	)
	(segment
		(start 143.6624 -30.425136)
		(end 143.662654 -30.223968)
		(width 0.14224)
		(layer "In11.Cu")
		(net "M_J_DQ<61>")
	)
	(segment
		(start 143.834612 0.53975)
		(end 144.031462 0.7366)
		(width 0.14224)
		(layer "In11.Cu")
		(net "M_J_DQ<61>")
	)
	(segment
		(start 143.954246 -12.318238)
		(end 143.954246 -11.695176)
		(width 0.14224)
		(layer "In11.Cu")
		(net "M_J_DQ<61>")
	)
	(segment
		(start 119.99976 -50.661824)
		(end 122.007376 -48.654208)
		(width 0.0889)
		(layer "In11.Cu")
		(net "M_J_DQ<61>")
	)
	(segment
		(start 144.090136 -29.796486)
		(end 144.090136 -26.058368)
		(width 0.14224)
		(layer "In11.Cu")
		(net "M_J_DQ<61>")
	)
	(segment
		(start 144.090136 -26.058368)
		(end 143.963136 -25.931368)
		(width 0.14224)
		(layer "In11.Cu")
		(net "M_J_DQ<61>")
	)
	(segment
		(start 143.048736 -3.970528)
		(end 143.048736 -3.551428)
		(width 0.14224)
		(layer "In11.Cu")
		(net "M_J_DQ<61>")
	)
	(segment
		(start 143.320262 1.5494)
		(end 142.749524 2.120138)
		(width 0.14224)
		(layer "In11.Cu")
		(net "M_J_DQ<61>")
	)
	(segment
		(start 141.82217 -32.445198)
		(end 141.822678 -32.063944)
		(width 0.14224)
		(layer "In11.Cu")
		(net "M_J_DQ<61>")
	)
	(segment
		(start 143.03629 -31.84017)
		(end 143.03629 -31.639002)
		(width 0.14224)
		(layer "In11.Cu")
		(net "M_J_DQ<61>")
	)
	(segment
		(start 143.523208 -3.076956)
		(end 143.834612 -2.765552)
		(width 0.14224)
		(layer "In11.Cu")
		(net "M_J_DQ<61>")
	)
	(segment
		(start 142.081504 -31.805118)
		(end 142.282672 -31.805118)
		(width 0.14224)
		(layer "In11.Cu")
		(net "M_J_DQ<61>")
	)
	(segment
		(start 143.939768 -18.478246)
		(end 144.039336 -18.378678)
		(width 0.14224)
		(layer "In11.Cu")
		(net "M_J_DQ<61>")
	)
	(segment
		(start 143.662654 -30.223968)
		(end 144.090136 -29.796486)
		(width 0.14224)
		(layer "In11.Cu")
		(net "M_J_DQ<61>")
	)
	(segment
		(start 143.996664 -8.902446)
		(end 143.996664 -7.327646)
		(width 0.14224)
		(layer "In11.Cu")
		(net "M_J_DQ<61>")
	)
	(segment
		(start 143.939768 -21.3106)
		(end 144.092168 -21.1582)
		(width 0.14224)
		(layer "In11.Cu")
		(net "M_J_DQ<61>")
	)
	(segment
		(start 142.282672 -31.805118)
		(end 142.57655 -32.098996)
		(width 0.14224)
		(layer "In11.Cu")
		(net "M_J_DQ<61>")
	)
	(segment
		(start 144.092168 -19.2024)
		(end 143.939768 -19.05)
		(width 0.14224)
		(layer "In11.Cu")
		(net "M_J_DQ<61>")
	)
	(segment
		(start 122.007376 -48.654208)
		(end 122.007376 -48.653192)
		(width 0.0889)
		(layer "In11.Cu")
		(net "M_J_DQ<61>")
	)
	(segment
		(start 144.039336 -17.159478)
		(end 143.990568 -17.11071)
		(width 0.14224)
		(layer "In11.Cu")
		(net "M_J_DQ<61>")
	)
	(segment
		(start 143.697198 -31.179262)
		(end 143.956278 -30.920182)
		(width 0.14224)
		(layer "In11.Cu")
		(net "M_J_DQ<61>")
	)
	(segment
		(start 119.949214 -53.922676)
		(end 119.949214 -52.907438)
		(width 0.0889)
		(layer "In11.Cu")
		(net "M_J_DQ<61>")
	)
	(segment
		(start 129.157222 -44.7294)
		(end 141.161516 -32.725106)
		(width 0.14224)
		(layer "In11.Cu")
		(net "M_J_DQ<61>")
	)
	(segment
		(start 141.822678 -32.063944)
		(end 142.081504 -31.805118)
		(width 0.14224)
		(layer "In11.Cu")
		(net "M_J_DQ<61>")
	)
	(segment
		(start 142.77721 -32.09925)
		(end 143.03629 -31.84017)
		(width 0.14224)
		(layer "In11.Cu")
		(net "M_J_DQ<61>")
	)
	(segment
		(start 119.873014 -62.549278)
		(end 119.869712 -62.543436)
		(width 0.0889)
		(layer "In11.Cu")
		(net "M_J_DQ<61>")
	)
	(segment
		(start 119.876062 -59.58205)
		(end 119.869712 -59.571382)
		(width 0.0889)
		(layer "In11.Cu")
		(net "M_J_DQ<61>")
	)
	(segment
		(start 143.631158 1.5494)
		(end 143.320262 1.5494)
		(width 0.14224)
		(layer "In11.Cu")
		(net "M_J_DQ<61>")
	)
	(segment
		(start 119.99976 -52.856892)
		(end 119.99976 -50.661824)
		(width 0.0889)
		(layer "In11.Cu")
		(net "M_J_DQ<61>")
	)
	(segment
		(start 120.216168 -64.324738)
		(end 120.3833 -63.9064)
		(width 0.0889)
		(layer "In11.Cu")
		(net "M_J_DQ<61>")
	)
	(segment
		(start 142.749524 2.120138)
		(end 142.749524 2.514854)
		(width 0.14224)
		(layer "In11.Cu")
		(net "M_J_DQ<61>")
	)
	(segment
		(start 142.742666 -31.143956)
		(end 143.001492 -30.88513)
		(width 0.14224)
		(layer "In11.Cu")
		(net "M_J_DQ<61>")
	)
	(segment
		(start 143.914368 -4.83616)
		(end 143.048736 -3.970528)
		(width 0.14224)
		(layer "In11.Cu")
		(net "M_J_DQ<61>")
	)
	(segment
		(start 144.031462 0.7366)
		(end 144.031462 1.149096)
		(width 0.14224)
		(layer "In11.Cu")
		(net "M_J_DQ<61>")
	)
	(segment
		(start 119.878602 -56.615076)
		(end 119.869712 -56.599836)
		(width 0.0889)
		(layer "In11.Cu")
		(net "M_J_DQ<61>")
	)
	(segment
		(start 119.869712 -59.171586)
		(end 119.876062 -59.160918)
		(width 0.0889)
		(layer "In11.Cu")
		(net "M_J_DQ<61>")
	)
	(segment
		(start 122.210068 -48.4505)
		(end 125.931168 -44.7294)
		(width 0.14224)
		(layer "In11.Cu")
		(net "M_J_DQ<61>")
	)
	(segment
		(start 144.039336 -13.575284)
		(end 144.039336 -12.403328)
		(width 0.14224)
		(layer "In11.Cu")
		(net "M_J_DQ<61>")
	)
	(segment
		(start 143.954246 -9.488678)
		(end 143.954246 -8.944864)
		(width 0.14224)
		(layer "In11.Cu")
		(net "M_J_DQ<61>")
	)
	(segment
		(start 143.990568 -13.624052)
		(end 144.039336 -13.575284)
		(width 0.14224)
		(layer "In11.Cu")
		(net "M_J_DQ<61>")
	)
	(segment
		(start 143.954246 -8.944864)
		(end 143.996664 -8.902446)
		(width 0.14224)
		(layer "In11.Cu")
		(net "M_J_DQ<61>")
	)
	(segment
		(start 119.878602 -54.633876)
		(end 119.861584 -54.604412)
		(width 0.0889)
		(layer "In11.Cu")
		(net "M_J_DQ<61>")
	)
	(segment
		(start 125.931168 -44.7294)
		(end 129.157222 -44.7294)
		(width 0.14224)
		(layer "In11.Cu")
		(net "M_J_DQ<61>")
	)
	(segment
		(start 120.3833 -63.9064)
		(end 120.498362 -63.61811)
		(width 0.0889)
		(layer "In11.Cu")
		(net "M_J_DQ<61>")
	)
	(segment
		(start 143.996664 -7.327646)
		(end 143.914368 -7.24535)
		(width 0.14224)
		(layer "In11.Cu")
		(net "M_J_DQ<61>")
	)
	(segment
		(start 143.20266 -30.88513)
		(end 143.496538 -31.179008)
		(width 0.14224)
		(layer "In11.Cu")
		(net "M_J_DQ<61>")
	)
	(segment
		(start 143.954246 -11.695176)
		(end 144.098264 -11.551158)
		(width 0.14224)
		(layer "In11.Cu")
		(net "M_J_DQ<61>")
	)
	(segment
		(start 144.041368 -21.9456)
		(end 143.939768 -21.844)
		(width 0.14224)
		(layer "In11.Cu")
		(net "M_J_DQ<61>")
	)
	(arc
		(start 119.869712 -62.14364)
		(mid 119.948843 -61.848238)
		(end 119.869712 -61.552836)
		(width 0.0889)
		(layer "In11.Cu")
		(net "M_J_DQ<61>")
	)
	(arc
		(start 119.869712 -61.552836)
		(mid 119.816179 -61.352938)
		(end 119.869712 -61.15304)
		(width 0.0889)
		(layer "In11.Cu")
		(net "M_J_DQ<61>")
	)
	(arc
		(start 119.869712 -55.20944)
		(mid 119.948901 -54.922825)
		(end 119.878602 -54.633876)
		(width 0.0889)
		(layer "In11.Cu")
		(net "M_J_DQ<61>")
	)
	(arc
		(start 119.869712 -62.543436)
		(mid 119.816179 -62.343538)
		(end 119.869712 -62.14364)
		(width 0.0889)
		(layer "In11.Cu")
		(net "M_J_DQ<61>")
	)
	(arc
		(start 119.869712 -57.19064)
		(mid 119.948901 -56.904025)
		(end 119.878602 -56.615076)
		(width 0.0889)
		(layer "In11.Cu")
		(net "M_J_DQ<61>")
	)
	(arc
		(start 119.869712 -54.218586)
		(mid 119.928968 -54.075871)
		(end 119.949214 -53.922676)
		(width 0.0889)
		(layer "In11.Cu")
		(net "M_J_DQ<61>")
	)
	(arc
		(start 119.876062 -59.160918)
		(mid 119.94886 -58.870155)
		(end 119.869712 -58.581036)
		(width 0.0889)
		(layer "In11.Cu")
		(net "M_J_DQ<61>")
	)
	(arc
		(start 119.869712 -56.599836)
		(mid 119.816179 -56.399938)
		(end 119.869712 -56.20004)
		(width 0.0889)
		(layer "In11.Cu")
		(net "M_J_DQ<61>")
	)
	(arc
		(start 119.869712 -57.590436)
		(mid 119.816179 -57.390538)
		(end 119.869712 -57.19064)
		(width 0.0889)
		(layer "In11.Cu")
		(net "M_J_DQ<61>")
	)
	(arc
		(start 119.869712 -61.15304)
		(mid 119.948901 -60.866425)
		(end 119.878602 -60.577476)
		(width 0.0889)
		(layer "In11.Cu")
		(net "M_J_DQ<61>")
	)
	(arc
		(start 119.869712 -55.609236)
		(mid 119.816179 -55.409338)
		(end 119.869712 -55.20944)
		(width 0.0889)
		(layer "In11.Cu")
		(net "M_J_DQ<61>")
	)
	(arc
		(start 119.869712 -58.18124)
		(mid 119.948901 -57.894625)
		(end 119.878602 -57.605676)
		(width 0.0889)
		(layer "In11.Cu")
		(net "M_J_DQ<61>")
	)
	(arc
		(start 119.869712 -59.571382)
		(mid 119.816179 -59.371484)
		(end 119.869712 -59.171586)
		(width 0.0889)
		(layer "In11.Cu")
		(net "M_J_DQ<61>")
	)
	(arc
		(start 119.869712 -60.16244)
		(mid 119.949061 -59.873068)
		(end 119.876062 -59.58205)
		(width 0.0889)
		(layer "In11.Cu")
		(net "M_J_DQ<61>")
	)
	(arc
		(start 120.498362 -63.61811)
		(mid 120.615464 -63.305219)
		(end 120.45442 -63.012574)
		(width 0.0889)
		(layer "In11.Cu")
		(net "M_J_DQ<61>")
	)
	(arc
		(start 119.869712 -58.581036)
		(mid 119.816179 -58.381138)
		(end 119.869712 -58.18124)
		(width 0.0889)
		(layer "In11.Cu")
		(net "M_J_DQ<61>")
	)
	(arc
		(start 119.869712 -60.562236)
		(mid 119.816179 -60.362338)
		(end 119.869712 -60.16244)
		(width 0.0889)
		(layer "In11.Cu")
		(net "M_J_DQ<61>")
	)
	(arc
		(start 119.861584 -54.604412)
		(mid 119.816121 -54.410469)
		(end 119.869712 -54.218586)
		(width 0.0889)
		(layer "In11.Cu")
		(net "M_J_DQ<61>")
	)
	(arc
		(start 119.869712 -56.20004)
		(mid 119.948901 -55.913425)
		(end 119.878602 -55.624476)
		(width 0.0889)
		(layer "In11.Cu")
		(net "M_J_DQ<61>")
	)
	(arc
		(start 120.080278 -62.767464)
		(mid 119.963176 -62.671165)
		(end 119.873014 -62.549278)
		(width 0.0889)
		(layer "In11.Cu")
		(net "M_J_DQ<61>")
	)
	(segment
		(start 143.599408 -0.821182)
		(end 143.599408 0.510032)
		(width 0.1651)
		(layer "F.Cu")
		(net "M_J_DQ<60>")
	)
	(segment
		(start 143.599408 0.510032)
		(end 143.501364 1.0414)
		(width 0.1651)
		(layer "F.Cu")
		(net "M_J_DQ<60>")
	)
	(segment
		(start 120.216168 -63.334138)
		(end 120.787668 -63.334138)
		(width 0.0889)
		(layer "F.Cu")
		(net "M_J_DQ<60>")
	)
	(via
		(at 120.216168 -63.334138)
		(size 0.508)
		(drill 0.254)
		(layers "F.Cu" "B.Cu")
		(net "M_J_DQ<60>")
	)
	(via
		(at 142.714472 -4.322826)
		(size 0.508)
		(drill 0.254)
		(layers "F.Cu" "B.Cu")
		(net "M_J_DQ<60>")
	)
	(via
		(at 143.501364 1.0414)
		(size 0.508)
		(drill 0.254)
		(layers "F.Cu" "B.Cu")
		(net "M_J_DQ<60>")
	)
	(segment
		(start 142.749524 -5.621782)
		(end 142.749524 -4.357878)
		(width 0.1651)
		(layer "B.Cu")
		(net "M_J_DQ<60>")
	)
	(segment
		(start 142.749524 -4.357878)
		(end 142.714472 -4.322826)
		(width 0.1651)
		(layer "B.Cu")
		(net "M_J_DQ<60>")
	)
	(segment
		(start 143.067532 -6.671564)
		(end 143.067532 -6.384036)
		(width 0.14224)
		(layer "In11.Cu")
		(net "M_J_DQ<60>")
	)
	(segment
		(start 143.225012 0.765048)
		(end 143.501364 1.0414)
		(width 0.14224)
		(layer "In11.Cu")
		(net "M_J_DQ<60>")
	)
	(segment
		(start 119.80926 -52.777898)
		(end 119.80926 -50.58283)
		(width 0.0889)
		(layer "In11.Cu")
		(net "M_J_DQ<60>")
	)
	(segment
		(start 143.304768 -18.8976)
		(end 143.304768 -18.63471)
		(width 0.14224)
		(layer "In11.Cu")
		(net "M_J_DQ<60>")
	)
	(segment
		(start 119.708422 -62.646052)
		(end 119.704358 -62.63894)
		(width 0.0889)
		(layer "In11.Cu")
		(net "M_J_DQ<60>")
	)
	(segment
		(start 143.24203 -1.0668)
		(end 143.24203 -0.762)
		(width 0.14224)
		(layer "In11.Cu")
		(net "M_J_DQ<60>")
	)
	(segment
		(start 143.253968 -7.213854)
		(end 143.253968 -6.858)
		(width 0.14224)
		(layer "In11.Cu")
		(net "M_J_DQ<60>")
	)
	(segment
		(start 143.253968 -6.858)
		(end 143.067532 -6.671564)
		(width 0.14224)
		(layer "In11.Cu")
		(net "M_J_DQ<60>")
	)
	(segment
		(start 119.757952 -52.829206)
		(end 119.80926 -52.777898)
		(width 0.0889)
		(layer "In11.Cu")
		(net "M_J_DQ<60>")
	)
	(segment
		(start 143.304768 -23.333456)
		(end 143.120364 -23.149052)
		(width 0.14224)
		(layer "In11.Cu")
		(net "M_J_DQ<60>")
	)
	(segment
		(start 143.279368 -4.887722)
		(end 142.714472 -4.322826)
		(width 0.14224)
		(layer "In11.Cu")
		(net "M_J_DQ<60>")
	)
	(segment
		(start 143.120364 -21.938996)
		(end 143.304768 -21.754592)
		(width 0.14224)
		(layer "In11.Cu")
		(net "M_J_DQ<60>")
	)
	(segment
		(start 143.120364 -23.149052)
		(end 143.120364 -21.938996)
		(width 0.14224)
		(layer "In11.Cu")
		(net "M_J_DQ<60>")
	)
	(segment
		(start 143.050768 -5.439156)
		(end 143.279368 -5.210556)
		(width 0.14224)
		(layer "In11.Cu")
		(net "M_J_DQ<60>")
	)
	(segment
		(start 143.225012 -2.141728)
		(end 142.87373 -1.790446)
		(width 0.14224)
		(layer "In11.Cu")
		(net "M_J_DQ<60>")
	)
	(segment
		(start 143.249904 -6.201664)
		(end 143.249904 -5.914136)
		(width 0.14224)
		(layer "In11.Cu")
		(net "M_J_DQ<60>")
	)
	(segment
		(start 143.24203 -0.762)
		(end 142.86103 -0.381)
		(width 0.14224)
		(layer "In11.Cu")
		(net "M_J_DQ<60>")
	)
	(segment
		(start 119.704358 -56.695086)
		(end 119.695468 -56.679846)
		(width 0.0889)
		(layer "In11.Cu")
		(net "M_J_DQ<60>")
	)
	(segment
		(start 143.304768 -9.4742)
		(end 143.304768 -8.99795)
		(width 0.14224)
		(layer "In11.Cu")
		(net "M_J_DQ<60>")
	)
	(segment
		(start 129.817368 -40.65524)
		(end 129.959608 -40.513)
		(width 0.14224)
		(layer "In11.Cu")
		(net "M_J_DQ<60>")
	)
	(segment
		(start 143.018764 -17.075658)
		(end 143.330168 -16.764254)
		(width 0.14224)
		(layer "In11.Cu")
		(net "M_J_DQ<60>")
	)
	(segment
		(start 130.708654 -41.7322)
		(end 131.074414 -41.7322)
		(width 0.14224)
		(layer "In11.Cu")
		(net "M_J_DQ<60>")
	)
	(segment
		(start 143.018764 -18.348706)
		(end 143.018764 -17.075658)
		(width 0.14224)
		(layer "In11.Cu")
		(net "M_J_DQ<60>")
	)
	(segment
		(start 143.304768 -8.99795)
		(end 143.018764 -8.711946)
		(width 0.14224)
		(layer "In11.Cu")
		(net "M_J_DQ<60>")
	)
	(segment
		(start 143.304768 -21.4122)
		(end 143.101568 -21.209)
		(width 0.14224)
		(layer "In11.Cu")
		(net "M_J_DQ<60>")
	)
	(segment
		(start 133.272022 -39.9542)
		(end 143.455136 -29.771086)
		(width 0.14224)
		(layer "In11.Cu")
		(net "M_J_DQ<60>")
	)
	(segment
		(start 143.249904 -5.914136)
		(end 143.050768 -5.715)
		(width 0.14224)
		(layer "In11.Cu")
		(net "M_J_DQ<60>")
	)
	(segment
		(start 143.126968 -11.557)
		(end 143.126968 -9.652)
		(width 0.14224)
		(layer "In11.Cu")
		(net "M_J_DQ<60>")
	)
	(segment
		(start 143.053308 -13.6017)
		(end 143.053308 -12.44346)
		(width 0.14224)
		(layer "In11.Cu")
		(net "M_J_DQ<60>")
	)
	(segment
		(start 143.053308 -12.44346)
		(end 143.304768 -12.192)
		(width 0.14224)
		(layer "In11.Cu")
		(net "M_J_DQ<60>")
	)
	(segment
		(start 143.101568 -19.1008)
		(end 143.304768 -18.8976)
		(width 0.14224)
		(layer "In11.Cu")
		(net "M_J_DQ<60>")
	)
	(segment
		(start 119.704358 -55.704486)
		(end 119.695468 -55.689246)
		(width 0.0889)
		(layer "In11.Cu")
		(net "M_J_DQ<60>")
	)
	(segment
		(start 142.87373 -1.790446)
		(end 142.87373 -1.4351)
		(width 0.14224)
		(layer "In11.Cu")
		(net "M_J_DQ<60>")
	)
	(segment
		(start 119.757952 -53.922676)
		(end 119.757952 -52.829206)
		(width 0.0889)
		(layer "In11.Cu")
		(net "M_J_DQ<60>")
	)
	(segment
		(start 130.566414 -40.65524)
		(end 130.566414 -41.58996)
		(width 0.14224)
		(layer "In11.Cu")
		(net "M_J_DQ<60>")
	)
	(segment
		(start 142.513812 -4.122166)
		(end 142.513812 -3.327654)
		(width 0.14224)
		(layer "In11.Cu")
		(net "M_J_DQ<60>")
	)
	(segment
		(start 143.225012 -2.616454)
		(end 143.225012 -2.141728)
		(width 0.14224)
		(layer "In11.Cu")
		(net "M_J_DQ<60>")
	)
	(segment
		(start 121.867168 -48.133)
		(end 121.867168 -48.006)
		(width 0.14224)
		(layer "In11.Cu")
		(net "M_J_DQ<60>")
	)
	(segment
		(start 130.424174 -40.513)
		(end 130.566414 -40.65524)
		(width 0.14224)
		(layer "In11.Cu")
		(net "M_J_DQ<60>")
	)
	(segment
		(start 119.80926 -50.58283)
		(end 121.816368 -48.575722)
		(width 0.0889)
		(layer "In11.Cu")
		(net "M_J_DQ<60>")
	)
	(segment
		(start 143.018764 -8.711946)
		(end 143.018764 -7.449058)
		(width 0.14224)
		(layer "In11.Cu")
		(net "M_J_DQ<60>")
	)
	(segment
		(start 143.304768 -11.7348)
		(end 143.126968 -11.557)
		(width 0.14224)
		(layer "In11.Cu")
		(net "M_J_DQ<60>")
	)
	(segment
		(start 131.074414 -41.7322)
		(end 131.216654 -41.58996)
		(width 0.14224)
		(layer "In11.Cu")
		(net "M_J_DQ<60>")
	)
	(segment
		(start 143.279368 -5.210556)
		(end 143.279368 -4.887722)
		(width 0.14224)
		(layer "In11.Cu")
		(net "M_J_DQ<60>")
	)
	(segment
		(start 128.065022 -44.2214)
		(end 129.817368 -42.469054)
		(width 0.14224)
		(layer "In11.Cu")
		(net "M_J_DQ<60>")
	)
	(segment
		(start 131.216654 -40.09644)
		(end 131.358894 -39.9542)
		(width 0.14224)
		(layer "In11.Cu")
		(net "M_J_DQ<60>")
	)
	(segment
		(start 129.817368 -42.469054)
		(end 129.817368 -40.65524)
		(width 0.14224)
		(layer "In11.Cu")
		(net "M_J_DQ<60>")
	)
	(segment
		(start 143.126968 -9.652)
		(end 143.304768 -9.4742)
		(width 0.14224)
		(layer "In11.Cu")
		(net "M_J_DQ<60>")
	)
	(segment
		(start 142.86103 -0.381)
		(end 142.86103 -0.076454)
		(width 0.14224)
		(layer "In11.Cu")
		(net "M_J_DQ<60>")
	)
	(segment
		(start 143.330168 -13.87856)
		(end 143.053308 -13.6017)
		(width 0.14224)
		(layer "In11.Cu")
		(net "M_J_DQ<60>")
	)
	(segment
		(start 143.455136 -29.771086)
		(end 143.455136 -26.388568)
		(width 0.14224)
		(layer "In11.Cu")
		(net "M_J_DQ<60>")
	)
	(segment
		(start 143.304768 -12.192)
		(end 143.304768 -11.7348)
		(width 0.14224)
		(layer "In11.Cu")
		(net "M_J_DQ<60>")
	)
	(segment
		(start 121.816368 -48.575722)
		(end 121.816368 -48.1838)
		(width 0.0889)
		(layer "In11.Cu")
		(net "M_J_DQ<60>")
	)
	(segment
		(start 143.304768 -18.63471)
		(end 143.018764 -18.348706)
		(width 0.14224)
		(layer "In11.Cu")
		(net "M_J_DQ<60>")
	)
	(segment
		(start 143.455136 -26.388568)
		(end 143.304768 -26.2382)
		(width 0.14224)
		(layer "In11.Cu")
		(net "M_J_DQ<60>")
	)
	(segment
		(start 143.050768 -5.715)
		(end 143.050768 -5.439156)
		(width 0.14224)
		(layer "In11.Cu")
		(net "M_J_DQ<60>")
	)
	(segment
		(start 119.704358 -58.67654)
		(end 119.698008 -58.665872)
		(width 0.0889)
		(layer "In11.Cu")
		(net "M_J_DQ<60>")
	)
	(segment
		(start 129.959608 -40.513)
		(end 130.424174 -40.513)
		(width 0.14224)
		(layer "In11.Cu")
		(net "M_J_DQ<60>")
	)
	(segment
		(start 142.714472 -4.322826)
		(end 142.513812 -4.122166)
		(width 0.14224)
		(layer "In11.Cu")
		(net "M_J_DQ<60>")
	)
	(segment
		(start 143.330168 -16.764254)
		(end 143.330168 -13.87856)
		(width 0.14224)
		(layer "In11.Cu")
		(net "M_J_DQ<60>")
	)
	(segment
		(start 143.225012 0.287528)
		(end 143.225012 0.765048)
		(width 0.14224)
		(layer "In11.Cu")
		(net "M_J_DQ<60>")
	)
	(segment
		(start 143.101568 -21.209)
		(end 143.101568 -19.1008)
		(width 0.14224)
		(layer "In11.Cu")
		(net "M_J_DQ<60>")
	)
	(segment
		(start 142.87373 -1.4351)
		(end 143.24203 -1.0668)
		(width 0.14224)
		(layer "In11.Cu")
		(net "M_J_DQ<60>")
	)
	(segment
		(start 119.704358 -60.657486)
		(end 119.695468 -60.642246)
		(width 0.0889)
		(layer "In11.Cu")
		(net "M_J_DQ<60>")
	)
	(segment
		(start 125.651768 -44.2214)
		(end 128.065022 -44.2214)
		(width 0.14224)
		(layer "In11.Cu")
		(net "M_J_DQ<60>")
	)
	(segment
		(start 131.358894 -39.9542)
		(end 133.272022 -39.9542)
		(width 0.14224)
		(layer "In11.Cu")
		(net "M_J_DQ<60>")
	)
	(segment
		(start 143.018764 -7.449058)
		(end 143.253968 -7.213854)
		(width 0.14224)
		(layer "In11.Cu")
		(net "M_J_DQ<60>")
	)
	(segment
		(start 142.86103 -0.076454)
		(end 143.225012 0.287528)
		(width 0.14224)
		(layer "In11.Cu")
		(net "M_J_DQ<60>")
	)
	(segment
		(start 119.704358 -54.713886)
		(end 119.69369 -54.695344)
		(width 0.0889)
		(layer "In11.Cu")
		(net "M_J_DQ<60>")
	)
	(segment
		(start 143.304768 -26.2382)
		(end 143.304768 -23.333456)
		(width 0.14224)
		(layer "In11.Cu")
		(net "M_J_DQ<60>")
	)
	(segment
		(start 143.067532 -6.384036)
		(end 143.249904 -6.201664)
		(width 0.14224)
		(layer "In11.Cu")
		(net "M_J_DQ<60>")
	)
	(segment
		(start 120.216168 -63.334138)
		(end 120.157494 -63.270892)
		(width 0.0889)
		(layer "In11.Cu")
		(net "M_J_DQ<60>")
	)
	(segment
		(start 121.816368 -48.1838)
		(end 121.867168 -48.133)
		(width 0.0889)
		(layer "In11.Cu")
		(net "M_J_DQ<60>")
	)
	(segment
		(start 142.513812 -3.327654)
		(end 143.225012 -2.616454)
		(width 0.14224)
		(layer "In11.Cu")
		(net "M_J_DQ<60>")
	)
	(segment
		(start 119.698008 -59.087004)
		(end 119.704358 -59.076336)
		(width 0.0889)
		(layer "In11.Cu")
		(net "M_J_DQ<60>")
	)
	(segment
		(start 143.304768 -21.754592)
		(end 143.304768 -21.4122)
		(width 0.14224)
		(layer "In11.Cu")
		(net "M_J_DQ<60>")
	)
	(segment
		(start 121.867168 -48.006)
		(end 125.651768 -44.2214)
		(width 0.14224)
		(layer "In11.Cu")
		(net "M_J_DQ<60>")
	)
	(segment
		(start 130.566414 -41.58996)
		(end 130.708654 -41.7322)
		(width 0.14224)
		(layer "In11.Cu")
		(net "M_J_DQ<60>")
	)
	(segment
		(start 131.216654 -41.58996)
		(end 131.216654 -40.09644)
		(width 0.14224)
		(layer "In11.Cu")
		(net "M_J_DQ<60>")
	)
	(segment
		(start 119.704358 -57.685686)
		(end 119.695468 -57.670446)
		(width 0.0889)
		(layer "In11.Cu")
		(net "M_J_DQ<60>")
	)
	(arc
		(start 119.704358 -56.104282)
		(mid 119.757891 -55.904384)
		(end 119.704358 -55.704486)
		(width 0.0889)
		(layer "In11.Cu")
		(net "M_J_DQ<60>")
	)
	(arc
		(start 119.704358 -60.066682)
		(mid 119.757891 -59.866784)
		(end 119.704358 -59.666886)
		(width 0.0889)
		(layer "In11.Cu")
		(net "M_J_DQ<60>")
	)
	(arc
		(start 119.704358 -62.048136)
		(mid 119.757891 -61.848238)
		(end 119.704358 -61.64834)
		(width 0.0889)
		(layer "In11.Cu")
		(net "M_J_DQ<60>")
	)
	(arc
		(start 119.704358 -58.085482)
		(mid 119.757891 -57.885584)
		(end 119.704358 -57.685686)
		(width 0.0889)
		(layer "In11.Cu")
		(net "M_J_DQ<60>")
	)
	(arc
		(start 119.704358 -61.057282)
		(mid 119.757891 -60.857384)
		(end 119.704358 -60.657486)
		(width 0.0889)
		(layer "In11.Cu")
		(net "M_J_DQ<60>")
	)
	(arc
		(start 119.695468 -60.642246)
		(mid 119.625071 -60.353295)
		(end 119.704358 -60.066682)
		(width 0.0889)
		(layer "In11.Cu")
		(net "M_J_DQ<60>")
	)
	(arc
		(start 119.704358 -54.122828)
		(mid 119.74437 -54.026286)
		(end 119.757952 -53.922676)
		(width 0.0889)
		(layer "In11.Cu")
		(net "M_J_DQ<60>")
	)
	(arc
		(start 119.695468 -57.670446)
		(mid 119.625071 -57.381495)
		(end 119.704358 -57.094882)
		(width 0.0889)
		(layer "In11.Cu")
		(net "M_J_DQ<60>")
	)
	(arc
		(start 120.157494 -63.270892)
		(mid 119.917347 -62.969691)
		(end 119.708422 -62.646052)
		(width 0.0889)
		(layer "In11.Cu")
		(net "M_J_DQ<60>")
	)
	(arc
		(start 119.704358 -57.094882)
		(mid 119.757891 -56.894984)
		(end 119.704358 -56.695086)
		(width 0.0889)
		(layer "In11.Cu")
		(net "M_J_DQ<60>")
	)
	(arc
		(start 119.704358 -61.64834)
		(mid 119.625295 -61.352828)
		(end 119.704358 -61.057282)
		(width 0.0889)
		(layer "In11.Cu")
		(net "M_J_DQ<60>")
	)
	(arc
		(start 119.704358 -55.113682)
		(mid 119.757891 -54.913784)
		(end 119.704358 -54.713886)
		(width 0.0889)
		(layer "In11.Cu")
		(net "M_J_DQ<60>")
	)
	(arc
		(start 119.69369 -54.695344)
		(mid 119.625091 -54.40771)
		(end 119.704358 -54.122828)
		(width 0.0889)
		(layer "In11.Cu")
		(net "M_J_DQ<60>")
	)
	(arc
		(start 119.695468 -56.679846)
		(mid 119.625071 -56.390895)
		(end 119.704358 -56.104282)
		(width 0.0889)
		(layer "In11.Cu")
		(net "M_J_DQ<60>")
	)
	(arc
		(start 119.698008 -58.665872)
		(mid 119.625088 -58.374855)
		(end 119.704358 -58.085482)
		(width 0.0889)
		(layer "In11.Cu")
		(net "M_J_DQ<60>")
	)
	(arc
		(start 119.695468 -55.689246)
		(mid 119.625071 -55.400295)
		(end 119.704358 -55.113682)
		(width 0.0889)
		(layer "In11.Cu")
		(net "M_J_DQ<60>")
	)
	(arc
		(start 119.704358 -59.666886)
		(mid 119.625136 -59.377768)
		(end 119.698008 -59.087004)
		(width 0.0889)
		(layer "In11.Cu")
		(net "M_J_DQ<60>")
	)
	(arc
		(start 119.704358 -59.076336)
		(mid 119.757891 -58.876438)
		(end 119.704358 -58.67654)
		(width 0.0889)
		(layer "In11.Cu")
		(net "M_J_DQ<60>")
	)
	(arc
		(start 119.704358 -62.63894)
		(mid 119.625227 -62.343538)
		(end 119.704358 -62.048136)
		(width 0.0889)
		(layer "In11.Cu")
		(net "M_J_DQ<60>")
	)
	(segment
		(start 78.051406 -66.48704)
		(end 77.479906 -66.48704)
		(width 0.0889)
		(layer "F.Cu")
		(net "M_J_DQ<5>")
	)
	(segment
		(start 31.39948 3.778758)
		(end 31.39948 2.514854)
		(width 0.1651)
		(layer "F.Cu")
		(net "M_J_DQ<5>")
	)
	(via
		(at 31.39948 2.514854)
		(size 0.508)
		(drill 0.254)
		(layers "F.Cu" "B.Cu")
		(net "M_J_DQ<5>")
	)
	(via
		(at 32.173164 -3.076956)
		(size 0.508)
		(drill 0.254)
		(layers "F.Cu" "B.Cu")
		(net "M_J_DQ<5>")
	)
	(via
		(at 77.479906 -66.48704)
		(size 0.508)
		(drill 0.254)
		(layers "F.Cu" "B.Cu")
		(net "M_J_DQ<5>")
	)
	(segment
		(start 32.249364 -3.000756)
		(end 32.249364 -1.021842)
		(width 0.1651)
		(layer "B.Cu")
		(net "M_J_DQ<5>")
	)
	(segment
		(start 32.173164 -3.076956)
		(end 32.249364 -3.000756)
		(width 0.1651)
		(layer "B.Cu")
		(net "M_J_DQ<5>")
	)
	(segment
		(start 32.713168 -9.6012)
		(end 32.713168 -11.6078)
		(width 0.14224)
		(layer "In11.Cu")
		(net "M_J_DQ<5>")
	)
	(segment
		(start 72.31761 -67.87769)
		(end 72.350376 -67.87769)
		(width 0.0889)
		(layer "In11.Cu")
		(net "M_J_DQ<5>")
	)
	(segment
		(start 32.58312 -13.681456)
		(end 32.58312 -16.4592)
		(width 0.14224)
		(layer "In11.Cu")
		(net "M_J_DQ<5>")
	)
	(segment
		(start 32.636968 -13.627608)
		(end 32.58312 -13.681456)
		(width 0.14224)
		(layer "In11.Cu")
		(net "M_J_DQ<5>")
	)
	(segment
		(start 76.65847 -66.582036)
		(end 77.479906 -66.48704)
		(width 0.0889)
		(layer "In11.Cu")
		(net "M_J_DQ<5>")
	)
	(segment
		(start 32.58312 -16.4592)
		(end 32.611568 -16.800576)
		(width 0.14224)
		(layer "In11.Cu")
		(net "M_J_DQ<5>")
	)
	(segment
		(start 66.397124 -67.08902)
		(end 66.599054 -66.88709)
		(width 0.0889)
		(layer "In11.Cu")
		(net "M_J_DQ<5>")
	)
	(segment
		(start 31.39948 2.514854)
		(end 31.39948 2.120138)
		(width 0.14224)
		(layer "In11.Cu")
		(net "M_J_DQ<5>")
	)
	(segment
		(start 32.173164 -3.076956)
		(end 31.697168 -3.552952)
		(width 0.14224)
		(layer "In11.Cu")
		(net "M_J_DQ<5>")
	)
	(segment
		(start 31.970218 1.5494)
		(end 32.281114 1.5494)
		(width 0.14224)
		(layer "In11.Cu")
		(net "M_J_DQ<5>")
	)
	(segment
		(start 68.018406 -66.391536)
		(end 68.053966 -66.391536)
		(width 0.0889)
		(layer "In11.Cu")
		(net "M_J_DQ<5>")
	)
	(segment
		(start 66.599054 -66.88709)
		(end 67.188842 -66.88709)
		(width 0.0889)
		(layer "In11.Cu")
		(net "M_J_DQ<5>")
	)
	(segment
		(start 32.55772 -21.336)
		(end 32.55772 -21.5646)
		(width 0.14224)
		(layer "In11.Cu")
		(net "M_J_DQ<5>")
	)
	(segment
		(start 76.23556 -66.850006)
		(end 76.274676 -66.782188)
		(width 0.0889)
		(layer "In11.Cu")
		(net "M_J_DQ<5>")
	)
	(segment
		(start 74.886566 -68.372736)
		(end 74.919332 -68.372736)
		(width 0.0889)
		(layer "In11.Cu")
		(net "M_J_DQ<5>")
	)
	(segment
		(start 32.611568 -21.282152)
		(end 32.55772 -21.336)
		(width 0.14224)
		(layer "In11.Cu")
		(net "M_J_DQ<5>")
	)
	(segment
		(start 76.162408 -67.454018)
		(end 76.183744 -67.074542)
		(width 0.0889)
		(layer "In11.Cu")
		(net "M_J_DQ<5>")
	)
	(segment
		(start 32.484568 0.53975)
		(end 32.484568 -2.765552)
		(width 0.14224)
		(layer "In11.Cu")
		(net "M_J_DQ<5>")
	)
	(segment
		(start 76.61021 -66.582036)
		(end 76.65847 -66.582036)
		(width 0.0889)
		(layer "In11.Cu")
		(net "M_J_DQ<5>")
	)
	(segment
		(start 66.133472 -67.08902)
		(end 66.397124 -67.08902)
		(width 0.0889)
		(layer "In11.Cu")
		(net "M_J_DQ<5>")
	)
	(segment
		(start 32.611568 -9.4996)
		(end 32.713168 -9.6012)
		(width 0.14224)
		(layer "In11.Cu")
		(net "M_J_DQ<5>")
	)
	(segment
		(start 32.509968 -23.66264)
		(end 32.509968 -39.114222)
		(width 0.14224)
		(layer "In11.Cu")
		(net "M_J_DQ<5>")
	)
	(segment
		(start 69.735446 -66.391536)
		(end 69.771006 -66.391536)
		(width 0.0889)
		(layer "In11.Cu")
		(net "M_J_DQ<5>")
	)
	(segment
		(start 76.183744 -67.074542)
		(end 76.23556 -66.850006)
		(width 0.0889)
		(layer "In11.Cu")
		(net "M_J_DQ<5>")
	)
	(segment
		(start 32.509968 -39.114222)
		(end 36.740084 -43.344338)
		(width 0.14224)
		(layer "In11.Cu")
		(net "M_J_DQ<5>")
	)
	(segment
		(start 32.681418 1.149096)
		(end 32.681418 0.7366)
		(width 0.14224)
		(layer "In11.Cu")
		(net "M_J_DQ<5>")
	)
	(segment
		(start 32.64662 -22.95144)
		(end 32.509968 -23.66264)
		(width 0.14224)
		(layer "In11.Cu")
		(net "M_J_DQ<5>")
	)
	(segment
		(start 75.741276 -67.87769)
		(end 75.774042 -67.87769)
		(width 0.0889)
		(layer "In11.Cu")
		(net "M_J_DQ<5>")
	)
	(segment
		(start 32.611568 -16.800576)
		(end 32.611568 -21.282152)
		(width 0.14224)
		(layer "In11.Cu")
		(net "M_J_DQ<5>")
	)
	(segment
		(start 31.697168 -3.969004)
		(end 31.967932 -4.239768)
		(width 0.14224)
		(layer "In11.Cu")
		(net "M_J_DQ<5>")
	)
	(segment
		(start 32.713168 -11.6078)
		(end 32.586168 -11.7348)
		(width 0.14224)
		(layer "In11.Cu")
		(net "M_J_DQ<5>")
	)
	(segment
		(start 32.611568 -7.151624)
		(end 32.611568 -9.4996)
		(width 0.14224)
		(layer "In11.Cu")
		(net "M_J_DQ<5>")
	)
	(segment
		(start 32.636968 -12.351004)
		(end 32.636968 -13.627608)
		(width 0.14224)
		(layer "In11.Cu")
		(net "M_J_DQ<5>")
	)
	(segment
		(start 32.484568 -2.765552)
		(end 32.173164 -3.076956)
		(width 0.14224)
		(layer "In11.Cu")
		(net "M_J_DQ<5>")
	)
	(segment
		(start 60.484766 -67.08902)
		(end 66.133472 -67.08902)
		(width 0.14224)
		(layer "In11.Cu")
		(net "M_J_DQ<5>")
	)
	(segment
		(start 32.681418 0.7366)
		(end 32.484568 0.53975)
		(width 0.14224)
		(layer "In11.Cu")
		(net "M_J_DQ<5>")
	)
	(segment
		(start 37.321744 -43.344338)
		(end 37.463984 -43.486578)
		(width 0.14224)
		(layer "In11.Cu")
		(net "M_J_DQ<5>")
	)
	(segment
		(start 32.281114 1.5494)
		(end 32.681418 1.149096)
		(width 0.14224)
		(layer "In11.Cu")
		(net "M_J_DQ<5>")
	)
	(segment
		(start 73.17232 -68.372736)
		(end 73.205086 -68.372736)
		(width 0.0889)
		(layer "In11.Cu")
		(net "M_J_DQ<5>")
	)
	(segment
		(start 32.55772 -21.5646)
		(end 32.64662 -22.225)
		(width 0.14224)
		(layer "In11.Cu")
		(net "M_J_DQ<5>")
	)
	(segment
		(start 37.463984 -44.068238)
		(end 60.484766 -67.08902)
		(width 0.14224)
		(layer "In11.Cu")
		(net "M_J_DQ<5>")
	)
	(segment
		(start 71.45528 -67.382136)
		(end 71.488046 -67.382136)
		(width 0.0889)
		(layer "In11.Cu")
		(net "M_J_DQ<5>")
	)
	(segment
		(start 32.586168 -12.300204)
		(end 32.636968 -12.351004)
		(width 0.14224)
		(layer "In11.Cu")
		(net "M_J_DQ<5>")
	)
	(segment
		(start 31.39948 2.120138)
		(end 31.970218 1.5494)
		(width 0.14224)
		(layer "In11.Cu")
		(net "M_J_DQ<5>")
	)
	(segment
		(start 31.697168 -3.552952)
		(end 31.697168 -3.969004)
		(width 0.14224)
		(layer "In11.Cu")
		(net "M_J_DQ<5>")
	)
	(segment
		(start 36.740084 -43.344338)
		(end 37.321744 -43.344338)
		(width 0.14224)
		(layer "In11.Cu")
		(net "M_J_DQ<5>")
	)
	(segment
		(start 32.586168 -11.7348)
		(end 32.586168 -12.300204)
		(width 0.14224)
		(layer "In11.Cu")
		(net "M_J_DQ<5>")
	)
	(segment
		(start 32.64662 -22.225)
		(end 32.64662 -22.95144)
		(width 0.14224)
		(layer "In11.Cu")
		(net "M_J_DQ<5>")
	)
	(segment
		(start 70.60057 -66.88709)
		(end 70.633336 -66.88709)
		(width 0.0889)
		(layer "In11.Cu")
		(net "M_J_DQ<5>")
	)
	(segment
		(start 37.463984 -43.486578)
		(end 37.463984 -44.068238)
		(width 0.14224)
		(layer "In11.Cu")
		(net "M_J_DQ<5>")
	)
	(segment
		(start 31.967932 -4.239768)
		(end 32.611568 -7.151624)
		(width 0.14224)
		(layer "In11.Cu")
		(net "M_J_DQ<5>")
	)
	(arc
		(start 70.633336 -66.88709)
		(mid 70.916553 -66.971371)
		(end 71.123556 -67.182238)
		(width 0.0889)
		(layer "In11.Cu")
		(net "M_J_DQ<5>")
	)
	(arc
		(start 72.350376 -67.87769)
		(mid 72.633593 -67.961971)
		(end 72.840596 -68.172838)
		(width 0.0889)
		(layer "In11.Cu")
		(net "M_J_DQ<5>")
	)
	(arc
		(start 71.488046 -67.382136)
		(mid 71.77347 -67.465603)
		(end 71.982076 -67.677538)
		(width 0.0889)
		(layer "In11.Cu")
		(net "M_J_DQ<5>")
	)
	(arc
		(start 75.251056 -68.172838)
		(mid 75.45806 -67.961974)
		(end 75.741276 -67.87769)
		(width 0.0889)
		(layer "In11.Cu")
		(net "M_J_DQ<5>")
	)
	(arc
		(start 69.771006 -66.391536)
		(mid 70.05643 -66.475003)
		(end 70.265036 -66.686938)
		(width 0.0889)
		(layer "In11.Cu")
		(net "M_J_DQ<5>")
	)
	(arc
		(start 76.274676 -66.782188)
		(mid 76.416359 -66.638384)
		(end 76.61021 -66.582036)
		(width 0.0889)
		(layer "In11.Cu")
		(net "M_J_DQ<5>")
	)
	(arc
		(start 72.840596 -68.172838)
		(mid 72.980675 -68.315574)
		(end 73.17232 -68.372736)
		(width 0.0889)
		(layer "In11.Cu")
		(net "M_J_DQ<5>")
	)
	(arc
		(start 68.053966 -66.391536)
		(mid 68.33939 -66.475003)
		(end 68.547996 -66.686938)
		(width 0.0889)
		(layer "In11.Cu")
		(net "M_J_DQ<5>")
	)
	(arc
		(start 73.699116 -68.668138)
		(mid 74.045826 -68.868449)
		(end 74.392536 -68.668138)
		(width 0.0889)
		(layer "In11.Cu")
		(net "M_J_DQ<5>")
	)
	(arc
		(start 68.547996 -66.686938)
		(mid 68.894706 -66.887249)
		(end 69.241416 -66.686938)
		(width 0.0889)
		(layer "In11.Cu")
		(net "M_J_DQ<5>")
	)
	(arc
		(start 67.188842 -66.88709)
		(mid 67.382692 -66.83074)
		(end 67.524376 -66.686938)
		(width 0.0889)
		(layer "In11.Cu")
		(net "M_J_DQ<5>")
	)
	(arc
		(start 74.392536 -68.668138)
		(mid 74.601144 -68.456206)
		(end 74.886566 -68.372736)
		(width 0.0889)
		(layer "In11.Cu")
		(net "M_J_DQ<5>")
	)
	(arc
		(start 70.265036 -66.686938)
		(mid 70.406719 -66.830742)
		(end 70.60057 -66.88709)
		(width 0.0889)
		(layer "In11.Cu")
		(net "M_J_DQ<5>")
	)
	(arc
		(start 73.205086 -68.372736)
		(mid 73.49051 -68.456203)
		(end 73.699116 -68.668138)
		(width 0.0889)
		(layer "In11.Cu")
		(net "M_J_DQ<5>")
	)
	(arc
		(start 74.919332 -68.372736)
		(mid 75.110974 -68.31557)
		(end 75.251056 -68.172838)
		(width 0.0889)
		(layer "In11.Cu")
		(net "M_J_DQ<5>")
	)
	(arc
		(start 69.241416 -66.686938)
		(mid 69.450024 -66.475006)
		(end 69.735446 -66.391536)
		(width 0.0889)
		(layer "In11.Cu")
		(net "M_J_DQ<5>")
	)
	(arc
		(start 75.774042 -67.87769)
		(mid 76.057891 -67.748057)
		(end 76.162408 -67.454018)
		(width 0.0889)
		(layer "In11.Cu")
		(net "M_J_DQ<5>")
	)
	(arc
		(start 67.524376 -66.686938)
		(mid 67.732984 -66.475006)
		(end 68.018406 -66.391536)
		(width 0.0889)
		(layer "In11.Cu")
		(net "M_J_DQ<5>")
	)
	(arc
		(start 71.123556 -67.182238)
		(mid 71.263635 -67.324974)
		(end 71.45528 -67.382136)
		(width 0.0889)
		(layer "In11.Cu")
		(net "M_J_DQ<5>")
	)
	(arc
		(start 71.982076 -67.677538)
		(mid 72.123759 -67.821342)
		(end 72.31761 -67.87769)
		(width 0.0889)
		(layer "In11.Cu")
		(net "M_J_DQ<5>")
	)
	(segment
		(start 124.221748 -64.324738)
		(end 123.650248 -64.324738)
		(width 0.0889)
		(layer "F.Cu")
		(net "M_J_DQ<59>")
	)
	(segment
		(start 150.399496 3.778758)
		(end 150.399496 2.514854)
		(width 0.1651)
		(layer "F.Cu")
		(net "M_J_DQ<59>")
	)
	(via
		(at 150.399496 2.514854)
		(size 0.508)
		(drill 0.254)
		(layers "F.Cu" "B.Cu")
		(net "M_J_DQ<59>")
	)
	(via
		(at 151.24938 -3.076956)
		(size 0.508)
		(drill 0.254)
		(layers "F.Cu" "B.Cu")
		(net "M_J_DQ<59>")
	)
	(via
		(at 123.650248 -64.324738)
		(size 0.508)
		(drill 0.254)
		(layers "F.Cu" "B.Cu")
		(net "M_J_DQ<59>")
	)
	(segment
		(start 151.24938 -1.021842)
		(end 151.24938 -3.076956)
		(width 0.1651)
		(layer "B.Cu")
		(net "M_J_DQ<59>")
	)
	(segment
		(start 125.829568 -52.197)
		(end 127.150368 -50.8762)
		(width 0.14224)
		(layer "In11.Cu")
		(net "M_J_DQ<59>")
	)
	(segment
		(start 127.150368 -50.8762)
		(end 130.249168 -50.8762)
		(width 0.14224)
		(layer "In11.Cu")
		(net "M_J_DQ<59>")
	)
	(segment
		(start 151.781764 -23.183596)
		(end 151.781764 -21.999956)
		(width 0.14224)
		(layer "In11.Cu")
		(net "M_J_DQ<59>")
	)
	(segment
		(start 124.157232 -59.675522)
		(end 124.162058 -59.666886)
		(width 0.0889)
		(layer "In11.Cu")
		(net "M_J_DQ<59>")
	)
	(segment
		(start 151.737568 -19.1516)
		(end 151.603964 -19.017996)
		(width 0.14224)
		(layer "In11.Cu")
		(net "M_J_DQ<59>")
	)
	(segment
		(start 151.757634 1.0922)
		(end 151.300434 1.5494)
		(width 0.14224)
		(layer "In11.Cu")
		(net "M_J_DQ<59>")
	)
	(segment
		(start 124.157232 -54.722522)
		(end 124.162058 -54.713886)
		(width 0.0889)
		(layer "In11.Cu")
		(net "M_J_DQ<59>")
	)
	(segment
		(start 124.050298 -63.749174)
		(end 124.11583 -63.683642)
		(width 0.0889)
		(layer "In11.Cu")
		(net "M_J_DQ<59>")
	)
	(segment
		(start 135.786368 -45.339)
		(end 136.878568 -45.339)
		(width 0.14224)
		(layer "In11.Cu")
		(net "M_J_DQ<59>")
	)
	(segment
		(start 151.813768 -11.5316)
		(end 151.813768 -9.582404)
		(width 0.14224)
		(layer "In11.Cu")
		(net "M_J_DQ<59>")
	)
	(segment
		(start 151.813768 -9.582404)
		(end 151.603964 -9.3726)
		(width 0.14224)
		(layer "In11.Cu")
		(net "M_J_DQ<59>")
	)
	(segment
		(start 151.737568 -21.227796)
		(end 151.737568 -19.1516)
		(width 0.14224)
		(layer "In11.Cu")
		(net "M_J_DQ<59>")
	)
	(segment
		(start 123.650248 -64.324738)
		(end 123.941078 -63.9064)
		(width 0.0889)
		(layer "In11.Cu")
		(net "M_J_DQ<59>")
	)
	(segment
		(start 151.616664 -13.681456)
		(end 151.781764 -13.516356)
		(width 0.14224)
		(layer "In11.Cu")
		(net "M_J_DQ<59>")
	)
	(segment
		(start 124.162058 -57.685686)
		(end 124.168408 -57.675018)
		(width 0.0889)
		(layer "In11.Cu")
		(net "M_J_DQ<59>")
	)
	(segment
		(start 151.603964 -19.017996)
		(end 151.603964 -18.574258)
		(width 0.14224)
		(layer "In11.Cu")
		(net "M_J_DQ<59>")
	)
	(segment
		(start 151.603964 -21.3614)
		(end 151.737568 -21.227796)
		(width 0.14224)
		(layer "In11.Cu")
		(net "M_J_DQ<59>")
	)
	(segment
		(start 151.616664 -16.890746)
		(end 151.616664 -13.681456)
		(width 0.14224)
		(layer "In11.Cu")
		(net "M_J_DQ<59>")
	)
	(segment
		(start 124.350272 -53.4416)
		(end 125.594872 -52.197)
		(width 0.0889)
		(layer "In11.Cu")
		(net "M_J_DQ<59>")
	)
	(segment
		(start 124.162058 -55.704486)
		(end 124.168408 -55.693818)
		(width 0.0889)
		(layer "In11.Cu")
		(net "M_J_DQ<59>")
	)
	(segment
		(start 151.603964 -9.3726)
		(end 151.603964 -8.947658)
		(width 0.14224)
		(layer "In11.Cu")
		(net "M_J_DQ<59>")
	)
	(segment
		(start 150.765764 -3.965956)
		(end 150.765764 -3.560572)
		(width 0.14224)
		(layer "In11.Cu")
		(net "M_J_DQ<59>")
	)
	(segment
		(start 124.162058 -56.695086)
		(end 124.168408 -56.684418)
		(width 0.0889)
		(layer "In11.Cu")
		(net "M_J_DQ<59>")
	)
	(segment
		(start 151.781764 -13.516356)
		(end 151.781764 -12.354052)
		(width 0.14224)
		(layer "In11.Cu")
		(net "M_J_DQ<59>")
	)
	(segment
		(start 124.17298 -61.019182)
		(end 124.16409 -61.003688)
		(width 0.0889)
		(layer "In11.Cu")
		(net "M_J_DQ<59>")
	)
	(segment
		(start 130.249168 -50.8762)
		(end 135.786368 -45.339)
		(width 0.14224)
		(layer "In11.Cu")
		(net "M_J_DQ<59>")
	)
	(segment
		(start 152.093168 -24.257)
		(end 151.629364 -23.793196)
		(width 0.14224)
		(layer "In11.Cu")
		(net "M_J_DQ<59>")
	)
	(segment
		(start 124.157232 -56.703722)
		(end 124.162058 -56.695086)
		(width 0.0889)
		(layer "In11.Cu")
		(net "M_J_DQ<59>")
	)
	(segment
		(start 124.172472 -62.051692)
		(end 124.162058 -62.033658)
		(width 0.0889)
		(layer "In11.Cu")
		(net "M_J_DQ<59>")
	)
	(segment
		(start 124.157232 -55.713122)
		(end 124.162058 -55.704486)
		(width 0.0889)
		(layer "In11.Cu")
		(net "M_J_DQ<59>")
	)
	(segment
		(start 151.603964 -18.574258)
		(end 151.756364 -18.421858)
		(width 0.14224)
		(layer "In11.Cu")
		(net "M_J_DQ<59>")
	)
	(segment
		(start 124.157232 -57.694322)
		(end 124.162058 -57.685686)
		(width 0.0889)
		(layer "In11.Cu")
		(net "M_J_DQ<59>")
	)
	(segment
		(start 123.941078 -63.9064)
		(end 124.050298 -63.749174)
		(width 0.0889)
		(layer "In11.Cu")
		(net "M_J_DQ<59>")
	)
	(segment
		(start 151.24938 -3.076956)
		(end 151.602186 -2.72415)
		(width 0.14224)
		(layer "In11.Cu")
		(net "M_J_DQ<59>")
	)
	(segment
		(start 151.757634 0.7366)
		(end 151.757634 1.0922)
		(width 0.14224)
		(layer "In11.Cu")
		(net "M_J_DQ<59>")
	)
	(segment
		(start 151.603964 -21.822156)
		(end 151.603964 -21.3614)
		(width 0.14224)
		(layer "In11.Cu")
		(net "M_J_DQ<59>")
	)
	(segment
		(start 125.594872 -52.197)
		(end 125.829568 -52.197)
		(width 0.0889)
		(layer "In11.Cu")
		(net "M_J_DQ<59>")
	)
	(segment
		(start 151.603964 -11.741404)
		(end 151.813768 -11.5316)
		(width 0.14224)
		(layer "In11.Cu")
		(net "M_J_DQ<59>")
	)
	(segment
		(start 151.616664 -7.289546)
		(end 151.616664 -4.816856)
		(width 0.14224)
		(layer "In11.Cu")
		(net "M_J_DQ<59>")
	)
	(segment
		(start 124.16536 -62.65291)
		(end 124.172472 -62.640972)
		(width 0.0889)
		(layer "In11.Cu")
		(net "M_J_DQ<59>")
	)
	(segment
		(start 150.399496 2.196338)
		(end 150.399496 2.514854)
		(width 0.14224)
		(layer "In11.Cu")
		(net "M_J_DQ<59>")
	)
	(segment
		(start 124.350272 -53.63337)
		(end 124.350272 -53.4416)
		(width 0.0889)
		(layer "In11.Cu")
		(net "M_J_DQ<59>")
	)
	(segment
		(start 136.878568 -45.339)
		(end 152.093168 -30.1244)
		(width 0.14224)
		(layer "In11.Cu")
		(net "M_J_DQ<59>")
	)
	(segment
		(start 151.046434 1.5494)
		(end 150.399496 2.196338)
		(width 0.14224)
		(layer "In11.Cu")
		(net "M_J_DQ<59>")
	)
	(segment
		(start 124.153168 -61.74359)
		(end 124.191522 -61.666374)
		(width 0.0889)
		(layer "In11.Cu")
		(net "M_J_DQ<59>")
	)
	(segment
		(start 151.300434 1.5494)
		(end 151.046434 1.5494)
		(width 0.14224)
		(layer "In11.Cu")
		(net "M_J_DQ<59>")
	)
	(segment
		(start 124.162058 -54.713886)
		(end 124.168408 -54.703218)
		(width 0.0889)
		(layer "In11.Cu")
		(net "M_J_DQ<59>")
	)
	(segment
		(start 124.111766 -53.871876)
		(end 124.350272 -53.63337)
		(width 0.0889)
		(layer "In11.Cu")
		(net "M_J_DQ<59>")
	)
	(segment
		(start 151.616664 -4.816856)
		(end 150.765764 -3.965956)
		(width 0.14224)
		(layer "In11.Cu")
		(net "M_J_DQ<59>")
	)
	(segment
		(start 152.093168 -30.1244)
		(end 152.093168 -24.257)
		(width 0.14224)
		(layer "In11.Cu")
		(net "M_J_DQ<59>")
	)
	(segment
		(start 150.765764 -3.560572)
		(end 151.24938 -3.076956)
		(width 0.14224)
		(layer "In11.Cu")
		(net "M_J_DQ<59>")
	)
	(segment
		(start 151.629364 -23.335996)
		(end 151.781764 -23.183596)
		(width 0.14224)
		(layer "In11.Cu")
		(net "M_J_DQ<59>")
	)
	(segment
		(start 151.781764 -21.999956)
		(end 151.603964 -21.822156)
		(width 0.14224)
		(layer "In11.Cu")
		(net "M_J_DQ<59>")
	)
	(segment
		(start 151.602186 0.581152)
		(end 151.757634 0.7366)
		(width 0.14224)
		(layer "In11.Cu")
		(net "M_J_DQ<59>")
	)
	(segment
		(start 151.602186 -2.72415)
		(end 151.602186 0.581152)
		(width 0.14224)
		(layer "In11.Cu")
		(net "M_J_DQ<59>")
	)
	(segment
		(start 124.162058 -60.657486)
		(end 124.168408 -60.646818)
		(width 0.0889)
		(layer "In11.Cu")
		(net "M_J_DQ<59>")
	)
	(segment
		(start 151.629364 -23.793196)
		(end 151.629364 -23.335996)
		(width 0.14224)
		(layer "In11.Cu")
		(net "M_J_DQ<59>")
	)
	(segment
		(start 151.603964 -12.176252)
		(end 151.603964 -11.741404)
		(width 0.14224)
		(layer "In11.Cu")
		(net "M_J_DQ<59>")
	)
	(segment
		(start 151.756364 -8.795258)
		(end 151.756364 -7.429246)
		(width 0.14224)
		(layer "In11.Cu")
		(net "M_J_DQ<59>")
	)
	(segment
		(start 151.603964 -8.947658)
		(end 151.756364 -8.795258)
		(width 0.14224)
		(layer "In11.Cu")
		(net "M_J_DQ<59>")
	)
	(segment
		(start 151.756364 -7.429246)
		(end 151.616664 -7.289546)
		(width 0.14224)
		(layer "In11.Cu")
		(net "M_J_DQ<59>")
	)
	(segment
		(start 151.756364 -17.030446)
		(end 151.616664 -16.890746)
		(width 0.14224)
		(layer "In11.Cu")
		(net "M_J_DQ<59>")
	)
	(segment
		(start 151.756364 -18.421858)
		(end 151.756364 -17.030446)
		(width 0.14224)
		(layer "In11.Cu")
		(net "M_J_DQ<59>")
	)
	(segment
		(start 124.168408 -59.087004)
		(end 124.162058 -59.076336)
		(width 0.0889)
		(layer "In11.Cu")
		(net "M_J_DQ<59>")
	)
	(segment
		(start 151.781764 -12.354052)
		(end 151.603964 -12.176252)
		(width 0.14224)
		(layer "In11.Cu")
		(net "M_J_DQ<59>")
	)
	(arc
		(start 124.162058 -60.066936)
		(mid 124.108588 -59.871873)
		(end 124.157232 -59.675522)
		(width 0.0889)
		(layer "In11.Cu")
		(net "M_J_DQ<59>")
	)
	(arc
		(start 124.162058 -58.085736)
		(mid 124.108588 -57.890673)
		(end 124.157232 -57.694322)
		(width 0.0889)
		(layer "In11.Cu")
		(net "M_J_DQ<59>")
	)
	(arc
		(start 124.162058 -63.024258)
		(mid 124.113135 -62.838133)
		(end 124.16536 -62.65291)
		(width 0.0889)
		(layer "In11.Cu")
		(net "M_J_DQ<59>")
	)
	(arc
		(start 124.162058 -59.076336)
		(mid 124.108559 -58.876438)
		(end 124.162058 -58.67654)
		(width 0.0889)
		(layer "In11.Cu")
		(net "M_J_DQ<59>")
	)
	(arc
		(start 124.168408 -54.703218)
		(mid 124.241206 -54.412455)
		(end 124.162058 -54.123336)
		(width 0.0889)
		(layer "In11.Cu")
		(net "M_J_DQ<59>")
	)
	(arc
		(start 124.16409 -61.003688)
		(mid 124.117394 -60.830841)
		(end 124.162058 -60.657486)
		(width 0.0889)
		(layer "In11.Cu")
		(net "M_J_DQ<59>")
	)
	(arc
		(start 124.168408 -60.646818)
		(mid 124.241206 -60.356055)
		(end 124.162058 -60.066936)
		(width 0.0889)
		(layer "In11.Cu")
		(net "M_J_DQ<59>")
	)
	(arc
		(start 124.191522 -61.666374)
		(mid 124.263262 -61.340446)
		(end 124.17298 -61.019182)
		(width 0.0889)
		(layer "In11.Cu")
		(net "M_J_DQ<59>")
	)
	(arc
		(start 124.162058 -59.666886)
		(mid 124.24128 -59.377768)
		(end 124.168408 -59.087004)
		(width 0.0889)
		(layer "In11.Cu")
		(net "M_J_DQ<59>")
	)
	(arc
		(start 124.168408 -56.684418)
		(mid 124.241206 -56.393655)
		(end 124.162058 -56.104536)
		(width 0.0889)
		(layer "In11.Cu")
		(net "M_J_DQ<59>")
	)
	(arc
		(start 124.162058 -56.104536)
		(mid 124.108588 -55.909473)
		(end 124.157232 -55.713122)
		(width 0.0889)
		(layer "In11.Cu")
		(net "M_J_DQ<59>")
	)
	(arc
		(start 124.162058 -58.67654)
		(mid 124.241189 -58.381138)
		(end 124.162058 -58.085736)
		(width 0.0889)
		(layer "In11.Cu")
		(net "M_J_DQ<59>")
	)
	(arc
		(start 124.168408 -57.675018)
		(mid 124.241206 -57.384255)
		(end 124.162058 -57.095136)
		(width 0.0889)
		(layer "In11.Cu")
		(net "M_J_DQ<59>")
	)
	(arc
		(start 124.162058 -55.113936)
		(mid 124.108588 -54.918873)
		(end 124.157232 -54.722522)
		(width 0.0889)
		(layer "In11.Cu")
		(net "M_J_DQ<59>")
	)
	(arc
		(start 124.168408 -55.693818)
		(mid 124.241206 -55.403055)
		(end 124.162058 -55.113936)
		(width 0.0889)
		(layer "In11.Cu")
		(net "M_J_DQ<59>")
	)
	(arc
		(start 124.172472 -62.640972)
		(mid 124.251393 -62.346332)
		(end 124.172472 -62.051692)
		(width 0.0889)
		(layer "In11.Cu")
		(net "M_J_DQ<59>")
	)
	(arc
		(start 124.162058 -57.095136)
		(mid 124.108588 -56.900073)
		(end 124.157232 -56.703722)
		(width 0.0889)
		(layer "In11.Cu")
		(net "M_J_DQ<59>")
	)
	(arc
		(start 124.162058 -62.033658)
		(mid 124.121159 -61.889731)
		(end 124.153168 -61.74359)
		(width 0.0889)
		(layer "In11.Cu")
		(net "M_J_DQ<59>")
	)
	(arc
		(start 124.11583 -63.683642)
		(mid 124.239773 -63.361014)
		(end 124.162058 -63.024258)
		(width 0.0889)
		(layer "In11.Cu")
		(net "M_J_DQ<59>")
	)
	(arc
		(start 124.162058 -54.123336)
		(mid 124.116216 -54.001743)
		(end 124.111766 -53.871876)
		(width 0.0889)
		(layer "In11.Cu")
		(net "M_J_DQ<59>")
	)
	(segment
		(start 151.380952 0.30734)
		(end 151.380952 0.53086)
		(width 0.1651)
		(layer "F.Cu")
		(net "M_J_DQ<58>")
	)
	(segment
		(start 151.380952 0.53086)
		(end 151.24938 0.662432)
		(width 0.1651)
		(layer "F.Cu")
		(net "M_J_DQ<58>")
	)
	(segment
		(start 124.221748 -63.334138)
		(end 123.650248 -63.334138)
		(width 0.0889)
		(layer "F.Cu")
		(net "M_J_DQ<58>")
	)
	(segment
		(start 151.24938 0.175768)
		(end 151.380952 0.30734)
		(width 0.1651)
		(layer "F.Cu")
		(net "M_J_DQ<58>")
	)
	(segment
		(start 151.24938 0.662432)
		(end 151.24938 0.9398)
		(width 0.1651)
		(layer "F.Cu")
		(net "M_J_DQ<58>")
	)
	(segment
		(start 151.24938 -0.821182)
		(end 151.24938 0.175768)
		(width 0.1651)
		(layer "F.Cu")
		(net "M_J_DQ<58>")
	)
	(via
		(at 150.399496 -4.357878)
		(size 0.508)
		(drill 0.254)
		(layers "F.Cu" "B.Cu")
		(net "M_J_DQ<58>")
	)
	(via
		(at 151.24938 0.9398)
		(size 0.508)
		(drill 0.254)
		(layers "F.Cu" "B.Cu")
		(net "M_J_DQ<58>")
	)
	(via
		(at 123.650248 -63.334138)
		(size 0.508)
		(drill 0.254)
		(layers "F.Cu" "B.Cu")
		(net "M_J_DQ<58>")
	)
	(segment
		(start 150.399496 -5.621782)
		(end 150.399496 -4.357878)
		(width 0.1651)
		(layer "B.Cu")
		(net "M_J_DQ<58>")
	)
	(segment
		(start 150.746968 -28.22575)
		(end 150.889208 -28.08351)
		(width 0.14224)
		(layer "In11.Cu")
		(net "M_J_DQ<58>")
	)
	(segment
		(start 136.592564 -44.736004)
		(end 150.746968 -30.5816)
		(width 0.14224)
		(layer "In11.Cu")
		(net "M_J_DQ<58>")
	)
	(segment
		(start 150.968964 -4.927346)
		(end 150.399496 -4.357878)
		(width 0.14224)
		(layer "In11.Cu")
		(net "M_J_DQ<58>")
	)
	(segment
		(start 150.96363 -2.2098)
		(end 150.50643 -1.7526)
		(width 0.14224)
		(layer "In11.Cu")
		(net "M_J_DQ<58>")
	)
	(segment
		(start 150.889208 -25.48255)
		(end 151.239728 -25.48255)
		(width 0.14224)
		(layer "In11.Cu")
		(net "M_J_DQ<58>")
	)
	(segment
		(start 150.889208 -28.08351)
		(end 151.239728 -28.08351)
		(width 0.14224)
		(layer "In11.Cu")
		(net "M_J_DQ<58>")
	)
	(segment
		(start 150.114762 -4.073144)
		(end 150.114762 -3.3274)
		(width 0.14224)
		(layer "In11.Cu")
		(net "M_J_DQ<58>")
	)
	(segment
		(start 150.746968 -27.29103)
		(end 150.746968 -26.92527)
		(width 0.14224)
		(layer "In11.Cu")
		(net "M_J_DQ<58>")
	)
	(segment
		(start 150.892764 -11.728196)
		(end 150.772368 -11.6078)
		(width 0.14224)
		(layer "In11.Cu")
		(net "M_J_DQ<58>")
	)
	(segment
		(start 151.239728 -24.83231)
		(end 150.889208 -24.83231)
		(width 0.14224)
		(layer "In11.Cu")
		(net "M_J_DQ<58>")
	)
	(segment
		(start 150.81123 -0.761746)
		(end 150.50643 -0.456946)
		(width 0.14224)
		(layer "In11.Cu")
		(net "M_J_DQ<58>")
	)
	(segment
		(start 123.990608 -60.572904)
		(end 123.996958 -60.562236)
		(width 0.0889)
		(layer "In11.Cu")
		(net "M_J_DQ<58>")
	)
	(segment
		(start 150.740364 -13.541756)
		(end 150.740364 -12.286996)
		(width 0.14224)
		(layer "In11.Cu")
		(net "M_J_DQ<58>")
	)
	(segment
		(start 150.889208 -26.13279)
		(end 150.746968 -25.99055)
		(width 0.14224)
		(layer "In11.Cu")
		(net "M_J_DQ<58>")
	)
	(segment
		(start 151.239728 -26.78303)
		(end 151.381968 -26.64079)
		(width 0.14224)
		(layer "In11.Cu")
		(net "M_J_DQ<58>")
	)
	(segment
		(start 124.159772 -53.53812)
		(end 124.159772 -53.362606)
		(width 0.0889)
		(layer "In11.Cu")
		(net "M_J_DQ<58>")
	)
	(segment
		(start 135.576564 -44.736004)
		(end 136.592564 -44.736004)
		(width 0.14224)
		(layer "In11.Cu")
		(net "M_J_DQ<58>")
	)
	(segment
		(start 151.381968 -25.34031)
		(end 151.381968 -24.97455)
		(width 0.14224)
		(layer "In11.Cu")
		(net "M_J_DQ<58>")
	)
	(segment
		(start 151.239728 -26.13279)
		(end 150.889208 -26.13279)
		(width 0.14224)
		(layer "In11.Cu")
		(net "M_J_DQ<58>")
	)
	(segment
		(start 130.045968 -50.2666)
		(end 135.576564 -44.736004)
		(width 0.14224)
		(layer "In11.Cu")
		(net "M_J_DQ<58>")
	)
	(segment
		(start 151.239728 -28.08351)
		(end 151.381968 -27.94127)
		(width 0.14224)
		(layer "In11.Cu")
		(net "M_J_DQ<58>")
	)
	(segment
		(start 150.892764 -18.955004)
		(end 150.892764 -18.58645)
		(width 0.14224)
		(layer "In11.Cu")
		(net "M_J_DQ<58>")
	)
	(segment
		(start 151.381968 -26.27503)
		(end 151.239728 -26.13279)
		(width 0.14224)
		(layer "In11.Cu")
		(net "M_J_DQ<58>")
	)
	(segment
		(start 150.889208 -26.78303)
		(end 151.239728 -26.78303)
		(width 0.14224)
		(layer "In11.Cu")
		(net "M_J_DQ<58>")
	)
	(segment
		(start 150.772368 -9.543796)
		(end 150.892764 -9.4234)
		(width 0.14224)
		(layer "In11.Cu")
		(net "M_J_DQ<58>")
	)
	(segment
		(start 124.159772 -53.362606)
		(end 125.397768 -52.12461)
		(width 0.0889)
		(layer "In11.Cu")
		(net "M_J_DQ<58>")
	)
	(segment
		(start 123.996958 -56.599836)
		(end 124.001784 -56.5912)
		(width 0.0889)
		(layer "In11.Cu")
		(net "M_J_DQ<58>")
	)
	(segment
		(start 150.746968 -26.92527)
		(end 150.889208 -26.78303)
		(width 0.14224)
		(layer "In11.Cu")
		(net "M_J_DQ<58>")
	)
	(segment
		(start 123.94184 -53.756052)
		(end 124.159772 -53.53812)
		(width 0.0889)
		(layer "In11.Cu")
		(net "M_J_DQ<58>")
	)
	(segment
		(start 150.746968 -25.99055)
		(end 150.746968 -25.62479)
		(width 0.14224)
		(layer "In11.Cu")
		(net "M_J_DQ<58>")
	)
	(segment
		(start 123.990608 -54.629304)
		(end 123.996958 -54.618636)
		(width 0.0889)
		(layer "In11.Cu")
		(net "M_J_DQ<58>")
	)
	(segment
		(start 150.981664 -16.82115)
		(end 150.981664 -13.783056)
		(width 0.14224)
		(layer "In11.Cu")
		(net "M_J_DQ<58>")
	)
	(segment
		(start 123.990608 -62.554104)
		(end 123.996958 -62.543436)
		(width 0.0889)
		(layer "In11.Cu")
		(net "M_J_DQ<58>")
	)
	(segment
		(start 150.772368 -19.0754)
		(end 150.892764 -18.955004)
		(width 0.14224)
		(layer "In11.Cu")
		(net "M_J_DQ<58>")
	)
	(segment
		(start 150.892764 -18.58645)
		(end 150.765764 -18.45945)
		(width 0.14224)
		(layer "In11.Cu")
		(net "M_J_DQ<58>")
	)
	(segment
		(start 123.990608 -55.619904)
		(end 123.996958 -55.609236)
		(width 0.0889)
		(layer "In11.Cu")
		(net "M_J_DQ<58>")
	)
	(segment
		(start 150.50643 -0.108204)
		(end 150.851362 0.236728)
		(width 0.14224)
		(layer "In11.Cu")
		(net "M_J_DQ<58>")
	)
	(segment
		(start 150.851362 0.236728)
		(end 150.851362 0.541782)
		(width 0.14224)
		(layer "In11.Cu")
		(net "M_J_DQ<58>")
	)
	(segment
		(start 151.381968 -27.57551)
		(end 151.239728 -27.43327)
		(width 0.14224)
		(layer "In11.Cu")
		(net "M_J_DQ<58>")
	)
	(segment
		(start 150.889208 -24.83231)
		(end 150.746968 -24.69007)
		(width 0.14224)
		(layer "In11.Cu")
		(net "M_J_DQ<58>")
	)
	(segment
		(start 150.96363 -2.478532)
		(end 150.96363 -2.2098)
		(width 0.14224)
		(layer "In11.Cu")
		(net "M_J_DQ<58>")
	)
	(segment
		(start 150.772368 -11.6078)
		(end 150.772368 -9.543796)
		(width 0.14224)
		(layer "In11.Cu")
		(net "M_J_DQ<58>")
	)
	(segment
		(start 150.772368 -21.241004)
		(end 150.772368 -19.0754)
		(width 0.14224)
		(layer "In11.Cu")
		(net "M_J_DQ<58>")
	)
	(segment
		(start 123.996958 -60.562236)
		(end 124.001784 -60.5536)
		(width 0.0889)
		(layer "In11.Cu")
		(net "M_J_DQ<58>")
	)
	(segment
		(start 150.740364 -21.949156)
		(end 150.892764 -21.796756)
		(width 0.14224)
		(layer "In11.Cu")
		(net "M_J_DQ<58>")
	)
	(segment
		(start 150.50643 -0.456946)
		(end 150.50643 -0.108204)
		(width 0.14224)
		(layer "In11.Cu")
		(net "M_J_DQ<58>")
	)
	(segment
		(start 150.765764 -7.365746)
		(end 150.968964 -7.162546)
		(width 0.14224)
		(layer "In11.Cu")
		(net "M_J_DQ<58>")
	)
	(segment
		(start 150.50643 -1.7526)
		(end 150.50643 -1.35255)
		(width 0.14224)
		(layer "In11.Cu")
		(net "M_J_DQ<58>")
	)
	(segment
		(start 150.968964 -7.162546)
		(end 150.968964 -4.927346)
		(width 0.14224)
		(layer "In11.Cu")
		(net "M_J_DQ<58>")
	)
	(segment
		(start 123.990608 -57.601104)
		(end 123.996958 -57.590436)
		(width 0.0889)
		(layer "In11.Cu")
		(net "M_J_DQ<58>")
	)
	(segment
		(start 151.381968 -27.94127)
		(end 151.381968 -27.57551)
		(width 0.14224)
		(layer "In11.Cu")
		(net "M_J_DQ<58>")
	)
	(segment
		(start 150.981664 -13.783056)
		(end 150.740364 -13.541756)
		(width 0.14224)
		(layer "In11.Cu")
		(net "M_J_DQ<58>")
	)
	(segment
		(start 150.892764 -9.4234)
		(end 150.892764 -8.93445)
		(width 0.14224)
		(layer "In11.Cu")
		(net "M_J_DQ<58>")
	)
	(segment
		(start 123.996958 -57.590436)
		(end 124.001784 -57.5818)
		(width 0.0889)
		(layer "In11.Cu")
		(net "M_J_DQ<58>")
	)
	(segment
		(start 123.996958 -55.609236)
		(end 124.001784 -55.6006)
		(width 0.0889)
		(layer "In11.Cu")
		(net "M_J_DQ<58>")
	)
	(segment
		(start 150.994364 -24.021796)
		(end 150.994364 -23.428452)
		(width 0.14224)
		(layer "In11.Cu")
		(net "M_J_DQ<58>")
	)
	(segment
		(start 150.740364 -12.286996)
		(end 150.892764 -12.134596)
		(width 0.14224)
		(layer "In11.Cu")
		(net "M_J_DQ<58>")
	)
	(segment
		(start 125.397768 -52.12461)
		(end 125.397768 -51.943)
		(width 0.0889)
		(layer "In11.Cu")
		(net "M_J_DQ<58>")
	)
	(segment
		(start 150.994364 -23.428452)
		(end 150.740364 -23.174452)
		(width 0.14224)
		(layer "In11.Cu")
		(net "M_J_DQ<58>")
	)
	(segment
		(start 123.996958 -61.566552)
		(end 124.020072 -61.52642)
		(width 0.0889)
		(layer "In11.Cu")
		(net "M_J_DQ<58>")
	)
	(segment
		(start 150.399496 -4.357878)
		(end 150.114762 -4.073144)
		(width 0.14224)
		(layer "In11.Cu")
		(net "M_J_DQ<58>")
	)
	(segment
		(start 124.020326 -61.155072)
		(end 124.015246 -61.147706)
		(width 0.0889)
		(layer "In11.Cu")
		(net "M_J_DQ<58>")
	)
	(segment
		(start 123.650248 -63.334138)
		(end 123.943364 -63.164974)
		(width 0.0889)
		(layer "In11.Cu")
		(net "M_J_DQ<58>")
	)
	(segment
		(start 150.765764 -8.80745)
		(end 150.765764 -7.365746)
		(width 0.14224)
		(layer "In11.Cu")
		(net "M_J_DQ<58>")
	)
	(segment
		(start 150.746968 -25.62479)
		(end 150.889208 -25.48255)
		(width 0.14224)
		(layer "In11.Cu")
		(net "M_J_DQ<58>")
	)
	(segment
		(start 123.996958 -58.581036)
		(end 124.001784 -58.5724)
		(width 0.0889)
		(layer "In11.Cu")
		(net "M_J_DQ<58>")
	)
	(segment
		(start 125.397768 -51.943)
		(end 127.074168 -50.2666)
		(width 0.14224)
		(layer "In11.Cu")
		(net "M_J_DQ<58>")
	)
	(segment
		(start 150.114762 -3.3274)
		(end 150.96363 -2.478532)
		(width 0.14224)
		(layer "In11.Cu")
		(net "M_J_DQ<58>")
	)
	(segment
		(start 127.074168 -50.2666)
		(end 130.045968 -50.2666)
		(width 0.14224)
		(layer "In11.Cu")
		(net "M_J_DQ<58>")
	)
	(segment
		(start 150.851362 0.541782)
		(end 151.24938 0.9398)
		(width 0.14224)
		(layer "In11.Cu")
		(net "M_J_DQ<58>")
	)
	(segment
		(start 150.765764 -18.45945)
		(end 150.765764 -17.03705)
		(width 0.14224)
		(layer "In11.Cu")
		(net "M_J_DQ<58>")
	)
	(segment
		(start 150.740364 -23.174452)
		(end 150.740364 -21.949156)
		(width 0.14224)
		(layer "In11.Cu")
		(net "M_J_DQ<58>")
	)
	(segment
		(start 150.81123 -1.04775)
		(end 150.81123 -0.761746)
		(width 0.14224)
		(layer "In11.Cu")
		(net "M_J_DQ<58>")
	)
	(segment
		(start 150.892764 -12.134596)
		(end 150.892764 -11.728196)
		(width 0.14224)
		(layer "In11.Cu")
		(net "M_J_DQ<58>")
	)
	(segment
		(start 151.381968 -26.64079)
		(end 151.381968 -26.27503)
		(width 0.14224)
		(layer "In11.Cu")
		(net "M_J_DQ<58>")
	)
	(segment
		(start 150.889208 -27.43327)
		(end 150.746968 -27.29103)
		(width 0.14224)
		(layer "In11.Cu")
		(net "M_J_DQ<58>")
	)
	(segment
		(start 150.50643 -1.35255)
		(end 150.81123 -1.04775)
		(width 0.14224)
		(layer "In11.Cu")
		(net "M_J_DQ<58>")
	)
	(segment
		(start 150.765764 -17.03705)
		(end 150.981664 -16.82115)
		(width 0.14224)
		(layer "In11.Cu")
		(net "M_J_DQ<58>")
	)
	(segment
		(start 150.746968 -24.69007)
		(end 150.746968 -24.269192)
		(width 0.14224)
		(layer "In11.Cu")
		(net "M_J_DQ<58>")
	)
	(segment
		(start 150.892764 -21.3614)
		(end 150.772368 -21.241004)
		(width 0.14224)
		(layer "In11.Cu")
		(net "M_J_DQ<58>")
	)
	(segment
		(start 150.892764 -21.796756)
		(end 150.892764 -21.3614)
		(width 0.14224)
		(layer "In11.Cu")
		(net "M_J_DQ<58>")
	)
	(segment
		(start 151.239728 -27.43327)
		(end 150.889208 -27.43327)
		(width 0.14224)
		(layer "In11.Cu")
		(net "M_J_DQ<58>")
	)
	(segment
		(start 151.381968 -24.97455)
		(end 151.239728 -24.83231)
		(width 0.14224)
		(layer "In11.Cu")
		(net "M_J_DQ<58>")
	)
	(segment
		(start 150.746968 -24.269192)
		(end 150.994364 -24.021796)
		(width 0.14224)
		(layer "In11.Cu")
		(net "M_J_DQ<58>")
	)
	(segment
		(start 123.996958 -54.618636)
		(end 124.001784 -54.61)
		(width 0.0889)
		(layer "In11.Cu")
		(net "M_J_DQ<58>")
	)
	(segment
		(start 123.943364 -63.164974)
		(end 123.96724 -63.075566)
		(width 0.0889)
		(layer "In11.Cu")
		(net "M_J_DQ<58>")
	)
	(segment
		(start 150.892764 -8.93445)
		(end 150.765764 -8.80745)
		(width 0.14224)
		(layer "In11.Cu")
		(net "M_J_DQ<58>")
	)
	(segment
		(start 151.239728 -25.48255)
		(end 151.381968 -25.34031)
		(width 0.14224)
		(layer "In11.Cu")
		(net "M_J_DQ<58>")
	)
	(segment
		(start 150.746968 -30.5816)
		(end 150.746968 -28.22575)
		(width 0.14224)
		(layer "In11.Cu")
		(net "M_J_DQ<58>")
	)
	(segment
		(start 123.996958 -59.171586)
		(end 123.990608 -59.160918)
		(width 0.0889)
		(layer "In11.Cu")
		(net "M_J_DQ<58>")
	)
	(segment
		(start 123.990608 -56.610504)
		(end 123.996958 -56.599836)
		(width 0.0889)
		(layer "In11.Cu")
		(net "M_J_DQ<58>")
	)
	(arc
		(start 124.001784 -58.5724)
		(mid 124.050539 -58.376048)
		(end 123.996958 -58.180986)
		(width 0.0889)
		(layer "In11.Cu")
		(net "M_J_DQ<58>")
	)
	(arc
		(start 124.001784 -57.5818)
		(mid 124.050539 -57.385448)
		(end 123.996958 -57.190386)
		(width 0.0889)
		(layer "In11.Cu")
		(net "M_J_DQ<58>")
	)
	(arc
		(start 123.996958 -57.190386)
		(mid 123.917736 -56.901268)
		(end 123.990608 -56.610504)
		(width 0.0889)
		(layer "In11.Cu")
		(net "M_J_DQ<58>")
	)
	(arc
		(start 124.015246 -61.147706)
		(mid 123.922682 -60.863763)
		(end 123.990608 -60.572904)
		(width 0.0889)
		(layer "In11.Cu")
		(net "M_J_DQ<58>")
	)
	(arc
		(start 124.043948 -62.444376)
		(mid 124.050408 -62.2823)
		(end 123.996958 -62.129162)
		(width 0.0889)
		(layer "In11.Cu")
		(net "M_J_DQ<58>")
	)
	(arc
		(start 123.996958 -62.543436)
		(mid 124.025811 -62.496447)
		(end 124.043948 -62.444376)
		(width 0.0889)
		(layer "In11.Cu")
		(net "M_J_DQ<58>")
	)
	(arc
		(start 123.996958 -54.218586)
		(mid 123.921864 -53.992974)
		(end 123.94184 -53.756052)
		(width 0.0889)
		(layer "In11.Cu")
		(net "M_J_DQ<58>")
	)
	(arc
		(start 123.96724 -63.075566)
		(mid 123.918228 -62.812117)
		(end 123.990608 -62.554104)
		(width 0.0889)
		(layer "In11.Cu")
		(net "M_J_DQ<58>")
	)
	(arc
		(start 124.020072 -61.52642)
		(mid 124.069886 -61.340775)
		(end 124.020326 -61.155072)
		(width 0.0889)
		(layer "In11.Cu")
		(net "M_J_DQ<58>")
	)
	(arc
		(start 123.996958 -58.180986)
		(mid 123.917736 -57.891868)
		(end 123.990608 -57.601104)
		(width 0.0889)
		(layer "In11.Cu")
		(net "M_J_DQ<58>")
	)
	(arc
		(start 123.996958 -60.162186)
		(mid 123.917827 -59.866784)
		(end 123.996958 -59.571382)
		(width 0.0889)
		(layer "In11.Cu")
		(net "M_J_DQ<58>")
	)
	(arc
		(start 124.001784 -56.5912)
		(mid 124.050539 -56.394848)
		(end 123.996958 -56.199786)
		(width 0.0889)
		(layer "In11.Cu")
		(net "M_J_DQ<58>")
	)
	(arc
		(start 123.996958 -62.129162)
		(mid 123.921672 -61.847874)
		(end 123.996958 -61.566552)
		(width 0.0889)
		(layer "In11.Cu")
		(net "M_J_DQ<58>")
	)
	(arc
		(start 124.001784 -55.6006)
		(mid 124.050539 -55.404248)
		(end 123.996958 -55.209186)
		(width 0.0889)
		(layer "In11.Cu")
		(net "M_J_DQ<58>")
	)
	(arc
		(start 124.001784 -60.5536)
		(mid 124.050539 -60.357248)
		(end 123.996958 -60.162186)
		(width 0.0889)
		(layer "In11.Cu")
		(net "M_J_DQ<58>")
	)
	(arc
		(start 124.001784 -54.61)
		(mid 124.050539 -54.413648)
		(end 123.996958 -54.218586)
		(width 0.0889)
		(layer "In11.Cu")
		(net "M_J_DQ<58>")
	)
	(arc
		(start 123.996958 -56.199786)
		(mid 123.917736 -55.910668)
		(end 123.990608 -55.619904)
		(width 0.0889)
		(layer "In11.Cu")
		(net "M_J_DQ<58>")
	)
	(arc
		(start 123.996958 -59.571382)
		(mid 124.050457 -59.371484)
		(end 123.996958 -59.171586)
		(width 0.0889)
		(layer "In11.Cu")
		(net "M_J_DQ<58>")
	)
	(arc
		(start 123.990608 -59.160918)
		(mid 123.91781 -58.870155)
		(end 123.996958 -58.581036)
		(width 0.0889)
		(layer "In11.Cu")
		(net "M_J_DQ<58>")
	)
	(arc
		(start 123.996958 -55.209186)
		(mid 123.917736 -54.920068)
		(end 123.990608 -54.629304)
		(width 0.0889)
		(layer "In11.Cu")
		(net "M_J_DQ<58>")
	)
	(segment
		(start 144.449546 3.778758)
		(end 144.449546 2.514854)
		(width 0.1651)
		(layer "F.Cu")
		(net "M_J_DQ<57>")
	)
	(segment
		(start 121.646188 -64.819784)
		(end 121.074688 -64.819784)
		(width 0.0889)
		(layer "F.Cu")
		(net "M_J_DQ<57>")
	)
	(via
		(at 144.449546 2.514854)
		(size 0.508)
		(drill 0.254)
		(layers "F.Cu" "B.Cu")
		(net "M_J_DQ<57>")
	)
	(via
		(at 145.12163 -3.076956)
		(size 0.508)
		(drill 0.254)
		(layers "F.Cu" "B.Cu")
		(net "M_J_DQ<57>")
	)
	(via
		(at 121.074688 -64.819784)
		(size 0.508)
		(drill 0.254)
		(layers "F.Cu" "B.Cu")
		(net "M_J_DQ<57>")
	)
	(segment
		(start 145.29943 -2.395982)
		(end 145.12163 -2.573782)
		(width 0.1651)
		(layer "B.Cu")
		(net "M_J_DQ<57>")
	)
	(segment
		(start 145.29943 -1.021842)
		(end 145.29943 -2.395982)
		(width 0.1651)
		(layer "B.Cu")
		(net "M_J_DQ<57>")
	)
	(segment
		(start 145.12163 -2.573782)
		(end 145.12163 -3.076956)
		(width 0.1651)
		(layer "B.Cu")
		(net "M_J_DQ<57>")
	)
	(segment
		(start 120.723152 -59.675522)
		(end 120.727978 -59.666886)
		(width 0.0889)
		(layer "In11.Cu")
		(net "M_J_DQ<57>")
	)
	(segment
		(start 120.723152 -54.722522)
		(end 120.727978 -54.713886)
		(width 0.0889)
		(layer "In11.Cu")
		(net "M_J_DQ<57>")
	)
	(segment
		(start 145.609564 -25.940004)
		(end 145.609564 -21.342858)
		(width 0.14224)
		(layer "In11.Cu")
		(net "M_J_DQ<57>")
	)
	(segment
		(start 145.609564 -18.9738)
		(end 145.609564 -11.690604)
		(width 0.14224)
		(layer "In11.Cu")
		(net "M_J_DQ<57>")
	)
	(segment
		(start 144.974564 -4.235196)
		(end 144.595088 -3.85572)
		(width 0.14224)
		(layer "In11.Cu")
		(net "M_J_DQ<57>")
	)
	(segment
		(start 120.727978 -55.704486)
		(end 120.734328 -55.693818)
		(width 0.0889)
		(layer "In11.Cu")
		(net "M_J_DQ<57>")
	)
	(segment
		(start 125.677168 -46.4566)
		(end 128.902714 -46.4566)
		(width 0.14224)
		(layer "In11.Cu")
		(net "M_J_DQ<57>")
	)
	(segment
		(start 121.448068 -50.456084)
		(end 121.448068 -50.32502)
		(width 0.0889)
		(layer "In11.Cu")
		(net "M_J_DQ<57>")
	)
	(segment
		(start 120.723152 -56.703722)
		(end 120.727978 -56.695086)
		(width 0.0889)
		(layer "In11.Cu")
		(net "M_J_DQ<57>")
	)
	(segment
		(start 120.727978 -57.685686)
		(end 120.734328 -57.675018)
		(width 0.0889)
		(layer "In11.Cu")
		(net "M_J_DQ<57>")
	)
	(segment
		(start 145.495772 0.630936)
		(end 145.652236 0.7874)
		(width 0.14224)
		(layer "In11.Cu")
		(net "M_J_DQ<57>")
	)
	(segment
		(start 145.844768 -21.107654)
		(end 145.844768 -19.209004)
		(width 0.14224)
		(layer "In11.Cu")
		(net "M_J_DQ<57>")
	)
	(segment
		(start 121.460768 -50.997612)
		(end 121.460768 -50.468784)
		(width 0.0889)
		(layer "In11.Cu")
		(net "M_J_DQ<57>")
	)
	(segment
		(start 144.449546 1.975866)
		(end 144.449546 2.514854)
		(width 0.14224)
		(layer "In11.Cu")
		(net "M_J_DQ<57>")
	)
	(segment
		(start 145.12163 -3.076956)
		(end 145.495772 -2.702814)
		(width 0.14224)
		(layer "In11.Cu")
		(net "M_J_DQ<57>")
	)
	(segment
		(start 120.704102 -53.754528)
		(end 120.766332 -53.604922)
		(width 0.0889)
		(layer "In11.Cu")
		(net "M_J_DQ<57>")
	)
	(segment
		(start 145.652236 1.128776)
		(end 145.282412 1.4986)
		(width 0.14224)
		(layer "In11.Cu")
		(net "M_J_DQ<57>")
	)
	(segment
		(start 135.328914 -40.0304)
		(end 136.30275 -40.0304)
		(width 0.14224)
		(layer "In11.Cu")
		(net "M_J_DQ<57>")
	)
	(segment
		(start 145.793968 -11.5062)
		(end 145.793968 -9.633204)
		(width 0.14224)
		(layer "In11.Cu")
		(net "M_J_DQ<57>")
	)
	(segment
		(start 121.460768 -50.468784)
		(end 121.448068 -50.456084)
		(width 0.0889)
		(layer "In11.Cu")
		(net "M_J_DQ<57>")
	)
	(segment
		(start 120.727978 -56.695086)
		(end 120.734328 -56.684418)
		(width 0.0889)
		(layer "In11.Cu")
		(net "M_J_DQ<57>")
	)
	(segment
		(start 121.448068 -50.32502)
		(end 122.446288 -49.3268)
		(width 0.0889)
		(layer "In11.Cu")
		(net "M_J_DQ<57>")
	)
	(segment
		(start 120.723152 -60.666122)
		(end 120.727978 -60.657486)
		(width 0.0889)
		(layer "In11.Cu")
		(net "M_J_DQ<57>")
	)
	(segment
		(start 120.766332 -53.604922)
		(end 120.766332 -51.692048)
		(width 0.0889)
		(layer "In11.Cu")
		(net "M_J_DQ<57>")
	)
	(segment
		(start 144.595088 -3.603498)
		(end 145.12163 -3.076956)
		(width 0.14224)
		(layer "In11.Cu")
		(net "M_J_DQ<57>")
	)
	(segment
		(start 122.806968 -49.3268)
		(end 125.677168 -46.4566)
		(width 0.14224)
		(layer "In11.Cu")
		(net "M_J_DQ<57>")
	)
	(segment
		(start 120.723152 -57.694322)
		(end 120.727978 -57.685686)
		(width 0.0889)
		(layer "In11.Cu")
		(net "M_J_DQ<57>")
	)
	(segment
		(start 145.495772 -2.702814)
		(end 145.495772 0.630936)
		(width 0.14224)
		(layer "In11.Cu")
		(net "M_J_DQ<57>")
	)
	(segment
		(start 120.801892 -64.198246)
		(end 120.727978 -64.029336)
		(width 0.0889)
		(layer "In11.Cu")
		(net "M_J_DQ<57>")
	)
	(segment
		(start 136.30275 -40.0304)
		(end 145.360136 -30.973014)
		(width 0.14224)
		(layer "In11.Cu")
		(net "M_J_DQ<57>")
	)
	(segment
		(start 145.609564 -6.520942)
		(end 144.974564 -5.885942)
		(width 0.14224)
		(layer "In11.Cu")
		(net "M_J_DQ<57>")
	)
	(segment
		(start 121.074688 -64.819784)
		(end 120.801892 -64.198246)
		(width 0.0889)
		(layer "In11.Cu")
		(net "M_J_DQ<57>")
	)
	(segment
		(start 144.595088 -3.85572)
		(end 144.595088 -3.603498)
		(width 0.14224)
		(layer "In11.Cu")
		(net "M_J_DQ<57>")
	)
	(segment
		(start 144.974564 -5.885942)
		(end 144.974564 -4.235196)
		(width 0.14224)
		(layer "In11.Cu")
		(net "M_J_DQ<57>")
	)
	(segment
		(start 145.360136 -26.189432)
		(end 145.609564 -25.940004)
		(width 0.14224)
		(layer "In11.Cu")
		(net "M_J_DQ<57>")
	)
	(segment
		(start 120.766332 -51.692048)
		(end 121.460768 -50.997612)
		(width 0.0889)
		(layer "In11.Cu")
		(net "M_J_DQ<57>")
	)
	(segment
		(start 120.727978 -60.657486)
		(end 120.734328 -60.646818)
		(width 0.0889)
		(layer "In11.Cu")
		(net "M_J_DQ<57>")
	)
	(segment
		(start 120.723152 -55.713122)
		(end 120.727978 -55.704486)
		(width 0.0889)
		(layer "In11.Cu")
		(net "M_J_DQ<57>")
	)
	(segment
		(start 122.446288 -49.3268)
		(end 122.806968 -49.3268)
		(width 0.0889)
		(layer "In11.Cu")
		(net "M_J_DQ<57>")
	)
	(segment
		(start 145.360136 -30.973014)
		(end 145.360136 -26.189432)
		(width 0.14224)
		(layer "In11.Cu")
		(net "M_J_DQ<57>")
	)
	(segment
		(start 120.734328 -59.087004)
		(end 120.727978 -59.076336)
		(width 0.0889)
		(layer "In11.Cu")
		(net "M_J_DQ<57>")
	)
	(segment
		(start 145.609564 -11.690604)
		(end 145.793968 -11.5062)
		(width 0.14224)
		(layer "In11.Cu")
		(net "M_J_DQ<57>")
	)
	(segment
		(start 145.844768 -19.209004)
		(end 145.609564 -18.9738)
		(width 0.14224)
		(layer "In11.Cu")
		(net "M_J_DQ<57>")
	)
	(segment
		(start 145.793968 -9.633204)
		(end 145.609564 -9.4488)
		(width 0.14224)
		(layer "In11.Cu")
		(net "M_J_DQ<57>")
	)
	(segment
		(start 144.926812 1.4986)
		(end 144.449546 1.975866)
		(width 0.14224)
		(layer "In11.Cu")
		(net "M_J_DQ<57>")
	)
	(segment
		(start 145.652236 0.7874)
		(end 145.652236 1.128776)
		(width 0.14224)
		(layer "In11.Cu")
		(net "M_J_DQ<57>")
	)
	(segment
		(start 145.282412 1.4986)
		(end 144.926812 1.4986)
		(width 0.14224)
		(layer "In11.Cu")
		(net "M_J_DQ<57>")
	)
	(segment
		(start 128.902714 -46.4566)
		(end 135.328914 -40.0304)
		(width 0.14224)
		(layer "In11.Cu")
		(net "M_J_DQ<57>")
	)
	(segment
		(start 145.609564 -9.4488)
		(end 145.609564 -6.520942)
		(width 0.14224)
		(layer "In11.Cu")
		(net "M_J_DQ<57>")
	)
	(segment
		(start 120.727978 -54.713886)
		(end 120.734328 -54.703218)
		(width 0.0889)
		(layer "In11.Cu")
		(net "M_J_DQ<57>")
	)
	(segment
		(start 145.609564 -21.342858)
		(end 145.844768 -21.107654)
		(width 0.14224)
		(layer "In11.Cu")
		(net "M_J_DQ<57>")
	)
	(arc
		(start 120.727978 -56.104536)
		(mid 120.674508 -55.909473)
		(end 120.723152 -55.713122)
		(width 0.0889)
		(layer "In11.Cu")
		(net "M_J_DQ<57>")
	)
	(arc
		(start 120.727978 -58.67654)
		(mid 120.807109 -58.381138)
		(end 120.727978 -58.085736)
		(width 0.0889)
		(layer "In11.Cu")
		(net "M_J_DQ<57>")
	)
	(arc
		(start 120.727978 -61.64834)
		(mid 120.807041 -61.352938)
		(end 120.727978 -61.057536)
		(width 0.0889)
		(layer "In11.Cu")
		(net "M_J_DQ<57>")
	)
	(arc
		(start 120.727978 -58.085736)
		(mid 120.674508 -57.890673)
		(end 120.723152 -57.694322)
		(width 0.0889)
		(layer "In11.Cu")
		(net "M_J_DQ<57>")
	)
	(arc
		(start 120.734328 -55.693818)
		(mid 120.807126 -55.403055)
		(end 120.727978 -55.113936)
		(width 0.0889)
		(layer "In11.Cu")
		(net "M_J_DQ<57>")
	)
	(arc
		(start 120.727978 -59.076336)
		(mid 120.674479 -58.876438)
		(end 120.727978 -58.67654)
		(width 0.0889)
		(layer "In11.Cu")
		(net "M_J_DQ<57>")
	)
	(arc
		(start 120.727978 -59.666886)
		(mid 120.8072 -59.377768)
		(end 120.734328 -59.087004)
		(width 0.0889)
		(layer "In11.Cu")
		(net "M_J_DQ<57>")
	)
	(arc
		(start 120.734328 -57.675018)
		(mid 120.807126 -57.384255)
		(end 120.727978 -57.095136)
		(width 0.0889)
		(layer "In11.Cu")
		(net "M_J_DQ<57>")
	)
	(arc
		(start 120.727978 -62.048136)
		(mid 120.674479 -61.848238)
		(end 120.727978 -61.64834)
		(width 0.0889)
		(layer "In11.Cu")
		(net "M_J_DQ<57>")
	)
	(arc
		(start 120.921272 -63.459868)
		(mid 121.183513 -63.304569)
		(end 121.392188 -63.082424)
		(width 0.0889)
		(layer "In11.Cu")
		(net "M_J_DQ<57>")
	)
	(arc
		(start 120.727978 -60.066936)
		(mid 120.674508 -59.871873)
		(end 120.723152 -59.675522)
		(width 0.0889)
		(layer "In11.Cu")
		(net "M_J_DQ<57>")
	)
	(arc
		(start 120.727978 -64.029336)
		(mid 120.695707 -63.700829)
		(end 120.921272 -63.459868)
		(width 0.0889)
		(layer "In11.Cu")
		(net "M_J_DQ<57>")
	)
	(arc
		(start 120.734328 -60.646818)
		(mid 120.807126 -60.356055)
		(end 120.727978 -60.066936)
		(width 0.0889)
		(layer "In11.Cu")
		(net "M_J_DQ<57>")
	)
	(arc
		(start 120.727978 -57.095136)
		(mid 120.674508 -56.900073)
		(end 120.723152 -56.703722)
		(width 0.0889)
		(layer "In11.Cu")
		(net "M_J_DQ<57>")
	)
	(arc
		(start 120.727978 -54.123336)
		(mid 120.673004 -53.941722)
		(end 120.704102 -53.754528)
		(width 0.0889)
		(layer "In11.Cu")
		(net "M_J_DQ<57>")
	)
	(arc
		(start 120.734328 -54.703218)
		(mid 120.807126 -54.412455)
		(end 120.727978 -54.123336)
		(width 0.0889)
		(layer "In11.Cu")
		(net "M_J_DQ<57>")
	)
	(arc
		(start 120.734328 -56.684418)
		(mid 120.807126 -56.393655)
		(end 120.727978 -56.104536)
		(width 0.0889)
		(layer "In11.Cu")
		(net "M_J_DQ<57>")
	)
	(arc
		(start 121.220484 -62.46622)
		(mid 120.937901 -62.299967)
		(end 120.727978 -62.048136)
		(width 0.0889)
		(layer "In11.Cu")
		(net "M_J_DQ<57>")
	)
	(arc
		(start 120.727978 -61.057536)
		(mid 120.674508 -60.862473)
		(end 120.723152 -60.666122)
		(width 0.0889)
		(layer "In11.Cu")
		(net "M_J_DQ<57>")
	)
	(arc
		(start 120.727978 -55.113936)
		(mid 120.674508 -54.918873)
		(end 120.723152 -54.722522)
		(width 0.0889)
		(layer "In11.Cu")
		(net "M_J_DQ<57>")
	)
	(arc
		(start 121.392188 -63.082424)
		(mid 121.460183 -62.73144)
		(end 121.220484 -62.46622)
		(width 0.0889)
		(layer "In11.Cu")
		(net "M_J_DQ<57>")
	)
	(segment
		(start 145.29943 -0.821182)
		(end 145.12163 1.0414)
		(width 0.1651)
		(layer "F.Cu")
		(net "M_J_DQ<56>")
	)
	(segment
		(start 121.646188 -62.838584)
		(end 121.074688 -62.838584)
		(width 0.0889)
		(layer "F.Cu")
		(net "M_J_DQ<56>")
	)
	(via
		(at 145.12163 1.0414)
		(size 0.508)
		(drill 0.254)
		(layers "F.Cu" "B.Cu")
		(net "M_J_DQ<56>")
	)
	(via
		(at 121.074688 -62.838584)
		(size 0.508)
		(drill 0.254)
		(layers "F.Cu" "B.Cu")
		(net "M_J_DQ<56>")
	)
	(via
		(at 144.449546 -4.357878)
		(size 0.508)
		(drill 0.254)
		(layers "F.Cu" "B.Cu")
		(net "M_J_DQ<56>")
	)
	(segment
		(start 144.449546 -5.621782)
		(end 144.449546 -4.357878)
		(width 0.1651)
		(layer "B.Cu")
		(net "M_J_DQ<56>")
	)
	(segment
		(start 137.747502 -37.614098)
		(end 137.51687 -37.383466)
		(width 0.14224)
		(layer "In11.Cu")
		(net "M_J_DQ<56>")
	)
	(segment
		(start 120.562878 -60.562236)
		(end 120.556528 -60.572904)
		(width 0.0889)
		(layer "In11.Cu")
		(net "M_J_DQ<56>")
	)
	(segment
		(start 136.725914 -38.432486)
		(end 136.596882 -38.303454)
		(width 0.14224)
		(layer "In11.Cu")
		(net "M_J_DQ<56>")
	)
	(segment
		(start 139.81684 -35.083496)
		(end 140.047472 -35.314128)
		(width 0.14224)
		(layer "In11.Cu")
		(net "M_J_DQ<56>")
	)
	(segment
		(start 144.906746 -25.778968)
		(end 144.906746 -23.395178)
		(width 0.14224)
		(layer "In11.Cu")
		(net "M_J_DQ<56>")
	)
	(segment
		(start 138.695684 -36.003484)
		(end 138.896852 -36.003484)
		(width 0.14224)
		(layer "In11.Cu")
		(net "M_J_DQ<56>")
	)
	(segment
		(start 144.906746 -23.395178)
		(end 144.650968 -23.1394)
		(width 0.14224)
		(layer "In11.Cu")
		(net "M_J_DQ<56>")
	)
	(segment
		(start 144.631664 -7.516876)
		(end 144.930368 -7.218172)
		(width 0.14224)
		(layer "In11.Cu")
		(net "M_J_DQ<56>")
	)
	(segment
		(start 144.828768 -10.1346)
		(end 144.600168 -9.906)
		(width 0.14224)
		(layer "In11.Cu")
		(net "M_J_DQ<56>")
	)
	(segment
		(start 120.562878 -56.599836)
		(end 120.556528 -56.610504)
		(width 0.0889)
		(layer "In11.Cu")
		(net "M_J_DQ<56>")
	)
	(segment
		(start 144.828768 -10.600436)
		(end 144.828768 -10.1346)
		(width 0.14224)
		(layer "In11.Cu")
		(net "M_J_DQ<56>")
	)
	(segment
		(start 144.650968 -11.362436)
		(end 144.650968 -10.778236)
		(width 0.14224)
		(layer "In11.Cu")
		(net "M_J_DQ<56>")
	)
	(segment
		(start 139.127484 -36.234116)
		(end 139.328652 -36.234116)
		(width 0.14224)
		(layer "In11.Cu")
		(net "M_J_DQ<56>")
	)
	(segment
		(start 144.901412 -2.5908)
		(end 144.901412 -2.090928)
		(width 0.14224)
		(layer "In11.Cu")
		(net "M_J_DQ<56>")
	)
	(segment
		(start 120.562878 -54.618636)
		(end 120.556528 -54.629304)
		(width 0.0889)
		(layer "In11.Cu")
		(net "M_J_DQ<56>")
	)
	(segment
		(start 144.930368 -21.652992)
		(end 144.930368 -21.361146)
		(width 0.14224)
		(layer "In11.Cu")
		(net "M_J_DQ<56>")
	)
	(segment
		(start 144.449546 -6.326124)
		(end 144.449546 -4.357878)
		(width 0.14224)
		(layer "In11.Cu")
		(net "M_J_DQ<56>")
	)
	(segment
		(start 137.51687 -37.383466)
		(end 137.51687 -37.182298)
		(width 0.14224)
		(layer "In11.Cu")
		(net "M_J_DQ<56>")
	)
	(segment
		(start 138.66749 -36.69411)
		(end 138.436858 -36.463478)
		(width 0.14224)
		(layer "In11.Cu")
		(net "M_J_DQ<56>")
	)
	(segment
		(start 136.855708 -37.84346)
		(end 137.056876 -37.84346)
		(width 0.14224)
		(layer "In11.Cu")
		(net "M_J_DQ<56>")
	)
	(segment
		(start 144.164812 -3.3274)
		(end 144.901412 -2.5908)
		(width 0.14224)
		(layer "In11.Cu")
		(net "M_J_DQ<56>")
	)
	(segment
		(start 139.615672 -35.083496)
		(end 139.81684 -35.083496)
		(width 0.14224)
		(layer "In11.Cu")
		(net "M_J_DQ<56>")
	)
	(segment
		(start 120.567704 -58.5724)
		(end 120.562878 -58.581036)
		(width 0.0889)
		(layer "In11.Cu")
		(net "M_J_DQ<56>")
	)
	(segment
		(start 120.567704 -54.61)
		(end 120.562878 -54.618636)
		(width 0.0889)
		(layer "In11.Cu")
		(net "M_J_DQ<56>")
	)
	(segment
		(start 138.896852 -36.003484)
		(end 139.127484 -36.234116)
		(width 0.14224)
		(layer "In11.Cu")
		(net "M_J_DQ<56>")
	)
	(segment
		(start 121.257568 -50.931318)
		(end 121.257568 -50.24501)
		(width 0.0889)
		(layer "In11.Cu")
		(net "M_J_DQ<56>")
	)
	(segment
		(start 121.032524 -62.79388)
		(end 121.074688 -62.838584)
		(width 0.0889)
		(layer "In11.Cu")
		(net "M_J_DQ<56>")
	)
	(segment
		(start 129.258568 -45.4406)
		(end 135.93572 -38.763448)
		(width 0.14224)
		(layer "In11.Cu")
		(net "M_J_DQ<56>")
	)
	(segment
		(start 137.747502 -37.815266)
		(end 137.747502 -37.614098)
		(width 0.14224)
		(layer "In11.Cu")
		(net "M_J_DQ<56>")
	)
	(segment
		(start 120.562878 -57.590436)
		(end 120.556528 -57.601104)
		(width 0.0889)
		(layer "In11.Cu")
		(net "M_J_DQ<56>")
	)
	(segment
		(start 140.50772 -35.055302)
		(end 144.725136 -30.837886)
		(width 0.14224)
		(layer "In11.Cu")
		(net "M_J_DQ<56>")
	)
	(segment
		(start 136.136888 -38.763448)
		(end 136.26592 -38.89248)
		(width 0.14224)
		(layer "In11.Cu")
		(net "M_J_DQ<56>")
	)
	(segment
		(start 144.631664 -13.408152)
		(end 144.631664 -12.424156)
		(width 0.14224)
		(layer "In11.Cu")
		(net "M_J_DQ<56>")
	)
	(segment
		(start 120.576086 -51.6128)
		(end 121.257568 -50.931318)
		(width 0.0889)
		(layer "In11.Cu")
		(net "M_J_DQ<56>")
	)
	(segment
		(start 144.51203 -1.397)
		(end 144.82953 -1.0795)
		(width 0.14224)
		(layer "In11.Cu")
		(net "M_J_DQ<56>")
	)
	(segment
		(start 120.576086 -53.407564)
		(end 120.576086 -51.6128)
		(width 0.0889)
		(layer "In11.Cu")
		(net "M_J_DQ<56>")
	)
	(segment
		(start 144.650968 -21.932392)
		(end 144.930368 -21.652992)
		(width 0.14224)
		(layer "In11.Cu")
		(net "M_J_DQ<56>")
	)
	(segment
		(start 139.587478 -35.774122)
		(end 139.356846 -35.54349)
		(width 0.14224)
		(layer "In11.Cu")
		(net "M_J_DQ<56>")
	)
	(segment
		(start 144.727168 -21.157946)
		(end 144.727168 -19.177)
		(width 0.14224)
		(layer "In11.Cu")
		(net "M_J_DQ<56>")
	)
	(segment
		(start 144.901412 0.821182)
		(end 145.12163 1.0414)
		(width 0.14224)
		(layer "In11.Cu")
		(net "M_J_DQ<56>")
	)
	(segment
		(start 137.775696 -36.923472)
		(end 137.976864 -36.923472)
		(width 0.14224)
		(layer "In11.Cu")
		(net "M_J_DQ<56>")
	)
	(segment
		(start 144.930368 -13.785342)
		(end 144.68856 -13.543534)
		(width 0.14224)
		(layer "In11.Cu")
		(net "M_J_DQ<56>")
	)
	(segment
		(start 122.324368 -49.0982)
		(end 125.981968 -45.4406)
		(width 0.14224)
		(layer "In11.Cu")
		(net "M_J_DQ<56>")
	)
	(segment
		(start 144.600168 -9.7028)
		(end 144.930368 -9.3726)
		(width 0.14224)
		(layer "In11.Cu")
		(net "M_J_DQ<56>")
	)
	(segment
		(start 120.567704 -56.5912)
		(end 120.562878 -56.599836)
		(width 0.0889)
		(layer "In11.Cu")
		(net "M_J_DQ<56>")
	)
	(segment
		(start 137.976864 -36.923472)
		(end 138.207496 -37.154104)
		(width 0.14224)
		(layer "In11.Cu")
		(net "M_J_DQ<56>")
	)
	(segment
		(start 120.567704 -60.5536)
		(end 120.562878 -60.562236)
		(width 0.0889)
		(layer "In11.Cu")
		(net "M_J_DQ<56>")
	)
	(segment
		(start 135.93572 -38.763448)
		(end 136.136888 -38.763448)
		(width 0.14224)
		(layer "In11.Cu")
		(net "M_J_DQ<56>")
	)
	(segment
		(start 144.631664 -12.424156)
		(end 144.930368 -12.125452)
		(width 0.14224)
		(layer "In11.Cu")
		(net "M_J_DQ<56>")
	)
	(segment
		(start 144.650968 -23.1394)
		(end 144.650968 -21.932392)
		(width 0.14224)
		(layer "In11.Cu")
		(net "M_J_DQ<56>")
	)
	(segment
		(start 144.930368 -18.617946)
		(end 144.631664 -18.319242)
		(width 0.14224)
		(layer "In11.Cu")
		(net "M_J_DQ<56>")
	)
	(segment
		(start 136.596882 -38.303454)
		(end 136.596882 -38.102286)
		(width 0.14224)
		(layer "In11.Cu")
		(net "M_J_DQ<56>")
	)
	(segment
		(start 120.562878 -55.609236)
		(end 120.556528 -55.619904)
		(width 0.0889)
		(layer "In11.Cu")
		(net "M_J_DQ<56>")
	)
	(segment
		(start 140.507466 -35.055302)
		(end 140.50772 -35.055302)
		(width 0.14224)
		(layer "In11.Cu")
		(net "M_J_DQ<56>")
	)
	(segment
		(start 138.207496 -37.154104)
		(end 138.408664 -37.154104)
		(width 0.14224)
		(layer "In11.Cu")
		(net "M_J_DQ<56>")
	)
	(segment
		(start 144.901412 0.236728)
		(end 144.901412 0.821182)
		(width 0.14224)
		(layer "In11.Cu")
		(net "M_J_DQ<56>")
	)
	(segment
		(start 144.930368 -9.3726)
		(end 144.930368 -8.981186)
		(width 0.14224)
		(layer "In11.Cu")
		(net "M_J_DQ<56>")
	)
	(segment
		(start 137.51687 -37.182298)
		(end 137.775696 -36.923472)
		(width 0.14224)
		(layer "In11.Cu")
		(net "M_J_DQ<56>")
	)
	(segment
		(start 122.324368 -49.17821)
		(end 122.324368 -49.0982)
		(width 0.0889)
		(layer "In11.Cu")
		(net "M_J_DQ<56>")
	)
	(segment
		(start 144.164812 -4.073144)
		(end 144.164812 -3.3274)
		(width 0.14224)
		(layer "In11.Cu")
		(net "M_J_DQ<56>")
	)
	(segment
		(start 144.725136 -25.960578)
		(end 144.906746 -25.778968)
		(width 0.14224)
		(layer "In11.Cu")
		(net "M_J_DQ<56>")
	)
	(segment
		(start 144.600168 -9.906)
		(end 144.600168 -9.7028)
		(width 0.14224)
		(layer "In11.Cu")
		(net "M_J_DQ<56>")
	)
	(segment
		(start 144.650968 -10.778236)
		(end 144.828768 -10.600436)
		(width 0.14224)
		(layer "In11.Cu")
		(net "M_J_DQ<56>")
	)
	(segment
		(start 144.449546 -4.357878)
		(end 144.164812 -4.073144)
		(width 0.14224)
		(layer "In11.Cu")
		(net "M_J_DQ<56>")
	)
	(segment
		(start 144.727168 -19.177)
		(end 144.930368 -18.9738)
		(width 0.14224)
		(layer "In11.Cu")
		(net "M_J_DQ<56>")
	)
	(segment
		(start 138.436858 -36.463478)
		(end 138.436858 -36.26231)
		(width 0.14224)
		(layer "In11.Cu")
		(net "M_J_DQ<56>")
	)
	(segment
		(start 140.047472 -35.314128)
		(end 140.24864 -35.314128)
		(width 0.14224)
		(layer "In11.Cu")
		(net "M_J_DQ<56>")
	)
	(segment
		(start 140.24864 -35.314128)
		(end 140.507466 -35.055302)
		(width 0.14224)
		(layer "In11.Cu")
		(net "M_J_DQ<56>")
	)
	(segment
		(start 144.930368 -18.9738)
		(end 144.930368 -18.617946)
		(width 0.14224)
		(layer "In11.Cu")
		(net "M_J_DQ<56>")
	)
	(segment
		(start 139.328652 -36.234116)
		(end 139.587478 -35.97529)
		(width 0.14224)
		(layer "In11.Cu")
		(net "M_J_DQ<56>")
	)
	(segment
		(start 139.587478 -35.97529)
		(end 139.587478 -35.774122)
		(width 0.14224)
		(layer "In11.Cu")
		(net "M_J_DQ<56>")
	)
	(segment
		(start 144.82953 -1.0795)
		(end 144.82953 -0.8509)
		(width 0.14224)
		(layer "In11.Cu")
		(net "M_J_DQ<56>")
	)
	(segment
		(start 120.556528 -59.160918)
		(end 120.562878 -59.171586)
		(width 0.0889)
		(layer "In11.Cu")
		(net "M_J_DQ<56>")
	)
	(segment
		(start 144.631664 -17.118076)
		(end 144.930368 -16.819372)
		(width 0.14224)
		(layer "In11.Cu")
		(net "M_J_DQ<56>")
	)
	(segment
		(start 120.567704 -57.5818)
		(end 120.562878 -57.590436)
		(width 0.0889)
		(layer "In11.Cu")
		(net "M_J_DQ<56>")
	)
	(segment
		(start 137.488676 -38.074092)
		(end 137.747502 -37.815266)
		(width 0.14224)
		(layer "In11.Cu")
		(net "M_J_DQ<56>")
	)
	(segment
		(start 144.68856 -13.543534)
		(end 144.68856 -13.465048)
		(width 0.14224)
		(layer "In11.Cu")
		(net "M_J_DQ<56>")
	)
	(segment
		(start 144.51203 -1.701546)
		(end 144.51203 -1.397)
		(width 0.14224)
		(layer "In11.Cu")
		(net "M_J_DQ<56>")
	)
	(segment
		(start 139.356846 -35.54349)
		(end 139.356846 -35.342322)
		(width 0.14224)
		(layer "In11.Cu")
		(net "M_J_DQ<56>")
	)
	(segment
		(start 120.576086 -53.407564)
		(end 120.494806 -53.78069)
		(width 0.0889)
		(layer "In11.Cu")
		(net "M_J_DQ<56>")
	)
	(segment
		(start 144.930368 -12.125452)
		(end 144.930368 -11.641836)
		(width 0.14224)
		(layer "In11.Cu")
		(net "M_J_DQ<56>")
	)
	(segment
		(start 136.725914 -38.633654)
		(end 136.725914 -38.432486)
		(width 0.14224)
		(layer "In11.Cu")
		(net "M_J_DQ<56>")
	)
	(segment
		(start 138.436858 -36.26231)
		(end 138.695684 -36.003484)
		(width 0.14224)
		(layer "In11.Cu")
		(net "M_J_DQ<56>")
	)
	(segment
		(start 144.68856 -13.465048)
		(end 144.631664 -13.408152)
		(width 0.14224)
		(layer "In11.Cu")
		(net "M_J_DQ<56>")
	)
	(segment
		(start 120.562878 -62.14364)
		(end 120.566942 -62.150752)
		(width 0.0889)
		(layer "In11.Cu")
		(net "M_J_DQ<56>")
	)
	(segment
		(start 139.356846 -35.342322)
		(end 139.615672 -35.083496)
		(width 0.14224)
		(layer "In11.Cu")
		(net "M_J_DQ<56>")
	)
	(segment
		(start 144.631664 -18.319242)
		(end 144.631664 -17.118076)
		(width 0.14224)
		(layer "In11.Cu")
		(net "M_J_DQ<56>")
	)
	(segment
		(start 136.596882 -38.102286)
		(end 136.855708 -37.84346)
		(width 0.14224)
		(layer "In11.Cu")
		(net "M_J_DQ<56>")
	)
	(segment
		(start 144.930368 -6.806946)
		(end 144.449546 -6.326124)
		(width 0.14224)
		(layer "In11.Cu")
		(net "M_J_DQ<56>")
	)
	(segment
		(start 136.26592 -38.89248)
		(end 136.467088 -38.89248)
		(width 0.14224)
		(layer "In11.Cu")
		(net "M_J_DQ<56>")
	)
	(segment
		(start 144.725136 -30.837886)
		(end 144.725136 -25.960578)
		(width 0.14224)
		(layer "In11.Cu")
		(net "M_J_DQ<56>")
	)
	(segment
		(start 144.48663 -0.178054)
		(end 144.901412 0.236728)
		(width 0.14224)
		(layer "In11.Cu")
		(net "M_J_DQ<56>")
	)
	(segment
		(start 144.930368 -21.361146)
		(end 144.727168 -21.157946)
		(width 0.14224)
		(layer "In11.Cu")
		(net "M_J_DQ<56>")
	)
	(segment
		(start 144.901412 -2.090928)
		(end 144.51203 -1.701546)
		(width 0.14224)
		(layer "In11.Cu")
		(net "M_J_DQ<56>")
	)
	(segment
		(start 144.48663 -0.508)
		(end 144.48663 -0.178054)
		(width 0.14224)
		(layer "In11.Cu")
		(net "M_J_DQ<56>")
	)
	(segment
		(start 136.467088 -38.89248)
		(end 136.725914 -38.633654)
		(width 0.14224)
		(layer "In11.Cu")
		(net "M_J_DQ<56>")
	)
	(segment
		(start 121.257568 -50.24501)
		(end 122.324368 -49.17821)
		(width 0.0889)
		(layer "In11.Cu")
		(net "M_J_DQ<56>")
	)
	(segment
		(start 144.82953 -0.8509)
		(end 144.48663 -0.508)
		(width 0.14224)
		(layer "In11.Cu")
		(net "M_J_DQ<56>")
	)
	(segment
		(start 120.567704 -55.6006)
		(end 120.562878 -55.609236)
		(width 0.0889)
		(layer "In11.Cu")
		(net "M_J_DQ<56>")
	)
	(segment
		(start 138.408664 -37.154104)
		(end 138.66749 -36.895278)
		(width 0.14224)
		(layer "In11.Cu")
		(net "M_J_DQ<56>")
	)
	(segment
		(start 125.981968 -45.4406)
		(end 129.258568 -45.4406)
		(width 0.14224)
		(layer "In11.Cu")
		(net "M_J_DQ<56>")
	)
	(segment
		(start 137.056876 -37.84346)
		(end 137.287508 -38.074092)
		(width 0.14224)
		(layer "In11.Cu")
		(net "M_J_DQ<56>")
	)
	(segment
		(start 144.930368 -16.819372)
		(end 144.930368 -13.785342)
		(width 0.14224)
		(layer "In11.Cu")
		(net "M_J_DQ<56>")
	)
	(segment
		(start 138.66749 -36.895278)
		(end 138.66749 -36.69411)
		(width 0.14224)
		(layer "In11.Cu")
		(net "M_J_DQ<56>")
	)
	(segment
		(start 144.631664 -8.682482)
		(end 144.631664 -7.516876)
		(width 0.14224)
		(layer "In11.Cu")
		(net "M_J_DQ<56>")
	)
	(segment
		(start 137.287508 -38.074092)
		(end 137.488676 -38.074092)
		(width 0.14224)
		(layer "In11.Cu")
		(net "M_J_DQ<56>")
	)
	(segment
		(start 144.930368 -8.981186)
		(end 144.631664 -8.682482)
		(width 0.14224)
		(layer "In11.Cu")
		(net "M_J_DQ<56>")
	)
	(segment
		(start 144.930368 -7.218172)
		(end 144.930368 -6.806946)
		(width 0.14224)
		(layer "In11.Cu")
		(net "M_J_DQ<56>")
	)
	(segment
		(start 144.930368 -11.641836)
		(end 144.650968 -11.362436)
		(width 0.14224)
		(layer "In11.Cu")
		(net "M_J_DQ<56>")
	)
	(arc
		(start 120.562878 -58.581036)
		(mid 120.483656 -58.870154)
		(end 120.556528 -59.160918)
		(width 0.0889)
		(layer "In11.Cu")
		(net "M_J_DQ<56>")
	)
	(arc
		(start 120.562878 -61.152786)
		(mid 120.616538 -61.352828)
		(end 120.562878 -61.552836)
		(width 0.0889)
		(layer "In11.Cu")
		(net "M_J_DQ<56>")
	)
	(arc
		(start 120.556528 -55.619904)
		(mid 120.48373 -55.910667)
		(end 120.562878 -56.199786)
		(width 0.0889)
		(layer "In11.Cu")
		(net "M_J_DQ<56>")
	)
	(arc
		(start 120.562878 -56.199786)
		(mid 120.616348 -56.394849)
		(end 120.567704 -56.5912)
		(width 0.0889)
		(layer "In11.Cu")
		(net "M_J_DQ<56>")
	)
	(arc
		(start 120.562878 -55.209186)
		(mid 120.616348 -55.404249)
		(end 120.567704 -55.6006)
		(width 0.0889)
		(layer "In11.Cu")
		(net "M_J_DQ<56>")
	)
	(arc
		(start 120.562878 -60.162186)
		(mid 120.616348 -60.357249)
		(end 120.567704 -60.5536)
		(width 0.0889)
		(layer "In11.Cu")
		(net "M_J_DQ<56>")
	)
	(arc
		(start 120.556528 -57.601104)
		(mid 120.48373 -57.891867)
		(end 120.562878 -58.180986)
		(width 0.0889)
		(layer "In11.Cu")
		(net "M_J_DQ<56>")
	)
	(arc
		(start 120.562878 -54.218586)
		(mid 120.616348 -54.413649)
		(end 120.567704 -54.61)
		(width 0.0889)
		(layer "In11.Cu")
		(net "M_J_DQ<56>")
	)
	(arc
		(start 120.556528 -54.629304)
		(mid 120.48373 -54.920067)
		(end 120.562878 -55.209186)
		(width 0.0889)
		(layer "In11.Cu")
		(net "M_J_DQ<56>")
	)
	(arc
		(start 120.562878 -57.190386)
		(mid 120.616348 -57.385449)
		(end 120.567704 -57.5818)
		(width 0.0889)
		(layer "In11.Cu")
		(net "M_J_DQ<56>")
	)
	(arc
		(start 120.562878 -59.571382)
		(mid 120.483747 -59.866784)
		(end 120.562878 -60.162186)
		(width 0.0889)
		(layer "In11.Cu")
		(net "M_J_DQ<56>")
	)
	(arc
		(start 120.562878 -58.180986)
		(mid 120.616348 -58.376049)
		(end 120.567704 -58.5724)
		(width 0.0889)
		(layer "In11.Cu")
		(net "M_J_DQ<56>")
	)
	(arc
		(start 120.562878 -59.171586)
		(mid 120.616377 -59.371484)
		(end 120.562878 -59.571382)
		(width 0.0889)
		(layer "In11.Cu")
		(net "M_J_DQ<56>")
	)
	(arc
		(start 120.566942 -62.150752)
		(mid 120.783163 -62.484311)
		(end 121.032524 -62.79388)
		(width 0.0889)
		(layer "In11.Cu")
		(net "M_J_DQ<56>")
	)
	(arc
		(start 120.556528 -60.572904)
		(mid 120.48373 -60.863667)
		(end 120.562878 -61.152786)
		(width 0.0889)
		(layer "In11.Cu")
		(net "M_J_DQ<56>")
	)
	(arc
		(start 120.562878 -61.552836)
		(mid 120.483747 -61.848238)
		(end 120.562878 -62.14364)
		(width 0.0889)
		(layer "In11.Cu")
		(net "M_J_DQ<56>")
	)
	(arc
		(start 120.556528 -56.610504)
		(mid 120.48373 -56.901267)
		(end 120.562878 -57.190386)
		(width 0.0889)
		(layer "In11.Cu")
		(net "M_J_DQ<56>")
	)
	(arc
		(start 120.494806 -53.78069)
		(mid 120.487929 -54.006001)
		(end 120.562878 -54.218586)
		(width 0.0889)
		(layer "In11.Cu")
		(net "M_J_DQ<56>")
	)
	(segment
		(start 139.34948 3.778758)
		(end 139.34948 2.514854)
		(width 0.1651)
		(layer "F.Cu")
		(net "M_J_DQ<55>")
	)
	(segment
		(start 117.640862 -64.819784)
		(end 118.212362 -64.819784)
		(width 0.0889)
		(layer "F.Cu")
		(net "M_J_DQ<55>")
	)
	(via
		(at 140.199364 -3.076956)
		(size 0.508)
		(drill 0.254)
		(layers "F.Cu" "B.Cu")
		(net "M_J_DQ<55>")
	)
	(via
		(at 139.34948 2.514854)
		(size 0.508)
		(drill 0.254)
		(layers "F.Cu" "B.Cu")
		(net "M_J_DQ<55>")
	)
	(via
		(at 117.640862 -64.819784)
		(size 0.508)
		(drill 0.254)
		(layers "F.Cu" "B.Cu")
		(net "M_J_DQ<55>")
	)
	(segment
		(start 140.199364 -1.021842)
		(end 140.199364 -3.076956)
		(width 0.1651)
		(layer "B.Cu")
		(net "M_J_DQ<55>")
	)
	(segment
		(start 140.592302 -4.80568)
		(end 139.73937 -3.952748)
		(width 0.14224)
		(layer "In11.Cu")
		(net "M_J_DQ<55>")
	)
	(segment
		(start 118.334536 -49.068736)
		(end 119.144288 -48.258984)
		(width 0.0889)
		(layer "In11.Cu")
		(net "M_J_DQ<55>")
	)
	(segment
		(start 140.707618 0.7366)
		(end 140.707618 1.0922)
		(width 0.14224)
		(layer "In11.Cu")
		(net "M_J_DQ<55>")
	)
	(segment
		(start 139.666218 1.8796)
		(end 139.666218 2.198116)
		(width 0.14224)
		(layer "In11.Cu")
		(net "M_J_DQ<55>")
	)
	(segment
		(start 140.698728 -26.925016)
		(end 140.554964 -26.781252)
		(width 0.14224)
		(layer "In11.Cu")
		(net "M_J_DQ<55>")
	)
	(segment
		(start 140.688568 -11.598402)
		(end 140.688568 -9.525)
		(width 0.14224)
		(layer "In11.Cu")
		(net "M_J_DQ<55>")
	)
	(segment
		(start 140.721588 -17.07261)
		(end 140.57757 -16.928592)
		(width 0.14224)
		(layer "In11.Cu")
		(net "M_J_DQ<55>")
	)
	(segment
		(start 140.57757 -16.928592)
		(end 140.57757 -13.712444)
		(width 0.14224)
		(layer "In11.Cu")
		(net "M_J_DQ<55>")
	)
	(segment
		(start 118.147846 -61.161676)
		(end 118.152672 -61.15304)
		(width 0.0889)
		(layer "In11.Cu")
		(net "M_J_DQ<55>")
	)
	(segment
		(start 119.144288 -48.258984)
		(end 119.144288 -47.734474)
		(width 0.0889)
		(layer "In11.Cu")
		(net "M_J_DQ<55>")
	)
	(segment
		(start 119.144288 -47.734474)
		(end 119.366792 -47.51197)
		(width 0.0889)
		(layer "In11.Cu")
		(net "M_J_DQ<55>")
	)
	(segment
		(start 140.688568 -8.8646)
		(end 140.688568 -7.400544)
		(width 0.14224)
		(layer "In11.Cu")
		(net "M_J_DQ<55>")
	)
	(segment
		(start 118.147846 -59.180476)
		(end 118.152672 -59.17184)
		(width 0.0889)
		(layer "In11.Cu")
		(net "M_J_DQ<55>")
	)
	(segment
		(start 139.666218 2.198116)
		(end 139.34948 2.514854)
		(width 0.14224)
		(layer "In11.Cu")
		(net "M_J_DQ<55>")
	)
	(segment
		(start 140.536168 -21.682456)
		(end 140.536168 -18.567654)
		(width 0.14224)
		(layer "In11.Cu")
		(net "M_J_DQ<55>")
	)
	(segment
		(start 140.57757 -13.712444)
		(end 140.75537 -13.534644)
		(width 0.14224)
		(layer "In11.Cu")
		(net "M_J_DQ<55>")
	)
	(segment
		(start 140.199364 -3.076956)
		(end 140.55217 -2.72415)
		(width 0.14224)
		(layer "In11.Cu")
		(net "M_J_DQ<55>")
	)
	(segment
		(start 118.152672 -60.16244)
		(end 118.159022 -60.151772)
		(width 0.0889)
		(layer "In11.Cu")
		(net "M_J_DQ<55>")
	)
	(segment
		(start 140.55217 -12.170156)
		(end 140.55217 -11.7348)
		(width 0.14224)
		(layer "In11.Cu")
		(net "M_J_DQ<55>")
	)
	(segment
		(start 140.55217 0.581152)
		(end 140.707618 0.7366)
		(width 0.14224)
		(layer "In11.Cu")
		(net "M_J_DQ<55>")
	)
	(segment
		(start 140.55217 -2.72415)
		(end 140.55217 0.581152)
		(width 0.14224)
		(layer "In11.Cu")
		(net "M_J_DQ<55>")
	)
	(segment
		(start 118.048786 -51.496976)
		(end 118.334536 -51.211226)
		(width 0.0889)
		(layer "In11.Cu")
		(net "M_J_DQ<55>")
	)
	(segment
		(start 122.781568 -40.4114)
		(end 125.854968 -37.338)
		(width 0.14224)
		(layer "In11.Cu")
		(net "M_J_DQ<55>")
	)
	(segment
		(start 140.592302 -7.304278)
		(end 140.592302 -4.80568)
		(width 0.14224)
		(layer "In11.Cu")
		(net "M_J_DQ<55>")
	)
	(segment
		(start 139.73937 -3.53695)
		(end 140.199364 -3.076956)
		(width 0.14224)
		(layer "In11.Cu")
		(net "M_J_DQ<55>")
	)
	(segment
		(start 118.23192 -54.5084)
		(end 118.048786 -54.325266)
		(width 0.0889)
		(layer "In11.Cu")
		(net "M_J_DQ<55>")
	)
	(segment
		(start 139.996418 1.5494)
		(end 139.666218 1.8796)
		(width 0.14224)
		(layer "In11.Cu")
		(net "M_J_DQ<55>")
	)
	(segment
		(start 139.73937 -3.952748)
		(end 139.73937 -3.53695)
		(width 0.14224)
		(layer "In11.Cu")
		(net "M_J_DQ<55>")
	)
	(segment
		(start 125.854968 -37.338)
		(end 132.96265 -37.338)
		(width 0.14224)
		(layer "In11.Cu")
		(net "M_J_DQ<55>")
	)
	(segment
		(start 140.698728 -28.145232)
		(end 140.698728 -26.925016)
		(width 0.14224)
		(layer "In11.Cu")
		(net "M_J_DQ<55>")
	)
	(segment
		(start 140.55217 -9.388602)
		(end 140.55217 -9.000998)
		(width 0.14224)
		(layer "In11.Cu")
		(net "M_J_DQ<55>")
	)
	(segment
		(start 140.55217 -9.000998)
		(end 140.688568 -8.8646)
		(width 0.14224)
		(layer "In11.Cu")
		(net "M_J_DQ<55>")
	)
	(segment
		(start 118.334536 -51.211226)
		(end 118.334536 -49.068736)
		(width 0.0889)
		(layer "In11.Cu")
		(net "M_J_DQ<55>")
	)
	(segment
		(start 118.147846 -58.189876)
		(end 118.152672 -58.18124)
		(width 0.0889)
		(layer "In11.Cu")
		(net "M_J_DQ<55>")
	)
	(segment
		(start 140.732764 -21.879052)
		(end 140.536168 -21.682456)
		(width 0.14224)
		(layer "In11.Cu")
		(net "M_J_DQ<55>")
	)
	(segment
		(start 140.721588 -18.382234)
		(end 140.721588 -17.07261)
		(width 0.14224)
		(layer "In11.Cu")
		(net "M_J_DQ<55>")
	)
	(segment
		(start 140.536168 -18.567654)
		(end 140.721588 -18.382234)
		(width 0.14224)
		(layer "In11.Cu")
		(net "M_J_DQ<55>")
	)
	(segment
		(start 122.781568 -43.646344)
		(end 122.781568 -40.4114)
		(width 0.14224)
		(layer "In11.Cu")
		(net "M_J_DQ<55>")
	)
	(segment
		(start 140.688568 -9.525)
		(end 140.55217 -9.388602)
		(width 0.14224)
		(layer "In11.Cu")
		(net "M_J_DQ<55>")
	)
	(segment
		(start 140.75537 -13.534644)
		(end 140.75537 -12.373356)
		(width 0.14224)
		(layer "In11.Cu")
		(net "M_J_DQ<55>")
	)
	(segment
		(start 118.152672 -59.17184)
		(end 118.159022 -59.161172)
		(width 0.0889)
		(layer "In11.Cu")
		(net "M_J_DQ<55>")
	)
	(segment
		(start 117.640862 -64.819784)
		(end 117.987572 -64.029336)
		(width 0.0889)
		(layer "In11.Cu")
		(net "M_J_DQ<55>")
	)
	(segment
		(start 132.96265 -37.338)
		(end 140.534136 -29.766514)
		(width 0.14224)
		(layer "In11.Cu")
		(net "M_J_DQ<55>")
	)
	(segment
		(start 140.554964 -26.781252)
		(end 140.554964 -23.285196)
		(width 0.14224)
		(layer "In11.Cu")
		(net "M_J_DQ<55>")
	)
	(segment
		(start 140.534136 -28.309824)
		(end 140.698728 -28.145232)
		(width 0.14224)
		(layer "In11.Cu")
		(net "M_J_DQ<55>")
	)
	(segment
		(start 140.55217 -11.7348)
		(end 140.688568 -11.598402)
		(width 0.14224)
		(layer "In11.Cu")
		(net "M_J_DQ<55>")
	)
	(segment
		(start 140.75537 -12.373356)
		(end 140.55217 -12.170156)
		(width 0.14224)
		(layer "In11.Cu")
		(net "M_J_DQ<55>")
	)
	(segment
		(start 140.707618 1.0922)
		(end 140.250418 1.5494)
		(width 0.14224)
		(layer "In11.Cu")
		(net "M_J_DQ<55>")
	)
	(segment
		(start 118.147846 -60.171076)
		(end 118.152672 -60.16244)
		(width 0.0889)
		(layer "In11.Cu")
		(net "M_J_DQ<55>")
	)
	(segment
		(start 140.554964 -23.285196)
		(end 140.732764 -23.107396)
		(width 0.14224)
		(layer "In11.Cu")
		(net "M_J_DQ<55>")
	)
	(segment
		(start 140.732764 -23.107396)
		(end 140.732764 -21.879052)
		(width 0.14224)
		(layer "In11.Cu")
		(net "M_J_DQ<55>")
	)
	(segment
		(start 140.250418 1.5494)
		(end 139.996418 1.5494)
		(width 0.14224)
		(layer "In11.Cu")
		(net "M_J_DQ<55>")
	)
	(segment
		(start 118.152672 -58.18124)
		(end 118.159022 -58.170572)
		(width 0.0889)
		(layer "In11.Cu")
		(net "M_J_DQ<55>")
	)
	(segment
		(start 118.048786 -54.325266)
		(end 118.048786 -51.496976)
		(width 0.0889)
		(layer "In11.Cu")
		(net "M_J_DQ<55>")
	)
	(segment
		(start 118.23192 -54.913784)
		(end 118.23192 -54.5084)
		(width 0.0889)
		(layer "In11.Cu")
		(net "M_J_DQ<55>")
	)
	(segment
		(start 119.366792 -47.06112)
		(end 122.781568 -43.646344)
		(width 0.14224)
		(layer "In11.Cu")
		(net "M_J_DQ<55>")
	)
	(segment
		(start 140.688568 -7.400544)
		(end 140.592302 -7.304278)
		(width 0.14224)
		(layer "In11.Cu")
		(net "M_J_DQ<55>")
	)
	(segment
		(start 119.366792 -47.51197)
		(end 119.366792 -47.06112)
		(width 0.14224)
		(layer "In11.Cu")
		(net "M_J_DQ<55>")
	)
	(segment
		(start 140.534136 -29.766514)
		(end 140.534136 -28.309824)
		(width 0.14224)
		(layer "In11.Cu")
		(net "M_J_DQ<55>")
	)
	(segment
		(start 118.152672 -61.15304)
		(end 118.159022 -61.142372)
		(width 0.0889)
		(layer "In11.Cu")
		(net "M_J_DQ<55>")
	)
	(arc
		(start 118.159022 -61.142372)
		(mid 118.23182 -60.851609)
		(end 118.152672 -60.56249)
		(width 0.0889)
		(layer "In11.Cu")
		(net "M_J_DQ<55>")
	)
	(arc
		(start 118.152672 -57.59069)
		(mid 118.099046 -57.390538)
		(end 118.152672 -57.190386)
		(width 0.0889)
		(layer "In11.Cu")
		(net "M_J_DQ<55>")
	)
	(arc
		(start 118.152672 -55.209186)
		(mid 118.211739 -55.0667)
		(end 118.23192 -54.913784)
		(width 0.0889)
		(layer "In11.Cu")
		(net "M_J_DQ<55>")
	)
	(arc
		(start 118.03507 -63.760858)
		(mid 118.040401 -63.437512)
		(end 118.152672 -63.13424)
		(width 0.0889)
		(layer "In11.Cu")
		(net "M_J_DQ<55>")
	)
	(arc
		(start 118.152672 -63.13424)
		(mid 118.231803 -62.838838)
		(end 118.152672 -62.543436)
		(width 0.0889)
		(layer "In11.Cu")
		(net "M_J_DQ<55>")
	)
	(arc
		(start 118.152672 -56.599582)
		(mid 118.099046 -56.39943)
		(end 118.152672 -56.199278)
		(width 0.0889)
		(layer "In11.Cu")
		(net "M_J_DQ<55>")
	)
	(arc
		(start 118.159022 -60.151772)
		(mid 118.23182 -59.861009)
		(end 118.152672 -59.57189)
		(width 0.0889)
		(layer "In11.Cu")
		(net "M_J_DQ<55>")
	)
	(arc
		(start 118.152672 -61.552836)
		(mid 118.099136 -61.357885)
		(end 118.147846 -61.161676)
		(width 0.0889)
		(layer "In11.Cu")
		(net "M_J_DQ<55>")
	)
	(arc
		(start 118.152672 -58.58129)
		(mid 118.099202 -58.386227)
		(end 118.147846 -58.189876)
		(width 0.0889)
		(layer "In11.Cu")
		(net "M_J_DQ<55>")
	)
	(arc
		(start 118.152672 -60.56249)
		(mid 118.099202 -60.367427)
		(end 118.147846 -60.171076)
		(width 0.0889)
		(layer "In11.Cu")
		(net "M_J_DQ<55>")
	)
	(arc
		(start 118.159022 -58.170572)
		(mid 118.23182 -57.879809)
		(end 118.152672 -57.59069)
		(width 0.0889)
		(layer "In11.Cu")
		(net "M_J_DQ<55>")
	)
	(arc
		(start 118.152672 -55.608474)
		(mid 118.150314 -55.604503)
		(end 118.147846 -55.6006)
		(width 0.0889)
		(layer "In11.Cu")
		(net "M_J_DQ<55>")
	)
	(arc
		(start 118.152672 -56.199278)
		(mid 118.231803 -55.903876)
		(end 118.152672 -55.608474)
		(width 0.0889)
		(layer "In11.Cu")
		(net "M_J_DQ<55>")
	)
	(arc
		(start 118.152672 -62.14364)
		(mid 118.231803 -61.848238)
		(end 118.152672 -61.552836)
		(width 0.0889)
		(layer "In11.Cu")
		(net "M_J_DQ<55>")
	)
	(arc
		(start 118.147846 -55.6006)
		(mid 118.099091 -55.404248)
		(end 118.152672 -55.209186)
		(width 0.0889)
		(layer "In11.Cu")
		(net "M_J_DQ<55>")
	)
	(arc
		(start 118.159022 -59.161172)
		(mid 118.23182 -58.870409)
		(end 118.152672 -58.58129)
		(width 0.0889)
		(layer "In11.Cu")
		(net "M_J_DQ<55>")
	)
	(arc
		(start 118.152672 -62.543436)
		(mid 118.099173 -62.343538)
		(end 118.152672 -62.14364)
		(width 0.0889)
		(layer "In11.Cu")
		(net "M_J_DQ<55>")
	)
	(arc
		(start 118.152672 -57.190386)
		(mid 118.231803 -56.894984)
		(end 118.152672 -56.599582)
		(width 0.0889)
		(layer "In11.Cu")
		(net "M_J_DQ<55>")
	)
	(arc
		(start 118.152672 -59.57189)
		(mid 118.099202 -59.376827)
		(end 118.147846 -59.180476)
		(width 0.0889)
		(layer "In11.Cu")
		(net "M_J_DQ<55>")
	)
	(arc
		(start 117.987572 -64.029336)
		(mid 118.034932 -63.899267)
		(end 118.03507 -63.760858)
		(width 0.0889)
		(layer "In11.Cu")
		(net "M_J_DQ<55>")
	)
	(segment
		(start 140.331698 0.28448)
		(end 140.331698 0.50292)
		(width 0.1651)
		(layer "F.Cu")
		(net "M_J_DQ<54>")
	)
	(segment
		(start 140.199364 -0.821182)
		(end 140.199618 -0.820928)
		(width 0.1651)
		(layer "F.Cu")
		(net "M_J_DQ<54>")
	)
	(segment
		(start 140.199618 -0.820928)
		(end 140.199618 0.1524)
		(width 0.1651)
		(layer "F.Cu")
		(net "M_J_DQ<54>")
	)
	(segment
		(start 140.331698 0.50292)
		(end 140.199618 0.635)
		(width 0.1651)
		(layer "F.Cu")
		(net "M_J_DQ<54>")
	)
	(segment
		(start 140.199618 0.1524)
		(end 140.331698 0.28448)
		(width 0.1651)
		(layer "F.Cu")
		(net "M_J_DQ<54>")
	)
	(segment
		(start 140.199618 0.939546)
		(end 140.199364 0.9398)
		(width 0.1651)
		(layer "F.Cu")
		(net "M_J_DQ<54>")
	)
	(segment
		(start 140.199618 0.635)
		(end 140.199618 0.939546)
		(width 0.1651)
		(layer "F.Cu")
		(net "M_J_DQ<54>")
	)
	(segment
		(start 118.212362 -62.838584)
		(end 117.640862 -62.838584)
		(width 0.0889)
		(layer "F.Cu")
		(net "M_J_DQ<54>")
	)
	(via
		(at 140.199364 0.9398)
		(size 0.508)
		(drill 0.254)
		(layers "F.Cu" "B.Cu")
		(net "M_J_DQ<54>")
	)
	(via
		(at 117.640862 -62.838584)
		(size 0.508)
		(drill 0.254)
		(layers "F.Cu" "B.Cu")
		(net "M_J_DQ<54>")
	)
	(via
		(at 139.34948 -4.357878)
		(size 0.508)
		(drill 0.254)
		(layers "F.Cu" "B.Cu")
		(net "M_J_DQ<54>")
	)
	(segment
		(start 139.34948 -5.621782)
		(end 139.34948 -4.357878)
		(width 0.1651)
		(layer "B.Cu")
		(net "M_J_DQ<54>")
	)
	(segment
		(start 118.041166 -54.913784)
		(end 118.041166 -54.587648)
		(width 0.0889)
		(layer "In11.Cu")
		(net "M_J_DQ<54>")
	)
	(segment
		(start 139.894564 -16.448786)
		(end 139.81557 -16.369792)
		(width 0.14224)
		(layer "In11.Cu")
		(net "M_J_DQ<54>")
	)
	(segment
		(start 122.82805 -39.067486)
		(end 123.045982 -39.285418)
		(width 0.14224)
		(layer "In11.Cu")
		(net "M_J_DQ<54>")
	)
	(segment
		(start 139.545568 -21.06676)
		(end 139.545568 -19.208496)
		(width 0.14224)
		(layer "In11.Cu")
		(net "M_J_DQ<54>")
	)
	(segment
		(start 139.91717 -12.170156)
		(end 139.91717 -11.7856)
		(width 0.14224)
		(layer "In11.Cu")
		(net "M_J_DQ<54>")
	)
	(segment
		(start 139.86637 -4.874768)
		(end 139.34948 -4.357878)
		(width 0.14224)
		(layer "In11.Cu")
		(net "M_J_DQ<54>")
	)
	(segment
		(start 139.691364 -26.993596)
		(end 139.869164 -26.815796)
		(width 0.14224)
		(layer "In11.Cu")
		(net "M_J_DQ<54>")
	)
	(segment
		(start 123.24715 -39.285418)
		(end 123.505976 -39.026592)
		(width 0.14224)
		(layer "In11.Cu")
		(net "M_J_DQ<54>")
	)
	(segment
		(start 117.933978 -62.669674)
		(end 117.957854 -62.58052)
		(width 0.0889)
		(layer "In11.Cu")
		(net "M_J_DQ<54>")
	)
	(segment
		(start 139.71397 -12.373356)
		(end 139.91717 -12.170156)
		(width 0.14224)
		(layer "In11.Cu")
		(net "M_J_DQ<54>")
	)
	(segment
		(start 123.748038 -38.147498)
		(end 123.96597 -38.36543)
		(width 0.14224)
		(layer "In11.Cu")
		(net "M_J_DQ<54>")
	)
	(segment
		(start 117.858286 -51.415696)
		(end 118.144036 -51.129946)
		(width 0.0889)
		(layer "In11.Cu")
		(net "M_J_DQ<54>")
	)
	(segment
		(start 123.288044 -38.406324)
		(end 123.54687 -38.147498)
		(width 0.14224)
		(layer "In11.Cu")
		(net "M_J_DQ<54>")
	)
	(segment
		(start 139.460986 -0.076454)
		(end 139.824968 0.287528)
		(width 0.14224)
		(layer "In11.Cu")
		(net "M_J_DQ<54>")
	)
	(segment
		(start 118.144036 -51.129946)
		(end 118.144036 -48.989742)
		(width 0.0889)
		(layer "In11.Cu")
		(net "M_J_DQ<54>")
	)
	(segment
		(start 117.981222 -60.077858)
		(end 117.987572 -60.06719)
		(width 0.0889)
		(layer "In11.Cu")
		(net "M_J_DQ<54>")
	)
	(segment
		(start 124.208032 -37.687504)
		(end 124.208032 -37.486336)
		(width 0.14224)
		(layer "In11.Cu")
		(net "M_J_DQ<54>")
	)
	(segment
		(start 124.838968 -36.8554)
		(end 132.503418 -36.8554)
		(width 0.14224)
		(layer "In11.Cu")
		(net "M_J_DQ<54>")
	)
	(segment
		(start 117.987572 -61.05779)
		(end 117.992398 -61.049154)
		(width 0.0889)
		(layer "In11.Cu")
		(net "M_J_DQ<54>")
	)
	(segment
		(start 139.894564 -16.829786)
		(end 139.894564 -16.448786)
		(width 0.14224)
		(layer "In11.Cu")
		(net "M_J_DQ<54>")
	)
	(segment
		(start 117.987572 -59.07659)
		(end 117.992398 -59.067954)
		(width 0.0889)
		(layer "In11.Cu")
		(net "M_J_DQ<54>")
	)
	(segment
		(start 124.425964 -38.106604)
		(end 124.425964 -37.905436)
		(width 0.14224)
		(layer "In11.Cu")
		(net "M_J_DQ<54>")
	)
	(segment
		(start 139.71397 -8.829802)
		(end 139.71397 -7.391146)
		(width 0.14224)
		(layer "In11.Cu")
		(net "M_J_DQ<54>")
	)
	(segment
		(start 124.167138 -38.36543)
		(end 124.425964 -38.106604)
		(width 0.14224)
		(layer "In11.Cu")
		(net "M_J_DQ<54>")
	)
	(segment
		(start 117.858286 -54.404768)
		(end 117.858286 -51.415696)
		(width 0.0889)
		(layer "In11.Cu")
		(net "M_J_DQ<54>")
	)
	(segment
		(start 118.041166 -54.587648)
		(end 117.858286 -54.404768)
		(width 0.0889)
		(layer "In11.Cu")
		(net "M_J_DQ<54>")
	)
	(segment
		(start 139.71397 -7.391146)
		(end 139.86637 -7.238746)
		(width 0.14224)
		(layer "In11.Cu")
		(net "M_J_DQ<54>")
	)
	(segment
		(start 139.869164 -23.301452)
		(end 139.665964 -23.098252)
		(width 0.14224)
		(layer "In11.Cu")
		(net "M_J_DQ<54>")
	)
	(segment
		(start 122.626882 -39.067486)
		(end 122.82805 -39.067486)
		(width 0.14224)
		(layer "In11.Cu")
		(net "M_J_DQ<54>")
	)
	(segment
		(start 123.54687 -38.147498)
		(end 123.748038 -38.147498)
		(width 0.14224)
		(layer "In11.Cu")
		(net "M_J_DQ<54>")
	)
	(segment
		(start 122.09272 -39.601648)
		(end 122.626882 -39.067486)
		(width 0.14224)
		(layer "In11.Cu")
		(net "M_J_DQ<54>")
	)
	(segment
		(start 139.869164 -21.390356)
		(end 139.545568 -21.06676)
		(width 0.14224)
		(layer "In11.Cu")
		(net "M_J_DQ<54>")
	)
	(segment
		(start 139.545568 -19.208496)
		(end 139.869164 -18.8849)
		(width 0.14224)
		(layer "In11.Cu")
		(net "M_J_DQ<54>")
	)
	(segment
		(start 139.34948 -4.357878)
		(end 139.113768 -4.122166)
		(width 0.14224)
		(layer "In11.Cu")
		(net "M_J_DQ<54>")
	)
	(segment
		(start 124.208032 -37.486336)
		(end 124.838968 -36.8554)
		(width 0.14224)
		(layer "In11.Cu")
		(net "M_J_DQ<54>")
	)
	(segment
		(start 117.981222 -61.068458)
		(end 117.987572 -61.05779)
		(width 0.0889)
		(layer "In11.Cu")
		(net "M_J_DQ<54>")
	)
	(segment
		(start 139.71397 -13.595604)
		(end 139.71397 -12.373356)
		(width 0.14224)
		(layer "In11.Cu")
		(net "M_J_DQ<54>")
	)
	(segment
		(start 139.824968 0.287528)
		(end 139.824968 0.565404)
		(width 0.14224)
		(layer "In11.Cu")
		(net "M_J_DQ<54>")
	)
	(segment
		(start 139.691364 -28.136596)
		(end 139.691364 -26.993596)
		(width 0.14224)
		(layer "In11.Cu")
		(net "M_J_DQ<54>")
	)
	(segment
		(start 139.869164 -21.684996)
		(end 139.869164 -21.390356)
		(width 0.14224)
		(layer "In11.Cu")
		(net "M_J_DQ<54>")
	)
	(segment
		(start 117.981222 -58.096658)
		(end 117.987572 -58.08599)
		(width 0.0889)
		(layer "In11.Cu")
		(net "M_J_DQ<54>")
	)
	(segment
		(start 139.80668 -28.251912)
		(end 139.691364 -28.136596)
		(width 0.14224)
		(layer "In11.Cu")
		(net "M_J_DQ<54>")
	)
	(segment
		(start 139.113768 -4.122166)
		(end 139.113768 -3.327654)
		(width 0.14224)
		(layer "In11.Cu")
		(net "M_J_DQ<54>")
	)
	(segment
		(start 118.953788 -47.733966)
		(end 118.731792 -47.51197)
		(width 0.0889)
		(layer "In11.Cu")
		(net "M_J_DQ<54>")
	)
	(segment
		(start 139.723368 -11.591798)
		(end 139.723368 -9.6012)
		(width 0.14224)
		(layer "In11.Cu")
		(net "M_J_DQ<54>")
	)
	(segment
		(start 139.886436 -2.203196)
		(end 139.460986 -1.777746)
		(width 0.14224)
		(layer "In11.Cu")
		(net "M_J_DQ<54>")
	)
	(segment
		(start 139.824968 0.565404)
		(end 140.199364 0.9398)
		(width 0.14224)
		(layer "In11.Cu")
		(net "M_J_DQ<54>")
	)
	(segment
		(start 139.460986 -1.492504)
		(end 139.841986 -1.111504)
		(width 0.14224)
		(layer "In11.Cu")
		(net "M_J_DQ<54>")
	)
	(segment
		(start 139.665964 -21.888196)
		(end 139.869164 -21.684996)
		(width 0.14224)
		(layer "In11.Cu")
		(net "M_J_DQ<54>")
	)
	(segment
		(start 118.144036 -48.989742)
		(end 118.953788 -48.17999)
		(width 0.0889)
		(layer "In11.Cu")
		(net "M_J_DQ<54>")
	)
	(segment
		(start 117.987572 -60.06719)
		(end 117.992398 -60.058554)
		(width 0.0889)
		(layer "In11.Cu")
		(net "M_J_DQ<54>")
	)
	(segment
		(start 139.723368 -9.6012)
		(end 139.91717 -9.407398)
		(width 0.14224)
		(layer "In11.Cu")
		(net "M_J_DQ<54>")
	)
	(segment
		(start 117.640862 -62.838584)
		(end 117.933978 -62.669674)
		(width 0.0889)
		(layer "In11.Cu")
		(net "M_J_DQ<54>")
	)
	(segment
		(start 139.869164 -18.8849)
		(end 139.869164 -18.58645)
		(width 0.14224)
		(layer "In11.Cu")
		(net "M_J_DQ<54>")
	)
	(segment
		(start 139.869164 -26.815796)
		(end 139.869164 -23.301452)
		(width 0.14224)
		(layer "In11.Cu")
		(net "M_J_DQ<54>")
	)
	(segment
		(start 117.987572 -58.08599)
		(end 117.992398 -58.077354)
		(width 0.0889)
		(layer "In11.Cu")
		(net "M_J_DQ<54>")
	)
	(segment
		(start 139.716764 -18.43405)
		(end 139.716764 -17.007586)
		(width 0.14224)
		(layer "In11.Cu")
		(net "M_J_DQ<54>")
	)
	(segment
		(start 139.716764 -17.007586)
		(end 139.894564 -16.829786)
		(width 0.14224)
		(layer "In11.Cu")
		(net "M_J_DQ<54>")
	)
	(segment
		(start 124.425964 -37.905436)
		(end 124.208032 -37.687504)
		(width 0.14224)
		(layer "In11.Cu")
		(net "M_J_DQ<54>")
	)
	(segment
		(start 139.81557 -16.369792)
		(end 139.81557 -13.697204)
		(width 0.14224)
		(layer "In11.Cu")
		(net "M_J_DQ<54>")
	)
	(segment
		(start 139.886436 -2.554986)
		(end 139.886436 -2.203196)
		(width 0.14224)
		(layer "In11.Cu")
		(net "M_J_DQ<54>")
	)
	(segment
		(start 123.96597 -38.36543)
		(end 124.167138 -38.36543)
		(width 0.14224)
		(layer "In11.Cu")
		(net "M_J_DQ<54>")
	)
	(segment
		(start 139.91717 -11.7856)
		(end 139.723368 -11.591798)
		(width 0.14224)
		(layer "In11.Cu")
		(net "M_J_DQ<54>")
	)
	(segment
		(start 132.503418 -36.8554)
		(end 139.80668 -29.552138)
		(width 0.14224)
		(layer "In11.Cu")
		(net "M_J_DQ<54>")
	)
	(segment
		(start 139.81557 -13.697204)
		(end 139.71397 -13.595604)
		(width 0.14224)
		(layer "In11.Cu")
		(net "M_J_DQ<54>")
	)
	(segment
		(start 122.09272 -43.545506)
		(end 122.09272 -39.601648)
		(width 0.14224)
		(layer "In11.Cu")
		(net "M_J_DQ<54>")
	)
	(segment
		(start 139.841986 -0.768096)
		(end 139.460986 -0.387096)
		(width 0.14224)
		(layer "In11.Cu")
		(net "M_J_DQ<54>")
	)
	(segment
		(start 123.505976 -39.026592)
		(end 123.505976 -38.825424)
		(width 0.14224)
		(layer "In11.Cu")
		(net "M_J_DQ<54>")
	)
	(segment
		(start 118.731792 -46.906434)
		(end 122.09272 -43.545506)
		(width 0.14224)
		(layer "In11.Cu")
		(net "M_J_DQ<54>")
	)
	(segment
		(start 139.80668 -29.552138)
		(end 139.80668 -28.251912)
		(width 0.14224)
		(layer "In11.Cu")
		(net "M_J_DQ<54>")
	)
	(segment
		(start 139.869164 -18.58645)
		(end 139.716764 -18.43405)
		(width 0.14224)
		(layer "In11.Cu")
		(net "M_J_DQ<54>")
	)
	(segment
		(start 123.505976 -38.825424)
		(end 123.288044 -38.607492)
		(width 0.14224)
		(layer "In11.Cu")
		(net "M_J_DQ<54>")
	)
	(segment
		(start 139.460986 -1.777746)
		(end 139.460986 -1.492504)
		(width 0.14224)
		(layer "In11.Cu")
		(net "M_J_DQ<54>")
	)
	(segment
		(start 118.731792 -47.51197)
		(end 118.731792 -46.906434)
		(width 0.14224)
		(layer "In11.Cu")
		(net "M_J_DQ<54>")
	)
	(segment
		(start 123.288044 -38.607492)
		(end 123.288044 -38.406324)
		(width 0.14224)
		(layer "In11.Cu")
		(net "M_J_DQ<54>")
	)
	(segment
		(start 139.841986 -1.111504)
		(end 139.841986 -0.768096)
		(width 0.14224)
		(layer "In11.Cu")
		(net "M_J_DQ<54>")
	)
	(segment
		(start 139.91717 -9.033002)
		(end 139.71397 -8.829802)
		(width 0.14224)
		(layer "In11.Cu")
		(net "M_J_DQ<54>")
	)
	(segment
		(start 139.665964 -23.098252)
		(end 139.665964 -21.888196)
		(width 0.14224)
		(layer "In11.Cu")
		(net "M_J_DQ<54>")
	)
	(segment
		(start 139.460986 -0.387096)
		(end 139.460986 -0.076454)
		(width 0.14224)
		(layer "In11.Cu")
		(net "M_J_DQ<54>")
	)
	(segment
		(start 139.113768 -3.327654)
		(end 139.886436 -2.554986)
		(width 0.14224)
		(layer "In11.Cu")
		(net "M_J_DQ<54>")
	)
	(segment
		(start 118.953788 -48.17999)
		(end 118.953788 -47.733966)
		(width 0.0889)
		(layer "In11.Cu")
		(net "M_J_DQ<54>")
	)
	(segment
		(start 139.91717 -9.407398)
		(end 139.91717 -9.033002)
		(width 0.14224)
		(layer "In11.Cu")
		(net "M_J_DQ<54>")
	)
	(segment
		(start 139.86637 -7.238746)
		(end 139.86637 -4.874768)
		(width 0.14224)
		(layer "In11.Cu")
		(net "M_J_DQ<54>")
	)
	(segment
		(start 117.981222 -59.087258)
		(end 117.987572 -59.07659)
		(width 0.0889)
		(layer "In11.Cu")
		(net "M_J_DQ<54>")
	)
	(segment
		(start 123.045982 -39.285418)
		(end 123.24715 -39.285418)
		(width 0.14224)
		(layer "In11.Cu")
		(net "M_J_DQ<54>")
	)
	(arc
		(start 117.981222 -55.693818)
		(mid 117.908424 -55.403055)
		(end 117.987572 -55.113936)
		(width 0.0889)
		(layer "In11.Cu")
		(net "M_J_DQ<54>")
	)
	(arc
		(start 117.987572 -55.703724)
		(mid 117.984226 -55.698881)
		(end 117.981222 -55.693818)
		(width 0.0889)
		(layer "In11.Cu")
		(net "M_J_DQ<54>")
	)
	(arc
		(start 117.957854 -62.58052)
		(mid 117.909294 -62.310795)
		(end 117.987572 -62.048136)
		(width 0.0889)
		(layer "In11.Cu")
		(net "M_J_DQ<54>")
	)
	(arc
		(start 117.992398 -59.067954)
		(mid 118.041153 -58.871602)
		(end 117.987572 -58.67654)
		(width 0.0889)
		(layer "In11.Cu")
		(net "M_J_DQ<54>")
	)
	(arc
		(start 117.987572 -57.68594)
		(mid 117.908441 -57.390538)
		(end 117.987572 -57.095136)
		(width 0.0889)
		(layer "In11.Cu")
		(net "M_J_DQ<54>")
	)
	(arc
		(start 117.987572 -56.694832)
		(mid 117.908441 -56.39943)
		(end 117.987572 -56.104028)
		(width 0.0889)
		(layer "In11.Cu")
		(net "M_J_DQ<54>")
	)
	(arc
		(start 117.987572 -60.65774)
		(mid 117.90835 -60.368622)
		(end 117.981222 -60.077858)
		(width 0.0889)
		(layer "In11.Cu")
		(net "M_J_DQ<54>")
	)
	(arc
		(start 117.992398 -61.049154)
		(mid 118.041153 -60.852802)
		(end 117.987572 -60.65774)
		(width 0.0889)
		(layer "In11.Cu")
		(net "M_J_DQ<54>")
	)
	(arc
		(start 117.992398 -60.058554)
		(mid 118.041153 -59.862202)
		(end 117.987572 -59.66714)
		(width 0.0889)
		(layer "In11.Cu")
		(net "M_J_DQ<54>")
	)
	(arc
		(start 117.992398 -58.077354)
		(mid 118.041153 -57.881002)
		(end 117.987572 -57.68594)
		(width 0.0889)
		(layer "In11.Cu")
		(net "M_J_DQ<54>")
	)
	(arc
		(start 117.987572 -57.095136)
		(mid 118.041198 -56.894984)
		(end 117.987572 -56.694832)
		(width 0.0889)
		(layer "In11.Cu")
		(net "M_J_DQ<54>")
	)
	(arc
		(start 117.987572 -61.64834)
		(mid 117.908452 -61.359222)
		(end 117.981222 -61.068458)
		(width 0.0889)
		(layer "In11.Cu")
		(net "M_J_DQ<54>")
	)
	(arc
		(start 117.987572 -62.048136)
		(mid 118.041071 -61.848238)
		(end 117.987572 -61.64834)
		(width 0.0889)
		(layer "In11.Cu")
		(net "M_J_DQ<54>")
	)
	(arc
		(start 117.987572 -59.66714)
		(mid 117.90835 -59.378022)
		(end 117.981222 -59.087258)
		(width 0.0889)
		(layer "In11.Cu")
		(net "M_J_DQ<54>")
	)
	(arc
		(start 117.987572 -58.67654)
		(mid 117.90835 -58.387422)
		(end 117.981222 -58.096658)
		(width 0.0889)
		(layer "In11.Cu")
		(net "M_J_DQ<54>")
	)
	(arc
		(start 117.987572 -56.104028)
		(mid 118.041198 -55.903876)
		(end 117.987572 -55.703724)
		(width 0.0889)
		(layer "In11.Cu")
		(net "M_J_DQ<54>")
	)
	(arc
		(start 117.987572 -55.113936)
		(mid 118.027534 -55.017385)
		(end 118.041166 -54.913784)
		(width 0.0889)
		(layer "In11.Cu")
		(net "M_J_DQ<54>")
	)
	(segment
		(start 133.39953 3.778758)
		(end 133.39953 2.514854)
		(width 0.1651)
		(layer "F.Cu")
		(net "M_J_DQ<53>")
	)
	(segment
		(start 115.636802 -64.324738)
		(end 115.065302 -64.324738)
		(width 0.0889)
		(layer "F.Cu")
		(net "M_J_DQ<53>")
	)
	(via
		(at 115.065302 -64.324738)
		(size 0.508)
		(drill 0.254)
		(layers "F.Cu" "B.Cu")
		(net "M_J_DQ<53>")
	)
	(via
		(at 134.173214 -3.076956)
		(size 0.508)
		(drill 0.254)
		(layers "F.Cu" "B.Cu")
		(net "M_J_DQ<53>")
	)
	(via
		(at 133.39953 2.514854)
		(size 0.508)
		(drill 0.254)
		(layers "F.Cu" "B.Cu")
		(net "M_J_DQ<53>")
	)
	(segment
		(start 134.249414 -1.021842)
		(end 134.249414 -3.000756)
		(width 0.1651)
		(layer "B.Cu")
		(net "M_J_DQ<53>")
	)
	(segment
		(start 134.249414 -3.000756)
		(end 134.173214 -3.076956)
		(width 0.1651)
		(layer "B.Cu")
		(net "M_J_DQ<53>")
	)
	(segment
		(start 134.484618 -2.765552)
		(end 134.484618 0.53975)
		(width 0.14224)
		(layer "In11.Cu")
		(net "M_J_DQ<53>")
	)
	(segment
		(start 134.5692 -18.975832)
		(end 134.5692 -18.476214)
		(width 0.14224)
		(layer "In11.Cu")
		(net "M_J_DQ<53>")
	)
	(segment
		(start 134.590536 -29.234892)
		(end 134.590536 -28.259024)
		(width 0.14224)
		(layer "In11.Cu")
		(net "M_J_DQ<53>")
	)
	(segment
		(start 114.79784 -53.922676)
		(end 114.79784 -53.507132)
		(width 0.0889)
		(layer "In11.Cu")
		(net "M_J_DQ<53>")
	)
	(segment
		(start 114.724942 -55.619904)
		(end 114.718592 -55.609236)
		(width 0.0889)
		(layer "In11.Cu")
		(net "M_J_DQ<53>")
	)
	(segment
		(start 114.718592 -55.609236)
		(end 114.713766 -55.6006)
		(width 0.0889)
		(layer "In11.Cu")
		(net "M_J_DQ<53>")
	)
	(segment
		(start 133.66877 -3.582416)
		(end 133.957314 -3.293872)
		(width 0.14224)
		(layer "In11.Cu")
		(net "M_J_DQ<53>")
	)
	(segment
		(start 114.704368 -47.159926)
		(end 114.704368 -45.329602)
		(width 0.14224)
		(layer "In11.Cu")
		(net "M_J_DQ<53>")
	)
	(segment
		(start 134.64667 -8.902446)
		(end 134.64667 -7.327646)
		(width 0.14224)
		(layer "In11.Cu")
		(net "M_J_DQ<53>")
	)
	(segment
		(start 130.288284 -30.0228)
		(end 130.694684 -30.0228)
		(width 0.14224)
		(layer "In11.Cu")
		(net "M_J_DQ<53>")
	)
	(segment
		(start 130.085084 -30.226)
		(end 130.288284 -30.0228)
		(width 0.14224)
		(layer "In11.Cu")
		(net "M_J_DQ<53>")
	)
	(segment
		(start 114.718592 -60.562236)
		(end 114.713766 -60.5536)
		(width 0.0889)
		(layer "In11.Cu")
		(net "M_J_DQ<53>")
	)
	(segment
		(start 134.55777 -12.198858)
		(end 134.55777 -8.991346)
		(width 0.14224)
		(layer "In11.Cu")
		(net "M_J_DQ<53>")
	)
	(segment
		(start 134.744968 -19.1516)
		(end 134.5692 -18.975832)
		(width 0.14224)
		(layer "In11.Cu")
		(net "M_J_DQ<53>")
	)
	(segment
		(start 134.58317 -7.264146)
		(end 134.58317 -6.670802)
		(width 0.14224)
		(layer "In11.Cu")
		(net "M_J_DQ<53>")
	)
	(segment
		(start 134.281164 1.5494)
		(end 133.970268 1.5494)
		(width 0.14224)
		(layer "In11.Cu")
		(net "M_J_DQ<53>")
	)
	(segment
		(start 114.469672 -47.394622)
		(end 114.704368 -47.159926)
		(width 0.0889)
		(layer "In11.Cu")
		(net "M_J_DQ<53>")
	)
	(segment
		(start 133.39953 2.120138)
		(end 133.39953 2.514854)
		(width 0.14224)
		(layer "In11.Cu")
		(net "M_J_DQ<53>")
	)
	(segment
		(start 134.738364 -12.379452)
		(end 134.55777 -12.198858)
		(width 0.14224)
		(layer "In11.Cu")
		(net "M_J_DQ<53>")
	)
	(segment
		(start 134.211568 -6.2992)
		(end 134.211568 -4.483354)
		(width 0.14224)
		(layer "In11.Cu")
		(net "M_J_DQ<53>")
	)
	(segment
		(start 114.718592 -56.599836)
		(end 114.713766 -56.5912)
		(width 0.0889)
		(layer "In11.Cu")
		(net "M_J_DQ<53>")
	)
	(segment
		(start 114.469672 -53.178964)
		(end 114.469672 -47.394622)
		(width 0.0889)
		(layer "In11.Cu")
		(net "M_J_DQ<53>")
	)
	(segment
		(start 133.957314 -3.293872)
		(end 133.957314 -3.292856)
		(width 0.14224)
		(layer "In11.Cu")
		(net "M_J_DQ<53>")
	)
	(segment
		(start 114.724942 -61.563504)
		(end 114.718592 -61.552836)
		(width 0.0889)
		(layer "In11.Cu")
		(net "M_J_DQ<53>")
	)
	(segment
		(start 114.704368 -45.329602)
		(end 117.800374 -42.233596)
		(width 0.14224)
		(layer "In11.Cu")
		(net "M_J_DQ<53>")
	)
	(segment
		(start 117.800374 -42.233596)
		(end 117.800374 -38.6207)
		(width 0.14224)
		(layer "In11.Cu")
		(net "M_J_DQ<53>")
	)
	(segment
		(start 134.681468 1.149096)
		(end 134.281164 1.5494)
		(width 0.14224)
		(layer "In11.Cu")
		(net "M_J_DQ<53>")
	)
	(segment
		(start 114.724942 -57.601104)
		(end 114.718592 -57.590436)
		(width 0.0889)
		(layer "In11.Cu")
		(net "M_J_DQ<53>")
	)
	(segment
		(start 134.590536 -28.259024)
		(end 134.666736 -28.182824)
		(width 0.14224)
		(layer "In11.Cu")
		(net "M_J_DQ<53>")
	)
	(segment
		(start 134.484618 0.53975)
		(end 134.681468 0.7366)
		(width 0.14224)
		(layer "In11.Cu")
		(net "M_J_DQ<53>")
	)
	(segment
		(start 115.39474 -63.563754)
		(end 115.416838 -63.5254)
		(width 0.0889)
		(layer "In11.Cu")
		(net "M_J_DQ<53>")
	)
	(segment
		(start 134.55777 -8.991346)
		(end 134.64667 -8.902446)
		(width 0.14224)
		(layer "In11.Cu")
		(net "M_J_DQ<53>")
	)
	(segment
		(start 134.763764 -23.183596)
		(end 134.763764 -21.980652)
		(width 0.14224)
		(layer "In11.Cu")
		(net "M_J_DQ<53>")
	)
	(segment
		(start 134.666736 -28.182824)
		(end 134.666736 -26.862024)
		(width 0.14224)
		(layer "In11.Cu")
		(net "M_J_DQ<53>")
	)
	(segment
		(start 130.694684 -30.0228)
		(end 130.974084 -30.3022)
		(width 0.14224)
		(layer "In11.Cu")
		(net "M_J_DQ<53>")
	)
	(segment
		(start 130.974084 -30.3022)
		(end 133.523228 -30.3022)
		(width 0.14224)
		(layer "In11.Cu")
		(net "M_J_DQ<53>")
	)
	(segment
		(start 134.64667 -7.327646)
		(end 134.58317 -7.264146)
		(width 0.14224)
		(layer "In11.Cu")
		(net "M_J_DQ<53>")
	)
	(segment
		(start 134.560564 -13.709396)
		(end 134.738364 -13.531596)
		(width 0.14224)
		(layer "In11.Cu")
		(net "M_J_DQ<53>")
	)
	(segment
		(start 117.800374 -38.6207)
		(end 124.366274 -32.0548)
		(width 0.14224)
		(layer "In11.Cu")
		(net "M_J_DQ<53>")
	)
	(segment
		(start 114.724942 -60.572904)
		(end 114.718592 -60.562236)
		(width 0.0889)
		(layer "In11.Cu")
		(net "M_J_DQ<53>")
	)
	(segment
		(start 114.724942 -56.610504)
		(end 114.718592 -56.599836)
		(width 0.0889)
		(layer "In11.Cu")
		(net "M_J_DQ<53>")
	)
	(segment
		(start 133.66877 -3.940556)
		(end 133.66877 -3.582416)
		(width 0.14224)
		(layer "In11.Cu")
		(net "M_J_DQ<53>")
	)
	(segment
		(start 115.246404 -63.9064)
		(end 115.37823 -63.6016)
		(width 0.0889)
		(layer "In11.Cu")
		(net "M_J_DQ<53>")
	)
	(segment
		(start 134.744968 -21.185632)
		(end 134.744968 -19.1516)
		(width 0.14224)
		(layer "In11.Cu")
		(net "M_J_DQ<53>")
	)
	(segment
		(start 114.724942 -54.629304)
		(end 114.718592 -54.618636)
		(width 0.0889)
		(layer "In11.Cu")
		(net "M_J_DQ<53>")
	)
	(segment
		(start 134.666736 -26.862024)
		(end 134.585964 -26.781252)
		(width 0.14224)
		(layer "In11.Cu")
		(net "M_J_DQ<53>")
	)
	(segment
		(start 115.358164 -63.040768)
		(end 114.91341 -62.71387)
		(width 0.0889)
		(layer "In11.Cu")
		(net "M_J_DQ<53>")
	)
	(segment
		(start 134.173214 -3.076956)
		(end 134.484618 -2.765552)
		(width 0.14224)
		(layer "In11.Cu")
		(net "M_J_DQ<53>")
	)
	(segment
		(start 115.37823 -63.6016)
		(end 115.39474 -63.563754)
		(width 0.0889)
		(layer "In11.Cu")
		(net "M_J_DQ<53>")
	)
	(segment
		(start 133.957314 -3.292856)
		(end 134.173214 -3.076956)
		(width 0.14224)
		(layer "In11.Cu")
		(net "M_J_DQ<53>")
	)
	(segment
		(start 134.5692 -21.3614)
		(end 134.744968 -21.185632)
		(width 0.14224)
		(layer "In11.Cu")
		(net "M_J_DQ<53>")
	)
	(segment
		(start 134.681468 0.7366)
		(end 134.681468 1.149096)
		(width 0.14224)
		(layer "In11.Cu")
		(net "M_J_DQ<53>")
	)
	(segment
		(start 134.58317 -6.670802)
		(end 134.211568 -6.2992)
		(width 0.14224)
		(layer "In11.Cu")
		(net "M_J_DQ<53>")
	)
	(segment
		(start 114.79784 -53.507132)
		(end 114.469672 -53.178964)
		(width 0.0889)
		(layer "In11.Cu")
		(net "M_J_DQ<53>")
	)
	(segment
		(start 134.211568 -4.483354)
		(end 133.66877 -3.940556)
		(width 0.14224)
		(layer "In11.Cu")
		(net "M_J_DQ<53>")
	)
	(segment
		(start 134.585964 -23.361396)
		(end 134.763764 -23.183596)
		(width 0.14224)
		(layer "In11.Cu")
		(net "M_J_DQ<53>")
	)
	(segment
		(start 134.5692 -18.476214)
		(end 134.712964 -18.33245)
		(width 0.14224)
		(layer "In11.Cu")
		(net "M_J_DQ<53>")
	)
	(segment
		(start 134.712964 -18.33245)
		(end 134.712964 -17.159986)
		(width 0.14224)
		(layer "In11.Cu")
		(net "M_J_DQ<53>")
	)
	(segment
		(start 114.718592 -57.590436)
		(end 114.713766 -57.5818)
		(width 0.0889)
		(layer "In11.Cu")
		(net "M_J_DQ<53>")
	)
	(segment
		(start 124.366274 -32.0548)
		(end 128.561084 -32.0548)
		(width 0.14224)
		(layer "In11.Cu")
		(net "M_J_DQ<53>")
	)
	(segment
		(start 115.065302 -64.324738)
		(end 115.246404 -63.9064)
		(width 0.0889)
		(layer "In11.Cu")
		(net "M_J_DQ<53>")
	)
	(segment
		(start 130.085084 -30.5308)
		(end 130.085084 -30.226)
		(width 0.14224)
		(layer "In11.Cu")
		(net "M_J_DQ<53>")
	)
	(segment
		(start 134.763764 -21.980652)
		(end 134.5692 -21.786088)
		(width 0.14224)
		(layer "In11.Cu")
		(net "M_J_DQ<53>")
	)
	(segment
		(start 114.718592 -58.581036)
		(end 114.713766 -58.5724)
		(width 0.0889)
		(layer "In11.Cu")
		(net "M_J_DQ<53>")
	)
	(segment
		(start 128.561084 -32.0548)
		(end 130.085084 -30.5308)
		(width 0.14224)
		(layer "In11.Cu")
		(net "M_J_DQ<53>")
	)
	(segment
		(start 134.560564 -17.007586)
		(end 134.560564 -13.709396)
		(width 0.14224)
		(layer "In11.Cu")
		(net "M_J_DQ<53>")
	)
	(segment
		(start 115.412012 -63.133986)
		(end 115.358164 -63.040768)
		(width 0.0889)
		(layer "In11.Cu")
		(net "M_J_DQ<53>")
	)
	(segment
		(start 114.718592 -61.552836)
		(end 114.713766 -61.5442)
		(width 0.0889)
		(layer "In11.Cu")
		(net "M_J_DQ<53>")
	)
	(segment
		(start 134.585964 -26.781252)
		(end 134.585964 -23.361396)
		(width 0.14224)
		(layer "In11.Cu")
		(net "M_J_DQ<53>")
	)
	(segment
		(start 133.523228 -30.3022)
		(end 134.590536 -29.234892)
		(width 0.14224)
		(layer "In11.Cu")
		(net "M_J_DQ<53>")
	)
	(segment
		(start 133.970268 1.5494)
		(end 133.39953 2.120138)
		(width 0.14224)
		(layer "In11.Cu")
		(net "M_J_DQ<53>")
	)
	(segment
		(start 134.712964 -17.159986)
		(end 134.560564 -17.007586)
		(width 0.14224)
		(layer "In11.Cu")
		(net "M_J_DQ<53>")
	)
	(segment
		(start 134.5692 -21.786088)
		(end 134.5692 -21.3614)
		(width 0.14224)
		(layer "In11.Cu")
		(net "M_J_DQ<53>")
	)
	(segment
		(start 134.738364 -13.531596)
		(end 134.738364 -12.379452)
		(width 0.14224)
		(layer "In11.Cu")
		(net "M_J_DQ<53>")
	)
	(segment
		(start 114.718592 -59.171586)
		(end 114.724942 -59.160918)
		(width 0.0889)
		(layer "In11.Cu")
		(net "M_J_DQ<53>")
	)
	(segment
		(start 114.718592 -54.618636)
		(end 114.713766 -54.61)
		(width 0.0889)
		(layer "In11.Cu")
		(net "M_J_DQ<53>")
	)
	(arc
		(start 114.713766 -58.5724)
		(mid 114.665011 -58.376048)
		(end 114.718592 -58.180986)
		(width 0.0889)
		(layer "In11.Cu")
		(net "M_J_DQ<53>")
	)
	(arc
		(start 114.713766 -57.5818)
		(mid 114.665011 -57.385448)
		(end 114.718592 -57.190386)
		(width 0.0889)
		(layer "In11.Cu")
		(net "M_J_DQ<53>")
	)
	(arc
		(start 114.718592 -60.162186)
		(mid 114.797723 -59.866784)
		(end 114.718592 -59.571382)
		(width 0.0889)
		(layer "In11.Cu")
		(net "M_J_DQ<53>")
	)
	(arc
		(start 114.718592 -57.190386)
		(mid 114.797814 -56.901268)
		(end 114.724942 -56.610504)
		(width 0.0889)
		(layer "In11.Cu")
		(net "M_J_DQ<53>")
	)
	(arc
		(start 114.713766 -61.5442)
		(mid 114.665011 -61.347848)
		(end 114.718592 -61.152786)
		(width 0.0889)
		(layer "In11.Cu")
		(net "M_J_DQ<53>")
	)
	(arc
		(start 114.91341 -62.71387)
		(mid 114.6865 -62.472868)
		(end 114.718592 -62.143386)
		(width 0.0889)
		(layer "In11.Cu")
		(net "M_J_DQ<53>")
	)
	(arc
		(start 114.718592 -62.143386)
		(mid 114.797814 -61.854268)
		(end 114.724942 -61.563504)
		(width 0.0889)
		(layer "In11.Cu")
		(net "M_J_DQ<53>")
	)
	(arc
		(start 114.713766 -55.6006)
		(mid 114.665011 -55.404248)
		(end 114.718592 -55.209186)
		(width 0.0889)
		(layer "In11.Cu")
		(net "M_J_DQ<53>")
	)
	(arc
		(start 114.718592 -56.199786)
		(mid 114.797814 -55.910668)
		(end 114.724942 -55.619904)
		(width 0.0889)
		(layer "In11.Cu")
		(net "M_J_DQ<53>")
	)
	(arc
		(start 114.718592 -58.180986)
		(mid 114.797814 -57.891868)
		(end 114.724942 -57.601104)
		(width 0.0889)
		(layer "In11.Cu")
		(net "M_J_DQ<53>")
	)
	(arc
		(start 114.713766 -60.5536)
		(mid 114.665011 -60.357248)
		(end 114.718592 -60.162186)
		(width 0.0889)
		(layer "In11.Cu")
		(net "M_J_DQ<53>")
	)
	(arc
		(start 114.718592 -61.152786)
		(mid 114.797814 -60.863668)
		(end 114.724942 -60.572904)
		(width 0.0889)
		(layer "In11.Cu")
		(net "M_J_DQ<53>")
	)
	(arc
		(start 114.718592 -54.218586)
		(mid 114.777725 -54.075855)
		(end 114.79784 -53.922676)
		(width 0.0889)
		(layer "In11.Cu")
		(net "M_J_DQ<53>")
	)
	(arc
		(start 114.724942 -59.160918)
		(mid 114.79774 -58.870155)
		(end 114.718592 -58.581036)
		(width 0.0889)
		(layer "In11.Cu")
		(net "M_J_DQ<53>")
	)
	(arc
		(start 114.713766 -54.61)
		(mid 114.665011 -54.413648)
		(end 114.718592 -54.218586)
		(width 0.0889)
		(layer "In11.Cu")
		(net "M_J_DQ<53>")
	)
	(arc
		(start 114.718592 -59.571382)
		(mid 114.665093 -59.371484)
		(end 114.718592 -59.171586)
		(width 0.0889)
		(layer "In11.Cu")
		(net "M_J_DQ<53>")
	)
	(arc
		(start 115.416838 -63.5254)
		(mid 115.465593 -63.329048)
		(end 115.412012 -63.133986)
		(width 0.0889)
		(layer "In11.Cu")
		(net "M_J_DQ<53>")
	)
	(arc
		(start 114.718592 -55.209186)
		(mid 114.797814 -54.920068)
		(end 114.724942 -54.629304)
		(width 0.0889)
		(layer "In11.Cu")
		(net "M_J_DQ<53>")
	)
	(arc
		(start 114.713766 -56.5912)
		(mid 114.665011 -56.394848)
		(end 114.718592 -56.199786)
		(width 0.0889)
		(layer "In11.Cu")
		(net "M_J_DQ<53>")
	)
	(segment
		(start 115.636802 -63.334138)
		(end 115.065302 -63.334138)
		(width 0.0889)
		(layer "F.Cu")
		(net "M_J_DQ<52>")
	)
	(segment
		(start 134.249414 0.510032)
		(end 134.15137 1.0414)
		(width 0.1651)
		(layer "F.Cu")
		(net "M_J_DQ<52>")
	)
	(segment
		(start 134.249414 -0.821182)
		(end 134.249414 0.510032)
		(width 0.1651)
		(layer "F.Cu")
		(net "M_J_DQ<52>")
	)
	(via
		(at 134.15137 1.0414)
		(size 0.508)
		(drill 0.254)
		(layers "F.Cu" "B.Cu")
		(net "M_J_DQ<52>")
	)
	(via
		(at 133.39953 -4.357878)
		(size 0.508)
		(drill 0.254)
		(layers "F.Cu" "B.Cu")
		(net "M_J_DQ<52>")
	)
	(via
		(at 115.065302 -63.334138)
		(size 0.508)
		(drill 0.254)
		(layers "F.Cu" "B.Cu")
		(net "M_J_DQ<52>")
	)
	(segment
		(start 133.39953 -5.621782)
		(end 133.39953 -4.357878)
		(width 0.1651)
		(layer "B.Cu")
		(net "M_J_DQ<52>")
	)
	(segment
		(start 133.511036 -0.381)
		(end 133.511036 -0.076454)
		(width 0.14224)
		(layer "In11.Cu")
		(net "M_J_DQ<52>")
	)
	(segment
		(start 126.891542 -29.972)
		(end 127.094742 -30.1752)
		(width 0.14224)
		(layer "In11.Cu")
		(net "M_J_DQ<52>")
	)
	(segment
		(start 133.539484 -29.3878)
		(end 133.881368 -29.045916)
		(width 0.14224)
		(layer "In11.Cu")
		(net "M_J_DQ<52>")
	)
	(segment
		(start 133.671564 -22.015196)
		(end 133.874764 -21.811996)
		(width 0.14224)
		(layer "In11.Cu")
		(net "M_J_DQ<52>")
	)
	(segment
		(start 114.145568 -44.963842)
		(end 117.288564 -41.820846)
		(width 0.14224)
		(layer "In11.Cu")
		(net "M_J_DQ<52>")
	)
	(segment
		(start 133.66877 -7.476998)
		(end 133.89737 -7.248398)
		(width 0.14224)
		(layer "In11.Cu")
		(net "M_J_DQ<52>")
	)
	(segment
		(start 133.39953 -6.376162)
		(end 133.39953 -4.357878)
		(width 0.14224)
		(layer "In11.Cu")
		(net "M_J_DQ<52>")
	)
	(segment
		(start 127.907542 -29.53004)
		(end 128.049782 -29.3878)
		(width 0.14224)
		(layer "In11.Cu")
		(net "M_J_DQ<52>")
	)
	(segment
		(start 133.671564 -23.107396)
		(end 133.671564 -22.015196)
		(width 0.14224)
		(layer "In11.Cu")
		(net "M_J_DQ<52>")
	)
	(segment
		(start 114.558318 -56.703722)
		(end 114.553492 -56.695086)
		(width 0.0889)
		(layer "In11.Cu")
		(net "M_J_DQ<52>")
	)
	(segment
		(start 133.875018 -2.616454)
		(end 133.875018 -2.141728)
		(width 0.14224)
		(layer "In11.Cu")
		(net "M_J_DQ<52>")
	)
	(segment
		(start 133.874764 -18.506186)
		(end 133.646164 -18.277586)
		(width 0.14224)
		(layer "In11.Cu")
		(net "M_J_DQ<52>")
	)
	(segment
		(start 114.558318 -61.656722)
		(end 114.553492 -61.648086)
		(width 0.0889)
		(layer "In11.Cu")
		(net "M_J_DQ<52>")
	)
	(segment
		(start 133.92277 -8.965946)
		(end 133.66877 -8.711946)
		(width 0.14224)
		(layer "In11.Cu")
		(net "M_J_DQ<52>")
	)
	(segment
		(start 114.558318 -60.666122)
		(end 114.553492 -60.657486)
		(width 0.0889)
		(layer "In11.Cu")
		(net "M_J_DQ<52>")
	)
	(segment
		(start 114.553492 -54.713886)
		(end 114.547142 -54.703218)
		(width 0.0889)
		(layer "In11.Cu")
		(net "M_J_DQ<52>")
	)
	(segment
		(start 133.696964 -12.388596)
		(end 133.92277 -12.16279)
		(width 0.14224)
		(layer "In11.Cu")
		(net "M_J_DQ<52>")
	)
	(segment
		(start 133.881368 -29.045916)
		(end 133.881368 -28.337256)
		(width 0.14224)
		(layer "In11.Cu")
		(net "M_J_DQ<52>")
	)
	(segment
		(start 133.89737 -6.874002)
		(end 133.39953 -6.376162)
		(width 0.14224)
		(layer "In11.Cu")
		(net "M_J_DQ<52>")
	)
	(segment
		(start 114.553492 -55.704486)
		(end 114.547142 -55.693818)
		(width 0.0889)
		(layer "In11.Cu")
		(net "M_J_DQ<52>")
	)
	(segment
		(start 133.892036 -0.762)
		(end 133.511036 -0.381)
		(width 0.14224)
		(layer "In11.Cu")
		(net "M_J_DQ<52>")
	)
	(segment
		(start 133.66877 -8.711946)
		(end 133.66877 -7.476998)
		(width 0.14224)
		(layer "In11.Cu")
		(net "M_J_DQ<52>")
	)
	(segment
		(start 133.92277 -12.16279)
		(end 133.92277 -8.965946)
		(width 0.14224)
		(layer "In11.Cu")
		(net "M_J_DQ<52>")
	)
	(segment
		(start 128.049782 -29.3878)
		(end 133.539484 -29.3878)
		(width 0.14224)
		(layer "In11.Cu")
		(net "M_J_DQ<52>")
	)
	(segment
		(start 133.523736 -1.4351)
		(end 133.892036 -1.0668)
		(width 0.14224)
		(layer "In11.Cu")
		(net "M_J_DQ<52>")
	)
	(segment
		(start 133.646164 -17.100804)
		(end 133.925564 -16.821404)
		(width 0.14224)
		(layer "In11.Cu")
		(net "M_J_DQ<52>")
	)
	(segment
		(start 133.696964 -13.522452)
		(end 133.696964 -12.388596)
		(width 0.14224)
		(layer "In11.Cu")
		(net "M_J_DQ<52>")
	)
	(segment
		(start 114.558318 -59.675522)
		(end 114.553492 -59.666886)
		(width 0.0889)
		(layer "In11.Cu")
		(net "M_J_DQ<52>")
	)
	(segment
		(start 133.511036 -0.076454)
		(end 133.875018 0.287528)
		(width 0.14224)
		(layer "In11.Cu")
		(net "M_J_DQ<52>")
	)
	(segment
		(start 114.607086 -53.922676)
		(end 114.607086 -53.585872)
		(width 0.0889)
		(layer "In11.Cu")
		(net "M_J_DQ<52>")
	)
	(segment
		(start 133.881368 -28.337256)
		(end 133.696964 -28.152852)
		(width 0.14224)
		(layer "In11.Cu")
		(net "M_J_DQ<52>")
	)
	(segment
		(start 133.696964 -26.968196)
		(end 133.900164 -26.764996)
		(width 0.14224)
		(layer "In11.Cu")
		(net "M_J_DQ<52>")
	)
	(segment
		(start 133.892036 -1.0668)
		(end 133.892036 -0.762)
		(width 0.14224)
		(layer "In11.Cu")
		(net "M_J_DQ<52>")
	)
	(segment
		(start 114.553492 -57.685686)
		(end 114.547142 -57.675018)
		(width 0.0889)
		(layer "In11.Cu")
		(net "M_J_DQ<52>")
	)
	(segment
		(start 117.288564 -41.820846)
		(end 117.288564 -38.234366)
		(width 0.14224)
		(layer "In11.Cu")
		(net "M_J_DQ<52>")
	)
	(segment
		(start 133.875018 0.287528)
		(end 133.875018 0.765048)
		(width 0.14224)
		(layer "In11.Cu")
		(net "M_J_DQ<52>")
	)
	(segment
		(start 127.297942 -31.3944)
		(end 127.704342 -31.3944)
		(width 0.14224)
		(layer "In11.Cu")
		(net "M_J_DQ<52>")
	)
	(segment
		(start 114.558318 -54.722522)
		(end 114.553492 -54.713886)
		(width 0.0889)
		(layer "In11.Cu")
		(net "M_J_DQ<52>")
	)
	(segment
		(start 133.646164 -18.277586)
		(end 133.646164 -17.100804)
		(width 0.14224)
		(layer "In11.Cu")
		(net "M_J_DQ<52>")
	)
	(segment
		(start 115.065302 -63.334138)
		(end 114.657124 -62.770512)
		(width 0.0889)
		(layer "In11.Cu")
		(net "M_J_DQ<52>")
	)
	(segment
		(start 114.558318 -57.694322)
		(end 114.553492 -57.685686)
		(width 0.0889)
		(layer "In11.Cu")
		(net "M_J_DQ<52>")
	)
	(segment
		(start 133.925564 -13.751052)
		(end 133.696964 -13.522452)
		(width 0.14224)
		(layer "In11.Cu")
		(net "M_J_DQ<52>")
	)
	(segment
		(start 133.925564 -16.821404)
		(end 133.925564 -13.751052)
		(width 0.14224)
		(layer "In11.Cu")
		(net "M_J_DQ<52>")
	)
	(segment
		(start 133.874764 -19.005804)
		(end 133.874764 -18.506186)
		(width 0.14224)
		(layer "In11.Cu")
		(net "M_J_DQ<52>")
	)
	(segment
		(start 114.553492 -56.695086)
		(end 114.547142 -56.684418)
		(width 0.0889)
		(layer "In11.Cu")
		(net "M_J_DQ<52>")
	)
	(segment
		(start 114.553492 -62.638686)
		(end 114.547142 -62.628018)
		(width 0.0889)
		(layer "In11.Cu")
		(net "M_J_DQ<52>")
	)
	(segment
		(start 114.558318 -55.713122)
		(end 114.553492 -55.704486)
		(width 0.0889)
		(layer "In11.Cu")
		(net "M_J_DQ<52>")
	)
	(segment
		(start 133.163818 -3.327654)
		(end 133.875018 -2.616454)
		(width 0.14224)
		(layer "In11.Cu")
		(net "M_J_DQ<52>")
	)
	(segment
		(start 127.907542 -31.1912)
		(end 127.907542 -29.53004)
		(width 0.14224)
		(layer "In11.Cu")
		(net "M_J_DQ<52>")
	)
	(segment
		(start 133.874764 -21.811996)
		(end 133.874764 -21.3106)
		(width 0.14224)
		(layer "In11.Cu")
		(net "M_J_DQ<52>")
	)
	(segment
		(start 133.875018 -2.141728)
		(end 133.523736 -1.790446)
		(width 0.14224)
		(layer "In11.Cu")
		(net "M_J_DQ<52>")
	)
	(segment
		(start 133.696964 -28.152852)
		(end 133.696964 -26.968196)
		(width 0.14224)
		(layer "In11.Cu")
		(net "M_J_DQ<52>")
	)
	(segment
		(start 114.279172 -47.338996)
		(end 114.145568 -47.205392)
		(width 0.0889)
		(layer "In11.Cu")
		(net "M_J_DQ<52>")
	)
	(segment
		(start 127.094742 -31.1912)
		(end 127.297942 -31.3944)
		(width 0.14224)
		(layer "In11.Cu")
		(net "M_J_DQ<52>")
	)
	(segment
		(start 125.55093 -29.972)
		(end 126.891542 -29.972)
		(width 0.14224)
		(layer "In11.Cu")
		(net "M_J_DQ<52>")
	)
	(segment
		(start 133.523736 -1.790446)
		(end 133.523736 -1.4351)
		(width 0.14224)
		(layer "In11.Cu")
		(net "M_J_DQ<52>")
	)
	(segment
		(start 133.900164 -26.764996)
		(end 133.900164 -23.335996)
		(width 0.14224)
		(layer "In11.Cu")
		(net "M_J_DQ<52>")
	)
	(segment
		(start 114.553492 -60.657486)
		(end 114.547142 -60.646818)
		(width 0.0889)
		(layer "In11.Cu")
		(net "M_J_DQ<52>")
	)
	(segment
		(start 133.900164 -23.335996)
		(end 133.671564 -23.107396)
		(width 0.14224)
		(layer "In11.Cu")
		(net "M_J_DQ<52>")
	)
	(segment
		(start 127.094742 -30.1752)
		(end 127.094742 -31.1912)
		(width 0.14224)
		(layer "In11.Cu")
		(net "M_J_DQ<52>")
	)
	(segment
		(start 133.875018 0.765048)
		(end 134.15137 1.0414)
		(width 0.14224)
		(layer "In11.Cu")
		(net "M_J_DQ<52>")
	)
	(segment
		(start 133.163818 -4.122166)
		(end 133.163818 -3.327654)
		(width 0.14224)
		(layer "In11.Cu")
		(net "M_J_DQ<52>")
	)
	(segment
		(start 133.779768 -19.1008)
		(end 133.874764 -19.005804)
		(width 0.14224)
		(layer "In11.Cu")
		(net "M_J_DQ<52>")
	)
	(segment
		(start 114.607086 -53.585872)
		(end 114.279172 -53.257958)
		(width 0.0889)
		(layer "In11.Cu")
		(net "M_J_DQ<52>")
	)
	(segment
		(start 127.704342 -31.3944)
		(end 127.907542 -31.1912)
		(width 0.14224)
		(layer "In11.Cu")
		(net "M_J_DQ<52>")
	)
	(segment
		(start 114.547142 -59.087004)
		(end 114.553492 -59.076336)
		(width 0.0889)
		(layer "In11.Cu")
		(net "M_J_DQ<52>")
	)
	(segment
		(start 133.779768 -21.215604)
		(end 133.779768 -19.1008)
		(width 0.14224)
		(layer "In11.Cu")
		(net "M_J_DQ<52>")
	)
	(segment
		(start 114.145568 -47.205392)
		(end 114.145568 -44.963842)
		(width 0.14224)
		(layer "In11.Cu")
		(net "M_J_DQ<52>")
	)
	(segment
		(start 117.288564 -38.234366)
		(end 125.55093 -29.972)
		(width 0.14224)
		(layer "In11.Cu")
		(net "M_J_DQ<52>")
	)
	(segment
		(start 133.89737 -7.248398)
		(end 133.89737 -6.874002)
		(width 0.14224)
		(layer "In11.Cu")
		(net "M_J_DQ<52>")
	)
	(segment
		(start 133.874764 -21.3106)
		(end 133.779768 -21.215604)
		(width 0.14224)
		(layer "In11.Cu")
		(net "M_J_DQ<52>")
	)
	(segment
		(start 114.279172 -53.257958)
		(end 114.279172 -47.338996)
		(width 0.0889)
		(layer "In11.Cu")
		(net "M_J_DQ<52>")
	)
	(segment
		(start 114.553492 -61.648086)
		(end 114.547142 -61.637418)
		(width 0.0889)
		(layer "In11.Cu")
		(net "M_J_DQ<52>")
	)
	(segment
		(start 133.39953 -4.357878)
		(end 133.163818 -4.122166)
		(width 0.14224)
		(layer "In11.Cu")
		(net "M_J_DQ<52>")
	)
	(arc
		(start 114.547142 -57.675018)
		(mid 114.474344 -57.384255)
		(end 114.553492 -57.095136)
		(width 0.0889)
		(layer "In11.Cu")
		(net "M_J_DQ<52>")
	)
	(arc
		(start 114.547142 -54.703218)
		(mid 114.474344 -54.412455)
		(end 114.553492 -54.123336)
		(width 0.0889)
		(layer "In11.Cu")
		(net "M_J_DQ<52>")
	)
	(arc
		(start 114.553492 -54.123336)
		(mid 114.593545 -54.026544)
		(end 114.607086 -53.922676)
		(width 0.0889)
		(layer "In11.Cu")
		(net "M_J_DQ<52>")
	)
	(arc
		(start 114.547142 -61.637418)
		(mid 114.474344 -61.346655)
		(end 114.553492 -61.057536)
		(width 0.0889)
		(layer "In11.Cu")
		(net "M_J_DQ<52>")
	)
	(arc
		(start 114.547142 -56.684418)
		(mid 114.474344 -56.393655)
		(end 114.553492 -56.104536)
		(width 0.0889)
		(layer "In11.Cu")
		(net "M_J_DQ<52>")
	)
	(arc
		(start 114.553492 -58.085736)
		(mid 114.606962 -57.890673)
		(end 114.558318 -57.694322)
		(width 0.0889)
		(layer "In11.Cu")
		(net "M_J_DQ<52>")
	)
	(arc
		(start 114.553492 -59.076336)
		(mid 114.606991 -58.876438)
		(end 114.553492 -58.67654)
		(width 0.0889)
		(layer "In11.Cu")
		(net "M_J_DQ<52>")
	)
	(arc
		(start 114.547142 -62.628018)
		(mid 114.474344 -62.337255)
		(end 114.553492 -62.048136)
		(width 0.0889)
		(layer "In11.Cu")
		(net "M_J_DQ<52>")
	)
	(arc
		(start 114.547142 -60.646818)
		(mid 114.474344 -60.356055)
		(end 114.553492 -60.066936)
		(width 0.0889)
		(layer "In11.Cu")
		(net "M_J_DQ<52>")
	)
	(arc
		(start 114.657124 -62.770512)
		(mid 114.600616 -62.708289)
		(end 114.553492 -62.638686)
		(width 0.0889)
		(layer "In11.Cu")
		(net "M_J_DQ<52>")
	)
	(arc
		(start 114.553492 -55.113936)
		(mid 114.606962 -54.918873)
		(end 114.558318 -54.722522)
		(width 0.0889)
		(layer "In11.Cu")
		(net "M_J_DQ<52>")
	)
	(arc
		(start 114.553492 -58.67654)
		(mid 114.474361 -58.381138)
		(end 114.553492 -58.085736)
		(width 0.0889)
		(layer "In11.Cu")
		(net "M_J_DQ<52>")
	)
	(arc
		(start 114.553492 -57.095136)
		(mid 114.606962 -56.900073)
		(end 114.558318 -56.703722)
		(width 0.0889)
		(layer "In11.Cu")
		(net "M_J_DQ<52>")
	)
	(arc
		(start 114.553492 -62.048136)
		(mid 114.606962 -61.853073)
		(end 114.558318 -61.656722)
		(width 0.0889)
		(layer "In11.Cu")
		(net "M_J_DQ<52>")
	)
	(arc
		(start 114.553492 -60.066936)
		(mid 114.606962 -59.871873)
		(end 114.558318 -59.675522)
		(width 0.0889)
		(layer "In11.Cu")
		(net "M_J_DQ<52>")
	)
	(arc
		(start 114.547142 -55.693818)
		(mid 114.474344 -55.403055)
		(end 114.553492 -55.113936)
		(width 0.0889)
		(layer "In11.Cu")
		(net "M_J_DQ<52>")
	)
	(arc
		(start 114.553492 -59.666886)
		(mid 114.47427 -59.377768)
		(end 114.547142 -59.087004)
		(width 0.0889)
		(layer "In11.Cu")
		(net "M_J_DQ<52>")
	)
	(arc
		(start 114.553492 -61.057536)
		(mid 114.606962 -60.862473)
		(end 114.558318 -60.666122)
		(width 0.0889)
		(layer "In11.Cu")
		(net "M_J_DQ<52>")
	)
	(arc
		(start 114.553492 -56.104536)
		(mid 114.606962 -55.909473)
		(end 114.558318 -55.713122)
		(width 0.0889)
		(layer "In11.Cu")
		(net "M_J_DQ<52>")
	)
	(segment
		(start 119.070882 -64.324738)
		(end 118.499382 -64.324738)
		(width 0.0889)
		(layer "F.Cu")
		(net "M_J_DQ<51>")
	)
	(segment
		(start 141.049502 3.778758)
		(end 141.049502 2.514854)
		(width 0.1651)
		(layer "F.Cu")
		(net "M_J_DQ<51>")
	)
	(via
		(at 118.499382 -64.324738)
		(size 0.508)
		(drill 0.254)
		(layers "F.Cu" "B.Cu")
		(net "M_J_DQ<51>")
	)
	(via
		(at 141.049502 2.514854)
		(size 0.508)
		(drill 0.254)
		(layers "F.Cu" "B.Cu")
		(net "M_J_DQ<51>")
	)
	(via
		(at 141.899386 -3.076956)
		(size 0.508)
		(drill 0.254)
		(layers "F.Cu" "B.Cu")
		(net "M_J_DQ<51>")
	)
	(segment
		(start 141.899386 -1.021842)
		(end 141.899386 -3.076956)
		(width 0.1651)
		(layer "B.Cu")
		(net "M_J_DQ<51>")
	)
	(segment
		(start 142.252192 -2.72415)
		(end 142.252192 0.581152)
		(width 0.14224)
		(layer "In11.Cu")
		(net "M_J_DQ<51>")
	)
	(segment
		(start 142.25397 -12.208256)
		(end 142.25397 -11.693398)
		(width 0.14224)
		(layer "In11.Cu")
		(net "M_J_DQ<51>")
	)
	(segment
		(start 124.04852 -40.897048)
		(end 125.829568 -39.116)
		(width 0.14224)
		(layer "In11.Cu")
		(net "M_J_DQ<51>")
	)
	(segment
		(start 120.636792 -47.51197)
		(end 120.636792 -47.23892)
		(width 0.14224)
		(layer "In11.Cu")
		(net "M_J_DQ<51>")
	)
	(segment
		(start 142.26667 -4.816856)
		(end 141.41577 -3.965956)
		(width 0.14224)
		(layer "In11.Cu")
		(net "M_J_DQ<51>")
	)
	(segment
		(start 142.40637 -8.797798)
		(end 142.40637 -7.429246)
		(width 0.14224)
		(layer "In11.Cu")
		(net "M_J_DQ<51>")
	)
	(segment
		(start 142.356586 -23.185374)
		(end 142.356586 -21.835618)
		(width 0.14224)
		(layer "In11.Cu")
		(net "M_J_DQ<51>")
	)
	(segment
		(start 125.829568 -39.116)
		(end 132.980938 -39.116)
		(width 0.14224)
		(layer "In11.Cu")
		(net "M_J_DQ<51>")
	)
	(segment
		(start 119.006366 -60.666122)
		(end 119.011192 -60.657486)
		(width 0.0889)
		(layer "In11.Cu")
		(net "M_J_DQ<51>")
	)
	(segment
		(start 142.235936 -21.3614)
		(end 142.390368 -21.206968)
		(width 0.14224)
		(layer "In11.Cu")
		(net "M_J_DQ<51>")
	)
	(segment
		(start 119.006366 -59.675522)
		(end 119.011192 -59.666886)
		(width 0.0889)
		(layer "In11.Cu")
		(net "M_J_DQ<51>")
	)
	(segment
		(start 142.383764 -13.577062)
		(end 142.383764 -12.33805)
		(width 0.14224)
		(layer "In11.Cu")
		(net "M_J_DQ<51>")
	)
	(segment
		(start 142.40764 1.0922)
		(end 141.95044 1.5494)
		(width 0.14224)
		(layer "In11.Cu")
		(net "M_J_DQ<51>")
	)
	(segment
		(start 118.957852 -53.042312)
		(end 119.10314 -52.897024)
		(width 0.0889)
		(layer "In11.Cu")
		(net "M_J_DQ<51>")
	)
	(segment
		(start 119.011192 -55.704486)
		(end 119.017542 -55.693818)
		(width 0.0889)
		(layer "In11.Cu")
		(net "M_J_DQ<51>")
	)
	(segment
		(start 142.288768 -23.253192)
		(end 142.356586 -23.185374)
		(width 0.14224)
		(layer "In11.Cu")
		(net "M_J_DQ<51>")
	)
	(segment
		(start 118.499382 -64.324738)
		(end 118.727474 -64.017906)
		(width 0.0889)
		(layer "In11.Cu")
		(net "M_J_DQ<51>")
	)
	(segment
		(start 132.980938 -39.116)
		(end 142.415768 -29.68117)
		(width 0.14224)
		(layer "In11.Cu")
		(net "M_J_DQ<51>")
	)
	(segment
		(start 142.383764 -18.447258)
		(end 142.383764 -17.032986)
		(width 0.14224)
		(layer "In11.Cu")
		(net "M_J_DQ<51>")
	)
	(segment
		(start 119.006366 -56.703722)
		(end 119.011192 -56.695086)
		(width 0.0889)
		(layer "In11.Cu")
		(net "M_J_DQ<51>")
	)
	(segment
		(start 142.252192 0.581152)
		(end 142.40764 0.7366)
		(width 0.14224)
		(layer "In11.Cu")
		(net "M_J_DQ<51>")
	)
	(segment
		(start 142.415768 -29.68117)
		(end 142.415768 -26.1874)
		(width 0.14224)
		(layer "In11.Cu")
		(net "M_J_DQ<51>")
	)
	(segment
		(start 119.10314 -49.385728)
		(end 120.41378 -48.075088)
		(width 0.0889)
		(layer "In11.Cu")
		(net "M_J_DQ<51>")
	)
	(segment
		(start 124.04852 -43.827192)
		(end 124.04852 -40.897048)
		(width 0.14224)
		(layer "In11.Cu")
		(net "M_J_DQ<51>")
	)
	(segment
		(start 142.40764 0.7366)
		(end 142.40764 1.0922)
		(width 0.14224)
		(layer "In11.Cu")
		(net "M_J_DQ<51>")
	)
	(segment
		(start 142.235936 -18.946368)
		(end 142.235936 -18.595086)
		(width 0.14224)
		(layer "In11.Cu")
		(net "M_J_DQ<51>")
	)
	(segment
		(start 119.017542 -59.087004)
		(end 119.011192 -59.076336)
		(width 0.0889)
		(layer "In11.Cu")
		(net "M_J_DQ<51>")
	)
	(segment
		(start 142.441168 -11.5062)
		(end 142.441168 -9.585198)
		(width 0.14224)
		(layer "In11.Cu")
		(net "M_J_DQ<51>")
	)
	(segment
		(start 142.25397 -8.950198)
		(end 142.40637 -8.797798)
		(width 0.14224)
		(layer "In11.Cu")
		(net "M_J_DQ<51>")
	)
	(segment
		(start 142.25397 -9.398)
		(end 142.25397 -8.950198)
		(width 0.14224)
		(layer "In11.Cu")
		(net "M_J_DQ<51>")
	)
	(segment
		(start 141.69644 1.5494)
		(end 141.36624 1.8796)
		(width 0.14224)
		(layer "In11.Cu")
		(net "M_J_DQ<51>")
	)
	(segment
		(start 141.36624 1.8796)
		(end 141.36624 2.198116)
		(width 0.14224)
		(layer "In11.Cu")
		(net "M_J_DQ<51>")
	)
	(segment
		(start 141.36624 2.198116)
		(end 141.049502 2.514854)
		(width 0.14224)
		(layer "In11.Cu")
		(net "M_J_DQ<51>")
	)
	(segment
		(start 118.957852 -55.02148)
		(end 118.957852 -53.042312)
		(width 0.0889)
		(layer "In11.Cu")
		(net "M_J_DQ<51>")
	)
	(segment
		(start 119.011192 -61.648086)
		(end 119.017542 -61.637418)
		(width 0.0889)
		(layer "In11.Cu")
		(net "M_J_DQ<51>")
	)
	(segment
		(start 141.41577 -3.965956)
		(end 141.41577 -3.560572)
		(width 0.14224)
		(layer "In11.Cu")
		(net "M_J_DQ<51>")
	)
	(segment
		(start 142.288768 -26.0604)
		(end 142.288768 -23.253192)
		(width 0.14224)
		(layer "In11.Cu")
		(net "M_J_DQ<51>")
	)
	(segment
		(start 120.636792 -47.23892)
		(end 124.04852 -43.827192)
		(width 0.14224)
		(layer "In11.Cu")
		(net "M_J_DQ<51>")
	)
	(segment
		(start 119.011192 -57.685686)
		(end 119.017542 -57.675018)
		(width 0.0889)
		(layer "In11.Cu")
		(net "M_J_DQ<51>")
	)
	(segment
		(start 141.899386 -3.076956)
		(end 142.252192 -2.72415)
		(width 0.14224)
		(layer "In11.Cu")
		(net "M_J_DQ<51>")
	)
	(segment
		(start 119.011192 -56.695086)
		(end 119.017542 -56.684418)
		(width 0.0889)
		(layer "In11.Cu")
		(net "M_J_DQ<51>")
	)
	(segment
		(start 142.383764 -17.032986)
		(end 142.26667 -16.915892)
		(width 0.14224)
		(layer "In11.Cu")
		(net "M_J_DQ<51>")
	)
	(segment
		(start 142.235936 -18.595086)
		(end 142.383764 -18.447258)
		(width 0.14224)
		(layer "In11.Cu")
		(net "M_J_DQ<51>")
	)
	(segment
		(start 119.006366 -61.656722)
		(end 119.011192 -61.648086)
		(width 0.0889)
		(layer "In11.Cu")
		(net "M_J_DQ<51>")
	)
	(segment
		(start 142.26667 -13.694156)
		(end 142.383764 -13.577062)
		(width 0.14224)
		(layer "In11.Cu")
		(net "M_J_DQ<51>")
	)
	(segment
		(start 142.40637 -7.429246)
		(end 142.26667 -7.289546)
		(width 0.14224)
		(layer "In11.Cu")
		(net "M_J_DQ<51>")
	)
	(segment
		(start 142.390368 -21.206968)
		(end 142.390368 -19.1008)
		(width 0.14224)
		(layer "In11.Cu")
		(net "M_J_DQ<51>")
	)
	(segment
		(start 141.41577 -3.560572)
		(end 141.899386 -3.076956)
		(width 0.14224)
		(layer "In11.Cu")
		(net "M_J_DQ<51>")
	)
	(segment
		(start 119.011192 -60.657486)
		(end 119.017542 -60.646818)
		(width 0.0889)
		(layer "In11.Cu")
		(net "M_J_DQ<51>")
	)
	(segment
		(start 120.41378 -48.075088)
		(end 120.41378 -47.734982)
		(width 0.0889)
		(layer "In11.Cu")
		(net "M_J_DQ<51>")
	)
	(segment
		(start 119.006366 -57.694322)
		(end 119.011192 -57.685686)
		(width 0.0889)
		(layer "In11.Cu")
		(net "M_J_DQ<51>")
	)
	(segment
		(start 142.235936 -21.714968)
		(end 142.235936 -21.3614)
		(width 0.14224)
		(layer "In11.Cu")
		(net "M_J_DQ<51>")
	)
	(segment
		(start 141.95044 1.5494)
		(end 141.69644 1.5494)
		(width 0.14224)
		(layer "In11.Cu")
		(net "M_J_DQ<51>")
	)
	(segment
		(start 142.383764 -12.33805)
		(end 142.25397 -12.208256)
		(width 0.14224)
		(layer "In11.Cu")
		(net "M_J_DQ<51>")
	)
	(segment
		(start 142.390368 -19.1008)
		(end 142.235936 -18.946368)
		(width 0.14224)
		(layer "In11.Cu")
		(net "M_J_DQ<51>")
	)
	(segment
		(start 142.356586 -21.835618)
		(end 142.235936 -21.714968)
		(width 0.14224)
		(layer "In11.Cu")
		(net "M_J_DQ<51>")
	)
	(segment
		(start 142.441168 -9.585198)
		(end 142.25397 -9.398)
		(width 0.14224)
		(layer "In11.Cu")
		(net "M_J_DQ<51>")
	)
	(segment
		(start 142.26667 -7.289546)
		(end 142.26667 -4.816856)
		(width 0.14224)
		(layer "In11.Cu")
		(net "M_J_DQ<51>")
	)
	(segment
		(start 120.41378 -47.734982)
		(end 120.636792 -47.51197)
		(width 0.0889)
		(layer "In11.Cu")
		(net "M_J_DQ<51>")
	)
	(segment
		(start 119.006366 -55.713122)
		(end 119.011192 -55.704486)
		(width 0.0889)
		(layer "In11.Cu")
		(net "M_J_DQ<51>")
	)
	(segment
		(start 119.011192 -62.638686)
		(end 119.017542 -62.628018)
		(width 0.0889)
		(layer "In11.Cu")
		(net "M_J_DQ<51>")
	)
	(segment
		(start 119.10314 -52.897024)
		(end 119.10314 -49.385728)
		(width 0.0889)
		(layer "In11.Cu")
		(net "M_J_DQ<51>")
	)
	(segment
		(start 119.011192 -55.113936)
		(end 118.957852 -55.02148)
		(width 0.0889)
		(layer "In11.Cu")
		(net "M_J_DQ<51>")
	)
	(segment
		(start 142.25397 -11.693398)
		(end 142.441168 -11.5062)
		(width 0.14224)
		(layer "In11.Cu")
		(net "M_J_DQ<51>")
	)
	(segment
		(start 119.006366 -62.647322)
		(end 119.011192 -62.638686)
		(width 0.0889)
		(layer "In11.Cu")
		(net "M_J_DQ<51>")
	)
	(segment
		(start 142.26667 -16.915892)
		(end 142.26667 -13.694156)
		(width 0.14224)
		(layer "In11.Cu")
		(net "M_J_DQ<51>")
	)
	(segment
		(start 118.727474 -64.017906)
		(end 118.980204 -63.6778)
		(width 0.0889)
		(layer "In11.Cu")
		(net "M_J_DQ<51>")
	)
	(segment
		(start 142.415768 -26.1874)
		(end 142.288768 -26.0604)
		(width 0.14224)
		(layer "In11.Cu")
		(net "M_J_DQ<51>")
	)
	(arc
		(start 119.011192 -56.104536)
		(mid 118.957722 -55.909473)
		(end 119.006366 -55.713122)
		(width 0.0889)
		(layer "In11.Cu")
		(net "M_J_DQ<51>")
	)
	(arc
		(start 119.017542 -62.628018)
		(mid 119.09034 -62.337255)
		(end 119.011192 -62.048136)
		(width 0.0889)
		(layer "In11.Cu")
		(net "M_J_DQ<51>")
	)
	(arc
		(start 119.017542 -55.693818)
		(mid 119.09034 -55.403055)
		(end 119.011192 -55.113936)
		(width 0.0889)
		(layer "In11.Cu")
		(net "M_J_DQ<51>")
	)
	(arc
		(start 119.011192 -62.048136)
		(mid 118.957722 -61.853073)
		(end 119.006366 -61.656722)
		(width 0.0889)
		(layer "In11.Cu")
		(net "M_J_DQ<51>")
	)
	(arc
		(start 119.017542 -57.675018)
		(mid 119.09034 -57.384255)
		(end 119.011192 -57.095136)
		(width 0.0889)
		(layer "In11.Cu")
		(net "M_J_DQ<51>")
	)
	(arc
		(start 119.017542 -56.684418)
		(mid 119.09034 -56.393655)
		(end 119.011192 -56.104536)
		(width 0.0889)
		(layer "In11.Cu")
		(net "M_J_DQ<51>")
	)
	(arc
		(start 119.017542 -61.637418)
		(mid 119.09034 -61.346655)
		(end 119.011192 -61.057536)
		(width 0.0889)
		(layer "In11.Cu")
		(net "M_J_DQ<51>")
	)
	(arc
		(start 119.011192 -59.666886)
		(mid 119.090414 -59.377768)
		(end 119.017542 -59.087004)
		(width 0.0889)
		(layer "In11.Cu")
		(net "M_J_DQ<51>")
	)
	(arc
		(start 119.011192 -59.076336)
		(mid 118.957693 -58.876438)
		(end 119.011192 -58.67654)
		(width 0.0889)
		(layer "In11.Cu")
		(net "M_J_DQ<51>")
	)
	(arc
		(start 119.011192 -58.085736)
		(mid 118.957722 -57.890673)
		(end 119.006366 -57.694322)
		(width 0.0889)
		(layer "In11.Cu")
		(net "M_J_DQ<51>")
	)
	(arc
		(start 119.011192 -63.038736)
		(mid 118.957722 -62.843673)
		(end 119.006366 -62.647322)
		(width 0.0889)
		(layer "In11.Cu")
		(net "M_J_DQ<51>")
	)
	(arc
		(start 119.011192 -58.67654)
		(mid 119.090323 -58.381138)
		(end 119.011192 -58.085736)
		(width 0.0889)
		(layer "In11.Cu")
		(net "M_J_DQ<51>")
	)
	(arc
		(start 119.017542 -60.646818)
		(mid 119.09034 -60.356055)
		(end 119.011192 -60.066936)
		(width 0.0889)
		(layer "In11.Cu")
		(net "M_J_DQ<51>")
	)
	(arc
		(start 119.011192 -61.057536)
		(mid 118.957722 -60.862473)
		(end 119.006366 -60.666122)
		(width 0.0889)
		(layer "In11.Cu")
		(net "M_J_DQ<51>")
	)
	(arc
		(start 119.011192 -57.095136)
		(mid 118.957722 -56.900073)
		(end 119.006366 -56.703722)
		(width 0.0889)
		(layer "In11.Cu")
		(net "M_J_DQ<51>")
	)
	(arc
		(start 118.980204 -63.6778)
		(mid 119.089696 -63.362816)
		(end 119.011192 -63.038736)
		(width 0.0889)
		(layer "In11.Cu")
		(net "M_J_DQ<51>")
	)
	(arc
		(start 119.011192 -60.066936)
		(mid 118.957722 -59.871873)
		(end 119.006366 -59.675522)
		(width 0.0889)
		(layer "In11.Cu")
		(net "M_J_DQ<51>")
	)
	(segment
		(start 141.899386 0.175768)
		(end 142.030958 0.30734)
		(width 0.1651)
		(layer "F.Cu")
		(net "M_J_DQ<50>")
	)
	(segment
		(start 142.030958 0.53086)
		(end 141.899386 0.662432)
		(width 0.1651)
		(layer "F.Cu")
		(net "M_J_DQ<50>")
	)
	(segment
		(start 142.030958 0.30734)
		(end 142.030958 0.53086)
		(width 0.1651)
		(layer "F.Cu")
		(net "M_J_DQ<50>")
	)
	(segment
		(start 119.070882 -63.334138)
		(end 118.499382 -63.334138)
		(width 0.0889)
		(layer "F.Cu")
		(net "M_J_DQ<50>")
	)
	(segment
		(start 141.899386 -0.821182)
		(end 141.899386 0.175768)
		(width 0.1651)
		(layer "F.Cu")
		(net "M_J_DQ<50>")
	)
	(segment
		(start 141.899386 0.662432)
		(end 141.899386 0.9398)
		(width 0.1651)
		(layer "F.Cu")
		(net "M_J_DQ<50>")
	)
	(via
		(at 118.499382 -63.334138)
		(size 0.508)
		(drill 0.254)
		(layers "F.Cu" "B.Cu")
		(net "M_J_DQ<50>")
	)
	(via
		(at 141.049502 -4.357878)
		(size 0.508)
		(drill 0.254)
		(layers "F.Cu" "B.Cu")
		(net "M_J_DQ<50>")
	)
	(via
		(at 141.899386 0.9398)
		(size 0.508)
		(drill 0.254)
		(layers "F.Cu" "B.Cu")
		(net "M_J_DQ<50>")
	)
	(segment
		(start 141.049502 -5.621782)
		(end 141.049502 -4.357878)
		(width 0.1651)
		(layer "B.Cu")
		(net "M_J_DQ<50>")
	)
	(segment
		(start 141.613636 -2.2098)
		(end 141.156436 -1.7526)
		(width 0.14224)
		(layer "In11.Cu")
		(net "M_J_DQ<50>")
	)
	(segment
		(start 141.545564 -21.329396)
		(end 141.374368 -21.1582)
		(width 0.14224)
		(layer "In11.Cu")
		(net "M_J_DQ<50>")
	)
	(segment
		(start 141.049502 -4.357878)
		(end 140.764768 -4.073144)
		(width 0.14224)
		(layer "In11.Cu")
		(net "M_J_DQ<50>")
	)
	(segment
		(start 141.545564 -21.761196)
		(end 141.545564 -21.329396)
		(width 0.14224)
		(layer "In11.Cu")
		(net "M_J_DQ<50>")
	)
	(segment
		(start 141.613636 -2.478532)
		(end 141.613636 -2.2098)
		(width 0.14224)
		(layer "In11.Cu")
		(net "M_J_DQ<50>")
	)
	(segment
		(start 141.374368 -21.1582)
		(end 141.374368 -19.170396)
		(width 0.14224)
		(layer "In11.Cu")
		(net "M_J_DQ<50>")
	)
	(segment
		(start 120.001792 -47.111412)
		(end 123.543568 -43.569636)
		(width 0.14224)
		(layer "In11.Cu")
		(net "M_J_DQ<50>")
	)
	(segment
		(start 118.91264 -49.306734)
		(end 120.22328 -47.996094)
		(width 0.0889)
		(layer "In11.Cu")
		(net "M_J_DQ<50>")
	)
	(segment
		(start 141.367764 -17.032986)
		(end 141.577568 -16.823182)
		(width 0.14224)
		(layer "In11.Cu")
		(net "M_J_DQ<50>")
	)
	(segment
		(start 118.792498 -63.164974)
		(end 118.816374 -63.075566)
		(width 0.0889)
		(layer "In11.Cu")
		(net "M_J_DQ<50>")
	)
	(segment
		(start 141.374368 -9.515602)
		(end 141.54277 -9.3472)
		(width 0.14224)
		(layer "In11.Cu")
		(net "M_J_DQ<50>")
	)
	(segment
		(start 141.501368 0.236728)
		(end 141.501368 0.541782)
		(width 0.14224)
		(layer "In11.Cu")
		(net "M_J_DQ<50>")
	)
	(segment
		(start 120.22328 -47.996094)
		(end 120.22328 -47.733458)
		(width 0.0889)
		(layer "In11.Cu")
		(net "M_J_DQ<50>")
	)
	(segment
		(start 118.846092 -55.209186)
		(end 118.767352 -55.072534)
		(width 0.0889)
		(layer "In11.Cu")
		(net "M_J_DQ<50>")
	)
	(segment
		(start 141.342364 -27.018996)
		(end 141.732 -26.62936)
		(width 0.14224)
		(layer "In11.Cu")
		(net "M_J_DQ<50>")
	)
	(segment
		(start 141.425168 -8.8646)
		(end 141.425168 -7.366)
		(width 0.14224)
		(layer "In11.Cu")
		(net "M_J_DQ<50>")
	)
	(segment
		(start 141.552168 -26.162)
		(end 141.552168 -23.282656)
		(width 0.14224)
		(layer "In11.Cu")
		(net "M_J_DQ<50>")
	)
	(segment
		(start 141.545564 -18.9992)
		(end 141.545564 -18.56105)
		(width 0.14224)
		(layer "In11.Cu")
		(net "M_J_DQ<50>")
	)
	(segment
		(start 126.27864 -38.5572)
		(end 126.42088 -38.41496)
		(width 0.14224)
		(layer "In11.Cu")
		(net "M_J_DQ<50>")
	)
	(segment
		(start 141.732 -26.62936)
		(end 141.732 -26.341832)
		(width 0.14224)
		(layer "In11.Cu")
		(net "M_J_DQ<50>")
	)
	(segment
		(start 141.156436 -0.456946)
		(end 141.156436 -0.108204)
		(width 0.14224)
		(layer "In11.Cu")
		(net "M_J_DQ<50>")
	)
	(segment
		(start 141.374368 -19.170396)
		(end 141.545564 -18.9992)
		(width 0.14224)
		(layer "In11.Cu")
		(net "M_J_DQ<50>")
	)
	(segment
		(start 141.61897 -4.927346)
		(end 141.049502 -4.357878)
		(width 0.14224)
		(layer "In11.Cu")
		(net "M_J_DQ<50>")
	)
	(segment
		(start 118.846092 -55.609236)
		(end 118.850918 -55.6006)
		(width 0.0889)
		(layer "In11.Cu")
		(net "M_J_DQ<50>")
	)
	(segment
		(start 127.72136 -38.41496)
		(end 127.72136 -38.08984)
		(width 0.14224)
		(layer "In11.Cu")
		(net "M_J_DQ<50>")
	)
	(segment
		(start 141.39037 -13.595604)
		(end 141.39037 -12.347956)
		(width 0.14224)
		(layer "In11.Cu")
		(net "M_J_DQ<50>")
	)
	(segment
		(start 141.54277 -11.700002)
		(end 141.374368 -11.5316)
		(width 0.14224)
		(layer "In11.Cu")
		(net "M_J_DQ<50>")
	)
	(segment
		(start 141.780768 -29.418026)
		(end 141.780768 -28.540456)
		(width 0.14224)
		(layer "In11.Cu")
		(net "M_J_DQ<50>")
	)
	(segment
		(start 118.839742 -55.619904)
		(end 118.846092 -55.609236)
		(width 0.0889)
		(layer "In11.Cu")
		(net "M_J_DQ<50>")
	)
	(segment
		(start 118.846092 -57.590436)
		(end 118.850918 -57.5818)
		(width 0.0889)
		(layer "In11.Cu")
		(net "M_J_DQ<50>")
	)
	(segment
		(start 141.54277 -12.195556)
		(end 141.54277 -11.700002)
		(width 0.14224)
		(layer "In11.Cu")
		(net "M_J_DQ<50>")
	)
	(segment
		(start 123.543568 -43.569636)
		(end 123.543568 -40.608504)
		(width 0.14224)
		(layer "In11.Cu")
		(net "M_J_DQ<50>")
	)
	(segment
		(start 118.839742 -61.563504)
		(end 118.846092 -61.552836)
		(width 0.0889)
		(layer "In11.Cu")
		(net "M_J_DQ<50>")
	)
	(segment
		(start 120.22328 -47.733458)
		(end 120.001792 -47.51197)
		(width 0.0889)
		(layer "In11.Cu")
		(net "M_J_DQ<50>")
	)
	(segment
		(start 127.57912 -38.5572)
		(end 127.72136 -38.41496)
		(width 0.14224)
		(layer "In11.Cu")
		(net "M_J_DQ<50>")
	)
	(segment
		(start 126.42088 -38.41496)
		(end 126.42088 -38.08984)
		(width 0.14224)
		(layer "In11.Cu")
		(net "M_J_DQ<50>")
	)
	(segment
		(start 127.72136 -38.08984)
		(end 127.8636 -37.9476)
		(width 0.14224)
		(layer "In11.Cu")
		(net "M_J_DQ<50>")
	)
	(segment
		(start 127.21336 -38.5572)
		(end 127.57912 -38.5572)
		(width 0.14224)
		(layer "In11.Cu")
		(net "M_J_DQ<50>")
	)
	(segment
		(start 141.780768 -28.540456)
		(end 141.342364 -28.102052)
		(width 0.14224)
		(layer "In11.Cu")
		(net "M_J_DQ<50>")
	)
	(segment
		(start 127.07112 -38.41496)
		(end 127.21336 -38.5572)
		(width 0.14224)
		(layer "In11.Cu")
		(net "M_J_DQ<50>")
	)
	(segment
		(start 128.22936 -37.9476)
		(end 128.45796 -38.1762)
		(width 0.14224)
		(layer "In11.Cu")
		(net "M_J_DQ<50>")
	)
	(segment
		(start 141.367764 -23.098252)
		(end 141.367764 -21.938996)
		(width 0.14224)
		(layer "In11.Cu")
		(net "M_J_DQ<50>")
	)
	(segment
		(start 118.839742 -60.572904)
		(end 118.846092 -60.562236)
		(width 0.0889)
		(layer "In11.Cu")
		(net "M_J_DQ<50>")
	)
	(segment
		(start 141.156436 -1.7526)
		(end 141.156436 -1.35255)
		(width 0.14224)
		(layer "In11.Cu")
		(net "M_J_DQ<50>")
	)
	(segment
		(start 125.594872 -38.5572)
		(end 126.27864 -38.5572)
		(width 0.14224)
		(layer "In11.Cu")
		(net "M_J_DQ<50>")
	)
	(segment
		(start 141.367764 -18.38325)
		(end 141.367764 -17.032986)
		(width 0.14224)
		(layer "In11.Cu")
		(net "M_J_DQ<50>")
	)
	(segment
		(start 141.156436 -0.108204)
		(end 141.501368 0.236728)
		(width 0.14224)
		(layer "In11.Cu")
		(net "M_J_DQ<50>")
	)
	(segment
		(start 120.001792 -47.51197)
		(end 120.001792 -47.111412)
		(width 0.14224)
		(layer "In11.Cu")
		(net "M_J_DQ<50>")
	)
	(segment
		(start 127.07112 -38.08984)
		(end 127.07112 -38.41496)
		(width 0.14224)
		(layer "In11.Cu")
		(net "M_J_DQ<50>")
	)
	(segment
		(start 141.54277 -9.3472)
		(end 141.54277 -8.982202)
		(width 0.14224)
		(layer "In11.Cu")
		(net "M_J_DQ<50>")
	)
	(segment
		(start 141.545564 -18.56105)
		(end 141.367764 -18.38325)
		(width 0.14224)
		(layer "In11.Cu")
		(net "M_J_DQ<50>")
	)
	(segment
		(start 118.846092 -60.562236)
		(end 118.850918 -60.5536)
		(width 0.0889)
		(layer "In11.Cu")
		(net "M_J_DQ<50>")
	)
	(segment
		(start 118.846092 -56.599836)
		(end 118.850918 -56.5912)
		(width 0.0889)
		(layer "In11.Cu")
		(net "M_J_DQ<50>")
	)
	(segment
		(start 141.54277 -8.982202)
		(end 141.425168 -8.8646)
		(width 0.14224)
		(layer "In11.Cu")
		(net "M_J_DQ<50>")
	)
	(segment
		(start 141.342364 -28.102052)
		(end 141.342364 -27.018996)
		(width 0.14224)
		(layer "In11.Cu")
		(net "M_J_DQ<50>")
	)
	(segment
		(start 118.499382 -63.334138)
		(end 118.792498 -63.164974)
		(width 0.0889)
		(layer "In11.Cu")
		(net "M_J_DQ<50>")
	)
	(segment
		(start 140.764768 -4.073144)
		(end 140.764768 -3.3274)
		(width 0.14224)
		(layer "In11.Cu")
		(net "M_J_DQ<50>")
	)
	(segment
		(start 118.846092 -61.552836)
		(end 118.850918 -61.5442)
		(width 0.0889)
		(layer "In11.Cu")
		(net "M_J_DQ<50>")
	)
	(segment
		(start 118.846092 -58.581036)
		(end 118.850918 -58.5724)
		(width 0.0889)
		(layer "In11.Cu")
		(net "M_J_DQ<50>")
	)
	(segment
		(start 118.767352 -55.072534)
		(end 118.767352 -52.963318)
		(width 0.0889)
		(layer "In11.Cu")
		(net "M_J_DQ<50>")
	)
	(segment
		(start 118.839742 -57.601104)
		(end 118.846092 -57.590436)
		(width 0.0889)
		(layer "In11.Cu")
		(net "M_J_DQ<50>")
	)
	(segment
		(start 123.543568 -40.608504)
		(end 125.594872 -38.5572)
		(width 0.14224)
		(layer "In11.Cu")
		(net "M_J_DQ<50>")
	)
	(segment
		(start 126.56312 -37.9476)
		(end 126.92888 -37.9476)
		(width 0.14224)
		(layer "In11.Cu")
		(net "M_J_DQ<50>")
	)
	(segment
		(start 141.577568 -13.782802)
		(end 141.39037 -13.595604)
		(width 0.14224)
		(layer "In11.Cu")
		(net "M_J_DQ<50>")
	)
	(segment
		(start 141.425168 -7.366)
		(end 141.61897 -7.172198)
		(width 0.14224)
		(layer "In11.Cu")
		(net "M_J_DQ<50>")
	)
	(segment
		(start 141.39037 -12.347956)
		(end 141.54277 -12.195556)
		(width 0.14224)
		(layer "In11.Cu")
		(net "M_J_DQ<50>")
	)
	(segment
		(start 118.767352 -52.963318)
		(end 118.91264 -52.81803)
		(width 0.0889)
		(layer "In11.Cu")
		(net "M_J_DQ<50>")
	)
	(segment
		(start 141.374368 -11.5316)
		(end 141.374368 -9.515602)
		(width 0.14224)
		(layer "In11.Cu")
		(net "M_J_DQ<50>")
	)
	(segment
		(start 141.577568 -16.823182)
		(end 141.577568 -13.782802)
		(width 0.14224)
		(layer "In11.Cu")
		(net "M_J_DQ<50>")
	)
	(segment
		(start 141.501368 0.541782)
		(end 141.899386 0.9398)
		(width 0.14224)
		(layer "In11.Cu")
		(net "M_J_DQ<50>")
	)
	(segment
		(start 141.552168 -23.282656)
		(end 141.367764 -23.098252)
		(width 0.14224)
		(layer "In11.Cu")
		(net "M_J_DQ<50>")
	)
	(segment
		(start 141.461236 -1.04775)
		(end 141.461236 -0.761746)
		(width 0.14224)
		(layer "In11.Cu")
		(net "M_J_DQ<50>")
	)
	(segment
		(start 127.8636 -37.9476)
		(end 128.22936 -37.9476)
		(width 0.14224)
		(layer "In11.Cu")
		(net "M_J_DQ<50>")
	)
	(segment
		(start 133.022594 -38.1762)
		(end 141.780768 -29.418026)
		(width 0.14224)
		(layer "In11.Cu")
		(net "M_J_DQ<50>")
	)
	(segment
		(start 141.367764 -21.938996)
		(end 141.545564 -21.761196)
		(width 0.14224)
		(layer "In11.Cu")
		(net "M_J_DQ<50>")
	)
	(segment
		(start 118.839742 -62.554104)
		(end 118.846092 -62.543436)
		(width 0.0889)
		(layer "In11.Cu")
		(net "M_J_DQ<50>")
	)
	(segment
		(start 141.732 -26.341832)
		(end 141.552168 -26.162)
		(width 0.14224)
		(layer "In11.Cu")
		(net "M_J_DQ<50>")
	)
	(segment
		(start 118.839742 -56.610504)
		(end 118.846092 -56.599836)
		(width 0.0889)
		(layer "In11.Cu")
		(net "M_J_DQ<50>")
	)
	(segment
		(start 141.156436 -1.35255)
		(end 141.461236 -1.04775)
		(width 0.14224)
		(layer "In11.Cu")
		(net "M_J_DQ<50>")
	)
	(segment
		(start 141.461236 -0.761746)
		(end 141.156436 -0.456946)
		(width 0.14224)
		(layer "In11.Cu")
		(net "M_J_DQ<50>")
	)
	(segment
		(start 140.764768 -3.3274)
		(end 141.613636 -2.478532)
		(width 0.14224)
		(layer "In11.Cu")
		(net "M_J_DQ<50>")
	)
	(segment
		(start 126.92888 -37.9476)
		(end 127.07112 -38.08984)
		(width 0.14224)
		(layer "In11.Cu")
		(net "M_J_DQ<50>")
	)
	(segment
		(start 141.61897 -7.172198)
		(end 141.61897 -4.927346)
		(width 0.14224)
		(layer "In11.Cu")
		(net "M_J_DQ<50>")
	)
	(segment
		(start 128.45796 -38.1762)
		(end 133.022594 -38.1762)
		(width 0.14224)
		(layer "In11.Cu")
		(net "M_J_DQ<50>")
	)
	(segment
		(start 118.846092 -59.171586)
		(end 118.839742 -59.160918)
		(width 0.0889)
		(layer "In11.Cu")
		(net "M_J_DQ<50>")
	)
	(segment
		(start 126.42088 -38.08984)
		(end 126.56312 -37.9476)
		(width 0.14224)
		(layer "In11.Cu")
		(net "M_J_DQ<50>")
	)
	(segment
		(start 118.91264 -52.81803)
		(end 118.91264 -49.306734)
		(width 0.0889)
		(layer "In11.Cu")
		(net "M_J_DQ<50>")
	)
	(arc
		(start 118.846092 -61.152786)
		(mid 118.76687 -60.863668)
		(end 118.839742 -60.572904)
		(width 0.0889)
		(layer "In11.Cu")
		(net "M_J_DQ<50>")
	)
	(arc
		(start 118.850918 -61.5442)
		(mid 118.899673 -61.347848)
		(end 118.846092 -61.152786)
		(width 0.0889)
		(layer "In11.Cu")
		(net "M_J_DQ<50>")
	)
	(arc
		(start 118.850918 -56.5912)
		(mid 118.899673 -56.394848)
		(end 118.846092 -56.199786)
		(width 0.0889)
		(layer "In11.Cu")
		(net "M_J_DQ<50>")
	)
	(arc
		(start 118.846092 -62.143386)
		(mid 118.76687 -61.854268)
		(end 118.839742 -61.563504)
		(width 0.0889)
		(layer "In11.Cu")
		(net "M_J_DQ<50>")
	)
	(arc
		(start 118.850918 -62.5348)
		(mid 118.899673 -62.338448)
		(end 118.846092 -62.143386)
		(width 0.0889)
		(layer "In11.Cu")
		(net "M_J_DQ<50>")
	)
	(arc
		(start 118.850918 -58.5724)
		(mid 118.899673 -58.376048)
		(end 118.846092 -58.180986)
		(width 0.0889)
		(layer "In11.Cu")
		(net "M_J_DQ<50>")
	)
	(arc
		(start 118.846092 -58.180986)
		(mid 118.76687 -57.891868)
		(end 118.839742 -57.601104)
		(width 0.0889)
		(layer "In11.Cu")
		(net "M_J_DQ<50>")
	)
	(arc
		(start 118.846092 -56.199786)
		(mid 118.76687 -55.910668)
		(end 118.839742 -55.619904)
		(width 0.0889)
		(layer "In11.Cu")
		(net "M_J_DQ<50>")
	)
	(arc
		(start 118.850918 -57.5818)
		(mid 118.899673 -57.385448)
		(end 118.846092 -57.190386)
		(width 0.0889)
		(layer "In11.Cu")
		(net "M_J_DQ<50>")
	)
	(arc
		(start 118.846092 -57.190386)
		(mid 118.76687 -56.901268)
		(end 118.839742 -56.610504)
		(width 0.0889)
		(layer "In11.Cu")
		(net "M_J_DQ<50>")
	)
	(arc
		(start 118.846092 -59.571382)
		(mid 118.899591 -59.371484)
		(end 118.846092 -59.171586)
		(width 0.0889)
		(layer "In11.Cu")
		(net "M_J_DQ<50>")
	)
	(arc
		(start 118.846092 -60.162186)
		(mid 118.766961 -59.866784)
		(end 118.846092 -59.571382)
		(width 0.0889)
		(layer "In11.Cu")
		(net "M_J_DQ<50>")
	)
	(arc
		(start 118.816374 -63.075566)
		(mid 118.767362 -62.812117)
		(end 118.839742 -62.554104)
		(width 0.0889)
		(layer "In11.Cu")
		(net "M_J_DQ<50>")
	)
	(arc
		(start 118.850918 -60.5536)
		(mid 118.899673 -60.357248)
		(end 118.846092 -60.162186)
		(width 0.0889)
		(layer "In11.Cu")
		(net "M_J_DQ<50>")
	)
	(arc
		(start 118.839742 -59.160918)
		(mid 118.766944 -58.870155)
		(end 118.846092 -58.581036)
		(width 0.0889)
		(layer "In11.Cu")
		(net "M_J_DQ<50>")
	)
	(arc
		(start 118.850918 -55.6006)
		(mid 118.899673 -55.404248)
		(end 118.846092 -55.209186)
		(width 0.0889)
		(layer "In11.Cu")
		(net "M_J_DQ<50>")
	)
	(arc
		(start 118.846092 -62.543436)
		(mid 118.848565 -62.539151)
		(end 118.850918 -62.5348)
		(width 0.0889)
		(layer "In11.Cu")
		(net "M_J_DQ<50>")
	)
	(segment
		(start 32.249364 -0.821182)
		(end 32.249364 0.510032)
		(width 0.1651)
		(layer "F.Cu")
		(net "M_J_DQ<4>")
	)
	(segment
		(start 32.249364 0.510032)
		(end 32.15132 1.0414)
		(width 0.1651)
		(layer "F.Cu")
		(net "M_J_DQ<4>")
	)
	(segment
		(start 77.192886 -66.982086)
		(end 76.621386 -66.982086)
		(width 0.0889)
		(layer "F.Cu")
		(net "M_J_DQ<4>")
	)
	(via
		(at 32.15132 1.0414)
		(size 0.508)
		(drill 0.254)
		(layers "F.Cu" "B.Cu")
		(net "M_J_DQ<4>")
	)
	(via
		(at 76.621386 -66.982086)
		(size 0.508)
		(drill 0.254)
		(layers "F.Cu" "B.Cu")
		(net "M_J_DQ<4>")
	)
	(via
		(at 31.39948 -4.357878)
		(size 0.508)
		(drill 0.254)
		(layers "F.Cu" "B.Cu")
		(net "M_J_DQ<4>")
	)
	(segment
		(start 31.39948 -5.621782)
		(end 31.39948 -4.357878)
		(width 0.1651)
		(layer "B.Cu")
		(net "M_J_DQ<4>")
	)
	(segment
		(start 31.92272 -18.976848)
		(end 31.92272 -18.567146)
		(width 0.14224)
		(layer "In11.Cu")
		(net "M_J_DQ<4>")
	)
	(segment
		(start 31.891986 -0.762)
		(end 31.891986 -1.0668)
		(width 0.14224)
		(layer "In11.Cu")
		(net "M_J_DQ<4>")
	)
	(segment
		(start 66.889122 -67.07759)
		(end 66.641472 -67.32524)
		(width 0.0889)
		(layer "In11.Cu")
		(net "M_J_DQ<4>")
	)
	(segment
		(start 31.66872 -13.567156)
		(end 31.66872 -12.347956)
		(width 0.14224)
		(layer "In11.Cu")
		(net "M_J_DQ<4>")
	)
	(segment
		(start 31.66872 -21.949156)
		(end 31.92272 -21.695156)
		(width 0.14224)
		(layer "In11.Cu")
		(net "M_J_DQ<4>")
	)
	(segment
		(start 74.925936 -68.563236)
		(end 74.89317 -68.563236)
		(width 0.0889)
		(layer "In11.Cu")
		(net "M_J_DQ<4>")
	)
	(segment
		(start 73.198482 -68.563236)
		(end 73.165716 -68.563236)
		(width 0.0889)
		(layer "In11.Cu")
		(net "M_J_DQ<4>")
	)
	(segment
		(start 31.92272 -9.039098)
		(end 31.66872 -8.785098)
		(width 0.14224)
		(layer "In11.Cu")
		(net "M_J_DQ<4>")
	)
	(segment
		(start 31.874968 0.765048)
		(end 31.874968 0.287528)
		(width 0.14224)
		(layer "In11.Cu")
		(net "M_J_DQ<4>")
	)
	(segment
		(start 31.66872 -17.046194)
		(end 31.89732 -16.817594)
		(width 0.14224)
		(layer "In11.Cu")
		(net "M_J_DQ<4>")
	)
	(segment
		(start 32.15132 1.0414)
		(end 31.874968 0.765048)
		(width 0.14224)
		(layer "In11.Cu")
		(net "M_J_DQ<4>")
	)
	(segment
		(start 60.406534 -67.72402)
		(end 31.874968 -39.192454)
		(width 0.14224)
		(layer "In11.Cu")
		(net "M_J_DQ<4>")
	)
	(segment
		(start 68.912486 -67.07759)
		(end 68.876926 -67.07759)
		(width 0.0889)
		(layer "In11.Cu")
		(net "M_J_DQ<4>")
	)
	(segment
		(start 31.66872 -23.168356)
		(end 31.66872 -21.949156)
		(width 0.14224)
		(layer "In11.Cu")
		(net "M_J_DQ<4>")
	)
	(segment
		(start 31.747968 -21.1582)
		(end 31.747968 -19.1516)
		(width 0.14224)
		(layer "In11.Cu")
		(net "M_J_DQ<4>")
	)
	(segment
		(start 31.92272 -11.7602)
		(end 31.747968 -11.585448)
		(width 0.14224)
		(layer "In11.Cu")
		(net "M_J_DQ<4>")
	)
	(segment
		(start 31.92272 -9.426448)
		(end 31.92272 -9.039098)
		(width 0.14224)
		(layer "In11.Cu")
		(net "M_J_DQ<4>")
	)
	(segment
		(start 65.867534 -67.72402)
		(end 60.406534 -67.72402)
		(width 0.14224)
		(layer "In11.Cu")
		(net "M_J_DQ<4>")
	)
	(segment
		(start 31.92272 -21.332952)
		(end 31.747968 -21.1582)
		(width 0.14224)
		(layer "In11.Cu")
		(net "M_J_DQ<4>")
	)
	(segment
		(start 31.874968 -39.192454)
		(end 31.874968 -23.374604)
		(width 0.14224)
		(layer "In11.Cu")
		(net "M_J_DQ<4>")
	)
	(segment
		(start 31.874968 -2.141728)
		(end 31.874968 -2.616454)
		(width 0.14224)
		(layer "In11.Cu")
		(net "M_J_DQ<4>")
	)
	(segment
		(start 31.89732 -13.795756)
		(end 31.66872 -13.567156)
		(width 0.14224)
		(layer "In11.Cu")
		(net "M_J_DQ<4>")
	)
	(segment
		(start 66.34607 -67.72402)
		(end 65.867534 -67.72402)
		(width 0.0889)
		(layer "In11.Cu")
		(net "M_J_DQ<4>")
	)
	(segment
		(start 31.66872 -8.785098)
		(end 31.66872 -7.470394)
		(width 0.14224)
		(layer "In11.Cu")
		(net "M_J_DQ<4>")
	)
	(segment
		(start 31.510986 -0.381)
		(end 31.891986 -0.762)
		(width 0.14224)
		(layer "In11.Cu")
		(net "M_J_DQ<4>")
	)
	(segment
		(start 31.66872 -18.313146)
		(end 31.66872 -17.046194)
		(width 0.14224)
		(layer "In11.Cu")
		(net "M_J_DQ<4>")
	)
	(segment
		(start 31.92272 -21.695156)
		(end 31.92272 -21.332952)
		(width 0.14224)
		(layer "In11.Cu")
		(net "M_J_DQ<4>")
	)
	(segment
		(start 31.874968 0.287528)
		(end 31.510986 -0.076454)
		(width 0.14224)
		(layer "In11.Cu")
		(net "M_J_DQ<4>")
	)
	(segment
		(start 75.780646 -68.06819)
		(end 75.74788 -68.06819)
		(width 0.0889)
		(layer "In11.Cu")
		(net "M_J_DQ<4>")
	)
	(segment
		(start 31.66872 -12.347956)
		(end 31.92272 -12.093956)
		(width 0.14224)
		(layer "In11.Cu")
		(net "M_J_DQ<4>")
	)
	(segment
		(start 31.163768 -3.327654)
		(end 31.163768 -4.122166)
		(width 0.14224)
		(layer "In11.Cu")
		(net "M_J_DQ<4>")
	)
	(segment
		(start 67.195446 -67.07759)
		(end 66.889122 -67.07759)
		(width 0.0889)
		(layer "In11.Cu")
		(net "M_J_DQ<4>")
	)
	(segment
		(start 31.163768 -4.122166)
		(end 31.39948 -4.357878)
		(width 0.14224)
		(layer "In11.Cu")
		(net "M_J_DQ<4>")
	)
	(segment
		(start 31.510986 -0.076454)
		(end 31.510986 -0.381)
		(width 0.14224)
		(layer "In11.Cu")
		(net "M_J_DQ<4>")
	)
	(segment
		(start 31.89732 -6.880098)
		(end 31.39948 -6.382258)
		(width 0.14224)
		(layer "In11.Cu")
		(net "M_J_DQ<4>")
	)
	(segment
		(start 70.626732 -67.07759)
		(end 70.593966 -67.07759)
		(width 0.0889)
		(layer "In11.Cu")
		(net "M_J_DQ<4>")
	)
	(segment
		(start 71.481442 -67.572636)
		(end 71.448676 -67.572636)
		(width 0.0889)
		(layer "In11.Cu")
		(net "M_J_DQ<4>")
	)
	(segment
		(start 74.063606 -69.05879)
		(end 74.028046 -69.05879)
		(width 0.0889)
		(layer "In11.Cu")
		(net "M_J_DQ<4>")
	)
	(segment
		(start 31.747968 -19.1516)
		(end 31.92272 -18.976848)
		(width 0.14224)
		(layer "In11.Cu")
		(net "M_J_DQ<4>")
	)
	(segment
		(start 31.523686 -1.790446)
		(end 31.874968 -2.141728)
		(width 0.14224)
		(layer "In11.Cu")
		(net "M_J_DQ<4>")
	)
	(segment
		(start 31.874968 -23.374604)
		(end 31.66872 -23.168356)
		(width 0.14224)
		(layer "In11.Cu")
		(net "M_J_DQ<4>")
	)
	(segment
		(start 31.874968 -2.616454)
		(end 31.163768 -3.327654)
		(width 0.14224)
		(layer "In11.Cu")
		(net "M_J_DQ<4>")
	)
	(segment
		(start 31.89732 -16.817594)
		(end 31.89732 -13.795756)
		(width 0.14224)
		(layer "In11.Cu")
		(net "M_J_DQ<4>")
	)
	(segment
		(start 66.641472 -67.32524)
		(end 66.641472 -67.428618)
		(width 0.0889)
		(layer "In11.Cu")
		(net "M_J_DQ<4>")
	)
	(segment
		(start 31.891986 -1.0668)
		(end 31.523686 -1.4351)
		(width 0.14224)
		(layer "In11.Cu")
		(net "M_J_DQ<4>")
	)
	(segment
		(start 31.89732 -7.241794)
		(end 31.89732 -6.880098)
		(width 0.14224)
		(layer "In11.Cu")
		(net "M_J_DQ<4>")
	)
	(segment
		(start 31.747968 -9.6012)
		(end 31.92272 -9.426448)
		(width 0.14224)
		(layer "In11.Cu")
		(net "M_J_DQ<4>")
	)
	(segment
		(start 31.92272 -18.567146)
		(end 31.66872 -18.313146)
		(width 0.14224)
		(layer "In11.Cu")
		(net "M_J_DQ<4>")
	)
	(segment
		(start 31.66872 -7.470394)
		(end 31.89732 -7.241794)
		(width 0.14224)
		(layer "In11.Cu")
		(net "M_J_DQ<4>")
	)
	(segment
		(start 72.343772 -68.06819)
		(end 72.311006 -68.06819)
		(width 0.0889)
		(layer "In11.Cu")
		(net "M_J_DQ<4>")
	)
	(segment
		(start 31.747968 -11.585448)
		(end 31.747968 -9.6012)
		(width 0.14224)
		(layer "In11.Cu")
		(net "M_J_DQ<4>")
	)
	(segment
		(start 76.621386 -66.982086)
		(end 76.316078 -67.68592)
		(width 0.0889)
		(layer "In11.Cu")
		(net "M_J_DQ<4>")
	)
	(segment
		(start 66.641472 -67.428618)
		(end 66.34607 -67.72402)
		(width 0.0889)
		(layer "In11.Cu")
		(net "M_J_DQ<4>")
	)
	(segment
		(start 31.39948 -6.382258)
		(end 31.39948 -4.357878)
		(width 0.14224)
		(layer "In11.Cu")
		(net "M_J_DQ<4>")
	)
	(segment
		(start 31.92272 -12.093956)
		(end 31.92272 -11.7602)
		(width 0.14224)
		(layer "In11.Cu")
		(net "M_J_DQ<4>")
	)
	(segment
		(start 31.523686 -1.4351)
		(end 31.523686 -1.790446)
		(width 0.14224)
		(layer "In11.Cu")
		(net "M_J_DQ<4>")
	)
	(arc
		(start 74.028046 -69.05879)
		(mid 73.742622 -68.975323)
		(end 73.534016 -68.763388)
		(width 0.0889)
		(layer "In11.Cu")
		(net "M_J_DQ<4>")
	)
	(arc
		(start 71.816976 -67.772788)
		(mid 71.675293 -67.628984)
		(end 71.481442 -67.572636)
		(width 0.0889)
		(layer "In11.Cu")
		(net "M_J_DQ<4>")
	)
	(arc
		(start 76.316078 -67.68592)
		(mid 76.106453 -67.958397)
		(end 75.780646 -68.06819)
		(width 0.0889)
		(layer "In11.Cu")
		(net "M_J_DQ<4>")
	)
	(arc
		(start 73.534016 -68.763388)
		(mid 73.392333 -68.619584)
		(end 73.198482 -68.563236)
		(width 0.0889)
		(layer "In11.Cu")
		(net "M_J_DQ<4>")
	)
	(arc
		(start 68.876926 -67.07759)
		(mid 68.591502 -66.994123)
		(end 68.382896 -66.782188)
		(width 0.0889)
		(layer "In11.Cu")
		(net "M_J_DQ<4>")
	)
	(arc
		(start 73.165716 -68.563236)
		(mid 72.882499 -68.478955)
		(end 72.675496 -68.268088)
		(width 0.0889)
		(layer "In11.Cu")
		(net "M_J_DQ<4>")
	)
	(arc
		(start 68.382896 -66.782188)
		(mid 68.036186 -66.581877)
		(end 67.689476 -66.782188)
		(width 0.0889)
		(layer "In11.Cu")
		(net "M_J_DQ<4>")
	)
	(arc
		(start 70.593966 -67.07759)
		(mid 70.308542 -66.994123)
		(end 70.099936 -66.782188)
		(width 0.0889)
		(layer "In11.Cu")
		(net "M_J_DQ<4>")
	)
	(arc
		(start 70.099936 -66.782188)
		(mid 69.753226 -66.581877)
		(end 69.406516 -66.782188)
		(width 0.0889)
		(layer "In11.Cu")
		(net "M_J_DQ<4>")
	)
	(arc
		(start 72.675496 -68.268088)
		(mid 72.535417 -68.125352)
		(end 72.343772 -68.06819)
		(width 0.0889)
		(layer "In11.Cu")
		(net "M_J_DQ<4>")
	)
	(arc
		(start 75.416156 -68.268088)
		(mid 75.209152 -68.478952)
		(end 74.925936 -68.563236)
		(width 0.0889)
		(layer "In11.Cu")
		(net "M_J_DQ<4>")
	)
	(arc
		(start 71.448676 -67.572636)
		(mid 71.165459 -67.488355)
		(end 70.958456 -67.277488)
		(width 0.0889)
		(layer "In11.Cu")
		(net "M_J_DQ<4>")
	)
	(arc
		(start 74.89317 -68.563236)
		(mid 74.69932 -68.619586)
		(end 74.557636 -68.763388)
		(width 0.0889)
		(layer "In11.Cu")
		(net "M_J_DQ<4>")
	)
	(arc
		(start 70.958456 -67.277488)
		(mid 70.818377 -67.134752)
		(end 70.626732 -67.07759)
		(width 0.0889)
		(layer "In11.Cu")
		(net "M_J_DQ<4>")
	)
	(arc
		(start 67.689476 -66.782188)
		(mid 67.480868 -66.99412)
		(end 67.195446 -67.07759)
		(width 0.0889)
		(layer "In11.Cu")
		(net "M_J_DQ<4>")
	)
	(arc
		(start 74.557636 -68.763388)
		(mid 74.349028 -68.97532)
		(end 74.063606 -69.05879)
		(width 0.0889)
		(layer "In11.Cu")
		(net "M_J_DQ<4>")
	)
	(arc
		(start 72.311006 -68.06819)
		(mid 72.025582 -67.984723)
		(end 71.816976 -67.772788)
		(width 0.0889)
		(layer "In11.Cu")
		(net "M_J_DQ<4>")
	)
	(arc
		(start 75.74788 -68.06819)
		(mid 75.556238 -68.125356)
		(end 75.416156 -68.268088)
		(width 0.0889)
		(layer "In11.Cu")
		(net "M_J_DQ<4>")
	)
	(arc
		(start 69.406516 -66.782188)
		(mid 69.197908 -66.99412)
		(end 68.912486 -67.07759)
		(width 0.0889)
		(layer "In11.Cu")
		(net "M_J_DQ<4>")
	)
	(segment
		(start 116.495322 -64.819784)
		(end 115.923822 -64.819784)
		(width 0.0889)
		(layer "F.Cu")
		(net "M_J_DQ<49>")
	)
	(segment
		(start 135.099552 3.778758)
		(end 135.099552 2.514854)
		(width 0.1651)
		(layer "F.Cu")
		(net "M_J_DQ<49>")
	)
	(via
		(at 135.771636 -3.076956)
		(size 0.508)
		(drill 0.254)
		(layers "F.Cu" "B.Cu")
		(net "M_J_DQ<49>")
	)
	(via
		(at 135.099552 2.514854)
		(size 0.508)
		(drill 0.254)
		(layers "F.Cu" "B.Cu")
		(net "M_J_DQ<49>")
	)
	(via
		(at 115.923822 -64.819784)
		(size 0.508)
		(drill 0.254)
		(layers "F.Cu" "B.Cu")
		(net "M_J_DQ<49>")
	)
	(segment
		(start 135.771636 -2.573782)
		(end 135.771636 -3.076956)
		(width 0.1651)
		(layer "B.Cu")
		(net "M_J_DQ<49>")
	)
	(segment
		(start 135.949436 -2.395982)
		(end 135.771636 -2.573782)
		(width 0.1651)
		(layer "B.Cu")
		(net "M_J_DQ<49>")
	)
	(segment
		(start 135.949436 -1.021842)
		(end 135.949436 -2.395982)
		(width 0.1651)
		(layer "B.Cu")
		(net "M_J_DQ<49>")
	)
	(segment
		(start 136.302242 1.128776)
		(end 135.932418 1.4986)
		(width 0.14224)
		(layer "In11.Cu")
		(net "M_J_DQ<49>")
	)
	(segment
		(start 116.031772 -62.39256)
		(end 115.761516 -62.213998)
		(width 0.0889)
		(layer "In11.Cu")
		(net "M_J_DQ<49>")
	)
	(segment
		(start 116.229384 -62.567312)
		(end 116.031772 -62.39256)
		(width 0.0889)
		(layer "In11.Cu")
		(net "M_J_DQ<49>")
	)
	(segment
		(start 136.421368 -21.148802)
		(end 136.421368 -19.177)
		(width 0.14224)
		(layer "In11.Cu")
		(net "M_J_DQ<49>")
	)
	(segment
		(start 115.236752 -53.155342)
		(end 115.236752 -47.803816)
		(width 0.0889)
		(layer "In11.Cu")
		(net "M_J_DQ<49>")
	)
	(segment
		(start 135.099552 1.975866)
		(end 135.099552 2.514854)
		(width 0.14224)
		(layer "In11.Cu")
		(net "M_J_DQ<49>")
	)
	(segment
		(start 124.413772 -33.803844)
		(end 125.370336 -33.803844)
		(width 0.14224)
		(layer "In11.Cu")
		(net "M_J_DQ<49>")
	)
	(segment
		(start 136.302242 0.7874)
		(end 136.302242 1.128776)
		(width 0.14224)
		(layer "In11.Cu")
		(net "M_J_DQ<49>")
	)
	(segment
		(start 115.577112 -61.648086)
		(end 115.583462 -61.637418)
		(width 0.0889)
		(layer "In11.Cu")
		(net "M_J_DQ<49>")
	)
	(segment
		(start 136.145778 0.630936)
		(end 136.302242 0.7874)
		(width 0.14224)
		(layer "In11.Cu")
		(net "M_J_DQ<49>")
	)
	(segment
		(start 125.370336 -33.803844)
		(end 125.87478 -33.2994)
		(width 0.14224)
		(layer "In11.Cu")
		(net "M_J_DQ<49>")
	)
	(segment
		(start 116.275358 -62.647322)
		(end 116.229384 -62.567312)
		(width 0.0889)
		(layer "In11.Cu")
		(net "M_J_DQ<49>")
	)
	(segment
		(start 135.62457 -4.232148)
		(end 135.245094 -3.852672)
		(width 0.14224)
		(layer "In11.Cu")
		(net "M_J_DQ<49>")
	)
	(segment
		(start 115.948968 -45.768768)
		(end 119.038624 -42.679112)
		(width 0.14224)
		(layer "In11.Cu")
		(net "M_J_DQ<49>")
	)
	(segment
		(start 116.23929 -63.092838)
		(end 116.270532 -63.038736)
		(width 0.0889)
		(layer "In11.Cu")
		(net "M_J_DQ<49>")
	)
	(segment
		(start 136.25957 -19.015202)
		(end 136.25957 -6.569202)
		(width 0.14224)
		(layer "In11.Cu")
		(net "M_J_DQ<49>")
	)
	(segment
		(start 115.577112 -54.123336)
		(end 115.576604 -54.12359)
		(width 0.0889)
		(layer "In11.Cu")
		(net "M_J_DQ<49>")
	)
	(segment
		(start 132.32257 -33.2994)
		(end 136.25957 -29.3624)
		(width 0.14224)
		(layer "In11.Cu")
		(net "M_J_DQ<49>")
	)
	(segment
		(start 135.245094 -3.603498)
		(end 135.771636 -3.076956)
		(width 0.14224)
		(layer "In11.Cu")
		(net "M_J_DQ<49>")
	)
	(segment
		(start 115.572286 -56.703722)
		(end 115.577112 -56.695086)
		(width 0.0889)
		(layer "In11.Cu")
		(net "M_J_DQ<49>")
	)
	(segment
		(start 115.572286 -61.656722)
		(end 115.577112 -61.648086)
		(width 0.0889)
		(layer "In11.Cu")
		(net "M_J_DQ<49>")
	)
	(segment
		(start 119.038624 -42.679112)
		(end 119.038624 -39.178992)
		(width 0.14224)
		(layer "In11.Cu")
		(net "M_J_DQ<49>")
	)
	(segment
		(start 115.572286 -63.637922)
		(end 115.577112 -63.629286)
		(width 0.0889)
		(layer "In11.Cu")
		(net "M_J_DQ<49>")
	)
	(segment
		(start 115.583462 -59.087004)
		(end 115.577112 -59.076336)
		(width 0.0889)
		(layer "In11.Cu")
		(net "M_J_DQ<49>")
	)
	(segment
		(start 135.771636 -3.076956)
		(end 136.145778 -2.702814)
		(width 0.14224)
		(layer "In11.Cu")
		(net "M_J_DQ<49>")
	)
	(segment
		(start 115.577112 -60.657486)
		(end 115.583462 -60.646818)
		(width 0.0889)
		(layer "In11.Cu")
		(net "M_J_DQ<49>")
	)
	(segment
		(start 115.576604 -54.12359)
		(end 115.523772 -54.03215)
		(width 0.0889)
		(layer "In11.Cu")
		(net "M_J_DQ<49>")
	)
	(segment
		(start 135.245094 -3.852672)
		(end 135.245094 -3.603498)
		(width 0.14224)
		(layer "In11.Cu")
		(net "M_J_DQ<49>")
	)
	(segment
		(start 115.738402 -63.474346)
		(end 116.131848 -63.200026)
		(width 0.0889)
		(layer "In11.Cu")
		(net "M_J_DQ<49>")
	)
	(segment
		(start 115.577112 -57.685686)
		(end 115.583462 -57.675018)
		(width 0.0889)
		(layer "In11.Cu")
		(net "M_J_DQ<49>")
	)
	(segment
		(start 135.62457 -5.934202)
		(end 135.62457 -4.232148)
		(width 0.14224)
		(layer "In11.Cu")
		(net "M_J_DQ<49>")
	)
	(segment
		(start 136.421368 -19.177)
		(end 136.25957 -19.015202)
		(width 0.14224)
		(layer "In11.Cu")
		(net "M_J_DQ<49>")
	)
	(segment
		(start 119.038624 -39.178992)
		(end 124.413772 -33.803844)
		(width 0.14224)
		(layer "In11.Cu")
		(net "M_J_DQ<49>")
	)
	(segment
		(start 115.572286 -57.694322)
		(end 115.577112 -57.685686)
		(width 0.0889)
		(layer "In11.Cu")
		(net "M_J_DQ<49>")
	)
	(segment
		(start 115.593876 -64.058038)
		(end 115.577112 -64.029336)
		(width 0.0889)
		(layer "In11.Cu")
		(net "M_J_DQ<49>")
	)
	(segment
		(start 115.577112 -54.713886)
		(end 115.583462 -54.703218)
		(width 0.0889)
		(layer "In11.Cu")
		(net "M_J_DQ<49>")
	)
	(segment
		(start 136.25957 -21.3106)
		(end 136.421368 -21.148802)
		(width 0.14224)
		(layer "In11.Cu")
		(net "M_J_DQ<49>")
	)
	(segment
		(start 135.932418 1.4986)
		(end 135.576818 1.4986)
		(width 0.14224)
		(layer "In11.Cu")
		(net "M_J_DQ<49>")
	)
	(segment
		(start 115.572286 -60.666122)
		(end 115.577112 -60.657486)
		(width 0.0889)
		(layer "In11.Cu")
		(net "M_J_DQ<49>")
	)
	(segment
		(start 115.572286 -59.675522)
		(end 115.577112 -59.666886)
		(width 0.0889)
		(layer "In11.Cu")
		(net "M_J_DQ<49>")
	)
	(segment
		(start 115.572286 -54.722522)
		(end 115.577112 -54.713886)
		(width 0.0889)
		(layer "In11.Cu")
		(net "M_J_DQ<49>")
	)
	(segment
		(start 115.236752 -47.803816)
		(end 115.948968 -47.0916)
		(width 0.0889)
		(layer "In11.Cu")
		(net "M_J_DQ<49>")
	)
	(segment
		(start 136.25957 -29.3624)
		(end 136.25957 -21.3106)
		(width 0.14224)
		(layer "In11.Cu")
		(net "M_J_DQ<49>")
	)
	(segment
		(start 115.948968 -47.0916)
		(end 115.948968 -45.768768)
		(width 0.14224)
		(layer "In11.Cu")
		(net "M_J_DQ<49>")
	)
	(segment
		(start 115.572286 -55.713122)
		(end 115.577112 -55.704486)
		(width 0.0889)
		(layer "In11.Cu")
		(net "M_J_DQ<49>")
	)
	(segment
		(start 115.577112 -56.695086)
		(end 115.583462 -56.684418)
		(width 0.0889)
		(layer "In11.Cu")
		(net "M_J_DQ<49>")
	)
	(segment
		(start 115.577112 -55.704486)
		(end 115.583462 -55.693818)
		(width 0.0889)
		(layer "In11.Cu")
		(net "M_J_DQ<49>")
	)
	(segment
		(start 115.523772 -53.442362)
		(end 115.236752 -53.155342)
		(width 0.0889)
		(layer "In11.Cu")
		(net "M_J_DQ<49>")
	)
	(segment
		(start 125.87478 -33.2994)
		(end 132.32257 -33.2994)
		(width 0.14224)
		(layer "In11.Cu")
		(net "M_J_DQ<49>")
	)
	(segment
		(start 136.25957 -6.569202)
		(end 135.62457 -5.934202)
		(width 0.14224)
		(layer "In11.Cu")
		(net "M_J_DQ<49>")
	)
	(segment
		(start 136.145778 -2.702814)
		(end 136.145778 0.630936)
		(width 0.14224)
		(layer "In11.Cu")
		(net "M_J_DQ<49>")
	)
	(segment
		(start 115.923822 -64.819784)
		(end 115.593876 -64.058038)
		(width 0.0889)
		(layer "In11.Cu")
		(net "M_J_DQ<49>")
	)
	(segment
		(start 116.131848 -63.200026)
		(end 116.23929 -63.092838)
		(width 0.0889)
		(layer "In11.Cu")
		(net "M_J_DQ<49>")
	)
	(segment
		(start 115.523772 -54.03215)
		(end 115.523772 -53.442362)
		(width 0.0889)
		(layer "In11.Cu")
		(net "M_J_DQ<49>")
	)
	(segment
		(start 135.576818 1.4986)
		(end 135.099552 1.975866)
		(width 0.14224)
		(layer "In11.Cu")
		(net "M_J_DQ<49>")
	)
	(arc
		(start 115.577112 -59.076336)
		(mid 115.523613 -58.876438)
		(end 115.577112 -58.67654)
		(width 0.0889)
		(layer "In11.Cu")
		(net "M_J_DQ<49>")
	)
	(arc
		(start 115.583462 -55.693818)
		(mid 115.65626 -55.403055)
		(end 115.577112 -55.113936)
		(width 0.0889)
		(layer "In11.Cu")
		(net "M_J_DQ<49>")
	)
	(arc
		(start 115.583462 -61.637418)
		(mid 115.65626 -61.346655)
		(end 115.577112 -61.057536)
		(width 0.0889)
		(layer "In11.Cu")
		(net "M_J_DQ<49>")
	)
	(arc
		(start 115.577112 -55.113936)
		(mid 115.523642 -54.918873)
		(end 115.572286 -54.722522)
		(width 0.0889)
		(layer "In11.Cu")
		(net "M_J_DQ<49>")
	)
	(arc
		(start 115.583462 -56.684418)
		(mid 115.65626 -56.393655)
		(end 115.577112 -56.104536)
		(width 0.0889)
		(layer "In11.Cu")
		(net "M_J_DQ<49>")
	)
	(arc
		(start 115.577112 -59.666886)
		(mid 115.656334 -59.377768)
		(end 115.583462 -59.087004)
		(width 0.0889)
		(layer "In11.Cu")
		(net "M_J_DQ<49>")
	)
	(arc
		(start 115.583462 -57.675018)
		(mid 115.65626 -57.384255)
		(end 115.577112 -57.095136)
		(width 0.0889)
		(layer "In11.Cu")
		(net "M_J_DQ<49>")
	)
	(arc
		(start 115.577112 -57.095136)
		(mid 115.523642 -56.900073)
		(end 115.572286 -56.703722)
		(width 0.0889)
		(layer "In11.Cu")
		(net "M_J_DQ<49>")
	)
	(arc
		(start 115.577112 -58.67654)
		(mid 115.656243 -58.381138)
		(end 115.577112 -58.085736)
		(width 0.0889)
		(layer "In11.Cu")
		(net "M_J_DQ<49>")
	)
	(arc
		(start 115.583462 -54.703218)
		(mid 115.65626 -54.412455)
		(end 115.577112 -54.123336)
		(width 0.0889)
		(layer "In11.Cu")
		(net "M_J_DQ<49>")
	)
	(arc
		(start 115.577112 -63.629286)
		(mid 115.646702 -63.540303)
		(end 115.738402 -63.474346)
		(width 0.0889)
		(layer "In11.Cu")
		(net "M_J_DQ<49>")
	)
	(arc
		(start 115.761516 -62.213998)
		(mid 115.544724 -61.976803)
		(end 115.572286 -61.656722)
		(width 0.0889)
		(layer "In11.Cu")
		(net "M_J_DQ<49>")
	)
	(arc
		(start 115.577112 -64.029336)
		(mid 115.523642 -63.834273)
		(end 115.572286 -63.637922)
		(width 0.0889)
		(layer "In11.Cu")
		(net "M_J_DQ<49>")
	)
	(arc
		(start 115.577112 -60.066936)
		(mid 115.523642 -59.871873)
		(end 115.572286 -59.675522)
		(width 0.0889)
		(layer "In11.Cu")
		(net "M_J_DQ<49>")
	)
	(arc
		(start 115.577112 -61.057536)
		(mid 115.523642 -60.862473)
		(end 115.572286 -60.666122)
		(width 0.0889)
		(layer "In11.Cu")
		(net "M_J_DQ<49>")
	)
	(arc
		(start 115.577112 -56.104536)
		(mid 115.523642 -55.909473)
		(end 115.572286 -55.713122)
		(width 0.0889)
		(layer "In11.Cu")
		(net "M_J_DQ<49>")
	)
	(arc
		(start 115.583462 -60.646818)
		(mid 115.65626 -60.356055)
		(end 115.577112 -60.066936)
		(width 0.0889)
		(layer "In11.Cu")
		(net "M_J_DQ<49>")
	)
	(arc
		(start 116.270532 -63.038736)
		(mid 116.324002 -62.843673)
		(end 116.275358 -62.647322)
		(width 0.0889)
		(layer "In11.Cu")
		(net "M_J_DQ<49>")
	)
	(arc
		(start 115.577112 -58.085736)
		(mid 115.523642 -57.890673)
		(end 115.572286 -57.694322)
		(width 0.0889)
		(layer "In11.Cu")
		(net "M_J_DQ<49>")
	)
	(segment
		(start 135.949436 -0.821182)
		(end 135.771636 1.0414)
		(width 0.1651)
		(layer "F.Cu")
		(net "M_J_DQ<48>")
	)
	(segment
		(start 116.495322 -62.838584)
		(end 115.923822 -62.838584)
		(width 0.0889)
		(layer "F.Cu")
		(net "M_J_DQ<48>")
	)
	(via
		(at 135.099552 -4.357878)
		(size 0.508)
		(drill 0.254)
		(layers "F.Cu" "B.Cu")
		(net "M_J_DQ<48>")
	)
	(via
		(at 115.923822 -62.838584)
		(size 0.508)
		(drill 0.254)
		(layers "F.Cu" "B.Cu")
		(net "M_J_DQ<48>")
	)
	(via
		(at 135.771636 1.0414)
		(size 0.508)
		(drill 0.254)
		(layers "F.Cu" "B.Cu")
		(net "M_J_DQ<48>")
	)
	(segment
		(start 135.099552 -5.621782)
		(end 135.099552 -4.357878)
		(width 0.1651)
		(layer "B.Cu")
		(net "M_J_DQ<48>")
	)
	(segment
		(start 135.551418 -2.5908)
		(end 135.551418 -2.090928)
		(width 0.14224)
		(layer "In11.Cu")
		(net "M_J_DQ<48>")
	)
	(segment
		(start 135.57377 -7.224776)
		(end 135.57377 -6.772402)
		(width 0.14224)
		(layer "In11.Cu")
		(net "M_J_DQ<48>")
	)
	(segment
		(start 135.297164 -26.942796)
		(end 135.576564 -26.663396)
		(width 0.14224)
		(layer "In11.Cu")
		(net "M_J_DQ<48>")
	)
	(segment
		(start 135.627364 -21.3868)
		(end 135.456168 -21.215604)
		(width 0.14224)
		(layer "In11.Cu")
		(net "M_J_DQ<48>")
	)
	(segment
		(start 130.615944 -31.8008)
		(end 130.819144 -32.004)
		(width 0.14224)
		(layer "In11.Cu")
		(net "M_J_DQ<48>")
	)
	(segment
		(start 135.62457 -9.033002)
		(end 135.28167 -8.690102)
		(width 0.14224)
		(layer "In11.Cu")
		(net "M_J_DQ<48>")
	)
	(segment
		(start 115.412012 -56.599836)
		(end 115.416838 -56.5912)
		(width 0.0889)
		(layer "In11.Cu")
		(net "M_J_DQ<48>")
	)
	(segment
		(start 115.046252 -53.235606)
		(end 115.046252 -47.707042)
		(width 0.0889)
		(layer "In11.Cu")
		(net "M_J_DQ<48>")
	)
	(segment
		(start 115.245896 -47.507398)
		(end 115.245896 -47.309278)
		(width 0.0889)
		(layer "In11.Cu")
		(net "M_J_DQ<48>")
	)
	(segment
		(start 132.038344 -31.237428)
		(end 132.241544 -31.440628)
		(width 0.14224)
		(layer "In11.Cu")
		(net "M_J_DQ<48>")
	)
	(segment
		(start 135.532622 -16.8656)
		(end 135.576564 -16.821658)
		(width 0.14224)
		(layer "In11.Cu")
		(net "M_J_DQ<48>")
	)
	(segment
		(start 115.333272 -54.108604)
		(end 115.333272 -53.522626)
		(width 0.0889)
		(layer "In11.Cu")
		(net "M_J_DQ<48>")
	)
	(segment
		(start 115.412012 -58.581036)
		(end 115.416838 -58.5724)
		(width 0.0889)
		(layer "In11.Cu")
		(net "M_J_DQ<48>")
	)
	(segment
		(start 135.136636 -0.508)
		(end 135.136636 -0.178054)
		(width 0.14224)
		(layer "In11.Cu")
		(net "M_J_DQ<48>")
	)
	(segment
		(start 115.388136 -45.421804)
		(end 118.427754 -42.382186)
		(width 0.14224)
		(layer "In11.Cu")
		(net "M_J_DQ<48>")
	)
	(segment
		(start 135.627364 -19.005804)
		(end 135.627364 -18.66265)
		(width 0.14224)
		(layer "In11.Cu")
		(net "M_J_DQ<48>")
	)
	(segment
		(start 132.719572 -32.004)
		(end 135.581136 -29.142436)
		(width 0.14224)
		(layer "In11.Cu")
		(net "M_J_DQ<48>")
	)
	(segment
		(start 132.444744 -32.004)
		(end 132.719572 -32.004)
		(width 0.14224)
		(layer "In11.Cu")
		(net "M_J_DQ<48>")
	)
	(segment
		(start 131.631944 -31.237428)
		(end 132.038344 -31.237428)
		(width 0.14224)
		(layer "In11.Cu")
		(net "M_J_DQ<48>")
	)
	(segment
		(start 129.945384 -31.496)
		(end 130.473704 -31.496)
		(width 0.14224)
		(layer "In11.Cu")
		(net "M_J_DQ<48>")
	)
	(segment
		(start 135.297164 -18.33245)
		(end 135.297164 -17.102582)
		(width 0.14224)
		(layer "In11.Cu")
		(net "M_J_DQ<48>")
	)
	(segment
		(start 135.576564 -16.821658)
		(end 135.576564 -13.781532)
		(width 0.14224)
		(layer "In11.Cu")
		(net "M_J_DQ<48>")
	)
	(segment
		(start 135.28167 -8.690102)
		(end 135.28167 -7.516876)
		(width 0.14224)
		(layer "In11.Cu")
		(net "M_J_DQ<48>")
	)
	(segment
		(start 135.627364 -21.634196)
		(end 135.627364 -21.3868)
		(width 0.14224)
		(layer "In11.Cu")
		(net "M_J_DQ<48>")
	)
	(segment
		(start 118.427754 -38.891464)
		(end 124.527818 -32.7914)
		(width 0.14224)
		(layer "In11.Cu")
		(net "M_J_DQ<48>")
	)
	(segment
		(start 135.551418 0.236728)
		(end 135.551418 0.821182)
		(width 0.14224)
		(layer "In11.Cu")
		(net "M_J_DQ<48>")
	)
	(segment
		(start 135.551418 -2.090928)
		(end 135.162036 -1.701546)
		(width 0.14224)
		(layer "In11.Cu")
		(net "M_J_DQ<48>")
	)
	(segment
		(start 132.241544 -31.8008)
		(end 132.444744 -32.004)
		(width 0.14224)
		(layer "In11.Cu")
		(net "M_J_DQ<48>")
	)
	(segment
		(start 132.241544 -31.440628)
		(end 132.241544 -31.8008)
		(width 0.14224)
		(layer "In11.Cu")
		(net "M_J_DQ<48>")
	)
	(segment
		(start 135.456168 -19.177)
		(end 135.627364 -19.005804)
		(width 0.14224)
		(layer "In11.Cu")
		(net "M_J_DQ<48>")
	)
	(segment
		(start 135.576564 -23.386796)
		(end 135.297164 -23.107396)
		(width 0.14224)
		(layer "In11.Cu")
		(net "M_J_DQ<48>")
	)
	(segment
		(start 135.627364 -18.66265)
		(end 135.297164 -18.33245)
		(width 0.14224)
		(layer "In11.Cu")
		(net "M_J_DQ<48>")
	)
	(segment
		(start 129.803144 -32.348424)
		(end 129.803144 -31.63824)
		(width 0.14224)
		(layer "In11.Cu")
		(net "M_J_DQ<48>")
	)
	(segment
		(start 115.923822 -62.838584)
		(end 115.428776 -62.17285)
		(width 0.0889)
		(layer "In11.Cu")
		(net "M_J_DQ<48>")
	)
	(segment
		(start 115.412012 -57.590436)
		(end 115.416838 -57.5818)
		(width 0.0889)
		(layer "In11.Cu")
		(net "M_J_DQ<48>")
	)
	(segment
		(start 115.412012 -60.562236)
		(end 115.416838 -60.5536)
		(width 0.0889)
		(layer "In11.Cu")
		(net "M_J_DQ<48>")
	)
	(segment
		(start 135.581136 -29.142436)
		(end 135.581136 -28.335224)
		(width 0.14224)
		(layer "In11.Cu")
		(net "M_J_DQ<48>")
	)
	(segment
		(start 135.297164 -17.102582)
		(end 135.532622 -16.867124)
		(width 0.14224)
		(layer "In11.Cu")
		(net "M_J_DQ<48>")
	)
	(segment
		(start 118.427754 -42.382186)
		(end 118.427754 -38.891464)
		(width 0.14224)
		(layer "In11.Cu")
		(net "M_J_DQ<48>")
	)
	(segment
		(start 115.333272 -53.522626)
		(end 115.046252 -53.235606)
		(width 0.0889)
		(layer "In11.Cu")
		(net "M_J_DQ<48>")
	)
	(segment
		(start 135.099552 -4.357878)
		(end 134.814818 -4.073144)
		(width 0.14224)
		(layer "In11.Cu")
		(net "M_J_DQ<48>")
	)
	(segment
		(start 135.162036 -1.701546)
		(end 135.162036 -1.397)
		(width 0.14224)
		(layer "In11.Cu")
		(net "M_J_DQ<48>")
	)
	(segment
		(start 135.551418 0.821182)
		(end 135.771636 1.0414)
		(width 0.14224)
		(layer "In11.Cu")
		(net "M_J_DQ<48>")
	)
	(segment
		(start 115.405662 -57.601104)
		(end 115.412012 -57.590436)
		(width 0.0889)
		(layer "In11.Cu")
		(net "M_J_DQ<48>")
	)
	(segment
		(start 115.412012 -54.618636)
		(end 115.416838 -54.61)
		(width 0.0889)
		(layer "In11.Cu")
		(net "M_J_DQ<48>")
	)
	(segment
		(start 115.412012 -61.552836)
		(end 115.416838 -61.5442)
		(width 0.0889)
		(layer "In11.Cu")
		(net "M_J_DQ<48>")
	)
	(segment
		(start 115.412012 -59.171586)
		(end 115.405662 -59.160918)
		(width 0.0889)
		(layer "In11.Cu")
		(net "M_J_DQ<48>")
	)
	(segment
		(start 131.225544 -32.004)
		(end 131.428744 -31.8008)
		(width 0.14224)
		(layer "In11.Cu")
		(net "M_J_DQ<48>")
	)
	(segment
		(start 135.162036 -1.397)
		(end 135.479536 -1.0795)
		(width 0.14224)
		(layer "In11.Cu")
		(net "M_J_DQ<48>")
	)
	(segment
		(start 135.576564 -13.781532)
		(end 135.297164 -13.502132)
		(width 0.14224)
		(layer "In11.Cu")
		(net "M_J_DQ<48>")
	)
	(segment
		(start 115.412012 -55.609236)
		(end 115.416838 -55.6006)
		(width 0.0889)
		(layer "In11.Cu")
		(net "M_J_DQ<48>")
	)
	(segment
		(start 135.532622 -16.867124)
		(end 135.532622 -16.8656)
		(width 0.14224)
		(layer "In11.Cu")
		(net "M_J_DQ<48>")
	)
	(segment
		(start 130.819144 -32.004)
		(end 131.225544 -32.004)
		(width 0.14224)
		(layer "In11.Cu")
		(net "M_J_DQ<48>")
	)
	(segment
		(start 135.62457 -12.02817)
		(end 135.62457 -9.033002)
		(width 0.14224)
		(layer "In11.Cu")
		(net "M_J_DQ<48>")
	)
	(segment
		(start 115.405662 -60.572904)
		(end 115.412012 -60.562236)
		(width 0.0889)
		(layer "In11.Cu")
		(net "M_J_DQ<48>")
	)
	(segment
		(start 134.814818 -3.3274)
		(end 135.551418 -2.5908)
		(width 0.14224)
		(layer "In11.Cu")
		(net "M_J_DQ<48>")
	)
	(segment
		(start 135.581136 -28.335224)
		(end 135.297164 -28.051252)
		(width 0.14224)
		(layer "In11.Cu")
		(net "M_J_DQ<48>")
	)
	(segment
		(start 115.405662 -61.563504)
		(end 115.412012 -61.552836)
		(width 0.0889)
		(layer "In11.Cu")
		(net "M_J_DQ<48>")
	)
	(segment
		(start 135.297164 -28.051252)
		(end 135.297164 -26.942796)
		(width 0.14224)
		(layer "In11.Cu")
		(net "M_J_DQ<48>")
	)
	(segment
		(start 135.099552 -6.298184)
		(end 135.099552 -4.357878)
		(width 0.14224)
		(layer "In11.Cu")
		(net "M_J_DQ<48>")
	)
	(segment
		(start 115.405662 -54.629304)
		(end 115.412012 -54.618636)
		(width 0.0889)
		(layer "In11.Cu")
		(net "M_J_DQ<48>")
	)
	(segment
		(start 135.297164 -21.964396)
		(end 135.627364 -21.634196)
		(width 0.14224)
		(layer "In11.Cu")
		(net "M_J_DQ<48>")
	)
	(segment
		(start 134.814818 -4.073144)
		(end 134.814818 -3.3274)
		(width 0.14224)
		(layer "In11.Cu")
		(net "M_J_DQ<48>")
	)
	(segment
		(start 130.615944 -31.63824)
		(end 130.615944 -31.8008)
		(width 0.14224)
		(layer "In11.Cu")
		(net "M_J_DQ<48>")
	)
	(segment
		(start 124.527818 -32.7914)
		(end 129.360168 -32.7914)
		(width 0.14224)
		(layer "In11.Cu")
		(net "M_J_DQ<48>")
	)
	(segment
		(start 135.297164 -12.355576)
		(end 135.62457 -12.02817)
		(width 0.14224)
		(layer "In11.Cu")
		(net "M_J_DQ<48>")
	)
	(segment
		(start 115.046252 -47.707042)
		(end 115.245896 -47.507398)
		(width 0.0889)
		(layer "In11.Cu")
		(net "M_J_DQ<48>")
	)
	(segment
		(start 135.297164 -13.502132)
		(end 135.297164 -12.355576)
		(width 0.14224)
		(layer "In11.Cu")
		(net "M_J_DQ<48>")
	)
	(segment
		(start 130.473704 -31.496)
		(end 130.615944 -31.63824)
		(width 0.14224)
		(layer "In11.Cu")
		(net "M_J_DQ<48>")
	)
	(segment
		(start 135.479536 -0.8509)
		(end 135.136636 -0.508)
		(width 0.14224)
		(layer "In11.Cu")
		(net "M_J_DQ<48>")
	)
	(segment
		(start 115.412012 -54.218586)
		(end 115.36934 -54.144672)
		(width 0.0889)
		(layer "In11.Cu")
		(net "M_J_DQ<48>")
	)
	(segment
		(start 115.36934 -54.144672)
		(end 115.333272 -54.108604)
		(width 0.0889)
		(layer "In11.Cu")
		(net "M_J_DQ<48>")
	)
	(segment
		(start 135.576564 -26.663396)
		(end 135.576564 -23.386796)
		(width 0.14224)
		(layer "In11.Cu")
		(net "M_J_DQ<48>")
	)
	(segment
		(start 135.28167 -7.516876)
		(end 135.57377 -7.224776)
		(width 0.14224)
		(layer "In11.Cu")
		(net "M_J_DQ<48>")
	)
	(segment
		(start 135.479536 -1.0795)
		(end 135.479536 -0.8509)
		(width 0.14224)
		(layer "In11.Cu")
		(net "M_J_DQ<48>")
	)
	(segment
		(start 115.388136 -47.167038)
		(end 115.388136 -45.421804)
		(width 0.14224)
		(layer "In11.Cu")
		(net "M_J_DQ<48>")
	)
	(segment
		(start 131.428744 -31.8008)
		(end 131.428744 -31.440628)
		(width 0.14224)
		(layer "In11.Cu")
		(net "M_J_DQ<48>")
	)
	(segment
		(start 115.405662 -56.610504)
		(end 115.412012 -56.599836)
		(width 0.0889)
		(layer "In11.Cu")
		(net "M_J_DQ<48>")
	)
	(segment
		(start 135.136636 -0.178054)
		(end 135.551418 0.236728)
		(width 0.14224)
		(layer "In11.Cu")
		(net "M_J_DQ<48>")
	)
	(segment
		(start 115.245896 -47.309278)
		(end 115.388136 -47.167038)
		(width 0.0889)
		(layer "In11.Cu")
		(net "M_J_DQ<48>")
	)
	(segment
		(start 129.360168 -32.7914)
		(end 129.803144 -32.348424)
		(width 0.14224)
		(layer "In11.Cu")
		(net "M_J_DQ<48>")
	)
	(segment
		(start 115.405662 -55.619904)
		(end 115.412012 -55.609236)
		(width 0.0889)
		(layer "In11.Cu")
		(net "M_J_DQ<48>")
	)
	(segment
		(start 135.297164 -23.107396)
		(end 135.297164 -21.964396)
		(width 0.14224)
		(layer "In11.Cu")
		(net "M_J_DQ<48>")
	)
	(segment
		(start 115.428776 -62.17285)
		(end 115.412012 -62.143386)
		(width 0.0889)
		(layer "In11.Cu")
		(net "M_J_DQ<48>")
	)
	(segment
		(start 135.57377 -6.772402)
		(end 135.099552 -6.298184)
		(width 0.14224)
		(layer "In11.Cu")
		(net "M_J_DQ<48>")
	)
	(segment
		(start 129.803144 -31.63824)
		(end 129.945384 -31.496)
		(width 0.14224)
		(layer "In11.Cu")
		(net "M_J_DQ<48>")
	)
	(segment
		(start 135.456168 -21.215604)
		(end 135.456168 -19.177)
		(width 0.14224)
		(layer "In11.Cu")
		(net "M_J_DQ<48>")
	)
	(segment
		(start 131.428744 -31.440628)
		(end 131.631944 -31.237428)
		(width 0.14224)
		(layer "In11.Cu")
		(net "M_J_DQ<48>")
	)
	(arc
		(start 115.412012 -60.162186)
		(mid 115.332881 -59.866784)
		(end 115.412012 -59.571382)
		(width 0.0889)
		(layer "In11.Cu")
		(net "M_J_DQ<48>")
	)
	(arc
		(start 115.412012 -56.199786)
		(mid 115.33279 -55.910668)
		(end 115.405662 -55.619904)
		(width 0.0889)
		(layer "In11.Cu")
		(net "M_J_DQ<48>")
	)
	(arc
		(start 115.416838 -61.5442)
		(mid 115.465593 -61.347848)
		(end 115.412012 -61.152786)
		(width 0.0889)
		(layer "In11.Cu")
		(net "M_J_DQ<48>")
	)
	(arc
		(start 115.412012 -62.143386)
		(mid 115.33279 -61.854268)
		(end 115.405662 -61.563504)
		(width 0.0889)
		(layer "In11.Cu")
		(net "M_J_DQ<48>")
	)
	(arc
		(start 115.416838 -55.6006)
		(mid 115.465593 -55.404248)
		(end 115.412012 -55.209186)
		(width 0.0889)
		(layer "In11.Cu")
		(net "M_J_DQ<48>")
	)
	(arc
		(start 115.416838 -57.5818)
		(mid 115.465593 -57.385448)
		(end 115.412012 -57.190386)
		(width 0.0889)
		(layer "In11.Cu")
		(net "M_J_DQ<48>")
	)
	(arc
		(start 115.412012 -55.209186)
		(mid 115.33279 -54.920068)
		(end 115.405662 -54.629304)
		(width 0.0889)
		(layer "In11.Cu")
		(net "M_J_DQ<48>")
	)
	(arc
		(start 115.416838 -60.5536)
		(mid 115.465593 -60.357248)
		(end 115.412012 -60.162186)
		(width 0.0889)
		(layer "In11.Cu")
		(net "M_J_DQ<48>")
	)
	(arc
		(start 115.405662 -59.160918)
		(mid 115.332864 -58.870155)
		(end 115.412012 -58.581036)
		(width 0.0889)
		(layer "In11.Cu")
		(net "M_J_DQ<48>")
	)
	(arc
		(start 115.412012 -61.152786)
		(mid 115.33279 -60.863668)
		(end 115.405662 -60.572904)
		(width 0.0889)
		(layer "In11.Cu")
		(net "M_J_DQ<48>")
	)
	(arc
		(start 115.416838 -58.5724)
		(mid 115.465593 -58.376048)
		(end 115.412012 -58.180986)
		(width 0.0889)
		(layer "In11.Cu")
		(net "M_J_DQ<48>")
	)
	(arc
		(start 115.416838 -54.61)
		(mid 115.465593 -54.413648)
		(end 115.412012 -54.218586)
		(width 0.0889)
		(layer "In11.Cu")
		(net "M_J_DQ<48>")
	)
	(arc
		(start 115.412012 -59.571382)
		(mid 115.465511 -59.371484)
		(end 115.412012 -59.171586)
		(width 0.0889)
		(layer "In11.Cu")
		(net "M_J_DQ<48>")
	)
	(arc
		(start 115.412012 -58.180986)
		(mid 115.33279 -57.891868)
		(end 115.405662 -57.601104)
		(width 0.0889)
		(layer "In11.Cu")
		(net "M_J_DQ<48>")
	)
	(arc
		(start 115.416838 -56.5912)
		(mid 115.465593 -56.394848)
		(end 115.412012 -56.199786)
		(width 0.0889)
		(layer "In11.Cu")
		(net "M_J_DQ<48>")
	)
	(arc
		(start 115.412012 -57.190386)
		(mid 115.33279 -56.901268)
		(end 115.405662 -56.610504)
		(width 0.0889)
		(layer "In11.Cu")
		(net "M_J_DQ<48>")
	)
	(segment
		(start 115.636802 -61.352938)
		(end 115.065302 -61.352938)
		(width 0.0889)
		(layer "F.Cu")
		(net "M_J_DQ<47>")
	)
	(segment
		(start 129.999486 3.778758)
		(end 129.999486 2.514854)
		(width 0.1651)
		(layer "F.Cu")
		(net "M_J_DQ<47>")
	)
	(via
		(at 129.999486 2.514854)
		(size 0.508)
		(drill 0.254)
		(layers "F.Cu" "B.Cu")
		(net "M_J_DQ<47>")
	)
	(via
		(at 115.065302 -61.352938)
		(size 0.508)
		(drill 0.254)
		(layers "F.Cu" "B.Cu")
		(net "M_J_DQ<47>")
	)
	(via
		(at 130.84937 -3.076956)
		(size 0.508)
		(drill 0.254)
		(layers "F.Cu" "B.Cu")
		(net "M_J_DQ<47>")
	)
	(segment
		(start 130.84937 -1.021842)
		(end 130.84937 -3.076956)
		(width 0.1651)
		(layer "B.Cu")
		(net "M_J_DQ<47>")
	)
	(segment
		(start 131.227576 -13.694156)
		(end 131.227576 -16.890746)
		(width 0.14224)
		(layer "In4.Cu")
		(net "M_J_DQ<47>")
	)
	(segment
		(start 130.363976 -3.985768)
		(end 131.151376 -4.773168)
		(width 0.14224)
		(layer "In4.Cu")
		(net "M_J_DQ<47>")
	)
	(segment
		(start 117.988588 -50.63744)
		(end 115.898168 -52.72786)
		(width 0.0889)
		(layer "In4.Cu")
		(net "M_J_DQ<47>")
	)
	(segment
		(start 115.898168 -52.72786)
		(end 115.898168 -53.162454)
		(width 0.0889)
		(layer "In4.Cu")
		(net "M_J_DQ<47>")
	)
	(segment
		(start 119.167148 -47.27702)
		(end 119.167148 -48.74768)
		(width 0.0889)
		(layer "In4.Cu")
		(net "M_J_DQ<47>")
	)
	(segment
		(start 131.227576 -16.890746)
		(end 131.430776 -17.093946)
		(width 0.14224)
		(layer "In4.Cu")
		(net "M_J_DQ<47>")
	)
	(segment
		(start 131.385564 -28.136596)
		(end 131.163568 -28.358592)
		(width 0.14224)
		(layer "In4.Cu")
		(net "M_J_DQ<47>")
	)
	(segment
		(start 131.163568 -28.358592)
		(end 131.163568 -28.7782)
		(width 0.14224)
		(layer "In4.Cu")
		(net "M_J_DQ<47>")
	)
	(segment
		(start 115.583462 -60.646818)
		(end 115.577112 -60.657486)
		(width 0.0889)
		(layer "In4.Cu")
		(net "M_J_DQ<47>")
	)
	(segment
		(start 130.84937 -3.076956)
		(end 130.363976 -3.56235)
		(width 0.14224)
		(layer "In4.Cu")
		(net "M_J_DQ<47>")
	)
	(segment
		(start 131.202176 -12.170156)
		(end 131.405376 -12.373356)
		(width 0.14224)
		(layer "In4.Cu")
		(net "M_J_DQ<47>")
	)
	(segment
		(start 115.560348 -60.68695)
		(end 115.065302 -61.352938)
		(width 0.0889)
		(layer "In4.Cu")
		(net "M_J_DQ<47>")
	)
	(segment
		(start 115.583462 -56.684418)
		(end 115.577112 -56.695086)
		(width 0.0889)
		(layer "In4.Cu")
		(net "M_J_DQ<47>")
	)
	(segment
		(start 131.202176 -21.771356)
		(end 131.405376 -21.974556)
		(width 0.14224)
		(layer "In4.Cu")
		(net "M_J_DQ<47>")
	)
	(segment
		(start 131.202176 -8.978138)
		(end 131.202176 -12.170156)
		(width 0.14224)
		(layer "In4.Cu")
		(net "M_J_DQ<47>")
	)
	(segment
		(start 131.405376 -13.516356)
		(end 131.227576 -13.694156)
		(width 0.14224)
		(layer "In4.Cu")
		(net "M_J_DQ<47>")
	)
	(segment
		(start 131.417568 -31.071312)
		(end 119.350536 -43.138344)
		(width 0.14224)
		(layer "In4.Cu")
		(net "M_J_DQ<47>")
	)
	(segment
		(start 115.577112 -59.666886)
		(end 115.572286 -59.675522)
		(width 0.0889)
		(layer "In4.Cu")
		(net "M_J_DQ<47>")
	)
	(segment
		(start 131.417568 -29.0322)
		(end 131.417568 -31.071312)
		(width 0.14224)
		(layer "In4.Cu")
		(net "M_J_DQ<47>")
	)
	(segment
		(start 115.583462 -54.703218)
		(end 115.577112 -54.713886)
		(width 0.0889)
		(layer "In4.Cu")
		(net "M_J_DQ<47>")
	)
	(segment
		(start 115.577112 -57.685686)
		(end 115.572286 -57.694322)
		(width 0.0889)
		(layer "In4.Cu")
		(net "M_J_DQ<47>")
	)
	(segment
		(start 115.577112 -56.695086)
		(end 115.572286 -56.703722)
		(width 0.0889)
		(layer "In4.Cu")
		(net "M_J_DQ<47>")
	)
	(segment
		(start 119.350536 -47.093632)
		(end 119.167148 -47.27702)
		(width 0.0889)
		(layer "In4.Cu")
		(net "M_J_DQ<47>")
	)
	(segment
		(start 115.577112 -59.076336)
		(end 115.583462 -59.087004)
		(width 0.0889)
		(layer "In4.Cu")
		(net "M_J_DQ<47>")
	)
	(segment
		(start 119.167148 -48.74768)
		(end 117.988588 -49.92624)
		(width 0.0889)
		(layer "In4.Cu")
		(net "M_J_DQ<47>")
	)
	(segment
		(start 115.577112 -60.657486)
		(end 115.560348 -60.68695)
		(width 0.0889)
		(layer "In4.Cu")
		(net "M_J_DQ<47>")
	)
	(segment
		(start 131.405376 -21.974556)
		(end 131.405376 -23.117556)
		(width 0.14224)
		(layer "In4.Cu")
		(net "M_J_DQ<47>")
	)
	(segment
		(start 131.385564 -26.993596)
		(end 131.385564 -28.136596)
		(width 0.14224)
		(layer "In4.Cu")
		(net "M_J_DQ<47>")
	)
	(segment
		(start 131.430776 -17.093946)
		(end 131.430776 -18.299938)
		(width 0.14224)
		(layer "In4.Cu")
		(net "M_J_DQ<47>")
	)
	(segment
		(start 115.898168 -53.162454)
		(end 115.572286 -53.731922)
		(width 0.0889)
		(layer "In4.Cu")
		(net "M_J_DQ<47>")
	)
	(segment
		(start 131.151376 -7.213346)
		(end 131.430776 -7.492746)
		(width 0.14224)
		(layer "In4.Cu")
		(net "M_J_DQ<47>")
	)
	(segment
		(start 131.430776 -7.492746)
		(end 131.430776 -8.749538)
		(width 0.14224)
		(layer "In4.Cu")
		(net "M_J_DQ<47>")
	)
	(segment
		(start 131.405376 -12.373356)
		(end 131.405376 -13.516356)
		(width 0.14224)
		(layer "In4.Cu")
		(net "M_J_DQ<47>")
	)
	(segment
		(start 131.202176 -18.528538)
		(end 131.202176 -21.771356)
		(width 0.14224)
		(layer "In4.Cu")
		(net "M_J_DQ<47>")
	)
	(segment
		(start 131.430776 -8.749538)
		(end 131.202176 -8.978138)
		(width 0.14224)
		(layer "In4.Cu")
		(net "M_J_DQ<47>")
	)
	(segment
		(start 131.430776 -18.299938)
		(end 131.202176 -18.528538)
		(width 0.14224)
		(layer "In4.Cu")
		(net "M_J_DQ<47>")
	)
	(segment
		(start 115.583462 -55.693818)
		(end 115.577112 -55.704486)
		(width 0.0889)
		(layer "In4.Cu")
		(net "M_J_DQ<47>")
	)
	(segment
		(start 130.363976 -3.56235)
		(end 130.363976 -3.985768)
		(width 0.14224)
		(layer "In4.Cu")
		(net "M_J_DQ<47>")
	)
	(segment
		(start 117.988588 -49.92624)
		(end 117.988588 -50.63744)
		(width 0.0889)
		(layer "In4.Cu")
		(net "M_J_DQ<47>")
	)
	(segment
		(start 131.163568 -28.7782)
		(end 131.417568 -29.0322)
		(width 0.14224)
		(layer "In4.Cu")
		(net "M_J_DQ<47>")
	)
	(segment
		(start 131.405376 -23.117556)
		(end 131.163568 -23.359364)
		(width 0.14224)
		(layer "In4.Cu")
		(net "M_J_DQ<47>")
	)
	(segment
		(start 115.577112 -55.704486)
		(end 115.572286 -55.713122)
		(width 0.0889)
		(layer "In4.Cu")
		(net "M_J_DQ<47>")
	)
	(segment
		(start 131.163568 -26.7716)
		(end 131.385564 -26.993596)
		(width 0.14224)
		(layer "In4.Cu")
		(net "M_J_DQ<47>")
	)
	(segment
		(start 115.583462 -57.675018)
		(end 115.577112 -57.685686)
		(width 0.0889)
		(layer "In4.Cu")
		(net "M_J_DQ<47>")
	)
	(segment
		(start 119.350536 -43.138344)
		(end 119.350536 -47.093632)
		(width 0.14224)
		(layer "In4.Cu")
		(net "M_J_DQ<47>")
	)
	(segment
		(start 131.163568 -23.359364)
		(end 131.163568 -26.7716)
		(width 0.14224)
		(layer "In4.Cu")
		(net "M_J_DQ<47>")
	)
	(segment
		(start 131.151376 -4.773168)
		(end 131.151376 -7.213346)
		(width 0.14224)
		(layer "In4.Cu")
		(net "M_J_DQ<47>")
	)
	(segment
		(start 115.577112 -54.713886)
		(end 115.572286 -54.722522)
		(width 0.0889)
		(layer "In4.Cu")
		(net "M_J_DQ<47>")
	)
	(arc
		(start 115.572286 -55.713122)
		(mid 115.523531 -55.909474)
		(end 115.577112 -56.104536)
		(width 0.0889)
		(layer "In4.Cu")
		(net "M_J_DQ<47>")
	)
	(arc
		(start 115.577112 -58.67654)
		(mid 115.523613 -58.876438)
		(end 115.577112 -59.076336)
		(width 0.0889)
		(layer "In4.Cu")
		(net "M_J_DQ<47>")
	)
	(arc
		(start 115.577112 -54.123336)
		(mid 115.656334 -54.412454)
		(end 115.583462 -54.703218)
		(width 0.0889)
		(layer "In4.Cu")
		(net "M_J_DQ<47>")
	)
	(arc
		(start 115.583462 -59.087004)
		(mid 115.65626 -59.377767)
		(end 115.577112 -59.666886)
		(width 0.0889)
		(layer "In4.Cu")
		(net "M_J_DQ<47>")
	)
	(arc
		(start 115.572286 -53.731922)
		(mid 115.523531 -53.928274)
		(end 115.577112 -54.123336)
		(width 0.0889)
		(layer "In4.Cu")
		(net "M_J_DQ<47>")
	)
	(arc
		(start 115.577112 -55.113936)
		(mid 115.656334 -55.403054)
		(end 115.583462 -55.693818)
		(width 0.0889)
		(layer "In4.Cu")
		(net "M_J_DQ<47>")
	)
	(arc
		(start 115.572286 -59.675522)
		(mid 115.523531 -59.871874)
		(end 115.577112 -60.066936)
		(width 0.0889)
		(layer "In4.Cu")
		(net "M_J_DQ<47>")
	)
	(arc
		(start 115.577112 -60.066936)
		(mid 115.656334 -60.356054)
		(end 115.583462 -60.646818)
		(width 0.0889)
		(layer "In4.Cu")
		(net "M_J_DQ<47>")
	)
	(arc
		(start 115.577112 -58.085736)
		(mid 115.656243 -58.381138)
		(end 115.577112 -58.67654)
		(width 0.0889)
		(layer "In4.Cu")
		(net "M_J_DQ<47>")
	)
	(arc
		(start 115.572286 -54.722522)
		(mid 115.523531 -54.918874)
		(end 115.577112 -55.113936)
		(width 0.0889)
		(layer "In4.Cu")
		(net "M_J_DQ<47>")
	)
	(arc
		(start 115.577112 -56.104536)
		(mid 115.656334 -56.393654)
		(end 115.583462 -56.684418)
		(width 0.0889)
		(layer "In4.Cu")
		(net "M_J_DQ<47>")
	)
	(arc
		(start 115.572286 -56.703722)
		(mid 115.523531 -56.900074)
		(end 115.577112 -57.095136)
		(width 0.0889)
		(layer "In4.Cu")
		(net "M_J_DQ<47>")
	)
	(arc
		(start 115.577112 -57.095136)
		(mid 115.656334 -57.384254)
		(end 115.583462 -57.675018)
		(width 0.0889)
		(layer "In4.Cu")
		(net "M_J_DQ<47>")
	)
	(arc
		(start 115.572286 -57.694322)
		(mid 115.523531 -57.890674)
		(end 115.577112 -58.085736)
		(width 0.0889)
		(layer "In4.Cu")
		(net "M_J_DQ<47>")
	)
	(segment
		(start 131.357624 1.0922)
		(end 130.900424 1.5494)
		(width 0.14224)
		(layer "In11.Cu")
		(net "M_J_DQ<47>")
	)
	(segment
		(start 130.84937 -3.076956)
		(end 131.202176 -2.72415)
		(width 0.14224)
		(layer "In11.Cu")
		(net "M_J_DQ<47>")
	)
	(segment
		(start 130.316224 1.8796)
		(end 130.316224 2.198116)
		(width 0.14224)
		(layer "In11.Cu")
		(net "M_J_DQ<47>")
	)
	(segment
		(start 130.646424 1.5494)
		(end 130.316224 1.8796)
		(width 0.14224)
		(layer "In11.Cu")
		(net "M_J_DQ<47>")
	)
	(segment
		(start 131.202176 0.581152)
		(end 131.357624 0.7366)
		(width 0.14224)
		(layer "In11.Cu")
		(net "M_J_DQ<47>")
	)
	(segment
		(start 130.900424 1.5494)
		(end 130.646424 1.5494)
		(width 0.14224)
		(layer "In11.Cu")
		(net "M_J_DQ<47>")
	)
	(segment
		(start 130.316224 2.198116)
		(end 129.999486 2.514854)
		(width 0.14224)
		(layer "In11.Cu")
		(net "M_J_DQ<47>")
	)
	(segment
		(start 131.202176 -2.72415)
		(end 131.202176 0.581152)
		(width 0.14224)
		(layer "In11.Cu")
		(net "M_J_DQ<47>")
	)
	(segment
		(start 131.357624 0.7366)
		(end 131.357624 1.0922)
		(width 0.14224)
		(layer "In11.Cu")
		(net "M_J_DQ<47>")
	)
	(segment
		(start 115.636802 -59.371484)
		(end 115.065302 -59.371484)
		(width 0.0889)
		(layer "F.Cu")
		(net "M_J_DQ<46>")
	)
	(segment
		(start 130.849624 0.635)
		(end 130.849624 0.939546)
		(width 0.1651)
		(layer "F.Cu")
		(net "M_J_DQ<46>")
	)
	(segment
		(start 130.981704 0.28448)
		(end 130.981704 0.50292)
		(width 0.1651)
		(layer "F.Cu")
		(net "M_J_DQ<46>")
	)
	(segment
		(start 130.981704 0.50292)
		(end 130.849624 0.635)
		(width 0.1651)
		(layer "F.Cu")
		(net "M_J_DQ<46>")
	)
	(segment
		(start 130.84937 -0.821182)
		(end 130.849624 -0.820928)
		(width 0.1651)
		(layer "F.Cu")
		(net "M_J_DQ<46>")
	)
	(segment
		(start 130.849624 0.1524)
		(end 130.981704 0.28448)
		(width 0.1651)
		(layer "F.Cu")
		(net "M_J_DQ<46>")
	)
	(segment
		(start 130.849624 0.939546)
		(end 130.84937 0.9398)
		(width 0.1651)
		(layer "F.Cu")
		(net "M_J_DQ<46>")
	)
	(segment
		(start 130.849624 -0.820928)
		(end 130.849624 0.1524)
		(width 0.1651)
		(layer "F.Cu")
		(net "M_J_DQ<46>")
	)
	(via
		(at 130.84937 0.9398)
		(size 0.508)
		(drill 0.254)
		(layers "F.Cu" "B.Cu")
		(net "M_J_DQ<46>")
	)
	(via
		(at 129.999486 -4.357878)
		(size 0.508)
		(drill 0.254)
		(layers "F.Cu" "B.Cu")
		(net "M_J_DQ<46>")
	)
	(via
		(at 115.065302 -59.371484)
		(size 0.508)
		(drill 0.254)
		(layers "F.Cu" "B.Cu")
		(net "M_J_DQ<46>")
	)
	(segment
		(start 129.999486 -5.621782)
		(end 129.999486 -4.357878)
		(width 0.1651)
		(layer "B.Cu")
		(net "M_J_DQ<46>")
	)
	(segment
		(start 130.363976 -21.974556)
		(end 130.363976 -23.168356)
		(width 0.14224)
		(layer "In4.Cu")
		(net "M_J_DQ<46>")
	)
	(segment
		(start 129.969768 -31.0134)
		(end 130.172968 -31.2166)
		(width 0.14224)
		(layer "In4.Cu")
		(net "M_J_DQ<46>")
	)
	(segment
		(start 130.223768 -10.864342)
		(end 130.223768 -11.333734)
		(width 0.14224)
		(layer "In4.Cu")
		(net "M_J_DQ<46>")
	)
	(segment
		(start 115.416838 -57.5818)
		(end 115.412012 -57.590436)
		(width 0.0889)
		(layer "In4.Cu")
		(net "M_J_DQ<46>")
	)
	(segment
		(start 129.999486 -4.357878)
		(end 129.999486 -4.576318)
		(width 0.14224)
		(layer "In4.Cu")
		(net "M_J_DQ<46>")
	)
	(segment
		(start 118.976648 -47.29988)
		(end 118.976648 -48.668432)
		(width 0.0889)
		(layer "In4.Cu")
		(net "M_J_DQ<46>")
	)
	(segment
		(start 130.528568 -28.2956)
		(end 130.528568 -28.7274)
		(width 0.14224)
		(layer "In4.Cu")
		(net "M_J_DQ<46>")
	)
	(segment
		(start 130.249168 -20.544536)
		(end 130.567176 -20.862544)
		(width 0.14224)
		(layer "In4.Cu")
		(net "M_J_DQ<46>")
	)
	(segment
		(start 130.363976 -23.168356)
		(end 130.528568 -23.332948)
		(width 0.14224)
		(layer "In4.Cu")
		(net "M_J_DQ<46>")
	)
	(segment
		(start 130.223768 -11.333734)
		(end 130.567176 -11.677142)
		(width 0.14224)
		(layer "In4.Cu")
		(net "M_J_DQ<46>")
	)
	(segment
		(start 130.567176 -21.771356)
		(end 130.363976 -21.974556)
		(width 0.14224)
		(layer "In4.Cu")
		(net "M_J_DQ<46>")
	)
	(segment
		(start 130.192272 -29.703776)
		(end 130.792728 -29.703776)
		(width 0.14224)
		(layer "In4.Cu")
		(net "M_J_DQ<46>")
	)
	(segment
		(start 130.172968 -30.516576)
		(end 129.969768 -30.719776)
		(width 0.14224)
		(layer "In4.Cu")
		(net "M_J_DQ<46>")
	)
	(segment
		(start 130.249168 -26.9494)
		(end 130.249168 -28.0162)
		(width 0.14224)
		(layer "In4.Cu")
		(net "M_J_DQ<46>")
	)
	(segment
		(start 117.780308 -49.864772)
		(end 117.780308 -50.527966)
		(width 0.0889)
		(layer "In4.Cu")
		(net "M_J_DQ<46>")
	)
	(segment
		(start 130.465576 -13.668756)
		(end 130.465576 -14.997938)
		(width 0.14224)
		(layer "In4.Cu")
		(net "M_J_DQ<46>")
	)
	(segment
		(start 130.363976 -8.826754)
		(end 130.567176 -9.029954)
		(width 0.14224)
		(layer "In4.Cu")
		(net "M_J_DQ<46>")
	)
	(segment
		(start 130.00482 -29.251148)
		(end 130.00482 -29.516324)
		(width 0.14224)
		(layer "In4.Cu")
		(net "M_J_DQ<46>")
	)
	(segment
		(start 130.567176 -20.862544)
		(end 130.567176 -21.771356)
		(width 0.14224)
		(layer "In4.Cu")
		(net "M_J_DQ<46>")
	)
	(segment
		(start 130.934968 -29.846016)
		(end 130.934968 -30.374336)
		(width 0.14224)
		(layer "In4.Cu")
		(net "M_J_DQ<46>")
	)
	(segment
		(start 118.976648 -48.668432)
		(end 117.780308 -49.864772)
		(width 0.0889)
		(layer "In4.Cu")
		(net "M_J_DQ<46>")
	)
	(segment
		(start 130.567176 -18.605754)
		(end 130.567176 -19.731736)
		(width 0.14224)
		(layer "In4.Cu")
		(net "M_J_DQ<46>")
	)
	(segment
		(start 130.567176 -19.731736)
		(end 130.249168 -20.049744)
		(width 0.14224)
		(layer "In4.Cu")
		(net "M_J_DQ<46>")
	)
	(segment
		(start 130.172968 -15.810738)
		(end 130.465576 -16.103346)
		(width 0.14224)
		(layer "In4.Cu")
		(net "M_J_DQ<46>")
	)
	(segment
		(start 130.249168 -28.0162)
		(end 130.528568 -28.2956)
		(width 0.14224)
		(layer "In4.Cu")
		(net "M_J_DQ<46>")
	)
	(segment
		(start 130.363976 -13.567156)
		(end 130.465576 -13.668756)
		(width 0.14224)
		(layer "In4.Cu")
		(net "M_J_DQ<46>")
	)
	(segment
		(start 115.412012 -55.609236)
		(end 115.405662 -55.619904)
		(width 0.0889)
		(layer "In4.Cu")
		(net "M_J_DQ<46>")
	)
	(segment
		(start 130.363976 -18.402554)
		(end 130.567176 -18.605754)
		(width 0.14224)
		(layer "In4.Cu")
		(net "M_J_DQ<46>")
	)
	(segment
		(start 130.567176 -11.677142)
		(end 130.567176 -12.170156)
		(width 0.14224)
		(layer "In4.Cu")
		(net "M_J_DQ<46>")
	)
	(segment
		(start 130.172968 -31.2166)
		(end 130.172968 -31.417768)
		(width 0.14224)
		(layer "In4.Cu")
		(net "M_J_DQ<46>")
	)
	(segment
		(start 115.416838 -55.6006)
		(end 115.412012 -55.609236)
		(width 0.0889)
		(layer "In4.Cu")
		(net "M_J_DQ<46>")
	)
	(segment
		(start 130.528568 -28.7274)
		(end 130.00482 -29.251148)
		(width 0.14224)
		(layer "In4.Cu")
		(net "M_J_DQ<46>")
	)
	(segment
		(start 115.687094 -53.125624)
		(end 115.405662 -53.638704)
		(width 0.0889)
		(layer "In4.Cu")
		(net "M_J_DQ<46>")
	)
	(segment
		(start 118.715536 -47.038768)
		(end 118.976648 -47.29988)
		(width 0.0889)
		(layer "In4.Cu")
		(net "M_J_DQ<46>")
	)
	(segment
		(start 115.412012 -56.599836)
		(end 115.405662 -56.610504)
		(width 0.0889)
		(layer "In4.Cu")
		(net "M_J_DQ<46>")
	)
	(segment
		(start 130.465576 -16.890746)
		(end 130.363976 -16.992346)
		(width 0.14224)
		(layer "In4.Cu")
		(net "M_J_DQ<46>")
	)
	(segment
		(start 130.792728 -29.703776)
		(end 130.934968 -29.846016)
		(width 0.14224)
		(layer "In4.Cu")
		(net "M_J_DQ<46>")
	)
	(segment
		(start 115.416838 -58.5724)
		(end 115.395502 -58.609484)
		(width 0.0889)
		(layer "In4.Cu")
		(net "M_J_DQ<46>")
	)
	(segment
		(start 130.528568 -26.67)
		(end 130.249168 -26.9494)
		(width 0.14224)
		(layer "In4.Cu")
		(net "M_J_DQ<46>")
	)
	(segment
		(start 130.172968 -31.417768)
		(end 118.715536 -42.8752)
		(width 0.14224)
		(layer "In4.Cu")
		(net "M_J_DQ<46>")
	)
	(segment
		(start 130.528568 -23.332948)
		(end 130.528568 -26.67)
		(width 0.14224)
		(layer "In4.Cu")
		(net "M_J_DQ<46>")
	)
	(segment
		(start 115.687094 -52.62118)
		(end 115.687094 -53.125624)
		(width 0.0889)
		(layer "In4.Cu")
		(net "M_J_DQ<46>")
	)
	(segment
		(start 130.567176 -12.170156)
		(end 130.363976 -12.373356)
		(width 0.14224)
		(layer "In4.Cu")
		(net "M_J_DQ<46>")
	)
	(segment
		(start 130.516376 -7.238746)
		(end 130.363976 -7.391146)
		(width 0.14224)
		(layer "In4.Cu")
		(net "M_J_DQ<46>")
	)
	(segment
		(start 115.412012 -54.618636)
		(end 115.405662 -54.629304)
		(width 0.0889)
		(layer "In4.Cu")
		(net "M_J_DQ<46>")
	)
	(segment
		(start 129.969768 -30.719776)
		(end 129.969768 -31.0134)
		(width 0.14224)
		(layer "In4.Cu")
		(net "M_J_DQ<46>")
	)
	(segment
		(start 130.249168 -20.049744)
		(end 130.249168 -20.544536)
		(width 0.14224)
		(layer "In4.Cu")
		(net "M_J_DQ<46>")
	)
	(segment
		(start 130.00482 -29.516324)
		(end 130.192272 -29.703776)
		(width 0.14224)
		(layer "In4.Cu")
		(net "M_J_DQ<46>")
	)
	(segment
		(start 130.465576 -16.103346)
		(end 130.465576 -16.890746)
		(width 0.14224)
		(layer "In4.Cu")
		(net "M_J_DQ<46>")
	)
	(segment
		(start 130.172968 -15.290546)
		(end 130.172968 -15.810738)
		(width 0.14224)
		(layer "In4.Cu")
		(net "M_J_DQ<46>")
	)
	(segment
		(start 118.715536 -42.8752)
		(end 118.715536 -47.038768)
		(width 0.14224)
		(layer "In4.Cu")
		(net "M_J_DQ<46>")
	)
	(segment
		(start 130.465576 -14.997938)
		(end 130.172968 -15.290546)
		(width 0.14224)
		(layer "In4.Cu")
		(net "M_J_DQ<46>")
	)
	(segment
		(start 129.999486 -4.576318)
		(end 130.516376 -5.093208)
		(width 0.14224)
		(layer "In4.Cu")
		(net "M_J_DQ<46>")
	)
	(segment
		(start 130.363976 -16.992346)
		(end 130.363976 -18.402554)
		(width 0.14224)
		(layer "In4.Cu")
		(net "M_J_DQ<46>")
	)
	(segment
		(start 130.363976 -7.391146)
		(end 130.363976 -8.826754)
		(width 0.14224)
		(layer "In4.Cu")
		(net "M_J_DQ<46>")
	)
	(segment
		(start 130.516376 -5.093208)
		(end 130.516376 -7.238746)
		(width 0.14224)
		(layer "In4.Cu")
		(net "M_J_DQ<46>")
	)
	(segment
		(start 130.934968 -30.374336)
		(end 130.792728 -30.516576)
		(width 0.14224)
		(layer "In4.Cu")
		(net "M_J_DQ<46>")
	)
	(segment
		(start 130.792728 -30.516576)
		(end 130.172968 -30.516576)
		(width 0.14224)
		(layer "In4.Cu")
		(net "M_J_DQ<46>")
	)
	(segment
		(start 130.567176 -9.029954)
		(end 130.567176 -10.520934)
		(width 0.14224)
		(layer "In4.Cu")
		(net "M_J_DQ<46>")
	)
	(segment
		(start 115.395502 -58.609484)
		(end 115.065302 -59.371484)
		(width 0.0889)
		(layer "In4.Cu")
		(net "M_J_DQ<46>")
	)
	(segment
		(start 130.363976 -12.373356)
		(end 130.363976 -13.567156)
		(width 0.14224)
		(layer "In4.Cu")
		(net "M_J_DQ<46>")
	)
	(segment
		(start 115.412012 -57.590436)
		(end 115.405662 -57.601104)
		(width 0.0889)
		(layer "In4.Cu")
		(net "M_J_DQ<46>")
	)
	(segment
		(start 115.416838 -54.61)
		(end 115.412012 -54.618636)
		(width 0.0889)
		(layer "In4.Cu")
		(net "M_J_DQ<46>")
	)
	(segment
		(start 115.416838 -56.5912)
		(end 115.412012 -56.599836)
		(width 0.0889)
		(layer "In4.Cu")
		(net "M_J_DQ<46>")
	)
	(segment
		(start 130.567176 -10.520934)
		(end 130.223768 -10.864342)
		(width 0.14224)
		(layer "In4.Cu")
		(net "M_J_DQ<46>")
	)
	(segment
		(start 117.780308 -50.527966)
		(end 115.687094 -52.62118)
		(width 0.0889)
		(layer "In4.Cu")
		(net "M_J_DQ<46>")
	)
	(arc
		(start 115.405662 -55.619904)
		(mid 115.332864 -55.910667)
		(end 115.412012 -56.199786)
		(width 0.0889)
		(layer "In4.Cu")
		(net "M_J_DQ<46>")
	)
	(arc
		(start 115.405662 -56.610504)
		(mid 115.332864 -56.901267)
		(end 115.412012 -57.190386)
		(width 0.0889)
		(layer "In4.Cu")
		(net "M_J_DQ<46>")
	)
	(arc
		(start 115.412012 -54.218586)
		(mid 115.465482 -54.413649)
		(end 115.416838 -54.61)
		(width 0.0889)
		(layer "In4.Cu")
		(net "M_J_DQ<46>")
	)
	(arc
		(start 115.412012 -57.190386)
		(mid 115.465482 -57.385449)
		(end 115.416838 -57.5818)
		(width 0.0889)
		(layer "In4.Cu")
		(net "M_J_DQ<46>")
	)
	(arc
		(start 115.405662 -57.601104)
		(mid 115.332864 -57.891867)
		(end 115.412012 -58.180986)
		(width 0.0889)
		(layer "In4.Cu")
		(net "M_J_DQ<46>")
	)
	(arc
		(start 115.412012 -55.209186)
		(mid 115.465482 -55.404249)
		(end 115.416838 -55.6006)
		(width 0.0889)
		(layer "In4.Cu")
		(net "M_J_DQ<46>")
	)
	(arc
		(start 115.412012 -58.180986)
		(mid 115.465482 -58.376049)
		(end 115.416838 -58.5724)
		(width 0.0889)
		(layer "In4.Cu")
		(net "M_J_DQ<46>")
	)
	(arc
		(start 115.405662 -53.638704)
		(mid 115.332864 -53.929467)
		(end 115.412012 -54.218586)
		(width 0.0889)
		(layer "In4.Cu")
		(net "M_J_DQ<46>")
	)
	(arc
		(start 115.412012 -56.199786)
		(mid 115.465482 -56.394849)
		(end 115.416838 -56.5912)
		(width 0.0889)
		(layer "In4.Cu")
		(net "M_J_DQ<46>")
	)
	(arc
		(start 115.405662 -54.629304)
		(mid 115.332864 -54.920067)
		(end 115.412012 -55.209186)
		(width 0.0889)
		(layer "In4.Cu")
		(net "M_J_DQ<46>")
	)
	(segment
		(start 130.491992 -1.111504)
		(end 130.491992 -0.768096)
		(width 0.14224)
		(layer "In11.Cu")
		(net "M_J_DQ<46>")
	)
	(segment
		(start 130.110992 -1.777746)
		(end 130.110992 -1.492504)
		(width 0.14224)
		(layer "In11.Cu")
		(net "M_J_DQ<46>")
	)
	(segment
		(start 130.491992 -0.768096)
		(end 130.110992 -0.387096)
		(width 0.14224)
		(layer "In11.Cu")
		(net "M_J_DQ<46>")
	)
	(segment
		(start 129.763774 -4.122166)
		(end 129.763774 -3.327654)
		(width 0.14224)
		(layer "In11.Cu")
		(net "M_J_DQ<46>")
	)
	(segment
		(start 129.763774 -3.327654)
		(end 130.536442 -2.554986)
		(width 0.14224)
		(layer "In11.Cu")
		(net "M_J_DQ<46>")
	)
	(segment
		(start 130.474974 0.287528)
		(end 130.474974 0.565404)
		(width 0.14224)
		(layer "In11.Cu")
		(net "M_J_DQ<46>")
	)
	(segment
		(start 130.536442 -2.203196)
		(end 130.110992 -1.777746)
		(width 0.14224)
		(layer "In11.Cu")
		(net "M_J_DQ<46>")
	)
	(segment
		(start 129.999486 -4.357878)
		(end 129.763774 -4.122166)
		(width 0.14224)
		(layer "In11.Cu")
		(net "M_J_DQ<46>")
	)
	(segment
		(start 130.110992 -1.492504)
		(end 130.491992 -1.111504)
		(width 0.14224)
		(layer "In11.Cu")
		(net "M_J_DQ<46>")
	)
	(segment
		(start 130.474974 0.565404)
		(end 130.84937 0.9398)
		(width 0.14224)
		(layer "In11.Cu")
		(net "M_J_DQ<46>")
	)
	(segment
		(start 130.110992 -0.387096)
		(end 130.110992 -0.076454)
		(width 0.14224)
		(layer "In11.Cu")
		(net "M_J_DQ<46>")
	)
	(segment
		(start 130.110992 -0.076454)
		(end 130.474974 0.287528)
		(width 0.14224)
		(layer "In11.Cu")
		(net "M_J_DQ<46>")
	)
	(segment
		(start 130.536442 -2.554986)
		(end 130.536442 -2.203196)
		(width 0.14224)
		(layer "In11.Cu")
		(net "M_J_DQ<46>")
	)
	(segment
		(start 124.049536 3.778758)
		(end 124.049536 2.514854)
		(width 0.1651)
		(layer "F.Cu")
		(net "M_J_DQ<45>")
	)
	(segment
		(start 113.061242 -60.857384)
		(end 112.489742 -60.857384)
		(width 0.0889)
		(layer "F.Cu")
		(net "M_J_DQ<45>")
	)
	(via
		(at 112.489742 -60.857384)
		(size 0.508)
		(drill 0.254)
		(layers "F.Cu" "B.Cu")
		(net "M_J_DQ<45>")
	)
	(via
		(at 124.82322 -3.076956)
		(size 0.508)
		(drill 0.254)
		(layers "F.Cu" "B.Cu")
		(net "M_J_DQ<45>")
	)
	(via
		(at 124.049536 2.514854)
		(size 0.508)
		(drill 0.254)
		(layers "F.Cu" "B.Cu")
		(net "M_J_DQ<45>")
	)
	(segment
		(start 124.89942 -1.021842)
		(end 124.89942 -3.000756)
		(width 0.1651)
		(layer "B.Cu")
		(net "M_J_DQ<45>")
	)
	(segment
		(start 124.89942 -3.000756)
		(end 124.82322 -3.076956)
		(width 0.1651)
		(layer "B.Cu")
		(net "M_J_DQ<45>")
	)
	(segment
		(start 118.048278 -37.065458)
		(end 118.420134 -37.437314)
		(width 0.14224)
		(layer "In4.Cu")
		(net "M_J_DQ<45>")
	)
	(segment
		(start 125.292358 -6.719062)
		(end 125.292358 -7.323328)
		(width 0.14224)
		(layer "In4.Cu")
		(net "M_J_DQ<45>")
	)
	(segment
		(start 112.149382 -57.675018)
		(end 112.143032 -57.685686)
		(width 0.0889)
		(layer "In4.Cu")
		(net "M_J_DQ<45>")
	)
	(segment
		(start 125.296168 -26.956004)
		(end 125.296168 -28.194)
		(width 0.14224)
		(layer "In4.Cu")
		(net "M_J_DQ<45>")
	)
	(segment
		(start 125.296676 -7.327646)
		(end 125.296676 -8.902446)
		(width 0.14224)
		(layer "In4.Cu")
		(net "M_J_DQ<45>")
	)
	(segment
		(start 125.207776 -12.271756)
		(end 125.296676 -12.360656)
		(width 0.14224)
		(layer "In4.Cu")
		(net "M_J_DQ<45>")
	)
	(segment
		(start 125.233176 -16.865346)
		(end 125.296676 -16.928846)
		(width 0.14224)
		(layer "In4.Cu")
		(net "M_J_DQ<45>")
	)
	(segment
		(start 112.011968 -52.898802)
		(end 112.013238 -52.900072)
		(width 0.0889)
		(layer "In4.Cu")
		(net "M_J_DQ<45>")
	)
	(segment
		(start 125.254258 -26.914094)
		(end 125.296168 -26.956004)
		(width 0.14224)
		(layer "In4.Cu")
		(net "M_J_DQ<45>")
	)
	(segment
		(start 113.688368 -50.393854)
		(end 112.011968 -52.070254)
		(width 0.0889)
		(layer "In4.Cu")
		(net "M_J_DQ<45>")
	)
	(segment
		(start 112.143032 -57.685686)
		(end 112.138206 -57.694322)
		(width 0.0889)
		(layer "In4.Cu")
		(net "M_J_DQ<45>")
	)
	(segment
		(start 112.836452 -60.066936)
		(end 112.819688 -60.095638)
		(width 0.0889)
		(layer "In4.Cu")
		(net "M_J_DQ<45>")
	)
	(segment
		(start 118.048278 -36.86429)
		(end 118.048278 -37.065458)
		(width 0.14224)
		(layer "In4.Cu")
		(net "M_J_DQ<45>")
	)
	(segment
		(start 125.233176 -13.681456)
		(end 125.233176 -16.865346)
		(width 0.14224)
		(layer "In4.Cu")
		(net "M_J_DQ<45>")
	)
	(segment
		(start 125.28042 -23.235412)
		(end 125.254258 -23.261574)
		(width 0.14224)
		(layer "In4.Cu")
		(net "M_J_DQ<45>")
	)
	(segment
		(start 118.420134 -37.724842)
		(end 114.856768 -41.288208)
		(width 0.14224)
		(layer "In4.Cu")
		(net "M_J_DQ<45>")
	)
	(segment
		(start 125.207776 -18.592546)
		(end 125.207776 -21.872956)
		(width 0.14224)
		(layer "In4.Cu")
		(net "M_J_DQ<45>")
	)
	(segment
		(start 118.62308 -36.490656)
		(end 118.421912 -36.490656)
		(width 0.14224)
		(layer "In4.Cu")
		(net "M_J_DQ<45>")
	)
	(segment
		(start 125.296676 -13.617956)
		(end 125.233176 -13.681456)
		(width 0.14224)
		(layer "In4.Cu")
		(net "M_J_DQ<45>")
	)
	(segment
		(start 119.589296 -36.55568)
		(end 119.282464 -36.862512)
		(width 0.14224)
		(layer "In4.Cu")
		(net "M_J_DQ<45>")
	)
	(segment
		(start 112.143032 -59.076336)
		(end 112.154716 -59.096656)
		(width 0.0889)
		(layer "In4.Cu")
		(net "M_J_DQ<45>")
	)
	(segment
		(start 114.856768 -41.288208)
		(end 114.856768 -46.736)
		(width 0.14224)
		(layer "In4.Cu")
		(net "M_J_DQ<45>")
	)
	(segment
		(start 125.219968 -28.965144)
		(end 118.971568 -35.213544)
		(width 0.14224)
		(layer "In4.Cu")
		(net "M_J_DQ<45>")
	)
	(segment
		(start 112.011968 -52.070254)
		(end 112.011968 -52.898802)
		(width 0.0889)
		(layer "In4.Cu")
		(net "M_J_DQ<45>")
	)
	(segment
		(start 124.82322 -3.076956)
		(end 124.318776 -3.5814)
		(width 0.14224)
		(layer "In4.Cu")
		(net "M_J_DQ<45>")
	)
	(segment
		(start 124.318776 -3.5814)
		(end 124.318776 -3.940556)
		(width 0.14224)
		(layer "In4.Cu")
		(net "M_J_DQ<45>")
	)
	(segment
		(start 112.149382 -55.693818)
		(end 112.143032 -55.704486)
		(width 0.0889)
		(layer "In4.Cu")
		(net "M_J_DQ<45>")
	)
	(segment
		(start 124.762768 -6.189472)
		(end 125.292358 -6.719062)
		(width 0.14224)
		(layer "In4.Cu")
		(net "M_J_DQ<45>")
	)
	(segment
		(start 112.143032 -54.713886)
		(end 112.138206 -54.722522)
		(width 0.0889)
		(layer "In4.Cu")
		(net "M_J_DQ<45>")
	)
	(segment
		(start 113.688368 -49.375568)
		(end 113.688368 -50.393854)
		(width 0.0889)
		(layer "In4.Cu")
		(net "M_J_DQ<45>")
	)
	(segment
		(start 119.282464 -36.862512)
		(end 118.994936 -36.862512)
		(width 0.14224)
		(layer "In4.Cu")
		(net "M_J_DQ<45>")
	)
	(segment
		(start 114.679984 -46.912784)
		(end 114.679984 -48.383952)
		(width 0.0889)
		(layer "In4.Cu")
		(net "M_J_DQ<45>")
	)
	(segment
		(start 118.971568 -35.594544)
		(end 119.589296 -36.212272)
		(width 0.14224)
		(layer "In4.Cu")
		(net "M_J_DQ<45>")
	)
	(segment
		(start 118.994936 -36.862512)
		(end 118.62308 -36.490656)
		(width 0.14224)
		(layer "In4.Cu")
		(net "M_J_DQ<45>")
	)
	(segment
		(start 112.154716 -59.096656)
		(end 112.297718 -59.28868)
		(width 0.0889)
		(layer "In4.Cu")
		(net "M_J_DQ<45>")
	)
	(segment
		(start 125.207776 -21.872956)
		(end 125.28042 -21.9456)
		(width 0.14224)
		(layer "In4.Cu")
		(net "M_J_DQ<45>")
	)
	(segment
		(start 112.149382 -56.684418)
		(end 112.143032 -56.695086)
		(width 0.0889)
		(layer "In4.Cu")
		(net "M_J_DQ<45>")
	)
	(segment
		(start 112.746536 -59.498484)
		(end 112.763808 -59.515756)
		(width 0.0889)
		(layer "In4.Cu")
		(net "M_J_DQ<45>")
	)
	(segment
		(start 125.296168 -28.194)
		(end 125.219968 -28.2702)
		(width 0.14224)
		(layer "In4.Cu")
		(net "M_J_DQ<45>")
	)
	(segment
		(start 119.589296 -36.212272)
		(end 119.589296 -36.55568)
		(width 0.14224)
		(layer "In4.Cu")
		(net "M_J_DQ<45>")
	)
	(segment
		(start 124.762768 -4.384548)
		(end 124.762768 -6.189472)
		(width 0.14224)
		(layer "In4.Cu")
		(net "M_J_DQ<45>")
	)
	(segment
		(start 114.679984 -48.383952)
		(end 113.688368 -49.375568)
		(width 0.0889)
		(layer "In4.Cu")
		(net "M_J_DQ<45>")
	)
	(segment
		(start 118.971568 -35.213544)
		(end 118.971568 -35.594544)
		(width 0.14224)
		(layer "In4.Cu")
		(net "M_J_DQ<45>")
	)
	(segment
		(start 125.296676 -18.503646)
		(end 125.207776 -18.592546)
		(width 0.14224)
		(layer "In4.Cu")
		(net "M_J_DQ<45>")
	)
	(segment
		(start 125.296676 -8.902446)
		(end 125.207776 -8.991346)
		(width 0.14224)
		(layer "In4.Cu")
		(net "M_J_DQ<45>")
	)
	(segment
		(start 125.28042 -21.9456)
		(end 125.28042 -23.235412)
		(width 0.14224)
		(layer "In4.Cu")
		(net "M_J_DQ<45>")
	)
	(segment
		(start 125.207776 -8.991346)
		(end 125.207776 -12.271756)
		(width 0.14224)
		(layer "In4.Cu")
		(net "M_J_DQ<45>")
	)
	(segment
		(start 125.219968 -28.2702)
		(end 125.219968 -28.965144)
		(width 0.14224)
		(layer "In4.Cu")
		(net "M_J_DQ<45>")
	)
	(segment
		(start 112.143032 -55.704486)
		(end 112.138206 -55.713122)
		(width 0.0889)
		(layer "In4.Cu")
		(net "M_J_DQ<45>")
	)
	(segment
		(start 112.819688 -60.095638)
		(end 112.489742 -60.857384)
		(width 0.0889)
		(layer "In4.Cu")
		(net "M_J_DQ<45>")
	)
	(segment
		(start 118.421912 -36.490656)
		(end 118.048278 -36.86429)
		(width 0.14224)
		(layer "In4.Cu")
		(net "M_J_DQ<45>")
	)
	(segment
		(start 125.296676 -12.360656)
		(end 125.296676 -13.617956)
		(width 0.14224)
		(layer "In4.Cu")
		(net "M_J_DQ<45>")
	)
	(segment
		(start 125.254258 -23.261574)
		(end 125.254258 -26.914094)
		(width 0.14224)
		(layer "In4.Cu")
		(net "M_J_DQ<45>")
	)
	(segment
		(start 114.856768 -46.736)
		(end 114.679984 -46.912784)
		(width 0.0889)
		(layer "In4.Cu")
		(net "M_J_DQ<45>")
	)
	(segment
		(start 112.138206 -54.1147)
		(end 112.143032 -54.123336)
		(width 0.0889)
		(layer "In4.Cu")
		(net "M_J_DQ<45>")
	)
	(segment
		(start 112.143032 -54.123336)
		(end 112.149382 -54.134004)
		(width 0.0889)
		(layer "In4.Cu")
		(net "M_J_DQ<45>")
	)
	(segment
		(start 125.296676 -16.928846)
		(end 125.296676 -18.503646)
		(width 0.14224)
		(layer "In4.Cu")
		(net "M_J_DQ<45>")
	)
	(segment
		(start 112.143032 -56.695086)
		(end 112.138206 -56.703722)
		(width 0.0889)
		(layer "In4.Cu")
		(net "M_J_DQ<45>")
	)
	(segment
		(start 125.292358 -7.323328)
		(end 125.296676 -7.327646)
		(width 0.14224)
		(layer "In4.Cu")
		(net "M_J_DQ<45>")
	)
	(segment
		(start 124.318776 -3.940556)
		(end 124.762768 -4.384548)
		(width 0.14224)
		(layer "In4.Cu")
		(net "M_J_DQ<45>")
	)
	(segment
		(start 118.420134 -37.437314)
		(end 118.420134 -37.724842)
		(width 0.14224)
		(layer "In4.Cu")
		(net "M_J_DQ<45>")
	)
	(segment
		(start 112.013238 -52.900072)
		(end 112.149382 -53.143404)
		(width 0.0889)
		(layer "In4.Cu")
		(net "M_J_DQ<45>")
	)
	(arc
		(start 112.149382 -53.143404)
		(mid 112.22218 -53.434167)
		(end 112.143032 -53.723286)
		(width 0.0889)
		(layer "In4.Cu")
		(net "M_J_DQ<45>")
	)
	(arc
		(start 112.138206 -56.703722)
		(mid 112.089451 -56.900074)
		(end 112.143032 -57.095136)
		(width 0.0889)
		(layer "In4.Cu")
		(net "M_J_DQ<45>")
	)
	(arc
		(start 112.297718 -59.28868)
		(mid 112.41709 -59.388877)
		(end 112.568736 -59.424824)
		(width 0.0889)
		(layer "In4.Cu")
		(net "M_J_DQ<45>")
	)
	(arc
		(start 112.138206 -54.722522)
		(mid 112.089451 -54.918874)
		(end 112.143032 -55.113936)
		(width 0.0889)
		(layer "In4.Cu")
		(net "M_J_DQ<45>")
	)
	(arc
		(start 112.143032 -56.104536)
		(mid 112.222254 -56.393654)
		(end 112.149382 -56.684418)
		(width 0.0889)
		(layer "In4.Cu")
		(net "M_J_DQ<45>")
	)
	(arc
		(start 112.143032 -53.723286)
		(mid 112.089562 -53.918349)
		(end 112.138206 -54.1147)
		(width 0.0889)
		(layer "In4.Cu")
		(net "M_J_DQ<45>")
	)
	(arc
		(start 112.138206 -55.713122)
		(mid 112.089451 -55.909474)
		(end 112.143032 -56.104536)
		(width 0.0889)
		(layer "In4.Cu")
		(net "M_J_DQ<45>")
	)
	(arc
		(start 112.149382 -54.134004)
		(mid 112.22218 -54.424767)
		(end 112.143032 -54.713886)
		(width 0.0889)
		(layer "In4.Cu")
		(net "M_J_DQ<45>")
	)
	(arc
		(start 112.138206 -57.694322)
		(mid 112.089451 -57.890674)
		(end 112.143032 -58.085736)
		(width 0.0889)
		(layer "In4.Cu")
		(net "M_J_DQ<45>")
	)
	(arc
		(start 112.143032 -58.085736)
		(mid 112.222163 -58.381138)
		(end 112.143032 -58.67654)
		(width 0.0889)
		(layer "In4.Cu")
		(net "M_J_DQ<45>")
	)
	(arc
		(start 112.143032 -58.67654)
		(mid 112.089533 -58.876438)
		(end 112.143032 -59.076336)
		(width 0.0889)
		(layer "In4.Cu")
		(net "M_J_DQ<45>")
	)
	(arc
		(start 112.143032 -57.095136)
		(mid 112.222254 -57.384254)
		(end 112.149382 -57.675018)
		(width 0.0889)
		(layer "In4.Cu")
		(net "M_J_DQ<45>")
	)
	(arc
		(start 112.143032 -55.113936)
		(mid 112.222254 -55.403054)
		(end 112.149382 -55.693818)
		(width 0.0889)
		(layer "In4.Cu")
		(net "M_J_DQ<45>")
	)
	(arc
		(start 112.763808 -59.515756)
		(mid 112.893553 -59.779007)
		(end 112.836452 -60.066936)
		(width 0.0889)
		(layer "In4.Cu")
		(net "M_J_DQ<45>")
	)
	(arc
		(start 112.568736 -59.424824)
		(mid 112.664966 -59.443965)
		(end 112.746536 -59.498484)
		(width 0.0889)
		(layer "In4.Cu")
		(net "M_J_DQ<45>")
	)
	(segment
		(start 125.331474 0.7366)
		(end 125.331474 1.149096)
		(width 0.14224)
		(layer "In11.Cu")
		(net "M_J_DQ<45>")
	)
	(segment
		(start 124.82322 -3.076956)
		(end 125.134624 -2.765552)
		(width 0.14224)
		(layer "In11.Cu")
		(net "M_J_DQ<45>")
	)
	(segment
		(start 125.331474 1.149096)
		(end 124.93117 1.5494)
		(width 0.14224)
		(layer "In11.Cu")
		(net "M_J_DQ<45>")
	)
	(segment
		(start 124.93117 1.5494)
		(end 124.620274 1.5494)
		(width 0.14224)
		(layer "In11.Cu")
		(net "M_J_DQ<45>")
	)
	(segment
		(start 125.134624 -2.765552)
		(end 125.134624 0.53975)
		(width 0.14224)
		(layer "In11.Cu")
		(net "M_J_DQ<45>")
	)
	(segment
		(start 124.049536 2.120138)
		(end 124.049536 2.514854)
		(width 0.14224)
		(layer "In11.Cu")
		(net "M_J_DQ<45>")
	)
	(segment
		(start 125.134624 0.53975)
		(end 125.331474 0.7366)
		(width 0.14224)
		(layer "In11.Cu")
		(net "M_J_DQ<45>")
	)
	(segment
		(start 124.620274 1.5494)
		(end 124.049536 2.120138)
		(width 0.14224)
		(layer "In11.Cu")
		(net "M_J_DQ<45>")
	)
	(segment
		(start 113.061242 -59.866784)
		(end 112.489742 -59.866784)
		(width 0.0889)
		(layer "F.Cu")
		(net "M_J_DQ<44>")
	)
	(segment
		(start 124.89942 -0.821182)
		(end 124.89942 0.510032)
		(width 0.1651)
		(layer "F.Cu")
		(net "M_J_DQ<44>")
	)
	(segment
		(start 124.89942 0.510032)
		(end 124.801376 1.0414)
		(width 0.1651)
		(layer "F.Cu")
		(net "M_J_DQ<44>")
	)
	(via
		(at 124.801376 1.0414)
		(size 0.508)
		(drill 0.254)
		(layers "F.Cu" "B.Cu")
		(net "M_J_DQ<44>")
	)
	(via
		(at 112.489742 -59.866784)
		(size 0.508)
		(drill 0.254)
		(layers "F.Cu" "B.Cu")
		(net "M_J_DQ<44>")
	)
	(via
		(at 124.049536 -4.357878)
		(size 0.508)
		(drill 0.254)
		(layers "F.Cu" "B.Cu")
		(net "M_J_DQ<44>")
	)
	(segment
		(start 124.049536 -5.621782)
		(end 124.049536 -4.357878)
		(width 0.1651)
		(layer "B.Cu")
		(net "M_J_DQ<44>")
	)
	(segment
		(start 111.808768 -52.00396)
		(end 111.808768 -52.93614)
		(width 0.0889)
		(layer "In4.Cu")
		(net "M_J_DQ<44>")
	)
	(segment
		(start 113.497868 -49.29632)
		(end 113.497868 -50.31486)
		(width 0.0889)
		(layer "In4.Cu")
		(net "M_J_DQ<44>")
	)
	(segment
		(start 115.761008 -39.198296)
		(end 115.393724 -38.831012)
		(width 0.14224)
		(layer "In4.Cu")
		(net "M_J_DQ<44>")
	)
	(segment
		(start 114.221768 -46.6598)
		(end 114.457988 -46.89602)
		(width 0.0889)
		(layer "In4.Cu")
		(net "M_J_DQ<44>")
	)
	(segment
		(start 116.492528 -37.630608)
		(end 116.29136 -37.630608)
		(width 0.14224)
		(layer "In4.Cu")
		(net "M_J_DQ<44>")
	)
	(segment
		(start 124.318776 -18.313146)
		(end 124.572776 -18.567146)
		(width 0.14224)
		(layer "In4.Cu")
		(net "M_J_DQ<44>")
	)
	(segment
		(start 124.547376 -13.795756)
		(end 124.547376 -16.826738)
		(width 0.14224)
		(layer "In4.Cu")
		(net "M_J_DQ<44>")
	)
	(segment
		(start 124.584968 -23.434548)
		(end 124.584968 -26.7208)
		(width 0.14224)
		(layer "In4.Cu")
		(net "M_J_DQ<44>")
	)
	(segment
		(start 111.977932 -56.599836)
		(end 111.971582 -56.610504)
		(width 0.0889)
		(layer "In4.Cu")
		(net "M_J_DQ<44>")
	)
	(segment
		(start 111.977932 -57.590436)
		(end 111.971582 -57.601104)
		(width 0.0889)
		(layer "In4.Cu")
		(net "M_J_DQ<44>")
	)
	(segment
		(start 111.977932 -54.618636)
		(end 111.971582 -54.629304)
		(width 0.0889)
		(layer "In4.Cu")
		(net "M_J_DQ<44>")
	)
	(segment
		(start 111.971582 -59.160918)
		(end 111.977932 -59.171586)
		(width 0.0889)
		(layer "In4.Cu")
		(net "M_J_DQ<44>")
	)
	(segment
		(start 116.33581 -38.623494)
		(end 116.33581 -38.911022)
		(width 0.14224)
		(layer "In4.Cu")
		(net "M_J_DQ<44>")
	)
	(segment
		(start 124.572776 -21.695156)
		(end 124.318776 -21.949156)
		(width 0.14224)
		(layer "In4.Cu")
		(net "M_J_DQ<44>")
	)
	(segment
		(start 111.982758 -58.5724)
		(end 111.977932 -58.581036)
		(width 0.0889)
		(layer "In4.Cu")
		(net "M_J_DQ<44>")
	)
	(segment
		(start 124.318776 -7.454138)
		(end 124.318776 -8.711946)
		(width 0.14224)
		(layer "In4.Cu")
		(net "M_J_DQ<44>")
	)
	(segment
		(start 124.305568 -27.0002)
		(end 124.305568 -28.0162)
		(width 0.14224)
		(layer "In4.Cu")
		(net "M_J_DQ<44>")
	)
	(segment
		(start 124.547376 -16.826738)
		(end 124.318776 -17.055338)
		(width 0.14224)
		(layer "In4.Cu")
		(net "M_J_DQ<44>")
	)
	(segment
		(start 124.049536 -6.415024)
		(end 124.547376 -6.912864)
		(width 0.14224)
		(layer "In4.Cu")
		(net "M_J_DQ<44>")
	)
	(segment
		(start 111.977932 -59.171586)
		(end 111.994696 -59.20105)
		(width 0.0889)
		(layer "In4.Cu")
		(net "M_J_DQ<44>")
	)
	(segment
		(start 124.584968 -26.7208)
		(end 124.305568 -27.0002)
		(width 0.14224)
		(layer "In4.Cu")
		(net "M_J_DQ<44>")
	)
	(segment
		(start 116.33581 -38.911022)
		(end 116.048536 -39.198296)
		(width 0.14224)
		(layer "In4.Cu")
		(net "M_J_DQ<44>")
	)
	(segment
		(start 124.049536 -4.357878)
		(end 124.049536 -6.415024)
		(width 0.14224)
		(layer "In4.Cu")
		(net "M_J_DQ<44>")
	)
	(segment
		(start 124.318776 -8.711946)
		(end 124.572776 -8.965946)
		(width 0.14224)
		(layer "In4.Cu")
		(net "M_J_DQ<44>")
	)
	(segment
		(start 124.584968 -28.7528)
		(end 124.153168 -29.1846)
		(width 0.14224)
		(layer "In4.Cu")
		(net "M_J_DQ<44>")
	)
	(segment
		(start 117.52199 -37.724842)
		(end 117.19814 -38.048692)
		(width 0.14224)
		(layer "In4.Cu")
		(net "M_J_DQ<44>")
	)
	(segment
		(start 115.917726 -38.20541)
		(end 116.33581 -38.623494)
		(width 0.14224)
		(layer "In4.Cu")
		(net "M_J_DQ<44>")
	)
	(segment
		(start 116.888768 -36.804092)
		(end 117.52199 -37.437314)
		(width 0.14224)
		(layer "In4.Cu")
		(net "M_J_DQ<44>")
	)
	(segment
		(start 124.318776 -23.168356)
		(end 124.584968 -23.434548)
		(width 0.14224)
		(layer "In4.Cu")
		(net "M_J_DQ<44>")
	)
	(segment
		(start 124.318776 -13.567156)
		(end 124.547376 -13.795756)
		(width 0.14224)
		(layer "In4.Cu")
		(net "M_J_DQ<44>")
	)
	(segment
		(start 124.102368 -29.1846)
		(end 116.888768 -36.3982)
		(width 0.14224)
		(layer "In4.Cu")
		(net "M_J_DQ<44>")
	)
	(segment
		(start 124.305568 -28.0162)
		(end 124.584968 -28.2956)
		(width 0.14224)
		(layer "In4.Cu")
		(net "M_J_DQ<44>")
	)
	(segment
		(start 111.982758 -55.6006)
		(end 111.977932 -55.609236)
		(width 0.0889)
		(layer "In4.Cu")
		(net "M_J_DQ<44>")
	)
	(segment
		(start 114.457988 -48.3362)
		(end 113.497868 -49.29632)
		(width 0.0889)
		(layer "In4.Cu")
		(net "M_J_DQ<44>")
	)
	(segment
		(start 124.584968 -28.2956)
		(end 124.584968 -28.7528)
		(width 0.14224)
		(layer "In4.Cu")
		(net "M_J_DQ<44>")
	)
	(segment
		(start 113.497868 -50.31486)
		(end 111.808768 -52.00396)
		(width 0.0889)
		(layer "In4.Cu")
		(net "M_J_DQ<44>")
	)
	(segment
		(start 116.29136 -37.630608)
		(end 115.917726 -38.004242)
		(width 0.14224)
		(layer "In4.Cu")
		(net "M_J_DQ<44>")
	)
	(segment
		(start 116.910612 -38.048692)
		(end 116.492528 -37.630608)
		(width 0.14224)
		(layer "In4.Cu")
		(net "M_J_DQ<44>")
	)
	(segment
		(start 111.808768 -52.93614)
		(end 111.982504 -53.23586)
		(width 0.0889)
		(layer "In4.Cu")
		(net "M_J_DQ<44>")
	)
	(segment
		(start 115.186206 -39.773098)
		(end 115.186206 -40.060626)
		(width 0.14224)
		(layer "In4.Cu")
		(net "M_J_DQ<44>")
	)
	(segment
		(start 117.52199 -37.437314)
		(end 117.52199 -37.724842)
		(width 0.14224)
		(layer "In4.Cu")
		(net "M_J_DQ<44>")
	)
	(segment
		(start 116.888768 -36.3982)
		(end 116.888768 -36.804092)
		(width 0.14224)
		(layer "In4.Cu")
		(net "M_J_DQ<44>")
	)
	(segment
		(start 111.971582 -54.207918)
		(end 111.977932 -54.218586)
		(width 0.0889)
		(layer "In4.Cu")
		(net "M_J_DQ<44>")
	)
	(segment
		(start 114.818922 -39.405814)
		(end 115.186206 -39.773098)
		(width 0.14224)
		(layer "In4.Cu")
		(net "M_J_DQ<44>")
	)
	(segment
		(start 114.457988 -46.89602)
		(end 114.457988 -48.3362)
		(width 0.0889)
		(layer "In4.Cu")
		(net "M_J_DQ<44>")
	)
	(segment
		(start 115.393724 -38.831012)
		(end 115.192556 -38.831012)
		(width 0.14224)
		(layer "In4.Cu")
		(net "M_J_DQ<44>")
	)
	(segment
		(start 116.048536 -39.198296)
		(end 115.761008 -39.198296)
		(width 0.14224)
		(layer "In4.Cu")
		(net "M_J_DQ<44>")
	)
	(segment
		(start 124.572776 -8.965946)
		(end 124.572776 -12.093956)
		(width 0.14224)
		(layer "In4.Cu")
		(net "M_J_DQ<44>")
	)
	(segment
		(start 111.982758 -57.5818)
		(end 111.977932 -57.590436)
		(width 0.0889)
		(layer "In4.Cu")
		(net "M_J_DQ<44>")
	)
	(segment
		(start 111.982758 -56.5912)
		(end 111.977932 -56.599836)
		(width 0.0889)
		(layer "In4.Cu")
		(net "M_J_DQ<44>")
	)
	(segment
		(start 124.547376 -7.225538)
		(end 124.318776 -7.454138)
		(width 0.14224)
		(layer "In4.Cu")
		(net "M_J_DQ<44>")
	)
	(segment
		(start 111.977932 -54.218586)
		(end 111.982758 -54.227222)
		(width 0.0889)
		(layer "In4.Cu")
		(net "M_J_DQ<44>")
	)
	(segment
		(start 114.221768 -41.025064)
		(end 114.221768 -46.6598)
		(width 0.14224)
		(layer "In4.Cu")
		(net "M_J_DQ<44>")
	)
	(segment
		(start 114.818922 -39.204646)
		(end 114.818922 -39.405814)
		(width 0.14224)
		(layer "In4.Cu")
		(net "M_J_DQ<44>")
	)
	(segment
		(start 117.19814 -38.048692)
		(end 116.910612 -38.048692)
		(width 0.14224)
		(layer "In4.Cu")
		(net "M_J_DQ<44>")
	)
	(segment
		(start 124.547376 -6.912864)
		(end 124.547376 -7.225538)
		(width 0.14224)
		(layer "In4.Cu")
		(net "M_J_DQ<44>")
	)
	(segment
		(start 115.192556 -38.831012)
		(end 114.818922 -39.204646)
		(width 0.14224)
		(layer "In4.Cu")
		(net "M_J_DQ<44>")
	)
	(segment
		(start 124.572776 -18.567146)
		(end 124.572776 -21.695156)
		(width 0.14224)
		(layer "In4.Cu")
		(net "M_J_DQ<44>")
	)
	(segment
		(start 124.318776 -12.347956)
		(end 124.318776 -13.567156)
		(width 0.14224)
		(layer "In4.Cu")
		(net "M_J_DQ<44>")
	)
	(segment
		(start 124.318776 -21.949156)
		(end 124.318776 -23.168356)
		(width 0.14224)
		(layer "In4.Cu")
		(net "M_J_DQ<44>")
	)
	(segment
		(start 124.153168 -29.1846)
		(end 124.102368 -29.1846)
		(width 0.14224)
		(layer "In4.Cu")
		(net "M_J_DQ<44>")
	)
	(segment
		(start 111.977932 -55.609236)
		(end 111.971582 -55.619904)
		(width 0.0889)
		(layer "In4.Cu")
		(net "M_J_DQ<44>")
	)
	(segment
		(start 124.572776 -12.093956)
		(end 124.318776 -12.347956)
		(width 0.14224)
		(layer "In4.Cu")
		(net "M_J_DQ<44>")
	)
	(segment
		(start 111.994696 -59.20105)
		(end 112.489742 -59.866784)
		(width 0.0889)
		(layer "In4.Cu")
		(net "M_J_DQ<44>")
	)
	(segment
		(start 115.917726 -38.004242)
		(end 115.917726 -38.20541)
		(width 0.14224)
		(layer "In4.Cu")
		(net "M_J_DQ<44>")
	)
	(segment
		(start 124.318776 -17.055338)
		(end 124.318776 -18.313146)
		(width 0.14224)
		(layer "In4.Cu")
		(net "M_J_DQ<44>")
	)
	(segment
		(start 115.186206 -40.060626)
		(end 114.221768 -41.025064)
		(width 0.14224)
		(layer "In4.Cu")
		(net "M_J_DQ<44>")
	)
	(arc
		(start 111.971582 -57.601104)
		(mid 111.898784 -57.891867)
		(end 111.977932 -58.180986)
		(width 0.0889)
		(layer "In4.Cu")
		(net "M_J_DQ<44>")
	)
	(arc
		(start 111.977932 -57.190386)
		(mid 112.031402 -57.385449)
		(end 111.982758 -57.5818)
		(width 0.0889)
		(layer "In4.Cu")
		(net "M_J_DQ<44>")
	)
	(arc
		(start 111.982504 -53.23586)
		(mid 112.031535 -53.432547)
		(end 111.977932 -53.628036)
		(width 0.0889)
		(layer "In4.Cu")
		(net "M_J_DQ<44>")
	)
	(arc
		(start 111.971582 -55.619904)
		(mid 111.898784 -55.910667)
		(end 111.977932 -56.199786)
		(width 0.0889)
		(layer "In4.Cu")
		(net "M_J_DQ<44>")
	)
	(arc
		(start 111.971582 -54.629304)
		(mid 111.898784 -54.920067)
		(end 111.977932 -55.209186)
		(width 0.0889)
		(layer "In4.Cu")
		(net "M_J_DQ<44>")
	)
	(arc
		(start 111.977932 -56.199786)
		(mid 112.031402 -56.394849)
		(end 111.982758 -56.5912)
		(width 0.0889)
		(layer "In4.Cu")
		(net "M_J_DQ<44>")
	)
	(arc
		(start 111.971582 -56.610504)
		(mid 111.898784 -56.901267)
		(end 111.977932 -57.190386)
		(width 0.0889)
		(layer "In4.Cu")
		(net "M_J_DQ<44>")
	)
	(arc
		(start 111.977932 -55.209186)
		(mid 112.031402 -55.404249)
		(end 111.982758 -55.6006)
		(width 0.0889)
		(layer "In4.Cu")
		(net "M_J_DQ<44>")
	)
	(arc
		(start 111.977932 -58.581036)
		(mid 111.89871 -58.870154)
		(end 111.971582 -59.160918)
		(width 0.0889)
		(layer "In4.Cu")
		(net "M_J_DQ<44>")
	)
	(arc
		(start 111.977932 -53.628036)
		(mid 111.89871 -53.917154)
		(end 111.971582 -54.207918)
		(width 0.0889)
		(layer "In4.Cu")
		(net "M_J_DQ<44>")
	)
	(arc
		(start 111.977932 -58.180986)
		(mid 112.031402 -58.376049)
		(end 111.982758 -58.5724)
		(width 0.0889)
		(layer "In4.Cu")
		(net "M_J_DQ<44>")
	)
	(arc
		(start 111.982758 -54.227222)
		(mid 112.031513 -54.423574)
		(end 111.977932 -54.618636)
		(width 0.0889)
		(layer "In4.Cu")
		(net "M_J_DQ<44>")
	)
	(segment
		(start 124.525024 0.287528)
		(end 124.525024 0.765048)
		(width 0.14224)
		(layer "In11.Cu")
		(net "M_J_DQ<44>")
	)
	(segment
		(start 124.173742 -1.790446)
		(end 124.173742 -1.4351)
		(width 0.14224)
		(layer "In11.Cu")
		(net "M_J_DQ<44>")
	)
	(segment
		(start 124.542042 -0.762)
		(end 124.161042 -0.381)
		(width 0.14224)
		(layer "In11.Cu")
		(net "M_J_DQ<44>")
	)
	(segment
		(start 123.813824 -3.327654)
		(end 124.525024 -2.616454)
		(width 0.14224)
		(layer "In11.Cu")
		(net "M_J_DQ<44>")
	)
	(segment
		(start 124.525024 0.765048)
		(end 124.801376 1.0414)
		(width 0.14224)
		(layer "In11.Cu")
		(net "M_J_DQ<44>")
	)
	(segment
		(start 124.173742 -1.4351)
		(end 124.542042 -1.0668)
		(width 0.14224)
		(layer "In11.Cu")
		(net "M_J_DQ<44>")
	)
	(segment
		(start 124.542042 -1.0668)
		(end 124.542042 -0.762)
		(width 0.14224)
		(layer "In11.Cu")
		(net "M_J_DQ<44>")
	)
	(segment
		(start 124.049536 -4.357878)
		(end 123.813824 -4.122166)
		(width 0.14224)
		(layer "In11.Cu")
		(net "M_J_DQ<44>")
	)
	(segment
		(start 124.525024 -2.616454)
		(end 124.525024 -2.141728)
		(width 0.14224)
		(layer "In11.Cu")
		(net "M_J_DQ<44>")
	)
	(segment
		(start 123.813824 -4.122166)
		(end 123.813824 -3.327654)
		(width 0.14224)
		(layer "In11.Cu")
		(net "M_J_DQ<44>")
	)
	(segment
		(start 124.525024 -2.141728)
		(end 124.173742 -1.790446)
		(width 0.14224)
		(layer "In11.Cu")
		(net "M_J_DQ<44>")
	)
	(segment
		(start 124.161042 -0.076454)
		(end 124.525024 0.287528)
		(width 0.14224)
		(layer "In11.Cu")
		(net "M_J_DQ<44>")
	)
	(segment
		(start 124.161042 -0.381)
		(end 124.161042 -0.076454)
		(width 0.14224)
		(layer "In11.Cu")
		(net "M_J_DQ<44>")
	)
	(segment
		(start 116.495322 -60.857384)
		(end 115.923822 -60.857384)
		(width 0.0889)
		(layer "F.Cu")
		(net "M_J_DQ<43>")
	)
	(segment
		(start 131.699508 3.778758)
		(end 131.699508 2.514854)
		(width 0.1651)
		(layer "F.Cu")
		(net "M_J_DQ<43>")
	)
	(via
		(at 131.699508 2.514854)
		(size 0.508)
		(drill 0.254)
		(layers "F.Cu" "B.Cu")
		(net "M_J_DQ<43>")
	)
	(via
		(at 132.549392 -3.076956)
		(size 0.508)
		(drill 0.254)
		(layers "F.Cu" "B.Cu")
		(net "M_J_DQ<43>")
	)
	(via
		(at 115.923822 -60.857384)
		(size 0.508)
		(drill 0.254)
		(layers "F.Cu" "B.Cu")
		(net "M_J_DQ<43>")
	)
	(segment
		(start 132.549392 -1.021842)
		(end 132.549392 -3.076956)
		(width 0.1651)
		(layer "B.Cu")
		(net "M_J_DQ<43>")
	)
	(segment
		(start 116.418868 -60.19165)
		(end 116.435632 -60.162186)
		(width 0.0889)
		(layer "In4.Cu")
		(net "M_J_DQ<43>")
	)
	(segment
		(start 133.056376 -17.030446)
		(end 132.916676 -16.890746)
		(width 0.14224)
		(layer "In4.Cu")
		(net "M_J_DQ<43>")
	)
	(segment
		(start 132.916168 -23.349204)
		(end 133.081776 -23.183596)
		(width 0.14224)
		(layer "In4.Cu")
		(net "M_J_DQ<43>")
	)
	(segment
		(start 118.730268 -50.295048)
		(end 120.439688 -48.585628)
		(width 0.0889)
		(layer "In4.Cu")
		(net "M_J_DQ<43>")
	)
	(segment
		(start 120.439688 -47.46498)
		(end 120.620536 -47.284132)
		(width 0.0889)
		(layer "In4.Cu")
		(net "M_J_DQ<43>")
	)
	(segment
		(start 133.011164 -26.917396)
		(end 132.916168 -26.8224)
		(width 0.14224)
		(layer "In4.Cu")
		(net "M_J_DQ<43>")
	)
	(segment
		(start 120.439688 -48.585628)
		(end 120.439688 -47.46498)
		(width 0.0889)
		(layer "In4.Cu")
		(net "M_J_DQ<43>")
	)
	(segment
		(start 132.916676 -4.816856)
		(end 132.065776 -3.965956)
		(width 0.14224)
		(layer "In4.Cu")
		(net "M_J_DQ<43>")
	)
	(segment
		(start 133.081776 -13.516356)
		(end 133.081776 -12.398756)
		(width 0.14224)
		(layer "In4.Cu")
		(net "M_J_DQ<43>")
	)
	(segment
		(start 116.441982 -55.619904)
		(end 116.435632 -55.609236)
		(width 0.0889)
		(layer "In4.Cu")
		(net "M_J_DQ<43>")
	)
	(segment
		(start 132.916676 -13.681456)
		(end 133.081776 -13.516356)
		(width 0.14224)
		(layer "In4.Cu")
		(net "M_J_DQ<43>")
	)
	(segment
		(start 133.081776 -23.183596)
		(end 133.081776 -21.999956)
		(width 0.14224)
		(layer "In4.Cu")
		(net "M_J_DQ<43>")
	)
	(segment
		(start 132.903976 -12.220956)
		(end 132.903976 -8.927338)
		(width 0.14224)
		(layer "In4.Cu")
		(net "M_J_DQ<43>")
	)
	(segment
		(start 132.916676 -16.890746)
		(end 132.916676 -13.681456)
		(width 0.14224)
		(layer "In4.Cu")
		(net "M_J_DQ<43>")
	)
	(segment
		(start 133.056376 -8.774938)
		(end 133.056376 -7.429246)
		(width 0.14224)
		(layer "In4.Cu")
		(net "M_J_DQ<43>")
	)
	(segment
		(start 133.246368 -29.1084)
		(end 132.833364 -28.695396)
		(width 0.14224)
		(layer "In4.Cu")
		(net "M_J_DQ<43>")
	)
	(segment
		(start 129.868168 -35.3568)
		(end 133.246368 -31.9786)
		(width 0.14224)
		(layer "In4.Cu")
		(net "M_J_DQ<43>")
	)
	(segment
		(start 116.423694 -53.330094)
		(end 118.730268 -51.02352)
		(width 0.0889)
		(layer "In4.Cu")
		(net "M_J_DQ<43>")
	)
	(segment
		(start 133.056376 -7.429246)
		(end 132.916676 -7.289546)
		(width 0.14224)
		(layer "In4.Cu")
		(net "M_J_DQ<43>")
	)
	(segment
		(start 116.441982 -57.601104)
		(end 116.435632 -57.590436)
		(width 0.0889)
		(layer "In4.Cu")
		(net "M_J_DQ<43>")
	)
	(segment
		(start 133.246368 -31.9786)
		(end 133.246368 -29.1084)
		(width 0.14224)
		(layer "In4.Cu")
		(net "M_J_DQ<43>")
	)
	(segment
		(start 132.903976 -8.927338)
		(end 133.056376 -8.774938)
		(width 0.14224)
		(layer "In4.Cu")
		(net "M_J_DQ<43>")
	)
	(segment
		(start 116.435632 -55.609236)
		(end 116.430806 -55.6006)
		(width 0.0889)
		(layer "In4.Cu")
		(net "M_J_DQ<43>")
	)
	(segment
		(start 116.441982 -54.629304)
		(end 116.435632 -54.618636)
		(width 0.0889)
		(layer "In4.Cu")
		(net "M_J_DQ<43>")
	)
	(segment
		(start 132.903976 -18.553938)
		(end 133.056376 -18.401538)
		(width 0.14224)
		(layer "In4.Cu")
		(net "M_J_DQ<43>")
	)
	(segment
		(start 116.423694 -53.583332)
		(end 116.423694 -53.330094)
		(width 0.0889)
		(layer "In4.Cu")
		(net "M_J_DQ<43>")
	)
	(segment
		(start 118.730268 -51.02352)
		(end 118.730268 -50.295048)
		(width 0.0889)
		(layer "In4.Cu")
		(net "M_J_DQ<43>")
	)
	(segment
		(start 116.441982 -56.610504)
		(end 116.435632 -56.599836)
		(width 0.0889)
		(layer "In4.Cu")
		(net "M_J_DQ<43>")
	)
	(segment
		(start 129.398776 -35.3568)
		(end 129.868168 -35.3568)
		(width 0.14224)
		(layer "In4.Cu")
		(net "M_J_DQ<43>")
	)
	(segment
		(start 116.435632 -54.618636)
		(end 116.430806 -54.61)
		(width 0.0889)
		(layer "In4.Cu")
		(net "M_J_DQ<43>")
	)
	(segment
		(start 120.620536 -47.284132)
		(end 120.620536 -44.13504)
		(width 0.14224)
		(layer "In4.Cu")
		(net "M_J_DQ<43>")
	)
	(segment
		(start 120.620536 -44.13504)
		(end 129.398776 -35.3568)
		(width 0.14224)
		(layer "In4.Cu")
		(net "M_J_DQ<43>")
	)
	(segment
		(start 116.435632 -58.581036)
		(end 116.430806 -58.5724)
		(width 0.0889)
		(layer "In4.Cu")
		(net "M_J_DQ<43>")
	)
	(segment
		(start 133.081776 -12.398756)
		(end 132.903976 -12.220956)
		(width 0.14224)
		(layer "In4.Cu")
		(net "M_J_DQ<43>")
	)
	(segment
		(start 132.916676 -7.289546)
		(end 132.916676 -4.816856)
		(width 0.14224)
		(layer "In4.Cu")
		(net "M_J_DQ<43>")
	)
	(segment
		(start 132.833364 -28.695396)
		(end 132.833364 -28.365196)
		(width 0.14224)
		(layer "In4.Cu")
		(net "M_J_DQ<43>")
	)
	(segment
		(start 132.065776 -3.560572)
		(end 132.549392 -3.076956)
		(width 0.14224)
		(layer "In4.Cu")
		(net "M_J_DQ<43>")
	)
	(segment
		(start 133.011164 -28.187396)
		(end 133.011164 -26.917396)
		(width 0.14224)
		(layer "In4.Cu")
		(net "M_J_DQ<43>")
	)
	(segment
		(start 116.435632 -57.590436)
		(end 116.430806 -57.5818)
		(width 0.0889)
		(layer "In4.Cu")
		(net "M_J_DQ<43>")
	)
	(segment
		(start 132.916168 -26.8224)
		(end 132.916168 -23.349204)
		(width 0.14224)
		(layer "In4.Cu")
		(net "M_J_DQ<43>")
	)
	(segment
		(start 132.833364 -28.365196)
		(end 133.011164 -28.187396)
		(width 0.14224)
		(layer "In4.Cu")
		(net "M_J_DQ<43>")
	)
	(segment
		(start 115.923822 -60.857384)
		(end 116.418868 -60.19165)
		(width 0.0889)
		(layer "In4.Cu")
		(net "M_J_DQ<43>")
	)
	(segment
		(start 116.435632 -56.599836)
		(end 116.430806 -56.5912)
		(width 0.0889)
		(layer "In4.Cu")
		(net "M_J_DQ<43>")
	)
	(segment
		(start 133.056376 -18.401538)
		(end 133.056376 -17.030446)
		(width 0.14224)
		(layer "In4.Cu")
		(net "M_J_DQ<43>")
	)
	(segment
		(start 116.435632 -59.171586)
		(end 116.441982 -59.160918)
		(width 0.0889)
		(layer "In4.Cu")
		(net "M_J_DQ<43>")
	)
	(segment
		(start 132.065776 -3.965956)
		(end 132.065776 -3.560572)
		(width 0.14224)
		(layer "In4.Cu")
		(net "M_J_DQ<43>")
	)
	(segment
		(start 133.081776 -21.999956)
		(end 132.903976 -21.822156)
		(width 0.14224)
		(layer "In4.Cu")
		(net "M_J_DQ<43>")
	)
	(segment
		(start 132.903976 -21.822156)
		(end 132.903976 -18.553938)
		(width 0.14224)
		(layer "In4.Cu")
		(net "M_J_DQ<43>")
	)
	(arc
		(start 116.430806 -58.5724)
		(mid 116.382051 -58.376048)
		(end 116.435632 -58.180986)
		(width 0.0889)
		(layer "In4.Cu")
		(net "M_J_DQ<43>")
	)
	(arc
		(start 116.430806 -57.5818)
		(mid 116.382051 -57.385448)
		(end 116.435632 -57.190386)
		(width 0.0889)
		(layer "In4.Cu")
		(net "M_J_DQ<43>")
	)
	(arc
		(start 116.435632 -55.209186)
		(mid 116.514854 -54.920068)
		(end 116.441982 -54.629304)
		(width 0.0889)
		(layer "In4.Cu")
		(net "M_J_DQ<43>")
	)
	(arc
		(start 116.435632 -53.627782)
		(mid 116.426773 -53.606337)
		(end 116.423694 -53.583332)
		(width 0.0889)
		(layer "In4.Cu")
		(net "M_J_DQ<43>")
	)
	(arc
		(start 116.435632 -57.190386)
		(mid 116.514854 -56.901268)
		(end 116.441982 -56.610504)
		(width 0.0889)
		(layer "In4.Cu")
		(net "M_J_DQ<43>")
	)
	(arc
		(start 116.435632 -56.199786)
		(mid 116.514854 -55.910668)
		(end 116.441982 -55.619904)
		(width 0.0889)
		(layer "In4.Cu")
		(net "M_J_DQ<43>")
	)
	(arc
		(start 116.430806 -56.5912)
		(mid 116.382051 -56.394848)
		(end 116.435632 -56.199786)
		(width 0.0889)
		(layer "In4.Cu")
		(net "M_J_DQ<43>")
	)
	(arc
		(start 116.435632 -54.218586)
		(mid 116.514763 -53.923184)
		(end 116.435632 -53.627782)
		(width 0.0889)
		(layer "In4.Cu")
		(net "M_J_DQ<43>")
	)
	(arc
		(start 116.441982 -59.160918)
		(mid 116.51478 -58.870155)
		(end 116.435632 -58.581036)
		(width 0.0889)
		(layer "In4.Cu")
		(net "M_J_DQ<43>")
	)
	(arc
		(start 116.430806 -55.6006)
		(mid 116.382051 -55.404248)
		(end 116.435632 -55.209186)
		(width 0.0889)
		(layer "In4.Cu")
		(net "M_J_DQ<43>")
	)
	(arc
		(start 116.435632 -59.571382)
		(mid 116.382133 -59.371484)
		(end 116.435632 -59.171586)
		(width 0.0889)
		(layer "In4.Cu")
		(net "M_J_DQ<43>")
	)
	(arc
		(start 116.435632 -58.180986)
		(mid 116.514854 -57.891868)
		(end 116.441982 -57.601104)
		(width 0.0889)
		(layer "In4.Cu")
		(net "M_J_DQ<43>")
	)
	(arc
		(start 116.430806 -54.61)
		(mid 116.382051 -54.413648)
		(end 116.435632 -54.218586)
		(width 0.0889)
		(layer "In4.Cu")
		(net "M_J_DQ<43>")
	)
	(arc
		(start 116.435632 -60.162186)
		(mid 116.514763 -59.866784)
		(end 116.435632 -59.571382)
		(width 0.0889)
		(layer "In4.Cu")
		(net "M_J_DQ<43>")
	)
	(segment
		(start 131.699508 2.514854)
		(end 132.016246 2.198116)
		(width 0.14224)
		(layer "In11.Cu")
		(net "M_J_DQ<43>")
	)
	(segment
		(start 132.902198 0.581152)
		(end 132.902198 -2.72415)
		(width 0.14224)
		(layer "In11.Cu")
		(net "M_J_DQ<43>")
	)
	(segment
		(start 132.600446 1.5494)
		(end 133.057646 1.0922)
		(width 0.14224)
		(layer "In11.Cu")
		(net "M_J_DQ<43>")
	)
	(segment
		(start 133.057646 0.7366)
		(end 132.902198 0.581152)
		(width 0.14224)
		(layer "In11.Cu")
		(net "M_J_DQ<43>")
	)
	(segment
		(start 133.057646 1.0922)
		(end 133.057646 0.7366)
		(width 0.14224)
		(layer "In11.Cu")
		(net "M_J_DQ<43>")
	)
	(segment
		(start 132.346446 1.5494)
		(end 132.600446 1.5494)
		(width 0.14224)
		(layer "In11.Cu")
		(net "M_J_DQ<43>")
	)
	(segment
		(start 132.902198 -2.72415)
		(end 132.549392 -3.076956)
		(width 0.14224)
		(layer "In11.Cu")
		(net "M_J_DQ<43>")
	)
	(segment
		(start 132.016246 2.198116)
		(end 132.016246 1.8796)
		(width 0.14224)
		(layer "In11.Cu")
		(net "M_J_DQ<43>")
	)
	(segment
		(start 132.016246 1.8796)
		(end 132.346446 1.5494)
		(width 0.14224)
		(layer "In11.Cu")
		(net "M_J_DQ<43>")
	)
	(segment
		(start 132.680964 0.30734)
		(end 132.680964 0.53086)
		(width 0.1651)
		(layer "F.Cu")
		(net "M_J_DQ<42>")
	)
	(segment
		(start 132.549392 -0.821182)
		(end 132.549392 0.175768)
		(width 0.1651)
		(layer "F.Cu")
		(net "M_J_DQ<42>")
	)
	(segment
		(start 132.549392 0.175768)
		(end 132.680964 0.30734)
		(width 0.1651)
		(layer "F.Cu")
		(net "M_J_DQ<42>")
	)
	(segment
		(start 132.549392 0.662432)
		(end 132.549392 0.9398)
		(width 0.1651)
		(layer "F.Cu")
		(net "M_J_DQ<42>")
	)
	(segment
		(start 132.680964 0.53086)
		(end 132.549392 0.662432)
		(width 0.1651)
		(layer "F.Cu")
		(net "M_J_DQ<42>")
	)
	(segment
		(start 116.495322 -59.866784)
		(end 115.923822 -59.866784)
		(width 0.0889)
		(layer "F.Cu")
		(net "M_J_DQ<42>")
	)
	(via
		(at 132.549392 0.9398)
		(size 0.508)
		(drill 0.254)
		(layers "F.Cu" "B.Cu")
		(net "M_J_DQ<42>")
	)
	(via
		(at 131.699508 -4.357878)
		(size 0.508)
		(drill 0.254)
		(layers "F.Cu" "B.Cu")
		(net "M_J_DQ<42>")
	)
	(via
		(at 115.923822 -59.866784)
		(size 0.508)
		(drill 0.254)
		(layers "F.Cu" "B.Cu")
		(net "M_J_DQ<42>")
	)
	(segment
		(start 131.699508 -5.621782)
		(end 131.699508 -4.357878)
		(width 0.1651)
		(layer "B.Cu")
		(net "M_J_DQ<42>")
	)
	(segment
		(start 132.294376 -23.396956)
		(end 132.040376 -23.142956)
		(width 0.14224)
		(layer "In4.Cu")
		(net "M_J_DQ<42>")
	)
	(segment
		(start 115.923822 -59.866784)
		(end 116.253514 -59.105546)
		(width 0.0889)
		(layer "In4.Cu")
		(net "M_J_DQ<42>")
	)
	(segment
		(start 130.006598 -33.380426)
		(end 130.294126 -33.380426)
		(width 0.14224)
		(layer "In4.Cu")
		(net "M_J_DQ<42>")
	)
	(segment
		(start 116.228368 -53.565806)
		(end 116.228368 -53.22824)
		(width 0.0889)
		(layer "In4.Cu")
		(net "M_J_DQ<42>")
	)
	(segment
		(start 116.275358 -53.731922)
		(end 116.270532 -53.723286)
		(width 0.0889)
		(layer "In4.Cu")
		(net "M_J_DQ<42>")
	)
	(segment
		(start 129.719324 -33.955228)
		(end 129.719324 -33.6677)
		(width 0.14224)
		(layer "In4.Cu")
		(net "M_J_DQ<42>")
	)
	(segment
		(start 132.268976 -7.162546)
		(end 132.268976 -4.927346)
		(width 0.14224)
		(layer "In4.Cu")
		(net "M_J_DQ<42>")
	)
	(segment
		(start 130.868928 -32.518096)
		(end 132.611368 -30.775656)
		(width 0.14224)
		(layer "In4.Cu")
		(net "M_J_DQ<42>")
	)
	(segment
		(start 116.270532 -57.685686)
		(end 116.264182 -57.675018)
		(width 0.0889)
		(layer "In4.Cu")
		(net "M_J_DQ<42>")
	)
	(segment
		(start 116.275358 -55.713122)
		(end 116.270532 -55.704486)
		(width 0.0889)
		(layer "In4.Cu")
		(net "M_J_DQ<42>")
	)
	(segment
		(start 131.849368 -27.0002)
		(end 132.294376 -26.555192)
		(width 0.14224)
		(layer "In4.Cu")
		(net "M_J_DQ<42>")
	)
	(segment
		(start 116.270532 -55.704486)
		(end 116.264182 -55.693818)
		(width 0.0889)
		(layer "In4.Cu")
		(net "M_J_DQ<42>")
	)
	(segment
		(start 118.539768 -50.91684)
		(end 118.539768 -50.2158)
		(width 0.0889)
		(layer "In4.Cu")
		(net "M_J_DQ<42>")
	)
	(segment
		(start 130.294126 -33.380426)
		(end 130.46837 -33.55467)
		(width 0.14224)
		(layer "In4.Cu")
		(net "M_J_DQ<42>")
	)
	(segment
		(start 132.268976 -4.927346)
		(end 131.699508 -4.357878)
		(width 0.14224)
		(layer "In4.Cu")
		(net "M_J_DQ<42>")
	)
	(segment
		(start 129.606294 -34.704274)
		(end 129.893568 -34.417)
		(width 0.14224)
		(layer "In4.Cu")
		(net "M_J_DQ<42>")
	)
	(segment
		(start 116.253514 -59.105546)
		(end 116.270532 -59.076336)
		(width 0.0889)
		(layer "In4.Cu")
		(net "M_J_DQ<42>")
	)
	(segment
		(start 131.823968 -10.388346)
		(end 132.192776 -10.019538)
		(width 0.14224)
		(layer "In4.Cu")
		(net "M_J_DQ<42>")
	)
	(segment
		(start 129.719324 -33.6677)
		(end 130.006598 -33.380426)
		(width 0.14224)
		(layer "In4.Cu")
		(net "M_J_DQ<42>")
	)
	(segment
		(start 132.294376 -26.555192)
		(end 132.294376 -23.396956)
		(width 0.14224)
		(layer "In4.Cu")
		(net "M_J_DQ<42>")
	)
	(segment
		(start 118.539768 -50.2158)
		(end 120.226328 -48.52924)
		(width 0.0889)
		(layer "In4.Cu")
		(net "M_J_DQ<42>")
	)
	(segment
		(start 116.270532 -56.695086)
		(end 116.264182 -56.684418)
		(width 0.0889)
		(layer "In4.Cu")
		(net "M_J_DQ<42>")
	)
	(segment
		(start 132.065776 -7.365746)
		(end 132.268976 -7.162546)
		(width 0.14224)
		(layer "In4.Cu")
		(net "M_J_DQ<42>")
	)
	(segment
		(start 132.281676 -13.783056)
		(end 132.040376 -13.541756)
		(width 0.14224)
		(layer "In4.Cu")
		(net "M_J_DQ<42>")
	)
	(segment
		(start 131.043172 -32.979868)
		(end 130.868928 -32.805624)
		(width 0.14224)
		(layer "In4.Cu")
		(net "M_J_DQ<42>")
	)
	(segment
		(start 119.985536 -47.141892)
		(end 119.985536 -43.401488)
		(width 0.14224)
		(layer "In4.Cu")
		(net "M_J_DQ<42>")
	)
	(segment
		(start 132.198364 -28.390596)
		(end 131.849368 -28.0416)
		(width 0.14224)
		(layer "In4.Cu")
		(net "M_J_DQ<42>")
	)
	(segment
		(start 132.192776 -11.201146)
		(end 131.823968 -10.832338)
		(width 0.14224)
		(layer "In4.Cu")
		(net "M_J_DQ<42>")
	)
	(segment
		(start 120.226328 -48.52924)
		(end 120.226328 -47.382684)
		(width 0.0889)
		(layer "In4.Cu")
		(net "M_J_DQ<42>")
	)
	(segment
		(start 132.040376 -21.949156)
		(end 132.192776 -21.796756)
		(width 0.14224)
		(layer "In4.Cu")
		(net "M_J_DQ<42>")
	)
	(segment
		(start 129.893568 -34.417)
		(end 129.893568 -34.129472)
		(width 0.14224)
		(layer "In4.Cu")
		(net "M_J_DQ<42>")
	)
	(segment
		(start 132.192776 -8.979154)
		(end 132.065776 -8.852154)
		(width 0.14224)
		(layer "In4.Cu")
		(net "M_J_DQ<42>")
	)
	(segment
		(start 132.040376 -12.347956)
		(end 132.192776 -12.195556)
		(width 0.14224)
		(layer "In4.Cu")
		(net "M_J_DQ<42>")
	)
	(segment
		(start 132.040376 -23.142956)
		(end 132.040376 -21.949156)
		(width 0.14224)
		(layer "In4.Cu")
		(net "M_J_DQ<42>")
	)
	(segment
		(start 116.270532 -54.713886)
		(end 116.264182 -54.703218)
		(width 0.0889)
		(layer "In4.Cu")
		(net "M_J_DQ<42>")
	)
	(segment
		(start 131.849368 -28.0416)
		(end 131.849368 -27.0002)
		(width 0.14224)
		(layer "In4.Cu")
		(net "M_J_DQ<42>")
	)
	(segment
		(start 132.192776 -12.195556)
		(end 132.192776 -11.201146)
		(width 0.14224)
		(layer "In4.Cu")
		(net "M_J_DQ<42>")
	)
	(segment
		(start 130.868928 -32.805624)
		(end 130.868928 -32.518096)
		(width 0.14224)
		(layer "In4.Cu")
		(net "M_J_DQ<42>")
	)
	(segment
		(start 128.856994 -34.53003)
		(end 129.144522 -34.53003)
		(width 0.14224)
		(layer "In4.Cu")
		(net "M_J_DQ<42>")
	)
	(segment
		(start 129.144522 -34.53003)
		(end 129.318766 -34.704274)
		(width 0.14224)
		(layer "In4.Cu")
		(net "M_J_DQ<42>")
	)
	(segment
		(start 130.46837 -33.55467)
		(end 130.755898 -33.55467)
		(width 0.14224)
		(layer "In4.Cu")
		(net "M_J_DQ<42>")
	)
	(segment
		(start 129.893568 -34.129472)
		(end 129.719324 -33.955228)
		(width 0.14224)
		(layer "In4.Cu")
		(net "M_J_DQ<42>")
	)
	(segment
		(start 120.226328 -47.382684)
		(end 119.985536 -47.141892)
		(width 0.0889)
		(layer "In4.Cu")
		(net "M_J_DQ<42>")
	)
	(segment
		(start 132.198364 -28.898596)
		(end 132.198364 -28.390596)
		(width 0.14224)
		(layer "In4.Cu")
		(net "M_J_DQ<42>")
	)
	(segment
		(start 132.192776 -18.554954)
		(end 132.077968 -18.440146)
		(width 0.14224)
		(layer "In4.Cu")
		(net "M_J_DQ<42>")
	)
	(segment
		(start 116.275358 -56.703722)
		(end 116.270532 -56.695086)
		(width 0.0889)
		(layer "In4.Cu")
		(net "M_J_DQ<42>")
	)
	(segment
		(start 132.040376 -13.541756)
		(end 132.040376 -12.347956)
		(width 0.14224)
		(layer "In4.Cu")
		(net "M_J_DQ<42>")
	)
	(segment
		(start 132.065776 -8.852154)
		(end 132.065776 -7.365746)
		(width 0.14224)
		(layer "In4.Cu")
		(net "M_J_DQ<42>")
	)
	(segment
		(start 129.318766 -34.704274)
		(end 129.606294 -34.704274)
		(width 0.14224)
		(layer "In4.Cu")
		(net "M_J_DQ<42>")
	)
	(segment
		(start 130.755898 -33.55467)
		(end 131.043172 -33.267396)
		(width 0.14224)
		(layer "In4.Cu")
		(net "M_J_DQ<42>")
	)
	(segment
		(start 116.228368 -53.22824)
		(end 118.539768 -50.91684)
		(width 0.0889)
		(layer "In4.Cu")
		(net "M_J_DQ<42>")
	)
	(segment
		(start 116.275358 -54.722522)
		(end 116.270532 -54.713886)
		(width 0.0889)
		(layer "In4.Cu")
		(net "M_J_DQ<42>")
	)
	(segment
		(start 132.611368 -29.3116)
		(end 132.198364 -28.898596)
		(width 0.14224)
		(layer "In4.Cu")
		(net "M_J_DQ<42>")
	)
	(segment
		(start 116.275358 -57.694322)
		(end 116.270532 -57.685686)
		(width 0.0889)
		(layer "In4.Cu")
		(net "M_J_DQ<42>")
	)
	(segment
		(start 132.611368 -30.775656)
		(end 132.611368 -29.3116)
		(width 0.14224)
		(layer "In4.Cu")
		(net "M_J_DQ<42>")
	)
	(segment
		(start 132.192776 -21.796756)
		(end 132.192776 -18.554954)
		(width 0.14224)
		(layer "In4.Cu")
		(net "M_J_DQ<42>")
	)
	(segment
		(start 131.043172 -33.267396)
		(end 131.043172 -32.979868)
		(width 0.14224)
		(layer "In4.Cu")
		(net "M_J_DQ<42>")
	)
	(segment
		(start 132.281676 -16.751046)
		(end 132.281676 -13.783056)
		(width 0.14224)
		(layer "In4.Cu")
		(net "M_J_DQ<42>")
	)
	(segment
		(start 132.192776 -10.019538)
		(end 132.192776 -8.979154)
		(width 0.14224)
		(layer "In4.Cu")
		(net "M_J_DQ<42>")
	)
	(segment
		(start 119.985536 -43.401488)
		(end 128.856994 -34.53003)
		(width 0.14224)
		(layer "In4.Cu")
		(net "M_J_DQ<42>")
	)
	(segment
		(start 132.077968 -18.440146)
		(end 132.077968 -16.954754)
		(width 0.14224)
		(layer "In4.Cu")
		(net "M_J_DQ<42>")
	)
	(segment
		(start 131.823968 -10.832338)
		(end 131.823968 -10.388346)
		(width 0.14224)
		(layer "In4.Cu")
		(net "M_J_DQ<42>")
	)
	(segment
		(start 132.077968 -16.954754)
		(end 132.281676 -16.751046)
		(width 0.14224)
		(layer "In4.Cu")
		(net "M_J_DQ<42>")
	)
	(arc
		(start 116.264182 -54.703218)
		(mid 116.191384 -54.412455)
		(end 116.270532 -54.123336)
		(width 0.0889)
		(layer "In4.Cu")
		(net "M_J_DQ<42>")
	)
	(arc
		(start 116.270532 -57.095136)
		(mid 116.324002 -56.900073)
		(end 116.275358 -56.703722)
		(width 0.0889)
		(layer "In4.Cu")
		(net "M_J_DQ<42>")
	)
	(arc
		(start 116.270532 -56.104536)
		(mid 116.324002 -55.909473)
		(end 116.275358 -55.713122)
		(width 0.0889)
		(layer "In4.Cu")
		(net "M_J_DQ<42>")
	)
	(arc
		(start 116.270532 -55.113936)
		(mid 116.324002 -54.918873)
		(end 116.275358 -54.722522)
		(width 0.0889)
		(layer "In4.Cu")
		(net "M_J_DQ<42>")
	)
	(arc
		(start 116.270532 -58.67654)
		(mid 116.191401 -58.381138)
		(end 116.270532 -58.085736)
		(width 0.0889)
		(layer "In4.Cu")
		(net "M_J_DQ<42>")
	)
	(arc
		(start 116.270532 -53.723286)
		(mid 116.239071 -53.647323)
		(end 116.228368 -53.565806)
		(width 0.0889)
		(layer "In4.Cu")
		(net "M_J_DQ<42>")
	)
	(arc
		(start 116.270532 -59.076336)
		(mid 116.324031 -58.876438)
		(end 116.270532 -58.67654)
		(width 0.0889)
		(layer "In4.Cu")
		(net "M_J_DQ<42>")
	)
	(arc
		(start 116.270532 -58.085736)
		(mid 116.324002 -57.890673)
		(end 116.275358 -57.694322)
		(width 0.0889)
		(layer "In4.Cu")
		(net "M_J_DQ<42>")
	)
	(arc
		(start 116.264182 -57.675018)
		(mid 116.191384 -57.384255)
		(end 116.270532 -57.095136)
		(width 0.0889)
		(layer "In4.Cu")
		(net "M_J_DQ<42>")
	)
	(arc
		(start 116.264182 -56.684418)
		(mid 116.191384 -56.393655)
		(end 116.270532 -56.104536)
		(width 0.0889)
		(layer "In4.Cu")
		(net "M_J_DQ<42>")
	)
	(arc
		(start 116.264182 -55.693818)
		(mid 116.191384 -55.403055)
		(end 116.270532 -55.113936)
		(width 0.0889)
		(layer "In4.Cu")
		(net "M_J_DQ<42>")
	)
	(arc
		(start 116.270532 -54.123336)
		(mid 116.324002 -53.928273)
		(end 116.275358 -53.731922)
		(width 0.0889)
		(layer "In4.Cu")
		(net "M_J_DQ<42>")
	)
	(segment
		(start 132.111242 -1.04775)
		(end 132.111242 -0.761746)
		(width 0.14224)
		(layer "In11.Cu")
		(net "M_J_DQ<42>")
	)
	(segment
		(start 132.263642 -2.478532)
		(end 132.263642 -2.2098)
		(width 0.14224)
		(layer "In11.Cu")
		(net "M_J_DQ<42>")
	)
	(segment
		(start 132.111242 -0.761746)
		(end 131.806442 -0.456946)
		(width 0.14224)
		(layer "In11.Cu")
		(net "M_J_DQ<42>")
	)
	(segment
		(start 131.414774 -3.3274)
		(end 132.263642 -2.478532)
		(width 0.14224)
		(layer "In11.Cu")
		(net "M_J_DQ<42>")
	)
	(segment
		(start 132.263642 -2.2098)
		(end 131.806442 -1.7526)
		(width 0.14224)
		(layer "In11.Cu")
		(net "M_J_DQ<42>")
	)
	(segment
		(start 131.806442 -1.35255)
		(end 132.111242 -1.04775)
		(width 0.14224)
		(layer "In11.Cu")
		(net "M_J_DQ<42>")
	)
	(segment
		(start 132.151374 0.541782)
		(end 132.549392 0.9398)
		(width 0.14224)
		(layer "In11.Cu")
		(net "M_J_DQ<42>")
	)
	(segment
		(start 131.806442 -0.456946)
		(end 131.806442 -0.108204)
		(width 0.14224)
		(layer "In11.Cu")
		(net "M_J_DQ<42>")
	)
	(segment
		(start 131.806442 -0.108204)
		(end 132.151374 0.236728)
		(width 0.14224)
		(layer "In11.Cu")
		(net "M_J_DQ<42>")
	)
	(segment
		(start 131.806442 -1.7526)
		(end 131.806442 -1.35255)
		(width 0.14224)
		(layer "In11.Cu")
		(net "M_J_DQ<42>")
	)
	(segment
		(start 132.151374 0.236728)
		(end 132.151374 0.541782)
		(width 0.14224)
		(layer "In11.Cu")
		(net "M_J_DQ<42>")
	)
	(segment
		(start 131.414774 -4.073144)
		(end 131.414774 -3.3274)
		(width 0.14224)
		(layer "In11.Cu")
		(net "M_J_DQ<42>")
	)
	(segment
		(start 131.699508 -4.357878)
		(end 131.414774 -4.073144)
		(width 0.14224)
		(layer "In11.Cu")
		(net "M_J_DQ<42>")
	)
	(segment
		(start 113.919762 -61.352938)
		(end 113.348262 -61.352938)
		(width 0.0889)
		(layer "F.Cu")
		(net "M_J_DQ<41>")
	)
	(segment
		(start 125.749558 3.778758)
		(end 125.749558 2.514854)
		(width 0.1651)
		(layer "F.Cu")
		(net "M_J_DQ<41>")
	)
	(via
		(at 125.749558 2.514854)
		(size 0.508)
		(drill 0.254)
		(layers "F.Cu" "B.Cu")
		(net "M_J_DQ<41>")
	)
	(via
		(at 113.348262 -61.352938)
		(size 0.508)
		(drill 0.254)
		(layers "F.Cu" "B.Cu")
		(net "M_J_DQ<41>")
	)
	(via
		(at 126.421642 -3.076956)
		(size 0.508)
		(drill 0.254)
		(layers "F.Cu" "B.Cu")
		(net "M_J_DQ<41>")
	)
	(segment
		(start 126.599442 -1.021842)
		(end 126.599442 -2.395982)
		(width 0.1651)
		(layer "B.Cu")
		(net "M_J_DQ<41>")
	)
	(segment
		(start 126.421642 -2.573782)
		(end 126.421642 -3.076956)
		(width 0.1651)
		(layer "B.Cu")
		(net "M_J_DQ<41>")
	)
	(segment
		(start 126.599442 -2.395982)
		(end 126.421642 -2.573782)
		(width 0.1651)
		(layer "B.Cu")
		(net "M_J_DQ<41>")
	)
	(segment
		(start 124.559568 -31.9024)
		(end 125.143768 -32.4866)
		(width 0.14224)
		(layer "In4.Cu")
		(net "M_J_DQ<41>")
	)
	(segment
		(start 114.488468 -49.677828)
		(end 114.488468 -50.701194)
		(width 0.0889)
		(layer "In4.Cu")
		(net "M_J_DQ<41>")
	)
	(segment
		(start 112.888522 -52.30114)
		(end 112.888522 -53.425344)
		(width 0.0889)
		(layer "In4.Cu")
		(net "M_J_DQ<41>")
	)
	(segment
		(start 115.928648 -47.16272)
		(end 115.928648 -48.237648)
		(width 0.0889)
		(layer "In4.Cu")
		(net "M_J_DQ<41>")
	)
	(segment
		(start 126.421642 -3.076956)
		(end 125.948694 -3.549904)
		(width 0.14224)
		(layer "In4.Cu")
		(net "M_J_DQ<41>")
	)
	(segment
		(start 112.996726 -60.5536)
		(end 113.018824 -60.591954)
		(width 0.0889)
		(layer "In4.Cu")
		(net "M_J_DQ<41>")
	)
	(segment
		(start 113.694972 -59.571382)
		(end 113.678208 -59.600338)
		(width 0.0889)
		(layer "In4.Cu")
		(net "M_J_DQ<41>")
	)
	(segment
		(start 116.126768 -41.814496)
		(end 116.126768 -46.9646)
		(width 0.14224)
		(layer "In4.Cu")
		(net "M_J_DQ<41>")
	)
	(segment
		(start 126.909576 -6.566662)
		(end 126.909576 -29.071824)
		(width 0.14224)
		(layer "In4.Cu")
		(net "M_J_DQ<41>")
	)
	(segment
		(start 116.126768 -46.9646)
		(end 115.928648 -47.16272)
		(width 0.0889)
		(layer "In4.Cu")
		(net "M_J_DQ<41>")
	)
	(segment
		(start 124.379228 -33.12414)
		(end 123.954794 -33.548574)
		(width 0.14224)
		(layer "In4.Cu")
		(net "M_J_DQ<41>")
	)
	(segment
		(start 124.817124 -33.12414)
		(end 124.379228 -33.12414)
		(width 0.14224)
		(layer "In4.Cu")
		(net "M_J_DQ<41>")
	)
	(segment
		(start 126.284736 -5.941822)
		(end 126.909576 -6.566662)
		(width 0.14224)
		(layer "In4.Cu")
		(net "M_J_DQ<41>")
	)
	(segment
		(start 113.361216 -59.962288)
		(end 113.333276 -59.962288)
		(width 0.0889)
		(layer "In4.Cu")
		(net "M_J_DQ<41>")
	)
	(segment
		(start 112.996726 -57.5818)
		(end 113.001552 -57.590436)
		(width 0.0889)
		(layer "In4.Cu")
		(net "M_J_DQ<41>")
	)
	(segment
		(start 112.888522 -53.425344)
		(end 113.007902 -53.638704)
		(width 0.0889)
		(layer "In4.Cu")
		(net "M_J_DQ<41>")
	)
	(segment
		(start 112.996726 -56.5912)
		(end 113.001552 -56.599836)
		(width 0.0889)
		(layer "In4.Cu")
		(net "M_J_DQ<41>")
	)
	(segment
		(start 113.018824 -60.591954)
		(end 113.348262 -61.352938)
		(width 0.0889)
		(layer "In4.Cu")
		(net "M_J_DQ<41>")
	)
	(segment
		(start 113.001552 -56.599836)
		(end 113.007902 -56.610504)
		(width 0.0889)
		(layer "In4.Cu")
		(net "M_J_DQ<41>")
	)
	(segment
		(start 126.284736 -4.239768)
		(end 126.284736 -5.941822)
		(width 0.14224)
		(layer "In4.Cu")
		(net "M_J_DQ<41>")
	)
	(segment
		(start 123.954794 -33.548574)
		(end 123.954794 -33.98647)
		(width 0.14224)
		(layer "In4.Cu")
		(net "M_J_DQ<41>")
	)
	(segment
		(start 125.143768 -32.4866)
		(end 125.143768 -32.797496)
		(width 0.14224)
		(layer "In4.Cu")
		(net "M_J_DQ<41>")
	)
	(segment
		(start 126.909576 -29.071824)
		(end 124.559568 -31.421832)
		(width 0.14224)
		(layer "In4.Cu")
		(net "M_J_DQ<41>")
	)
	(segment
		(start 113.007902 -54.229254)
		(end 113.003076 -54.23789)
		(width 0.0889)
		(layer "In4.Cu")
		(net "M_J_DQ<41>")
	)
	(segment
		(start 123.954794 -33.98647)
		(end 116.126768 -41.814496)
		(width 0.14224)
		(layer "In4.Cu")
		(net "M_J_DQ<41>")
	)
	(segment
		(start 113.018316 -58.152284)
		(end 113.001552 -58.180986)
		(width 0.0889)
		(layer "In4.Cu")
		(net "M_J_DQ<41>")
	)
	(segment
		(start 124.559568 -31.421832)
		(end 124.559568 -31.9024)
		(width 0.14224)
		(layer "In4.Cu")
		(net "M_J_DQ<41>")
	)
	(segment
		(start 112.996726 -55.6006)
		(end 113.001552 -55.609236)
		(width 0.0889)
		(layer "In4.Cu")
		(net "M_J_DQ<41>")
	)
	(segment
		(start 113.001552 -55.609236)
		(end 113.007902 -55.619904)
		(width 0.0889)
		(layer "In4.Cu")
		(net "M_J_DQ<41>")
	)
	(segment
		(start 114.488468 -50.701194)
		(end 112.888522 -52.30114)
		(width 0.0889)
		(layer "In4.Cu")
		(net "M_J_DQ<41>")
	)
	(segment
		(start 125.143768 -32.797496)
		(end 124.817124 -33.12414)
		(width 0.14224)
		(layer "In4.Cu")
		(net "M_J_DQ<41>")
	)
	(segment
		(start 113.014252 -54.218586)
		(end 113.007902 -54.229254)
		(width 0.0889)
		(layer "In4.Cu")
		(net "M_J_DQ<41>")
	)
	(segment
		(start 115.928648 -48.237648)
		(end 114.488468 -49.677828)
		(width 0.0889)
		(layer "In4.Cu")
		(net "M_J_DQ<41>")
	)
	(segment
		(start 125.948694 -3.549904)
		(end 125.948694 -3.903726)
		(width 0.14224)
		(layer "In4.Cu")
		(net "M_J_DQ<41>")
	)
	(segment
		(start 113.001552 -57.590436)
		(end 113.007902 -57.601104)
		(width 0.0889)
		(layer "In4.Cu")
		(net "M_J_DQ<41>")
	)
	(segment
		(start 125.948694 -3.903726)
		(end 126.284736 -4.239768)
		(width 0.14224)
		(layer "In4.Cu")
		(net "M_J_DQ<41>")
	)
	(arc
		(start 113.007902 -53.638704)
		(mid 113.087124 -53.927822)
		(end 113.014252 -54.218586)
		(width 0.0889)
		(layer "In4.Cu")
		(net "M_J_DQ<41>")
	)
	(arc
		(start 113.562638 -59.03341)
		(mid 113.593716 -59.055225)
		(end 113.622582 -59.079892)
		(width 0.0889)
		(layer "In4.Cu")
		(net "M_J_DQ<41>")
	)
	(arc
		(start 113.001552 -55.209186)
		(mid 112.948082 -55.404249)
		(end 112.996726 -55.6006)
		(width 0.0889)
		(layer "In4.Cu")
		(net "M_J_DQ<41>")
	)
	(arc
		(start 113.007902 -56.610504)
		(mid 113.0807 -56.901267)
		(end 113.001552 -57.190386)
		(width 0.0889)
		(layer "In4.Cu")
		(net "M_J_DQ<41>")
	)
	(arc
		(start 113.001552 -58.180986)
		(mid 112.973326 -58.521465)
		(end 113.218214 -58.759598)
		(width 0.0889)
		(layer "In4.Cu")
		(net "M_J_DQ<41>")
	)
	(arc
		(start 113.007902 -54.629304)
		(mid 113.0807 -54.920067)
		(end 113.001552 -55.209186)
		(width 0.0889)
		(layer "In4.Cu")
		(net "M_J_DQ<41>")
	)
	(arc
		(start 113.622582 -59.079892)
		(mid 113.662154 -59.123075)
		(end 113.694972 -59.171586)
		(width 0.0889)
		(layer "In4.Cu")
		(net "M_J_DQ<41>")
	)
	(arc
		(start 113.694972 -59.171586)
		(mid 113.748471 -59.371484)
		(end 113.694972 -59.571382)
		(width 0.0889)
		(layer "In4.Cu")
		(net "M_J_DQ<41>")
	)
	(arc
		(start 113.001552 -56.199786)
		(mid 112.948082 -56.394849)
		(end 112.996726 -56.5912)
		(width 0.0889)
		(layer "In4.Cu")
		(net "M_J_DQ<41>")
	)
	(arc
		(start 113.007902 -57.601104)
		(mid 113.077602 -57.824548)
		(end 113.055146 -58.057542)
		(width 0.0889)
		(layer "In4.Cu")
		(net "M_J_DQ<41>")
	)
	(arc
		(start 113.678208 -59.600338)
		(mid 113.537374 -59.796782)
		(end 113.361216 -59.962288)
		(width 0.0889)
		(layer "In4.Cu")
		(net "M_J_DQ<41>")
	)
	(arc
		(start 113.218214 -58.759598)
		(mid 113.383088 -58.905734)
		(end 113.562638 -59.03341)
		(width 0.0889)
		(layer "In4.Cu")
		(net "M_J_DQ<41>")
	)
	(arc
		(start 113.007902 -55.619904)
		(mid 113.0807 -55.910667)
		(end 113.001552 -56.199786)
		(width 0.0889)
		(layer "In4.Cu")
		(net "M_J_DQ<41>")
	)
	(arc
		(start 113.333276 -59.962288)
		(mid 113.000358 -60.164279)
		(end 112.996726 -60.5536)
		(width 0.0889)
		(layer "In4.Cu")
		(net "M_J_DQ<41>")
	)
	(arc
		(start 113.003076 -54.23789)
		(mid 112.954321 -54.434242)
		(end 113.007902 -54.629304)
		(width 0.0889)
		(layer "In4.Cu")
		(net "M_J_DQ<41>")
	)
	(arc
		(start 113.001552 -57.190386)
		(mid 112.948082 -57.385449)
		(end 112.996726 -57.5818)
		(width 0.0889)
		(layer "In4.Cu")
		(net "M_J_DQ<41>")
	)
	(arc
		(start 113.055146 -58.057542)
		(mid 113.038511 -58.105605)
		(end 113.018316 -58.152284)
		(width 0.0889)
		(layer "In4.Cu")
		(net "M_J_DQ<41>")
	)
	(segment
		(start 125.749558 1.975866)
		(end 125.749558 2.514854)
		(width 0.14224)
		(layer "In11.Cu")
		(net "M_J_DQ<41>")
	)
	(segment
		(start 126.795784 -2.702814)
		(end 126.795784 0.630936)
		(width 0.14224)
		(layer "In11.Cu")
		(net "M_J_DQ<41>")
	)
	(segment
		(start 126.952248 1.128776)
		(end 126.582424 1.4986)
		(width 0.14224)
		(layer "In11.Cu")
		(net "M_J_DQ<41>")
	)
	(segment
		(start 126.795784 0.630936)
		(end 126.952248 0.7874)
		(width 0.14224)
		(layer "In11.Cu")
		(net "M_J_DQ<41>")
	)
	(segment
		(start 126.226824 1.4986)
		(end 125.749558 1.975866)
		(width 0.14224)
		(layer "In11.Cu")
		(net "M_J_DQ<41>")
	)
	(segment
		(start 126.582424 1.4986)
		(end 126.226824 1.4986)
		(width 0.14224)
		(layer "In11.Cu")
		(net "M_J_DQ<41>")
	)
	(segment
		(start 126.421642 -3.076956)
		(end 126.795784 -2.702814)
		(width 0.14224)
		(layer "In11.Cu")
		(net "M_J_DQ<41>")
	)
	(segment
		(start 126.952248 0.7874)
		(end 126.952248 1.128776)
		(width 0.14224)
		(layer "In11.Cu")
		(net "M_J_DQ<41>")
	)
	(segment
		(start 126.599442 -0.821182)
		(end 126.421642 1.0414)
		(width 0.1651)
		(layer "F.Cu")
		(net "M_J_DQ<40>")
	)
	(segment
		(start 113.919762 -59.371484)
		(end 113.348262 -59.371484)
		(width 0.0889)
		(layer "F.Cu")
		(net "M_J_DQ<40>")
	)
	(via
		(at 125.749558 -4.357878)
		(size 0.508)
		(drill 0.254)
		(layers "F.Cu" "B.Cu")
		(net "M_J_DQ<40>")
	)
	(via
		(at 126.421642 1.0414)
		(size 0.508)
		(drill 0.254)
		(layers "F.Cu" "B.Cu")
		(net "M_J_DQ<40>")
	)
	(via
		(at 113.348262 -59.371484)
		(size 0.508)
		(drill 0.254)
		(layers "F.Cu" "B.Cu")
		(net "M_J_DQ<40>")
	)
	(segment
		(start 125.749558 -5.621782)
		(end 125.749558 -4.357878)
		(width 0.1651)
		(layer "B.Cu")
		(net "M_J_DQ<40>")
	)
	(segment
		(start 122.579384 -34.415984)
		(end 122.291856 -34.415984)
		(width 0.14224)
		(layer "In4.Cu")
		(net "M_J_DQ<40>")
	)
	(segment
		(start 125.931676 -17.118838)
		(end 125.931676 -18.314162)
		(width 0.14224)
		(layer "In4.Cu")
		(net "M_J_DQ<40>")
	)
	(segment
		(start 125.931676 -18.314162)
		(end 126.274576 -18.657062)
		(width 0.14224)
		(layer "In4.Cu")
		(net "M_J_DQ<40>")
	)
	(segment
		(start 120.420638 -35.10153)
		(end 119.999252 -35.522916)
		(width 0.14224)
		(layer "In4.Cu")
		(net "M_J_DQ<40>")
	)
	(segment
		(start 125.931676 -7.517638)
		(end 125.931676 -8.687562)
		(width 0.14224)
		(layer "In4.Cu")
		(net "M_J_DQ<40>")
	)
	(segment
		(start 120.51538 -36.240212)
		(end 120.51538 -36.52774)
		(width 0.14224)
		(layer "In4.Cu")
		(net "M_J_DQ<40>")
	)
	(segment
		(start 114.297968 -50.6222)
		(end 112.698022 -52.222146)
		(width 0.0889)
		(layer "In4.Cu")
		(net "M_J_DQ<40>")
	)
	(segment
		(start 112.830102 -55.693818)
		(end 112.836452 -55.704486)
		(width 0.0889)
		(layer "In4.Cu")
		(net "M_J_DQ<40>")
	)
	(segment
		(start 125.931676 -13.487908)
		(end 126.274576 -13.830808)
		(width 0.14224)
		(layer "In4.Cu")
		(net "M_J_DQ<40>")
	)
	(segment
		(start 122.19813 -32.885126)
		(end 122.19813 -33.172654)
		(width 0.14224)
		(layer "In4.Cu")
		(net "M_J_DQ<40>")
	)
	(segment
		(start 112.836452 -55.704486)
		(end 112.841278 -55.713122)
		(width 0.0889)
		(layer "In4.Cu")
		(net "M_J_DQ<40>")
	)
	(segment
		(start 112.698022 -52.222146)
		(end 112.698022 -53.475128)
		(width 0.0889)
		(layer "In4.Cu")
		(net "M_J_DQ<40>")
	)
	(segment
		(start 125.931676 -22.025356)
		(end 125.931676 -23.092156)
		(width 0.14224)
		(layer "In4.Cu")
		(net "M_J_DQ<40>")
	)
	(segment
		(start 126.274576 -18.657062)
		(end 126.274576 -21.682456)
		(width 0.14224)
		(layer "In4.Cu")
		(net "M_J_DQ<40>")
	)
	(segment
		(start 125.931676 -12.424156)
		(end 125.931676 -13.487908)
		(width 0.14224)
		(layer "In4.Cu")
		(net "M_J_DQ<40>")
	)
	(segment
		(start 125.924564 -28.034996)
		(end 126.261368 -28.3718)
		(width 0.14224)
		(layer "In4.Cu")
		(net "M_J_DQ<40>")
	)
	(segment
		(start 120.51538 -36.52774)
		(end 115.491768 -41.551352)
		(width 0.14224)
		(layer "In4.Cu")
		(net "M_J_DQ<40>")
	)
	(segment
		(start 126.274576 -13.830808)
		(end 126.274576 -16.775938)
		(width 0.14224)
		(layer "In4.Cu")
		(net "M_J_DQ<40>")
	)
	(segment
		(start 112.830102 -56.684418)
		(end 112.836452 -56.695086)
		(width 0.0889)
		(layer "In4.Cu")
		(net "M_J_DQ<40>")
	)
	(segment
		(start 122.291856 -34.415984)
		(end 122.002804 -34.126932)
		(width 0.14224)
		(layer "In4.Cu")
		(net "M_J_DQ<40>")
	)
	(segment
		(start 120.621806 -35.10153)
		(end 120.420638 -35.10153)
		(width 0.14224)
		(layer "In4.Cu")
		(net "M_J_DQ<40>")
	)
	(segment
		(start 115.738148 -47.18558)
		(end 115.738148 -48.1584)
		(width 0.0889)
		(layer "In4.Cu")
		(net "M_J_DQ<40>")
	)
	(segment
		(start 126.261368 -28.821888)
		(end 122.19813 -32.885126)
		(width 0.14224)
		(layer "In4.Cu")
		(net "M_J_DQ<40>")
	)
	(segment
		(start 122.866658 -33.841182)
		(end 122.866658 -34.12871)
		(width 0.14224)
		(layer "In4.Cu")
		(net "M_J_DQ<40>")
	)
	(segment
		(start 112.852962 -58.705496)
		(end 113.348262 -59.371484)
		(width 0.0889)
		(layer "In4.Cu")
		(net "M_J_DQ<40>")
	)
	(segment
		(start 126.223776 -6.769862)
		(end 126.223776 -7.225538)
		(width 0.14224)
		(layer "In4.Cu")
		(net "M_J_DQ<40>")
	)
	(segment
		(start 121.801636 -34.126932)
		(end 121.399808 -34.52876)
		(width 0.14224)
		(layer "In4.Cu")
		(net "M_J_DQ<40>")
	)
	(segment
		(start 119.999252 -35.724084)
		(end 120.51538 -36.240212)
		(width 0.14224)
		(layer "In4.Cu")
		(net "M_J_DQ<40>")
	)
	(segment
		(start 112.836452 -57.685686)
		(end 112.841278 -57.694322)
		(width 0.0889)
		(layer "In4.Cu")
		(net "M_J_DQ<40>")
	)
	(segment
		(start 121.68886 -35.01898)
		(end 121.68886 -35.306508)
		(width 0.14224)
		(layer "In4.Cu")
		(net "M_J_DQ<40>")
	)
	(segment
		(start 112.836452 -58.67654)
		(end 112.852962 -58.705496)
		(width 0.0889)
		(layer "In4.Cu")
		(net "M_J_DQ<40>")
	)
	(segment
		(start 125.931676 -23.092156)
		(end 126.274576 -23.435056)
		(width 0.14224)
		(layer "In4.Cu")
		(net "M_J_DQ<40>")
	)
	(segment
		(start 122.002804 -34.126932)
		(end 121.801636 -34.126932)
		(width 0.14224)
		(layer "In4.Cu")
		(net "M_J_DQ<40>")
	)
	(segment
		(start 126.274576 -12.081256)
		(end 125.931676 -12.424156)
		(width 0.14224)
		(layer "In4.Cu")
		(net "M_J_DQ<40>")
	)
	(segment
		(start 121.399808 -34.52876)
		(end 121.399808 -34.729928)
		(width 0.14224)
		(layer "In4.Cu")
		(net "M_J_DQ<40>")
	)
	(segment
		(start 112.841278 -54.131972)
		(end 112.834928 -54.14264)
		(width 0.0889)
		(layer "In4.Cu")
		(net "M_J_DQ<40>")
	)
	(segment
		(start 125.749558 -4.357878)
		(end 125.749558 -6.295644)
		(width 0.14224)
		(layer "In4.Cu")
		(net "M_J_DQ<40>")
	)
	(segment
		(start 112.846104 -54.123336)
		(end 112.841278 -54.131972)
		(width 0.0889)
		(layer "In4.Cu")
		(net "M_J_DQ<40>")
	)
	(segment
		(start 112.836452 -56.695086)
		(end 112.841278 -56.703722)
		(width 0.0889)
		(layer "In4.Cu")
		(net "M_J_DQ<40>")
	)
	(segment
		(start 115.491768 -41.551352)
		(end 115.491768 -46.9392)
		(width 0.14224)
		(layer "In4.Cu")
		(net "M_J_DQ<40>")
	)
	(segment
		(start 125.749558 -6.295644)
		(end 126.223776 -6.769862)
		(width 0.14224)
		(layer "In4.Cu")
		(net "M_J_DQ<40>")
	)
	(segment
		(start 121.68886 -35.306508)
		(end 121.401586 -35.593782)
		(width 0.14224)
		(layer "In4.Cu")
		(net "M_J_DQ<40>")
	)
	(segment
		(start 126.274576 -9.030462)
		(end 126.274576 -12.081256)
		(width 0.14224)
		(layer "In4.Cu")
		(net "M_J_DQ<40>")
	)
	(segment
		(start 122.866658 -34.12871)
		(end 122.579384 -34.415984)
		(width 0.14224)
		(layer "In4.Cu")
		(net "M_J_DQ<40>")
	)
	(segment
		(start 125.924564 -26.968196)
		(end 125.924564 -28.034996)
		(width 0.14224)
		(layer "In4.Cu")
		(net "M_J_DQ<40>")
	)
	(segment
		(start 119.999252 -35.522916)
		(end 119.999252 -35.724084)
		(width 0.14224)
		(layer "In4.Cu")
		(net "M_J_DQ<40>")
	)
	(segment
		(start 115.738148 -48.1584)
		(end 114.297968 -49.59858)
		(width 0.0889)
		(layer "In4.Cu")
		(net "M_J_DQ<40>")
	)
	(segment
		(start 112.698022 -53.475128)
		(end 112.841278 -53.731922)
		(width 0.0889)
		(layer "In4.Cu")
		(net "M_J_DQ<40>")
	)
	(segment
		(start 115.491768 -46.9392)
		(end 115.738148 -47.18558)
		(width 0.0889)
		(layer "In4.Cu")
		(net "M_J_DQ<40>")
	)
	(segment
		(start 126.274576 -16.775938)
		(end 125.931676 -17.118838)
		(width 0.14224)
		(layer "In4.Cu")
		(net "M_J_DQ<40>")
	)
	(segment
		(start 126.274576 -23.435056)
		(end 126.274576 -26.618184)
		(width 0.14224)
		(layer "In4.Cu")
		(net "M_J_DQ<40>")
	)
	(segment
		(start 125.931676 -8.687562)
		(end 126.274576 -9.030462)
		(width 0.14224)
		(layer "In4.Cu")
		(net "M_J_DQ<40>")
	)
	(segment
		(start 121.399808 -34.729928)
		(end 121.68886 -35.01898)
		(width 0.14224)
		(layer "In4.Cu")
		(net "M_J_DQ<40>")
	)
	(segment
		(start 121.401586 -35.593782)
		(end 121.114058 -35.593782)
		(width 0.14224)
		(layer "In4.Cu")
		(net "M_J_DQ<40>")
	)
	(segment
		(start 126.261368 -28.3718)
		(end 126.261368 -28.821888)
		(width 0.14224)
		(layer "In4.Cu")
		(net "M_J_DQ<40>")
	)
	(segment
		(start 126.223776 -7.225538)
		(end 125.931676 -7.517638)
		(width 0.14224)
		(layer "In4.Cu")
		(net "M_J_DQ<40>")
	)
	(segment
		(start 114.297968 -49.59858)
		(end 114.297968 -50.6222)
		(width 0.0889)
		(layer "In4.Cu")
		(net "M_J_DQ<40>")
	)
	(segment
		(start 126.274576 -21.682456)
		(end 125.931676 -22.025356)
		(width 0.14224)
		(layer "In4.Cu")
		(net "M_J_DQ<40>")
	)
	(segment
		(start 126.274576 -26.618184)
		(end 125.924564 -26.968196)
		(width 0.14224)
		(layer "In4.Cu")
		(net "M_J_DQ<40>")
	)
	(segment
		(start 112.830102 -57.675018)
		(end 112.836452 -57.685686)
		(width 0.0889)
		(layer "In4.Cu")
		(net "M_J_DQ<40>")
	)
	(segment
		(start 122.19813 -33.172654)
		(end 122.866658 -33.841182)
		(width 0.14224)
		(layer "In4.Cu")
		(net "M_J_DQ<40>")
	)
	(segment
		(start 121.114058 -35.593782)
		(end 120.621806 -35.10153)
		(width 0.14224)
		(layer "In4.Cu")
		(net "M_J_DQ<40>")
	)
	(arc
		(start 112.836452 -56.104536)
		(mid 112.75723 -56.393654)
		(end 112.830102 -56.684418)
		(width 0.0889)
		(layer "In4.Cu")
		(net "M_J_DQ<40>")
	)
	(arc
		(start 112.841278 -56.703722)
		(mid 112.890033 -56.900074)
		(end 112.836452 -57.095136)
		(width 0.0889)
		(layer "In4.Cu")
		(net "M_J_DQ<40>")
	)
	(arc
		(start 112.841278 -55.713122)
		(mid 112.890033 -55.909474)
		(end 112.836452 -56.104536)
		(width 0.0889)
		(layer "In4.Cu")
		(net "M_J_DQ<40>")
	)
	(arc
		(start 112.836452 -57.095136)
		(mid 112.75723 -57.384254)
		(end 112.830102 -57.675018)
		(width 0.0889)
		(layer "In4.Cu")
		(net "M_J_DQ<40>")
	)
	(arc
		(start 112.836452 -55.113936)
		(mid 112.75723 -55.403054)
		(end 112.830102 -55.693818)
		(width 0.0889)
		(layer "In4.Cu")
		(net "M_J_DQ<40>")
	)
	(arc
		(start 112.841278 -54.722522)
		(mid 112.890033 -54.918874)
		(end 112.836452 -55.113936)
		(width 0.0889)
		(layer "In4.Cu")
		(net "M_J_DQ<40>")
	)
	(arc
		(start 112.834928 -54.14264)
		(mid 112.76213 -54.433403)
		(end 112.841278 -54.722522)
		(width 0.0889)
		(layer "In4.Cu")
		(net "M_J_DQ<40>")
	)
	(arc
		(start 112.836452 -58.085736)
		(mid 112.757321 -58.381138)
		(end 112.836452 -58.67654)
		(width 0.0889)
		(layer "In4.Cu")
		(net "M_J_DQ<40>")
	)
	(arc
		(start 112.841278 -53.731922)
		(mid 112.894748 -53.926985)
		(end 112.846104 -54.123336)
		(width 0.0889)
		(layer "In4.Cu")
		(net "M_J_DQ<40>")
	)
	(arc
		(start 112.841278 -57.694322)
		(mid 112.890033 -57.890674)
		(end 112.836452 -58.085736)
		(width 0.0889)
		(layer "In4.Cu")
		(net "M_J_DQ<40>")
	)
	(segment
		(start 126.129542 -0.8509)
		(end 125.786642 -0.508)
		(width 0.14224)
		(layer "In11.Cu")
		(net "M_J_DQ<40>")
	)
	(segment
		(start 126.201424 -2.5908)
		(end 126.201424 -2.090928)
		(width 0.14224)
		(layer "In11.Cu")
		(net "M_J_DQ<40>")
	)
	(segment
		(start 126.201424 0.821182)
		(end 126.421642 1.0414)
		(width 0.14224)
		(layer "In11.Cu")
		(net "M_J_DQ<40>")
	)
	(segment
		(start 125.786642 -0.508)
		(end 125.786642 -0.178054)
		(width 0.14224)
		(layer "In11.Cu")
		(net "M_J_DQ<40>")
	)
	(segment
		(start 125.786642 -0.178054)
		(end 126.201424 0.236728)
		(width 0.14224)
		(layer "In11.Cu")
		(net "M_J_DQ<40>")
	)
	(segment
		(start 126.201424 0.236728)
		(end 126.201424 0.821182)
		(width 0.14224)
		(layer "In11.Cu")
		(net "M_J_DQ<40>")
	)
	(segment
		(start 125.812042 -1.397)
		(end 126.129542 -1.0795)
		(width 0.14224)
		(layer "In11.Cu")
		(net "M_J_DQ<40>")
	)
	(segment
		(start 125.464824 -3.3274)
		(end 126.201424 -2.5908)
		(width 0.14224)
		(layer "In11.Cu")
		(net "M_J_DQ<40>")
	)
	(segment
		(start 125.464824 -4.073144)
		(end 125.464824 -3.3274)
		(width 0.14224)
		(layer "In11.Cu")
		(net "M_J_DQ<40>")
	)
	(segment
		(start 126.201424 -2.090928)
		(end 125.812042 -1.701546)
		(width 0.14224)
		(layer "In11.Cu")
		(net "M_J_DQ<40>")
	)
	(segment
		(start 125.812042 -1.701546)
		(end 125.812042 -1.397)
		(width 0.14224)
		(layer "In11.Cu")
		(net "M_J_DQ<40>")
	)
	(segment
		(start 125.749558 -4.357878)
		(end 125.464824 -4.073144)
		(width 0.14224)
		(layer "In11.Cu")
		(net "M_J_DQ<40>")
	)
	(segment
		(start 126.129542 -1.0795)
		(end 126.129542 -0.8509)
		(width 0.14224)
		(layer "In11.Cu")
		(net "M_J_DQ<40>")
	)
	(segment
		(start 39.049452 3.778758)
		(end 39.049452 2.514854)
		(width 0.1651)
		(layer "F.Cu")
		(net "M_J_DQ<3>")
	)
	(segment
		(start 76.334366 -63.51524)
		(end 75.762866 -63.51524)
		(width 0.0889)
		(layer "F.Cu")
		(net "M_J_DQ<3>")
	)
	(via
		(at 75.762866 -63.51524)
		(size 0.508)
		(drill 0.254)
		(layers "F.Cu" "B.Cu")
		(net "M_J_DQ<3>")
	)
	(via
		(at 39.049452 2.514854)
		(size 0.508)
		(drill 0.254)
		(layers "F.Cu" "B.Cu")
		(net "M_J_DQ<3>")
	)
	(via
		(at 39.899336 -3.076956)
		(size 0.508)
		(drill 0.254)
		(layers "F.Cu" "B.Cu")
		(net "M_J_DQ<3>")
	)
	(segment
		(start 39.899336 -1.021842)
		(end 39.899336 -3.076956)
		(width 0.1651)
		(layer "B.Cu")
		(net "M_J_DQ<3>")
	)
	(segment
		(start 54.95671 -53.461666)
		(end 55.50408 -52.914296)
		(width 0.14224)
		(layer "In11.Cu")
		(net "M_J_DQ<3>")
	)
	(segment
		(start 58.902346 -57.62625)
		(end 59.121802 -57.845706)
		(width 0.14224)
		(layer "In11.Cu")
		(net "M_J_DQ<3>")
	)
	(segment
		(start 56.491378 -55.215282)
		(end 56.710326 -55.215282)
		(width 0.14224)
		(layer "In11.Cu")
		(net "M_J_DQ<3>")
	)
	(segment
		(start 40.26662 -13.694156)
		(end 40.26662 -16.890746)
		(width 0.14224)
		(layer "In11.Cu")
		(net "M_J_DQ<3>")
	)
	(segment
		(start 55.61457 -54.338474)
		(end 55.833518 -54.338474)
		(width 0.14224)
		(layer "In11.Cu")
		(net "M_J_DQ<3>")
	)
	(segment
		(start 60.107068 -57.298336)
		(end 64.017652 -61.20892)
		(width 0.14224)
		(layer "In11.Cu")
		(net "M_J_DQ<3>")
	)
	(segment
		(start 58.572908 -55.764176)
		(end 58.572908 -55.983124)
		(width 0.14224)
		(layer "In11.Cu")
		(net "M_J_DQ<3>")
	)
	(segment
		(start 72.31761 -62.92469)
		(end 72.350376 -62.92469)
		(width 0.0889)
		(layer "In11.Cu")
		(net "M_J_DQ<3>")
	)
	(segment
		(start 40.25392 -19.1008)
		(end 40.358568 -19.205448)
		(width 0.14224)
		(layer "In11.Cu")
		(net "M_J_DQ<3>")
	)
	(segment
		(start 39.977568 -5.8928)
		(end 39.977568 -6.223)
		(width 0.14224)
		(layer "In11.Cu")
		(net "M_J_DQ<3>")
	)
	(segment
		(start 40.433752 -37.62502)
		(end 55.065676 -52.256944)
		(width 0.14224)
		(layer "In11.Cu")
		(net "M_J_DQ<3>")
	)
	(segment
		(start 66.910458 -61.93409)
		(end 67.267836 -61.93409)
		(width 0.0889)
		(layer "In11.Cu")
		(net "M_J_DQ<3>")
	)
	(segment
		(start 58.025538 -56.530494)
		(end 58.025538 -56.749442)
		(width 0.14224)
		(layer "In11.Cu")
		(net "M_J_DQ<3>")
	)
	(segment
		(start 40.39362 -18.405094)
		(end 40.25392 -18.544794)
		(width 0.14224)
		(layer "In11.Cu")
		(net "M_J_DQ<3>")
	)
	(segment
		(start 55.395114 -54.119018)
		(end 55.61457 -54.338474)
		(width 0.14224)
		(layer "In11.Cu")
		(net "M_J_DQ<3>")
	)
	(segment
		(start 59.23026 -56.421528)
		(end 59.449716 -56.640984)
		(width 0.14224)
		(layer "In11.Cu")
		(net "M_J_DQ<3>")
	)
	(segment
		(start 55.065676 -52.256944)
		(end 55.065676 -52.475892)
		(width 0.14224)
		(layer "In11.Cu")
		(net "M_J_DQ<3>")
	)
	(segment
		(start 39.899336 -3.076956)
		(end 40.252142 -2.72415)
		(width 0.14224)
		(layer "In11.Cu")
		(net "M_J_DQ<3>")
	)
	(segment
		(start 57.476644 -54.667912)
		(end 57.6961 -54.887368)
		(width 0.14224)
		(layer "In11.Cu")
		(net "M_J_DQ<3>")
	)
	(segment
		(start 54.518306 -53.023262)
		(end 54.518306 -53.24221)
		(width 0.14224)
		(layer "In11.Cu")
		(net "M_J_DQ<3>")
	)
	(segment
		(start 40.26662 -4.816856)
		(end 40.26662 -5.603748)
		(width 0.14224)
		(layer "In11.Cu")
		(net "M_J_DQ<3>")
	)
	(segment
		(start 69.735446 -61.438536)
		(end 69.771006 -61.438536)
		(width 0.0889)
		(layer "In11.Cu")
		(net "M_J_DQ<3>")
	)
	(segment
		(start 40.383714 -12.33805)
		(end 40.383714 -13.577062)
		(width 0.14224)
		(layer "In11.Cu")
		(net "M_J_DQ<3>")
	)
	(segment
		(start 59.34075 -57.845706)
		(end 59.88812 -57.298336)
		(width 0.14224)
		(layer "In11.Cu")
		(net "M_J_DQ<3>")
	)
	(segment
		(start 40.40759 1.0922)
		(end 39.95039 1.5494)
		(width 0.14224)
		(layer "In11.Cu")
		(net "M_J_DQ<3>")
	)
	(segment
		(start 65.808098 -61.20892)
		(end 66.037714 -61.438536)
		(width 0.0889)
		(layer "In11.Cu")
		(net "M_J_DQ<3>")
	)
	(segment
		(start 57.6961 -55.106316)
		(end 57.14873 -55.653686)
		(width 0.14224)
		(layer "In11.Cu")
		(net "M_J_DQ<3>")
	)
	(segment
		(start 55.50408 -52.914296)
		(end 55.723028 -52.914296)
		(width 0.14224)
		(layer "In11.Cu")
		(net "M_J_DQ<3>")
	)
	(segment
		(start 55.942484 -53.133752)
		(end 55.942484 -53.3527)
		(width 0.14224)
		(layer "In11.Cu")
		(net "M_J_DQ<3>")
	)
	(segment
		(start 56.710326 -55.215282)
		(end 57.257696 -54.667912)
		(width 0.14224)
		(layer "In11.Cu")
		(net "M_J_DQ<3>")
	)
	(segment
		(start 40.409368 -9.578848)
		(end 40.409368 -11.557)
		(width 0.14224)
		(layer "In11.Cu")
		(net "M_J_DQ<3>")
	)
	(segment
		(start 40.40632 -8.867394)
		(end 40.25392 -9.019794)
		(width 0.14224)
		(layer "In11.Cu")
		(net "M_J_DQ<3>")
	)
	(segment
		(start 40.383714 -13.577062)
		(end 40.26662 -13.694156)
		(width 0.14224)
		(layer "In11.Cu")
		(net "M_J_DQ<3>")
	)
	(segment
		(start 74.89317 -63.610236)
		(end 74.94143 -63.610236)
		(width 0.0889)
		(layer "In11.Cu")
		(net "M_J_DQ<3>")
	)
	(segment
		(start 66.037714 -61.438536)
		(end 66.414904 -61.438536)
		(width 0.0889)
		(layer "In11.Cu")
		(net "M_J_DQ<3>")
	)
	(segment
		(start 40.180768 -23.434548)
		(end 40.180768 -23.911306)
		(width 0.14224)
		(layer "In11.Cu")
		(net "M_J_DQ<3>")
	)
	(segment
		(start 39.41572 -3.560572)
		(end 39.41572 -3.965956)
		(width 0.14224)
		(layer "In11.Cu")
		(net "M_J_DQ<3>")
	)
	(segment
		(start 40.26662 -16.890746)
		(end 40.39362 -17.017746)
		(width 0.14224)
		(layer "In11.Cu")
		(net "M_J_DQ<3>")
	)
	(segment
		(start 58.134504 -55.54472)
		(end 58.353452 -55.54472)
		(width 0.14224)
		(layer "In11.Cu")
		(net "M_J_DQ<3>")
	)
	(segment
		(start 59.449716 -56.859932)
		(end 58.902346 -57.407302)
		(width 0.14224)
		(layer "In11.Cu")
		(net "M_J_DQ<3>")
	)
	(segment
		(start 74.03465 -63.91529)
		(end 74.168 -63.91529)
		(width 0.0889)
		(layer "In11.Cu")
		(net "M_J_DQ<3>")
	)
	(segment
		(start 40.26662 -5.603748)
		(end 39.977568 -5.8928)
		(width 0.14224)
		(layer "In11.Cu")
		(net "M_J_DQ<3>")
	)
	(segment
		(start 55.833518 -54.338474)
		(end 56.380888 -53.791104)
		(width 0.14224)
		(layer "In11.Cu")
		(net "M_J_DQ<3>")
	)
	(segment
		(start 40.433752 -24.16429)
		(end 40.433752 -37.62502)
		(width 0.14224)
		(layer "In11.Cu")
		(net "M_J_DQ<3>")
	)
	(segment
		(start 40.25392 -18.544794)
		(end 40.25392 -19.1008)
		(width 0.14224)
		(layer "In11.Cu")
		(net "M_J_DQ<3>")
	)
	(segment
		(start 55.723028 -52.914296)
		(end 55.942484 -53.133752)
		(width 0.14224)
		(layer "In11.Cu")
		(net "M_J_DQ<3>")
	)
	(segment
		(start 40.358568 -19.205448)
		(end 40.358568 -21.2344)
		(width 0.14224)
		(layer "In11.Cu")
		(net "M_J_DQ<3>")
	)
	(segment
		(start 40.40632 -7.429246)
		(end 40.40632 -8.867394)
		(width 0.14224)
		(layer "In11.Cu")
		(net "M_J_DQ<3>")
	)
	(segment
		(start 40.25392 -11.712448)
		(end 40.25392 -12.208256)
		(width 0.14224)
		(layer "In11.Cu")
		(net "M_J_DQ<3>")
	)
	(segment
		(start 73.17232 -63.419736)
		(end 73.205086 -63.419736)
		(width 0.0889)
		(layer "In11.Cu")
		(net "M_J_DQ<3>")
	)
	(segment
		(start 74.168 -63.91529)
		(end 74.66584 -63.688976)
		(width 0.0889)
		(layer "In11.Cu")
		(net "M_J_DQ<3>")
	)
	(segment
		(start 39.95039 1.5494)
		(end 39.69639 1.5494)
		(width 0.14224)
		(layer "In11.Cu")
		(net "M_J_DQ<3>")
	)
	(segment
		(start 40.40759 0.7366)
		(end 40.40759 1.0922)
		(width 0.14224)
		(layer "In11.Cu")
		(net "M_J_DQ<3>")
	)
	(segment
		(start 40.26662 -7.289546)
		(end 40.40632 -7.429246)
		(width 0.14224)
		(layer "In11.Cu")
		(net "M_J_DQ<3>")
	)
	(segment
		(start 56.271922 -54.776878)
		(end 56.271922 -54.995826)
		(width 0.14224)
		(layer "In11.Cu")
		(net "M_J_DQ<3>")
	)
	(segment
		(start 40.180768 -23.911306)
		(end 40.433752 -24.16429)
		(width 0.14224)
		(layer "In11.Cu")
		(net "M_J_DQ<3>")
	)
	(segment
		(start 58.353452 -55.54472)
		(end 58.572908 -55.764176)
		(width 0.14224)
		(layer "In11.Cu")
		(net "M_J_DQ<3>")
	)
	(segment
		(start 58.902346 -57.407302)
		(end 58.902346 -57.62625)
		(width 0.14224)
		(layer "In11.Cu")
		(net "M_J_DQ<3>")
	)
	(segment
		(start 67.833494 -61.438536)
		(end 68.053966 -61.438536)
		(width 0.0889)
		(layer "In11.Cu")
		(net "M_J_DQ<3>")
	)
	(segment
		(start 70.60057 -61.93409)
		(end 70.633336 -61.93409)
		(width 0.0889)
		(layer "In11.Cu")
		(net "M_J_DQ<3>")
	)
	(segment
		(start 58.572908 -55.983124)
		(end 58.025538 -56.530494)
		(width 0.14224)
		(layer "In11.Cu")
		(net "M_J_DQ<3>")
	)
	(segment
		(start 39.36619 2.198116)
		(end 39.049452 2.514854)
		(width 0.14224)
		(layer "In11.Cu")
		(net "M_J_DQ<3>")
	)
	(segment
		(start 57.368186 -56.09209)
		(end 57.587134 -56.09209)
		(width 0.14224)
		(layer "In11.Cu")
		(net "M_J_DQ<3>")
	)
	(segment
		(start 40.252142 0.581152)
		(end 40.40759 0.7366)
		(width 0.14224)
		(layer "In11.Cu")
		(net "M_J_DQ<3>")
	)
	(segment
		(start 56.599836 -53.791104)
		(end 56.819292 -54.01056)
		(width 0.14224)
		(layer "In11.Cu")
		(net "M_J_DQ<3>")
	)
	(segment
		(start 58.463942 -56.968898)
		(end 59.011312 -56.421528)
		(width 0.14224)
		(layer "In11.Cu")
		(net "M_J_DQ<3>")
	)
	(segment
		(start 58.025538 -56.749442)
		(end 58.244994 -56.968898)
		(width 0.14224)
		(layer "In11.Cu")
		(net "M_J_DQ<3>")
	)
	(segment
		(start 54.737762 -53.461666)
		(end 54.95671 -53.461666)
		(width 0.14224)
		(layer "In11.Cu")
		(net "M_J_DQ<3>")
	)
	(segment
		(start 58.244994 -56.968898)
		(end 58.463942 -56.968898)
		(width 0.14224)
		(layer "In11.Cu")
		(net "M_J_DQ<3>")
	)
	(segment
		(start 40.25392 -21.339048)
		(end 40.25392 -21.822156)
		(width 0.14224)
		(layer "In11.Cu")
		(net "M_J_DQ<3>")
	)
	(segment
		(start 59.88812 -57.298336)
		(end 60.107068 -57.298336)
		(width 0.14224)
		(layer "In11.Cu")
		(net "M_J_DQ<3>")
	)
	(segment
		(start 71.45528 -62.429136)
		(end 71.488046 -62.429136)
		(width 0.0889)
		(layer "In11.Cu")
		(net "M_J_DQ<3>")
	)
	(segment
		(start 57.14873 -55.872634)
		(end 57.368186 -56.09209)
		(width 0.14224)
		(layer "In11.Cu")
		(net "M_J_DQ<3>")
	)
	(segment
		(start 40.25392 -12.208256)
		(end 40.383714 -12.33805)
		(width 0.14224)
		(layer "In11.Cu")
		(net "M_J_DQ<3>")
	)
	(segment
		(start 59.121802 -57.845706)
		(end 59.34075 -57.845706)
		(width 0.14224)
		(layer "In11.Cu")
		(net "M_J_DQ<3>")
	)
	(segment
		(start 74.94143 -63.610236)
		(end 75.762866 -63.51524)
		(width 0.0889)
		(layer "In11.Cu")
		(net "M_J_DQ<3>")
	)
	(segment
		(start 59.449716 -56.640984)
		(end 59.449716 -56.859932)
		(width 0.14224)
		(layer "In11.Cu")
		(net "M_J_DQ<3>")
	)
	(segment
		(start 40.409368 -11.557)
		(end 40.25392 -11.712448)
		(width 0.14224)
		(layer "In11.Cu")
		(net "M_J_DQ<3>")
	)
	(segment
		(start 66.414904 -61.438536)
		(end 66.910458 -61.93409)
		(width 0.0889)
		(layer "In11.Cu")
		(net "M_J_DQ<3>")
	)
	(segment
		(start 57.587134 -56.09209)
		(end 58.134504 -55.54472)
		(width 0.14224)
		(layer "In11.Cu")
		(net "M_J_DQ<3>")
	)
	(segment
		(start 40.25392 -9.4234)
		(end 40.409368 -9.578848)
		(width 0.14224)
		(layer "In11.Cu")
		(net "M_J_DQ<3>")
	)
	(segment
		(start 55.395114 -53.90007)
		(end 55.395114 -54.119018)
		(width 0.14224)
		(layer "In11.Cu")
		(net "M_J_DQ<3>")
	)
	(segment
		(start 40.39362 -17.017746)
		(end 40.39362 -18.405094)
		(width 0.14224)
		(layer "In11.Cu")
		(net "M_J_DQ<3>")
	)
	(segment
		(start 55.065676 -52.475892)
		(end 54.518306 -53.023262)
		(width 0.14224)
		(layer "In11.Cu")
		(net "M_J_DQ<3>")
	)
	(segment
		(start 39.41572 -3.965956)
		(end 40.26662 -4.816856)
		(width 0.14224)
		(layer "In11.Cu")
		(net "M_J_DQ<3>")
	)
	(segment
		(start 56.819292 -54.229508)
		(end 56.271922 -54.776878)
		(width 0.14224)
		(layer "In11.Cu")
		(net "M_J_DQ<3>")
	)
	(segment
		(start 39.899336 -3.076956)
		(end 39.41572 -3.560572)
		(width 0.14224)
		(layer "In11.Cu")
		(net "M_J_DQ<3>")
	)
	(segment
		(start 57.14873 -55.653686)
		(end 57.14873 -55.872634)
		(width 0.14224)
		(layer "In11.Cu")
		(net "M_J_DQ<3>")
	)
	(segment
		(start 56.380888 -53.791104)
		(end 56.599836 -53.791104)
		(width 0.14224)
		(layer "In11.Cu")
		(net "M_J_DQ<3>")
	)
	(segment
		(start 57.257696 -54.667912)
		(end 57.476644 -54.667912)
		(width 0.14224)
		(layer "In11.Cu")
		(net "M_J_DQ<3>")
	)
	(segment
		(start 40.25392 -21.822156)
		(end 40.43172 -21.999956)
		(width 0.14224)
		(layer "In11.Cu")
		(net "M_J_DQ<3>")
	)
	(segment
		(start 39.977568 -6.223)
		(end 40.26662 -6.512052)
		(width 0.14224)
		(layer "In11.Cu")
		(net "M_J_DQ<3>")
	)
	(segment
		(start 40.26662 -6.512052)
		(end 40.26662 -7.289546)
		(width 0.14224)
		(layer "In11.Cu")
		(net "M_J_DQ<3>")
	)
	(segment
		(start 40.25392 -9.019794)
		(end 40.25392 -9.4234)
		(width 0.14224)
		(layer "In11.Cu")
		(net "M_J_DQ<3>")
	)
	(segment
		(start 56.271922 -54.995826)
		(end 56.491378 -55.215282)
		(width 0.14224)
		(layer "In11.Cu")
		(net "M_J_DQ<3>")
	)
	(segment
		(start 59.011312 -56.421528)
		(end 59.23026 -56.421528)
		(width 0.14224)
		(layer "In11.Cu")
		(net "M_J_DQ<3>")
	)
	(segment
		(start 40.252142 -2.72415)
		(end 40.252142 0.581152)
		(width 0.14224)
		(layer "In11.Cu")
		(net "M_J_DQ<3>")
	)
	(segment
		(start 40.43172 -23.183596)
		(end 40.180768 -23.434548)
		(width 0.14224)
		(layer "In11.Cu")
		(net "M_J_DQ<3>")
	)
	(segment
		(start 64.017652 -61.20892)
		(end 65.808098 -61.20892)
		(width 0.14224)
		(layer "In11.Cu")
		(net "M_J_DQ<3>")
	)
	(segment
		(start 39.36619 1.8796)
		(end 39.36619 2.198116)
		(width 0.14224)
		(layer "In11.Cu")
		(net "M_J_DQ<3>")
	)
	(segment
		(start 56.819292 -54.01056)
		(end 56.819292 -54.229508)
		(width 0.14224)
		(layer "In11.Cu")
		(net "M_J_DQ<3>")
	)
	(segment
		(start 39.69639 1.5494)
		(end 39.36619 1.8796)
		(width 0.14224)
		(layer "In11.Cu")
		(net "M_J_DQ<3>")
	)
	(segment
		(start 40.358568 -21.2344)
		(end 40.25392 -21.339048)
		(width 0.14224)
		(layer "In11.Cu")
		(net "M_J_DQ<3>")
	)
	(segment
		(start 55.942484 -53.3527)
		(end 55.395114 -53.90007)
		(width 0.14224)
		(layer "In11.Cu")
		(net "M_J_DQ<3>")
	)
	(segment
		(start 54.518306 -53.24221)
		(end 54.737762 -53.461666)
		(width 0.14224)
		(layer "In11.Cu")
		(net "M_J_DQ<3>")
	)
	(segment
		(start 40.43172 -21.999956)
		(end 40.43172 -23.183596)
		(width 0.14224)
		(layer "In11.Cu")
		(net "M_J_DQ<3>")
	)
	(segment
		(start 57.6961 -54.887368)
		(end 57.6961 -55.106316)
		(width 0.14224)
		(layer "In11.Cu")
		(net "M_J_DQ<3>")
	)
	(arc
		(start 67.267836 -61.93409)
		(mid 67.393323 -61.854257)
		(end 67.484498 -61.736732)
		(width 0.0889)
		(layer "In11.Cu")
		(net "M_J_DQ<3>")
	)
	(arc
		(start 68.547996 -61.733938)
		(mid 68.894706 -61.934249)
		(end 69.241416 -61.733938)
		(width 0.0889)
		(layer "In11.Cu")
		(net "M_J_DQ<3>")
	)
	(arc
		(start 69.771006 -61.438536)
		(mid 70.05643 -61.522003)
		(end 70.265036 -61.733938)
		(width 0.0889)
		(layer "In11.Cu")
		(net "M_J_DQ<3>")
	)
	(arc
		(start 71.488046 -62.429136)
		(mid 71.77347 -62.512603)
		(end 71.982076 -62.724538)
		(width 0.0889)
		(layer "In11.Cu")
		(net "M_J_DQ<3>")
	)
	(arc
		(start 67.484498 -61.736732)
		(mid 67.630598 -61.554398)
		(end 67.833494 -61.438536)
		(width 0.0889)
		(layer "In11.Cu")
		(net "M_J_DQ<3>")
	)
	(arc
		(start 74.66584 -63.688976)
		(mid 74.773452 -63.632143)
		(end 74.89317 -63.610236)
		(width 0.0889)
		(layer "In11.Cu")
		(net "M_J_DQ<3>")
	)
	(arc
		(start 69.241416 -61.733938)
		(mid 69.450024 -61.522006)
		(end 69.735446 -61.438536)
		(width 0.0889)
		(layer "In11.Cu")
		(net "M_J_DQ<3>")
	)
	(arc
		(start 68.053966 -61.438536)
		(mid 68.33939 -61.522003)
		(end 68.547996 -61.733938)
		(width 0.0889)
		(layer "In11.Cu")
		(net "M_J_DQ<3>")
	)
	(arc
		(start 71.123556 -62.229238)
		(mid 71.263635 -62.371974)
		(end 71.45528 -62.429136)
		(width 0.0889)
		(layer "In11.Cu")
		(net "M_J_DQ<3>")
	)
	(arc
		(start 70.265036 -61.733938)
		(mid 70.406719 -61.877742)
		(end 70.60057 -61.93409)
		(width 0.0889)
		(layer "In11.Cu")
		(net "M_J_DQ<3>")
	)
	(arc
		(start 70.633336 -61.93409)
		(mid 70.916553 -62.018371)
		(end 71.123556 -62.229238)
		(width 0.0889)
		(layer "In11.Cu")
		(net "M_J_DQ<3>")
	)
	(arc
		(start 72.350376 -62.92469)
		(mid 72.633593 -63.008971)
		(end 72.840596 -63.219838)
		(width 0.0889)
		(layer "In11.Cu")
		(net "M_J_DQ<3>")
	)
	(arc
		(start 72.840596 -63.219838)
		(mid 72.980675 -63.362574)
		(end 73.17232 -63.419736)
		(width 0.0889)
		(layer "In11.Cu")
		(net "M_J_DQ<3>")
	)
	(arc
		(start 73.699116 -63.715138)
		(mid 73.840799 -63.858942)
		(end 74.03465 -63.91529)
		(width 0.0889)
		(layer "In11.Cu")
		(net "M_J_DQ<3>")
	)
	(arc
		(start 71.982076 -62.724538)
		(mid 72.123759 -62.868342)
		(end 72.31761 -62.92469)
		(width 0.0889)
		(layer "In11.Cu")
		(net "M_J_DQ<3>")
	)
	(arc
		(start 73.205086 -63.419736)
		(mid 73.49051 -63.503203)
		(end 73.699116 -63.715138)
		(width 0.0889)
		(layer "In11.Cu")
		(net "M_J_DQ<3>")
	)
	(segment
		(start 120.649492 3.778758)
		(end 120.649492 2.514854)
		(width 0.1651)
		(layer "F.Cu")
		(net "M_J_DQ<39>")
	)
	(segment
		(start 110.485682 -61.352938)
		(end 109.914182 -61.352938)
		(width 0.0889)
		(layer "F.Cu")
		(net "M_J_DQ<39>")
	)
	(via
		(at 121.499376 -3.076956)
		(size 0.508)
		(drill 0.254)
		(layers "F.Cu" "B.Cu")
		(net "M_J_DQ<39>")
	)
	(via
		(at 109.914182 -61.352938)
		(size 0.508)
		(drill 0.254)
		(layers "F.Cu" "B.Cu")
		(net "M_J_DQ<39>")
	)
	(via
		(at 120.649492 2.514854)
		(size 0.508)
		(drill 0.254)
		(layers "F.Cu" "B.Cu")
		(net "M_J_DQ<39>")
	)
	(segment
		(start 121.499376 -1.021842)
		(end 121.499376 -3.076956)
		(width 0.1651)
		(layer "B.Cu")
		(net "M_J_DQ<39>")
	)
	(segment
		(start 110.425992 -56.695086)
		(end 110.432342 -56.684418)
		(width 0.0889)
		(layer "In11.Cu")
		(net "M_J_DQ<39>")
	)
	(segment
		(start 121.867168 -23.30577)
		(end 122.055382 -23.117556)
		(width 0.14224)
		(layer "In11.Cu")
		(net "M_J_DQ<39>")
	)
	(segment
		(start 122.00763 1.0922)
		(end 121.55043 1.5494)
		(width 0.14224)
		(layer "In11.Cu")
		(net "M_J_DQ<39>")
	)
	(segment
		(start 121.852182 -21.2852)
		(end 121.943368 -21.194014)
		(width 0.14224)
		(layer "In11.Cu")
		(net "M_J_DQ<39>")
	)
	(segment
		(start 121.943368 -21.194014)
		(end 121.943368 -19.0754)
		(width 0.14224)
		(layer "In11.Cu")
		(net "M_J_DQ<39>")
	)
	(segment
		(start 121.987564 -12.305538)
		(end 121.852182 -12.170156)
		(width 0.14224)
		(layer "In11.Cu")
		(net "M_J_DQ<39>")
	)
	(segment
		(start 121.039382 -3.9497)
		(end 121.039382 -3.53695)
		(width 0.14224)
		(layer "In11.Cu")
		(net "M_J_DQ<39>")
	)
	(segment
		(start 111.075724 -48.74006)
		(end 111.589312 -48.226472)
		(width 0.0889)
		(layer "In11.Cu")
		(net "M_J_DQ<39>")
	)
	(segment
		(start 110.421674 -55.712106)
		(end 110.425992 -55.704486)
		(width 0.0889)
		(layer "In11.Cu")
		(net "M_J_DQ<39>")
	)
	(segment
		(start 111.589312 -47.514256)
		(end 111.828834 -47.274734)
		(width 0.0889)
		(layer "In11.Cu")
		(net "M_J_DQ<39>")
	)
	(segment
		(start 110.425992 -55.704486)
		(end 110.432342 -55.693818)
		(width 0.0889)
		(layer "In11.Cu")
		(net "M_J_DQ<39>")
	)
	(segment
		(start 121.852182 -18.984214)
		(end 121.852182 -18.582386)
		(width 0.14224)
		(layer "In11.Cu")
		(net "M_J_DQ<39>")
	)
	(segment
		(start 122.055382 -23.117556)
		(end 122.055382 -21.974556)
		(width 0.14224)
		(layer "In11.Cu")
		(net "M_J_DQ<39>")
	)
	(segment
		(start 121.29643 1.5494)
		(end 120.96623 1.8796)
		(width 0.14224)
		(layer "In11.Cu")
		(net "M_J_DQ<39>")
	)
	(segment
		(start 122.273568 -24.501856)
		(end 121.867168 -24.095456)
		(width 0.14224)
		(layer "In11.Cu")
		(net "M_J_DQ<39>")
	)
	(segment
		(start 121.852182 -12.170156)
		(end 121.852182 -11.749786)
		(width 0.14224)
		(layer "In11.Cu")
		(net "M_J_DQ<39>")
	)
	(segment
		(start 120.96623 1.8796)
		(end 120.96623 2.198116)
		(width 0.14224)
		(layer "In11.Cu")
		(net "M_J_DQ<39>")
	)
	(segment
		(start 121.852182 -18.582386)
		(end 122.080782 -18.353786)
		(width 0.14224)
		(layer "In11.Cu")
		(net "M_J_DQ<39>")
	)
	(segment
		(start 109.914182 -61.352938)
		(end 110.260892 -60.561982)
		(width 0.0889)
		(layer "In11.Cu")
		(net "M_J_DQ<39>")
	)
	(segment
		(start 121.867168 -24.095456)
		(end 121.867168 -23.30577)
		(width 0.14224)
		(layer "In11.Cu")
		(net "M_J_DQ<39>")
	)
	(segment
		(start 121.877582 -13.694156)
		(end 121.987564 -13.584174)
		(width 0.14224)
		(layer "In11.Cu")
		(net "M_J_DQ<39>")
	)
	(segment
		(start 121.867168 -4.777486)
		(end 121.039382 -3.9497)
		(width 0.14224)
		(layer "In11.Cu")
		(net "M_J_DQ<39>")
	)
	(segment
		(start 111.075724 -52.117244)
		(end 111.075724 -48.74006)
		(width 0.0889)
		(layer "In11.Cu")
		(net "M_J_DQ<39>")
	)
	(segment
		(start 110.372652 -53.9242)
		(end 110.372652 -52.820316)
		(width 0.0889)
		(layer "In11.Cu")
		(net "M_J_DQ<39>")
	)
	(segment
		(start 110.372652 -52.820316)
		(end 111.075724 -52.117244)
		(width 0.0889)
		(layer "In11.Cu")
		(net "M_J_DQ<39>")
	)
	(segment
		(start 122.080782 -7.492746)
		(end 121.867168 -7.279132)
		(width 0.14224)
		(layer "In11.Cu")
		(net "M_J_DQ<39>")
	)
	(segment
		(start 122.080782 -8.727186)
		(end 122.080782 -7.492746)
		(width 0.14224)
		(layer "In11.Cu")
		(net "M_J_DQ<39>")
	)
	(segment
		(start 121.852182 -9.33196)
		(end 121.852182 -8.955786)
		(width 0.14224)
		(layer "In11.Cu")
		(net "M_J_DQ<39>")
	)
	(segment
		(start 122.019568 -9.499346)
		(end 121.852182 -9.33196)
		(width 0.14224)
		(layer "In11.Cu")
		(net "M_J_DQ<39>")
	)
	(segment
		(start 122.00763 0.7366)
		(end 122.00763 1.0922)
		(width 0.14224)
		(layer "In11.Cu")
		(net "M_J_DQ<39>")
	)
	(segment
		(start 121.039382 -3.53695)
		(end 121.499376 -3.076956)
		(width 0.14224)
		(layer "In11.Cu")
		(net "M_J_DQ<39>")
	)
	(segment
		(start 111.589312 -48.226472)
		(end 111.589312 -47.514256)
		(width 0.0889)
		(layer "In11.Cu")
		(net "M_J_DQ<39>")
	)
	(segment
		(start 113.11128 -42.99331)
		(end 113.11128 -39.178484)
		(width 0.14224)
		(layer "In11.Cu")
		(net "M_J_DQ<39>")
	)
	(segment
		(start 110.421166 -56.703722)
		(end 110.425992 -56.695086)
		(width 0.0889)
		(layer "In11.Cu")
		(net "M_J_DQ<39>")
	)
	(segment
		(start 122.019568 -11.5824)
		(end 122.019568 -9.499346)
		(width 0.14224)
		(layer "In11.Cu")
		(net "M_J_DQ<39>")
	)
	(segment
		(start 121.852182 -21.771356)
		(end 121.852182 -21.2852)
		(width 0.14224)
		(layer "In11.Cu")
		(net "M_J_DQ<39>")
	)
	(segment
		(start 122.273568 -30.016196)
		(end 122.273568 -24.501856)
		(width 0.14224)
		(layer "In11.Cu")
		(net "M_J_DQ<39>")
	)
	(segment
		(start 122.080782 -17.093946)
		(end 121.877582 -16.890746)
		(width 0.14224)
		(layer "In11.Cu")
		(net "M_J_DQ<39>")
	)
	(segment
		(start 113.11128 -39.178484)
		(end 122.273568 -30.016196)
		(width 0.14224)
		(layer "In11.Cu")
		(net "M_J_DQ<39>")
	)
	(segment
		(start 121.867168 -7.279132)
		(end 121.867168 -4.777486)
		(width 0.14224)
		(layer "In11.Cu")
		(net "M_J_DQ<39>")
	)
	(segment
		(start 111.828834 -47.274734)
		(end 111.828834 -44.275756)
		(width 0.14224)
		(layer "In11.Cu")
		(net "M_J_DQ<39>")
	)
	(segment
		(start 122.080782 -18.353786)
		(end 122.080782 -17.093946)
		(width 0.14224)
		(layer "In11.Cu")
		(net "M_J_DQ<39>")
	)
	(segment
		(start 121.852182 0.581152)
		(end 122.00763 0.7366)
		(width 0.14224)
		(layer "In11.Cu")
		(net "M_J_DQ<39>")
	)
	(segment
		(start 110.425992 -54.713886)
		(end 110.432342 -54.703218)
		(width 0.0889)
		(layer "In11.Cu")
		(net "M_J_DQ<39>")
	)
	(segment
		(start 111.828834 -44.275756)
		(end 113.11128 -42.99331)
		(width 0.14224)
		(layer "In11.Cu")
		(net "M_J_DQ<39>")
	)
	(segment
		(start 110.421166 -55.713122)
		(end 110.421674 -55.712106)
		(width 0.0889)
		(layer "In11.Cu")
		(net "M_J_DQ<39>")
	)
	(segment
		(start 121.943368 -19.0754)
		(end 121.852182 -18.984214)
		(width 0.14224)
		(layer "In11.Cu")
		(net "M_J_DQ<39>")
	)
	(segment
		(start 110.421166 -54.722522)
		(end 110.425992 -54.713886)
		(width 0.0889)
		(layer "In11.Cu")
		(net "M_J_DQ<39>")
	)
	(segment
		(start 121.852182 -11.749786)
		(end 122.019568 -11.5824)
		(width 0.14224)
		(layer "In11.Cu")
		(net "M_J_DQ<39>")
	)
	(segment
		(start 122.055382 -21.974556)
		(end 121.852182 -21.771356)
		(width 0.14224)
		(layer "In11.Cu")
		(net "M_J_DQ<39>")
	)
	(segment
		(start 110.425992 -57.685686)
		(end 110.432342 -57.675018)
		(width 0.0889)
		(layer "In11.Cu")
		(net "M_J_DQ<39>")
	)
	(segment
		(start 110.421166 -57.694322)
		(end 110.425992 -57.685686)
		(width 0.0889)
		(layer "In11.Cu")
		(net "M_J_DQ<39>")
	)
	(segment
		(start 121.852182 -8.955786)
		(end 122.080782 -8.727186)
		(width 0.14224)
		(layer "In11.Cu")
		(net "M_J_DQ<39>")
	)
	(segment
		(start 121.55043 1.5494)
		(end 121.29643 1.5494)
		(width 0.14224)
		(layer "In11.Cu")
		(net "M_J_DQ<39>")
	)
	(segment
		(start 120.96623 2.198116)
		(end 120.649492 2.514854)
		(width 0.14224)
		(layer "In11.Cu")
		(net "M_J_DQ<39>")
	)
	(segment
		(start 121.877582 -16.890746)
		(end 121.877582 -13.694156)
		(width 0.14224)
		(layer "In11.Cu")
		(net "M_J_DQ<39>")
	)
	(segment
		(start 121.987564 -13.584174)
		(end 121.987564 -12.305538)
		(width 0.14224)
		(layer "In11.Cu")
		(net "M_J_DQ<39>")
	)
	(segment
		(start 121.852182 -2.72415)
		(end 121.852182 0.581152)
		(width 0.14224)
		(layer "In11.Cu")
		(net "M_J_DQ<39>")
	)
	(segment
		(start 121.499376 -3.076956)
		(end 121.852182 -2.72415)
		(width 0.14224)
		(layer "In11.Cu")
		(net "M_J_DQ<39>")
	)
	(arc
		(start 110.30839 -60.293504)
		(mid 110.313721 -59.970158)
		(end 110.425992 -59.666886)
		(width 0.0889)
		(layer "In11.Cu")
		(net "M_J_DQ<39>")
	)
	(arc
		(start 110.425992 -58.676286)
		(mid 110.505123 -58.380884)
		(end 110.425992 -58.085482)
		(width 0.0889)
		(layer "In11.Cu")
		(net "M_J_DQ<39>")
	)
	(arc
		(start 110.425992 -59.666886)
		(mid 110.505123 -59.371484)
		(end 110.425992 -59.076082)
		(width 0.0889)
		(layer "In11.Cu")
		(net "M_J_DQ<39>")
	)
	(arc
		(start 110.425992 -59.076082)
		(mid 110.372493 -58.876184)
		(end 110.425992 -58.676286)
		(width 0.0889)
		(layer "In11.Cu")
		(net "M_J_DQ<39>")
	)
	(arc
		(start 110.425992 -57.095136)
		(mid 110.372522 -56.900073)
		(end 110.421166 -56.703722)
		(width 0.0889)
		(layer "In11.Cu")
		(net "M_J_DQ<39>")
	)
	(arc
		(start 110.432342 -57.675018)
		(mid 110.50514 -57.384255)
		(end 110.425992 -57.095136)
		(width 0.0889)
		(layer "In11.Cu")
		(net "M_J_DQ<39>")
	)
	(arc
		(start 110.425992 -56.104536)
		(mid 110.372522 -55.909473)
		(end 110.421166 -55.713122)
		(width 0.0889)
		(layer "In11.Cu")
		(net "M_J_DQ<39>")
	)
	(arc
		(start 110.260892 -60.561982)
		(mid 110.308252 -60.431913)
		(end 110.30839 -60.293504)
		(width 0.0889)
		(layer "In11.Cu")
		(net "M_J_DQ<39>")
	)
	(arc
		(start 110.432342 -56.684418)
		(mid 110.50514 -56.393655)
		(end 110.425992 -56.104536)
		(width 0.0889)
		(layer "In11.Cu")
		(net "M_J_DQ<39>")
	)
	(arc
		(start 110.425992 -58.085482)
		(mid 110.372456 -57.890531)
		(end 110.421166 -57.694322)
		(width 0.0889)
		(layer "In11.Cu")
		(net "M_J_DQ<39>")
	)
	(arc
		(start 110.425992 -55.113936)
		(mid 110.372522 -54.918873)
		(end 110.421166 -54.722522)
		(width 0.0889)
		(layer "In11.Cu")
		(net "M_J_DQ<39>")
	)
	(arc
		(start 110.425992 -54.123336)
		(mid 110.386231 -54.027276)
		(end 110.372652 -53.9242)
		(width 0.0889)
		(layer "In11.Cu")
		(net "M_J_DQ<39>")
	)
	(arc
		(start 110.432342 -55.693818)
		(mid 110.50514 -55.403055)
		(end 110.425992 -55.113936)
		(width 0.0889)
		(layer "In11.Cu")
		(net "M_J_DQ<39>")
	)
	(arc
		(start 110.432342 -54.703218)
		(mid 110.50514 -54.412455)
		(end 110.425992 -54.123336)
		(width 0.0889)
		(layer "In11.Cu")
		(net "M_J_DQ<39>")
	)
	(segment
		(start 121.49963 0.1524)
		(end 121.63171 0.28448)
		(width 0.1651)
		(layer "F.Cu")
		(net "M_J_DQ<38>")
	)
	(segment
		(start 121.49963 0.939546)
		(end 121.499376 0.9398)
		(width 0.1651)
		(layer "F.Cu")
		(net "M_J_DQ<38>")
	)
	(segment
		(start 121.499376 -0.821182)
		(end 121.49963 -0.820928)
		(width 0.1651)
		(layer "F.Cu")
		(net "M_J_DQ<38>")
	)
	(segment
		(start 121.63171 0.50292)
		(end 121.49963 0.635)
		(width 0.1651)
		(layer "F.Cu")
		(net "M_J_DQ<38>")
	)
	(segment
		(start 121.63171 0.28448)
		(end 121.63171 0.50292)
		(width 0.1651)
		(layer "F.Cu")
		(net "M_J_DQ<38>")
	)
	(segment
		(start 121.49963 0.635)
		(end 121.49963 0.939546)
		(width 0.1651)
		(layer "F.Cu")
		(net "M_J_DQ<38>")
	)
	(segment
		(start 110.485682 -59.371484)
		(end 109.914182 -59.371484)
		(width 0.0889)
		(layer "F.Cu")
		(net "M_J_DQ<38>")
	)
	(segment
		(start 121.49963 -0.820928)
		(end 121.49963 0.1524)
		(width 0.1651)
		(layer "F.Cu")
		(net "M_J_DQ<38>")
	)
	(via
		(at 120.649492 -4.357878)
		(size 0.508)
		(drill 0.254)
		(layers "F.Cu" "B.Cu")
		(net "M_J_DQ<38>")
	)
	(via
		(at 121.499376 0.9398)
		(size 0.508)
		(drill 0.254)
		(layers "F.Cu" "B.Cu")
		(net "M_J_DQ<38>")
	)
	(via
		(at 109.914182 -59.371484)
		(size 0.508)
		(drill 0.254)
		(layers "F.Cu" "B.Cu")
		(net "M_J_DQ<38>")
	)
	(segment
		(start 120.649492 -5.621782)
		(end 120.649492 -4.357878)
		(width 0.1651)
		(layer "B.Cu")
		(net "M_J_DQ<38>")
	)
	(segment
		(start 121.130568 -25.7556)
		(end 121.130568 -23.284942)
		(width 0.14224)
		(layer "In11.Cu")
		(net "M_J_DQ<38>")
	)
	(segment
		(start 121.282968 -7.12216)
		(end 121.282968 -4.991354)
		(width 0.14224)
		(layer "In11.Cu")
		(net "M_J_DQ<38>")
	)
	(segment
		(start 121.115582 -13.668756)
		(end 121.013982 -13.567156)
		(width 0.14224)
		(layer "In11.Cu")
		(net "M_J_DQ<38>")
	)
	(segment
		(start 121.186448 -2.203196)
		(end 120.760998 -1.777746)
		(width 0.14224)
		(layer "In11.Cu")
		(net "M_J_DQ<38>")
	)
	(segment
		(start 121.013982 -12.373356)
		(end 121.217182 -12.170156)
		(width 0.14224)
		(layer "In11.Cu")
		(net "M_J_DQ<38>")
	)
	(segment
		(start 120.952768 -21.1582)
		(end 120.952768 -19.177)
		(width 0.14224)
		(layer "In11.Cu")
		(net "M_J_DQ<38>")
	)
	(segment
		(start 110.885732 -48.660558)
		(end 111.398812 -48.147478)
		(width 0.0889)
		(layer "In11.Cu")
		(net "M_J_DQ<38>")
	)
	(segment
		(start 120.815608 -0.44196)
		(end 120.760998 -0.387096)
		(width 0.14224)
		(layer "In11.Cu")
		(net "M_J_DQ<38>")
	)
	(segment
		(start 111.348774 -43.18508)
		(end 111.717328 -43.18508)
		(width 0.14224)
		(layer "In11.Cu")
		(net "M_J_DQ<38>")
	)
	(segment
		(start 120.800368 -29.337)
		(end 120.800368 -29.121608)
		(width 0.14224)
		(layer "In11.Cu")
		(net "M_J_DQ<38>")
	)
	(segment
		(start 120.927368 -7.47776)
		(end 121.282968 -7.12216)
		(width 0.14224)
		(layer "In11.Cu")
		(net "M_J_DQ<38>")
	)
	(segment
		(start 110.260892 -57.590436)
		(end 110.265718 -57.5818)
		(width 0.0889)
		(layer "In11.Cu")
		(net "M_J_DQ<38>")
	)
	(segment
		(start 110.254542 -56.610504)
		(end 110.260892 -56.599836)
		(width 0.0889)
		(layer "In11.Cu")
		(net "M_J_DQ<38>")
	)
	(segment
		(start 121.282968 -4.991354)
		(end 120.649492 -4.357878)
		(width 0.14224)
		(layer "In11.Cu")
		(net "M_J_DQ<38>")
	)
	(segment
		(start 120.952768 -19.177)
		(end 121.217182 -18.912586)
		(width 0.14224)
		(layer "In11.Cu")
		(net "M_J_DQ<38>")
	)
	(segment
		(start 111.398812 -48.147478)
		(end 111.398812 -47.418244)
		(width 0.0889)
		(layer "In11.Cu")
		(net "M_J_DQ<38>")
	)
	(segment
		(start 120.927368 -22.06117)
		(end 121.217182 -21.771356)
		(width 0.14224)
		(layer "In11.Cu")
		(net "M_J_DQ<38>")
	)
	(segment
		(start 121.217182 -21.771356)
		(end 121.217182 -21.422614)
		(width 0.14224)
		(layer "In11.Cu")
		(net "M_J_DQ<38>")
	)
	(segment
		(start 121.003568 -9.626854)
		(end 121.217182 -9.41324)
		(width 0.14224)
		(layer "In11.Cu")
		(net "M_J_DQ<38>")
	)
	(segment
		(start 111.859568 -42.53738)
		(end 111.717328 -42.39514)
		(width 0.14224)
		(layer "In11.Cu")
		(net "M_J_DQ<38>")
	)
	(segment
		(start 111.859568 -43.04284)
		(end 111.859568 -42.53738)
		(width 0.14224)
		(layer "In11.Cu")
		(net "M_J_DQ<38>")
	)
	(segment
		(start 110.885732 -52.038504)
		(end 110.885732 -48.660558)
		(width 0.0889)
		(layer "In11.Cu")
		(net "M_J_DQ<38>")
	)
	(segment
		(start 110.260892 -55.609236)
		(end 110.265718 -55.6006)
		(width 0.0889)
		(layer "In11.Cu")
		(net "M_J_DQ<38>")
	)
	(segment
		(start 111.717328 -42.39514)
		(end 111.348774 -42.39514)
		(width 0.14224)
		(layer "In11.Cu")
		(net "M_J_DQ<38>")
	)
	(segment
		(start 110.260892 -56.599836)
		(end 110.265718 -56.5912)
		(width 0.0889)
		(layer "In11.Cu")
		(net "M_J_DQ<38>")
	)
	(segment
		(start 121.217182 -18.628614)
		(end 120.952768 -18.3642)
		(width 0.14224)
		(layer "In11.Cu")
		(net "M_J_DQ<38>")
	)
	(segment
		(start 121.74601 -28.715208)
		(end 121.74601 -28.308808)
		(width 0.14224)
		(layer "In11.Cu")
		(net "M_J_DQ<38>")
	)
	(segment
		(start 120.927368 -23.081742)
		(end 120.927368 -22.06117)
		(width 0.14224)
		(layer "In11.Cu")
		(net "M_J_DQ<38>")
	)
	(segment
		(start 120.41378 -3.327654)
		(end 121.186448 -2.554986)
		(width 0.14224)
		(layer "In11.Cu")
		(net "M_J_DQ<38>")
	)
	(segment
		(start 110.254542 -54.629304)
		(end 110.260892 -54.618636)
		(width 0.0889)
		(layer "In11.Cu")
		(net "M_J_DQ<38>")
	)
	(segment
		(start 121.54281 -28.918408)
		(end 121.74601 -28.715208)
		(width 0.14224)
		(layer "In11.Cu")
		(net "M_J_DQ<38>")
	)
	(segment
		(start 121.486168 -26.683208)
		(end 121.282968 -26.480008)
		(width 0.14224)
		(layer "In11.Cu")
		(net "M_J_DQ<38>")
	)
	(segment
		(start 120.800368 -26.0858)
		(end 121.130568 -25.7556)
		(width 0.14224)
		(layer "In11.Cu")
		(net "M_J_DQ<38>")
	)
	(segment
		(start 121.003568 -28.105608)
		(end 120.800368 -27.902408)
		(width 0.14224)
		(layer "In11.Cu")
		(net "M_J_DQ<38>")
	)
	(segment
		(start 111.193834 -43.34002)
		(end 111.348774 -43.18508)
		(width 0.14224)
		(layer "In11.Cu")
		(net "M_J_DQ<38>")
	)
	(segment
		(start 110.260892 -58.581036)
		(end 110.260892 -58.580782)
		(width 0.0889)
		(layer "In11.Cu")
		(net "M_J_DQ<38>")
	)
	(segment
		(start 121.003568 -26.480008)
		(end 120.800368 -26.276808)
		(width 0.14224)
		(layer "In11.Cu")
		(net "M_J_DQ<38>")
	)
	(segment
		(start 121.217182 -11.821414)
		(end 121.003568 -11.6078)
		(width 0.14224)
		(layer "In11.Cu")
		(net "M_J_DQ<38>")
	)
	(segment
		(start 120.800368 -26.276808)
		(end 120.800368 -26.0858)
		(width 0.14224)
		(layer "In11.Cu")
		(net "M_J_DQ<38>")
	)
	(segment
		(start 120.800368 -27.496008)
		(end 121.003568 -27.292808)
		(width 0.14224)
		(layer "In11.Cu")
		(net "M_J_DQ<38>")
	)
	(segment
		(start 121.217182 -21.422614)
		(end 120.952768 -21.1582)
		(width 0.14224)
		(layer "In11.Cu")
		(net "M_J_DQ<38>")
	)
	(segment
		(start 111.193834 -40.197786)
		(end 121.232168 -30.159452)
		(width 0.14224)
		(layer "In11.Cu")
		(net "M_J_DQ<38>")
	)
	(segment
		(start 111.717328 -43.18508)
		(end 111.859568 -43.04284)
		(width 0.14224)
		(layer "In11.Cu")
		(net "M_J_DQ<38>")
	)
	(segment
		(start 121.115582 -16.890746)
		(end 121.115582 -13.668756)
		(width 0.14224)
		(layer "In11.Cu")
		(net "M_J_DQ<38>")
	)
	(segment
		(start 121.232168 -30.159452)
		(end 121.232168 -29.7688)
		(width 0.14224)
		(layer "In11.Cu")
		(net "M_J_DQ<38>")
	)
	(segment
		(start 110.182152 -53.924962)
		(end 110.182152 -52.742084)
		(width 0.0889)
		(layer "In11.Cu")
		(net "M_J_DQ<38>")
	)
	(segment
		(start 120.952768 -17.05356)
		(end 121.115582 -16.890746)
		(width 0.14224)
		(layer "In11.Cu")
		(net "M_J_DQ<38>")
	)
	(segment
		(start 121.282968 -27.292808)
		(end 121.486168 -27.089608)
		(width 0.14224)
		(layer "In11.Cu")
		(net "M_J_DQ<38>")
	)
	(segment
		(start 120.760998 -1.492504)
		(end 121.141998 -1.111504)
		(width 0.14224)
		(layer "In11.Cu")
		(net "M_J_DQ<38>")
	)
	(segment
		(start 110.207298 -59.202574)
		(end 110.231174 -59.11342)
		(width 0.0889)
		(layer "In11.Cu")
		(net "M_J_DQ<38>")
	)
	(segment
		(start 111.348774 -42.39514)
		(end 111.193834 -42.2402)
		(width 0.14224)
		(layer "In11.Cu")
		(net "M_J_DQ<38>")
	)
	(segment
		(start 111.398812 -47.418244)
		(end 111.193834 -47.213266)
		(width 0.0889)
		(layer "In11.Cu")
		(net "M_J_DQ<38>")
	)
	(segment
		(start 111.193834 -42.2402)
		(end 111.193834 -40.197786)
		(width 0.14224)
		(layer "In11.Cu")
		(net "M_J_DQ<38>")
	)
	(segment
		(start 109.914182 -59.371484)
		(end 110.207298 -59.202574)
		(width 0.0889)
		(layer "In11.Cu")
		(net "M_J_DQ<38>")
	)
	(segment
		(start 121.217182 -9.41324)
		(end 121.217182 -9.027414)
		(width 0.14224)
		(layer "In11.Cu")
		(net "M_J_DQ<38>")
	)
	(segment
		(start 121.217182 -18.912586)
		(end 121.217182 -18.628614)
		(width 0.14224)
		(layer "In11.Cu")
		(net "M_J_DQ<38>")
	)
	(segment
		(start 110.260892 -54.618636)
		(end 110.265718 -54.61)
		(width 0.0889)
		(layer "In11.Cu")
		(net "M_J_DQ<38>")
	)
	(segment
		(start 121.003568 -27.292808)
		(end 121.282968 -27.292808)
		(width 0.14224)
		(layer "In11.Cu")
		(net "M_J_DQ<38>")
	)
	(segment
		(start 121.282968 -26.480008)
		(end 121.003568 -26.480008)
		(width 0.14224)
		(layer "In11.Cu")
		(net "M_J_DQ<38>")
	)
	(segment
		(start 120.760998 -1.777746)
		(end 120.760998 -1.492504)
		(width 0.14224)
		(layer "In11.Cu")
		(net "M_J_DQ<38>")
	)
	(segment
		(start 120.760998 -0.076454)
		(end 121.12498 0.287528)
		(width 0.14224)
		(layer "In11.Cu")
		(net "M_J_DQ<38>")
	)
	(segment
		(start 121.217182 -12.170156)
		(end 121.217182 -11.821414)
		(width 0.14224)
		(layer "In11.Cu")
		(net "M_J_DQ<38>")
	)
	(segment
		(start 121.013982 -13.567156)
		(end 121.013982 -12.373356)
		(width 0.14224)
		(layer "In11.Cu")
		(net "M_J_DQ<38>")
	)
	(segment
		(start 121.12498 0.565404)
		(end 121.499376 0.9398)
		(width 0.14224)
		(layer "In11.Cu")
		(net "M_J_DQ<38>")
	)
	(segment
		(start 121.74601 -28.308808)
		(end 121.54281 -28.105608)
		(width 0.14224)
		(layer "In11.Cu")
		(net "M_J_DQ<38>")
	)
	(segment
		(start 121.54281 -28.105608)
		(end 121.003568 -28.105608)
		(width 0.14224)
		(layer "In11.Cu")
		(net "M_J_DQ<38>")
	)
	(segment
		(start 120.649492 -4.357878)
		(end 120.41378 -4.122166)
		(width 0.14224)
		(layer "In11.Cu")
		(net "M_J_DQ<38>")
	)
	(segment
		(start 121.141998 -1.111504)
		(end 121.141998 -0.768096)
		(width 0.14224)
		(layer "In11.Cu")
		(net "M_J_DQ<38>")
	)
	(segment
		(start 121.003568 -11.6078)
		(end 121.003568 -9.626854)
		(width 0.14224)
		(layer "In11.Cu")
		(net "M_J_DQ<38>")
	)
	(segment
		(start 121.130568 -23.284942)
		(end 120.927368 -23.081742)
		(width 0.14224)
		(layer "In11.Cu")
		(net "M_J_DQ<38>")
	)
	(segment
		(start 120.952768 -18.3642)
		(end 120.952768 -17.05356)
		(width 0.14224)
		(layer "In11.Cu")
		(net "M_J_DQ<38>")
	)
	(segment
		(start 120.41378 -4.122166)
		(end 120.41378 -3.327654)
		(width 0.14224)
		(layer "In11.Cu")
		(net "M_J_DQ<38>")
	)
	(segment
		(start 121.217182 -9.027414)
		(end 120.927368 -8.7376)
		(width 0.14224)
		(layer "In11.Cu")
		(net "M_J_DQ<38>")
	)
	(segment
		(start 121.141998 -0.768096)
		(end 120.815608 -0.44196)
		(width 0.14224)
		(layer "In11.Cu")
		(net "M_J_DQ<38>")
	)
	(segment
		(start 121.003568 -28.918408)
		(end 121.54281 -28.918408)
		(width 0.14224)
		(layer "In11.Cu")
		(net "M_J_DQ<38>")
	)
	(segment
		(start 120.800368 -27.902408)
		(end 120.800368 -27.496008)
		(width 0.14224)
		(layer "In11.Cu")
		(net "M_J_DQ<38>")
	)
	(segment
		(start 110.254542 -55.619904)
		(end 110.260892 -55.609236)
		(width 0.0889)
		(layer "In11.Cu")
		(net "M_J_DQ<38>")
	)
	(segment
		(start 121.186448 -2.554986)
		(end 121.186448 -2.203196)
		(width 0.14224)
		(layer "In11.Cu")
		(net "M_J_DQ<38>")
	)
	(segment
		(start 120.760998 -0.387096)
		(end 120.760998 -0.076454)
		(width 0.14224)
		(layer "In11.Cu")
		(net "M_J_DQ<38>")
	)
	(segment
		(start 110.254542 -57.601104)
		(end 110.260892 -57.590436)
		(width 0.0889)
		(layer "In11.Cu")
		(net "M_J_DQ<38>")
	)
	(segment
		(start 120.927368 -8.7376)
		(end 120.927368 -7.47776)
		(width 0.14224)
		(layer "In11.Cu")
		(net "M_J_DQ<38>")
	)
	(segment
		(start 120.800368 -29.121608)
		(end 121.003568 -28.918408)
		(width 0.14224)
		(layer "In11.Cu")
		(net "M_J_DQ<38>")
	)
	(segment
		(start 121.232168 -29.7688)
		(end 120.800368 -29.337)
		(width 0.14224)
		(layer "In11.Cu")
		(net "M_J_DQ<38>")
	)
	(segment
		(start 121.486168 -27.089608)
		(end 121.486168 -26.683208)
		(width 0.14224)
		(layer "In11.Cu")
		(net "M_J_DQ<38>")
	)
	(segment
		(start 121.12498 0.287528)
		(end 121.12498 0.565404)
		(width 0.14224)
		(layer "In11.Cu")
		(net "M_J_DQ<38>")
	)
	(segment
		(start 110.182152 -52.742084)
		(end 110.885732 -52.038504)
		(width 0.0889)
		(layer "In11.Cu")
		(net "M_J_DQ<38>")
	)
	(segment
		(start 111.193834 -47.213266)
		(end 111.193834 -43.34002)
		(width 0.14224)
		(layer "In11.Cu")
		(net "M_J_DQ<38>")
	)
	(arc
		(start 110.260892 -56.199786)
		(mid 110.18167 -55.910668)
		(end 110.254542 -55.619904)
		(width 0.0889)
		(layer "In11.Cu")
		(net "M_J_DQ<38>")
	)
	(arc
		(start 110.265718 -54.61)
		(mid 110.314473 -54.413648)
		(end 110.260892 -54.218586)
		(width 0.0889)
		(layer "In11.Cu")
		(net "M_J_DQ<38>")
	)
	(arc
		(start 110.260892 -58.180986)
		(mid 110.181772 -57.891868)
		(end 110.254542 -57.601104)
		(width 0.0889)
		(layer "In11.Cu")
		(net "M_J_DQ<38>")
	)
	(arc
		(start 110.265718 -55.6006)
		(mid 110.314473 -55.404248)
		(end 110.260892 -55.209186)
		(width 0.0889)
		(layer "In11.Cu")
		(net "M_J_DQ<38>")
	)
	(arc
		(start 110.265718 -56.5912)
		(mid 110.314473 -56.394848)
		(end 110.260892 -56.199786)
		(width 0.0889)
		(layer "In11.Cu")
		(net "M_J_DQ<38>")
	)
	(arc
		(start 110.260892 -55.209186)
		(mid 110.18167 -54.920068)
		(end 110.254542 -54.629304)
		(width 0.0889)
		(layer "In11.Cu")
		(net "M_J_DQ<38>")
	)
	(arc
		(start 110.231174 -59.11342)
		(mid 110.182614 -58.843695)
		(end 110.260892 -58.581036)
		(width 0.0889)
		(layer "In11.Cu")
		(net "M_J_DQ<38>")
	)
	(arc
		(start 110.260892 -58.580782)
		(mid 110.314391 -58.380884)
		(end 110.260892 -58.180986)
		(width 0.0889)
		(layer "In11.Cu")
		(net "M_J_DQ<38>")
	)
	(arc
		(start 110.265718 -57.5818)
		(mid 110.314473 -57.385448)
		(end 110.260892 -57.190386)
		(width 0.0889)
		(layer "In11.Cu")
		(net "M_J_DQ<38>")
	)
	(arc
		(start 110.260892 -54.218586)
		(mid 110.202219 -54.076954)
		(end 110.182152 -53.924962)
		(width 0.0889)
		(layer "In11.Cu")
		(net "M_J_DQ<38>")
	)
	(arc
		(start 110.260892 -57.190386)
		(mid 110.18167 -56.901268)
		(end 110.254542 -56.610504)
		(width 0.0889)
		(layer "In11.Cu")
		(net "M_J_DQ<38>")
	)
	(segment
		(start 114.699542 3.778758)
		(end 114.699542 2.514854)
		(width 0.1651)
		(layer "F.Cu")
		(net "M_J_DQ<37>")
	)
	(segment
		(start 107.910376 -60.857384)
		(end 107.338876 -60.857384)
		(width 0.0889)
		(layer "F.Cu")
		(net "M_J_DQ<37>")
	)
	(via
		(at 107.338876 -60.857384)
		(size 0.508)
		(drill 0.254)
		(layers "F.Cu" "B.Cu")
		(net "M_J_DQ<37>")
	)
	(via
		(at 114.699542 2.514854)
		(size 0.508)
		(drill 0.254)
		(layers "F.Cu" "B.Cu")
		(net "M_J_DQ<37>")
	)
	(via
		(at 115.473226 -3.076956)
		(size 0.508)
		(drill 0.254)
		(layers "F.Cu" "B.Cu")
		(net "M_J_DQ<37>")
	)
	(segment
		(start 115.549426 -2.279142)
		(end 115.473226 -2.355342)
		(width 0.1651)
		(layer "B.Cu")
		(net "M_J_DQ<37>")
	)
	(segment
		(start 115.549426 -1.021842)
		(end 115.549426 -2.279142)
		(width 0.1651)
		(layer "B.Cu")
		(net "M_J_DQ<37>")
	)
	(segment
		(start 115.473226 -2.355342)
		(end 115.473226 -3.076956)
		(width 0.1651)
		(layer "B.Cu")
		(net "M_J_DQ<37>")
	)
	(segment
		(start 110.649766 -33.795716)
		(end 110.448598 -33.795716)
		(width 0.14224)
		(layer "In11.Cu")
		(net "M_J_DQ<37>")
	)
	(segment
		(start 115.946682 -12.113768)
		(end 115.946682 -13.617956)
		(width 0.14224)
		(layer "In11.Cu")
		(net "M_J_DQ<37>")
	)
	(segment
		(start 115.415568 -26.4668)
		(end 115.415568 -28.257246)
		(width 0.14224)
		(layer "In11.Cu")
		(net "M_J_DQ<37>")
	)
	(segment
		(start 110.090966 -34.354516)
		(end 110.652814 -34.916364)
		(width 0.14224)
		(layer "In11.Cu")
		(net "M_J_DQ<37>")
	)
	(segment
		(start 115.870736 -26.011632)
		(end 115.415568 -26.4668)
		(width 0.14224)
		(layer "In11.Cu")
		(net "M_J_DQ<37>")
	)
	(segment
		(start 115.364768 -6.0452)
		(end 115.883182 -6.563614)
		(width 0.14224)
		(layer "In11.Cu")
		(net "M_J_DQ<37>")
	)
	(segment
		(start 107.070906 -54.57698)
		(end 106.98734 -54.722522)
		(width 0.0889)
		(layer "In11.Cu")
		(net "M_J_DQ<37>")
	)
	(segment
		(start 107.033568 -59.147964)
		(end 107.452414 -59.48299)
		(width 0.0889)
		(layer "In11.Cu")
		(net "M_J_DQ<37>")
	)
	(segment
		(start 115.802918 -21.82495)
		(end 115.967764 -21.989796)
		(width 0.14224)
		(layer "In11.Cu")
		(net "M_J_DQ<37>")
	)
	(segment
		(start 110.448598 -33.795716)
		(end 110.090966 -34.153348)
		(width 0.14224)
		(layer "In11.Cu")
		(net "M_J_DQ<37>")
	)
	(segment
		(start 115.923568 -16.905732)
		(end 115.946682 -16.928846)
		(width 0.14224)
		(layer "In11.Cu")
		(net "M_J_DQ<37>")
	)
	(segment
		(start 115.78463 0.53975)
		(end 115.78463 -2.765552)
		(width 0.14224)
		(layer "In11.Cu")
		(net "M_J_DQ<37>")
	)
	(segment
		(start 115.857782 -12.024868)
		(end 115.946682 -12.113768)
		(width 0.14224)
		(layer "In11.Cu")
		(net "M_J_DQ<37>")
	)
	(segment
		(start 115.883182 -6.563614)
		(end 115.883182 -7.264146)
		(width 0.14224)
		(layer "In11.Cu")
		(net "M_J_DQ<37>")
	)
	(segment
		(start 106.998516 -56.684418)
		(end 106.992166 -56.695086)
		(width 0.0889)
		(layer "In11.Cu")
		(net "M_J_DQ<37>")
	)
	(segment
		(start 110.090966 -34.153348)
		(end 110.090966 -34.354516)
		(width 0.14224)
		(layer "In11.Cu")
		(net "M_J_DQ<37>")
	)
	(segment
		(start 115.78463 -2.765552)
		(end 115.473226 -3.076956)
		(width 0.14224)
		(layer "In11.Cu")
		(net "M_J_DQ<37>")
	)
	(segment
		(start 110.652814 -34.916364)
		(end 110.652814 -35.135312)
		(width 0.14224)
		(layer "In11.Cu")
		(net "M_J_DQ<37>")
	)
	(segment
		(start 115.946682 -7.327646)
		(end 115.946682 -8.902446)
		(width 0.14224)
		(layer "In11.Cu")
		(net "M_J_DQ<37>")
	)
	(segment
		(start 107.685586 -60.066936)
		(end 107.668822 -60.095638)
		(width 0.0889)
		(layer "In11.Cu")
		(net "M_J_DQ<37>")
	)
	(segment
		(start 115.27028 1.5494)
		(end 115.581176 1.5494)
		(width 0.14224)
		(layer "In11.Cu")
		(net "M_J_DQ<37>")
	)
	(segment
		(start 115.364768 -4.336542)
		(end 115.364768 -6.0452)
		(width 0.14224)
		(layer "In11.Cu")
		(net "M_J_DQ<37>")
	)
	(segment
		(start 107.696 -51.160426)
		(end 107.011978 -51.844448)
		(width 0.0889)
		(layer "In11.Cu")
		(net "M_J_DQ<37>")
	)
	(segment
		(start 115.946682 -8.902446)
		(end 115.857782 -8.991346)
		(width 0.14224)
		(layer "In11.Cu")
		(net "M_J_DQ<37>")
	)
	(segment
		(start 106.998516 -57.675018)
		(end 106.992166 -57.685686)
		(width 0.0889)
		(layer "In11.Cu")
		(net "M_J_DQ<37>")
	)
	(segment
		(start 115.967764 -23.234396)
		(end 115.870736 -23.331424)
		(width 0.14224)
		(layer "In11.Cu")
		(net "M_J_DQ<37>")
	)
	(segment
		(start 115.857782 -11.7348)
		(end 115.857782 -12.024868)
		(width 0.14224)
		(layer "In11.Cu")
		(net "M_J_DQ<37>")
	)
	(segment
		(start 115.98148 1.149096)
		(end 115.98148 0.7366)
		(width 0.14224)
		(layer "In11.Cu")
		(net "M_J_DQ<37>")
	)
	(segment
		(start 115.946682 -13.617956)
		(end 115.923568 -13.64107)
		(width 0.14224)
		(layer "In11.Cu")
		(net "M_J_DQ<37>")
	)
	(segment
		(start 115.581176 1.5494)
		(end 115.98148 1.149096)
		(width 0.14224)
		(layer "In11.Cu")
		(net "M_J_DQ<37>")
	)
	(segment
		(start 115.923568 -13.64107)
		(end 115.923568 -16.905732)
		(width 0.14224)
		(layer "In11.Cu")
		(net "M_J_DQ<37>")
	)
	(segment
		(start 110.652814 -35.135312)
		(end 107.260136 -38.52799)
		(width 0.14224)
		(layer "In11.Cu")
		(net "M_J_DQ<37>")
	)
	(segment
		(start 115.999768 -18.9992)
		(end 115.999768 -21.2344)
		(width 0.14224)
		(layer "In11.Cu")
		(net "M_J_DQ<37>")
	)
	(segment
		(start 115.946682 -16.928846)
		(end 115.946682 -18.273268)
		(width 0.14224)
		(layer "In11.Cu")
		(net "M_J_DQ<37>")
	)
	(segment
		(start 114.968782 -3.940556)
		(end 115.364768 -4.336542)
		(width 0.14224)
		(layer "In11.Cu")
		(net "M_J_DQ<37>")
	)
	(segment
		(start 111.211614 -34.357564)
		(end 110.649766 -33.795716)
		(width 0.14224)
		(layer "In11.Cu")
		(net "M_J_DQ<37>")
	)
	(segment
		(start 111.430562 -34.357564)
		(end 111.211614 -34.357564)
		(width 0.14224)
		(layer "In11.Cu")
		(net "M_J_DQ<37>")
	)
	(segment
		(start 115.946682 -18.273268)
		(end 115.802918 -18.417032)
		(width 0.14224)
		(layer "In11.Cu")
		(net "M_J_DQ<37>")
	)
	(segment
		(start 107.668822 -60.095638)
		(end 107.338876 -60.857384)
		(width 0.0889)
		(layer "In11.Cu")
		(net "M_J_DQ<37>")
	)
	(segment
		(start 107.070906 -53.592476)
		(end 107.070906 -54.57698)
		(width 0.0889)
		(layer "In11.Cu")
		(net "M_J_DQ<37>")
	)
	(segment
		(start 106.992166 -59.076082)
		(end 107.033568 -59.147964)
		(width 0.0889)
		(layer "In11.Cu")
		(net "M_J_DQ<37>")
	)
	(segment
		(start 107.011978 -53.533548)
		(end 107.070906 -53.592476)
		(width 0.0889)
		(layer "In11.Cu")
		(net "M_J_DQ<37>")
	)
	(segment
		(start 114.699542 2.120138)
		(end 115.27028 1.5494)
		(width 0.14224)
		(layer "In11.Cu")
		(net "M_J_DQ<37>")
	)
	(segment
		(start 116.025168 -11.567414)
		(end 115.857782 -11.7348)
		(width 0.14224)
		(layer "In11.Cu")
		(net "M_J_DQ<37>")
	)
	(segment
		(start 115.802918 -18.80235)
		(end 115.999768 -18.9992)
		(width 0.14224)
		(layer "In11.Cu")
		(net "M_J_DQ<37>")
	)
	(segment
		(start 115.999768 -21.2344)
		(end 115.802918 -21.43125)
		(width 0.14224)
		(layer "In11.Cu")
		(net "M_J_DQ<37>")
	)
	(segment
		(start 107.260136 -38.52799)
		(end 107.260136 -48.108616)
		(width 0.14224)
		(layer "In11.Cu")
		(net "M_J_DQ<37>")
	)
	(segment
		(start 106.992166 -57.685686)
		(end 106.98734 -57.694322)
		(width 0.0889)
		(layer "In11.Cu")
		(net "M_J_DQ<37>")
	)
	(segment
		(start 107.123992 -48.332644)
		(end 107.123992 -48.64862)
		(width 0.0889)
		(layer "In11.Cu")
		(net "M_J_DQ<37>")
	)
	(segment
		(start 115.98148 0.7366)
		(end 115.78463 0.53975)
		(width 0.14224)
		(layer "In11.Cu")
		(net "M_J_DQ<37>")
	)
	(segment
		(start 115.857782 -8.991346)
		(end 115.857782 -9.383014)
		(width 0.14224)
		(layer "In11.Cu")
		(net "M_J_DQ<37>")
	)
	(segment
		(start 107.696 -49.220628)
		(end 107.696 -51.160426)
		(width 0.0889)
		(layer "In11.Cu")
		(net "M_J_DQ<37>")
	)
	(segment
		(start 115.967764 -21.989796)
		(end 115.967764 -23.234396)
		(width 0.14224)
		(layer "In11.Cu")
		(net "M_J_DQ<37>")
	)
	(segment
		(start 111.72444 -34.063686)
		(end 111.430562 -34.357564)
		(width 0.14224)
		(layer "In11.Cu")
		(net "M_J_DQ<37>")
	)
	(segment
		(start 115.883182 -7.264146)
		(end 115.946682 -7.327646)
		(width 0.14224)
		(layer "In11.Cu")
		(net "M_J_DQ<37>")
	)
	(segment
		(start 115.802918 -21.43125)
		(end 115.802918 -21.82495)
		(width 0.14224)
		(layer "In11.Cu")
		(net "M_J_DQ<37>")
	)
	(segment
		(start 115.473226 -3.076956)
		(end 114.968782 -3.5814)
		(width 0.14224)
		(layer "In11.Cu")
		(net "M_J_DQ<37>")
	)
	(segment
		(start 116.025168 -9.5504)
		(end 116.025168 -11.567414)
		(width 0.14224)
		(layer "In11.Cu")
		(net "M_J_DQ<37>")
	)
	(segment
		(start 107.260136 -48.108616)
		(end 107.304078 -48.152558)
		(width 0.14224)
		(layer "In11.Cu")
		(net "M_J_DQ<37>")
	)
	(segment
		(start 115.857782 -9.383014)
		(end 116.025168 -9.5504)
		(width 0.14224)
		(layer "In11.Cu")
		(net "M_J_DQ<37>")
	)
	(segment
		(start 106.998516 -55.693818)
		(end 106.992166 -55.704486)
		(width 0.0889)
		(layer "In11.Cu")
		(net "M_J_DQ<37>")
	)
	(segment
		(start 115.415568 -28.257246)
		(end 111.72444 -31.948374)
		(width 0.14224)
		(layer "In11.Cu")
		(net "M_J_DQ<37>")
	)
	(segment
		(start 107.304078 -48.152558)
		(end 107.123992 -48.332644)
		(width 0.0889)
		(layer "In11.Cu")
		(net "M_J_DQ<37>")
	)
	(segment
		(start 115.870736 -23.331424)
		(end 115.870736 -26.011632)
		(width 0.14224)
		(layer "In11.Cu")
		(net "M_J_DQ<37>")
	)
	(segment
		(start 114.968782 -3.5814)
		(end 114.968782 -3.940556)
		(width 0.14224)
		(layer "In11.Cu")
		(net "M_J_DQ<37>")
	)
	(segment
		(start 107.123992 -48.64862)
		(end 107.696 -49.220628)
		(width 0.0889)
		(layer "In11.Cu")
		(net "M_J_DQ<37>")
	)
	(segment
		(start 111.72444 -31.948374)
		(end 111.72444 -34.063686)
		(width 0.14224)
		(layer "In11.Cu")
		(net "M_J_DQ<37>")
	)
	(segment
		(start 106.992166 -55.704486)
		(end 106.98734 -55.713122)
		(width 0.0889)
		(layer "In11.Cu")
		(net "M_J_DQ<37>")
	)
	(segment
		(start 106.992166 -56.695086)
		(end 106.98734 -56.703722)
		(width 0.0889)
		(layer "In11.Cu")
		(net "M_J_DQ<37>")
	)
	(segment
		(start 115.802918 -18.417032)
		(end 115.802918 -18.80235)
		(width 0.14224)
		(layer "In11.Cu")
		(net "M_J_DQ<37>")
	)
	(segment
		(start 114.699542 2.514854)
		(end 114.699542 2.120138)
		(width 0.14224)
		(layer "In11.Cu")
		(net "M_J_DQ<37>")
	)
	(segment
		(start 107.011978 -51.844448)
		(end 107.011978 -53.533548)
		(width 0.0889)
		(layer "In11.Cu")
		(net "M_J_DQ<37>")
	)
	(arc
		(start 106.992166 -58.085482)
		(mid 107.071297 -58.380884)
		(end 106.992166 -58.676286)
		(width 0.0889)
		(layer "In11.Cu")
		(net "M_J_DQ<37>")
	)
	(arc
		(start 106.992166 -58.676286)
		(mid 106.938633 -58.876184)
		(end 106.992166 -59.076082)
		(width 0.0889)
		(layer "In11.Cu")
		(net "M_J_DQ<37>")
	)
	(arc
		(start 106.98734 -54.722522)
		(mid 106.938585 -54.918874)
		(end 106.992166 -55.113936)
		(width 0.0889)
		(layer "In11.Cu")
		(net "M_J_DQ<37>")
	)
	(arc
		(start 106.992166 -57.095136)
		(mid 107.071388 -57.384254)
		(end 106.998516 -57.675018)
		(width 0.0889)
		(layer "In11.Cu")
		(net "M_J_DQ<37>")
	)
	(arc
		(start 106.98734 -55.713122)
		(mid 106.938585 -55.909474)
		(end 106.992166 -56.104536)
		(width 0.0889)
		(layer "In11.Cu")
		(net "M_J_DQ<37>")
	)
	(arc
		(start 106.98734 -57.694322)
		(mid 106.938646 -57.89053)
		(end 106.992166 -58.085482)
		(width 0.0889)
		(layer "In11.Cu")
		(net "M_J_DQ<37>")
	)
	(arc
		(start 106.992166 -55.113936)
		(mid 107.071388 -55.403054)
		(end 106.998516 -55.693818)
		(width 0.0889)
		(layer "In11.Cu")
		(net "M_J_DQ<37>")
	)
	(arc
		(start 107.452414 -59.48299)
		(mid 107.710589 -59.7184)
		(end 107.685586 -60.066936)
		(width 0.0889)
		(layer "In11.Cu")
		(net "M_J_DQ<37>")
	)
	(arc
		(start 106.992166 -56.104536)
		(mid 107.071388 -56.393654)
		(end 106.998516 -56.684418)
		(width 0.0889)
		(layer "In11.Cu")
		(net "M_J_DQ<37>")
	)
	(arc
		(start 106.98734 -56.703722)
		(mid 106.938585 -56.900074)
		(end 106.992166 -57.095136)
		(width 0.0889)
		(layer "In11.Cu")
		(net "M_J_DQ<37>")
	)
	(segment
		(start 115.549426 -0.821182)
		(end 115.549426 0.510032)
		(width 0.1651)
		(layer "F.Cu")
		(net "M_J_DQ<36>")
	)
	(segment
		(start 107.910376 -59.866784)
		(end 107.338876 -59.866784)
		(width 0.0889)
		(layer "F.Cu")
		(net "M_J_DQ<36>")
	)
	(segment
		(start 115.549426 0.510032)
		(end 115.451382 1.0414)
		(width 0.1651)
		(layer "F.Cu")
		(net "M_J_DQ<36>")
	)
	(via
		(at 114.699542 -4.357878)
		(size 0.508)
		(drill 0.254)
		(layers "F.Cu" "B.Cu")
		(net "M_J_DQ<36>")
	)
	(via
		(at 115.451382 1.0414)
		(size 0.508)
		(drill 0.254)
		(layers "F.Cu" "B.Cu")
		(net "M_J_DQ<36>")
	)
	(via
		(at 107.338876 -59.866784)
		(size 0.508)
		(drill 0.254)
		(layers "F.Cu" "B.Cu")
		(net "M_J_DQ<36>")
	)
	(segment
		(start 114.699542 -5.621782)
		(end 114.699542 -4.357878)
		(width 0.1651)
		(layer "B.Cu")
		(net "M_J_DQ<36>")
	)
	(segment
		(start 107.5055 -49.299622)
		(end 107.5055 -51.081686)
		(width 0.0889)
		(layer "In11.Cu")
		(net "M_J_DQ<36>")
	)
	(segment
		(start 106.831892 -55.6006)
		(end 106.827066 -55.609236)
		(width 0.0889)
		(layer "In11.Cu")
		(net "M_J_DQ<36>")
	)
	(segment
		(start 106.831892 -56.5912)
		(end 106.827066 -56.599836)
		(width 0.0889)
		(layer "In11.Cu")
		(net "M_J_DQ<36>")
	)
	(segment
		(start 106.821732 -51.765454)
		(end 106.821732 -53.612034)
		(width 0.0889)
		(layer "In11.Cu")
		(net "M_J_DQ<36>")
	)
	(segment
		(start 115.212368 -7.2136)
		(end 114.968782 -7.457186)
		(width 0.14224)
		(layer "In11.Cu")
		(net "M_J_DQ<36>")
	)
	(segment
		(start 114.968782 -8.748014)
		(end 115.237768 -9.017)
		(width 0.14224)
		(layer "In11.Cu")
		(net "M_J_DQ<36>")
	)
	(segment
		(start 109.57941 -35.274758)
		(end 109.247686 -35.606482)
		(width 0.14224)
		(layer "In11.Cu")
		(net "M_J_DQ<36>")
	)
	(segment
		(start 115.167918 -18.556986)
		(end 115.167918 -18.99285)
		(width 0.14224)
		(layer "In11.Cu")
		(net "M_J_DQ<36>")
	)
	(segment
		(start 115.237768 -9.017)
		(end 115.237768 -9.3726)
		(width 0.14224)
		(layer "In11.Cu")
		(net "M_J_DQ<36>")
	)
	(segment
		(start 114.968782 -7.457186)
		(end 114.968782 -8.748014)
		(width 0.14224)
		(layer "In11.Cu")
		(net "M_J_DQ<36>")
	)
	(segment
		(start 115.003326 -13.507212)
		(end 115.390168 -13.894054)
		(width 0.14224)
		(layer "In11.Cu")
		(net "M_J_DQ<36>")
	)
	(segment
		(start 115.167918 -18.99285)
		(end 115.009168 -19.1516)
		(width 0.14224)
		(layer "In11.Cu")
		(net "M_J_DQ<36>")
	)
	(segment
		(start 114.823748 -1.790446)
		(end 115.17503 -2.141728)
		(width 0.14224)
		(layer "In11.Cu")
		(net "M_J_DQ<36>")
	)
	(segment
		(start 106.827066 -55.609236)
		(end 106.820716 -55.619904)
		(width 0.0889)
		(layer "In11.Cu")
		(net "M_J_DQ<36>")
	)
	(segment
		(start 115.179094 -23.309326)
		(end 115.179094 -25.670764)
		(width 0.14224)
		(layer "In11.Cu")
		(net "M_J_DQ<36>")
	)
	(segment
		(start 109.57941 -34.98723)
		(end 109.57941 -35.274758)
		(width 0.14224)
		(layer "In11.Cu")
		(net "M_J_DQ<36>")
	)
	(segment
		(start 114.699542 -6.294374)
		(end 115.212368 -6.8072)
		(width 0.14224)
		(layer "In11.Cu")
		(net "M_J_DQ<36>")
	)
	(segment
		(start 115.167918 -21.336)
		(end 115.167918 -21.799042)
		(width 0.14224)
		(layer "In11.Cu")
		(net "M_J_DQ<36>")
	)
	(segment
		(start 115.17503 0.765048)
		(end 115.17503 0.287528)
		(width 0.14224)
		(layer "In11.Cu")
		(net "M_J_DQ<36>")
	)
	(segment
		(start 108.300012 -36.554156)
		(end 106.625136 -38.229032)
		(width 0.14224)
		(layer "In11.Cu")
		(net "M_J_DQ<36>")
	)
	(segment
		(start 115.451382 1.0414)
		(end 115.17503 0.765048)
		(width 0.14224)
		(layer "In11.Cu")
		(net "M_J_DQ<36>")
	)
	(segment
		(start 106.625136 -38.229032)
		(end 106.625136 -48.108616)
		(width 0.14224)
		(layer "In11.Cu")
		(net "M_J_DQ<36>")
	)
	(segment
		(start 115.009168 -19.1516)
		(end 115.009168 -21.17725)
		(width 0.14224)
		(layer "In11.Cu")
		(net "M_J_DQ<36>")
	)
	(segment
		(start 115.003326 -12.273788)
		(end 115.003326 -13.507212)
		(width 0.14224)
		(layer "In11.Cu")
		(net "M_J_DQ<36>")
	)
	(segment
		(start 115.17503 0.287528)
		(end 114.811048 -0.076454)
		(width 0.14224)
		(layer "In11.Cu")
		(net "M_J_DQ<36>")
	)
	(segment
		(start 106.880406 -54.520846)
		(end 106.827066 -54.618636)
		(width 0.0889)
		(layer "In11.Cu")
		(net "M_J_DQ<36>")
	)
	(segment
		(start 114.755168 -28.092654)
		(end 108.924852 -33.92297)
		(width 0.14224)
		(layer "In11.Cu")
		(net "M_J_DQ<36>")
	)
	(segment
		(start 114.968782 -17.058386)
		(end 114.968782 -18.35785)
		(width 0.14224)
		(layer "In11.Cu")
		(net "M_J_DQ<36>")
	)
	(segment
		(start 115.17503 -2.616454)
		(end 114.46383 -3.327654)
		(width 0.14224)
		(layer "In11.Cu")
		(net "M_J_DQ<36>")
	)
	(segment
		(start 106.826812 -59.171586)
		(end 107.03687 -59.539124)
		(width 0.0889)
		(layer "In11.Cu")
		(net "M_J_DQ<36>")
	)
	(segment
		(start 115.237768 -11.7348)
		(end 115.237768 -12.039346)
		(width 0.14224)
		(layer "In11.Cu")
		(net "M_J_DQ<36>")
	)
	(segment
		(start 108.924852 -33.92297)
		(end 108.924852 -34.332672)
		(width 0.14224)
		(layer "In11.Cu")
		(net "M_J_DQ<36>")
	)
	(segment
		(start 115.002564 -21.964396)
		(end 115.002564 -23.132796)
		(width 0.14224)
		(layer "In11.Cu")
		(net "M_J_DQ<36>")
	)
	(segment
		(start 107.63377 -35.600386)
		(end 108.300012 -36.266628)
		(width 0.14224)
		(layer "In11.Cu")
		(net "M_J_DQ<36>")
	)
	(segment
		(start 115.179094 -25.670764)
		(end 114.755168 -26.09469)
		(width 0.14224)
		(layer "In11.Cu")
		(net "M_J_DQ<36>")
	)
	(segment
		(start 114.46383 -3.327654)
		(end 114.46383 -4.122166)
		(width 0.14224)
		(layer "In11.Cu")
		(net "M_J_DQ<36>")
	)
	(segment
		(start 108.006388 -34.94024)
		(end 107.63377 -35.312858)
		(width 0.14224)
		(layer "In11.Cu")
		(net "M_J_DQ<36>")
	)
	(segment
		(start 115.390168 -13.894054)
		(end 115.390168 -16.637)
		(width 0.14224)
		(layer "In11.Cu")
		(net "M_J_DQ<36>")
	)
	(segment
		(start 115.237768 -9.3726)
		(end 115.059968 -9.5504)
		(width 0.14224)
		(layer "In11.Cu")
		(net "M_J_DQ<36>")
	)
	(segment
		(start 115.212368 -6.8072)
		(end 115.212368 -7.2136)
		(width 0.14224)
		(layer "In11.Cu")
		(net "M_J_DQ<36>")
	)
	(segment
		(start 115.192048 -1.0668)
		(end 114.823748 -1.4351)
		(width 0.14224)
		(layer "In11.Cu")
		(net "M_J_DQ<36>")
	)
	(segment
		(start 114.811048 -0.381)
		(end 115.192048 -0.762)
		(width 0.14224)
		(layer "In11.Cu")
		(net "M_J_DQ<36>")
	)
	(segment
		(start 109.247686 -35.606482)
		(end 108.960158 -35.606482)
		(width 0.14224)
		(layer "In11.Cu")
		(net "M_J_DQ<36>")
	)
	(segment
		(start 108.300012 -36.266628)
		(end 108.300012 -36.554156)
		(width 0.14224)
		(layer "In11.Cu")
		(net "M_J_DQ<36>")
	)
	(segment
		(start 115.002564 -23.132796)
		(end 115.179094 -23.309326)
		(width 0.14224)
		(layer "In11.Cu")
		(net "M_J_DQ<36>")
	)
	(segment
		(start 107.63377 -35.312858)
		(end 107.63377 -35.600386)
		(width 0.14224)
		(layer "In11.Cu")
		(net "M_J_DQ<36>")
	)
	(segment
		(start 115.390168 -16.637)
		(end 114.968782 -17.058386)
		(width 0.14224)
		(layer "In11.Cu")
		(net "M_J_DQ<36>")
	)
	(segment
		(start 106.933492 -48.727614)
		(end 107.5055 -49.299622)
		(width 0.0889)
		(layer "In11.Cu")
		(net "M_J_DQ<36>")
	)
	(segment
		(start 106.827066 -56.599836)
		(end 106.820716 -56.610504)
		(width 0.0889)
		(layer "In11.Cu")
		(net "M_J_DQ<36>")
	)
	(segment
		(start 114.46383 -4.122166)
		(end 114.699542 -4.357878)
		(width 0.14224)
		(layer "In11.Cu")
		(net "M_J_DQ<36>")
	)
	(segment
		(start 108.293916 -34.94024)
		(end 108.006388 -34.94024)
		(width 0.14224)
		(layer "In11.Cu")
		(net "M_J_DQ<36>")
	)
	(segment
		(start 106.827066 -54.618636)
		(end 106.820716 -54.629304)
		(width 0.0889)
		(layer "In11.Cu")
		(net "M_J_DQ<36>")
	)
	(segment
		(start 106.827066 -57.590436)
		(end 106.820716 -57.601104)
		(width 0.0889)
		(layer "In11.Cu")
		(net "M_J_DQ<36>")
	)
	(segment
		(start 106.831892 -57.5818)
		(end 106.827066 -57.590436)
		(width 0.0889)
		(layer "In11.Cu")
		(net "M_J_DQ<36>")
	)
	(segment
		(start 114.968782 -18.35785)
		(end 115.167918 -18.556986)
		(width 0.14224)
		(layer "In11.Cu")
		(net "M_J_DQ<36>")
	)
	(segment
		(start 106.821732 -53.612034)
		(end 106.880406 -53.670708)
		(width 0.0889)
		(layer "In11.Cu")
		(net "M_J_DQ<36>")
	)
	(segment
		(start 108.924852 -34.332672)
		(end 109.57941 -34.98723)
		(width 0.14224)
		(layer "In11.Cu")
		(net "M_J_DQ<36>")
	)
	(segment
		(start 106.625136 -48.108616)
		(end 106.669078 -48.152558)
		(width 0.14224)
		(layer "In11.Cu")
		(net "M_J_DQ<36>")
	)
	(segment
		(start 114.699542 -4.357878)
		(end 114.699542 -6.294374)
		(width 0.14224)
		(layer "In11.Cu")
		(net "M_J_DQ<36>")
	)
	(segment
		(start 107.5055 -51.081686)
		(end 106.821732 -51.765454)
		(width 0.0889)
		(layer "In11.Cu")
		(net "M_J_DQ<36>")
	)
	(segment
		(start 115.17503 -2.141728)
		(end 115.17503 -2.616454)
		(width 0.14224)
		(layer "In11.Cu")
		(net "M_J_DQ<36>")
	)
	(segment
		(start 108.960158 -35.606482)
		(end 108.293916 -34.94024)
		(width 0.14224)
		(layer "In11.Cu")
		(net "M_J_DQ<36>")
	)
	(segment
		(start 107.049062 -59.555634)
		(end 107.338876 -59.866784)
		(width 0.0889)
		(layer "In11.Cu")
		(net "M_J_DQ<36>")
	)
	(segment
		(start 106.880406 -53.670708)
		(end 106.880406 -54.520846)
		(width 0.0889)
		(layer "In11.Cu")
		(net "M_J_DQ<36>")
	)
	(segment
		(start 115.237768 -12.039346)
		(end 115.003326 -12.273788)
		(width 0.14224)
		(layer "In11.Cu")
		(net "M_J_DQ<36>")
	)
	(segment
		(start 115.167918 -21.799042)
		(end 115.002564 -21.964396)
		(width 0.14224)
		(layer "In11.Cu")
		(net "M_J_DQ<36>")
	)
	(segment
		(start 106.933492 -48.416972)
		(end 106.933492 -48.727614)
		(width 0.0889)
		(layer "In11.Cu")
		(net "M_J_DQ<36>")
	)
	(segment
		(start 114.823748 -1.4351)
		(end 114.823748 -1.790446)
		(width 0.14224)
		(layer "In11.Cu")
		(net "M_J_DQ<36>")
	)
	(segment
		(start 115.059968 -11.557)
		(end 115.237768 -11.7348)
		(width 0.14224)
		(layer "In11.Cu")
		(net "M_J_DQ<36>")
	)
	(segment
		(start 115.059968 -9.5504)
		(end 115.059968 -11.557)
		(width 0.14224)
		(layer "In11.Cu")
		(net "M_J_DQ<36>")
	)
	(segment
		(start 115.009168 -21.17725)
		(end 115.167918 -21.336)
		(width 0.14224)
		(layer "In11.Cu")
		(net "M_J_DQ<36>")
	)
	(segment
		(start 114.811048 -0.076454)
		(end 114.811048 -0.381)
		(width 0.14224)
		(layer "In11.Cu")
		(net "M_J_DQ<36>")
	)
	(segment
		(start 114.755168 -26.09469)
		(end 114.755168 -28.092654)
		(width 0.14224)
		(layer "In11.Cu")
		(net "M_J_DQ<36>")
	)
	(segment
		(start 115.192048 -0.762)
		(end 115.192048 -1.0668)
		(width 0.14224)
		(layer "In11.Cu")
		(net "M_J_DQ<36>")
	)
	(segment
		(start 106.669078 -48.152558)
		(end 106.933492 -48.416972)
		(width 0.0889)
		(layer "In11.Cu")
		(net "M_J_DQ<36>")
	)
	(arc
		(start 106.820716 -57.601104)
		(mid 106.747761 -57.891838)
		(end 106.826812 -58.180986)
		(width 0.0889)
		(layer "In11.Cu")
		(net "M_J_DQ<36>")
	)
	(arc
		(start 106.826812 -58.580782)
		(mid 106.747681 -58.876184)
		(end 106.826812 -59.171586)
		(width 0.0889)
		(layer "In11.Cu")
		(net "M_J_DQ<36>")
	)
	(arc
		(start 106.827066 -56.199786)
		(mid 106.880536 -56.394849)
		(end 106.831892 -56.5912)
		(width 0.0889)
		(layer "In11.Cu")
		(net "M_J_DQ<36>")
	)
	(arc
		(start 106.827066 -57.190386)
		(mid 106.880536 -57.385449)
		(end 106.831892 -57.5818)
		(width 0.0889)
		(layer "In11.Cu")
		(net "M_J_DQ<36>")
	)
	(arc
		(start 106.820716 -56.610504)
		(mid 106.747918 -56.901267)
		(end 106.827066 -57.190386)
		(width 0.0889)
		(layer "In11.Cu")
		(net "M_J_DQ<36>")
	)
	(arc
		(start 106.820716 -54.629304)
		(mid 106.747918 -54.920067)
		(end 106.827066 -55.209186)
		(width 0.0889)
		(layer "In11.Cu")
		(net "M_J_DQ<36>")
	)
	(arc
		(start 106.827066 -55.209186)
		(mid 106.880536 -55.404249)
		(end 106.831892 -55.6006)
		(width 0.0889)
		(layer "In11.Cu")
		(net "M_J_DQ<36>")
	)
	(arc
		(start 106.826812 -58.180986)
		(mid 106.880345 -58.380884)
		(end 106.826812 -58.580782)
		(width 0.0889)
		(layer "In11.Cu")
		(net "M_J_DQ<36>")
	)
	(arc
		(start 107.03687 -59.539124)
		(mid 107.042483 -59.547736)
		(end 107.049062 -59.555634)
		(width 0.0889)
		(layer "In11.Cu")
		(net "M_J_DQ<36>")
	)
	(arc
		(start 106.820716 -55.619904)
		(mid 106.747918 -55.910667)
		(end 106.827066 -56.199786)
		(width 0.0889)
		(layer "In11.Cu")
		(net "M_J_DQ<36>")
	)
	(segment
		(start 111.344202 -60.857384)
		(end 110.772702 -60.857384)
		(width 0.0889)
		(layer "F.Cu")
		(net "M_J_DQ<35>")
	)
	(segment
		(start 122.349514 3.778758)
		(end 122.349514 2.514854)
		(width 0.1651)
		(layer "F.Cu")
		(net "M_J_DQ<35>")
	)
	(via
		(at 110.772702 -60.857384)
		(size 0.508)
		(drill 0.254)
		(layers "F.Cu" "B.Cu")
		(net "M_J_DQ<35>")
	)
	(via
		(at 123.199398 -3.076956)
		(size 0.508)
		(drill 0.254)
		(layers "F.Cu" "B.Cu")
		(net "M_J_DQ<35>")
	)
	(via
		(at 122.349514 2.514854)
		(size 0.508)
		(drill 0.254)
		(layers "F.Cu" "B.Cu")
		(net "M_J_DQ<35>")
	)
	(segment
		(start 123.199398 -1.021842)
		(end 123.199398 -3.076956)
		(width 0.1651)
		(layer "B.Cu")
		(net "M_J_DQ<35>")
	)
	(segment
		(start 111.284512 -58.581036)
		(end 111.279686 -58.5724)
		(width 0.0889)
		(layer "In11.Cu")
		(net "M_J_DQ<35>")
	)
	(segment
		(start 123.731782 -23.183596)
		(end 123.731782 -21.999956)
		(width 0.14224)
		(layer "In11.Cu")
		(net "M_J_DQ<35>")
	)
	(segment
		(start 123.695968 -19.1008)
		(end 123.553982 -18.958814)
		(width 0.14224)
		(layer "In11.Cu")
		(net "M_J_DQ<35>")
	)
	(segment
		(start 111.284512 -53.627782)
		(end 111.279686 -53.619146)
		(width 0.0889)
		(layer "In11.Cu")
		(net "M_J_DQ<35>")
	)
	(segment
		(start 123.518168 -13.72997)
		(end 123.663964 -13.584174)
		(width 0.14224)
		(layer "In11.Cu")
		(net "M_J_DQ<35>")
	)
	(segment
		(start 122.715782 -3.560572)
		(end 123.199398 -3.076956)
		(width 0.14224)
		(layer "In11.Cu")
		(net "M_J_DQ<35>")
	)
	(segment
		(start 111.290862 -55.619904)
		(end 111.284512 -55.609236)
		(width 0.0889)
		(layer "In11.Cu")
		(net "M_J_DQ<35>")
	)
	(segment
		(start 123.518168 -16.842232)
		(end 123.518168 -13.72997)
		(width 0.14224)
		(layer "In11.Cu")
		(net "M_J_DQ<35>")
	)
	(segment
		(start 122.666252 1.8796)
		(end 122.666252 2.198116)
		(width 0.14224)
		(layer "In11.Cu")
		(net "M_J_DQ<35>")
	)
	(segment
		(start 112.846612 -48.15078)
		(end 113.098834 -47.898558)
		(width 0.0889)
		(layer "In11.Cu")
		(net "M_J_DQ<35>")
	)
	(segment
		(start 123.695968 -21.194014)
		(end 123.695968 -19.1008)
		(width 0.14224)
		(layer "In11.Cu")
		(net "M_J_DQ<35>")
	)
	(segment
		(start 123.731782 -21.999956)
		(end 123.553982 -21.822156)
		(width 0.14224)
		(layer "In11.Cu")
		(net "M_J_DQ<35>")
	)
	(segment
		(start 116.16563 -37.920422)
		(end 123.543568 -30.542484)
		(width 0.14224)
		(layer "In11.Cu")
		(net "M_J_DQ<35>")
	)
	(segment
		(start 116.02339 -39.658798)
		(end 115.532408 -39.658798)
		(width 0.14224)
		(layer "In11.Cu")
		(net "M_J_DQ<35>")
	)
	(segment
		(start 123.553982 -18.958814)
		(end 123.553982 -18.582386)
		(width 0.14224)
		(layer "In11.Cu")
		(net "M_J_DQ<35>")
	)
	(segment
		(start 111.290862 -54.629304)
		(end 111.284512 -54.618636)
		(width 0.0889)
		(layer "In11.Cu")
		(net "M_J_DQ<35>")
	)
	(segment
		(start 123.416568 -9.1186)
		(end 123.706382 -8.828786)
		(width 0.14224)
		(layer "In11.Cu")
		(net "M_J_DQ<35>")
	)
	(segment
		(start 123.566682 -7.289546)
		(end 123.566682 -4.816856)
		(width 0.14224)
		(layer "In11.Cu")
		(net "M_J_DQ<35>")
	)
	(segment
		(start 111.284512 -59.171586)
		(end 111.290862 -59.160918)
		(width 0.0889)
		(layer "In11.Cu")
		(net "M_J_DQ<35>")
	)
	(segment
		(start 116.02339 -39.008558)
		(end 116.16563 -38.866318)
		(width 0.14224)
		(layer "In11.Cu")
		(net "M_J_DQ<35>")
	)
	(segment
		(start 122.715782 -3.965956)
		(end 122.715782 -3.560572)
		(width 0.14224)
		(layer "In11.Cu")
		(net "M_J_DQ<35>")
	)
	(segment
		(start 123.663964 -13.584174)
		(end 123.663964 -12.330938)
		(width 0.14224)
		(layer "In11.Cu")
		(net "M_J_DQ<35>")
	)
	(segment
		(start 116.16563 -38.866318)
		(end 116.16563 -37.920422)
		(width 0.14224)
		(layer "In11.Cu")
		(net "M_J_DQ<35>")
	)
	(segment
		(start 111.290862 -57.601104)
		(end 111.284512 -57.590436)
		(width 0.0889)
		(layer "In11.Cu")
		(net "M_J_DQ<35>")
	)
	(segment
		(start 115.532408 -39.658798)
		(end 115.390168 -39.516558)
		(width 0.14224)
		(layer "In11.Cu")
		(net "M_J_DQ<35>")
	)
	(segment
		(start 111.267748 -60.19165)
		(end 111.284512 -60.162186)
		(width 0.0889)
		(layer "In11.Cu")
		(net "M_J_DQ<35>")
	)
	(segment
		(start 111.290862 -56.610504)
		(end 111.284512 -56.599836)
		(width 0.0889)
		(layer "In11.Cu")
		(net "M_J_DQ<35>")
	)
	(segment
		(start 116.16563 -39.801038)
		(end 116.02339 -39.658798)
		(width 0.14224)
		(layer "In11.Cu")
		(net "M_J_DQ<35>")
	)
	(segment
		(start 123.250452 1.5494)
		(end 122.996452 1.5494)
		(width 0.14224)
		(layer "In11.Cu")
		(net "M_J_DQ<35>")
	)
	(segment
		(start 123.553982 -18.582386)
		(end 123.706382 -18.429986)
		(width 0.14224)
		(layer "In11.Cu")
		(net "M_J_DQ<35>")
	)
	(segment
		(start 123.553982 -21.822156)
		(end 123.553982 -21.336)
		(width 0.14224)
		(layer "In11.Cu")
		(net "M_J_DQ<35>")
	)
	(segment
		(start 123.706382 -17.030446)
		(end 123.518168 -16.842232)
		(width 0.14224)
		(layer "In11.Cu")
		(net "M_J_DQ<35>")
	)
	(segment
		(start 113.098834 -44.904152)
		(end 116.16563 -41.837356)
		(width 0.14224)
		(layer "In11.Cu")
		(net "M_J_DQ<35>")
	)
	(segment
		(start 111.230918 -53.047646)
		(end 111.800132 -52.478432)
		(width 0.0889)
		(layer "In11.Cu")
		(net "M_J_DQ<35>")
	)
	(segment
		(start 123.416568 -12.083542)
		(end 123.416568 -9.1186)
		(width 0.14224)
		(layer "In11.Cu")
		(net "M_J_DQ<35>")
	)
	(segment
		(start 123.706382 -8.828786)
		(end 123.706382 -7.429246)
		(width 0.14224)
		(layer "In11.Cu")
		(net "M_J_DQ<35>")
	)
	(segment
		(start 123.707652 0.7366)
		(end 123.707652 1.0922)
		(width 0.14224)
		(layer "In11.Cu")
		(net "M_J_DQ<35>")
	)
	(segment
		(start 112.846612 -48.43526)
		(end 112.846612 -48.15078)
		(width 0.0889)
		(layer "In11.Cu")
		(net "M_J_DQ<35>")
	)
	(segment
		(start 111.284512 -56.599836)
		(end 111.279686 -56.5912)
		(width 0.0889)
		(layer "In11.Cu")
		(net "M_J_DQ<35>")
	)
	(segment
		(start 122.996452 1.5494)
		(end 122.666252 1.8796)
		(width 0.14224)
		(layer "In11.Cu")
		(net "M_J_DQ<35>")
	)
	(segment
		(start 115.532408 -39.008558)
		(end 116.02339 -39.008558)
		(width 0.14224)
		(layer "In11.Cu")
		(net "M_J_DQ<35>")
	)
	(segment
		(start 123.552204 0.581152)
		(end 123.707652 0.7366)
		(width 0.14224)
		(layer "In11.Cu")
		(net "M_J_DQ<35>")
	)
	(segment
		(start 123.199398 -3.076956)
		(end 123.552204 -2.72415)
		(width 0.14224)
		(layer "In11.Cu")
		(net "M_J_DQ<35>")
	)
	(segment
		(start 115.390168 -39.150798)
		(end 115.532408 -39.008558)
		(width 0.14224)
		(layer "In11.Cu")
		(net "M_J_DQ<35>")
	)
	(segment
		(start 123.552204 -2.72415)
		(end 123.552204 0.581152)
		(width 0.14224)
		(layer "In11.Cu")
		(net "M_J_DQ<35>")
	)
	(segment
		(start 111.284512 -54.618636)
		(end 111.279686 -54.61)
		(width 0.0889)
		(layer "In11.Cu")
		(net "M_J_DQ<35>")
	)
	(segment
		(start 111.800132 -49.48174)
		(end 112.846612 -48.43526)
		(width 0.0889)
		(layer "In11.Cu")
		(net "M_J_DQ<35>")
	)
	(segment
		(start 123.707652 1.0922)
		(end 123.250452 1.5494)
		(width 0.14224)
		(layer "In11.Cu")
		(net "M_J_DQ<35>")
	)
	(segment
		(start 123.553982 -21.336)
		(end 123.695968 -21.194014)
		(width 0.14224)
		(layer "In11.Cu")
		(net "M_J_DQ<35>")
	)
	(segment
		(start 111.230918 -53.427884)
		(end 111.230918 -53.047646)
		(width 0.0889)
		(layer "In11.Cu")
		(net "M_J_DQ<35>")
	)
	(segment
		(start 111.800132 -52.478432)
		(end 111.800132 -49.48174)
		(width 0.0889)
		(layer "In11.Cu")
		(net "M_J_DQ<35>")
	)
	(segment
		(start 122.666252 2.198116)
		(end 122.349514 2.514854)
		(width 0.14224)
		(layer "In11.Cu")
		(net "M_J_DQ<35>")
	)
	(segment
		(start 113.098834 -47.898558)
		(end 113.098834 -44.904152)
		(width 0.14224)
		(layer "In11.Cu")
		(net "M_J_DQ<35>")
	)
	(segment
		(start 111.284512 -55.609236)
		(end 111.279686 -55.6006)
		(width 0.0889)
		(layer "In11.Cu")
		(net "M_J_DQ<35>")
	)
	(segment
		(start 110.772702 -60.857384)
		(end 111.267748 -60.19165)
		(width 0.0889)
		(layer "In11.Cu")
		(net "M_J_DQ<35>")
	)
	(segment
		(start 123.706382 -7.429246)
		(end 123.566682 -7.289546)
		(width 0.14224)
		(layer "In11.Cu")
		(net "M_J_DQ<35>")
	)
	(segment
		(start 111.284512 -57.590436)
		(end 111.279686 -57.5818)
		(width 0.0889)
		(layer "In11.Cu")
		(net "M_J_DQ<35>")
	)
	(segment
		(start 116.16563 -41.837356)
		(end 116.16563 -39.801038)
		(width 0.14224)
		(layer "In11.Cu")
		(net "M_J_DQ<35>")
	)
	(segment
		(start 123.663964 -12.330938)
		(end 123.416568 -12.083542)
		(width 0.14224)
		(layer "In11.Cu")
		(net "M_J_DQ<35>")
	)
	(segment
		(start 123.706382 -18.429986)
		(end 123.706382 -17.030446)
		(width 0.14224)
		(layer "In11.Cu")
		(net "M_J_DQ<35>")
	)
	(segment
		(start 123.543568 -30.542484)
		(end 123.543568 -23.37181)
		(width 0.14224)
		(layer "In11.Cu")
		(net "M_J_DQ<35>")
	)
	(segment
		(start 115.390168 -39.516558)
		(end 115.390168 -39.150798)
		(width 0.14224)
		(layer "In11.Cu")
		(net "M_J_DQ<35>")
	)
	(segment
		(start 123.566682 -4.816856)
		(end 122.715782 -3.965956)
		(width 0.14224)
		(layer "In11.Cu")
		(net "M_J_DQ<35>")
	)
	(segment
		(start 123.543568 -23.37181)
		(end 123.731782 -23.183596)
		(width 0.14224)
		(layer "In11.Cu")
		(net "M_J_DQ<35>")
	)
	(arc
		(start 111.284512 -54.218586)
		(mid 111.363643 -53.923184)
		(end 111.284512 -53.627782)
		(width 0.0889)
		(layer "In11.Cu")
		(net "M_J_DQ<35>")
	)
	(arc
		(start 111.279686 -54.61)
		(mid 111.230931 -54.413648)
		(end 111.284512 -54.218586)
		(width 0.0889)
		(layer "In11.Cu")
		(net "M_J_DQ<35>")
	)
	(arc
		(start 111.284512 -55.209186)
		(mid 111.363734 -54.920068)
		(end 111.290862 -54.629304)
		(width 0.0889)
		(layer "In11.Cu")
		(net "M_J_DQ<35>")
	)
	(arc
		(start 111.279686 -58.5724)
		(mid 111.230931 -58.376048)
		(end 111.284512 -58.180986)
		(width 0.0889)
		(layer "In11.Cu")
		(net "M_J_DQ<35>")
	)
	(arc
		(start 111.284512 -59.571382)
		(mid 111.231013 -59.371484)
		(end 111.284512 -59.171586)
		(width 0.0889)
		(layer "In11.Cu")
		(net "M_J_DQ<35>")
	)
	(arc
		(start 111.284512 -57.190386)
		(mid 111.363734 -56.901268)
		(end 111.290862 -56.610504)
		(width 0.0889)
		(layer "In11.Cu")
		(net "M_J_DQ<35>")
	)
	(arc
		(start 111.290862 -59.160918)
		(mid 111.36366 -58.870155)
		(end 111.284512 -58.581036)
		(width 0.0889)
		(layer "In11.Cu")
		(net "M_J_DQ<35>")
	)
	(arc
		(start 111.284512 -56.199786)
		(mid 111.363734 -55.910668)
		(end 111.290862 -55.619904)
		(width 0.0889)
		(layer "In11.Cu")
		(net "M_J_DQ<35>")
	)
	(arc
		(start 111.279686 -56.5912)
		(mid 111.230931 -56.394848)
		(end 111.284512 -56.199786)
		(width 0.0889)
		(layer "In11.Cu")
		(net "M_J_DQ<35>")
	)
	(arc
		(start 111.279686 -53.619146)
		(mid 111.243321 -53.526569)
		(end 111.230918 -53.427884)
		(width 0.0889)
		(layer "In11.Cu")
		(net "M_J_DQ<35>")
	)
	(arc
		(start 111.284512 -60.162186)
		(mid 111.363643 -59.866784)
		(end 111.284512 -59.571382)
		(width 0.0889)
		(layer "In11.Cu")
		(net "M_J_DQ<35>")
	)
	(arc
		(start 111.279686 -55.6006)
		(mid 111.230931 -55.404248)
		(end 111.284512 -55.209186)
		(width 0.0889)
		(layer "In11.Cu")
		(net "M_J_DQ<35>")
	)
	(arc
		(start 111.284512 -58.180986)
		(mid 111.363734 -57.891868)
		(end 111.290862 -57.601104)
		(width 0.0889)
		(layer "In11.Cu")
		(net "M_J_DQ<35>")
	)
	(arc
		(start 111.279686 -57.5818)
		(mid 111.230931 -57.385448)
		(end 111.284512 -57.190386)
		(width 0.0889)
		(layer "In11.Cu")
		(net "M_J_DQ<35>")
	)
	(segment
		(start 111.344202 -59.866784)
		(end 110.772702 -59.866784)
		(width 0.0889)
		(layer "F.Cu")
		(net "M_J_DQ<34>")
	)
	(segment
		(start 123.199398 0.175768)
		(end 123.33097 0.30734)
		(width 0.1651)
		(layer "F.Cu")
		(net "M_J_DQ<34>")
	)
	(segment
		(start 123.199398 -0.821182)
		(end 123.199398 0.175768)
		(width 0.1651)
		(layer "F.Cu")
		(net "M_J_DQ<34>")
	)
	(segment
		(start 123.199398 0.662432)
		(end 123.199398 0.9398)
		(width 0.1651)
		(layer "F.Cu")
		(net "M_J_DQ<34>")
	)
	(segment
		(start 123.33097 0.53086)
		(end 123.199398 0.662432)
		(width 0.1651)
		(layer "F.Cu")
		(net "M_J_DQ<34>")
	)
	(segment
		(start 123.33097 0.30734)
		(end 123.33097 0.53086)
		(width 0.1651)
		(layer "F.Cu")
		(net "M_J_DQ<34>")
	)
	(via
		(at 110.772702 -59.866784)
		(size 0.508)
		(drill 0.254)
		(layers "F.Cu" "B.Cu")
		(net "M_J_DQ<34>")
	)
	(via
		(at 123.199398 0.9398)
		(size 0.508)
		(drill 0.254)
		(layers "F.Cu" "B.Cu")
		(net "M_J_DQ<34>")
	)
	(via
		(at 122.349514 -4.357878)
		(size 0.508)
		(drill 0.254)
		(layers "F.Cu" "B.Cu")
		(net "M_J_DQ<34>")
	)
	(segment
		(start 122.349514 -5.621782)
		(end 122.349514 -4.357878)
		(width 0.1651)
		(layer "B.Cu")
		(net "M_J_DQ<34>")
	)
	(segment
		(start 122.825764 -16.198596)
		(end 122.825764 -15.957804)
		(width 0.14224)
		(layer "In11.Cu")
		(net "M_J_DQ<34>")
	)
	(segment
		(start 122.80138 0.541782)
		(end 123.199398 0.9398)
		(width 0.14224)
		(layer "In11.Cu")
		(net "M_J_DQ<34>")
	)
	(segment
		(start 114.49812 -40.29075)
		(end 114.34318 -40.13581)
		(width 0.14224)
		(layer "In11.Cu")
		(net "M_J_DQ<34>")
	)
	(segment
		(start 114.49812 -40.77081)
		(end 114.49812 -40.29075)
		(width 0.14224)
		(layer "In11.Cu")
		(net "M_J_DQ<34>")
	)
	(segment
		(start 122.924316 -21.427694)
		(end 122.730768 -21.234146)
		(width 0.14224)
		(layer "In11.Cu")
		(net "M_J_DQ<34>")
	)
	(segment
		(start 111.040164 -53.427884)
		(end 111.040164 -52.968398)
		(width 0.0889)
		(layer "In11.Cu")
		(net "M_J_DQ<34>")
	)
	(segment
		(start 122.825764 -14.2748)
		(end 122.825764 -13.677138)
		(width 0.14224)
		(layer "In11.Cu")
		(net "M_J_DQ<34>")
	)
	(segment
		(start 111.119412 -53.723286)
		(end 111.124238 -53.731922)
		(width 0.0889)
		(layer "In11.Cu")
		(net "M_J_DQ<34>")
	)
	(segment
		(start 113.91011 -41.71569)
		(end 113.75517 -41.56075)
		(width 0.14224)
		(layer "In11.Cu")
		(net "M_J_DQ<34>")
	)
	(segment
		(start 122.984768 -7.09676)
		(end 122.984768 -6.7056)
		(width 0.14224)
		(layer "In11.Cu")
		(net "M_J_DQ<34>")
	)
	(segment
		(start 122.959368 -4.967732)
		(end 122.349514 -4.357878)
		(width 0.14224)
		(layer "In11.Cu")
		(net "M_J_DQ<34>")
	)
	(segment
		(start 113.75517 -41.08069)
		(end 113.91011 -40.92575)
		(width 0.14224)
		(layer "In11.Cu")
		(net "M_J_DQ<34>")
	)
	(segment
		(start 122.842782 -11.745468)
		(end 122.603768 -11.506454)
		(width 0.14224)
		(layer "In11.Cu")
		(net "M_J_DQ<34>")
	)
	(segment
		(start 122.578368 -10.007346)
		(end 122.578368 -9.6266)
		(width 0.14224)
		(layer "In11.Cu")
		(net "M_J_DQ<34>")
	)
	(segment
		(start 122.908568 -30.27934)
		(end 122.908568 -23.368254)
		(width 0.14224)
		(layer "In11.Cu")
		(net "M_J_DQ<34>")
	)
	(segment
		(start 122.960638 -18.87093)
		(end 122.960638 -18.67027)
		(width 0.14224)
		(layer "In11.Cu")
		(net "M_J_DQ<34>")
	)
	(segment
		(start 122.705368 -21.93417)
		(end 122.924316 -21.715222)
		(width 0.14224)
		(layer "In11.Cu")
		(net "M_J_DQ<34>")
	)
	(segment
		(start 113.91011 -40.13581)
		(end 113.75517 -39.98087)
		(width 0.14224)
		(layer "In11.Cu")
		(net "M_J_DQ<34>")
	)
	(segment
		(start 122.761248 -1.04775)
		(end 122.761248 -0.761746)
		(width 0.14224)
		(layer "In11.Cu")
		(net "M_J_DQ<34>")
	)
	(segment
		(start 122.825764 -15.957804)
		(end 123.035568 -15.748)
		(width 0.14224)
		(layer "In11.Cu")
		(net "M_J_DQ<34>")
	)
	(segment
		(start 122.629168 -13.480542)
		(end 122.629168 -12.40917)
		(width 0.14224)
		(layer "In11.Cu")
		(net "M_J_DQ<34>")
	)
	(segment
		(start 122.578368 -9.6266)
		(end 122.842782 -9.362186)
		(width 0.14224)
		(layer "In11.Cu")
		(net "M_J_DQ<34>")
	)
	(segment
		(start 122.705368 -23.165054)
		(end 122.705368 -21.93417)
		(width 0.14224)
		(layer "In11.Cu")
		(net "M_J_DQ<34>")
	)
	(segment
		(start 114.34318 -40.92575)
		(end 114.49812 -40.77081)
		(width 0.14224)
		(layer "In11.Cu")
		(net "M_J_DQ<34>")
	)
	(segment
		(start 111.102394 -59.105546)
		(end 110.772702 -59.866784)
		(width 0.0889)
		(layer "In11.Cu")
		(net "M_J_DQ<34>")
	)
	(segment
		(start 114.49812 -38.689788)
		(end 122.908568 -30.27934)
		(width 0.14224)
		(layer "In11.Cu")
		(net "M_J_DQ<34>")
	)
	(segment
		(start 111.113062 -56.684418)
		(end 111.119412 -56.695086)
		(width 0.0889)
		(layer "In11.Cu")
		(net "M_J_DQ<34>")
	)
	(segment
		(start 122.825764 -13.677138)
		(end 122.629168 -13.480542)
		(width 0.14224)
		(layer "In11.Cu")
		(net "M_J_DQ<34>")
	)
	(segment
		(start 113.91011 -40.92575)
		(end 114.34318 -40.92575)
		(width 0.14224)
		(layer "In11.Cu")
		(net "M_J_DQ<34>")
	)
	(segment
		(start 111.119412 -59.076336)
		(end 111.102394 -59.105546)
		(width 0.0889)
		(layer "In11.Cu")
		(net "M_J_DQ<34>")
	)
	(segment
		(start 122.80138 0.236728)
		(end 122.80138 0.541782)
		(width 0.14224)
		(layer "In11.Cu")
		(net "M_J_DQ<34>")
	)
	(segment
		(start 111.119412 -55.704486)
		(end 111.124238 -55.713122)
		(width 0.0889)
		(layer "In11.Cu")
		(net "M_J_DQ<34>")
	)
	(segment
		(start 122.715782 -7.365746)
		(end 122.984768 -7.09676)
		(width 0.14224)
		(layer "In11.Cu")
		(net "M_J_DQ<34>")
	)
	(segment
		(start 122.913648 -2.478532)
		(end 122.913648 -2.2098)
		(width 0.14224)
		(layer "In11.Cu")
		(net "M_J_DQ<34>")
	)
	(segment
		(start 113.75517 -39.98087)
		(end 113.75517 -39.50081)
		(width 0.14224)
		(layer "In11.Cu")
		(net "M_J_DQ<34>")
	)
	(segment
		(start 122.842782 -8.925814)
		(end 122.715782 -8.798814)
		(width 0.14224)
		(layer "In11.Cu")
		(net "M_J_DQ<34>")
	)
	(segment
		(start 122.603768 -10.661396)
		(end 122.756168 -10.508996)
		(width 0.14224)
		(layer "In11.Cu")
		(net "M_J_DQ<34>")
	)
	(segment
		(start 122.456448 -0.456946)
		(end 122.456448 -0.108204)
		(width 0.14224)
		(layer "In11.Cu")
		(net "M_J_DQ<34>")
	)
	(segment
		(start 114.49812 -42.63009)
		(end 114.49812 -41.87063)
		(width 0.14224)
		(layer "In11.Cu")
		(net "M_J_DQ<34>")
	)
	(segment
		(start 122.756168 -10.185146)
		(end 122.578368 -10.007346)
		(width 0.14224)
		(layer "In11.Cu")
		(net "M_J_DQ<34>")
	)
	(segment
		(start 123.035568 -16.64716)
		(end 123.035568 -16.4084)
		(width 0.14224)
		(layer "In11.Cu")
		(net "M_J_DQ<34>")
	)
	(segment
		(start 122.781568 -6.5024)
		(end 122.781568 -5.816854)
		(width 0.14224)
		(layer "In11.Cu")
		(net "M_J_DQ<34>")
	)
	(segment
		(start 114.49812 -39.19093)
		(end 114.49812 -38.689788)
		(width 0.14224)
		(layer "In11.Cu")
		(net "M_J_DQ<34>")
	)
	(segment
		(start 114.34318 -39.34587)
		(end 114.49812 -39.19093)
		(width 0.14224)
		(layer "In11.Cu")
		(net "M_J_DQ<34>")
	)
	(segment
		(start 122.715782 -18.425414)
		(end 122.715782 -16.966946)
		(width 0.14224)
		(layer "In11.Cu")
		(net "M_J_DQ<34>")
	)
	(segment
		(start 122.756168 -10.508996)
		(end 122.756168 -10.185146)
		(width 0.14224)
		(layer "In11.Cu")
		(net "M_J_DQ<34>")
	)
	(segment
		(start 122.06478 -3.3274)
		(end 122.913648 -2.478532)
		(width 0.14224)
		(layer "In11.Cu")
		(net "M_J_DQ<34>")
	)
	(segment
		(start 111.119412 -54.713886)
		(end 111.124238 -54.722522)
		(width 0.0889)
		(layer "In11.Cu")
		(net "M_J_DQ<34>")
	)
	(segment
		(start 114.34318 -40.13581)
		(end 113.91011 -40.13581)
		(width 0.14224)
		(layer "In11.Cu")
		(net "M_J_DQ<34>")
	)
	(segment
		(start 111.113062 -54.703218)
		(end 111.119412 -54.713886)
		(width 0.0889)
		(layer "In11.Cu")
		(net "M_J_DQ<34>")
	)
	(segment
		(start 122.349514 -4.357878)
		(end 122.06478 -4.073144)
		(width 0.14224)
		(layer "In11.Cu")
		(net "M_J_DQ<34>")
	)
	(segment
		(start 113.75517 -39.50081)
		(end 113.91011 -39.34587)
		(width 0.14224)
		(layer "In11.Cu")
		(net "M_J_DQ<34>")
	)
	(segment
		(start 112.463834 -44.664376)
		(end 114.49812 -42.63009)
		(width 0.14224)
		(layer "In11.Cu")
		(net "M_J_DQ<34>")
	)
	(segment
		(start 113.91011 -39.34587)
		(end 114.34318 -39.34587)
		(width 0.14224)
		(layer "In11.Cu")
		(net "M_J_DQ<34>")
	)
	(segment
		(start 122.913648 -2.2098)
		(end 122.456448 -1.7526)
		(width 0.14224)
		(layer "In11.Cu")
		(net "M_J_DQ<34>")
	)
	(segment
		(start 122.842782 -9.362186)
		(end 122.842782 -8.925814)
		(width 0.14224)
		(layer "In11.Cu")
		(net "M_J_DQ<34>")
	)
	(segment
		(start 123.010168 -14.459204)
		(end 122.825764 -14.2748)
		(width 0.14224)
		(layer "In11.Cu")
		(net "M_J_DQ<34>")
	)
	(segment
		(start 111.119412 -56.695086)
		(end 111.124238 -56.703722)
		(width 0.0889)
		(layer "In11.Cu")
		(net "M_J_DQ<34>")
	)
	(segment
		(start 123.010168 -14.732)
		(end 123.010168 -14.459204)
		(width 0.14224)
		(layer "In11.Cu")
		(net "M_J_DQ<34>")
	)
	(segment
		(start 122.715782 -16.966946)
		(end 123.035568 -16.64716)
		(width 0.14224)
		(layer "In11.Cu")
		(net "M_J_DQ<34>")
	)
	(segment
		(start 112.656112 -48.090836)
		(end 112.463834 -47.898558)
		(width 0.0889)
		(layer "In11.Cu")
		(net "M_J_DQ<34>")
	)
	(segment
		(start 122.629168 -12.40917)
		(end 122.842782 -12.195556)
		(width 0.14224)
		(layer "In11.Cu")
		(net "M_J_DQ<34>")
	)
	(segment
		(start 122.825764 -15.2654)
		(end 122.825764 -14.916404)
		(width 0.14224)
		(layer "In11.Cu")
		(net "M_J_DQ<34>")
	)
	(segment
		(start 122.715782 -8.798814)
		(end 122.715782 -7.365746)
		(width 0.14224)
		(layer "In11.Cu")
		(net "M_J_DQ<34>")
	)
	(segment
		(start 123.035568 -16.4084)
		(end 122.825764 -16.198596)
		(width 0.14224)
		(layer "In11.Cu")
		(net "M_J_DQ<34>")
	)
	(segment
		(start 122.960638 -18.67027)
		(end 122.715782 -18.425414)
		(width 0.14224)
		(layer "In11.Cu")
		(net "M_J_DQ<34>")
	)
	(segment
		(start 123.035568 -15.748)
		(end 123.035568 -15.475204)
		(width 0.14224)
		(layer "In11.Cu")
		(net "M_J_DQ<34>")
	)
	(segment
		(start 111.609632 -52.39893)
		(end 111.609632 -49.402492)
		(width 0.0889)
		(layer "In11.Cu")
		(net "M_J_DQ<34>")
	)
	(segment
		(start 122.456448 -0.108204)
		(end 122.80138 0.236728)
		(width 0.14224)
		(layer "In11.Cu")
		(net "M_J_DQ<34>")
	)
	(segment
		(start 122.730768 -19.1008)
		(end 122.960638 -18.87093)
		(width 0.14224)
		(layer "In11.Cu")
		(net "M_J_DQ<34>")
	)
	(segment
		(start 111.040164 -52.968398)
		(end 111.609632 -52.39893)
		(width 0.0889)
		(layer "In11.Cu")
		(net "M_J_DQ<34>")
	)
	(segment
		(start 122.456448 -1.35255)
		(end 122.761248 -1.04775)
		(width 0.14224)
		(layer "In11.Cu")
		(net "M_J_DQ<34>")
	)
	(segment
		(start 111.609632 -49.402492)
		(end 112.656112 -48.356012)
		(width 0.0889)
		(layer "In11.Cu")
		(net "M_J_DQ<34>")
	)
	(segment
		(start 122.924316 -21.715222)
		(end 122.924316 -21.427694)
		(width 0.14224)
		(layer "In11.Cu")
		(net "M_J_DQ<34>")
	)
	(segment
		(start 112.656112 -48.356012)
		(end 112.656112 -48.090836)
		(width 0.0889)
		(layer "In11.Cu")
		(net "M_J_DQ<34>")
	)
	(segment
		(start 122.456448 -1.7526)
		(end 122.456448 -1.35255)
		(width 0.14224)
		(layer "In11.Cu")
		(net "M_J_DQ<34>")
	)
	(segment
		(start 122.984768 -6.7056)
		(end 122.781568 -6.5024)
		(width 0.14224)
		(layer "In11.Cu")
		(net "M_J_DQ<34>")
	)
	(segment
		(start 123.035568 -15.475204)
		(end 122.825764 -15.2654)
		(width 0.14224)
		(layer "In11.Cu")
		(net "M_J_DQ<34>")
	)
	(segment
		(start 122.842782 -12.195556)
		(end 122.842782 -11.745468)
		(width 0.14224)
		(layer "In11.Cu")
		(net "M_J_DQ<34>")
	)
	(segment
		(start 113.75517 -41.56075)
		(end 113.75517 -41.08069)
		(width 0.14224)
		(layer "In11.Cu")
		(net "M_J_DQ<34>")
	)
	(segment
		(start 111.113062 -57.675018)
		(end 111.119412 -57.685686)
		(width 0.0889)
		(layer "In11.Cu")
		(net "M_J_DQ<34>")
	)
	(segment
		(start 122.781568 -5.816854)
		(end 122.959368 -5.639054)
		(width 0.14224)
		(layer "In11.Cu")
		(net "M_J_DQ<34>")
	)
	(segment
		(start 122.959368 -5.639054)
		(end 122.959368 -4.967732)
		(width 0.14224)
		(layer "In11.Cu")
		(net "M_J_DQ<34>")
	)
	(segment
		(start 112.463834 -47.898558)
		(end 112.463834 -44.664376)
		(width 0.14224)
		(layer "In11.Cu")
		(net "M_J_DQ<34>")
	)
	(segment
		(start 114.49812 -41.87063)
		(end 114.34318 -41.71569)
		(width 0.14224)
		(layer "In11.Cu")
		(net "M_J_DQ<34>")
	)
	(segment
		(start 122.603768 -11.506454)
		(end 122.603768 -10.661396)
		(width 0.14224)
		(layer "In11.Cu")
		(net "M_J_DQ<34>")
	)
	(segment
		(start 122.730768 -21.234146)
		(end 122.730768 -19.1008)
		(width 0.14224)
		(layer "In11.Cu")
		(net "M_J_DQ<34>")
	)
	(segment
		(start 122.761248 -0.761746)
		(end 122.456448 -0.456946)
		(width 0.14224)
		(layer "In11.Cu")
		(net "M_J_DQ<34>")
	)
	(segment
		(start 111.113062 -55.693818)
		(end 111.119412 -55.704486)
		(width 0.0889)
		(layer "In11.Cu")
		(net "M_J_DQ<34>")
	)
	(segment
		(start 122.06478 -4.073144)
		(end 122.06478 -3.3274)
		(width 0.14224)
		(layer "In11.Cu")
		(net "M_J_DQ<34>")
	)
	(segment
		(start 111.119412 -57.685686)
		(end 111.124238 -57.694322)
		(width 0.0889)
		(layer "In11.Cu")
		(net "M_J_DQ<34>")
	)
	(segment
		(start 122.908568 -23.368254)
		(end 122.705368 -23.165054)
		(width 0.14224)
		(layer "In11.Cu")
		(net "M_J_DQ<34>")
	)
	(segment
		(start 114.34318 -41.71569)
		(end 113.91011 -41.71569)
		(width 0.14224)
		(layer "In11.Cu")
		(net "M_J_DQ<34>")
	)
	(segment
		(start 122.825764 -14.916404)
		(end 123.010168 -14.732)
		(width 0.14224)
		(layer "In11.Cu")
		(net "M_J_DQ<34>")
	)
	(arc
		(start 111.124238 -57.694322)
		(mid 111.172993 -57.890674)
		(end 111.119412 -58.085736)
		(width 0.0889)
		(layer "In11.Cu")
		(net "M_J_DQ<34>")
	)
	(arc
		(start 111.040164 -53.427884)
		(mid 111.060355 -53.580798)
		(end 111.119412 -53.723286)
		(width 0.0889)
		(layer "In11.Cu")
		(net "M_J_DQ<34>")
	)
	(arc
		(start 111.124238 -53.731922)
		(mid 111.172993 -53.928274)
		(end 111.119412 -54.123336)
		(width 0.0889)
		(layer "In11.Cu")
		(net "M_J_DQ<34>")
	)
	(arc
		(start 111.119412 -58.085736)
		(mid 111.040281 -58.381138)
		(end 111.119412 -58.67654)
		(width 0.0889)
		(layer "In11.Cu")
		(net "M_J_DQ<34>")
	)
	(arc
		(start 111.119412 -56.104536)
		(mid 111.04019 -56.393654)
		(end 111.113062 -56.684418)
		(width 0.0889)
		(layer "In11.Cu")
		(net "M_J_DQ<34>")
	)
	(arc
		(start 111.124238 -54.722522)
		(mid 111.172993 -54.918874)
		(end 111.119412 -55.113936)
		(width 0.0889)
		(layer "In11.Cu")
		(net "M_J_DQ<34>")
	)
	(arc
		(start 111.119412 -54.123336)
		(mid 111.04019 -54.412454)
		(end 111.113062 -54.703218)
		(width 0.0889)
		(layer "In11.Cu")
		(net "M_J_DQ<34>")
	)
	(arc
		(start 111.119412 -58.67654)
		(mid 111.172911 -58.876438)
		(end 111.119412 -59.076336)
		(width 0.0889)
		(layer "In11.Cu")
		(net "M_J_DQ<34>")
	)
	(arc
		(start 111.119412 -55.113936)
		(mid 111.04019 -55.403054)
		(end 111.113062 -55.693818)
		(width 0.0889)
		(layer "In11.Cu")
		(net "M_J_DQ<34>")
	)
	(arc
		(start 111.119412 -57.095136)
		(mid 111.04019 -57.384254)
		(end 111.113062 -57.675018)
		(width 0.0889)
		(layer "In11.Cu")
		(net "M_J_DQ<34>")
	)
	(arc
		(start 111.124238 -55.713122)
		(mid 111.172993 -55.909474)
		(end 111.119412 -56.104536)
		(width 0.0889)
		(layer "In11.Cu")
		(net "M_J_DQ<34>")
	)
	(arc
		(start 111.124238 -56.703722)
		(mid 111.172993 -56.900074)
		(end 111.119412 -57.095136)
		(width 0.0889)
		(layer "In11.Cu")
		(net "M_J_DQ<34>")
	)
	(segment
		(start 108.768896 -61.352938)
		(end 108.197396 -61.352938)
		(width 0.0889)
		(layer "F.Cu")
		(net "M_J_DQ<33>")
	)
	(segment
		(start 116.399564 3.778758)
		(end 116.399564 2.514854)
		(width 0.1651)
		(layer "F.Cu")
		(net "M_J_DQ<33>")
	)
	(via
		(at 116.399564 2.514854)
		(size 0.508)
		(drill 0.254)
		(layers "F.Cu" "B.Cu")
		(net "M_J_DQ<33>")
	)
	(via
		(at 117.071648 -3.076956)
		(size 0.508)
		(drill 0.254)
		(layers "F.Cu" "B.Cu")
		(net "M_J_DQ<33>")
	)
	(via
		(at 108.197396 -61.352938)
		(size 0.508)
		(drill 0.254)
		(layers "F.Cu" "B.Cu")
		(net "M_J_DQ<33>")
	)
	(segment
		(start 117.249448 -2.395982)
		(end 117.071648 -2.573782)
		(width 0.1651)
		(layer "B.Cu")
		(net "M_J_DQ<33>")
	)
	(segment
		(start 117.249448 -1.021842)
		(end 117.249448 -2.395982)
		(width 0.1651)
		(layer "B.Cu")
		(net "M_J_DQ<33>")
	)
	(segment
		(start 117.071648 -2.573782)
		(end 117.071648 -3.076956)
		(width 0.1651)
		(layer "B.Cu")
		(net "M_J_DQ<33>")
	)
	(segment
		(start 108.197396 -61.352938)
		(end 107.850432 -60.561982)
		(width 0.0889)
		(layer "In11.Cu")
		(net "M_J_DQ<33>")
	)
	(segment
		(start 107.779312 -52.160678)
		(end 108.463334 -51.476656)
		(width 0.0889)
		(layer "In11.Cu")
		(net "M_J_DQ<33>")
	)
	(segment
		(start 107.92968 -54.914292)
		(end 107.92968 -54.666388)
		(width 0.0889)
		(layer "In11.Cu")
		(net "M_J_DQ<33>")
	)
	(segment
		(start 117.295168 -29.849572)
		(end 117.091968 -29.646372)
		(width 0.14224)
		(layer "In11.Cu")
		(net "M_J_DQ<33>")
	)
	(segment
		(start 107.857036 -55.619904)
		(end 107.850686 -55.609236)
		(width 0.0889)
		(layer "In11.Cu")
		(net "M_J_DQ<33>")
	)
	(segment
		(start 117.091968 -30.459172)
		(end 117.295168 -30.255972)
		(width 0.14224)
		(layer "In11.Cu")
		(net "M_J_DQ<33>")
	)
	(segment
		(start 117.44579 -2.702814)
		(end 117.44579 0.630936)
		(width 0.14224)
		(layer "In11.Cu")
		(net "M_J_DQ<33>")
	)
	(segment
		(start 117.7036 -11.604498)
		(end 117.7036 -9.577832)
		(width 0.14224)
		(layer "In11.Cu")
		(net "M_J_DQ<33>")
	)
	(segment
		(start 108.463334 -51.476656)
		(end 108.46308 -51.476402)
		(width 0.0889)
		(layer "In11.Cu")
		(net "M_J_DQ<33>")
	)
	(segment
		(start 117.091968 -29.646372)
		(end 116.888768 -29.646372)
		(width 0.14224)
		(layer "In11.Cu")
		(net "M_J_DQ<33>")
	)
	(segment
		(start 117.44579 0.630936)
		(end 117.602254 0.7874)
		(width 0.14224)
		(layer "In11.Cu")
		(net "M_J_DQ<33>")
	)
	(segment
		(start 117.559582 -9.433814)
		(end 117.559582 -6.335014)
		(width 0.14224)
		(layer "In11.Cu")
		(net "M_J_DQ<33>")
	)
	(segment
		(start 117.559582 -19.05)
		(end 117.559582 -11.748516)
		(width 0.14224)
		(layer "In11.Cu")
		(net "M_J_DQ<33>")
	)
	(segment
		(start 117.602254 0.7874)
		(end 117.602254 1.128776)
		(width 0.14224)
		(layer "In11.Cu")
		(net "M_J_DQ<33>")
	)
	(segment
		(start 116.399564 1.975866)
		(end 116.399564 2.514854)
		(width 0.14224)
		(layer "In11.Cu")
		(net "M_J_DQ<33>")
	)
	(segment
		(start 116.685568 -30.898846)
		(end 116.685568 -30.662372)
		(width 0.14224)
		(layer "In11.Cu")
		(net "M_J_DQ<33>")
	)
	(segment
		(start 107.778804 -52.161694)
		(end 107.779312 -52.161186)
		(width 0.0889)
		(layer "In11.Cu")
		(net "M_J_DQ<33>")
	)
	(segment
		(start 117.7036 -9.577832)
		(end 117.559582 -9.433814)
		(width 0.14224)
		(layer "In11.Cu")
		(net "M_J_DQ<33>")
	)
	(segment
		(start 108.574078 -47.898558)
		(end 108.574078 -39.010336)
		(width 0.14224)
		(layer "In11.Cu")
		(net "M_J_DQ<33>")
	)
	(segment
		(start 107.778804 -52.758848)
		(end 107.778804 -52.161694)
		(width 0.0889)
		(layer "In11.Cu")
		(net "M_J_DQ<33>")
	)
	(segment
		(start 117.295168 -30.255972)
		(end 117.295168 -29.849572)
		(width 0.14224)
		(layer "In11.Cu")
		(net "M_J_DQ<33>")
	)
	(segment
		(start 117.559582 -21.325586)
		(end 117.726968 -21.1582)
		(width 0.14224)
		(layer "In11.Cu")
		(net "M_J_DQ<33>")
	)
	(segment
		(start 117.602254 1.128776)
		(end 117.23243 1.4986)
		(width 0.14224)
		(layer "In11.Cu")
		(net "M_J_DQ<33>")
	)
	(segment
		(start 117.559582 -26.6827)
		(end 117.559582 -21.325586)
		(width 0.14224)
		(layer "In11.Cu")
		(net "M_J_DQ<33>")
	)
	(segment
		(start 117.559582 -11.748516)
		(end 117.7036 -11.604498)
		(width 0.14224)
		(layer "In11.Cu")
		(net "M_J_DQ<33>")
	)
	(segment
		(start 117.071648 -3.076956)
		(end 117.44579 -2.702814)
		(width 0.14224)
		(layer "In11.Cu")
		(net "M_J_DQ<33>")
	)
	(segment
		(start 116.952268 -26.8859)
		(end 117.356382 -26.8859)
		(width 0.14224)
		(layer "In11.Cu")
		(net "M_J_DQ<33>")
	)
	(segment
		(start 107.850686 -55.609236)
		(end 107.84586 -55.6006)
		(width 0.0889)
		(layer "In11.Cu")
		(net "M_J_DQ<33>")
	)
	(segment
		(start 116.685568 -27.1526)
		(end 116.952268 -26.8859)
		(width 0.14224)
		(layer "In11.Cu")
		(net "M_J_DQ<33>")
	)
	(segment
		(start 107.857036 -57.601104)
		(end 107.850686 -57.590436)
		(width 0.0889)
		(layer "In11.Cu")
		(net "M_J_DQ<33>")
	)
	(segment
		(start 116.87683 1.4986)
		(end 116.399564 1.975866)
		(width 0.14224)
		(layer "In11.Cu")
		(net "M_J_DQ<33>")
	)
	(segment
		(start 108.46308 -48.90262)
		(end 108.307632 -48.747172)
		(width 0.0889)
		(layer "In11.Cu")
		(net "M_J_DQ<33>")
	)
	(segment
		(start 107.92968 -54.666388)
		(end 107.837986 -54.574694)
		(width 0.0889)
		(layer "In11.Cu")
		(net "M_J_DQ<33>")
	)
	(segment
		(start 116.685568 -30.662372)
		(end 116.888768 -30.459172)
		(width 0.14224)
		(layer "In11.Cu")
		(net "M_J_DQ<33>")
	)
	(segment
		(start 108.307632 -48.165004)
		(end 108.574078 -47.898558)
		(width 0.0889)
		(layer "In11.Cu")
		(net "M_J_DQ<33>")
	)
	(segment
		(start 108.574078 -39.010336)
		(end 116.685568 -30.898846)
		(width 0.14224)
		(layer "In11.Cu")
		(net "M_J_DQ<33>")
	)
	(segment
		(start 117.726968 -21.1582)
		(end 117.726968 -19.217386)
		(width 0.14224)
		(layer "In11.Cu")
		(net "M_J_DQ<33>")
	)
	(segment
		(start 116.545106 -3.872992)
		(end 116.545106 -3.603498)
		(width 0.14224)
		(layer "In11.Cu")
		(net "M_J_DQ<33>")
	)
	(segment
		(start 107.850686 -57.590436)
		(end 107.84586 -57.5818)
		(width 0.0889)
		(layer "In11.Cu")
		(net "M_J_DQ<33>")
	)
	(segment
		(start 107.837986 -52.81803)
		(end 107.778804 -52.758848)
		(width 0.0889)
		(layer "In11.Cu")
		(net "M_J_DQ<33>")
	)
	(segment
		(start 116.545106 -3.603498)
		(end 117.071648 -3.076956)
		(width 0.14224)
		(layer "In11.Cu")
		(net "M_J_DQ<33>")
	)
	(segment
		(start 108.307632 -48.747172)
		(end 108.307632 -48.165004)
		(width 0.0889)
		(layer "In11.Cu")
		(net "M_J_DQ<33>")
	)
	(segment
		(start 107.857036 -56.610504)
		(end 107.850686 -56.599836)
		(width 0.0889)
		(layer "In11.Cu")
		(net "M_J_DQ<33>")
	)
	(segment
		(start 116.888768 -30.459172)
		(end 117.091968 -30.459172)
		(width 0.14224)
		(layer "In11.Cu")
		(net "M_J_DQ<33>")
	)
	(segment
		(start 117.559582 -6.335014)
		(end 116.924582 -5.700014)
		(width 0.14224)
		(layer "In11.Cu")
		(net "M_J_DQ<33>")
	)
	(segment
		(start 107.850686 -56.599836)
		(end 107.84586 -56.5912)
		(width 0.0889)
		(layer "In11.Cu")
		(net "M_J_DQ<33>")
	)
	(segment
		(start 117.356382 -26.8859)
		(end 117.559582 -26.6827)
		(width 0.14224)
		(layer "In11.Cu")
		(net "M_J_DQ<33>")
	)
	(segment
		(start 116.924582 -5.700014)
		(end 116.924582 -4.252468)
		(width 0.14224)
		(layer "In11.Cu")
		(net "M_J_DQ<33>")
	)
	(segment
		(start 116.685568 -29.443172)
		(end 116.685568 -27.1526)
		(width 0.14224)
		(layer "In11.Cu")
		(net "M_J_DQ<33>")
	)
	(segment
		(start 116.924582 -4.252468)
		(end 116.545106 -3.872992)
		(width 0.14224)
		(layer "In11.Cu")
		(net "M_J_DQ<33>")
	)
	(segment
		(start 107.779312 -52.161186)
		(end 107.779312 -52.160678)
		(width 0.0889)
		(layer "In11.Cu")
		(net "M_J_DQ<33>")
	)
	(segment
		(start 107.837986 -54.574694)
		(end 107.837986 -52.81803)
		(width 0.0889)
		(layer "In11.Cu")
		(net "M_J_DQ<33>")
	)
	(segment
		(start 117.23243 1.4986)
		(end 116.87683 1.4986)
		(width 0.14224)
		(layer "In11.Cu")
		(net "M_J_DQ<33>")
	)
	(segment
		(start 108.46308 -51.476402)
		(end 108.46308 -48.90262)
		(width 0.0889)
		(layer "In11.Cu")
		(net "M_J_DQ<33>")
	)
	(segment
		(start 117.726968 -19.217386)
		(end 117.559582 -19.05)
		(width 0.14224)
		(layer "In11.Cu")
		(net "M_J_DQ<33>")
	)
	(segment
		(start 116.888768 -29.646372)
		(end 116.685568 -29.443172)
		(width 0.14224)
		(layer "In11.Cu")
		(net "M_J_DQ<33>")
	)
	(arc
		(start 107.850686 -55.209186)
		(mid 107.909579 -55.066936)
		(end 107.92968 -54.914292)
		(width 0.0889)
		(layer "In11.Cu")
		(net "M_J_DQ<33>")
	)
	(arc
		(start 107.850686 -56.199786)
		(mid 107.929908 -55.910668)
		(end 107.857036 -55.619904)
		(width 0.0889)
		(layer "In11.Cu")
		(net "M_J_DQ<33>")
	)
	(arc
		(start 107.84586 -56.5912)
		(mid 107.797105 -56.394848)
		(end 107.850686 -56.199786)
		(width 0.0889)
		(layer "In11.Cu")
		(net "M_J_DQ<33>")
	)
	(arc
		(start 107.84586 -57.5818)
		(mid 107.797105 -57.385448)
		(end 107.850686 -57.190386)
		(width 0.0889)
		(layer "In11.Cu")
		(net "M_J_DQ<33>")
	)
	(arc
		(start 107.850686 -57.190386)
		(mid 107.929908 -56.901268)
		(end 107.857036 -56.610504)
		(width 0.0889)
		(layer "In11.Cu")
		(net "M_J_DQ<33>")
	)
	(arc
		(start 107.850432 -60.561982)
		(mid 107.818161 -60.233475)
		(end 108.043726 -59.992514)
		(width 0.0889)
		(layer "In11.Cu")
		(net "M_J_DQ<33>")
	)
	(arc
		(start 108.342938 -58.998866)
		(mid 108.060355 -58.832613)
		(end 107.850432 -58.580782)
		(width 0.0889)
		(layer "In11.Cu")
		(net "M_J_DQ<33>")
	)
	(arc
		(start 107.84586 -55.6006)
		(mid 107.797105 -55.404248)
		(end 107.850686 -55.209186)
		(width 0.0889)
		(layer "In11.Cu")
		(net "M_J_DQ<33>")
	)
	(arc
		(start 108.043726 -59.992514)
		(mid 108.305967 -59.837215)
		(end 108.514642 -59.61507)
		(width 0.0889)
		(layer "In11.Cu")
		(net "M_J_DQ<33>")
	)
	(arc
		(start 107.850432 -58.580782)
		(mid 107.796933 -58.380884)
		(end 107.850432 -58.180986)
		(width 0.0889)
		(layer "In11.Cu")
		(net "M_J_DQ<33>")
	)
	(arc
		(start 108.514642 -59.61507)
		(mid 108.582637 -59.264086)
		(end 108.342938 -58.998866)
		(width 0.0889)
		(layer "In11.Cu")
		(net "M_J_DQ<33>")
	)
	(arc
		(start 107.850432 -58.180986)
		(mid 107.929608 -57.891898)
		(end 107.857036 -57.601104)
		(width 0.0889)
		(layer "In11.Cu")
		(net "M_J_DQ<33>")
	)
	(segment
		(start 108.768896 -59.371484)
		(end 108.197396 -59.371484)
		(width 0.0889)
		(layer "F.Cu")
		(net "M_J_DQ<32>")
	)
	(segment
		(start 117.249448 -0.821182)
		(end 117.071648 1.0414)
		(width 0.1651)
		(layer "F.Cu")
		(net "M_J_DQ<32>")
	)
	(via
		(at 116.399564 -4.357878)
		(size 0.508)
		(drill 0.254)
		(layers "F.Cu" "B.Cu")
		(net "M_J_DQ<32>")
	)
	(via
		(at 108.197396 -59.371484)
		(size 0.508)
		(drill 0.254)
		(layers "F.Cu" "B.Cu")
		(net "M_J_DQ<32>")
	)
	(via
		(at 117.071648 1.0414)
		(size 0.508)
		(drill 0.254)
		(layers "F.Cu" "B.Cu")
		(net "M_J_DQ<32>")
	)
	(segment
		(start 116.399564 -5.621782)
		(end 116.399564 -4.357878)
		(width 0.1651)
		(layer "B.Cu")
		(net "M_J_DQ<32>")
	)
	(segment
		(start 116.882164 -23.374096)
		(end 116.602764 -23.094696)
		(width 0.14224)
		(layer "In11.Cu")
		(net "M_J_DQ<32>")
	)
	(segment
		(start 107.685586 -55.704486)
		(end 107.679236 -55.693818)
		(width 0.0889)
		(layer "In11.Cu")
		(net "M_J_DQ<32>")
	)
	(segment
		(start 116.050568 -26.797)
		(end 116.882164 -25.965404)
		(width 0.14224)
		(layer "In11.Cu")
		(net "M_J_DQ<32>")
	)
	(segment
		(start 116.856764 -18.586196)
		(end 116.581682 -18.311114)
		(width 0.14224)
		(layer "In11.Cu")
		(net "M_J_DQ<32>")
	)
	(segment
		(start 116.581682 -17.121886)
		(end 116.924582 -16.778986)
		(width 0.14224)
		(layer "In11.Cu")
		(net "M_J_DQ<32>")
	)
	(segment
		(start 112.35563 -33.548066)
		(end 112.35563 -33.261046)
		(width 0.14224)
		(layer "In11.Cu")
		(net "M_J_DQ<32>")
	)
	(segment
		(start 113.178082 -33.221168)
		(end 113.465102 -33.221168)
		(width 0.14224)
		(layer "In11.Cu")
		(net "M_J_DQ<32>")
	)
	(segment
		(start 114.614706 -32.071564)
		(end 114.902488 -31.783782)
		(width 0.14224)
		(layer "In11.Cu")
		(net "M_J_DQ<32>")
	)
	(segment
		(start 116.863368 -8.9662)
		(end 116.581682 -8.684514)
		(width 0.14224)
		(layer "In11.Cu")
		(net "M_J_DQ<32>")
	)
	(segment
		(start 112.930178 -32.973264)
		(end 113.178082 -33.221168)
		(width 0.14224)
		(layer "In11.Cu")
		(net "M_J_DQ<32>")
	)
	(segment
		(start 116.780818 -21.20265)
		(end 116.780818 -19.193764)
		(width 0.14224)
		(layer "In11.Cu")
		(net "M_J_DQ<32>")
	)
	(segment
		(start 114.586258 -31.180278)
		(end 114.586258 -30.97911)
		(width 0.14224)
		(layer "In11.Cu")
		(net "M_J_DQ<32>")
	)
	(segment
		(start 116.050568 -30.635702)
		(end 116.050568 -26.797)
		(width 0.14224)
		(layer "In11.Cu")
		(net "M_J_DQ<32>")
	)
	(segment
		(start 116.856764 -19.117818)
		(end 116.856764 -18.586196)
		(width 0.14224)
		(layer "In11.Cu")
		(net "M_J_DQ<32>")
	)
	(segment
		(start 114.959892 -30.605476)
		(end 115.16106 -30.605476)
		(width 0.14224)
		(layer "In11.Cu")
		(net "M_J_DQ<32>")
	)
	(segment
		(start 113.481358 -31.512002)
		(end 113.768124 -31.512002)
		(width 0.14224)
		(layer "In11.Cu")
		(net "M_J_DQ<32>")
	)
	(segment
		(start 114.902488 -31.496508)
		(end 114.586258 -31.180278)
		(width 0.14224)
		(layer "In11.Cu")
		(net "M_J_DQ<32>")
	)
	(segment
		(start 113.768124 -31.512002)
		(end 114.327686 -32.071564)
		(width 0.14224)
		(layer "In11.Cu")
		(net "M_J_DQ<32>")
	)
	(segment
		(start 113.193576 -32.086804)
		(end 113.193576 -31.799784)
		(width 0.14224)
		(layer "In11.Cu")
		(net "M_J_DQ<32>")
	)
	(segment
		(start 107.73918 -54.745382)
		(end 107.647486 -54.653688)
		(width 0.0889)
		(layer "In11.Cu")
		(net "M_J_DQ<32>")
	)
	(segment
		(start 116.736368 -11.597386)
		(end 116.736368 -9.6012)
		(width 0.14224)
		(layer "In11.Cu")
		(net "M_J_DQ<32>")
	)
	(segment
		(start 107.690412 -55.713122)
		(end 107.685586 -55.704486)
		(width 0.0889)
		(layer "In11.Cu")
		(net "M_J_DQ<32>")
	)
	(segment
		(start 107.827826 -47.787306)
		(end 107.827826 -38.859968)
		(width 0.14224)
		(layer "In11.Cu")
		(net "M_J_DQ<32>")
	)
	(segment
		(start 112.35563 -33.261046)
		(end 112.643412 -32.973264)
		(width 0.14224)
		(layer "In11.Cu")
		(net "M_J_DQ<32>")
	)
	(segment
		(start 113.752884 -32.933386)
		(end 113.752884 -32.646112)
		(width 0.14224)
		(layer "In11.Cu")
		(net "M_J_DQ<32>")
	)
	(segment
		(start 116.780818 -19.193764)
		(end 116.856764 -19.117818)
		(width 0.14224)
		(layer "In11.Cu")
		(net "M_J_DQ<32>")
	)
	(segment
		(start 116.602764 -21.989796)
		(end 116.837968 -21.754592)
		(width 0.14224)
		(layer "In11.Cu")
		(net "M_J_DQ<32>")
	)
	(segment
		(start 115.76431 -30.92196)
		(end 116.050568 -30.635702)
		(width 0.14224)
		(layer "In11.Cu")
		(net "M_J_DQ<32>")
	)
	(segment
		(start 116.581682 -12.424156)
		(end 116.837968 -12.16787)
		(width 0.14224)
		(layer "In11.Cu")
		(net "M_J_DQ<32>")
	)
	(segment
		(start 116.837968 -11.698986)
		(end 116.736368 -11.597386)
		(width 0.14224)
		(layer "In11.Cu")
		(net "M_J_DQ<32>")
	)
	(segment
		(start 116.924582 -16.778986)
		(end 116.924582 -13.853668)
		(width 0.14224)
		(layer "In11.Cu")
		(net "M_J_DQ<32>")
	)
	(segment
		(start 113.465102 -33.221168)
		(end 113.752884 -32.933386)
		(width 0.14224)
		(layer "In11.Cu")
		(net "M_J_DQ<32>")
	)
	(segment
		(start 114.327686 -32.071564)
		(end 114.614706 -32.071564)
		(width 0.14224)
		(layer "In11.Cu")
		(net "M_J_DQ<32>")
	)
	(segment
		(start 116.85143 0.821182)
		(end 117.071648 1.0414)
		(width 0.14224)
		(layer "In11.Cu")
		(net "M_J_DQ<32>")
	)
	(segment
		(start 116.85143 -2.5908)
		(end 116.85143 -2.090928)
		(width 0.14224)
		(layer "In11.Cu")
		(net "M_J_DQ<32>")
	)
	(segment
		(start 113.193576 -31.799784)
		(end 113.481358 -31.512002)
		(width 0.14224)
		(layer "In11.Cu")
		(net "M_J_DQ<32>")
	)
	(segment
		(start 108.117132 -48.076612)
		(end 107.939078 -47.898558)
		(width 0.0889)
		(layer "In11.Cu")
		(net "M_J_DQ<32>")
	)
	(segment
		(start 107.73918 -54.913784)
		(end 107.73918 -54.745382)
		(width 0.0889)
		(layer "In11.Cu")
		(net "M_J_DQ<32>")
	)
	(segment
		(start 116.779548 -0.8509)
		(end 116.436648 -0.508)
		(width 0.14224)
		(layer "In11.Cu")
		(net "M_J_DQ<32>")
	)
	(segment
		(start 107.690412 -56.703722)
		(end 107.685586 -56.695086)
		(width 0.0889)
		(layer "In11.Cu")
		(net "M_J_DQ<32>")
	)
	(segment
		(start 116.602764 -23.094696)
		(end 116.602764 -21.989796)
		(width 0.14224)
		(layer "In11.Cu")
		(net "M_J_DQ<32>")
	)
	(segment
		(start 114.902488 -31.783782)
		(end 114.902488 -31.496508)
		(width 0.14224)
		(layer "In11.Cu")
		(net "M_J_DQ<32>")
	)
	(segment
		(start 116.837968 -21.2598)
		(end 116.780818 -21.20265)
		(width 0.14224)
		(layer "In11.Cu")
		(net "M_J_DQ<32>")
	)
	(segment
		(start 116.581682 -7.520686)
		(end 116.873782 -7.228586)
		(width 0.14224)
		(layer "In11.Cu")
		(net "M_J_DQ<32>")
	)
	(segment
		(start 108.197396 -59.371484)
		(end 108.154978 -59.326526)
		(width 0.0889)
		(layer "In11.Cu")
		(net "M_J_DQ<32>")
	)
	(segment
		(start 116.779548 -1.0795)
		(end 116.779548 -0.8509)
		(width 0.14224)
		(layer "In11.Cu")
		(net "M_J_DQ<32>")
	)
	(segment
		(start 116.462048 -1.397)
		(end 116.779548 -1.0795)
		(width 0.14224)
		(layer "In11.Cu")
		(net "M_J_DQ<32>")
	)
	(segment
		(start 116.85143 0.236728)
		(end 116.85143 0.821182)
		(width 0.14224)
		(layer "In11.Cu")
		(net "M_J_DQ<32>")
	)
	(segment
		(start 107.647486 -54.653688)
		(end 107.647486 -52.896262)
		(width 0.0889)
		(layer "In11.Cu")
		(net "M_J_DQ<32>")
	)
	(segment
		(start 116.399564 -6.140196)
		(end 116.399564 -4.357878)
		(width 0.14224)
		(layer "In11.Cu")
		(net "M_J_DQ<32>")
	)
	(segment
		(start 113.752884 -32.646112)
		(end 113.193576 -32.086804)
		(width 0.14224)
		(layer "In11.Cu")
		(net "M_J_DQ<32>")
	)
	(segment
		(start 107.939078 -47.898558)
		(end 107.827826 -47.787306)
		(width 0.14224)
		(layer "In11.Cu")
		(net "M_J_DQ<32>")
	)
	(segment
		(start 107.690412 -57.694322)
		(end 107.685586 -57.685686)
		(width 0.0889)
		(layer "In11.Cu")
		(net "M_J_DQ<32>")
	)
	(segment
		(start 115.16106 -30.605476)
		(end 115.477544 -30.92196)
		(width 0.14224)
		(layer "In11.Cu")
		(net "M_J_DQ<32>")
	)
	(segment
		(start 107.685586 -56.695086)
		(end 107.679236 -56.684418)
		(width 0.0889)
		(layer "In11.Cu")
		(net "M_J_DQ<32>")
	)
	(segment
		(start 107.588558 -52.081176)
		(end 108.27258 -51.397154)
		(width 0.0889)
		(layer "In11.Cu")
		(net "M_J_DQ<32>")
	)
	(segment
		(start 116.873782 -7.228586)
		(end 116.873782 -6.614414)
		(width 0.14224)
		(layer "In11.Cu")
		(net "M_J_DQ<32>")
	)
	(segment
		(start 116.11483 -3.3274)
		(end 116.85143 -2.5908)
		(width 0.14224)
		(layer "In11.Cu")
		(net "M_J_DQ<32>")
	)
	(segment
		(start 114.586258 -30.97911)
		(end 114.959892 -30.605476)
		(width 0.14224)
		(layer "In11.Cu")
		(net "M_J_DQ<32>")
	)
	(segment
		(start 116.436648 -0.508)
		(end 116.436648 -0.178054)
		(width 0.14224)
		(layer "In11.Cu")
		(net "M_J_DQ<32>")
	)
	(segment
		(start 116.837968 -21.754592)
		(end 116.837968 -21.2598)
		(width 0.14224)
		(layer "In11.Cu")
		(net "M_J_DQ<32>")
	)
	(segment
		(start 112.643412 -32.973264)
		(end 112.930178 -32.973264)
		(width 0.14224)
		(layer "In11.Cu")
		(net "M_J_DQ<32>")
	)
	(segment
		(start 116.11483 -4.073144)
		(end 116.11483 -3.3274)
		(width 0.14224)
		(layer "In11.Cu")
		(net "M_J_DQ<32>")
	)
	(segment
		(start 115.477544 -30.92196)
		(end 115.76431 -30.92196)
		(width 0.14224)
		(layer "In11.Cu")
		(net "M_J_DQ<32>")
	)
	(segment
		(start 107.588558 -52.837334)
		(end 107.588558 -52.081176)
		(width 0.0889)
		(layer "In11.Cu")
		(net "M_J_DQ<32>")
	)
	(segment
		(start 116.85143 -2.090928)
		(end 116.462048 -1.701546)
		(width 0.14224)
		(layer "In11.Cu")
		(net "M_J_DQ<32>")
	)
	(segment
		(start 116.863368 -9.4742)
		(end 116.863368 -8.9662)
		(width 0.14224)
		(layer "In11.Cu")
		(net "M_J_DQ<32>")
	)
	(segment
		(start 116.581682 -18.311114)
		(end 116.581682 -17.121886)
		(width 0.14224)
		(layer "In11.Cu")
		(net "M_J_DQ<32>")
	)
	(segment
		(start 116.736368 -9.6012)
		(end 116.863368 -9.4742)
		(width 0.14224)
		(layer "In11.Cu")
		(net "M_J_DQ<32>")
	)
	(segment
		(start 107.647486 -52.896262)
		(end 107.588558 -52.837334)
		(width 0.0889)
		(layer "In11.Cu")
		(net "M_J_DQ<32>")
	)
	(segment
		(start 112.60328 -34.08299)
		(end 112.60328 -33.795716)
		(width 0.14224)
		(layer "In11.Cu")
		(net "M_J_DQ<32>")
	)
	(segment
		(start 107.689396 -58.683398)
		(end 107.685332 -58.676286)
		(width 0.0889)
		(layer "In11.Cu")
		(net "M_J_DQ<32>")
	)
	(segment
		(start 116.882164 -25.965404)
		(end 116.882164 -23.374096)
		(width 0.14224)
		(layer "In11.Cu")
		(net "M_J_DQ<32>")
	)
	(segment
		(start 116.436648 -0.178054)
		(end 116.85143 0.236728)
		(width 0.14224)
		(layer "In11.Cu")
		(net "M_J_DQ<32>")
	)
	(segment
		(start 108.27258 -51.397154)
		(end 108.27258 -48.981614)
		(width 0.0889)
		(layer "In11.Cu")
		(net "M_J_DQ<32>")
	)
	(segment
		(start 116.924582 -13.853668)
		(end 116.581682 -13.510768)
		(width 0.14224)
		(layer "In11.Cu")
		(net "M_J_DQ<32>")
	)
	(segment
		(start 116.399564 -4.357878)
		(end 116.11483 -4.073144)
		(width 0.14224)
		(layer "In11.Cu")
		(net "M_J_DQ<32>")
	)
	(segment
		(start 108.27258 -48.981614)
		(end 108.117132 -48.826166)
		(width 0.0889)
		(layer "In11.Cu")
		(net "M_J_DQ<32>")
	)
	(segment
		(start 116.581682 -13.510768)
		(end 116.581682 -12.424156)
		(width 0.14224)
		(layer "In11.Cu")
		(net "M_J_DQ<32>")
	)
	(segment
		(start 107.685586 -57.685686)
		(end 107.679236 -57.675018)
		(width 0.0889)
		(layer "In11.Cu")
		(net "M_J_DQ<32>")
	)
	(segment
		(start 108.117132 -48.826166)
		(end 108.117132 -48.076612)
		(width 0.0889)
		(layer "In11.Cu")
		(net "M_J_DQ<32>")
	)
	(segment
		(start 116.873782 -6.614414)
		(end 116.399564 -6.140196)
		(width 0.14224)
		(layer "In11.Cu")
		(net "M_J_DQ<32>")
	)
	(segment
		(start 116.462048 -1.701546)
		(end 116.462048 -1.397)
		(width 0.14224)
		(layer "In11.Cu")
		(net "M_J_DQ<32>")
	)
	(segment
		(start 107.827826 -38.859968)
		(end 112.60328 -34.08299)
		(width 0.14224)
		(layer "In11.Cu")
		(net "M_J_DQ<32>")
	)
	(segment
		(start 116.581682 -8.684514)
		(end 116.581682 -7.520686)
		(width 0.14224)
		(layer "In11.Cu")
		(net "M_J_DQ<32>")
	)
	(segment
		(start 112.60328 -33.795716)
		(end 112.35563 -33.548066)
		(width 0.14224)
		(layer "In11.Cu")
		(net "M_J_DQ<32>")
	)
	(segment
		(start 116.837968 -12.16787)
		(end 116.837968 -11.698986)
		(width 0.14224)
		(layer "In11.Cu")
		(net "M_J_DQ<32>")
	)
	(arc
		(start 107.679236 -57.675018)
		(mid 107.606438 -57.384255)
		(end 107.685586 -57.095136)
		(width 0.0889)
		(layer "In11.Cu")
		(net "M_J_DQ<32>")
	)
	(arc
		(start 107.685586 -55.113936)
		(mid 107.725537 -55.017386)
		(end 107.73918 -54.913784)
		(width 0.0889)
		(layer "In11.Cu")
		(net "M_J_DQ<32>")
	)
	(arc
		(start 107.685332 -58.085482)
		(mid 107.738923 -57.89056)
		(end 107.690412 -57.694322)
		(width 0.0889)
		(layer "In11.Cu")
		(net "M_J_DQ<32>")
	)
	(arc
		(start 107.685586 -56.104536)
		(mid 107.739056 -55.909473)
		(end 107.690412 -55.713122)
		(width 0.0889)
		(layer "In11.Cu")
		(net "M_J_DQ<32>")
	)
	(arc
		(start 107.685332 -58.676286)
		(mid 107.606201 -58.380884)
		(end 107.685332 -58.085482)
		(width 0.0889)
		(layer "In11.Cu")
		(net "M_J_DQ<32>")
	)
	(arc
		(start 108.154978 -59.326526)
		(mid 107.905611 -59.016962)
		(end 107.689396 -58.683398)
		(width 0.0889)
		(layer "In11.Cu")
		(net "M_J_DQ<32>")
	)
	(arc
		(start 107.679236 -55.693818)
		(mid 107.606438 -55.403055)
		(end 107.685586 -55.113936)
		(width 0.0889)
		(layer "In11.Cu")
		(net "M_J_DQ<32>")
	)
	(arc
		(start 107.685586 -57.095136)
		(mid 107.739056 -56.900073)
		(end 107.690412 -56.703722)
		(width 0.0889)
		(layer "In11.Cu")
		(net "M_J_DQ<32>")
	)
	(arc
		(start 107.679236 -56.684418)
		(mid 107.606438 -56.393655)
		(end 107.685586 -56.104536)
		(width 0.0889)
		(layer "In11.Cu")
		(net "M_J_DQ<32>")
	)
	(segment
		(start 85.777832 -66.982086)
		(end 85.206332 -66.982086)
		(width 0.0889)
		(layer "F.Cu")
		(net "M_J_DQ<31>")
	)
	(segment
		(start 65.399412 3.778758)
		(end 65.399412 2.514854)
		(width 0.1651)
		(layer "F.Cu")
		(net "M_J_DQ<31>")
	)
	(via
		(at 65.399412 2.514854)
		(size 0.508)
		(drill 0.254)
		(layers "F.Cu" "B.Cu")
		(net "M_J_DQ<31>")
	)
	(via
		(at 85.206332 -66.982086)
		(size 0.508)
		(drill 0.254)
		(layers "F.Cu" "B.Cu")
		(net "M_J_DQ<31>")
	)
	(via
		(at 66.249296 -3.076956)
		(size 0.508)
		(drill 0.254)
		(layers "F.Cu" "B.Cu")
		(net "M_J_DQ<31>")
	)
	(segment
		(start 66.249296 -1.022096)
		(end 66.249296 -3.076956)
		(width 0.1651)
		(layer "B.Cu")
		(net "M_J_DQ<31>")
	)
	(segment
		(start 66.24955 -1.021842)
		(end 66.249296 -1.022096)
		(width 0.1651)
		(layer "B.Cu")
		(net "M_J_DQ<31>")
	)
	(segment
		(start 85.718142 -60.743338)
		(end 85.713316 -60.734702)
		(width 0.0889)
		(layer "In11.Cu")
		(net "M_J_DQ<31>")
	)
	(segment
		(start 66.793364 -26.866596)
		(end 66.627502 -26.700734)
		(width 0.14224)
		(layer "In11.Cu")
		(net "M_J_DQ<31>")
	)
	(segment
		(start 85.718142 -61.733938)
		(end 85.713316 -61.725302)
		(width 0.0889)
		(layer "In11.Cu")
		(net "M_J_DQ<31>")
	)
	(segment
		(start 85.724492 -61.744606)
		(end 85.718142 -61.733938)
		(width 0.0889)
		(layer "In11.Cu")
		(net "M_J_DQ<31>")
	)
	(segment
		(start 85.206332 -66.982086)
		(end 85.553042 -66.191638)
		(width 0.0889)
		(layer "In11.Cu")
		(net "M_J_DQ<31>")
	)
	(segment
		(start 85.718142 -54.799738)
		(end 85.674962 -54.724808)
		(width 0.0889)
		(layer "In11.Cu")
		(net "M_J_DQ<31>")
	)
	(segment
		(start 66.830702 -17.093946)
		(end 66.627502 -16.890746)
		(width 0.14224)
		(layer "In11.Cu")
		(net "M_J_DQ<31>")
	)
	(segment
		(start 73.937368 -38.615366)
		(end 73.937368 -36.238688)
		(width 0.14224)
		(layer "In11.Cu")
		(net "M_J_DQ<31>")
	)
	(segment
		(start 84.002372 -48.68037)
		(end 73.937368 -38.615366)
		(width 0.14224)
		(layer "In11.Cu")
		(net "M_J_DQ<31>")
	)
	(segment
		(start 66.602102 0.581152)
		(end 66.75755 0.7366)
		(width 0.14224)
		(layer "In11.Cu")
		(net "M_J_DQ<31>")
	)
	(segment
		(start 66.590164 -28.314396)
		(end 66.793364 -28.111196)
		(width 0.14224)
		(layer "In11.Cu")
		(net "M_J_DQ<31>")
	)
	(segment
		(start 66.602102 -2.72415)
		(end 66.602102 0.581152)
		(width 0.14224)
		(layer "In11.Cu")
		(net "M_J_DQ<31>")
	)
	(segment
		(start 66.793364 -28.111196)
		(end 66.793364 -26.866596)
		(width 0.14224)
		(layer "In11.Cu")
		(net "M_J_DQ<31>")
	)
	(segment
		(start 66.627502 -6.44017)
		(end 66.627502 -5.252212)
		(width 0.14224)
		(layer "In11.Cu")
		(net "M_J_DQ<31>")
	)
	(segment
		(start 66.30035 1.5494)
		(end 66.04635 1.5494)
		(width 0.14224)
		(layer "In11.Cu")
		(net "M_J_DQ<31>")
	)
	(segment
		(start 66.602102 -19.080734)
		(end 66.602102 -18.587466)
		(width 0.14224)
		(layer "In11.Cu")
		(net "M_J_DQ<31>")
	)
	(segment
		(start 85.724492 -59.763406)
		(end 85.718142 -59.752738)
		(width 0.0889)
		(layer "In11.Cu")
		(net "M_J_DQ<31>")
	)
	(segment
		(start 66.602102 -9.428734)
		(end 66.602102 -8.960866)
		(width 0.14224)
		(layer "In11.Cu")
		(net "M_J_DQ<31>")
	)
	(segment
		(start 66.749168 -9.5758)
		(end 66.602102 -9.428734)
		(width 0.14224)
		(layer "In11.Cu")
		(net "M_J_DQ<31>")
	)
	(segment
		(start 73.937368 -36.238688)
		(end 66.590164 -28.891484)
		(width 0.14224)
		(layer "In11.Cu")
		(net "M_J_DQ<31>")
	)
	(segment
		(start 84.887308 -52.543202)
		(end 83.660742 -51.316636)
		(width 0.0889)
		(layer "In11.Cu")
		(net "M_J_DQ<31>")
	)
	(segment
		(start 66.590164 -28.891484)
		(end 66.590164 -28.314396)
		(width 0.14224)
		(layer "In11.Cu")
		(net "M_J_DQ<31>")
	)
	(segment
		(start 85.713316 -55.398924)
		(end 85.718142 -55.390288)
		(width 0.0889)
		(layer "In11.Cu")
		(net "M_J_DQ<31>")
	)
	(segment
		(start 66.749168 -21.138134)
		(end 66.749168 -19.2278)
		(width 0.14224)
		(layer "In11.Cu")
		(net "M_J_DQ<31>")
	)
	(segment
		(start 85.724492 -55.801006)
		(end 85.718142 -55.790338)
		(width 0.0889)
		(layer "In11.Cu")
		(net "M_J_DQ<31>")
	)
	(segment
		(start 66.602102 -21.771356)
		(end 66.602102 -21.2852)
		(width 0.14224)
		(layer "In11.Cu")
		(net "M_J_DQ<31>")
	)
	(segment
		(start 66.627502 -16.890746)
		(end 66.627502 -13.694156)
		(width 0.14224)
		(layer "In11.Cu")
		(net "M_J_DQ<31>")
	)
	(segment
		(start 85.718142 -59.752738)
		(end 85.713316 -59.744102)
		(width 0.0889)
		(layer "In11.Cu")
		(net "M_J_DQ<31>")
	)
	(segment
		(start 66.805302 -21.974556)
		(end 66.602102 -21.771356)
		(width 0.14224)
		(layer "In11.Cu")
		(net "M_J_DQ<31>")
	)
	(segment
		(start 85.724492 -56.791606)
		(end 85.718142 -56.780938)
		(width 0.0889)
		(layer "In11.Cu")
		(net "M_J_DQ<31>")
	)
	(segment
		(start 66.627502 -5.252212)
		(end 66.157602 -4.782312)
		(width 0.14224)
		(layer "In11.Cu")
		(net "M_J_DQ<31>")
	)
	(segment
		(start 65.71615 1.8796)
		(end 65.71615 2.198116)
		(width 0.14224)
		(layer "In11.Cu")
		(net "M_J_DQ<31>")
	)
	(segment
		(start 66.627502 -13.694156)
		(end 66.805302 -13.516356)
		(width 0.14224)
		(layer "In11.Cu")
		(net "M_J_DQ<31>")
	)
	(segment
		(start 66.805302 -12.373356)
		(end 66.602102 -12.170156)
		(width 0.14224)
		(layer "In11.Cu")
		(net "M_J_DQ<31>")
	)
	(segment
		(start 66.602102 -18.587466)
		(end 66.830702 -18.358866)
		(width 0.14224)
		(layer "In11.Cu")
		(net "M_J_DQ<31>")
	)
	(segment
		(start 65.71615 2.198116)
		(end 65.399412 2.514854)
		(width 0.14224)
		(layer "In11.Cu")
		(net "M_J_DQ<31>")
	)
	(segment
		(start 85.724492 -62.735206)
		(end 85.718142 -62.724538)
		(width 0.0889)
		(layer "In11.Cu")
		(net "M_J_DQ<31>")
	)
	(segment
		(start 66.249296 -3.076956)
		(end 66.602102 -2.72415)
		(width 0.14224)
		(layer "In11.Cu")
		(net "M_J_DQ<31>")
	)
	(segment
		(start 66.805302 -13.516356)
		(end 66.805302 -12.373356)
		(width 0.14224)
		(layer "In11.Cu")
		(net "M_J_DQ<31>")
	)
	(segment
		(start 66.627502 -23.295356)
		(end 66.805302 -23.117556)
		(width 0.14224)
		(layer "In11.Cu")
		(net "M_J_DQ<31>")
	)
	(segment
		(start 84.002372 -49.636934)
		(end 84.002372 -48.68037)
		(width 0.14224)
		(layer "In11.Cu")
		(net "M_J_DQ<31>")
	)
	(segment
		(start 66.602102 -12.170156)
		(end 66.602102 -11.7348)
		(width 0.14224)
		(layer "In11.Cu")
		(net "M_J_DQ<31>")
	)
	(segment
		(start 83.660742 -51.316636)
		(end 83.660742 -50.227738)
		(width 0.0889)
		(layer "In11.Cu")
		(net "M_J_DQ<31>")
	)
	(segment
		(start 85.718142 -57.771538)
		(end 85.713316 -57.762902)
		(width 0.0889)
		(layer "In11.Cu")
		(net "M_J_DQ<31>")
	)
	(segment
		(start 85.674962 -54.724808)
		(end 84.887308 -53.937154)
		(width 0.0889)
		(layer "In11.Cu")
		(net "M_J_DQ<31>")
	)
	(segment
		(start 66.830702 -18.358866)
		(end 66.830702 -17.093946)
		(width 0.14224)
		(layer "In11.Cu")
		(net "M_J_DQ<31>")
	)
	(segment
		(start 66.749168 -19.2278)
		(end 66.602102 -19.080734)
		(width 0.14224)
		(layer "In11.Cu")
		(net "M_J_DQ<31>")
	)
	(segment
		(start 85.718142 -58.362088)
		(end 85.724492 -58.35142)
		(width 0.0889)
		(layer "In11.Cu")
		(net "M_J_DQ<31>")
	)
	(segment
		(start 83.816444 -50.072036)
		(end 83.816444 -49.822862)
		(width 0.0889)
		(layer "In11.Cu")
		(net "M_J_DQ<31>")
	)
	(segment
		(start 66.551302 -6.51637)
		(end 66.627502 -6.44017)
		(width 0.14224)
		(layer "In11.Cu")
		(net "M_J_DQ<31>")
	)
	(segment
		(start 66.602102 -11.7348)
		(end 66.749168 -11.587734)
		(width 0.14224)
		(layer "In11.Cu")
		(net "M_J_DQ<31>")
	)
	(segment
		(start 66.830702 -8.732266)
		(end 66.830702 -7.492746)
		(width 0.14224)
		(layer "In11.Cu")
		(net "M_J_DQ<31>")
	)
	(segment
		(start 66.04635 1.5494)
		(end 65.71615 1.8796)
		(width 0.14224)
		(layer "In11.Cu")
		(net "M_J_DQ<31>")
	)
	(segment
		(start 85.718142 -55.390288)
		(end 85.724492 -55.37962)
		(width 0.0889)
		(layer "In11.Cu")
		(net "M_J_DQ<31>")
	)
	(segment
		(start 65.789302 -4.067556)
		(end 65.789302 -3.53695)
		(width 0.14224)
		(layer "In11.Cu")
		(net "M_J_DQ<31>")
	)
	(segment
		(start 66.602102 -8.960866)
		(end 66.830702 -8.732266)
		(width 0.14224)
		(layer "In11.Cu")
		(net "M_J_DQ<31>")
	)
	(segment
		(start 83.816444 -49.822862)
		(end 84.002372 -49.636934)
		(width 0.0889)
		(layer "In11.Cu")
		(net "M_J_DQ<31>")
	)
	(segment
		(start 85.718142 -62.724538)
		(end 85.713316 -62.715902)
		(width 0.0889)
		(layer "In11.Cu")
		(net "M_J_DQ<31>")
	)
	(segment
		(start 85.718142 -56.780938)
		(end 85.713316 -56.772302)
		(width 0.0889)
		(layer "In11.Cu")
		(net "M_J_DQ<31>")
	)
	(segment
		(start 66.75755 0.7366)
		(end 66.75755 1.0922)
		(width 0.14224)
		(layer "In11.Cu")
		(net "M_J_DQ<31>")
	)
	(segment
		(start 84.887308 -53.937154)
		(end 84.887308 -52.543202)
		(width 0.0889)
		(layer "In11.Cu")
		(net "M_J_DQ<31>")
	)
	(segment
		(start 66.749168 -11.587734)
		(end 66.749168 -9.5758)
		(width 0.14224)
		(layer "In11.Cu")
		(net "M_J_DQ<31>")
	)
	(segment
		(start 66.805302 -23.117556)
		(end 66.805302 -21.974556)
		(width 0.14224)
		(layer "In11.Cu")
		(net "M_J_DQ<31>")
	)
	(segment
		(start 83.660742 -50.227738)
		(end 83.816444 -50.072036)
		(width 0.0889)
		(layer "In11.Cu")
		(net "M_J_DQ<31>")
	)
	(segment
		(start 66.830702 -7.492746)
		(end 66.551302 -7.213346)
		(width 0.14224)
		(layer "In11.Cu")
		(net "M_J_DQ<31>")
	)
	(segment
		(start 66.627502 -26.700734)
		(end 66.627502 -23.295356)
		(width 0.14224)
		(layer "In11.Cu")
		(net "M_J_DQ<31>")
	)
	(segment
		(start 66.157602 -4.435856)
		(end 65.789302 -4.067556)
		(width 0.14224)
		(layer "In11.Cu")
		(net "M_J_DQ<31>")
	)
	(segment
		(start 85.724492 -60.754006)
		(end 85.718142 -60.743338)
		(width 0.0889)
		(layer "In11.Cu")
		(net "M_J_DQ<31>")
	)
	(segment
		(start 66.551302 -7.213346)
		(end 66.551302 -6.51637)
		(width 0.14224)
		(layer "In11.Cu")
		(net "M_J_DQ<31>")
	)
	(segment
		(start 65.789302 -3.53695)
		(end 66.249296 -3.076956)
		(width 0.14224)
		(layer "In11.Cu")
		(net "M_J_DQ<31>")
	)
	(segment
		(start 66.602102 -21.2852)
		(end 66.749168 -21.138134)
		(width 0.14224)
		(layer "In11.Cu")
		(net "M_J_DQ<31>")
	)
	(segment
		(start 66.75755 1.0922)
		(end 66.30035 1.5494)
		(width 0.14224)
		(layer "In11.Cu")
		(net "M_J_DQ<31>")
	)
	(segment
		(start 66.157602 -4.782312)
		(end 66.157602 -4.435856)
		(width 0.14224)
		(layer "In11.Cu")
		(net "M_J_DQ<31>")
	)
	(arc
		(start 85.553042 -66.191638)
		(mid 85.600402 -66.061569)
		(end 85.60054 -65.92316)
		(width 0.0889)
		(layer "In11.Cu")
		(net "M_J_DQ<31>")
	)
	(arc
		(start 85.60054 -65.92316)
		(mid 85.605871 -65.599814)
		(end 85.718142 -65.296542)
		(width 0.0889)
		(layer "In11.Cu")
		(net "M_J_DQ<31>")
	)
	(arc
		(start 85.718142 -58.761884)
		(mid 85.664643 -58.561986)
		(end 85.718142 -58.362088)
		(width 0.0889)
		(layer "In11.Cu")
		(net "M_J_DQ<31>")
	)
	(arc
		(start 85.718142 -60.343288)
		(mid 85.797364 -60.05417)
		(end 85.724492 -59.763406)
		(width 0.0889)
		(layer "In11.Cu")
		(net "M_J_DQ<31>")
	)
	(arc
		(start 85.713316 -59.744102)
		(mid 85.664561 -59.54775)
		(end 85.718142 -59.352688)
		(width 0.0889)
		(layer "In11.Cu")
		(net "M_J_DQ<31>")
	)
	(arc
		(start 85.718142 -57.371488)
		(mid 85.797364 -57.08237)
		(end 85.724492 -56.791606)
		(width 0.0889)
		(layer "In11.Cu")
		(net "M_J_DQ<31>")
	)
	(arc
		(start 85.713316 -57.762902)
		(mid 85.664561 -57.56655)
		(end 85.718142 -57.371488)
		(width 0.0889)
		(layer "In11.Cu")
		(net "M_J_DQ<31>")
	)
	(arc
		(start 85.713316 -60.734702)
		(mid 85.664561 -60.53835)
		(end 85.718142 -60.343288)
		(width 0.0889)
		(layer "In11.Cu")
		(net "M_J_DQ<31>")
	)
	(arc
		(start 85.713316 -62.715902)
		(mid 85.664561 -62.51955)
		(end 85.718142 -62.324488)
		(width 0.0889)
		(layer "In11.Cu")
		(net "M_J_DQ<31>")
	)
	(arc
		(start 85.718142 -64.705738)
		(mid 85.664643 -64.50584)
		(end 85.718142 -64.305942)
		(width 0.0889)
		(layer "In11.Cu")
		(net "M_J_DQ<31>")
	)
	(arc
		(start 85.718142 -61.333888)
		(mid 85.797364 -61.04477)
		(end 85.724492 -60.754006)
		(width 0.0889)
		(layer "In11.Cu")
		(net "M_J_DQ<31>")
	)
	(arc
		(start 85.713316 -61.725302)
		(mid 85.664561 -61.52895)
		(end 85.718142 -61.333888)
		(width 0.0889)
		(layer "In11.Cu")
		(net "M_J_DQ<31>")
	)
	(arc
		(start 85.718142 -65.296542)
		(mid 85.797273 -65.00114)
		(end 85.718142 -64.705738)
		(width 0.0889)
		(layer "In11.Cu")
		(net "M_J_DQ<31>")
	)
	(arc
		(start 85.718142 -64.305942)
		(mid 85.797273 -64.01054)
		(end 85.718142 -63.715138)
		(width 0.0889)
		(layer "In11.Cu")
		(net "M_J_DQ<31>")
	)
	(arc
		(start 85.718142 -63.715138)
		(mid 85.664609 -63.51513)
		(end 85.718142 -63.315088)
		(width 0.0889)
		(layer "In11.Cu")
		(net "M_J_DQ<31>")
	)
	(arc
		(start 85.724492 -58.35142)
		(mid 85.79729 -58.060657)
		(end 85.718142 -57.771538)
		(width 0.0889)
		(layer "In11.Cu")
		(net "M_J_DQ<31>")
	)
	(arc
		(start 85.718142 -55.790338)
		(mid 85.664672 -55.595275)
		(end 85.713316 -55.398924)
		(width 0.0889)
		(layer "In11.Cu")
		(net "M_J_DQ<31>")
	)
	(arc
		(start 85.718142 -56.380888)
		(mid 85.797364 -56.09177)
		(end 85.724492 -55.801006)
		(width 0.0889)
		(layer "In11.Cu")
		(net "M_J_DQ<31>")
	)
	(arc
		(start 85.718142 -63.315088)
		(mid 85.797364 -63.02597)
		(end 85.724492 -62.735206)
		(width 0.0889)
		(layer "In11.Cu")
		(net "M_J_DQ<31>")
	)
	(arc
		(start 85.724492 -55.37962)
		(mid 85.79729 -55.088857)
		(end 85.718142 -54.799738)
		(width 0.0889)
		(layer "In11.Cu")
		(net "M_J_DQ<31>")
	)
	(arc
		(start 85.713316 -56.772302)
		(mid 85.664561 -56.57595)
		(end 85.718142 -56.380888)
		(width 0.0889)
		(layer "In11.Cu")
		(net "M_J_DQ<31>")
	)
	(arc
		(start 85.718142 -59.352688)
		(mid 85.797273 -59.057286)
		(end 85.718142 -58.761884)
		(width 0.0889)
		(layer "In11.Cu")
		(net "M_J_DQ<31>")
	)
	(arc
		(start 85.718142 -62.324488)
		(mid 85.797364 -62.03537)
		(end 85.724492 -61.744606)
		(width 0.0889)
		(layer "In11.Cu")
		(net "M_J_DQ<31>")
	)
	(segment
		(start 66.24955 0.635)
		(end 66.24955 0.939546)
		(width 0.1651)
		(layer "F.Cu")
		(net "M_J_DQ<30>")
	)
	(segment
		(start 85.777832 -65.000886)
		(end 85.206332 -65.000886)
		(width 0.0889)
		(layer "F.Cu")
		(net "M_J_DQ<30>")
	)
	(segment
		(start 66.24955 -0.821182)
		(end 66.24955 0.1524)
		(width 0.1651)
		(layer "F.Cu")
		(net "M_J_DQ<30>")
	)
	(segment
		(start 66.24955 0.939546)
		(end 66.249296 0.9398)
		(width 0.1651)
		(layer "F.Cu")
		(net "M_J_DQ<30>")
	)
	(segment
		(start 66.38163 0.28448)
		(end 66.38163 0.50292)
		(width 0.1651)
		(layer "F.Cu")
		(net "M_J_DQ<30>")
	)
	(segment
		(start 66.24955 0.1524)
		(end 66.38163 0.28448)
		(width 0.1651)
		(layer "F.Cu")
		(net "M_J_DQ<30>")
	)
	(segment
		(start 66.38163 0.50292)
		(end 66.24955 0.635)
		(width 0.1651)
		(layer "F.Cu")
		(net "M_J_DQ<30>")
	)
	(via
		(at 85.206332 -65.000886)
		(size 0.508)
		(drill 0.254)
		(layers "F.Cu" "B.Cu")
		(net "M_J_DQ<30>")
	)
	(via
		(at 66.249296 0.9398)
		(size 0.508)
		(drill 0.254)
		(layers "F.Cu" "B.Cu")
		(net "M_J_DQ<30>")
	)
	(via
		(at 65.399412 -4.357878)
		(size 0.508)
		(drill 0.254)
		(layers "F.Cu" "B.Cu")
		(net "M_J_DQ<30>")
	)
	(segment
		(start 65.399412 -5.621782)
		(end 65.399412 -4.357878)
		(width 0.1651)
		(layer "B.Cu")
		(net "M_J_DQ<30>")
	)
	(segment
		(start 65.891918 -0.768096)
		(end 65.891918 -1.111504)
		(width 0.14224)
		(layer "In11.Cu")
		(net "M_J_DQ<30>")
	)
	(segment
		(start 85.553042 -60.838588)
		(end 85.557868 -60.847224)
		(width 0.0889)
		(layer "In11.Cu")
		(net "M_J_DQ<30>")
	)
	(segment
		(start 85.546692 -56.86552)
		(end 85.553042 -56.876188)
		(width 0.0889)
		(layer "In11.Cu")
		(net "M_J_DQ<30>")
	)
	(segment
		(start 85.546692 -61.81852)
		(end 85.553042 -61.829188)
		(width 0.0889)
		(layer "In11.Cu")
		(net "M_J_DQ<30>")
	)
	(segment
		(start 85.553042 -58.857388)
		(end 85.557868 -58.866024)
		(width 0.0889)
		(layer "In11.Cu")
		(net "M_J_DQ<30>")
	)
	(segment
		(start 65.763902 -8.819134)
		(end 65.967102 -9.022334)
		(width 0.14224)
		(layer "In11.Cu")
		(net "M_J_DQ<30>")
	)
	(segment
		(start 65.763902 -12.373356)
		(end 65.763902 -13.567156)
		(width 0.14224)
		(layer "In11.Cu")
		(net "M_J_DQ<30>")
	)
	(segment
		(start 65.763902 -13.567156)
		(end 65.865502 -13.668756)
		(width 0.14224)
		(layer "In11.Cu")
		(net "M_J_DQ<30>")
	)
	(segment
		(start 84.696808 -54.016402)
		(end 85.522562 -54.842156)
		(width 0.0889)
		(layer "In11.Cu")
		(net "M_J_DQ<30>")
	)
	(segment
		(start 65.763902 -7.391146)
		(end 65.763902 -8.819134)
		(width 0.14224)
		(layer "In11.Cu")
		(net "M_J_DQ<30>")
	)
	(segment
		(start 72.27062 -35.470084)
		(end 72.27062 -35.689032)
		(width 0.14224)
		(layer "In11.Cu")
		(net "M_J_DQ<30>")
	)
	(segment
		(start 85.557868 -55.286402)
		(end 85.553042 -55.295038)
		(width 0.0889)
		(layer "In11.Cu")
		(net "M_J_DQ<30>")
	)
	(segment
		(start 85.553042 -56.876188)
		(end 85.557868 -56.884824)
		(width 0.0889)
		(layer "In11.Cu")
		(net "M_J_DQ<30>")
	)
	(segment
		(start 85.553042 -55.885588)
		(end 85.557868 -55.894224)
		(width 0.0889)
		(layer "In11.Cu")
		(net "M_J_DQ<30>")
	)
	(segment
		(start 65.929764 -28.314396)
		(end 65.929764 -29.129228)
		(width 0.14224)
		(layer "In11.Cu")
		(net "M_J_DQ<30>")
	)
	(segment
		(start 65.967102 -18.623534)
		(end 65.967102 -19.044666)
		(width 0.14224)
		(layer "In11.Cu")
		(net "M_J_DQ<30>")
	)
	(segment
		(start 65.809368 -19.2024)
		(end 65.809368 -21.208746)
		(width 0.14224)
		(layer "In11.Cu")
		(net "M_J_DQ<30>")
	)
	(segment
		(start 73.157334 -36.555934)
		(end 72.311768 -37.4015)
		(width 0.14224)
		(layer "In11.Cu")
		(net "M_J_DQ<30>")
	)
	(segment
		(start 85.553042 -58.266838)
		(end 85.546692 -58.277506)
		(width 0.0889)
		(layer "In11.Cu")
		(net "M_J_DQ<30>")
	)
	(segment
		(start 71.451216 -36.508436)
		(end 71.451216 -36.727384)
		(width 0.14224)
		(layer "In11.Cu")
		(net "M_J_DQ<30>")
	)
	(segment
		(start 72.311768 -37.4015)
		(end 72.311768 -37.88791)
		(width 0.14224)
		(layer "In11.Cu")
		(net "M_J_DQ<30>")
	)
	(segment
		(start 72.920098 -36.11753)
		(end 73.157334 -36.354766)
		(width 0.14224)
		(layer "In11.Cu")
		(net "M_J_DQ<30>")
	)
	(segment
		(start 65.916302 -7.238746)
		(end 65.763902 -7.391146)
		(width 0.14224)
		(layer "In11.Cu")
		(net "M_J_DQ<30>")
	)
	(segment
		(start 65.510918 -0.387096)
		(end 65.891918 -0.768096)
		(width 0.14224)
		(layer "In11.Cu")
		(net "M_J_DQ<30>")
	)
	(segment
		(start 65.967102 -21.771356)
		(end 65.763902 -21.974556)
		(width 0.14224)
		(layer "In11.Cu")
		(net "M_J_DQ<30>")
	)
	(segment
		(start 65.675764 -27.018996)
		(end 65.675764 -28.060396)
		(width 0.14224)
		(layer "In11.Cu")
		(net "M_J_DQ<30>")
	)
	(segment
		(start 83.411568 -49.633378)
		(end 83.405472 -49.639474)
		(width 0.14224)
		(layer "In11.Cu")
		(net "M_J_DQ<30>")
	)
	(segment
		(start 65.936368 -2.203196)
		(end 65.936368 -2.554986)
		(width 0.14224)
		(layer "In11.Cu")
		(net "M_J_DQ<30>")
	)
	(segment
		(start 65.891918 -1.111504)
		(end 65.510918 -1.492504)
		(width 0.14224)
		(layer "In11.Cu")
		(net "M_J_DQ<30>")
	)
	(segment
		(start 71.88962 -36.94684)
		(end 72.71893 -36.11753)
		(width 0.14224)
		(layer "In11.Cu")
		(net "M_J_DQ<30>")
	)
	(segment
		(start 65.763902 -23.168356)
		(end 65.865502 -23.269956)
		(width 0.14224)
		(layer "In11.Cu")
		(net "M_J_DQ<30>")
	)
	(segment
		(start 65.916302 -5.439156)
		(end 65.916302 -7.238746)
		(width 0.14224)
		(layer "In11.Cu")
		(net "M_J_DQ<30>")
	)
	(segment
		(start 65.763902 -21.974556)
		(end 65.763902 -23.168356)
		(width 0.14224)
		(layer "In11.Cu")
		(net "M_J_DQ<30>")
	)
	(segment
		(start 83.405472 -49.639474)
		(end 83.626452 -49.860454)
		(width 0.0889)
		(layer "In11.Cu")
		(net "M_J_DQ<30>")
	)
	(segment
		(start 65.675764 -28.060396)
		(end 65.929764 -28.314396)
		(width 0.14224)
		(layer "In11.Cu")
		(net "M_J_DQ<30>")
	)
	(segment
		(start 65.936368 -2.554986)
		(end 65.1637 -3.327654)
		(width 0.14224)
		(layer "In11.Cu")
		(net "M_J_DQ<30>")
	)
	(segment
		(start 72.27062 -35.689032)
		(end 71.451216 -36.508436)
		(width 0.14224)
		(layer "In11.Cu")
		(net "M_J_DQ<30>")
	)
	(segment
		(start 85.553042 -61.829188)
		(end 85.557868 -61.837824)
		(width 0.0889)
		(layer "In11.Cu")
		(net "M_J_DQ<30>")
	)
	(segment
		(start 85.553042 -59.847988)
		(end 85.557868 -59.856624)
		(width 0.0889)
		(layer "In11.Cu")
		(net "M_J_DQ<30>")
	)
	(segment
		(start 85.553042 -62.819788)
		(end 85.557868 -62.828424)
		(width 0.0889)
		(layer "In11.Cu")
		(net "M_J_DQ<30>")
	)
	(segment
		(start 72.311768 -37.88791)
		(end 83.411568 -48.98771)
		(width 0.14224)
		(layer "In11.Cu")
		(net "M_J_DQ<30>")
	)
	(segment
		(start 65.865502 -16.890746)
		(end 65.763902 -16.992346)
		(width 0.14224)
		(layer "In11.Cu")
		(net "M_J_DQ<30>")
	)
	(segment
		(start 65.865502 -26.829258)
		(end 65.675764 -27.018996)
		(width 0.14224)
		(layer "In11.Cu")
		(net "M_J_DQ<30>")
	)
	(segment
		(start 85.546692 -60.82792)
		(end 85.553042 -60.838588)
		(width 0.0889)
		(layer "In11.Cu")
		(net "M_J_DQ<30>")
	)
	(segment
		(start 65.763902 -16.992346)
		(end 65.763902 -18.420334)
		(width 0.14224)
		(layer "In11.Cu")
		(net "M_J_DQ<30>")
	)
	(segment
		(start 65.967102 -21.36648)
		(end 65.967102 -21.771356)
		(width 0.14224)
		(layer "In11.Cu")
		(net "M_J_DQ<30>")
	)
	(segment
		(start 65.510918 -1.492504)
		(end 65.510918 -1.777746)
		(width 0.14224)
		(layer "In11.Cu")
		(net "M_J_DQ<30>")
	)
	(segment
		(start 72.71893 -36.11753)
		(end 72.920098 -36.11753)
		(width 0.14224)
		(layer "In11.Cu")
		(net "M_J_DQ<30>")
	)
	(segment
		(start 85.519768 -64.277494)
		(end 85.206332 -65.000886)
		(width 0.0889)
		(layer "In11.Cu")
		(net "M_J_DQ<30>")
	)
	(segment
		(start 65.399412 -4.922266)
		(end 65.916302 -5.439156)
		(width 0.14224)
		(layer "In11.Cu")
		(net "M_J_DQ<30>")
	)
	(segment
		(start 65.510918 -1.777746)
		(end 65.936368 -2.203196)
		(width 0.14224)
		(layer "In11.Cu")
		(net "M_J_DQ<30>")
	)
	(segment
		(start 65.783968 -9.5758)
		(end 65.783968 -11.602466)
		(width 0.14224)
		(layer "In11.Cu")
		(net "M_J_DQ<30>")
	)
	(segment
		(start 83.626452 -49.992534)
		(end 83.470242 -50.148744)
		(width 0.0889)
		(layer "In11.Cu")
		(net "M_J_DQ<30>")
	)
	(segment
		(start 65.1637 -3.327654)
		(end 65.1637 -4.122166)
		(width 0.14224)
		(layer "In11.Cu")
		(net "M_J_DQ<30>")
	)
	(segment
		(start 71.451216 -36.727384)
		(end 71.670672 -36.94684)
		(width 0.14224)
		(layer "In11.Cu")
		(net "M_J_DQ<30>")
	)
	(segment
		(start 65.1637 -4.122166)
		(end 65.399412 -4.357878)
		(width 0.14224)
		(layer "In11.Cu")
		(net "M_J_DQ<30>")
	)
	(segment
		(start 65.8749 0.565404)
		(end 65.8749 0.287528)
		(width 0.14224)
		(layer "In11.Cu")
		(net "M_J_DQ<30>")
	)
	(segment
		(start 83.411568 -48.98771)
		(end 83.411568 -49.633378)
		(width 0.14224)
		(layer "In11.Cu")
		(net "M_J_DQ<30>")
	)
	(segment
		(start 73.157334 -36.354766)
		(end 73.157334 -36.555934)
		(width 0.14224)
		(layer "In11.Cu")
		(net "M_J_DQ<30>")
	)
	(segment
		(start 85.553042 -55.295038)
		(end 85.546692 -55.305706)
		(width 0.0889)
		(layer "In11.Cu")
		(net "M_J_DQ<30>")
	)
	(segment
		(start 65.510918 -0.076454)
		(end 65.510918 -0.387096)
		(width 0.14224)
		(layer "In11.Cu")
		(net "M_J_DQ<30>")
	)
	(segment
		(start 66.249296 0.9398)
		(end 65.8749 0.565404)
		(width 0.14224)
		(layer "In11.Cu")
		(net "M_J_DQ<30>")
	)
	(segment
		(start 65.929764 -29.129228)
		(end 72.27062 -35.470084)
		(width 0.14224)
		(layer "In11.Cu")
		(net "M_J_DQ<30>")
	)
	(segment
		(start 85.522562 -54.842156)
		(end 85.553042 -54.894988)
		(width 0.0889)
		(layer "In11.Cu")
		(net "M_J_DQ<30>")
	)
	(segment
		(start 71.670672 -36.94684)
		(end 71.88962 -36.94684)
		(width 0.14224)
		(layer "In11.Cu")
		(net "M_J_DQ<30>")
	)
	(segment
		(start 65.763902 -18.420334)
		(end 65.967102 -18.623534)
		(width 0.14224)
		(layer "In11.Cu")
		(net "M_J_DQ<30>")
	)
	(segment
		(start 85.546692 -62.80912)
		(end 85.553042 -62.819788)
		(width 0.0889)
		(layer "In11.Cu")
		(net "M_J_DQ<30>")
	)
	(segment
		(start 65.967102 -19.044666)
		(end 65.809368 -19.2024)
		(width 0.14224)
		(layer "In11.Cu")
		(net "M_J_DQ<30>")
	)
	(segment
		(start 65.399412 -4.357878)
		(end 65.399412 -4.922266)
		(width 0.14224)
		(layer "In11.Cu")
		(net "M_J_DQ<30>")
	)
	(segment
		(start 65.967102 -9.392666)
		(end 65.783968 -9.5758)
		(width 0.14224)
		(layer "In11.Cu")
		(net "M_J_DQ<30>")
	)
	(segment
		(start 65.809368 -21.208746)
		(end 65.967102 -21.36648)
		(width 0.14224)
		(layer "In11.Cu")
		(net "M_J_DQ<30>")
	)
	(segment
		(start 65.967102 -11.7856)
		(end 65.967102 -12.170156)
		(width 0.14224)
		(layer "In11.Cu")
		(net "M_J_DQ<30>")
	)
	(segment
		(start 65.865502 -23.269956)
		(end 65.865502 -26.829258)
		(width 0.14224)
		(layer "In11.Cu")
		(net "M_J_DQ<30>")
	)
	(segment
		(start 65.783968 -11.602466)
		(end 65.967102 -11.7856)
		(width 0.14224)
		(layer "In11.Cu")
		(net "M_J_DQ<30>")
	)
	(segment
		(start 83.470242 -51.395884)
		(end 84.696808 -52.62245)
		(width 0.0889)
		(layer "In11.Cu")
		(net "M_J_DQ<30>")
	)
	(segment
		(start 65.967102 -12.170156)
		(end 65.763902 -12.373356)
		(width 0.14224)
		(layer "In11.Cu")
		(net "M_J_DQ<30>")
	)
	(segment
		(start 84.696808 -52.62245)
		(end 84.696808 -54.016402)
		(width 0.0889)
		(layer "In11.Cu")
		(net "M_J_DQ<30>")
	)
	(segment
		(start 65.8749 0.287528)
		(end 65.510918 -0.076454)
		(width 0.14224)
		(layer "In11.Cu")
		(net "M_J_DQ<30>")
	)
	(segment
		(start 83.470242 -50.148744)
		(end 83.470242 -51.395884)
		(width 0.0889)
		(layer "In11.Cu")
		(net "M_J_DQ<30>")
	)
	(segment
		(start 65.865502 -13.668756)
		(end 65.865502 -16.890746)
		(width 0.14224)
		(layer "In11.Cu")
		(net "M_J_DQ<30>")
	)
	(segment
		(start 65.967102 -9.022334)
		(end 65.967102 -9.392666)
		(width 0.14224)
		(layer "In11.Cu")
		(net "M_J_DQ<30>")
	)
	(segment
		(start 85.546692 -59.83732)
		(end 85.553042 -59.847988)
		(width 0.0889)
		(layer "In11.Cu")
		(net "M_J_DQ<30>")
	)
	(segment
		(start 83.626452 -49.860454)
		(end 83.626452 -49.992534)
		(width 0.0889)
		(layer "In11.Cu")
		(net "M_J_DQ<30>")
	)
	(arc
		(start 85.553042 -63.810642)
		(mid 85.606541 -64.01054)
		(end 85.553042 -64.210438)
		(width 0.0889)
		(layer "In11.Cu")
		(net "M_J_DQ<30>")
	)
	(arc
		(start 85.557868 -62.828424)
		(mid 85.606623 -63.024776)
		(end 85.553042 -63.219838)
		(width 0.0889)
		(layer "In11.Cu")
		(net "M_J_DQ<30>")
	)
	(arc
		(start 85.557868 -60.847224)
		(mid 85.606623 -61.043576)
		(end 85.553042 -61.238638)
		(width 0.0889)
		(layer "In11.Cu")
		(net "M_J_DQ<30>")
	)
	(arc
		(start 85.553042 -54.894988)
		(mid 85.606512 -55.090051)
		(end 85.557868 -55.286402)
		(width 0.0889)
		(layer "In11.Cu")
		(net "M_J_DQ<30>")
	)
	(arc
		(start 85.557868 -56.884824)
		(mid 85.606623 -57.081176)
		(end 85.553042 -57.276238)
		(width 0.0889)
		(layer "In11.Cu")
		(net "M_J_DQ<30>")
	)
	(arc
		(start 85.553042 -61.238638)
		(mid 85.47382 -61.527756)
		(end 85.546692 -61.81852)
		(width 0.0889)
		(layer "In11.Cu")
		(net "M_J_DQ<30>")
	)
	(arc
		(start 85.553042 -63.219838)
		(mid 85.473979 -63.51524)
		(end 85.553042 -63.810642)
		(width 0.0889)
		(layer "In11.Cu")
		(net "M_J_DQ<30>")
	)
	(arc
		(start 85.557868 -59.856624)
		(mid 85.606623 -60.052976)
		(end 85.553042 -60.248038)
		(width 0.0889)
		(layer "In11.Cu")
		(net "M_J_DQ<30>")
	)
	(arc
		(start 85.553042 -57.276238)
		(mid 85.473911 -57.57164)
		(end 85.553042 -57.867042)
		(width 0.0889)
		(layer "In11.Cu")
		(net "M_J_DQ<30>")
	)
	(arc
		(start 85.553042 -62.229238)
		(mid 85.47382 -62.518356)
		(end 85.546692 -62.80912)
		(width 0.0889)
		(layer "In11.Cu")
		(net "M_J_DQ<30>")
	)
	(arc
		(start 85.553042 -60.248038)
		(mid 85.47382 -60.537156)
		(end 85.546692 -60.82792)
		(width 0.0889)
		(layer "In11.Cu")
		(net "M_J_DQ<30>")
	)
	(arc
		(start 85.557868 -61.837824)
		(mid 85.606623 -62.034176)
		(end 85.553042 -62.229238)
		(width 0.0889)
		(layer "In11.Cu")
		(net "M_J_DQ<30>")
	)
	(arc
		(start 85.557868 -55.894224)
		(mid 85.606623 -56.090576)
		(end 85.553042 -56.285638)
		(width 0.0889)
		(layer "In11.Cu")
		(net "M_J_DQ<30>")
	)
	(arc
		(start 85.553042 -64.210438)
		(mid 85.53534 -64.243438)
		(end 85.519768 -64.277494)
		(width 0.0889)
		(layer "In11.Cu")
		(net "M_J_DQ<30>")
	)
	(arc
		(start 85.553042 -57.867042)
		(mid 85.606541 -58.06694)
		(end 85.553042 -58.266838)
		(width 0.0889)
		(layer "In11.Cu")
		(net "M_J_DQ<30>")
	)
	(arc
		(start 85.553042 -56.285638)
		(mid 85.47382 -56.574756)
		(end 85.546692 -56.86552)
		(width 0.0889)
		(layer "In11.Cu")
		(net "M_J_DQ<30>")
	)
	(arc
		(start 85.546692 -58.277506)
		(mid 85.473894 -58.568269)
		(end 85.553042 -58.857388)
		(width 0.0889)
		(layer "In11.Cu")
		(net "M_J_DQ<30>")
	)
	(arc
		(start 85.546692 -55.305706)
		(mid 85.473894 -55.596469)
		(end 85.553042 -55.885588)
		(width 0.0889)
		(layer "In11.Cu")
		(net "M_J_DQ<30>")
	)
	(arc
		(start 85.557868 -58.866024)
		(mid 85.606623 -59.062376)
		(end 85.553042 -59.257438)
		(width 0.0889)
		(layer "In11.Cu")
		(net "M_J_DQ<30>")
	)
	(arc
		(start 85.553042 -59.257438)
		(mid 85.47382 -59.546556)
		(end 85.546692 -59.83732)
		(width 0.0889)
		(layer "In11.Cu")
		(net "M_J_DQ<30>")
	)
	(segment
		(start 75.475846 -64.010286)
		(end 74.904346 -64.010286)
		(width 0.0889)
		(layer "F.Cu")
		(net "M_J_DQ<2>")
	)
	(segment
		(start 39.899336 0.662432)
		(end 39.899336 0.9398)
		(width 0.1651)
		(layer "F.Cu")
		(net "M_J_DQ<2>")
	)
	(segment
		(start 39.899336 -0.821182)
		(end 39.899336 0.175768)
		(width 0.1651)
		(layer "F.Cu")
		(net "M_J_DQ<2>")
	)
	(segment
		(start 40.030908 0.53086)
		(end 39.899336 0.662432)
		(width 0.1651)
		(layer "F.Cu")
		(net "M_J_DQ<2>")
	)
	(segment
		(start 40.030908 0.30734)
		(end 40.030908 0.53086)
		(width 0.1651)
		(layer "F.Cu")
		(net "M_J_DQ<2>")
	)
	(segment
		(start 39.899336 0.175768)
		(end 40.030908 0.30734)
		(width 0.1651)
		(layer "F.Cu")
		(net "M_J_DQ<2>")
	)
	(via
		(at 74.904346 -64.010286)
		(size 0.508)
		(drill 0.254)
		(layers "F.Cu" "B.Cu")
		(net "M_J_DQ<2>")
	)
	(via
		(at 39.899336 0.9398)
		(size 0.508)
		(drill 0.254)
		(layers "F.Cu" "B.Cu")
		(net "M_J_DQ<2>")
	)
	(via
		(at 39.049452 -4.357878)
		(size 0.508)
		(drill 0.254)
		(layers "F.Cu" "B.Cu")
		(net "M_J_DQ<2>")
	)
	(segment
		(start 39.049452 -5.621782)
		(end 39.049452 -4.357878)
		(width 0.1651)
		(layer "B.Cu")
		(net "M_J_DQ<2>")
	)
	(segment
		(start 47.371762 -45.422312)
		(end 47.371762 -45.64126)
		(width 0.14224)
		(layer "In11.Cu")
		(net "M_J_DQ<2>")
	)
	(segment
		(start 67.869816 -61.629036)
		(end 68.047362 -61.629036)
		(width 0.0889)
		(layer "In11.Cu")
		(net "M_J_DQ<2>")
	)
	(segment
		(start 59.123072 -58.692288)
		(end 60.01512 -58.692288)
		(width 0.14224)
		(layer "In11.Cu")
		(net "M_J_DQ<2>")
	)
	(segment
		(start 39.418768 -21.237448)
		(end 39.54272 -21.3614)
		(width 0.14224)
		(layer "In11.Cu")
		(net "M_J_DQ<2>")
	)
	(segment
		(start 39.41572 -16.966946)
		(end 39.41572 -18.437098)
		(width 0.14224)
		(layer "In11.Cu")
		(net "M_J_DQ<2>")
	)
	(segment
		(start 51.474116 -50.964846)
		(end 51.693064 -50.964846)
		(width 0.14224)
		(layer "In11.Cu")
		(net "M_J_DQ<2>")
	)
	(segment
		(start 71.448676 -62.619636)
		(end 71.481442 -62.619636)
		(width 0.0889)
		(layer "In11.Cu")
		(net "M_J_DQ<2>")
	)
	(segment
		(start 39.461186 -1.04775)
		(end 39.461186 -0.761746)
		(width 0.14224)
		(layer "In11.Cu")
		(net "M_J_DQ<2>")
	)
	(segment
		(start 50.878994 -49.148492)
		(end 50.377852 -49.649634)
		(width 0.14224)
		(layer "In11.Cu")
		(net "M_J_DQ<2>")
	)
	(segment
		(start 47.090076 -46.580806)
		(end 47.309024 -46.580806)
		(width 0.14224)
		(layer "In11.Cu")
		(net "M_J_DQ<2>")
	)
	(segment
		(start 52.131468 -51.40325)
		(end 52.131468 -51.622198)
		(width 0.14224)
		(layer "In11.Cu")
		(net "M_J_DQ<2>")
	)
	(segment
		(start 39.156386 -1.35255)
		(end 39.461186 -1.04775)
		(width 0.14224)
		(layer "In11.Cu")
		(net "M_J_DQ<2>")
	)
	(segment
		(start 74.183748 -64.10579)
		(end 74.893932 -64.02324)
		(width 0.0889)
		(layer "In11.Cu")
		(net "M_J_DQ<2>")
	)
	(segment
		(start 48.24857 -46.518068)
		(end 47.747428 -47.01921)
		(width 0.14224)
		(layer "In11.Cu")
		(net "M_J_DQ<2>")
	)
	(segment
		(start 39.41572 -8.810498)
		(end 39.54272 -8.937498)
		(width 0.14224)
		(layer "In11.Cu")
		(net "M_J_DQ<2>")
	)
	(segment
		(start 39.63162 -16.751046)
		(end 39.41572 -16.966946)
		(width 0.14224)
		(layer "In11.Cu")
		(net "M_J_DQ<2>")
	)
	(segment
		(start 48.686974 -46.956472)
		(end 48.905922 -46.956472)
		(width 0.14224)
		(layer "In11.Cu")
		(net "M_J_DQ<2>")
	)
	(segment
		(start 39.41572 -7.365746)
		(end 39.41572 -8.810498)
		(width 0.14224)
		(layer "In11.Cu")
		(net "M_J_DQ<2>")
	)
	(segment
		(start 39.39032 -23.142956)
		(end 39.545768 -23.298404)
		(width 0.14224)
		(layer "In11.Cu")
		(net "M_J_DQ<2>")
	)
	(segment
		(start 51.25466 -50.74539)
		(end 51.474116 -50.964846)
		(width 0.14224)
		(layer "In11.Cu")
		(net "M_J_DQ<2>")
	)
	(segment
		(start 51.317398 -49.586896)
		(end 51.536346 -49.586896)
		(width 0.14224)
		(layer "In11.Cu")
		(net "M_J_DQ<2>")
	)
	(segment
		(start 66.775838 -62.068456)
		(end 66.775838 -62.068964)
		(width 0.0889)
		(layer "In11.Cu")
		(net "M_J_DQ<2>")
	)
	(segment
		(start 39.393368 -11.6078)
		(end 39.54272 -11.757152)
		(width 0.14224)
		(layer "In11.Cu")
		(net "M_J_DQ<2>")
	)
	(segment
		(start 50.878994 -48.929544)
		(end 50.878994 -49.148492)
		(width 0.14224)
		(layer "In11.Cu")
		(net "M_J_DQ<2>")
	)
	(segment
		(start 52.194206 -50.463704)
		(end 52.413154 -50.463704)
		(width 0.14224)
		(layer "In11.Cu")
		(net "M_J_DQ<2>")
	)
	(segment
		(start 39.545768 -23.298404)
		(end 39.545768 -25.603454)
		(width 0.14224)
		(layer "In11.Cu")
		(net "M_J_DQ<2>")
	)
	(segment
		(start 39.291768 -4.600194)
		(end 39.291768 -6.530848)
		(width 0.14224)
		(layer "In11.Cu")
		(net "M_J_DQ<2>")
	)
	(segment
		(start 51.536346 -49.586896)
		(end 51.755802 -49.806352)
		(width 0.14224)
		(layer "In11.Cu")
		(net "M_J_DQ<2>")
	)
	(segment
		(start 49.501044 -48.772826)
		(end 49.501044 -48.991774)
		(width 0.14224)
		(layer "In11.Cu")
		(net "M_J_DQ<2>")
	)
	(segment
		(start 39.54272 -21.3614)
		(end 39.54272 -21.796756)
		(width 0.14224)
		(layer "In11.Cu")
		(net "M_J_DQ<2>")
	)
	(segment
		(start 39.156386 -1.7526)
		(end 39.156386 -1.35255)
		(width 0.14224)
		(layer "In11.Cu")
		(net "M_J_DQ<2>")
	)
	(segment
		(start 52.63261 -50.902108)
		(end 52.131468 -51.40325)
		(width 0.14224)
		(layer "In11.Cu")
		(net "M_J_DQ<2>")
	)
	(segment
		(start 50.659538 -48.710088)
		(end 50.878994 -48.929544)
		(width 0.14224)
		(layer "In11.Cu")
		(net "M_J_DQ<2>")
	)
	(segment
		(start 39.54272 -11.757152)
		(end 39.54272 -12.195556)
		(width 0.14224)
		(layer "In11.Cu")
		(net "M_J_DQ<2>")
	)
	(segment
		(start 66.2432 -61.62929)
		(end 66.243962 -61.628528)
		(width 0.0889)
		(layer "In11.Cu")
		(net "M_J_DQ<2>")
	)
	(segment
		(start 53.071014 -51.340512)
		(end 53.289962 -51.340512)
		(width 0.14224)
		(layer "In11.Cu")
		(net "M_J_DQ<2>")
	)
	(segment
		(start 53.289962 -51.340512)
		(end 53.719984 -51.770534)
		(width 0.14224)
		(layer "In11.Cu")
		(net "M_J_DQ<2>")
	)
	(segment
		(start 39.54272 -19.027648)
		(end 39.418768 -19.1516)
		(width 0.14224)
		(layer "In11.Cu")
		(net "M_J_DQ<2>")
	)
	(segment
		(start 50.377852 -49.649634)
		(end 50.377852 -49.868582)
		(width 0.14224)
		(layer "In11.Cu")
		(net "M_J_DQ<2>")
	)
	(segment
		(start 39.156386 -0.108204)
		(end 39.501318 0.236728)
		(width 0.14224)
		(layer "In11.Cu")
		(net "M_J_DQ<2>")
	)
	(segment
		(start 50.377852 -49.868582)
		(end 50.597308 -50.088038)
		(width 0.14224)
		(layer "In11.Cu")
		(net "M_J_DQ<2>")
	)
	(segment
		(start 39.834312 -25.891998)
		(end 39.834312 -32.537146)
		(width 0.14224)
		(layer "In11.Cu")
		(net "M_J_DQ<2>")
	)
	(segment
		(start 39.139368 -32.821626)
		(end 39.139368 -33.187386)
		(width 0.14224)
		(layer "In11.Cu")
		(net "M_J_DQ<2>")
	)
	(segment
		(start 49.563782 -47.83328)
		(end 49.78273 -47.83328)
		(width 0.14224)
		(layer "In11.Cu")
		(net "M_J_DQ<2>")
	)
	(segment
		(start 72.311006 -63.11519)
		(end 72.343772 -63.11519)
		(width 0.0889)
		(layer "In11.Cu")
		(net "M_J_DQ<2>")
	)
	(segment
		(start 39.156386 -0.456946)
		(end 39.156386 -0.108204)
		(width 0.14224)
		(layer "In11.Cu")
		(net "M_J_DQ<2>")
	)
	(segment
		(start 39.834312 -33.471866)
		(end 39.834312 -37.884862)
		(width 0.14224)
		(layer "In11.Cu")
		(net "M_J_DQ<2>")
	)
	(segment
		(start 39.54272 -18.564098)
		(end 39.54272 -19.027648)
		(width 0.14224)
		(layer "In11.Cu")
		(net "M_J_DQ<2>")
	)
	(segment
		(start 39.418768 -19.1516)
		(end 39.418768 -21.237448)
		(width 0.14224)
		(layer "In11.Cu")
		(net "M_J_DQ<2>")
	)
	(segment
		(start 74.893932 -64.02324)
		(end 74.904346 -64.010286)
		(width 0.0889)
		(layer "In11.Cu")
		(net "M_J_DQ<2>")
	)
	(segment
		(start 39.54272 -8.937498)
		(end 39.54272 -9.3472)
		(width 0.14224)
		(layer "In11.Cu")
		(net "M_J_DQ<2>")
	)
	(segment
		(start 53.719984 -53.2892)
		(end 59.123072 -58.692288)
		(width 0.14224)
		(layer "In11.Cu")
		(net "M_J_DQ<2>")
	)
	(segment
		(start 39.281608 -33.329626)
		(end 39.692072 -33.329626)
		(width 0.14224)
		(layer "In11.Cu")
		(net "M_J_DQ<2>")
	)
	(segment
		(start 52.413154 -50.463704)
		(end 52.63261 -50.68316)
		(width 0.14224)
		(layer "In11.Cu")
		(net "M_J_DQ<2>")
	)
	(segment
		(start 70.593966 -62.12459)
		(end 70.626732 -62.12459)
		(width 0.0889)
		(layer "In11.Cu")
		(net "M_J_DQ<2>")
	)
	(segment
		(start 39.501318 0.236728)
		(end 39.501318 0.541782)
		(width 0.14224)
		(layer "In11.Cu")
		(net "M_J_DQ<2>")
	)
	(segment
		(start 39.39032 -21.949156)
		(end 39.39032 -23.142956)
		(width 0.14224)
		(layer "In11.Cu")
		(net "M_J_DQ<2>")
	)
	(segment
		(start 49.78273 -47.83328)
		(end 50.002186 -48.052736)
		(width 0.14224)
		(layer "In11.Cu")
		(net "M_J_DQ<2>")
	)
	(segment
		(start 39.393368 -9.496552)
		(end 39.393368 -11.6078)
		(width 0.14224)
		(layer "In11.Cu")
		(net "M_J_DQ<2>")
	)
	(segment
		(start 48.624236 -47.896018)
		(end 48.624236 -48.114966)
		(width 0.14224)
		(layer "In11.Cu")
		(net "M_J_DQ<2>")
	)
	(segment
		(start 46.87062 -46.142402)
		(end 46.87062 -46.36135)
		(width 0.14224)
		(layer "In11.Cu")
		(net "M_J_DQ<2>")
	)
	(segment
		(start 48.843692 -48.334422)
		(end 49.06264 -48.334422)
		(width 0.14224)
		(layer "In11.Cu")
		(net "M_J_DQ<2>")
	)
	(segment
		(start 39.501318 0.541782)
		(end 39.899336 0.9398)
		(width 0.14224)
		(layer "In11.Cu")
		(net "M_J_DQ<2>")
	)
	(segment
		(start 49.06264 -48.334422)
		(end 49.563782 -47.83328)
		(width 0.14224)
		(layer "In11.Cu")
		(net "M_J_DQ<2>")
	)
	(segment
		(start 48.24857 -46.29912)
		(end 48.24857 -46.518068)
		(width 0.14224)
		(layer "In11.Cu")
		(net "M_J_DQ<2>")
	)
	(segment
		(start 47.371762 -45.64126)
		(end 46.87062 -46.142402)
		(width 0.14224)
		(layer "In11.Cu")
		(net "M_J_DQ<2>")
	)
	(segment
		(start 66.336164 -61.628528)
		(end 66.776092 -62.068456)
		(width 0.0889)
		(layer "In11.Cu")
		(net "M_J_DQ<2>")
	)
	(segment
		(start 39.61892 -6.858)
		(end 39.61892 -7.162546)
		(width 0.14224)
		(layer "In11.Cu")
		(net "M_J_DQ<2>")
	)
	(segment
		(start 50.002186 -48.052736)
		(end 50.002186 -48.271684)
		(width 0.14224)
		(layer "In11.Cu")
		(net "M_J_DQ<2>")
	)
	(segment
		(start 66.775838 -62.068964)
		(end 66.831464 -62.12459)
		(width 0.0889)
		(layer "In11.Cu")
		(net "M_J_DQ<2>")
	)
	(segment
		(start 47.747428 -47.238158)
		(end 47.966884 -47.457614)
		(width 0.14224)
		(layer "In11.Cu")
		(net "M_J_DQ<2>")
	)
	(segment
		(start 51.755802 -49.806352)
		(end 51.755802 -50.0253)
		(width 0.14224)
		(layer "In11.Cu")
		(net "M_J_DQ<2>")
	)
	(segment
		(start 39.692072 -32.679386)
		(end 39.281608 -32.679386)
		(width 0.14224)
		(layer "In11.Cu")
		(net "M_J_DQ<2>")
	)
	(segment
		(start 39.291768 -6.530848)
		(end 39.61892 -6.858)
		(width 0.14224)
		(layer "In11.Cu")
		(net "M_J_DQ<2>")
	)
	(segment
		(start 39.54272 -21.796756)
		(end 39.39032 -21.949156)
		(width 0.14224)
		(layer "In11.Cu")
		(net "M_J_DQ<2>")
	)
	(segment
		(start 39.63162 -13.783056)
		(end 39.63162 -16.751046)
		(width 0.14224)
		(layer "In11.Cu")
		(net "M_J_DQ<2>")
	)
	(segment
		(start 39.049452 -4.357878)
		(end 39.291768 -4.600194)
		(width 0.14224)
		(layer "In11.Cu")
		(net "M_J_DQ<2>")
	)
	(segment
		(start 74.028046 -64.10579)
		(end 74.183748 -64.10579)
		(width 0.0889)
		(layer "In11.Cu")
		(net "M_J_DQ<2>")
	)
	(segment
		(start 49.939448 -49.21123)
		(end 50.44059 -48.710088)
		(width 0.14224)
		(layer "In11.Cu")
		(net "M_J_DQ<2>")
	)
	(segment
		(start 50.597308 -50.088038)
		(end 50.816256 -50.088038)
		(width 0.14224)
		(layer "In11.Cu")
		(net "M_J_DQ<2>")
	)
	(segment
		(start 49.7205 -49.21123)
		(end 49.939448 -49.21123)
		(width 0.14224)
		(layer "In11.Cu")
		(net "M_J_DQ<2>")
	)
	(segment
		(start 39.54272 -9.3472)
		(end 39.393368 -9.496552)
		(width 0.14224)
		(layer "In11.Cu")
		(net "M_J_DQ<2>")
	)
	(segment
		(start 38.764718 -3.3274)
		(end 39.613586 -2.478532)
		(width 0.14224)
		(layer "In11.Cu")
		(net "M_J_DQ<2>")
	)
	(segment
		(start 48.905922 -46.956472)
		(end 49.125378 -47.175928)
		(width 0.14224)
		(layer "In11.Cu")
		(net "M_J_DQ<2>")
	)
	(segment
		(start 66.002916 -61.62929)
		(end 66.2432 -61.62929)
		(width 0.0889)
		(layer "In11.Cu")
		(net "M_J_DQ<2>")
	)
	(segment
		(start 47.810166 -46.079664)
		(end 48.029114 -46.079664)
		(width 0.14224)
		(layer "In11.Cu")
		(net "M_J_DQ<2>")
	)
	(segment
		(start 50.002186 -48.271684)
		(end 49.501044 -48.772826)
		(width 0.14224)
		(layer "In11.Cu")
		(net "M_J_DQ<2>")
	)
	(segment
		(start 52.569872 -51.841654)
		(end 53.071014 -51.340512)
		(width 0.14224)
		(layer "In11.Cu")
		(net "M_J_DQ<2>")
	)
	(segment
		(start 39.613586 -2.2098)
		(end 39.156386 -1.7526)
		(width 0.14224)
		(layer "In11.Cu")
		(net "M_J_DQ<2>")
	)
	(segment
		(start 73.165716 -63.610236)
		(end 73.198482 -63.610236)
		(width 0.0889)
		(layer "In11.Cu")
		(net "M_J_DQ<2>")
	)
	(segment
		(start 52.350924 -51.841654)
		(end 52.569872 -51.841654)
		(width 0.14224)
		(layer "In11.Cu")
		(net "M_J_DQ<2>")
	)
	(segment
		(start 53.719984 -51.770534)
		(end 53.719984 -53.2892)
		(width 0.14224)
		(layer "In11.Cu")
		(net "M_J_DQ<2>")
	)
	(segment
		(start 39.61892 -7.162546)
		(end 39.41572 -7.365746)
		(width 0.14224)
		(layer "In11.Cu")
		(net "M_J_DQ<2>")
	)
	(segment
		(start 52.63261 -50.68316)
		(end 52.63261 -50.902108)
		(width 0.14224)
		(layer "In11.Cu")
		(net "M_J_DQ<2>")
	)
	(segment
		(start 47.966884 -47.457614)
		(end 48.185832 -47.457614)
		(width 0.14224)
		(layer "In11.Cu")
		(net "M_J_DQ<2>")
	)
	(segment
		(start 46.87062 -46.36135)
		(end 47.090076 -46.580806)
		(width 0.14224)
		(layer "In11.Cu")
		(net "M_J_DQ<2>")
	)
	(segment
		(start 39.139368 -33.187386)
		(end 39.281608 -33.329626)
		(width 0.14224)
		(layer "In11.Cu")
		(net "M_J_DQ<2>")
	)
	(segment
		(start 49.501044 -48.991774)
		(end 49.7205 -49.21123)
		(width 0.14224)
		(layer "In11.Cu")
		(net "M_J_DQ<2>")
	)
	(segment
		(start 50.816256 -50.088038)
		(end 51.317398 -49.586896)
		(width 0.14224)
		(layer "In11.Cu")
		(net "M_J_DQ<2>")
	)
	(segment
		(start 48.624236 -48.114966)
		(end 48.843692 -48.334422)
		(width 0.14224)
		(layer "In11.Cu")
		(net "M_J_DQ<2>")
	)
	(segment
		(start 49.125378 -47.175928)
		(end 49.125378 -47.394876)
		(width 0.14224)
		(layer "In11.Cu")
		(net "M_J_DQ<2>")
	)
	(segment
		(start 65.788286 -61.84392)
		(end 66.002916 -61.62929)
		(width 0.0889)
		(layer "In11.Cu")
		(net "M_J_DQ<2>")
	)
	(segment
		(start 39.39032 -13.541756)
		(end 39.63162 -13.783056)
		(width 0.14224)
		(layer "In11.Cu")
		(net "M_J_DQ<2>")
	)
	(segment
		(start 39.41572 -18.437098)
		(end 39.54272 -18.564098)
		(width 0.14224)
		(layer "In11.Cu")
		(net "M_J_DQ<2>")
	)
	(segment
		(start 39.613586 -2.478532)
		(end 39.613586 -2.2098)
		(width 0.14224)
		(layer "In11.Cu")
		(net "M_J_DQ<2>")
	)
	(segment
		(start 50.44059 -48.710088)
		(end 50.659538 -48.710088)
		(width 0.14224)
		(layer "In11.Cu")
		(net "M_J_DQ<2>")
	)
	(segment
		(start 39.545768 -25.603454)
		(end 39.834312 -25.891998)
		(width 0.14224)
		(layer "In11.Cu")
		(net "M_J_DQ<2>")
	)
	(segment
		(start 66.243962 -61.628528)
		(end 66.336164 -61.628528)
		(width 0.0889)
		(layer "In11.Cu")
		(net "M_J_DQ<2>")
	)
	(segment
		(start 68.876926 -62.12459)
		(end 68.912486 -62.12459)
		(width 0.0889)
		(layer "In11.Cu")
		(net "M_J_DQ<2>")
	)
	(segment
		(start 39.461186 -0.761746)
		(end 39.156386 -0.456946)
		(width 0.14224)
		(layer "In11.Cu")
		(net "M_J_DQ<2>")
	)
	(segment
		(start 60.01512 -58.692288)
		(end 63.166752 -61.84392)
		(width 0.14224)
		(layer "In11.Cu")
		(net "M_J_DQ<2>")
	)
	(segment
		(start 66.831464 -62.12459)
		(end 67.304158 -62.12459)
		(width 0.0889)
		(layer "In11.Cu")
		(net "M_J_DQ<2>")
	)
	(segment
		(start 47.747428 -47.01921)
		(end 47.747428 -47.238158)
		(width 0.14224)
		(layer "In11.Cu")
		(net "M_J_DQ<2>")
	)
	(segment
		(start 51.25466 -50.526442)
		(end 51.25466 -50.74539)
		(width 0.14224)
		(layer "In11.Cu")
		(net "M_J_DQ<2>")
	)
	(segment
		(start 48.029114 -46.079664)
		(end 48.24857 -46.29912)
		(width 0.14224)
		(layer "In11.Cu")
		(net "M_J_DQ<2>")
	)
	(segment
		(start 66.776092 -62.068456)
		(end 66.775838 -62.068456)
		(width 0.0889)
		(layer "In11.Cu")
		(net "M_J_DQ<2>")
	)
	(segment
		(start 39.834312 -32.537146)
		(end 39.692072 -32.679386)
		(width 0.14224)
		(layer "In11.Cu")
		(net "M_J_DQ<2>")
	)
	(segment
		(start 47.309024 -46.580806)
		(end 47.810166 -46.079664)
		(width 0.14224)
		(layer "In11.Cu")
		(net "M_J_DQ<2>")
	)
	(segment
		(start 39.692072 -33.329626)
		(end 39.834312 -33.471866)
		(width 0.14224)
		(layer "In11.Cu")
		(net "M_J_DQ<2>")
	)
	(segment
		(start 39.281608 -32.679386)
		(end 39.139368 -32.821626)
		(width 0.14224)
		(layer "In11.Cu")
		(net "M_J_DQ<2>")
	)
	(segment
		(start 51.693064 -50.964846)
		(end 52.194206 -50.463704)
		(width 0.14224)
		(layer "In11.Cu")
		(net "M_J_DQ<2>")
	)
	(segment
		(start 63.166752 -61.84392)
		(end 65.788286 -61.84392)
		(width 0.14224)
		(layer "In11.Cu")
		(net "M_J_DQ<2>")
	)
	(segment
		(start 39.54272 -12.195556)
		(end 39.39032 -12.347956)
		(width 0.14224)
		(layer "In11.Cu")
		(net "M_J_DQ<2>")
	)
	(segment
		(start 39.39032 -12.347956)
		(end 39.39032 -13.541756)
		(width 0.14224)
		(layer "In11.Cu")
		(net "M_J_DQ<2>")
	)
	(segment
		(start 51.755802 -50.0253)
		(end 51.25466 -50.526442)
		(width 0.14224)
		(layer "In11.Cu")
		(net "M_J_DQ<2>")
	)
	(segment
		(start 48.185832 -47.457614)
		(end 48.686974 -46.956472)
		(width 0.14224)
		(layer "In11.Cu")
		(net "M_J_DQ<2>")
	)
	(segment
		(start 49.125378 -47.394876)
		(end 48.624236 -47.896018)
		(width 0.14224)
		(layer "In11.Cu")
		(net "M_J_DQ<2>")
	)
	(segment
		(start 39.834312 -37.884862)
		(end 47.371762 -45.422312)
		(width 0.14224)
		(layer "In11.Cu")
		(net "M_J_DQ<2>")
	)
	(segment
		(start 39.049452 -4.357878)
		(end 38.764718 -4.073144)
		(width 0.14224)
		(layer "In11.Cu")
		(net "M_J_DQ<2>")
	)
	(segment
		(start 38.764718 -4.073144)
		(end 38.764718 -3.3274)
		(width 0.14224)
		(layer "In11.Cu")
		(net "M_J_DQ<2>")
	)
	(segment
		(start 52.131468 -51.622198)
		(end 52.350924 -51.841654)
		(width 0.14224)
		(layer "In11.Cu")
		(net "M_J_DQ<2>")
	)
	(arc
		(start 67.653154 -61.826394)
		(mid 67.744268 -61.708802)
		(end 67.869816 -61.629036)
		(width 0.0889)
		(layer "In11.Cu")
		(net "M_J_DQ<2>")
	)
	(arc
		(start 67.304158 -62.12459)
		(mid 67.507056 -62.00873)
		(end 67.653154 -61.826394)
		(width 0.0889)
		(layer "In11.Cu")
		(net "M_J_DQ<2>")
	)
	(arc
		(start 70.626732 -62.12459)
		(mid 70.818374 -62.181756)
		(end 70.958456 -62.324488)
		(width 0.0889)
		(layer "In11.Cu")
		(net "M_J_DQ<2>")
	)
	(arc
		(start 70.099936 -61.829188)
		(mid 70.308544 -62.04112)
		(end 70.593966 -62.12459)
		(width 0.0889)
		(layer "In11.Cu")
		(net "M_J_DQ<2>")
	)
	(arc
		(start 68.047362 -61.629036)
		(mid 68.241212 -61.685386)
		(end 68.382896 -61.829188)
		(width 0.0889)
		(layer "In11.Cu")
		(net "M_J_DQ<2>")
	)
	(arc
		(start 70.958456 -62.324488)
		(mid 71.16546 -62.535352)
		(end 71.448676 -62.619636)
		(width 0.0889)
		(layer "In11.Cu")
		(net "M_J_DQ<2>")
	)
	(arc
		(start 73.198482 -63.610236)
		(mid 73.392332 -63.666586)
		(end 73.534016 -63.810388)
		(width 0.0889)
		(layer "In11.Cu")
		(net "M_J_DQ<2>")
	)
	(arc
		(start 71.481442 -62.619636)
		(mid 71.675292 -62.675986)
		(end 71.816976 -62.819788)
		(width 0.0889)
		(layer "In11.Cu")
		(net "M_J_DQ<2>")
	)
	(arc
		(start 69.406516 -61.829188)
		(mid 69.753226 -61.628877)
		(end 70.099936 -61.829188)
		(width 0.0889)
		(layer "In11.Cu")
		(net "M_J_DQ<2>")
	)
	(arc
		(start 68.382896 -61.829188)
		(mid 68.591504 -62.04112)
		(end 68.876926 -62.12459)
		(width 0.0889)
		(layer "In11.Cu")
		(net "M_J_DQ<2>")
	)
	(arc
		(start 72.675496 -63.315088)
		(mid 72.8825 -63.525952)
		(end 73.165716 -63.610236)
		(width 0.0889)
		(layer "In11.Cu")
		(net "M_J_DQ<2>")
	)
	(arc
		(start 71.816976 -62.819788)
		(mid 72.025584 -63.03172)
		(end 72.311006 -63.11519)
		(width 0.0889)
		(layer "In11.Cu")
		(net "M_J_DQ<2>")
	)
	(arc
		(start 73.534016 -63.810388)
		(mid 73.742624 -64.02232)
		(end 74.028046 -64.10579)
		(width 0.0889)
		(layer "In11.Cu")
		(net "M_J_DQ<2>")
	)
	(arc
		(start 72.343772 -63.11519)
		(mid 72.535414 -63.172356)
		(end 72.675496 -63.315088)
		(width 0.0889)
		(layer "In11.Cu")
		(net "M_J_DQ<2>")
	)
	(arc
		(start 68.912486 -62.12459)
		(mid 69.19791 -62.041123)
		(end 69.406516 -61.829188)
		(width 0.0889)
		(layer "In11.Cu")
		(net "M_J_DQ<2>")
	)
	(segment
		(start 59.449462 3.778758)
		(end 59.449462 2.514854)
		(width 0.1651)
		(layer "F.Cu")
		(net "M_J_DQ<29>")
	)
	(segment
		(start 83.202272 -66.48704)
		(end 82.630772 -66.48704)
		(width 0.0889)
		(layer "F.Cu")
		(net "M_J_DQ<29>")
	)
	(via
		(at 59.449462 2.514854)
		(size 0.508)
		(drill 0.254)
		(layers "F.Cu" "B.Cu")
		(net "M_J_DQ<29>")
	)
	(via
		(at 82.630772 -66.48704)
		(size 0.508)
		(drill 0.254)
		(layers "F.Cu" "B.Cu")
		(net "M_J_DQ<29>")
	)
	(via
		(at 60.223146 -3.076956)
		(size 0.508)
		(drill 0.254)
		(layers "F.Cu" "B.Cu")
		(net "M_J_DQ<29>")
	)
	(segment
		(start 60.299346 -1.021842)
		(end 60.299346 -3.000756)
		(width 0.1651)
		(layer "B.Cu")
		(net "M_J_DQ<29>")
	)
	(segment
		(start 60.299346 -3.000756)
		(end 60.223146 -3.076956)
		(width 0.1651)
		(layer "B.Cu")
		(net "M_J_DQ<29>")
	)
	(segment
		(start 82.284062 -56.780938)
		(end 82.279236 -56.772302)
		(width 0.0889)
		(layer "In11.Cu")
		(net "M_J_DQ<29>")
	)
	(segment
		(start 60.633102 -26.309066)
		(end 60.691268 -26.2509)
		(width 0.14224)
		(layer "In11.Cu")
		(net "M_J_DQ<29>")
	)
	(segment
		(start 82.977482 -65.296288)
		(end 82.912204 -65.183004)
		(width 0.0889)
		(layer "In11.Cu")
		(net "M_J_DQ<29>")
	)
	(segment
		(start 60.7314 0.7366)
		(end 60.7314 1.149096)
		(width 0.14224)
		(layer "In11.Cu")
		(net "M_J_DQ<29>")
	)
	(segment
		(start 82.290412 -61.744606)
		(end 82.284062 -61.733938)
		(width 0.0889)
		(layer "In11.Cu")
		(net "M_J_DQ<29>")
	)
	(segment
		(start 60.544964 -28.390596)
		(end 60.697364 -28.238196)
		(width 0.14224)
		(layer "In11.Cu")
		(net "M_J_DQ<29>")
	)
	(segment
		(start 60.697364 -26.891996)
		(end 60.633102 -26.827734)
		(width 0.14224)
		(layer "In11.Cu")
		(net "M_J_DQ<29>")
	)
	(segment
		(start 60.633102 -26.827734)
		(end 60.633102 -26.309066)
		(width 0.14224)
		(layer "In11.Cu")
		(net "M_J_DQ<29>")
	)
	(segment
		(start 82.284062 -63.715138)
		(end 82.279236 -63.706502)
		(width 0.0889)
		(layer "In11.Cu")
		(net "M_J_DQ<29>")
	)
	(segment
		(start 82.284062 -61.733938)
		(end 82.279236 -61.725302)
		(width 0.0889)
		(layer "In11.Cu")
		(net "M_J_DQ<29>")
	)
	(segment
		(start 80.921606 -54.350666)
		(end 80.921606 -54.000908)
		(width 0.0889)
		(layer "In11.Cu")
		(net "M_J_DQ<29>")
	)
	(segment
		(start 60.607702 -11.7348)
		(end 60.983368 -11.359134)
		(width 0.14224)
		(layer "In11.Cu")
		(net "M_J_DQ<29>")
	)
	(segment
		(start 60.678568 -16.4338)
		(end 60.633102 -16.388334)
		(width 0.14224)
		(layer "In11.Cu")
		(net "M_J_DQ<29>")
	)
	(segment
		(start 60.607702 -12.271756)
		(end 60.607702 -11.7348)
		(width 0.14224)
		(layer "In11.Cu")
		(net "M_J_DQ<29>")
	)
	(segment
		(start 82.284062 -55.790084)
		(end 82.178906 -55.607966)
		(width 0.0889)
		(layer "In11.Cu")
		(net "M_J_DQ<29>")
	)
	(segment
		(start 82.290412 -62.735206)
		(end 82.284062 -62.724538)
		(width 0.0889)
		(layer "In11.Cu")
		(net "M_J_DQ<29>")
	)
	(segment
		(start 82.290412 -63.725806)
		(end 82.284062 -63.715138)
		(width 0.0889)
		(layer "In11.Cu")
		(net "M_J_DQ<29>")
	)
	(segment
		(start 59.718702 -3.940556)
		(end 59.718702 -3.5814)
		(width 0.14224)
		(layer "In11.Cu")
		(net "M_J_DQ<29>")
	)
	(segment
		(start 60.551568 -7.182612)
		(end 60.551568 -4.773422)
		(width 0.14224)
		(layer "In11.Cu")
		(net "M_J_DQ<29>")
	)
	(segment
		(start 60.53455 0.53975)
		(end 60.7314 0.7366)
		(width 0.14224)
		(layer "In11.Cu")
		(net "M_J_DQ<29>")
	)
	(segment
		(start 77.493368 -51.215544)
		(end 77.493368 -48.506888)
		(width 0.14224)
		(layer "In11.Cu")
		(net "M_J_DQ<29>")
	)
	(segment
		(start 60.805568 -19.151346)
		(end 60.678568 -19.024346)
		(width 0.14224)
		(layer "In11.Cu")
		(net "M_J_DQ<29>")
	)
	(segment
		(start 82.284062 -57.771538)
		(end 82.279236 -57.762902)
		(width 0.0889)
		(layer "In11.Cu")
		(net "M_J_DQ<29>")
	)
	(segment
		(start 60.53455 -2.765552)
		(end 60.53455 0.53975)
		(width 0.14224)
		(layer "In11.Cu")
		(net "M_J_DQ<29>")
	)
	(segment
		(start 80.434434 -53.513736)
		(end 80.040226 -53.513736)
		(width 0.0889)
		(layer "In11.Cu")
		(net "M_J_DQ<29>")
	)
	(segment
		(start 60.544964 -31.558484)
		(end 60.544964 -28.390596)
		(width 0.14224)
		(layer "In11.Cu")
		(net "M_J_DQ<29>")
	)
	(segment
		(start 60.691268 -21.956522)
		(end 60.653168 -21.918422)
		(width 0.14224)
		(layer "In11.Cu")
		(net "M_J_DQ<29>")
	)
	(segment
		(start 60.692284 -7.323328)
		(end 60.551568 -7.182612)
		(width 0.14224)
		(layer "In11.Cu")
		(net "M_J_DQ<29>")
	)
	(segment
		(start 60.331096 1.5494)
		(end 60.0202 1.5494)
		(width 0.14224)
		(layer "In11.Cu")
		(net "M_J_DQ<29>")
	)
	(segment
		(start 77.493368 -48.506888)
		(end 60.544964 -31.558484)
		(width 0.14224)
		(layer "In11.Cu")
		(net "M_J_DQ<29>")
	)
	(segment
		(start 60.223146 -3.076956)
		(end 60.53455 -2.765552)
		(width 0.14224)
		(layer "In11.Cu")
		(net "M_J_DQ<29>")
	)
	(segment
		(start 60.633102 -13.681456)
		(end 60.696602 -13.617956)
		(width 0.14224)
		(layer "In11.Cu")
		(net "M_J_DQ<29>")
	)
	(segment
		(start 60.805568 -21.1582)
		(end 60.805568 -19.151346)
		(width 0.14224)
		(layer "In11.Cu")
		(net "M_J_DQ<29>")
	)
	(segment
		(start 82.284062 -62.724538)
		(end 82.279236 -62.715902)
		(width 0.0889)
		(layer "In11.Cu")
		(net "M_J_DQ<29>")
	)
	(segment
		(start 59.449462 2.120138)
		(end 59.449462 2.514854)
		(width 0.14224)
		(layer "In11.Cu")
		(net "M_J_DQ<29>")
	)
	(segment
		(start 60.633102 -16.388334)
		(end 60.633102 -13.681456)
		(width 0.14224)
		(layer "In11.Cu")
		(net "M_J_DQ<29>")
	)
	(segment
		(start 60.7314 1.149096)
		(end 60.331096 1.5494)
		(width 0.14224)
		(layer "In11.Cu")
		(net "M_J_DQ<29>")
	)
	(segment
		(start 60.653168 -21.918422)
		(end 60.653168 -21.3106)
		(width 0.14224)
		(layer "In11.Cu")
		(net "M_J_DQ<29>")
	)
	(segment
		(start 77.823568 -51.81981)
		(end 77.823568 -51.545744)
		(width 0.0889)
		(layer "In11.Cu")
		(net "M_J_DQ<29>")
	)
	(segment
		(start 82.284062 -59.752738)
		(end 82.279236 -59.744102)
		(width 0.0889)
		(layer "In11.Cu")
		(net "M_J_DQ<29>")
	)
	(segment
		(start 60.696602 -12.360656)
		(end 60.607702 -12.271756)
		(width 0.14224)
		(layer "In11.Cu")
		(net "M_J_DQ<29>")
	)
	(segment
		(start 82.290412 -56.791606)
		(end 82.284062 -56.780938)
		(width 0.0889)
		(layer "In11.Cu")
		(net "M_J_DQ<29>")
	)
	(segment
		(start 82.284062 -58.362088)
		(end 82.290412 -58.35142)
		(width 0.0889)
		(layer "In11.Cu")
		(net "M_J_DQ<29>")
	)
	(segment
		(start 60.983368 -9.637268)
		(end 60.692284 -9.346184)
		(width 0.14224)
		(layer "In11.Cu")
		(net "M_J_DQ<29>")
	)
	(segment
		(start 82.912204 -65.183004)
		(end 82.487008 -64.879474)
		(width 0.0889)
		(layer "In11.Cu")
		(net "M_J_DQ<29>")
	)
	(segment
		(start 82.630772 -66.48704)
		(end 82.96021 -65.726056)
		(width 0.0889)
		(layer "In11.Cu")
		(net "M_J_DQ<29>")
	)
	(segment
		(start 82.284062 -60.743338)
		(end 82.279236 -60.734702)
		(width 0.0889)
		(layer "In11.Cu")
		(net "M_J_DQ<29>")
	)
	(segment
		(start 60.696602 -13.617956)
		(end 60.696602 -12.360656)
		(width 0.14224)
		(layer "In11.Cu")
		(net "M_J_DQ<29>")
	)
	(segment
		(start 60.551568 -4.773422)
		(end 59.718702 -3.940556)
		(width 0.14224)
		(layer "In11.Cu")
		(net "M_J_DQ<29>")
	)
	(segment
		(start 80.921606 -54.000908)
		(end 80.434434 -53.513736)
		(width 0.0889)
		(layer "In11.Cu")
		(net "M_J_DQ<29>")
	)
	(segment
		(start 82.290412 -59.763406)
		(end 82.284062 -59.752738)
		(width 0.0889)
		(layer "In11.Cu")
		(net "M_J_DQ<29>")
	)
	(segment
		(start 82.290412 -60.754006)
		(end 82.284062 -60.743338)
		(width 0.0889)
		(layer "In11.Cu")
		(net "M_J_DQ<29>")
	)
	(segment
		(start 60.697364 -28.238196)
		(end 60.697364 -26.891996)
		(width 0.14224)
		(layer "In11.Cu")
		(net "M_J_DQ<29>")
	)
	(segment
		(start 82.96021 -65.726056)
		(end 82.982308 -65.687702)
		(width 0.0889)
		(layer "In11.Cu")
		(net "M_J_DQ<29>")
	)
	(segment
		(start 60.983368 -11.359134)
		(end 60.983368 -9.637268)
		(width 0.14224)
		(layer "In11.Cu")
		(net "M_J_DQ<29>")
	)
	(segment
		(start 77.823568 -51.545744)
		(end 77.493368 -51.215544)
		(width 0.14224)
		(layer "In11.Cu")
		(net "M_J_DQ<29>")
	)
	(segment
		(start 79.022448 -53.01869)
		(end 77.823568 -51.81981)
		(width 0.0889)
		(layer "In11.Cu")
		(net "M_J_DQ<29>")
	)
	(segment
		(start 60.691268 -26.2509)
		(end 60.691268 -21.956522)
		(width 0.14224)
		(layer "In11.Cu")
		(net "M_J_DQ<29>")
	)
	(segment
		(start 82.178906 -55.607966)
		(end 80.921606 -54.350666)
		(width 0.0889)
		(layer "In11.Cu")
		(net "M_J_DQ<29>")
	)
	(segment
		(start 60.0202 1.5494)
		(end 59.449462 2.120138)
		(width 0.14224)
		(layer "In11.Cu")
		(net "M_J_DQ<29>")
	)
	(segment
		(start 59.718702 -3.5814)
		(end 60.223146 -3.076956)
		(width 0.14224)
		(layer "In11.Cu")
		(net "M_J_DQ<29>")
	)
	(segment
		(start 79.196692 -53.01869)
		(end 79.022448 -53.01869)
		(width 0.0889)
		(layer "In11.Cu")
		(net "M_J_DQ<29>")
	)
	(segment
		(start 60.653168 -21.3106)
		(end 60.805568 -21.1582)
		(width 0.14224)
		(layer "In11.Cu")
		(net "M_J_DQ<29>")
	)
	(segment
		(start 60.692284 -9.346184)
		(end 60.692284 -7.323328)
		(width 0.14224)
		(layer "In11.Cu")
		(net "M_J_DQ<29>")
	)
	(segment
		(start 60.678568 -19.024346)
		(end 60.678568 -16.4338)
		(width 0.14224)
		(layer "In11.Cu")
		(net "M_J_DQ<29>")
	)
	(arc
		(start 82.284062 -64.305688)
		(mid 82.363284 -64.01657)
		(end 82.290412 -63.725806)
		(width 0.0889)
		(layer "In11.Cu")
		(net "M_J_DQ<29>")
	)
	(arc
		(start 82.279236 -60.734702)
		(mid 82.230481 -60.53835)
		(end 82.284062 -60.343288)
		(width 0.0889)
		(layer "In11.Cu")
		(net "M_J_DQ<29>")
	)
	(arc
		(start 82.284062 -59.352688)
		(mid 82.363193 -59.057286)
		(end 82.284062 -58.761884)
		(width 0.0889)
		(layer "In11.Cu")
		(net "M_J_DQ<29>")
	)
	(arc
		(start 82.284062 -60.343288)
		(mid 82.363284 -60.05417)
		(end 82.290412 -59.763406)
		(width 0.0889)
		(layer "In11.Cu")
		(net "M_J_DQ<29>")
	)
	(arc
		(start 79.708502 -53.313838)
		(mid 79.492187 -53.097591)
		(end 79.196692 -53.01869)
		(width 0.0889)
		(layer "In11.Cu")
		(net "M_J_DQ<29>")
	)
	(arc
		(start 82.284062 -58.761884)
		(mid 82.230563 -58.561986)
		(end 82.284062 -58.362088)
		(width 0.0889)
		(layer "In11.Cu")
		(net "M_J_DQ<29>")
	)
	(arc
		(start 82.284062 -61.333888)
		(mid 82.363284 -61.04477)
		(end 82.290412 -60.754006)
		(width 0.0889)
		(layer "In11.Cu")
		(net "M_J_DQ<29>")
	)
	(arc
		(start 82.279236 -59.744102)
		(mid 82.230481 -59.54775)
		(end 82.284062 -59.352688)
		(width 0.0889)
		(layer "In11.Cu")
		(net "M_J_DQ<29>")
	)
	(arc
		(start 82.290412 -58.35142)
		(mid 82.36321 -58.060657)
		(end 82.284062 -57.771538)
		(width 0.0889)
		(layer "In11.Cu")
		(net "M_J_DQ<29>")
	)
	(arc
		(start 82.284062 -57.371488)
		(mid 82.363284 -57.08237)
		(end 82.290412 -56.791606)
		(width 0.0889)
		(layer "In11.Cu")
		(net "M_J_DQ<29>")
	)
	(arc
		(start 82.279236 -61.725302)
		(mid 82.230481 -61.52895)
		(end 82.284062 -61.333888)
		(width 0.0889)
		(layer "In11.Cu")
		(net "M_J_DQ<29>")
	)
	(arc
		(start 82.279236 -62.715902)
		(mid 82.230481 -62.51955)
		(end 82.284062 -62.324488)
		(width 0.0889)
		(layer "In11.Cu")
		(net "M_J_DQ<29>")
	)
	(arc
		(start 82.284062 -56.380888)
		(mid 82.363193 -56.085486)
		(end 82.284062 -55.790084)
		(width 0.0889)
		(layer "In11.Cu")
		(net "M_J_DQ<29>")
	)
	(arc
		(start 82.284062 -62.324488)
		(mid 82.363284 -62.03537)
		(end 82.290412 -61.744606)
		(width 0.0889)
		(layer "In11.Cu")
		(net "M_J_DQ<29>")
	)
	(arc
		(start 80.040226 -53.513736)
		(mid 79.848584 -53.45657)
		(end 79.708502 -53.313838)
		(width 0.0889)
		(layer "In11.Cu")
		(net "M_J_DQ<29>")
	)
	(arc
		(start 82.279236 -56.772302)
		(mid 82.230481 -56.57595)
		(end 82.284062 -56.380888)
		(width 0.0889)
		(layer "In11.Cu")
		(net "M_J_DQ<29>")
	)
	(arc
		(start 82.487008 -64.879474)
		(mid 82.253347 -64.639335)
		(end 82.284062 -64.305688)
		(width 0.0889)
		(layer "In11.Cu")
		(net "M_J_DQ<29>")
	)
	(arc
		(start 82.284062 -63.315088)
		(mid 82.363284 -63.02597)
		(end 82.290412 -62.735206)
		(width 0.0889)
		(layer "In11.Cu")
		(net "M_J_DQ<29>")
	)
	(arc
		(start 82.279236 -63.706502)
		(mid 82.230481 -63.51015)
		(end 82.284062 -63.315088)
		(width 0.0889)
		(layer "In11.Cu")
		(net "M_J_DQ<29>")
	)
	(arc
		(start 82.982308 -65.687702)
		(mid 83.031063 -65.49135)
		(end 82.977482 -65.296288)
		(width 0.0889)
		(layer "In11.Cu")
		(net "M_J_DQ<29>")
	)
	(arc
		(start 82.279236 -57.762902)
		(mid 82.230481 -57.56655)
		(end 82.284062 -57.371488)
		(width 0.0889)
		(layer "In11.Cu")
		(net "M_J_DQ<29>")
	)
	(segment
		(start 60.299346 -0.821182)
		(end 60.299346 0.510032)
		(width 0.1651)
		(layer "F.Cu")
		(net "M_J_DQ<28>")
	)
	(segment
		(start 83.202272 -65.49644)
		(end 82.630772 -65.49644)
		(width 0.1016)
		(layer "F.Cu")
		(net "M_J_DQ<28>")
	)
	(segment
		(start 60.299346 0.510032)
		(end 60.201302 1.0414)
		(width 0.1651)
		(layer "F.Cu")
		(net "M_J_DQ<28>")
	)
	(via
		(at 60.201302 1.0414)
		(size 0.508)
		(drill 0.254)
		(layers "F.Cu" "B.Cu")
		(net "M_J_DQ<28>")
	)
	(via
		(at 59.449462 -4.357878)
		(size 0.508)
		(drill 0.254)
		(layers "F.Cu" "B.Cu")
		(net "M_J_DQ<28>")
	)
	(via
		(at 82.630772 -65.49644)
		(size 0.508)
		(drill 0.254)
		(layers "F.Cu" "B.Cu")
		(net "M_J_DQ<28>")
	)
	(segment
		(start 59.449462 -5.621782)
		(end 59.449462 -4.357878)
		(width 0.1651)
		(layer "B.Cu")
		(net "M_J_DQ<28>")
	)
	(segment
		(start 59.972702 -9.341866)
		(end 59.972702 -8.965946)
		(width 0.14224)
		(layer "In11.Cu")
		(net "M_J_DQ<28>")
	)
	(segment
		(start 59.92495 0.287528)
		(end 59.92495 0.765048)
		(width 0.14224)
		(layer "In11.Cu")
		(net "M_J_DQ<28>")
	)
	(segment
		(start 59.718702 -23.168356)
		(end 59.718702 -21.949156)
		(width 0.14224)
		(layer "In11.Cu")
		(net "M_J_DQ<28>")
	)
	(segment
		(start 82.118962 -64.800988)
		(end 82.112612 -64.79032)
		(width 0.0889)
		(layer "In11.Cu")
		(net "M_J_DQ<28>")
	)
	(segment
		(start 75.969368 -50.0126)
		(end 75.969368 -49.0474)
		(width 0.14224)
		(layer "In11.Cu")
		(net "M_J_DQ<28>")
	)
	(segment
		(start 59.972702 -18.968466)
		(end 59.972702 -18.567146)
		(width 0.14224)
		(layer "In11.Cu")
		(net "M_J_DQ<28>")
	)
	(segment
		(start 82.123788 -56.884824)
		(end 82.118962 -56.876188)
		(width 0.0889)
		(layer "In11.Cu")
		(net "M_J_DQ<28>")
	)
	(segment
		(start 76.223368 -48.135032)
		(end 70.162166 -42.07383)
		(width 0.14224)
		(layer "In11.Cu")
		(net "M_J_DQ<28>")
	)
	(segment
		(start 59.560968 -0.381)
		(end 59.560968 -0.076454)
		(width 0.14224)
		(layer "In11.Cu")
		(net "M_J_DQ<28>")
	)
	(segment
		(start 82.123788 -60.847224)
		(end 82.118962 -60.838588)
		(width 0.0889)
		(layer "In11.Cu")
		(net "M_J_DQ<28>")
	)
	(segment
		(start 82.118962 -61.829188)
		(end 82.112612 -61.81852)
		(width 0.0889)
		(layer "In11.Cu")
		(net "M_J_DQ<28>")
	)
	(segment
		(start 69.874638 -42.07383)
		(end 69.688202 -42.260266)
		(width 0.14224)
		(layer "In11.Cu")
		(net "M_J_DQ<28>")
	)
	(segment
		(start 59.906662 -31.818326)
		(end 59.906662 -28.285694)
		(width 0.14224)
		(layer "In11.Cu")
		(net "M_J_DQ<28>")
	)
	(segment
		(start 59.840368 -19.1008)
		(end 59.972702 -18.968466)
		(width 0.14224)
		(layer "In11.Cu")
		(net "M_J_DQ<28>")
	)
	(segment
		(start 59.21375 -4.122166)
		(end 59.21375 -3.327654)
		(width 0.14224)
		(layer "In11.Cu")
		(net "M_J_DQ<28>")
	)
	(segment
		(start 59.947302 -7.233666)
		(end 59.947302 -4.855718)
		(width 0.14224)
		(layer "In11.Cu")
		(net "M_J_DQ<28>")
	)
	(segment
		(start 59.718702 -8.711946)
		(end 59.718702 -7.462266)
		(width 0.14224)
		(layer "In11.Cu")
		(net "M_J_DQ<28>")
	)
	(segment
		(start 75.969368 -49.0474)
		(end 76.223368 -48.7934)
		(width 0.14224)
		(layer "In11.Cu")
		(net "M_J_DQ<28>")
	)
	(segment
		(start 80.731106 -54.080664)
		(end 80.354678 -53.704236)
		(width 0.0889)
		(layer "In11.Cu")
		(net "M_J_DQ<28>")
	)
	(segment
		(start 82.112612 -58.277506)
		(end 82.118962 -58.266838)
		(width 0.0889)
		(layer "In11.Cu")
		(net "M_J_DQ<28>")
	)
	(segment
		(start 69.299836 -41.499028)
		(end 69.299836 -41.2115)
		(width 0.14224)
		(layer "In11.Cu")
		(net "M_J_DQ<28>")
	)
	(segment
		(start 59.732164 -28.111196)
		(end 59.732164 -26.891996)
		(width 0.14224)
		(layer "In11.Cu")
		(net "M_J_DQ<28>")
	)
	(segment
		(start 82.123788 -58.866024)
		(end 82.118962 -58.857388)
		(width 0.0889)
		(layer "In11.Cu")
		(net "M_J_DQ<28>")
	)
	(segment
		(start 59.972702 -18.567146)
		(end 59.718702 -18.313146)
		(width 0.14224)
		(layer "In11.Cu")
		(net "M_J_DQ<28>")
	)
	(segment
		(start 82.123788 -59.856624)
		(end 82.118962 -59.847988)
		(width 0.0889)
		(layer "In11.Cu")
		(net "M_J_DQ<28>")
	)
	(segment
		(start 79.196692 -53.20919)
		(end 78.940152 -53.20919)
		(width 0.0889)
		(layer "In11.Cu")
		(net "M_J_DQ<28>")
	)
	(segment
		(start 69.688202 -42.260266)
		(end 69.487034 -42.260266)
		(width 0.14224)
		(layer "In11.Cu")
		(net "M_J_DQ<28>")
	)
	(segment
		(start 59.947302 -16.809466)
		(end 59.947302 -13.795756)
		(width 0.14224)
		(layer "In11.Cu")
		(net "M_J_DQ<28>")
	)
	(segment
		(start 76.680568 -51.30292)
		(end 76.680568 -50.7238)
		(width 0.14224)
		(layer "In11.Cu")
		(net "M_J_DQ<28>")
	)
	(segment
		(start 59.947302 -23.396956)
		(end 59.718702 -23.168356)
		(width 0.14224)
		(layer "In11.Cu")
		(net "M_J_DQ<28>")
	)
	(segment
		(start 59.573668 -1.790446)
		(end 59.573668 -1.4351)
		(width 0.14224)
		(layer "In11.Cu")
		(net "M_J_DQ<28>")
	)
	(segment
		(start 59.972702 -21.34108)
		(end 59.840368 -21.208746)
		(width 0.14224)
		(layer "In11.Cu")
		(net "M_J_DQ<28>")
	)
	(segment
		(start 59.92495 -2.141728)
		(end 59.573668 -1.790446)
		(width 0.14224)
		(layer "In11.Cu")
		(net "M_J_DQ<28>")
	)
	(segment
		(start 78.940152 -53.20919)
		(end 77.699362 -51.9684)
		(width 0.0889)
		(layer "In11.Cu")
		(net "M_J_DQ<28>")
	)
	(segment
		(start 77.699362 -51.9684)
		(end 77.346048 -51.9684)
		(width 0.0889)
		(layer "In11.Cu")
		(net "M_J_DQ<28>")
	)
	(segment
		(start 82.135726 -64.830452)
		(end 82.118962 -64.800988)
		(width 0.0889)
		(layer "In11.Cu")
		(net "M_J_DQ<28>")
	)
	(segment
		(start 59.573668 -1.4351)
		(end 59.941968 -1.0668)
		(width 0.14224)
		(layer "In11.Cu")
		(net "M_J_DQ<28>")
	)
	(segment
		(start 59.92495 -2.616454)
		(end 59.92495 -2.141728)
		(width 0.14224)
		(layer "In11.Cu")
		(net "M_J_DQ<28>")
	)
	(segment
		(start 59.732164 -26.891996)
		(end 59.947302 -26.676858)
		(width 0.14224)
		(layer "In11.Cu")
		(net "M_J_DQ<28>")
	)
	(segment
		(start 82.630772 -65.49644)
		(end 82.135726 -64.830452)
		(width 0.0889)
		(layer "In11.Cu")
		(net "M_J_DQ<28>")
	)
	(segment
		(start 82.118962 -56.876188)
		(end 82.112612 -56.86552)
		(width 0.0889)
		(layer "In11.Cu")
		(net "M_J_DQ<28>")
	)
	(segment
		(start 59.718702 -7.462266)
		(end 59.947302 -7.233666)
		(width 0.14224)
		(layer "In11.Cu")
		(net "M_J_DQ<28>")
	)
	(segment
		(start 59.947302 -13.795756)
		(end 59.718702 -13.567156)
		(width 0.14224)
		(layer "In11.Cu")
		(net "M_J_DQ<28>")
	)
	(segment
		(start 59.718702 -12.347956)
		(end 59.972702 -12.093956)
		(width 0.14224)
		(layer "In11.Cu")
		(net "M_J_DQ<28>")
	)
	(segment
		(start 82.118962 -63.810388)
		(end 82.112612 -63.79972)
		(width 0.0889)
		(layer "In11.Cu")
		(net "M_J_DQ<28>")
	)
	(segment
		(start 59.21375 -3.327654)
		(end 59.92495 -2.616454)
		(width 0.14224)
		(layer "In11.Cu")
		(net "M_J_DQ<28>")
	)
	(segment
		(start 59.972702 -12.093956)
		(end 59.972702 -11.7348)
		(width 0.14224)
		(layer "In11.Cu")
		(net "M_J_DQ<28>")
	)
	(segment
		(start 59.840368 -21.208746)
		(end 59.840368 -19.1008)
		(width 0.14224)
		(layer "In11.Cu")
		(net "M_J_DQ<28>")
	)
	(segment
		(start 69.1134 -41.685464)
		(end 69.299836 -41.499028)
		(width 0.14224)
		(layer "In11.Cu")
		(net "M_J_DQ<28>")
	)
	(segment
		(start 59.941968 -1.0668)
		(end 59.941968 -0.762)
		(width 0.14224)
		(layer "In11.Cu")
		(net "M_J_DQ<28>")
	)
	(segment
		(start 76.680568 -50.7238)
		(end 75.969368 -50.0126)
		(width 0.14224)
		(layer "In11.Cu")
		(net "M_J_DQ<28>")
	)
	(segment
		(start 82.123788 -62.828424)
		(end 82.118962 -62.819788)
		(width 0.0889)
		(layer "In11.Cu")
		(net "M_J_DQ<28>")
	)
	(segment
		(start 69.1134 -41.886632)
		(end 69.1134 -41.685464)
		(width 0.14224)
		(layer "In11.Cu")
		(net "M_J_DQ<28>")
	)
	(segment
		(start 59.449462 -4.357878)
		(end 59.21375 -4.122166)
		(width 0.14224)
		(layer "In11.Cu")
		(net "M_J_DQ<28>")
	)
	(segment
		(start 69.299836 -41.2115)
		(end 59.906662 -31.818326)
		(width 0.14224)
		(layer "In11.Cu")
		(net "M_J_DQ<28>")
	)
	(segment
		(start 59.718702 -17.038066)
		(end 59.947302 -16.809466)
		(width 0.14224)
		(layer "In11.Cu")
		(net "M_J_DQ<28>")
	)
	(segment
		(start 82.027268 -55.726584)
		(end 80.731106 -54.430422)
		(width 0.0889)
		(layer "In11.Cu")
		(net "M_J_DQ<28>")
	)
	(segment
		(start 59.947302 -4.855718)
		(end 59.449462 -4.357878)
		(width 0.14224)
		(layer "In11.Cu")
		(net "M_J_DQ<28>")
	)
	(segment
		(start 59.560968 -0.076454)
		(end 59.92495 0.287528)
		(width 0.14224)
		(layer "In11.Cu")
		(net "M_J_DQ<28>")
	)
	(segment
		(start 59.947302 -26.676858)
		(end 59.947302 -23.396956)
		(width 0.14224)
		(layer "In11.Cu")
		(net "M_J_DQ<28>")
	)
	(segment
		(start 59.941968 -0.762)
		(end 59.560968 -0.381)
		(width 0.14224)
		(layer "In11.Cu")
		(net "M_J_DQ<28>")
	)
	(segment
		(start 59.92495 0.765048)
		(end 60.201302 1.0414)
		(width 0.14224)
		(layer "In11.Cu")
		(net "M_J_DQ<28>")
	)
	(segment
		(start 82.118962 -55.885334)
		(end 82.027268 -55.726584)
		(width 0.0889)
		(layer "In11.Cu")
		(net "M_J_DQ<28>")
	)
	(segment
		(start 77.346048 -51.9684)
		(end 76.680568 -51.30292)
		(width 0.14224)
		(layer "In11.Cu")
		(net "M_J_DQ<28>")
	)
	(segment
		(start 82.123788 -63.819024)
		(end 82.118962 -63.810388)
		(width 0.0889)
		(layer "In11.Cu")
		(net "M_J_DQ<28>")
	)
	(segment
		(start 76.223368 -48.7934)
		(end 76.223368 -48.135032)
		(width 0.14224)
		(layer "In11.Cu")
		(net "M_J_DQ<28>")
	)
	(segment
		(start 59.972702 -11.7348)
		(end 59.840368 -11.602466)
		(width 0.14224)
		(layer "In11.Cu")
		(net "M_J_DQ<28>")
	)
	(segment
		(start 59.972702 -21.695156)
		(end 59.972702 -21.34108)
		(width 0.14224)
		(layer "In11.Cu")
		(net "M_J_DQ<28>")
	)
	(segment
		(start 59.718702 -18.313146)
		(end 59.718702 -17.038066)
		(width 0.14224)
		(layer "In11.Cu")
		(net "M_J_DQ<28>")
	)
	(segment
		(start 80.354678 -53.704236)
		(end 80.033622 -53.704236)
		(width 0.0889)
		(layer "In11.Cu")
		(net "M_J_DQ<28>")
	)
	(segment
		(start 59.718702 -21.949156)
		(end 59.972702 -21.695156)
		(width 0.14224)
		(layer "In11.Cu")
		(net "M_J_DQ<28>")
	)
	(segment
		(start 82.123788 -61.837824)
		(end 82.118962 -61.829188)
		(width 0.0889)
		(layer "In11.Cu")
		(net "M_J_DQ<28>")
	)
	(segment
		(start 82.118962 -62.819788)
		(end 82.112612 -62.80912)
		(width 0.0889)
		(layer "In11.Cu")
		(net "M_J_DQ<28>")
	)
	(segment
		(start 59.840368 -9.4742)
		(end 59.972702 -9.341866)
		(width 0.14224)
		(layer "In11.Cu")
		(net "M_J_DQ<28>")
	)
	(segment
		(start 59.972702 -8.965946)
		(end 59.718702 -8.711946)
		(width 0.14224)
		(layer "In11.Cu")
		(net "M_J_DQ<28>")
	)
	(segment
		(start 80.731106 -54.430422)
		(end 80.731106 -54.080664)
		(width 0.0889)
		(layer "In11.Cu")
		(net "M_J_DQ<28>")
	)
	(segment
		(start 69.487034 -42.260266)
		(end 69.1134 -41.886632)
		(width 0.14224)
		(layer "In11.Cu")
		(net "M_J_DQ<28>")
	)
	(segment
		(start 70.162166 -42.07383)
		(end 69.874638 -42.07383)
		(width 0.14224)
		(layer "In11.Cu")
		(net "M_J_DQ<28>")
	)
	(segment
		(start 59.718702 -13.567156)
		(end 59.718702 -12.347956)
		(width 0.14224)
		(layer "In11.Cu")
		(net "M_J_DQ<28>")
	)
	(segment
		(start 82.118962 -60.838588)
		(end 82.112612 -60.82792)
		(width 0.0889)
		(layer "In11.Cu")
		(net "M_J_DQ<28>")
	)
	(segment
		(start 59.906662 -28.285694)
		(end 59.732164 -28.111196)
		(width 0.14224)
		(layer "In11.Cu")
		(net "M_J_DQ<28>")
	)
	(segment
		(start 82.118962 -59.847988)
		(end 82.112612 -59.83732)
		(width 0.0889)
		(layer "In11.Cu")
		(net "M_J_DQ<28>")
	)
	(segment
		(start 59.840368 -11.602466)
		(end 59.840368 -9.4742)
		(width 0.14224)
		(layer "In11.Cu")
		(net "M_J_DQ<28>")
	)
	(arc
		(start 82.118962 -61.238638)
		(mid 82.172432 -61.043575)
		(end 82.123788 -60.847224)
		(width 0.0889)
		(layer "In11.Cu")
		(net "M_J_DQ<28>")
	)
	(arc
		(start 82.112612 -60.82792)
		(mid 82.039814 -60.537157)
		(end 82.118962 -60.248038)
		(width 0.0889)
		(layer "In11.Cu")
		(net "M_J_DQ<28>")
	)
	(arc
		(start 82.118962 -63.219838)
		(mid 82.172432 -63.024775)
		(end 82.123788 -62.828424)
		(width 0.0889)
		(layer "In11.Cu")
		(net "M_J_DQ<28>")
	)
	(arc
		(start 82.112612 -64.79032)
		(mid 82.039814 -64.499557)
		(end 82.118962 -64.210438)
		(width 0.0889)
		(layer "In11.Cu")
		(net "M_J_DQ<28>")
	)
	(arc
		(start 82.118962 -58.266838)
		(mid 82.172461 -58.06694)
		(end 82.118962 -57.867042)
		(width 0.0889)
		(layer "In11.Cu")
		(net "M_J_DQ<28>")
	)
	(arc
		(start 82.118962 -59.257438)
		(mid 82.172432 -59.062375)
		(end 82.123788 -58.866024)
		(width 0.0889)
		(layer "In11.Cu")
		(net "M_J_DQ<28>")
	)
	(arc
		(start 82.118962 -64.210438)
		(mid 82.172432 -64.015375)
		(end 82.123788 -63.819024)
		(width 0.0889)
		(layer "In11.Cu")
		(net "M_J_DQ<28>")
	)
	(arc
		(start 82.112612 -63.79972)
		(mid 82.039814 -63.508957)
		(end 82.118962 -63.219838)
		(width 0.0889)
		(layer "In11.Cu")
		(net "M_J_DQ<28>")
	)
	(arc
		(start 82.112612 -62.80912)
		(mid 82.039814 -62.518357)
		(end 82.118962 -62.229238)
		(width 0.0889)
		(layer "In11.Cu")
		(net "M_J_DQ<28>")
	)
	(arc
		(start 82.118962 -56.285638)
		(mid 82.172588 -56.085486)
		(end 82.118962 -55.885334)
		(width 0.0889)
		(layer "In11.Cu")
		(net "M_J_DQ<28>")
	)
	(arc
		(start 82.118962 -62.229238)
		(mid 82.172432 -62.034175)
		(end 82.123788 -61.837824)
		(width 0.0889)
		(layer "In11.Cu")
		(net "M_J_DQ<28>")
	)
	(arc
		(start 82.112612 -56.86552)
		(mid 82.039814 -56.574757)
		(end 82.118962 -56.285638)
		(width 0.0889)
		(layer "In11.Cu")
		(net "M_J_DQ<28>")
	)
	(arc
		(start 82.118962 -57.276238)
		(mid 82.172432 -57.081175)
		(end 82.123788 -56.884824)
		(width 0.0889)
		(layer "In11.Cu")
		(net "M_J_DQ<28>")
	)
	(arc
		(start 82.118962 -57.867042)
		(mid 82.039831 -57.57164)
		(end 82.118962 -57.276238)
		(width 0.0889)
		(layer "In11.Cu")
		(net "M_J_DQ<28>")
	)
	(arc
		(start 82.112612 -61.81852)
		(mid 82.039814 -61.527757)
		(end 82.118962 -61.238638)
		(width 0.0889)
		(layer "In11.Cu")
		(net "M_J_DQ<28>")
	)
	(arc
		(start 80.033622 -53.704236)
		(mid 79.750405 -53.619955)
		(end 79.543402 -53.409088)
		(width 0.0889)
		(layer "In11.Cu")
		(net "M_J_DQ<28>")
	)
	(arc
		(start 82.118962 -58.857388)
		(mid 82.03974 -58.56827)
		(end 82.112612 -58.277506)
		(width 0.0889)
		(layer "In11.Cu")
		(net "M_J_DQ<28>")
	)
	(arc
		(start 79.543402 -53.409088)
		(mid 79.396858 -53.262645)
		(end 79.196692 -53.20919)
		(width 0.0889)
		(layer "In11.Cu")
		(net "M_J_DQ<28>")
	)
	(arc
		(start 82.112612 -59.83732)
		(mid 82.039814 -59.546557)
		(end 82.118962 -59.257438)
		(width 0.0889)
		(layer "In11.Cu")
		(net "M_J_DQ<28>")
	)
	(arc
		(start 82.118962 -60.248038)
		(mid 82.172432 -60.052975)
		(end 82.123788 -59.856624)
		(width 0.0889)
		(layer "In11.Cu")
		(net "M_J_DQ<28>")
	)
	(segment
		(start 86.636352 -66.48704)
		(end 86.064852 -66.48704)
		(width 0.0889)
		(layer "F.Cu")
		(net "M_J_DQ<27>")
	)
	(segment
		(start 67.099434 3.778758)
		(end 67.099434 2.514854)
		(width 0.1651)
		(layer "F.Cu")
		(net "M_J_DQ<27>")
	)
	(via
		(at 86.064852 -66.48704)
		(size 0.508)
		(drill 0.254)
		(layers "F.Cu" "B.Cu")
		(net "M_J_DQ<27>")
	)
	(via
		(at 67.099434 2.514854)
		(size 0.508)
		(drill 0.254)
		(layers "F.Cu" "B.Cu")
		(net "M_J_DQ<27>")
	)
	(via
		(at 67.949318 -3.076956)
		(size 0.508)
		(drill 0.254)
		(layers "F.Cu" "B.Cu")
		(net "M_J_DQ<27>")
	)
	(segment
		(start 67.949318 -1.022096)
		(end 67.949318 -3.076956)
		(width 0.1651)
		(layer "B.Cu")
		(net "M_J_DQ<27>")
	)
	(segment
		(start 67.949572 -1.021842)
		(end 67.949318 -1.022096)
		(width 0.1651)
		(layer "B.Cu")
		(net "M_J_DQ<27>")
	)
	(segment
		(start 68.316602 -7.289546)
		(end 68.316602 -4.816856)
		(width 0.14224)
		(layer "In11.Cu")
		(net "M_J_DQ<27>")
	)
	(segment
		(start 68.303902 -11.729466)
		(end 68.476368 -11.557)
		(width 0.14224)
		(layer "In11.Cu")
		(net "M_J_DQ<27>")
	)
	(segment
		(start 68.476368 -21.138134)
		(end 68.476368 -19.1262)
		(width 0.14224)
		(layer "In11.Cu")
		(net "M_J_DQ<27>")
	)
	(segment
		(start 68.329302 -23.335996)
		(end 68.481702 -23.183596)
		(width 0.14224)
		(layer "In11.Cu")
		(net "M_J_DQ<27>")
	)
	(segment
		(start 68.461636 -26.909014)
		(end 68.329302 -26.77668)
		(width 0.14224)
		(layer "In11.Cu")
		(net "M_J_DQ<27>")
	)
	(segment
		(start 86.571836 -54.903624)
		(end 86.576662 -54.894988)
		(width 0.0889)
		(layer "In11.Cu")
		(net "M_J_DQ<27>")
	)
	(segment
		(start 68.303902 -8.986266)
		(end 68.456302 -8.833866)
		(width 0.14224)
		(layer "In11.Cu")
		(net "M_J_DQ<27>")
	)
	(segment
		(start 86.571836 -59.856624)
		(end 86.576662 -59.847988)
		(width 0.0889)
		(layer "In11.Cu")
		(net "M_J_DQ<27>")
	)
	(segment
		(start 86.571836 -56.884824)
		(end 86.576662 -56.876188)
		(width 0.0889)
		(layer "In11.Cu")
		(net "M_J_DQ<27>")
	)
	(segment
		(start 86.571836 -61.837824)
		(end 86.576662 -61.829188)
		(width 0.0889)
		(layer "In11.Cu")
		(net "M_J_DQ<27>")
	)
	(segment
		(start 68.000372 1.5494)
		(end 67.746372 1.5494)
		(width 0.14224)
		(layer "In11.Cu")
		(net "M_J_DQ<27>")
	)
	(segment
		(start 67.416172 1.8796)
		(end 67.416172 2.198116)
		(width 0.14224)
		(layer "In11.Cu")
		(net "M_J_DQ<27>")
	)
	(segment
		(start 86.571836 -58.866024)
		(end 86.576662 -58.857388)
		(width 0.0889)
		(layer "In11.Cu")
		(net "M_J_DQ<27>")
	)
	(segment
		(start 86.576662 -60.838588)
		(end 86.583012 -60.82792)
		(width 0.0889)
		(layer "In11.Cu")
		(net "M_J_DQ<27>")
	)
	(segment
		(start 67.746372 1.5494)
		(end 67.416172 1.8796)
		(width 0.14224)
		(layer "In11.Cu")
		(net "M_J_DQ<27>")
	)
	(segment
		(start 68.303902 -21.822156)
		(end 68.303902 -21.3106)
		(width 0.14224)
		(layer "In11.Cu")
		(net "M_J_DQ<27>")
	)
	(segment
		(start 68.476368 -9.545066)
		(end 68.303902 -9.3726)
		(width 0.14224)
		(layer "In11.Cu")
		(net "M_J_DQ<27>")
	)
	(segment
		(start 86.559898 -65.821052)
		(end 86.576662 -65.791588)
		(width 0.0889)
		(layer "In11.Cu")
		(net "M_J_DQ<27>")
	)
	(segment
		(start 85.655912 -51.877214)
		(end 84.502752 -50.724054)
		(width 0.0889)
		(layer "In11.Cu")
		(net "M_J_DQ<27>")
	)
	(segment
		(start 77.239368 -37.7444)
		(end 68.291964 -28.796996)
		(width 0.14224)
		(layer "In11.Cu")
		(net "M_J_DQ<27>")
	)
	(segment
		(start 68.303902 -12.220956)
		(end 68.303902 -11.729466)
		(width 0.14224)
		(layer "In11.Cu")
		(net "M_J_DQ<27>")
	)
	(segment
		(start 86.583012 -58.277506)
		(end 86.576662 -58.266838)
		(width 0.0889)
		(layer "In11.Cu")
		(net "M_J_DQ<27>")
	)
	(segment
		(start 67.949318 -3.076956)
		(end 68.302124 -2.72415)
		(width 0.14224)
		(layer "In11.Cu")
		(net "M_J_DQ<27>")
	)
	(segment
		(start 86.576662 -59.847988)
		(end 86.583012 -59.83732)
		(width 0.0889)
		(layer "In11.Cu")
		(net "M_J_DQ<27>")
	)
	(segment
		(start 85.272372 -49.426114)
		(end 85.272372 -48.154082)
		(width 0.14224)
		(layer "In11.Cu")
		(net "M_J_DQ<27>")
	)
	(segment
		(start 67.465702 -3.965956)
		(end 67.465702 -3.560572)
		(width 0.14224)
		(layer "In11.Cu")
		(net "M_J_DQ<27>")
	)
	(segment
		(start 68.303902 -18.587466)
		(end 68.456302 -18.435066)
		(width 0.14224)
		(layer "In11.Cu")
		(net "M_J_DQ<27>")
	)
	(segment
		(start 68.457572 1.0922)
		(end 68.000372 1.5494)
		(width 0.14224)
		(layer "In11.Cu")
		(net "M_J_DQ<27>")
	)
	(segment
		(start 68.291964 -28.263596)
		(end 68.461636 -28.093924)
		(width 0.14224)
		(layer "In11.Cu")
		(net "M_J_DQ<27>")
	)
	(segment
		(start 68.302124 -2.72415)
		(end 68.302124 0.581152)
		(width 0.14224)
		(layer "In11.Cu")
		(net "M_J_DQ<27>")
	)
	(segment
		(start 68.457572 0.7366)
		(end 68.457572 1.0922)
		(width 0.14224)
		(layer "In11.Cu")
		(net "M_J_DQ<27>")
	)
	(segment
		(start 85.272372 -48.154082)
		(end 77.239368 -40.121078)
		(width 0.14224)
		(layer "In11.Cu")
		(net "M_J_DQ<27>")
	)
	(segment
		(start 86.571836 -63.819024)
		(end 86.576662 -63.810388)
		(width 0.0889)
		(layer "In11.Cu")
		(net "M_J_DQ<27>")
	)
	(segment
		(start 84.502752 -50.409094)
		(end 85.038692 -49.873154)
		(width 0.0889)
		(layer "In11.Cu")
		(net "M_J_DQ<27>")
	)
	(segment
		(start 86.576662 -54.894988)
		(end 86.583012 -54.88432)
		(width 0.0889)
		(layer "In11.Cu")
		(net "M_J_DQ<27>")
	)
	(segment
		(start 86.576662 -63.810388)
		(end 86.583012 -63.79972)
		(width 0.0889)
		(layer "In11.Cu")
		(net "M_J_DQ<27>")
	)
	(segment
		(start 86.576662 -64.800988)
		(end 86.583012 -64.79032)
		(width 0.0889)
		(layer "In11.Cu")
		(net "M_J_DQ<27>")
	)
	(segment
		(start 85.897466 -54.00929)
		(end 85.655912 -53.767736)
		(width 0.0889)
		(layer "In11.Cu")
		(net "M_J_DQ<27>")
	)
	(segment
		(start 86.576662 -62.819788)
		(end 86.583012 -62.80912)
		(width 0.0889)
		(layer "In11.Cu")
		(net "M_J_DQ<27>")
	)
	(segment
		(start 86.571836 -64.809624)
		(end 86.576662 -64.800988)
		(width 0.0889)
		(layer "In11.Cu")
		(net "M_J_DQ<27>")
	)
	(segment
		(start 86.571836 -62.828424)
		(end 86.576662 -62.819788)
		(width 0.0889)
		(layer "In11.Cu")
		(net "M_J_DQ<27>")
	)
	(segment
		(start 68.461636 -28.093924)
		(end 68.461636 -26.909014)
		(width 0.14224)
		(layer "In11.Cu")
		(net "M_J_DQ<27>")
	)
	(segment
		(start 85.655912 -53.767736)
		(end 85.655912 -51.877214)
		(width 0.0889)
		(layer "In11.Cu")
		(net "M_J_DQ<27>")
	)
	(segment
		(start 86.571836 -60.847224)
		(end 86.576662 -60.838588)
		(width 0.0889)
		(layer "In11.Cu")
		(net "M_J_DQ<27>")
	)
	(segment
		(start 86.576662 -65.791588)
		(end 86.583012 -65.78092)
		(width 0.0889)
		(layer "In11.Cu")
		(net "M_J_DQ<27>")
	)
	(segment
		(start 67.465702 -3.560572)
		(end 67.949318 -3.076956)
		(width 0.14224)
		(layer "In11.Cu")
		(net "M_J_DQ<27>")
	)
	(segment
		(start 68.476368 -19.1262)
		(end 68.303902 -18.953734)
		(width 0.14224)
		(layer "In11.Cu")
		(net "M_J_DQ<27>")
	)
	(segment
		(start 68.302124 0.581152)
		(end 68.457572 0.7366)
		(width 0.14224)
		(layer "In11.Cu")
		(net "M_J_DQ<27>")
	)
	(segment
		(start 68.400168 -12.317222)
		(end 68.303902 -12.220956)
		(width 0.14224)
		(layer "In11.Cu")
		(net "M_J_DQ<27>")
	)
	(segment
		(start 68.456302 -7.429246)
		(end 68.316602 -7.289546)
		(width 0.14224)
		(layer "In11.Cu")
		(net "M_J_DQ<27>")
	)
	(segment
		(start 68.303902 -18.953734)
		(end 68.303902 -18.587466)
		(width 0.14224)
		(layer "In11.Cu")
		(net "M_J_DQ<27>")
	)
	(segment
		(start 86.571836 -55.894224)
		(end 86.576662 -55.885588)
		(width 0.0889)
		(layer "In11.Cu")
		(net "M_J_DQ<27>")
	)
	(segment
		(start 84.502752 -50.724054)
		(end 84.502752 -50.409094)
		(width 0.0889)
		(layer "In11.Cu")
		(net "M_J_DQ<27>")
	)
	(segment
		(start 86.576662 -55.885588)
		(end 86.583012 -55.87492)
		(width 0.0889)
		(layer "In11.Cu")
		(net "M_J_DQ<27>")
	)
	(segment
		(start 68.303902 -9.3726)
		(end 68.303902 -8.986266)
		(width 0.14224)
		(layer "In11.Cu")
		(net "M_J_DQ<27>")
	)
	(segment
		(start 67.416172 2.198116)
		(end 67.099434 2.514854)
		(width 0.14224)
		(layer "In11.Cu")
		(net "M_J_DQ<27>")
	)
	(segment
		(start 68.316602 -13.681456)
		(end 68.400168 -13.59789)
		(width 0.14224)
		(layer "In11.Cu")
		(net "M_J_DQ<27>")
	)
	(segment
		(start 68.329302 -26.77668)
		(end 68.329302 -23.335996)
		(width 0.14224)
		(layer "In11.Cu")
		(net "M_J_DQ<27>")
	)
	(segment
		(start 86.576662 -56.876188)
		(end 86.583012 -56.86552)
		(width 0.0889)
		(layer "In11.Cu")
		(net "M_J_DQ<27>")
	)
	(segment
		(start 68.481702 -23.183596)
		(end 68.481702 -21.999956)
		(width 0.14224)
		(layer "In11.Cu")
		(net "M_J_DQ<27>")
	)
	(segment
		(start 85.038692 -49.659794)
		(end 85.272372 -49.426114)
		(width 0.0889)
		(layer "In11.Cu")
		(net "M_J_DQ<27>")
	)
	(segment
		(start 68.303902 -21.3106)
		(end 68.476368 -21.138134)
		(width 0.14224)
		(layer "In11.Cu")
		(net "M_J_DQ<27>")
	)
	(segment
		(start 68.291964 -28.796996)
		(end 68.291964 -28.263596)
		(width 0.14224)
		(layer "In11.Cu")
		(net "M_J_DQ<27>")
	)
	(segment
		(start 77.239368 -40.121078)
		(end 77.239368 -37.7444)
		(width 0.14224)
		(layer "In11.Cu")
		(net "M_J_DQ<27>")
	)
	(segment
		(start 68.456302 -18.435066)
		(end 68.456302 -17.030446)
		(width 0.14224)
		(layer "In11.Cu")
		(net "M_J_DQ<27>")
	)
	(segment
		(start 86.086442 -54.00929)
		(end 85.897466 -54.00929)
		(width 0.0889)
		(layer "In11.Cu")
		(net "M_J_DQ<27>")
	)
	(segment
		(start 68.400168 -13.59789)
		(end 68.400168 -12.317222)
		(width 0.14224)
		(layer "In11.Cu")
		(net "M_J_DQ<27>")
	)
	(segment
		(start 68.476368 -11.557)
		(end 68.476368 -9.545066)
		(width 0.14224)
		(layer "In11.Cu")
		(net "M_J_DQ<27>")
	)
	(segment
		(start 68.316602 -4.816856)
		(end 67.465702 -3.965956)
		(width 0.14224)
		(layer "In11.Cu")
		(net "M_J_DQ<27>")
	)
	(segment
		(start 86.064852 -66.48704)
		(end 86.559898 -65.821052)
		(width 0.0889)
		(layer "In11.Cu")
		(net "M_J_DQ<27>")
	)
	(segment
		(start 68.456302 -8.833866)
		(end 68.456302 -7.429246)
		(width 0.14224)
		(layer "In11.Cu")
		(net "M_J_DQ<27>")
	)
	(segment
		(start 86.576662 -61.829188)
		(end 86.583012 -61.81852)
		(width 0.0889)
		(layer "In11.Cu")
		(net "M_J_DQ<27>")
	)
	(segment
		(start 85.038692 -49.873154)
		(end 85.038692 -49.659794)
		(width 0.0889)
		(layer "In11.Cu")
		(net "M_J_DQ<27>")
	)
	(segment
		(start 68.456302 -17.030446)
		(end 68.316602 -16.890746)
		(width 0.14224)
		(layer "In11.Cu")
		(net "M_J_DQ<27>")
	)
	(segment
		(start 68.481702 -21.999956)
		(end 68.303902 -21.822156)
		(width 0.14224)
		(layer "In11.Cu")
		(net "M_J_DQ<27>")
	)
	(segment
		(start 68.316602 -16.890746)
		(end 68.316602 -13.681456)
		(width 0.14224)
		(layer "In11.Cu")
		(net "M_J_DQ<27>")
	)
	(arc
		(start 86.576662 -60.248038)
		(mid 86.523192 -60.052975)
		(end 86.571836 -59.856624)
		(width 0.0889)
		(layer "In11.Cu")
		(net "M_J_DQ<27>")
	)
	(arc
		(start 86.576662 -55.295038)
		(mid 86.523192 -55.099975)
		(end 86.571836 -54.903624)
		(width 0.0889)
		(layer "In11.Cu")
		(net "M_J_DQ<27>")
	)
	(arc
		(start 86.583012 -62.80912)
		(mid 86.65581 -62.518357)
		(end 86.576662 -62.229238)
		(width 0.0889)
		(layer "In11.Cu")
		(net "M_J_DQ<27>")
	)
	(arc
		(start 86.583012 -60.82792)
		(mid 86.65581 -60.537157)
		(end 86.576662 -60.248038)
		(width 0.0889)
		(layer "In11.Cu")
		(net "M_J_DQ<27>")
	)
	(arc
		(start 86.583012 -54.88432)
		(mid 86.578981 -54.308138)
		(end 86.086442 -54.00929)
		(width 0.0889)
		(layer "In11.Cu")
		(net "M_J_DQ<27>")
	)
	(arc
		(start 86.576662 -63.219838)
		(mid 86.523192 -63.024775)
		(end 86.571836 -62.828424)
		(width 0.0889)
		(layer "In11.Cu")
		(net "M_J_DQ<27>")
	)
	(arc
		(start 86.583012 -61.81852)
		(mid 86.65581 -61.527757)
		(end 86.576662 -61.238638)
		(width 0.0889)
		(layer "In11.Cu")
		(net "M_J_DQ<27>")
	)
	(arc
		(start 86.576662 -56.285638)
		(mid 86.523192 -56.090575)
		(end 86.571836 -55.894224)
		(width 0.0889)
		(layer "In11.Cu")
		(net "M_J_DQ<27>")
	)
	(arc
		(start 86.583012 -56.86552)
		(mid 86.65581 -56.574757)
		(end 86.576662 -56.285638)
		(width 0.0889)
		(layer "In11.Cu")
		(net "M_J_DQ<27>")
	)
	(arc
		(start 86.583012 -63.79972)
		(mid 86.65581 -63.508957)
		(end 86.576662 -63.219838)
		(width 0.0889)
		(layer "In11.Cu")
		(net "M_J_DQ<27>")
	)
	(arc
		(start 86.576662 -64.210438)
		(mid 86.523192 -64.015375)
		(end 86.571836 -63.819024)
		(width 0.0889)
		(layer "In11.Cu")
		(net "M_J_DQ<27>")
	)
	(arc
		(start 86.583012 -59.83732)
		(mid 86.65581 -59.546557)
		(end 86.576662 -59.257438)
		(width 0.0889)
		(layer "In11.Cu")
		(net "M_J_DQ<27>")
	)
	(arc
		(start 86.576662 -57.867042)
		(mid 86.655793 -57.57164)
		(end 86.576662 -57.276238)
		(width 0.0889)
		(layer "In11.Cu")
		(net "M_J_DQ<27>")
	)
	(arc
		(start 86.583012 -55.87492)
		(mid 86.65581 -55.584157)
		(end 86.576662 -55.295038)
		(width 0.0889)
		(layer "In11.Cu")
		(net "M_J_DQ<27>")
	)
	(arc
		(start 86.583012 -64.79032)
		(mid 86.65581 -64.499557)
		(end 86.576662 -64.210438)
		(width 0.0889)
		(layer "In11.Cu")
		(net "M_J_DQ<27>")
	)
	(arc
		(start 86.576662 -58.266838)
		(mid 86.523163 -58.06694)
		(end 86.576662 -57.867042)
		(width 0.0889)
		(layer "In11.Cu")
		(net "M_J_DQ<27>")
	)
	(arc
		(start 86.576662 -65.201038)
		(mid 86.523192 -65.005975)
		(end 86.571836 -64.809624)
		(width 0.0889)
		(layer "In11.Cu")
		(net "M_J_DQ<27>")
	)
	(arc
		(start 86.576662 -57.276238)
		(mid 86.523192 -57.081175)
		(end 86.571836 -56.884824)
		(width 0.0889)
		(layer "In11.Cu")
		(net "M_J_DQ<27>")
	)
	(arc
		(start 86.583012 -65.78092)
		(mid 86.65581 -65.490157)
		(end 86.576662 -65.201038)
		(width 0.0889)
		(layer "In11.Cu")
		(net "M_J_DQ<27>")
	)
	(arc
		(start 86.576662 -62.229238)
		(mid 86.523192 -62.034175)
		(end 86.571836 -61.837824)
		(width 0.0889)
		(layer "In11.Cu")
		(net "M_J_DQ<27>")
	)
	(arc
		(start 86.576662 -61.238638)
		(mid 86.523192 -61.043575)
		(end 86.571836 -60.847224)
		(width 0.0889)
		(layer "In11.Cu")
		(net "M_J_DQ<27>")
	)
	(arc
		(start 86.576662 -59.257438)
		(mid 86.523192 -59.062375)
		(end 86.571836 -58.866024)
		(width 0.0889)
		(layer "In11.Cu")
		(net "M_J_DQ<27>")
	)
	(arc
		(start 86.576662 -58.857388)
		(mid 86.655884 -58.56827)
		(end 86.583012 -58.277506)
		(width 0.0889)
		(layer "In11.Cu")
		(net "M_J_DQ<27>")
	)
	(segment
		(start 67.949572 -0.821182)
		(end 67.949318 -0.820928)
		(width 0.1651)
		(layer "F.Cu")
		(net "M_J_DQ<26>")
	)
	(segment
		(start 67.949318 -0.820928)
		(end 67.949318 0.175768)
		(width 0.1651)
		(layer "F.Cu")
		(net "M_J_DQ<26>")
	)
	(segment
		(start 68.08089 0.53086)
		(end 67.949318 0.662432)
		(width 0.1651)
		(layer "F.Cu")
		(net "M_J_DQ<26>")
	)
	(segment
		(start 86.636352 -65.49644)
		(end 86.064852 -65.49644)
		(width 0.0889)
		(layer "F.Cu")
		(net "M_J_DQ<26>")
	)
	(segment
		(start 67.949318 0.662432)
		(end 67.949318 0.9398)
		(width 0.1651)
		(layer "F.Cu")
		(net "M_J_DQ<26>")
	)
	(segment
		(start 67.949318 0.175768)
		(end 68.08089 0.30734)
		(width 0.1651)
		(layer "F.Cu")
		(net "M_J_DQ<26>")
	)
	(segment
		(start 68.08089 0.30734)
		(end 68.08089 0.53086)
		(width 0.1651)
		(layer "F.Cu")
		(net "M_J_DQ<26>")
	)
	(via
		(at 67.949318 0.9398)
		(size 0.508)
		(drill 0.254)
		(layers "F.Cu" "B.Cu")
		(net "M_J_DQ<26>")
	)
	(via
		(at 67.099434 -4.357878)
		(size 0.508)
		(drill 0.254)
		(layers "F.Cu" "B.Cu")
		(net "M_J_DQ<26>")
	)
	(via
		(at 86.064852 -65.49644)
		(size 0.508)
		(drill 0.254)
		(layers "F.Cu" "B.Cu")
		(net "M_J_DQ<26>")
	)
	(segment
		(start 67.099434 -5.621782)
		(end 67.099434 -4.357878)
		(width 0.1651)
		(layer "B.Cu")
		(net "M_J_DQ<26>")
	)
	(segment
		(start 76.49464 -38.295072)
		(end 76.49464 -38.49624)
		(width 0.14224)
		(layer "In11.Cu")
		(net "M_J_DQ<26>")
	)
	(segment
		(start 86.416388 -60.734702)
		(end 86.411562 -60.743338)
		(width 0.0889)
		(layer "In11.Cu")
		(net "M_J_DQ<26>")
	)
	(segment
		(start 66.8147 -4.073144)
		(end 67.099434 -4.357878)
		(width 0.14224)
		(layer "In11.Cu")
		(net "M_J_DQ<26>")
	)
	(segment
		(start 86.39429 -64.735456)
		(end 86.064852 -65.49644)
		(width 0.0889)
		(layer "In11.Cu")
		(net "M_J_DQ<26>")
	)
	(segment
		(start 67.681602 -16.751046)
		(end 67.465702 -16.966946)
		(width 0.14224)
		(layer "In11.Cu")
		(net "M_J_DQ<26>")
	)
	(segment
		(start 85.465412 -53.849524)
		(end 85.815678 -54.19979)
		(width 0.0889)
		(layer "In11.Cu")
		(net "M_J_DQ<26>")
	)
	(segment
		(start 86.405212 -58.35142)
		(end 86.411562 -58.362088)
		(width 0.0889)
		(layer "In11.Cu")
		(net "M_J_DQ<26>")
	)
	(segment
		(start 67.592702 -21.336)
		(end 67.592702 -21.796756)
		(width 0.14224)
		(layer "In11.Cu")
		(net "M_J_DQ<26>")
	)
	(segment
		(start 86.416388 -62.715902)
		(end 86.411562 -62.724538)
		(width 0.0889)
		(layer "In11.Cu")
		(net "M_J_DQ<26>")
	)
	(segment
		(start 76.235814 -38.036246)
		(end 76.49464 -38.295072)
		(width 0.14224)
		(layer "In11.Cu")
		(net "M_J_DQ<26>")
	)
	(segment
		(start 67.206368 -0.108204)
		(end 67.206368 -0.456946)
		(width 0.14224)
		(layer "In11.Cu")
		(net "M_J_DQ<26>")
	)
	(segment
		(start 67.668902 -7.162546)
		(end 67.465702 -7.365746)
		(width 0.14224)
		(layer "In11.Cu")
		(net "M_J_DQ<26>")
	)
	(segment
		(start 67.663568 -2.478532)
		(end 66.8147 -3.3274)
		(width 0.14224)
		(layer "In11.Cu")
		(net "M_J_DQ<26>")
	)
	(segment
		(start 67.428364 -28.085796)
		(end 67.580764 -28.238196)
		(width 0.14224)
		(layer "In11.Cu")
		(net "M_J_DQ<26>")
	)
	(segment
		(start 67.511168 -0.761746)
		(end 67.511168 -1.04775)
		(width 0.14224)
		(layer "In11.Cu")
		(net "M_J_DQ<26>")
	)
	(segment
		(start 86.416388 -56.772302)
		(end 86.411562 -56.780938)
		(width 0.0889)
		(layer "In11.Cu")
		(net "M_J_DQ<26>")
	)
	(segment
		(start 67.668902 -5.08381)
		(end 67.668902 -7.162546)
		(width 0.14224)
		(layer "In11.Cu")
		(net "M_J_DQ<26>")
	)
	(segment
		(start 67.099434 -4.357878)
		(end 67.099434 -4.514342)
		(width 0.14224)
		(layer "In11.Cu")
		(net "M_J_DQ<26>")
	)
	(segment
		(start 86.416388 -54.791102)
		(end 86.411562 -54.799738)
		(width 0.0889)
		(layer "In11.Cu")
		(net "M_J_DQ<26>")
	)
	(segment
		(start 67.465702 -18.445734)
		(end 67.592702 -18.572734)
		(width 0.14224)
		(layer "In11.Cu")
		(net "M_J_DQ<26>")
	)
	(segment
		(start 67.448684 -9.587484)
		(end 67.448684 -11.590782)
		(width 0.14224)
		(layer "In11.Cu")
		(net "M_J_DQ<26>")
	)
	(segment
		(start 67.448684 -11.590782)
		(end 67.592702 -11.7348)
		(width 0.14224)
		(layer "In11.Cu")
		(net "M_J_DQ<26>")
	)
	(segment
		(start 84.312252 -50.802794)
		(end 85.465412 -51.955954)
		(width 0.0889)
		(layer "In11.Cu")
		(net "M_J_DQ<26>")
	)
	(segment
		(start 86.411562 -62.724538)
		(end 86.405212 -62.735206)
		(width 0.0889)
		(layer "In11.Cu")
		(net "M_J_DQ<26>")
	)
	(segment
		(start 67.099434 -4.514342)
		(end 67.668902 -5.08381)
		(width 0.14224)
		(layer "In11.Cu")
		(net "M_J_DQ<26>")
	)
	(segment
		(start 84.637372 -48.41748)
		(end 84.637372 -49.426114)
		(width 0.14224)
		(layer "In11.Cu")
		(net "M_J_DQ<26>")
	)
	(segment
		(start 86.411562 -56.780938)
		(end 86.405212 -56.791606)
		(width 0.0889)
		(layer "In11.Cu")
		(net "M_J_DQ<26>")
	)
	(segment
		(start 84.312252 -50.330354)
		(end 84.312252 -50.802794)
		(width 0.0889)
		(layer "In11.Cu")
		(net "M_J_DQ<26>")
	)
	(segment
		(start 67.440302 -13.541756)
		(end 67.681602 -13.783056)
		(width 0.14224)
		(layer "In11.Cu")
		(net "M_J_DQ<26>")
	)
	(segment
		(start 67.580764 -23.283418)
		(end 67.580764 -26.663396)
		(width 0.14224)
		(layer "In11.Cu")
		(net "M_J_DQ<26>")
	)
	(segment
		(start 76.034646 -38.036246)
		(end 76.235814 -38.036246)
		(width 0.14224)
		(layer "In11.Cu")
		(net "M_J_DQ<26>")
	)
	(segment
		(start 86.411562 -59.752738)
		(end 86.405212 -59.763406)
		(width 0.0889)
		(layer "In11.Cu")
		(net "M_J_DQ<26>")
	)
	(segment
		(start 86.416388 -59.744102)
		(end 86.411562 -59.752738)
		(width 0.0889)
		(layer "In11.Cu")
		(net "M_J_DQ<26>")
	)
	(segment
		(start 67.409568 -19.1516)
		(end 67.409568 -21.152866)
		(width 0.14224)
		(layer "In11.Cu")
		(net "M_J_DQ<26>")
	)
	(segment
		(start 86.416388 -57.762902)
		(end 86.411562 -57.771538)
		(width 0.0889)
		(layer "In11.Cu")
		(net "M_J_DQ<26>")
	)
	(segment
		(start 76.49464 -38.49624)
		(end 75.70597 -39.28491)
		(width 0.14224)
		(layer "In11.Cu")
		(net "M_J_DQ<26>")
	)
	(segment
		(start 67.440302 -23.142956)
		(end 67.580764 -23.283418)
		(width 0.14224)
		(layer "In11.Cu")
		(net "M_J_DQ<26>")
	)
	(segment
		(start 67.465702 -8.844534)
		(end 67.592702 -8.971534)
		(width 0.14224)
		(layer "In11.Cu")
		(net "M_J_DQ<26>")
	)
	(segment
		(start 67.206368 -0.456946)
		(end 67.511168 -0.761746)
		(width 0.14224)
		(layer "In11.Cu")
		(net "M_J_DQ<26>")
	)
	(segment
		(start 67.681602 -13.783056)
		(end 67.681602 -16.751046)
		(width 0.14224)
		(layer "In11.Cu")
		(net "M_J_DQ<26>")
	)
	(segment
		(start 67.592702 -11.7348)
		(end 67.592702 -12.195556)
		(width 0.14224)
		(layer "In11.Cu")
		(net "M_J_DQ<26>")
	)
	(segment
		(start 84.848192 -49.636934)
		(end 84.848192 -49.794414)
		(width 0.0889)
		(layer "In11.Cu")
		(net "M_J_DQ<26>")
	)
	(segment
		(start 67.5513 0.236728)
		(end 67.206368 -0.108204)
		(width 0.14224)
		(layer "In11.Cu")
		(net "M_J_DQ<26>")
	)
	(segment
		(start 84.637372 -49.426114)
		(end 84.848192 -49.636934)
		(width 0.0889)
		(layer "In11.Cu")
		(net "M_J_DQ<26>")
	)
	(segment
		(start 74.572368 -35.975544)
		(end 74.572368 -38.352476)
		(width 0.14224)
		(layer "In11.Cu")
		(net "M_J_DQ<26>")
	)
	(segment
		(start 86.411562 -63.715138)
		(end 86.405212 -63.725806)
		(width 0.0889)
		(layer "In11.Cu")
		(net "M_J_DQ<26>")
	)
	(segment
		(start 86.411562 -55.790338)
		(end 86.405212 -55.801006)
		(width 0.0889)
		(layer "In11.Cu")
		(net "M_J_DQ<26>")
	)
	(segment
		(start 67.440302 -21.949156)
		(end 67.440302 -23.142956)
		(width 0.14224)
		(layer "In11.Cu")
		(net "M_J_DQ<26>")
	)
	(segment
		(start 67.592702 -21.796756)
		(end 67.440302 -21.949156)
		(width 0.14224)
		(layer "In11.Cu")
		(net "M_J_DQ<26>")
	)
	(segment
		(start 67.592702 -12.195556)
		(end 67.440302 -12.347956)
		(width 0.14224)
		(layer "In11.Cu")
		(net "M_J_DQ<26>")
	)
	(segment
		(start 67.206368 -1.35255)
		(end 67.206368 -1.7526)
		(width 0.14224)
		(layer "In11.Cu")
		(net "M_J_DQ<26>")
	)
	(segment
		(start 67.465702 -7.365746)
		(end 67.465702 -8.844534)
		(width 0.14224)
		(layer "In11.Cu")
		(net "M_J_DQ<26>")
	)
	(segment
		(start 85.815678 -54.19979)
		(end 86.079838 -54.19979)
		(width 0.0889)
		(layer "In11.Cu")
		(net "M_J_DQ<26>")
	)
	(segment
		(start 75.70597 -39.486078)
		(end 84.637372 -48.41748)
		(width 0.14224)
		(layer "In11.Cu")
		(net "M_J_DQ<26>")
	)
	(segment
		(start 67.440302 -12.347956)
		(end 67.440302 -13.541756)
		(width 0.14224)
		(layer "In11.Cu")
		(net "M_J_DQ<26>")
	)
	(segment
		(start 67.592702 -18.572734)
		(end 67.592702 -18.968466)
		(width 0.14224)
		(layer "In11.Cu")
		(net "M_J_DQ<26>")
	)
	(segment
		(start 85.465412 -51.955954)
		(end 85.465412 -53.849524)
		(width 0.0889)
		(layer "In11.Cu")
		(net "M_J_DQ<26>")
	)
	(segment
		(start 86.411562 -61.733938)
		(end 86.405212 -61.744606)
		(width 0.0889)
		(layer "In11.Cu")
		(net "M_J_DQ<26>")
	)
	(segment
		(start 67.663568 -2.2098)
		(end 67.663568 -2.478532)
		(width 0.14224)
		(layer "In11.Cu")
		(net "M_J_DQ<26>")
	)
	(segment
		(start 67.580764 -28.238196)
		(end 67.580764 -28.98394)
		(width 0.14224)
		(layer "In11.Cu")
		(net "M_J_DQ<26>")
	)
	(segment
		(start 86.411562 -60.743338)
		(end 86.405212 -60.754006)
		(width 0.0889)
		(layer "In11.Cu")
		(net "M_J_DQ<26>")
	)
	(segment
		(start 67.592702 -8.971534)
		(end 67.592702 -9.443466)
		(width 0.14224)
		(layer "In11.Cu")
		(net "M_J_DQ<26>")
	)
	(segment
		(start 86.411562 -54.799738)
		(end 86.405212 -54.810406)
		(width 0.0889)
		(layer "In11.Cu")
		(net "M_J_DQ<26>")
	)
	(segment
		(start 74.572368 -38.352476)
		(end 75.044808 -38.824916)
		(width 0.14224)
		(layer "In11.Cu")
		(net "M_J_DQ<26>")
	)
	(segment
		(start 67.580764 -28.98394)
		(end 74.572368 -35.975544)
		(width 0.14224)
		(layer "In11.Cu")
		(net "M_J_DQ<26>")
	)
	(segment
		(start 75.70597 -39.28491)
		(end 75.70597 -39.486078)
		(width 0.14224)
		(layer "In11.Cu")
		(net "M_J_DQ<26>")
	)
	(segment
		(start 66.8147 -3.3274)
		(end 66.8147 -4.073144)
		(width 0.14224)
		(layer "In11.Cu")
		(net "M_J_DQ<26>")
	)
	(segment
		(start 67.949318 0.9398)
		(end 67.5513 0.541782)
		(width 0.14224)
		(layer "In11.Cu")
		(net "M_J_DQ<26>")
	)
	(segment
		(start 75.044808 -38.824916)
		(end 75.245976 -38.824916)
		(width 0.14224)
		(layer "In11.Cu")
		(net "M_J_DQ<26>")
	)
	(segment
		(start 67.592702 -18.968466)
		(end 67.409568 -19.1516)
		(width 0.14224)
		(layer "In11.Cu")
		(net "M_J_DQ<26>")
	)
	(segment
		(start 86.416388 -64.697102)
		(end 86.39429 -64.735456)
		(width 0.0889)
		(layer "In11.Cu")
		(net "M_J_DQ<26>")
	)
	(segment
		(start 67.580764 -26.663396)
		(end 67.428364 -26.815796)
		(width 0.14224)
		(layer "In11.Cu")
		(net "M_J_DQ<26>")
	)
	(segment
		(start 67.409568 -21.152866)
		(end 67.592702 -21.336)
		(width 0.14224)
		(layer "In11.Cu")
		(net "M_J_DQ<26>")
	)
	(segment
		(start 84.848192 -49.794414)
		(end 84.312252 -50.330354)
		(width 0.0889)
		(layer "In11.Cu")
		(net "M_J_DQ<26>")
	)
	(segment
		(start 67.465702 -16.966946)
		(end 67.465702 -18.445734)
		(width 0.14224)
		(layer "In11.Cu")
		(net "M_J_DQ<26>")
	)
	(segment
		(start 86.416388 -63.706502)
		(end 86.411562 -63.715138)
		(width 0.0889)
		(layer "In11.Cu")
		(net "M_J_DQ<26>")
	)
	(segment
		(start 86.416388 -61.725302)
		(end 86.411562 -61.733938)
		(width 0.0889)
		(layer "In11.Cu")
		(net "M_J_DQ<26>")
	)
	(segment
		(start 75.245976 -38.824916)
		(end 76.034646 -38.036246)
		(width 0.14224)
		(layer "In11.Cu")
		(net "M_J_DQ<26>")
	)
	(segment
		(start 67.206368 -1.7526)
		(end 67.663568 -2.2098)
		(width 0.14224)
		(layer "In11.Cu")
		(net "M_J_DQ<26>")
	)
	(segment
		(start 67.511168 -1.04775)
		(end 67.206368 -1.35255)
		(width 0.14224)
		(layer "In11.Cu")
		(net "M_J_DQ<26>")
	)
	(segment
		(start 86.416388 -55.781702)
		(end 86.411562 -55.790338)
		(width 0.0889)
		(layer "In11.Cu")
		(net "M_J_DQ<26>")
	)
	(segment
		(start 67.5513 0.541782)
		(end 67.5513 0.236728)
		(width 0.14224)
		(layer "In11.Cu")
		(net "M_J_DQ<26>")
	)
	(segment
		(start 67.428364 -26.815796)
		(end 67.428364 -28.085796)
		(width 0.14224)
		(layer "In11.Cu")
		(net "M_J_DQ<26>")
	)
	(segment
		(start 67.592702 -9.443466)
		(end 67.448684 -9.587484)
		(width 0.14224)
		(layer "In11.Cu")
		(net "M_J_DQ<26>")
	)
	(arc
		(start 86.405212 -54.810406)
		(mid 86.332414 -55.101169)
		(end 86.411562 -55.390288)
		(width 0.0889)
		(layer "In11.Cu")
		(net "M_J_DQ<26>")
	)
	(arc
		(start 86.405212 -55.801006)
		(mid 86.332414 -56.091769)
		(end 86.411562 -56.380888)
		(width 0.0889)
		(layer "In11.Cu")
		(net "M_J_DQ<26>")
	)
	(arc
		(start 86.411562 -57.371488)
		(mid 86.465032 -57.566551)
		(end 86.416388 -57.762902)
		(width 0.0889)
		(layer "In11.Cu")
		(net "M_J_DQ<26>")
	)
	(arc
		(start 86.411562 -59.352688)
		(mid 86.465032 -59.547751)
		(end 86.416388 -59.744102)
		(width 0.0889)
		(layer "In11.Cu")
		(net "M_J_DQ<26>")
	)
	(arc
		(start 86.411562 -61.333888)
		(mid 86.465032 -61.528951)
		(end 86.416388 -61.725302)
		(width 0.0889)
		(layer "In11.Cu")
		(net "M_J_DQ<26>")
	)
	(arc
		(start 86.405212 -63.725806)
		(mid 86.332414 -64.016569)
		(end 86.411562 -64.305688)
		(width 0.0889)
		(layer "In11.Cu")
		(net "M_J_DQ<26>")
	)
	(arc
		(start 86.405212 -61.744606)
		(mid 86.332414 -62.035369)
		(end 86.411562 -62.324488)
		(width 0.0889)
		(layer "In11.Cu")
		(net "M_J_DQ<26>")
	)
	(arc
		(start 86.411562 -57.771538)
		(mid 86.33234 -58.060656)
		(end 86.405212 -58.35142)
		(width 0.0889)
		(layer "In11.Cu")
		(net "M_J_DQ<26>")
	)
	(arc
		(start 86.411562 -63.315088)
		(mid 86.465032 -63.510151)
		(end 86.416388 -63.706502)
		(width 0.0889)
		(layer "In11.Cu")
		(net "M_J_DQ<26>")
	)
	(arc
		(start 86.411562 -55.390288)
		(mid 86.465032 -55.585351)
		(end 86.416388 -55.781702)
		(width 0.0889)
		(layer "In11.Cu")
		(net "M_J_DQ<26>")
	)
	(arc
		(start 86.411562 -64.305688)
		(mid 86.465032 -64.500751)
		(end 86.416388 -64.697102)
		(width 0.0889)
		(layer "In11.Cu")
		(net "M_J_DQ<26>")
	)
	(arc
		(start 86.411562 -56.380888)
		(mid 86.465032 -56.575951)
		(end 86.416388 -56.772302)
		(width 0.0889)
		(layer "In11.Cu")
		(net "M_J_DQ<26>")
	)
	(arc
		(start 86.411562 -62.324488)
		(mid 86.465032 -62.519551)
		(end 86.416388 -62.715902)
		(width 0.0889)
		(layer "In11.Cu")
		(net "M_J_DQ<26>")
	)
	(arc
		(start 86.405212 -60.754006)
		(mid 86.332414 -61.044769)
		(end 86.411562 -61.333888)
		(width 0.0889)
		(layer "In11.Cu")
		(net "M_J_DQ<26>")
	)
	(arc
		(start 86.411562 -58.761884)
		(mid 86.332431 -59.057286)
		(end 86.411562 -59.352688)
		(width 0.0889)
		(layer "In11.Cu")
		(net "M_J_DQ<26>")
	)
	(arc
		(start 86.405212 -59.763406)
		(mid 86.332414 -60.054169)
		(end 86.411562 -60.343288)
		(width 0.0889)
		(layer "In11.Cu")
		(net "M_J_DQ<26>")
	)
	(arc
		(start 86.411562 -58.362088)
		(mid 86.465061 -58.561986)
		(end 86.411562 -58.761884)
		(width 0.0889)
		(layer "In11.Cu")
		(net "M_J_DQ<26>")
	)
	(arc
		(start 86.079838 -54.19979)
		(mid 86.412756 -54.401781)
		(end 86.416388 -54.791102)
		(width 0.0889)
		(layer "In11.Cu")
		(net "M_J_DQ<26>")
	)
	(arc
		(start 86.411562 -60.343288)
		(mid 86.465032 -60.538351)
		(end 86.416388 -60.734702)
		(width 0.0889)
		(layer "In11.Cu")
		(net "M_J_DQ<26>")
	)
	(arc
		(start 86.405212 -62.735206)
		(mid 86.332414 -63.025969)
		(end 86.411562 -63.315088)
		(width 0.0889)
		(layer "In11.Cu")
		(net "M_J_DQ<26>")
	)
	(arc
		(start 86.405212 -56.791606)
		(mid 86.332414 -57.082369)
		(end 86.411562 -57.371488)
		(width 0.0889)
		(layer "In11.Cu")
		(net "M_J_DQ<26>")
	)
	(segment
		(start 61.149484 3.778758)
		(end 61.149484 2.514854)
		(width 0.1651)
		(layer "F.Cu")
		(net "M_J_DQ<25>")
	)
	(segment
		(start 84.060792 -66.982086)
		(end 83.489292 -66.982086)
		(width 0.1016)
		(layer "F.Cu")
		(net "M_J_DQ<25>")
	)
	(via
		(at 83.489292 -66.982086)
		(size 0.508)
		(drill 0.254)
		(layers "F.Cu" "B.Cu")
		(net "M_J_DQ<25>")
	)
	(via
		(at 61.149484 2.514854)
		(size 0.508)
		(drill 0.254)
		(layers "F.Cu" "B.Cu")
		(net "M_J_DQ<25>")
	)
	(via
		(at 61.821568 -3.076956)
		(size 0.508)
		(drill 0.254)
		(layers "F.Cu" "B.Cu")
		(net "M_J_DQ<25>")
	)
	(segment
		(start 61.821568 -2.573782)
		(end 61.821568 -3.076956)
		(width 0.1651)
		(layer "B.Cu")
		(net "M_J_DQ<25>")
	)
	(segment
		(start 61.999368 -1.021842)
		(end 61.999368 -2.395982)
		(width 0.1651)
		(layer "B.Cu")
		(net "M_J_DQ<25>")
	)
	(segment
		(start 61.999368 -2.395982)
		(end 61.821568 -2.573782)
		(width 0.1651)
		(layer "B.Cu")
		(net "M_J_DQ<25>")
	)
	(segment
		(start 63.802768 -32.424116)
		(end 63.802768 -30.65145)
		(width 0.14224)
		(layer "In11.Cu")
		(net "M_J_DQ<25>")
	)
	(segment
		(start 82.158332 -53.851302)
		(end 82.158332 -53.439822)
		(width 0.0889)
		(layer "In11.Cu")
		(net "M_J_DQ<25>")
	)
	(segment
		(start 62.456568 -11.562334)
		(end 62.456568 -9.6012)
		(width 0.14224)
		(layer "In11.Cu")
		(net "M_J_DQ<25>")
	)
	(segment
		(start 82.452464 -54.145434)
		(end 82.158332 -53.851302)
		(width 0.0889)
		(layer "In11.Cu")
		(net "M_J_DQ<25>")
	)
	(segment
		(start 61.149484 1.975866)
		(end 61.149484 2.514854)
		(width 0.14224)
		(layer "In11.Cu")
		(net "M_J_DQ<25>")
	)
	(segment
		(start 80.295496 -51.24831)
		(end 78.966568 -49.919382)
		(width 0.14224)
		(layer "In11.Cu")
		(net "M_J_DQ<25>")
	)
	(segment
		(start 83.142582 -59.847988)
		(end 83.148932 -59.83732)
		(width 0.0889)
		(layer "In11.Cu")
		(net "M_J_DQ<25>")
	)
	(segment
		(start 83.084162 -56.184546)
		(end 83.084162 -55.52821)
		(width 0.0889)
		(layer "In11.Cu")
		(net "M_J_DQ<25>")
	)
	(segment
		(start 62.19571 0.630936)
		(end 62.352174 0.7874)
		(width 0.14224)
		(layer "In11.Cu")
		(net "M_J_DQ<25>")
	)
	(segment
		(start 83.137756 -61.837824)
		(end 83.142582 -61.829188)
		(width 0.0889)
		(layer "In11.Cu")
		(net "M_J_DQ<25>")
	)
	(segment
		(start 62.352174 1.128776)
		(end 61.98235 1.4986)
		(width 0.14224)
		(layer "In11.Cu")
		(net "M_J_DQ<25>")
	)
	(segment
		(start 62.352174 0.7874)
		(end 62.352174 1.128776)
		(width 0.14224)
		(layer "In11.Cu")
		(net "M_J_DQ<25>")
	)
	(segment
		(start 83.137756 -60.847224)
		(end 83.142582 -60.838588)
		(width 0.0889)
		(layer "In11.Cu")
		(net "M_J_DQ<25>")
	)
	(segment
		(start 62.309502 -21.33092)
		(end 62.456568 -21.183854)
		(width 0.14224)
		(layer "In11.Cu")
		(net "M_J_DQ<25>")
	)
	(segment
		(start 63.802768 -30.65145)
		(end 62.309502 -29.158184)
		(width 0.14224)
		(layer "In11.Cu")
		(net "M_J_DQ<25>")
	)
	(segment
		(start 83.142582 -56.285638)
		(end 83.084162 -56.184546)
		(width 0.0889)
		(layer "In11.Cu")
		(net "M_J_DQ<25>")
	)
	(segment
		(start 82.452464 -54.896512)
		(end 82.452464 -54.145434)
		(width 0.0889)
		(layer "In11.Cu")
		(net "M_J_DQ<25>")
	)
	(segment
		(start 83.137756 -56.884824)
		(end 83.142582 -56.876188)
		(width 0.0889)
		(layer "In11.Cu")
		(net "M_J_DQ<25>")
	)
	(segment
		(start 78.966568 -49.919382)
		(end 78.966568 -48.1838)
		(width 0.14224)
		(layer "In11.Cu")
		(net "M_J_DQ<25>")
	)
	(segment
		(start 82.158332 -53.439822)
		(end 80.295496 -51.576986)
		(width 0.0889)
		(layer "In11.Cu")
		(net "M_J_DQ<25>")
	)
	(segment
		(start 62.309502 -11.7094)
		(end 62.456568 -11.562334)
		(width 0.14224)
		(layer "In11.Cu")
		(net "M_J_DQ<25>")
	)
	(segment
		(start 68.299076 -37.516308)
		(end 68.299076 -36.920424)
		(width 0.14224)
		(layer "In11.Cu")
		(net "M_J_DQ<25>")
	)
	(segment
		(start 83.48599 -66.980816)
		(end 83.148424 -66.203322)
		(width 0.0889)
		(layer "In11.Cu")
		(net "M_J_DQ<25>")
	)
	(segment
		(start 62.309502 -29.158184)
		(end 62.309502 -21.33092)
		(width 0.14224)
		(layer "In11.Cu")
		(net "M_J_DQ<25>")
	)
	(segment
		(start 83.489292 -66.982086)
		(end 83.48599 -66.980816)
		(width 0.0889)
		(layer "In11.Cu")
		(net "M_J_DQ<25>")
	)
	(segment
		(start 62.19571 -2.702814)
		(end 62.19571 0.630936)
		(width 0.14224)
		(layer "In11.Cu")
		(net "M_J_DQ<25>")
	)
	(segment
		(start 61.62675 1.4986)
		(end 61.149484 1.975866)
		(width 0.14224)
		(layer "In11.Cu")
		(net "M_J_DQ<25>")
	)
	(segment
		(start 83.142582 -61.829188)
		(end 83.148932 -61.81852)
		(width 0.0889)
		(layer "In11.Cu")
		(net "M_J_DQ<25>")
	)
	(segment
		(start 62.309502 -19.004534)
		(end 62.309502 -11.7094)
		(width 0.14224)
		(layer "In11.Cu")
		(net "M_J_DQ<25>")
	)
	(segment
		(start 61.295026 -3.867912)
		(end 61.295026 -3.603498)
		(width 0.14224)
		(layer "In11.Cu")
		(net "M_J_DQ<25>")
	)
	(segment
		(start 83.137756 -59.856624)
		(end 83.142582 -59.847988)
		(width 0.0889)
		(layer "In11.Cu")
		(net "M_J_DQ<25>")
	)
	(segment
		(start 83.148932 -58.277506)
		(end 83.142582 -58.266838)
		(width 0.0889)
		(layer "In11.Cu")
		(net "M_J_DQ<25>")
	)
	(segment
		(start 61.98235 1.4986)
		(end 61.62675 1.4986)
		(width 0.14224)
		(layer "In11.Cu")
		(net "M_J_DQ<25>")
	)
	(segment
		(start 83.137756 -58.866024)
		(end 83.142582 -58.857388)
		(width 0.0889)
		(layer "In11.Cu")
		(net "M_J_DQ<25>")
	)
	(segment
		(start 62.456568 -19.1516)
		(end 62.309502 -19.004534)
		(width 0.14224)
		(layer "In11.Cu")
		(net "M_J_DQ<25>")
	)
	(segment
		(start 62.456568 -9.6012)
		(end 62.309502 -9.454134)
		(width 0.14224)
		(layer "In11.Cu")
		(net "M_J_DQ<25>")
	)
	(segment
		(start 83.142582 -60.838588)
		(end 83.148932 -60.82792)
		(width 0.0889)
		(layer "In11.Cu")
		(net "M_J_DQ<25>")
	)
	(segment
		(start 83.142582 -56.876188)
		(end 83.148932 -56.86552)
		(width 0.0889)
		(layer "In11.Cu")
		(net "M_J_DQ<25>")
	)
	(segment
		(start 80.295496 -51.576986)
		(end 80.295496 -51.24831)
		(width 0.0889)
		(layer "In11.Cu")
		(net "M_J_DQ<25>")
	)
	(segment
		(start 68.299076 -36.920424)
		(end 63.802768 -32.424116)
		(width 0.14224)
		(layer "In11.Cu")
		(net "M_J_DQ<25>")
	)
	(segment
		(start 83.142582 -62.819788)
		(end 83.148932 -62.80912)
		(width 0.0889)
		(layer "In11.Cu")
		(net "M_J_DQ<25>")
	)
	(segment
		(start 78.966568 -48.1838)
		(end 68.299076 -37.516308)
		(width 0.14224)
		(layer "In11.Cu")
		(net "M_J_DQ<25>")
	)
	(segment
		(start 61.821568 -3.076956)
		(end 62.19571 -2.702814)
		(width 0.14224)
		(layer "In11.Cu")
		(net "M_J_DQ<25>")
	)
	(segment
		(start 62.309502 -9.454134)
		(end 62.309502 -6.583934)
		(width 0.14224)
		(layer "In11.Cu")
		(net "M_J_DQ<25>")
	)
	(segment
		(start 83.084162 -55.52821)
		(end 82.452464 -54.896512)
		(width 0.0889)
		(layer "In11.Cu")
		(net "M_J_DQ<25>")
	)
	(segment
		(start 62.309502 -6.583934)
		(end 61.674502 -5.948934)
		(width 0.14224)
		(layer "In11.Cu")
		(net "M_J_DQ<25>")
	)
	(segment
		(start 62.456568 -21.183854)
		(end 62.456568 -19.1516)
		(width 0.14224)
		(layer "In11.Cu")
		(net "M_J_DQ<25>")
	)
	(segment
		(start 61.295026 -3.603498)
		(end 61.821568 -3.076956)
		(width 0.14224)
		(layer "In11.Cu")
		(net "M_J_DQ<25>")
	)
	(segment
		(start 61.674502 -5.948934)
		(end 61.674502 -4.247388)
		(width 0.14224)
		(layer "In11.Cu")
		(net "M_J_DQ<25>")
	)
	(segment
		(start 61.674502 -4.247388)
		(end 61.295026 -3.867912)
		(width 0.14224)
		(layer "In11.Cu")
		(net "M_J_DQ<25>")
	)
	(segment
		(start 83.137756 -62.828424)
		(end 83.142582 -62.819788)
		(width 0.0889)
		(layer "In11.Cu")
		(net "M_J_DQ<25>")
	)
	(arc
		(start 83.142582 -64.210438)
		(mid 83.089083 -64.01054)
		(end 83.142582 -63.810642)
		(width 0.0889)
		(layer "In11.Cu")
		(net "M_J_DQ<25>")
	)
	(arc
		(start 83.148932 -61.81852)
		(mid 83.22173 -61.527757)
		(end 83.142582 -61.238638)
		(width 0.0889)
		(layer "In11.Cu")
		(net "M_J_DQ<25>")
	)
	(arc
		(start 83.142582 -57.867042)
		(mid 83.221713 -57.57164)
		(end 83.142582 -57.276238)
		(width 0.0889)
		(layer "In11.Cu")
		(net "M_J_DQ<25>")
	)
	(arc
		(start 83.142582 -63.219838)
		(mid 83.089112 -63.024775)
		(end 83.137756 -62.828424)
		(width 0.0889)
		(layer "In11.Cu")
		(net "M_J_DQ<25>")
	)
	(arc
		(start 83.142582 -58.857388)
		(mid 83.221804 -58.56827)
		(end 83.148932 -58.277506)
		(width 0.0889)
		(layer "In11.Cu")
		(net "M_J_DQ<25>")
	)
	(arc
		(start 83.148932 -60.82792)
		(mid 83.22173 -60.537157)
		(end 83.142582 -60.248038)
		(width 0.0889)
		(layer "In11.Cu")
		(net "M_J_DQ<25>")
	)
	(arc
		(start 83.142582 -58.266838)
		(mid 83.089083 -58.06694)
		(end 83.142582 -57.867042)
		(width 0.0889)
		(layer "In11.Cu")
		(net "M_J_DQ<25>")
	)
	(arc
		(start 83.335876 -65.62217)
		(mid 83.598117 -65.466871)
		(end 83.806792 -65.244726)
		(width 0.0889)
		(layer "In11.Cu")
		(net "M_J_DQ<25>")
	)
	(arc
		(start 83.635088 -64.628522)
		(mid 83.352505 -64.462269)
		(end 83.142582 -64.210438)
		(width 0.0889)
		(layer "In11.Cu")
		(net "M_J_DQ<25>")
	)
	(arc
		(start 83.148424 -66.203322)
		(mid 83.145671 -66.197396)
		(end 83.142582 -66.191638)
		(width 0.0889)
		(layer "In11.Cu")
		(net "M_J_DQ<25>")
	)
	(arc
		(start 83.148932 -56.86552)
		(mid 83.22173 -56.574757)
		(end 83.142582 -56.285638)
		(width 0.0889)
		(layer "In11.Cu")
		(net "M_J_DQ<25>")
	)
	(arc
		(start 83.142582 -60.248038)
		(mid 83.089112 -60.052975)
		(end 83.137756 -59.856624)
		(width 0.0889)
		(layer "In11.Cu")
		(net "M_J_DQ<25>")
	)
	(arc
		(start 83.148932 -62.80912)
		(mid 83.22173 -62.518357)
		(end 83.142582 -62.229238)
		(width 0.0889)
		(layer "In11.Cu")
		(net "M_J_DQ<25>")
	)
	(arc
		(start 83.142582 -62.229238)
		(mid 83.089112 -62.034175)
		(end 83.137756 -61.837824)
		(width 0.0889)
		(layer "In11.Cu")
		(net "M_J_DQ<25>")
	)
	(arc
		(start 83.142582 -61.238638)
		(mid 83.089112 -61.043575)
		(end 83.137756 -60.847224)
		(width 0.0889)
		(layer "In11.Cu")
		(net "M_J_DQ<25>")
	)
	(arc
		(start 83.148932 -59.83732)
		(mid 83.22173 -59.546557)
		(end 83.142582 -59.257438)
		(width 0.0889)
		(layer "In11.Cu")
		(net "M_J_DQ<25>")
	)
	(arc
		(start 83.142582 -63.810642)
		(mid 83.221645 -63.51524)
		(end 83.142582 -63.219838)
		(width 0.0889)
		(layer "In11.Cu")
		(net "M_J_DQ<25>")
	)
	(arc
		(start 83.142582 -59.257438)
		(mid 83.089112 -59.062375)
		(end 83.137756 -58.866024)
		(width 0.0889)
		(layer "In11.Cu")
		(net "M_J_DQ<25>")
	)
	(arc
		(start 83.142582 -66.191638)
		(mid 83.110311 -65.863131)
		(end 83.335876 -65.62217)
		(width 0.0889)
		(layer "In11.Cu")
		(net "M_J_DQ<25>")
	)
	(arc
		(start 83.806792 -65.244726)
		(mid 83.874787 -64.893742)
		(end 83.635088 -64.628522)
		(width 0.0889)
		(layer "In11.Cu")
		(net "M_J_DQ<25>")
	)
	(arc
		(start 83.142582 -57.276238)
		(mid 83.089112 -57.081175)
		(end 83.137756 -56.884824)
		(width 0.0889)
		(layer "In11.Cu")
		(net "M_J_DQ<25>")
	)
	(segment
		(start 61.999368 -0.821182)
		(end 61.821568 1.0414)
		(width 0.1651)
		(layer "F.Cu")
		(net "M_J_DQ<24>")
	)
	(segment
		(start 84.060792 -65.000886)
		(end 83.489292 -65.000886)
		(width 0.0889)
		(layer "F.Cu")
		(net "M_J_DQ<24>")
	)
	(via
		(at 83.489292 -65.000886)
		(size 0.508)
		(drill 0.254)
		(layers "F.Cu" "B.Cu")
		(net "M_J_DQ<24>")
	)
	(via
		(at 61.821568 1.0414)
		(size 0.508)
		(drill 0.254)
		(layers "F.Cu" "B.Cu")
		(net "M_J_DQ<24>")
	)
	(via
		(at 61.149484 -4.357878)
		(size 0.508)
		(drill 0.254)
		(layers "F.Cu" "B.Cu")
		(net "M_J_DQ<24>")
	)
	(segment
		(start 61.149484 -5.621782)
		(end 61.149484 -4.357878)
		(width 0.1651)
		(layer "B.Cu")
		(net "M_J_DQ<24>")
	)
	(segment
		(start 82.977482 -60.743338)
		(end 82.971132 -60.754006)
		(width 0.0889)
		(layer "In11.Cu")
		(net "M_J_DQ<24>")
	)
	(segment
		(start 61.60135 -2.090928)
		(end 61.60135 -2.5908)
		(width 0.14224)
		(layer "In11.Cu")
		(net "M_J_DQ<24>")
	)
	(segment
		(start 61.623702 -6.837934)
		(end 61.623702 -7.224776)
		(width 0.14224)
		(layer "In11.Cu")
		(net "M_J_DQ<24>")
	)
	(segment
		(start 61.529468 -1.0795)
		(end 61.211968 -1.397)
		(width 0.14224)
		(layer "In11.Cu")
		(net "M_J_DQ<24>")
	)
	(segment
		(start 61.331602 -23.106888)
		(end 61.674502 -23.449788)
		(width 0.14224)
		(layer "In11.Cu")
		(net "M_J_DQ<24>")
	)
	(segment
		(start 61.611764 -29.35859)
		(end 62.141608 -29.888434)
		(width 0.14224)
		(layer "In11.Cu")
		(net "M_J_DQ<24>")
	)
	(segment
		(start 63.00343 -30.750256)
		(end 63.317374 -31.0642)
		(width 0.14224)
		(layer "In11.Cu")
		(net "M_J_DQ<24>")
	)
	(segment
		(start 67.687444 -37.144452)
		(end 67.687444 -37.80282)
		(width 0.14224)
		(layer "In11.Cu")
		(net "M_J_DQ<24>")
	)
	(segment
		(start 62.69609 -31.973266)
		(end 62.69609 -32.153098)
		(width 0.14224)
		(layer "In11.Cu")
		(net "M_J_DQ<24>")
	)
	(segment
		(start 62.69609 -32.153098)
		(end 67.687444 -37.144452)
		(width 0.14224)
		(layer "In11.Cu")
		(net "M_J_DQ<24>")
	)
	(segment
		(start 82.261964 -54.975506)
		(end 82.893662 -55.607204)
		(width 0.0889)
		(layer "In11.Cu")
		(net "M_J_DQ<24>")
	)
	(segment
		(start 61.338968 -17.116552)
		(end 61.338968 -18.291048)
		(width 0.14224)
		(layer "In11.Cu")
		(net "M_J_DQ<24>")
	)
	(segment
		(start 62.716664 -30.750256)
		(end 63.00343 -30.750256)
		(width 0.14224)
		(layer "In11.Cu")
		(net "M_J_DQ<24>")
	)
	(segment
		(start 82.982308 -62.715902)
		(end 82.977482 -62.724538)
		(width 0.0889)
		(layer "In11.Cu")
		(net "M_J_DQ<24>")
	)
	(segment
		(start 61.331602 -22.025356)
		(end 61.331602 -23.106888)
		(width 0.14224)
		(layer "In11.Cu")
		(net "M_J_DQ<24>")
	)
	(segment
		(start 63.317374 -31.0642)
		(end 63.317374 -31.351982)
		(width 0.14224)
		(layer "In11.Cu")
		(net "M_J_DQ<24>")
	)
	(segment
		(start 82.977482 -64.305942)
		(end 82.981546 -64.313054)
		(width 0.0889)
		(layer "In11.Cu")
		(net "M_J_DQ<24>")
	)
	(segment
		(start 62.141608 -29.888434)
		(end 62.141608 -30.175708)
		(width 0.14224)
		(layer "In11.Cu")
		(net "M_J_DQ<24>")
	)
	(segment
		(start 82.977482 -61.733938)
		(end 82.971132 -61.744606)
		(width 0.0889)
		(layer "In11.Cu")
		(net "M_J_DQ<24>")
	)
	(segment
		(start 61.652658 -30.84449)
		(end 62.047628 -31.23946)
		(width 0.14224)
		(layer "In11.Cu")
		(net "M_J_DQ<24>")
	)
	(segment
		(start 61.674502 -21.682456)
		(end 61.331602 -22.025356)
		(width 0.14224)
		(layer "In11.Cu")
		(net "M_J_DQ<24>")
	)
	(segment
		(start 80.113378 -51.6636)
		(end 81.967832 -53.518054)
		(width 0.0889)
		(layer "In11.Cu")
		(net "M_J_DQ<24>")
	)
	(segment
		(start 60.86475 -4.073144)
		(end 61.149484 -4.357878)
		(width 0.14224)
		(layer "In11.Cu")
		(net "M_J_DQ<24>")
	)
	(segment
		(start 81.967832 -53.93055)
		(end 82.261964 -54.224682)
		(width 0.0889)
		(layer "In11.Cu")
		(net "M_J_DQ<24>")
	)
	(segment
		(start 82.977482 -59.752738)
		(end 82.971132 -59.763406)
		(width 0.0889)
		(layer "In11.Cu")
		(net "M_J_DQ<24>")
	)
	(segment
		(start 61.338968 -18.291048)
		(end 61.674502 -18.626582)
		(width 0.14224)
		(layer "In11.Cu")
		(net "M_J_DQ<24>")
	)
	(segment
		(start 61.211968 -1.397)
		(end 61.211968 -1.701546)
		(width 0.14224)
		(layer "In11.Cu")
		(net "M_J_DQ<24>")
	)
	(segment
		(start 79.727806 -51.6636)
		(end 80.113378 -51.6636)
		(width 0.0889)
		(layer "In11.Cu")
		(net "M_J_DQ<24>")
	)
	(segment
		(start 67.687444 -37.80282)
		(end 78.229968 -48.345344)
		(width 0.14224)
		(layer "In11.Cu")
		(net "M_J_DQ<24>")
	)
	(segment
		(start 82.893662 -56.235346)
		(end 82.977482 -56.380888)
		(width 0.0889)
		(layer "In11.Cu")
		(net "M_J_DQ<24>")
	)
	(segment
		(start 78.229968 -48.345344)
		(end 78.229968 -50.165762)
		(width 0.14224)
		(layer "In11.Cu")
		(net "M_J_DQ<24>")
	)
	(segment
		(start 82.971132 -58.35142)
		(end 82.977482 -58.362088)
		(width 0.0889)
		(layer "In11.Cu")
		(net "M_J_DQ<24>")
	)
	(segment
		(start 61.332364 -28.034996)
		(end 61.611764 -28.314396)
		(width 0.14224)
		(layer "In11.Cu")
		(net "M_J_DQ<24>")
	)
	(segment
		(start 61.542168 -19.0754)
		(end 61.542168 -21.229066)
		(width 0.14224)
		(layer "In11.Cu")
		(net "M_J_DQ<24>")
	)
	(segment
		(start 82.982308 -56.772302)
		(end 82.977482 -56.780938)
		(width 0.0889)
		(layer "In11.Cu")
		(net "M_J_DQ<24>")
	)
	(segment
		(start 61.674502 -18.943066)
		(end 61.542168 -19.0754)
		(width 0.14224)
		(layer "In11.Cu")
		(net "M_J_DQ<24>")
	)
	(segment
		(start 82.982308 -57.762902)
		(end 82.977482 -57.771538)
		(width 0.0889)
		(layer "In11.Cu")
		(net "M_J_DQ<24>")
	)
	(segment
		(start 61.529468 -0.8509)
		(end 61.529468 -1.0795)
		(width 0.14224)
		(layer "In11.Cu")
		(net "M_J_DQ<24>")
	)
	(segment
		(start 61.149484 -4.357878)
		(end 61.149484 -6.363716)
		(width 0.14224)
		(layer "In11.Cu")
		(net "M_J_DQ<24>")
	)
	(segment
		(start 61.674502 -18.626582)
		(end 61.674502 -18.943066)
		(width 0.14224)
		(layer "In11.Cu")
		(net "M_J_DQ<24>")
	)
	(segment
		(start 61.618368 -8.9916)
		(end 61.618368 -9.4488)
		(width 0.14224)
		(layer "In11.Cu")
		(net "M_J_DQ<24>")
	)
	(segment
		(start 61.60135 0.821182)
		(end 61.60135 0.236728)
		(width 0.14224)
		(layer "In11.Cu")
		(net "M_J_DQ<24>")
	)
	(segment
		(start 61.364368 -8.7376)
		(end 61.618368 -8.9916)
		(width 0.14224)
		(layer "In11.Cu")
		(net "M_J_DQ<24>")
	)
	(segment
		(start 62.22746 -31.23946)
		(end 62.716664 -30.750256)
		(width 0.14224)
		(layer "In11.Cu")
		(net "M_J_DQ<24>")
	)
	(segment
		(start 61.542168 -21.229066)
		(end 61.674502 -21.3614)
		(width 0.14224)
		(layer "In11.Cu")
		(net "M_J_DQ<24>")
	)
	(segment
		(start 61.149484 -6.363716)
		(end 61.623702 -6.837934)
		(width 0.14224)
		(layer "In11.Cu")
		(net "M_J_DQ<24>")
	)
	(segment
		(start 61.611764 -28.314396)
		(end 61.611764 -29.35859)
		(width 0.14224)
		(layer "In11.Cu")
		(net "M_J_DQ<24>")
	)
	(segment
		(start 61.618368 -9.4488)
		(end 61.516768 -9.5504)
		(width 0.14224)
		(layer "In11.Cu")
		(net "M_J_DQ<24>")
	)
	(segment
		(start 60.86475 -3.3274)
		(end 60.86475 -4.073144)
		(width 0.14224)
		(layer "In11.Cu")
		(net "M_J_DQ<24>")
	)
	(segment
		(start 82.977482 -62.724538)
		(end 82.971132 -62.735206)
		(width 0.0889)
		(layer "In11.Cu")
		(net "M_J_DQ<24>")
	)
	(segment
		(start 81.967832 -53.518054)
		(end 81.967832 -53.93055)
		(width 0.0889)
		(layer "In11.Cu")
		(net "M_J_DQ<24>")
	)
	(segment
		(start 61.674502 -26.626058)
		(end 61.332364 -26.968196)
		(width 0.14224)
		(layer "In11.Cu")
		(net "M_J_DQ<24>")
	)
	(segment
		(start 78.229968 -50.165762)
		(end 79.727806 -51.6636)
		(width 0.14224)
		(layer "In11.Cu")
		(net "M_J_DQ<24>")
	)
	(segment
		(start 61.60135 0.236728)
		(end 61.186568 -0.178054)
		(width 0.14224)
		(layer "In11.Cu")
		(net "M_J_DQ<24>")
	)
	(segment
		(start 63.317374 -31.351982)
		(end 62.69609 -31.973266)
		(width 0.14224)
		(layer "In11.Cu")
		(net "M_J_DQ<24>")
	)
	(segment
		(start 83.447128 -64.956182)
		(end 83.489292 -65.000886)
		(width 0.0889)
		(layer "In11.Cu")
		(net "M_J_DQ<24>")
	)
	(segment
		(start 61.60135 -2.5908)
		(end 60.86475 -3.3274)
		(width 0.14224)
		(layer "In11.Cu")
		(net "M_J_DQ<24>")
	)
	(segment
		(start 61.643768 -16.811752)
		(end 61.338968 -17.116552)
		(width 0.14224)
		(layer "In11.Cu")
		(net "M_J_DQ<24>")
	)
	(segment
		(start 61.623702 -7.224776)
		(end 61.364368 -7.48411)
		(width 0.14224)
		(layer "In11.Cu")
		(net "M_J_DQ<24>")
	)
	(segment
		(start 82.893662 -55.607204)
		(end 82.893662 -56.235346)
		(width 0.0889)
		(layer "In11.Cu")
		(net "M_J_DQ<24>")
	)
	(segment
		(start 61.186568 -0.178054)
		(end 61.186568 -0.508)
		(width 0.14224)
		(layer "In11.Cu")
		(net "M_J_DQ<24>")
	)
	(segment
		(start 61.332364 -26.968196)
		(end 61.332364 -28.034996)
		(width 0.14224)
		(layer "In11.Cu")
		(net "M_J_DQ<24>")
	)
	(segment
		(start 61.674502 -21.3614)
		(end 61.674502 -21.682456)
		(width 0.14224)
		(layer "In11.Cu")
		(net "M_J_DQ<24>")
	)
	(segment
		(start 62.141608 -30.175708)
		(end 61.652658 -30.664658)
		(width 0.14224)
		(layer "In11.Cu")
		(net "M_J_DQ<24>")
	)
	(segment
		(start 61.652658 -30.664658)
		(end 61.652658 -30.84449)
		(width 0.14224)
		(layer "In11.Cu")
		(net "M_J_DQ<24>")
	)
	(segment
		(start 61.186568 -0.508)
		(end 61.529468 -0.8509)
		(width 0.14224)
		(layer "In11.Cu")
		(net "M_J_DQ<24>")
	)
	(segment
		(start 62.047628 -31.23946)
		(end 62.22746 -31.23946)
		(width 0.14224)
		(layer "In11.Cu")
		(net "M_J_DQ<24>")
	)
	(segment
		(start 82.982308 -61.725302)
		(end 82.977482 -61.733938)
		(width 0.0889)
		(layer "In11.Cu")
		(net "M_J_DQ<24>")
	)
	(segment
		(start 82.982308 -60.734702)
		(end 82.977482 -60.743338)
		(width 0.0889)
		(layer "In11.Cu")
		(net "M_J_DQ<24>")
	)
	(segment
		(start 82.261964 -54.224682)
		(end 82.261964 -54.975506)
		(width 0.0889)
		(layer "In11.Cu")
		(net "M_J_DQ<24>")
	)
	(segment
		(start 82.982308 -59.744102)
		(end 82.977482 -59.752738)
		(width 0.0889)
		(layer "In11.Cu")
		(net "M_J_DQ<24>")
	)
	(segment
		(start 61.211968 -1.701546)
		(end 61.60135 -2.090928)
		(width 0.14224)
		(layer "In11.Cu")
		(net "M_J_DQ<24>")
	)
	(segment
		(start 61.516768 -9.5504)
		(end 61.516768 -11.6586)
		(width 0.14224)
		(layer "In11.Cu")
		(net "M_J_DQ<24>")
	)
	(segment
		(start 61.364368 -7.48411)
		(end 61.364368 -8.7376)
		(width 0.14224)
		(layer "In11.Cu")
		(net "M_J_DQ<24>")
	)
	(segment
		(start 61.821568 1.0414)
		(end 61.60135 0.821182)
		(width 0.14224)
		(layer "In11.Cu")
		(net "M_J_DQ<24>")
	)
	(segment
		(start 61.618368 -11.7602)
		(end 61.618368 -12.13739)
		(width 0.14224)
		(layer "In11.Cu")
		(net "M_J_DQ<24>")
	)
	(segment
		(start 82.977482 -56.780938)
		(end 82.971132 -56.791606)
		(width 0.0889)
		(layer "In11.Cu")
		(net "M_J_DQ<24>")
	)
	(segment
		(start 61.618368 -12.13739)
		(end 61.331602 -12.424156)
		(width 0.14224)
		(layer "In11.Cu")
		(net "M_J_DQ<24>")
	)
	(segment
		(start 61.643768 -13.817854)
		(end 61.643768 -16.811752)
		(width 0.14224)
		(layer "In11.Cu")
		(net "M_J_DQ<24>")
	)
	(segment
		(start 61.674502 -23.449788)
		(end 61.674502 -26.626058)
		(width 0.14224)
		(layer "In11.Cu")
		(net "M_J_DQ<24>")
	)
	(segment
		(start 61.331602 -12.424156)
		(end 61.331602 -13.505688)
		(width 0.14224)
		(layer "In11.Cu")
		(net "M_J_DQ<24>")
	)
	(segment
		(start 61.331602 -13.505688)
		(end 61.643768 -13.817854)
		(width 0.14224)
		(layer "In11.Cu")
		(net "M_J_DQ<24>")
	)
	(segment
		(start 61.516768 -11.6586)
		(end 61.618368 -11.7602)
		(width 0.14224)
		(layer "In11.Cu")
		(net "M_J_DQ<24>")
	)
	(arc
		(start 82.977482 -58.362088)
		(mid 83.030981 -58.561986)
		(end 82.977482 -58.761884)
		(width 0.0889)
		(layer "In11.Cu")
		(net "M_J_DQ<24>")
	)
	(arc
		(start 82.971132 -56.791606)
		(mid 82.898334 -57.082369)
		(end 82.977482 -57.371488)
		(width 0.0889)
		(layer "In11.Cu")
		(net "M_J_DQ<24>")
	)
	(arc
		(start 82.977482 -59.352688)
		(mid 83.030952 -59.547751)
		(end 82.982308 -59.744102)
		(width 0.0889)
		(layer "In11.Cu")
		(net "M_J_DQ<24>")
	)
	(arc
		(start 82.977482 -63.315088)
		(mid 83.031142 -63.51513)
		(end 82.977482 -63.715138)
		(width 0.0889)
		(layer "In11.Cu")
		(net "M_J_DQ<24>")
	)
	(arc
		(start 82.971132 -62.735206)
		(mid 82.898334 -63.025969)
		(end 82.977482 -63.315088)
		(width 0.0889)
		(layer "In11.Cu")
		(net "M_J_DQ<24>")
	)
	(arc
		(start 82.971132 -59.763406)
		(mid 82.898334 -60.054169)
		(end 82.977482 -60.343288)
		(width 0.0889)
		(layer "In11.Cu")
		(net "M_J_DQ<24>")
	)
	(arc
		(start 82.971132 -60.754006)
		(mid 82.898334 -61.044769)
		(end 82.977482 -61.333888)
		(width 0.0889)
		(layer "In11.Cu")
		(net "M_J_DQ<24>")
	)
	(arc
		(start 82.977482 -60.343288)
		(mid 83.030952 -60.538351)
		(end 82.982308 -60.734702)
		(width 0.0889)
		(layer "In11.Cu")
		(net "M_J_DQ<24>")
	)
	(arc
		(start 82.977482 -63.715138)
		(mid 82.898351 -64.01054)
		(end 82.977482 -64.305942)
		(width 0.0889)
		(layer "In11.Cu")
		(net "M_J_DQ<24>")
	)
	(arc
		(start 82.977482 -58.761884)
		(mid 82.898351 -59.057286)
		(end 82.977482 -59.352688)
		(width 0.0889)
		(layer "In11.Cu")
		(net "M_J_DQ<24>")
	)
	(arc
		(start 82.977482 -61.333888)
		(mid 83.030952 -61.528951)
		(end 82.982308 -61.725302)
		(width 0.0889)
		(layer "In11.Cu")
		(net "M_J_DQ<24>")
	)
	(arc
		(start 82.977482 -62.324488)
		(mid 83.030952 -62.519551)
		(end 82.982308 -62.715902)
		(width 0.0889)
		(layer "In11.Cu")
		(net "M_J_DQ<24>")
	)
	(arc
		(start 82.977482 -57.371488)
		(mid 83.030952 -57.566551)
		(end 82.982308 -57.762902)
		(width 0.0889)
		(layer "In11.Cu")
		(net "M_J_DQ<24>")
	)
	(arc
		(start 82.977482 -57.771538)
		(mid 82.89826 -58.060656)
		(end 82.971132 -58.35142)
		(width 0.0889)
		(layer "In11.Cu")
		(net "M_J_DQ<24>")
	)
	(arc
		(start 82.971132 -61.744606)
		(mid 82.898334 -62.035369)
		(end 82.977482 -62.324488)
		(width 0.0889)
		(layer "In11.Cu")
		(net "M_J_DQ<24>")
	)
	(arc
		(start 82.981546 -64.313054)
		(mid 83.197767 -64.646613)
		(end 83.447128 -64.956182)
		(width 0.0889)
		(layer "In11.Cu")
		(net "M_J_DQ<24>")
	)
	(arc
		(start 82.977482 -56.380888)
		(mid 83.030952 -56.575951)
		(end 82.982308 -56.772302)
		(width 0.0889)
		(layer "In11.Cu")
		(net "M_J_DQ<24>")
	)
	(segment
		(start 56.049418 3.778758)
		(end 56.049418 2.514854)
		(width 0.1651)
		(layer "F.Cu")
		(net "M_J_DQ<23>")
	)
	(segment
		(start 82.343752 -58.06694)
		(end 81.772252 -58.06694)
		(width 0.0889)
		(layer "F.Cu")
		(net "M_J_DQ<23>")
	)
	(via
		(at 56.049418 2.514854)
		(size 0.508)
		(drill 0.254)
		(layers "F.Cu" "B.Cu")
		(net "M_J_DQ<23>")
	)
	(via
		(at 56.899302 -3.076956)
		(size 0.508)
		(drill 0.254)
		(layers "F.Cu" "B.Cu")
		(net "M_J_DQ<23>")
	)
	(via
		(at 81.772252 -58.06694)
		(size 0.508)
		(drill 0.254)
		(layers "F.Cu" "B.Cu")
		(net "M_J_DQ<23>")
	)
	(segment
		(start 56.899302 -1.022096)
		(end 56.899302 -3.076956)
		(width 0.1651)
		(layer "B.Cu")
		(net "M_J_DQ<23>")
	)
	(segment
		(start 56.899556 -1.021842)
		(end 56.899302 -1.022096)
		(width 0.1651)
		(layer "B.Cu")
		(net "M_J_DQ<23>")
	)
	(segment
		(start 60.804552 -35.990784)
		(end 56.820308 -32.00654)
		(width 0.14224)
		(layer "In11.Cu")
		(net "M_J_DQ<23>")
	)
	(segment
		(start 63.016638 -38.501066)
		(end 62.758066 -38.242494)
		(width 0.14224)
		(layer "In11.Cu")
		(net "M_J_DQ<23>")
	)
	(segment
		(start 57.274968 -12.193016)
		(end 57.274968 -11.7348)
		(width 0.14224)
		(layer "In11.Cu")
		(net "M_J_DQ<23>")
	)
	(segment
		(start 56.899302 -3.076956)
		(end 57.252108 -2.72415)
		(width 0.14224)
		(layer "In11.Cu")
		(net "M_J_DQ<23>")
	)
	(segment
		(start 56.820308 -27.785568)
		(end 56.975248 -27.630628)
		(width 0.14224)
		(layer "In11.Cu")
		(net "M_J_DQ<23>")
	)
	(segment
		(start 73.208896 -52.523136)
		(end 73.169272 -52.523136)
		(width 0.0889)
		(layer "In11.Cu")
		(net "M_J_DQ<23>")
	)
	(segment
		(start 63.016638 -38.680898)
		(end 63.016638 -38.501066)
		(width 0.14224)
		(layer "In11.Cu")
		(net "M_J_DQ<23>")
	)
	(segment
		(start 57.455308 -21.974556)
		(end 57.252108 -21.771356)
		(width 0.14224)
		(layer "In11.Cu")
		(net "M_J_DQ<23>")
	)
	(segment
		(start 81.772252 -58.06694)
		(end 81.442306 -57.305194)
		(width 0.0889)
		(layer "In11.Cu")
		(net "M_J_DQ<23>")
	)
	(segment
		(start 56.366156 1.8796)
		(end 56.366156 2.198116)
		(width 0.14224)
		(layer "In11.Cu")
		(net "M_J_DQ<23>")
	)
	(segment
		(start 57.351168 -11.6586)
		(end 57.351168 -9.5504)
		(width 0.14224)
		(layer "In11.Cu")
		(net "M_J_DQ<23>")
	)
	(segment
		(start 60.804552 -36.95573)
		(end 60.804552 -35.990784)
		(width 0.14224)
		(layer "In11.Cu")
		(net "M_J_DQ<23>")
	)
	(segment
		(start 56.820308 -26.855928)
		(end 56.820308 -26.546048)
		(width 0.14224)
		(layer "In11.Cu")
		(net "M_J_DQ<23>")
	)
	(segment
		(start 57.274968 -4.903216)
		(end 56.439308 -4.067556)
		(width 0.14224)
		(layer "In11.Cu")
		(net "M_J_DQ<23>")
	)
	(segment
		(start 62.882526 -38.81501)
		(end 63.016638 -38.680898)
		(width 0.14224)
		(layer "In11.Cu")
		(net "M_J_DQ<23>")
	)
	(segment
		(start 57.277508 -13.694156)
		(end 57.455308 -13.516356)
		(width 0.14224)
		(layer "In11.Cu")
		(net "M_J_DQ<23>")
	)
	(segment
		(start 57.252108 -21.771356)
		(end 57.252108 -21.3106)
		(width 0.14224)
		(layer "In11.Cu")
		(net "M_J_DQ<23>")
	)
	(segment
		(start 74.05878 -53.018436)
		(end 74.03465 -53.018436)
		(width 0.0889)
		(layer "In11.Cu")
		(net "M_J_DQ<23>")
	)
	(segment
		(start 74.922126 -53.513736)
		(end 74.88936 -53.513736)
		(width 0.0889)
		(layer "In11.Cu")
		(net "M_J_DQ<23>")
	)
	(segment
		(start 56.439308 -4.067556)
		(end 56.439308 -3.53695)
		(width 0.14224)
		(layer "In11.Cu")
		(net "M_J_DQ<23>")
	)
	(segment
		(start 62.882526 -39.033704)
		(end 62.882526 -38.81501)
		(width 0.14224)
		(layer "In11.Cu")
		(net "M_J_DQ<23>")
	)
	(segment
		(start 57.24652 -27.010868)
		(end 56.975248 -27.010868)
		(width 0.14224)
		(layer "In11.Cu")
		(net "M_J_DQ<23>")
	)
	(segment
		(start 62.225174 -38.376352)
		(end 60.804552 -36.95573)
		(width 0.14224)
		(layer "In11.Cu")
		(net "M_J_DQ<23>")
	)
	(segment
		(start 81.442306 -57.305194)
		(end 81.425542 -57.276238)
		(width 0.0889)
		(layer "In11.Cu")
		(net "M_J_DQ<23>")
	)
	(segment
		(start 79.218282 -55.99049)
		(end 79.185516 -55.99049)
		(width 0.0889)
		(layer "In11.Cu")
		(net "M_J_DQ<23>")
	)
	(segment
		(start 57.351168 -9.5504)
		(end 57.274968 -9.4742)
		(width 0.14224)
		(layer "In11.Cu")
		(net "M_J_DQ<23>")
	)
	(segment
		(start 62.758066 -38.242494)
		(end 62.578234 -38.242494)
		(width 0.14224)
		(layer "In11.Cu")
		(net "M_J_DQ<23>")
	)
	(segment
		(start 57.274968 -7.287006)
		(end 57.274968 -4.903216)
		(width 0.14224)
		(layer "In11.Cu")
		(net "M_J_DQ<23>")
	)
	(segment
		(start 57.274968 -23.297896)
		(end 57.455308 -23.117556)
		(width 0.14224)
		(layer "In11.Cu")
		(net "M_J_DQ<23>")
	)
	(segment
		(start 56.975248 -27.010868)
		(end 56.820308 -26.855928)
		(width 0.14224)
		(layer "In11.Cu")
		(net "M_J_DQ<23>")
	)
	(segment
		(start 77.995018 -55.300626)
		(end 77.991716 -55.294784)
		(width 0.0889)
		(layer "In11.Cu")
		(net "M_J_DQ<23>")
	)
	(segment
		(start 57.455308 -12.373356)
		(end 57.274968 -12.193016)
		(width 0.14224)
		(layer "In11.Cu")
		(net "M_J_DQ<23>")
	)
	(segment
		(start 57.274968 -9.4742)
		(end 57.274968 -8.966454)
		(width 0.14224)
		(layer "In11.Cu")
		(net "M_J_DQ<23>")
	)
	(segment
		(start 78.355952 -55.494936)
		(end 78.338172 -55.494936)
		(width 0.0889)
		(layer "In11.Cu")
		(net "M_J_DQ<23>")
	)
	(segment
		(start 56.439308 -3.53695)
		(end 56.899302 -3.076956)
		(width 0.14224)
		(layer "In11.Cu")
		(net "M_J_DQ<23>")
	)
	(segment
		(start 80.072992 -56.485536)
		(end 80.040226 -56.485536)
		(width 0.0889)
		(layer "In11.Cu")
		(net "M_J_DQ<23>")
	)
	(segment
		(start 72.83577 -50.941224)
		(end 72.840596 -50.932588)
		(width 0.0889)
		(layer "In11.Cu")
		(net "M_J_DQ<23>")
	)
	(segment
		(start 56.950356 1.5494)
		(end 56.696356 1.5494)
		(width 0.14224)
		(layer "In11.Cu")
		(net "M_J_DQ<23>")
	)
	(segment
		(start 57.274968 -24.657558)
		(end 57.274968 -23.297896)
		(width 0.14224)
		(layer "In11.Cu")
		(net "M_J_DQ<23>")
	)
	(segment
		(start 57.277508 -16.890746)
		(end 57.277508 -13.694156)
		(width 0.14224)
		(layer "In11.Cu")
		(net "M_J_DQ<23>")
	)
	(segment
		(start 56.696356 1.5494)
		(end 56.366156 1.8796)
		(width 0.14224)
		(layer "In11.Cu")
		(net "M_J_DQ<23>")
	)
	(segment
		(start 57.274968 -11.7348)
		(end 57.351168 -11.6586)
		(width 0.14224)
		(layer "In11.Cu")
		(net "M_J_DQ<23>")
	)
	(segment
		(start 57.40146 -27.165808)
		(end 57.24652 -27.010868)
		(width 0.14224)
		(layer "In11.Cu")
		(net "M_J_DQ<23>")
	)
	(segment
		(start 56.975248 -26.391108)
		(end 57.24652 -26.391108)
		(width 0.14224)
		(layer "In11.Cu")
		(net "M_J_DQ<23>")
	)
	(segment
		(start 72.380348 -48.399954)
		(end 72.380348 -48.116998)
		(width 0.0889)
		(layer "In11.Cu")
		(net "M_J_DQ<23>")
	)
	(segment
		(start 56.820308 -32.00654)
		(end 56.820308 -27.785568)
		(width 0.14224)
		(layer "In11.Cu")
		(net "M_J_DQ<23>")
	)
	(segment
		(start 56.820308 -25.112218)
		(end 57.274968 -24.657558)
		(width 0.14224)
		(layer "In11.Cu")
		(net "M_J_DQ<23>")
	)
	(segment
		(start 57.40146 -27.475688)
		(end 57.40146 -27.165808)
		(width 0.14224)
		(layer "In11.Cu")
		(net "M_J_DQ<23>")
	)
	(segment
		(start 72.91959 -50.63744)
		(end 72.91959 -48.939196)
		(width 0.0889)
		(layer "In11.Cu")
		(net "M_J_DQ<23>")
	)
	(segment
		(start 57.252108 0.581152)
		(end 57.407556 0.7366)
		(width 0.14224)
		(layer "In11.Cu")
		(net "M_J_DQ<23>")
	)
	(segment
		(start 57.252108 -2.72415)
		(end 57.252108 0.581152)
		(width 0.14224)
		(layer "In11.Cu")
		(net "M_J_DQ<23>")
	)
	(segment
		(start 57.480708 -18.336514)
		(end 57.480708 -17.093946)
		(width 0.14224)
		(layer "In11.Cu")
		(net "M_J_DQ<23>")
	)
	(segment
		(start 71.40575 -47.1424)
		(end 70.991222 -47.1424)
		(width 0.14224)
		(layer "In11.Cu")
		(net "M_J_DQ<23>")
	)
	(segment
		(start 57.274968 -8.966454)
		(end 57.376568 -8.864854)
		(width 0.14224)
		(layer "In11.Cu")
		(net "M_J_DQ<23>")
	)
	(segment
		(start 57.40146 -25.926288)
		(end 57.24652 -25.771348)
		(width 0.14224)
		(layer "In11.Cu")
		(net "M_J_DQ<23>")
	)
	(segment
		(start 57.252108 -18.565114)
		(end 57.480708 -18.336514)
		(width 0.14224)
		(layer "In11.Cu")
		(net "M_J_DQ<23>")
	)
	(segment
		(start 57.252108 -19.00174)
		(end 57.252108 -18.565114)
		(width 0.14224)
		(layer "In11.Cu")
		(net "M_J_DQ<23>")
	)
	(segment
		(start 57.401968 -21.16074)
		(end 57.401968 -19.1516)
		(width 0.14224)
		(layer "In11.Cu")
		(net "M_J_DQ<23>")
	)
	(segment
		(start 77.504798 -54.99989)
		(end 77.46873 -54.99989)
		(width 0.0889)
		(layer "In11.Cu")
		(net "M_J_DQ<23>")
	)
	(segment
		(start 57.407556 1.0922)
		(end 56.950356 1.5494)
		(width 0.14224)
		(layer "In11.Cu")
		(net "M_J_DQ<23>")
	)
	(segment
		(start 56.975248 -25.771348)
		(end 56.820308 -25.616408)
		(width 0.14224)
		(layer "In11.Cu")
		(net "M_J_DQ<23>")
	)
	(segment
		(start 57.24652 -27.630628)
		(end 57.40146 -27.475688)
		(width 0.14224)
		(layer "In11.Cu")
		(net "M_J_DQ<23>")
	)
	(segment
		(start 56.820308 -26.546048)
		(end 56.975248 -26.391108)
		(width 0.14224)
		(layer "In11.Cu")
		(net "M_J_DQ<23>")
	)
	(segment
		(start 80.935322 -56.98109)
		(end 80.902556 -56.98109)
		(width 0.0889)
		(layer "In11.Cu")
		(net "M_J_DQ<23>")
	)
	(segment
		(start 75.784456 -54.00929)
		(end 75.75169 -54.00929)
		(width 0.0889)
		(layer "In11.Cu")
		(net "M_J_DQ<23>")
	)
	(segment
		(start 57.480708 -17.093946)
		(end 57.277508 -16.890746)
		(width 0.14224)
		(layer "In11.Cu")
		(net "M_J_DQ<23>")
	)
	(segment
		(start 72.91959 -48.939196)
		(end 72.380348 -48.399954)
		(width 0.0889)
		(layer "In11.Cu")
		(net "M_J_DQ<23>")
	)
	(segment
		(start 56.820308 -25.616408)
		(end 56.820308 -25.112218)
		(width 0.14224)
		(layer "In11.Cu")
		(net "M_J_DQ<23>")
	)
	(segment
		(start 57.407556 0.7366)
		(end 57.407556 1.0922)
		(width 0.14224)
		(layer "In11.Cu")
		(net "M_J_DQ<23>")
	)
	(segment
		(start 56.366156 2.198116)
		(end 56.049418 2.514854)
		(width 0.14224)
		(layer "In11.Cu")
		(net "M_J_DQ<23>")
	)
	(segment
		(start 57.24652 -25.771348)
		(end 56.975248 -25.771348)
		(width 0.14224)
		(layer "In11.Cu")
		(net "M_J_DQ<23>")
	)
	(segment
		(start 57.40146 -26.236168)
		(end 57.40146 -25.926288)
		(width 0.14224)
		(layer "In11.Cu")
		(net "M_J_DQ<23>")
	)
	(segment
		(start 62.444376 -38.376352)
		(end 62.225174 -38.376352)
		(width 0.14224)
		(layer "In11.Cu")
		(net "M_J_DQ<23>")
	)
	(segment
		(start 57.376568 -8.864854)
		(end 57.376568 -7.388606)
		(width 0.14224)
		(layer "In11.Cu")
		(net "M_J_DQ<23>")
	)
	(segment
		(start 72.380348 -48.116998)
		(end 71.40575 -47.1424)
		(width 0.14224)
		(layer "In11.Cu")
		(net "M_J_DQ<23>")
	)
	(segment
		(start 57.455308 -13.516356)
		(end 57.455308 -12.373356)
		(width 0.14224)
		(layer "In11.Cu")
		(net "M_J_DQ<23>")
	)
	(segment
		(start 57.401968 -19.1516)
		(end 57.252108 -19.00174)
		(width 0.14224)
		(layer "In11.Cu")
		(net "M_J_DQ<23>")
	)
	(segment
		(start 56.975248 -27.630628)
		(end 57.24652 -27.630628)
		(width 0.14224)
		(layer "In11.Cu")
		(net "M_J_DQ<23>")
	)
	(segment
		(start 76.639166 -54.504336)
		(end 76.6064 -54.504336)
		(width 0.0889)
		(layer "In11.Cu")
		(net "M_J_DQ<23>")
	)
	(segment
		(start 57.252108 -21.3106)
		(end 57.401968 -21.16074)
		(width 0.14224)
		(layer "In11.Cu")
		(net "M_J_DQ<23>")
	)
	(segment
		(start 57.24652 -26.391108)
		(end 57.40146 -26.236168)
		(width 0.14224)
		(layer "In11.Cu")
		(net "M_J_DQ<23>")
	)
	(segment
		(start 57.376568 -7.388606)
		(end 57.274968 -7.287006)
		(width 0.14224)
		(layer "In11.Cu")
		(net "M_J_DQ<23>")
	)
	(segment
		(start 70.991222 -47.1424)
		(end 62.882526 -39.033704)
		(width 0.14224)
		(layer "In11.Cu")
		(net "M_J_DQ<23>")
	)
	(segment
		(start 57.455308 -23.117556)
		(end 57.455308 -21.974556)
		(width 0.14224)
		(layer "In11.Cu")
		(net "M_J_DQ<23>")
	)
	(segment
		(start 62.578234 -38.242494)
		(end 62.444376 -38.376352)
		(width 0.14224)
		(layer "In11.Cu")
		(net "M_J_DQ<23>")
	)
	(arc
		(start 72.840596 -51.923442)
		(mid 72.919727 -51.62804)
		(end 72.840596 -51.332638)
		(width 0.0889)
		(layer "In11.Cu")
		(net "M_J_DQ<23>")
	)
	(arc
		(start 75.416156 -53.809138)
		(mid 75.207548 -53.597206)
		(end 74.922126 -53.513736)
		(width 0.0889)
		(layer "In11.Cu")
		(net "M_J_DQ<23>")
	)
	(arc
		(start 75.75169 -54.00929)
		(mid 75.55784 -53.95294)
		(end 75.416156 -53.809138)
		(width 0.0889)
		(layer "In11.Cu")
		(net "M_J_DQ<23>")
	)
	(arc
		(start 73.699116 -52.818284)
		(mid 73.492112 -52.60742)
		(end 73.208896 -52.523136)
		(width 0.0889)
		(layer "In11.Cu")
		(net "M_J_DQ<23>")
	)
	(arc
		(start 78.849982 -55.790338)
		(mid 78.641374 -55.578406)
		(end 78.355952 -55.494936)
		(width 0.0889)
		(layer "In11.Cu")
		(net "M_J_DQ<23>")
	)
	(arc
		(start 80.902556 -56.98109)
		(mid 80.708706 -56.92474)
		(end 80.567022 -56.780938)
		(width 0.0889)
		(layer "In11.Cu")
		(net "M_J_DQ<23>")
	)
	(arc
		(start 80.040226 -56.485536)
		(mid 79.848584 -56.42837)
		(end 79.708502 -56.285638)
		(width 0.0889)
		(layer "In11.Cu")
		(net "M_J_DQ<23>")
	)
	(arc
		(start 79.185516 -55.99049)
		(mid 78.991666 -55.93414)
		(end 78.849982 -55.790338)
		(width 0.0889)
		(layer "In11.Cu")
		(net "M_J_DQ<23>")
	)
	(arc
		(start 76.274676 -54.304438)
		(mid 76.067672 -54.093574)
		(end 75.784456 -54.00929)
		(width 0.0889)
		(layer "In11.Cu")
		(net "M_J_DQ<23>")
	)
	(arc
		(start 72.840596 -50.932588)
		(mid 72.899508 -50.790209)
		(end 72.91959 -50.63744)
		(width 0.0889)
		(layer "In11.Cu")
		(net "M_J_DQ<23>")
	)
	(arc
		(start 77.46873 -54.99989)
		(mid 77.27488 -54.94354)
		(end 77.133196 -54.799738)
		(width 0.0889)
		(layer "In11.Cu")
		(net "M_J_DQ<23>")
	)
	(arc
		(start 74.03465 -53.018436)
		(mid 73.8408 -52.962086)
		(end 73.699116 -52.818284)
		(width 0.0889)
		(layer "In11.Cu")
		(net "M_J_DQ<23>")
	)
	(arc
		(start 77.133196 -54.799738)
		(mid 76.924588 -54.587806)
		(end 76.639166 -54.504336)
		(width 0.0889)
		(layer "In11.Cu")
		(net "M_J_DQ<23>")
	)
	(arc
		(start 73.169272 -52.523136)
		(mid 72.836356 -52.315684)
		(end 72.840596 -51.923442)
		(width 0.0889)
		(layer "In11.Cu")
		(net "M_J_DQ<23>")
	)
	(arc
		(start 81.425542 -57.276238)
		(mid 81.218538 -57.065374)
		(end 80.935322 -56.98109)
		(width 0.0889)
		(layer "In11.Cu")
		(net "M_J_DQ<23>")
	)
	(arc
		(start 77.991716 -55.294784)
		(mid 77.786095 -55.084861)
		(end 77.504798 -54.99989)
		(width 0.0889)
		(layer "In11.Cu")
		(net "M_J_DQ<23>")
	)
	(arc
		(start 80.567022 -56.780938)
		(mid 80.358414 -56.569006)
		(end 80.072992 -56.485536)
		(width 0.0889)
		(layer "In11.Cu")
		(net "M_J_DQ<23>")
	)
	(arc
		(start 72.840596 -51.332638)
		(mid 72.787126 -51.137575)
		(end 72.83577 -50.941224)
		(width 0.0889)
		(layer "In11.Cu")
		(net "M_J_DQ<23>")
	)
	(arc
		(start 79.708502 -56.285638)
		(mid 79.501498 -56.074774)
		(end 79.218282 -55.99049)
		(width 0.0889)
		(layer "In11.Cu")
		(net "M_J_DQ<23>")
	)
	(arc
		(start 74.557636 -53.313838)
		(mid 74.346923 -53.100759)
		(end 74.05878 -53.018436)
		(width 0.0889)
		(layer "In11.Cu")
		(net "M_J_DQ<23>")
	)
	(arc
		(start 76.6064 -54.504336)
		(mid 76.414758 -54.44717)
		(end 76.274676 -54.304438)
		(width 0.0889)
		(layer "In11.Cu")
		(net "M_J_DQ<23>")
	)
	(arc
		(start 74.88936 -53.513736)
		(mid 74.697718 -53.45657)
		(end 74.557636 -53.313838)
		(width 0.0889)
		(layer "In11.Cu")
		(net "M_J_DQ<23>")
	)
	(arc
		(start 78.338172 -55.494936)
		(mid 78.141011 -55.442977)
		(end 77.995018 -55.300626)
		(width 0.0889)
		(layer "In11.Cu")
		(net "M_J_DQ<23>")
	)
	(segment
		(start 57.031636 0.28448)
		(end 57.031636 0.50292)
		(width 0.1651)
		(layer "F.Cu")
		(net "M_J_DQ<22>")
	)
	(segment
		(start 80.626712 -57.076086)
		(end 80.055212 -57.076086)
		(width 0.0889)
		(layer "F.Cu")
		(net "M_J_DQ<22>")
	)
	(segment
		(start 56.899556 0.939546)
		(end 56.899302 0.9398)
		(width 0.1651)
		(layer "F.Cu")
		(net "M_J_DQ<22>")
	)
	(segment
		(start 56.899556 0.1524)
		(end 57.031636 0.28448)
		(width 0.1651)
		(layer "F.Cu")
		(net "M_J_DQ<22>")
	)
	(segment
		(start 56.899556 -0.821182)
		(end 56.899556 0.1524)
		(width 0.1651)
		(layer "F.Cu")
		(net "M_J_DQ<22>")
	)
	(segment
		(start 56.899556 0.635)
		(end 56.899556 0.939546)
		(width 0.1651)
		(layer "F.Cu")
		(net "M_J_DQ<22>")
	)
	(segment
		(start 57.031636 0.50292)
		(end 56.899556 0.635)
		(width 0.1651)
		(layer "F.Cu")
		(net "M_J_DQ<22>")
	)
	(via
		(at 56.049418 -4.357878)
		(size 0.508)
		(drill 0.254)
		(layers "F.Cu" "B.Cu")
		(net "M_J_DQ<22>")
	)
	(via
		(at 56.899302 0.9398)
		(size 0.508)
		(drill 0.254)
		(layers "F.Cu" "B.Cu")
		(net "M_J_DQ<22>")
	)
	(via
		(at 80.055212 -57.076086)
		(size 0.508)
		(drill 0.254)
		(layers "F.Cu" "B.Cu")
		(net "M_J_DQ<22>")
	)
	(segment
		(start 56.049418 -5.621782)
		(end 56.049418 -4.357878)
		(width 0.1651)
		(layer "B.Cu")
		(net "M_J_DQ<22>")
	)
	(segment
		(start 76.632562 -54.694836)
		(end 76.599796 -54.694836)
		(width 0.0889)
		(layer "In11.Cu")
		(net "M_J_DQ<22>")
	)
	(segment
		(start 79.560166 -56.410352)
		(end 79.543402 -56.380888)
		(width 0.0889)
		(layer "In11.Cu")
		(net "M_J_DQ<22>")
	)
	(segment
		(start 69.58711 -47.45482)
		(end 69.929502 -47.112428)
		(width 0.14224)
		(layer "In11.Cu")
		(net "M_J_DQ<22>")
	)
	(segment
		(start 56.512968 -9.4742)
		(end 56.512968 -8.941054)
		(width 0.14224)
		(layer "In11.Cu")
		(net "M_J_DQ<22>")
	)
	(segment
		(start 79.211678 -56.18099)
		(end 79.178912 -56.18099)
		(width 0.0889)
		(layer "In11.Cu")
		(net "M_J_DQ<22>")
	)
	(segment
		(start 57.220866 -33.965896)
		(end 57.526682 -33.66008)
		(width 0.14224)
		(layer "In11.Cu")
		(net "M_J_DQ<22>")
	)
	(segment
		(start 56.524906 0.287528)
		(end 56.524906 0.565404)
		(width 0.14224)
		(layer "In11.Cu")
		(net "M_J_DQ<22>")
	)
	(segment
		(start 74.915522 -53.704236)
		(end 74.882756 -53.704236)
		(width 0.0889)
		(layer "In11.Cu")
		(net "M_J_DQ<22>")
	)
	(segment
		(start 57.526682 -33.441132)
		(end 57.307226 -33.221676)
		(width 0.14224)
		(layer "In11.Cu")
		(net "M_J_DQ<22>")
	)
	(segment
		(start 56.185308 -33.149286)
		(end 56.185308 -24.852884)
		(width 0.14224)
		(layer "In11.Cu")
		(net "M_J_DQ<22>")
	)
	(segment
		(start 69.710046 -46.674024)
		(end 69.491098 -46.674024)
		(width 0.14224)
		(layer "In11.Cu")
		(net "M_J_DQ<22>")
	)
	(segment
		(start 69.929502 -47.112428)
		(end 69.929502 -46.89348)
		(width 0.14224)
		(layer "In11.Cu")
		(net "M_J_DQ<22>")
	)
	(segment
		(start 69.806566 -47.893224)
		(end 69.58711 -47.673768)
		(width 0.14224)
		(layer "In11.Cu")
		(net "M_J_DQ<22>")
	)
	(segment
		(start 58.40349 -34.536888)
		(end 58.40349 -34.31794)
		(width 0.14224)
		(layer "In11.Cu")
		(net "M_J_DQ<22>")
	)
	(segment
		(start 56.541924 -0.768096)
		(end 56.160924 -0.387096)
		(width 0.14224)
		(layer "In11.Cu")
		(net "M_J_DQ<22>")
	)
	(segment
		(start 56.413908 -7.391146)
		(end 56.512968 -7.292086)
		(width 0.14224)
		(layer "In11.Cu")
		(net "M_J_DQ<22>")
	)
	(segment
		(start 75.777852 -54.19979)
		(end 75.745086 -54.19979)
		(width 0.0889)
		(layer "In11.Cu")
		(net "M_J_DQ<22>")
	)
	(segment
		(start 69.148706 -47.016416)
		(end 68.929758 -47.016416)
		(width 0.14224)
		(layer "In11.Cu")
		(net "M_J_DQ<22>")
	)
	(segment
		(start 69.052694 -46.016672)
		(end 58.974482 -35.93846)
		(width 0.14224)
		(layer "In11.Cu")
		(net "M_J_DQ<22>")
	)
	(segment
		(start 56.185308 -24.852884)
		(end 56.512968 -24.525224)
		(width 0.14224)
		(layer "In11.Cu")
		(net "M_J_DQ<22>")
	)
	(segment
		(start 56.512968 -12.274296)
		(end 56.512968 -11.684)
		(width 0.14224)
		(layer "In11.Cu")
		(net "M_J_DQ<22>")
	)
	(segment
		(start 56.512968 -11.684)
		(end 56.411368 -11.5824)
		(width 0.14224)
		(layer "In11.Cu")
		(net "M_J_DQ<22>")
	)
	(segment
		(start 70.367906 -47.550832)
		(end 70.025514 -47.893224)
		(width 0.14224)
		(layer "In11.Cu")
		(net "M_J_DQ<22>")
	)
	(segment
		(start 56.512968 -23.267416)
		(end 56.413908 -23.168356)
		(width 0.14224)
		(layer "In11.Cu")
		(net "M_J_DQ<22>")
	)
	(segment
		(start 69.491098 -46.674024)
		(end 69.148706 -47.016416)
		(width 0.14224)
		(layer "In11.Cu")
		(net "M_J_DQ<22>")
	)
	(segment
		(start 78.349348 -55.685436)
		(end 78.31328 -55.685436)
		(width 0.0889)
		(layer "In11.Cu")
		(net "M_J_DQ<22>")
	)
	(segment
		(start 57.440322 -34.4043)
		(end 57.220866 -34.184844)
		(width 0.14224)
		(layer "In11.Cu")
		(net "M_J_DQ<22>")
	)
	(segment
		(start 77.479906 -55.19039)
		(end 77.462126 -55.19039)
		(width 0.0889)
		(layer "In11.Cu")
		(net "M_J_DQ<22>")
	)
	(segment
		(start 56.411368 -9.5758)
		(end 56.512968 -9.4742)
		(width 0.14224)
		(layer "In11.Cu")
		(net "M_J_DQ<22>")
	)
	(segment
		(start 56.512968 -4.821428)
		(end 56.049418 -4.357878)
		(width 0.14224)
		(layer "In11.Cu")
		(net "M_J_DQ<22>")
	)
	(segment
		(start 56.413908 -8.841994)
		(end 56.413908 -7.391146)
		(width 0.14224)
		(layer "In11.Cu")
		(net "M_J_DQ<22>")
	)
	(segment
		(start 72.006206 -48.62576)
		(end 71.661782 -48.62576)
		(width 0.14224)
		(layer "In11.Cu")
		(net "M_J_DQ<22>")
	)
	(segment
		(start 56.617108 -21.771356)
		(end 56.617108 -21.3868)
		(width 0.14224)
		(layer "In11.Cu")
		(net "M_J_DQ<22>")
	)
	(segment
		(start 56.049418 -4.357878)
		(end 55.813706 -4.122166)
		(width 0.14224)
		(layer "In11.Cu")
		(net "M_J_DQ<22>")
	)
	(segment
		(start 58.974482 -35.719512)
		(end 59.280298 -35.413696)
		(width 0.14224)
		(layer "In11.Cu")
		(net "M_J_DQ<22>")
	)
	(segment
		(start 59.060842 -34.975292)
		(end 58.841894 -34.975292)
		(width 0.14224)
		(layer "In11.Cu")
		(net "M_J_DQ<22>")
	)
	(segment
		(start 56.160924 -1.492504)
		(end 56.541924 -1.111504)
		(width 0.14224)
		(layer "In11.Cu")
		(net "M_J_DQ<22>")
	)
	(segment
		(start 57.65927 -34.4043)
		(end 57.440322 -34.4043)
		(width 0.14224)
		(layer "In11.Cu")
		(net "M_J_DQ<22>")
	)
	(segment
		(start 56.617108 -21.3868)
		(end 56.436768 -21.20646)
		(width 0.14224)
		(layer "In11.Cu")
		(net "M_J_DQ<22>")
	)
	(segment
		(start 71.661782 -48.62576)
		(end 70.586854 -47.550832)
		(width 0.14224)
		(layer "In11.Cu")
		(net "M_J_DQ<22>")
	)
	(segment
		(start 56.617108 -18.646394)
		(end 56.413908 -18.443194)
		(width 0.14224)
		(layer "In11.Cu")
		(net "M_J_DQ<22>")
	)
	(segment
		(start 58.184034 -34.098484)
		(end 57.965086 -34.098484)
		(width 0.14224)
		(layer "In11.Cu")
		(net "M_J_DQ<22>")
	)
	(segment
		(start 56.160924 -0.076454)
		(end 56.524906 0.287528)
		(width 0.14224)
		(layer "In11.Cu")
		(net "M_J_DQ<22>")
	)
	(segment
		(start 72.729344 -49.054766)
		(end 72.300338 -48.62576)
		(width 0.0889)
		(layer "In11.Cu")
		(net "M_J_DQ<22>")
	)
	(segment
		(start 58.097674 -35.061652)
		(end 58.097674 -34.842704)
		(width 0.14224)
		(layer "In11.Cu")
		(net "M_J_DQ<22>")
	)
	(segment
		(start 72.729344 -50.636932)
		(end 72.729344 -49.054766)
		(width 0.0889)
		(layer "In11.Cu")
		(net "M_J_DQ<22>")
	)
	(segment
		(start 56.515508 -13.668756)
		(end 56.413908 -13.567156)
		(width 0.14224)
		(layer "In11.Cu")
		(net "M_J_DQ<22>")
	)
	(segment
		(start 73.20534 -52.71389)
		(end 73.169526 -52.71389)
		(width 0.0889)
		(layer "In11.Cu")
		(net "M_J_DQ<22>")
	)
	(segment
		(start 56.413908 -16.992346)
		(end 56.515508 -16.890746)
		(width 0.14224)
		(layer "In11.Cu")
		(net "M_J_DQ<22>")
	)
	(segment
		(start 56.436768 -21.20646)
		(end 56.436768 -19.177)
		(width 0.14224)
		(layer "In11.Cu")
		(net "M_J_DQ<22>")
	)
	(segment
		(start 57.307226 -33.221676)
		(end 57.088278 -33.221676)
		(width 0.14224)
		(layer "In11.Cu")
		(net "M_J_DQ<22>")
	)
	(segment
		(start 57.526682 -33.66008)
		(end 57.526682 -33.441132)
		(width 0.14224)
		(layer "In11.Cu")
		(net "M_J_DQ<22>")
	)
	(segment
		(start 55.813706 -3.327654)
		(end 56.586374 -2.554986)
		(width 0.14224)
		(layer "In11.Cu")
		(net "M_J_DQ<22>")
	)
	(segment
		(start 69.052694 -46.23562)
		(end 69.052694 -46.016672)
		(width 0.14224)
		(layer "In11.Cu")
		(net "M_J_DQ<22>")
	)
	(segment
		(start 56.782462 -33.527492)
		(end 56.563514 -33.527492)
		(width 0.14224)
		(layer "In11.Cu")
		(net "M_J_DQ<22>")
	)
	(segment
		(start 69.58711 -47.673768)
		(end 69.58711 -47.45482)
		(width 0.14224)
		(layer "In11.Cu")
		(net "M_J_DQ<22>")
	)
	(segment
		(start 70.025514 -47.893224)
		(end 69.806566 -47.893224)
		(width 0.14224)
		(layer "In11.Cu")
		(net "M_J_DQ<22>")
	)
	(segment
		(start 72.300338 -48.62576)
		(end 72.006206 -48.62576)
		(width 0.0889)
		(layer "In11.Cu")
		(net "M_J_DQ<22>")
	)
	(segment
		(start 72.675496 -51.827938)
		(end 72.680322 -51.819302)
		(width 0.0889)
		(layer "In11.Cu")
		(net "M_J_DQ<22>")
	)
	(segment
		(start 57.220866 -34.184844)
		(end 57.220866 -33.965896)
		(width 0.14224)
		(layer "In11.Cu")
		(net "M_J_DQ<22>")
	)
	(segment
		(start 56.160924 -1.777746)
		(end 56.160924 -1.492504)
		(width 0.14224)
		(layer "In11.Cu")
		(net "M_J_DQ<22>")
	)
	(segment
		(start 72.669146 -50.848006)
		(end 72.675496 -50.837338)
		(width 0.0889)
		(layer "In11.Cu")
		(net "M_J_DQ<22>")
	)
	(segment
		(start 59.280298 -35.194748)
		(end 59.060842 -34.975292)
		(width 0.14224)
		(layer "In11.Cu")
		(net "M_J_DQ<22>")
	)
	(segment
		(start 58.536078 -35.281108)
		(end 58.31713 -35.281108)
		(width 0.14224)
		(layer "In11.Cu")
		(net "M_J_DQ<22>")
	)
	(segment
		(start 56.563514 -33.527492)
		(end 56.185308 -33.149286)
		(width 0.14224)
		(layer "In11.Cu")
		(net "M_J_DQ<22>")
	)
	(segment
		(start 56.524906 0.565404)
		(end 56.899302 0.9398)
		(width 0.14224)
		(layer "In11.Cu")
		(net "M_J_DQ<22>")
	)
	(segment
		(start 56.512968 -8.941054)
		(end 56.413908 -8.841994)
		(width 0.14224)
		(layer "In11.Cu")
		(net "M_J_DQ<22>")
	)
	(segment
		(start 58.841894 -34.975292)
		(end 58.536078 -35.281108)
		(width 0.14224)
		(layer "In11.Cu")
		(net "M_J_DQ<22>")
	)
	(segment
		(start 68.710302 -46.79696)
		(end 68.710302 -46.578012)
		(width 0.14224)
		(layer "In11.Cu")
		(net "M_J_DQ<22>")
	)
	(segment
		(start 58.31713 -35.281108)
		(end 58.097674 -35.061652)
		(width 0.14224)
		(layer "In11.Cu")
		(net "M_J_DQ<22>")
	)
	(segment
		(start 58.097674 -34.842704)
		(end 58.40349 -34.536888)
		(width 0.14224)
		(layer "In11.Cu")
		(net "M_J_DQ<22>")
	)
	(segment
		(start 56.617108 -18.99666)
		(end 56.617108 -18.646394)
		(width 0.14224)
		(layer "In11.Cu")
		(net "M_J_DQ<22>")
	)
	(segment
		(start 77.826362 -55.390542)
		(end 77.82306 -55.3847)
		(width 0.0889)
		(layer "In11.Cu")
		(net "M_J_DQ<22>")
	)
	(segment
		(start 74.060812 -53.20919)
		(end 74.032872 -53.20919)
		(width 0.0889)
		(layer "In11.Cu")
		(net "M_J_DQ<22>")
	)
	(segment
		(start 56.413908 -21.974556)
		(end 56.617108 -21.771356)
		(width 0.14224)
		(layer "In11.Cu")
		(net "M_J_DQ<22>")
	)
	(segment
		(start 56.413908 -12.373356)
		(end 56.512968 -12.274296)
		(width 0.14224)
		(layer "In11.Cu")
		(net "M_J_DQ<22>")
	)
	(segment
		(start 56.586374 -2.203196)
		(end 56.160924 -1.777746)
		(width 0.14224)
		(layer "In11.Cu")
		(net "M_J_DQ<22>")
	)
	(segment
		(start 56.411368 -11.5824)
		(end 56.411368 -9.5758)
		(width 0.14224)
		(layer "In11.Cu")
		(net "M_J_DQ<22>")
	)
	(segment
		(start 56.586374 -2.554986)
		(end 56.586374 -2.203196)
		(width 0.14224)
		(layer "In11.Cu")
		(net "M_J_DQ<22>")
	)
	(segment
		(start 56.413908 -23.168356)
		(end 56.413908 -21.974556)
		(width 0.14224)
		(layer "In11.Cu")
		(net "M_J_DQ<22>")
	)
	(segment
		(start 56.436768 -19.177)
		(end 56.617108 -18.99666)
		(width 0.14224)
		(layer "In11.Cu")
		(net "M_J_DQ<22>")
	)
	(segment
		(start 56.541924 -1.111504)
		(end 56.541924 -0.768096)
		(width 0.14224)
		(layer "In11.Cu")
		(net "M_J_DQ<22>")
	)
	(segment
		(start 56.413908 -18.443194)
		(end 56.413908 -16.992346)
		(width 0.14224)
		(layer "In11.Cu")
		(net "M_J_DQ<22>")
	)
	(segment
		(start 72.728836 -50.63744)
		(end 72.729344 -50.636932)
		(width 0.0889)
		(layer "In11.Cu")
		(net "M_J_DQ<22>")
	)
	(segment
		(start 55.813706 -4.122166)
		(end 55.813706 -3.327654)
		(width 0.14224)
		(layer "In11.Cu")
		(net "M_J_DQ<22>")
	)
	(segment
		(start 58.40349 -34.31794)
		(end 58.184034 -34.098484)
		(width 0.14224)
		(layer "In11.Cu")
		(net "M_J_DQ<22>")
	)
	(segment
		(start 56.515508 -16.890746)
		(end 56.515508 -13.668756)
		(width 0.14224)
		(layer "In11.Cu")
		(net "M_J_DQ<22>")
	)
	(segment
		(start 68.929758 -47.016416)
		(end 68.710302 -46.79696)
		(width 0.14224)
		(layer "In11.Cu")
		(net "M_J_DQ<22>")
	)
	(segment
		(start 69.929502 -46.89348)
		(end 69.710046 -46.674024)
		(width 0.14224)
		(layer "In11.Cu")
		(net "M_J_DQ<22>")
	)
	(segment
		(start 59.280298 -35.413696)
		(end 59.280298 -35.194748)
		(width 0.14224)
		(layer "In11.Cu")
		(net "M_J_DQ<22>")
	)
	(segment
		(start 56.413908 -13.567156)
		(end 56.413908 -12.373356)
		(width 0.14224)
		(layer "In11.Cu")
		(net "M_J_DQ<22>")
	)
	(segment
		(start 68.710302 -46.578012)
		(end 69.052694 -46.23562)
		(width 0.14224)
		(layer "In11.Cu")
		(net "M_J_DQ<22>")
	)
	(segment
		(start 58.974482 -35.93846)
		(end 58.974482 -35.719512)
		(width 0.14224)
		(layer "In11.Cu")
		(net "M_J_DQ<22>")
	)
	(segment
		(start 80.055212 -57.076086)
		(end 79.560166 -56.410352)
		(width 0.0889)
		(layer "In11.Cu")
		(net "M_J_DQ<22>")
	)
	(segment
		(start 70.586854 -47.550832)
		(end 70.367906 -47.550832)
		(width 0.14224)
		(layer "In11.Cu")
		(net "M_J_DQ<22>")
	)
	(segment
		(start 56.512968 -7.292086)
		(end 56.512968 -4.821428)
		(width 0.14224)
		(layer "In11.Cu")
		(net "M_J_DQ<22>")
	)
	(segment
		(start 57.088278 -33.221676)
		(end 56.782462 -33.527492)
		(width 0.14224)
		(layer "In11.Cu")
		(net "M_J_DQ<22>")
	)
	(segment
		(start 57.965086 -34.098484)
		(end 57.65927 -34.4043)
		(width 0.14224)
		(layer "In11.Cu")
		(net "M_J_DQ<22>")
	)
	(segment
		(start 56.160924 -0.387096)
		(end 56.160924 -0.076454)
		(width 0.14224)
		(layer "In11.Cu")
		(net "M_J_DQ<22>")
	)
	(segment
		(start 56.512968 -24.525224)
		(end 56.512968 -23.267416)
		(width 0.14224)
		(layer "In11.Cu")
		(net "M_J_DQ<22>")
	)
	(arc
		(start 74.032872 -53.20919)
		(mid 73.744727 -53.126871)
		(end 73.534016 -52.913788)
		(width 0.0889)
		(layer "In11.Cu")
		(net "M_J_DQ<22>")
	)
	(arc
		(start 76.109576 -54.399688)
		(mid 75.969497 -54.256952)
		(end 75.777852 -54.19979)
		(width 0.0889)
		(layer "In11.Cu")
		(net "M_J_DQ<22>")
	)
	(arc
		(start 77.82306 -55.3847)
		(mid 77.677094 -55.242301)
		(end 77.479906 -55.19039)
		(width 0.0889)
		(layer "In11.Cu")
		(net "M_J_DQ<22>")
	)
	(arc
		(start 77.462126 -55.19039)
		(mid 77.176702 -55.106923)
		(end 76.968096 -54.894988)
		(width 0.0889)
		(layer "In11.Cu")
		(net "M_J_DQ<22>")
	)
	(arc
		(start 75.745086 -54.19979)
		(mid 75.459662 -54.116323)
		(end 75.251056 -53.904388)
		(width 0.0889)
		(layer "In11.Cu")
		(net "M_J_DQ<22>")
	)
	(arc
		(start 79.543402 -56.380888)
		(mid 79.403323 -56.238152)
		(end 79.211678 -56.18099)
		(width 0.0889)
		(layer "In11.Cu")
		(net "M_J_DQ<22>")
	)
	(arc
		(start 75.251056 -53.904388)
		(mid 75.109373 -53.760584)
		(end 74.915522 -53.704236)
		(width 0.0889)
		(layer "In11.Cu")
		(net "M_J_DQ<22>")
	)
	(arc
		(start 72.675496 -51.427888)
		(mid 72.596274 -51.13877)
		(end 72.669146 -50.848006)
		(width 0.0889)
		(layer "In11.Cu")
		(net "M_J_DQ<22>")
	)
	(arc
		(start 72.675496 -50.837338)
		(mid 72.715327 -50.740899)
		(end 72.728836 -50.63744)
		(width 0.0889)
		(layer "In11.Cu")
		(net "M_J_DQ<22>")
	)
	(arc
		(start 79.178912 -56.18099)
		(mid 78.893488 -56.097523)
		(end 78.684882 -55.885588)
		(width 0.0889)
		(layer "In11.Cu")
		(net "M_J_DQ<22>")
	)
	(arc
		(start 72.680322 -51.819302)
		(mid 72.729077 -51.62295)
		(end 72.675496 -51.427888)
		(width 0.0889)
		(layer "In11.Cu")
		(net "M_J_DQ<22>")
	)
	(arc
		(start 73.534016 -52.913788)
		(mid 73.395272 -52.771755)
		(end 73.20534 -52.71389)
		(width 0.0889)
		(layer "In11.Cu")
		(net "M_J_DQ<22>")
	)
	(arc
		(start 73.169526 -52.71389)
		(mid 72.671275 -52.41105)
		(end 72.675496 -51.827938)
		(width 0.0889)
		(layer "In11.Cu")
		(net "M_J_DQ<22>")
	)
	(arc
		(start 76.968096 -54.894988)
		(mid 76.826413 -54.751184)
		(end 76.632562 -54.694836)
		(width 0.0889)
		(layer "In11.Cu")
		(net "M_J_DQ<22>")
	)
	(arc
		(start 74.392536 -53.409088)
		(mid 74.252457 -53.266352)
		(end 74.060812 -53.20919)
		(width 0.0889)
		(layer "In11.Cu")
		(net "M_J_DQ<22>")
	)
	(arc
		(start 78.684882 -55.885588)
		(mid 78.543199 -55.741784)
		(end 78.349348 -55.685436)
		(width 0.0889)
		(layer "In11.Cu")
		(net "M_J_DQ<22>")
	)
	(arc
		(start 76.599796 -54.694836)
		(mid 76.316579 -54.610555)
		(end 76.109576 -54.399688)
		(width 0.0889)
		(layer "In11.Cu")
		(net "M_J_DQ<22>")
	)
	(arc
		(start 78.31328 -55.685436)
		(mid 78.03198 -55.60047)
		(end 77.826362 -55.390542)
		(width 0.0889)
		(layer "In11.Cu")
		(net "M_J_DQ<22>")
	)
	(arc
		(start 74.882756 -53.704236)
		(mid 74.599539 -53.619955)
		(end 74.392536 -53.409088)
		(width 0.0889)
		(layer "In11.Cu")
		(net "M_J_DQ<22>")
	)
	(segment
		(start 80.626712 -60.047886)
		(end 80.055212 -60.047886)
		(width 0.0889)
		(layer "F.Cu")
		(net "M_J_DQ<21>")
	)
	(segment
		(start 50.099468 3.778758)
		(end 50.099468 2.514854)
		(width 0.1651)
		(layer "F.Cu")
		(net "M_J_DQ<21>")
	)
	(via
		(at 80.055212 -60.047886)
		(size 0.508)
		(drill 0.254)
		(layers "F.Cu" "B.Cu")
		(net "M_J_DQ<21>")
	)
	(via
		(at 50.099468 2.514854)
		(size 0.508)
		(drill 0.254)
		(layers "F.Cu" "B.Cu")
		(net "M_J_DQ<21>")
	)
	(via
		(at 50.873152 -3.076956)
		(size 0.508)
		(drill 0.254)
		(layers "F.Cu" "B.Cu")
		(net "M_J_DQ<21>")
	)
	(segment
		(start 50.949352 -1.021842)
		(end 50.949352 -3.000756)
		(width 0.1651)
		(layer "B.Cu")
		(net "M_J_DQ<21>")
	)
	(segment
		(start 50.949352 -3.000756)
		(end 50.873152 -3.076956)
		(width 0.1651)
		(layer "B.Cu")
		(net "M_J_DQ<21>")
	)
	(segment
		(start 62.999366 -45.371258)
		(end 52.347368 -34.71926)
		(width 0.14224)
		(layer "In11.Cu")
		(net "M_J_DQ<21>")
	)
	(segment
		(start 77.995018 -59.263026)
		(end 77.991716 -59.257184)
		(width 0.0889)
		(layer "In11.Cu")
		(net "M_J_DQ<21>")
	)
	(segment
		(start 62.999366 -46.669198)
		(end 62.999366 -45.371258)
		(width 0.14224)
		(layer "In11.Cu")
		(net "M_J_DQ<21>")
	)
	(segment
		(start 51.184556 0.53975)
		(end 51.381406 0.7366)
		(width 0.14224)
		(layer "In11.Cu")
		(net "M_J_DQ<21>")
	)
	(segment
		(start 68.916296 -53.018436)
		(end 68.88353 -53.018436)
		(width 0.0889)
		(layer "In11.Cu")
		(net "M_J_DQ<21>")
	)
	(segment
		(start 75.780646 -57.971436)
		(end 75.744832 -57.971436)
		(width 0.0889)
		(layer "In11.Cu")
		(net "M_J_DQ<21>")
	)
	(segment
		(start 72.350376 -55.99049)
		(end 72.31761 -55.99049)
		(width 0.0889)
		(layer "In11.Cu")
		(net "M_J_DQ<21>")
	)
	(segment
		(start 78.90383 -59.218068)
		(end 78.612746 -59.348624)
		(width 0.0889)
		(layer "In11.Cu")
		(net "M_J_DQ<21>")
	)
	(segment
		(start 68.312792 -52.055014)
		(end 68.312792 -51.982624)
		(width 0.14224)
		(layer "In11.Cu")
		(net "M_J_DQ<21>")
	)
	(segment
		(start 50.873152 -3.076956)
		(end 51.184556 -2.765552)
		(width 0.14224)
		(layer "In11.Cu")
		(net "M_J_DQ<21>")
	)
	(segment
		(start 68.363592 -52.385214)
		(end 68.363592 -52.105814)
		(width 0.0889)
		(layer "In11.Cu")
		(net "M_J_DQ<21>")
	)
	(segment
		(start 79.560166 -59.382152)
		(end 79.543402 -59.352688)
		(width 0.0889)
		(layer "In11.Cu")
		(net "M_J_DQ<21>")
	)
	(segment
		(start 74.067416 -56.98109)
		(end 74.03465 -56.98109)
		(width 0.0889)
		(layer "In11.Cu")
		(net "M_J_DQ<21>")
	)
	(segment
		(start 51.407568 -9.6266)
		(end 51.257708 -9.47674)
		(width 0.14224)
		(layer "In11.Cu")
		(net "M_J_DQ<21>")
	)
	(segment
		(start 79.211678 -59.15279)
		(end 79.138272 -59.15279)
		(width 0.0889)
		(layer "In11.Cu")
		(net "M_J_DQ<21>")
	)
	(segment
		(start 51.346608 -13.617956)
		(end 51.346608 -12.360656)
		(width 0.14224)
		(layer "In11.Cu")
		(net "M_J_DQ<21>")
	)
	(segment
		(start 52.347368 -34.71926)
		(end 52.347368 -28.680156)
		(width 0.14224)
		(layer "In11.Cu")
		(net "M_J_DQ<21>")
	)
	(segment
		(start 71.488046 -55.494936)
		(end 71.45528 -55.494936)
		(width 0.0889)
		(layer "In11.Cu")
		(net "M_J_DQ<21>")
	)
	(segment
		(start 68.501768 -52.736242)
		(end 68.493132 -52.721002)
		(width 0.0889)
		(layer "In11.Cu")
		(net "M_J_DQ<21>")
	)
	(segment
		(start 51.257708 -12.271756)
		(end 51.257708 -11.684)
		(width 0.14224)
		(layer "In11.Cu")
		(net "M_J_DQ<21>")
	)
	(segment
		(start 50.981102 1.5494)
		(end 50.670206 1.5494)
		(width 0.14224)
		(layer "In11.Cu")
		(net "M_J_DQ<21>")
	)
	(segment
		(start 68.493132 -52.514754)
		(end 68.363592 -52.385214)
		(width 0.0889)
		(layer "In11.Cu")
		(net "M_J_DQ<21>")
	)
	(segment
		(start 68.493132 -52.721002)
		(end 68.493132 -52.514754)
		(width 0.0889)
		(layer "In11.Cu")
		(net "M_J_DQ<21>")
	)
	(segment
		(start 51.381406 1.149096)
		(end 50.981102 1.5494)
		(width 0.14224)
		(layer "In11.Cu")
		(net "M_J_DQ<21>")
	)
	(segment
		(start 51.178968 -4.750816)
		(end 50.368708 -3.940556)
		(width 0.14224)
		(layer "In11.Cu")
		(net "M_J_DQ<21>")
	)
	(segment
		(start 50.368708 -3.5814)
		(end 50.873152 -3.076956)
		(width 0.14224)
		(layer "In11.Cu")
		(net "M_J_DQ<21>")
	)
	(segment
		(start 68.312792 -51.982624)
		(end 62.999366 -46.669198)
		(width 0.14224)
		(layer "In11.Cu")
		(net "M_J_DQ<21>")
	)
	(segment
		(start 79.138272 -59.15279)
		(end 78.90383 -59.218068)
		(width 0.0889)
		(layer "In11.Cu")
		(net "M_J_DQ<21>")
	)
	(segment
		(start 51.257708 -8.991346)
		(end 51.346608 -8.902446)
		(width 0.14224)
		(layer "In11.Cu")
		(net "M_J_DQ<21>")
	)
	(segment
		(start 76.642976 -58.466736)
		(end 76.603352 -58.466736)
		(width 0.0889)
		(layer "In11.Cu")
		(net "M_J_DQ<21>")
	)
	(segment
		(start 51.283108 -16.865346)
		(end 51.283108 -13.681456)
		(width 0.14224)
		(layer "In11.Cu")
		(net "M_J_DQ<21>")
	)
	(segment
		(start 51.34229 -27.675078)
		(end 51.34229 -23.223474)
		(width 0.14224)
		(layer "In11.Cu")
		(net "M_J_DQ<21>")
	)
	(segment
		(start 52.347368 -28.680156)
		(end 51.34229 -27.675078)
		(width 0.14224)
		(layer "In11.Cu")
		(net "M_J_DQ<21>")
	)
	(segment
		(start 51.178968 -7.160006)
		(end 51.178968 -4.750816)
		(width 0.14224)
		(layer "In11.Cu")
		(net "M_J_DQ<21>")
	)
	(segment
		(start 77.497686 -58.962036)
		(end 77.46873 -58.962036)
		(width 0.0889)
		(layer "In11.Cu")
		(net "M_J_DQ<21>")
	)
	(segment
		(start 51.257708 -19.10334)
		(end 51.257708 -18.592546)
		(width 0.14224)
		(layer "In11.Cu")
		(net "M_J_DQ<21>")
	)
	(segment
		(start 73.205086 -56.485536)
		(end 73.17232 -56.485536)
		(width 0.0889)
		(layer "In11.Cu")
		(net "M_J_DQ<21>")
	)
	(segment
		(start 51.283108 -13.681456)
		(end 51.346608 -13.617956)
		(width 0.14224)
		(layer "In11.Cu")
		(net "M_J_DQ<21>")
	)
	(segment
		(start 51.407568 -19.2532)
		(end 51.257708 -19.10334)
		(width 0.14224)
		(layer "In11.Cu")
		(net "M_J_DQ<21>")
	)
	(segment
		(start 51.346608 -8.902446)
		(end 51.346608 -7.327646)
		(width 0.14224)
		(layer "In11.Cu")
		(net "M_J_DQ<21>")
	)
	(segment
		(start 51.346608 -7.327646)
		(end 51.178968 -7.160006)
		(width 0.14224)
		(layer "In11.Cu")
		(net "M_J_DQ<21>")
	)
	(segment
		(start 51.346608 -21.961856)
		(end 51.257708 -21.872956)
		(width 0.14224)
		(layer "In11.Cu")
		(net "M_J_DQ<21>")
	)
	(segment
		(start 51.257708 -21.3106)
		(end 51.407568 -21.16074)
		(width 0.14224)
		(layer "In11.Cu")
		(net "M_J_DQ<21>")
	)
	(segment
		(start 51.407568 -21.16074)
		(end 51.407568 -19.2532)
		(width 0.14224)
		(layer "In11.Cu")
		(net "M_J_DQ<21>")
	)
	(segment
		(start 51.257708 -18.592546)
		(end 51.346608 -18.503646)
		(width 0.14224)
		(layer "In11.Cu")
		(net "M_J_DQ<21>")
	)
	(segment
		(start 68.363592 -52.105814)
		(end 68.312792 -52.055014)
		(width 0.0889)
		(layer "In11.Cu")
		(net "M_J_DQ<21>")
	)
	(segment
		(start 51.346608 -23.219156)
		(end 51.346608 -21.961856)
		(width 0.14224)
		(layer "In11.Cu")
		(net "M_J_DQ<21>")
	)
	(segment
		(start 68.547996 -52.818284)
		(end 68.501768 -52.736242)
		(width 0.0889)
		(layer "In11.Cu")
		(net "M_J_DQ<21>")
	)
	(segment
		(start 51.257708 -9.47674)
		(end 51.257708 -8.991346)
		(width 0.14224)
		(layer "In11.Cu")
		(net "M_J_DQ<21>")
	)
	(segment
		(start 70.633336 -54.99989)
		(end 70.60057 -54.99989)
		(width 0.0889)
		(layer "In11.Cu")
		(net "M_J_DQ<21>")
	)
	(segment
		(start 51.346608 -18.503646)
		(end 51.346608 -16.928846)
		(width 0.14224)
		(layer "In11.Cu")
		(net "M_J_DQ<21>")
	)
	(segment
		(start 51.346608 -16.928846)
		(end 51.283108 -16.865346)
		(width 0.14224)
		(layer "In11.Cu")
		(net "M_J_DQ<21>")
	)
	(segment
		(start 50.099468 2.120138)
		(end 50.099468 2.514854)
		(width 0.14224)
		(layer "In11.Cu")
		(net "M_J_DQ<21>")
	)
	(segment
		(start 51.257708 -11.684)
		(end 51.407568 -11.53414)
		(width 0.14224)
		(layer "In11.Cu")
		(net "M_J_DQ<21>")
	)
	(segment
		(start 51.407568 -11.53414)
		(end 51.407568 -9.6266)
		(width 0.14224)
		(layer "In11.Cu")
		(net "M_J_DQ<21>")
	)
	(segment
		(start 69.771006 -54.504336)
		(end 69.74205 -54.504336)
		(width 0.0889)
		(layer "In11.Cu")
		(net "M_J_DQ<21>")
	)
	(segment
		(start 51.184556 -2.765552)
		(end 51.184556 0.53975)
		(width 0.14224)
		(layer "In11.Cu")
		(net "M_J_DQ<21>")
	)
	(segment
		(start 51.257708 -21.872956)
		(end 51.257708 -21.3106)
		(width 0.14224)
		(layer "In11.Cu")
		(net "M_J_DQ<21>")
	)
	(segment
		(start 51.381406 0.7366)
		(end 51.381406 1.149096)
		(width 0.14224)
		(layer "In11.Cu")
		(net "M_J_DQ<21>")
	)
	(segment
		(start 51.346608 -12.360656)
		(end 51.257708 -12.271756)
		(width 0.14224)
		(layer "In11.Cu")
		(net "M_J_DQ<21>")
	)
	(segment
		(start 50.368708 -3.940556)
		(end 50.368708 -3.5814)
		(width 0.14224)
		(layer "In11.Cu")
		(net "M_J_DQ<21>")
	)
	(segment
		(start 50.670206 1.5494)
		(end 50.099468 2.120138)
		(width 0.14224)
		(layer "In11.Cu")
		(net "M_J_DQ<21>")
	)
	(segment
		(start 80.055212 -60.047886)
		(end 79.560166 -59.382152)
		(width 0.0889)
		(layer "In11.Cu")
		(net "M_J_DQ<21>")
	)
	(segment
		(start 74.9173 -57.476136)
		(end 74.88936 -57.476136)
		(width 0.0889)
		(layer "In11.Cu")
		(net "M_J_DQ<21>")
	)
	(segment
		(start 51.34229 -23.223474)
		(end 51.346608 -23.219156)
		(width 0.14224)
		(layer "In11.Cu")
		(net "M_J_DQ<21>")
	)
	(arc
		(start 71.982076 -55.790338)
		(mid 71.773468 -55.578406)
		(end 71.488046 -55.494936)
		(width 0.0889)
		(layer "In11.Cu")
		(net "M_J_DQ<21>")
	)
	(arc
		(start 75.416156 -57.771538)
		(mid 75.205443 -57.558459)
		(end 74.9173 -57.476136)
		(width 0.0889)
		(layer "In11.Cu")
		(net "M_J_DQ<21>")
	)
	(arc
		(start 76.274676 -58.266838)
		(mid 76.066068 -58.054906)
		(end 75.780646 -57.971436)
		(width 0.0889)
		(layer "In11.Cu")
		(net "M_J_DQ<21>")
	)
	(arc
		(start 68.88353 -53.018436)
		(mid 68.68968 -52.962086)
		(end 68.547996 -52.818284)
		(width 0.0889)
		(layer "In11.Cu")
		(net "M_J_DQ<21>")
	)
	(arc
		(start 74.03465 -56.98109)
		(mid 73.8408 -56.92474)
		(end 73.699116 -56.780938)
		(width 0.0889)
		(layer "In11.Cu")
		(net "M_J_DQ<21>")
	)
	(arc
		(start 77.991716 -59.257184)
		(mid 77.783046 -59.045427)
		(end 77.497686 -58.962036)
		(width 0.0889)
		(layer "In11.Cu")
		(net "M_J_DQ<21>")
	)
	(arc
		(start 69.74205 -54.504336)
		(mid 69.403935 -54.299634)
		(end 69.406516 -53.904388)
		(width 0.0889)
		(layer "In11.Cu")
		(net "M_J_DQ<21>")
	)
	(arc
		(start 70.60057 -54.99989)
		(mid 70.40672 -54.94354)
		(end 70.265036 -54.799738)
		(width 0.0889)
		(layer "In11.Cu")
		(net "M_J_DQ<21>")
	)
	(arc
		(start 72.31761 -55.99049)
		(mid 72.12376 -55.93414)
		(end 71.982076 -55.790338)
		(width 0.0889)
		(layer "In11.Cu")
		(net "M_J_DQ<21>")
	)
	(arc
		(start 73.699116 -56.780938)
		(mid 73.490508 -56.569006)
		(end 73.205086 -56.485536)
		(width 0.0889)
		(layer "In11.Cu")
		(net "M_J_DQ<21>")
	)
	(arc
		(start 71.45528 -55.494936)
		(mid 71.263638 -55.43777)
		(end 71.123556 -55.295038)
		(width 0.0889)
		(layer "In11.Cu")
		(net "M_J_DQ<21>")
	)
	(arc
		(start 74.557636 -57.276238)
		(mid 74.350632 -57.065374)
		(end 74.067416 -56.98109)
		(width 0.0889)
		(layer "In11.Cu")
		(net "M_J_DQ<21>")
	)
	(arc
		(start 73.17232 -56.485536)
		(mid 72.980678 -56.42837)
		(end 72.840596 -56.285638)
		(width 0.0889)
		(layer "In11.Cu")
		(net "M_J_DQ<21>")
	)
	(arc
		(start 71.123556 -55.295038)
		(mid 70.916552 -55.084174)
		(end 70.633336 -54.99989)
		(width 0.0889)
		(layer "In11.Cu")
		(net "M_J_DQ<21>")
	)
	(arc
		(start 74.88936 -57.476136)
		(mid 74.697718 -57.41897)
		(end 74.557636 -57.276238)
		(width 0.0889)
		(layer "In11.Cu")
		(net "M_J_DQ<21>")
	)
	(arc
		(start 75.744832 -57.971436)
		(mid 75.554903 -57.913566)
		(end 75.416156 -57.771538)
		(width 0.0889)
		(layer "In11.Cu")
		(net "M_J_DQ<21>")
	)
	(arc
		(start 69.406516 -53.904388)
		(mid 69.41177 -53.32288)
		(end 68.916296 -53.018436)
		(width 0.0889)
		(layer "In11.Cu")
		(net "M_J_DQ<21>")
	)
	(arc
		(start 77.133196 -58.761884)
		(mid 76.926192 -58.55102)
		(end 76.642976 -58.466736)
		(width 0.0889)
		(layer "In11.Cu")
		(net "M_J_DQ<21>")
	)
	(arc
		(start 78.612746 -59.348624)
		(mid 78.283437 -59.453651)
		(end 77.995018 -59.263026)
		(width 0.0889)
		(layer "In11.Cu")
		(net "M_J_DQ<21>")
	)
	(arc
		(start 79.543402 -59.352688)
		(mid 79.403323 -59.209952)
		(end 79.211678 -59.15279)
		(width 0.0889)
		(layer "In11.Cu")
		(net "M_J_DQ<21>")
	)
	(arc
		(start 72.840596 -56.285638)
		(mid 72.633592 -56.074774)
		(end 72.350376 -55.99049)
		(width 0.0889)
		(layer "In11.Cu")
		(net "M_J_DQ<21>")
	)
	(arc
		(start 76.603352 -58.466736)
		(mid 76.413423 -58.408866)
		(end 76.274676 -58.266838)
		(width 0.0889)
		(layer "In11.Cu")
		(net "M_J_DQ<21>")
	)
	(arc
		(start 70.265036 -54.799738)
		(mid 70.056428 -54.587806)
		(end 69.771006 -54.504336)
		(width 0.0889)
		(layer "In11.Cu")
		(net "M_J_DQ<21>")
	)
	(arc
		(start 77.46873 -58.962036)
		(mid 77.27488 -58.905686)
		(end 77.133196 -58.761884)
		(width 0.0889)
		(layer "In11.Cu")
		(net "M_J_DQ<21>")
	)
	(segment
		(start 50.949352 0.510032)
		(end 50.851308 1.0414)
		(width 0.1651)
		(layer "F.Cu")
		(net "M_J_DQ<20>")
	)
	(segment
		(start 50.949352 -0.821182)
		(end 50.949352 0.510032)
		(width 0.1651)
		(layer "F.Cu")
		(net "M_J_DQ<20>")
	)
	(segment
		(start 79.768192 -59.55284)
		(end 79.196692 -59.55284)
		(width 0.0889)
		(layer "F.Cu")
		(net "M_J_DQ<20>")
	)
	(via
		(at 79.196692 -59.55284)
		(size 0.508)
		(drill 0.254)
		(layers "F.Cu" "B.Cu")
		(net "M_J_DQ<20>")
	)
	(via
		(at 50.099468 -4.357878)
		(size 0.508)
		(drill 0.254)
		(layers "F.Cu" "B.Cu")
		(net "M_J_DQ<20>")
	)
	(via
		(at 50.851308 1.0414)
		(size 0.508)
		(drill 0.254)
		(layers "F.Cu" "B.Cu")
		(net "M_J_DQ<20>")
	)
	(segment
		(start 50.099468 -5.621782)
		(end 50.099468 -4.357878)
		(width 0.1651)
		(layer "B.Cu")
		(net "M_J_DQ<20>")
	)
	(segment
		(start 50.622708 -21.695156)
		(end 50.368708 -21.949156)
		(width 0.14224)
		(layer "In11.Cu")
		(net "M_J_DQ<20>")
	)
	(segment
		(start 77.466952 -59.15279)
		(end 77.479906 -59.15279)
		(width 0.0889)
		(layer "In11.Cu")
		(net "M_J_DQ<20>")
	)
	(segment
		(start 76.603606 -58.65749)
		(end 76.63942 -58.65749)
		(width 0.0889)
		(layer "In11.Cu")
		(net "M_J_DQ<20>")
	)
	(segment
		(start 50.574956 0.287528)
		(end 50.210974 -0.076454)
		(width 0.14224)
		(layer "In11.Cu")
		(net "M_J_DQ<20>")
	)
	(segment
		(start 77.82306 -59.3471)
		(end 77.826362 -59.352942)
		(width 0.0889)
		(layer "In11.Cu")
		(net "M_J_DQ<20>")
	)
	(segment
		(start 68.255896 -52.69357)
		(end 68.349368 -52.855622)
		(width 0.0889)
		(layer "In11.Cu")
		(net "M_J_DQ<20>")
	)
	(segment
		(start 50.622708 -18.567146)
		(end 50.622708 -18.99666)
		(width 0.14224)
		(layer "In11.Cu")
		(net "M_J_DQ<20>")
	)
	(segment
		(start 50.210974 -0.381)
		(end 50.591974 -0.762)
		(width 0.14224)
		(layer "In11.Cu")
		(net "M_J_DQ<20>")
	)
	(segment
		(start 50.851308 1.0414)
		(end 50.574956 0.765048)
		(width 0.14224)
		(layer "In11.Cu")
		(net "M_J_DQ<20>")
	)
	(segment
		(start 50.696368 -28.074112)
		(end 51.712368 -29.090112)
		(width 0.14224)
		(layer "In11.Cu")
		(net "M_J_DQ<20>")
	)
	(segment
		(start 69.731636 -54.694836)
		(end 69.764402 -54.694836)
		(width 0.0889)
		(layer "In11.Cu")
		(net "M_J_DQ<20>")
	)
	(segment
		(start 50.591974 -0.762)
		(end 50.591974 -1.0668)
		(width 0.14224)
		(layer "In11.Cu")
		(net "M_J_DQ<20>")
	)
	(segment
		(start 50.368708 -18.313146)
		(end 50.622708 -18.567146)
		(width 0.14224)
		(layer "In11.Cu")
		(net "M_J_DQ<20>")
	)
	(segment
		(start 50.591974 -1.0668)
		(end 50.223674 -1.4351)
		(width 0.14224)
		(layer "In11.Cu")
		(net "M_J_DQ<20>")
	)
	(segment
		(start 50.368708 -21.949156)
		(end 50.368708 -23.168356)
		(width 0.14224)
		(layer "In11.Cu")
		(net "M_J_DQ<20>")
	)
	(segment
		(start 50.597308 -16.837914)
		(end 50.368708 -17.066514)
		(width 0.14224)
		(layer "In11.Cu")
		(net "M_J_DQ<20>")
	)
	(segment
		(start 51.712368 -35.129216)
		(end 62.383924 -45.800772)
		(width 0.14224)
		(layer "In11.Cu")
		(net "M_J_DQ<20>")
	)
	(segment
		(start 68.349368 -52.855622)
		(end 68.382896 -52.913788)
		(width 0.0889)
		(layer "In11.Cu")
		(net "M_J_DQ<20>")
	)
	(segment
		(start 50.622708 -18.99666)
		(end 50.442368 -19.177)
		(width 0.14224)
		(layer "In11.Cu")
		(net "M_J_DQ<20>")
	)
	(segment
		(start 50.574956 -2.141728)
		(end 50.574956 -2.616454)
		(width 0.14224)
		(layer "In11.Cu")
		(net "M_J_DQ<20>")
	)
	(segment
		(start 50.368708 -17.066514)
		(end 50.368708 -18.313146)
		(width 0.14224)
		(layer "In11.Cu")
		(net "M_J_DQ<20>")
	)
	(segment
		(start 50.368708 -7.465314)
		(end 50.368708 -8.711946)
		(width 0.14224)
		(layer "In11.Cu")
		(net "M_J_DQ<20>")
	)
	(segment
		(start 50.622708 -12.093956)
		(end 50.368708 -12.347956)
		(width 0.14224)
		(layer "In11.Cu")
		(net "M_J_DQ<20>")
	)
	(segment
		(start 50.210974 -0.076454)
		(end 50.210974 -0.381)
		(width 0.14224)
		(layer "In11.Cu")
		(net "M_J_DQ<20>")
	)
	(segment
		(start 49.863756 -4.122166)
		(end 50.099468 -4.357878)
		(width 0.14224)
		(layer "In11.Cu")
		(net "M_J_DQ<20>")
	)
	(segment
		(start 50.622708 -8.965946)
		(end 50.622708 -9.4488)
		(width 0.14224)
		(layer "In11.Cu")
		(net "M_J_DQ<20>")
	)
	(segment
		(start 74.891392 -57.66689)
		(end 74.915522 -57.66689)
		(width 0.0889)
		(layer "In11.Cu")
		(net "M_J_DQ<20>")
	)
	(segment
		(start 50.368708 -13.567156)
		(end 50.597308 -13.795756)
		(width 0.14224)
		(layer "In11.Cu")
		(net "M_J_DQ<20>")
	)
	(segment
		(start 50.368708 -12.347956)
		(end 50.368708 -13.567156)
		(width 0.14224)
		(layer "In11.Cu")
		(net "M_J_DQ<20>")
	)
	(segment
		(start 51.712368 -29.090112)
		(end 51.712368 -35.129216)
		(width 0.14224)
		(layer "In11.Cu")
		(net "M_J_DQ<20>")
	)
	(segment
		(start 50.442368 -9.62914)
		(end 50.442368 -11.5824)
		(width 0.14224)
		(layer "In11.Cu")
		(net "M_J_DQ<20>")
	)
	(segment
		(start 50.597308 -13.795756)
		(end 50.597308 -16.837914)
		(width 0.14224)
		(layer "In11.Cu")
		(net "M_J_DQ<20>")
	)
	(segment
		(start 68.873116 -53.208936)
		(end 68.905882 -53.208936)
		(width 0.0889)
		(layer "In11.Cu")
		(net "M_J_DQ<20>")
	)
	(segment
		(start 78.31328 -59.647836)
		(end 78.359762 -59.647836)
		(width 0.0889)
		(layer "In11.Cu")
		(net "M_J_DQ<20>")
	)
	(segment
		(start 50.099468 -4.609846)
		(end 50.597308 -5.107686)
		(width 0.14224)
		(layer "In11.Cu")
		(net "M_J_DQ<20>")
	)
	(segment
		(start 50.622708 -11.76274)
		(end 50.622708 -12.093956)
		(width 0.14224)
		(layer "In11.Cu")
		(net "M_J_DQ<20>")
	)
	(segment
		(start 72.311006 -56.18099)
		(end 72.343772 -56.18099)
		(width 0.0889)
		(layer "In11.Cu")
		(net "M_J_DQ<20>")
	)
	(segment
		(start 50.368708 -23.168356)
		(end 50.696368 -23.496016)
		(width 0.14224)
		(layer "In11.Cu")
		(net "M_J_DQ<20>")
	)
	(segment
		(start 50.597308 -7.236714)
		(end 50.368708 -7.465314)
		(width 0.14224)
		(layer "In11.Cu")
		(net "M_J_DQ<20>")
	)
	(segment
		(start 62.383924 -47.044356)
		(end 67.83832 -52.498752)
		(width 0.14224)
		(layer "In11.Cu")
		(net "M_J_DQ<20>")
	)
	(segment
		(start 73.165716 -56.676036)
		(end 73.198482 -56.676036)
		(width 0.0889)
		(layer "In11.Cu")
		(net "M_J_DQ<20>")
	)
	(segment
		(start 50.442368 -21.20646)
		(end 50.622708 -21.3868)
		(width 0.14224)
		(layer "In11.Cu")
		(net "M_J_DQ<20>")
	)
	(segment
		(start 78.429358 -59.641232)
		(end 79.196692 -59.55284)
		(width 0.0889)
		(layer "In11.Cu")
		(net "M_J_DQ<20>")
	)
	(segment
		(start 71.448676 -55.685436)
		(end 71.481442 -55.685436)
		(width 0.0889)
		(layer "In11.Cu")
		(net "M_J_DQ<20>")
	)
	(segment
		(start 50.368708 -8.711946)
		(end 50.622708 -8.965946)
		(width 0.14224)
		(layer "In11.Cu")
		(net "M_J_DQ<20>")
	)
	(segment
		(start 50.442368 -19.177)
		(end 50.442368 -21.20646)
		(width 0.14224)
		(layer "In11.Cu")
		(net "M_J_DQ<20>")
	)
	(segment
		(start 50.223674 -1.790446)
		(end 50.574956 -2.141728)
		(width 0.14224)
		(layer "In11.Cu")
		(net "M_J_DQ<20>")
	)
	(segment
		(start 67.83832 -52.498752)
		(end 67.83832 -52.52974)
		(width 0.14224)
		(layer "In11.Cu")
		(net "M_J_DQ<20>")
	)
	(segment
		(start 50.099468 -4.357878)
		(end 50.099468 -4.609846)
		(width 0.14224)
		(layer "In11.Cu")
		(net "M_J_DQ<20>")
	)
	(segment
		(start 49.863756 -3.327654)
		(end 49.863756 -4.122166)
		(width 0.14224)
		(layer "In11.Cu")
		(net "M_J_DQ<20>")
	)
	(segment
		(start 50.574956 -2.616454)
		(end 49.863756 -3.327654)
		(width 0.14224)
		(layer "In11.Cu")
		(net "M_J_DQ<20>")
	)
	(segment
		(start 50.574956 0.765048)
		(end 50.574956 0.287528)
		(width 0.14224)
		(layer "In11.Cu")
		(net "M_J_DQ<20>")
	)
	(segment
		(start 75.741276 -58.16219)
		(end 75.7809 -58.16219)
		(width 0.0889)
		(layer "In11.Cu")
		(net "M_J_DQ<20>")
	)
	(segment
		(start 70.593966 -55.19039)
		(end 70.626732 -55.19039)
		(width 0.0889)
		(layer "In11.Cu")
		(net "M_J_DQ<20>")
	)
	(segment
		(start 50.622708 -9.4488)
		(end 50.442368 -9.62914)
		(width 0.14224)
		(layer "In11.Cu")
		(net "M_J_DQ<20>")
	)
	(segment
		(start 74.028046 -57.17159)
		(end 74.060812 -57.17159)
		(width 0.0889)
		(layer "In11.Cu")
		(net "M_J_DQ<20>")
	)
	(segment
		(start 50.223674 -1.4351)
		(end 50.223674 -1.790446)
		(width 0.14224)
		(layer "In11.Cu")
		(net "M_J_DQ<20>")
	)
	(segment
		(start 67.83832 -52.52974)
		(end 68.092066 -52.52974)
		(width 0.0889)
		(layer "In11.Cu")
		(net "M_J_DQ<20>")
	)
	(segment
		(start 50.696368 -23.496016)
		(end 50.696368 -28.074112)
		(width 0.14224)
		(layer "In11.Cu")
		(net "M_J_DQ<20>")
	)
	(segment
		(start 50.442368 -11.5824)
		(end 50.622708 -11.76274)
		(width 0.14224)
		(layer "In11.Cu")
		(net "M_J_DQ<20>")
	)
	(segment
		(start 62.383924 -45.800772)
		(end 62.383924 -47.044356)
		(width 0.14224)
		(layer "In11.Cu")
		(net "M_J_DQ<20>")
	)
	(segment
		(start 68.092066 -52.52974)
		(end 68.255896 -52.69357)
		(width 0.0889)
		(layer "In11.Cu")
		(net "M_J_DQ<20>")
	)
	(segment
		(start 50.597308 -5.107686)
		(end 50.597308 -7.236714)
		(width 0.14224)
		(layer "In11.Cu")
		(net "M_J_DQ<20>")
	)
	(segment
		(start 50.622708 -21.3868)
		(end 50.622708 -21.695156)
		(width 0.14224)
		(layer "In11.Cu")
		(net "M_J_DQ<20>")
	)
	(arc
		(start 76.63942 -58.65749)
		(mid 76.829349 -58.71536)
		(end 76.968096 -58.857388)
		(width 0.0889)
		(layer "In11.Cu")
		(net "M_J_DQ<20>")
	)
	(arc
		(start 76.109576 -58.362088)
		(mid 76.318184 -58.57402)
		(end 76.603606 -58.65749)
		(width 0.0889)
		(layer "In11.Cu")
		(net "M_J_DQ<20>")
	)
	(arc
		(start 78.359762 -59.647836)
		(mid 78.394658 -59.64557)
		(end 78.429358 -59.641232)
		(width 0.0889)
		(layer "In11.Cu")
		(net "M_J_DQ<20>")
	)
	(arc
		(start 72.343772 -56.18099)
		(mid 72.535414 -56.238156)
		(end 72.675496 -56.380888)
		(width 0.0889)
		(layer "In11.Cu")
		(net "M_J_DQ<20>")
	)
	(arc
		(start 74.392536 -57.371488)
		(mid 74.603249 -57.584567)
		(end 74.891392 -57.66689)
		(width 0.0889)
		(layer "In11.Cu")
		(net "M_J_DQ<20>")
	)
	(arc
		(start 76.968096 -58.857388)
		(mid 77.178809 -59.070467)
		(end 77.466952 -59.15279)
		(width 0.0889)
		(layer "In11.Cu")
		(net "M_J_DQ<20>")
	)
	(arc
		(start 70.626732 -55.19039)
		(mid 70.818374 -55.247556)
		(end 70.958456 -55.390288)
		(width 0.0889)
		(layer "In11.Cu")
		(net "M_J_DQ<20>")
	)
	(arc
		(start 73.198482 -56.676036)
		(mid 73.392332 -56.732386)
		(end 73.534016 -56.876188)
		(width 0.0889)
		(layer "In11.Cu")
		(net "M_J_DQ<20>")
	)
	(arc
		(start 74.060812 -57.17159)
		(mid 74.252454 -57.228756)
		(end 74.392536 -57.371488)
		(width 0.0889)
		(layer "In11.Cu")
		(net "M_J_DQ<20>")
	)
	(arc
		(start 68.905882 -53.208936)
		(mid 69.243997 -53.413638)
		(end 69.241416 -53.808884)
		(width 0.0889)
		(layer "In11.Cu")
		(net "M_J_DQ<20>")
	)
	(arc
		(start 75.251056 -57.867042)
		(mid 75.45806 -58.077906)
		(end 75.741276 -58.16219)
		(width 0.0889)
		(layer "In11.Cu")
		(net "M_J_DQ<20>")
	)
	(arc
		(start 73.534016 -56.876188)
		(mid 73.742624 -57.08812)
		(end 74.028046 -57.17159)
		(width 0.0889)
		(layer "In11.Cu")
		(net "M_J_DQ<20>")
	)
	(arc
		(start 75.7809 -58.16219)
		(mid 75.970829 -58.22006)
		(end 76.109576 -58.362088)
		(width 0.0889)
		(layer "In11.Cu")
		(net "M_J_DQ<20>")
	)
	(arc
		(start 68.382896 -52.913788)
		(mid 68.5899 -53.124652)
		(end 68.873116 -53.208936)
		(width 0.0889)
		(layer "In11.Cu")
		(net "M_J_DQ<20>")
	)
	(arc
		(start 74.915522 -57.66689)
		(mid 75.109372 -57.72324)
		(end 75.251056 -57.867042)
		(width 0.0889)
		(layer "In11.Cu")
		(net "M_J_DQ<20>")
	)
	(arc
		(start 70.099936 -54.894988)
		(mid 70.308544 -55.10692)
		(end 70.593966 -55.19039)
		(width 0.0889)
		(layer "In11.Cu")
		(net "M_J_DQ<20>")
	)
	(arc
		(start 71.481442 -55.685436)
		(mid 71.675292 -55.741786)
		(end 71.816976 -55.885588)
		(width 0.0889)
		(layer "In11.Cu")
		(net "M_J_DQ<20>")
	)
	(arc
		(start 72.675496 -56.380888)
		(mid 72.8825 -56.591752)
		(end 73.165716 -56.676036)
		(width 0.0889)
		(layer "In11.Cu")
		(net "M_J_DQ<20>")
	)
	(arc
		(start 69.764402 -54.694836)
		(mid 69.958252 -54.751186)
		(end 70.099936 -54.894988)
		(width 0.0889)
		(layer "In11.Cu")
		(net "M_J_DQ<20>")
	)
	(arc
		(start 77.479906 -59.15279)
		(mid 77.677067 -59.204749)
		(end 77.82306 -59.3471)
		(width 0.0889)
		(layer "In11.Cu")
		(net "M_J_DQ<20>")
	)
	(arc
		(start 69.241416 -53.808884)
		(mid 69.236162 -54.390392)
		(end 69.731636 -54.694836)
		(width 0.0889)
		(layer "In11.Cu")
		(net "M_J_DQ<20>")
	)
	(arc
		(start 77.826362 -59.352942)
		(mid 78.031983 -59.562865)
		(end 78.31328 -59.647836)
		(width 0.0889)
		(layer "In11.Cu")
		(net "M_J_DQ<20>")
	)
	(arc
		(start 71.816976 -55.885588)
		(mid 72.025584 -56.09752)
		(end 72.311006 -56.18099)
		(width 0.0889)
		(layer "In11.Cu")
		(net "M_J_DQ<20>")
	)
	(arc
		(start 70.958456 -55.390288)
		(mid 71.16546 -55.601152)
		(end 71.448676 -55.685436)
		(width 0.0889)
		(layer "In11.Cu")
		(net "M_J_DQ<20>")
	)
	(segment
		(start 33.099502 3.778758)
		(end 33.099502 2.514854)
		(width 0.1651)
		(layer "F.Cu")
		(net "M_J_DQ<1>")
	)
	(segment
		(start 78.051406 -65.49644)
		(end 77.479906 -65.49644)
		(width 0.0889)
		(layer "F.Cu")
		(net "M_J_DQ<1>")
	)
	(via
		(at 77.479906 -65.49644)
		(size 0.508)
		(drill 0.254)
		(layers "F.Cu" "B.Cu")
		(net "M_J_DQ<1>")
	)
	(via
		(at 33.771586 -3.076956)
		(size 0.508)
		(drill 0.254)
		(layers "F.Cu" "B.Cu")
		(net "M_J_DQ<1>")
	)
	(via
		(at 33.099502 2.514854)
		(size 0.508)
		(drill 0.254)
		(layers "F.Cu" "B.Cu")
		(net "M_J_DQ<1>")
	)
	(segment
		(start 33.771586 -2.573782)
		(end 33.771586 -3.076956)
		(width 0.1651)
		(layer "B.Cu")
		(net "M_J_DQ<1>")
	)
	(segment
		(start 33.949386 -2.395982)
		(end 33.771586 -2.573782)
		(width 0.1651)
		(layer "B.Cu")
		(net "M_J_DQ<1>")
	)
	(segment
		(start 33.949386 -1.021842)
		(end 33.949386 -2.395982)
		(width 0.1651)
		(layer "B.Cu")
		(net "M_J_DQ<1>")
	)
	(segment
		(start 76.98486 -66.162174)
		(end 77.479906 -65.49644)
		(width 0.0889)
		(layer "In11.Cu")
		(net "M_J_DQ<1>")
	)
	(segment
		(start 33.771586 -3.076956)
		(end 34.145728 -2.702814)
		(width 0.14224)
		(layer "In11.Cu")
		(net "M_J_DQ<1>")
	)
	(segment
		(start 75.251056 -67.182238)
		(end 75.309984 -67.080384)
		(width 0.0889)
		(layer "In11.Cu")
		(net "M_J_DQ<1>")
	)
	(segment
		(start 33.099502 1.975866)
		(end 33.099502 2.514854)
		(width 0.14224)
		(layer "In11.Cu")
		(net "M_J_DQ<1>")
	)
	(segment
		(start 69.735446 -65.400936)
		(end 69.771006 -65.400936)
		(width 0.0889)
		(layer "In11.Cu")
		(net "M_J_DQ<1>")
	)
	(segment
		(start 75.74788 -66.08699)
		(end 75.864212 -66.08699)
		(width 0.0889)
		(layer "In11.Cu")
		(net "M_J_DQ<1>")
	)
	(segment
		(start 76.6064 -66.391536)
		(end 76.636372 -66.391536)
		(width 0.0889)
		(layer "In11.Cu")
		(net "M_J_DQ<1>")
	)
	(segment
		(start 34.302192 1.128776)
		(end 33.932368 1.4986)
		(width 0.14224)
		(layer "In11.Cu")
		(net "M_J_DQ<1>")
	)
	(segment
		(start 34.25952 -19.046952)
		(end 34.414968 -19.2024)
		(width 0.14224)
		(layer "In11.Cu")
		(net "M_J_DQ<1>")
	)
	(segment
		(start 66.061844 -65.81902)
		(end 66.552572 -65.81902)
		(width 0.0889)
		(layer "In11.Cu")
		(net "M_J_DQ<1>")
	)
	(segment
		(start 34.145728 0.630936)
		(end 34.302192 0.7874)
		(width 0.14224)
		(layer "In11.Cu")
		(net "M_J_DQ<1>")
	)
	(segment
		(start 71.45528 -66.391536)
		(end 71.488046 -66.391536)
		(width 0.0889)
		(layer "In11.Cu")
		(net "M_J_DQ<1>")
	)
	(segment
		(start 60.807854 -65.81902)
		(end 66.061844 -65.81902)
		(width 0.14224)
		(layer "In11.Cu")
		(net "M_J_DQ<1>")
	)
	(segment
		(start 70.60057 -65.89649)
		(end 70.633336 -65.89649)
		(width 0.0889)
		(layer "In11.Cu")
		(net "M_J_DQ<1>")
	)
	(segment
		(start 66.552572 -65.81902)
		(end 66.630042 -65.89649)
		(width 0.0889)
		(layer "In11.Cu")
		(net "M_J_DQ<1>")
	)
	(segment
		(start 66.630042 -65.89649)
		(end 67.188842 -65.89649)
		(width 0.0889)
		(layer "In11.Cu")
		(net "M_J_DQ<1>")
	)
	(segment
		(start 34.414968 -21.180552)
		(end 34.25952 -21.336)
		(width 0.14224)
		(layer "In11.Cu")
		(net "M_J_DQ<1>")
	)
	(segment
		(start 33.245044 -3.859276)
		(end 33.62452 -4.238752)
		(width 0.14224)
		(layer "In11.Cu")
		(net "M_J_DQ<1>")
	)
	(segment
		(start 34.302192 0.7874)
		(end 34.302192 1.128776)
		(width 0.14224)
		(layer "In11.Cu")
		(net "M_J_DQ<1>")
	)
	(segment
		(start 34.414968 -19.2024)
		(end 34.414968 -21.180552)
		(width 0.14224)
		(layer "In11.Cu")
		(net "M_J_DQ<1>")
	)
	(segment
		(start 76.968096 -66.191638)
		(end 76.98486 -66.162174)
		(width 0.0889)
		(layer "In11.Cu")
		(net "M_J_DQ<1>")
	)
	(segment
		(start 75.310746 -66.667126)
		(end 75.375516 -66.385948)
		(width 0.0889)
		(layer "In11.Cu")
		(net "M_J_DQ<1>")
	)
	(segment
		(start 33.245044 -3.603498)
		(end 33.245044 -3.859276)
		(width 0.14224)
		(layer "In11.Cu")
		(net "M_J_DQ<1>")
	)
	(segment
		(start 73.17232 -67.382136)
		(end 73.205086 -67.382136)
		(width 0.0889)
		(layer "In11.Cu")
		(net "M_J_DQ<1>")
	)
	(segment
		(start 34.25952 -6.398006)
		(end 34.25952 -9.4742)
		(width 0.14224)
		(layer "In11.Cu")
		(net "M_J_DQ<1>")
	)
	(segment
		(start 34.998914 -39.7256)
		(end 35.527742 -39.7256)
		(width 0.14224)
		(layer "In11.Cu")
		(net "M_J_DQ<1>")
	)
	(segment
		(start 38.692328 -43.703494)
		(end 60.807854 -65.81902)
		(width 0.14224)
		(layer "In11.Cu")
		(net "M_J_DQ<1>")
	)
	(segment
		(start 33.576768 1.4986)
		(end 33.099502 1.975866)
		(width 0.14224)
		(layer "In11.Cu")
		(net "M_J_DQ<1>")
	)
	(segment
		(start 33.779968 -24.507952)
		(end 33.779968 -38.506654)
		(width 0.14224)
		(layer "In11.Cu")
		(net "M_J_DQ<1>")
	)
	(segment
		(start 33.771586 -3.076956)
		(end 33.245044 -3.603498)
		(width 0.14224)
		(layer "In11.Cu")
		(net "M_J_DQ<1>")
	)
	(segment
		(start 33.62452 -4.238752)
		(end 33.62452 -5.763006)
		(width 0.14224)
		(layer "In11.Cu")
		(net "M_J_DQ<1>")
	)
	(segment
		(start 35.527742 -39.7256)
		(end 37.552376 -41.750234)
		(width 0.14224)
		(layer "In11.Cu")
		(net "M_J_DQ<1>")
	)
	(segment
		(start 75.309984 -67.080384)
		(end 75.324462 -66.890392)
		(width 0.0889)
		(layer "In11.Cu")
		(net "M_J_DQ<1>")
	)
	(segment
		(start 34.403284 -11.543284)
		(end 34.25952 -11.687048)
		(width 0.14224)
		(layer "In11.Cu")
		(net "M_J_DQ<1>")
	)
	(segment
		(start 75.864212 -66.08699)
		(end 76.414122 -66.334132)
		(width 0.0889)
		(layer "In11.Cu")
		(net "M_J_DQ<1>")
	)
	(segment
		(start 72.31761 -66.88709)
		(end 72.350376 -66.88709)
		(width 0.0889)
		(layer "In11.Cu")
		(net "M_J_DQ<1>")
	)
	(segment
		(start 74.886566 -67.382136)
		(end 74.919332 -67.382136)
		(width 0.0889)
		(layer "In11.Cu")
		(net "M_J_DQ<1>")
	)
	(segment
		(start 68.018406 -65.400936)
		(end 68.053966 -65.400936)
		(width 0.0889)
		(layer "In11.Cu")
		(net "M_J_DQ<1>")
	)
	(segment
		(start 34.25952 -9.4742)
		(end 34.403284 -9.617964)
		(width 0.14224)
		(layer "In11.Cu")
		(net "M_J_DQ<1>")
	)
	(segment
		(start 34.593784 -39.320216)
		(end 34.998914 -39.7256)
		(width 0.14224)
		(layer "In11.Cu")
		(net "M_J_DQ<1>")
	)
	(segment
		(start 33.62452 -5.763006)
		(end 34.25952 -6.398006)
		(width 0.14224)
		(layer "In11.Cu")
		(net "M_J_DQ<1>")
	)
	(segment
		(start 34.403284 -9.617964)
		(end 34.403284 -11.543284)
		(width 0.14224)
		(layer "In11.Cu")
		(net "M_J_DQ<1>")
	)
	(segment
		(start 34.145728 -2.702814)
		(end 34.145728 0.630936)
		(width 0.14224)
		(layer "In11.Cu")
		(net "M_J_DQ<1>")
	)
	(segment
		(start 34.25952 -11.687048)
		(end 34.25952 -19.046952)
		(width 0.14224)
		(layer "In11.Cu")
		(net "M_J_DQ<1>")
	)
	(segment
		(start 34.25952 -24.0284)
		(end 33.779968 -24.507952)
		(width 0.14224)
		(layer "In11.Cu")
		(net "M_J_DQ<1>")
	)
	(segment
		(start 75.324462 -66.890392)
		(end 75.310746 -66.667126)
		(width 0.0889)
		(layer "In11.Cu")
		(net "M_J_DQ<1>")
	)
	(segment
		(start 37.937948 -41.750234)
		(end 38.692328 -42.504614)
		(width 0.14224)
		(layer "In11.Cu")
		(net "M_J_DQ<1>")
	)
	(segment
		(start 33.779968 -38.506654)
		(end 34.593784 -39.320216)
		(width 0.14224)
		(layer "In11.Cu")
		(net "M_J_DQ<1>")
	)
	(segment
		(start 37.552376 -41.750234)
		(end 37.937948 -41.750234)
		(width 0.14224)
		(layer "In11.Cu")
		(net "M_J_DQ<1>")
	)
	(segment
		(start 34.25952 -21.336)
		(end 34.25952 -24.0284)
		(width 0.14224)
		(layer "In11.Cu")
		(net "M_J_DQ<1>")
	)
	(segment
		(start 33.932368 1.4986)
		(end 33.576768 1.4986)
		(width 0.14224)
		(layer "In11.Cu")
		(net "M_J_DQ<1>")
	)
	(segment
		(start 38.692328 -42.504614)
		(end 38.692328 -43.703494)
		(width 0.14224)
		(layer "In11.Cu")
		(net "M_J_DQ<1>")
	)
	(arc
		(start 70.265036 -65.696338)
		(mid 70.406719 -65.840142)
		(end 70.60057 -65.89649)
		(width 0.0889)
		(layer "In11.Cu")
		(net "M_J_DQ<1>")
	)
	(arc
		(start 75.375516 -66.385948)
		(mid 75.512244 -66.174873)
		(end 75.74788 -66.08699)
		(width 0.0889)
		(layer "In11.Cu")
		(net "M_J_DQ<1>")
	)
	(arc
		(start 74.392536 -67.677538)
		(mid 74.601144 -67.465606)
		(end 74.886566 -67.382136)
		(width 0.0889)
		(layer "In11.Cu")
		(net "M_J_DQ<1>")
	)
	(arc
		(start 68.053966 -65.400936)
		(mid 68.33939 -65.484403)
		(end 68.547996 -65.696338)
		(width 0.0889)
		(layer "In11.Cu")
		(net "M_J_DQ<1>")
	)
	(arc
		(start 71.488046 -66.391536)
		(mid 71.77347 -66.475003)
		(end 71.982076 -66.686938)
		(width 0.0889)
		(layer "In11.Cu")
		(net "M_J_DQ<1>")
	)
	(arc
		(start 73.205086 -67.382136)
		(mid 73.49051 -67.465603)
		(end 73.699116 -67.677538)
		(width 0.0889)
		(layer "In11.Cu")
		(net "M_J_DQ<1>")
	)
	(arc
		(start 72.840596 -67.182238)
		(mid 72.980675 -67.324974)
		(end 73.17232 -67.382136)
		(width 0.0889)
		(layer "In11.Cu")
		(net "M_J_DQ<1>")
	)
	(arc
		(start 73.699116 -67.677538)
		(mid 74.045826 -67.877849)
		(end 74.392536 -67.677538)
		(width 0.0889)
		(layer "In11.Cu")
		(net "M_J_DQ<1>")
	)
	(arc
		(start 76.636372 -66.391536)
		(mid 76.828014 -66.33437)
		(end 76.968096 -66.191638)
		(width 0.0889)
		(layer "In11.Cu")
		(net "M_J_DQ<1>")
	)
	(arc
		(start 68.547996 -65.696338)
		(mid 68.894706 -65.896649)
		(end 69.241416 -65.696338)
		(width 0.0889)
		(layer "In11.Cu")
		(net "M_J_DQ<1>")
	)
	(arc
		(start 74.919332 -67.382136)
		(mid 75.110974 -67.32497)
		(end 75.251056 -67.182238)
		(width 0.0889)
		(layer "In11.Cu")
		(net "M_J_DQ<1>")
	)
	(arc
		(start 76.414122 -66.334132)
		(mid 76.506606 -66.375078)
		(end 76.6064 -66.391536)
		(width 0.0889)
		(layer "In11.Cu")
		(net "M_J_DQ<1>")
	)
	(arc
		(start 70.633336 -65.89649)
		(mid 70.916553 -65.980771)
		(end 71.123556 -66.191638)
		(width 0.0889)
		(layer "In11.Cu")
		(net "M_J_DQ<1>")
	)
	(arc
		(start 67.188842 -65.89649)
		(mid 67.382692 -65.84014)
		(end 67.524376 -65.696338)
		(width 0.0889)
		(layer "In11.Cu")
		(net "M_J_DQ<1>")
	)
	(arc
		(start 69.241416 -65.696338)
		(mid 69.450024 -65.484406)
		(end 69.735446 -65.400936)
		(width 0.0889)
		(layer "In11.Cu")
		(net "M_J_DQ<1>")
	)
	(arc
		(start 71.982076 -66.686938)
		(mid 72.123759 -66.830742)
		(end 72.31761 -66.88709)
		(width 0.0889)
		(layer "In11.Cu")
		(net "M_J_DQ<1>")
	)
	(arc
		(start 71.123556 -66.191638)
		(mid 71.263635 -66.334374)
		(end 71.45528 -66.391536)
		(width 0.0889)
		(layer "In11.Cu")
		(net "M_J_DQ<1>")
	)
	(arc
		(start 69.771006 -65.400936)
		(mid 70.05643 -65.484403)
		(end 70.265036 -65.696338)
		(width 0.0889)
		(layer "In11.Cu")
		(net "M_J_DQ<1>")
	)
	(arc
		(start 72.350376 -66.88709)
		(mid 72.633593 -66.971371)
		(end 72.840596 -67.182238)
		(width 0.0889)
		(layer "In11.Cu")
		(net "M_J_DQ<1>")
	)
	(arc
		(start 67.524376 -65.696338)
		(mid 67.732984 -65.484406)
		(end 68.018406 -65.400936)
		(width 0.0889)
		(layer "In11.Cu")
		(net "M_J_DQ<1>")
	)
	(segment
		(start 82.343752 -57.076086)
		(end 81.772252 -57.076086)
		(width 0.0889)
		(layer "F.Cu")
		(net "M_J_DQ<19>")
	)
	(segment
		(start 57.74944 3.778758)
		(end 57.74944 2.514854)
		(width 0.1651)
		(layer "F.Cu")
		(net "M_J_DQ<19>")
	)
	(via
		(at 81.772252 -57.076086)
		(size 0.508)
		(drill 0.254)
		(layers "F.Cu" "B.Cu")
		(net "M_J_DQ<19>")
	)
	(via
		(at 58.599324 -3.076956)
		(size 0.508)
		(drill 0.254)
		(layers "F.Cu" "B.Cu")
		(net "M_J_DQ<19>")
	)
	(via
		(at 57.74944 2.514854)
		(size 0.508)
		(drill 0.254)
		(layers "F.Cu" "B.Cu")
		(net "M_J_DQ<19>")
	)
	(segment
		(start 58.599578 -1.021842)
		(end 58.599324 -1.022096)
		(width 0.1651)
		(layer "B.Cu")
		(net "M_J_DQ<19>")
	)
	(segment
		(start 58.599324 -1.022096)
		(end 58.599324 -3.076956)
		(width 0.1651)
		(layer "B.Cu")
		(net "M_J_DQ<19>")
	)
	(segment
		(start 58.953908 -21.336)
		(end 59.052968 -21.23694)
		(width 0.14224)
		(layer "In11.Cu")
		(net "M_J_DQ<19>")
	)
	(segment
		(start 58.953908 -12.208256)
		(end 58.953908 -11.7602)
		(width 0.14224)
		(layer "In11.Cu")
		(net "M_J_DQ<19>")
	)
	(segment
		(start 58.890662 -32.239204)
		(end 58.890662 -31.841186)
		(width 0.14224)
		(layer "In11.Cu")
		(net "M_J_DQ<19>")
	)
	(segment
		(start 58.735722 -31.686246)
		(end 58.206894 -31.686246)
		(width 0.14224)
		(layer "In11.Cu")
		(net "M_J_DQ<19>")
	)
	(segment
		(start 59.083702 -12.33805)
		(end 58.953908 -12.208256)
		(width 0.14224)
		(layer "In11.Cu")
		(net "M_J_DQ<19>")
	)
	(segment
		(start 58.206894 -31.066486)
		(end 58.735722 -31.066486)
		(width 0.14224)
		(layer "In11.Cu")
		(net "M_J_DQ<19>")
	)
	(segment
		(start 58.890662 -23.424642)
		(end 59.131708 -23.183596)
		(width 0.14224)
		(layer "In11.Cu")
		(net "M_J_DQ<19>")
	)
	(segment
		(start 71.163434 -45.638466)
		(end 71.163434 -45.419518)
		(width 0.14224)
		(layer "In11.Cu")
		(net "M_J_DQ<19>")
	)
	(segment
		(start 58.953908 -9.37514)
		(end 58.953908 -8.963914)
		(width 0.14224)
		(layer "In11.Cu")
		(net "M_J_DQ<19>")
	)
	(segment
		(start 58.966608 -16.890746)
		(end 58.966608 -13.694156)
		(width 0.14224)
		(layer "In11.Cu")
		(net "M_J_DQ<19>")
	)
	(segment
		(start 59.083702 -13.577062)
		(end 59.083702 -12.33805)
		(width 0.14224)
		(layer "In11.Cu")
		(net "M_J_DQ<19>")
	)
	(segment
		(start 58.953908 -21.822156)
		(end 58.953908 -21.336)
		(width 0.14224)
		(layer "In11.Cu")
		(net "M_J_DQ<19>")
	)
	(segment
		(start 73.739248 -46.785276)
		(end 73.45172 -46.497748)
		(width 0.14224)
		(layer "In11.Cu")
		(net "M_J_DQ<19>")
	)
	(segment
		(start 58.396378 1.5494)
		(end 58.066178 1.8796)
		(width 0.14224)
		(layer "In11.Cu")
		(net "M_J_DQ<19>")
	)
	(segment
		(start 58.115708 -3.560572)
		(end 58.599324 -3.076956)
		(width 0.14224)
		(layer "In11.Cu")
		(net "M_J_DQ<19>")
	)
	(segment
		(start 73.705466 -50.848006)
		(end 73.699116 -50.837338)
		(width 0.0889)
		(layer "In11.Cu")
		(net "M_J_DQ<19>")
	)
	(segment
		(start 74.925936 -52.523136)
		(end 74.886312 -52.523136)
		(width 0.0889)
		(layer "In11.Cu")
		(net "M_J_DQ<19>")
	)
	(segment
		(start 73.99655 -48.2727)
		(end 73.739248 -48.015398)
		(width 0.0889)
		(layer "In11.Cu")
		(net "M_J_DQ<19>")
	)
	(segment
		(start 71.226426 -44.479718)
		(end 70.983602 -44.722542)
		(width 0.14224)
		(layer "In11.Cu")
		(net "M_J_DQ<19>")
	)
	(segment
		(start 68.167504 -42.642536)
		(end 68.167504 -41.516046)
		(width 0.14224)
		(layer "In11.Cu")
		(net "M_J_DQ<19>")
	)
	(segment
		(start 68.823332 -43.298364)
		(end 68.167504 -42.642536)
		(width 0.14224)
		(layer "In11.Cu")
		(net "M_J_DQ<19>")
	)
	(segment
		(start 73.699116 -50.437288)
		(end 73.99655 -49.922938)
		(width 0.0889)
		(layer "In11.Cu")
		(net "M_J_DQ<19>")
	)
	(segment
		(start 72.011794 -45.8978)
		(end 71.422768 -45.8978)
		(width 0.14224)
		(layer "In11.Cu")
		(net "M_J_DQ<19>")
	)
	(segment
		(start 70.983602 -44.722542)
		(end 70.782434 -44.722542)
		(width 0.14224)
		(layer "In11.Cu")
		(net "M_J_DQ<19>")
	)
	(segment
		(start 77.995018 -54.310026)
		(end 77.991716 -54.304184)
		(width 0.0889)
		(layer "In11.Cu")
		(net "M_J_DQ<19>")
	)
	(segment
		(start 58.051954 -31.531306)
		(end 58.051954 -31.221426)
		(width 0.14224)
		(layer "In11.Cu")
		(net "M_J_DQ<19>")
	)
	(segment
		(start 73.0504 -46.497748)
		(end 72.9234 -46.370748)
		(width 0.14224)
		(layer "In11.Cu")
		(net "M_J_DQ<19>")
	)
	(segment
		(start 72.580754 -45.626782)
		(end 72.282812 -45.626782)
		(width 0.14224)
		(layer "In11.Cu")
		(net "M_J_DQ<19>")
	)
	(segment
		(start 72.282812 -45.626782)
		(end 72.011794 -45.8978)
		(width 0.14224)
		(layer "In11.Cu")
		(net "M_J_DQ<19>")
	)
	(segment
		(start 59.107578 0.7366)
		(end 59.107578 1.0922)
		(width 0.14224)
		(layer "In11.Cu")
		(net "M_J_DQ<19>")
	)
	(segment
		(start 58.206894 -31.686246)
		(end 58.051954 -31.531306)
		(width 0.14224)
		(layer "In11.Cu")
		(net "M_J_DQ<19>")
	)
	(segment
		(start 71.445374 -44.479718)
		(end 71.226426 -44.479718)
		(width 0.14224)
		(layer "In11.Cu")
		(net "M_J_DQ<19>")
	)
	(segment
		(start 76.639166 -53.513736)
		(end 76.6064 -53.513736)
		(width 0.0889)
		(layer "In11.Cu")
		(net "M_J_DQ<19>")
	)
	(segment
		(start 58.599324 -3.076956)
		(end 58.95213 -2.72415)
		(width 0.14224)
		(layer "In11.Cu")
		(net "M_J_DQ<19>")
	)
	(segment
		(start 71.66483 -44.918122)
		(end 71.66483 -44.699174)
		(width 0.14224)
		(layer "In11.Cu")
		(net "M_J_DQ<19>")
	)
	(segment
		(start 81.772252 -57.076086)
		(end 81.454498 -56.342788)
		(width 0.0889)
		(layer "In11.Cu")
		(net "M_J_DQ<19>")
	)
	(segment
		(start 58.966608 -13.694156)
		(end 59.083702 -13.577062)
		(width 0.14224)
		(layer "In11.Cu")
		(net "M_J_DQ<19>")
	)
	(segment
		(start 70.782434 -44.722542)
		(end 69.358256 -43.298364)
		(width 0.14224)
		(layer "In11.Cu")
		(net "M_J_DQ<19>")
	)
	(segment
		(start 73.739248 -48.015398)
		(end 73.739248 -47.47768)
		(width 0.0889)
		(layer "In11.Cu")
		(net "M_J_DQ<19>")
	)
	(segment
		(start 58.890662 -30.911546)
		(end 58.890662 -23.424642)
		(width 0.14224)
		(layer "In11.Cu")
		(net "M_J_DQ<19>")
	)
	(segment
		(start 72.9234 -46.370748)
		(end 72.9234 -45.969428)
		(width 0.14224)
		(layer "In11.Cu")
		(net "M_J_DQ<19>")
	)
	(segment
		(start 59.106308 -8.811514)
		(end 59.106308 -7.429246)
		(width 0.14224)
		(layer "In11.Cu")
		(net "M_J_DQ<19>")
	)
	(segment
		(start 71.422768 -45.8978)
		(end 71.163434 -45.638466)
		(width 0.14224)
		(layer "In11.Cu")
		(net "M_J_DQ<19>")
	)
	(segment
		(start 59.131708 -21.999956)
		(end 58.953908 -21.822156)
		(width 0.14224)
		(layer "In11.Cu")
		(net "M_J_DQ<19>")
	)
	(segment
		(start 78.355952 -54.504336)
		(end 78.338172 -54.504336)
		(width 0.0889)
		(layer "In11.Cu")
		(net "M_J_DQ<19>")
	)
	(segment
		(start 58.051954 -31.221426)
		(end 58.206894 -31.066486)
		(width 0.14224)
		(layer "In11.Cu")
		(net "M_J_DQ<19>")
	)
	(segment
		(start 58.95213 -2.72415)
		(end 58.95213 0.581152)
		(width 0.14224)
		(layer "In11.Cu")
		(net "M_J_DQ<19>")
	)
	(segment
		(start 73.699116 -50.837338)
		(end 73.69429 -50.828702)
		(width 0.0889)
		(layer "In11.Cu")
		(net "M_J_DQ<19>")
	)
	(segment
		(start 59.052968 -19.05)
		(end 58.953908 -18.95094)
		(width 0.14224)
		(layer "In11.Cu")
		(net "M_J_DQ<19>")
	)
	(segment
		(start 59.129168 -11.58494)
		(end 59.129168 -9.5504)
		(width 0.14224)
		(layer "In11.Cu")
		(net "M_J_DQ<19>")
	)
	(segment
		(start 58.890662 -31.841186)
		(end 58.735722 -31.686246)
		(width 0.14224)
		(layer "In11.Cu")
		(net "M_J_DQ<19>")
	)
	(segment
		(start 69.358256 -43.298364)
		(end 68.823332 -43.298364)
		(width 0.14224)
		(layer "In11.Cu")
		(net "M_J_DQ<19>")
	)
	(segment
		(start 58.966608 -7.289546)
		(end 58.966608 -4.816856)
		(width 0.14224)
		(layer "In11.Cu")
		(net "M_J_DQ<19>")
	)
	(segment
		(start 80.072992 -55.494936)
		(end 80.040226 -55.494936)
		(width 0.0889)
		(layer "In11.Cu")
		(net "M_J_DQ<19>")
	)
	(segment
		(start 59.052968 -21.23694)
		(end 59.052968 -19.05)
		(width 0.14224)
		(layer "In11.Cu")
		(net "M_J_DQ<19>")
	)
	(segment
		(start 72.9234 -45.969428)
		(end 72.580754 -45.626782)
		(width 0.14224)
		(layer "In11.Cu")
		(net "M_J_DQ<19>")
	)
	(segment
		(start 75.77582 -53.018436)
		(end 75.75169 -53.018436)
		(width 0.0889)
		(layer "In11.Cu")
		(net "M_J_DQ<19>")
	)
	(segment
		(start 73.45172 -46.497748)
		(end 73.0504 -46.497748)
		(width 0.14224)
		(layer "In11.Cu")
		(net "M_J_DQ<19>")
	)
	(segment
		(start 71.66483 -44.699174)
		(end 71.445374 -44.479718)
		(width 0.14224)
		(layer "In11.Cu")
		(net "M_J_DQ<19>")
	)
	(segment
		(start 58.953908 -18.95094)
		(end 58.953908 -18.565114)
		(width 0.14224)
		(layer "In11.Cu")
		(net "M_J_DQ<19>")
	)
	(segment
		(start 58.95213 0.581152)
		(end 59.107578 0.7366)
		(width 0.14224)
		(layer "In11.Cu")
		(net "M_J_DQ<19>")
	)
	(segment
		(start 58.953908 -11.7602)
		(end 59.129168 -11.58494)
		(width 0.14224)
		(layer "In11.Cu")
		(net "M_J_DQ<19>")
	)
	(segment
		(start 68.167504 -41.516046)
		(end 58.890662 -32.239204)
		(width 0.14224)
		(layer "In11.Cu")
		(net "M_J_DQ<19>")
	)
	(segment
		(start 58.953908 -8.963914)
		(end 59.106308 -8.811514)
		(width 0.14224)
		(layer "In11.Cu")
		(net "M_J_DQ<19>")
	)
	(segment
		(start 79.218282 -54.99989)
		(end 79.185516 -54.99989)
		(width 0.0889)
		(layer "In11.Cu")
		(net "M_J_DQ<19>")
	)
	(segment
		(start 58.650378 1.5494)
		(end 58.396378 1.5494)
		(width 0.14224)
		(layer "In11.Cu")
		(net "M_J_DQ<19>")
	)
	(segment
		(start 59.106308 -7.429246)
		(end 58.966608 -7.289546)
		(width 0.14224)
		(layer "In11.Cu")
		(net "M_J_DQ<19>")
	)
	(segment
		(start 58.066178 2.198116)
		(end 57.74944 2.514854)
		(width 0.14224)
		(layer "In11.Cu")
		(net "M_J_DQ<19>")
	)
	(segment
		(start 80.935322 -55.99049)
		(end 80.902556 -55.99049)
		(width 0.0889)
		(layer "In11.Cu")
		(net "M_J_DQ<19>")
	)
	(segment
		(start 59.093608 -18.425414)
		(end 59.093608 -17.017746)
		(width 0.14224)
		(layer "In11.Cu")
		(net "M_J_DQ<19>")
	)
	(segment
		(start 58.066178 1.8796)
		(end 58.066178 2.198116)
		(width 0.14224)
		(layer "In11.Cu")
		(net "M_J_DQ<19>")
	)
	(segment
		(start 58.953908 -18.565114)
		(end 59.093608 -18.425414)
		(width 0.14224)
		(layer "In11.Cu")
		(net "M_J_DQ<19>")
	)
	(segment
		(start 58.115708 -3.965956)
		(end 58.115708 -3.560572)
		(width 0.14224)
		(layer "In11.Cu")
		(net "M_J_DQ<19>")
	)
	(segment
		(start 58.735722 -31.066486)
		(end 58.890662 -30.911546)
		(width 0.14224)
		(layer "In11.Cu")
		(net "M_J_DQ<19>")
	)
	(segment
		(start 59.107578 1.0922)
		(end 58.650378 1.5494)
		(width 0.14224)
		(layer "In11.Cu")
		(net "M_J_DQ<19>")
	)
	(segment
		(start 73.99655 -49.922938)
		(end 73.99655 -48.2727)
		(width 0.0889)
		(layer "In11.Cu")
		(net "M_J_DQ<19>")
	)
	(segment
		(start 73.739248 -47.47768)
		(end 73.739248 -46.785276)
		(width 0.14224)
		(layer "In11.Cu")
		(net "M_J_DQ<19>")
	)
	(segment
		(start 59.131708 -23.183596)
		(end 59.131708 -21.999956)
		(width 0.14224)
		(layer "In11.Cu")
		(net "M_J_DQ<19>")
	)
	(segment
		(start 59.129168 -9.5504)
		(end 58.953908 -9.37514)
		(width 0.14224)
		(layer "In11.Cu")
		(net "M_J_DQ<19>")
	)
	(segment
		(start 77.504798 -54.00929)
		(end 77.46492 -54.00929)
		(width 0.0889)
		(layer "In11.Cu")
		(net "M_J_DQ<19>")
	)
	(segment
		(start 71.163434 -45.419518)
		(end 71.66483 -44.918122)
		(width 0.14224)
		(layer "In11.Cu")
		(net "M_J_DQ<19>")
	)
	(segment
		(start 59.093608 -17.017746)
		(end 58.966608 -16.890746)
		(width 0.14224)
		(layer "In11.Cu")
		(net "M_J_DQ<19>")
	)
	(segment
		(start 74.063606 -52.027836)
		(end 74.027792 -52.027836)
		(width 0.0889)
		(layer "In11.Cu")
		(net "M_J_DQ<19>")
	)
	(segment
		(start 58.966608 -4.816856)
		(end 58.115708 -3.965956)
		(width 0.14224)
		(layer "In11.Cu")
		(net "M_J_DQ<19>")
	)
	(arc
		(start 78.338172 -54.504336)
		(mid 78.141011 -54.452377)
		(end 77.995018 -54.310026)
		(width 0.0889)
		(layer "In11.Cu")
		(net "M_J_DQ<19>")
	)
	(arc
		(start 76.6064 -53.513736)
		(mid 76.414758 -53.45657)
		(end 76.274676 -53.313838)
		(width 0.0889)
		(layer "In11.Cu")
		(net "M_J_DQ<19>")
	)
	(arc
		(start 75.416156 -52.818284)
		(mid 75.209152 -52.60742)
		(end 74.925936 -52.523136)
		(width 0.0889)
		(layer "In11.Cu")
		(net "M_J_DQ<19>")
	)
	(arc
		(start 79.185516 -54.99989)
		(mid 78.991666 -54.94354)
		(end 78.849982 -54.799738)
		(width 0.0889)
		(layer "In11.Cu")
		(net "M_J_DQ<19>")
	)
	(arc
		(start 73.69429 -50.828702)
		(mid 73.645535 -50.63235)
		(end 73.699116 -50.437288)
		(width 0.0889)
		(layer "In11.Cu")
		(net "M_J_DQ<19>")
	)
	(arc
		(start 73.699116 -51.427888)
		(mid 73.778338 -51.13877)
		(end 73.705466 -50.848006)
		(width 0.0889)
		(layer "In11.Cu")
		(net "M_J_DQ<19>")
	)
	(arc
		(start 80.040226 -55.494936)
		(mid 79.848584 -55.43777)
		(end 79.708502 -55.295038)
		(width 0.0889)
		(layer "In11.Cu")
		(net "M_J_DQ<19>")
	)
	(arc
		(start 79.708502 -55.295038)
		(mid 79.501498 -55.084174)
		(end 79.218282 -54.99989)
		(width 0.0889)
		(layer "In11.Cu")
		(net "M_J_DQ<19>")
	)
	(arc
		(start 77.46492 -54.00929)
		(mid 77.273216 -53.952044)
		(end 77.133196 -53.809138)
		(width 0.0889)
		(layer "In11.Cu")
		(net "M_J_DQ<19>")
	)
	(arc
		(start 74.886312 -52.523136)
		(mid 74.696383 -52.465266)
		(end 74.557636 -52.323238)
		(width 0.0889)
		(layer "In11.Cu")
		(net "M_J_DQ<19>")
	)
	(arc
		(start 74.557636 -52.323238)
		(mid 74.349028 -52.111306)
		(end 74.063606 -52.027836)
		(width 0.0889)
		(layer "In11.Cu")
		(net "M_J_DQ<19>")
	)
	(arc
		(start 80.567022 -55.790338)
		(mid 80.358414 -55.578406)
		(end 80.072992 -55.494936)
		(width 0.0889)
		(layer "In11.Cu")
		(net "M_J_DQ<19>")
	)
	(arc
		(start 80.902556 -55.99049)
		(mid 80.708706 -55.93414)
		(end 80.567022 -55.790338)
		(width 0.0889)
		(layer "In11.Cu")
		(net "M_J_DQ<19>")
	)
	(arc
		(start 77.133196 -53.809138)
		(mid 76.924588 -53.597206)
		(end 76.639166 -53.513736)
		(width 0.0889)
		(layer "In11.Cu")
		(net "M_J_DQ<19>")
	)
	(arc
		(start 78.849982 -54.799738)
		(mid 78.641374 -54.587806)
		(end 78.355952 -54.504336)
		(width 0.0889)
		(layer "In11.Cu")
		(net "M_J_DQ<19>")
	)
	(arc
		(start 77.991716 -54.304184)
		(mid 77.786095 -54.094261)
		(end 77.504798 -54.00929)
		(width 0.0889)
		(layer "In11.Cu")
		(net "M_J_DQ<19>")
	)
	(arc
		(start 74.027792 -52.027836)
		(mid 73.694823 -51.820288)
		(end 73.699116 -51.427888)
		(width 0.0889)
		(layer "In11.Cu")
		(net "M_J_DQ<19>")
	)
	(arc
		(start 75.75169 -53.018436)
		(mid 75.55784 -52.962086)
		(end 75.416156 -52.818284)
		(width 0.0889)
		(layer "In11.Cu")
		(net "M_J_DQ<19>")
	)
	(arc
		(start 76.274676 -53.313838)
		(mid 76.063963 -53.100759)
		(end 75.77582 -53.018436)
		(width 0.0889)
		(layer "In11.Cu")
		(net "M_J_DQ<19>")
	)
	(arc
		(start 81.454498 -56.342788)
		(mid 81.245524 -56.092055)
		(end 80.935322 -55.99049)
		(width 0.0889)
		(layer "In11.Cu")
		(net "M_J_DQ<19>")
	)
	(segment
		(start 58.730896 0.30734)
		(end 58.730896 0.53086)
		(width 0.1651)
		(layer "F.Cu")
		(net "M_J_DQ<18>")
	)
	(segment
		(start 58.599324 -0.820928)
		(end 58.599324 0.175768)
		(width 0.1651)
		(layer "F.Cu")
		(net "M_J_DQ<18>")
	)
	(segment
		(start 58.599324 0.662432)
		(end 58.599324 0.9398)
		(width 0.1651)
		(layer "F.Cu")
		(net "M_J_DQ<18>")
	)
	(segment
		(start 58.599324 0.175768)
		(end 58.730896 0.30734)
		(width 0.1651)
		(layer "F.Cu")
		(net "M_J_DQ<18>")
	)
	(segment
		(start 58.599578 -0.821182)
		(end 58.599324 -0.820928)
		(width 0.1651)
		(layer "F.Cu")
		(net "M_J_DQ<18>")
	)
	(segment
		(start 58.730896 0.53086)
		(end 58.599324 0.662432)
		(width 0.1651)
		(layer "F.Cu")
		(net "M_J_DQ<18>")
	)
	(segment
		(start 81.485232 -56.58104)
		(end 80.913732 -56.58104)
		(width 0.0889)
		(layer "F.Cu")
		(net "M_J_DQ<18>")
	)
	(via
		(at 80.913732 -56.58104)
		(size 0.508)
		(drill 0.254)
		(layers "F.Cu" "B.Cu")
		(net "M_J_DQ<18>")
	)
	(via
		(at 57.74944 -4.357878)
		(size 0.508)
		(drill 0.254)
		(layers "F.Cu" "B.Cu")
		(net "M_J_DQ<18>")
	)
	(via
		(at 58.599324 0.9398)
		(size 0.508)
		(drill 0.254)
		(layers "F.Cu" "B.Cu")
		(net "M_J_DQ<18>")
	)
	(segment
		(start 57.74944 -5.621782)
		(end 57.74944 -4.357878)
		(width 0.1651)
		(layer "B.Cu")
		(net "M_J_DQ<18>")
	)
	(segment
		(start 67.563492 -41.936924)
		(end 66.967862 -41.341294)
		(width 0.14224)
		(layer "In11.Cu")
		(net "M_J_DQ<18>")
	)
	(segment
		(start 57.506108 -29.60751)
		(end 57.506108 -29.371544)
		(width 0.14224)
		(layer "In11.Cu")
		(net "M_J_DQ<18>")
	)
	(segment
		(start 65.404492 -39.869872)
		(end 65.021714 -40.25265)
		(width 0.14224)
		(layer "In11.Cu")
		(net "M_J_DQ<18>")
	)
	(segment
		(start 58.090308 -21.949156)
		(end 58.242708 -21.796756)
		(width 0.14224)
		(layer "In11.Cu")
		(net "M_J_DQ<18>")
	)
	(segment
		(start 78.349348 -54.694836)
		(end 78.31328 -54.694836)
		(width 0.0889)
		(layer "In11.Cu")
		(net "M_J_DQ<18>")
	)
	(segment
		(start 58.214768 -7.266686)
		(end 58.214768 -4.823206)
		(width 0.14224)
		(layer "In11.Cu")
		(net "M_J_DQ<18>")
	)
	(segment
		(start 58.106056 -30.389576)
		(end 58.260996 -30.234636)
		(width 0.14224)
		(layer "In11.Cu")
		(net "M_J_DQ<18>")
	)
	(segment
		(start 57.464706 -4.073144)
		(end 57.464706 -3.3274)
		(width 0.14224)
		(layer "In11.Cu")
		(net "M_J_DQ<18>")
	)
	(segment
		(start 58.242708 -11.7094)
		(end 58.098944 -11.565636)
		(width 0.14224)
		(layer "In11.Cu")
		(net "M_J_DQ<18>")
	)
	(segment
		(start 58.242708 -12.195556)
		(end 58.242708 -11.7094)
		(width 0.14224)
		(layer "In11.Cu")
		(net "M_J_DQ<18>")
	)
	(segment
		(start 58.242708 -8.994394)
		(end 58.138568 -8.890254)
		(width 0.14224)
		(layer "In11.Cu")
		(net "M_J_DQ<18>")
	)
	(segment
		(start 66.967862 -41.341294)
		(end 65.89141 -41.341294)
		(width 0.14224)
		(layer "In11.Cu")
		(net "M_J_DQ<18>")
	)
	(segment
		(start 61.82995 -36.076382)
		(end 57.506108 -31.75254)
		(width 0.14224)
		(layer "In11.Cu")
		(net "M_J_DQ<18>")
	)
	(segment
		(start 75.777852 -53.20919)
		(end 75.749912 -53.20919)
		(width 0.0889)
		(layer "In11.Cu")
		(net "M_J_DQ<18>")
	)
	(segment
		(start 58.242708 -9.39546)
		(end 58.242708 -8.994394)
		(width 0.14224)
		(layer "In11.Cu")
		(net "M_J_DQ<18>")
	)
	(segment
		(start 58.161174 -0.761746)
		(end 57.856374 -0.456946)
		(width 0.14224)
		(layer "In11.Cu")
		(net "M_J_DQ<18>")
	)
	(segment
		(start 58.161174 -1.04775)
		(end 58.161174 -0.761746)
		(width 0.14224)
		(layer "In11.Cu")
		(net "M_J_DQ<18>")
	)
	(segment
		(start 58.115708 -16.966946)
		(end 58.331608 -16.751046)
		(width 0.14224)
		(layer "In11.Cu")
		(net "M_J_DQ<18>")
	)
	(segment
		(start 58.106056 -28.659074)
		(end 57.661048 -28.659074)
		(width 0.14224)
		(layer "In11.Cu")
		(net "M_J_DQ<18>")
	)
	(segment
		(start 58.260996 -29.061664)
		(end 58.260996 -28.814014)
		(width 0.14224)
		(layer "In11.Cu")
		(net "M_J_DQ<18>")
	)
	(segment
		(start 57.506108 -30.544516)
		(end 57.661048 -30.389576)
		(width 0.14224)
		(layer "In11.Cu")
		(net "M_J_DQ<18>")
	)
	(segment
		(start 58.260996 -30.234636)
		(end 58.260996 -29.91739)
		(width 0.14224)
		(layer "In11.Cu")
		(net "M_J_DQ<18>")
	)
	(segment
		(start 62.289944 -36.737544)
		(end 62.046612 -36.980876)
		(width 0.14224)
		(layer "In11.Cu")
		(net "M_J_DQ<18>")
	)
	(segment
		(start 80.913732 -56.58104)
		(end 80.512666 -56.024272)
		(width 0.0889)
		(layer "In11.Cu")
		(net "M_J_DQ<18>")
	)
	(segment
		(start 57.856374 -0.108204)
		(end 58.201306 0.236728)
		(width 0.14224)
		(layer "In11.Cu")
		(net "M_J_DQ<18>")
	)
	(segment
		(start 65.460118 -40.691054)
		(end 65.842896 -40.308276)
		(width 0.14224)
		(layer "In11.Cu")
		(net "M_J_DQ<18>")
	)
	(segment
		(start 57.464706 -3.3274)
		(end 58.313574 -2.478532)
		(width 0.14224)
		(layer "In11.Cu")
		(net "M_J_DQ<18>")
	)
	(segment
		(start 64.58331 -40.033194)
		(end 64.58331 -39.814246)
		(width 0.14224)
		(layer "In11.Cu")
		(net "M_J_DQ<18>")
	)
	(segment
		(start 57.856374 -1.35255)
		(end 58.161174 -1.04775)
		(width 0.14224)
		(layer "In11.Cu")
		(net "M_J_DQ<18>")
	)
	(segment
		(start 57.856374 -1.7526)
		(end 57.856374 -1.35255)
		(width 0.14224)
		(layer "In11.Cu")
		(net "M_J_DQ<18>")
	)
	(segment
		(start 64.08928 -38.55466)
		(end 64.08928 -38.335712)
		(width 0.14224)
		(layer "In11.Cu")
		(net "M_J_DQ<18>")
	)
	(segment
		(start 73.80605 -48.353472)
		(end 73.577958 -48.12538)
		(width 0.0889)
		(layer "In11.Cu")
		(net "M_J_DQ<18>")
	)
	(segment
		(start 57.856374 -0.456946)
		(end 57.856374 -0.108204)
		(width 0.14224)
		(layer "In11.Cu")
		(net "M_J_DQ<18>")
	)
	(segment
		(start 65.842896 -40.089328)
		(end 65.62344 -39.869872)
		(width 0.14224)
		(layer "In11.Cu")
		(net "M_J_DQ<18>")
	)
	(segment
		(start 58.331608 -13.783056)
		(end 58.090308 -13.541756)
		(width 0.14224)
		(layer "In11.Cu")
		(net "M_J_DQ<18>")
	)
	(segment
		(start 57.74944 -4.357878)
		(end 57.464706 -4.073144)
		(width 0.14224)
		(layer "In11.Cu")
		(net "M_J_DQ<18>")
	)
	(segment
		(start 64.527684 -38.993064)
		(end 64.144906 -39.375842)
		(width 0.14224)
		(layer "In11.Cu")
		(net "M_J_DQ<18>")
	)
	(segment
		(start 73.538842 -50.941224)
		(end 73.534016 -50.932588)
		(width 0.0889)
		(layer "In11.Cu")
		(net "M_J_DQ<18>")
	)
	(segment
		(start 74.92238 -52.71389)
		(end 74.886566 -52.71389)
		(width 0.0889)
		(layer "In11.Cu")
		(net "M_J_DQ<18>")
	)
	(segment
		(start 71.618094 -46.4566)
		(end 71.169022 -46.4566)
		(width 0.14224)
		(layer "In11.Cu")
		(net "M_J_DQ<18>")
	)
	(segment
		(start 58.313574 -2.2098)
		(end 57.856374 -1.7526)
		(width 0.14224)
		(layer "In11.Cu")
		(net "M_J_DQ<18>")
	)
	(segment
		(start 73.286874 -48.12538)
		(end 71.618094 -46.4566)
		(width 0.14224)
		(layer "In11.Cu")
		(net "M_J_DQ<18>")
	)
	(segment
		(start 79.211678 -55.19039)
		(end 79.178912 -55.19039)
		(width 0.0889)
		(layer "In11.Cu")
		(net "M_J_DQ<18>")
	)
	(segment
		(start 61.82995 -36.27755)
		(end 61.82995 -36.076382)
		(width 0.14224)
		(layer "In11.Cu")
		(net "M_J_DQ<18>")
	)
	(segment
		(start 58.138568 -8.890254)
		(end 58.138568 -7.342886)
		(width 0.14224)
		(layer "In11.Cu")
		(net "M_J_DQ<18>")
	)
	(segment
		(start 58.255662 -27.841194)
		(end 58.255662 -23.30831)
		(width 0.14224)
		(layer "In11.Cu")
		(net "M_J_DQ<18>")
	)
	(segment
		(start 57.661048 -28.659074)
		(end 57.506108 -28.504134)
		(width 0.14224)
		(layer "In11.Cu")
		(net "M_J_DQ<18>")
	)
	(segment
		(start 58.098944 -11.565636)
		(end 58.098944 -9.539224)
		(width 0.14224)
		(layer "In11.Cu")
		(net "M_J_DQ<18>")
	)
	(segment
		(start 61.586618 -36.72205)
		(end 61.586618 -36.520882)
		(width 0.14224)
		(layer "In11.Cu")
		(net "M_J_DQ<18>")
	)
	(segment
		(start 57.661048 -30.389576)
		(end 58.106056 -30.389576)
		(width 0.14224)
		(layer "In11.Cu")
		(net "M_J_DQ<18>")
	)
	(segment
		(start 58.242708 -21.796756)
		(end 58.242708 -21.336)
		(width 0.14224)
		(layer "In11.Cu")
		(net "M_J_DQ<18>")
	)
	(segment
		(start 62.491112 -36.737544)
		(end 62.289944 -36.737544)
		(width 0.14224)
		(layer "In11.Cu")
		(net "M_J_DQ<18>")
	)
	(segment
		(start 57.506108 -28.24099)
		(end 57.778904 -27.968194)
		(width 0.14224)
		(layer "In11.Cu")
		(net "M_J_DQ<18>")
	)
	(segment
		(start 58.090308 -12.347956)
		(end 58.242708 -12.195556)
		(width 0.14224)
		(layer "In11.Cu")
		(net "M_J_DQ<18>")
	)
	(segment
		(start 57.506108 -28.504134)
		(end 57.506108 -28.24099)
		(width 0.14224)
		(layer "In11.Cu")
		(net "M_J_DQ<18>")
	)
	(segment
		(start 58.098944 -9.539224)
		(end 58.242708 -9.39546)
		(width 0.14224)
		(layer "In11.Cu")
		(net "M_J_DQ<18>")
	)
	(segment
		(start 58.313574 -2.478532)
		(end 58.313574 -2.2098)
		(width 0.14224)
		(layer "In11.Cu")
		(net "M_J_DQ<18>")
	)
	(segment
		(start 71.169022 -46.4566)
		(end 67.563492 -42.85107)
		(width 0.14224)
		(layer "In11.Cu")
		(net "M_J_DQ<18>")
	)
	(segment
		(start 73.534016 -50.932588)
		(end 73.525126 -50.917348)
		(width 0.0889)
		(layer "In11.Cu")
		(net "M_J_DQ<18>")
	)
	(segment
		(start 58.090308 -13.541756)
		(end 58.090308 -12.347956)
		(width 0.14224)
		(layer "In11.Cu")
		(net "M_J_DQ<18>")
	)
	(segment
		(start 65.460118 -40.910002)
		(end 65.460118 -40.691054)
		(width 0.14224)
		(layer "In11.Cu")
		(net "M_J_DQ<18>")
	)
	(segment
		(start 58.201306 0.236728)
		(end 58.201306 0.541782)
		(width 0.14224)
		(layer "In11.Cu")
		(net "M_J_DQ<18>")
	)
	(segment
		(start 63.925958 -39.375842)
		(end 63.706502 -39.156386)
		(width 0.14224)
		(layer "In11.Cu")
		(net "M_J_DQ<18>")
	)
	(segment
		(start 73.80605 -49.87163)
		(end 73.80605 -48.353472)
		(width 0.0889)
		(layer "In11.Cu")
		(net "M_J_DQ<18>")
	)
	(segment
		(start 64.58331 -39.814246)
		(end 64.966088 -39.431468)
		(width 0.14224)
		(layer "In11.Cu")
		(net "M_J_DQ<18>")
	)
	(segment
		(start 65.842896 -40.308276)
		(end 65.842896 -40.089328)
		(width 0.14224)
		(layer "In11.Cu")
		(net "M_J_DQ<18>")
	)
	(segment
		(start 63.706502 -38.937438)
		(end 64.08928 -38.55466)
		(width 0.14224)
		(layer "In11.Cu")
		(net "M_J_DQ<18>")
	)
	(segment
		(start 57.778904 -27.968194)
		(end 58.128662 -27.968194)
		(width 0.14224)
		(layer "In11.Cu")
		(net "M_J_DQ<18>")
	)
	(segment
		(start 58.214768 -4.823206)
		(end 57.74944 -4.357878)
		(width 0.14224)
		(layer "In11.Cu")
		(net "M_J_DQ<18>")
	)
	(segment
		(start 58.138568 -19.1516)
		(end 58.242708 -19.04746)
		(width 0.14224)
		(layer "In11.Cu")
		(net "M_J_DQ<18>")
	)
	(segment
		(start 58.128662 -27.968194)
		(end 58.255662 -27.841194)
		(width 0.14224)
		(layer "In11.Cu")
		(net "M_J_DQ<18>")
	)
	(segment
		(start 61.845444 -36.980876)
		(end 61.586618 -36.72205)
		(width 0.14224)
		(layer "In11.Cu")
		(net "M_J_DQ<18>")
	)
	(segment
		(start 62.046612 -36.980876)
		(end 61.845444 -36.980876)
		(width 0.14224)
		(layer "In11.Cu")
		(net "M_J_DQ<18>")
	)
	(segment
		(start 61.586618 -36.520882)
		(end 61.82995 -36.27755)
		(width 0.14224)
		(layer "In11.Cu")
		(net "M_J_DQ<18>")
	)
	(segment
		(start 58.138568 -7.342886)
		(end 58.214768 -7.266686)
		(width 0.14224)
		(layer "In11.Cu")
		(net "M_J_DQ<18>")
	)
	(segment
		(start 73.534016 -50.341784)
		(end 73.80605 -49.87163)
		(width 0.0889)
		(layer "In11.Cu")
		(net "M_J_DQ<18>")
	)
	(segment
		(start 65.62344 -39.869872)
		(end 65.404492 -39.869872)
		(width 0.14224)
		(layer "In11.Cu")
		(net "M_J_DQ<18>")
	)
	(segment
		(start 58.201306 0.541782)
		(end 58.599324 0.9398)
		(width 0.14224)
		(layer "In11.Cu")
		(net "M_J_DQ<18>")
	)
	(segment
		(start 65.89141 -41.341294)
		(end 65.460118 -40.910002)
		(width 0.14224)
		(layer "In11.Cu")
		(net "M_J_DQ<18>")
	)
	(segment
		(start 64.966088 -39.431468)
		(end 64.966088 -39.21252)
		(width 0.14224)
		(layer "In11.Cu")
		(net "M_J_DQ<18>")
	)
	(segment
		(start 77.492098 -54.200044)
		(end 77.462126 -54.200044)
		(width 0.0889)
		(layer "In11.Cu")
		(net "M_J_DQ<18>")
	)
	(segment
		(start 64.144906 -39.375842)
		(end 63.925958 -39.375842)
		(width 0.14224)
		(layer "In11.Cu")
		(net "M_J_DQ<18>")
	)
	(segment
		(start 58.260996 -29.91739)
		(end 58.106056 -29.76245)
		(width 0.14224)
		(layer "In11.Cu")
		(net "M_J_DQ<18>")
	)
	(segment
		(start 76.626212 -53.704236)
		(end 76.599796 -53.704236)
		(width 0.0889)
		(layer "In11.Cu")
		(net "M_J_DQ<18>")
	)
	(segment
		(start 64.08928 -38.335712)
		(end 62.491112 -36.737544)
		(width 0.14224)
		(layer "In11.Cu")
		(net "M_J_DQ<18>")
	)
	(segment
		(start 63.706502 -39.156386)
		(end 63.706502 -38.937438)
		(width 0.14224)
		(layer "In11.Cu")
		(net "M_J_DQ<18>")
	)
	(segment
		(start 57.506108 -29.371544)
		(end 57.661048 -29.216604)
		(width 0.14224)
		(layer "In11.Cu")
		(net "M_J_DQ<18>")
	)
	(segment
		(start 73.577958 -48.12538)
		(end 73.286874 -48.12538)
		(width 0.0889)
		(layer "In11.Cu")
		(net "M_J_DQ<18>")
	)
	(segment
		(start 57.661048 -29.216604)
		(end 58.106056 -29.216604)
		(width 0.14224)
		(layer "In11.Cu")
		(net "M_J_DQ<18>")
	)
	(segment
		(start 58.138568 -21.23186)
		(end 58.138568 -19.1516)
		(width 0.14224)
		(layer "In11.Cu")
		(net "M_J_DQ<18>")
	)
	(segment
		(start 57.661048 -29.76245)
		(end 57.506108 -29.60751)
		(width 0.14224)
		(layer "In11.Cu")
		(net "M_J_DQ<18>")
	)
	(segment
		(start 58.255662 -23.30831)
		(end 58.090308 -23.142956)
		(width 0.14224)
		(layer "In11.Cu")
		(net "M_J_DQ<18>")
	)
	(segment
		(start 64.966088 -39.21252)
		(end 64.746632 -38.993064)
		(width 0.14224)
		(layer "In11.Cu")
		(net "M_J_DQ<18>")
	)
	(segment
		(start 57.506108 -31.75254)
		(end 57.506108 -30.544516)
		(width 0.14224)
		(layer "In11.Cu")
		(net "M_J_DQ<18>")
	)
	(segment
		(start 58.242708 -19.04746)
		(end 58.242708 -18.570194)
		(width 0.14224)
		(layer "In11.Cu")
		(net "M_J_DQ<18>")
	)
	(segment
		(start 58.260996 -28.814014)
		(end 58.106056 -28.659074)
		(width 0.14224)
		(layer "In11.Cu")
		(net "M_J_DQ<18>")
	)
	(segment
		(start 58.106056 -29.216604)
		(end 58.260996 -29.061664)
		(width 0.14224)
		(layer "In11.Cu")
		(net "M_J_DQ<18>")
	)
	(segment
		(start 64.802766 -40.25265)
		(end 64.58331 -40.033194)
		(width 0.14224)
		(layer "In11.Cu")
		(net "M_J_DQ<18>")
	)
	(segment
		(start 64.746632 -38.993064)
		(end 64.527684 -38.993064)
		(width 0.14224)
		(layer "In11.Cu")
		(net "M_J_DQ<18>")
	)
	(segment
		(start 58.106056 -29.76245)
		(end 57.661048 -29.76245)
		(width 0.14224)
		(layer "In11.Cu")
		(net "M_J_DQ<18>")
	)
	(segment
		(start 58.115708 -18.443194)
		(end 58.115708 -16.966946)
		(width 0.14224)
		(layer "In11.Cu")
		(net "M_J_DQ<18>")
	)
	(segment
		(start 65.021714 -40.25265)
		(end 64.802766 -40.25265)
		(width 0.14224)
		(layer "In11.Cu")
		(net "M_J_DQ<18>")
	)
	(segment
		(start 74.06386 -52.21859)
		(end 74.024236 -52.21859)
		(width 0.0889)
		(layer "In11.Cu")
		(net "M_J_DQ<18>")
	)
	(segment
		(start 58.242708 -21.336)
		(end 58.138568 -21.23186)
		(width 0.14224)
		(layer "In11.Cu")
		(net "M_J_DQ<18>")
	)
	(segment
		(start 58.242708 -18.570194)
		(end 58.115708 -18.443194)
		(width 0.14224)
		(layer "In11.Cu")
		(net "M_J_DQ<18>")
	)
	(segment
		(start 58.090308 -23.142956)
		(end 58.090308 -21.949156)
		(width 0.14224)
		(layer "In11.Cu")
		(net "M_J_DQ<18>")
	)
	(segment
		(start 67.563492 -42.85107)
		(end 67.563492 -41.936924)
		(width 0.14224)
		(layer "In11.Cu")
		(net "M_J_DQ<18>")
	)
	(segment
		(start 80.066388 -55.685436)
		(end 80.033622 -55.685436)
		(width 0.0889)
		(layer "In11.Cu")
		(net "M_J_DQ<18>")
	)
	(segment
		(start 58.331608 -16.751046)
		(end 58.331608 -13.783056)
		(width 0.14224)
		(layer "In11.Cu")
		(net "M_J_DQ<18>")
	)
	(arc
		(start 80.033622 -55.685436)
		(mid 79.750405 -55.601155)
		(end 79.543402 -55.390288)
		(width 0.0889)
		(layer "In11.Cu")
		(net "M_J_DQ<18>")
	)
	(arc
		(start 73.525126 -50.917348)
		(mid 73.454729 -50.628397)
		(end 73.534016 -50.341784)
		(width 0.0889)
		(layer "In11.Cu")
		(net "M_J_DQ<18>")
	)
	(arc
		(start 75.749912 -53.20919)
		(mid 75.461767 -53.126871)
		(end 75.251056 -52.913788)
		(width 0.0889)
		(layer "In11.Cu")
		(net "M_J_DQ<18>")
	)
	(arc
		(start 78.31328 -54.694836)
		(mid 78.03198 -54.60987)
		(end 77.826362 -54.399942)
		(width 0.0889)
		(layer "In11.Cu")
		(net "M_J_DQ<18>")
	)
	(arc
		(start 79.178912 -55.19039)
		(mid 78.893488 -55.106923)
		(end 78.684882 -54.894988)
		(width 0.0889)
		(layer "In11.Cu")
		(net "M_J_DQ<18>")
	)
	(arc
		(start 77.826362 -54.399942)
		(mid 77.685205 -54.256557)
		(end 77.492098 -54.200044)
		(width 0.0889)
		(layer "In11.Cu")
		(net "M_J_DQ<18>")
	)
	(arc
		(start 80.512666 -56.024272)
		(mid 80.452056 -55.959113)
		(end 80.401922 -55.885588)
		(width 0.0889)
		(layer "In11.Cu")
		(net "M_J_DQ<18>")
	)
	(arc
		(start 76.109576 -53.409088)
		(mid 75.969497 -53.266352)
		(end 75.777852 -53.20919)
		(width 0.0889)
		(layer "In11.Cu")
		(net "M_J_DQ<18>")
	)
	(arc
		(start 75.251056 -52.913788)
		(mid 75.112312 -52.771755)
		(end 74.92238 -52.71389)
		(width 0.0889)
		(layer "In11.Cu")
		(net "M_J_DQ<18>")
	)
	(arc
		(start 76.968096 -53.904642)
		(mid 76.823711 -53.759134)
		(end 76.626212 -53.704236)
		(width 0.0889)
		(layer "In11.Cu")
		(net "M_J_DQ<18>")
	)
	(arc
		(start 73.534016 -51.332638)
		(mid 73.587486 -51.137575)
		(end 73.538842 -50.941224)
		(width 0.0889)
		(layer "In11.Cu")
		(net "M_J_DQ<18>")
	)
	(arc
		(start 76.599796 -53.704236)
		(mid 76.316579 -53.619955)
		(end 76.109576 -53.409088)
		(width 0.0889)
		(layer "In11.Cu")
		(net "M_J_DQ<18>")
	)
	(arc
		(start 78.684882 -54.894988)
		(mid 78.543199 -54.751184)
		(end 78.349348 -54.694836)
		(width 0.0889)
		(layer "In11.Cu")
		(net "M_J_DQ<18>")
	)
	(arc
		(start 74.392536 -52.418488)
		(mid 74.253792 -52.276455)
		(end 74.06386 -52.21859)
		(width 0.0889)
		(layer "In11.Cu")
		(net "M_J_DQ<18>")
	)
	(arc
		(start 77.462126 -54.200044)
		(mid 77.176702 -54.116577)
		(end 76.968096 -53.904642)
		(width 0.0889)
		(layer "In11.Cu")
		(net "M_J_DQ<18>")
	)
	(arc
		(start 74.886566 -52.71389)
		(mid 74.601142 -52.630423)
		(end 74.392536 -52.418488)
		(width 0.0889)
		(layer "In11.Cu")
		(net "M_J_DQ<18>")
	)
	(arc
		(start 80.401922 -55.885588)
		(mid 80.260239 -55.741784)
		(end 80.066388 -55.685436)
		(width 0.0889)
		(layer "In11.Cu")
		(net "M_J_DQ<18>")
	)
	(arc
		(start 74.024236 -52.21859)
		(mid 73.528759 -51.914147)
		(end 73.534016 -51.332638)
		(width 0.0889)
		(layer "In11.Cu")
		(net "M_J_DQ<18>")
	)
	(arc
		(start 79.543402 -55.390288)
		(mid 79.403323 -55.247552)
		(end 79.211678 -55.19039)
		(width 0.0889)
		(layer "In11.Cu")
		(net "M_J_DQ<18>")
	)
	(segment
		(start 81.485232 -59.55284)
		(end 80.913732 -59.55284)
		(width 0.0889)
		(layer "F.Cu")
		(net "M_J_DQ<17>")
	)
	(segment
		(start 51.79949 3.778758)
		(end 51.79949 2.514854)
		(width 0.1651)
		(layer "F.Cu")
		(net "M_J_DQ<17>")
	)
	(via
		(at 51.79949 2.514854)
		(size 0.508)
		(drill 0.254)
		(layers "F.Cu" "B.Cu")
		(net "M_J_DQ<17>")
	)
	(via
		(at 80.913732 -59.55284)
		(size 0.508)
		(drill 0.254)
		(layers "F.Cu" "B.Cu")
		(net "M_J_DQ<17>")
	)
	(via
		(at 52.471574 -3.076956)
		(size 0.508)
		(drill 0.254)
		(layers "F.Cu" "B.Cu")
		(net "M_J_DQ<17>")
	)
	(segment
		(start 52.471574 -2.573782)
		(end 52.471574 -3.076956)
		(width 0.1651)
		(layer "B.Cu")
		(net "M_J_DQ<17>")
	)
	(segment
		(start 52.649374 -1.021842)
		(end 52.649374 -2.395982)
		(width 0.1651)
		(layer "B.Cu")
		(net "M_J_DQ<17>")
	)
	(segment
		(start 52.649374 -2.395982)
		(end 52.471574 -2.573782)
		(width 0.1651)
		(layer "B.Cu")
		(net "M_J_DQ<17>")
	)
	(segment
		(start 52.959508 -9.34974)
		(end 52.959508 -6.428994)
		(width 0.14224)
		(layer "In11.Cu")
		(net "M_J_DQ<17>")
	)
	(segment
		(start 68.458842 -50.122074)
		(end 65.937638 -47.60087)
		(width 0.14224)
		(layer "In11.Cu")
		(net "M_J_DQ<17>")
	)
	(segment
		(start 52.271168 -5.740654)
		(end 52.271168 -4.191)
		(width 0.14224)
		(layer "In11.Cu")
		(net "M_J_DQ<17>")
	)
	(segment
		(start 52.271168 -4.191)
		(end 51.945032 -3.864864)
		(width 0.14224)
		(layer "In11.Cu")
		(net "M_J_DQ<17>")
	)
	(segment
		(start 76.63434 -57.476136)
		(end 76.6064 -57.476136)
		(width 0.0889)
		(layer "In11.Cu")
		(net "M_J_DQ<17>")
	)
	(segment
		(start 77.501496 -57.971436)
		(end 77.461872 -57.971436)
		(width 0.0889)
		(layer "In11.Cu")
		(net "M_J_DQ<17>")
	)
	(segment
		(start 51.79949 1.975866)
		(end 51.79949 2.514854)
		(width 0.14224)
		(layer "In11.Cu")
		(net "M_J_DQ<17>")
	)
	(segment
		(start 52.959508 -6.428994)
		(end 52.271168 -5.740654)
		(width 0.14224)
		(layer "In11.Cu")
		(net "M_J_DQ<17>")
	)
	(segment
		(start 74.922126 -56.485536)
		(end 74.88936 -56.485536)
		(width 0.0889)
		(layer "In11.Cu")
		(net "M_J_DQ<17>")
	)
	(segment
		(start 73.205086 -55.494936)
		(end 73.17232 -55.494936)
		(width 0.0889)
		(layer "In11.Cu")
		(net "M_J_DQ<17>")
	)
	(segment
		(start 52.845716 -2.702814)
		(end 52.845716 0.630936)
		(width 0.14224)
		(layer "In11.Cu")
		(net "M_J_DQ<17>")
	)
	(segment
		(start 69.774816 -52.523136)
		(end 69.735192 -52.523136)
		(width 0.0889)
		(layer "In11.Cu")
		(net "M_J_DQ<17>")
	)
	(segment
		(start 79.323692 -58.16219)
		(end 79.049372 -58.16219)
		(width 0.0889)
		(layer "In11.Cu")
		(net "M_J_DQ<17>")
	)
	(segment
		(start 53.109368 -21.199348)
		(end 53.109368 -19.1516)
		(width 0.14224)
		(layer "In11.Cu")
		(net "M_J_DQ<17>")
	)
	(segment
		(start 52.632356 1.4986)
		(end 52.276756 1.4986)
		(width 0.14224)
		(layer "In11.Cu")
		(net "M_J_DQ<17>")
	)
	(segment
		(start 69.214492 -50.999898)
		(end 69.214492 -50.670968)
		(width 0.0889)
		(layer "In11.Cu")
		(net "M_J_DQ<17>")
	)
	(segment
		(start 51.945032 -3.603498)
		(end 52.471574 -3.076956)
		(width 0.14224)
		(layer "In11.Cu")
		(net "M_J_DQ<17>")
	)
	(segment
		(start 53.134768 -9.525)
		(end 52.959508 -9.34974)
		(width 0.14224)
		(layer "In11.Cu")
		(net "M_J_DQ<17>")
	)
	(segment
		(start 51.945032 -3.864864)
		(end 51.945032 -3.603498)
		(width 0.14224)
		(layer "In11.Cu")
		(net "M_J_DQ<17>")
	)
	(segment
		(start 69.406516 -51.332638)
		(end 69.214492 -50.999898)
		(width 0.0889)
		(layer "In11.Cu")
		(net "M_J_DQ<17>")
	)
	(segment
		(start 77.995018 -58.272426)
		(end 77.991716 -58.266584)
		(width 0.0889)
		(layer "In11.Cu")
		(net "M_J_DQ<17>")
	)
	(segment
		(start 72.350376 -54.99989)
		(end 72.31761 -54.99989)
		(width 0.0889)
		(layer "In11.Cu")
		(net "M_J_DQ<17>")
	)
	(segment
		(start 65.937638 -47.60087)
		(end 65.937638 -46.497494)
		(width 0.14224)
		(layer "In11.Cu")
		(net "M_J_DQ<17>")
	)
	(segment
		(start 52.959508 -19.00174)
		(end 52.959508 -11.7348)
		(width 0.14224)
		(layer "In11.Cu")
		(net "M_J_DQ<17>")
	)
	(segment
		(start 53.134768 -11.55954)
		(end 53.134768 -9.525)
		(width 0.14224)
		(layer "In11.Cu")
		(net "M_J_DQ<17>")
	)
	(segment
		(start 52.959508 -11.7348)
		(end 53.134768 -11.55954)
		(width 0.14224)
		(layer "In11.Cu")
		(net "M_J_DQ<17>")
	)
	(segment
		(start 68.665598 -50.122074)
		(end 68.458842 -50.122074)
		(width 0.14224)
		(layer "In11.Cu")
		(net "M_J_DQ<17>")
	)
	(segment
		(start 80.913732 -59.55284)
		(end 80.09128 -59.457336)
		(width 0.0889)
		(layer "In11.Cu")
		(net "M_J_DQ<17>")
	)
	(segment
		(start 53.00218 0.7874)
		(end 53.00218 1.128776)
		(width 0.14224)
		(layer "In11.Cu")
		(net "M_J_DQ<17>")
	)
	(segment
		(start 53.109368 -19.1516)
		(end 52.959508 -19.00174)
		(width 0.14224)
		(layer "In11.Cu")
		(net "M_J_DQ<17>")
	)
	(segment
		(start 70.633336 -54.00929)
		(end 70.60057 -54.00929)
		(width 0.0889)
		(layer "In11.Cu")
		(net "M_J_DQ<17>")
	)
	(segment
		(start 78.356206 -58.466736)
		(end 78.338172 -58.466736)
		(width 0.0889)
		(layer "In11.Cu")
		(net "M_J_DQ<17>")
	)
	(segment
		(start 53.00218 1.128776)
		(end 52.632356 1.4986)
		(width 0.14224)
		(layer "In11.Cu")
		(net "M_J_DQ<17>")
	)
	(segment
		(start 79.596488 -58.454036)
		(end 79.520542 -58.284618)
		(width 0.0889)
		(layer "In11.Cu")
		(net "M_J_DQ<17>")
	)
	(segment
		(start 71.488046 -54.504336)
		(end 71.45528 -54.504336)
		(width 0.0889)
		(layer "In11.Cu")
		(net "M_J_DQ<17>")
	)
	(segment
		(start 79.049372 -58.16219)
		(end 78.636876 -58.333386)
		(width 0.0889)
		(layer "In11.Cu")
		(net "M_J_DQ<17>")
	)
	(segment
		(start 80.09128 -59.457336)
		(end 80.040226 -59.457336)
		(width 0.0889)
		(layer "In11.Cu")
		(net "M_J_DQ<17>")
	)
	(segment
		(start 53.617368 -34.177224)
		(end 53.617368 -27.94)
		(width 0.14224)
		(layer "In11.Cu")
		(net "M_J_DQ<17>")
	)
	(segment
		(start 74.067416 -55.99049)
		(end 74.03465 -55.99049)
		(width 0.0889)
		(layer "In11.Cu")
		(net "M_J_DQ<17>")
	)
	(segment
		(start 52.845716 0.630936)
		(end 53.00218 0.7874)
		(width 0.14224)
		(layer "In11.Cu")
		(net "M_J_DQ<17>")
	)
	(segment
		(start 53.617368 -27.94)
		(end 52.804568 -27.1272)
		(width 0.14224)
		(layer "In11.Cu")
		(net "M_J_DQ<17>")
	)
	(segment
		(start 75.784456 -56.98109)
		(end 75.75169 -56.98109)
		(width 0.0889)
		(layer "In11.Cu")
		(net "M_J_DQ<17>")
	)
	(segment
		(start 79.520542 -58.284618)
		(end 79.412592 -58.217562)
		(width 0.0889)
		(layer "In11.Cu")
		(net "M_J_DQ<17>")
	)
	(segment
		(start 65.937638 -46.497494)
		(end 53.617368 -34.177224)
		(width 0.14224)
		(layer "In11.Cu")
		(net "M_J_DQ<17>")
	)
	(segment
		(start 52.804568 -27.1272)
		(end 52.804568 -24.1046)
		(width 0.14224)
		(layer "In11.Cu")
		(net "M_J_DQ<17>")
	)
	(segment
		(start 52.471574 -3.076956)
		(end 52.845716 -2.702814)
		(width 0.14224)
		(layer "In11.Cu")
		(net "M_J_DQ<17>")
	)
	(segment
		(start 52.276756 1.4986)
		(end 51.79949 1.975866)
		(width 0.14224)
		(layer "In11.Cu")
		(net "M_J_DQ<17>")
	)
	(segment
		(start 52.804568 -24.1046)
		(end 52.959508 -23.94966)
		(width 0.14224)
		(layer "In11.Cu")
		(net "M_J_DQ<17>")
	)
	(segment
		(start 69.214492 -50.670968)
		(end 68.665598 -50.122074)
		(width 0.0889)
		(layer "In11.Cu")
		(net "M_J_DQ<17>")
	)
	(segment
		(start 52.959508 -23.94966)
		(end 52.959508 -21.349208)
		(width 0.14224)
		(layer "In11.Cu")
		(net "M_J_DQ<17>")
	)
	(segment
		(start 52.959508 -21.349208)
		(end 53.109368 -21.199348)
		(width 0.14224)
		(layer "In11.Cu")
		(net "M_J_DQ<17>")
	)
	(segment
		(start 79.412592 -58.217562)
		(end 79.323692 -58.16219)
		(width 0.0889)
		(layer "In11.Cu")
		(net "M_J_DQ<17>")
	)
	(segment
		(start 79.660496 -58.990992)
		(end 79.596488 -58.454036)
		(width 0.0889)
		(layer "In11.Cu")
		(net "M_J_DQ<17>")
	)
	(arc
		(start 74.557636 -56.285638)
		(mid 74.350632 -56.074774)
		(end 74.067416 -55.99049)
		(width 0.0889)
		(layer "In11.Cu")
		(net "M_J_DQ<17>")
	)
	(arc
		(start 80.040226 -59.457336)
		(mid 79.744803 -59.310092)
		(end 79.660496 -58.990992)
		(width 0.0889)
		(layer "In11.Cu")
		(net "M_J_DQ<17>")
	)
	(arc
		(start 75.75169 -56.98109)
		(mid 75.55784 -56.92474)
		(end 75.416156 -56.780938)
		(width 0.0889)
		(layer "In11.Cu")
		(net "M_J_DQ<17>")
	)
	(arc
		(start 70.60057 -54.00929)
		(mid 70.262401 -53.804492)
		(end 70.265036 -53.409088)
		(width 0.0889)
		(layer "In11.Cu")
		(net "M_J_DQ<17>")
	)
	(arc
		(start 77.991716 -58.266584)
		(mid 77.784712 -58.05572)
		(end 77.501496 -57.971436)
		(width 0.0889)
		(layer "In11.Cu")
		(net "M_J_DQ<17>")
	)
	(arc
		(start 73.17232 -55.494936)
		(mid 72.980678 -55.43777)
		(end 72.840596 -55.295038)
		(width 0.0889)
		(layer "In11.Cu")
		(net "M_J_DQ<17>")
	)
	(arc
		(start 78.636876 -58.333386)
		(mid 78.591613 -58.376827)
		(end 78.540102 -58.412634)
		(width 0.0889)
		(layer "In11.Cu")
		(net "M_J_DQ<17>")
	)
	(arc
		(start 69.735192 -52.523136)
		(mid 69.402276 -52.315684)
		(end 69.406516 -51.923442)
		(width 0.0889)
		(layer "In11.Cu")
		(net "M_J_DQ<17>")
	)
	(arc
		(start 70.265036 -53.409088)
		(mid 70.27029 -52.82758)
		(end 69.774816 -52.523136)
		(width 0.0889)
		(layer "In11.Cu")
		(net "M_J_DQ<17>")
	)
	(arc
		(start 78.540102 -58.412634)
		(mid 78.451444 -58.450873)
		(end 78.356206 -58.466736)
		(width 0.0889)
		(layer "In11.Cu")
		(net "M_J_DQ<17>")
	)
	(arc
		(start 76.6064 -57.476136)
		(mid 76.414758 -57.41897)
		(end 76.274676 -57.276238)
		(width 0.0889)
		(layer "In11.Cu")
		(net "M_J_DQ<17>")
	)
	(arc
		(start 72.840596 -55.295038)
		(mid 72.633592 -55.084174)
		(end 72.350376 -54.99989)
		(width 0.0889)
		(layer "In11.Cu")
		(net "M_J_DQ<17>")
	)
	(arc
		(start 71.982076 -54.799738)
		(mid 71.773468 -54.587806)
		(end 71.488046 -54.504336)
		(width 0.0889)
		(layer "In11.Cu")
		(net "M_J_DQ<17>")
	)
	(arc
		(start 74.88936 -56.485536)
		(mid 74.697718 -56.42837)
		(end 74.557636 -56.285638)
		(width 0.0889)
		(layer "In11.Cu")
		(net "M_J_DQ<17>")
	)
	(arc
		(start 77.461872 -57.971436)
		(mid 77.271943 -57.913566)
		(end 77.133196 -57.771538)
		(width 0.0889)
		(layer "In11.Cu")
		(net "M_J_DQ<17>")
	)
	(arc
		(start 69.406516 -51.923442)
		(mid 69.485647 -51.62804)
		(end 69.406516 -51.332638)
		(width 0.0889)
		(layer "In11.Cu")
		(net "M_J_DQ<17>")
	)
	(arc
		(start 77.133196 -57.771538)
		(mid 76.922483 -57.558459)
		(end 76.63434 -57.476136)
		(width 0.0889)
		(layer "In11.Cu")
		(net "M_J_DQ<17>")
	)
	(arc
		(start 71.123556 -54.304438)
		(mid 70.916552 -54.093574)
		(end 70.633336 -54.00929)
		(width 0.0889)
		(layer "In11.Cu")
		(net "M_J_DQ<17>")
	)
	(arc
		(start 71.45528 -54.504336)
		(mid 71.263638 -54.44717)
		(end 71.123556 -54.304438)
		(width 0.0889)
		(layer "In11.Cu")
		(net "M_J_DQ<17>")
	)
	(arc
		(start 76.274676 -57.276238)
		(mid 76.067672 -57.065374)
		(end 75.784456 -56.98109)
		(width 0.0889)
		(layer "In11.Cu")
		(net "M_J_DQ<17>")
	)
	(arc
		(start 72.31761 -54.99989)
		(mid 72.12376 -54.94354)
		(end 71.982076 -54.799738)
		(width 0.0889)
		(layer "In11.Cu")
		(net "M_J_DQ<17>")
	)
	(arc
		(start 73.699116 -55.790338)
		(mid 73.490508 -55.578406)
		(end 73.205086 -55.494936)
		(width 0.0889)
		(layer "In11.Cu")
		(net "M_J_DQ<17>")
	)
	(arc
		(start 74.03465 -55.99049)
		(mid 73.8408 -55.93414)
		(end 73.699116 -55.790338)
		(width 0.0889)
		(layer "In11.Cu")
		(net "M_J_DQ<17>")
	)
	(arc
		(start 75.416156 -56.780938)
		(mid 75.207548 -56.569006)
		(end 74.922126 -56.485536)
		(width 0.0889)
		(layer "In11.Cu")
		(net "M_J_DQ<17>")
	)
	(arc
		(start 78.338172 -58.466736)
		(mid 78.141011 -58.414777)
		(end 77.995018 -58.272426)
		(width 0.0889)
		(layer "In11.Cu")
		(net "M_J_DQ<17>")
	)
	(segment
		(start 52.649374 -0.821182)
		(end 52.471574 1.0414)
		(width 0.1651)
		(layer "F.Cu")
		(net "M_J_DQ<16>")
	)
	(segment
		(start 79.768192 -58.561986)
		(end 79.196692 -58.561986)
		(width 0.0889)
		(layer "F.Cu")
		(net "M_J_DQ<16>")
	)
	(via
		(at 51.79949 -4.357878)
		(size 0.508)
		(drill 0.254)
		(layers "F.Cu" "B.Cu")
		(net "M_J_DQ<16>")
	)
	(via
		(at 52.471574 1.0414)
		(size 0.508)
		(drill 0.254)
		(layers "F.Cu" "B.Cu")
		(net "M_J_DQ<16>")
	)
	(via
		(at 79.196692 -58.561986)
		(size 0.508)
		(drill 0.254)
		(layers "F.Cu" "B.Cu")
		(net "M_J_DQ<16>")
	)
	(segment
		(start 51.79949 -5.621782)
		(end 51.79949 -4.357878)
		(width 0.1651)
		(layer "B.Cu")
		(net "M_J_DQ<16>")
	)
	(segment
		(start 52.251356 0.236728)
		(end 51.836574 -0.178054)
		(width 0.14224)
		(layer "In11.Cu")
		(net "M_J_DQ<16>")
	)
	(segment
		(start 68.246752 -50.757074)
		(end 68.717922 -51.228244)
		(width 0.0889)
		(layer "In11.Cu")
		(net "M_J_DQ<16>")
	)
	(segment
		(start 75.745086 -57.17159)
		(end 75.777852 -57.17159)
		(width 0.0889)
		(layer "In11.Cu")
		(net "M_J_DQ<16>")
	)
	(segment
		(start 51.981608 -13.50264)
		(end 52.324508 -13.84554)
		(width 0.14224)
		(layer "In11.Cu")
		(net "M_J_DQ<16>")
	)
	(segment
		(start 52.118768 -21.1328)
		(end 52.324508 -21.33854)
		(width 0.14224)
		(layer "In11.Cu")
		(net "M_J_DQ<16>")
	)
	(segment
		(start 51.981608 -18.302986)
		(end 52.324508 -18.645886)
		(width 0.14224)
		(layer "In11.Cu")
		(net "M_J_DQ<16>")
	)
	(segment
		(start 51.981608 -12.424156)
		(end 51.981608 -13.50264)
		(width 0.14224)
		(layer "In11.Cu")
		(net "M_J_DQ<16>")
	)
	(segment
		(start 52.251356 -2.5908)
		(end 51.514756 -3.3274)
		(width 0.14224)
		(layer "In11.Cu")
		(net "M_J_DQ<16>")
	)
	(segment
		(start 69.735446 -52.71389)
		(end 69.77126 -52.71389)
		(width 0.0889)
		(layer "In11.Cu")
		(net "M_J_DQ<16>")
	)
	(segment
		(start 63.731648 -46.369732)
		(end 63.731648 -46.58868)
		(width 0.14224)
		(layer "In11.Cu")
		(net "M_J_DQ<16>")
	)
	(segment
		(start 51.836574 -0.178054)
		(end 51.836574 -0.508)
		(width 0.14224)
		(layer "In11.Cu")
		(net "M_J_DQ<16>")
	)
	(segment
		(start 52.118768 -19.1516)
		(end 52.118768 -21.1328)
		(width 0.14224)
		(layer "In11.Cu")
		(net "M_J_DQ<16>")
	)
	(segment
		(start 52.273708 -7.224776)
		(end 51.981608 -7.516876)
		(width 0.14224)
		(layer "In11.Cu")
		(net "M_J_DQ<16>")
	)
	(segment
		(start 52.324508 -21.682456)
		(end 51.981608 -22.025356)
		(width 0.14224)
		(layer "In11.Cu")
		(net "M_J_DQ<16>")
	)
	(segment
		(start 77.458316 -58.16219)
		(end 77.492098 -58.16219)
		(width 0.0889)
		(layer "In11.Cu")
		(net "M_J_DQ<16>")
	)
	(segment
		(start 52.982368 -28.223464)
		(end 52.982368 -34.425128)
		(width 0.14224)
		(layer "In11.Cu")
		(net "M_J_DQ<16>")
	)
	(segment
		(start 74.028046 -56.18099)
		(end 74.060812 -56.18099)
		(width 0.0889)
		(layer "In11.Cu")
		(net "M_J_DQ<16>")
	)
	(segment
		(start 52.251356 0.821182)
		(end 52.251356 0.236728)
		(width 0.14224)
		(layer "In11.Cu")
		(net "M_J_DQ<16>")
	)
	(segment
		(start 64.202056 -46.84014)
		(end 64.690244 -46.351952)
		(width 0.14224)
		(layer "In11.Cu")
		(net "M_J_DQ<16>")
	)
	(segment
		(start 51.981608 -17.123918)
		(end 51.981608 -18.302986)
		(width 0.14224)
		(layer "In11.Cu")
		(net "M_J_DQ<16>")
	)
	(segment
		(start 51.836574 -0.508)
		(end 52.179474 -0.8509)
		(width 0.14224)
		(layer "In11.Cu")
		(net "M_J_DQ<16>")
	)
	(segment
		(start 52.324508 -16.781018)
		(end 51.981608 -17.123918)
		(width 0.14224)
		(layer "In11.Cu")
		(net "M_J_DQ<16>")
	)
	(segment
		(start 52.324508 -21.33854)
		(end 52.324508 -21.682456)
		(width 0.14224)
		(layer "In11.Cu")
		(net "M_J_DQ<16>")
	)
	(segment
		(start 64.219836 -45.881544)
		(end 63.731648 -46.369732)
		(width 0.14224)
		(layer "In11.Cu")
		(net "M_J_DQ<16>")
	)
	(segment
		(start 69.246242 -51.819302)
		(end 69.241416 -51.827938)
		(width 0.0889)
		(layer "In11.Cu")
		(net "M_J_DQ<16>")
	)
	(segment
		(start 52.324508 -13.84554)
		(end 52.324508 -16.781018)
		(width 0.14224)
		(layer "In11.Cu")
		(net "M_J_DQ<16>")
	)
	(segment
		(start 52.271168 -27.512264)
		(end 52.982368 -28.223464)
		(width 0.14224)
		(layer "In11.Cu")
		(net "M_J_DQ<16>")
	)
	(segment
		(start 52.251356 -2.090928)
		(end 52.251356 -2.5908)
		(width 0.14224)
		(layer "In11.Cu")
		(net "M_J_DQ<16>")
	)
	(segment
		(start 51.514756 -3.3274)
		(end 51.514756 -4.073144)
		(width 0.14224)
		(layer "In11.Cu")
		(net "M_J_DQ<16>")
	)
	(segment
		(start 76.608432 -57.66689)
		(end 76.632562 -57.66689)
		(width 0.0889)
		(layer "In11.Cu")
		(net "M_J_DQ<16>")
	)
	(segment
		(start 51.981608 -23.10384)
		(end 52.271168 -23.3934)
		(width 0.14224)
		(layer "In11.Cu")
		(net "M_J_DQ<16>")
	)
	(segment
		(start 70.593966 -54.19979)
		(end 70.626732 -54.19979)
		(width 0.0889)
		(layer "In11.Cu")
		(net "M_J_DQ<16>")
	)
	(segment
		(start 68.717922 -51.228244)
		(end 68.91528 -51.228244)
		(width 0.0889)
		(layer "In11.Cu")
		(net "M_J_DQ<16>")
	)
	(segment
		(start 52.324508 -11.7856)
		(end 52.324508 -12.081256)
		(width 0.14224)
		(layer "In11.Cu")
		(net "M_J_DQ<16>")
	)
	(segment
		(start 52.324508 -9.044686)
		(end 52.324508 -9.34466)
		(width 0.14224)
		(layer "In11.Cu")
		(net "M_J_DQ<16>")
	)
	(segment
		(start 51.861974 -1.701546)
		(end 52.251356 -2.090928)
		(width 0.14224)
		(layer "In11.Cu")
		(net "M_J_DQ<16>")
	)
	(segment
		(start 52.179474 -0.8509)
		(end 52.179474 -1.0795)
		(width 0.14224)
		(layer "In11.Cu")
		(net "M_J_DQ<16>")
	)
	(segment
		(start 74.882756 -56.676036)
		(end 74.915522 -56.676036)
		(width 0.0889)
		(layer "In11.Cu")
		(net "M_J_DQ<16>")
	)
	(segment
		(start 64.219836 -45.662596)
		(end 64.219836 -45.881544)
		(width 0.14224)
		(layer "In11.Cu")
		(net "M_J_DQ<16>")
	)
	(segment
		(start 52.471574 1.0414)
		(end 52.251356 0.821182)
		(width 0.14224)
		(layer "In11.Cu")
		(net "M_J_DQ<16>")
	)
	(segment
		(start 68.195698 -50.757074)
		(end 68.246752 -50.757074)
		(width 0.14224)
		(layer "In11.Cu")
		(net "M_J_DQ<16>")
	)
	(segment
		(start 65.310512 -46.753272)
		(end 65.310512 -46.955456)
		(width 0.14224)
		(layer "In11.Cu")
		(net "M_J_DQ<16>")
	)
	(segment
		(start 52.271168 -23.3934)
		(end 52.271168 -27.512264)
		(width 0.14224)
		(layer "In11.Cu")
		(net "M_J_DQ<16>")
	)
	(segment
		(start 65.310512 -46.955456)
		(end 64.95288 -47.313088)
		(width 0.14224)
		(layer "In11.Cu")
		(net "M_J_DQ<16>")
	)
	(segment
		(start 71.448676 -54.694836)
		(end 71.481442 -54.694836)
		(width 0.0889)
		(layer "In11.Cu")
		(net "M_J_DQ<16>")
	)
	(segment
		(start 63.983108 -46.84014)
		(end 64.202056 -46.84014)
		(width 0.14224)
		(layer "In11.Cu")
		(net "M_J_DQ<16>")
	)
	(segment
		(start 64.909192 -46.351952)
		(end 65.310512 -46.753272)
		(width 0.14224)
		(layer "In11.Cu")
		(net "M_J_DQ<16>")
	)
	(segment
		(start 52.324508 -18.94586)
		(end 52.118768 -19.1516)
		(width 0.14224)
		(layer "In11.Cu")
		(net "M_J_DQ<16>")
	)
	(segment
		(start 51.981608 -22.025356)
		(end 51.981608 -23.10384)
		(width 0.14224)
		(layer "In11.Cu")
		(net "M_J_DQ<16>")
	)
	(segment
		(start 52.169568 -9.4996)
		(end 52.169568 -11.63066)
		(width 0.14224)
		(layer "In11.Cu")
		(net "M_J_DQ<16>")
	)
	(segment
		(start 52.273708 -6.682486)
		(end 52.273708 -7.224776)
		(width 0.14224)
		(layer "In11.Cu")
		(net "M_J_DQ<16>")
	)
	(segment
		(start 64.95288 -47.514256)
		(end 68.195698 -50.757074)
		(width 0.14224)
		(layer "In11.Cu")
		(net "M_J_DQ<16>")
	)
	(segment
		(start 64.95288 -47.313088)
		(end 64.95288 -47.514256)
		(width 0.14224)
		(layer "In11.Cu")
		(net "M_J_DQ<16>")
	)
	(segment
		(start 52.179474 -1.0795)
		(end 51.861974 -1.397)
		(width 0.14224)
		(layer "In11.Cu")
		(net "M_J_DQ<16>")
	)
	(segment
		(start 78.320392 -58.65749)
		(end 78.688946 -58.65749)
		(width 0.0889)
		(layer "In11.Cu")
		(net "M_J_DQ<16>")
	)
	(segment
		(start 78.688946 -58.65749)
		(end 79.164688 -58.602118)
		(width 0.0889)
		(layer "In11.Cu")
		(net "M_J_DQ<16>")
	)
	(segment
		(start 72.311006 -55.19039)
		(end 72.343772 -55.19039)
		(width 0.0889)
		(layer "In11.Cu")
		(net "M_J_DQ<16>")
	)
	(segment
		(start 52.324508 -12.081256)
		(end 51.981608 -12.424156)
		(width 0.14224)
		(layer "In11.Cu")
		(net "M_J_DQ<16>")
	)
	(segment
		(start 73.165716 -55.685436)
		(end 73.198482 -55.685436)
		(width 0.0889)
		(layer "In11.Cu")
		(net "M_J_DQ<16>")
	)
	(segment
		(start 51.79949 -6.208268)
		(end 52.273708 -6.682486)
		(width 0.14224)
		(layer "In11.Cu")
		(net "M_J_DQ<16>")
	)
	(segment
		(start 52.982368 -34.425128)
		(end 64.219836 -45.662596)
		(width 0.14224)
		(layer "In11.Cu")
		(net "M_J_DQ<16>")
	)
	(segment
		(start 51.981608 -7.516876)
		(end 51.981608 -8.701786)
		(width 0.14224)
		(layer "In11.Cu")
		(net "M_J_DQ<16>")
	)
	(segment
		(start 51.981608 -8.701786)
		(end 52.324508 -9.044686)
		(width 0.14224)
		(layer "In11.Cu")
		(net "M_J_DQ<16>")
	)
	(segment
		(start 51.79949 -4.357878)
		(end 51.79949 -6.208268)
		(width 0.14224)
		(layer "In11.Cu")
		(net "M_J_DQ<16>")
	)
	(segment
		(start 64.690244 -46.351952)
		(end 64.909192 -46.351952)
		(width 0.14224)
		(layer "In11.Cu")
		(net "M_J_DQ<16>")
	)
	(segment
		(start 52.169568 -11.63066)
		(end 52.324508 -11.7856)
		(width 0.14224)
		(layer "In11.Cu")
		(net "M_J_DQ<16>")
	)
	(segment
		(start 51.861974 -1.397)
		(end 51.861974 -1.701546)
		(width 0.14224)
		(layer "In11.Cu")
		(net "M_J_DQ<16>")
	)
	(segment
		(start 52.324508 -18.645886)
		(end 52.324508 -18.94586)
		(width 0.14224)
		(layer "In11.Cu")
		(net "M_J_DQ<16>")
	)
	(segment
		(start 63.731648 -46.58868)
		(end 63.983108 -46.84014)
		(width 0.14224)
		(layer "In11.Cu")
		(net "M_J_DQ<16>")
	)
	(segment
		(start 51.514756 -4.073144)
		(end 51.79949 -4.357878)
		(width 0.14224)
		(layer "In11.Cu")
		(net "M_J_DQ<16>")
	)
	(segment
		(start 79.164688 -58.602118)
		(end 79.196692 -58.561986)
		(width 0.0889)
		(layer "In11.Cu")
		(net "M_J_DQ<16>")
	)
	(segment
		(start 52.324508 -9.34466)
		(end 52.169568 -9.4996)
		(width 0.14224)
		(layer "In11.Cu")
		(net "M_J_DQ<16>")
	)
	(arc
		(start 73.198482 -55.685436)
		(mid 73.392332 -55.741786)
		(end 73.534016 -55.885588)
		(width 0.0889)
		(layer "In11.Cu")
		(net "M_J_DQ<16>")
	)
	(arc
		(start 72.343772 -55.19039)
		(mid 72.535414 -55.247556)
		(end 72.675496 -55.390288)
		(width 0.0889)
		(layer "In11.Cu")
		(net "M_J_DQ<16>")
	)
	(arc
		(start 75.777852 -57.17159)
		(mid 75.969494 -57.228756)
		(end 76.109576 -57.371488)
		(width 0.0889)
		(layer "In11.Cu")
		(net "M_J_DQ<16>")
	)
	(arc
		(start 70.099936 -53.313838)
		(mid 70.095607 -53.89701)
		(end 70.593966 -54.19979)
		(width 0.0889)
		(layer "In11.Cu")
		(net "M_J_DQ<16>")
	)
	(arc
		(start 74.392536 -56.380888)
		(mid 74.59954 -56.591752)
		(end 74.882756 -56.676036)
		(width 0.0889)
		(layer "In11.Cu")
		(net "M_J_DQ<16>")
	)
	(arc
		(start 74.915522 -56.676036)
		(mid 75.109372 -56.732386)
		(end 75.251056 -56.876188)
		(width 0.0889)
		(layer "In11.Cu")
		(net "M_J_DQ<16>")
	)
	(arc
		(start 76.968096 -57.867042)
		(mid 77.1751 -58.077906)
		(end 77.458316 -58.16219)
		(width 0.0889)
		(layer "In11.Cu")
		(net "M_J_DQ<16>")
	)
	(arc
		(start 75.251056 -56.876188)
		(mid 75.459664 -57.08812)
		(end 75.745086 -57.17159)
		(width 0.0889)
		(layer "In11.Cu")
		(net "M_J_DQ<16>")
	)
	(arc
		(start 69.241416 -51.827938)
		(mid 69.237087 -52.41111)
		(end 69.735446 -52.71389)
		(width 0.0889)
		(layer "In11.Cu")
		(net "M_J_DQ<16>")
	)
	(arc
		(start 72.675496 -55.390288)
		(mid 72.8825 -55.601152)
		(end 73.165716 -55.685436)
		(width 0.0889)
		(layer "In11.Cu")
		(net "M_J_DQ<16>")
	)
	(arc
		(start 71.481442 -54.694836)
		(mid 71.675292 -54.751186)
		(end 71.816976 -54.894988)
		(width 0.0889)
		(layer "In11.Cu")
		(net "M_J_DQ<16>")
	)
	(arc
		(start 74.060812 -56.18099)
		(mid 74.252454 -56.238156)
		(end 74.392536 -56.380888)
		(width 0.0889)
		(layer "In11.Cu")
		(net "M_J_DQ<16>")
	)
	(arc
		(start 73.534016 -55.885588)
		(mid 73.742624 -56.09752)
		(end 74.028046 -56.18099)
		(width 0.0889)
		(layer "In11.Cu")
		(net "M_J_DQ<16>")
	)
	(arc
		(start 68.91528 -51.228244)
		(mid 69.24398 -51.432419)
		(end 69.246242 -51.819302)
		(width 0.0889)
		(layer "In11.Cu")
		(net "M_J_DQ<16>")
	)
	(arc
		(start 76.632562 -57.66689)
		(mid 76.826412 -57.72324)
		(end 76.968096 -57.867042)
		(width 0.0889)
		(layer "In11.Cu")
		(net "M_J_DQ<16>")
	)
	(arc
		(start 76.109576 -57.371488)
		(mid 76.320289 -57.584567)
		(end 76.608432 -57.66689)
		(width 0.0889)
		(layer "In11.Cu")
		(net "M_J_DQ<16>")
	)
	(arc
		(start 71.816976 -54.894988)
		(mid 72.025584 -55.10692)
		(end 72.311006 -55.19039)
		(width 0.0889)
		(layer "In11.Cu")
		(net "M_J_DQ<16>")
	)
	(arc
		(start 69.77126 -52.71389)
		(mid 70.104229 -52.921438)
		(end 70.099936 -53.313838)
		(width 0.0889)
		(layer "In11.Cu")
		(net "M_J_DQ<16>")
	)
	(arc
		(start 70.626732 -54.19979)
		(mid 70.818374 -54.256956)
		(end 70.958456 -54.399688)
		(width 0.0889)
		(layer "In11.Cu")
		(net "M_J_DQ<16>")
	)
	(arc
		(start 70.958456 -54.399688)
		(mid 71.16546 -54.610552)
		(end 71.448676 -54.694836)
		(width 0.0889)
		(layer "In11.Cu")
		(net "M_J_DQ<16>")
	)
	(arc
		(start 77.826362 -58.362088)
		(mid 78.03497 -58.57402)
		(end 78.320392 -58.65749)
		(width 0.0889)
		(layer "In11.Cu")
		(net "M_J_DQ<16>")
	)
	(arc
		(start 77.492098 -58.16219)
		(mid 77.685201 -58.218709)
		(end 77.826362 -58.362088)
		(width 0.0889)
		(layer "In11.Cu")
		(net "M_J_DQ<16>")
	)
	(segment
		(start 46.699424 3.778758)
		(end 46.699424 2.514854)
		(width 0.1651)
		(layer "F.Cu")
		(net "M_J_DQ<15>")
	)
	(segment
		(start 77.192886 -59.057286)
		(end 76.621386 -59.057286)
		(width 0.0889)
		(layer "F.Cu")
		(net "M_J_DQ<15>")
	)
	(via
		(at 47.549308 -3.076956)
		(size 0.508)
		(drill 0.254)
		(layers "F.Cu" "B.Cu")
		(net "M_J_DQ<15>")
	)
	(via
		(at 46.699424 2.514854)
		(size 0.508)
		(drill 0.254)
		(layers "F.Cu" "B.Cu")
		(net "M_J_DQ<15>")
	)
	(via
		(at 76.621386 -59.057286)
		(size 0.508)
		(drill 0.254)
		(layers "F.Cu" "B.Cu")
		(net "M_J_DQ<15>")
	)
	(segment
		(start 47.549562 -1.021842)
		(end 47.549308 -1.022096)
		(width 0.1651)
		(layer "B.Cu")
		(net "M_J_DQ<15>")
	)
	(segment
		(start 47.549308 -1.022096)
		(end 47.549308 -3.076956)
		(width 0.1651)
		(layer "B.Cu")
		(net "M_J_DQ<15>")
	)
	(segment
		(start 47.902114 -18.593054)
		(end 48.130714 -18.364454)
		(width 0.14224)
		(layer "In11.Cu")
		(net "M_J_DQ<15>")
	)
	(segment
		(start 48.057562 1.0922)
		(end 47.600362 1.5494)
		(width 0.14224)
		(layer "In11.Cu")
		(net "M_J_DQ<15>")
	)
	(segment
		(start 48.156368 -33.2994)
		(end 47.953168 -33.5026)
		(width 0.14224)
		(layer "In11.Cu")
		(net "M_J_DQ<15>")
	)
	(segment
		(start 47.927514 -7.289546)
		(end 47.927514 -5.252212)
		(width 0.14224)
		(layer "In11.Cu")
		(net "M_J_DQ<15>")
	)
	(segment
		(start 47.953168 -33.5026)
		(end 47.546768 -33.5026)
		(width 0.14224)
		(layer "In11.Cu")
		(net "M_J_DQ<15>")
	)
	(segment
		(start 48.130714 -17.093946)
		(end 47.927514 -16.890746)
		(width 0.14224)
		(layer "In11.Cu")
		(net "M_J_DQ<15>")
	)
	(segment
		(start 47.089314 -4.067556)
		(end 47.089314 -3.53695)
		(width 0.14224)
		(layer "In11.Cu")
		(net "M_J_DQ<15>")
	)
	(segment
		(start 48.130714 -18.364454)
		(end 48.130714 -17.093946)
		(width 0.14224)
		(layer "In11.Cu")
		(net "M_J_DQ<15>")
	)
	(segment
		(start 48.054768 -19.177)
		(end 47.902114 -19.024346)
		(width 0.14224)
		(layer "In11.Cu")
		(net "M_J_DQ<15>")
	)
	(segment
		(start 48.359568 -30.353)
		(end 48.156368 -30.5562)
		(width 0.14224)
		(layer "In11.Cu")
		(net "M_J_DQ<15>")
	)
	(segment
		(start 74.05878 -58.962036)
		(end 74.03465 -58.962036)
		(width 0.0889)
		(layer "In11.Cu")
		(net "M_J_DQ<15>")
	)
	(segment
		(start 75.23861 -59.388248)
		(end 75.03287 -59.457336)
		(width 0.0889)
		(layer "In11.Cu")
		(net "M_J_DQ<15>")
	)
	(segment
		(start 47.457614 -4.435856)
		(end 47.089314 -4.067556)
		(width 0.14224)
		(layer "In11.Cu")
		(net "M_J_DQ<15>")
	)
	(segment
		(start 47.902114 -12.170156)
		(end 47.902114 -11.709654)
		(width 0.14224)
		(layer "In11.Cu")
		(net "M_J_DQ<15>")
	)
	(segment
		(start 70.633336 -56.98109)
		(end 70.60057 -56.98109)
		(width 0.0889)
		(layer "In11.Cu")
		(net "M_J_DQ<15>")
	)
	(segment
		(start 48.003968 -11.6078)
		(end 48.003968 -9.576054)
		(width 0.14224)
		(layer "In11.Cu")
		(net "M_J_DQ<15>")
	)
	(segment
		(start 47.902114 0.581152)
		(end 48.057562 0.7366)
		(width 0.14224)
		(layer "In11.Cu")
		(net "M_J_DQ<15>")
	)
	(segment
		(start 48.105314 -12.373356)
		(end 47.902114 -12.170156)
		(width 0.14224)
		(layer "In11.Cu")
		(net "M_J_DQ<15>")
	)
	(segment
		(start 69.12356 -56.485536)
		(end 67.466718 -54.828694)
		(width 0.0889)
		(layer "In11.Cu")
		(net "M_J_DQ<15>")
	)
	(segment
		(start 67.466718 -54.828694)
		(end 67.019424 -54.828694)
		(width 0.0889)
		(layer "In11.Cu")
		(net "M_J_DQ<15>")
	)
	(segment
		(start 47.927514 -16.890746)
		(end 47.927514 -13.694156)
		(width 0.14224)
		(layer "In11.Cu")
		(net "M_J_DQ<15>")
	)
	(segment
		(start 73.208896 -58.466736)
		(end 73.169272 -58.466736)
		(width 0.0889)
		(layer "In11.Cu")
		(net "M_J_DQ<15>")
	)
	(segment
		(start 55.77713 -43.329098)
		(end 48.969168 -36.521136)
		(width 0.14224)
		(layer "In11.Cu")
		(net "M_J_DQ<15>")
	)
	(segment
		(start 48.156368 -30.5562)
		(end 48.156368 -33.2994)
		(width 0.14224)
		(layer "In11.Cu")
		(net "M_J_DQ<15>")
	)
	(segment
		(start 72.346566 -57.971436)
		(end 72.310752 -57.971436)
		(width 0.0889)
		(layer "In11.Cu")
		(net "M_J_DQ<15>")
	)
	(segment
		(start 76.621386 -59.057286)
		(end 75.79741 -59.15279)
		(width 0.0889)
		(layer "In11.Cu")
		(net "M_J_DQ<15>")
	)
	(segment
		(start 47.927514 -13.694156)
		(end 48.105314 -13.516356)
		(width 0.14224)
		(layer "In11.Cu")
		(net "M_J_DQ<15>")
	)
	(segment
		(start 47.549308 -3.076956)
		(end 47.902114 -2.72415)
		(width 0.14224)
		(layer "In11.Cu")
		(net "M_J_DQ<15>")
	)
	(segment
		(start 47.902114 -21.3614)
		(end 48.054768 -21.208746)
		(width 0.14224)
		(layer "In11.Cu")
		(net "M_J_DQ<15>")
	)
	(segment
		(start 48.969168 -30.5562)
		(end 48.765968 -30.353)
		(width 0.14224)
		(layer "In11.Cu")
		(net "M_J_DQ<15>")
	)
	(segment
		(start 55.77713 -44.603162)
		(end 55.77713 -43.329098)
		(width 0.14224)
		(layer "In11.Cu")
		(net "M_J_DQ<15>")
	)
	(segment
		(start 47.343568 -28.041854)
		(end 47.927514 -27.457908)
		(width 0.14224)
		(layer "In11.Cu")
		(net "M_J_DQ<15>")
	)
	(segment
		(start 65.46215 -54.567582)
		(end 64.107568 -53.213)
		(width 0.14224)
		(layer "In11.Cu")
		(net "M_J_DQ<15>")
	)
	(segment
		(start 48.765968 -30.353)
		(end 48.359568 -30.353)
		(width 0.14224)
		(layer "In11.Cu")
		(net "M_J_DQ<15>")
	)
	(segment
		(start 48.105314 -23.117556)
		(end 48.105314 -21.974556)
		(width 0.14224)
		(layer "In11.Cu")
		(net "M_J_DQ<15>")
	)
	(segment
		(start 48.130714 -7.492746)
		(end 47.927514 -7.289546)
		(width 0.14224)
		(layer "In11.Cu")
		(net "M_J_DQ<15>")
	)
	(segment
		(start 47.902114 -11.709654)
		(end 48.003968 -11.6078)
		(width 0.14224)
		(layer "In11.Cu")
		(net "M_J_DQ<15>")
	)
	(segment
		(start 47.600362 1.5494)
		(end 47.346362 1.5494)
		(width 0.14224)
		(layer "In11.Cu")
		(net "M_J_DQ<15>")
	)
	(segment
		(start 47.902114 -8.966454)
		(end 48.130714 -8.737854)
		(width 0.14224)
		(layer "In11.Cu")
		(net "M_J_DQ<15>")
	)
	(segment
		(start 71.48322 -57.476136)
		(end 71.45528 -57.476136)
		(width 0.0889)
		(layer "In11.Cu")
		(net "M_J_DQ<15>")
	)
	(segment
		(start 75.03287 -59.457336)
		(end 74.88936 -59.457336)
		(width 0.0889)
		(layer "In11.Cu")
		(net "M_J_DQ<15>")
	)
	(segment
		(start 48.003968 -9.576054)
		(end 47.902114 -9.4742)
		(width 0.14224)
		(layer "In11.Cu")
		(net "M_J_DQ<15>")
	)
	(segment
		(start 47.902114 -2.72415)
		(end 47.902114 0.581152)
		(width 0.14224)
		(layer "In11.Cu")
		(net "M_J_DQ<15>")
	)
	(segment
		(start 48.105314 -13.516356)
		(end 48.105314 -12.373356)
		(width 0.14224)
		(layer "In11.Cu")
		(net "M_J_DQ<15>")
	)
	(segment
		(start 47.927514 -27.457908)
		(end 47.927514 -23.295356)
		(width 0.14224)
		(layer "In11.Cu")
		(net "M_J_DQ<15>")
	)
	(segment
		(start 47.902114 -21.771356)
		(end 47.902114 -21.3614)
		(width 0.14224)
		(layer "In11.Cu")
		(net "M_J_DQ<15>")
	)
	(segment
		(start 48.054768 -21.208746)
		(end 48.054768 -19.177)
		(width 0.14224)
		(layer "In11.Cu")
		(net "M_J_DQ<15>")
	)
	(segment
		(start 47.089314 -3.53695)
		(end 47.549308 -3.076956)
		(width 0.14224)
		(layer "In11.Cu")
		(net "M_J_DQ<15>")
	)
	(segment
		(start 64.107568 -53.213)
		(end 64.107568 -52.9336)
		(width 0.14224)
		(layer "In11.Cu")
		(net "M_J_DQ<15>")
	)
	(segment
		(start 48.969168 -36.521136)
		(end 48.969168 -30.5562)
		(width 0.14224)
		(layer "In11.Cu")
		(net "M_J_DQ<15>")
	)
	(segment
		(start 66.758312 -54.567582)
		(end 65.46215 -54.567582)
		(width 0.14224)
		(layer "In11.Cu")
		(net "M_J_DQ<15>")
	)
	(segment
		(start 47.546768 -33.5026)
		(end 47.343568 -33.2994)
		(width 0.14224)
		(layer "In11.Cu")
		(net "M_J_DQ<15>")
	)
	(segment
		(start 47.346362 1.5494)
		(end 47.016162 1.8796)
		(width 0.14224)
		(layer "In11.Cu")
		(net "M_J_DQ<15>")
	)
	(segment
		(start 47.016162 2.198116)
		(end 46.699424 2.514854)
		(width 0.14224)
		(layer "In11.Cu")
		(net "M_J_DQ<15>")
	)
	(segment
		(start 47.902114 -9.4742)
		(end 47.902114 -8.966454)
		(width 0.14224)
		(layer "In11.Cu")
		(net "M_J_DQ<15>")
	)
	(segment
		(start 47.927514 -5.252212)
		(end 47.457614 -4.782312)
		(width 0.14224)
		(layer "In11.Cu")
		(net "M_J_DQ<15>")
	)
	(segment
		(start 47.343568 -33.2994)
		(end 47.343568 -28.041854)
		(width 0.14224)
		(layer "In11.Cu")
		(net "M_J_DQ<15>")
	)
	(segment
		(start 47.016162 1.8796)
		(end 47.016162 2.198116)
		(width 0.14224)
		(layer "In11.Cu")
		(net "M_J_DQ<15>")
	)
	(segment
		(start 75.79741 -59.15279)
		(end 75.74788 -59.15279)
		(width 0.0889)
		(layer "In11.Cu")
		(net "M_J_DQ<15>")
	)
	(segment
		(start 48.057562 0.7366)
		(end 48.057562 1.0922)
		(width 0.14224)
		(layer "In11.Cu")
		(net "M_J_DQ<15>")
	)
	(segment
		(start 75.502262 -59.248802)
		(end 75.23861 -59.388248)
		(width 0.0889)
		(layer "In11.Cu")
		(net "M_J_DQ<15>")
	)
	(segment
		(start 47.457614 -4.782312)
		(end 47.457614 -4.435856)
		(width 0.14224)
		(layer "In11.Cu")
		(net "M_J_DQ<15>")
	)
	(segment
		(start 47.902114 -19.024346)
		(end 47.902114 -18.593054)
		(width 0.14224)
		(layer "In11.Cu")
		(net "M_J_DQ<15>")
	)
	(segment
		(start 47.927514 -23.295356)
		(end 48.105314 -23.117556)
		(width 0.14224)
		(layer "In11.Cu")
		(net "M_J_DQ<15>")
	)
	(segment
		(start 48.105314 -21.974556)
		(end 47.902114 -21.771356)
		(width 0.14224)
		(layer "In11.Cu")
		(net "M_J_DQ<15>")
	)
	(segment
		(start 67.019424 -54.828694)
		(end 66.758312 -54.567582)
		(width 0.0889)
		(layer "In11.Cu")
		(net "M_J_DQ<15>")
	)
	(segment
		(start 64.107568 -52.9336)
		(end 55.77713 -44.603162)
		(width 0.14224)
		(layer "In11.Cu")
		(net "M_J_DQ<15>")
	)
	(segment
		(start 69.771006 -56.485536)
		(end 69.12356 -56.485536)
		(width 0.0889)
		(layer "In11.Cu")
		(net "M_J_DQ<15>")
	)
	(segment
		(start 48.130714 -8.737854)
		(end 48.130714 -7.492746)
		(width 0.14224)
		(layer "In11.Cu")
		(net "M_J_DQ<15>")
	)
	(arc
		(start 71.45528 -57.476136)
		(mid 71.263638 -57.41897)
		(end 71.123556 -57.276238)
		(width 0.0889)
		(layer "In11.Cu")
		(net "M_J_DQ<15>")
	)
	(arc
		(start 71.982076 -57.771538)
		(mid 71.771363 -57.558459)
		(end 71.48322 -57.476136)
		(width 0.0889)
		(layer "In11.Cu")
		(net "M_J_DQ<15>")
	)
	(arc
		(start 70.60057 -56.98109)
		(mid 70.40672 -56.92474)
		(end 70.265036 -56.780938)
		(width 0.0889)
		(layer "In11.Cu")
		(net "M_J_DQ<15>")
	)
	(arc
		(start 73.169272 -58.466736)
		(mid 72.979343 -58.408866)
		(end 72.840596 -58.266838)
		(width 0.0889)
		(layer "In11.Cu")
		(net "M_J_DQ<15>")
	)
	(arc
		(start 71.123556 -57.276238)
		(mid 70.916552 -57.065374)
		(end 70.633336 -56.98109)
		(width 0.0889)
		(layer "In11.Cu")
		(net "M_J_DQ<15>")
	)
	(arc
		(start 70.265036 -56.780938)
		(mid 70.056428 -56.569006)
		(end 69.771006 -56.485536)
		(width 0.0889)
		(layer "In11.Cu")
		(net "M_J_DQ<15>")
	)
	(arc
		(start 75.74788 -59.15279)
		(mid 75.616926 -59.179969)
		(end 75.502262 -59.248802)
		(width 0.0889)
		(layer "In11.Cu")
		(net "M_J_DQ<15>")
	)
	(arc
		(start 72.840596 -58.266838)
		(mid 72.631988 -58.054906)
		(end 72.346566 -57.971436)
		(width 0.0889)
		(layer "In11.Cu")
		(net "M_J_DQ<15>")
	)
	(arc
		(start 74.03465 -58.962036)
		(mid 73.8408 -58.905686)
		(end 73.699116 -58.761884)
		(width 0.0889)
		(layer "In11.Cu")
		(net "M_J_DQ<15>")
	)
	(arc
		(start 72.310752 -57.971436)
		(mid 72.120823 -57.913566)
		(end 71.982076 -57.771538)
		(width 0.0889)
		(layer "In11.Cu")
		(net "M_J_DQ<15>")
	)
	(arc
		(start 74.557636 -59.257438)
		(mid 74.346923 -59.044359)
		(end 74.05878 -58.962036)
		(width 0.0889)
		(layer "In11.Cu")
		(net "M_J_DQ<15>")
	)
	(arc
		(start 73.699116 -58.761884)
		(mid 73.492112 -58.55102)
		(end 73.208896 -58.466736)
		(width 0.0889)
		(layer "In11.Cu")
		(net "M_J_DQ<15>")
	)
	(arc
		(start 74.88936 -59.457336)
		(mid 74.697718 -59.40017)
		(end 74.557636 -59.257438)
		(width 0.0889)
		(layer "In11.Cu")
		(net "M_J_DQ<15>")
	)
	(segment
		(start 47.549562 0.939546)
		(end 47.549308 0.9398)
		(width 0.1651)
		(layer "F.Cu")
		(net "M_J_DQ<14>")
	)
	(segment
		(start 47.549562 0.635)
		(end 47.549562 0.939546)
		(width 0.1651)
		(layer "F.Cu")
		(net "M_J_DQ<14>")
	)
	(segment
		(start 75.475846 -60.047886)
		(end 74.904346 -60.047886)
		(width 0.0889)
		(layer "F.Cu")
		(net "M_J_DQ<14>")
	)
	(segment
		(start 47.549562 -0.821182)
		(end 47.549562 0.1524)
		(width 0.1651)
		(layer "F.Cu")
		(net "M_J_DQ<14>")
	)
	(segment
		(start 47.681642 0.50292)
		(end 47.549562 0.635)
		(width 0.1651)
		(layer "F.Cu")
		(net "M_J_DQ<14>")
	)
	(segment
		(start 47.549562 0.1524)
		(end 47.681642 0.28448)
		(width 0.1651)
		(layer "F.Cu")
		(net "M_J_DQ<14>")
	)
	(segment
		(start 47.681642 0.28448)
		(end 47.681642 0.50292)
		(width 0.1651)
		(layer "F.Cu")
		(net "M_J_DQ<14>")
	)
	(via
		(at 46.699424 -4.357878)
		(size 0.508)
		(drill 0.254)
		(layers "F.Cu" "B.Cu")
		(net "M_J_DQ<14>")
	)
	(via
		(at 47.549308 0.9398)
		(size 0.508)
		(drill 0.254)
		(layers "F.Cu" "B.Cu")
		(net "M_J_DQ<14>")
	)
	(via
		(at 74.904346 -60.047886)
		(size 0.508)
		(drill 0.254)
		(layers "F.Cu" "B.Cu")
		(net "M_J_DQ<14>")
	)
	(segment
		(start 46.699424 -5.621782)
		(end 46.699424 -4.357878)
		(width 0.1651)
		(layer "B.Cu")
		(net "M_J_DQ<14>")
	)
	(segment
		(start 47.23638 -2.203196)
		(end 46.81093 -1.777746)
		(width 0.14224)
		(layer "In11.Cu")
		(net "M_J_DQ<14>")
	)
	(segment
		(start 47.165514 -27.076908)
		(end 47.165514 -23.269956)
		(width 0.14224)
		(layer "In11.Cu")
		(net "M_J_DQ<14>")
	)
	(segment
		(start 46.759368 -28.958286)
		(end 46.759368 -28.551886)
		(width 0.14224)
		(layer "In11.Cu")
		(net "M_J_DQ<14>")
	)
	(segment
		(start 47.267114 -18.643346)
		(end 47.063914 -18.440146)
		(width 0.14224)
		(layer "In11.Cu")
		(net "M_J_DQ<14>")
	)
	(segment
		(start 71.481442 -57.66689)
		(end 71.457312 -57.66689)
		(width 0.0889)
		(layer "In11.Cu")
		(net "M_J_DQ<14>")
	)
	(segment
		(start 46.911768 -36.3982)
		(end 46.708568 -36.195)
		(width 0.14224)
		(layer "In11.Cu")
		(net "M_J_DQ<14>")
	)
	(segment
		(start 47.267114 -19.024854)
		(end 47.267114 -18.643346)
		(width 0.14224)
		(layer "In11.Cu")
		(net "M_J_DQ<14>")
	)
	(segment
		(start 47.267114 -21.3868)
		(end 47.114968 -21.234654)
		(width 0.14224)
		(layer "In11.Cu")
		(net "M_J_DQ<14>")
	)
	(segment
		(start 47.114968 -21.234654)
		(end 47.114968 -19.177)
		(width 0.14224)
		(layer "In11.Cu")
		(net "M_J_DQ<14>")
	)
	(segment
		(start 49.192942 -38.605206)
		(end 48.991774 -38.605206)
		(width 0.14224)
		(layer "In11.Cu")
		(net "M_J_DQ<14>")
	)
	(segment
		(start 47.267114 -12.170156)
		(end 47.267114 -11.759946)
		(width 0.14224)
		(layer "In11.Cu")
		(net "M_J_DQ<14>")
	)
	(segment
		(start 47.267114 -21.771356)
		(end 47.267114 -21.3868)
		(width 0.14224)
		(layer "In11.Cu")
		(net "M_J_DQ<14>")
	)
	(segment
		(start 69.764402 -56.676036)
		(end 69.044566 -56.676036)
		(width 0.0889)
		(layer "In11.Cu")
		(net "M_J_DQ<14>")
	)
	(segment
		(start 47.267114 -9.398)
		(end 47.267114 -9.067546)
		(width 0.14224)
		(layer "In11.Cu")
		(net "M_J_DQ<14>")
	)
	(segment
		(start 54.46268 -43.012868)
		(end 49.724564 -38.274752)
		(width 0.14224)
		(layer "In11.Cu")
		(net "M_J_DQ<14>")
	)
	(segment
		(start 49.063402 -37.814758)
		(end 49.063402 -37.61359)
		(width 0.14224)
		(layer "In11.Cu")
		(net "M_J_DQ<14>")
	)
	(segment
		(start 46.81093 -0.387096)
		(end 46.81093 -0.076454)
		(width 0.14224)
		(layer "In11.Cu")
		(net "M_J_DQ<14>")
	)
	(segment
		(start 48.130968 -34.2138)
		(end 47.724568 -34.2138)
		(width 0.14224)
		(layer "In11.Cu")
		(net "M_J_DQ<14>")
	)
	(segment
		(start 49.063402 -37.61359)
		(end 48.334168 -36.884356)
		(width 0.14224)
		(layer "In11.Cu")
		(net "M_J_DQ<14>")
	)
	(segment
		(start 47.19193 -0.768096)
		(end 46.81093 -0.387096)
		(width 0.14224)
		(layer "In11.Cu")
		(net "M_J_DQ<14>")
	)
	(segment
		(start 45.709078 -29.364686)
		(end 45.912278 -29.161486)
		(width 0.14224)
		(layer "In11.Cu")
		(net "M_J_DQ<14>")
	)
	(segment
		(start 74.4093 -59.382152)
		(end 74.392536 -59.352688)
		(width 0.0889)
		(layer "In11.Cu")
		(net "M_J_DQ<14>")
	)
	(segment
		(start 46.556168 -28.348686)
		(end 45.912278 -28.348686)
		(width 0.14224)
		(layer "In11.Cu")
		(net "M_J_DQ<14>")
	)
	(segment
		(start 45.912278 -29.161486)
		(end 46.556168 -29.161486)
		(width 0.14224)
		(layer "In11.Cu")
		(net "M_J_DQ<14>")
	)
	(segment
		(start 46.699424 -4.922266)
		(end 46.699424 -4.357878)
		(width 0.14224)
		(layer "In11.Cu")
		(net "M_J_DQ<14>")
	)
	(segment
		(start 46.556168 -29.161486)
		(end 46.759368 -28.958286)
		(width 0.14224)
		(layer "In11.Cu")
		(net "M_J_DQ<14>")
	)
	(segment
		(start 47.165768 -5.38861)
		(end 46.699424 -4.922266)
		(width 0.14224)
		(layer "In11.Cu")
		(net "M_J_DQ<14>")
	)
	(segment
		(start 46.463712 -3.327654)
		(end 47.23638 -2.554986)
		(width 0.14224)
		(layer "In11.Cu")
		(net "M_J_DQ<14>")
	)
	(segment
		(start 47.063914 -8.864346)
		(end 47.063914 -7.391146)
		(width 0.14224)
		(layer "In11.Cu")
		(net "M_J_DQ<14>")
	)
	(segment
		(start 46.81093 -1.777746)
		(end 46.81093 -1.492504)
		(width 0.14224)
		(layer "In11.Cu")
		(net "M_J_DQ<14>")
	)
	(segment
		(start 47.19193 -1.111504)
		(end 47.19193 -0.768096)
		(width 0.14224)
		(layer "In11.Cu")
		(net "M_J_DQ<14>")
	)
	(segment
		(start 47.174912 0.287528)
		(end 47.174912 0.565404)
		(width 0.14224)
		(layer "In11.Cu")
		(net "M_J_DQ<14>")
	)
	(segment
		(start 67.387724 -55.019194)
		(end 66.9417 -55.019194)
		(width 0.0889)
		(layer "In11.Cu")
		(net "M_J_DQ<14>")
	)
	(segment
		(start 47.063914 -18.440146)
		(end 47.063914 -16.992346)
		(width 0.14224)
		(layer "In11.Cu")
		(net "M_J_DQ<14>")
	)
	(segment
		(start 47.174912 0.565404)
		(end 47.549308 0.9398)
		(width 0.14224)
		(layer "In11.Cu")
		(net "M_J_DQ<14>")
	)
	(segment
		(start 45.709078 -29.771086)
		(end 45.709078 -29.364686)
		(width 0.14224)
		(layer "In11.Cu")
		(net "M_J_DQ<14>")
	)
	(segment
		(start 47.23638 -2.554986)
		(end 47.23638 -2.203196)
		(width 0.14224)
		(layer "In11.Cu")
		(net "M_J_DQ<14>")
	)
	(segment
		(start 74.904346 -60.047886)
		(end 74.4093 -59.382152)
		(width 0.0889)
		(layer "In11.Cu")
		(net "M_J_DQ<14>")
	)
	(segment
		(start 47.063914 -7.391146)
		(end 47.165768 -7.289292)
		(width 0.14224)
		(layer "In11.Cu")
		(net "M_J_DQ<14>")
	)
	(segment
		(start 48.334168 -34.417)
		(end 48.130968 -34.2138)
		(width 0.14224)
		(layer "In11.Cu")
		(net "M_J_DQ<14>")
	)
	(segment
		(start 47.063914 -12.373356)
		(end 47.267114 -12.170156)
		(width 0.14224)
		(layer "In11.Cu")
		(net "M_J_DQ<14>")
	)
	(segment
		(start 66.758312 -55.202582)
		(end 65.419986 -55.202582)
		(width 0.14224)
		(layer "In11.Cu")
		(net "M_J_DQ<14>")
	)
	(segment
		(start 47.165514 -13.668756)
		(end 47.063914 -13.567156)
		(width 0.14224)
		(layer "In11.Cu")
		(net "M_J_DQ<14>")
	)
	(segment
		(start 46.759368 -28.551886)
		(end 46.556168 -28.348686)
		(width 0.14224)
		(layer "In11.Cu")
		(net "M_J_DQ<14>")
	)
	(segment
		(start 47.063914 -23.168356)
		(end 47.063914 -21.974556)
		(width 0.14224)
		(layer "In11.Cu")
		(net "M_J_DQ<14>")
	)
	(segment
		(start 48.732948 -38.145212)
		(end 49.063402 -37.814758)
		(width 0.14224)
		(layer "In11.Cu")
		(net "M_J_DQ<14>")
	)
	(segment
		(start 73.20534 -58.65749)
		(end 73.169526 -58.65749)
		(width 0.0889)
		(layer "In11.Cu")
		(net "M_J_DQ<14>")
	)
	(segment
		(start 47.165514 -23.269956)
		(end 47.063914 -23.168356)
		(width 0.14224)
		(layer "In11.Cu")
		(net "M_J_DQ<14>")
	)
	(segment
		(start 47.267114 -11.759946)
		(end 47.064168 -11.557)
		(width 0.14224)
		(layer "In11.Cu")
		(net "M_J_DQ<14>")
	)
	(segment
		(start 66.9417 -55.019194)
		(end 66.758312 -55.202582)
		(width 0.0889)
		(layer "In11.Cu")
		(net "M_J_DQ<14>")
	)
	(segment
		(start 48.732948 -38.34638)
		(end 48.732948 -38.145212)
		(width 0.14224)
		(layer "In11.Cu")
		(net "M_J_DQ<14>")
	)
	(segment
		(start 54.46268 -44.245276)
		(end 54.46268 -43.012868)
		(width 0.14224)
		(layer "In11.Cu")
		(net "M_J_DQ<14>")
	)
	(segment
		(start 46.463712 -4.122166)
		(end 46.463712 -3.327654)
		(width 0.14224)
		(layer "In11.Cu")
		(net "M_J_DQ<14>")
	)
	(segment
		(start 65.419986 -55.202582)
		(end 54.46268 -44.245276)
		(width 0.14224)
		(layer "In11.Cu")
		(net "M_J_DQ<14>")
	)
	(segment
		(start 47.318168 -36.3982)
		(end 46.911768 -36.3982)
		(width 0.14224)
		(layer "In11.Cu")
		(net "M_J_DQ<14>")
	)
	(segment
		(start 47.114968 -19.177)
		(end 47.267114 -19.024854)
		(width 0.14224)
		(layer "In11.Cu")
		(net "M_J_DQ<14>")
	)
	(segment
		(start 46.81093 -0.076454)
		(end 47.174912 0.287528)
		(width 0.14224)
		(layer "In11.Cu")
		(net "M_J_DQ<14>")
	)
	(segment
		(start 45.912278 -28.348686)
		(end 45.709078 -28.145486)
		(width 0.14224)
		(layer "In11.Cu")
		(net "M_J_DQ<14>")
	)
	(segment
		(start 48.334168 -36.884356)
		(end 48.334168 -34.417)
		(width 0.14224)
		(layer "In11.Cu")
		(net "M_J_DQ<14>")
	)
	(segment
		(start 47.267114 -9.067546)
		(end 47.063914 -8.864346)
		(width 0.14224)
		(layer "In11.Cu")
		(net "M_J_DQ<14>")
	)
	(segment
		(start 47.165768 -7.289292)
		(end 47.165768 -5.38861)
		(width 0.14224)
		(layer "In11.Cu")
		(net "M_J_DQ<14>")
	)
	(segment
		(start 46.706536 -27.535886)
		(end 47.165514 -27.076908)
		(width 0.14224)
		(layer "In11.Cu")
		(net "M_J_DQ<14>")
	)
	(segment
		(start 48.991774 -38.605206)
		(end 48.732948 -38.34638)
		(width 0.14224)
		(layer "In11.Cu")
		(net "M_J_DQ<14>")
	)
	(segment
		(start 47.063914 -16.992346)
		(end 47.165514 -16.890746)
		(width 0.14224)
		(layer "In11.Cu")
		(net "M_J_DQ<14>")
	)
	(segment
		(start 47.521368 -36.195)
		(end 47.318168 -36.3982)
		(width 0.14224)
		(layer "In11.Cu")
		(net "M_J_DQ<14>")
	)
	(segment
		(start 69.044566 -56.676036)
		(end 67.387724 -55.019194)
		(width 0.0889)
		(layer "In11.Cu")
		(net "M_J_DQ<14>")
	)
	(segment
		(start 46.699424 -4.357878)
		(end 46.463712 -4.122166)
		(width 0.14224)
		(layer "In11.Cu")
		(net "M_J_DQ<14>")
	)
	(segment
		(start 49.724564 -38.274752)
		(end 49.523396 -38.274752)
		(width 0.14224)
		(layer "In11.Cu")
		(net "M_J_DQ<14>")
	)
	(segment
		(start 45.912278 -29.974286)
		(end 45.709078 -29.771086)
		(width 0.14224)
		(layer "In11.Cu")
		(net "M_J_DQ<14>")
	)
	(segment
		(start 47.165514 -16.890746)
		(end 47.165514 -13.668756)
		(width 0.14224)
		(layer "In11.Cu")
		(net "M_J_DQ<14>")
	)
	(segment
		(start 47.064168 -9.600946)
		(end 47.267114 -9.398)
		(width 0.14224)
		(layer "In11.Cu")
		(net "M_J_DQ<14>")
	)
	(segment
		(start 46.530768 -29.974286)
		(end 45.912278 -29.974286)
		(width 0.14224)
		(layer "In11.Cu")
		(net "M_J_DQ<14>")
	)
	(segment
		(start 47.063914 -13.567156)
		(end 47.063914 -12.373356)
		(width 0.14224)
		(layer "In11.Cu")
		(net "M_J_DQ<14>")
	)
	(segment
		(start 45.709078 -28.145486)
		(end 45.709078 -27.739086)
		(width 0.14224)
		(layer "In11.Cu")
		(net "M_J_DQ<14>")
	)
	(segment
		(start 46.81093 -1.492504)
		(end 47.19193 -1.111504)
		(width 0.14224)
		(layer "In11.Cu")
		(net "M_J_DQ<14>")
	)
	(segment
		(start 47.064168 -11.557)
		(end 47.064168 -9.600946)
		(width 0.14224)
		(layer "In11.Cu")
		(net "M_J_DQ<14>")
	)
	(segment
		(start 47.724568 -34.2138)
		(end 47.521368 -34.417)
		(width 0.14224)
		(layer "In11.Cu")
		(net "M_J_DQ<14>")
	)
	(segment
		(start 70.626732 -57.17159)
		(end 70.593966 -57.17159)
		(width 0.0889)
		(layer "In11.Cu")
		(net "M_J_DQ<14>")
	)
	(segment
		(start 45.912278 -27.535886)
		(end 46.706536 -27.535886)
		(width 0.14224)
		(layer "In11.Cu")
		(net "M_J_DQ<14>")
	)
	(segment
		(start 45.709078 -27.739086)
		(end 45.912278 -27.535886)
		(width 0.14224)
		(layer "In11.Cu")
		(net "M_J_DQ<14>")
	)
	(segment
		(start 72.34682 -58.16219)
		(end 72.307196 -58.16219)
		(width 0.0889)
		(layer "In11.Cu")
		(net "M_J_DQ<14>")
	)
	(segment
		(start 49.523396 -38.274752)
		(end 49.192942 -38.605206)
		(width 0.14224)
		(layer "In11.Cu")
		(net "M_J_DQ<14>")
	)
	(segment
		(start 46.708568 -30.152086)
		(end 46.530768 -29.974286)
		(width 0.14224)
		(layer "In11.Cu")
		(net "M_J_DQ<14>")
	)
	(segment
		(start 47.521368 -34.417)
		(end 47.521368 -36.195)
		(width 0.14224)
		(layer "In11.Cu")
		(net "M_J_DQ<14>")
	)
	(segment
		(start 74.060812 -59.15279)
		(end 74.032872 -59.15279)
		(width 0.0889)
		(layer "In11.Cu")
		(net "M_J_DQ<14>")
	)
	(segment
		(start 47.063914 -21.974556)
		(end 47.267114 -21.771356)
		(width 0.14224)
		(layer "In11.Cu")
		(net "M_J_DQ<14>")
	)
	(segment
		(start 46.708568 -36.195)
		(end 46.708568 -30.152086)
		(width 0.14224)
		(layer "In11.Cu")
		(net "M_J_DQ<14>")
	)
	(arc
		(start 74.032872 -59.15279)
		(mid 73.744727 -59.070471)
		(end 73.534016 -58.857388)
		(width 0.0889)
		(layer "In11.Cu")
		(net "M_J_DQ<14>")
	)
	(arc
		(start 71.816976 -57.867042)
		(mid 71.675293 -57.723238)
		(end 71.481442 -57.66689)
		(width 0.0889)
		(layer "In11.Cu")
		(net "M_J_DQ<14>")
	)
	(arc
		(start 70.593966 -57.17159)
		(mid 70.308542 -57.088123)
		(end 70.099936 -56.876188)
		(width 0.0889)
		(layer "In11.Cu")
		(net "M_J_DQ<14>")
	)
	(arc
		(start 74.392536 -59.352688)
		(mid 74.252457 -59.209952)
		(end 74.060812 -59.15279)
		(width 0.0889)
		(layer "In11.Cu")
		(net "M_J_DQ<14>")
	)
	(arc
		(start 70.099936 -56.876188)
		(mid 69.958253 -56.732384)
		(end 69.764402 -56.676036)
		(width 0.0889)
		(layer "In11.Cu")
		(net "M_J_DQ<14>")
	)
	(arc
		(start 73.169526 -58.65749)
		(mid 72.884102 -58.574023)
		(end 72.675496 -58.362088)
		(width 0.0889)
		(layer "In11.Cu")
		(net "M_J_DQ<14>")
	)
	(arc
		(start 70.958456 -57.371488)
		(mid 70.818377 -57.228752)
		(end 70.626732 -57.17159)
		(width 0.0889)
		(layer "In11.Cu")
		(net "M_J_DQ<14>")
	)
	(arc
		(start 71.457312 -57.66689)
		(mid 71.169167 -57.584571)
		(end 70.958456 -57.371488)
		(width 0.0889)
		(layer "In11.Cu")
		(net "M_J_DQ<14>")
	)
	(arc
		(start 72.307196 -58.16219)
		(mid 72.023979 -58.077909)
		(end 71.816976 -57.867042)
		(width 0.0889)
		(layer "In11.Cu")
		(net "M_J_DQ<14>")
	)
	(arc
		(start 73.534016 -58.857388)
		(mid 73.395272 -58.715355)
		(end 73.20534 -58.65749)
		(width 0.0889)
		(layer "In11.Cu")
		(net "M_J_DQ<14>")
	)
	(arc
		(start 72.675496 -58.362088)
		(mid 72.536752 -58.220055)
		(end 72.34682 -58.16219)
		(width 0.0889)
		(layer "In11.Cu")
		(net "M_J_DQ<14>")
	)
	(segment
		(start 40.749474 3.778758)
		(end 40.749474 2.514854)
		(width 0.1651)
		(layer "F.Cu")
		(net "M_J_DQ<13>")
	)
	(segment
		(start 78.051406 -61.53404)
		(end 77.479906 -61.53404)
		(width 0.0889)
		(layer "F.Cu")
		(net "M_J_DQ<13>")
	)
	(via
		(at 41.523158 -3.076956)
		(size 0.508)
		(drill 0.254)
		(layers "F.Cu" "B.Cu")
		(net "M_J_DQ<13>")
	)
	(via
		(at 77.479906 -61.53404)
		(size 0.508)
		(drill 0.254)
		(layers "F.Cu" "B.Cu")
		(net "M_J_DQ<13>")
	)
	(via
		(at 40.749474 2.514854)
		(size 0.508)
		(drill 0.254)
		(layers "F.Cu" "B.Cu")
		(net "M_J_DQ<13>")
	)
	(segment
		(start 41.599358 -1.021842)
		(end 41.599358 -3.000756)
		(width 0.1651)
		(layer "B.Cu")
		(net "M_J_DQ<13>")
	)
	(segment
		(start 41.599358 -3.000756)
		(end 41.523158 -3.076956)
		(width 0.1651)
		(layer "B.Cu")
		(net "M_J_DQ<13>")
	)
	(segment
		(start 42.263568 -24.549354)
		(end 42.263568 -24.904446)
		(width 0.14224)
		(layer "In11.Cu")
		(net "M_J_DQ<13>")
	)
	(segment
		(start 42.263568 -24.904446)
		(end 41.996614 -25.1714)
		(width 0.14224)
		(layer "In11.Cu")
		(net "M_J_DQ<13>")
	)
	(segment
		(start 41.996614 -18.1864)
		(end 41.933368 -18.7706)
		(width 0.14224)
		(layer "In11.Cu")
		(net "M_J_DQ<13>")
	)
	(segment
		(start 41.044368 -3.555746)
		(end 41.044368 -3.936746)
		(width 0.14224)
		(layer "In11.Cu")
		(net "M_J_DQ<13>")
	)
	(segment
		(start 71.45528 -61.438536)
		(end 71.488046 -61.438536)
		(width 0.0889)
		(layer "In11.Cu")
		(net "M_J_DQ<13>")
	)
	(segment
		(start 41.044368 -3.936746)
		(end 41.780968 -4.673346)
		(width 0.14224)
		(layer "In11.Cu")
		(net "M_J_DQ<13>")
	)
	(segment
		(start 41.996614 -24.2824)
		(end 42.263568 -24.549354)
		(width 0.14224)
		(layer "In11.Cu")
		(net "M_J_DQ<13>")
	)
	(segment
		(start 41.996614 -25.1714)
		(end 41.996614 -37.184584)
		(width 0.14224)
		(layer "In11.Cu")
		(net "M_J_DQ<13>")
	)
	(segment
		(start 41.834562 -2.765552)
		(end 41.834562 0.53975)
		(width 0.14224)
		(layer "In11.Cu")
		(net "M_J_DQ<13>")
	)
	(segment
		(start 42.031412 1.149096)
		(end 41.631108 1.5494)
		(width 0.14224)
		(layer "In11.Cu")
		(net "M_J_DQ<13>")
	)
	(segment
		(start 70.60057 -60.94349)
		(end 70.633336 -60.94349)
		(width 0.0889)
		(layer "In11.Cu")
		(net "M_J_DQ<13>")
	)
	(segment
		(start 41.907714 -21.5392)
		(end 41.983406 -22.165564)
		(width 0.14224)
		(layer "In11.Cu")
		(net "M_J_DQ<13>")
	)
	(segment
		(start 42.031412 0.7366)
		(end 42.031412 1.149096)
		(width 0.14224)
		(layer "In11.Cu")
		(net "M_J_DQ<13>")
	)
	(segment
		(start 74.210672 -62.92469)
		(end 74.656442 -62.705488)
		(width 0.0889)
		(layer "In11.Cu")
		(net "M_J_DQ<13>")
	)
	(segment
		(start 41.780968 -4.673346)
		(end 41.780968 -7.112)
		(width 0.14224)
		(layer "In11.Cu")
		(net "M_J_DQ<13>")
	)
	(segment
		(start 41.780968 -7.112)
		(end 41.996614 -7.327646)
		(width 0.14224)
		(layer "In11.Cu")
		(net "M_J_DQ<13>")
	)
	(segment
		(start 74.89317 -62.619636)
		(end 74.925936 -62.619636)
		(width 0.0889)
		(layer "In11.Cu")
		(net "M_J_DQ<13>")
	)
	(segment
		(start 41.834562 0.53975)
		(end 42.031412 0.7366)
		(width 0.14224)
		(layer "In11.Cu")
		(net "M_J_DQ<13>")
	)
	(segment
		(start 41.996614 -7.327646)
		(end 41.996614 -8.5852)
		(width 0.14224)
		(layer "In11.Cu")
		(net "M_J_DQ<13>")
	)
	(segment
		(start 41.631108 1.5494)
		(end 41.320212 1.5494)
		(width 0.14224)
		(layer "In11.Cu")
		(net "M_J_DQ<13>")
	)
	(segment
		(start 42.060368 -19.3294)
		(end 42.060368 -21.208746)
		(width 0.14224)
		(layer "In11.Cu")
		(net "M_J_DQ<13>")
	)
	(segment
		(start 42.015664 -19.177)
		(end 42.060368 -19.3294)
		(width 0.14224)
		(layer "In11.Cu")
		(net "M_J_DQ<13>")
	)
	(segment
		(start 41.933368 -18.8976)
		(end 42.015664 -19.177)
		(width 0.14224)
		(layer "In11.Cu")
		(net "M_J_DQ<13>")
	)
	(segment
		(start 72.31761 -61.93409)
		(end 72.350376 -61.93409)
		(width 0.0889)
		(layer "In11.Cu")
		(net "M_J_DQ<13>")
	)
	(segment
		(start 41.996614 -13.617956)
		(end 41.933114 -13.681456)
		(width 0.14224)
		(layer "In11.Cu")
		(net "M_J_DQ<13>")
	)
	(segment
		(start 41.996614 -16.928846)
		(end 41.996614 -18.1864)
		(width 0.14224)
		(layer "In11.Cu")
		(net "M_J_DQ<13>")
	)
	(segment
		(start 42.060368 -11.6078)
		(end 41.907714 -11.760454)
		(width 0.14224)
		(layer "In11.Cu")
		(net "M_J_DQ<13>")
	)
	(segment
		(start 41.933114 -16.865346)
		(end 41.996614 -16.928846)
		(width 0.14224)
		(layer "In11.Cu")
		(net "M_J_DQ<13>")
	)
	(segment
		(start 75.74788 -62.12459)
		(end 75.780646 -62.12459)
		(width 0.0889)
		(layer "In11.Cu")
		(net "M_J_DQ<13>")
	)
	(segment
		(start 41.907714 -11.760454)
		(end 41.907714 -12.065)
		(width 0.14224)
		(layer "In11.Cu")
		(net "M_J_DQ<13>")
	)
	(segment
		(start 41.907714 -12.065)
		(end 41.996614 -12.6746)
		(width 0.14224)
		(layer "In11.Cu")
		(net "M_J_DQ<13>")
	)
	(segment
		(start 42.060368 -21.208746)
		(end 41.907714 -21.3614)
		(width 0.14224)
		(layer "In11.Cu")
		(net "M_J_DQ<13>")
	)
	(segment
		(start 65.391792 -59.548268)
		(end 65.620138 -59.776614)
		(width 0.0889)
		(layer "In11.Cu")
		(net "M_J_DQ<13>")
	)
	(segment
		(start 67.673982 -59.776614)
		(end 68.421504 -60.524136)
		(width 0.0889)
		(layer "In11.Cu")
		(net "M_J_DQ<13>")
	)
	(segment
		(start 41.320212 1.5494)
		(end 40.749474 2.120138)
		(width 0.14224)
		(layer "In11.Cu")
		(net "M_J_DQ<13>")
	)
	(segment
		(start 41.996614 -37.184584)
		(end 64.360298 -59.548268)
		(width 0.14224)
		(layer "In11.Cu")
		(net "M_J_DQ<13>")
	)
	(segment
		(start 41.933368 -18.7706)
		(end 41.933368 -18.8976)
		(width 0.14224)
		(layer "In11.Cu")
		(net "M_J_DQ<13>")
	)
	(segment
		(start 41.958768 -8.844788)
		(end 41.958768 -9.550654)
		(width 0.14224)
		(layer "In11.Cu")
		(net "M_J_DQ<13>")
	)
	(segment
		(start 41.996614 -12.6746)
		(end 41.996614 -13.617956)
		(width 0.14224)
		(layer "In11.Cu")
		(net "M_J_DQ<13>")
	)
	(segment
		(start 41.958768 -9.550654)
		(end 42.060368 -9.652254)
		(width 0.14224)
		(layer "In11.Cu")
		(net "M_J_DQ<13>")
	)
	(segment
		(start 64.360298 -59.548268)
		(end 65.391792 -59.548268)
		(width 0.14224)
		(layer "In11.Cu")
		(net "M_J_DQ<13>")
	)
	(segment
		(start 41.996614 -8.5852)
		(end 41.970706 -8.763)
		(width 0.14224)
		(layer "In11.Cu")
		(net "M_J_DQ<13>")
	)
	(segment
		(start 74.03465 -62.92469)
		(end 74.210672 -62.92469)
		(width 0.0889)
		(layer "In11.Cu")
		(net "M_J_DQ<13>")
	)
	(segment
		(start 42.060368 -9.652254)
		(end 42.060368 -11.6078)
		(width 0.14224)
		(layer "In11.Cu")
		(net "M_J_DQ<13>")
	)
	(segment
		(start 73.17232 -62.429136)
		(end 73.205086 -62.429136)
		(width 0.0889)
		(layer "In11.Cu")
		(net "M_J_DQ<13>")
	)
	(segment
		(start 41.996614 -22.2758)
		(end 41.996614 -24.2824)
		(width 0.14224)
		(layer "In11.Cu")
		(net "M_J_DQ<13>")
	)
	(segment
		(start 41.933114 -13.681456)
		(end 41.933114 -16.865346)
		(width 0.14224)
		(layer "In11.Cu")
		(net "M_J_DQ<13>")
	)
	(segment
		(start 41.523158 -3.076956)
		(end 41.044368 -3.555746)
		(width 0.14224)
		(layer "In11.Cu")
		(net "M_J_DQ<13>")
	)
	(segment
		(start 41.907714 -21.3614)
		(end 41.907714 -21.5392)
		(width 0.14224)
		(layer "In11.Cu")
		(net "M_J_DQ<13>")
	)
	(segment
		(start 68.421504 -60.524136)
		(end 68.547996 -60.743338)
		(width 0.0889)
		(layer "In11.Cu")
		(net "M_J_DQ<13>")
	)
	(segment
		(start 65.620138 -59.776614)
		(end 67.673982 -59.776614)
		(width 0.0889)
		(layer "In11.Cu")
		(net "M_J_DQ<13>")
	)
	(segment
		(start 69.735446 -60.447936)
		(end 69.771006 -60.447936)
		(width 0.0889)
		(layer "In11.Cu")
		(net "M_J_DQ<13>")
	)
	(segment
		(start 41.983406 -22.165564)
		(end 41.996614 -22.2758)
		(width 0.14224)
		(layer "In11.Cu")
		(net "M_J_DQ<13>")
	)
	(segment
		(start 41.523158 -3.076956)
		(end 41.834562 -2.765552)
		(width 0.14224)
		(layer "In11.Cu")
		(net "M_J_DQ<13>")
	)
	(segment
		(start 76.61021 -61.629036)
		(end 76.65847 -61.629036)
		(width 0.0889)
		(layer "In11.Cu")
		(net "M_J_DQ<13>")
	)
	(segment
		(start 76.65847 -61.629036)
		(end 77.479906 -61.53404)
		(width 0.0889)
		(layer "In11.Cu")
		(net "M_J_DQ<13>")
	)
	(segment
		(start 40.749474 2.120138)
		(end 40.749474 2.514854)
		(width 0.14224)
		(layer "In11.Cu")
		(net "M_J_DQ<13>")
	)
	(segment
		(start 41.970706 -8.763)
		(end 41.958768 -8.844788)
		(width 0.14224)
		(layer "In11.Cu")
		(net "M_J_DQ<13>")
	)
	(arc
		(start 76.274676 -61.829188)
		(mid 76.416359 -61.685384)
		(end 76.61021 -61.629036)
		(width 0.0889)
		(layer "In11.Cu")
		(net "M_J_DQ<13>")
	)
	(arc
		(start 68.547996 -60.743338)
		(mid 68.894706 -60.943649)
		(end 69.241416 -60.743338)
		(width 0.0889)
		(layer "In11.Cu")
		(net "M_J_DQ<13>")
	)
	(arc
		(start 74.656442 -62.705488)
		(mid 74.767876 -62.643451)
		(end 74.89317 -62.619636)
		(width 0.0889)
		(layer "In11.Cu")
		(net "M_J_DQ<13>")
	)
	(arc
		(start 71.982076 -61.733938)
		(mid 72.123759 -61.877742)
		(end 72.31761 -61.93409)
		(width 0.0889)
		(layer "In11.Cu")
		(net "M_J_DQ<13>")
	)
	(arc
		(start 70.633336 -60.94349)
		(mid 70.916553 -61.027771)
		(end 71.123556 -61.238638)
		(width 0.0889)
		(layer "In11.Cu")
		(net "M_J_DQ<13>")
	)
	(arc
		(start 74.925936 -62.619636)
		(mid 75.209153 -62.535355)
		(end 75.416156 -62.324488)
		(width 0.0889)
		(layer "In11.Cu")
		(net "M_J_DQ<13>")
	)
	(arc
		(start 72.840596 -62.229238)
		(mid 72.980675 -62.371974)
		(end 73.17232 -62.429136)
		(width 0.0889)
		(layer "In11.Cu")
		(net "M_J_DQ<13>")
	)
	(arc
		(start 69.771006 -60.447936)
		(mid 70.05643 -60.531403)
		(end 70.265036 -60.743338)
		(width 0.0889)
		(layer "In11.Cu")
		(net "M_J_DQ<13>")
	)
	(arc
		(start 73.699116 -62.724538)
		(mid 73.840799 -62.868342)
		(end 74.03465 -62.92469)
		(width 0.0889)
		(layer "In11.Cu")
		(net "M_J_DQ<13>")
	)
	(arc
		(start 71.123556 -61.238638)
		(mid 71.263635 -61.381374)
		(end 71.45528 -61.438536)
		(width 0.0889)
		(layer "In11.Cu")
		(net "M_J_DQ<13>")
	)
	(arc
		(start 75.780646 -62.12459)
		(mid 76.06607 -62.041123)
		(end 76.274676 -61.829188)
		(width 0.0889)
		(layer "In11.Cu")
		(net "M_J_DQ<13>")
	)
	(arc
		(start 71.488046 -61.438536)
		(mid 71.77347 -61.522003)
		(end 71.982076 -61.733938)
		(width 0.0889)
		(layer "In11.Cu")
		(net "M_J_DQ<13>")
	)
	(arc
		(start 73.205086 -62.429136)
		(mid 73.49051 -62.512603)
		(end 73.699116 -62.724538)
		(width 0.0889)
		(layer "In11.Cu")
		(net "M_J_DQ<13>")
	)
	(arc
		(start 75.416156 -62.324488)
		(mid 75.556235 -62.181752)
		(end 75.74788 -62.12459)
		(width 0.0889)
		(layer "In11.Cu")
		(net "M_J_DQ<13>")
	)
	(arc
		(start 70.265036 -60.743338)
		(mid 70.406719 -60.887142)
		(end 70.60057 -60.94349)
		(width 0.0889)
		(layer "In11.Cu")
		(net "M_J_DQ<13>")
	)
	(arc
		(start 72.350376 -61.93409)
		(mid 72.633593 -62.018371)
		(end 72.840596 -62.229238)
		(width 0.0889)
		(layer "In11.Cu")
		(net "M_J_DQ<13>")
	)
	(arc
		(start 69.241416 -60.743338)
		(mid 69.450024 -60.531406)
		(end 69.735446 -60.447936)
		(width 0.0889)
		(layer "In11.Cu")
		(net "M_J_DQ<13>")
	)
	(segment
		(start 41.599358 0.510032)
		(end 41.501314 1.0414)
		(width 0.1651)
		(layer "F.Cu")
		(net "M_J_DQ<12>")
	)
	(segment
		(start 77.192886 -62.029086)
		(end 76.621386 -62.029086)
		(width 0.0889)
		(layer "F.Cu")
		(net "M_J_DQ<12>")
	)
	(segment
		(start 41.599358 -0.821182)
		(end 41.599358 0.510032)
		(width 0.1651)
		(layer "F.Cu")
		(net "M_J_DQ<12>")
	)
	(via
		(at 41.501314 1.0414)
		(size 0.508)
		(drill 0.254)
		(layers "F.Cu" "B.Cu")
		(net "M_J_DQ<12>")
	)
	(via
		(at 40.749474 -4.357878)
		(size 0.508)
		(drill 0.254)
		(layers "F.Cu" "B.Cu")
		(net "M_J_DQ<12>")
	)
	(via
		(at 76.621386 -62.029086)
		(size 0.508)
		(drill 0.254)
		(layers "F.Cu" "B.Cu")
		(net "M_J_DQ<12>")
	)
	(segment
		(start 40.749474 -5.621782)
		(end 40.749474 -4.357878)
		(width 0.1651)
		(layer "B.Cu")
		(net "M_J_DQ<12>")
	)
	(segment
		(start 41.24198 -1.0668)
		(end 41.24198 -0.762)
		(width 0.14224)
		(layer "In11.Cu")
		(net "M_J_DQ<12>")
	)
	(segment
		(start 41.018968 -11.4808)
		(end 41.222168 -11.684)
		(width 0.14224)
		(layer "In11.Cu")
		(net "M_J_DQ<12>")
	)
	(segment
		(start 41.018968 -17.0434)
		(end 41.018968 -18.3134)
		(width 0.14224)
		(layer "In11.Cu")
		(net "M_J_DQ<12>")
	)
	(segment
		(start 41.018714 -7.467854)
		(end 41.018714 -8.711946)
		(width 0.14224)
		(layer "In11.Cu")
		(net "M_J_DQ<12>")
	)
	(segment
		(start 41.222168 -13.77061)
		(end 41.222168 -16.8402)
		(width 0.14224)
		(layer "In11.Cu")
		(net "M_J_DQ<12>")
	)
	(segment
		(start 40.749474 -4.357878)
		(end 40.513762 -4.122166)
		(width 0.14224)
		(layer "In11.Cu")
		(net "M_J_DQ<12>")
	)
	(segment
		(start 40.513762 -3.327654)
		(end 41.224962 -2.616454)
		(width 0.14224)
		(layer "In11.Cu")
		(net "M_J_DQ<12>")
	)
	(segment
		(start 41.044368 -23.164546)
		(end 41.26992 -23.390098)
		(width 0.14224)
		(layer "In11.Cu")
		(net "M_J_DQ<12>")
	)
	(segment
		(start 41.26992 -37.356034)
		(end 64.097154 -60.183268)
		(width 0.14224)
		(layer "In11.Cu")
		(net "M_J_DQ<12>")
	)
	(segment
		(start 41.222168 -21.3106)
		(end 41.222168 -21.745702)
		(width 0.14224)
		(layer "In11.Cu")
		(net "M_J_DQ<12>")
	)
	(segment
		(start 71.448676 -61.629036)
		(end 71.481442 -61.629036)
		(width 0.0889)
		(layer "In11.Cu")
		(net "M_J_DQ<12>")
	)
	(segment
		(start 70.593966 -61.13399)
		(end 70.626732 -61.13399)
		(width 0.0889)
		(layer "In11.Cu")
		(net "M_J_DQ<12>")
	)
	(segment
		(start 41.222168 -19.05)
		(end 41.145968 -19.1262)
		(width 0.14224)
		(layer "In11.Cu")
		(net "M_J_DQ<12>")
	)
	(segment
		(start 41.224962 0.765048)
		(end 41.501314 1.0414)
		(width 0.14224)
		(layer "In11.Cu")
		(net "M_J_DQ<12>")
	)
	(segment
		(start 41.26992 -23.390098)
		(end 41.26992 -37.356034)
		(width 0.14224)
		(layer "In11.Cu")
		(net "M_J_DQ<12>")
	)
	(segment
		(start 41.222168 -9.3726)
		(end 41.018968 -9.5758)
		(width 0.14224)
		(layer "In11.Cu")
		(net "M_J_DQ<12>")
	)
	(segment
		(start 41.224962 -2.616454)
		(end 41.224962 -2.141728)
		(width 0.14224)
		(layer "In11.Cu")
		(net "M_J_DQ<12>")
	)
	(segment
		(start 40.749474 -4.357878)
		(end 41.247314 -4.855718)
		(width 0.14224)
		(layer "In11.Cu")
		(net "M_J_DQ<12>")
	)
	(segment
		(start 68.297044 -60.689744)
		(end 68.382896 -60.838588)
		(width 0.0889)
		(layer "In11.Cu")
		(net "M_J_DQ<12>")
	)
	(segment
		(start 41.145968 -21.2344)
		(end 41.222168 -21.3106)
		(width 0.14224)
		(layer "In11.Cu")
		(net "M_J_DQ<12>")
	)
	(segment
		(start 41.247314 -4.855718)
		(end 41.247314 -7.239254)
		(width 0.14224)
		(layer "In11.Cu")
		(net "M_J_DQ<12>")
	)
	(segment
		(start 41.018968 -18.3134)
		(end 41.222168 -18.5166)
		(width 0.14224)
		(layer "In11.Cu")
		(net "M_J_DQ<12>")
	)
	(segment
		(start 76.12634 -62.695074)
		(end 76.621386 -62.029086)
		(width 0.0889)
		(layer "In11.Cu")
		(net "M_J_DQ<12>")
	)
	(segment
		(start 41.222168 -12.144502)
		(end 41.044368 -12.322302)
		(width 0.14224)
		(layer "In11.Cu")
		(net "M_J_DQ<12>")
	)
	(segment
		(start 74.88936 -63.419736)
		(end 74.919332 -63.419736)
		(width 0.0889)
		(layer "In11.Cu")
		(net "M_J_DQ<12>")
	)
	(segment
		(start 41.224962 0.287528)
		(end 41.224962 0.765048)
		(width 0.14224)
		(layer "In11.Cu")
		(net "M_J_DQ<12>")
	)
	(segment
		(start 41.224962 -2.141728)
		(end 40.87368 -1.790446)
		(width 0.14224)
		(layer "In11.Cu")
		(net "M_J_DQ<12>")
	)
	(segment
		(start 74.210672 -63.11519)
		(end 74.665586 -63.340996)
		(width 0.0889)
		(layer "In11.Cu")
		(net "M_J_DQ<12>")
	)
	(segment
		(start 64.097154 -60.183268)
		(end 65.3415 -60.183268)
		(width 0.14224)
		(layer "In11.Cu")
		(net "M_J_DQ<12>")
	)
	(segment
		(start 41.145968 -19.1262)
		(end 41.145968 -21.2344)
		(width 0.14224)
		(layer "In11.Cu")
		(net "M_J_DQ<12>")
	)
	(segment
		(start 67.573906 -59.966606)
		(end 68.297044 -60.689744)
		(width 0.0889)
		(layer "In11.Cu")
		(net "M_J_DQ<12>")
	)
	(segment
		(start 65.558162 -59.966606)
		(end 67.573906 -59.966606)
		(width 0.0889)
		(layer "In11.Cu")
		(net "M_J_DQ<12>")
	)
	(segment
		(start 68.876926 -61.13399)
		(end 68.912486 -61.13399)
		(width 0.0889)
		(layer "In11.Cu")
		(net "M_J_DQ<12>")
	)
	(segment
		(start 74.028046 -63.11519)
		(end 74.210672 -63.11519)
		(width 0.0889)
		(layer "In11.Cu")
		(net "M_J_DQ<12>")
	)
	(segment
		(start 41.018714 -8.711946)
		(end 41.222168 -8.9154)
		(width 0.14224)
		(layer "In11.Cu")
		(net "M_J_DQ<12>")
	)
	(segment
		(start 41.044368 -21.923502)
		(end 41.044368 -23.164546)
		(width 0.14224)
		(layer "In11.Cu")
		(net "M_J_DQ<12>")
	)
	(segment
		(start 65.3415 -60.183268)
		(end 65.558162 -59.966606)
		(width 0.0889)
		(layer "In11.Cu")
		(net "M_J_DQ<12>")
	)
	(segment
		(start 40.513762 -4.122166)
		(end 40.513762 -3.327654)
		(width 0.14224)
		(layer "In11.Cu")
		(net "M_J_DQ<12>")
	)
	(segment
		(start 72.311006 -62.12459)
		(end 72.343772 -62.12459)
		(width 0.0889)
		(layer "In11.Cu")
		(net "M_J_DQ<12>")
	)
	(segment
		(start 41.018968 -9.5758)
		(end 41.018968 -11.4808)
		(width 0.14224)
		(layer "In11.Cu")
		(net "M_J_DQ<12>")
	)
	(segment
		(start 41.222168 -21.745702)
		(end 41.044368 -21.923502)
		(width 0.14224)
		(layer "In11.Cu")
		(net "M_J_DQ<12>")
	)
	(segment
		(start 76.109576 -62.724538)
		(end 76.12634 -62.695074)
		(width 0.0889)
		(layer "In11.Cu")
		(net "M_J_DQ<12>")
	)
	(segment
		(start 40.86098 -0.381)
		(end 40.86098 -0.076454)
		(width 0.14224)
		(layer "In11.Cu")
		(net "M_J_DQ<12>")
	)
	(segment
		(start 41.044368 -12.322302)
		(end 41.044368 -13.59281)
		(width 0.14224)
		(layer "In11.Cu")
		(net "M_J_DQ<12>")
	)
	(segment
		(start 41.222168 -11.684)
		(end 41.222168 -12.144502)
		(width 0.14224)
		(layer "In11.Cu")
		(net "M_J_DQ<12>")
	)
	(segment
		(start 40.87368 -1.4351)
		(end 41.24198 -1.0668)
		(width 0.14224)
		(layer "In11.Cu")
		(net "M_J_DQ<12>")
	)
	(segment
		(start 40.87368 -1.790446)
		(end 40.87368 -1.4351)
		(width 0.14224)
		(layer "In11.Cu")
		(net "M_J_DQ<12>")
	)
	(segment
		(start 75.741276 -62.92469)
		(end 75.774042 -62.92469)
		(width 0.0889)
		(layer "In11.Cu")
		(net "M_J_DQ<12>")
	)
	(segment
		(start 41.24198 -0.762)
		(end 40.86098 -0.381)
		(width 0.14224)
		(layer "In11.Cu")
		(net "M_J_DQ<12>")
	)
	(segment
		(start 41.247314 -7.239254)
		(end 41.018714 -7.467854)
		(width 0.14224)
		(layer "In11.Cu")
		(net "M_J_DQ<12>")
	)
	(segment
		(start 41.044368 -13.59281)
		(end 41.222168 -13.77061)
		(width 0.14224)
		(layer "In11.Cu")
		(net "M_J_DQ<12>")
	)
	(segment
		(start 41.222168 -16.8402)
		(end 41.018968 -17.0434)
		(width 0.14224)
		(layer "In11.Cu")
		(net "M_J_DQ<12>")
	)
	(segment
		(start 41.222168 -18.5166)
		(end 41.222168 -19.05)
		(width 0.14224)
		(layer "In11.Cu")
		(net "M_J_DQ<12>")
	)
	(segment
		(start 41.222168 -8.9154)
		(end 41.222168 -9.3726)
		(width 0.14224)
		(layer "In11.Cu")
		(net "M_J_DQ<12>")
	)
	(segment
		(start 40.86098 -0.076454)
		(end 41.224962 0.287528)
		(width 0.14224)
		(layer "In11.Cu")
		(net "M_J_DQ<12>")
	)
	(segment
		(start 73.165716 -62.619636)
		(end 73.198482 -62.619636)
		(width 0.0889)
		(layer "In11.Cu")
		(net "M_J_DQ<12>")
	)
	(arc
		(start 70.958456 -61.333888)
		(mid 71.16546 -61.544752)
		(end 71.448676 -61.629036)
		(width 0.0889)
		(layer "In11.Cu")
		(net "M_J_DQ<12>")
	)
	(arc
		(start 71.481442 -61.629036)
		(mid 71.675292 -61.685386)
		(end 71.816976 -61.829188)
		(width 0.0889)
		(layer "In11.Cu")
		(net "M_J_DQ<12>")
	)
	(arc
		(start 72.675496 -62.324488)
		(mid 72.8825 -62.535352)
		(end 73.165716 -62.619636)
		(width 0.0889)
		(layer "In11.Cu")
		(net "M_J_DQ<12>")
	)
	(arc
		(start 68.382896 -60.838588)
		(mid 68.591504 -61.05052)
		(end 68.876926 -61.13399)
		(width 0.0889)
		(layer "In11.Cu")
		(net "M_J_DQ<12>")
	)
	(arc
		(start 73.198482 -62.619636)
		(mid 73.392332 -62.675986)
		(end 73.534016 -62.819788)
		(width 0.0889)
		(layer "In11.Cu")
		(net "M_J_DQ<12>")
	)
	(arc
		(start 75.774042 -62.92469)
		(mid 75.967892 -62.86834)
		(end 76.109576 -62.724538)
		(width 0.0889)
		(layer "In11.Cu")
		(net "M_J_DQ<12>")
	)
	(arc
		(start 75.251056 -63.219838)
		(mid 75.45806 -63.008974)
		(end 75.741276 -62.92469)
		(width 0.0889)
		(layer "In11.Cu")
		(net "M_J_DQ<12>")
	)
	(arc
		(start 69.406516 -60.838588)
		(mid 69.753226 -60.638277)
		(end 70.099936 -60.838588)
		(width 0.0889)
		(layer "In11.Cu")
		(net "M_J_DQ<12>")
	)
	(arc
		(start 70.099936 -60.838588)
		(mid 70.308544 -61.05052)
		(end 70.593966 -61.13399)
		(width 0.0889)
		(layer "In11.Cu")
		(net "M_J_DQ<12>")
	)
	(arc
		(start 71.816976 -61.829188)
		(mid 72.025584 -62.04112)
		(end 72.311006 -62.12459)
		(width 0.0889)
		(layer "In11.Cu")
		(net "M_J_DQ<12>")
	)
	(arc
		(start 74.665586 -63.340996)
		(mid 74.771509 -63.397311)
		(end 74.88936 -63.419736)
		(width 0.0889)
		(layer "In11.Cu")
		(net "M_J_DQ<12>")
	)
	(arc
		(start 73.534016 -62.819788)
		(mid 73.742624 -63.03172)
		(end 74.028046 -63.11519)
		(width 0.0889)
		(layer "In11.Cu")
		(net "M_J_DQ<12>")
	)
	(arc
		(start 68.912486 -61.13399)
		(mid 69.19791 -61.050523)
		(end 69.406516 -60.838588)
		(width 0.0889)
		(layer "In11.Cu")
		(net "M_J_DQ<12>")
	)
	(arc
		(start 72.343772 -62.12459)
		(mid 72.535414 -62.181756)
		(end 72.675496 -62.324488)
		(width 0.0889)
		(layer "In11.Cu")
		(net "M_J_DQ<12>")
	)
	(arc
		(start 70.626732 -61.13399)
		(mid 70.818374 -61.191156)
		(end 70.958456 -61.333888)
		(width 0.0889)
		(layer "In11.Cu")
		(net "M_J_DQ<12>")
	)
	(arc
		(start 74.919332 -63.419736)
		(mid 75.110974 -63.36257)
		(end 75.251056 -63.219838)
		(width 0.0889)
		(layer "In11.Cu")
		(net "M_J_DQ<12>")
	)
	(segment
		(start 48.399446 3.778758)
		(end 48.399446 2.514854)
		(width 0.1651)
		(layer "F.Cu")
		(net "M_J_DQ<11>")
	)
	(segment
		(start 76.334366 -58.561986)
		(end 75.762866 -58.561986)
		(width 0.0889)
		(layer "F.Cu")
		(net "M_J_DQ<11>")
	)
	(via
		(at 48.399446 2.514854)
		(size 0.508)
		(drill 0.254)
		(layers "F.Cu" "B.Cu")
		(net "M_J_DQ<11>")
	)
	(via
		(at 49.24933 -3.076956)
		(size 0.508)
		(drill 0.254)
		(layers "F.Cu" "B.Cu")
		(net "M_J_DQ<11>")
	)
	(via
		(at 75.762866 -58.561986)
		(size 0.508)
		(drill 0.254)
		(layers "F.Cu" "B.Cu")
		(net "M_J_DQ<11>")
	)
	(segment
		(start 49.249584 -1.021842)
		(end 49.24933 -1.022096)
		(width 0.1651)
		(layer "B.Cu")
		(net "M_J_DQ<11>")
	)
	(segment
		(start 49.24933 -1.022096)
		(end 49.24933 -3.076956)
		(width 0.1651)
		(layer "B.Cu")
		(net "M_J_DQ<11>")
	)
	(segment
		(start 54.699662 -40.29329)
		(end 54.963822 -40.02913)
		(width 0.14224)
		(layer "In11.Cu")
		(net "M_J_DQ<11>")
	)
	(segment
		(start 57.1881 -42.008806)
		(end 57.1881 -41.789858)
		(width 0.14224)
		(layer "In11.Cu")
		(net "M_J_DQ<11>")
	)
	(segment
		(start 49.602136 0.581152)
		(end 49.757584 0.7366)
		(width 0.14224)
		(layer "In11.Cu")
		(net "M_J_DQ<11>")
	)
	(segment
		(start 56.332882 -41.110408)
		(end 56.332882 -40.891714)
		(width 0.14224)
		(layer "In11.Cu")
		(net "M_J_DQ<11>")
	)
	(segment
		(start 57.626504 -42.44721)
		(end 57.24906 -42.824654)
		(width 0.14224)
		(layer "In11.Cu")
		(net "M_J_DQ<11>")
	)
	(segment
		(start 54.239668 -39.833042)
		(end 54.0385 -39.833042)
		(width 0.14224)
		(layer "In11.Cu")
		(net "M_J_DQ<11>")
	)
	(segment
		(start 55.276496 -41.071038)
		(end 54.699408 -40.49395)
		(width 0.14224)
		(layer "In11.Cu")
		(net "M_J_DQ<11>")
	)
	(segment
		(start 49.781714 -13.516356)
		(end 49.781714 -12.398756)
		(width 0.14224)
		(layer "In11.Cu")
		(net "M_J_DQ<11>")
	)
	(segment
		(start 60.537344 -46.331886)
		(end 60.317888 -46.11243)
		(width 0.14224)
		(layer "In11.Cu")
		(net "M_J_DQ<11>")
	)
	(segment
		(start 59.818524 -44.63923)
		(end 59.818524 -44.420282)
		(width 0.14224)
		(layer "In11.Cu")
		(net "M_J_DQ<11>")
	)
	(segment
		(start 49.756314 -7.429246)
		(end 49.616614 -7.289546)
		(width 0.14224)
		(layer "In11.Cu")
		(net "M_J_DQ<11>")
	)
	(segment
		(start 54.963822 -40.02913)
		(end 54.963822 -39.827962)
		(width 0.14224)
		(layer "In11.Cu")
		(net "M_J_DQ<11>")
	)
	(segment
		(start 56.810656 -42.38625)
		(end 57.1881 -42.008806)
		(width 0.14224)
		(layer "In11.Cu")
		(net "M_J_DQ<11>")
	)
	(segment
		(start 58.783728 -44.57827)
		(end 58.564272 -44.358814)
		(width 0.14224)
		(layer "In11.Cu")
		(net "M_J_DQ<11>")
	)
	(segment
		(start 56.332882 -40.891714)
		(end 56.113426 -40.672258)
		(width 0.14224)
		(layer "In11.Cu")
		(net "M_J_DQ<11>")
	)
	(segment
		(start 49.300384 1.5494)
		(end 49.046384 1.5494)
		(width 0.14224)
		(layer "In11.Cu")
		(net "M_J_DQ<11>")
	)
	(segment
		(start 57.90692 -43.701462)
		(end 57.687464 -43.482006)
		(width 0.14224)
		(layer "In11.Cu")
		(net "M_J_DQ<11>")
	)
	(segment
		(start 49.603914 -18.567654)
		(end 49.756314 -18.415254)
		(width 0.14224)
		(layer "In11.Cu")
		(net "M_J_DQ<11>")
	)
	(segment
		(start 52.829968 -38.62451)
		(end 52.829968 -37.922454)
		(width 0.14224)
		(layer "In11.Cu")
		(net "M_J_DQ<11>")
	)
	(segment
		(start 54.704996 -39.569136)
		(end 54.503828 -39.568882)
		(width 0.14224)
		(layer "In11.Cu")
		(net "M_J_DQ<11>")
	)
	(segment
		(start 59.44108 -45.235622)
		(end 59.44108 -45.016674)
		(width 0.14224)
		(layer "In11.Cu")
		(net "M_J_DQ<11>")
	)
	(segment
		(start 53.785008 -38.649148)
		(end 53.58384 -38.648894)
		(width 0.14224)
		(layer "In11.Cu")
		(net "M_J_DQ<11>")
	)
	(segment
		(start 49.781968 -9.525)
		(end 49.603914 -9.346946)
		(width 0.14224)
		(layer "In11.Cu")
		(net "M_J_DQ<11>")
	)
	(segment
		(start 58.941716 -43.543474)
		(end 58.72226 -43.324018)
		(width 0.14224)
		(layer "In11.Cu")
		(net "M_J_DQ<11>")
	)
	(segment
		(start 53.118512 -38.913054)
		(end 52.829968 -38.62451)
		(width 0.14224)
		(layer "In11.Cu")
		(net "M_J_DQ<11>")
	)
	(segment
		(start 48.765714 -3.560572)
		(end 49.24933 -3.076956)
		(width 0.14224)
		(layer "In11.Cu")
		(net "M_J_DQ<11>")
	)
	(segment
		(start 74.940922 -58.466736)
		(end 74.886312 -58.466736)
		(width 0.0889)
		(layer "In11.Cu")
		(net "M_J_DQ<11>")
	)
	(segment
		(start 49.603914 -21.3106)
		(end 49.756568 -21.157946)
		(width 0.14224)
		(layer "In11.Cu")
		(net "M_J_DQ<11>")
	)
	(segment
		(start 49.629314 -28.4734)
		(end 49.629314 -23.335996)
		(width 0.14224)
		(layer "In11.Cu")
		(net "M_J_DQ<11>")
	)
	(segment
		(start 49.616614 -16.890746)
		(end 49.616614 -13.681456)
		(width 0.14224)
		(layer "In11.Cu")
		(net "M_J_DQ<11>")
	)
	(segment
		(start 54.963822 -39.827962)
		(end 54.704996 -39.569136)
		(width 0.14224)
		(layer "In11.Cu")
		(net "M_J_DQ<11>")
	)
	(segment
		(start 49.781968 -11.531346)
		(end 49.781968 -9.525)
		(width 0.14224)
		(layer "In11.Cu")
		(net "M_J_DQ<11>")
	)
	(segment
		(start 59.818524 -44.420282)
		(end 59.599068 -44.200826)
		(width 0.14224)
		(layer "In11.Cu")
		(net "M_J_DQ<11>")
	)
	(segment
		(start 59.38012 -44.200826)
		(end 59.002676 -44.57827)
		(width 0.14224)
		(layer "In11.Cu")
		(net "M_J_DQ<11>")
	)
	(segment
		(start 60.695332 -45.29709)
		(end 60.475876 -45.077634)
		(width 0.14224)
		(layer "In11.Cu")
		(net "M_J_DQ<11>")
	)
	(segment
		(start 57.1881 -41.789858)
		(end 56.968644 -41.570402)
		(width 0.14224)
		(layer "In11.Cu")
		(net "M_J_DQ<11>")
	)
	(segment
		(start 50.67554 -29.519626)
		(end 49.629314 -28.4734)
		(width 0.14224)
		(layer "In11.Cu")
		(net "M_J_DQ<11>")
	)
	(segment
		(start 57.687464 -43.263058)
		(end 58.064908 -42.885614)
		(width 0.14224)
		(layer "In11.Cu")
		(net "M_J_DQ<11>")
	)
	(segment
		(start 49.046384 1.5494)
		(end 48.716184 1.8796)
		(width 0.14224)
		(layer "In11.Cu")
		(net "M_J_DQ<11>")
	)
	(segment
		(start 55.933848 -41.509442)
		(end 56.332882 -41.110408)
		(width 0.14224)
		(layer "In11.Cu")
		(net "M_J_DQ<11>")
	)
	(segment
		(start 55.933848 -41.72839)
		(end 55.933848 -41.509442)
		(width 0.14224)
		(layer "In11.Cu")
		(net "M_J_DQ<11>")
	)
	(segment
		(start 71.488046 -56.485536)
		(end 71.45528 -56.485536)
		(width 0.0889)
		(layer "In11.Cu")
		(net "M_J_DQ<11>")
	)
	(segment
		(start 60.256928 -45.077634)
		(end 59.879484 -45.455078)
		(width 0.14224)
		(layer "In11.Cu")
		(net "M_J_DQ<11>")
	)
	(segment
		(start 60.695332 -45.516038)
		(end 60.695332 -45.29709)
		(width 0.14224)
		(layer "In11.Cu")
		(net "M_J_DQ<11>")
	)
	(segment
		(start 55.894224 -40.672258)
		(end 55.495444 -41.071038)
		(width 0.14224)
		(layer "In11.Cu")
		(net "M_J_DQ<11>")
	)
	(segment
		(start 53.58384 -38.648894)
		(end 53.31968 -38.913054)
		(width 0.14224)
		(layer "In11.Cu")
		(net "M_J_DQ<11>")
	)
	(segment
		(start 49.603914 -9.346946)
		(end 49.603914 -8.941054)
		(width 0.14224)
		(layer "In11.Cu")
		(net "M_J_DQ<11>")
	)
	(segment
		(start 61.194696 -46.77029)
		(end 61.57214 -46.392846)
		(width 0.14224)
		(layer "In11.Cu")
		(net "M_J_DQ<11>")
	)
	(segment
		(start 49.603914 -11.7094)
		(end 49.781968 -11.531346)
		(width 0.14224)
		(layer "In11.Cu")
		(net "M_J_DQ<11>")
	)
	(segment
		(start 58.941716 -43.762422)
		(end 58.941716 -43.543474)
		(width 0.14224)
		(layer "In11.Cu")
		(net "M_J_DQ<11>")
	)
	(segment
		(start 49.757584 1.0922)
		(end 49.300384 1.5494)
		(width 0.14224)
		(layer "In11.Cu")
		(net "M_J_DQ<11>")
	)
	(segment
		(start 58.503312 -43.324018)
		(end 58.125868 -43.701462)
		(width 0.14224)
		(layer "In11.Cu")
		(net "M_J_DQ<11>")
	)
	(segment
		(start 50.67554 -35.768026)
		(end 50.67554 -29.519626)
		(width 0.14224)
		(layer "In11.Cu")
		(net "M_J_DQ<11>")
	)
	(segment
		(start 49.756568 -19.2532)
		(end 49.603914 -19.100546)
		(width 0.14224)
		(layer "In11.Cu")
		(net "M_J_DQ<11>")
	)
	(segment
		(start 61.352684 -45.954442)
		(end 61.133736 -45.954442)
		(width 0.14224)
		(layer "In11.Cu")
		(net "M_J_DQ<11>")
	)
	(segment
		(start 49.24933 -3.076956)
		(end 49.602136 -2.72415)
		(width 0.14224)
		(layer "In11.Cu")
		(net "M_J_DQ<11>")
	)
	(segment
		(start 49.629314 -23.335996)
		(end 49.781714 -23.183596)
		(width 0.14224)
		(layer "In11.Cu")
		(net "M_J_DQ<11>")
	)
	(segment
		(start 48.716184 1.8796)
		(end 48.716184 2.198116)
		(width 0.14224)
		(layer "In11.Cu")
		(net "M_J_DQ<11>")
	)
	(segment
		(start 56.968644 -41.570402)
		(end 56.749696 -41.570402)
		(width 0.14224)
		(layer "In11.Cu")
		(net "M_J_DQ<11>")
	)
	(segment
		(start 49.616614 -13.681456)
		(end 49.781714 -13.516356)
		(width 0.14224)
		(layer "In11.Cu")
		(net "M_J_DQ<11>")
	)
	(segment
		(start 54.0385 -39.833042)
		(end 53.77942 -39.573962)
		(width 0.14224)
		(layer "In11.Cu")
		(net "M_J_DQ<11>")
	)
	(segment
		(start 49.603914 -19.100546)
		(end 49.603914 -18.567654)
		(width 0.14224)
		(layer "In11.Cu")
		(net "M_J_DQ<11>")
	)
	(segment
		(start 49.616614 -5.1308)
		(end 49.132236 -4.646422)
		(width 0.14224)
		(layer "In11.Cu")
		(net "M_J_DQ<11>")
	)
	(segment
		(start 59.599068 -44.200826)
		(end 59.38012 -44.200826)
		(width 0.14224)
		(layer "In11.Cu")
		(net "M_J_DQ<11>")
	)
	(segment
		(start 66.758312 -53.297582)
		(end 65.682368 -52.221638)
		(width 0.14224)
		(layer "In11.Cu")
		(net "M_J_DQ<11>")
	)
	(segment
		(start 49.757584 0.7366)
		(end 49.757584 1.0922)
		(width 0.14224)
		(layer "In11.Cu")
		(net "M_J_DQ<11>")
	)
	(segment
		(start 53.31968 -38.913054)
		(end 53.118512 -38.913054)
		(width 0.14224)
		(layer "In11.Cu")
		(net "M_J_DQ<11>")
	)
	(segment
		(start 49.602136 -2.72415)
		(end 49.602136 0.581152)
		(width 0.14224)
		(layer "In11.Cu")
		(net "M_J_DQ<11>")
	)
	(segment
		(start 53.77942 -39.573962)
		(end 53.779674 -39.373302)
		(width 0.14224)
		(layer "In11.Cu")
		(net "M_J_DQ<11>")
	)
	(segment
		(start 56.372252 -41.947846)
		(end 56.153304 -41.947846)
		(width 0.14224)
		(layer "In11.Cu")
		(net "M_J_DQ<11>")
	)
	(segment
		(start 57.24906 -42.824654)
		(end 57.030112 -42.824654)
		(width 0.14224)
		(layer "In11.Cu")
		(net "M_J_DQ<11>")
	)
	(segment
		(start 58.72226 -43.324018)
		(end 58.503312 -43.324018)
		(width 0.14224)
		(layer "In11.Cu")
		(net "M_J_DQ<11>")
	)
	(segment
		(start 60.475876 -45.077634)
		(end 60.256928 -45.077634)
		(width 0.14224)
		(layer "In11.Cu")
		(net "M_J_DQ<11>")
	)
	(segment
		(start 59.879484 -45.455078)
		(end 59.660536 -45.455078)
		(width 0.14224)
		(layer "In11.Cu")
		(net "M_J_DQ<11>")
	)
	(segment
		(start 74.063606 -57.971436)
		(end 74.027792 -57.971436)
		(width 0.0889)
		(layer "In11.Cu")
		(net "M_J_DQ<11>")
	)
	(segment
		(start 61.57214 -46.392846)
		(end 61.57214 -46.173898)
		(width 0.14224)
		(layer "In11.Cu")
		(net "M_J_DQ<11>")
	)
	(segment
		(start 54.043834 -39.109142)
		(end 54.043834 -38.907974)
		(width 0.14224)
		(layer "In11.Cu")
		(net "M_J_DQ<11>")
	)
	(segment
		(start 60.317888 -46.11243)
		(end 60.317888 -45.893482)
		(width 0.14224)
		(layer "In11.Cu")
		(net "M_J_DQ<11>")
	)
	(segment
		(start 58.064908 -42.666666)
		(end 57.845452 -42.44721)
		(width 0.14224)
		(layer "In11.Cu")
		(net "M_J_DQ<11>")
	)
	(segment
		(start 49.132236 -4.646422)
		(end 49.132236 -4.332478)
		(width 0.14224)
		(layer "In11.Cu")
		(net "M_J_DQ<11>")
	)
	(segment
		(start 59.002676 -44.57827)
		(end 58.783728 -44.57827)
		(width 0.14224)
		(layer "In11.Cu")
		(net "M_J_DQ<11>")
	)
	(segment
		(start 49.756314 -8.788654)
		(end 49.756314 -7.429246)
		(width 0.14224)
		(layer "In11.Cu")
		(net "M_J_DQ<11>")
	)
	(segment
		(start 58.564272 -44.139866)
		(end 58.941716 -43.762422)
		(width 0.14224)
		(layer "In11.Cu")
		(net "M_J_DQ<11>")
	)
	(segment
		(start 49.781714 -12.398756)
		(end 49.603914 -12.220956)
		(width 0.14224)
		(layer "In11.Cu")
		(net "M_J_DQ<11>")
	)
	(segment
		(start 58.564272 -44.358814)
		(end 58.564272 -44.139866)
		(width 0.14224)
		(layer "In11.Cu")
		(net "M_J_DQ<11>")
	)
	(segment
		(start 49.616614 -7.289546)
		(end 49.616614 -5.1308)
		(width 0.14224)
		(layer "In11.Cu")
		(net "M_J_DQ<11>")
	)
	(segment
		(start 57.687464 -43.482006)
		(end 57.687464 -43.263058)
		(width 0.14224)
		(layer "In11.Cu")
		(net "M_J_DQ<11>")
	)
	(segment
		(start 56.153304 -41.947846)
		(end 55.933848 -41.72839)
		(width 0.14224)
		(layer "In11.Cu")
		(net "M_J_DQ<11>")
	)
	(segment
		(start 56.113426 -40.672258)
		(end 55.894224 -40.672258)
		(width 0.14224)
		(layer "In11.Cu")
		(net "M_J_DQ<11>")
	)
	(segment
		(start 61.194696 -46.989238)
		(end 61.194696 -46.77029)
		(width 0.14224)
		(layer "In11.Cu")
		(net "M_J_DQ<11>")
	)
	(segment
		(start 49.756314 -18.415254)
		(end 49.756314 -17.030446)
		(width 0.14224)
		(layer "In11.Cu")
		(net "M_J_DQ<11>")
	)
	(segment
		(start 56.749696 -41.570402)
		(end 56.372252 -41.947846)
		(width 0.14224)
		(layer "In11.Cu")
		(net "M_J_DQ<11>")
	)
	(segment
		(start 61.133736 -45.954442)
		(end 60.756292 -46.331886)
		(width 0.14224)
		(layer "In11.Cu")
		(net "M_J_DQ<11>")
	)
	(segment
		(start 48.716184 2.198116)
		(end 48.399446 2.514854)
		(width 0.14224)
		(layer "In11.Cu")
		(net "M_J_DQ<11>")
	)
	(segment
		(start 49.603914 -8.941054)
		(end 49.756314 -8.788654)
		(width 0.14224)
		(layer "In11.Cu")
		(net "M_J_DQ<11>")
	)
	(segment
		(start 73.20026 -57.476136)
		(end 73.17232 -57.476136)
		(width 0.0889)
		(layer "In11.Cu")
		(net "M_J_DQ<11>")
	)
	(segment
		(start 69.771006 -55.494936)
		(end 69.217286 -55.494936)
		(width 0.0889)
		(layer "In11.Cu")
		(net "M_J_DQ<11>")
	)
	(segment
		(start 66.994024 -53.533294)
		(end 66.758312 -53.297582)
		(width 0.0889)
		(layer "In11.Cu")
		(net "M_J_DQ<11>")
	)
	(segment
		(start 60.756292 -46.331886)
		(end 60.537344 -46.331886)
		(width 0.14224)
		(layer "In11.Cu")
		(net "M_J_DQ<11>")
	)
	(segment
		(start 60.317888 -45.893482)
		(end 60.695332 -45.516038)
		(width 0.14224)
		(layer "In11.Cu")
		(net "M_J_DQ<11>")
	)
	(segment
		(start 48.765714 -3.965956)
		(end 48.765714 -3.560572)
		(width 0.14224)
		(layer "In11.Cu")
		(net "M_J_DQ<11>")
	)
	(segment
		(start 58.064908 -42.885614)
		(end 58.064908 -42.666666)
		(width 0.14224)
		(layer "In11.Cu")
		(net "M_J_DQ<11>")
	)
	(segment
		(start 49.756568 -21.157946)
		(end 49.756568 -19.2532)
		(width 0.14224)
		(layer "In11.Cu")
		(net "M_J_DQ<11>")
	)
	(segment
		(start 65.682368 -51.47691)
		(end 61.194696 -46.989238)
		(width 0.14224)
		(layer "In11.Cu")
		(net "M_J_DQ<11>")
	)
	(segment
		(start 54.503828 -39.568882)
		(end 54.239668 -39.833042)
		(width 0.14224)
		(layer "In11.Cu")
		(net "M_J_DQ<11>")
	)
	(segment
		(start 53.779674 -39.373302)
		(end 54.043834 -39.109142)
		(width 0.14224)
		(layer "In11.Cu")
		(net "M_J_DQ<11>")
	)
	(segment
		(start 59.660536 -45.455078)
		(end 59.44108 -45.235622)
		(width 0.14224)
		(layer "In11.Cu")
		(net "M_J_DQ<11>")
	)
	(segment
		(start 65.682368 -52.221638)
		(end 65.682368 -51.47691)
		(width 0.14224)
		(layer "In11.Cu")
		(net "M_J_DQ<11>")
	)
	(segment
		(start 75.762866 -58.561986)
		(end 74.940922 -58.466736)
		(width 0.0889)
		(layer "In11.Cu")
		(net "M_J_DQ<11>")
	)
	(segment
		(start 54.043834 -38.907974)
		(end 53.785008 -38.649148)
		(width 0.14224)
		(layer "In11.Cu")
		(net "M_J_DQ<11>")
	)
	(segment
		(start 57.030112 -42.824654)
		(end 56.810656 -42.605198)
		(width 0.14224)
		(layer "In11.Cu")
		(net "M_J_DQ<11>")
	)
	(segment
		(start 59.44108 -45.016674)
		(end 59.818524 -44.63923)
		(width 0.14224)
		(layer "In11.Cu")
		(net "M_J_DQ<11>")
	)
	(segment
		(start 67.255644 -53.533294)
		(end 66.994024 -53.533294)
		(width 0.0889)
		(layer "In11.Cu")
		(net "M_J_DQ<11>")
	)
	(segment
		(start 61.57214 -46.173898)
		(end 61.352684 -45.954442)
		(width 0.14224)
		(layer "In11.Cu")
		(net "M_J_DQ<11>")
	)
	(segment
		(start 56.810656 -42.605198)
		(end 56.810656 -42.38625)
		(width 0.14224)
		(layer "In11.Cu")
		(net "M_J_DQ<11>")
	)
	(segment
		(start 49.132236 -4.332478)
		(end 48.765714 -3.965956)
		(width 0.14224)
		(layer "In11.Cu")
		(net "M_J_DQ<11>")
	)
	(segment
		(start 70.633336 -55.99049)
		(end 70.60057 -55.99049)
		(width 0.0889)
		(layer "In11.Cu")
		(net "M_J_DQ<11>")
	)
	(segment
		(start 54.699408 -40.49395)
		(end 54.699662 -40.29329)
		(width 0.14224)
		(layer "In11.Cu")
		(net "M_J_DQ<11>")
	)
	(segment
		(start 58.125868 -43.701462)
		(end 57.90692 -43.701462)
		(width 0.14224)
		(layer "In11.Cu")
		(net "M_J_DQ<11>")
	)
	(segment
		(start 49.781714 -23.183596)
		(end 49.781714 -21.999956)
		(width 0.14224)
		(layer "In11.Cu")
		(net "M_J_DQ<11>")
	)
	(segment
		(start 49.603914 -21.822156)
		(end 49.603914 -21.3106)
		(width 0.14224)
		(layer "In11.Cu")
		(net "M_J_DQ<11>")
	)
	(segment
		(start 49.756314 -17.030446)
		(end 49.616614 -16.890746)
		(width 0.14224)
		(layer "In11.Cu")
		(net "M_J_DQ<11>")
	)
	(segment
		(start 69.217286 -55.494936)
		(end 67.255644 -53.533294)
		(width 0.0889)
		(layer "In11.Cu")
		(net "M_J_DQ<11>")
	)
	(segment
		(start 52.829968 -37.922454)
		(end 50.67554 -35.768026)
		(width 0.14224)
		(layer "In11.Cu")
		(net "M_J_DQ<11>")
	)
	(segment
		(start 72.350376 -56.98109)
		(end 72.31761 -56.98109)
		(width 0.0889)
		(layer "In11.Cu")
		(net "M_J_DQ<11>")
	)
	(segment
		(start 49.781714 -21.999956)
		(end 49.603914 -21.822156)
		(width 0.14224)
		(layer "In11.Cu")
		(net "M_J_DQ<11>")
	)
	(segment
		(start 55.495444 -41.071038)
		(end 55.276496 -41.071038)
		(width 0.14224)
		(layer "In11.Cu")
		(net "M_J_DQ<11>")
	)
	(segment
		(start 57.845452 -42.44721)
		(end 57.626504 -42.44721)
		(width 0.14224)
		(layer "In11.Cu")
		(net "M_J_DQ<11>")
	)
	(segment
		(start 49.603914 -12.220956)
		(end 49.603914 -11.7094)
		(width 0.14224)
		(layer "In11.Cu")
		(net "M_J_DQ<11>")
	)
	(arc
		(start 71.45528 -56.485536)
		(mid 71.263638 -56.42837)
		(end 71.123556 -56.285638)
		(width 0.0889)
		(layer "In11.Cu")
		(net "M_J_DQ<11>")
	)
	(arc
		(start 71.982076 -56.780938)
		(mid 71.773468 -56.569006)
		(end 71.488046 -56.485536)
		(width 0.0889)
		(layer "In11.Cu")
		(net "M_J_DQ<11>")
	)
	(arc
		(start 74.027792 -57.971436)
		(mid 73.837863 -57.913566)
		(end 73.699116 -57.771538)
		(width 0.0889)
		(layer "In11.Cu")
		(net "M_J_DQ<11>")
	)
	(arc
		(start 72.31761 -56.98109)
		(mid 72.12376 -56.92474)
		(end 71.982076 -56.780938)
		(width 0.0889)
		(layer "In11.Cu")
		(net "M_J_DQ<11>")
	)
	(arc
		(start 74.886312 -58.466736)
		(mid 74.696383 -58.408866)
		(end 74.557636 -58.266838)
		(width 0.0889)
		(layer "In11.Cu")
		(net "M_J_DQ<11>")
	)
	(arc
		(start 74.557636 -58.266838)
		(mid 74.349028 -58.054906)
		(end 74.063606 -57.971436)
		(width 0.0889)
		(layer "In11.Cu")
		(net "M_J_DQ<11>")
	)
	(arc
		(start 73.699116 -57.771538)
		(mid 73.488403 -57.558459)
		(end 73.20026 -57.476136)
		(width 0.0889)
		(layer "In11.Cu")
		(net "M_J_DQ<11>")
	)
	(arc
		(start 70.265036 -55.790338)
		(mid 70.056428 -55.578406)
		(end 69.771006 -55.494936)
		(width 0.0889)
		(layer "In11.Cu")
		(net "M_J_DQ<11>")
	)
	(arc
		(start 71.123556 -56.285638)
		(mid 70.916552 -56.074774)
		(end 70.633336 -55.99049)
		(width 0.0889)
		(layer "In11.Cu")
		(net "M_J_DQ<11>")
	)
	(arc
		(start 70.60057 -55.99049)
		(mid 70.40672 -55.93414)
		(end 70.265036 -55.790338)
		(width 0.0889)
		(layer "In11.Cu")
		(net "M_J_DQ<11>")
	)
	(arc
		(start 72.840596 -57.276238)
		(mid 72.633592 -57.065374)
		(end 72.350376 -56.98109)
		(width 0.0889)
		(layer "In11.Cu")
		(net "M_J_DQ<11>")
	)
	(arc
		(start 73.17232 -57.476136)
		(mid 72.980678 -57.41897)
		(end 72.840596 -57.276238)
		(width 0.0889)
		(layer "In11.Cu")
		(net "M_J_DQ<11>")
	)
	(segment
		(start 49.24933 0.662432)
		(end 49.24933 0.9398)
		(width 0.1651)
		(layer "F.Cu")
		(net "M_J_DQ<10>")
	)
	(segment
		(start 49.380902 0.30734)
		(end 49.380902 0.53086)
		(width 0.1651)
		(layer "F.Cu")
		(net "M_J_DQ<10>")
	)
	(segment
		(start 49.380902 0.53086)
		(end 49.24933 0.662432)
		(width 0.1651)
		(layer "F.Cu")
		(net "M_J_DQ<10>")
	)
	(segment
		(start 49.249584 -0.821182)
		(end 49.24933 -0.820928)
		(width 0.1651)
		(layer "F.Cu")
		(net "M_J_DQ<10>")
	)
	(segment
		(start 75.475846 -59.057286)
		(end 74.904346 -59.057286)
		(width 0.0889)
		(layer "F.Cu")
		(net "M_J_DQ<10>")
	)
	(segment
		(start 49.24933 0.175768)
		(end 49.380902 0.30734)
		(width 0.1651)
		(layer "F.Cu")
		(net "M_J_DQ<10>")
	)
	(segment
		(start 49.24933 -0.820928)
		(end 49.24933 0.175768)
		(width 0.1651)
		(layer "F.Cu")
		(net "M_J_DQ<10>")
	)
	(via
		(at 49.24933 0.9398)
		(size 0.508)
		(drill 0.254)
		(layers "F.Cu" "B.Cu")
		(net "M_J_DQ<10>")
	)
	(via
		(at 74.904346 -59.057286)
		(size 0.508)
		(drill 0.254)
		(layers "F.Cu" "B.Cu")
		(net "M_J_DQ<10>")
	)
	(via
		(at 48.399446 -4.357878)
		(size 0.508)
		(drill 0.254)
		(layers "F.Cu" "B.Cu")
		(net "M_J_DQ<10>")
	)
	(segment
		(start 48.399446 -5.621782)
		(end 48.399446 -4.357878)
		(width 0.1651)
		(layer "B.Cu")
		(net "M_J_DQ<10>")
	)
	(segment
		(start 57.96915 -44.54525)
		(end 57.96915 -44.764198)
		(width 0.14224)
		(layer "In11.Cu")
		(net "M_J_DQ<10>")
	)
	(segment
		(start 49.553368 -29.8196)
		(end 49.553368 -36.129468)
		(width 0.14224)
		(layer "In11.Cu")
		(net "M_J_DQ<10>")
	)
	(segment
		(start 51.786282 -38.362382)
		(end 57.092342 -43.668442)
		(width 0.14224)
		(layer "In11.Cu")
		(net "M_J_DQ<10>")
	)
	(segment
		(start 48.892714 -19.024854)
		(end 48.765968 -19.1516)
		(width 0.14224)
		(layer "In11.Cu")
		(net "M_J_DQ<10>")
	)
	(segment
		(start 62.246002 -49.04105)
		(end 62.46495 -49.04105)
		(width 0.14224)
		(layer "In11.Cu")
		(net "M_J_DQ<10>")
	)
	(segment
		(start 59.657488 -47.245524)
		(end 59.657488 -47.464472)
		(width 0.14224)
		(layer "In11.Cu")
		(net "M_J_DQ<10>")
	)
	(segment
		(start 48.740314 -13.541756)
		(end 48.981614 -13.783056)
		(width 0.14224)
		(layer "In11.Cu")
		(net "M_J_DQ<10>")
	)
	(segment
		(start 50.866294 -37.241226)
		(end 50.866294 -37.442394)
		(width 0.14224)
		(layer "In11.Cu")
		(net "M_J_DQ<10>")
	)
	(segment
		(start 48.114712 -3.3274)
		(end 48.114712 -4.073144)
		(width 0.14224)
		(layer "In11.Cu")
		(net "M_J_DQ<10>")
	)
	(segment
		(start 63.384176 -51.19116)
		(end 63.603124 -51.19116)
		(width 0.14224)
		(layer "In11.Cu")
		(net "M_J_DQ<10>")
	)
	(segment
		(start 48.892714 -8.991346)
		(end 48.892714 -9.372854)
		(width 0.14224)
		(layer "In11.Cu")
		(net "M_J_DQ<10>")
	)
	(segment
		(start 59.284362 -46.07941)
		(end 59.50331 -46.07941)
		(width 0.14224)
		(layer "In11.Cu")
		(net "M_J_DQ<10>")
	)
	(segment
		(start 48.851312 0.236728)
		(end 48.50638 -0.108204)
		(width 0.14224)
		(layer "In11.Cu")
		(net "M_J_DQ<10>")
	)
	(segment
		(start 74.4093 -58.391552)
		(end 74.904346 -59.057286)
		(width 0.0889)
		(layer "In11.Cu")
		(net "M_J_DQ<10>")
	)
	(segment
		(start 67.177412 -53.723794)
		(end 69.139054 -55.685436)
		(width 0.0889)
		(layer "In11.Cu")
		(net "M_J_DQ<10>")
	)
	(segment
		(start 50.866294 -37.442394)
		(end 51.12512 -37.70122)
		(width 0.14224)
		(layer "In11.Cu")
		(net "M_J_DQ<10>")
	)
	(segment
		(start 63.16472 -50.971704)
		(end 63.384176 -51.19116)
		(width 0.14224)
		(layer "In11.Cu")
		(net "M_J_DQ<10>")
	)
	(segment
		(start 51.01336 -36.892992)
		(end 51.01336 -37.09416)
		(width 0.14224)
		(layer "In11.Cu")
		(net "M_J_DQ<10>")
	)
	(segment
		(start 64.683386 -52.072794)
		(end 66.543174 -53.932582)
		(width 0.14224)
		(layer "In11.Cu")
		(net "M_J_DQ<10>")
	)
	(segment
		(start 48.81118 -1.04775)
		(end 48.50638 -1.35255)
		(width 0.14224)
		(layer "In11.Cu")
		(net "M_J_DQ<10>")
	)
	(segment
		(start 48.114712 -4.073144)
		(end 48.399446 -4.357878)
		(width 0.14224)
		(layer "In11.Cu")
		(net "M_J_DQ<10>")
	)
	(segment
		(start 51.786282 -38.161214)
		(end 51.786282 -38.362382)
		(width 0.14224)
		(layer "In11.Cu")
		(net "M_J_DQ<10>")
	)
	(segment
		(start 48.860964 -23.263606)
		(end 48.860964 -29.127196)
		(width 0.14224)
		(layer "In11.Cu")
		(net "M_J_DQ<10>")
	)
	(segment
		(start 59.657488 -47.464472)
		(end 59.876944 -47.683928)
		(width 0.14224)
		(layer "In11.Cu")
		(net "M_J_DQ<10>")
	)
	(segment
		(start 48.81118 -0.761746)
		(end 48.81118 -1.04775)
		(width 0.14224)
		(layer "In11.Cu")
		(net "M_J_DQ<10>")
	)
	(segment
		(start 48.50638 -1.35255)
		(end 48.50638 -1.7526)
		(width 0.14224)
		(layer "In11.Cu")
		(net "M_J_DQ<10>")
	)
	(segment
		(start 63.561214 -50.356262)
		(end 63.16472 -50.752756)
		(width 0.14224)
		(layer "In11.Cu")
		(net "M_J_DQ<10>")
	)
	(segment
		(start 57.96915 -44.764198)
		(end 57.58434 -45.149008)
		(width 0.14224)
		(layer "In11.Cu")
		(net "M_J_DQ<10>")
	)
	(segment
		(start 74.392536 -58.362088)
		(end 74.4093 -58.391552)
		(width 0.0889)
		(layer "In11.Cu")
		(net "M_J_DQ<10>")
	)
	(segment
		(start 58.461148 -46.244764)
		(end 58.680604 -46.46422)
		(width 0.14224)
		(layer "In11.Cu")
		(net "M_J_DQ<10>")
	)
	(segment
		(start 48.968914 -5.460746)
		(end 48.968914 -7.162546)
		(width 0.14224)
		(layer "In11.Cu")
		(net "M_J_DQ<10>")
	)
	(segment
		(start 70.593966 -56.18099)
		(end 70.626732 -56.18099)
		(width 0.0889)
		(layer "In11.Cu")
		(net "M_J_DQ<10>")
	)
	(segment
		(start 48.765968 -19.1516)
		(end 48.765968 -21.209254)
		(width 0.14224)
		(layer "In11.Cu")
		(net "M_J_DQ<10>")
	)
	(segment
		(start 56.707532 -44.2722)
		(end 56.707532 -44.491148)
		(width 0.14224)
		(layer "In11.Cu")
		(net "M_J_DQ<10>")
	)
	(segment
		(start 48.740314 -21.949156)
		(end 48.740314 -23.142956)
		(width 0.14224)
		(layer "In11.Cu")
		(net "M_J_DQ<10>")
	)
	(segment
		(start 57.58434 -45.367956)
		(end 57.803796 -45.587412)
		(width 0.14224)
		(layer "In11.Cu")
		(net "M_J_DQ<10>")
	)
	(segment
		(start 60.053982 -46.630082)
		(end 60.053982 -46.84903)
		(width 0.14224)
		(layer "In11.Cu")
		(net "M_J_DQ<10>")
	)
	(segment
		(start 58.845958 -45.422058)
		(end 58.845958 -45.641006)
		(width 0.14224)
		(layer "In11.Cu")
		(net "M_J_DQ<10>")
	)
	(segment
		(start 63.16472 -50.752756)
		(end 63.16472 -50.971704)
		(width 0.14224)
		(layer "In11.Cu")
		(net "M_J_DQ<10>")
	)
	(segment
		(start 62.684406 -49.479454)
		(end 62.287912 -49.875948)
		(width 0.14224)
		(layer "In11.Cu")
		(net "M_J_DQ<10>")
	)
	(segment
		(start 60.534296 -48.34128)
		(end 60.753752 -48.560736)
		(width 0.14224)
		(layer "In11.Cu")
		(net "M_J_DQ<10>")
	)
	(segment
		(start 48.892714 -12.195556)
		(end 48.740314 -12.347956)
		(width 0.14224)
		(layer "In11.Cu")
		(net "M_J_DQ<10>")
	)
	(segment
		(start 57.092342 -43.88739)
		(end 56.707532 -44.2722)
		(width 0.14224)
		(layer "In11.Cu")
		(net "M_J_DQ<10>")
	)
	(segment
		(start 58.845958 -45.641006)
		(end 58.461148 -46.025816)
		(width 0.14224)
		(layer "In11.Cu")
		(net "M_J_DQ<10>")
	)
	(segment
		(start 61.588142 -48.164242)
		(end 61.807598 -48.383698)
		(width 0.14224)
		(layer "In11.Cu")
		(net "M_J_DQ<10>")
	)
	(segment
		(start 50.754534 -36.634166)
		(end 51.01336 -36.892992)
		(width 0.14224)
		(layer "In11.Cu")
		(net "M_J_DQ<10>")
	)
	(segment
		(start 61.63056 -49.437544)
		(end 61.849508 -49.437544)
		(width 0.14224)
		(layer "In11.Cu")
		(net "M_J_DQ<10>")
	)
	(segment
		(start 49.24933 0.9398)
		(end 48.851312 0.541782)
		(width 0.14224)
		(layer "In11.Cu")
		(net "M_J_DQ<10>")
	)
	(segment
		(start 61.807598 -48.602646)
		(end 61.411104 -48.99914)
		(width 0.14224)
		(layer "In11.Cu")
		(net "M_J_DQ<10>")
	)
	(segment
		(start 66.9671 -53.723794)
		(end 67.177412 -53.723794)
		(width 0.0889)
		(layer "In11.Cu")
		(net "M_J_DQ<10>")
	)
	(segment
		(start 51.01336 -37.09416)
		(end 50.866294 -37.241226)
		(width 0.14224)
		(layer "In11.Cu")
		(net "M_J_DQ<10>")
	)
	(segment
		(start 58.022744 -45.587412)
		(end 58.407554 -45.202602)
		(width 0.14224)
		(layer "In11.Cu")
		(net "M_J_DQ<10>")
	)
	(segment
		(start 62.726316 -50.314352)
		(end 63.12281 -49.917858)
		(width 0.14224)
		(layer "In11.Cu")
		(net "M_J_DQ<10>")
	)
	(segment
		(start 58.407554 -45.202602)
		(end 58.626502 -45.202602)
		(width 0.14224)
		(layer "In11.Cu")
		(net "M_J_DQ<10>")
	)
	(segment
		(start 49.553368 -36.129468)
		(end 50.205132 -36.781232)
		(width 0.14224)
		(layer "In11.Cu")
		(net "M_J_DQ<10>")
	)
	(segment
		(start 51.326288 -37.70122)
		(end 51.473354 -37.554154)
		(width 0.14224)
		(layer "In11.Cu")
		(net "M_J_DQ<10>")
	)
	(segment
		(start 58.899552 -46.46422)
		(end 59.284362 -46.07941)
		(width 0.14224)
		(layer "In11.Cu")
		(net "M_J_DQ<10>")
	)
	(segment
		(start 73.174352 -57.66689)
		(end 73.198482 -57.66689)
		(width 0.0889)
		(layer "In11.Cu")
		(net "M_J_DQ<10>")
	)
	(segment
		(start 50.553366 -36.634166)
		(end 50.754534 -36.634166)
		(width 0.14224)
		(layer "In11.Cu")
		(net "M_J_DQ<10>")
	)
	(segment
		(start 60.053982 -46.84903)
		(end 59.657488 -47.245524)
		(width 0.14224)
		(layer "In11.Cu")
		(net "M_J_DQ<10>")
	)
	(segment
		(start 72.311006 -57.17159)
		(end 72.343772 -57.17159)
		(width 0.0889)
		(layer "In11.Cu")
		(net "M_J_DQ<10>")
	)
	(segment
		(start 62.46495 -49.04105)
		(end 62.684406 -49.260506)
		(width 0.14224)
		(layer "In11.Cu")
		(net "M_J_DQ<10>")
	)
	(segment
		(start 48.50638 -0.456946)
		(end 48.81118 -0.761746)
		(width 0.14224)
		(layer "In11.Cu")
		(net "M_J_DQ<10>")
	)
	(segment
		(start 60.753752 -48.560736)
		(end 60.9727 -48.560736)
		(width 0.14224)
		(layer "In11.Cu")
		(net "M_J_DQ<10>")
	)
	(segment
		(start 48.981614 -13.783056)
		(end 48.981614 -16.751046)
		(width 0.14224)
		(layer "In11.Cu")
		(net "M_J_DQ<10>")
	)
	(segment
		(start 48.968914 -7.162546)
		(end 48.765714 -7.365746)
		(width 0.14224)
		(layer "In11.Cu")
		(net "M_J_DQ<10>")
	)
	(segment
		(start 59.50331 -46.07941)
		(end 60.053982 -46.630082)
		(width 0.14224)
		(layer "In11.Cu")
		(net "M_J_DQ<10>")
	)
	(segment
		(start 51.12512 -37.70122)
		(end 51.326288 -37.70122)
		(width 0.14224)
		(layer "In11.Cu")
		(net "M_J_DQ<10>")
	)
	(segment
		(start 57.530746 -44.325794)
		(end 57.749694 -44.325794)
		(width 0.14224)
		(layer "In11.Cu")
		(net "M_J_DQ<10>")
	)
	(segment
		(start 71.448676 -56.676036)
		(end 71.481442 -56.676036)
		(width 0.0889)
		(layer "In11.Cu")
		(net "M_J_DQ<10>")
	)
	(segment
		(start 48.96358 -2.2098)
		(end 48.96358 -2.478532)
		(width 0.14224)
		(layer "In11.Cu")
		(net "M_J_DQ<10>")
	)
	(segment
		(start 48.399446 -4.891278)
		(end 48.968914 -5.460746)
		(width 0.14224)
		(layer "In11.Cu")
		(net "M_J_DQ<10>")
	)
	(segment
		(start 63.341758 -49.917858)
		(end 63.561214 -50.137314)
		(width 0.14224)
		(layer "In11.Cu")
		(net "M_J_DQ<10>")
	)
	(segment
		(start 48.851312 0.541782)
		(end 48.851312 0.236728)
		(width 0.14224)
		(layer "In11.Cu")
		(net "M_J_DQ<10>")
	)
	(segment
		(start 66.543174 -53.932582)
		(end 66.758312 -53.932582)
		(width 0.14224)
		(layer "In11.Cu")
		(net "M_J_DQ<10>")
	)
	(segment
		(start 61.807598 -48.383698)
		(end 61.807598 -48.602646)
		(width 0.14224)
		(layer "In11.Cu")
		(net "M_J_DQ<10>")
	)
	(segment
		(start 58.461148 -46.025816)
		(end 58.461148 -46.244764)
		(width 0.14224)
		(layer "In11.Cu")
		(net "M_J_DQ<10>")
	)
	(segment
		(start 62.684406 -49.260506)
		(end 62.684406 -49.479454)
		(width 0.14224)
		(layer "In11.Cu")
		(net "M_J_DQ<10>")
	)
	(segment
		(start 66.758312 -53.932582)
		(end 66.9671 -53.723794)
		(width 0.0889)
		(layer "In11.Cu")
		(net "M_J_DQ<10>")
	)
	(segment
		(start 60.095892 -47.683928)
		(end 60.492386 -47.287434)
		(width 0.14224)
		(layer "In11.Cu")
		(net "M_J_DQ<10>")
	)
	(segment
		(start 61.411104 -49.218088)
		(end 61.63056 -49.437544)
		(width 0.14224)
		(layer "In11.Cu")
		(net "M_J_DQ<10>")
	)
	(segment
		(start 51.933348 -38.014148)
		(end 51.786282 -38.161214)
		(width 0.14224)
		(layer "In11.Cu")
		(net "M_J_DQ<10>")
	)
	(segment
		(start 48.50638 -0.108204)
		(end 48.50638 -0.456946)
		(width 0.14224)
		(layer "In11.Cu")
		(net "M_J_DQ<10>")
	)
	(segment
		(start 48.892714 -21.336)
		(end 48.892714 -21.796756)
		(width 0.14224)
		(layer "In11.Cu")
		(net "M_J_DQ<10>")
	)
	(segment
		(start 61.411104 -48.99914)
		(end 61.411104 -49.218088)
		(width 0.14224)
		(layer "In11.Cu")
		(net "M_J_DQ<10>")
	)
	(segment
		(start 48.740568 -11.608054)
		(end 48.892714 -11.7602)
		(width 0.14224)
		(layer "In11.Cu")
		(net "M_J_DQ<10>")
	)
	(segment
		(start 61.369194 -48.164242)
		(end 61.588142 -48.164242)
		(width 0.14224)
		(layer "In11.Cu")
		(net "M_J_DQ<10>")
	)
	(segment
		(start 50.4063 -36.781232)
		(end 50.553366 -36.634166)
		(width 0.14224)
		(layer "In11.Cu")
		(net "M_J_DQ<10>")
	)
	(segment
		(start 51.674522 -37.554154)
		(end 51.933348 -37.81298)
		(width 0.14224)
		(layer "In11.Cu")
		(net "M_J_DQ<10>")
	)
	(segment
		(start 63.12281 -49.917858)
		(end 63.341758 -49.917858)
		(width 0.14224)
		(layer "In11.Cu")
		(net "M_J_DQ<10>")
	)
	(segment
		(start 48.765714 -7.365746)
		(end 48.765714 -8.864346)
		(width 0.14224)
		(layer "In11.Cu")
		(net "M_J_DQ<10>")
	)
	(segment
		(start 60.9727 -48.560736)
		(end 61.369194 -48.164242)
		(width 0.14224)
		(layer "In11.Cu")
		(net "M_J_DQ<10>")
	)
	(segment
		(start 48.50638 -1.7526)
		(end 48.96358 -2.2098)
		(width 0.14224)
		(layer "In11.Cu")
		(net "M_J_DQ<10>")
	)
	(segment
		(start 57.58434 -45.149008)
		(end 57.58434 -45.367956)
		(width 0.14224)
		(layer "In11.Cu")
		(net "M_J_DQ<10>")
	)
	(segment
		(start 48.860964 -29.127196)
		(end 49.553368 -29.8196)
		(width 0.14224)
		(layer "In11.Cu")
		(net "M_J_DQ<10>")
	)
	(segment
		(start 48.765714 -8.864346)
		(end 48.892714 -8.991346)
		(width 0.14224)
		(layer "In11.Cu")
		(net "M_J_DQ<10>")
	)
	(segment
		(start 64.218566 -50.794666)
		(end 64.683386 -51.259486)
		(width 0.14224)
		(layer "In11.Cu")
		(net "M_J_DQ<10>")
	)
	(segment
		(start 56.926988 -44.710604)
		(end 57.145936 -44.710604)
		(width 0.14224)
		(layer "In11.Cu")
		(net "M_J_DQ<10>")
	)
	(segment
		(start 48.892714 -9.372854)
		(end 48.740568 -9.525)
		(width 0.14224)
		(layer "In11.Cu")
		(net "M_J_DQ<10>")
	)
	(segment
		(start 63.999618 -50.794666)
		(end 64.218566 -50.794666)
		(width 0.14224)
		(layer "In11.Cu")
		(net "M_J_DQ<10>")
	)
	(segment
		(start 48.399446 -4.357878)
		(end 48.399446 -4.891278)
		(width 0.14224)
		(layer "In11.Cu")
		(net "M_J_DQ<10>")
	)
	(segment
		(start 62.287912 -50.094896)
		(end 62.507368 -50.314352)
		(width 0.14224)
		(layer "In11.Cu")
		(net "M_J_DQ<10>")
	)
	(segment
		(start 48.892714 -21.796756)
		(end 48.740314 -21.949156)
		(width 0.14224)
		(layer "In11.Cu")
		(net "M_J_DQ<10>")
	)
	(segment
		(start 58.626502 -45.202602)
		(end 58.845958 -45.422058)
		(width 0.14224)
		(layer "In11.Cu")
		(net "M_J_DQ<10>")
	)
	(segment
		(start 64.683386 -51.259486)
		(end 64.683386 -52.072794)
		(width 0.14224)
		(layer "In11.Cu")
		(net "M_J_DQ<10>")
	)
	(segment
		(start 48.765714 -18.440146)
		(end 48.892714 -18.567146)
		(width 0.14224)
		(layer "In11.Cu")
		(net "M_J_DQ<10>")
	)
	(segment
		(start 48.765714 -16.966946)
		(end 48.765714 -18.440146)
		(width 0.14224)
		(layer "In11.Cu")
		(net "M_J_DQ<10>")
	)
	(segment
		(start 59.876944 -47.683928)
		(end 60.095892 -47.683928)
		(width 0.14224)
		(layer "In11.Cu")
		(net "M_J_DQ<10>")
	)
	(segment
		(start 56.707532 -44.491148)
		(end 56.926988 -44.710604)
		(width 0.14224)
		(layer "In11.Cu")
		(net "M_J_DQ<10>")
	)
	(segment
		(start 50.205132 -36.781232)
		(end 50.4063 -36.781232)
		(width 0.14224)
		(layer "In11.Cu")
		(net "M_J_DQ<10>")
	)
	(segment
		(start 48.740314 -12.347956)
		(end 48.740314 -13.541756)
		(width 0.14224)
		(layer "In11.Cu")
		(net "M_J_DQ<10>")
	)
	(segment
		(start 60.492386 -47.287434)
		(end 60.711334 -47.287434)
		(width 0.14224)
		(layer "In11.Cu")
		(net "M_J_DQ<10>")
	)
	(segment
		(start 58.680604 -46.46422)
		(end 58.899552 -46.46422)
		(width 0.14224)
		(layer "In11.Cu")
		(net "M_J_DQ<10>")
	)
	(segment
		(start 60.93079 -47.50689)
		(end 60.93079 -47.725838)
		(width 0.14224)
		(layer "In11.Cu")
		(net "M_J_DQ<10>")
	)
	(segment
		(start 63.561214 -50.137314)
		(end 63.561214 -50.356262)
		(width 0.14224)
		(layer "In11.Cu")
		(net "M_J_DQ<10>")
	)
	(segment
		(start 60.711334 -47.287434)
		(end 60.93079 -47.50689)
		(width 0.14224)
		(layer "In11.Cu")
		(net "M_J_DQ<10>")
	)
	(segment
		(start 69.139054 -55.685436)
		(end 69.764402 -55.685436)
		(width 0.0889)
		(layer "In11.Cu")
		(net "M_J_DQ<10>")
	)
	(segment
		(start 62.287912 -49.875948)
		(end 62.287912 -50.094896)
		(width 0.14224)
		(layer "In11.Cu")
		(net "M_J_DQ<10>")
	)
	(segment
		(start 48.740314 -23.142956)
		(end 48.860964 -23.263606)
		(width 0.14224)
		(layer "In11.Cu")
		(net "M_J_DQ<10>")
	)
	(segment
		(start 57.749694 -44.325794)
		(end 57.96915 -44.54525)
		(width 0.14224)
		(layer "In11.Cu")
		(net "M_J_DQ<10>")
	)
	(segment
		(start 48.96358 -2.478532)
		(end 48.114712 -3.3274)
		(width 0.14224)
		(layer "In11.Cu")
		(net "M_J_DQ<10>")
	)
	(segment
		(start 57.092342 -43.668442)
		(end 57.092342 -43.88739)
		(width 0.14224)
		(layer "In11.Cu")
		(net "M_J_DQ<10>")
	)
	(segment
		(start 51.933348 -37.81298)
		(end 51.933348 -38.014148)
		(width 0.14224)
		(layer "In11.Cu")
		(net "M_J_DQ<10>")
	)
	(segment
		(start 48.892714 -18.567146)
		(end 48.892714 -19.024854)
		(width 0.14224)
		(layer "In11.Cu")
		(net "M_J_DQ<10>")
	)
	(segment
		(start 51.473354 -37.554154)
		(end 51.674522 -37.554154)
		(width 0.14224)
		(layer "In11.Cu")
		(net "M_J_DQ<10>")
	)
	(segment
		(start 48.892714 -11.7602)
		(end 48.892714 -12.195556)
		(width 0.14224)
		(layer "In11.Cu")
		(net "M_J_DQ<10>")
	)
	(segment
		(start 57.803796 -45.587412)
		(end 58.022744 -45.587412)
		(width 0.14224)
		(layer "In11.Cu")
		(net "M_J_DQ<10>")
	)
	(segment
		(start 60.93079 -47.725838)
		(end 60.534296 -48.122332)
		(width 0.14224)
		(layer "In11.Cu")
		(net "M_J_DQ<10>")
	)
	(segment
		(start 63.603124 -51.19116)
		(end 63.999618 -50.794666)
		(width 0.14224)
		(layer "In11.Cu")
		(net "M_J_DQ<10>")
	)
	(segment
		(start 74.024236 -58.16219)
		(end 74.06386 -58.16219)
		(width 0.0889)
		(layer "In11.Cu")
		(net "M_J_DQ<10>")
	)
	(segment
		(start 48.740568 -9.525)
		(end 48.740568 -11.608054)
		(width 0.14224)
		(layer "In11.Cu")
		(net "M_J_DQ<10>")
	)
	(segment
		(start 48.981614 -16.751046)
		(end 48.765714 -16.966946)
		(width 0.14224)
		(layer "In11.Cu")
		(net "M_J_DQ<10>")
	)
	(segment
		(start 57.145936 -44.710604)
		(end 57.530746 -44.325794)
		(width 0.14224)
		(layer "In11.Cu")
		(net "M_J_DQ<10>")
	)
	(segment
		(start 62.507368 -50.314352)
		(end 62.726316 -50.314352)
		(width 0.14224)
		(layer "In11.Cu")
		(net "M_J_DQ<10>")
	)
	(segment
		(start 60.534296 -48.122332)
		(end 60.534296 -48.34128)
		(width 0.14224)
		(layer "In11.Cu")
		(net "M_J_DQ<10>")
	)
	(segment
		(start 61.849508 -49.437544)
		(end 62.246002 -49.04105)
		(width 0.14224)
		(layer "In11.Cu")
		(net "M_J_DQ<10>")
	)
	(segment
		(start 48.765968 -21.209254)
		(end 48.892714 -21.336)
		(width 0.14224)
		(layer "In11.Cu")
		(net "M_J_DQ<10>")
	)
	(arc
		(start 70.958456 -56.380888)
		(mid 71.16546 -56.591752)
		(end 71.448676 -56.676036)
		(width 0.0889)
		(layer "In11.Cu")
		(net "M_J_DQ<10>")
	)
	(arc
		(start 70.099936 -55.885588)
		(mid 70.308544 -56.09752)
		(end 70.593966 -56.18099)
		(width 0.0889)
		(layer "In11.Cu")
		(net "M_J_DQ<10>")
	)
	(arc
		(start 73.198482 -57.66689)
		(mid 73.392332 -57.72324)
		(end 73.534016 -57.867042)
		(width 0.0889)
		(layer "In11.Cu")
		(net "M_J_DQ<10>")
	)
	(arc
		(start 70.626732 -56.18099)
		(mid 70.818374 -56.238156)
		(end 70.958456 -56.380888)
		(width 0.0889)
		(layer "In11.Cu")
		(net "M_J_DQ<10>")
	)
	(arc
		(start 72.343772 -57.17159)
		(mid 72.535414 -57.228756)
		(end 72.675496 -57.371488)
		(width 0.0889)
		(layer "In11.Cu")
		(net "M_J_DQ<10>")
	)
	(arc
		(start 74.06386 -58.16219)
		(mid 74.253789 -58.22006)
		(end 74.392536 -58.362088)
		(width 0.0889)
		(layer "In11.Cu")
		(net "M_J_DQ<10>")
	)
	(arc
		(start 73.534016 -57.867042)
		(mid 73.74102 -58.077906)
		(end 74.024236 -58.16219)
		(width 0.0889)
		(layer "In11.Cu")
		(net "M_J_DQ<10>")
	)
	(arc
		(start 69.764402 -55.685436)
		(mid 69.958252 -55.741786)
		(end 70.099936 -55.885588)
		(width 0.0889)
		(layer "In11.Cu")
		(net "M_J_DQ<10>")
	)
	(arc
		(start 71.816976 -56.876188)
		(mid 72.025584 -57.08812)
		(end 72.311006 -57.17159)
		(width 0.0889)
		(layer "In11.Cu")
		(net "M_J_DQ<10>")
	)
	(arc
		(start 71.481442 -56.676036)
		(mid 71.675292 -56.732386)
		(end 71.816976 -56.876188)
		(width 0.0889)
		(layer "In11.Cu")
		(net "M_J_DQ<10>")
	)
	(arc
		(start 72.675496 -57.371488)
		(mid 72.886209 -57.584567)
		(end 73.174352 -57.66689)
		(width 0.0889)
		(layer "In11.Cu")
		(net "M_J_DQ<10>")
	)
	(segment
		(start 33.949386 -0.821182)
		(end 33.771586 1.0414)
		(width 0.1651)
		(layer "F.Cu")
		(net "M_J_DQ<0>")
	)
	(segment
		(start 76.334366 -66.48704)
		(end 75.762866 -66.48704)
		(width 0.0889)
		(layer "F.Cu")
		(net "M_J_DQ<0>")
	)
	(via
		(at 75.762866 -66.48704)
		(size 0.508)
		(drill 0.254)
		(layers "F.Cu" "B.Cu")
		(net "M_J_DQ<0>")
	)
	(via
		(at 33.099502 -4.357878)
		(size 0.508)
		(drill 0.254)
		(layers "F.Cu" "B.Cu")
		(net "M_J_DQ<0>")
	)
	(via
		(at 33.771586 1.0414)
		(size 0.508)
		(drill 0.254)
		(layers "F.Cu" "B.Cu")
		(net "M_J_DQ<0>")
	)
	(segment
		(start 33.099502 -5.621782)
		(end 33.099502 -4.357878)
		(width 0.1651)
		(layer "B.Cu")
		(net "M_J_DQ<0>")
	)
	(segment
		(start 33.40989 -39.3192)
		(end 33.91535 -39.3192)
		(width 0.14224)
		(layer "In11.Cu")
		(net "M_J_DQ<0>")
	)
	(segment
		(start 33.551368 -2.5908)
		(end 33.551368 -2.090928)
		(width 0.14224)
		(layer "In11.Cu")
		(net "M_J_DQ<0>")
	)
	(segment
		(start 36.802568 -41.783)
		(end 36.802568 -42.28973)
		(width 0.14224)
		(layer "In11.Cu")
		(net "M_J_DQ<0>")
	)
	(segment
		(start 37.989002 -42.478452)
		(end 38.116256 -42.605706)
		(width 0.14224)
		(layer "In11.Cu")
		(net "M_J_DQ<0>")
	)
	(segment
		(start 33.099502 -4.357878)
		(end 32.814768 -4.073144)
		(width 0.14224)
		(layer "In11.Cu")
		(net "M_J_DQ<0>")
	)
	(segment
		(start 33.28162 -23.098252)
		(end 33.576768 -23.3934)
		(width 0.14224)
		(layer "In11.Cu")
		(net "M_J_DQ<0>")
	)
	(segment
		(start 33.62452 -18.640806)
		(end 33.62452 -19.002248)
		(width 0.14224)
		(layer "In11.Cu")
		(net "M_J_DQ<0>")
	)
	(segment
		(start 33.576768 -23.771352)
		(end 33.144968 -24.203152)
		(width 0.14224)
		(layer "In11.Cu")
		(net "M_J_DQ<0>")
	)
	(segment
		(start 60.54471 -66.45402)
		(end 66.133726 -66.45402)
		(width 0.14224)
		(layer "In11.Cu")
		(net "M_J_DQ<0>")
	)
	(segment
		(start 33.551368 -2.090928)
		(end 33.161986 -1.701546)
		(width 0.14224)
		(layer "In11.Cu")
		(net "M_J_DQ<0>")
	)
	(segment
		(start 66.692272 -66.08699)
		(end 67.195446 -66.08699)
		(width 0.0889)
		(layer "In11.Cu")
		(net "M_J_DQ<0>")
	)
	(segment
		(start 33.57372 -7.229094)
		(end 33.28162 -7.521194)
		(width 0.14224)
		(layer "In11.Cu")
		(net "M_J_DQ<0>")
	)
	(segment
		(start 75.479402 -67.16903)
		(end 75.768454 -66.501518)
		(width 0.0889)
		(layer "In11.Cu")
		(net "M_J_DQ<0>")
	)
	(segment
		(start 38.116256 -44.025566)
		(end 60.54471 -66.45402)
		(width 0.14224)
		(layer "In11.Cu")
		(net "M_J_DQ<0>")
	)
	(segment
		(start 36.99129 -42.478452)
		(end 37.989002 -42.478452)
		(width 0.14224)
		(layer "In11.Cu")
		(net "M_J_DQ<0>")
	)
	(segment
		(start 33.28162 -12.424156)
		(end 33.28162 -13.497052)
		(width 0.14224)
		(layer "In11.Cu")
		(net "M_J_DQ<0>")
	)
	(segment
		(start 70.593966 -66.08699)
		(end 70.626732 -66.08699)
		(width 0.0889)
		(layer "In11.Cu")
		(net "M_J_DQ<0>")
	)
	(segment
		(start 33.62452 -21.3614)
		(end 33.62452 -21.682456)
		(width 0.14224)
		(layer "In11.Cu")
		(net "M_J_DQ<0>")
	)
	(segment
		(start 73.165716 -67.572636)
		(end 73.198482 -67.572636)
		(width 0.0889)
		(layer "In11.Cu")
		(net "M_J_DQ<0>")
	)
	(segment
		(start 33.62452 -9.039606)
		(end 33.62452 -9.375648)
		(width 0.14224)
		(layer "In11.Cu")
		(net "M_J_DQ<0>")
	)
	(segment
		(start 33.576768 -23.3934)
		(end 33.576768 -23.771352)
		(width 0.14224)
		(layer "In11.Cu")
		(net "M_J_DQ<0>")
	)
	(segment
		(start 32.814768 -4.073144)
		(end 32.814768 -3.3274)
		(width 0.14224)
		(layer "In11.Cu")
		(net "M_J_DQ<0>")
	)
	(segment
		(start 33.62452 -12.081256)
		(end 33.28162 -12.424156)
		(width 0.14224)
		(layer "In11.Cu")
		(net "M_J_DQ<0>")
	)
	(segment
		(start 68.876926 -66.08699)
		(end 68.912486 -66.08699)
		(width 0.0889)
		(layer "In11.Cu")
		(net "M_J_DQ<0>")
	)
	(segment
		(start 35.405568 -41.314878)
		(end 35.69589 -41.6052)
		(width 0.14224)
		(layer "In11.Cu")
		(net "M_J_DQ<0>")
	)
	(segment
		(start 75.416156 -67.277488)
		(end 75.479402 -67.16903)
		(width 0.0889)
		(layer "In11.Cu")
		(net "M_J_DQ<0>")
	)
	(segment
		(start 33.475168 -9.525)
		(end 33.475168 -11.585448)
		(width 0.14224)
		(layer "In11.Cu")
		(net "M_J_DQ<0>")
	)
	(segment
		(start 33.62452 -11.7348)
		(end 33.62452 -12.081256)
		(width 0.14224)
		(layer "In11.Cu")
		(net "M_J_DQ<0>")
	)
	(segment
		(start 75.768454 -66.501518)
		(end 75.762866 -66.48704)
		(width 0.0889)
		(layer "In11.Cu")
		(net "M_J_DQ<0>")
	)
	(segment
		(start 33.136586 -0.178054)
		(end 33.551368 0.236728)
		(width 0.14224)
		(layer "In11.Cu")
		(net "M_J_DQ<0>")
	)
	(segment
		(start 33.479486 -0.8509)
		(end 33.136586 -0.508)
		(width 0.14224)
		(layer "In11.Cu")
		(net "M_J_DQ<0>")
	)
	(segment
		(start 33.144968 -39.054278)
		(end 33.40989 -39.3192)
		(width 0.14224)
		(layer "In11.Cu")
		(net "M_J_DQ<0>")
	)
	(segment
		(start 32.98952 -5.966206)
		(end 33.57372 -6.550406)
		(width 0.14224)
		(layer "In11.Cu")
		(net "M_J_DQ<0>")
	)
	(segment
		(start 74.028046 -68.06819)
		(end 74.063606 -68.06819)
		(width 0.0889)
		(layer "In11.Cu")
		(net "M_J_DQ<0>")
	)
	(segment
		(start 71.448676 -66.582036)
		(end 71.481442 -66.582036)
		(width 0.0889)
		(layer "In11.Cu")
		(net "M_J_DQ<0>")
	)
	(segment
		(start 33.144968 -24.203152)
		(end 33.144968 -39.054278)
		(width 0.14224)
		(layer "In11.Cu")
		(net "M_J_DQ<0>")
	)
	(segment
		(start 33.28162 -22.025356)
		(end 33.28162 -23.098252)
		(width 0.14224)
		(layer "In11.Cu")
		(net "M_J_DQ<0>")
	)
	(segment
		(start 33.28162 -17.122394)
		(end 33.28162 -18.297906)
		(width 0.14224)
		(layer "In11.Cu")
		(net "M_J_DQ<0>")
	)
	(segment
		(start 35.177222 -40.386)
		(end 35.405568 -40.614346)
		(width 0.14224)
		(layer "In11.Cu")
		(net "M_J_DQ<0>")
	)
	(segment
		(start 35.69589 -41.6052)
		(end 36.624768 -41.6052)
		(width 0.14224)
		(layer "In11.Cu")
		(net "M_J_DQ<0>")
	)
	(segment
		(start 33.551368 0.236728)
		(end 33.551368 0.821182)
		(width 0.14224)
		(layer "In11.Cu")
		(net "M_J_DQ<0>")
	)
	(segment
		(start 33.28162 -8.696706)
		(end 33.62452 -9.039606)
		(width 0.14224)
		(layer "In11.Cu")
		(net "M_J_DQ<0>")
	)
	(segment
		(start 33.424368 -19.2024)
		(end 33.424368 -21.161248)
		(width 0.14224)
		(layer "In11.Cu")
		(net "M_J_DQ<0>")
	)
	(segment
		(start 33.62452 -9.375648)
		(end 33.475168 -9.525)
		(width 0.14224)
		(layer "In11.Cu")
		(net "M_J_DQ<0>")
	)
	(segment
		(start 74.89317 -67.572636)
		(end 74.925936 -67.572636)
		(width 0.0889)
		(layer "In11.Cu")
		(net "M_J_DQ<0>")
	)
	(segment
		(start 33.099502 -4.693666)
		(end 32.98952 -4.803648)
		(width 0.14224)
		(layer "In11.Cu")
		(net "M_J_DQ<0>")
	)
	(segment
		(start 33.57372 -6.550406)
		(end 33.57372 -7.229094)
		(width 0.14224)
		(layer "In11.Cu")
		(net "M_J_DQ<0>")
	)
	(segment
		(start 33.28162 -13.497052)
		(end 33.62452 -13.839952)
		(width 0.14224)
		(layer "In11.Cu")
		(net "M_J_DQ<0>")
	)
	(segment
		(start 33.424368 -21.161248)
		(end 33.62452 -21.3614)
		(width 0.14224)
		(layer "In11.Cu")
		(net "M_J_DQ<0>")
	)
	(segment
		(start 33.136586 -0.508)
		(end 33.136586 -0.178054)
		(width 0.14224)
		(layer "In11.Cu")
		(net "M_J_DQ<0>")
	)
	(segment
		(start 33.62452 -13.839952)
		(end 33.62452 -16.779494)
		(width 0.14224)
		(layer "In11.Cu")
		(net "M_J_DQ<0>")
	)
	(segment
		(start 33.62452 -21.682456)
		(end 33.28162 -22.025356)
		(width 0.14224)
		(layer "In11.Cu")
		(net "M_J_DQ<0>")
	)
	(segment
		(start 32.98952 -4.803648)
		(end 32.98952 -5.966206)
		(width 0.14224)
		(layer "In11.Cu")
		(net "M_J_DQ<0>")
	)
	(segment
		(start 34.47669 -40.386)
		(end 35.177222 -40.386)
		(width 0.14224)
		(layer "In11.Cu")
		(net "M_J_DQ<0>")
	)
	(segment
		(start 33.28162 -18.297906)
		(end 33.62452 -18.640806)
		(width 0.14224)
		(layer "In11.Cu")
		(net "M_J_DQ<0>")
	)
	(segment
		(start 34.211768 -39.615618)
		(end 34.211768 -40.121078)
		(width 0.14224)
		(layer "In11.Cu")
		(net "M_J_DQ<0>")
	)
	(segment
		(start 36.624768 -41.6052)
		(end 36.802568 -41.783)
		(width 0.14224)
		(layer "In11.Cu")
		(net "M_J_DQ<0>")
	)
	(segment
		(start 34.211768 -40.121078)
		(end 34.47669 -40.386)
		(width 0.14224)
		(layer "In11.Cu")
		(net "M_J_DQ<0>")
	)
	(segment
		(start 38.116256 -42.605706)
		(end 38.116256 -44.025566)
		(width 0.14224)
		(layer "In11.Cu")
		(net "M_J_DQ<0>")
	)
	(segment
		(start 33.62452 -19.002248)
		(end 33.424368 -19.2024)
		(width 0.14224)
		(layer "In11.Cu")
		(net "M_J_DQ<0>")
	)
	(segment
		(start 66.325242 -66.45402)
		(end 66.692272 -66.08699)
		(width 0.0889)
		(layer "In11.Cu")
		(net "M_J_DQ<0>")
	)
	(segment
		(start 33.62452 -16.779494)
		(end 33.28162 -17.122394)
		(width 0.14224)
		(layer "In11.Cu")
		(net "M_J_DQ<0>")
	)
	(segment
		(start 36.802568 -42.28973)
		(end 36.99129 -42.478452)
		(width 0.14224)
		(layer "In11.Cu")
		(net "M_J_DQ<0>")
	)
	(segment
		(start 72.311006 -67.07759)
		(end 72.343772 -67.07759)
		(width 0.0889)
		(layer "In11.Cu")
		(net "M_J_DQ<0>")
	)
	(segment
		(start 33.479486 -1.0795)
		(end 33.479486 -0.8509)
		(width 0.14224)
		(layer "In11.Cu")
		(net "M_J_DQ<0>")
	)
	(segment
		(start 33.28162 -7.521194)
		(end 33.28162 -8.696706)
		(width 0.14224)
		(layer "In11.Cu")
		(net "M_J_DQ<0>")
	)
	(segment
		(start 35.405568 -40.614346)
		(end 35.405568 -41.314878)
		(width 0.14224)
		(layer "In11.Cu")
		(net "M_J_DQ<0>")
	)
	(segment
		(start 33.475168 -11.585448)
		(end 33.62452 -11.7348)
		(width 0.14224)
		(layer "In11.Cu")
		(net "M_J_DQ<0>")
	)
	(segment
		(start 33.551368 0.821182)
		(end 33.771586 1.0414)
		(width 0.14224)
		(layer "In11.Cu")
		(net "M_J_DQ<0>")
	)
	(segment
		(start 33.099502 -4.357878)
		(end 33.099502 -4.693666)
		(width 0.14224)
		(layer "In11.Cu")
		(net "M_J_DQ<0>")
	)
	(segment
		(start 66.133726 -66.45402)
		(end 66.325242 -66.45402)
		(width 0.0889)
		(layer "In11.Cu")
		(net "M_J_DQ<0>")
	)
	(segment
		(start 32.814768 -3.3274)
		(end 33.551368 -2.5908)
		(width 0.14224)
		(layer "In11.Cu")
		(net "M_J_DQ<0>")
	)
	(segment
		(start 33.91535 -39.3192)
		(end 34.211768 -39.615618)
		(width 0.14224)
		(layer "In11.Cu")
		(net "M_J_DQ<0>")
	)
	(segment
		(start 33.161986 -1.397)
		(end 33.479486 -1.0795)
		(width 0.14224)
		(layer "In11.Cu")
		(net "M_J_DQ<0>")
	)
	(segment
		(start 33.161986 -1.701546)
		(end 33.161986 -1.397)
		(width 0.14224)
		(layer "In11.Cu")
		(net "M_J_DQ<0>")
	)
	(arc
		(start 67.195446 -66.08699)
		(mid 67.48087 -66.003523)
		(end 67.689476 -65.791588)
		(width 0.0889)
		(layer "In11.Cu")
		(net "M_J_DQ<0>")
	)
	(arc
		(start 74.925936 -67.572636)
		(mid 75.209153 -67.488355)
		(end 75.416156 -67.277488)
		(width 0.0889)
		(layer "In11.Cu")
		(net "M_J_DQ<0>")
	)
	(arc
		(start 70.099936 -65.791588)
		(mid 70.308544 -66.00352)
		(end 70.593966 -66.08699)
		(width 0.0889)
		(layer "In11.Cu")
		(net "M_J_DQ<0>")
	)
	(arc
		(start 69.406516 -65.791588)
		(mid 69.753226 -65.591277)
		(end 70.099936 -65.791588)
		(width 0.0889)
		(layer "In11.Cu")
		(net "M_J_DQ<0>")
	)
	(arc
		(start 68.912486 -66.08699)
		(mid 69.19791 -66.003523)
		(end 69.406516 -65.791588)
		(width 0.0889)
		(layer "In11.Cu")
		(net "M_J_DQ<0>")
	)
	(arc
		(start 67.689476 -65.791588)
		(mid 68.036186 -65.591277)
		(end 68.382896 -65.791588)
		(width 0.0889)
		(layer "In11.Cu")
		(net "M_J_DQ<0>")
	)
	(arc
		(start 72.675496 -67.277488)
		(mid 72.8825 -67.488352)
		(end 73.165716 -67.572636)
		(width 0.0889)
		(layer "In11.Cu")
		(net "M_J_DQ<0>")
	)
	(arc
		(start 71.481442 -66.582036)
		(mid 71.675292 -66.638386)
		(end 71.816976 -66.782188)
		(width 0.0889)
		(layer "In11.Cu")
		(net "M_J_DQ<0>")
	)
	(arc
		(start 73.534016 -67.772788)
		(mid 73.742624 -67.98472)
		(end 74.028046 -68.06819)
		(width 0.0889)
		(layer "In11.Cu")
		(net "M_J_DQ<0>")
	)
	(arc
		(start 72.343772 -67.07759)
		(mid 72.535414 -67.134756)
		(end 72.675496 -67.277488)
		(width 0.0889)
		(layer "In11.Cu")
		(net "M_J_DQ<0>")
	)
	(arc
		(start 68.382896 -65.791588)
		(mid 68.591504 -66.00352)
		(end 68.876926 -66.08699)
		(width 0.0889)
		(layer "In11.Cu")
		(net "M_J_DQ<0>")
	)
	(arc
		(start 70.626732 -66.08699)
		(mid 70.818374 -66.144156)
		(end 70.958456 -66.286888)
		(width 0.0889)
		(layer "In11.Cu")
		(net "M_J_DQ<0>")
	)
	(arc
		(start 74.063606 -68.06819)
		(mid 74.34903 -67.984723)
		(end 74.557636 -67.772788)
		(width 0.0889)
		(layer "In11.Cu")
		(net "M_J_DQ<0>")
	)
	(arc
		(start 70.958456 -66.286888)
		(mid 71.16546 -66.497752)
		(end 71.448676 -66.582036)
		(width 0.0889)
		(layer "In11.Cu")
		(net "M_J_DQ<0>")
	)
	(arc
		(start 73.198482 -67.572636)
		(mid 73.392332 -67.628986)
		(end 73.534016 -67.772788)
		(width 0.0889)
		(layer "In11.Cu")
		(net "M_J_DQ<0>")
	)
	(arc
		(start 71.816976 -66.782188)
		(mid 72.025584 -66.99412)
		(end 72.311006 -67.07759)
		(width 0.0889)
		(layer "In11.Cu")
		(net "M_J_DQ<0>")
	)
	(arc
		(start 74.557636 -67.772788)
		(mid 74.699319 -67.628984)
		(end 74.89317 -67.572636)
		(width 0.0889)
		(layer "In11.Cu")
		(net "M_J_DQ<0>")
	)
	(segment
		(start 102.947724 -58.06694)
		(end 103.557324 -58.06694)
		(width 0.1016)
		(layer "F.Cu")
		(net "M_J_CS_N<7>")
	)
	(via
		(at 112.99952 -2.316988)
		(size 0.4572)
		(drill 0.2032)
		(layers "F.Cu" "B.Cu")
		(net "M_J_CS_N<7>")
	)
	(via
		(at 103.557324 -58.06694)
		(size 0.508)
		(drill 0.254)
		(layers "F.Cu" "B.Cu")
		(net "M_J_CS_N<7>")
	)
	(segment
		(start 112.99952 -2.316988)
		(end 112.99952 -1.021842)
		(width 0.1651)
		(layer "B.Cu")
		(net "M_J_CS_N<7>")
	)
	(segment
		(start 113.49609 -13.26896)
		(end 113.408206 -13.181076)
		(width 0.14224)
		(layer "In2.Cu")
		(net "M_J_CS_N<7>")
	)
	(segment
		(start 103.477568 -56.5912)
		(end 103.147368 -56.261)
		(width 0.0889)
		(layer "In2.Cu")
		(net "M_J_CS_N<7>")
	)
	(segment
		(start 103.960168 -56.896)
		(end 103.655368 -56.5912)
		(width 0.0889)
		(layer "In2.Cu")
		(net "M_J_CS_N<7>")
	)
	(segment
		(start 103.325168 -51.689254)
		(end 103.325168 -49.7332)
		(width 0.0889)
		(layer "In2.Cu")
		(net "M_J_CS_N<7>")
	)
	(segment
		(start 104.83596 -47.932848)
		(end 104.83596 -33.48736)
		(width 0.14224)
		(layer "In2.Cu")
		(net "M_J_CS_N<7>")
	)
	(segment
		(start 103.655368 -56.5912)
		(end 103.477568 -56.5912)
		(width 0.0889)
		(layer "In2.Cu")
		(net "M_J_CS_N<7>")
	)
	(segment
		(start 113.535968 -6.669532)
		(end 113.535968 -4.085336)
		(width 0.14224)
		(layer "In2.Cu")
		(net "M_J_CS_N<7>")
	)
	(segment
		(start 113.238026 -2.555494)
		(end 112.99952 -2.316988)
		(width 0.14224)
		(layer "In2.Cu")
		(net "M_J_CS_N<7>")
	)
	(segment
		(start 104.83596 -33.48736)
		(end 113.49609 -24.82723)
		(width 0.14224)
		(layer "In2.Cu")
		(net "M_J_CS_N<7>")
	)
	(segment
		(start 113.535968 -4.085336)
		(end 113.238026 -3.787394)
		(width 0.14224)
		(layer "In2.Cu")
		(net "M_J_CS_N<7>")
	)
	(segment
		(start 113.408206 -6.797294)
		(end 113.535968 -6.669532)
		(width 0.14224)
		(layer "In2.Cu")
		(net "M_J_CS_N<7>")
	)
	(segment
		(start 104.83596 -48.222408)
		(end 104.83596 -47.932848)
		(width 0.0889)
		(layer "In2.Cu")
		(net "M_J_CS_N<7>")
	)
	(segment
		(start 113.49609 -24.82723)
		(end 113.49609 -13.26896)
		(width 0.14224)
		(layer "In2.Cu")
		(net "M_J_CS_N<7>")
	)
	(segment
		(start 103.147368 -51.867054)
		(end 103.325168 -51.689254)
		(width 0.0889)
		(layer "In2.Cu")
		(net "M_J_CS_N<7>")
	)
	(segment
		(start 103.147368 -56.261)
		(end 103.147368 -51.867054)
		(width 0.0889)
		(layer "In2.Cu")
		(net "M_J_CS_N<7>")
	)
	(segment
		(start 113.408206 -13.181076)
		(end 113.408206 -6.797294)
		(width 0.14224)
		(layer "In2.Cu")
		(net "M_J_CS_N<7>")
	)
	(segment
		(start 103.325168 -49.7332)
		(end 104.83596 -48.222408)
		(width 0.0889)
		(layer "In2.Cu")
		(net "M_J_CS_N<7>")
	)
	(segment
		(start 103.960168 -57.664096)
		(end 103.960168 -56.896)
		(width 0.0889)
		(layer "In2.Cu")
		(net "M_J_CS_N<7>")
	)
	(segment
		(start 113.238026 -3.787394)
		(end 113.238026 -2.555494)
		(width 0.14224)
		(layer "In2.Cu")
		(net "M_J_CS_N<7>")
	)
	(segment
		(start 103.557324 -58.06694)
		(end 103.960168 -57.664096)
		(width 0.0889)
		(layer "In2.Cu")
		(net "M_J_CS_N<7>")
	)
	(segment
		(start 102.947724 -57.076086)
		(end 103.557324 -57.076086)
		(width 0.1016)
		(layer "F.Cu")
		(net "M_J_CS_N<6>")
	)
	(via
		(at 103.557324 -57.076086)
		(size 0.508)
		(drill 0.254)
		(layers "F.Cu" "B.Cu")
		(net "M_J_CS_N<6>")
	)
	(via
		(at 112.99952 -4.332986)
		(size 0.4572)
		(drill 0.2032)
		(layers "F.Cu" "B.Cu")
		(net "M_J_CS_N<6>")
	)
	(segment
		(start 112.99952 -5.621782)
		(end 112.99952 -4.332986)
		(width 0.1651)
		(layer "B.Cu")
		(net "M_J_CS_N<6>")
	)
	(segment
		(start 112.50549 -21.811996)
		(end 112.50549 -19.242278)
		(width 0.14224)
		(layer "In2.Cu")
		(net "M_J_CS_N<6>")
	)
	(segment
		(start 112.296956 -14.84249)
		(end 112.296956 -14.467078)
		(width 0.14224)
		(layer "In2.Cu")
		(net "M_J_CS_N<6>")
	)
	(segment
		(start 112.583976 -5.752592)
		(end 112.99952 -5.337048)
		(width 0.14224)
		(layer "In2.Cu")
		(net "M_J_CS_N<6>")
	)
	(segment
		(start 112.585246 -14.178788)
		(end 112.585246 -13.527024)
		(width 0.14224)
		(layer "In2.Cu")
		(net "M_J_CS_N<6>")
	)
	(segment
		(start 112.88141 -15.024354)
		(end 112.47882 -15.024354)
		(width 0.14224)
		(layer "In2.Cu")
		(net "M_J_CS_N<6>")
	)
	(segment
		(start 112.503712 -15.687294)
		(end 112.88141 -15.687294)
		(width 0.14224)
		(layer "In2.Cu")
		(net "M_J_CS_N<6>")
	)
	(segment
		(start 112.582452 -12.809982)
		(end 112.582452 -11.070844)
		(width 0.14224)
		(layer "In2.Cu")
		(net "M_J_CS_N<6>")
	)
	(segment
		(start 111.618522 -25.986232)
		(end 111.906304 -25.69845)
		(width 0.14224)
		(layer "In2.Cu")
		(net "M_J_CS_N<6>")
	)
	(segment
		(start 102.780592 -56.299354)
		(end 102.780592 -51.80203)
		(width 0.0889)
		(layer "In2.Cu")
		(net "M_J_CS_N<6>")
	)
	(segment
		(start 112.88141 -15.687294)
		(end 113.03635 -15.532354)
		(width 0.14224)
		(layer "In2.Cu")
		(net "M_J_CS_N<6>")
	)
	(segment
		(start 112.99952 -5.337048)
		(end 112.99952 -4.332986)
		(width 0.14224)
		(layer "In2.Cu")
		(net "M_J_CS_N<6>")
	)
	(segment
		(start 104.300528 -48.300386)
		(end 104.300528 -47.991522)
		(width 0.0889)
		(layer "In2.Cu")
		(net "M_J_CS_N<6>")
	)
	(segment
		(start 112.585246 -16.488664)
		(end 112.326166 -16.229584)
		(width 0.14224)
		(layer "In2.Cu")
		(net "M_J_CS_N<6>")
	)
	(segment
		(start 104.300528 -33.304226)
		(end 110.7567 -26.848054)
		(width 0.14224)
		(layer "In2.Cu")
		(net "M_J_CS_N<6>")
	)
	(segment
		(start 112.05464 -24.697436)
		(end 112.341914 -24.697436)
		(width 0.14224)
		(layer "In2.Cu")
		(net "M_J_CS_N<6>")
	)
	(segment
		(start 112.296956 -14.467078)
		(end 112.585246 -14.178788)
		(width 0.14224)
		(layer "In2.Cu")
		(net "M_J_CS_N<6>")
	)
	(segment
		(start 112.358678 -17.463008)
		(end 112.585246 -17.23644)
		(width 0.14224)
		(layer "In2.Cu")
		(net "M_J_CS_N<6>")
	)
	(segment
		(start 110.7567 -26.848054)
		(end 110.7567 -26.561034)
		(width 0.14224)
		(layer "In2.Cu")
		(net "M_J_CS_N<6>")
	)
	(segment
		(start 112.45469 -23.132796)
		(end 112.45469 -22.599396)
		(width 0.14224)
		(layer "In2.Cu")
		(net "M_J_CS_N<6>")
	)
	(segment
		(start 112.585246 -17.23644)
		(end 112.585246 -16.488664)
		(width 0.14224)
		(layer "In2.Cu")
		(net "M_J_CS_N<6>")
	)
	(segment
		(start 112.585246 -18.318226)
		(end 112.358678 -18.091658)
		(width 0.14224)
		(layer "In2.Cu")
		(net "M_J_CS_N<6>")
	)
	(segment
		(start 113.010442 -24.594312)
		(end 113.010442 -23.688548)
		(width 0.14224)
		(layer "In2.Cu")
		(net "M_J_CS_N<6>")
	)
	(segment
		(start 111.766858 -24.985218)
		(end 112.05464 -24.697436)
		(width 0.14224)
		(layer "In2.Cu")
		(net "M_J_CS_N<6>")
	)
	(segment
		(start 112.358678 -18.091658)
		(end 112.358678 -17.463008)
		(width 0.14224)
		(layer "In2.Cu")
		(net "M_J_CS_N<6>")
	)
	(segment
		(start 112.45469 -12.937744)
		(end 112.582452 -12.809982)
		(width 0.14224)
		(layer "In2.Cu")
		(net "M_J_CS_N<6>")
	)
	(segment
		(start 103.557324 -57.076086)
		(end 102.780592 -56.299354)
		(width 0.0889)
		(layer "In2.Cu")
		(net "M_J_CS_N<6>")
	)
	(segment
		(start 103.121968 -51.460654)
		(end 103.121968 -49.478946)
		(width 0.0889)
		(layer "In2.Cu")
		(net "M_J_CS_N<6>")
	)
	(segment
		(start 110.7567 -26.561034)
		(end 110.617254 -26.421842)
		(width 0.14224)
		(layer "In2.Cu")
		(net "M_J_CS_N<6>")
	)
	(segment
		(start 112.768126 -24.836628)
		(end 113.010442 -24.594312)
		(width 0.14224)
		(layer "In2.Cu")
		(net "M_J_CS_N<6>")
	)
	(segment
		(start 111.19231 -25.84704)
		(end 111.331502 -25.986232)
		(width 0.14224)
		(layer "In2.Cu")
		(net "M_J_CS_N<6>")
	)
	(segment
		(start 102.780592 -51.80203)
		(end 103.121968 -51.460654)
		(width 0.0889)
		(layer "In2.Cu")
		(net "M_J_CS_N<6>")
	)
	(segment
		(start 113.03635 -15.179294)
		(end 112.88141 -15.024354)
		(width 0.14224)
		(layer "In2.Cu")
		(net "M_J_CS_N<6>")
	)
	(segment
		(start 112.585246 -13.527024)
		(end 112.45469 -13.396468)
		(width 0.14224)
		(layer "In2.Cu")
		(net "M_J_CS_N<6>")
	)
	(segment
		(start 111.906304 -25.69845)
		(end 111.906304 -25.41143)
		(width 0.14224)
		(layer "In2.Cu")
		(net "M_J_CS_N<6>")
	)
	(segment
		(start 110.905036 -25.84704)
		(end 111.19231 -25.84704)
		(width 0.14224)
		(layer "In2.Cu")
		(net "M_J_CS_N<6>")
	)
	(segment
		(start 111.766858 -25.272238)
		(end 111.766858 -24.985218)
		(width 0.14224)
		(layer "In2.Cu")
		(net "M_J_CS_N<6>")
	)
	(segment
		(start 112.45469 -13.396468)
		(end 112.45469 -12.937744)
		(width 0.14224)
		(layer "In2.Cu")
		(net "M_J_CS_N<6>")
	)
	(segment
		(start 112.582452 -11.070844)
		(end 112.649254 -11.004042)
		(width 0.14224)
		(layer "In2.Cu")
		(net "M_J_CS_N<6>")
	)
	(segment
		(start 112.481106 -24.836628)
		(end 112.768126 -24.836628)
		(width 0.14224)
		(layer "In2.Cu")
		(net "M_J_CS_N<6>")
	)
	(segment
		(start 112.649254 -11.004042)
		(end 112.649254 -9.83869)
		(width 0.14224)
		(layer "In2.Cu")
		(net "M_J_CS_N<6>")
	)
	(segment
		(start 110.617254 -26.421842)
		(end 110.617254 -26.134822)
		(width 0.14224)
		(layer "In2.Cu")
		(net "M_J_CS_N<6>")
	)
	(segment
		(start 112.326166 -16.229584)
		(end 112.326166 -15.86484)
		(width 0.14224)
		(layer "In2.Cu")
		(net "M_J_CS_N<6>")
	)
	(segment
		(start 104.300528 -47.991522)
		(end 104.300528 -33.304226)
		(width 0.14224)
		(layer "In2.Cu")
		(net "M_J_CS_N<6>")
	)
	(segment
		(start 103.121968 -49.478946)
		(end 104.300528 -48.300386)
		(width 0.0889)
		(layer "In2.Cu")
		(net "M_J_CS_N<6>")
	)
	(segment
		(start 111.331502 -25.986232)
		(end 111.618522 -25.986232)
		(width 0.14224)
		(layer "In2.Cu")
		(net "M_J_CS_N<6>")
	)
	(segment
		(start 112.47882 -15.024354)
		(end 112.296956 -14.84249)
		(width 0.14224)
		(layer "In2.Cu")
		(net "M_J_CS_N<6>")
	)
	(segment
		(start 113.03635 -15.532354)
		(end 113.03635 -15.179294)
		(width 0.14224)
		(layer "In2.Cu")
		(net "M_J_CS_N<6>")
	)
	(segment
		(start 113.010442 -23.688548)
		(end 112.45469 -23.132796)
		(width 0.14224)
		(layer "In2.Cu")
		(net "M_J_CS_N<6>")
	)
	(segment
		(start 111.906304 -25.41143)
		(end 111.766858 -25.272238)
		(width 0.14224)
		(layer "In2.Cu")
		(net "M_J_CS_N<6>")
	)
	(segment
		(start 112.50549 -19.242278)
		(end 112.585246 -19.162522)
		(width 0.14224)
		(layer "In2.Cu")
		(net "M_J_CS_N<6>")
	)
	(segment
		(start 112.587278 -8.086598)
		(end 112.583976 -8.083296)
		(width 0.14224)
		(layer "In2.Cu")
		(net "M_J_CS_N<6>")
	)
	(segment
		(start 112.341914 -24.697436)
		(end 112.481106 -24.836628)
		(width 0.14224)
		(layer "In2.Cu")
		(net "M_J_CS_N<6>")
	)
	(segment
		(start 112.585246 -19.162522)
		(end 112.585246 -18.318226)
		(width 0.14224)
		(layer "In2.Cu")
		(net "M_J_CS_N<6>")
	)
	(segment
		(start 112.45469 -22.599396)
		(end 112.63249 -22.421596)
		(width 0.14224)
		(layer "In2.Cu")
		(net "M_J_CS_N<6>")
	)
	(segment
		(start 112.649254 -9.83869)
		(end 112.587278 -9.776714)
		(width 0.14224)
		(layer "In2.Cu")
		(net "M_J_CS_N<6>")
	)
	(segment
		(start 112.587278 -9.776714)
		(end 112.587278 -8.086598)
		(width 0.14224)
		(layer "In2.Cu")
		(net "M_J_CS_N<6>")
	)
	(segment
		(start 112.63249 -22.421596)
		(end 112.63249 -21.938996)
		(width 0.14224)
		(layer "In2.Cu")
		(net "M_J_CS_N<6>")
	)
	(segment
		(start 112.326166 -15.86484)
		(end 112.503712 -15.687294)
		(width 0.14224)
		(layer "In2.Cu")
		(net "M_J_CS_N<6>")
	)
	(segment
		(start 112.63249 -21.938996)
		(end 112.50549 -21.811996)
		(width 0.14224)
		(layer "In2.Cu")
		(net "M_J_CS_N<6>")
	)
	(segment
		(start 110.617254 -26.134822)
		(end 110.905036 -25.84704)
		(width 0.14224)
		(layer "In2.Cu")
		(net "M_J_CS_N<6>")
	)
	(segment
		(start 112.583976 -8.083296)
		(end 112.583976 -5.752592)
		(width 0.14224)
		(layer "In2.Cu")
		(net "M_J_CS_N<6>")
	)
	(segment
		(start 100.372164 -58.561986)
		(end 99.800664 -58.561986)
		(width 0.1016)
		(layer "F.Cu")
		(net "M_J_CS_N<5>")
	)
	(via
		(at 99.800664 -58.561986)
		(size 0.508)
		(drill 0.254)
		(layers "F.Cu" "B.Cu")
		(net "M_J_CS_N<5>")
	)
	(via
		(at 109.599476 -4.328668)
		(size 0.4572)
		(drill 0.2032)
		(layers "F.Cu" "B.Cu")
		(net "M_J_CS_N<5>")
	)
	(segment
		(start 109.599476 -5.621782)
		(end 109.599476 -4.328668)
		(width 0.1651)
		(layer "B.Cu")
		(net "M_J_CS_N<5>")
	)
	(segment
		(start 109.599476 -4.328668)
		(end 109.319568 -4.608576)
		(width 0.14224)
		(layer "In2.Cu")
		(net "M_J_CS_N<5>")
	)
	(segment
		(start 100.454968 -52.286408)
		(end 100.147374 -52.818792)
		(width 0.0889)
		(layer "In2.Cu")
		(net "M_J_CS_N<5>")
	)
	(segment
		(start 108.278168 -24.3078)
		(end 107.56392 -25.022048)
		(width 0.14224)
		(layer "In2.Cu")
		(net "M_J_CS_N<5>")
	)
	(segment
		(start 106.577892 -25.56002)
		(end 106.577892 -27.43327)
		(width 0.14224)
		(layer "In2.Cu")
		(net "M_J_CS_N<5>")
	)
	(segment
		(start 108.576364 -9.600184)
		(end 108.576364 -10.051288)
		(width 0.14224)
		(layer "In2.Cu")
		(net "M_J_CS_N<5>")
	)
	(segment
		(start 108.576364 -10.051288)
		(end 108.421424 -10.206228)
		(width 0.14224)
		(layer "In2.Cu")
		(net "M_J_CS_N<5>")
	)
	(segment
		(start 108.241846 -17.134586)
		(end 108.241846 -17.642586)
		(width 0.14224)
		(layer "In2.Cu")
		(net "M_J_CS_N<5>")
	)
	(segment
		(start 108.421424 -10.206228)
		(end 108.111798 -10.206228)
		(width 0.14224)
		(layer "In2.Cu")
		(net "M_J_CS_N<5>")
	)
	(segment
		(start 108.419646 -12.972796)
		(end 108.419646 -13.506196)
		(width 0.14224)
		(layer "In2.Cu")
		(net "M_J_CS_N<5>")
	)
	(segment
		(start 101.760528 -48.462946)
		(end 101.760528 -48.78324)
		(width 0.0889)
		(layer "In2.Cu")
		(net "M_J_CS_N<5>")
	)
	(segment
		(start 108.335064 -9.358884)
		(end 108.576364 -9.600184)
		(width 0.14224)
		(layer "In2.Cu")
		(net "M_J_CS_N<5>")
	)
	(segment
		(start 108.341414 -12.212828)
		(end 108.241846 -12.312396)
		(width 0.14224)
		(layer "In2.Cu")
		(net "M_J_CS_N<5>")
	)
	(segment
		(start 108.336334 -14.592046)
		(end 108.336334 -17.040098)
		(width 0.14224)
		(layer "In2.Cu")
		(net "M_J_CS_N<5>")
	)
	(segment
		(start 108.333794 -18.439638)
		(end 108.333794 -18.95475)
		(width 0.14224)
		(layer "In2.Cu")
		(net "M_J_CS_N<5>")
	)
	(segment
		(start 108.38434 -20.111212)
		(end 108.059474 -20.111212)
		(width 0.14224)
		(layer "In2.Cu")
		(net "M_J_CS_N<5>")
	)
	(segment
		(start 101.133148 -50.23358)
		(end 100.454968 -50.91176)
		(width 0.0889)
		(layer "In2.Cu")
		(net "M_J_CS_N<5>")
	)
	(segment
		(start 101.760528 -32.250634)
		(end 101.760528 -48.462946)
		(width 0.14224)
		(layer "In2.Cu")
		(net "M_J_CS_N<5>")
	)
	(segment
		(start 107.956858 -10.714228)
		(end 108.111798 -10.869168)
		(width 0.14224)
		(layer "In2.Cu")
		(net "M_J_CS_N<5>")
	)
	(segment
		(start 109.319568 -4.61518)
		(end 108.335064 -5.599684)
		(width 0.14224)
		(layer "In2.Cu")
		(net "M_J_CS_N<5>")
	)
	(segment
		(start 108.394246 -18.379186)
		(end 108.333794 -18.439638)
		(width 0.14224)
		(layer "In2.Cu")
		(net "M_J_CS_N<5>")
	)
	(segment
		(start 108.421424 -10.869168)
		(end 108.576364 -11.024108)
		(width 0.14224)
		(layer "In2.Cu")
		(net "M_J_CS_N<5>")
	)
	(segment
		(start 101.133148 -49.41062)
		(end 101.133148 -50.23358)
		(width 0.0889)
		(layer "In2.Cu")
		(net "M_J_CS_N<5>")
	)
	(segment
		(start 108.278168 -23.248874)
		(end 108.278168 -24.3078)
		(width 0.14224)
		(layer "In2.Cu")
		(net "M_J_CS_N<5>")
	)
	(segment
		(start 108.53928 -21.616162)
		(end 108.241846 -21.913596)
		(width 0.14224)
		(layer "In2.Cu")
		(net "M_J_CS_N<5>")
	)
	(segment
		(start 108.53928 -20.929092)
		(end 108.53928 -21.616162)
		(width 0.14224)
		(layer "In2.Cu")
		(net "M_J_CS_N<5>")
	)
	(segment
		(start 108.333794 -18.95475)
		(end 108.53928 -19.160236)
		(width 0.14224)
		(layer "In2.Cu")
		(net "M_J_CS_N<5>")
	)
	(segment
		(start 108.38434 -20.774152)
		(end 108.53928 -20.929092)
		(width 0.14224)
		(layer "In2.Cu")
		(net "M_J_CS_N<5>")
	)
	(segment
		(start 108.241846 -17.642586)
		(end 108.394246 -17.794986)
		(width 0.14224)
		(layer "In2.Cu")
		(net "M_J_CS_N<5>")
	)
	(segment
		(start 108.53928 -19.160236)
		(end 108.53928 -19.956272)
		(width 0.14224)
		(layer "In2.Cu")
		(net "M_J_CS_N<5>")
	)
	(segment
		(start 108.241846 -22.396196)
		(end 108.419646 -22.573996)
		(width 0.14224)
		(layer "In2.Cu")
		(net "M_J_CS_N<5>")
	)
	(segment
		(start 108.312966 -14.568678)
		(end 108.336334 -14.592046)
		(width 0.14224)
		(layer "In2.Cu")
		(net "M_J_CS_N<5>")
	)
	(segment
		(start 108.241846 -21.913596)
		(end 108.241846 -22.396196)
		(width 0.14224)
		(layer "In2.Cu")
		(net "M_J_CS_N<5>")
	)
	(segment
		(start 107.56392 -25.022048)
		(end 107.115864 -25.022048)
		(width 0.14224)
		(layer "In2.Cu")
		(net "M_J_CS_N<5>")
	)
	(segment
		(start 107.913932 -20.256754)
		(end 107.913932 -20.609814)
		(width 0.14224)
		(layer "In2.Cu")
		(net "M_J_CS_N<5>")
	)
	(segment
		(start 108.312966 -13.612876)
		(end 108.312966 -14.568678)
		(width 0.14224)
		(layer "In2.Cu")
		(net "M_J_CS_N<5>")
	)
	(segment
		(start 108.335064 -5.599684)
		(end 108.335064 -9.358884)
		(width 0.14224)
		(layer "In2.Cu")
		(net "M_J_CS_N<5>")
	)
	(segment
		(start 107.913932 -20.609814)
		(end 108.07827 -20.774152)
		(width 0.14224)
		(layer "In2.Cu")
		(net "M_J_CS_N<5>")
	)
	(segment
		(start 108.576364 -11.024108)
		(end 108.576364 -11.449304)
		(width 0.14224)
		(layer "In2.Cu")
		(net "M_J_CS_N<5>")
	)
	(segment
		(start 108.341414 -11.684254)
		(end 108.341414 -12.212828)
		(width 0.14224)
		(layer "In2.Cu")
		(net "M_J_CS_N<5>")
	)
	(segment
		(start 108.241846 -12.312396)
		(end 108.241846 -12.794996)
		(width 0.14224)
		(layer "In2.Cu")
		(net "M_J_CS_N<5>")
	)
	(segment
		(start 107.115864 -25.022048)
		(end 106.577892 -25.56002)
		(width 0.14224)
		(layer "In2.Cu")
		(net "M_J_CS_N<5>")
	)
	(segment
		(start 108.419646 -13.506196)
		(end 108.312966 -13.612876)
		(width 0.14224)
		(layer "In2.Cu")
		(net "M_J_CS_N<5>")
	)
	(segment
		(start 108.07827 -20.774152)
		(end 108.38434 -20.774152)
		(width 0.14224)
		(layer "In2.Cu")
		(net "M_J_CS_N<5>")
	)
	(segment
		(start 108.53928 -19.956272)
		(end 108.38434 -20.111212)
		(width 0.14224)
		(layer "In2.Cu")
		(net "M_J_CS_N<5>")
	)
	(segment
		(start 108.111798 -10.869168)
		(end 108.421424 -10.869168)
		(width 0.14224)
		(layer "In2.Cu")
		(net "M_J_CS_N<5>")
	)
	(segment
		(start 100.105464 -57.860692)
		(end 99.800664 -58.561986)
		(width 0.0889)
		(layer "In2.Cu")
		(net "M_J_CS_N<5>")
	)
	(segment
		(start 108.336334 -17.040098)
		(end 108.241846 -17.134586)
		(width 0.14224)
		(layer "In2.Cu")
		(net "M_J_CS_N<5>")
	)
	(segment
		(start 101.760528 -48.78324)
		(end 101.133148 -49.41062)
		(width 0.0889)
		(layer "In2.Cu")
		(net "M_J_CS_N<5>")
	)
	(segment
		(start 107.956858 -10.361168)
		(end 107.956858 -10.714228)
		(width 0.14224)
		(layer "In2.Cu")
		(net "M_J_CS_N<5>")
	)
	(segment
		(start 108.059474 -20.111212)
		(end 107.913932 -20.256754)
		(width 0.14224)
		(layer "In2.Cu")
		(net "M_J_CS_N<5>")
	)
	(segment
		(start 108.394246 -17.794986)
		(end 108.394246 -18.379186)
		(width 0.14224)
		(layer "In2.Cu")
		(net "M_J_CS_N<5>")
	)
	(segment
		(start 108.576364 -11.449304)
		(end 108.341414 -11.684254)
		(width 0.14224)
		(layer "In2.Cu")
		(net "M_J_CS_N<5>")
	)
	(segment
		(start 108.111798 -10.206228)
		(end 107.956858 -10.361168)
		(width 0.14224)
		(layer "In2.Cu")
		(net "M_J_CS_N<5>")
	)
	(segment
		(start 108.419646 -23.107396)
		(end 108.278168 -23.248874)
		(width 0.14224)
		(layer "In2.Cu")
		(net "M_J_CS_N<5>")
	)
	(segment
		(start 106.577892 -27.43327)
		(end 101.760528 -32.250634)
		(width 0.14224)
		(layer "In2.Cu")
		(net "M_J_CS_N<5>")
	)
	(segment
		(start 109.319568 -4.608576)
		(end 109.319568 -4.61518)
		(width 0.14224)
		(layer "In2.Cu")
		(net "M_J_CS_N<5>")
	)
	(segment
		(start 108.419646 -22.573996)
		(end 108.419646 -23.107396)
		(width 0.14224)
		(layer "In2.Cu")
		(net "M_J_CS_N<5>")
	)
	(segment
		(start 100.454968 -50.91176)
		(end 100.454968 -52.286408)
		(width 0.0889)
		(layer "In2.Cu")
		(net "M_J_CS_N<5>")
	)
	(segment
		(start 108.241846 -12.794996)
		(end 108.419646 -12.972796)
		(width 0.14224)
		(layer "In2.Cu")
		(net "M_J_CS_N<5>")
	)
	(arc
		(start 100.147374 -54.400196)
		(mid 100.200873 -54.600094)
		(end 100.147374 -54.799992)
		(width 0.0889)
		(layer "In2.Cu")
		(net "M_J_CS_N<5>")
	)
	(arc
		(start 100.147374 -57.771792)
		(mid 100.124565 -57.815368)
		(end 100.105464 -57.860692)
		(width 0.0889)
		(layer "In2.Cu")
		(net "M_J_CS_N<5>")
	)
	(arc
		(start 100.147374 -53.409596)
		(mid 100.200873 -53.609494)
		(end 100.147374 -53.809392)
		(width 0.0889)
		(layer "In2.Cu")
		(net "M_J_CS_N<5>")
	)
	(arc
		(start 100.147374 -56.781192)
		(mid 100.068243 -57.076594)
		(end 100.147374 -57.371996)
		(width 0.0889)
		(layer "In2.Cu")
		(net "M_J_CS_N<5>")
	)
	(arc
		(start 100.147374 -54.799992)
		(mid 100.068243 -55.095394)
		(end 100.147374 -55.390796)
		(width 0.0889)
		(layer "In2.Cu")
		(net "M_J_CS_N<5>")
	)
	(arc
		(start 100.147374 -52.818792)
		(mid 100.068243 -53.114194)
		(end 100.147374 -53.409596)
		(width 0.0889)
		(layer "In2.Cu")
		(net "M_J_CS_N<5>")
	)
	(arc
		(start 100.147374 -55.390796)
		(mid 100.200873 -55.590694)
		(end 100.147374 -55.790592)
		(width 0.0889)
		(layer "In2.Cu")
		(net "M_J_CS_N<5>")
	)
	(arc
		(start 100.147374 -55.790592)
		(mid 100.068243 -56.085994)
		(end 100.147374 -56.381396)
		(width 0.0889)
		(layer "In2.Cu")
		(net "M_J_CS_N<5>")
	)
	(arc
		(start 100.147374 -56.381396)
		(mid 100.200873 -56.581294)
		(end 100.147374 -56.781192)
		(width 0.0889)
		(layer "In2.Cu")
		(net "M_J_CS_N<5>")
	)
	(arc
		(start 100.147374 -57.371996)
		(mid 100.200873 -57.571894)
		(end 100.147374 -57.771792)
		(width 0.0889)
		(layer "In2.Cu")
		(net "M_J_CS_N<5>")
	)
	(arc
		(start 100.147374 -53.809392)
		(mid 100.068311 -54.104794)
		(end 100.147374 -54.400196)
		(width 0.0889)
		(layer "In2.Cu")
		(net "M_J_CS_N<5>")
	)
	(segment
		(start 97.796858 -60.047886)
		(end 97.225358 -60.047886)
		(width 0.1016)
		(layer "F.Cu")
		(net "M_J_CS_N<4>")
	)
	(via
		(at 97.225358 -60.047886)
		(size 0.508)
		(drill 0.254)
		(layers "F.Cu" "B.Cu")
		(net "M_J_CS_N<4>")
	)
	(via
		(at 105.349548 -4.332732)
		(size 0.4572)
		(drill 0.2032)
		(layers "F.Cu" "B.Cu")
		(net "M_J_CS_N<4>")
	)
	(segment
		(start 105.349548 -4.332732)
		(end 105.349548 -5.621782)
		(width 0.1651)
		(layer "B.Cu")
		(net "M_J_CS_N<4>")
	)
	(segment
		(start 97.737168 -58.362088)
		(end 97.743518 -58.35142)
		(width 0.0889)
		(layer "In2.Cu")
		(net "M_J_CS_N<4>")
	)
	(segment
		(start 104.003602 -21.278596)
		(end 104.086914 -21.195284)
		(width 0.14224)
		(layer "In2.Cu")
		(net "M_J_CS_N<4>")
	)
	(segment
		(start 104.083104 -8.5598)
		(end 104.206802 -8.436102)
		(width 0.14224)
		(layer "In2.Cu")
		(net "M_J_CS_N<4>")
	)
	(segment
		(start 97.743518 -56.791606)
		(end 97.737168 -56.780938)
		(width 0.0889)
		(layer "In2.Cu")
		(net "M_J_CS_N<4>")
	)
	(segment
		(start 104.156002 -21.888196)
		(end 104.003602 -21.735796)
		(width 0.14224)
		(layer "In2.Cu")
		(net "M_J_CS_N<4>")
	)
	(segment
		(start 104.206802 -18.233898)
		(end 104.206802 -17.210786)
		(width 0.14224)
		(layer "In2.Cu")
		(net "M_J_CS_N<4>")
	)
	(segment
		(start 98.372168 -51.1048)
		(end 98.678492 -50.798476)
		(width 0.0889)
		(layer "In2.Cu")
		(net "M_J_CS_N<4>")
	)
	(segment
		(start 97.743518 -55.801006)
		(end 97.737168 -55.790338)
		(width 0.0889)
		(layer "In2.Cu")
		(net "M_J_CS_N<4>")
	)
	(segment
		(start 98.678492 -50.798476)
		(end 98.678492 -49.07153)
		(width 0.0889)
		(layer "In2.Cu")
		(net "M_J_CS_N<4>")
	)
	(segment
		(start 104.083104 -12.214098)
		(end 104.083104 -8.5598)
		(width 0.14224)
		(layer "In2.Cu")
		(net "M_J_CS_N<4>")
	)
	(segment
		(start 104.182164 -24.172672)
		(end 104.182164 -23.285958)
		(width 0.14224)
		(layer "In2.Cu")
		(net "M_J_CS_N<4>")
	)
	(segment
		(start 104.182164 -23.285958)
		(end 104.003602 -23.107396)
		(width 0.14224)
		(layer "In2.Cu")
		(net "M_J_CS_N<4>")
	)
	(segment
		(start 98.678492 -49.07153)
		(end 99.220528 -48.529494)
		(width 0.0889)
		(layer "In2.Cu")
		(net "M_J_CS_N<4>")
	)
	(segment
		(start 104.088692 -5.593588)
		(end 105.349548 -4.332732)
		(width 0.14224)
		(layer "In2.Cu")
		(net "M_J_CS_N<4>")
	)
	(segment
		(start 104.086914 -21.195284)
		(end 104.086914 -18.353786)
		(width 0.14224)
		(layer "In2.Cu")
		(net "M_J_CS_N<4>")
	)
	(segment
		(start 97.737168 -53.809138)
		(end 97.732342 -53.800502)
		(width 0.0889)
		(layer "In2.Cu")
		(net "M_J_CS_N<4>")
	)
	(segment
		(start 97.654872 -52.673758)
		(end 97.654872 -52.458366)
		(width 0.0889)
		(layer "In2.Cu")
		(net "M_J_CS_N<4>")
	)
	(segment
		(start 97.737168 -56.780938)
		(end 97.732342 -56.772302)
		(width 0.0889)
		(layer "In2.Cu")
		(net "M_J_CS_N<4>")
	)
	(segment
		(start 99.220528 -31.196788)
		(end 102.690168 -27.727148)
		(width 0.14224)
		(layer "In2.Cu")
		(net "M_J_CS_N<4>")
	)
	(segment
		(start 97.720404 -59.382152)
		(end 97.737168 -59.352688)
		(width 0.0889)
		(layer "In2.Cu")
		(net "M_J_CS_N<4>")
	)
	(segment
		(start 97.737168 -57.771538)
		(end 97.732342 -57.762902)
		(width 0.0889)
		(layer "In2.Cu")
		(net "M_J_CS_N<4>")
	)
	(segment
		(start 102.690168 -25.664668)
		(end 104.182164 -24.172672)
		(width 0.14224)
		(layer "In2.Cu")
		(net "M_J_CS_N<4>")
	)
	(segment
		(start 104.088692 -7.491476)
		(end 104.088692 -5.593588)
		(width 0.14224)
		(layer "In2.Cu")
		(net "M_J_CS_N<4>")
	)
	(segment
		(start 104.206802 -7.609586)
		(end 104.088692 -7.491476)
		(width 0.14224)
		(layer "In2.Cu")
		(net "M_J_CS_N<4>")
	)
	(segment
		(start 104.003602 -21.735796)
		(end 104.003602 -21.278596)
		(width 0.14224)
		(layer "In2.Cu")
		(net "M_J_CS_N<4>")
	)
	(segment
		(start 104.08285 -17.086834)
		(end 104.08285 -15.85468)
		(width 0.14224)
		(layer "In2.Cu")
		(net "M_J_CS_N<4>")
	)
	(segment
		(start 102.690168 -27.727148)
		(end 102.690168 -25.664668)
		(width 0.14224)
		(layer "In2.Cu")
		(net "M_J_CS_N<4>")
	)
	(segment
		(start 99.220528 -48.32096)
		(end 99.220528 -31.196788)
		(width 0.14224)
		(layer "In2.Cu")
		(net "M_J_CS_N<4>")
	)
	(segment
		(start 97.737168 -52.818284)
		(end 97.654872 -52.673758)
		(width 0.0889)
		(layer "In2.Cu")
		(net "M_J_CS_N<4>")
	)
	(segment
		(start 97.743518 -53.819806)
		(end 97.737168 -53.809138)
		(width 0.0889)
		(layer "In2.Cu")
		(net "M_J_CS_N<4>")
	)
	(segment
		(start 97.225358 -60.047886)
		(end 97.720404 -59.382152)
		(width 0.0889)
		(layer "In2.Cu")
		(net "M_J_CS_N<4>")
	)
	(segment
		(start 98.372168 -51.74107)
		(end 98.372168 -51.1048)
		(width 0.0889)
		(layer "In2.Cu")
		(net "M_J_CS_N<4>")
	)
	(segment
		(start 104.156002 -22.446996)
		(end 104.156002 -21.888196)
		(width 0.14224)
		(layer "In2.Cu")
		(net "M_J_CS_N<4>")
	)
	(segment
		(start 99.220528 -48.529494)
		(end 99.220528 -48.32096)
		(width 0.0889)
		(layer "In2.Cu")
		(net "M_J_CS_N<4>")
	)
	(segment
		(start 104.156002 -13.397484)
		(end 104.156002 -12.286996)
		(width 0.14224)
		(layer "In2.Cu")
		(net "M_J_CS_N<4>")
	)
	(segment
		(start 104.003602 -23.107396)
		(end 104.003602 -22.599396)
		(width 0.14224)
		(layer "In2.Cu")
		(net "M_J_CS_N<4>")
	)
	(segment
		(start 97.737168 -54.799738)
		(end 97.732342 -54.791102)
		(width 0.0889)
		(layer "In2.Cu")
		(net "M_J_CS_N<4>")
	)
	(segment
		(start 97.737168 -55.790338)
		(end 97.732342 -55.781702)
		(width 0.0889)
		(layer "In2.Cu")
		(net "M_J_CS_N<4>")
	)
	(segment
		(start 104.003602 -22.599396)
		(end 104.156002 -22.446996)
		(width 0.14224)
		(layer "In2.Cu")
		(net "M_J_CS_N<4>")
	)
	(segment
		(start 104.156002 -12.286996)
		(end 104.083104 -12.214098)
		(width 0.14224)
		(layer "In2.Cu")
		(net "M_J_CS_N<4>")
	)
	(segment
		(start 97.654872 -52.458366)
		(end 98.372168 -51.74107)
		(width 0.0889)
		(layer "In2.Cu")
		(net "M_J_CS_N<4>")
	)
	(segment
		(start 104.08285 -15.85468)
		(end 104.065578 -15.837408)
		(width 0.14224)
		(layer "In2.Cu")
		(net "M_J_CS_N<4>")
	)
	(segment
		(start 104.065578 -13.487908)
		(end 104.156002 -13.397484)
		(width 0.14224)
		(layer "In2.Cu")
		(net "M_J_CS_N<4>")
	)
	(segment
		(start 104.206802 -17.210786)
		(end 104.08285 -17.086834)
		(width 0.14224)
		(layer "In2.Cu")
		(net "M_J_CS_N<4>")
	)
	(segment
		(start 104.065578 -15.837408)
		(end 104.065578 -13.487908)
		(width 0.14224)
		(layer "In2.Cu")
		(net "M_J_CS_N<4>")
	)
	(segment
		(start 104.206802 -8.436102)
		(end 104.206802 -7.609586)
		(width 0.14224)
		(layer "In2.Cu")
		(net "M_J_CS_N<4>")
	)
	(segment
		(start 97.743518 -54.810406)
		(end 97.737168 -54.799738)
		(width 0.0889)
		(layer "In2.Cu")
		(net "M_J_CS_N<4>")
	)
	(segment
		(start 104.086914 -18.353786)
		(end 104.206802 -18.233898)
		(width 0.14224)
		(layer "In2.Cu")
		(net "M_J_CS_N<4>")
	)
	(arc
		(start 97.737168 -55.390288)
		(mid 97.81639 -55.10117)
		(end 97.743518 -54.810406)
		(width 0.0889)
		(layer "In2.Cu")
		(net "M_J_CS_N<4>")
	)
	(arc
		(start 97.732342 -53.800502)
		(mid 97.683587 -53.60415)
		(end 97.737168 -53.409088)
		(width 0.0889)
		(layer "In2.Cu")
		(net "M_J_CS_N<4>")
	)
	(arc
		(start 97.732342 -54.791102)
		(mid 97.683587 -54.59475)
		(end 97.737168 -54.399688)
		(width 0.0889)
		(layer "In2.Cu")
		(net "M_J_CS_N<4>")
	)
	(arc
		(start 97.737168 -58.761884)
		(mid 97.683669 -58.561986)
		(end 97.737168 -58.362088)
		(width 0.0889)
		(layer "In2.Cu")
		(net "M_J_CS_N<4>")
	)
	(arc
		(start 97.743518 -58.35142)
		(mid 97.816316 -58.060657)
		(end 97.737168 -57.771538)
		(width 0.0889)
		(layer "In2.Cu")
		(net "M_J_CS_N<4>")
	)
	(arc
		(start 97.732342 -57.762902)
		(mid 97.683587 -57.56655)
		(end 97.737168 -57.371488)
		(width 0.0889)
		(layer "In2.Cu")
		(net "M_J_CS_N<4>")
	)
	(arc
		(start 97.732342 -55.781702)
		(mid 97.683587 -55.58535)
		(end 97.737168 -55.390288)
		(width 0.0889)
		(layer "In2.Cu")
		(net "M_J_CS_N<4>")
	)
	(arc
		(start 97.737168 -53.409088)
		(mid 97.816299 -53.113686)
		(end 97.737168 -52.818284)
		(width 0.0889)
		(layer "In2.Cu")
		(net "M_J_CS_N<4>")
	)
	(arc
		(start 97.732342 -56.772302)
		(mid 97.683587 -56.57595)
		(end 97.737168 -56.380888)
		(width 0.0889)
		(layer "In2.Cu")
		(net "M_J_CS_N<4>")
	)
	(arc
		(start 97.737168 -56.380888)
		(mid 97.81639 -56.09177)
		(end 97.743518 -55.801006)
		(width 0.0889)
		(layer "In2.Cu")
		(net "M_J_CS_N<4>")
	)
	(arc
		(start 97.737168 -54.399688)
		(mid 97.81639 -54.11057)
		(end 97.743518 -53.819806)
		(width 0.0889)
		(layer "In2.Cu")
		(net "M_J_CS_N<4>")
	)
	(arc
		(start 97.737168 -59.352688)
		(mid 97.816299 -59.057286)
		(end 97.737168 -58.761884)
		(width 0.0889)
		(layer "In2.Cu")
		(net "M_J_CS_N<4>")
	)
	(arc
		(start 97.737168 -57.371488)
		(mid 97.81639 -57.08237)
		(end 97.743518 -56.791606)
		(width 0.0889)
		(layer "In2.Cu")
		(net "M_J_CS_N<4>")
	)
	(segment
		(start 112.99952 -0.821182)
		(end 112.99952 1.152144)
		(width 0.1651)
		(layer "F.Cu")
		(net "M_J_CS_N<3>")
	)
	(segment
		(start 101.517704 -59.55284)
		(end 102.089204 -59.55284)
		(width 0.1016)
		(layer "F.Cu")
		(net "M_J_CS_N<3>")
	)
	(via
		(at 101.517704 -59.55284)
		(size 0.508)
		(drill 0.254)
		(layers "F.Cu" "B.Cu")
		(net "M_J_CS_N<3>")
	)
	(via
		(at 112.99952 1.152144)
		(size 0.508)
		(drill 0.254)
		(layers "F.Cu" "B.Cu")
		(net "M_J_CS_N<3>")
	)
	(segment
		(start 112.587024 -4.733544)
		(end 112.587024 -1.837944)
		(width 0.14224)
		(layer "In2.Cu")
		(net "M_J_CS_N<3>")
	)
	(segment
		(start 109.802168 -26.212546)
		(end 111.64189 -24.372824)
		(width 0.14224)
		(layer "In2.Cu")
		(net "M_J_CS_N<3>")
	)
	(segment
		(start 111.79429 -17.794986)
		(end 111.64189 -17.642586)
		(width 0.14224)
		(layer "In2.Cu")
		(net "M_J_CS_N<3>")
	)
	(segment
		(start 103.792528 -48.093122)
		(end 103.792528 -33.09366)
		(width 0.14224)
		(layer "In2.Cu")
		(net "M_J_CS_N<3>")
	)
	(segment
		(start 103.792528 -33.09366)
		(end 109.802168 -27.08402)
		(width 0.14224)
		(layer "In2.Cu")
		(net "M_J_CS_N<3>")
	)
	(segment
		(start 111.79429 -19.141186)
		(end 111.709962 -19.056858)
		(width 0.14224)
		(layer "In2.Cu")
		(net "M_J_CS_N<3>")
	)
	(segment
		(start 111.64189 -23.285196)
		(end 111.81969 -23.107396)
		(width 0.14224)
		(layer "In2.Cu")
		(net "M_J_CS_N<3>")
	)
	(segment
		(start 111.64189 -21.913596)
		(end 111.79429 -21.761196)
		(width 0.14224)
		(layer "In2.Cu")
		(net "M_J_CS_N<3>")
	)
	(segment
		(start 111.79429 -18.379186)
		(end 111.79429 -17.794986)
		(width 0.14224)
		(layer "In2.Cu")
		(net "M_J_CS_N<3>")
	)
	(segment
		(start 111.79429 -11.085576)
		(end 111.79429 -9.539986)
		(width 0.14224)
		(layer "In2.Cu")
		(net "M_J_CS_N<3>")
	)
	(segment
		(start 111.81969 -12.91336)
		(end 111.712502 -12.806172)
		(width 0.14224)
		(layer "In2.Cu")
		(net "M_J_CS_N<3>")
	)
	(segment
		(start 103.792528 -48.35144)
		(end 103.792528 -48.093122)
		(width 0.0889)
		(layer "In2.Cu")
		(net "M_J_CS_N<3>")
	)
	(segment
		(start 101.517704 -59.55284)
		(end 102.410768 -58.659776)
		(width 0.0889)
		(layer "In2.Cu")
		(net "M_J_CS_N<3>")
	)
	(segment
		(start 111.71555 -9.461246)
		(end 111.71555 -8.856726)
		(width 0.14224)
		(layer "In2.Cu")
		(net "M_J_CS_N<3>")
	)
	(segment
		(start 111.714026 -7.46125)
		(end 111.714026 -5.606542)
		(width 0.14224)
		(layer "In2.Cu")
		(net "M_J_CS_N<3>")
	)
	(segment
		(start 111.79429 -9.539986)
		(end 111.71555 -9.461246)
		(width 0.14224)
		(layer "In2.Cu")
		(net "M_J_CS_N<3>")
	)
	(segment
		(start 111.709962 -18.463514)
		(end 111.79429 -18.379186)
		(width 0.14224)
		(layer "In2.Cu")
		(net "M_J_CS_N<3>")
	)
	(segment
		(start 111.709962 -19.056858)
		(end 111.709962 -18.463514)
		(width 0.14224)
		(layer "In2.Cu")
		(net "M_J_CS_N<3>")
	)
	(segment
		(start 111.714026 -5.606542)
		(end 112.587024 -4.733544)
		(width 0.14224)
		(layer "In2.Cu")
		(net "M_J_CS_N<3>")
	)
	(segment
		(start 111.79429 -8.777986)
		(end 111.79429 -8.193786)
		(width 0.14224)
		(layer "In2.Cu")
		(net "M_J_CS_N<3>")
	)
	(segment
		(start 111.712756 -13.61313)
		(end 111.81969 -13.506196)
		(width 0.14224)
		(layer "In2.Cu")
		(net "M_J_CS_N<3>")
	)
	(segment
		(start 111.81969 -23.107396)
		(end 111.81969 -22.573996)
		(width 0.14224)
		(layer "In2.Cu")
		(net "M_J_CS_N<3>")
	)
	(segment
		(start 111.64189 -24.372824)
		(end 111.64189 -23.285196)
		(width 0.14224)
		(layer "In2.Cu")
		(net "M_J_CS_N<3>")
	)
	(segment
		(start 112.99952 -1.425448)
		(end 112.99952 1.152144)
		(width 0.14224)
		(layer "In2.Cu")
		(net "M_J_CS_N<3>")
	)
	(segment
		(start 111.712502 -12.806172)
		(end 111.712502 -11.167364)
		(width 0.14224)
		(layer "In2.Cu")
		(net "M_J_CS_N<3>")
	)
	(segment
		(start 111.64189 -17.642586)
		(end 111.64189 -17.134586)
		(width 0.14224)
		(layer "In2.Cu")
		(net "M_J_CS_N<3>")
	)
	(segment
		(start 112.587024 -1.837944)
		(end 112.99952 -1.425448)
		(width 0.14224)
		(layer "In2.Cu")
		(net "M_J_CS_N<3>")
	)
	(segment
		(start 102.410768 -58.659776)
		(end 102.410768 -51.7398)
		(width 0.0889)
		(layer "In2.Cu")
		(net "M_J_CS_N<3>")
	)
	(segment
		(start 111.81969 -13.506196)
		(end 111.81969 -12.91336)
		(width 0.14224)
		(layer "In2.Cu")
		(net "M_J_CS_N<3>")
	)
	(segment
		(start 102.410768 -51.7398)
		(end 102.207568 -51.5366)
		(width 0.0889)
		(layer "In2.Cu")
		(net "M_J_CS_N<3>")
	)
	(segment
		(start 111.71555 -8.856726)
		(end 111.79429 -8.777986)
		(width 0.14224)
		(layer "In2.Cu")
		(net "M_J_CS_N<3>")
	)
	(segment
		(start 111.64189 -7.533386)
		(end 111.714026 -7.46125)
		(width 0.14224)
		(layer "In2.Cu")
		(net "M_J_CS_N<3>")
	)
	(segment
		(start 111.79429 -21.761196)
		(end 111.79429 -19.141186)
		(width 0.14224)
		(layer "In2.Cu")
		(net "M_J_CS_N<3>")
	)
	(segment
		(start 111.79429 -8.193786)
		(end 111.64189 -8.041386)
		(width 0.14224)
		(layer "In2.Cu")
		(net "M_J_CS_N<3>")
	)
	(segment
		(start 111.64189 -8.041386)
		(end 111.64189 -7.533386)
		(width 0.14224)
		(layer "In2.Cu")
		(net "M_J_CS_N<3>")
	)
	(segment
		(start 102.207568 -51.5366)
		(end 102.207568 -49.9364)
		(width 0.0889)
		(layer "In2.Cu")
		(net "M_J_CS_N<3>")
	)
	(segment
		(start 111.64189 -22.396196)
		(end 111.64189 -21.913596)
		(width 0.14224)
		(layer "In2.Cu")
		(net "M_J_CS_N<3>")
	)
	(segment
		(start 109.802168 -27.08402)
		(end 109.802168 -26.212546)
		(width 0.14224)
		(layer "In2.Cu")
		(net "M_J_CS_N<3>")
	)
	(segment
		(start 111.81969 -22.573996)
		(end 111.64189 -22.396196)
		(width 0.14224)
		(layer "In2.Cu")
		(net "M_J_CS_N<3>")
	)
	(segment
		(start 111.712756 -17.06372)
		(end 111.712756 -13.61313)
		(width 0.14224)
		(layer "In2.Cu")
		(net "M_J_CS_N<3>")
	)
	(segment
		(start 102.207568 -49.9364)
		(end 103.792528 -48.35144)
		(width 0.0889)
		(layer "In2.Cu")
		(net "M_J_CS_N<3>")
	)
	(segment
		(start 111.712502 -11.167364)
		(end 111.79429 -11.085576)
		(width 0.14224)
		(layer "In2.Cu")
		(net "M_J_CS_N<3>")
	)
	(segment
		(start 111.64189 -17.134586)
		(end 111.712756 -17.06372)
		(width 0.14224)
		(layer "In2.Cu")
		(net "M_J_CS_N<3>")
	)
	(segment
		(start 102.089204 -58.561986)
		(end 101.517704 -58.561986)
		(width 0.1016)
		(layer "F.Cu")
		(net "M_J_CS_N<2>")
	)
	(segment
		(start 112.99952 3.778758)
		(end 112.99952 2.485644)
		(width 0.1651)
		(layer "F.Cu")
		(net "M_J_CS_N<2>")
	)
	(via
		(at 112.99952 2.485644)
		(size 0.508)
		(drill 0.254)
		(layers "F.Cu" "B.Cu")
		(net "M_J_CS_N<2>")
	)
	(via
		(at 101.517704 -58.561986)
		(size 0.508)
		(drill 0.254)
		(layers "F.Cu" "B.Cu")
		(net "M_J_CS_N<2>")
	)
	(segment
		(start 110.883446 -18.408142)
		(end 110.80369 -18.328386)
		(width 0.14224)
		(layer "In2.Cu")
		(net "M_J_CS_N<2>")
	)
	(segment
		(start 110.80369 -23.107396)
		(end 110.80369 -22.599396)
		(width 0.14224)
		(layer "In2.Cu")
		(net "M_J_CS_N<2>")
	)
	(segment
		(start 109.268768 -26.898854)
		(end 109.268768 -25.983946)
		(width 0.14224)
		(layer "In2.Cu")
		(net "M_J_CS_N<2>")
	)
	(segment
		(start 110.891828 -13.594334)
		(end 110.80369 -13.506196)
		(width 0.14224)
		(layer "In2.Cu")
		(net "M_J_CS_N<2>")
	)
	(segment
		(start 111.714026 0.094742)
		(end 111.656368 0.1524)
		(width 0.14224)
		(layer "In2.Cu")
		(net "M_J_CS_N<2>")
	)
	(segment
		(start 110.80369 -21.735796)
		(end 110.80369 -21.278596)
		(width 0.14224)
		(layer "In2.Cu")
		(net "M_J_CS_N<2>")
	)
	(segment
		(start 103.284528 -32.883094)
		(end 109.268768 -26.898854)
		(width 0.14224)
		(layer "In2.Cu")
		(net "M_J_CS_N<2>")
	)
	(segment
		(start 101.972872 -49.790096)
		(end 103.284528 -48.47844)
		(width 0.0889)
		(layer "In2.Cu")
		(net "M_J_CS_N<2>")
	)
	(segment
		(start 109.268768 -25.983946)
		(end 110.95609 -24.296624)
		(width 0.14224)
		(layer "In2.Cu")
		(net "M_J_CS_N<2>")
	)
	(segment
		(start 110.80369 -21.278596)
		(end 110.883446 -21.19884)
		(width 0.14224)
		(layer "In2.Cu")
		(net "M_J_CS_N<2>")
	)
	(segment
		(start 110.871254 -9.696704)
		(end 110.871254 -8.100822)
		(width 0.14224)
		(layer "In2.Cu")
		(net "M_J_CS_N<2>")
	)
	(segment
		(start 110.95609 -22.446996)
		(end 110.95609 -21.888196)
		(width 0.14224)
		(layer "In2.Cu")
		(net "M_J_CS_N<2>")
	)
	(segment
		(start 110.892336 -5.564378)
		(end 111.714026 -4.742688)
		(width 0.14224)
		(layer "In2.Cu")
		(net "M_J_CS_N<2>")
	)
	(segment
		(start 110.871254 -8.100822)
		(end 111.00689 -7.965186)
		(width 0.14224)
		(layer "In2.Cu")
		(net "M_J_CS_N<2>")
	)
	(segment
		(start 110.95609 -23.259796)
		(end 110.80369 -23.107396)
		(width 0.14224)
		(layer "In2.Cu")
		(net "M_J_CS_N<2>")
	)
	(segment
		(start 110.80369 -17.769586)
		(end 111.00689 -17.566386)
		(width 0.14224)
		(layer "In2.Cu")
		(net "M_J_CS_N<2>")
	)
	(segment
		(start 110.95609 -12.286996)
		(end 110.88751 -12.218416)
		(width 0.14224)
		(layer "In2.Cu")
		(net "M_J_CS_N<2>")
	)
	(segment
		(start 103.284528 -48.47844)
		(end 103.284528 -48.194722)
		(width 0.0889)
		(layer "In2.Cu")
		(net "M_J_CS_N<2>")
	)
	(segment
		(start 110.80369 -13.506196)
		(end 110.80369 -12.998196)
		(width 0.14224)
		(layer "In2.Cu")
		(net "M_J_CS_N<2>")
	)
	(segment
		(start 110.88751 -12.218416)
		(end 110.88751 -11.593576)
		(width 0.14224)
		(layer "In2.Cu")
		(net "M_J_CS_N<2>")
	)
	(segment
		(start 111.656368 0.696976)
		(end 112.99952 2.040128)
		(width 0.14224)
		(layer "In2.Cu")
		(net "M_J_CS_N<2>")
	)
	(segment
		(start 110.95609 -11.524996)
		(end 110.95609 -9.901682)
		(width 0.14224)
		(layer "In2.Cu")
		(net "M_J_CS_N<2>")
	)
	(segment
		(start 110.80369 -12.998196)
		(end 110.95609 -12.845796)
		(width 0.14224)
		(layer "In2.Cu")
		(net "M_J_CS_N<2>")
	)
	(segment
		(start 110.95609 -21.888196)
		(end 110.80369 -21.735796)
		(width 0.14224)
		(layer "In2.Cu")
		(net "M_J_CS_N<2>")
	)
	(segment
		(start 111.656368 0.1524)
		(end 111.656368 0.696976)
		(width 0.14224)
		(layer "In2.Cu")
		(net "M_J_CS_N<2>")
	)
	(segment
		(start 103.284528 -48.194722)
		(end 103.284528 -32.883094)
		(width 0.14224)
		(layer "In2.Cu")
		(net "M_J_CS_N<2>")
	)
	(segment
		(start 110.892336 -7.495032)
		(end 110.892336 -5.564378)
		(width 0.14224)
		(layer "In2.Cu")
		(net "M_J_CS_N<2>")
	)
	(segment
		(start 101.517704 -58.561986)
		(end 101.972872 -58.106818)
		(width 0.0889)
		(layer "In2.Cu")
		(net "M_J_CS_N<2>")
	)
	(segment
		(start 110.95609 -9.901682)
		(end 110.871254 -9.696704)
		(width 0.14224)
		(layer "In2.Cu")
		(net "M_J_CS_N<2>")
	)
	(segment
		(start 110.80369 -18.328386)
		(end 110.80369 -17.769586)
		(width 0.14224)
		(layer "In2.Cu")
		(net "M_J_CS_N<2>")
	)
	(segment
		(start 111.00689 -17.566386)
		(end 111.00689 -17.210786)
		(width 0.14224)
		(layer "In2.Cu")
		(net "M_J_CS_N<2>")
	)
	(segment
		(start 110.891828 -17.095724)
		(end 110.891828 -13.594334)
		(width 0.14224)
		(layer "In2.Cu")
		(net "M_J_CS_N<2>")
	)
	(segment
		(start 111.00689 -17.210786)
		(end 110.891828 -17.095724)
		(width 0.14224)
		(layer "In2.Cu")
		(net "M_J_CS_N<2>")
	)
	(segment
		(start 110.95609 -12.845796)
		(end 110.95609 -12.286996)
		(width 0.14224)
		(layer "In2.Cu")
		(net "M_J_CS_N<2>")
	)
	(segment
		(start 101.972872 -58.106818)
		(end 101.972872 -49.790096)
		(width 0.0889)
		(layer "In2.Cu")
		(net "M_J_CS_N<2>")
	)
	(segment
		(start 110.80369 -22.599396)
		(end 110.95609 -22.446996)
		(width 0.14224)
		(layer "In2.Cu")
		(net "M_J_CS_N<2>")
	)
	(segment
		(start 111.00689 -7.965186)
		(end 111.00689 -7.609586)
		(width 0.14224)
		(layer "In2.Cu")
		(net "M_J_CS_N<2>")
	)
	(segment
		(start 111.714026 -4.742688)
		(end 111.714026 0.094742)
		(width 0.14224)
		(layer "In2.Cu")
		(net "M_J_CS_N<2>")
	)
	(segment
		(start 112.99952 2.040128)
		(end 112.99952 2.485644)
		(width 0.14224)
		(layer "In2.Cu")
		(net "M_J_CS_N<2>")
	)
	(segment
		(start 110.88751 -11.593576)
		(end 110.95609 -11.524996)
		(width 0.14224)
		(layer "In2.Cu")
		(net "M_J_CS_N<2>")
	)
	(segment
		(start 111.00689 -7.609586)
		(end 110.892336 -7.495032)
		(width 0.14224)
		(layer "In2.Cu")
		(net "M_J_CS_N<2>")
	)
	(segment
		(start 110.883446 -21.19884)
		(end 110.883446 -18.408142)
		(width 0.14224)
		(layer "In2.Cu")
		(net "M_J_CS_N<2>")
	)
	(segment
		(start 110.95609 -24.296624)
		(end 110.95609 -23.259796)
		(width 0.14224)
		(layer "In2.Cu")
		(net "M_J_CS_N<2>")
	)
	(segment
		(start 109.599476 3.778758)
		(end 109.599476 2.514854)
		(width 0.1651)
		(layer "F.Cu")
		(net "M_J_CS_N<1>")
	)
	(segment
		(start 99.513898 -60.047886)
		(end 98.942398 -60.047886)
		(width 0.1016)
		(layer "F.Cu")
		(net "M_J_CS_N<1>")
	)
	(via
		(at 109.599476 2.514854)
		(size 0.508)
		(drill 0.254)
		(layers "F.Cu" "B.Cu")
		(net "M_J_CS_N<1>")
	)
	(via
		(at 98.942398 -60.047886)
		(size 0.508)
		(drill 0.254)
		(layers "F.Cu" "B.Cu")
		(net "M_J_CS_N<1>")
	)
	(segment
		(start 101.252528 -48.589184)
		(end 101.252528 -48.970184)
		(width 0.0889)
		(layer "In2.Cu")
		(net "M_J_CS_N<1>")
	)
	(segment
		(start 107.461304 -18.188432)
		(end 107.461304 -19.05381)
		(width 0.14224)
		(layer "In2.Cu")
		(net "M_J_CS_N<1>")
	)
	(segment
		(start 100.20046 -50.022252)
		(end 100.20046 -52.115974)
		(width 0.0889)
		(layer "In2.Cu")
		(net "M_J_CS_N<1>")
	)
	(segment
		(start 107.45978 -7.46252)
		(end 107.642914 -7.645654)
		(width 0.14224)
		(layer "In2.Cu")
		(net "M_J_CS_N<1>")
	)
	(segment
		(start 107.45851 -12.18946)
		(end 107.484672 -12.215622)
		(width 0.14224)
		(layer "In2.Cu")
		(net "M_J_CS_N<1>")
	)
	(segment
		(start 107.403646 -19.111468)
		(end 107.403646 -21.735796)
		(width 0.14224)
		(layer "In2.Cu")
		(net "M_J_CS_N<1>")
	)
	(segment
		(start 109.599476 2.514854)
		(end 109.599476 1.829308)
		(width 0.14224)
		(layer "In2.Cu")
		(net "M_J_CS_N<1>")
	)
	(segment
		(start 99.454208 -59.352942)
		(end 99.438714 -59.380374)
		(width 0.0889)
		(layer "In2.Cu")
		(net "M_J_CS_N<1>")
	)
	(segment
		(start 107.606846 -18.04289)
		(end 107.461304 -18.188432)
		(width 0.14224)
		(layer "In2.Cu")
		(net "M_J_CS_N<1>")
	)
	(segment
		(start 107.484672 -12.215622)
		(end 107.484672 -14.568932)
		(width 0.14224)
		(layer "In2.Cu")
		(net "M_J_CS_N<1>")
	)
	(segment
		(start 107.556046 -23.708868)
		(end 106.017568 -25.247346)
		(width 0.14224)
		(layer "In2.Cu")
		(net "M_J_CS_N<1>")
	)
	(segment
		(start 107.46105 -14.592554)
		(end 107.46105 -17.06499)
		(width 0.14224)
		(layer "In2.Cu")
		(net "M_J_CS_N<1>")
	)
	(segment
		(start 106.017568 -27.274774)
		(end 101.252528 -32.039814)
		(width 0.14224)
		(layer "In2.Cu")
		(net "M_J_CS_N<1>")
	)
	(segment
		(start 107.45851 -8.682482)
		(end 107.45851 -12.18946)
		(width 0.14224)
		(layer "In2.Cu")
		(net "M_J_CS_N<1>")
	)
	(segment
		(start 107.46105 -17.06499)
		(end 107.606846 -17.210786)
		(width 0.14224)
		(layer "In2.Cu")
		(net "M_J_CS_N<1>")
	)
	(segment
		(start 107.556046 -23.259796)
		(end 107.556046 -23.708868)
		(width 0.14224)
		(layer "In2.Cu")
		(net "M_J_CS_N<1>")
	)
	(segment
		(start 99.454208 -54.799738)
		(end 99.463098 -54.814978)
		(width 0.0889)
		(layer "In2.Cu")
		(net "M_J_CS_N<1>")
	)
	(segment
		(start 107.642914 -8.498078)
		(end 107.45851 -8.682482)
		(width 0.14224)
		(layer "In2.Cu")
		(net "M_J_CS_N<1>")
	)
	(segment
		(start 107.461304 -19.05381)
		(end 107.403646 -19.111468)
		(width 0.14224)
		(layer "In2.Cu")
		(net "M_J_CS_N<1>")
	)
	(segment
		(start 107.556046 -21.888196)
		(end 107.556046 -22.446996)
		(width 0.14224)
		(layer "In2.Cu")
		(net "M_J_CS_N<1>")
	)
	(segment
		(start 107.484672 -14.568932)
		(end 107.46105 -14.592554)
		(width 0.14224)
		(layer "In2.Cu")
		(net "M_J_CS_N<1>")
	)
	(segment
		(start 109.158278 -0.05969)
		(end 109.158278 -3.15849)
		(width 0.14224)
		(layer "In2.Cu")
		(net "M_J_CS_N<1>")
	)
	(segment
		(start 99.454208 -58.761884)
		(end 99.460558 -58.772552)
		(width 0.0889)
		(layer "In2.Cu")
		(net "M_J_CS_N<1>")
	)
	(segment
		(start 101.252528 -32.039814)
		(end 101.252528 -48.589184)
		(width 0.14224)
		(layer "In2.Cu")
		(net "M_J_CS_N<1>")
	)
	(segment
		(start 107.642914 -7.645654)
		(end 107.642914 -8.498078)
		(width 0.14224)
		(layer "In2.Cu")
		(net "M_J_CS_N<1>")
	)
	(segment
		(start 109.141768 1.3716)
		(end 109.141768 0.8636)
		(width 0.14224)
		(layer "In2.Cu")
		(net "M_J_CS_N<1>")
	)
	(segment
		(start 99.438714 -59.380374)
		(end 98.942398 -60.047886)
		(width 0.0889)
		(layer "In2.Cu")
		(net "M_J_CS_N<1>")
	)
	(segment
		(start 99.454208 -53.809138)
		(end 99.463098 -53.824378)
		(width 0.0889)
		(layer "In2.Cu")
		(net "M_J_CS_N<1>")
	)
	(segment
		(start 109.243368 0.0254)
		(end 109.158278 -0.05969)
		(width 0.14224)
		(layer "In2.Cu")
		(net "M_J_CS_N<1>")
	)
	(segment
		(start 99.454208 -55.790338)
		(end 99.463098 -55.805578)
		(width 0.0889)
		(layer "In2.Cu")
		(net "M_J_CS_N<1>")
	)
	(segment
		(start 99.454208 -56.780938)
		(end 99.463098 -56.796178)
		(width 0.0889)
		(layer "In2.Cu")
		(net "M_J_CS_N<1>")
	)
	(segment
		(start 109.158278 -3.15849)
		(end 108.307632 -4.009136)
		(width 0.14224)
		(layer "In2.Cu")
		(net "M_J_CS_N<1>")
	)
	(segment
		(start 109.141768 0.8636)
		(end 109.243368 0.762)
		(width 0.14224)
		(layer "In2.Cu")
		(net "M_J_CS_N<1>")
	)
	(segment
		(start 106.017568 -25.247346)
		(end 106.017568 -27.274774)
		(width 0.14224)
		(layer "In2.Cu")
		(net "M_J_CS_N<1>")
	)
	(segment
		(start 107.45978 -5.756402)
		(end 107.45978 -7.46252)
		(width 0.14224)
		(layer "In2.Cu")
		(net "M_J_CS_N<1>")
	)
	(segment
		(start 100.20046 -52.115974)
		(end 99.454208 -53.409342)
		(width 0.0889)
		(layer "In2.Cu")
		(net "M_J_CS_N<1>")
	)
	(segment
		(start 107.403646 -21.735796)
		(end 107.556046 -21.888196)
		(width 0.14224)
		(layer "In2.Cu")
		(net "M_J_CS_N<1>")
	)
	(segment
		(start 107.403646 -23.107396)
		(end 107.556046 -23.259796)
		(width 0.14224)
		(layer "In2.Cu")
		(net "M_J_CS_N<1>")
	)
	(segment
		(start 108.307632 -4.009136)
		(end 108.307632 -4.90855)
		(width 0.14224)
		(layer "In2.Cu")
		(net "M_J_CS_N<1>")
	)
	(segment
		(start 107.556046 -22.446996)
		(end 107.403646 -22.599396)
		(width 0.14224)
		(layer "In2.Cu")
		(net "M_J_CS_N<1>")
	)
	(segment
		(start 108.307632 -4.90855)
		(end 107.45978 -5.756402)
		(width 0.14224)
		(layer "In2.Cu")
		(net "M_J_CS_N<1>")
	)
	(segment
		(start 109.243368 0.762)
		(end 109.243368 0.0254)
		(width 0.14224)
		(layer "In2.Cu")
		(net "M_J_CS_N<1>")
	)
	(segment
		(start 99.460558 -58.35142)
		(end 99.454208 -58.362088)
		(width 0.0889)
		(layer "In2.Cu")
		(net "M_J_CS_N<1>")
	)
	(segment
		(start 109.599476 1.829308)
		(end 109.141768 1.3716)
		(width 0.14224)
		(layer "In2.Cu")
		(net "M_J_CS_N<1>")
	)
	(segment
		(start 107.403646 -22.599396)
		(end 107.403646 -23.107396)
		(width 0.14224)
		(layer "In2.Cu")
		(net "M_J_CS_N<1>")
	)
	(segment
		(start 107.606846 -17.210786)
		(end 107.606846 -18.04289)
		(width 0.14224)
		(layer "In2.Cu")
		(net "M_J_CS_N<1>")
	)
	(segment
		(start 101.252528 -48.970184)
		(end 100.20046 -50.022252)
		(width 0.0889)
		(layer "In2.Cu")
		(net "M_J_CS_N<1>")
	)
	(arc
		(start 99.463098 -53.824378)
		(mid 99.533495 -54.113329)
		(end 99.454208 -54.399942)
		(width 0.0889)
		(layer "In2.Cu")
		(net "M_J_CS_N<1>")
	)
	(arc
		(start 99.463098 -56.796178)
		(mid 99.533495 -57.085129)
		(end 99.454208 -57.371742)
		(width 0.0889)
		(layer "In2.Cu")
		(net "M_J_CS_N<1>")
	)
	(arc
		(start 99.454208 -55.390542)
		(mid 99.400675 -55.59044)
		(end 99.454208 -55.790338)
		(width 0.0889)
		(layer "In2.Cu")
		(net "M_J_CS_N<1>")
	)
	(arc
		(start 99.463098 -55.805578)
		(mid 99.533495 -56.094529)
		(end 99.454208 -56.381142)
		(width 0.0889)
		(layer "In2.Cu")
		(net "M_J_CS_N<1>")
	)
	(arc
		(start 99.454208 -53.409342)
		(mid 99.400675 -53.60924)
		(end 99.454208 -53.809138)
		(width 0.0889)
		(layer "In2.Cu")
		(net "M_J_CS_N<1>")
	)
	(arc
		(start 99.460558 -58.772552)
		(mid 99.533478 -59.063569)
		(end 99.454208 -59.352942)
		(width 0.0889)
		(layer "In2.Cu")
		(net "M_J_CS_N<1>")
	)
	(arc
		(start 99.454208 -56.381142)
		(mid 99.400675 -56.58104)
		(end 99.454208 -56.780938)
		(width 0.0889)
		(layer "In2.Cu")
		(net "M_J_CS_N<1>")
	)
	(arc
		(start 99.454208 -57.771538)
		(mid 99.53343 -58.060656)
		(end 99.460558 -58.35142)
		(width 0.0889)
		(layer "In2.Cu")
		(net "M_J_CS_N<1>")
	)
	(arc
		(start 99.454208 -58.362088)
		(mid 99.400675 -58.561986)
		(end 99.454208 -58.761884)
		(width 0.0889)
		(layer "In2.Cu")
		(net "M_J_CS_N<1>")
	)
	(arc
		(start 99.454208 -57.371742)
		(mid 99.400675 -57.57164)
		(end 99.454208 -57.771538)
		(width 0.0889)
		(layer "In2.Cu")
		(net "M_J_CS_N<1>")
	)
	(arc
		(start 99.463098 -54.814978)
		(mid 99.533495 -55.103929)
		(end 99.454208 -55.390542)
		(width 0.0889)
		(layer "In2.Cu")
		(net "M_J_CS_N<1>")
	)
	(arc
		(start 99.454208 -54.399942)
		(mid 99.400675 -54.59984)
		(end 99.454208 -54.799738)
		(width 0.0889)
		(layer "In2.Cu")
		(net "M_J_CS_N<1>")
	)
	(segment
		(start 97.796858 -58.06694)
		(end 97.225358 -58.06694)
		(width 0.1016)
		(layer "F.Cu")
		(net "M_J_CS_N<0>")
	)
	(segment
		(start 105.349548 3.778758)
		(end 105.349548 1.805686)
		(width 0.1651)
		(layer "F.Cu")
		(net "M_J_CS_N<0>")
	)
	(segment
		(start 105.349548 1.805686)
		(end 105.349294 1.805432)
		(width 0.1651)
		(layer "F.Cu")
		(net "M_J_CS_N<0>")
	)
	(via
		(at 105.349294 1.805432)
		(size 0.508)
		(drill 0.254)
		(layers "F.Cu" "B.Cu")
		(net "M_J_CS_N<0>")
	)
	(via
		(at 97.225358 -58.06694)
		(size 0.508)
		(drill 0.254)
		(layers "F.Cu" "B.Cu")
		(net "M_J_CS_N<0>")
	)
	(segment
		(start 104.585516 -1.477518)
		(end 104.792272 -1.270762)
		(width 0.14224)
		(layer "In2.Cu")
		(net "M_J_CS_N<0>")
	)
	(segment
		(start 104.244394 -1.477518)
		(end 104.585516 -1.477518)
		(width 0.14224)
		(layer "In2.Cu")
		(net "M_J_CS_N<0>")
	)
	(segment
		(start 97.572068 -52.913788)
		(end 97.441004 -52.704492)
		(width 0.0889)
		(layer "In2.Cu")
		(net "M_J_CS_N<0>")
	)
	(segment
		(start 97.218246 -58.04916)
		(end 97.49663 -57.406286)
		(width 0.0889)
		(layer "In2.Cu")
		(net "M_J_CS_N<0>")
	)
	(segment
		(start 103.373428 -23.106126)
		(end 103.373428 -22.740366)
		(width 0.14224)
		(layer "In2.Cu")
		(net "M_J_CS_N<0>")
	)
	(segment
		(start 103.041958 -13.503148)
		(end 103.041958 -12.363196)
		(width 0.14224)
		(layer "In2.Cu")
		(net "M_J_CS_N<0>")
	)
	(segment
		(start 104.010968 0.8636)
		(end 104.010968 1.448308)
		(width 0.14224)
		(layer "In2.Cu")
		(net "M_J_CS_N<0>")
	)
	(segment
		(start 104.334818 -3.572764)
		(end 104.334818 -2.81686)
		(width 0.14224)
		(layer "In2.Cu")
		(net "M_J_CS_N<0>")
	)
	(segment
		(start 103.373428 -22.740366)
		(end 103.041958 -22.408896)
		(width 0.14224)
		(layer "In2.Cu")
		(net "M_J_CS_N<0>")
	)
	(segment
		(start 104.106472 0.768096)
		(end 104.010968 0.8636)
		(width 0.14224)
		(layer "In2.Cu")
		(net "M_J_CS_N<0>")
	)
	(segment
		(start 98.041968 -50.952654)
		(end 98.284792 -50.70983)
		(width 0.0889)
		(layer "In2.Cu")
		(net "M_J_CS_N<0>")
	)
	(segment
		(start 104.089454 -2.571496)
		(end 104.089454 -1.632458)
		(width 0.14224)
		(layer "In2.Cu")
		(net "M_J_CS_N<0>")
	)
	(segment
		(start 97.572068 -53.904388)
		(end 97.565718 -53.89372)
		(width 0.0889)
		(layer "In2.Cu")
		(net "M_J_CS_N<0>")
	)
	(segment
		(start 97.441004 -52.188618)
		(end 98.041968 -51.587654)
		(width 0.0889)
		(layer "In2.Cu")
		(net "M_J_CS_N<0>")
	)
	(segment
		(start 103.398574 -10.858246)
		(end 103.398574 -9.769602)
		(width 0.14224)
		(layer "In2.Cu")
		(net "M_J_CS_N<0>")
	)
	(segment
		(start 103.295958 -19.268186)
		(end 103.208328 -19.180556)
		(width 0.14224)
		(layer "In2.Cu")
		(net "M_J_CS_N<0>")
	)
	(segment
		(start 104.089454 -1.632458)
		(end 104.244394 -1.477518)
		(width 0.14224)
		(layer "In2.Cu")
		(net "M_J_CS_N<0>")
	)
	(segment
		(start 104.060498 -4.72567)
		(end 104.060498 -3.847084)
		(width 0.14224)
		(layer "In2.Cu")
		(net "M_J_CS_N<0>")
	)
	(segment
		(start 97.576894 -52.922424)
		(end 97.572068 -52.913788)
		(width 0.0889)
		(layer "In2.Cu")
		(net "M_J_CS_N<0>")
	)
	(segment
		(start 97.576894 -55.894224)
		(end 97.572068 -55.885588)
		(width 0.0889)
		(layer "In2.Cu")
		(net "M_J_CS_N<0>")
	)
	(segment
		(start 98.284792 -50.70983)
		(end 98.284792 -48.956976)
		(width 0.0889)
		(layer "In2.Cu")
		(net "M_J_CS_N<0>")
	)
	(segment
		(start 103.213408 -9.584436)
		(end 103.213408 -8.162036)
		(width 0.14224)
		(layer "In2.Cu")
		(net "M_J_CS_N<0>")
	)
	(segment
		(start 103.041958 -17.159986)
		(end 103.208582 -16.993362)
		(width 0.14224)
		(layer "In2.Cu")
		(net "M_J_CS_N<0>")
	)
	(segment
		(start 104.010968 1.448308)
		(end 104.368092 1.805432)
		(width 0.14224)
		(layer "In2.Cu")
		(net "M_J_CS_N<0>")
	)
	(segment
		(start 97.572068 -55.885588)
		(end 97.565718 -55.87492)
		(width 0.0889)
		(layer "In2.Cu")
		(net "M_J_CS_N<0>")
	)
	(segment
		(start 103.041958 -23.437596)
		(end 103.373428 -23.106126)
		(width 0.14224)
		(layer "In2.Cu")
		(net "M_J_CS_N<0>")
	)
	(segment
		(start 101.343968 -28.354528)
		(end 101.343968 -26.149808)
		(width 0.14224)
		(layer "In2.Cu")
		(net "M_J_CS_N<0>")
	)
	(segment
		(start 97.576894 -56.884824)
		(end 97.572068 -56.876188)
		(width 0.0889)
		(layer "In2.Cu")
		(net "M_J_CS_N<0>")
	)
	(segment
		(start 104.368092 1.805432)
		(end 105.349294 1.805432)
		(width 0.14224)
		(layer "In2.Cu")
		(net "M_J_CS_N<0>")
	)
	(segment
		(start 97.576894 -53.913024)
		(end 97.572068 -53.904388)
		(width 0.0889)
		(layer "In2.Cu")
		(net "M_J_CS_N<0>")
	)
	(segment
		(start 104.592628 -0.664718)
		(end 104.309672 -0.664718)
		(width 0.14224)
		(layer "In2.Cu")
		(net "M_J_CS_N<0>")
	)
	(segment
		(start 103.041958 -7.558786)
		(end 103.208074 -7.39267)
		(width 0.14224)
		(layer "In2.Cu")
		(net "M_J_CS_N<0>")
	)
	(segment
		(start 103.211376 -12.193778)
		(end 103.211376 -11.045444)
		(width 0.14224)
		(layer "In2.Cu")
		(net "M_J_CS_N<0>")
	)
	(segment
		(start 103.295958 -21.710396)
		(end 103.295958 -19.268186)
		(width 0.14224)
		(layer "In2.Cu")
		(net "M_J_CS_N<0>")
	)
	(segment
		(start 103.208328 -17.758156)
		(end 103.041958 -17.591786)
		(width 0.14224)
		(layer "In2.Cu")
		(net "M_J_CS_N<0>")
	)
	(segment
		(start 103.041958 -7.990586)
		(end 103.041958 -7.558786)
		(width 0.14224)
		(layer "In2.Cu")
		(net "M_J_CS_N<0>")
	)
	(segment
		(start 103.398574 -9.769602)
		(end 103.213408 -9.584436)
		(width 0.14224)
		(layer "In2.Cu")
		(net "M_J_CS_N<0>")
	)
	(segment
		(start 103.208582 -16.993362)
		(end 103.208582 -13.669772)
		(width 0.14224)
		(layer "In2.Cu")
		(net "M_J_CS_N<0>")
	)
	(segment
		(start 104.792272 -0.864362)
		(end 104.592628 -0.664718)
		(width 0.14224)
		(layer "In2.Cu")
		(net "M_J_CS_N<0>")
	)
	(segment
		(start 97.572068 -56.876188)
		(end 97.565718 -56.86552)
		(width 0.0889)
		(layer "In2.Cu")
		(net "M_J_CS_N<0>")
	)
	(segment
		(start 104.792272 -1.270762)
		(end 104.792272 -0.864362)
		(width 0.14224)
		(layer "In2.Cu")
		(net "M_J_CS_N<0>")
	)
	(segment
		(start 103.041958 -21.964396)
		(end 103.295958 -21.710396)
		(width 0.14224)
		(layer "In2.Cu")
		(net "M_J_CS_N<0>")
	)
	(segment
		(start 98.712528 -48.281336)
		(end 98.712528 -30.985968)
		(width 0.14224)
		(layer "In2.Cu")
		(net "M_J_CS_N<0>")
	)
	(segment
		(start 103.041958 -17.591786)
		(end 103.041958 -17.159986)
		(width 0.14224)
		(layer "In2.Cu")
		(net "M_J_CS_N<0>")
	)
	(segment
		(start 103.213408 -8.162036)
		(end 103.041958 -7.990586)
		(width 0.14224)
		(layer "In2.Cu")
		(net "M_J_CS_N<0>")
	)
	(segment
		(start 104.309672 -0.664718)
		(end 104.106472 -0.461518)
		(width 0.14224)
		(layer "In2.Cu")
		(net "M_J_CS_N<0>")
	)
	(segment
		(start 104.334818 -2.81686)
		(end 104.089454 -2.571496)
		(width 0.14224)
		(layer "In2.Cu")
		(net "M_J_CS_N<0>")
	)
	(segment
		(start 101.343968 -26.149808)
		(end 103.041958 -24.451818)
		(width 0.14224)
		(layer "In2.Cu")
		(net "M_J_CS_N<0>")
	)
	(segment
		(start 104.060498 -3.847084)
		(end 104.334818 -3.572764)
		(width 0.14224)
		(layer "In2.Cu")
		(net "M_J_CS_N<0>")
	)
	(segment
		(start 103.211376 -11.045444)
		(end 103.398574 -10.858246)
		(width 0.14224)
		(layer "In2.Cu")
		(net "M_J_CS_N<0>")
	)
	(segment
		(start 103.208074 -5.578094)
		(end 104.060498 -4.72567)
		(width 0.14224)
		(layer "In2.Cu")
		(net "M_J_CS_N<0>")
	)
	(segment
		(start 97.572068 -54.894988)
		(end 97.565718 -54.88432)
		(width 0.0889)
		(layer "In2.Cu")
		(net "M_J_CS_N<0>")
	)
	(segment
		(start 97.225358 -58.06694)
		(end 97.218246 -58.04916)
		(width 0.0889)
		(layer "In2.Cu")
		(net "M_J_CS_N<0>")
	)
	(segment
		(start 103.208582 -13.669772)
		(end 103.041958 -13.503148)
		(width 0.14224)
		(layer "In2.Cu")
		(net "M_J_CS_N<0>")
	)
	(segment
		(start 103.208328 -19.180556)
		(end 103.208328 -17.758156)
		(width 0.14224)
		(layer "In2.Cu")
		(net "M_J_CS_N<0>")
	)
	(segment
		(start 103.041958 -12.363196)
		(end 103.211376 -12.193778)
		(width 0.14224)
		(layer "In2.Cu")
		(net "M_J_CS_N<0>")
	)
	(segment
		(start 98.712528 -48.52924)
		(end 98.712528 -48.281336)
		(width 0.0889)
		(layer "In2.Cu")
		(net "M_J_CS_N<0>")
	)
	(segment
		(start 104.106472 -0.461518)
		(end 104.106472 0.768096)
		(width 0.14224)
		(layer "In2.Cu")
		(net "M_J_CS_N<0>")
	)
	(segment
		(start 98.284792 -48.956976)
		(end 98.712528 -48.52924)
		(width 0.0889)
		(layer "In2.Cu")
		(net "M_J_CS_N<0>")
	)
	(segment
		(start 103.041958 -24.451818)
		(end 103.041958 -23.437596)
		(width 0.14224)
		(layer "In2.Cu")
		(net "M_J_CS_N<0>")
	)
	(segment
		(start 98.712528 -30.985968)
		(end 101.343968 -28.354528)
		(width 0.14224)
		(layer "In2.Cu")
		(net "M_J_CS_N<0>")
	)
	(segment
		(start 97.441004 -52.704492)
		(end 97.441004 -52.188618)
		(width 0.0889)
		(layer "In2.Cu")
		(net "M_J_CS_N<0>")
	)
	(segment
		(start 103.208074 -7.39267)
		(end 103.208074 -5.578094)
		(width 0.14224)
		(layer "In2.Cu")
		(net "M_J_CS_N<0>")
	)
	(segment
		(start 97.49663 -57.406286)
		(end 97.572068 -57.276238)
		(width 0.0889)
		(layer "In2.Cu")
		(net "M_J_CS_N<0>")
	)
	(segment
		(start 98.041968 -51.587654)
		(end 98.041968 -50.952654)
		(width 0.0889)
		(layer "In2.Cu")
		(net "M_J_CS_N<0>")
	)
	(segment
		(start 103.041958 -22.408896)
		(end 103.041958 -21.964396)
		(width 0.14224)
		(layer "In2.Cu")
		(net "M_J_CS_N<0>")
	)
	(segment
		(start 97.576894 -54.903624)
		(end 97.572068 -54.894988)
		(width 0.0889)
		(layer "In2.Cu")
		(net "M_J_CS_N<0>")
	)
	(arc
		(start 97.565718 -53.89372)
		(mid 97.49292 -53.602957)
		(end 97.572068 -53.313838)
		(width 0.0889)
		(layer "In2.Cu")
		(net "M_J_CS_N<0>")
	)
	(arc
		(start 97.565718 -55.87492)
		(mid 97.49292 -55.584157)
		(end 97.572068 -55.295038)
		(width 0.0889)
		(layer "In2.Cu")
		(net "M_J_CS_N<0>")
	)
	(arc
		(start 97.565718 -54.88432)
		(mid 97.49292 -54.593557)
		(end 97.572068 -54.304438)
		(width 0.0889)
		(layer "In2.Cu")
		(net "M_J_CS_N<0>")
	)
	(arc
		(start 97.565718 -56.86552)
		(mid 97.49292 -56.574757)
		(end 97.572068 -56.285638)
		(width 0.0889)
		(layer "In2.Cu")
		(net "M_J_CS_N<0>")
	)
	(arc
		(start 97.572068 -53.313838)
		(mid 97.625538 -53.118775)
		(end 97.576894 -52.922424)
		(width 0.0889)
		(layer "In2.Cu")
		(net "M_J_CS_N<0>")
	)
	(arc
		(start 97.572068 -56.285638)
		(mid 97.625538 -56.090575)
		(end 97.576894 -55.894224)
		(width 0.0889)
		(layer "In2.Cu")
		(net "M_J_CS_N<0>")
	)
	(arc
		(start 97.572068 -54.304438)
		(mid 97.625538 -54.109375)
		(end 97.576894 -53.913024)
		(width 0.0889)
		(layer "In2.Cu")
		(net "M_J_CS_N<0>")
	)
	(arc
		(start 97.572068 -57.276238)
		(mid 97.625538 -57.081175)
		(end 97.576894 -56.884824)
		(width 0.0889)
		(layer "In2.Cu")
		(net "M_J_CS_N<0>")
	)
	(arc
		(start 97.572068 -55.295038)
		(mid 97.625538 -55.099975)
		(end 97.576894 -54.903624)
		(width 0.0889)
		(layer "In2.Cu")
		(net "M_J_CS_N<0>")
	)
	(segment
		(start 92.645738 -58.06694)
		(end 92.074238 -58.06694)
		(width 0.1016)
		(layer "F.Cu")
		(net "M_J_CLK_DP<3>")
	)
	(via
		(at 92.074238 -58.06694)
		(size 0.508)
		(drill 0.254)
		(layers "F.Cu" "B.Cu")
		(net "M_J_CLK_DP<3>")
	)
	(via
		(at 91.749372 -2.314956)
		(size 0.508)
		(drill 0.254)
		(layers "F.Cu" "B.Cu")
		(net "M_J_CLK_DP<3>")
	)
	(segment
		(start 91.749372 -1.021842)
		(end 91.749372 -2.314956)
		(width 0.1651)
		(layer "B.Cu")
		(net "M_J_CLK_DP<3>")
	)
	(segment
		(start 93.69679 -6.44652)
		(end 92.388436 -6.44652)
		(width 0.14224)
		(layer "In2.Cu")
		(net "M_J_CLK_DP<3>")
	)
	(segment
		(start 93.324172 -49.861724)
		(end 93.324172 -49.839626)
		(width 0.0889)
		(layer "In2.Cu")
		(net "M_J_CLK_DP<3>")
	)
	(segment
		(start 91.778328 -21.343874)
		(end 91.778328 -18.20164)
		(width 0.14224)
		(layer "In2.Cu")
		(net "M_J_CLK_DP<3>")
	)
	(segment
		(start 94.059248 -6.808978)
		(end 93.69679 -6.44652)
		(width 0.14224)
		(layer "In2.Cu")
		(net "M_J_CLK_DP<3>")
	)
	(segment
		(start 94.059248 -11.00328)
		(end 94.059248 -6.808978)
		(width 0.14224)
		(layer "In2.Cu")
		(net "M_J_CLK_DP<3>")
	)
	(segment
		(start 92.420948 -54.304692)
		(end 92.526866 -54.122066)
		(width 0.0889)
		(layer "In2.Cu")
		(net "M_J_CLK_DP<3>")
	)
	(segment
		(start 93.363542 -49.901094)
		(end 93.324172 -49.861724)
		(width 0.0889)
		(layer "In2.Cu")
		(net "M_J_CLK_DP<3>")
	)
	(segment
		(start 91.413838 -3.831082)
		(end 92.020644 -3.224276)
		(width 0.14224)
		(layer "In2.Cu")
		(net "M_J_CLK_DP<3>")
	)
	(segment
		(start 92.526866 -52.105814)
		(end 92.331032 -51.76774)
		(width 0.0889)
		(layer "In2.Cu")
		(net "M_J_CLK_DP<3>")
	)
	(segment
		(start 94.724728 -11.66876)
		(end 94.059248 -11.00328)
		(width 0.14224)
		(layer "In2.Cu")
		(net "M_J_CLK_DP<3>")
	)
	(segment
		(start 94.059248 -13.54582)
		(end 94.724728 -12.88034)
		(width 0.14224)
		(layer "In2.Cu")
		(net "M_J_CLK_DP<3>")
	)
	(segment
		(start 93.324172 -26.17597)
		(end 91.35618 -24.207978)
		(width 0.14224)
		(layer "In2.Cu")
		(net "M_J_CLK_DP<3>")
	)
	(segment
		(start 93.324172 -49.839626)
		(end 93.324172 -26.17597)
		(width 0.14224)
		(layer "In2.Cu")
		(net "M_J_CLK_DP<3>")
	)
	(segment
		(start 92.388436 -6.44652)
		(end 91.413838 -5.471922)
		(width 0.14224)
		(layer "In2.Cu")
		(net "M_J_CLK_DP<3>")
	)
	(segment
		(start 92.331032 -51.328066)
		(end 93.363542 -50.295556)
		(width 0.0889)
		(layer "In2.Cu")
		(net "M_J_CLK_DP<3>")
	)
	(segment
		(start 91.413838 -5.471922)
		(end 91.413838 -3.831082)
		(width 0.14224)
		(layer "In2.Cu")
		(net "M_J_CLK_DP<3>")
	)
	(segment
		(start 92.367354 -58.236104)
		(end 92.446094 -58.214768)
		(width 0.0889)
		(layer "In2.Cu")
		(net "M_J_CLK_DP<3>")
	)
	(segment
		(start 94.724728 -12.88034)
		(end 94.724728 -11.66876)
		(width 0.14224)
		(layer "In2.Cu")
		(net "M_J_CLK_DP<3>")
	)
	(segment
		(start 92.074238 -58.06694)
		(end 92.367354 -58.236104)
		(width 0.0889)
		(layer "In2.Cu")
		(net "M_J_CLK_DP<3>")
	)
	(segment
		(start 94.059248 -14.24432)
		(end 94.059248 -13.54582)
		(width 0.14224)
		(layer "In2.Cu")
		(net "M_J_CLK_DP<3>")
	)
	(segment
		(start 92.453968 -17.526)
		(end 92.453968 -15.8496)
		(width 0.14224)
		(layer "In2.Cu")
		(net "M_J_CLK_DP<3>")
	)
	(segment
		(start 91.35618 -24.207978)
		(end 91.35618 -21.766022)
		(width 0.14224)
		(layer "In2.Cu")
		(net "M_J_CLK_DP<3>")
	)
	(segment
		(start 92.453968 -15.8496)
		(end 94.059248 -14.24432)
		(width 0.14224)
		(layer "In2.Cu")
		(net "M_J_CLK_DP<3>")
	)
	(segment
		(start 92.526866 -54.122066)
		(end 92.526866 -52.105814)
		(width 0.0889)
		(layer "In2.Cu")
		(net "M_J_CLK_DP<3>")
	)
	(segment
		(start 92.331032 -51.76774)
		(end 92.331032 -51.328066)
		(width 0.0889)
		(layer "In2.Cu")
		(net "M_J_CLK_DP<3>")
	)
	(segment
		(start 93.363542 -50.295556)
		(end 93.363542 -49.901094)
		(width 0.0889)
		(layer "In2.Cu")
		(net "M_J_CLK_DP<3>")
	)
	(segment
		(start 92.020644 -2.586228)
		(end 91.749372 -2.314956)
		(width 0.14224)
		(layer "In2.Cu")
		(net "M_J_CLK_DP<3>")
	)
	(segment
		(start 91.35618 -21.766022)
		(end 91.778328 -21.343874)
		(width 0.14224)
		(layer "In2.Cu")
		(net "M_J_CLK_DP<3>")
	)
	(segment
		(start 91.778328 -18.20164)
		(end 92.453968 -17.526)
		(width 0.14224)
		(layer "In2.Cu")
		(net "M_J_CLK_DP<3>")
	)
	(segment
		(start 92.020644 -3.224276)
		(end 92.020644 -2.586228)
		(width 0.14224)
		(layer "In2.Cu")
		(net "M_J_CLK_DP<3>")
	)
	(arc
		(start 92.446094 -58.214768)
		(mid 92.467343 -58.141442)
		(end 92.474288 -58.065416)
		(width 0.0889)
		(layer "In2.Cu")
		(net "M_J_CLK_DP<3>")
	)
	(arc
		(start 92.420948 -56.876696)
		(mid 92.341817 -56.581294)
		(end 92.420948 -56.285892)
		(width 0.0889)
		(layer "In2.Cu")
		(net "M_J_CLK_DP<3>")
	)
	(arc
		(start 92.420948 -57.276492)
		(mid 92.474447 -57.076594)
		(end 92.420948 -56.876696)
		(width 0.0889)
		(layer "In2.Cu")
		(net "M_J_CLK_DP<3>")
	)
	(arc
		(start 92.420948 -54.895496)
		(mid 92.341817 -54.600094)
		(end 92.420948 -54.304692)
		(width 0.0889)
		(layer "In2.Cu")
		(net "M_J_CLK_DP<3>")
	)
	(arc
		(start 92.420948 -57.867296)
		(mid 92.341817 -57.571894)
		(end 92.420948 -57.276492)
		(width 0.0889)
		(layer "In2.Cu")
		(net "M_J_CLK_DP<3>")
	)
	(arc
		(start 92.420948 -55.295292)
		(mid 92.474447 -55.095394)
		(end 92.420948 -54.895496)
		(width 0.0889)
		(layer "In2.Cu")
		(net "M_J_CLK_DP<3>")
	)
	(arc
		(start 92.420948 -55.886096)
		(mid 92.341817 -55.590694)
		(end 92.420948 -55.295292)
		(width 0.0889)
		(layer "In2.Cu")
		(net "M_J_CLK_DP<3>")
	)
	(arc
		(start 92.420948 -56.285892)
		(mid 92.474447 -56.085994)
		(end 92.420948 -55.886096)
		(width 0.0889)
		(layer "In2.Cu")
		(net "M_J_CLK_DP<3>")
	)
	(arc
		(start 92.474288 -58.065416)
		(mid 92.460529 -57.96288)
		(end 92.420948 -57.867296)
		(width 0.0889)
		(layer "In2.Cu")
		(net "M_J_CLK_DP<3>")
	)
	(segment
		(start 91.749372 -0.821182)
		(end 91.749372 0.471932)
		(width 0.1651)
		(layer "F.Cu")
		(net "M_J_CLK_DP<1>")
	)
	(segment
		(start 94.362778 -58.06694)
		(end 93.791278 -58.06694)
		(width 0.1016)
		(layer "F.Cu")
		(net "M_J_CLK_DP<1>")
	)
	(via
		(at 93.791278 -58.06694)
		(size 0.508)
		(drill 0.254)
		(layers "F.Cu" "B.Cu")
		(net "M_J_CLK_DP<1>")
	)
	(via
		(at 91.749372 0.471932)
		(size 0.508)
		(drill 0.254)
		(layers "F.Cu" "B.Cu")
		(net "M_J_CLK_DP<1>")
	)
	(segment
		(start 96.223328 -10.77976)
		(end 95.957644 -10.514076)
		(width 0.14224)
		(layer "In2.Cu")
		(net "M_J_CLK_DP<1>")
	)
	(segment
		(start 95.957644 -10.514076)
		(end 95.957644 -2.880614)
		(width 0.14224)
		(layer "In2.Cu")
		(net "M_J_CLK_DP<1>")
	)
	(segment
		(start 95.046292 -48.132238)
		(end 95.013272 -48.099218)
		(width 0.0889)
		(layer "In2.Cu")
		(net "M_J_CLK_DP<1>")
	)
	(segment
		(start 93.36659 -1.471422)
		(end 93.012006 -1.826006)
		(width 0.14224)
		(layer "In2.Cu")
		(net "M_J_CLK_DP<1>")
	)
	(segment
		(start 90.997786 -1.826006)
		(end 90.674444 -1.502664)
		(width 0.14224)
		(layer "In2.Cu")
		(net "M_J_CLK_DP<1>")
	)
	(segment
		(start 95.957644 -2.880614)
		(end 95.593916 -2.516886)
		(width 0.14224)
		(layer "In2.Cu")
		(net "M_J_CLK_DP<1>")
	)
	(segment
		(start 94.137988 -52.323492)
		(end 94.137988 -51.678586)
		(width 0.0889)
		(layer "In2.Cu")
		(net "M_J_CLK_DP<1>")
	)
	(segment
		(start 95.593916 -2.516886)
		(end 95.221044 -2.516886)
		(width 0.14224)
		(layer "In2.Cu")
		(net "M_J_CLK_DP<1>")
	)
	(segment
		(start 94.881192 -50.935382)
		(end 94.881192 -48.661574)
		(width 0.0889)
		(layer "In2.Cu")
		(net "M_J_CLK_DP<1>")
	)
	(segment
		(start 93.36659 -0.42291)
		(end 93.36659 -1.471422)
		(width 0.14224)
		(layer "In2.Cu")
		(net "M_J_CLK_DP<1>")
	)
	(segment
		(start 95.957644 -25.954482)
		(end 95.957644 -14.022324)
		(width 0.14224)
		(layer "In2.Cu")
		(net "M_J_CLK_DP<1>")
	)
	(segment
		(start 95.957644 -14.022324)
		(end 96.223328 -13.75664)
		(width 0.14224)
		(layer "In2.Cu")
		(net "M_J_CLK_DP<1>")
	)
	(segment
		(start 95.046292 -48.496474)
		(end 95.046292 -48.132238)
		(width 0.0889)
		(layer "In2.Cu")
		(net "M_J_CLK_DP<1>")
	)
	(segment
		(start 91.84386 -0.489458)
		(end 92.020644 -0.312674)
		(width 0.14224)
		(layer "In2.Cu")
		(net "M_J_CLK_DP<1>")
	)
	(segment
		(start 95.013272 -26.898854)
		(end 95.957644 -25.954482)
		(width 0.14224)
		(layer "In2.Cu")
		(net "M_J_CLK_DP<1>")
	)
	(segment
		(start 95.013272 -48.099218)
		(end 95.013272 -26.898854)
		(width 0.14224)
		(layer "In2.Cu")
		(net "M_J_CLK_DP<1>")
	)
	(segment
		(start 96.223328 -13.75664)
		(end 96.223328 -10.77976)
		(width 0.14224)
		(layer "In2.Cu")
		(net "M_J_CLK_DP<1>")
	)
	(segment
		(start 93.012006 -1.826006)
		(end 90.997786 -1.826006)
		(width 0.14224)
		(layer "In2.Cu")
		(net "M_J_CLK_DP<1>")
	)
	(segment
		(start 90.674444 -1.502664)
		(end 90.674444 -0.796798)
		(width 0.14224)
		(layer "In2.Cu")
		(net "M_J_CLK_DP<1>")
	)
	(segment
		(start 93.791278 -58.06694)
		(end 94.084394 -58.236104)
		(width 0.0889)
		(layer "In2.Cu")
		(net "M_J_CLK_DP<1>")
	)
	(segment
		(start 92.020644 -0.312674)
		(end 92.020644 0.20066)
		(width 0.14224)
		(layer "In2.Cu")
		(net "M_J_CLK_DP<1>")
	)
	(segment
		(start 93.522292 -0.267208)
		(end 93.36659 -0.42291)
		(width 0.14224)
		(layer "In2.Cu")
		(net "M_J_CLK_DP<1>")
	)
	(segment
		(start 94.881192 -48.661574)
		(end 95.046292 -48.496474)
		(width 0.0889)
		(layer "In2.Cu")
		(net "M_J_CLK_DP<1>")
	)
	(segment
		(start 94.084394 -58.236104)
		(end 94.163134 -58.214768)
		(width 0.0889)
		(layer "In2.Cu")
		(net "M_J_CLK_DP<1>")
	)
	(segment
		(start 90.981784 -0.489458)
		(end 91.84386 -0.489458)
		(width 0.14224)
		(layer "In2.Cu")
		(net "M_J_CLK_DP<1>")
	)
	(segment
		(start 95.221044 -2.516886)
		(end 94.044516 -1.340358)
		(width 0.14224)
		(layer "In2.Cu")
		(net "M_J_CLK_DP<1>")
	)
	(segment
		(start 94.137988 -51.678586)
		(end 94.881192 -50.935382)
		(width 0.0889)
		(layer "In2.Cu")
		(net "M_J_CLK_DP<1>")
	)
	(segment
		(start 90.674444 -0.796798)
		(end 90.981784 -0.489458)
		(width 0.14224)
		(layer "In2.Cu")
		(net "M_J_CLK_DP<1>")
	)
	(segment
		(start 94.044516 -1.340358)
		(end 94.044516 -0.422656)
		(width 0.14224)
		(layer "In2.Cu")
		(net "M_J_CLK_DP<1>")
	)
	(segment
		(start 94.044516 -0.422656)
		(end 93.889068 -0.267208)
		(width 0.14224)
		(layer "In2.Cu")
		(net "M_J_CLK_DP<1>")
	)
	(segment
		(start 92.020644 0.20066)
		(end 91.749372 0.471932)
		(width 0.14224)
		(layer "In2.Cu")
		(net "M_J_CLK_DP<1>")
	)
	(segment
		(start 93.889068 -0.267208)
		(end 93.522292 -0.267208)
		(width 0.14224)
		(layer "In2.Cu")
		(net "M_J_CLK_DP<1>")
	)
	(arc
		(start 94.137988 -54.895496)
		(mid 94.058857 -54.600094)
		(end 94.137988 -54.304692)
		(width 0.0889)
		(layer "In2.Cu")
		(net "M_J_CLK_DP<1>")
	)
	(arc
		(start 94.137988 -55.886096)
		(mid 94.058857 -55.590694)
		(end 94.137988 -55.295292)
		(width 0.0889)
		(layer "In2.Cu")
		(net "M_J_CLK_DP<1>")
	)
	(arc
		(start 94.137988 -54.304692)
		(mid 94.191487 -54.104794)
		(end 94.137988 -53.904896)
		(width 0.0889)
		(layer "In2.Cu")
		(net "M_J_CLK_DP<1>")
	)
	(arc
		(start 94.137988 -56.285892)
		(mid 94.191487 -56.085994)
		(end 94.137988 -55.886096)
		(width 0.0889)
		(layer "In2.Cu")
		(net "M_J_CLK_DP<1>")
	)
	(arc
		(start 94.137988 -52.914296)
		(mid 94.058857 -52.618894)
		(end 94.137988 -52.323492)
		(width 0.0889)
		(layer "In2.Cu")
		(net "M_J_CLK_DP<1>")
	)
	(arc
		(start 94.137988 -53.904896)
		(mid 94.058857 -53.609494)
		(end 94.137988 -53.314092)
		(width 0.0889)
		(layer "In2.Cu")
		(net "M_J_CLK_DP<1>")
	)
	(arc
		(start 94.137988 -53.314092)
		(mid 94.191487 -53.114194)
		(end 94.137988 -52.914296)
		(width 0.0889)
		(layer "In2.Cu")
		(net "M_J_CLK_DP<1>")
	)
	(arc
		(start 94.191328 -58.065416)
		(mid 94.177569 -57.96288)
		(end 94.137988 -57.867296)
		(width 0.0889)
		(layer "In2.Cu")
		(net "M_J_CLK_DP<1>")
	)
	(arc
		(start 94.163134 -58.214768)
		(mid 94.184383 -58.141442)
		(end 94.191328 -58.065416)
		(width 0.0889)
		(layer "In2.Cu")
		(net "M_J_CLK_DP<1>")
	)
	(arc
		(start 94.137988 -57.867296)
		(mid 94.058857 -57.571894)
		(end 94.137988 -57.276492)
		(width 0.0889)
		(layer "In2.Cu")
		(net "M_J_CLK_DP<1>")
	)
	(arc
		(start 94.137988 -57.276492)
		(mid 94.191487 -57.076594)
		(end 94.137988 -56.876696)
		(width 0.0889)
		(layer "In2.Cu")
		(net "M_J_CLK_DP<1>")
	)
	(arc
		(start 94.137988 -56.876696)
		(mid 94.058857 -56.581294)
		(end 94.137988 -56.285892)
		(width 0.0889)
		(layer "In2.Cu")
		(net "M_J_CLK_DP<1>")
	)
	(arc
		(start 94.137988 -55.295292)
		(mid 94.191487 -55.095394)
		(end 94.137988 -54.895496)
		(width 0.0889)
		(layer "In2.Cu")
		(net "M_J_CLK_DP<1>")
	)
	(segment
		(start 92.645738 -60.047886)
		(end 92.074238 -60.047886)
		(width 0.1016)
		(layer "F.Cu")
		(net "M_J_CLK_DP<2>")
	)
	(via
		(at 92.074238 -60.047886)
		(size 0.508)
		(drill 0.254)
		(layers "F.Cu" "B.Cu")
		(net "M_J_CLK_DP<2>")
	)
	(via
		(at 92.116148 -4.321556)
		(size 0.508)
		(drill 0.254)
		(layers "F.Cu" "B.Cu")
		(net "M_J_CLK_DP<2>")
	)
	(segment
		(start 91.897708 -4.539996)
		(end 92.116148 -4.321556)
		(width 0.1651)
		(layer "B.Cu")
		(net "M_J_CLK_DP<2>")
	)
	(segment
		(start 91.749372 -4.898136)
		(end 91.897708 -4.539996)
		(width 0.1651)
		(layer "B.Cu")
		(net "M_J_CLK_DP<2>")
	)
	(segment
		(start 91.749372 -5.621782)
		(end 91.749372 -4.898136)
		(width 0.1651)
		(layer "B.Cu")
		(net "M_J_CLK_DP<2>")
	)
	(segment
		(start 95.512128 -13.18514)
		(end 95.512128 -11.10996)
		(width 0.14224)
		(layer "In2.Cu")
		(net "M_J_CLK_DP<2>")
	)
	(segment
		(start 94.201742 -47.977298)
		(end 94.162372 -47.937928)
		(width 0.0889)
		(layer "In2.Cu")
		(net "M_J_CLK_DP<2>")
	)
	(segment
		(start 94.162372 -21.492718)
		(end 94.007432 -21.337778)
		(width 0.14224)
		(layer "In2.Cu")
		(net "M_J_CLK_DP<2>")
	)
	(segment
		(start 92.61094 -5.30352)
		(end 92.27693 -4.96951)
		(width 0.14224)
		(layer "In2.Cu")
		(net "M_J_CLK_DP<2>")
	)
	(segment
		(start 93.22308 -20.136358)
		(end 94.007432 -20.136358)
		(width 0.14224)
		(layer "In2.Cu")
		(net "M_J_CLK_DP<2>")
	)
	(segment
		(start 94.162372 -19.981418)
		(end 94.162372 -15.690596)
		(width 0.14224)
		(layer "In2.Cu")
		(net "M_J_CLK_DP<2>")
	)
	(segment
		(start 92.903294 -20.456144)
		(end 93.22308 -20.136358)
		(width 0.14224)
		(layer "In2.Cu")
		(net "M_J_CLK_DP<2>")
	)
	(segment
		(start 94.162372 -47.937928)
		(end 94.162372 -47.926752)
		(width 0.0889)
		(layer "In2.Cu")
		(net "M_J_CLK_DP<2>")
	)
	(segment
		(start 94.007432 -21.337778)
		(end 93.208348 -21.337778)
		(width 0.14224)
		(layer "In2.Cu")
		(net "M_J_CLK_DP<2>")
	)
	(segment
		(start 94.948248 -10.54608)
		(end 94.948248 -6.181344)
		(width 0.14224)
		(layer "In2.Cu")
		(net "M_J_CLK_DP<2>")
	)
	(segment
		(start 92.911168 -58.962544)
		(end 92.943934 -58.962544)
		(width 0.0889)
		(layer "In2.Cu")
		(net "M_J_CLK_DP<2>")
	)
	(segment
		(start 93.355668 -52.031392)
		(end 93.355668 -51.533044)
		(width 0.0889)
		(layer "In2.Cu")
		(net "M_J_CLK_DP<2>")
	)
	(segment
		(start 92.903294 -21.032724)
		(end 92.903294 -20.456144)
		(width 0.14224)
		(layer "In2.Cu")
		(net "M_J_CLK_DP<2>")
	)
	(segment
		(start 92.27693 -4.482338)
		(end 92.116148 -4.321556)
		(width 0.14224)
		(layer "In2.Cu")
		(net "M_J_CLK_DP<2>")
	)
	(segment
		(start 92.27693 -4.96951)
		(end 92.27693 -4.482338)
		(width 0.14224)
		(layer "In2.Cu")
		(net "M_J_CLK_DP<2>")
	)
	(segment
		(start 94.007432 -20.136358)
		(end 94.162372 -19.981418)
		(width 0.14224)
		(layer "In2.Cu")
		(net "M_J_CLK_DP<2>")
	)
	(segment
		(start 94.948248 -13.74902)
		(end 95.512128 -13.18514)
		(width 0.14224)
		(layer "In2.Cu")
		(net "M_J_CLK_DP<2>")
	)
	(segment
		(start 93.20022 -52.18684)
		(end 93.355668 -52.031392)
		(width 0.0889)
		(layer "In2.Cu")
		(net "M_J_CLK_DP<2>")
	)
	(segment
		(start 94.162372 -47.926752)
		(end 94.162372 -21.492718)
		(width 0.14224)
		(layer "In2.Cu")
		(net "M_J_CLK_DP<2>")
	)
	(segment
		(start 94.070424 -5.30352)
		(end 92.61094 -5.30352)
		(width 0.14224)
		(layer "In2.Cu")
		(net "M_J_CLK_DP<2>")
	)
	(segment
		(start 92.074238 -60.047886)
		(end 92.18803 -59.93384)
		(width 0.0889)
		(layer "In2.Cu")
		(net "M_J_CLK_DP<2>")
	)
	(segment
		(start 94.162372 -15.690596)
		(end 94.948248 -14.90472)
		(width 0.14224)
		(layer "In2.Cu")
		(net "M_J_CLK_DP<2>")
	)
	(segment
		(start 94.948248 -14.90472)
		(end 94.948248 -13.74902)
		(width 0.14224)
		(layer "In2.Cu")
		(net "M_J_CLK_DP<2>")
	)
	(segment
		(start 93.208348 -21.337778)
		(end 92.903294 -21.032724)
		(width 0.14224)
		(layer "In2.Cu")
		(net "M_J_CLK_DP<2>")
	)
	(segment
		(start 95.512128 -11.10996)
		(end 94.948248 -10.54608)
		(width 0.14224)
		(layer "In2.Cu")
		(net "M_J_CLK_DP<2>")
	)
	(segment
		(start 93.20022 -54.097682)
		(end 93.20022 -52.18684)
		(width 0.0889)
		(layer "In2.Cu")
		(net "M_J_CLK_DP<2>")
	)
	(segment
		(start 94.201742 -50.68697)
		(end 94.201742 -47.977298)
		(width 0.0889)
		(layer "In2.Cu")
		(net "M_J_CLK_DP<2>")
	)
	(segment
		(start 94.948248 -6.181344)
		(end 94.070424 -5.30352)
		(width 0.14224)
		(layer "In2.Cu")
		(net "M_J_CLK_DP<2>")
	)
	(segment
		(start 93.355668 -51.533044)
		(end 94.201742 -50.68697)
		(width 0.0889)
		(layer "In2.Cu")
		(net "M_J_CLK_DP<2>")
	)
	(arc
		(start 93.279468 -55.390796)
		(mid 93.200337 -55.095394)
		(end 93.279468 -54.799992)
		(width 0.0889)
		(layer "In2.Cu")
		(net "M_J_CLK_DP<2>")
	)
	(arc
		(start 93.279468 -54.799992)
		(mid 93.332967 -54.600094)
		(end 93.279468 -54.400196)
		(width 0.0889)
		(layer "In2.Cu")
		(net "M_J_CLK_DP<2>")
	)
	(arc
		(start 93.279468 -55.790592)
		(mid 93.332967 -55.590694)
		(end 93.279468 -55.390796)
		(width 0.0889)
		(layer "In2.Cu")
		(net "M_J_CLK_DP<2>")
	)
	(arc
		(start 93.279468 -54.400196)
		(mid 93.21949 -54.254273)
		(end 93.20022 -54.097682)
		(width 0.0889)
		(layer "In2.Cu")
		(net "M_J_CLK_DP<2>")
	)
	(arc
		(start 92.943934 -58.962544)
		(mid 93.282049 -58.757842)
		(end 93.279468 -58.362596)
		(width 0.0889)
		(layer "In2.Cu")
		(net "M_J_CLK_DP<2>")
	)
	(arc
		(start 93.279468 -56.781192)
		(mid 93.332967 -56.581294)
		(end 93.279468 -56.381396)
		(width 0.0889)
		(layer "In2.Cu")
		(net "M_J_CLK_DP<2>")
	)
	(arc
		(start 93.279468 -58.362596)
		(mid 93.200337 -58.067194)
		(end 93.279468 -57.771792)
		(width 0.0889)
		(layer "In2.Cu")
		(net "M_J_CLK_DP<2>")
	)
	(arc
		(start 92.18803 -59.93384)
		(mid 92.301721 -59.763829)
		(end 92.3417 -59.563254)
		(width 0.0889)
		(layer "In2.Cu")
		(net "M_J_CLK_DP<2>")
	)
	(arc
		(start 93.279468 -57.371996)
		(mid 93.200337 -57.076594)
		(end 93.279468 -56.781192)
		(width 0.0889)
		(layer "In2.Cu")
		(net "M_J_CLK_DP<2>")
	)
	(arc
		(start 93.279468 -57.771792)
		(mid 93.332967 -57.571894)
		(end 93.279468 -57.371996)
		(width 0.0889)
		(layer "In2.Cu")
		(net "M_J_CLK_DP<2>")
	)
	(arc
		(start 92.3417 -59.563254)
		(mid 92.503678 -59.14647)
		(end 92.911168 -58.962544)
		(width 0.0889)
		(layer "In2.Cu")
		(net "M_J_CLK_DP<2>")
	)
	(arc
		(start 93.279468 -56.381396)
		(mid 93.200337 -56.085994)
		(end 93.279468 -55.790592)
		(width 0.0889)
		(layer "In2.Cu")
		(net "M_J_CLK_DP<2>")
	)
	(segment
		(start 91.749372 3.778758)
		(end 91.749372 2.485644)
		(width 0.1651)
		(layer "F.Cu")
		(net "M_J_CLK_DP<0>")
	)
	(segment
		(start 94.362778 -60.047886)
		(end 93.791278 -60.047886)
		(width 0.1016)
		(layer "F.Cu")
		(net "M_J_CLK_DP<0>")
	)
	(via
		(at 93.791278 -60.047886)
		(size 0.508)
		(drill 0.254)
		(layers "F.Cu" "B.Cu")
		(net "M_J_CLK_DP<0>")
	)
	(via
		(at 91.749372 2.485644)
		(size 0.508)
		(drill 0.254)
		(layers "F.Cu" "B.Cu")
		(net "M_J_CLK_DP<0>")
	)
	(segment
		(start 92.020644 2.214372)
		(end 91.749372 2.485644)
		(width 0.14224)
		(layer "In2.Cu")
		(net "M_J_CLK_DP<0>")
	)
	(segment
		(start 97.213928 -20.08124)
		(end 97.213928 -11.69924)
		(width 0.14224)
		(layer "In2.Cu")
		(net "M_J_CLK_DP<0>")
	)
	(segment
		(start 94.003876 1.42367)
		(end 92.40647 1.42367)
		(width 0.14224)
		(layer "In2.Cu")
		(net "M_J_CLK_DP<0>")
	)
	(segment
		(start 94.816168 -0.508)
		(end 94.816168 0.611378)
		(width 0.14224)
		(layer "In2.Cu")
		(net "M_J_CLK_DP<0>")
	)
	(segment
		(start 97.533968 -11.3792)
		(end 97.533968 -10.27684)
		(width 0.14224)
		(layer "In2.Cu")
		(net "M_J_CLK_DP<0>")
	)
	(segment
		(start 95.451168 -1.143)
		(end 94.816168 -0.508)
		(width 0.14224)
		(layer "In2.Cu")
		(net "M_J_CLK_DP<0>")
	)
	(segment
		(start 94.628208 -58.962544)
		(end 94.660974 -58.962544)
		(width 0.0889)
		(layer "In2.Cu")
		(net "M_J_CLK_DP<0>")
	)
	(segment
		(start 95.489268 -48.891444)
		(end 95.890842 -48.48987)
		(width 0.0889)
		(layer "In2.Cu")
		(net "M_J_CLK_DP<0>")
	)
	(segment
		(start 94.816168 0.611378)
		(end 94.003876 1.42367)
		(width 0.14224)
		(layer "In2.Cu")
		(net "M_J_CLK_DP<0>")
	)
	(segment
		(start 95.851472 -48.104806)
		(end 95.851472 -48.082708)
		(width 0.0889)
		(layer "In2.Cu")
		(net "M_J_CLK_DP<0>")
	)
	(segment
		(start 94.996508 -52.418996)
		(end 94.906592 -52.269898)
		(width 0.0889)
		(layer "In2.Cu")
		(net "M_J_CLK_DP<0>")
	)
	(segment
		(start 95.851472 -48.082708)
		(end 95.851472 -27.509216)
		(width 0.14224)
		(layer "In2.Cu")
		(net "M_J_CLK_DP<0>")
	)
	(segment
		(start 92.40647 1.42367)
		(end 92.020644 1.809496)
		(width 0.14224)
		(layer "In2.Cu")
		(net "M_J_CLK_DP<0>")
	)
	(segment
		(start 95.489268 -51.254406)
		(end 95.489268 -48.891444)
		(width 0.0889)
		(layer "In2.Cu")
		(net "M_J_CLK_DP<0>")
	)
	(segment
		(start 94.906592 -52.269898)
		(end 94.906592 -51.837082)
		(width 0.0889)
		(layer "In2.Cu")
		(net "M_J_CLK_DP<0>")
	)
	(segment
		(start 95.851472 -27.509216)
		(end 96.904048 -26.45664)
		(width 0.14224)
		(layer "In2.Cu")
		(net "M_J_CLK_DP<0>")
	)
	(segment
		(start 92.020644 1.809496)
		(end 92.020644 2.214372)
		(width 0.14224)
		(layer "In2.Cu")
		(net "M_J_CLK_DP<0>")
	)
	(segment
		(start 95.890842 -48.144176)
		(end 95.851472 -48.104806)
		(width 0.0889)
		(layer "In2.Cu")
		(net "M_J_CLK_DP<0>")
	)
	(segment
		(start 95.890842 -48.48987)
		(end 95.890842 -48.144176)
		(width 0.0889)
		(layer "In2.Cu")
		(net "M_J_CLK_DP<0>")
	)
	(segment
		(start 96.904048 -26.45664)
		(end 96.904048 -20.39112)
		(width 0.14224)
		(layer "In2.Cu")
		(net "M_J_CLK_DP<0>")
	)
	(segment
		(start 97.533968 -10.27684)
		(end 97.229168 -9.97204)
		(width 0.14224)
		(layer "In2.Cu")
		(net "M_J_CLK_DP<0>")
	)
	(segment
		(start 96.904048 -20.39112)
		(end 97.213928 -20.08124)
		(width 0.14224)
		(layer "In2.Cu")
		(net "M_J_CLK_DP<0>")
	)
	(segment
		(start 97.229168 -1.915414)
		(end 96.456754 -1.143)
		(width 0.14224)
		(layer "In2.Cu")
		(net "M_J_CLK_DP<0>")
	)
	(segment
		(start 94.906592 -51.837082)
		(end 95.489268 -51.254406)
		(width 0.0889)
		(layer "In2.Cu")
		(net "M_J_CLK_DP<0>")
	)
	(segment
		(start 97.213928 -11.69924)
		(end 97.533968 -11.3792)
		(width 0.14224)
		(layer "In2.Cu")
		(net "M_J_CLK_DP<0>")
	)
	(segment
		(start 93.791278 -60.047886)
		(end 93.90507 -59.93384)
		(width 0.0889)
		(layer "In2.Cu")
		(net "M_J_CLK_DP<0>")
	)
	(segment
		(start 96.456754 -1.143)
		(end 95.451168 -1.143)
		(width 0.14224)
		(layer "In2.Cu")
		(net "M_J_CLK_DP<0>")
	)
	(segment
		(start 97.229168 -9.97204)
		(end 97.229168 -1.915414)
		(width 0.14224)
		(layer "In2.Cu")
		(net "M_J_CLK_DP<0>")
	)
	(arc
		(start 94.996508 -55.790592)
		(mid 95.050007 -55.590694)
		(end 94.996508 -55.390796)
		(width 0.0889)
		(layer "In2.Cu")
		(net "M_J_CLK_DP<0>")
	)
	(arc
		(start 94.05874 -59.563254)
		(mid 94.220718 -59.14647)
		(end 94.628208 -58.962544)
		(width 0.0889)
		(layer "In2.Cu")
		(net "M_J_CLK_DP<0>")
	)
	(arc
		(start 94.996508 -53.409596)
		(mid 94.917377 -53.114194)
		(end 94.996508 -52.818792)
		(width 0.0889)
		(layer "In2.Cu")
		(net "M_J_CLK_DP<0>")
	)
	(arc
		(start 94.996508 -52.818792)
		(mid 95.050007 -52.618894)
		(end 94.996508 -52.418996)
		(width 0.0889)
		(layer "In2.Cu")
		(net "M_J_CLK_DP<0>")
	)
	(arc
		(start 94.996508 -55.390796)
		(mid 94.917377 -55.095394)
		(end 94.996508 -54.799992)
		(width 0.0889)
		(layer "In2.Cu")
		(net "M_J_CLK_DP<0>")
	)
	(arc
		(start 94.660974 -58.962544)
		(mid 94.999089 -58.757842)
		(end 94.996508 -58.362596)
		(width 0.0889)
		(layer "In2.Cu")
		(net "M_J_CLK_DP<0>")
	)
	(arc
		(start 94.996508 -54.400196)
		(mid 94.917377 -54.104794)
		(end 94.996508 -53.809392)
		(width 0.0889)
		(layer "In2.Cu")
		(net "M_J_CLK_DP<0>")
	)
	(arc
		(start 94.996508 -57.371996)
		(mid 94.917377 -57.076594)
		(end 94.996508 -56.781192)
		(width 0.0889)
		(layer "In2.Cu")
		(net "M_J_CLK_DP<0>")
	)
	(arc
		(start 94.996508 -54.799992)
		(mid 95.050007 -54.600094)
		(end 94.996508 -54.400196)
		(width 0.0889)
		(layer "In2.Cu")
		(net "M_J_CLK_DP<0>")
	)
	(arc
		(start 94.996508 -57.771792)
		(mid 95.050007 -57.571894)
		(end 94.996508 -57.371996)
		(width 0.0889)
		(layer "In2.Cu")
		(net "M_J_CLK_DP<0>")
	)
	(arc
		(start 93.90507 -59.93384)
		(mid 94.018761 -59.763829)
		(end 94.05874 -59.563254)
		(width 0.0889)
		(layer "In2.Cu")
		(net "M_J_CLK_DP<0>")
	)
	(arc
		(start 94.996508 -56.781192)
		(mid 95.050007 -56.581294)
		(end 94.996508 -56.381396)
		(width 0.0889)
		(layer "In2.Cu")
		(net "M_J_CLK_DP<0>")
	)
	(arc
		(start 94.996508 -53.809392)
		(mid 95.050007 -53.609494)
		(end 94.996508 -53.409596)
		(width 0.0889)
		(layer "In2.Cu")
		(net "M_J_CLK_DP<0>")
	)
	(arc
		(start 94.996508 -56.381396)
		(mid 94.917377 -56.085994)
		(end 94.996508 -55.790592)
		(width 0.0889)
		(layer "In2.Cu")
		(net "M_J_CLK_DP<0>")
	)
	(arc
		(start 94.996508 -58.362596)
		(mid 94.917377 -58.067194)
		(end 94.996508 -57.771792)
		(width 0.0889)
		(layer "In2.Cu")
		(net "M_J_CLK_DP<0>")
	)
	(segment
		(start 93.504258 -58.561986)
		(end 92.932758 -58.561986)
		(width 0.1016)
		(layer "F.Cu")
		(net "M_J_CLK_DN<3>")
	)
	(via
		(at 92.59951 -2.314956)
		(size 0.508)
		(drill 0.254)
		(layers "F.Cu" "B.Cu")
		(net "M_J_CLK_DN<3>")
	)
	(via
		(at 92.932758 -58.561986)
		(size 0.508)
		(drill 0.254)
		(layers "F.Cu" "B.Cu")
		(net "M_J_CLK_DN<3>")
	)
	(segment
		(start 92.59951 -1.021842)
		(end 92.59951 -2.314956)
		(width 0.1651)
		(layer "B.Cu")
		(net "M_J_CLK_DN<3>")
	)
	(segment
		(start 92.932758 -58.561986)
		(end 92.827856 -58.457084)
		(width 0.0889)
		(layer "In2.Cu")
		(net "M_J_CLK_DN<3>")
	)
	(segment
		(start 92.289884 -2.624582)
		(end 92.59951 -2.314956)
		(width 0.14224)
		(layer "In2.Cu")
		(net "M_J_CLK_DN<3>")
	)
	(segment
		(start 92.500196 -6.17728)
		(end 91.683078 -5.360162)
		(width 0.14224)
		(layer "In2.Cu")
		(net "M_J_CLK_DN<3>")
	)
	(segment
		(start 92.047568 -18.3134)
		(end 92.723208 -17.63776)
		(width 0.14224)
		(layer "In2.Cu")
		(net "M_J_CLK_DN<3>")
	)
	(segment
		(start 92.289884 -3.336036)
		(end 92.289884 -2.624582)
		(width 0.14224)
		(layer "In2.Cu")
		(net "M_J_CLK_DN<3>")
	)
	(segment
		(start 91.683078 -3.942842)
		(end 92.289884 -3.336036)
		(width 0.14224)
		(layer "In2.Cu")
		(net "M_J_CLK_DN<3>")
	)
	(segment
		(start 94.328488 -13.65758)
		(end 94.993968 -12.9921)
		(width 0.14224)
		(layer "In2.Cu")
		(net "M_J_CLK_DN<3>")
	)
	(segment
		(start 94.328488 -14.35608)
		(end 94.328488 -13.65758)
		(width 0.14224)
		(layer "In2.Cu")
		(net "M_J_CLK_DN<3>")
	)
	(segment
		(start 93.554042 -49.901094)
		(end 93.593412 -49.861724)
		(width 0.0889)
		(layer "In2.Cu")
		(net "M_J_CLK_DN<3>")
	)
	(segment
		(start 92.047568 -21.455634)
		(end 92.047568 -18.3134)
		(width 0.14224)
		(layer "In2.Cu")
		(net "M_J_CLK_DN<3>")
	)
	(segment
		(start 93.593412 -26.06421)
		(end 91.62542 -24.096218)
		(width 0.14224)
		(layer "In2.Cu")
		(net "M_J_CLK_DN<3>")
	)
	(segment
		(start 93.593412 -49.861724)
		(end 93.593412 -49.839626)
		(width 0.0889)
		(layer "In2.Cu")
		(net "M_J_CLK_DN<3>")
	)
	(segment
		(start 92.717366 -54.173374)
		(end 92.717366 -52.054506)
		(width 0.0889)
		(layer "In2.Cu")
		(net "M_J_CLK_DN<3>")
	)
	(segment
		(start 92.723208 -15.96136)
		(end 94.328488 -14.35608)
		(width 0.14224)
		(layer "In2.Cu")
		(net "M_J_CLK_DN<3>")
	)
	(segment
		(start 92.723208 -17.63776)
		(end 92.723208 -15.96136)
		(width 0.14224)
		(layer "In2.Cu")
		(net "M_J_CLK_DN<3>")
	)
	(segment
		(start 94.993968 -12.9921)
		(end 94.993968 -11.557)
		(width 0.14224)
		(layer "In2.Cu")
		(net "M_J_CLK_DN<3>")
	)
	(segment
		(start 93.80855 -6.17728)
		(end 92.500196 -6.17728)
		(width 0.14224)
		(layer "In2.Cu")
		(net "M_J_CLK_DN<3>")
	)
	(segment
		(start 91.62542 -24.096218)
		(end 91.62542 -21.877782)
		(width 0.14224)
		(layer "In2.Cu")
		(net "M_J_CLK_DN<3>")
	)
	(segment
		(start 91.62542 -21.877782)
		(end 92.047568 -21.455634)
		(width 0.14224)
		(layer "In2.Cu")
		(net "M_J_CLK_DN<3>")
	)
	(segment
		(start 92.521532 -51.716432)
		(end 92.521532 -51.40706)
		(width 0.0889)
		(layer "In2.Cu")
		(net "M_J_CLK_DN<3>")
	)
	(segment
		(start 94.328488 -6.697218)
		(end 93.80855 -6.17728)
		(width 0.14224)
		(layer "In2.Cu")
		(net "M_J_CLK_DN<3>")
	)
	(segment
		(start 94.328488 -10.89152)
		(end 94.328488 -6.697218)
		(width 0.14224)
		(layer "In2.Cu")
		(net "M_J_CLK_DN<3>")
	)
	(segment
		(start 94.993968 -11.557)
		(end 94.328488 -10.89152)
		(width 0.14224)
		(layer "In2.Cu")
		(net "M_J_CLK_DN<3>")
	)
	(segment
		(start 92.586048 -54.400196)
		(end 92.717366 -54.173374)
		(width 0.0889)
		(layer "In2.Cu")
		(net "M_J_CLK_DN<3>")
	)
	(segment
		(start 92.717366 -52.054506)
		(end 92.521532 -51.716432)
		(width 0.0889)
		(layer "In2.Cu")
		(net "M_J_CLK_DN<3>")
	)
	(segment
		(start 91.683078 -5.360162)
		(end 91.683078 -3.942842)
		(width 0.14224)
		(layer "In2.Cu")
		(net "M_J_CLK_DN<3>")
	)
	(segment
		(start 93.554042 -50.37455)
		(end 93.554042 -49.901094)
		(width 0.0889)
		(layer "In2.Cu")
		(net "M_J_CLK_DN<3>")
	)
	(segment
		(start 93.593412 -49.839626)
		(end 93.593412 -26.06421)
		(width 0.14224)
		(layer "In2.Cu")
		(net "M_J_CLK_DN<3>")
	)
	(segment
		(start 92.521532 -51.40706)
		(end 93.554042 -50.37455)
		(width 0.0889)
		(layer "In2.Cu")
		(net "M_J_CLK_DN<3>")
	)
	(arc
		(start 92.586048 -56.381396)
		(mid 92.665179 -56.085994)
		(end 92.586048 -55.790592)
		(width 0.0889)
		(layer "In2.Cu")
		(net "M_J_CLK_DN<3>")
	)
	(arc
		(start 92.665296 -58.064654)
		(mid 92.644781 -57.913052)
		(end 92.586048 -57.771792)
		(width 0.0889)
		(layer "In2.Cu")
		(net "M_J_CLK_DN<3>")
	)
	(arc
		(start 92.586048 -57.771792)
		(mid 92.532549 -57.571894)
		(end 92.586048 -57.371996)
		(width 0.0889)
		(layer "In2.Cu")
		(net "M_J_CLK_DN<3>")
	)
	(arc
		(start 92.827856 -58.457084)
		(mid 92.707551 -58.277036)
		(end 92.665296 -58.064654)
		(width 0.0889)
		(layer "In2.Cu")
		(net "M_J_CLK_DN<3>")
	)
	(arc
		(start 92.586048 -55.390796)
		(mid 92.665179 -55.095394)
		(end 92.586048 -54.799992)
		(width 0.0889)
		(layer "In2.Cu")
		(net "M_J_CLK_DN<3>")
	)
	(arc
		(start 92.586048 -55.790592)
		(mid 92.532549 -55.590694)
		(end 92.586048 -55.390796)
		(width 0.0889)
		(layer "In2.Cu")
		(net "M_J_CLK_DN<3>")
	)
	(arc
		(start 92.586048 -57.371996)
		(mid 92.665179 -57.076594)
		(end 92.586048 -56.781192)
		(width 0.0889)
		(layer "In2.Cu")
		(net "M_J_CLK_DN<3>")
	)
	(arc
		(start 92.586048 -56.781192)
		(mid 92.532549 -56.581294)
		(end 92.586048 -56.381396)
		(width 0.0889)
		(layer "In2.Cu")
		(net "M_J_CLK_DN<3>")
	)
	(arc
		(start 92.586048 -54.799992)
		(mid 92.532549 -54.600094)
		(end 92.586048 -54.400196)
		(width 0.0889)
		(layer "In2.Cu")
		(net "M_J_CLK_DN<3>")
	)
	(segment
		(start 92.59951 -0.821182)
		(end 92.59951 0.471932)
		(width 0.1651)
		(layer "F.Cu")
		(net "M_J_CLK_DN<1>")
	)
	(segment
		(start 95.221298 -58.561986)
		(end 94.649798 -58.561986)
		(width 0.1016)
		(layer "F.Cu")
		(net "M_J_CLK_DN<1>")
	)
	(via
		(at 92.59951 0.471932)
		(size 0.508)
		(drill 0.254)
		(layers "F.Cu" "B.Cu")
		(net "M_J_CLK_DN<1>")
	)
	(via
		(at 94.649798 -58.561986)
		(size 0.508)
		(drill 0.254)
		(layers "F.Cu" "B.Cu")
		(net "M_J_CLK_DN<1>")
	)
	(segment
		(start 95.332804 -2.247646)
		(end 94.313756 -1.228598)
		(width 0.14224)
		(layer "In2.Cu")
		(net "M_J_CLK_DN<1>")
	)
	(segment
		(start 96.226884 -2.768854)
		(end 95.705676 -2.247646)
		(width 0.14224)
		(layer "In2.Cu")
		(net "M_J_CLK_DN<1>")
	)
	(segment
		(start 90.943684 -1.390904)
		(end 90.943684 -0.908558)
		(width 0.14224)
		(layer "In2.Cu")
		(net "M_J_CLK_DN<1>")
	)
	(segment
		(start 94.000828 0.002032)
		(end 93.410532 0.002032)
		(width 0.14224)
		(layer "In2.Cu")
		(net "M_J_CLK_DN<1>")
	)
	(segment
		(start 95.705676 -2.247646)
		(end 95.332804 -2.247646)
		(width 0.14224)
		(layer "In2.Cu")
		(net "M_J_CLK_DN<1>")
	)
	(segment
		(start 92.289884 -0.424434)
		(end 92.289884 0.162306)
		(width 0.14224)
		(layer "In2.Cu")
		(net "M_J_CLK_DN<1>")
	)
	(segment
		(start 96.226884 -26.066242)
		(end 96.226884 -14.134084)
		(width 0.14224)
		(layer "In2.Cu")
		(net "M_J_CLK_DN<1>")
	)
	(segment
		(start 94.303088 -52.818792)
		(end 94.303088 -52.819046)
		(width 0.0889)
		(layer "In2.Cu")
		(net "M_J_CLK_DN<1>")
	)
	(segment
		(start 92.289884 0.162306)
		(end 92.59951 0.471932)
		(width 0.14224)
		(layer "In2.Cu")
		(net "M_J_CLK_DN<1>")
	)
	(segment
		(start 96.492568 -10.668)
		(end 96.226884 -10.402316)
		(width 0.14224)
		(layer "In2.Cu")
		(net "M_J_CLK_DN<1>")
	)
	(segment
		(start 91.95562 -0.758698)
		(end 92.289884 -0.424434)
		(width 0.14224)
		(layer "In2.Cu")
		(net "M_J_CLK_DN<1>")
	)
	(segment
		(start 95.071692 -48.740568)
		(end 95.236792 -48.575468)
		(width 0.0889)
		(layer "In2.Cu")
		(net "M_J_CLK_DN<1>")
	)
	(segment
		(start 95.282512 -27.010614)
		(end 96.226884 -26.066242)
		(width 0.14224)
		(layer "In2.Cu")
		(net "M_J_CLK_DN<1>")
	)
	(segment
		(start 95.071692 -51.014376)
		(end 95.071692 -48.740568)
		(width 0.0889)
		(layer "In2.Cu")
		(net "M_J_CLK_DN<1>")
	)
	(segment
		(start 94.649798 -58.561986)
		(end 94.544896 -58.457084)
		(width 0.0889)
		(layer "In2.Cu")
		(net "M_J_CLK_DN<1>")
	)
	(segment
		(start 96.492568 -13.8684)
		(end 96.492568 -10.668)
		(width 0.14224)
		(layer "In2.Cu")
		(net "M_J_CLK_DN<1>")
	)
	(segment
		(start 93.410532 0.002032)
		(end 93.09735 -0.31115)
		(width 0.14224)
		(layer "In2.Cu")
		(net "M_J_CLK_DN<1>")
	)
	(segment
		(start 95.236792 -48.575468)
		(end 95.236792 -48.126904)
		(width 0.0889)
		(layer "In2.Cu")
		(net "M_J_CLK_DN<1>")
	)
	(segment
		(start 93.09735 -0.31115)
		(end 93.09735 -1.359662)
		(width 0.14224)
		(layer "In2.Cu")
		(net "M_J_CLK_DN<1>")
	)
	(segment
		(start 91.093544 -0.758698)
		(end 91.95562 -0.758698)
		(width 0.14224)
		(layer "In2.Cu")
		(net "M_J_CLK_DN<1>")
	)
	(segment
		(start 95.282512 -48.059086)
		(end 95.282512 -27.010614)
		(width 0.14224)
		(layer "In2.Cu")
		(net "M_J_CLK_DN<1>")
	)
	(segment
		(start 95.236792 -48.126904)
		(end 95.282512 -48.081184)
		(width 0.0889)
		(layer "In2.Cu")
		(net "M_J_CLK_DN<1>")
	)
	(segment
		(start 92.900246 -1.556766)
		(end 91.109546 -1.556766)
		(width 0.14224)
		(layer "In2.Cu")
		(net "M_J_CLK_DN<1>")
	)
	(segment
		(start 94.328488 -52.374546)
		(end 94.328488 -51.75758)
		(width 0.0889)
		(layer "In2.Cu")
		(net "M_J_CLK_DN<1>")
	)
	(segment
		(start 95.282512 -48.081184)
		(end 95.282512 -48.059086)
		(width 0.0889)
		(layer "In2.Cu")
		(net "M_J_CLK_DN<1>")
	)
	(segment
		(start 96.226884 -10.402316)
		(end 96.226884 -2.768854)
		(width 0.14224)
		(layer "In2.Cu")
		(net "M_J_CLK_DN<1>")
	)
	(segment
		(start 96.226884 -14.134084)
		(end 96.492568 -13.8684)
		(width 0.14224)
		(layer "In2.Cu")
		(net "M_J_CLK_DN<1>")
	)
	(segment
		(start 94.303088 -52.418742)
		(end 94.328488 -52.374546)
		(width 0.0889)
		(layer "In2.Cu")
		(net "M_J_CLK_DN<1>")
	)
	(segment
		(start 94.313756 -1.228598)
		(end 94.313756 -0.310896)
		(width 0.14224)
		(layer "In2.Cu")
		(net "M_J_CLK_DN<1>")
	)
	(segment
		(start 94.313756 -0.310896)
		(end 94.000828 0.002032)
		(width 0.14224)
		(layer "In2.Cu")
		(net "M_J_CLK_DN<1>")
	)
	(segment
		(start 93.09735 -1.359662)
		(end 92.900246 -1.556766)
		(width 0.14224)
		(layer "In2.Cu")
		(net "M_J_CLK_DN<1>")
	)
	(segment
		(start 90.943684 -0.908558)
		(end 91.093544 -0.758698)
		(width 0.14224)
		(layer "In2.Cu")
		(net "M_J_CLK_DN<1>")
	)
	(segment
		(start 91.109546 -1.556766)
		(end 90.943684 -1.390904)
		(width 0.14224)
		(layer "In2.Cu")
		(net "M_J_CLK_DN<1>")
	)
	(segment
		(start 94.328488 -51.75758)
		(end 95.071692 -51.014376)
		(width 0.0889)
		(layer "In2.Cu")
		(net "M_J_CLK_DN<1>")
	)
	(arc
		(start 94.303088 -53.809392)
		(mid 94.249589 -53.609494)
		(end 94.303088 -53.409596)
		(width 0.0889)
		(layer "In2.Cu")
		(net "M_J_CLK_DN<1>")
	)
	(arc
		(start 94.303088 -57.371996)
		(mid 94.382219 -57.076594)
		(end 94.303088 -56.781192)
		(width 0.0889)
		(layer "In2.Cu")
		(net "M_J_CLK_DN<1>")
	)
	(arc
		(start 94.303088 -54.799992)
		(mid 94.249589 -54.600094)
		(end 94.303088 -54.400196)
		(width 0.0889)
		(layer "In2.Cu")
		(net "M_J_CLK_DN<1>")
	)
	(arc
		(start 94.303088 -52.819046)
		(mid 94.249462 -52.618894)
		(end 94.303088 -52.418742)
		(width 0.0889)
		(layer "In2.Cu")
		(net "M_J_CLK_DN<1>")
	)
	(arc
		(start 94.303088 -55.390796)
		(mid 94.382219 -55.095394)
		(end 94.303088 -54.799992)
		(width 0.0889)
		(layer "In2.Cu")
		(net "M_J_CLK_DN<1>")
	)
	(arc
		(start 94.303088 -56.381396)
		(mid 94.382219 -56.085994)
		(end 94.303088 -55.790592)
		(width 0.0889)
		(layer "In2.Cu")
		(net "M_J_CLK_DN<1>")
	)
	(arc
		(start 94.382336 -58.064654)
		(mid 94.361821 -57.913052)
		(end 94.303088 -57.771792)
		(width 0.0889)
		(layer "In2.Cu")
		(net "M_J_CLK_DN<1>")
	)
	(arc
		(start 94.303088 -53.409596)
		(mid 94.382219 -53.114194)
		(end 94.303088 -52.818792)
		(width 0.0889)
		(layer "In2.Cu")
		(net "M_J_CLK_DN<1>")
	)
	(arc
		(start 94.303088 -54.400196)
		(mid 94.382219 -54.104794)
		(end 94.303088 -53.809392)
		(width 0.0889)
		(layer "In2.Cu")
		(net "M_J_CLK_DN<1>")
	)
	(arc
		(start 94.303088 -55.790592)
		(mid 94.249589 -55.590694)
		(end 94.303088 -55.390796)
		(width 0.0889)
		(layer "In2.Cu")
		(net "M_J_CLK_DN<1>")
	)
	(arc
		(start 94.303088 -57.771792)
		(mid 94.249589 -57.571894)
		(end 94.303088 -57.371996)
		(width 0.0889)
		(layer "In2.Cu")
		(net "M_J_CLK_DN<1>")
	)
	(arc
		(start 94.544896 -58.457084)
		(mid 94.424591 -58.277036)
		(end 94.382336 -58.064654)
		(width 0.0889)
		(layer "In2.Cu")
		(net "M_J_CLK_DN<1>")
	)
	(arc
		(start 94.303088 -56.781192)
		(mid 94.249589 -56.581294)
		(end 94.303088 -56.381396)
		(width 0.0889)
		(layer "In2.Cu")
		(net "M_J_CLK_DN<1>")
	)
	(segment
		(start 93.504258 -59.55284)
		(end 92.932758 -59.55284)
		(width 0.1016)
		(layer "F.Cu")
		(net "M_J_CLK_DN<2>")
	)
	(via
		(at 92.932758 -59.55284)
		(size 0.508)
		(drill 0.254)
		(layers "F.Cu" "B.Cu")
		(net "M_J_CLK_DN<2>")
	)
	(via
		(at 92.788994 -4.328668)
		(size 0.508)
		(drill 0.254)
		(layers "F.Cu" "B.Cu")
		(net "M_J_CLK_DN<2>")
	)
	(segment
		(start 92.59951 -5.621782)
		(end 92.59951 -4.518152)
		(width 0.1651)
		(layer "B.Cu")
		(net "M_J_CLK_DN<2>")
	)
	(segment
		(start 92.59951 -4.518152)
		(end 92.788994 -4.328668)
		(width 0.1651)
		(layer "B.Cu")
		(net "M_J_CLK_DN<2>")
	)
	(segment
		(start 93.390974 -54.099968)
		(end 93.39072 -54.097682)
		(width 0.0889)
		(layer "In2.Cu")
		(net "M_J_CLK_DN<2>")
	)
	(segment
		(start 95.781368 -10.9982)
		(end 95.217488 -10.43432)
		(width 0.14224)
		(layer "In2.Cu")
		(net "M_J_CLK_DN<2>")
	)
	(segment
		(start 94.431612 -47.926752)
		(end 94.431612 -21.380958)
		(width 0.14224)
		(layer "In2.Cu")
		(net "M_J_CLK_DN<2>")
	)
	(segment
		(start 92.932758 -59.55284)
		(end 92.639642 -59.722004)
		(width 0.0889)
		(layer "In2.Cu")
		(net "M_J_CLK_DN<2>")
	)
	(segment
		(start 94.431612 -47.94885)
		(end 94.431612 -47.926752)
		(width 0.0889)
		(layer "In2.Cu")
		(net "M_J_CLK_DN<2>")
	)
	(segment
		(start 93.172534 -20.920964)
		(end 93.172534 -20.567904)
		(width 0.14224)
		(layer "In2.Cu")
		(net "M_J_CLK_DN<2>")
	)
	(segment
		(start 93.39072 -54.097682)
		(end 93.39072 -52.265834)
		(width 0.0889)
		(layer "In2.Cu")
		(net "M_J_CLK_DN<2>")
	)
	(segment
		(start 94.431612 -20.093178)
		(end 94.431612 -15.802356)
		(width 0.14224)
		(layer "In2.Cu")
		(net "M_J_CLK_DN<2>")
	)
	(segment
		(start 94.431612 -15.802356)
		(end 95.217488 -15.01648)
		(width 0.14224)
		(layer "In2.Cu")
		(net "M_J_CLK_DN<2>")
	)
	(segment
		(start 93.546168 -51.612038)
		(end 94.392242 -50.765964)
		(width 0.0889)
		(layer "In2.Cu")
		(net "M_J_CLK_DN<2>")
	)
	(segment
		(start 92.54617 -4.85775)
		(end 92.54617 -4.571492)
		(width 0.14224)
		(layer "In2.Cu")
		(net "M_J_CLK_DN<2>")
	)
	(segment
		(start 95.217488 -13.86078)
		(end 95.781368 -13.2969)
		(width 0.14224)
		(layer "In2.Cu")
		(net "M_J_CLK_DN<2>")
	)
	(segment
		(start 94.119192 -21.068538)
		(end 93.320108 -21.068538)
		(width 0.14224)
		(layer "In2.Cu")
		(net "M_J_CLK_DN<2>")
	)
	(segment
		(start 94.392242 -50.765964)
		(end 94.392242 -47.98822)
		(width 0.0889)
		(layer "In2.Cu")
		(net "M_J_CLK_DN<2>")
	)
	(segment
		(start 93.546168 -52.110386)
		(end 93.546168 -51.612038)
		(width 0.0889)
		(layer "In2.Cu")
		(net "M_J_CLK_DN<2>")
	)
	(segment
		(start 95.217488 -6.069584)
		(end 94.182184 -5.03428)
		(width 0.14224)
		(layer "In2.Cu")
		(net "M_J_CLK_DN<2>")
	)
	(segment
		(start 95.217488 -15.01648)
		(end 95.217488 -13.86078)
		(width 0.14224)
		(layer "In2.Cu")
		(net "M_J_CLK_DN<2>")
	)
	(segment
		(start 92.639642 -59.722004)
		(end 92.560902 -59.700668)
		(width 0.0889)
		(layer "In2.Cu")
		(net "M_J_CLK_DN<2>")
	)
	(segment
		(start 95.781368 -13.2969)
		(end 95.781368 -10.9982)
		(width 0.14224)
		(layer "In2.Cu")
		(net "M_J_CLK_DN<2>")
	)
	(segment
		(start 94.392242 -47.98822)
		(end 94.431612 -47.94885)
		(width 0.0889)
		(layer "In2.Cu")
		(net "M_J_CLK_DN<2>")
	)
	(segment
		(start 93.172534 -20.567904)
		(end 93.33484 -20.405598)
		(width 0.14224)
		(layer "In2.Cu")
		(net "M_J_CLK_DN<2>")
	)
	(segment
		(start 94.431612 -21.380958)
		(end 94.119192 -21.068538)
		(width 0.14224)
		(layer "In2.Cu")
		(net "M_J_CLK_DN<2>")
	)
	(segment
		(start 95.217488 -10.43432)
		(end 95.217488 -6.069584)
		(width 0.14224)
		(layer "In2.Cu")
		(net "M_J_CLK_DN<2>")
	)
	(segment
		(start 93.33484 -20.405598)
		(end 94.119192 -20.405598)
		(width 0.14224)
		(layer "In2.Cu")
		(net "M_J_CLK_DN<2>")
	)
	(segment
		(start 93.320108 -21.068538)
		(end 93.172534 -20.920964)
		(width 0.14224)
		(layer "In2.Cu")
		(net "M_J_CLK_DN<2>")
	)
	(segment
		(start 94.182184 -5.03428)
		(end 92.7227 -5.03428)
		(width 0.14224)
		(layer "In2.Cu")
		(net "M_J_CLK_DN<2>")
	)
	(segment
		(start 94.119192 -20.405598)
		(end 94.431612 -20.093178)
		(width 0.14224)
		(layer "In2.Cu")
		(net "M_J_CLK_DN<2>")
	)
	(segment
		(start 92.7227 -5.03428)
		(end 92.54617 -4.85775)
		(width 0.14224)
		(layer "In2.Cu")
		(net "M_J_CLK_DN<2>")
	)
	(segment
		(start 92.921582 -59.153044)
		(end 92.954348 -59.153044)
		(width 0.0889)
		(layer "In2.Cu")
		(net "M_J_CLK_DN<2>")
	)
	(segment
		(start 93.39072 -52.265834)
		(end 93.546168 -52.110386)
		(width 0.0889)
		(layer "In2.Cu")
		(net "M_J_CLK_DN<2>")
	)
	(segment
		(start 92.54617 -4.571492)
		(end 92.788994 -4.328668)
		(width 0.14224)
		(layer "In2.Cu")
		(net "M_J_CLK_DN<2>")
	)
	(arc
		(start 92.532708 -59.559952)
		(mid 92.643535 -59.276621)
		(end 92.921582 -59.153044)
		(width 0.0889)
		(layer "In2.Cu")
		(net "M_J_CLK_DN<2>")
	)
	(arc
		(start 93.444568 -58.267092)
		(mid 93.391069 -58.067194)
		(end 93.444568 -57.867296)
		(width 0.0889)
		(layer "In2.Cu")
		(net "M_J_CLK_DN<2>")
	)
	(arc
		(start 93.444568 -55.886096)
		(mid 93.523699 -55.590694)
		(end 93.444568 -55.295292)
		(width 0.0889)
		(layer "In2.Cu")
		(net "M_J_CLK_DN<2>")
	)
	(arc
		(start 93.444568 -56.285892)
		(mid 93.391069 -56.085994)
		(end 93.444568 -55.886096)
		(width 0.0889)
		(layer "In2.Cu")
		(net "M_J_CLK_DN<2>")
	)
	(arc
		(start 93.444568 -55.295292)
		(mid 93.391069 -55.095394)
		(end 93.444568 -54.895496)
		(width 0.0889)
		(layer "In2.Cu")
		(net "M_J_CLK_DN<2>")
	)
	(arc
		(start 93.444568 -54.895496)
		(mid 93.523699 -54.600094)
		(end 93.444568 -54.304692)
		(width 0.0889)
		(layer "In2.Cu")
		(net "M_J_CLK_DN<2>")
	)
	(arc
		(start 92.954348 -59.153044)
		(mid 93.449825 -58.848601)
		(end 93.444568 -58.267092)
		(width 0.0889)
		(layer "In2.Cu")
		(net "M_J_CLK_DN<2>")
	)
	(arc
		(start 93.444568 -56.876696)
		(mid 93.523699 -56.581294)
		(end 93.444568 -56.285892)
		(width 0.0889)
		(layer "In2.Cu")
		(net "M_J_CLK_DN<2>")
	)
	(arc
		(start 93.444568 -54.304692)
		(mid 93.403996 -54.205936)
		(end 93.390974 -54.099968)
		(width 0.0889)
		(layer "In2.Cu")
		(net "M_J_CLK_DN<2>")
	)
	(arc
		(start 92.560902 -59.700668)
		(mid 92.540464 -59.631582)
		(end 92.532708 -59.559952)
		(width 0.0889)
		(layer "In2.Cu")
		(net "M_J_CLK_DN<2>")
	)
	(arc
		(start 93.444568 -57.276492)
		(mid 93.391069 -57.076594)
		(end 93.444568 -56.876696)
		(width 0.0889)
		(layer "In2.Cu")
		(net "M_J_CLK_DN<2>")
	)
	(arc
		(start 93.444568 -57.867296)
		(mid 93.523699 -57.571894)
		(end 93.444568 -57.276492)
		(width 0.0889)
		(layer "In2.Cu")
		(net "M_J_CLK_DN<2>")
	)
	(segment
		(start 92.59951 3.778758)
		(end 92.59951 2.485644)
		(width 0.1651)
		(layer "F.Cu")
		(net "M_J_CLK_DN<0>")
	)
	(segment
		(start 95.221298 -59.55284)
		(end 94.649798 -59.55284)
		(width 0.1016)
		(layer "F.Cu")
		(net "M_J_CLK_DN<0>")
	)
	(via
		(at 92.59951 2.485644)
		(size 0.508)
		(drill 0.254)
		(layers "F.Cu" "B.Cu")
		(net "M_J_CLK_DN<0>")
	)
	(via
		(at 94.649798 -59.55284)
		(size 0.508)
		(drill 0.254)
		(layers "F.Cu" "B.Cu")
		(net "M_J_CLK_DN<0>")
	)
	(segment
		(start 95.085408 0.723138)
		(end 94.115636 1.69291)
		(width 0.14224)
		(layer "In2.Cu")
		(net "M_J_CLK_DN<0>")
	)
	(segment
		(start 97.483168 -11.811)
		(end 97.803208 -11.49096)
		(width 0.14224)
		(layer "In2.Cu")
		(net "M_J_CLK_DN<0>")
	)
	(segment
		(start 95.160338 -52.321714)
		(end 95.097092 -52.216812)
		(width 0.0889)
		(layer "In2.Cu")
		(net "M_J_CLK_DN<0>")
	)
	(segment
		(start 92.289884 2.176018)
		(end 92.59951 2.485644)
		(width 0.14224)
		(layer "In2.Cu")
		(net "M_J_CLK_DN<0>")
	)
	(segment
		(start 96.120712 -27.620976)
		(end 97.173288 -26.5684)
		(width 0.14224)
		(layer "In2.Cu")
		(net "M_J_CLK_DN<0>")
	)
	(segment
		(start 97.173288 -26.5684)
		(end 97.173288 -20.50288)
		(width 0.14224)
		(layer "In2.Cu")
		(net "M_J_CLK_DN<0>")
	)
	(segment
		(start 95.097092 -52.216812)
		(end 95.097092 -51.916076)
		(width 0.0889)
		(layer "In2.Cu")
		(net "M_J_CLK_DN<0>")
	)
	(segment
		(start 96.081342 -48.144176)
		(end 96.120712 -48.104806)
		(width 0.0889)
		(layer "In2.Cu")
		(net "M_J_CLK_DN<0>")
	)
	(segment
		(start 96.120712 -48.104806)
		(end 96.120712 -48.082708)
		(width 0.0889)
		(layer "In2.Cu")
		(net "M_J_CLK_DN<0>")
	)
	(segment
		(start 97.498408 -1.803654)
		(end 96.568514 -0.87376)
		(width 0.14224)
		(layer "In2.Cu")
		(net "M_J_CLK_DN<0>")
	)
	(segment
		(start 95.097092 -51.916076)
		(end 95.679768 -51.3334)
		(width 0.0889)
		(layer "In2.Cu")
		(net "M_J_CLK_DN<0>")
	)
	(segment
		(start 97.173288 -20.50288)
		(end 97.483168 -20.193)
		(width 0.14224)
		(layer "In2.Cu")
		(net "M_J_CLK_DN<0>")
	)
	(segment
		(start 95.679768 -48.970438)
		(end 96.081342 -48.568864)
		(width 0.0889)
		(layer "In2.Cu")
		(net "M_J_CLK_DN<0>")
	)
	(segment
		(start 95.562928 -0.87376)
		(end 95.085408 -0.39624)
		(width 0.14224)
		(layer "In2.Cu")
		(net "M_J_CLK_DN<0>")
	)
	(segment
		(start 97.803208 -10.16508)
		(end 97.498408 -9.86028)
		(width 0.14224)
		(layer "In2.Cu")
		(net "M_J_CLK_DN<0>")
	)
	(segment
		(start 96.081342 -48.568864)
		(end 96.081342 -48.144176)
		(width 0.0889)
		(layer "In2.Cu")
		(net "M_J_CLK_DN<0>")
	)
	(segment
		(start 92.51823 1.69291)
		(end 92.289884 1.921256)
		(width 0.14224)
		(layer "In2.Cu")
		(net "M_J_CLK_DN<0>")
	)
	(segment
		(start 97.483168 -20.193)
		(end 97.483168 -11.811)
		(width 0.14224)
		(layer "In2.Cu")
		(net "M_J_CLK_DN<0>")
	)
	(segment
		(start 95.085408 -0.39624)
		(end 95.085408 0.723138)
		(width 0.14224)
		(layer "In2.Cu")
		(net "M_J_CLK_DN<0>")
	)
	(segment
		(start 97.803208 -11.49096)
		(end 97.803208 -10.16508)
		(width 0.14224)
		(layer "In2.Cu")
		(net "M_J_CLK_DN<0>")
	)
	(segment
		(start 96.568514 -0.87376)
		(end 95.562928 -0.87376)
		(width 0.14224)
		(layer "In2.Cu")
		(net "M_J_CLK_DN<0>")
	)
	(segment
		(start 92.289884 1.921256)
		(end 92.289884 2.176018)
		(width 0.14224)
		(layer "In2.Cu")
		(net "M_J_CLK_DN<0>")
	)
	(segment
		(start 94.356682 -59.722004)
		(end 94.277942 -59.700668)
		(width 0.0889)
		(layer "In2.Cu")
		(net "M_J_CLK_DN<0>")
	)
	(segment
		(start 94.638622 -59.153044)
		(end 94.671388 -59.153044)
		(width 0.0889)
		(layer "In2.Cu")
		(net "M_J_CLK_DN<0>")
	)
	(segment
		(start 94.115636 1.69291)
		(end 92.51823 1.69291)
		(width 0.14224)
		(layer "In2.Cu")
		(net "M_J_CLK_DN<0>")
	)
	(segment
		(start 97.498408 -9.86028)
		(end 97.498408 -1.803654)
		(width 0.14224)
		(layer "In2.Cu")
		(net "M_J_CLK_DN<0>")
	)
	(segment
		(start 95.679768 -51.3334)
		(end 95.679768 -48.970438)
		(width 0.0889)
		(layer "In2.Cu")
		(net "M_J_CLK_DN<0>")
	)
	(segment
		(start 94.649798 -59.55284)
		(end 94.356682 -59.722004)
		(width 0.0889)
		(layer "In2.Cu")
		(net "M_J_CLK_DN<0>")
	)
	(segment
		(start 96.120712 -48.082708)
		(end 96.120712 -27.620976)
		(width 0.14224)
		(layer "In2.Cu")
		(net "M_J_CLK_DN<0>")
	)
	(segment
		(start 95.161608 -52.914296)
		(end 95.161608 -52.914042)
		(width 0.0889)
		(layer "In2.Cu")
		(net "M_J_CLK_DN<0>")
	)
	(arc
		(start 95.161608 -56.285892)
		(mid 95.108109 -56.085994)
		(end 95.161608 -55.886096)
		(width 0.0889)
		(layer "In2.Cu")
		(net "M_J_CLK_DN<0>")
	)
	(arc
		(start 95.161608 -52.914042)
		(mid 95.240611 -52.617696)
		(end 95.160338 -52.321714)
		(width 0.0889)
		(layer "In2.Cu")
		(net "M_J_CLK_DN<0>")
	)
	(arc
		(start 95.161608 -53.314092)
		(mid 95.108109 -53.114194)
		(end 95.161608 -52.914296)
		(width 0.0889)
		(layer "In2.Cu")
		(net "M_J_CLK_DN<0>")
	)
	(arc
		(start 94.277942 -59.700668)
		(mid 94.257504 -59.631582)
		(end 94.249748 -59.559952)
		(width 0.0889)
		(layer "In2.Cu")
		(net "M_J_CLK_DN<0>")
	)
	(arc
		(start 95.161608 -53.904896)
		(mid 95.240739 -53.609494)
		(end 95.161608 -53.314092)
		(width 0.0889)
		(layer "In2.Cu")
		(net "M_J_CLK_DN<0>")
	)
	(arc
		(start 95.161608 -57.276492)
		(mid 95.108109 -57.076594)
		(end 95.161608 -56.876696)
		(width 0.0889)
		(layer "In2.Cu")
		(net "M_J_CLK_DN<0>")
	)
	(arc
		(start 95.161608 -54.304692)
		(mid 95.108109 -54.104794)
		(end 95.161608 -53.904896)
		(width 0.0889)
		(layer "In2.Cu")
		(net "M_J_CLK_DN<0>")
	)
	(arc
		(start 95.161608 -58.267092)
		(mid 95.108109 -58.067194)
		(end 95.161608 -57.867296)
		(width 0.0889)
		(layer "In2.Cu")
		(net "M_J_CLK_DN<0>")
	)
	(arc
		(start 94.249748 -59.559952)
		(mid 94.360575 -59.276621)
		(end 94.638622 -59.153044)
		(width 0.0889)
		(layer "In2.Cu")
		(net "M_J_CLK_DN<0>")
	)
	(arc
		(start 95.161608 -55.295292)
		(mid 95.108109 -55.095394)
		(end 95.161608 -54.895496)
		(width 0.0889)
		(layer "In2.Cu")
		(net "M_J_CLK_DN<0>")
	)
	(arc
		(start 95.161608 -55.886096)
		(mid 95.240739 -55.590694)
		(end 95.161608 -55.295292)
		(width 0.0889)
		(layer "In2.Cu")
		(net "M_J_CLK_DN<0>")
	)
	(arc
		(start 95.161608 -57.867296)
		(mid 95.240739 -57.571894)
		(end 95.161608 -57.276492)
		(width 0.0889)
		(layer "In2.Cu")
		(net "M_J_CLK_DN<0>")
	)
	(arc
		(start 95.161608 -56.876696)
		(mid 95.240739 -56.581294)
		(end 95.161608 -56.285892)
		(width 0.0889)
		(layer "In2.Cu")
		(net "M_J_CLK_DN<0>")
	)
	(arc
		(start 95.161608 -54.895496)
		(mid 95.240739 -54.600094)
		(end 95.161608 -54.304692)
		(width 0.0889)
		(layer "In2.Cu")
		(net "M_J_CLK_DN<0>")
	)
	(arc
		(start 94.671388 -59.153044)
		(mid 95.166865 -58.848601)
		(end 95.161608 -58.267092)
		(width 0.0889)
		(layer "In2.Cu")
		(net "M_J_CLK_DN<0>")
	)
	(segment
		(start 87.494872 -60.047886)
		(end 86.923372 -60.047886)
		(width 0.1016)
		(layer "F.Cu")
		(net "M_J_CKE<3>")
	)
	(via
		(at 78.999334 -2.314956)
		(size 0.4572)
		(drill 0.2032)
		(layers "F.Cu" "B.Cu")
		(net "M_J_CKE<3>")
	)
	(via
		(at 86.923372 -60.047886)
		(size 0.508)
		(drill 0.254)
		(layers "F.Cu" "B.Cu")
		(net "M_J_CKE<3>")
	)
	(segment
		(start 78.999334 -2.314956)
		(end 78.999334 -1.021842)
		(width 0.1651)
		(layer "B.Cu")
		(net "M_J_CKE<3>")
	)
	(segment
		(start 79.35849 -24.648922)
		(end 79.35849 -23.31847)
		(width 0.14224)
		(layer "In2.Cu")
		(net "M_J_CKE<3>")
	)
	(segment
		(start 86.405212 -55.801006)
		(end 86.411562 -55.790338)
		(width 0.0889)
		(layer "In2.Cu")
		(net "M_J_CKE<3>")
	)
	(segment
		(start 79.366364 -21.938996)
		(end 79.493364 -21.811996)
		(width 0.14224)
		(layer "In2.Cu")
		(net "M_J_CKE<3>")
	)
	(segment
		(start 86.923372 -60.047886)
		(end 86.593426 -59.28614)
		(width 0.0889)
		(layer "In2.Cu")
		(net "M_J_CKE<3>")
	)
	(segment
		(start 79.544164 -22.599396)
		(end 79.366364 -22.421596)
		(width 0.14224)
		(layer "In2.Cu")
		(net "M_J_CKE<3>")
	)
	(segment
		(start 79.441802 -17.008348)
		(end 79.441802 -12.37234)
		(width 0.14224)
		(layer "In2.Cu")
		(net "M_J_CKE<3>")
	)
	(segment
		(start 79.35849 -23.31847)
		(end 79.544164 -23.132796)
		(width 0.14224)
		(layer "In2.Cu")
		(net "M_J_CKE<3>")
	)
	(segment
		(start 79.411068 -7.62)
		(end 79.432404 -7.598664)
		(width 0.14224)
		(layer "In2.Cu")
		(net "M_J_CKE<3>")
	)
	(segment
		(start 86.295484 -48.97882)
		(end 86.175342 -48.858678)
		(width 0.0889)
		(layer "In2.Cu")
		(net "M_J_CKE<3>")
	)
	(segment
		(start 86.405212 -56.791606)
		(end 86.411562 -56.780938)
		(width 0.0889)
		(layer "In2.Cu")
		(net "M_J_CKE<3>")
	)
	(segment
		(start 79.422752 -19.333718)
		(end 79.422752 -18.475198)
		(width 0.14224)
		(layer "In2.Cu")
		(net "M_J_CKE<3>")
	)
	(segment
		(start 80.998568 -27.482292)
		(end 80.998568 -26.289)
		(width 0.14224)
		(layer "In2.Cu")
		(net "M_J_CKE<3>")
	)
	(segment
		(start 79.422752 -18.475198)
		(end 79.493364 -18.404586)
		(width 0.14224)
		(layer "In2.Cu")
		(net "M_J_CKE<3>")
	)
	(segment
		(start 86.405212 -53.819806)
		(end 86.411562 -53.809138)
		(width 0.0889)
		(layer "In2.Cu")
		(net "M_J_CKE<3>")
	)
	(segment
		(start 86.332314 -57.378346)
		(end 86.332314 -57.08142)
		(width 0.0889)
		(layer "In2.Cu")
		(net "M_J_CKE<3>")
	)
	(segment
		(start 86.475062 -57.521094)
		(end 86.332314 -57.378346)
		(width 0.0889)
		(layer "In2.Cu")
		(net "M_J_CKE<3>")
	)
	(segment
		(start 86.571836 -58.866024)
		(end 86.594188 -58.826146)
		(width 0.0889)
		(layer "In2.Cu")
		(net "M_J_CKE<3>")
	)
	(segment
		(start 86.295484 -51.231546)
		(end 86.295484 -48.97882)
		(width 0.0889)
		(layer "In2.Cu")
		(net "M_J_CKE<3>")
	)
	(segment
		(start 79.493364 -17.769586)
		(end 79.340964 -17.617186)
		(width 0.14224)
		(layer "In2.Cu")
		(net "M_J_CKE<3>")
	)
	(segment
		(start 79.432404 -7.598664)
		(end 79.432404 -2.748026)
		(width 0.14224)
		(layer "In2.Cu")
		(net "M_J_CKE<3>")
	)
	(segment
		(start 86.411562 -53.809138)
		(end 86.416388 -53.800502)
		(width 0.0889)
		(layer "In2.Cu")
		(net "M_J_CKE<3>")
	)
	(segment
		(start 79.432404 -2.748026)
		(end 78.999334 -2.314956)
		(width 0.14224)
		(layer "In2.Cu")
		(net "M_J_CKE<3>")
	)
	(segment
		(start 86.411562 -56.780938)
		(end 86.416388 -56.772302)
		(width 0.0889)
		(layer "In2.Cu")
		(net "M_J_CKE<3>")
	)
	(segment
		(start 79.493364 -19.40433)
		(end 79.422752 -19.333718)
		(width 0.14224)
		(layer "In2.Cu")
		(net "M_J_CKE<3>")
	)
	(segment
		(start 86.475062 -58.090562)
		(end 86.475062 -57.521094)
		(width 0.0889)
		(layer "In2.Cu")
		(net "M_J_CKE<3>")
	)
	(segment
		(start 79.340964 -17.109186)
		(end 79.441802 -17.008348)
		(width 0.14224)
		(layer "In2.Cu")
		(net "M_J_CKE<3>")
	)
	(segment
		(start 86.175342 -48.858678)
		(end 86.175342 -48.567848)
		(width 0.0889)
		(layer "In2.Cu")
		(net "M_J_CKE<3>")
	)
	(segment
		(start 79.544164 -23.132796)
		(end 79.544164 -22.599396)
		(width 0.14224)
		(layer "In2.Cu")
		(net "M_J_CKE<3>")
	)
	(segment
		(start 86.411562 -54.799738)
		(end 86.416388 -54.791102)
		(width 0.0889)
		(layer "In2.Cu")
		(net "M_J_CKE<3>")
	)
	(segment
		(start 86.411562 -55.790338)
		(end 86.416388 -55.781702)
		(width 0.0889)
		(layer "In2.Cu")
		(net "M_J_CKE<3>")
	)
	(segment
		(start 86.593426 -59.28614)
		(end 86.576662 -59.257438)
		(width 0.0889)
		(layer "In2.Cu")
		(net "M_J_CKE<3>")
	)
	(segment
		(start 80.998568 -26.289)
		(end 79.35849 -24.648922)
		(width 0.14224)
		(layer "In2.Cu")
		(net "M_J_CKE<3>")
	)
	(segment
		(start 86.411562 -51.828192)
		(end 86.467442 -51.731164)
		(width 0.0889)
		(layer "In2.Cu")
		(net "M_J_CKE<3>")
	)
	(segment
		(start 86.467442 -51.731164)
		(end 86.467442 -51.403504)
		(width 0.0889)
		(layer "In2.Cu")
		(net "M_J_CKE<3>")
	)
	(segment
		(start 79.411068 -12.341606)
		(end 79.411068 -7.62)
		(width 0.14224)
		(layer "In2.Cu")
		(net "M_J_CKE<3>")
	)
	(segment
		(start 86.175342 -48.567848)
		(end 86.175342 -32.659066)
		(width 0.14224)
		(layer "In2.Cu")
		(net "M_J_CKE<3>")
	)
	(segment
		(start 79.340964 -17.617186)
		(end 79.340964 -17.109186)
		(width 0.14224)
		(layer "In2.Cu")
		(net "M_J_CKE<3>")
	)
	(segment
		(start 79.493364 -18.404586)
		(end 79.493364 -17.769586)
		(width 0.14224)
		(layer "In2.Cu")
		(net "M_J_CKE<3>")
	)
	(segment
		(start 86.467442 -51.403504)
		(end 86.295484 -51.231546)
		(width 0.0889)
		(layer "In2.Cu")
		(net "M_J_CKE<3>")
	)
	(segment
		(start 86.405212 -54.810406)
		(end 86.411562 -54.799738)
		(width 0.0889)
		(layer "In2.Cu")
		(net "M_J_CKE<3>")
	)
	(segment
		(start 79.441802 -12.37234)
		(end 79.411068 -12.341606)
		(width 0.14224)
		(layer "In2.Cu")
		(net "M_J_CKE<3>")
	)
	(segment
		(start 79.493364 -21.811996)
		(end 79.493364 -19.40433)
		(width 0.14224)
		(layer "In2.Cu")
		(net "M_J_CKE<3>")
	)
	(segment
		(start 86.175342 -32.659066)
		(end 80.998568 -27.482292)
		(width 0.14224)
		(layer "In2.Cu")
		(net "M_J_CKE<3>")
	)
	(segment
		(start 79.366364 -22.421596)
		(end 79.366364 -21.938996)
		(width 0.14224)
		(layer "In2.Cu")
		(net "M_J_CKE<3>")
	)
	(segment
		(start 86.590378 -58.289952)
		(end 86.475062 -58.090562)
		(width 0.0889)
		(layer "In2.Cu")
		(net "M_J_CKE<3>")
	)
	(arc
		(start 86.332314 -57.08142)
		(mid 86.350162 -56.931836)
		(end 86.405212 -56.791606)
		(width 0.0889)
		(layer "In2.Cu")
		(net "M_J_CKE<3>")
	)
	(arc
		(start 86.416388 -56.772302)
		(mid 86.465143 -56.57595)
		(end 86.411562 -56.380888)
		(width 0.0889)
		(layer "In2.Cu")
		(net "M_J_CKE<3>")
	)
	(arc
		(start 86.411562 -52.418488)
		(mid 86.332557 -52.12334)
		(end 86.411562 -51.828192)
		(width 0.0889)
		(layer "In2.Cu")
		(net "M_J_CKE<3>")
	)
	(arc
		(start 86.411562 -56.380888)
		(mid 86.33234 -56.09177)
		(end 86.405212 -55.801006)
		(width 0.0889)
		(layer "In2.Cu")
		(net "M_J_CKE<3>")
	)
	(arc
		(start 86.411562 -53.409088)
		(mid 86.332431 -53.113686)
		(end 86.411562 -52.818284)
		(width 0.0889)
		(layer "In2.Cu")
		(net "M_J_CKE<3>")
	)
	(arc
		(start 86.411562 -52.818284)
		(mid 86.465061 -52.618386)
		(end 86.411562 -52.418488)
		(width 0.0889)
		(layer "In2.Cu")
		(net "M_J_CKE<3>")
	)
	(arc
		(start 86.594188 -58.826146)
		(mid 86.663097 -58.557556)
		(end 86.590378 -58.289952)
		(width 0.0889)
		(layer "In2.Cu")
		(net "M_J_CKE<3>")
	)
	(arc
		(start 86.416388 -54.791102)
		(mid 86.465143 -54.59475)
		(end 86.411562 -54.399688)
		(width 0.0889)
		(layer "In2.Cu")
		(net "M_J_CKE<3>")
	)
	(arc
		(start 86.411562 -55.390288)
		(mid 86.33234 -55.10117)
		(end 86.405212 -54.810406)
		(width 0.0889)
		(layer "In2.Cu")
		(net "M_J_CKE<3>")
	)
	(arc
		(start 86.416388 -55.781702)
		(mid 86.465143 -55.58535)
		(end 86.411562 -55.390288)
		(width 0.0889)
		(layer "In2.Cu")
		(net "M_J_CKE<3>")
	)
	(arc
		(start 86.416388 -53.800502)
		(mid 86.465143 -53.60415)
		(end 86.411562 -53.409088)
		(width 0.0889)
		(layer "In2.Cu")
		(net "M_J_CKE<3>")
	)
	(arc
		(start 86.576662 -59.257438)
		(mid 86.523192 -59.062375)
		(end 86.571836 -58.866024)
		(width 0.0889)
		(layer "In2.Cu")
		(net "M_J_CKE<3>")
	)
	(arc
		(start 86.411562 -54.399688)
		(mid 86.33234 -54.11057)
		(end 86.405212 -53.819806)
		(width 0.0889)
		(layer "In2.Cu")
		(net "M_J_CKE<3>")
	)
	(segment
		(start 87.494872 -58.06694)
		(end 86.923372 -58.06694)
		(width 0.1016)
		(layer "F.Cu")
		(net "M_J_CKE<2>")
	)
	(via
		(at 86.923372 -58.06694)
		(size 0.508)
		(drill 0.254)
		(layers "F.Cu" "B.Cu")
		(net "M_J_CKE<2>")
	)
	(via
		(at 79.849472 -4.332478)
		(size 0.4572)
		(drill 0.2032)
		(layers "F.Cu" "B.Cu")
		(net "M_J_CKE<2>")
	)
	(segment
		(start 79.849472 -5.621782)
		(end 79.849472 -4.332478)
		(width 0.1651)
		(layer "B.Cu")
		(net "M_J_CKE<2>")
	)
	(segment
		(start 86.571836 -52.922424)
		(end 86.576662 -52.913788)
		(width 0.0889)
		(layer "In2.Cu")
		(net "M_J_CKE<2>")
	)
	(segment
		(start 79.850742 -4.694174)
		(end 79.850742 -4.333748)
		(width 0.14224)
		(layer "In2.Cu")
		(net "M_J_CKE<2>")
	)
	(segment
		(start 86.576662 -51.923442)
		(end 86.683342 -51.738276)
		(width 0.0889)
		(layer "In2.Cu")
		(net "M_J_CKE<2>")
	)
	(segment
		(start 86.683342 -32.4993)
		(end 81.506568 -27.322526)
		(width 0.14224)
		(layer "In2.Cu")
		(net "M_J_CKE<2>")
	)
	(segment
		(start 80.204564 -21.761196)
		(end 80.204564 -19.141186)
		(width 0.14224)
		(layer "In2.Cu")
		(net "M_J_CKE<2>")
	)
	(segment
		(start 86.683342 -50.922174)
		(end 86.683342 -32.4993)
		(width 0.14224)
		(layer "In2.Cu")
		(net "M_J_CKE<2>")
	)
	(segment
		(start 86.683342 -51.738276)
		(end 86.683342 -50.922174)
		(width 0.0889)
		(layer "In2.Cu")
		(net "M_J_CKE<2>")
	)
	(segment
		(start 86.571836 -55.894224)
		(end 86.576662 -55.885588)
		(width 0.0889)
		(layer "In2.Cu")
		(net "M_J_CKE<2>")
	)
	(segment
		(start 80.204564 -8.777986)
		(end 80.204564 -8.193786)
		(width 0.14224)
		(layer "In2.Cu")
		(net "M_J_CKE<2>")
	)
	(segment
		(start 80.356964 -17.642586)
		(end 80.356964 -17.134586)
		(width 0.14224)
		(layer "In2.Cu")
		(net "M_J_CKE<2>")
	)
	(segment
		(start 80.287368 -8.86079)
		(end 80.204564 -8.777986)
		(width 0.14224)
		(layer "In2.Cu")
		(net "M_J_CKE<2>")
	)
	(segment
		(start 80.204564 -8.193786)
		(end 80.356964 -8.041386)
		(width 0.14224)
		(layer "In2.Cu")
		(net "M_J_CKE<2>")
	)
	(segment
		(start 80.204564 -18.379186)
		(end 80.204564 -17.794986)
		(width 0.14224)
		(layer "In2.Cu")
		(net "M_J_CKE<2>")
	)
	(segment
		(start 81.506568 -27.322526)
		(end 81.506568 -26.035)
		(width 0.14224)
		(layer "In2.Cu")
		(net "M_J_CKE<2>")
	)
	(segment
		(start 80.356964 -7.533386)
		(end 80.266286 -7.442708)
		(width 0.14224)
		(layer "In2.Cu")
		(net "M_J_CKE<2>")
	)
	(segment
		(start 86.571836 -56.884824)
		(end 86.576662 -56.876188)
		(width 0.0889)
		(layer "In2.Cu")
		(net "M_J_CKE<2>")
	)
	(segment
		(start 80.204564 -17.794986)
		(end 80.356964 -17.642586)
		(width 0.14224)
		(layer "In2.Cu")
		(net "M_J_CKE<2>")
	)
	(segment
		(start 86.593426 -57.305194)
		(end 86.576662 -57.276238)
		(width 0.0889)
		(layer "In2.Cu")
		(net "M_J_CKE<2>")
	)
	(segment
		(start 86.571836 -53.913024)
		(end 86.576662 -53.904388)
		(width 0.0889)
		(layer "In2.Cu")
		(net "M_J_CKE<2>")
	)
	(segment
		(start 80.179164 -23.107396)
		(end 80.179164 -22.573996)
		(width 0.14224)
		(layer "In2.Cu")
		(net "M_J_CKE<2>")
	)
	(segment
		(start 81.506568 -26.035)
		(end 80.356964 -24.885396)
		(width 0.14224)
		(layer "In2.Cu")
		(net "M_J_CKE<2>")
	)
	(segment
		(start 86.576662 -53.904388)
		(end 86.583012 -53.89372)
		(width 0.0889)
		(layer "In2.Cu")
		(net "M_J_CKE<2>")
	)
	(segment
		(start 86.576662 -55.885588)
		(end 86.583012 -55.87492)
		(width 0.0889)
		(layer "In2.Cu")
		(net "M_J_CKE<2>")
	)
	(segment
		(start 80.204564 -19.141186)
		(end 80.287114 -19.058636)
		(width 0.14224)
		(layer "In2.Cu")
		(net "M_J_CKE<2>")
	)
	(segment
		(start 80.356964 -24.885396)
		(end 80.356964 -23.285196)
		(width 0.14224)
		(layer "In2.Cu")
		(net "M_J_CKE<2>")
	)
	(segment
		(start 80.287368 -12.41044)
		(end 80.287368 -8.86079)
		(width 0.14224)
		(layer "In2.Cu")
		(net "M_J_CKE<2>")
	)
	(segment
		(start 80.179164 -22.573996)
		(end 80.356964 -22.396196)
		(width 0.14224)
		(layer "In2.Cu")
		(net "M_J_CKE<2>")
	)
	(segment
		(start 79.850742 -4.333748)
		(end 79.849472 -4.332478)
		(width 0.14224)
		(layer "In2.Cu")
		(net "M_J_CKE<2>")
	)
	(segment
		(start 86.571836 -54.903624)
		(end 86.576662 -54.894988)
		(width 0.0889)
		(layer "In2.Cu")
		(net "M_J_CKE<2>")
	)
	(segment
		(start 80.356964 -21.913596)
		(end 80.204564 -21.761196)
		(width 0.14224)
		(layer "In2.Cu")
		(net "M_J_CKE<2>")
	)
	(segment
		(start 80.261968 -17.03959)
		(end 80.261968 -12.43584)
		(width 0.14224)
		(layer "In2.Cu")
		(net "M_J_CKE<2>")
	)
	(segment
		(start 80.356964 -17.134586)
		(end 80.261968 -17.03959)
		(width 0.14224)
		(layer "In2.Cu")
		(net "M_J_CKE<2>")
	)
	(segment
		(start 80.266286 -7.442708)
		(end 80.266286 -5.109718)
		(width 0.14224)
		(layer "In2.Cu")
		(net "M_J_CKE<2>")
	)
	(segment
		(start 80.356964 -8.041386)
		(end 80.356964 -7.533386)
		(width 0.14224)
		(layer "In2.Cu")
		(net "M_J_CKE<2>")
	)
	(segment
		(start 80.287114 -18.461736)
		(end 80.204564 -18.379186)
		(width 0.14224)
		(layer "In2.Cu")
		(net "M_J_CKE<2>")
	)
	(segment
		(start 86.576662 -56.876188)
		(end 86.583012 -56.86552)
		(width 0.0889)
		(layer "In2.Cu")
		(net "M_J_CKE<2>")
	)
	(segment
		(start 86.576662 -54.894988)
		(end 86.583012 -54.88432)
		(width 0.0889)
		(layer "In2.Cu")
		(net "M_J_CKE<2>")
	)
	(segment
		(start 86.923372 -58.06694)
		(end 86.593426 -57.305194)
		(width 0.0889)
		(layer "In2.Cu")
		(net "M_J_CKE<2>")
	)
	(segment
		(start 80.266286 -5.109718)
		(end 79.850742 -4.694174)
		(width 0.14224)
		(layer "In2.Cu")
		(net "M_J_CKE<2>")
	)
	(segment
		(start 86.583012 -52.333906)
		(end 86.576662 -52.323238)
		(width 0.0889)
		(layer "In2.Cu")
		(net "M_J_CKE<2>")
	)
	(segment
		(start 80.261968 -12.43584)
		(end 80.287368 -12.41044)
		(width 0.14224)
		(layer "In2.Cu")
		(net "M_J_CKE<2>")
	)
	(segment
		(start 80.356964 -22.396196)
		(end 80.356964 -21.913596)
		(width 0.14224)
		(layer "In2.Cu")
		(net "M_J_CKE<2>")
	)
	(segment
		(start 80.287114 -19.058636)
		(end 80.287114 -18.461736)
		(width 0.14224)
		(layer "In2.Cu")
		(net "M_J_CKE<2>")
	)
	(segment
		(start 80.356964 -23.285196)
		(end 80.179164 -23.107396)
		(width 0.14224)
		(layer "In2.Cu")
		(net "M_J_CKE<2>")
	)
	(arc
		(start 86.576662 -53.313838)
		(mid 86.523192 -53.118775)
		(end 86.571836 -52.922424)
		(width 0.0889)
		(layer "In2.Cu")
		(net "M_J_CKE<2>")
	)
	(arc
		(start 86.583012 -55.87492)
		(mid 86.65581 -55.584157)
		(end 86.576662 -55.295038)
		(width 0.0889)
		(layer "In2.Cu")
		(net "M_J_CKE<2>")
	)
	(arc
		(start 86.576662 -56.285638)
		(mid 86.523192 -56.090575)
		(end 86.571836 -55.894224)
		(width 0.0889)
		(layer "In2.Cu")
		(net "M_J_CKE<2>")
	)
	(arc
		(start 86.583012 -53.89372)
		(mid 86.65581 -53.602957)
		(end 86.576662 -53.313838)
		(width 0.0889)
		(layer "In2.Cu")
		(net "M_J_CKE<2>")
	)
	(arc
		(start 86.576662 -57.276238)
		(mid 86.523192 -57.081175)
		(end 86.571836 -56.884824)
		(width 0.0889)
		(layer "In2.Cu")
		(net "M_J_CKE<2>")
	)
	(arc
		(start 86.576662 -52.323238)
		(mid 86.523163 -52.12334)
		(end 86.576662 -51.923442)
		(width 0.0889)
		(layer "In2.Cu")
		(net "M_J_CKE<2>")
	)
	(arc
		(start 86.576662 -52.913788)
		(mid 86.655884 -52.62467)
		(end 86.583012 -52.333906)
		(width 0.0889)
		(layer "In2.Cu")
		(net "M_J_CKE<2>")
	)
	(arc
		(start 86.583012 -56.86552)
		(mid 86.65581 -56.574757)
		(end 86.576662 -56.285638)
		(width 0.0889)
		(layer "In2.Cu")
		(net "M_J_CKE<2>")
	)
	(arc
		(start 86.576662 -55.295038)
		(mid 86.523192 -55.099975)
		(end 86.571836 -54.903624)
		(width 0.0889)
		(layer "In2.Cu")
		(net "M_J_CKE<2>")
	)
	(arc
		(start 86.576662 -54.304438)
		(mid 86.523192 -54.109375)
		(end 86.571836 -53.913024)
		(width 0.0889)
		(layer "In2.Cu")
		(net "M_J_CKE<2>")
	)
	(arc
		(start 86.583012 -54.88432)
		(mid 86.65581 -54.593557)
		(end 86.576662 -54.304438)
		(width 0.0889)
		(layer "In2.Cu")
		(net "M_J_CKE<2>")
	)
	(segment
		(start 78.999334 -0.821182)
		(end 78.999334 1.152144)
		(width 0.1651)
		(layer "F.Cu")
		(net "M_J_CKE<1>")
	)
	(segment
		(start 87.494872 -61.038486)
		(end 86.923372 -61.038486)
		(width 0.1016)
		(layer "F.Cu")
		(net "M_J_CKE<1>")
	)
	(via
		(at 86.923372 -61.038486)
		(size 0.508)
		(drill 0.254)
		(layers "F.Cu" "B.Cu")
		(net "M_J_CKE<1>")
	)
	(via
		(at 78.999334 1.152144)
		(size 0.508)
		(drill 0.254)
		(layers "F.Cu" "B.Cu")
		(net "M_J_CKE<1>")
	)
	(segment
		(start 86.416642 -58.370978)
		(end 86.256368 -58.092848)
		(width 0.0889)
		(layer "In2.Cu")
		(net "M_J_CKE<1>")
	)
	(segment
		(start 78.502764 -23.183596)
		(end 78.502764 -22.662896)
		(width 0.14224)
		(layer "In2.Cu")
		(net "M_J_CKE<1>")
	)
	(segment
		(start 86.593426 -60.27674)
		(end 86.411562 -59.962034)
		(width 0.0889)
		(layer "In2.Cu")
		(net "M_J_CKE<1>")
	)
	(segment
		(start 78.502764 -21.710396)
		(end 78.502764 -20.284186)
		(width 0.14224)
		(layer "In2.Cu")
		(net "M_J_CKE<1>")
	)
	(segment
		(start 78.737968 -12.591288)
		(end 78.58252 -12.43584)
		(width 0.14224)
		(layer "In2.Cu")
		(net "M_J_CKE<1>")
	)
	(segment
		(start 86.256368 -58.092848)
		(end 86.256368 -57.6326)
		(width 0.0889)
		(layer "In2.Cu")
		(net "M_J_CKE<1>")
	)
	(segment
		(start 78.560168 -7.36219)
		(end 78.560168 -3.81)
		(width 0.14224)
		(layer "In2.Cu")
		(net "M_J_CKE<1>")
	)
	(segment
		(start 78.58252 -8.486902)
		(end 78.756764 -8.312658)
		(width 0.14224)
		(layer "In2.Cu")
		(net "M_J_CKE<1>")
	)
	(segment
		(start 78.737968 -13.088874)
		(end 78.737968 -12.591288)
		(width 0.14224)
		(layer "In2.Cu")
		(net "M_J_CKE<1>")
	)
	(segment
		(start 78.756764 -23.437596)
		(end 78.502764 -23.183596)
		(width 0.14224)
		(layer "In2.Cu")
		(net "M_J_CKE<1>")
	)
	(segment
		(start 78.566264 -13.260578)
		(end 78.737968 -13.088874)
		(width 0.14224)
		(layer "In2.Cu")
		(net "M_J_CKE<1>")
	)
	(segment
		(start 78.566264 -16.969486)
		(end 78.566264 -13.260578)
		(width 0.14224)
		(layer "In2.Cu")
		(net "M_J_CKE<1>")
	)
	(segment
		(start 78.756764 -7.558786)
		(end 78.560168 -7.36219)
		(width 0.14224)
		(layer "In2.Cu")
		(net "M_J_CKE<1>")
	)
	(segment
		(start 78.756764 -17.159986)
		(end 78.566264 -16.969486)
		(width 0.14224)
		(layer "In2.Cu")
		(net "M_J_CKE<1>")
	)
	(segment
		(start 78.502764 -22.662896)
		(end 78.756764 -22.408896)
		(width 0.14224)
		(layer "In2.Cu")
		(net "M_J_CKE<1>")
	)
	(segment
		(start 78.756764 -8.312658)
		(end 78.756764 -7.558786)
		(width 0.14224)
		(layer "In2.Cu")
		(net "M_J_CKE<1>")
	)
	(segment
		(start 85.664548 -51.39182)
		(end 85.979762 -51.076606)
		(width 0.0889)
		(layer "In2.Cu")
		(net "M_J_CKE<1>")
	)
	(segment
		(start 78.756764 -21.964396)
		(end 78.502764 -21.710396)
		(width 0.14224)
		(layer "In2.Cu")
		(net "M_J_CKE<1>")
	)
	(segment
		(start 78.999334 -0.526034)
		(end 78.999334 1.152144)
		(width 0.14224)
		(layer "In2.Cu")
		(net "M_J_CKE<1>")
	)
	(segment
		(start 78.756764 -20.030186)
		(end 78.756764 -17.159986)
		(width 0.14224)
		(layer "In2.Cu")
		(net "M_J_CKE<1>")
	)
	(segment
		(start 78.756764 -24.809196)
		(end 78.756764 -23.437596)
		(width 0.14224)
		(layer "In2.Cu")
		(net "M_J_CKE<1>")
	)
	(segment
		(start 86.464902 -58.592974)
		(end 86.464902 -58.55208)
		(width 0.0889)
		(layer "In2.Cu")
		(net "M_J_CKE<1>")
	)
	(segment
		(start 78.585568 -2.660396)
		(end 78.585568 -0.9398)
		(width 0.14224)
		(layer "In2.Cu")
		(net "M_J_CKE<1>")
	)
	(segment
		(start 80.414368 -27.752294)
		(end 80.414368 -26.4668)
		(width 0.14224)
		(layer "In2.Cu")
		(net "M_J_CKE<1>")
	)
	(segment
		(start 85.664548 -53.605938)
		(end 85.664548 -51.39182)
		(width 0.0889)
		(layer "In2.Cu")
		(net "M_J_CKE<1>")
	)
	(segment
		(start 86.463886 -58.59399)
		(end 86.464902 -58.592974)
		(width 0.0889)
		(layer "In2.Cu")
		(net "M_J_CKE<1>")
	)
	(segment
		(start 78.737968 -3.6322)
		(end 78.737968 -2.812796)
		(width 0.14224)
		(layer "In2.Cu")
		(net "M_J_CKE<1>")
	)
	(segment
		(start 86.256368 -57.6326)
		(end 85.79739 -57.173622)
		(width 0.0889)
		(layer "In2.Cu")
		(net "M_J_CKE<1>")
	)
	(segment
		(start 86.923372 -61.038486)
		(end 86.593426 -60.27674)
		(width 0.0889)
		(layer "In2.Cu")
		(net "M_J_CKE<1>")
	)
	(segment
		(start 78.560168 -3.81)
		(end 78.737968 -3.6322)
		(width 0.14224)
		(layer "In2.Cu")
		(net "M_J_CKE<1>")
	)
	(segment
		(start 86.411562 -59.752738)
		(end 86.416388 -59.744102)
		(width 0.0889)
		(layer "In2.Cu")
		(net "M_J_CKE<1>")
	)
	(segment
		(start 78.585568 -0.9398)
		(end 78.999334 -0.526034)
		(width 0.14224)
		(layer "In2.Cu")
		(net "M_J_CKE<1>")
	)
	(segment
		(start 78.756764 -22.408896)
		(end 78.756764 -21.964396)
		(width 0.14224)
		(layer "In2.Cu")
		(net "M_J_CKE<1>")
	)
	(segment
		(start 78.502764 -20.284186)
		(end 78.756764 -20.030186)
		(width 0.14224)
		(layer "In2.Cu")
		(net "M_J_CKE<1>")
	)
	(segment
		(start 85.979762 -49.235868)
		(end 85.667342 -48.923448)
		(width 0.0889)
		(layer "In2.Cu")
		(net "M_J_CKE<1>")
	)
	(segment
		(start 85.667342 -33.005268)
		(end 80.414368 -27.752294)
		(width 0.14224)
		(layer "In2.Cu")
		(net "M_J_CKE<1>")
	)
	(segment
		(start 85.667342 -48.432212)
		(end 85.667342 -33.005268)
		(width 0.14224)
		(layer "In2.Cu")
		(net "M_J_CKE<1>")
	)
	(segment
		(start 78.58252 -12.43584)
		(end 78.58252 -8.486902)
		(width 0.14224)
		(layer "In2.Cu")
		(net "M_J_CKE<1>")
	)
	(segment
		(start 85.79739 -57.173622)
		(end 85.79739 -57.0738)
		(width 0.0889)
		(layer "In2.Cu")
		(net "M_J_CKE<1>")
	)
	(segment
		(start 78.737968 -2.812796)
		(end 78.585568 -2.660396)
		(width 0.14224)
		(layer "In2.Cu")
		(net "M_J_CKE<1>")
	)
	(segment
		(start 85.979762 -51.076606)
		(end 85.979762 -49.235868)
		(width 0.0889)
		(layer "In2.Cu")
		(net "M_J_CKE<1>")
	)
	(segment
		(start 85.667342 -48.923448)
		(end 85.667342 -48.432212)
		(width 0.0889)
		(layer "In2.Cu")
		(net "M_J_CKE<1>")
	)
	(segment
		(start 80.414368 -26.4668)
		(end 78.756764 -24.809196)
		(width 0.14224)
		(layer "In2.Cu")
		(net "M_J_CKE<1>")
	)
	(arc
		(start 85.718142 -55.790592)
		(mid 85.664643 -55.590694)
		(end 85.718142 -55.390796)
		(width 0.0889)
		(layer "In2.Cu")
		(net "M_J_CKE<1>")
	)
	(arc
		(start 85.79739 -57.0738)
		(mid 85.776843 -56.922329)
		(end 85.718142 -56.781192)
		(width 0.0889)
		(layer "In2.Cu")
		(net "M_J_CKE<1>")
	)
	(arc
		(start 85.718142 -56.381396)
		(mid 85.797273 -56.085994)
		(end 85.718142 -55.790592)
		(width 0.0889)
		(layer "In2.Cu")
		(net "M_J_CKE<1>")
	)
	(arc
		(start 86.411562 -59.962034)
		(mid 86.383535 -59.857386)
		(end 86.411562 -59.752738)
		(width 0.0889)
		(layer "In2.Cu")
		(net "M_J_CKE<1>")
	)
	(arc
		(start 85.718142 -53.809392)
		(mid 85.677731 -53.71125)
		(end 85.664548 -53.605938)
		(width 0.0889)
		(layer "In2.Cu")
		(net "M_J_CKE<1>")
	)
	(arc
		(start 85.718142 -56.781192)
		(mid 85.664643 -56.581294)
		(end 85.718142 -56.381396)
		(width 0.0889)
		(layer "In2.Cu")
		(net "M_J_CKE<1>")
	)
	(arc
		(start 85.718142 -54.799992)
		(mid 85.664643 -54.600094)
		(end 85.718142 -54.400196)
		(width 0.0889)
		(layer "In2.Cu")
		(net "M_J_CKE<1>")
	)
	(arc
		(start 86.411562 -58.761884)
		(mid 86.447057 -58.680846)
		(end 86.463886 -58.59399)
		(width 0.0889)
		(layer "In2.Cu")
		(net "M_J_CKE<1>")
	)
	(arc
		(start 85.718142 -54.400196)
		(mid 85.797273 -54.104794)
		(end 85.718142 -53.809392)
		(width 0.0889)
		(layer "In2.Cu")
		(net "M_J_CKE<1>")
	)
	(arc
		(start 86.464902 -58.55208)
		(mid 86.451526 -58.458662)
		(end 86.416642 -58.370978)
		(width 0.0889)
		(layer "In2.Cu")
		(net "M_J_CKE<1>")
	)
	(arc
		(start 85.718142 -55.390796)
		(mid 85.797273 -55.095394)
		(end 85.718142 -54.799992)
		(width 0.0889)
		(layer "In2.Cu")
		(net "M_J_CKE<1>")
	)
	(arc
		(start 86.416388 -59.744102)
		(mid 86.465143 -59.54775)
		(end 86.411562 -59.352688)
		(width 0.0889)
		(layer "In2.Cu")
		(net "M_J_CKE<1>")
	)
	(arc
		(start 86.411562 -59.352688)
		(mid 86.332431 -59.057286)
		(end 86.411562 -58.761884)
		(width 0.0889)
		(layer "In2.Cu")
		(net "M_J_CKE<1>")
	)
	(segment
		(start 79.849472 3.778758)
		(end 79.849472 1.805432)
		(width 0.1651)
		(layer "F.Cu")
		(net "M_J_CKE<0>")
	)
	(segment
		(start 88.353392 -59.55284)
		(end 87.781892 -59.55284)
		(width 0.1016)
		(layer "F.Cu")
		(net "M_J_CKE<0>")
	)
	(via
		(at 87.781892 -59.55284)
		(size 0.508)
		(drill 0.254)
		(layers "F.Cu" "B.Cu")
		(net "M_J_CKE<0>")
	)
	(via
		(at 79.849472 1.805432)
		(size 0.508)
		(drill 0.254)
		(layers "F.Cu" "B.Cu")
		(net "M_J_CKE<0>")
	)
	(segment
		(start 79.849472 1.199896)
		(end 79.849472 1.805432)
		(width 0.14224)
		(layer "In2.Cu")
		(net "M_J_CKE<0>")
	)
	(segment
		(start 81.195164 -23.107396)
		(end 81.195164 -22.599396)
		(width 0.14224)
		(layer "In2.Cu")
		(net "M_J_CKE<0>")
	)
	(segment
		(start 81.139284 -6.715506)
		(end 80.8736 -6.449822)
		(width 0.14224)
		(layer "In2.Cu")
		(net "M_J_CKE<0>")
	)
	(segment
		(start 80.261968 -2.807462)
		(end 80.29067 -2.77876)
		(width 0.14224)
		(layer "In2.Cu")
		(net "M_J_CKE<0>")
	)
	(segment
		(start 87.270082 -54.894988)
		(end 87.263732 -54.88432)
		(width 0.0889)
		(layer "In2.Cu")
		(net "M_J_CKE<0>")
	)
	(segment
		(start 81.042764 -22.446996)
		(end 81.042764 -21.888196)
		(width 0.14224)
		(layer "In2.Cu")
		(net "M_J_CKE<0>")
	)
	(segment
		(start 87.781892 -59.55284)
		(end 87.771732 -59.551316)
		(width 0.0889)
		(layer "In2.Cu")
		(net "M_J_CKE<0>")
	)
	(segment
		(start 81.112868 -8.809482)
		(end 80.991964 -8.688578)
		(width 0.14224)
		(layer "In2.Cu")
		(net "M_J_CKE<0>")
	)
	(segment
		(start 81.938368 -25.7048)
		(end 80.896968 -24.6634)
		(width 0.14224)
		(layer "In2.Cu")
		(net "M_J_CKE<0>")
	)
	(segment
		(start 87.191342 -50.972974)
		(end 87.191342 -32.261048)
		(width 0.14224)
		(layer "In2.Cu")
		(net "M_J_CKE<0>")
	)
	(segment
		(start 87.263732 -52.333906)
		(end 87.270082 -52.323238)
		(width 0.0889)
		(layer "In2.Cu")
		(net "M_J_CKE<0>")
	)
	(segment
		(start 87.270082 -51.923188)
		(end 87.191342 -51.782472)
		(width 0.0889)
		(layer "In2.Cu")
		(net "M_J_CKE<0>")
	)
	(segment
		(start 81.141824 -13.468096)
		(end 81.112868 -13.43914)
		(width 0.14224)
		(layer "In2.Cu")
		(net "M_J_CKE<0>")
	)
	(segment
		(start 81.139284 -7.462266)
		(end 81.139284 -6.715506)
		(width 0.14224)
		(layer "In2.Cu")
		(net "M_J_CKE<0>")
	)
	(segment
		(start 87.191342 -51.782472)
		(end 87.191342 -50.972974)
		(width 0.0889)
		(layer "In2.Cu")
		(net "M_J_CKE<0>")
	)
	(segment
		(start 80.29067 -2.77876)
		(end 80.29067 0.758698)
		(width 0.14224)
		(layer "In2.Cu")
		(net "M_J_CKE<0>")
	)
	(segment
		(start 80.29067 0.758698)
		(end 79.849472 1.199896)
		(width 0.14224)
		(layer "In2.Cu")
		(net "M_J_CKE<0>")
	)
	(segment
		(start 81.049368 -17.153382)
		(end 81.141824 -17.060926)
		(width 0.14224)
		(layer "In2.Cu")
		(net "M_J_CKE<0>")
	)
	(segment
		(start 87.274908 -54.903624)
		(end 87.270082 -54.894988)
		(width 0.0889)
		(layer "In2.Cu")
		(net "M_J_CKE<0>")
	)
	(segment
		(start 87.270082 -56.876188)
		(end 87.263732 -56.86552)
		(width 0.0889)
		(layer "In2.Cu")
		(net "M_J_CKE<0>")
	)
	(segment
		(start 80.991964 -7.609586)
		(end 81.139284 -7.462266)
		(width 0.14224)
		(layer "In2.Cu")
		(net "M_J_CKE<0>")
	)
	(segment
		(start 81.110074 -17.684496)
		(end 81.049368 -17.62379)
		(width 0.14224)
		(layer "In2.Cu")
		(net "M_J_CKE<0>")
	)
	(segment
		(start 87.31758 -58.940192)
		(end 87.270082 -58.857388)
		(width 0.0889)
		(layer "In2.Cu")
		(net "M_J_CKE<0>")
	)
	(segment
		(start 87.270082 -53.904388)
		(end 87.263732 -53.89372)
		(width 0.0889)
		(layer "In2.Cu")
		(net "M_J_CKE<0>")
	)
	(segment
		(start 80.8736 -5.132578)
		(end 80.261968 -4.520946)
		(width 0.14224)
		(layer "In2.Cu")
		(net "M_J_CKE<0>")
	)
	(segment
		(start 81.049368 -17.62379)
		(end 81.049368 -17.153382)
		(width 0.14224)
		(layer "In2.Cu")
		(net "M_J_CKE<0>")
	)
	(segment
		(start 80.896968 -24.6634)
		(end 80.896968 -23.405592)
		(width 0.14224)
		(layer "In2.Cu")
		(net "M_J_CKE<0>")
	)
	(segment
		(start 81.195164 -21.278596)
		(end 81.110074 -21.193506)
		(width 0.14224)
		(layer "In2.Cu")
		(net "M_J_CKE<0>")
	)
	(segment
		(start 81.195164 -21.735796)
		(end 81.195164 -21.278596)
		(width 0.14224)
		(layer "In2.Cu")
		(net "M_J_CKE<0>")
	)
	(segment
		(start 81.141824 -17.060926)
		(end 81.141824 -13.468096)
		(width 0.14224)
		(layer "In2.Cu")
		(net "M_J_CKE<0>")
	)
	(segment
		(start 87.270082 -55.885588)
		(end 87.263732 -55.87492)
		(width 0.0889)
		(layer "In2.Cu")
		(net "M_J_CKE<0>")
	)
	(segment
		(start 80.8736 -6.449822)
		(end 80.8736 -5.132578)
		(width 0.14224)
		(layer "In2.Cu")
		(net "M_J_CKE<0>")
	)
	(segment
		(start 81.112868 -13.43914)
		(end 81.112868 -8.809482)
		(width 0.14224)
		(layer "In2.Cu")
		(net "M_J_CKE<0>")
	)
	(segment
		(start 81.042764 -21.888196)
		(end 81.195164 -21.735796)
		(width 0.14224)
		(layer "In2.Cu")
		(net "M_J_CKE<0>")
	)
	(segment
		(start 87.274908 -56.884824)
		(end 87.270082 -56.876188)
		(width 0.0889)
		(layer "In2.Cu")
		(net "M_J_CKE<0>")
	)
	(segment
		(start 80.896968 -23.405592)
		(end 81.195164 -23.107396)
		(width 0.14224)
		(layer "In2.Cu")
		(net "M_J_CKE<0>")
	)
	(segment
		(start 81.195164 -22.599396)
		(end 81.042764 -22.446996)
		(width 0.14224)
		(layer "In2.Cu")
		(net "M_J_CKE<0>")
	)
	(segment
		(start 87.263732 -58.277506)
		(end 87.270082 -58.266838)
		(width 0.0889)
		(layer "In2.Cu")
		(net "M_J_CKE<0>")
	)
	(segment
		(start 80.261968 -4.520946)
		(end 80.261968 -2.807462)
		(width 0.14224)
		(layer "In2.Cu")
		(net "M_J_CKE<0>")
	)
	(segment
		(start 87.771732 -59.551316)
		(end 87.31758 -58.940192)
		(width 0.0889)
		(layer "In2.Cu")
		(net "M_J_CKE<0>")
	)
	(segment
		(start 87.191342 -32.261048)
		(end 81.938368 -27.008074)
		(width 0.14224)
		(layer "In2.Cu")
		(net "M_J_CKE<0>")
	)
	(segment
		(start 87.274908 -55.894224)
		(end 87.270082 -55.885588)
		(width 0.0889)
		(layer "In2.Cu")
		(net "M_J_CKE<0>")
	)
	(segment
		(start 81.938368 -27.008074)
		(end 81.938368 -25.7048)
		(width 0.14224)
		(layer "In2.Cu")
		(net "M_J_CKE<0>")
	)
	(segment
		(start 81.110074 -21.193506)
		(end 81.110074 -17.684496)
		(width 0.14224)
		(layer "In2.Cu")
		(net "M_J_CKE<0>")
	)
	(segment
		(start 87.274908 -52.922424)
		(end 87.270082 -52.913788)
		(width 0.0889)
		(layer "In2.Cu")
		(net "M_J_CKE<0>")
	)
	(segment
		(start 80.991964 -8.688578)
		(end 80.991964 -7.609586)
		(width 0.14224)
		(layer "In2.Cu")
		(net "M_J_CKE<0>")
	)
	(segment
		(start 87.274908 -53.913024)
		(end 87.270082 -53.904388)
		(width 0.0889)
		(layer "In2.Cu")
		(net "M_J_CKE<0>")
	)
	(arc
		(start 87.270082 -58.266838)
		(mid 87.323581 -58.06694)
		(end 87.270082 -57.867042)
		(width 0.0889)
		(layer "In2.Cu")
		(net "M_J_CKE<0>")
	)
	(arc
		(start 87.270082 -52.323238)
		(mid 87.323581 -52.12323)
		(end 87.270082 -51.923188)
		(width 0.0889)
		(layer "In2.Cu")
		(net "M_J_CKE<0>")
	)
	(arc
		(start 87.270082 -56.285638)
		(mid 87.323552 -56.090575)
		(end 87.274908 -55.894224)
		(width 0.0889)
		(layer "In2.Cu")
		(net "M_J_CKE<0>")
	)
	(arc
		(start 87.270082 -57.276238)
		(mid 87.323552 -57.081175)
		(end 87.274908 -56.884824)
		(width 0.0889)
		(layer "In2.Cu")
		(net "M_J_CKE<0>")
	)
	(arc
		(start 87.270082 -55.295038)
		(mid 87.323552 -55.099975)
		(end 87.274908 -54.903624)
		(width 0.0889)
		(layer "In2.Cu")
		(net "M_J_CKE<0>")
	)
	(arc
		(start 87.270082 -53.313838)
		(mid 87.323552 -53.118775)
		(end 87.274908 -52.922424)
		(width 0.0889)
		(layer "In2.Cu")
		(net "M_J_CKE<0>")
	)
	(arc
		(start 87.270082 -54.304438)
		(mid 87.323552 -54.109375)
		(end 87.274908 -53.913024)
		(width 0.0889)
		(layer "In2.Cu")
		(net "M_J_CKE<0>")
	)
	(arc
		(start 87.263732 -56.86552)
		(mid 87.190934 -56.574757)
		(end 87.270082 -56.285638)
		(width 0.0889)
		(layer "In2.Cu")
		(net "M_J_CKE<0>")
	)
	(arc
		(start 87.263732 -53.89372)
		(mid 87.190934 -53.602957)
		(end 87.270082 -53.313838)
		(width 0.0889)
		(layer "In2.Cu")
		(net "M_J_CKE<0>")
	)
	(arc
		(start 87.263732 -55.87492)
		(mid 87.190934 -55.584157)
		(end 87.270082 -55.295038)
		(width 0.0889)
		(layer "In2.Cu")
		(net "M_J_CKE<0>")
	)
	(arc
		(start 87.270082 -57.867042)
		(mid 87.190951 -57.57164)
		(end 87.270082 -57.276238)
		(width 0.0889)
		(layer "In2.Cu")
		(net "M_J_CKE<0>")
	)
	(arc
		(start 87.270082 -58.857388)
		(mid 87.19086 -58.56827)
		(end 87.263732 -58.277506)
		(width 0.0889)
		(layer "In2.Cu")
		(net "M_J_CKE<0>")
	)
	(arc
		(start 87.270082 -52.913788)
		(mid 87.19086 -52.62467)
		(end 87.263732 -52.333906)
		(width 0.0889)
		(layer "In2.Cu")
		(net "M_J_CKE<0>")
	)
	(arc
		(start 87.263732 -54.88432)
		(mid 87.190934 -54.593557)
		(end 87.270082 -54.304438)
		(width 0.0889)
		(layer "In2.Cu")
		(net "M_J_CKE<0>")
	)
	(segment
		(start 102.947724 -60.047886)
		(end 103.557324 -60.047886)
		(width 0.1016)
		(layer "F.Cu")
		(net "M_J_C<2>")
	)
	(segment
		(start 111.299498 -0.821182)
		(end 111.299498 1.152144)
		(width 0.1651)
		(layer "F.Cu")
		(net "M_J_C<2>")
	)
	(via
		(at 103.557324 -60.047886)
		(size 0.508)
		(drill 0.254)
		(layers "F.Cu" "B.Cu")
		(net "M_J_C<2>")
	)
	(via
		(at 111.299498 1.152144)
		(size 0.508)
		(drill 0.254)
		(layers "F.Cu" "B.Cu")
		(net "M_J_C<2>")
	)
	(via
		(at 111.299498 -2.31648)
		(size 0.4572)
		(drill 0.2032)
		(layers "F.Cu" "B.Cu")
		(net "M_J_C<2>")
	)
	(segment
		(start 111.299498 -2.31648)
		(end 111.299498 -1.021842)
		(width 0.1651)
		(layer "B.Cu")
		(net "M_J_C<2>")
	)
	(segment
		(start 112.007396 -4.837938)
		(end 111.707168 -4.53771)
		(width 0.14224)
		(layer "In11.Cu")
		(net "M_J_C<2>")
	)
	(segment
		(start 113.45672 -25.961848)
		(end 113.45672 -21.745448)
		(width 0.14224)
		(layer "In11.Cu")
		(net "M_J_C<2>")
	)
	(segment
		(start 113.25225 -27.072082)
		(end 113.078768 -26.8986)
		(width 0.14224)
		(layer "In11.Cu")
		(net "M_J_C<2>")
	)
	(segment
		(start 113.459768 -21.7424)
		(end 113.459768 -9.4742)
		(width 0.14224)
		(layer "In11.Cu")
		(net "M_J_C<2>")
	)
	(segment
		(start 111.300006 -2.316988)
		(end 111.299498 -2.317496)
		(width 0.14224)
		(layer "In11.Cu")
		(net "M_J_C<2>")
	)
	(segment
		(start 112.648746 -4.837938)
		(end 112.007396 -4.837938)
		(width 0.14224)
		(layer "In11.Cu")
		(net "M_J_C<2>")
	)
	(segment
		(start 111.707168 -3.24358)
		(end 111.299498 -2.83591)
		(width 0.14224)
		(layer "In11.Cu")
		(net "M_J_C<2>")
	)
	(segment
		(start 105.017316 -35.976052)
		(end 113.25225 -27.741118)
		(width 0.14224)
		(layer "In11.Cu")
		(net "M_J_C<2>")
	)
	(segment
		(start 112.590072 -7.359904)
		(end 112.590072 -6.919722)
		(width 0.14224)
		(layer "In11.Cu")
		(net "M_J_C<2>")
	)
	(segment
		(start 105.017316 -49.590452)
		(end 105.017316 -35.976052)
		(width 0.14224)
		(layer "In11.Cu")
		(net "M_J_C<2>")
	)
	(segment
		(start 111.707168 -4.53771)
		(end 111.707168 -3.24358)
		(width 0.14224)
		(layer "In11.Cu")
		(net "M_J_C<2>")
	)
	(segment
		(start 113.459768 -9.4742)
		(end 113.411 -9.425432)
		(width 0.14224)
		(layer "In11.Cu")
		(net "M_J_C<2>")
	)
	(segment
		(start 113.411 -8.180832)
		(end 112.590072 -7.359904)
		(width 0.14224)
		(layer "In11.Cu")
		(net "M_J_C<2>")
	)
	(segment
		(start 113.45672 -21.745448)
		(end 113.459768 -21.7424)
		(width 0.14224)
		(layer "In11.Cu")
		(net "M_J_C<2>")
	)
	(segment
		(start 112.800384 -5.472176)
		(end 112.800384 -4.989576)
		(width 0.14224)
		(layer "In11.Cu")
		(net "M_J_C<2>")
	)
	(segment
		(start 112.590072 -6.919722)
		(end 112.34293 -6.67258)
		(width 0.14224)
		(layer "In11.Cu")
		(net "M_J_C<2>")
	)
	(segment
		(start 112.34293 -5.92963)
		(end 112.800384 -5.472176)
		(width 0.14224)
		(layer "In11.Cu")
		(net "M_J_C<2>")
	)
	(segment
		(start 111.299498 -2.317496)
		(end 111.299498 -2.31648)
		(width 0.14224)
		(layer "In11.Cu")
		(net "M_J_C<2>")
	)
	(segment
		(start 113.078768 -26.3398)
		(end 113.45672 -25.961848)
		(width 0.14224)
		(layer "In11.Cu")
		(net "M_J_C<2>")
	)
	(segment
		(start 113.078768 -26.8986)
		(end 113.078768 -26.3398)
		(width 0.14224)
		(layer "In11.Cu")
		(net "M_J_C<2>")
	)
	(segment
		(start 113.411 -9.425432)
		(end 113.411 -8.180832)
		(width 0.14224)
		(layer "In11.Cu")
		(net "M_J_C<2>")
	)
	(segment
		(start 112.34293 -6.67258)
		(end 112.34293 -5.92963)
		(width 0.14224)
		(layer "In11.Cu")
		(net "M_J_C<2>")
	)
	(segment
		(start 103.557324 -60.047886)
		(end 102.907592 -59.398154)
		(width 0.14224)
		(layer "In11.Cu")
		(net "M_J_C<2>")
	)
	(segment
		(start 102.907592 -53.07203)
		(end 103.960168 -52.019454)
		(width 0.14224)
		(layer "In11.Cu")
		(net "M_J_C<2>")
	)
	(segment
		(start 111.299498 1.152144)
		(end 111.300006 1.151636)
		(width 0.14224)
		(layer "In11.Cu")
		(net "M_J_C<2>")
	)
	(segment
		(start 103.960168 -50.6476)
		(end 105.017316 -49.590452)
		(width 0.14224)
		(layer "In11.Cu")
		(net "M_J_C<2>")
	)
	(segment
		(start 102.907592 -59.398154)
		(end 102.907592 -53.07203)
		(width 0.14224)
		(layer "In11.Cu")
		(net "M_J_C<2>")
	)
	(segment
		(start 113.25225 -27.741118)
		(end 113.25225 -27.072082)
		(width 0.15494)
		(layer "In11.Cu")
		(net "M_J_C<2>")
	)
	(segment
		(start 111.299498 -2.83591)
		(end 111.299498 -2.317496)
		(width 0.14224)
		(layer "In11.Cu")
		(net "M_J_C<2>")
	)
	(segment
		(start 111.300006 1.151636)
		(end 111.300006 -2.316988)
		(width 0.14224)
		(layer "In11.Cu")
		(net "M_J_C<2>")
	)
	(segment
		(start 103.960168 -52.019454)
		(end 103.960168 -50.6476)
		(width 0.14224)
		(layer "In11.Cu")
		(net "M_J_C<2>")
	)
	(segment
		(start 112.800384 -4.989576)
		(end 112.648746 -4.837938)
		(width 0.14224)
		(layer "In11.Cu")
		(net "M_J_C<2>")
	)
	(segment
		(start 88.353392 -61.53404)
		(end 87.781892 -61.53404)
		(width 0.1016)
		(layer "F.Cu")
		(net "M_J_BG<1>")
	)
	(segment
		(start 82.399378 -0.821182)
		(end 82.399378 1.152144)
		(width 0.1651)
		(layer "F.Cu")
		(net "M_J_BG<1>")
	)
	(via
		(at 87.781892 -61.53404)
		(size 0.508)
		(drill 0.254)
		(layers "F.Cu" "B.Cu")
		(net "M_J_BG<1>")
	)
	(via
		(at 82.399378 -2.314956)
		(size 0.4572)
		(drill 0.2032)
		(layers "F.Cu" "B.Cu")
		(net "M_J_BG<1>")
	)
	(via
		(at 82.399378 1.152144)
		(size 0.508)
		(drill 0.254)
		(layers "F.Cu" "B.Cu")
		(net "M_J_BG<1>")
	)
	(segment
		(start 82.399378 -1.021842)
		(end 82.399378 -2.314956)
		(width 0.1651)
		(layer "B.Cu")
		(net "M_J_BG<1>")
	)
	(segment
		(start 90.749882 -59.23661)
		(end 90.527886 -59.458606)
		(width 0.0889)
		(layer "In11.Cu")
		(net "M_J_BG<1>")
	)
	(segment
		(start 90.815414 -54.604666)
		(end 90.815414 -58.88482)
		(width 0.0889)
		(layer "In11.Cu")
		(net "M_J_BG<1>")
	)
	(segment
		(start 87.091266 -10.064242)
		(end 86.624668 -10.53084)
		(width 0.14224)
		(layer "In11.Cu")
		(net "M_J_BG<1>")
	)
	(segment
		(start 91.190572 -26.323036)
		(end 91.393772 -26.526236)
		(width 0.14224)
		(layer "In11.Cu")
		(net "M_J_BG<1>")
	)
	(segment
		(start 85.976968 -6.6548)
		(end 86.239858 -6.91769)
		(width 0.14224)
		(layer "In11.Cu")
		(net "M_J_BG<1>")
	)
	(segment
		(start 89.64549 -23.027132)
		(end 89.51595 -23.156672)
		(width 0.14224)
		(layer "In11.Cu")
		(net "M_J_BG<1>")
	)
	(segment
		(start 86.239858 -7.80669)
		(end 87.091266 -8.658098)
		(width 0.14224)
		(layer "In11.Cu")
		(net "M_J_BG<1>")
	)
	(segment
		(start 88.293702 -60.838588)
		(end 88.276938 -60.868052)
		(width 0.0889)
		(layer "In11.Cu")
		(net "M_J_BG<1>")
	)
	(segment
		(start 89.928446 -28.10637)
		(end 90.387678 -28.10637)
		(width 0.14224)
		(layer "In11.Cu")
		(net "M_J_BG<1>")
	)
	(segment
		(start 89.634568 -15.23746)
		(end 89.634568 -17.730216)
		(width 0.14224)
		(layer "In11.Cu")
		(net "M_J_BG<1>")
	)
	(segment
		(start 83.563968 -5.756148)
		(end 83.563968 -6.4516)
		(width 0.14224)
		(layer "In11.Cu")
		(net "M_J_BG<1>")
	)
	(segment
		(start 90.864182 -53.800502)
		(end 90.869008 -53.809138)
		(width 0.0889)
		(layer "In11.Cu")
		(net "M_J_BG<1>")
	)
	(segment
		(start 90.599768 -18.695416)
		(end 90.599768 -20.310602)
		(width 0.14224)
		(layer "In11.Cu")
		(net "M_J_BG<1>")
	)
	(segment
		(start 90.406982 -59.535822)
		(end 88.439244 -60.692538)
		(width 0.0889)
		(layer "In11.Cu")
		(net "M_J_BG<1>")
	)
	(segment
		(start 83.563968 -6.4516)
		(end 83.767168 -6.6548)
		(width 0.14224)
		(layer "In11.Cu")
		(net "M_J_BG<1>")
	)
	(segment
		(start 86.624668 -10.53084)
		(end 86.624668 -10.96772)
		(width 0.14224)
		(layer "In11.Cu")
		(net "M_J_BG<1>")
	)
	(segment
		(start 87.086948 -12.15898)
		(end 88.161368 -13.2334)
		(width 0.14224)
		(layer "In11.Cu")
		(net "M_J_BG<1>")
	)
	(segment
		(start 88.161368 -13.2334)
		(end 88.598248 -13.2334)
		(width 0.14224)
		(layer "In11.Cu")
		(net "M_J_BG<1>")
	)
	(segment
		(start 87.091266 -8.658098)
		(end 87.091266 -10.064242)
		(width 0.14224)
		(layer "In11.Cu")
		(net "M_J_BG<1>")
	)
	(segment
		(start 90.527886 -59.458606)
		(end 90.406982 -59.535822)
		(width 0.0889)
		(layer "In11.Cu")
		(net "M_J_BG<1>")
	)
	(segment
		(start 89.634568 -17.730216)
		(end 90.599768 -18.695416)
		(width 0.14224)
		(layer "In11.Cu")
		(net "M_J_BG<1>")
	)
	(segment
		(start 82.816446 -2.732024)
		(end 82.816446 -5.008626)
		(width 0.14224)
		(layer "In11.Cu")
		(net "M_J_BG<1>")
	)
	(segment
		(start 86.239858 -6.91769)
		(end 86.239858 -7.80669)
		(width 0.14224)
		(layer "In11.Cu")
		(net "M_J_BG<1>")
	)
	(segment
		(start 91.393772 -26.526236)
		(end 91.393772 -50.562256)
		(width 0.14224)
		(layer "In11.Cu")
		(net "M_J_BG<1>")
	)
	(segment
		(start 90.580972 -26.526236)
		(end 90.784172 -26.323036)
		(width 0.14224)
		(layer "In11.Cu")
		(net "M_J_BG<1>")
	)
	(segment
		(start 89.768172 -27.946096)
		(end 89.928446 -28.10637)
		(width 0.14224)
		(layer "In11.Cu")
		(net "M_J_BG<1>")
	)
	(segment
		(start 88.598248 -13.2334)
		(end 88.791288 -13.42644)
		(width 0.14224)
		(layer "In11.Cu")
		(net "M_J_BG<1>")
	)
	(segment
		(start 89.51595 -25.510236)
		(end 89.768172 -25.762458)
		(width 0.14224)
		(layer "In11.Cu")
		(net "M_J_BG<1>")
	)
	(segment
		(start 90.387678 -28.10637)
		(end 90.580972 -27.913076)
		(width 0.14224)
		(layer "In11.Cu")
		(net "M_J_BG<1>")
	)
	(segment
		(start 90.580972 -27.913076)
		(end 90.580972 -26.526236)
		(width 0.14224)
		(layer "In11.Cu")
		(net "M_J_BG<1>")
	)
	(segment
		(start 89.51595 -23.156672)
		(end 89.51595 -25.510236)
		(width 0.14224)
		(layer "In11.Cu")
		(net "M_J_BG<1>")
	)
	(segment
		(start 90.599768 -20.310602)
		(end 89.698576 -21.211794)
		(width 0.14224)
		(layer "In11.Cu")
		(net "M_J_BG<1>")
	)
	(segment
		(start 89.698576 -21.211794)
		(end 89.698576 -21.777706)
		(width 0.14224)
		(layer "In11.Cu")
		(net "M_J_BG<1>")
	)
	(segment
		(start 89.569036 -21.907246)
		(end 89.569036 -22.372828)
		(width 0.14224)
		(layer "In11.Cu")
		(net "M_J_BG<1>")
	)
	(segment
		(start 88.276938 -60.868052)
		(end 87.781892 -61.53404)
		(width 0.0889)
		(layer "In11.Cu")
		(net "M_J_BG<1>")
	)
	(segment
		(start 89.768172 -25.762458)
		(end 89.768172 -27.946096)
		(width 0.14224)
		(layer "In11.Cu")
		(net "M_J_BG<1>")
	)
	(segment
		(start 82.399378 -2.314956)
		(end 82.816446 -2.732024)
		(width 0.14224)
		(layer "In11.Cu")
		(net "M_J_BG<1>")
	)
	(segment
		(start 86.624668 -10.96772)
		(end 87.086948 -11.43)
		(width 0.14224)
		(layer "In11.Cu")
		(net "M_J_BG<1>")
	)
	(segment
		(start 89.698576 -21.777706)
		(end 89.569036 -21.907246)
		(width 0.14224)
		(layer "In11.Cu")
		(net "M_J_BG<1>")
	)
	(segment
		(start 91.203272 -52.02682)
		(end 91.203272 -52.864512)
		(width 0.0889)
		(layer "In11.Cu")
		(net "M_J_BG<1>")
	)
	(segment
		(start 90.815414 -58.88482)
		(end 90.749882 -59.23661)
		(width 0.0889)
		(layer "In11.Cu")
		(net "M_J_BG<1>")
	)
	(segment
		(start 91.393772 -51.201574)
		(end 91.203272 -52.02682)
		(width 0.0889)
		(layer "In11.Cu")
		(net "M_J_BG<1>")
	)
	(segment
		(start 82.816446 -5.008626)
		(end 83.563968 -5.756148)
		(width 0.14224)
		(layer "In11.Cu")
		(net "M_J_BG<1>")
	)
	(segment
		(start 88.791288 -13.42644)
		(end 88.791288 -14.39418)
		(width 0.14224)
		(layer "In11.Cu")
		(net "M_J_BG<1>")
	)
	(segment
		(start 82.399378 1.152144)
		(end 82.399378 -2.314956)
		(width 0.14224)
		(layer "In11.Cu")
		(net "M_J_BG<1>")
	)
	(segment
		(start 90.784172 -26.323036)
		(end 91.190572 -26.323036)
		(width 0.14224)
		(layer "In11.Cu")
		(net "M_J_BG<1>")
	)
	(segment
		(start 89.569036 -22.372828)
		(end 89.64549 -22.449282)
		(width 0.14224)
		(layer "In11.Cu")
		(net "M_J_BG<1>")
	)
	(segment
		(start 87.086948 -11.43)
		(end 87.086948 -12.15898)
		(width 0.14224)
		(layer "In11.Cu")
		(net "M_J_BG<1>")
	)
	(segment
		(start 89.64549 -22.449282)
		(end 89.64549 -23.027132)
		(width 0.14224)
		(layer "In11.Cu")
		(net "M_J_BG<1>")
	)
	(segment
		(start 88.791288 -14.39418)
		(end 89.634568 -15.23746)
		(width 0.14224)
		(layer "In11.Cu")
		(net "M_J_BG<1>")
	)
	(segment
		(start 91.203272 -52.864512)
		(end 90.869008 -53.409088)
		(width 0.0889)
		(layer "In11.Cu")
		(net "M_J_BG<1>")
	)
	(segment
		(start 83.767168 -6.6548)
		(end 85.976968 -6.6548)
		(width 0.14224)
		(layer "In11.Cu")
		(net "M_J_BG<1>")
	)
	(segment
		(start 91.393772 -50.562256)
		(end 91.393772 -51.201574)
		(width 0.0889)
		(layer "In11.Cu")
		(net "M_J_BG<1>")
	)
	(segment
		(start 90.869008 -53.809138)
		(end 90.875358 -53.819806)
		(width 0.0889)
		(layer "In11.Cu")
		(net "M_J_BG<1>")
	)
	(arc
		(start 90.875358 -53.819806)
		(mid 90.948156 -54.110569)
		(end 90.869008 -54.399688)
		(width 0.0889)
		(layer "In11.Cu")
		(net "M_J_BG<1>")
	)
	(arc
		(start 88.439244 -60.692538)
		(mid 88.356915 -60.756036)
		(end 88.293702 -60.838588)
		(width 0.0889)
		(layer "In11.Cu")
		(net "M_J_BG<1>")
	)
	(arc
		(start 90.869008 -53.409088)
		(mid 90.815538 -53.604151)
		(end 90.864182 -53.800502)
		(width 0.0889)
		(layer "In11.Cu")
		(net "M_J_BG<1>")
	)
	(arc
		(start 90.869008 -54.399688)
		(mid 90.828404 -54.498567)
		(end 90.815414 -54.604666)
		(width 0.0889)
		(layer "In11.Cu")
		(net "M_J_BG<1>")
	)
	(segment
		(start 90.070178 -59.55284)
		(end 89.498678 -59.55284)
		(width 0.1016)
		(layer "F.Cu")
		(net "M_J_BG<0>")
	)
	(segment
		(start 82.399378 3.778758)
		(end 82.399378 2.514854)
		(width 0.1651)
		(layer "F.Cu")
		(net "M_J_BG<0>")
	)
	(via
		(at 89.498678 -59.55284)
		(size 0.508)
		(drill 0.254)
		(layers "F.Cu" "B.Cu")
		(net "M_J_BG<0>")
	)
	(via
		(at 82.399378 2.514854)
		(size 0.508)
		(drill 0.254)
		(layers "F.Cu" "B.Cu")
		(net "M_J_BG<0>")
	)
	(via
		(at 82.399378 -4.332478)
		(size 0.4572)
		(drill 0.2032)
		(layers "F.Cu" "B.Cu")
		(net "M_J_BG<0>")
	)
	(segment
		(start 82.399378 -5.621782)
		(end 82.399378 -4.332478)
		(width 0.1651)
		(layer "B.Cu")
		(net "M_J_BG<0>")
	)
	(segment
		(start 83.579208 -22.66442)
		(end 83.82889 -22.414738)
		(width 0.14224)
		(layer "In2.Cu")
		(net "M_J_BG<0>")
	)
	(segment
		(start 83.82889 -21.985478)
		(end 83.604608 -21.761196)
		(width 0.14224)
		(layer "In2.Cu")
		(net "M_J_BG<0>")
	)
	(segment
		(start 88.293702 -55.885588)
		(end 88.300052 -55.87492)
		(width 0.0889)
		(layer "In2.Cu")
		(net "M_J_BG<0>")
	)
	(segment
		(start 88.288876 -55.894224)
		(end 88.293702 -55.885588)
		(width 0.0889)
		(layer "In2.Cu")
		(net "M_J_BG<0>")
	)
	(segment
		(start 83.523582 -8.69696)
		(end 83.523582 -8.274812)
		(width 0.14224)
		(layer "In2.Cu")
		(net "M_J_BG<0>")
	)
	(segment
		(start 88.293702 -56.876188)
		(end 88.300052 -56.86552)
		(width 0.0889)
		(layer "In2.Cu")
		(net "M_J_BG<0>")
	)
	(segment
		(start 83.757008 -5.690108)
		(end 82.399378 -4.332478)
		(width 0.14224)
		(layer "In2.Cu")
		(net "M_J_BG<0>")
	)
	(segment
		(start 84.732368 -26.92781)
		(end 84.732368 -25.7556)
		(width 0.14224)
		(layer "In2.Cu")
		(net "M_J_BG<0>")
	)
	(segment
		(start 83.663028 -18.529046)
		(end 83.520534 -18.386552)
		(width 0.14224)
		(layer "In2.Cu")
		(net "M_J_BG<0>")
	)
	(segment
		(start 83.816444 -1.044956)
		(end 83.816444 0.560324)
		(width 0.14224)
		(layer "In2.Cu")
		(net "M_J_BG<0>")
	)
	(segment
		(start 88.288876 -53.913024)
		(end 88.293702 -53.904388)
		(width 0.0889)
		(layer "In2.Cu")
		(net "M_J_BG<0>")
	)
	(segment
		(start 83.816698 -12.735306)
		(end 83.816698 -12.372086)
		(width 0.14224)
		(layer "In2.Cu")
		(net "M_J_BG<0>")
	)
	(segment
		(start 83.757008 -24.78024)
		(end 83.757008 -23.285196)
		(width 0.14224)
		(layer "In2.Cu")
		(net "M_J_BG<0>")
	)
	(segment
		(start 88.288876 -54.903624)
		(end 88.293702 -54.894988)
		(width 0.0889)
		(layer "In2.Cu")
		(net "M_J_BG<0>")
	)
	(segment
		(start 83.84413 -17.555464)
		(end 83.84413 -17.07388)
		(width 0.14224)
		(layer "In2.Cu")
		(net "M_J_BG<0>")
	)
	(segment
		(start 83.690968 -7.29615)
		(end 83.690968 -6.735826)
		(width 0.14224)
		(layer "In2.Cu")
		(net "M_J_BG<0>")
	)
	(segment
		(start 83.884008 -7.914386)
		(end 83.884008 -7.48919)
		(width 0.14224)
		(layer "In2.Cu")
		(net "M_J_BG<0>")
	)
	(segment
		(start 83.663028 -19.082766)
		(end 83.663028 -18.529046)
		(width 0.14224)
		(layer "In2.Cu")
		(net "M_J_BG<0>")
	)
	(segment
		(start 82.399378 1.97739)
		(end 82.399378 2.514854)
		(width 0.14224)
		(layer "In2.Cu")
		(net "M_J_BG<0>")
	)
	(segment
		(start 83.816698 -12.372086)
		(end 83.660488 -12.215876)
		(width 0.14224)
		(layer "In2.Cu")
		(net "M_J_BG<0>")
	)
	(segment
		(start 83.520534 -18.386552)
		(end 83.520534 -17.87906)
		(width 0.14224)
		(layer "In2.Cu")
		(net "M_J_BG<0>")
	)
	(segment
		(start 83.520534 -17.87906)
		(end 83.84413 -17.555464)
		(width 0.14224)
		(layer "In2.Cu")
		(net "M_J_BG<0>")
	)
	(segment
		(start 83.508596 -13.043408)
		(end 83.816698 -12.735306)
		(width 0.14224)
		(layer "In2.Cu")
		(net "M_J_BG<0>")
	)
	(segment
		(start 83.816444 0.560324)
		(end 82.399378 1.97739)
		(width 0.14224)
		(layer "In2.Cu")
		(net "M_J_BG<0>")
	)
	(segment
		(start 89.498678 -59.55284)
		(end 89.00287 -58.885328)
		(width 0.0889)
		(layer "In2.Cu")
		(net "M_J_BG<0>")
	)
	(segment
		(start 88.33485 -58.338212)
		(end 88.293702 -58.266838)
		(width 0.0889)
		(layer "In2.Cu")
		(net "M_J_BG<0>")
	)
	(segment
		(start 88.721692 -30.917134)
		(end 84.732368 -26.92781)
		(width 0.14224)
		(layer "In2.Cu")
		(net "M_J_BG<0>")
	)
	(segment
		(start 89.00287 -58.885328)
		(end 88.986868 -58.857388)
		(width 0.0889)
		(layer "In2.Cu")
		(net "M_J_BG<0>")
	)
	(segment
		(start 83.690968 -13.617956)
		(end 83.508596 -13.435584)
		(width 0.14224)
		(layer "In2.Cu")
		(net "M_J_BG<0>")
	)
	(segment
		(start 83.508596 -13.435584)
		(end 83.508596 -13.043408)
		(width 0.14224)
		(layer "In2.Cu")
		(net "M_J_BG<0>")
	)
	(segment
		(start 88.598502 -58.551064)
		(end 88.33485 -58.338212)
		(width 0.0889)
		(layer "In2.Cu")
		(net "M_J_BG<0>")
	)
	(segment
		(start 83.604608 -19.141186)
		(end 83.663028 -19.082766)
		(width 0.14224)
		(layer "In2.Cu")
		(net "M_J_BG<0>")
	)
	(segment
		(start 83.660488 -8.833866)
		(end 83.523582 -8.69696)
		(width 0.14224)
		(layer "In2.Cu")
		(net "M_J_BG<0>")
	)
	(segment
		(start 88.8492 -58.716164)
		(end 88.598502 -58.551064)
		(width 0.0889)
		(layer "In2.Cu")
		(net "M_J_BG<0>")
	)
	(segment
		(start 83.665568 -3.066288)
		(end 83.665568 -1.195832)
		(width 0.14224)
		(layer "In2.Cu")
		(net "M_J_BG<0>")
	)
	(segment
		(start 88.300052 -52.333906)
		(end 88.293702 -52.323238)
		(width 0.0889)
		(layer "In2.Cu")
		(net "M_J_BG<0>")
	)
	(segment
		(start 83.660488 -12.215876)
		(end 83.660488 -8.833866)
		(width 0.14224)
		(layer "In2.Cu")
		(net "M_J_BG<0>")
	)
	(segment
		(start 88.288876 -52.922424)
		(end 88.293702 -52.913788)
		(width 0.0889)
		(layer "In2.Cu")
		(net "M_J_BG<0>")
	)
	(segment
		(start 84.732368 -25.7556)
		(end 83.757008 -24.78024)
		(width 0.14224)
		(layer "In2.Cu")
		(net "M_J_BG<0>")
	)
	(segment
		(start 88.293702 -53.904388)
		(end 88.300052 -53.89372)
		(width 0.0889)
		(layer "In2.Cu")
		(net "M_J_BG<0>")
	)
	(segment
		(start 83.665568 -1.195832)
		(end 83.816444 -1.044956)
		(width 0.14224)
		(layer "In2.Cu")
		(net "M_J_BG<0>")
	)
	(segment
		(start 88.721692 -51.246786)
		(end 88.721692 -51.052476)
		(width 0.0889)
		(layer "In2.Cu")
		(net "M_J_BG<0>")
	)
	(segment
		(start 83.579208 -23.107396)
		(end 83.579208 -22.66442)
		(width 0.14224)
		(layer "In2.Cu")
		(net "M_J_BG<0>")
	)
	(segment
		(start 83.84413 -17.07388)
		(end 83.690968 -16.920718)
		(width 0.14224)
		(layer "In2.Cu")
		(net "M_J_BG<0>")
	)
	(segment
		(start 83.690968 -16.920718)
		(end 83.690968 -13.617956)
		(width 0.14224)
		(layer "In2.Cu")
		(net "M_J_BG<0>")
	)
	(segment
		(start 83.757008 -23.285196)
		(end 83.579208 -23.107396)
		(width 0.14224)
		(layer "In2.Cu")
		(net "M_J_BG<0>")
	)
	(segment
		(start 88.288876 -56.884824)
		(end 88.293702 -56.876188)
		(width 0.0889)
		(layer "In2.Cu")
		(net "M_J_BG<0>")
	)
	(segment
		(start 83.690968 -6.735826)
		(end 83.757008 -6.669786)
		(width 0.14224)
		(layer "In2.Cu")
		(net "M_J_BG<0>")
	)
	(segment
		(start 83.757008 -6.669786)
		(end 83.757008 -5.690108)
		(width 0.14224)
		(layer "In2.Cu")
		(net "M_J_BG<0>")
	)
	(segment
		(start 83.523582 -8.274812)
		(end 83.884008 -7.914386)
		(width 0.14224)
		(layer "In2.Cu")
		(net "M_J_BG<0>")
	)
	(segment
		(start 82.399378 -4.332478)
		(end 83.665568 -3.066288)
		(width 0.14224)
		(layer "In2.Cu")
		(net "M_J_BG<0>")
	)
	(segment
		(start 83.604608 -21.761196)
		(end 83.604608 -19.141186)
		(width 0.14224)
		(layer "In2.Cu")
		(net "M_J_BG<0>")
	)
	(segment
		(start 88.293702 -54.894988)
		(end 88.300052 -54.88432)
		(width 0.0889)
		(layer "In2.Cu")
		(net "M_J_BG<0>")
	)
	(segment
		(start 88.293702 -51.923442)
		(end 88.721692 -51.246786)
		(width 0.0889)
		(layer "In2.Cu")
		(net "M_J_BG<0>")
	)
	(segment
		(start 83.82889 -22.414738)
		(end 83.82889 -21.985478)
		(width 0.14224)
		(layer "In2.Cu")
		(net "M_J_BG<0>")
	)
	(segment
		(start 88.721692 -51.052476)
		(end 88.721692 -30.917134)
		(width 0.14224)
		(layer "In2.Cu")
		(net "M_J_BG<0>")
	)
	(segment
		(start 83.884008 -7.48919)
		(end 83.690968 -7.29615)
		(width 0.14224)
		(layer "In2.Cu")
		(net "M_J_BG<0>")
	)
	(arc
		(start 88.300052 -53.89372)
		(mid 88.37285 -53.602957)
		(end 88.293702 -53.313838)
		(width 0.0889)
		(layer "In2.Cu")
		(net "M_J_BG<0>")
	)
	(arc
		(start 88.300052 -56.86552)
		(mid 88.37285 -56.574757)
		(end 88.293702 -56.285638)
		(width 0.0889)
		(layer "In2.Cu")
		(net "M_J_BG<0>")
	)
	(arc
		(start 88.293702 -57.276238)
		(mid 88.240232 -57.081175)
		(end 88.288876 -56.884824)
		(width 0.0889)
		(layer "In2.Cu")
		(net "M_J_BG<0>")
	)
	(arc
		(start 88.293702 -52.913788)
		(mid 88.372924 -52.62467)
		(end 88.300052 -52.333906)
		(width 0.0889)
		(layer "In2.Cu")
		(net "M_J_BG<0>")
	)
	(arc
		(start 88.300052 -54.88432)
		(mid 88.37285 -54.593557)
		(end 88.293702 -54.304438)
		(width 0.0889)
		(layer "In2.Cu")
		(net "M_J_BG<0>")
	)
	(arc
		(start 88.293702 -56.285638)
		(mid 88.240232 -56.090575)
		(end 88.288876 -55.894224)
		(width 0.0889)
		(layer "In2.Cu")
		(net "M_J_BG<0>")
	)
	(arc
		(start 88.293702 -52.323238)
		(mid 88.240203 -52.12334)
		(end 88.293702 -51.923442)
		(width 0.0889)
		(layer "In2.Cu")
		(net "M_J_BG<0>")
	)
	(arc
		(start 88.293702 -54.304438)
		(mid 88.240232 -54.109375)
		(end 88.288876 -53.913024)
		(width 0.0889)
		(layer "In2.Cu")
		(net "M_J_BG<0>")
	)
	(arc
		(start 88.293702 -53.313838)
		(mid 88.240232 -53.118775)
		(end 88.288876 -52.922424)
		(width 0.0889)
		(layer "In2.Cu")
		(net "M_J_BG<0>")
	)
	(arc
		(start 88.293702 -57.867042)
		(mid 88.372833 -57.57164)
		(end 88.293702 -57.276238)
		(width 0.0889)
		(layer "In2.Cu")
		(net "M_J_BG<0>")
	)
	(arc
		(start 88.293702 -58.266838)
		(mid 88.240203 -58.06694)
		(end 88.293702 -57.867042)
		(width 0.0889)
		(layer "In2.Cu")
		(net "M_J_BG<0>")
	)
	(arc
		(start 88.293702 -55.295038)
		(mid 88.240232 -55.099975)
		(end 88.288876 -54.903624)
		(width 0.0889)
		(layer "In2.Cu")
		(net "M_J_BG<0>")
	)
	(arc
		(start 88.300052 -55.87492)
		(mid 88.37285 -55.584157)
		(end 88.293702 -55.295038)
		(width 0.0889)
		(layer "In2.Cu")
		(net "M_J_BG<0>")
	)
	(arc
		(start 88.986868 -58.857388)
		(mid 88.926889 -58.778141)
		(end 88.8492 -58.716164)
		(width 0.0889)
		(layer "In2.Cu")
		(net "M_J_BG<0>")
	)
	(segment
		(start 101.949504 0.442468)
		(end 101.94925 0.442722)
		(width 0.1651)
		(layer "F.Cu")
		(net "M_J_BA<1>")
	)
	(segment
		(start 93.504258 -61.53404)
		(end 92.932758 -61.53404)
		(width 0.1016)
		(layer "F.Cu")
		(net "M_J_BA<1>")
	)
	(segment
		(start 101.949504 -0.821182)
		(end 101.949504 0.442468)
		(width 0.1651)
		(layer "F.Cu")
		(net "M_J_BA<1>")
	)
	(via
		(at 101.949504 -2.316734)
		(size 0.4572)
		(drill 0.2032)
		(layers "F.Cu" "B.Cu")
		(net "M_J_BA<1>")
	)
	(via
		(at 101.94925 0.442722)
		(size 0.508)
		(drill 0.254)
		(layers "F.Cu" "B.Cu")
		(net "M_J_BA<1>")
	)
	(via
		(at 92.932758 -61.53404)
		(size 0.508)
		(drill 0.254)
		(layers "F.Cu" "B.Cu")
		(net "M_J_BA<1>")
	)
	(segment
		(start 101.949504 -1.021842)
		(end 101.949504 -2.316734)
		(width 0.1651)
		(layer "B.Cu")
		(net "M_J_BA<1>")
	)
	(segment
		(start 101.949758 -2.99466)
		(end 101.949758 -2.316988)
		(width 0.14224)
		(layer "In11.Cu")
		(net "M_J_BA<1>")
	)
	(segment
		(start 93.501972 -50.475896)
		(end 93.501972 -26.202386)
		(width 0.14224)
		(layer "In11.Cu")
		(net "M_J_BA<1>")
	)
	(segment
		(start 95.527368 -11.3538)
		(end 97.121218 -9.75995)
		(width 0.14224)
		(layer "In11.Cu")
		(net "M_J_BA<1>")
	)
	(segment
		(start 94.902528 -22.271228)
		(end 94.902528 -21.000212)
		(width 0.14224)
		(layer "In11.Cu")
		(net "M_J_BA<1>")
	)
	(segment
		(start 101.94925 0.442722)
		(end 101.949758 0.442214)
		(width 0.14224)
		(layer "In11.Cu")
		(net "M_J_BA<1>")
	)
	(segment
		(start 95.131382 -24.572976)
		(end 95.131382 -22.500082)
		(width 0.14224)
		(layer "In11.Cu")
		(net "M_J_BA<1>")
	)
	(segment
		(start 95.131382 -22.500082)
		(end 94.902528 -22.271228)
		(width 0.14224)
		(layer "In11.Cu")
		(net "M_J_BA<1>")
	)
	(segment
		(start 101.244146 -0.351282)
		(end 101.082348 -0.51308)
		(width 0.14224)
		(layer "In11.Cu")
		(net "M_J_BA<1>")
	)
	(segment
		(start 101.082348 -0.51308)
		(end 101.082348 -0.99568)
		(width 0.14224)
		(layer "In11.Cu")
		(net "M_J_BA<1>")
	)
	(segment
		(start 98.126296 -6.392418)
		(end 100.20173 -6.392418)
		(width 0.14224)
		(layer "In11.Cu")
		(net "M_J_BA<1>")
	)
	(segment
		(start 101.949758 -2.316988)
		(end 101.949504 -2.316734)
		(width 0.14224)
		(layer "In11.Cu")
		(net "M_J_BA<1>")
	)
	(segment
		(start 101.949758 -0.196342)
		(end 101.794818 -0.351282)
		(width 0.14224)
		(layer "In11.Cu")
		(net "M_J_BA<1>")
	)
	(segment
		(start 101.769418 -3.58775)
		(end 101.769418 -3.175)
		(width 0.14224)
		(layer "In11.Cu")
		(net "M_J_BA<1>")
	)
	(segment
		(start 93.342968 -53.6194)
		(end 93.342968 -50.977546)
		(width 0.0889)
		(layer "In11.Cu")
		(net "M_J_BA<1>")
	)
	(segment
		(start 97.121218 -7.397496)
		(end 98.126296 -6.392418)
		(width 0.14224)
		(layer "In11.Cu")
		(net "M_J_BA<1>")
	)
	(segment
		(start 101.507798 -5.08635)
		(end 101.507798 -3.84937)
		(width 0.14224)
		(layer "In11.Cu")
		(net "M_J_BA<1>")
	)
	(segment
		(start 101.082348 -0.99568)
		(end 101.23043 -1.143762)
		(width 0.14224)
		(layer "In11.Cu")
		(net "M_J_BA<1>")
	)
	(segment
		(start 95.527368 -20.375372)
		(end 95.527368 -11.3538)
		(width 0.14224)
		(layer "In11.Cu")
		(net "M_J_BA<1>")
	)
	(segment
		(start 93.501972 -50.818542)
		(end 93.501972 -50.475896)
		(width 0.0889)
		(layer "In11.Cu")
		(net "M_J_BA<1>")
	)
	(segment
		(start 101.949758 0.442214)
		(end 101.949758 -0.196342)
		(width 0.14224)
		(layer "In11.Cu")
		(net "M_J_BA<1>")
	)
	(segment
		(start 101.794818 -1.143762)
		(end 101.949758 -1.298702)
		(width 0.14224)
		(layer "In11.Cu")
		(net "M_J_BA<1>")
	)
	(segment
		(start 101.23043 -1.143762)
		(end 101.794818 -1.143762)
		(width 0.14224)
		(layer "In11.Cu")
		(net "M_J_BA<1>")
	)
	(segment
		(start 97.121218 -9.75995)
		(end 97.121218 -7.397496)
		(width 0.14224)
		(layer "In11.Cu")
		(net "M_J_BA<1>")
	)
	(segment
		(start 101.769418 -3.175)
		(end 101.949758 -2.99466)
		(width 0.14224)
		(layer "In11.Cu")
		(net "M_J_BA<1>")
	)
	(segment
		(start 93.342968 -50.977546)
		(end 93.501972 -50.818542)
		(width 0.0889)
		(layer "In11.Cu")
		(net "M_J_BA<1>")
	)
	(segment
		(start 101.507798 -3.84937)
		(end 101.769418 -3.58775)
		(width 0.14224)
		(layer "In11.Cu")
		(net "M_J_BA<1>")
	)
	(segment
		(start 93.262958 -60.77204)
		(end 93.279468 -60.743592)
		(width 0.0889)
		(layer "In11.Cu")
		(net "M_J_BA<1>")
	)
	(segment
		(start 100.20173 -6.392418)
		(end 101.507798 -5.08635)
		(width 0.14224)
		(layer "In11.Cu")
		(net "M_J_BA<1>")
	)
	(segment
		(start 93.501972 -26.202386)
		(end 95.131382 -24.572976)
		(width 0.14224)
		(layer "In11.Cu")
		(net "M_J_BA<1>")
	)
	(segment
		(start 101.794818 -0.351282)
		(end 101.244146 -0.351282)
		(width 0.14224)
		(layer "In11.Cu")
		(net "M_J_BA<1>")
	)
	(segment
		(start 93.20022 -53.762148)
		(end 93.342968 -53.6194)
		(width 0.0889)
		(layer "In11.Cu")
		(net "M_J_BA<1>")
	)
	(segment
		(start 94.902528 -21.000212)
		(end 95.527368 -20.375372)
		(width 0.14224)
		(layer "In11.Cu")
		(net "M_J_BA<1>")
	)
	(segment
		(start 92.932758 -61.53404)
		(end 93.262958 -60.77204)
		(width 0.0889)
		(layer "In11.Cu")
		(net "M_J_BA<1>")
	)
	(segment
		(start 101.949758 -1.298702)
		(end 101.949758 -2.316988)
		(width 0.14224)
		(layer "In11.Cu")
		(net "M_J_BA<1>")
	)
	(segment
		(start 93.20022 -54.102)
		(end 93.20022 -53.762148)
		(width 0.0889)
		(layer "In11.Cu")
		(net "M_J_BA<1>")
	)
	(arc
		(start 93.279468 -55.390796)
		(mid 93.200337 -55.095394)
		(end 93.279468 -54.799992)
		(width 0.0889)
		(layer "In11.Cu")
		(net "M_J_BA<1>")
	)
	(arc
		(start 93.279468 -60.743592)
		(mid 93.332967 -60.543694)
		(end 93.279468 -60.343796)
		(width 0.0889)
		(layer "In11.Cu")
		(net "M_J_BA<1>")
	)
	(arc
		(start 93.279468 -56.781192)
		(mid 93.332967 -56.581294)
		(end 93.279468 -56.381396)
		(width 0.0889)
		(layer "In11.Cu")
		(net "M_J_BA<1>")
	)
	(arc
		(start 93.279468 -56.381396)
		(mid 93.200337 -56.085994)
		(end 93.279468 -55.790592)
		(width 0.0889)
		(layer "In11.Cu")
		(net "M_J_BA<1>")
	)
	(arc
		(start 93.279468 -57.771792)
		(mid 93.332967 -57.571894)
		(end 93.279468 -57.371996)
		(width 0.0889)
		(layer "In11.Cu")
		(net "M_J_BA<1>")
	)
	(arc
		(start 93.279468 -59.353196)
		(mid 93.200337 -59.057794)
		(end 93.279468 -58.762392)
		(width 0.0889)
		(layer "In11.Cu")
		(net "M_J_BA<1>")
	)
	(arc
		(start 93.279468 -58.362596)
		(mid 93.200337 -58.067194)
		(end 93.279468 -57.771792)
		(width 0.0889)
		(layer "In11.Cu")
		(net "M_J_BA<1>")
	)
	(arc
		(start 93.279468 -54.400196)
		(mid 93.22004 -54.256361)
		(end 93.20022 -54.102)
		(width 0.0889)
		(layer "In11.Cu")
		(net "M_J_BA<1>")
	)
	(arc
		(start 93.279468 -59.752992)
		(mid 93.332967 -59.553094)
		(end 93.279468 -59.353196)
		(width 0.0889)
		(layer "In11.Cu")
		(net "M_J_BA<1>")
	)
	(arc
		(start 93.279468 -58.762392)
		(mid 93.332967 -58.562494)
		(end 93.279468 -58.362596)
		(width 0.0889)
		(layer "In11.Cu")
		(net "M_J_BA<1>")
	)
	(arc
		(start 93.279468 -54.799992)
		(mid 93.332967 -54.600094)
		(end 93.279468 -54.400196)
		(width 0.0889)
		(layer "In11.Cu")
		(net "M_J_BA<1>")
	)
	(arc
		(start 93.279468 -60.343796)
		(mid 93.200337 -60.048394)
		(end 93.279468 -59.752992)
		(width 0.0889)
		(layer "In11.Cu")
		(net "M_J_BA<1>")
	)
	(arc
		(start 93.279468 -55.790592)
		(mid 93.332967 -55.590694)
		(end 93.279468 -55.390796)
		(width 0.0889)
		(layer "In11.Cu")
		(net "M_J_BA<1>")
	)
	(arc
		(start 93.279468 -57.371996)
		(mid 93.200337 -57.076594)
		(end 93.279468 -56.781192)
		(width 0.0889)
		(layer "In11.Cu")
		(net "M_J_BA<1>")
	)
	(segment
		(start 102.799388 3.778758)
		(end 102.799388 2.514854)
		(width 0.1651)
		(layer "F.Cu")
		(net "M_J_BA<0>")
	)
	(segment
		(start 96.938338 -58.561986)
		(end 96.366838 -58.561986)
		(width 0.1016)
		(layer "F.Cu")
		(net "M_J_BA<0>")
	)
	(via
		(at 102.799388 2.514854)
		(size 0.508)
		(drill 0.254)
		(layers "F.Cu" "B.Cu")
		(net "M_J_BA<0>")
	)
	(via
		(at 96.366838 -58.561986)
		(size 0.508)
		(drill 0.254)
		(layers "F.Cu" "B.Cu")
		(net "M_J_BA<0>")
	)
	(via
		(at 102.799642 -4.332478)
		(size 0.4572)
		(drill 0.2032)
		(layers "F.Cu" "B.Cu")
		(net "M_J_BA<0>")
	)
	(segment
		(start 102.799388 -4.332732)
		(end 102.799642 -4.332478)
		(width 0.1651)
		(layer "B.Cu")
		(net "M_J_BA<0>")
	)
	(segment
		(start 102.799388 -5.621782)
		(end 102.799388 -4.332732)
		(width 0.1651)
		(layer "B.Cu")
		(net "M_J_BA<0>")
	)
	(segment
		(start 96.713548 -53.809138)
		(end 96.718374 -53.800502)
		(width 0.0889)
		(layer "In2.Cu")
		(net "M_J_BA<0>")
	)
	(segment
		(start 101.441758 -17.642586)
		(end 101.441758 -17.134586)
		(width 0.14224)
		(layer "In2.Cu")
		(net "M_J_BA<0>")
	)
	(segment
		(start 101.635814 -19.182842)
		(end 101.533706 -19.080734)
		(width 0.14224)
		(layer "In2.Cu")
		(net "M_J_BA<0>")
	)
	(segment
		(start 96.697038 -57.799986)
		(end 96.718374 -57.762902)
		(width 0.0889)
		(layer "In2.Cu")
		(net "M_J_BA<0>")
	)
	(segment
		(start 102.512368 -4.045204)
		(end 102.799642 -4.332478)
		(width 0.14224)
		(layer "In2.Cu")
		(net "M_J_BA<0>")
	)
	(segment
		(start 101.505766 -20.63623)
		(end 101.294946 -20.63623)
		(width 0.14224)
		(layer "In2.Cu")
		(net "M_J_BA<0>")
	)
	(segment
		(start 101.294946 -20.63623)
		(end 101.146102 -20.487386)
		(width 0.14224)
		(layer "In2.Cu")
		(net "M_J_BA<0>")
	)
	(segment
		(start 101.533452 -13.592302)
		(end 101.533452 -5.598668)
		(width 0.14224)
		(layer "In2.Cu")
		(net "M_J_BA<0>")
	)
	(segment
		(start 97.508568 -50.256694)
		(end 97.508568 -48.679608)
		(width 0.0889)
		(layer "In2.Cu")
		(net "M_J_BA<0>")
	)
	(segment
		(start 96.707198 -55.801006)
		(end 96.713548 -55.790338)
		(width 0.0889)
		(layer "In2.Cu")
		(net "M_J_BA<0>")
	)
	(segment
		(start 101.441758 -23.285196)
		(end 101.562154 -23.1648)
		(width 0.14224)
		(layer "In2.Cu")
		(net "M_J_BA<0>")
	)
	(segment
		(start 96.713548 -55.790338)
		(end 96.718374 -55.781702)
		(width 0.0889)
		(layer "In2.Cu")
		(net "M_J_BA<0>")
	)
	(segment
		(start 98.968306 -29.248862)
		(end 98.968306 -28.961334)
		(width 0.14224)
		(layer "In2.Cu")
		(net "M_J_BA<0>")
	)
	(segment
		(start 96.713548 -54.799738)
		(end 96.718374 -54.791102)
		(width 0.0889)
		(layer "In2.Cu")
		(net "M_J_BA<0>")
	)
	(segment
		(start 101.441758 -17.134586)
		(end 101.539548 -17.036796)
		(width 0.14224)
		(layer "In2.Cu")
		(net "M_J_BA<0>")
	)
	(segment
		(start 98.393504 -29.536136)
		(end 98.681032 -29.536136)
		(width 0.14224)
		(layer "In2.Cu")
		(net "M_J_BA<0>")
	)
	(segment
		(start 96.713548 -56.780938)
		(end 96.718374 -56.772302)
		(width 0.0889)
		(layer "In2.Cu")
		(net "M_J_BA<0>")
	)
	(segment
		(start 101.709982 -21.645372)
		(end 101.709982 -20.840446)
		(width 0.14224)
		(layer "In2.Cu")
		(net "M_J_BA<0>")
	)
	(segment
		(start 102.37851 -0.235458)
		(end 102.37851 -2.634742)
		(width 0.14224)
		(layer "In2.Cu")
		(net "M_J_BA<0>")
	)
	(segment
		(start 97.508568 -48.679608)
		(end 97.696528 -48.491648)
		(width 0.0889)
		(layer "In2.Cu")
		(net "M_J_BA<0>")
	)
	(segment
		(start 98.794824 -28.787852)
		(end 98.794824 -28.500324)
		(width 0.14224)
		(layer "In2.Cu")
		(net "M_J_BA<0>")
	)
	(segment
		(start 101.533452 -5.598668)
		(end 102.799642 -4.332478)
		(width 0.14224)
		(layer "In2.Cu")
		(net "M_J_BA<0>")
	)
	(segment
		(start 96.771968 -52.600098)
		(end 96.771968 -50.993294)
		(width 0.0889)
		(layer "In2.Cu")
		(net "M_J_BA<0>")
	)
	(segment
		(start 102.309168 0.8636)
		(end 102.461568 0.7112)
		(width 0.14224)
		(layer "In2.Cu")
		(net "M_J_BA<0>")
	)
	(segment
		(start 101.469698 -22.424136)
		(end 101.469698 -21.885656)
		(width 0.14224)
		(layer "In2.Cu")
		(net "M_J_BA<0>")
	)
	(segment
		(start 96.707198 -54.810406)
		(end 96.713548 -54.799738)
		(width 0.0889)
		(layer "In2.Cu")
		(net "M_J_BA<0>")
	)
	(segment
		(start 101.469698 -21.885656)
		(end 101.709982 -21.645372)
		(width 0.14224)
		(layer "In2.Cu")
		(net "M_J_BA<0>")
	)
	(segment
		(start 97.696528 -48.278034)
		(end 97.696528 -29.59862)
		(width 0.14224)
		(layer "In2.Cu")
		(net "M_J_BA<0>")
	)
	(segment
		(start 101.562154 -23.1648)
		(end 101.562154 -22.516592)
		(width 0.14224)
		(layer "In2.Cu")
		(net "M_J_BA<0>")
	)
	(segment
		(start 102.461568 -0.1524)
		(end 102.37851 -0.235458)
		(width 0.14224)
		(layer "In2.Cu")
		(net "M_J_BA<0>")
	)
	(segment
		(start 100.327968 -26.96718)
		(end 100.327968 -25.728168)
		(width 0.14224)
		(layer "In2.Cu")
		(net "M_J_BA<0>")
	)
	(segment
		(start 102.799388 2.514854)
		(end 102.799388 1.88722)
		(width 0.14224)
		(layer "In2.Cu")
		(net "M_J_BA<0>")
	)
	(segment
		(start 101.533706 -18.439638)
		(end 101.594158 -18.379186)
		(width 0.14224)
		(layer "In2.Cu")
		(net "M_J_BA<0>")
	)
	(segment
		(start 102.799388 1.88722)
		(end 102.309168 1.397)
		(width 0.14224)
		(layer "In2.Cu")
		(net "M_J_BA<0>")
	)
	(segment
		(start 101.508814 -19.84375)
		(end 101.635814 -19.71675)
		(width 0.14224)
		(layer "In2.Cu")
		(net "M_J_BA<0>")
	)
	(segment
		(start 101.709982 -20.840446)
		(end 101.505766 -20.63623)
		(width 0.14224)
		(layer "In2.Cu")
		(net "M_J_BA<0>")
	)
	(segment
		(start 101.307138 -19.84375)
		(end 101.508814 -19.84375)
		(width 0.14224)
		(layer "In2.Cu")
		(net "M_J_BA<0>")
	)
	(segment
		(start 97.932494 -29.362654)
		(end 98.220022 -29.362654)
		(width 0.14224)
		(layer "In2.Cu")
		(net "M_J_BA<0>")
	)
	(segment
		(start 101.441758 -24.614378)
		(end 101.441758 -23.285196)
		(width 0.14224)
		(layer "In2.Cu")
		(net "M_J_BA<0>")
	)
	(segment
		(start 101.513132 -13.612622)
		(end 101.533452 -13.592302)
		(width 0.14224)
		(layer "In2.Cu")
		(net "M_J_BA<0>")
	)
	(segment
		(start 98.220022 -29.362654)
		(end 98.393504 -29.536136)
		(width 0.14224)
		(layer "In2.Cu")
		(net "M_J_BA<0>")
	)
	(segment
		(start 101.594158 -18.379186)
		(end 101.594158 -17.794986)
		(width 0.14224)
		(layer "In2.Cu")
		(net "M_J_BA<0>")
	)
	(segment
		(start 96.707198 -56.791606)
		(end 96.713548 -56.780938)
		(width 0.0889)
		(layer "In2.Cu")
		(net "M_J_BA<0>")
	)
	(segment
		(start 101.539548 -17.036796)
		(end 101.539548 -14.595348)
		(width 0.14224)
		(layer "In2.Cu")
		(net "M_J_BA<0>")
	)
	(segment
		(start 101.513132 -14.568932)
		(end 101.513132 -13.612622)
		(width 0.14224)
		(layer "In2.Cu")
		(net "M_J_BA<0>")
	)
	(segment
		(start 101.146102 -20.004786)
		(end 101.307138 -19.84375)
		(width 0.14224)
		(layer "In2.Cu")
		(net "M_J_BA<0>")
	)
	(segment
		(start 98.681032 -29.536136)
		(end 98.968306 -29.248862)
		(width 0.14224)
		(layer "In2.Cu")
		(net "M_J_BA<0>")
	)
	(segment
		(start 98.794824 -28.500324)
		(end 100.327968 -26.96718)
		(width 0.14224)
		(layer "In2.Cu")
		(net "M_J_BA<0>")
	)
	(segment
		(start 102.37851 -2.634742)
		(end 102.512368 -2.7686)
		(width 0.14224)
		(layer "In2.Cu")
		(net "M_J_BA<0>")
	)
	(segment
		(start 102.512368 -2.7686)
		(end 102.512368 -4.045204)
		(width 0.14224)
		(layer "In2.Cu")
		(net "M_J_BA<0>")
	)
	(segment
		(start 101.539548 -14.595348)
		(end 101.513132 -14.568932)
		(width 0.14224)
		(layer "In2.Cu")
		(net "M_J_BA<0>")
	)
	(segment
		(start 96.707198 -53.819806)
		(end 96.713548 -53.809138)
		(width 0.0889)
		(layer "In2.Cu")
		(net "M_J_BA<0>")
	)
	(segment
		(start 101.533706 -19.080734)
		(end 101.533706 -18.439638)
		(width 0.14224)
		(layer "In2.Cu")
		(net "M_J_BA<0>")
	)
	(segment
		(start 101.594158 -17.794986)
		(end 101.441758 -17.642586)
		(width 0.14224)
		(layer "In2.Cu")
		(net "M_J_BA<0>")
	)
	(segment
		(start 101.562154 -22.516592)
		(end 101.469698 -22.424136)
		(width 0.14224)
		(layer "In2.Cu")
		(net "M_J_BA<0>")
	)
	(segment
		(start 102.461568 0.7112)
		(end 102.461568 -0.1524)
		(width 0.14224)
		(layer "In2.Cu")
		(net "M_J_BA<0>")
	)
	(segment
		(start 101.635814 -19.71675)
		(end 101.635814 -19.182842)
		(width 0.14224)
		(layer "In2.Cu")
		(net "M_J_BA<0>")
	)
	(segment
		(start 98.968306 -28.961334)
		(end 98.794824 -28.787852)
		(width 0.14224)
		(layer "In2.Cu")
		(net "M_J_BA<0>")
	)
	(segment
		(start 100.327968 -25.728168)
		(end 101.441758 -24.614378)
		(width 0.14224)
		(layer "In2.Cu")
		(net "M_J_BA<0>")
	)
	(segment
		(start 97.696528 -48.491648)
		(end 97.696528 -48.278034)
		(width 0.0889)
		(layer "In2.Cu")
		(net "M_J_BA<0>")
	)
	(segment
		(start 96.771968 -50.993294)
		(end 97.508568 -50.256694)
		(width 0.0889)
		(layer "In2.Cu")
		(net "M_J_BA<0>")
	)
	(segment
		(start 101.146102 -20.487386)
		(end 101.146102 -20.004786)
		(width 0.14224)
		(layer "In2.Cu")
		(net "M_J_BA<0>")
	)
	(segment
		(start 96.366838 -58.561986)
		(end 96.697038 -57.799986)
		(width 0.0889)
		(layer "In2.Cu")
		(net "M_J_BA<0>")
	)
	(segment
		(start 102.309168 1.397)
		(end 102.309168 0.8636)
		(width 0.14224)
		(layer "In2.Cu")
		(net "M_J_BA<0>")
	)
	(segment
		(start 97.696528 -29.59862)
		(end 97.932494 -29.362654)
		(width 0.14224)
		(layer "In2.Cu")
		(net "M_J_BA<0>")
	)
	(arc
		(start 96.718374 -57.762902)
		(mid 96.767129 -57.56655)
		(end 96.713548 -57.371488)
		(width 0.0889)
		(layer "In2.Cu")
		(net "M_J_BA<0>")
	)
	(arc
		(start 96.713548 -55.390288)
		(mid 96.634326 -55.10117)
		(end 96.707198 -54.810406)
		(width 0.0889)
		(layer "In2.Cu")
		(net "M_J_BA<0>")
	)
	(arc
		(start 96.718374 -55.781702)
		(mid 96.767129 -55.58535)
		(end 96.713548 -55.390288)
		(width 0.0889)
		(layer "In2.Cu")
		(net "M_J_BA<0>")
	)
	(arc
		(start 96.713548 -54.399688)
		(mid 96.634326 -54.11057)
		(end 96.707198 -53.819806)
		(width 0.0889)
		(layer "In2.Cu")
		(net "M_J_BA<0>")
	)
	(arc
		(start 96.718374 -56.772302)
		(mid 96.767129 -56.57595)
		(end 96.713548 -56.380888)
		(width 0.0889)
		(layer "In2.Cu")
		(net "M_J_BA<0>")
	)
	(arc
		(start 96.718374 -53.800502)
		(mid 96.767129 -53.60415)
		(end 96.713548 -53.409088)
		(width 0.0889)
		(layer "In2.Cu")
		(net "M_J_BA<0>")
	)
	(arc
		(start 96.718374 -54.791102)
		(mid 96.767129 -54.59475)
		(end 96.713548 -54.399688)
		(width 0.0889)
		(layer "In2.Cu")
		(net "M_J_BA<0>")
	)
	(arc
		(start 96.713548 -56.380888)
		(mid 96.634326 -56.09177)
		(end 96.707198 -55.801006)
		(width 0.0889)
		(layer "In2.Cu")
		(net "M_J_BA<0>")
	)
	(arc
		(start 96.713548 -53.409088)
		(mid 96.634417 -53.113686)
		(end 96.713548 -52.818284)
		(width 0.0889)
		(layer "In2.Cu")
		(net "M_J_BA<0>")
	)
	(arc
		(start 96.713548 -52.818284)
		(mid 96.757138 -52.713039)
		(end 96.771968 -52.600098)
		(width 0.0889)
		(layer "In2.Cu")
		(net "M_J_BA<0>")
	)
	(arc
		(start 96.713548 -57.371488)
		(mid 96.634326 -57.08237)
		(end 96.707198 -56.791606)
		(width 0.0889)
		(layer "In2.Cu")
		(net "M_J_BA<0>")
	)
	(segment
		(start 83.249516 -0.821182)
		(end 83.249516 0.442722)
		(width 0.1651)
		(layer "F.Cu")
		(net "M_J_ALERT_N")
	)
	(segment
		(start 89.211912 -61.038486)
		(end 88.640412 -61.038486)
		(width 0.1016)
		(layer "F.Cu")
		(net "M_J_ALERT_N")
	)
	(via
		(at 83.249516 0.442722)
		(size 0.508)
		(drill 0.254)
		(layers "F.Cu" "B.Cu")
		(net "M_J_ALERT_N")
	)
	(via
		(at 88.640412 -61.038486)
		(size 0.508)
		(drill 0.254)
		(layers "F.Cu" "B.Cu")
		(net "M_J_ALERT_N")
	)
	(via
		(at 83.249516 -2.314956)
		(size 0.4572)
		(drill 0.2032)
		(layers "F.Cu" "B.Cu")
		(net "M_J_ALERT_N")
	)
	(segment
		(start 83.249516 -1.021842)
		(end 83.249516 -2.314956)
		(width 0.1651)
		(layer "B.Cu")
		(net "M_J_ALERT_N")
	)
	(segment
		(start 81.963768 -4.782566)
		(end 81.963768 -3.600704)
		(width 0.14224)
		(layer "In2.Cu")
		(net "M_J_ALERT_N")
	)
	(segment
		(start 88.213692 -31.1277)
		(end 84.275168 -27.189176)
		(width 0.14224)
		(layer "In2.Cu")
		(net "M_J_ALERT_N")
	)
	(segment
		(start 88.240362 -59.045602)
		(end 88.226138 -58.824114)
		(width 0.0889)
		(layer "In2.Cu")
		(net "M_J_ALERT_N")
	)
	(segment
		(start 82.766408 -22.421596)
		(end 82.766408 -21.938996)
		(width 0.14224)
		(layer "In2.Cu")
		(net "M_J_ALERT_N")
	)
	(segment
		(start 82.816446 -5.635244)
		(end 81.963768 -4.782566)
		(width 0.14224)
		(layer "In2.Cu")
		(net "M_J_ALERT_N")
	)
	(segment
		(start 82.893408 -20.73402)
		(end 82.830924 -20.671536)
		(width 0.14224)
		(layer "In2.Cu")
		(net "M_J_ALERT_N")
	)
	(segment
		(start 88.872568 -59.563)
		(end 88.653112 -59.563)
		(width 0.0889)
		(layer "In2.Cu")
		(net "M_J_ALERT_N")
	)
	(segment
		(start 88.640412 -61.038486)
		(end 88.640412 -60.810902)
		(width 0.0889)
		(layer "In2.Cu")
		(net "M_J_ALERT_N")
	)
	(segment
		(start 88.128602 -56.780938)
		(end 88.133428 -56.772302)
		(width 0.0889)
		(layer "In2.Cu")
		(net "M_J_ALERT_N")
	)
	(segment
		(start 88.226138 -58.824114)
		(end 88.171528 -58.436764)
		(width 0.0889)
		(layer "In2.Cu")
		(net "M_J_ALERT_N")
	)
	(segment
		(start 88.128602 -55.790338)
		(end 88.133428 -55.781702)
		(width 0.0889)
		(layer "In2.Cu")
		(net "M_J_ALERT_N")
	)
	(segment
		(start 83.249516 -0.060452)
		(end 83.249516 0.442722)
		(width 0.14224)
		(layer "In2.Cu")
		(net "M_J_ALERT_N")
	)
	(segment
		(start 88.128602 -54.799738)
		(end 88.133428 -54.791102)
		(width 0.0889)
		(layer "In2.Cu")
		(net "M_J_ALERT_N")
	)
	(segment
		(start 83.249516 -2.314956)
		(end 83.106768 -2.172208)
		(width 0.14224)
		(layer "In2.Cu")
		(net "M_J_ALERT_N")
	)
	(segment
		(start 82.809588 -13.666216)
		(end 82.829908 -13.645896)
		(width 0.14224)
		(layer "In2.Cu")
		(net "M_J_ALERT_N")
	)
	(segment
		(start 82.944208 -23.132796)
		(end 82.944208 -22.599396)
		(width 0.14224)
		(layer "In2.Cu")
		(net "M_J_ALERT_N")
	)
	(segment
		(start 88.122252 -54.810406)
		(end 88.128602 -54.799738)
		(width 0.0889)
		(layer "In2.Cu")
		(net "M_J_ALERT_N")
	)
	(segment
		(start 82.809588 -17.040606)
		(end 82.809588 -13.666216)
		(width 0.14224)
		(layer "In2.Cu")
		(net "M_J_ALERT_N")
	)
	(segment
		(start 82.893408 -17.769586)
		(end 82.741008 -17.617186)
		(width 0.14224)
		(layer "In2.Cu")
		(net "M_J_ALERT_N")
	)
	(segment
		(start 82.893408 -21.811996)
		(end 82.893408 -20.73402)
		(width 0.14224)
		(layer "In2.Cu")
		(net "M_J_ALERT_N")
	)
	(segment
		(start 82.758534 -24.416766)
		(end 82.758534 -23.31847)
		(width 0.14224)
		(layer "In2.Cu")
		(net "M_J_ALERT_N")
	)
	(segment
		(start 81.963768 -3.600704)
		(end 83.249516 -2.314956)
		(width 0.14224)
		(layer "In2.Cu")
		(net "M_J_ALERT_N")
	)
	(segment
		(start 88.128602 -57.771538)
		(end 88.133428 -57.762902)
		(width 0.0889)
		(layer "In2.Cu")
		(net "M_J_ALERT_N")
	)
	(segment
		(start 88.122252 -56.791606)
		(end 88.128602 -56.780938)
		(width 0.0889)
		(layer "In2.Cu")
		(net "M_J_ALERT_N")
	)
	(segment
		(start 88.171528 -58.436764)
		(end 88.122252 -58.35142)
		(width 0.0889)
		(layer "In2.Cu")
		(net "M_J_ALERT_N")
	)
	(segment
		(start 88.122252 -53.819806)
		(end 88.128602 -53.809138)
		(width 0.0889)
		(layer "In2.Cu")
		(net "M_J_ALERT_N")
	)
	(segment
		(start 88.213692 -51.680872)
		(end 88.213692 -51.08067)
		(width 0.0889)
		(layer "In2.Cu")
		(net "M_J_ALERT_N")
	)
	(segment
		(start 82.829908 -8.308086)
		(end 82.700368 -8.178546)
		(width 0.14224)
		(layer "In2.Cu")
		(net "M_J_ALERT_N")
	)
	(segment
		(start 82.741008 -17.617186)
		(end 82.741008 -17.109186)
		(width 0.14224)
		(layer "In2.Cu")
		(net "M_J_ALERT_N")
	)
	(segment
		(start 82.829908 -13.645896)
		(end 82.829908 -8.308086)
		(width 0.14224)
		(layer "In2.Cu")
		(net "M_J_ALERT_N")
	)
	(segment
		(start 88.640412 -60.810902)
		(end 89.126568 -60.324746)
		(width 0.0889)
		(layer "In2.Cu")
		(net "M_J_ALERT_N")
	)
	(segment
		(start 84.275168 -25.9334)
		(end 82.758534 -24.416766)
		(width 0.14224)
		(layer "In2.Cu")
		(net "M_J_ALERT_N")
	)
	(segment
		(start 88.128602 -53.809138)
		(end 88.133428 -53.800502)
		(width 0.0889)
		(layer "In2.Cu")
		(net "M_J_ALERT_N")
	)
	(segment
		(start 89.126568 -59.817)
		(end 88.872568 -59.563)
		(width 0.0889)
		(layer "In2.Cu")
		(net "M_J_ALERT_N")
	)
	(segment
		(start 89.126568 -60.324746)
		(end 89.126568 -59.817)
		(width 0.0889)
		(layer "In2.Cu")
		(net "M_J_ALERT_N")
	)
	(segment
		(start 82.944208 -22.599396)
		(end 82.766408 -22.421596)
		(width 0.14224)
		(layer "In2.Cu")
		(net "M_J_ALERT_N")
	)
	(segment
		(start 84.275168 -27.189176)
		(end 84.275168 -25.9334)
		(width 0.14224)
		(layer "In2.Cu")
		(net "M_J_ALERT_N")
	)
	(segment
		(start 88.213692 -51.08067)
		(end 88.213692 -31.1277)
		(width 0.14224)
		(layer "In2.Cu")
		(net "M_J_ALERT_N")
	)
	(segment
		(start 88.122252 -55.801006)
		(end 88.128602 -55.790338)
		(width 0.0889)
		(layer "In2.Cu")
		(net "M_J_ALERT_N")
	)
	(segment
		(start 88.128602 -51.827938)
		(end 88.213692 -51.680872)
		(width 0.0889)
		(layer "In2.Cu")
		(net "M_J_ALERT_N")
	)
	(segment
		(start 82.893408 -18.404586)
		(end 82.893408 -17.769586)
		(width 0.14224)
		(layer "In2.Cu")
		(net "M_J_ALERT_N")
	)
	(segment
		(start 83.106768 -0.2032)
		(end 83.249516 -0.060452)
		(width 0.14224)
		(layer "In2.Cu")
		(net "M_J_ALERT_N")
	)
	(segment
		(start 88.128602 -52.418488)
		(end 88.122252 -52.40782)
		(width 0.0889)
		(layer "In2.Cu")
		(net "M_J_ALERT_N")
	)
	(segment
		(start 82.766408 -21.938996)
		(end 82.893408 -21.811996)
		(width 0.14224)
		(layer "In2.Cu")
		(net "M_J_ALERT_N")
	)
	(segment
		(start 82.830924 -18.46707)
		(end 82.893408 -18.404586)
		(width 0.14224)
		(layer "In2.Cu")
		(net "M_J_ALERT_N")
	)
	(segment
		(start 88.653112 -59.563)
		(end 88.53297 -59.442858)
		(width 0.0889)
		(layer "In2.Cu")
		(net "M_J_ALERT_N")
	)
	(segment
		(start 82.830924 -20.671536)
		(end 82.830924 -18.46707)
		(width 0.14224)
		(layer "In2.Cu")
		(net "M_J_ALERT_N")
	)
	(segment
		(start 82.816446 -7.432548)
		(end 82.816446 -5.635244)
		(width 0.14224)
		(layer "In2.Cu")
		(net "M_J_ALERT_N")
	)
	(segment
		(start 82.700368 -8.178546)
		(end 82.700368 -7.548626)
		(width 0.14224)
		(layer "In2.Cu")
		(net "M_J_ALERT_N")
	)
	(segment
		(start 83.106768 -2.172208)
		(end 83.106768 -0.2032)
		(width 0.14224)
		(layer "In2.Cu")
		(net "M_J_ALERT_N")
	)
	(segment
		(start 82.741008 -17.109186)
		(end 82.809588 -17.040606)
		(width 0.14224)
		(layer "In2.Cu")
		(net "M_J_ALERT_N")
	)
	(segment
		(start 82.758534 -23.31847)
		(end 82.944208 -23.132796)
		(width 0.14224)
		(layer "In2.Cu")
		(net "M_J_ALERT_N")
	)
	(segment
		(start 82.700368 -7.548626)
		(end 82.816446 -7.432548)
		(width 0.14224)
		(layer "In2.Cu")
		(net "M_J_ALERT_N")
	)
	(arc
		(start 88.133428 -57.762902)
		(mid 88.182183 -57.56655)
		(end 88.128602 -57.371488)
		(width 0.0889)
		(layer "In2.Cu")
		(net "M_J_ALERT_N")
	)
	(arc
		(start 88.133428 -56.772302)
		(mid 88.182183 -56.57595)
		(end 88.128602 -56.380888)
		(width 0.0889)
		(layer "In2.Cu")
		(net "M_J_ALERT_N")
	)
	(arc
		(start 88.128602 -56.380888)
		(mid 88.04938 -56.09177)
		(end 88.122252 -55.801006)
		(width 0.0889)
		(layer "In2.Cu")
		(net "M_J_ALERT_N")
	)
	(arc
		(start 88.133428 -54.791102)
		(mid 88.182183 -54.59475)
		(end 88.128602 -54.399688)
		(width 0.0889)
		(layer "In2.Cu")
		(net "M_J_ALERT_N")
	)
	(arc
		(start 88.128602 -57.371488)
		(mid 88.04938 -57.08237)
		(end 88.122252 -56.791606)
		(width 0.0889)
		(layer "In2.Cu")
		(net "M_J_ALERT_N")
	)
	(arc
		(start 88.53297 -59.442858)
		(mid 88.318153 -59.294686)
		(end 88.240362 -59.045602)
		(width 0.0889)
		(layer "In2.Cu")
		(net "M_J_ALERT_N")
	)
	(arc
		(start 88.128602 -55.390288)
		(mid 88.04938 -55.10117)
		(end 88.122252 -54.810406)
		(width 0.0889)
		(layer "In2.Cu")
		(net "M_J_ALERT_N")
	)
	(arc
		(start 88.133428 -53.800502)
		(mid 88.182183 -53.60415)
		(end 88.128602 -53.409088)
		(width 0.0889)
		(layer "In2.Cu")
		(net "M_J_ALERT_N")
	)
	(arc
		(start 88.128602 -53.409088)
		(mid 88.049471 -53.113686)
		(end 88.128602 -52.818284)
		(width 0.0889)
		(layer "In2.Cu")
		(net "M_J_ALERT_N")
	)
	(arc
		(start 88.122252 -52.40782)
		(mid 88.049454 -52.117057)
		(end 88.128602 -51.827938)
		(width 0.0889)
		(layer "In2.Cu")
		(net "M_J_ALERT_N")
	)
	(arc
		(start 88.133428 -55.781702)
		(mid 88.182183 -55.58535)
		(end 88.128602 -55.390288)
		(width 0.0889)
		(layer "In2.Cu")
		(net "M_J_ALERT_N")
	)
	(arc
		(start 88.122252 -58.35142)
		(mid 88.049454 -58.060657)
		(end 88.128602 -57.771538)
		(width 0.0889)
		(layer "In2.Cu")
		(net "M_J_ALERT_N")
	)
	(arc
		(start 88.128602 -52.818284)
		(mid 88.182101 -52.618386)
		(end 88.128602 -52.418488)
		(width 0.0889)
		(layer "In2.Cu")
		(net "M_J_ALERT_N")
	)
	(arc
		(start 88.128602 -54.399688)
		(mid 88.04938 -54.11057)
		(end 88.122252 -53.819806)
		(width 0.0889)
		(layer "In2.Cu")
		(net "M_J_ALERT_N")
	)
	(segment
		(start 81.549494 3.778758)
		(end 81.549494 1.805432)
		(width 0.1651)
		(layer "F.Cu")
		(net "M_J_ACT_N")
	)
	(segment
		(start 89.211912 -60.047886)
		(end 88.640412 -60.047886)
		(width 0.1016)
		(layer "F.Cu")
		(net "M_J_ACT_N")
	)
	(via
		(at 81.549494 1.805432)
		(size 0.508)
		(drill 0.254)
		(layers "F.Cu" "B.Cu")
		(net "M_J_ACT_N")
	)
	(via
		(at 88.640412 -60.047886)
		(size 0.508)
		(drill 0.254)
		(layers "F.Cu" "B.Cu")
		(net "M_J_ACT_N")
	)
	(via
		(at 81.549494 -4.332478)
		(size 0.4572)
		(drill 0.2032)
		(layers "F.Cu" "B.Cu")
		(net "M_J_ACT_N")
	)
	(segment
		(start 81.549494 -5.621782)
		(end 81.549494 -4.332478)
		(width 0.1651)
		(layer "B.Cu")
		(net "M_J_ACT_N")
	)
	(segment
		(start 81.271364 -1.315212)
		(end 81.116424 -1.470152)
		(width 0.14224)
		(layer "In2.Cu")
		(net "M_J_ACT_N")
	)
	(segment
		(start 82.156808 -7.558786)
		(end 82.156808 -8.696706)
		(width 0.14224)
		(layer "In2.Cu")
		(net "M_J_ACT_N")
	)
	(segment
		(start 81.549494 1.185926)
		(end 81.116424 0.752856)
		(width 0.14224)
		(layer "In2.Cu")
		(net "M_J_ACT_N")
	)
	(segment
		(start 81.942178 -23.222966)
		(end 82.014568 -23.295356)
		(width 0.14224)
		(layer "In2.Cu")
		(net "M_J_ACT_N")
	)
	(segment
		(start 87.705692 -51.135026)
		(end 87.381842 -51.458876)
		(width 0.0889)
		(layer "In2.Cu")
		(net "M_J_ACT_N")
	)
	(segment
		(start 82.014568 -23.295356)
		(end 82.014568 -24.3332)
		(width 0.14224)
		(layer "In2.Cu")
		(net "M_J_ACT_N")
	)
	(segment
		(start 81.693258 -1.160272)
		(end 81.538318 -1.315212)
		(width 0.14224)
		(layer "In2.Cu")
		(net "M_J_ACT_N")
	)
	(segment
		(start 87.435182 -54.799738)
		(end 87.441532 -54.810406)
		(width 0.0889)
		(layer "In2.Cu")
		(net "M_J_ACT_N")
	)
	(segment
		(start 81.988152 -18.46453)
		(end 81.988152 -19.182842)
		(width 0.14224)
		(layer "In2.Cu")
		(net "M_J_ACT_N")
	)
	(segment
		(start 81.549494 -6.215126)
		(end 81.963768 -6.6294)
		(width 0.14224)
		(layer "In2.Cu")
		(net "M_J_ACT_N")
	)
	(segment
		(start 87.705692 -50.885344)
		(end 87.705692 -51.135026)
		(width 0.0889)
		(layer "In2.Cu")
		(net "M_J_ACT_N")
	)
	(segment
		(start 82.156808 -12.98956)
		(end 81.984088 -13.16228)
		(width 0.14224)
		(layer "In2.Cu")
		(net "M_J_ACT_N")
	)
	(segment
		(start 81.989168 -8.864346)
		(end 81.989168 -12.195556)
		(width 0.14224)
		(layer "In2.Cu")
		(net "M_J_ACT_N")
	)
	(segment
		(start 87.855552 -59.131962)
		(end 87.992458 -59.21248)
		(width 0.0889)
		(layer "In2.Cu")
		(net "M_J_ACT_N")
	)
	(segment
		(start 87.430356 -53.800502)
		(end 87.435182 -53.809138)
		(width 0.0889)
		(layer "In2.Cu")
		(net "M_J_ACT_N")
	)
	(segment
		(start 81.984088 -13.16228)
		(end 81.984088 -16.987266)
		(width 0.14224)
		(layer "In2.Cu")
		(net "M_J_ACT_N")
	)
	(segment
		(start 81.693258 -0.677672)
		(end 81.693258 -1.160272)
		(width 0.14224)
		(layer "In2.Cu")
		(net "M_J_ACT_N")
	)
	(segment
		(start 81.988152 -19.182842)
		(end 81.902808 -19.268186)
		(width 0.14224)
		(layer "In2.Cu")
		(net "M_J_ACT_N")
	)
	(segment
		(start 81.538318 -1.315212)
		(end 81.271364 -1.315212)
		(width 0.14224)
		(layer "In2.Cu")
		(net "M_J_ACT_N")
	)
	(segment
		(start 87.441532 -58.35142)
		(end 87.435182 -58.362088)
		(width 0.0889)
		(layer "In2.Cu")
		(net "M_J_ACT_N")
	)
	(segment
		(start 81.942178 -22.623526)
		(end 81.942178 -23.222966)
		(width 0.14224)
		(layer "In2.Cu")
		(net "M_J_ACT_N")
	)
	(segment
		(start 81.963768 -6.6294)
		(end 81.963768 -7.365746)
		(width 0.14224)
		(layer "In2.Cu")
		(net "M_J_ACT_N")
	)
	(segment
		(start 81.902808 -21.710396)
		(end 82.006694 -21.814282)
		(width 0.14224)
		(layer "In2.Cu")
		(net "M_J_ACT_N")
	)
	(segment
		(start 87.430356 -54.791102)
		(end 87.435182 -54.799738)
		(width 0.0889)
		(layer "In2.Cu")
		(net "M_J_ACT_N")
	)
	(segment
		(start 82.156808 -8.696706)
		(end 81.989168 -8.864346)
		(width 0.14224)
		(layer "In2.Cu")
		(net "M_J_ACT_N")
	)
	(segment
		(start 87.435182 -55.790338)
		(end 87.441532 -55.801006)
		(width 0.0889)
		(layer "In2.Cu")
		(net "M_J_ACT_N")
	)
	(segment
		(start 88.186768 -59.893454)
		(end 88.3412 -60.047886)
		(width 0.0889)
		(layer "In2.Cu")
		(net "M_J_ACT_N")
	)
	(segment
		(start 82.065368 -18.387314)
		(end 81.988152 -18.46453)
		(width 0.14224)
		(layer "In2.Cu")
		(net "M_J_ACT_N")
	)
	(segment
		(start 82.065368 -17.068546)
		(end 82.065368 -18.387314)
		(width 0.14224)
		(layer "In2.Cu")
		(net "M_J_ACT_N")
	)
	(segment
		(start 87.381842 -51.458876)
		(end 87.381842 -51.732688)
		(width 0.0889)
		(layer "In2.Cu")
		(net "M_J_ACT_N")
	)
	(segment
		(start 81.549494 1.805432)
		(end 81.549494 1.185926)
		(width 0.14224)
		(layer "In2.Cu")
		(net "M_J_ACT_N")
	)
	(segment
		(start 81.271364 -0.522732)
		(end 81.538318 -0.522732)
		(width 0.14224)
		(layer "In2.Cu")
		(net "M_J_ACT_N")
	)
	(segment
		(start 81.989168 -12.195556)
		(end 82.156808 -12.363196)
		(width 0.14224)
		(layer "In2.Cu")
		(net "M_J_ACT_N")
	)
	(segment
		(start 82.006694 -21.814282)
		(end 82.006694 -22.55901)
		(width 0.14224)
		(layer "In2.Cu")
		(net "M_J_ACT_N")
	)
	(segment
		(start 81.116424 -1.470152)
		(end 81.116424 -3.673856)
		(width 0.14224)
		(layer "In2.Cu")
		(net "M_J_ACT_N")
	)
	(segment
		(start 81.116424 -0.367792)
		(end 81.271364 -0.522732)
		(width 0.14224)
		(layer "In2.Cu")
		(net "M_J_ACT_N")
	)
	(segment
		(start 87.430356 -55.781702)
		(end 87.435182 -55.790338)
		(width 0.0889)
		(layer "In2.Cu")
		(net "M_J_ACT_N")
	)
	(segment
		(start 81.116424 0.752856)
		(end 81.116424 -0.367792)
		(width 0.14224)
		(layer "In2.Cu")
		(net "M_J_ACT_N")
	)
	(segment
		(start 81.984088 -16.987266)
		(end 82.065368 -17.068546)
		(width 0.14224)
		(layer "In2.Cu")
		(net "M_J_ACT_N")
	)
	(segment
		(start 82.006694 -22.55901)
		(end 81.942178 -22.623526)
		(width 0.14224)
		(layer "In2.Cu")
		(net "M_J_ACT_N")
	)
	(segment
		(start 87.705692 -31.826962)
		(end 87.705692 -50.885344)
		(width 0.14224)
		(layer "In2.Cu")
		(net "M_J_ACT_N")
	)
	(segment
		(start 88.186768 -59.538616)
		(end 88.186768 -59.893454)
		(width 0.0889)
		(layer "In2.Cu")
		(net "M_J_ACT_N")
	)
	(segment
		(start 83.716368 -27.837638)
		(end 87.705692 -31.826962)
		(width 0.14224)
		(layer "In2.Cu")
		(net "M_J_ACT_N")
	)
	(segment
		(start 82.014568 -24.3332)
		(end 83.716368 -26.035)
		(width 0.14224)
		(layer "In2.Cu")
		(net "M_J_ACT_N")
	)
	(segment
		(start 88.128602 -59.352688)
		(end 88.145366 -59.382152)
		(width 0.0889)
		(layer "In2.Cu")
		(net "M_J_ACT_N")
	)
	(segment
		(start 81.549494 -4.332478)
		(end 81.549494 -6.215126)
		(width 0.14224)
		(layer "In2.Cu")
		(net "M_J_ACT_N")
	)
	(segment
		(start 81.902808 -19.268186)
		(end 81.902808 -21.710396)
		(width 0.14224)
		(layer "In2.Cu")
		(net "M_J_ACT_N")
	)
	(segment
		(start 87.435182 -58.761884)
		(end 87.477092 -58.834528)
		(width 0.0889)
		(layer "In2.Cu")
		(net "M_J_ACT_N")
	)
	(segment
		(start 81.538318 -0.522732)
		(end 81.693258 -0.677672)
		(width 0.14224)
		(layer "In2.Cu")
		(net "M_J_ACT_N")
	)
	(segment
		(start 88.3412 -60.047886)
		(end 88.640412 -60.047886)
		(width 0.0889)
		(layer "In2.Cu")
		(net "M_J_ACT_N")
	)
	(segment
		(start 83.716368 -26.035)
		(end 83.716368 -27.837638)
		(width 0.14224)
		(layer "In2.Cu")
		(net "M_J_ACT_N")
	)
	(segment
		(start 87.430356 -57.762902)
		(end 87.435182 -57.771538)
		(width 0.0889)
		(layer "In2.Cu")
		(net "M_J_ACT_N")
	)
	(segment
		(start 82.156808 -12.363196)
		(end 82.156808 -12.98956)
		(width 0.14224)
		(layer "In2.Cu")
		(net "M_J_ACT_N")
	)
	(segment
		(start 87.435182 -53.809138)
		(end 87.441532 -53.819806)
		(width 0.0889)
		(layer "In2.Cu")
		(net "M_J_ACT_N")
	)
	(segment
		(start 87.435182 -56.780938)
		(end 87.441532 -56.791606)
		(width 0.0889)
		(layer "In2.Cu")
		(net "M_J_ACT_N")
	)
	(segment
		(start 87.381842 -51.732688)
		(end 87.435182 -51.827938)
		(width 0.0889)
		(layer "In2.Cu")
		(net "M_J_ACT_N")
	)
	(segment
		(start 81.963768 -7.365746)
		(end 82.156808 -7.558786)
		(width 0.14224)
		(layer "In2.Cu")
		(net "M_J_ACT_N")
	)
	(segment
		(start 87.430356 -56.772302)
		(end 87.435182 -56.780938)
		(width 0.0889)
		(layer "In2.Cu")
		(net "M_J_ACT_N")
	)
	(segment
		(start 87.441532 -52.40782)
		(end 87.435182 -52.418488)
		(width 0.0889)
		(layer "In2.Cu")
		(net "M_J_ACT_N")
	)
	(segment
		(start 81.116424 -3.673856)
		(end 81.549494 -4.106926)
		(width 0.14224)
		(layer "In2.Cu")
		(net "M_J_ACT_N")
	)
	(segment
		(start 81.549494 -4.106926)
		(end 81.549494 -4.332478)
		(width 0.14224)
		(layer "In2.Cu")
		(net "M_J_ACT_N")
	)
	(segment
		(start 87.477092 -58.834528)
		(end 87.855552 -59.131962)
		(width 0.0889)
		(layer "In2.Cu")
		(net "M_J_ACT_N")
	)
	(arc
		(start 87.441532 -56.791606)
		(mid 87.51433 -57.082369)
		(end 87.435182 -57.371488)
		(width 0.0889)
		(layer "In2.Cu")
		(net "M_J_ACT_N")
	)
	(arc
		(start 88.145366 -59.382152)
		(mid 88.17623 -59.457694)
		(end 88.186768 -59.538616)
		(width 0.0889)
		(layer "In2.Cu")
		(net "M_J_ACT_N")
	)
	(arc
		(start 87.435182 -57.371488)
		(mid 87.381712 -57.566551)
		(end 87.430356 -57.762902)
		(width 0.0889)
		(layer "In2.Cu")
		(net "M_J_ACT_N")
	)
	(arc
		(start 87.435182 -55.390288)
		(mid 87.381712 -55.585351)
		(end 87.430356 -55.781702)
		(width 0.0889)
		(layer "In2.Cu")
		(net "M_J_ACT_N")
	)
	(arc
		(start 87.435182 -56.380888)
		(mid 87.381712 -56.575951)
		(end 87.430356 -56.772302)
		(width 0.0889)
		(layer "In2.Cu")
		(net "M_J_ACT_N")
	)
	(arc
		(start 87.435182 -58.362088)
		(mid 87.381683 -58.561986)
		(end 87.435182 -58.761884)
		(width 0.0889)
		(layer "In2.Cu")
		(net "M_J_ACT_N")
	)
	(arc
		(start 87.435182 -57.771538)
		(mid 87.514404 -58.060656)
		(end 87.441532 -58.35142)
		(width 0.0889)
		(layer "In2.Cu")
		(net "M_J_ACT_N")
	)
	(arc
		(start 87.435182 -52.418488)
		(mid 87.381683 -52.618386)
		(end 87.435182 -52.818284)
		(width 0.0889)
		(layer "In2.Cu")
		(net "M_J_ACT_N")
	)
	(arc
		(start 87.441532 -55.801006)
		(mid 87.51433 -56.091769)
		(end 87.435182 -56.380888)
		(width 0.0889)
		(layer "In2.Cu")
		(net "M_J_ACT_N")
	)
	(arc
		(start 87.435182 -51.827938)
		(mid 87.514404 -52.117056)
		(end 87.441532 -52.40782)
		(width 0.0889)
		(layer "In2.Cu")
		(net "M_J_ACT_N")
	)
	(arc
		(start 87.435182 -52.818284)
		(mid 87.514313 -53.113686)
		(end 87.435182 -53.409088)
		(width 0.0889)
		(layer "In2.Cu")
		(net "M_J_ACT_N")
	)
	(arc
		(start 87.992458 -59.21248)
		(mid 88.069246 -59.274127)
		(end 88.128602 -59.352688)
		(width 0.0889)
		(layer "In2.Cu")
		(net "M_J_ACT_N")
	)
	(arc
		(start 87.435182 -54.399688)
		(mid 87.381712 -54.594751)
		(end 87.430356 -54.791102)
		(width 0.0889)
		(layer "In2.Cu")
		(net "M_J_ACT_N")
	)
	(arc
		(start 87.441532 -53.819806)
		(mid 87.51433 -54.110569)
		(end 87.435182 -54.399688)
		(width 0.0889)
		(layer "In2.Cu")
		(net "M_J_ACT_N")
	)
	(arc
		(start 87.441532 -54.810406)
		(mid 87.51433 -55.101169)
		(end 87.435182 -55.390288)
		(width 0.0889)
		(layer "In2.Cu")
		(net "M_J_ACT_N")
	)
	(arc
		(start 87.435182 -53.409088)
		(mid 87.381712 -53.604151)
		(end 87.430356 -53.800502)
		(width 0.0889)
		(layer "In2.Cu")
		(net "M_J_ACT_N")
	)
	(segment
		(start 100.249736 -9.158478)
		(end 100.249736 -9.133078)
		(width 0.1651)
		(layer "F.Cu")
		(net "M_H_PAR")
	)
	(segment
		(start 96.079818 -54.104286)
		(end 95.508318 -54.104286)
		(width 0.1651)
		(layer "F.Cu")
		(net "M_H_PAR")
	)
	(segment
		(start 100.249482 -10.422382)
		(end 100.249482 -9.158732)
		(width 0.1651)
		(layer "F.Cu")
		(net "M_H_PAR")
	)
	(segment
		(start 100.249482 -9.158732)
		(end 100.249736 -9.158478)
		(width 0.1651)
		(layer "F.Cu")
		(net "M_H_PAR")
	)
	(via
		(at 95.508318 -54.104286)
		(size 0.508)
		(drill 0.254)
		(layers "F.Cu" "B.Cu")
		(net "M_H_PAR")
	)
	(via
		(at 100.249228 -12.596368)
		(size 0.508)
		(drill 0.254)
		(layers "F.Cu" "B.Cu")
		(net "M_H_PAR")
	)
	(via
		(at 100.249736 -9.133078)
		(size 0.4572)
		(drill 0.2032)
		(layers "F.Cu" "B.Cu")
		(net "M_H_PAR")
	)
	(segment
		(start 100.249482 -10.623042)
		(end 100.249228 -10.623296)
		(width 0.1651)
		(layer "B.Cu")
		(net "M_H_PAR")
	)
	(segment
		(start 100.249228 -10.623296)
		(end 100.249228 -12.596368)
		(width 0.1651)
		(layer "B.Cu")
		(net "M_H_PAR")
	)
	(segment
		(start 97.158556 -27.110436)
		(end 97.606612 -26.66238)
		(width 0.14224)
		(layer "In4.Cu")
		(net "M_H_PAR")
	)
	(segment
		(start 98.834702 -24.50211)
		(end 99.769168 -23.567644)
		(width 0.14224)
		(layer "In4.Cu")
		(net "M_H_PAR")
	)
	(segment
		(start 99.743768 -14.1732)
		(end 99.743768 -13.101828)
		(width 0.14224)
		(layer "In4.Cu")
		(net "M_H_PAR")
	)
	(segment
		(start 97.158556 -50.024792)
		(end 97.158556 -49.603406)
		(width 0.0889)
		(layer "In4.Cu")
		(net "M_H_PAR")
	)
	(segment
		(start 98.981768 -14.9352)
		(end 99.743768 -14.1732)
		(width 0.14224)
		(layer "In4.Cu")
		(net "M_H_PAR")
	)
	(segment
		(start 95.508318 -54.104286)
		(end 95.51162 -54.104286)
		(width 0.0889)
		(layer "In4.Cu")
		(net "M_H_PAR")
	)
	(segment
		(start 97.606612 -26.66238)
		(end 97.606612 -24.997156)
		(width 0.14224)
		(layer "In4.Cu")
		(net "M_H_PAR")
	)
	(segment
		(start 97.606612 -24.997156)
		(end 98.101658 -24.50211)
		(width 0.14224)
		(layer "In4.Cu")
		(net "M_H_PAR")
	)
	(segment
		(start 95.909892 -53.706014)
		(end 95.909892 -51.273456)
		(width 0.0889)
		(layer "In4.Cu")
		(net "M_H_PAR")
	)
	(segment
		(start 100.708968 -11.5824)
		(end 100.708968 -9.59231)
		(width 0.14224)
		(layer "In4.Cu")
		(net "M_H_PAR")
	)
	(segment
		(start 99.769168 -23.567644)
		(end 99.769168 -16.5862)
		(width 0.14224)
		(layer "In4.Cu")
		(net "M_H_PAR")
	)
	(segment
		(start 95.909892 -51.273456)
		(end 97.158556 -50.024792)
		(width 0.0889)
		(layer "In4.Cu")
		(net "M_H_PAR")
	)
	(segment
		(start 98.981768 -15.7988)
		(end 98.981768 -14.9352)
		(width 0.14224)
		(layer "In4.Cu")
		(net "M_H_PAR")
	)
	(segment
		(start 95.51162 -54.104286)
		(end 95.909892 -53.706014)
		(width 0.0889)
		(layer "In4.Cu")
		(net "M_H_PAR")
	)
	(segment
		(start 99.769168 -16.5862)
		(end 98.981768 -15.7988)
		(width 0.14224)
		(layer "In4.Cu")
		(net "M_H_PAR")
	)
	(segment
		(start 100.708968 -9.59231)
		(end 100.249736 -9.133078)
		(width 0.14224)
		(layer "In4.Cu")
		(net "M_H_PAR")
	)
	(segment
		(start 97.158556 -49.603406)
		(end 97.158556 -27.110436)
		(width 0.14224)
		(layer "In4.Cu")
		(net "M_H_PAR")
	)
	(segment
		(start 100.556568 -11.7348)
		(end 100.708968 -11.5824)
		(width 0.14224)
		(layer "In4.Cu")
		(net "M_H_PAR")
	)
	(segment
		(start 99.743768 -13.101828)
		(end 100.249228 -12.596368)
		(width 0.14224)
		(layer "In4.Cu")
		(net "M_H_PAR")
	)
	(segment
		(start 98.101658 -24.50211)
		(end 98.834702 -24.50211)
		(width 0.14224)
		(layer "In4.Cu")
		(net "M_H_PAR")
	)
	(segment
		(start 100.556568 -12.289028)
		(end 100.556568 -11.7348)
		(width 0.14224)
		(layer "In4.Cu")
		(net "M_H_PAR")
	)
	(segment
		(start 100.249228 -12.596368)
		(end 100.556568 -12.289028)
		(width 0.14224)
		(layer "In4.Cu")
		(net "M_H_PAR")
	)
	(segment
		(start 100.659184 -57.076086)
		(end 101.230684 -57.076086)
		(width 0.1016)
		(layer "F.Cu")
		(net "M_H_ODT<3>")
	)
	(via
		(at 111.299498 -13.934186)
		(size 0.4572)
		(drill 0.2032)
		(layers "F.Cu" "B.Cu")
		(net "M_H_ODT<3>")
	)
	(via
		(at 100.659184 -57.076086)
		(size 0.508)
		(drill 0.254)
		(layers "F.Cu" "B.Cu")
		(net "M_H_ODT<3>")
	)
	(segment
		(start 111.299498 -15.222982)
		(end 111.299498 -13.934186)
		(width 0.1651)
		(layer "B.Cu")
		(net "M_H_ODT<3>")
	)
	(segment
		(start 101.170994 -54.799738)
		(end 101.177344 -54.810406)
		(width 0.0889)
		(layer "In4.Cu")
		(net "M_H_ODT<3>")
	)
	(segment
		(start 110.068106 -22.567138)
		(end 110.068106 -23.139654)
		(width 0.14224)
		(layer "In4.Cu")
		(net "M_H_ODT<3>")
	)
	(segment
		(start 101.170994 -55.390288)
		(end 101.005894 -55.676292)
		(width 0.0889)
		(layer "In4.Cu")
		(net "M_H_ODT<3>")
	)
	(segment
		(start 100.98913 -56.31434)
		(end 100.659184 -57.076086)
		(width 0.0889)
		(layer "In4.Cu")
		(net "M_H_ODT<3>")
	)
	(segment
		(start 109.974634 -21.836126)
		(end 109.974634 -22.473666)
		(width 0.14224)
		(layer "In4.Cu")
		(net "M_H_ODT<3>")
	)
	(segment
		(start 110.037626 -16.93418)
		(end 109.660944 -17.310862)
		(width 0.14224)
		(layer "In4.Cu")
		(net "M_H_ODT<3>")
	)
	(segment
		(start 101.779578 -54.19979)
		(end 101.502718 -54.19979)
		(width 0.0889)
		(layer "In4.Cu")
		(net "M_H_ODT<3>")
	)
	(segment
		(start 109.893862 -23.313898)
		(end 109.893862 -24.165306)
		(width 0.14224)
		(layer "In4.Cu")
		(net "M_H_ODT<3>")
	)
	(segment
		(start 109.660944 -17.310862)
		(end 109.660944 -18.075402)
		(width 0.14224)
		(layer "In4.Cu")
		(net "M_H_ODT<3>")
	)
	(segment
		(start 102.108 -53.871368)
		(end 101.779578 -54.19979)
		(width 0.0889)
		(layer "In4.Cu")
		(net "M_H_ODT<3>")
	)
	(segment
		(start 110.037626 -15.196058)
		(end 110.037626 -16.93418)
		(width 0.14224)
		(layer "In4.Cu")
		(net "M_H_ODT<3>")
	)
	(segment
		(start 108.125768 -25.9334)
		(end 108.125768 -27.52852)
		(width 0.14224)
		(layer "In4.Cu")
		(net "M_H_ODT<3>")
	)
	(segment
		(start 109.974634 -22.473666)
		(end 110.068106 -22.567138)
		(width 0.14224)
		(layer "In4.Cu")
		(net "M_H_ODT<3>")
	)
	(segment
		(start 101.005894 -56.285638)
		(end 100.98913 -56.31434)
		(width 0.0889)
		(layer "In4.Cu")
		(net "M_H_ODT<3>")
	)
	(segment
		(start 109.893862 -24.165306)
		(end 108.125768 -25.9334)
		(width 0.14224)
		(layer "In4.Cu")
		(net "M_H_ODT<3>")
	)
	(segment
		(start 109.660944 -18.075402)
		(end 110.0328 -18.447258)
		(width 0.14224)
		(layer "In4.Cu")
		(net "M_H_ODT<3>")
	)
	(segment
		(start 102.108 -50.160682)
		(end 102.108 -53.871368)
		(width 0.0889)
		(layer "In4.Cu")
		(net "M_H_ODT<3>")
	)
	(segment
		(start 101.005894 -55.885588)
		(end 101.01072 -55.894224)
		(width 0.0889)
		(layer "In4.Cu")
		(net "M_H_ODT<3>")
	)
	(segment
		(start 108.125768 -27.52852)
		(end 102.312724 -33.341564)
		(width 0.14224)
		(layer "In4.Cu")
		(net "M_H_ODT<3>")
	)
	(segment
		(start 102.312724 -33.341564)
		(end 102.312724 -49.67097)
		(width 0.14224)
		(layer "In4.Cu")
		(net "M_H_ODT<3>")
	)
	(segment
		(start 110.068106 -23.139654)
		(end 109.893862 -23.313898)
		(width 0.14224)
		(layer "In4.Cu")
		(net "M_H_ODT<3>")
	)
	(segment
		(start 111.299498 -13.934186)
		(end 110.037626 -15.196058)
		(width 0.14224)
		(layer "In4.Cu")
		(net "M_H_ODT<3>")
	)
	(segment
		(start 101.166168 -54.791102)
		(end 101.170994 -54.799738)
		(width 0.0889)
		(layer "In4.Cu")
		(net "M_H_ODT<3>")
	)
	(segment
		(start 110.0328 -18.447258)
		(end 110.0328 -21.77796)
		(width 0.14224)
		(layer "In4.Cu")
		(net "M_H_ODT<3>")
	)
	(segment
		(start 110.0328 -21.77796)
		(end 109.974634 -21.836126)
		(width 0.14224)
		(layer "In4.Cu")
		(net "M_H_ODT<3>")
	)
	(segment
		(start 102.312724 -49.67097)
		(end 102.312724 -49.955958)
		(width 0.0889)
		(layer "In4.Cu")
		(net "M_H_ODT<3>")
	)
	(segment
		(start 102.312724 -49.955958)
		(end 102.108 -50.160682)
		(width 0.0889)
		(layer "In4.Cu")
		(net "M_H_ODT<3>")
	)
	(arc
		(start 101.177344 -54.810406)
		(mid 101.250142 -55.101169)
		(end 101.170994 -55.390288)
		(width 0.0889)
		(layer "In4.Cu")
		(net "M_H_ODT<3>")
	)
	(arc
		(start 101.01072 -55.894224)
		(mid 101.059475 -56.090576)
		(end 101.005894 -56.285638)
		(width 0.0889)
		(layer "In4.Cu")
		(net "M_H_ODT<3>")
	)
	(arc
		(start 101.502718 -54.19979)
		(mid 101.1698 -54.401781)
		(end 101.166168 -54.791102)
		(width 0.0889)
		(layer "In4.Cu")
		(net "M_H_ODT<3>")
	)
	(arc
		(start 101.005894 -55.676292)
		(mid 100.977867 -55.78094)
		(end 101.005894 -55.885588)
		(width 0.0889)
		(layer "In4.Cu")
		(net "M_H_ODT<3>")
	)
	(segment
		(start 98.942398 -55.094886)
		(end 99.513898 -55.094886)
		(width 0.1016)
		(layer "F.Cu")
		(net "M_H_ODT<2>")
	)
	(via
		(at 98.942398 -55.094886)
		(size 0.508)
		(drill 0.254)
		(layers "F.Cu" "B.Cu")
		(net "M_H_ODT<2>")
	)
	(via
		(at 107.899454 -13.929868)
		(size 0.4572)
		(drill 0.2032)
		(layers "F.Cu" "B.Cu")
		(net "M_H_ODT<2>")
	)
	(segment
		(start 107.899454 -15.222982)
		(end 107.899454 -13.929868)
		(width 0.1651)
		(layer "B.Cu")
		(net "M_H_ODT<2>")
	)
	(segment
		(start 99.591368 -52.832)
		(end 100.061014 -52.362354)
		(width 0.0889)
		(layer "In4.Cu")
		(net "M_H_ODT<2>")
	)
	(segment
		(start 106.640376 -19.063716)
		(end 106.640376 -18.456656)
		(width 0.14224)
		(layer "In4.Cu")
		(net "M_H_ODT<2>")
	)
	(segment
		(start 106.565446 -18.153634)
		(end 106.565446 -17.134586)
		(width 0.14224)
		(layer "In4.Cu")
		(net "M_H_ODT<2>")
	)
	(segment
		(start 106.418888 -15.27048)
		(end 107.7595 -13.929868)
		(width 0.14224)
		(layer "In4.Cu")
		(net "M_H_ODT<2>")
	)
	(segment
		(start 99.454208 -53.409342)
		(end 99.591368 -53.158136)
		(width 0.0889)
		(layer "In4.Cu")
		(net "M_H_ODT<2>")
	)
	(segment
		(start 104.798368 -27.980894)
		(end 104.798368 -25.9842)
		(width 0.14224)
		(layer "In4.Cu")
		(net "M_H_ODT<2>")
	)
	(segment
		(start 99.463098 -53.824378)
		(end 99.454208 -53.809138)
		(width 0.0889)
		(layer "In4.Cu")
		(net "M_H_ODT<2>")
	)
	(segment
		(start 106.565446 -17.134586)
		(end 106.639868 -17.060164)
		(width 0.14224)
		(layer "In4.Cu")
		(net "M_H_ODT<2>")
	)
	(segment
		(start 100.520246 -32.259016)
		(end 104.798368 -27.980894)
		(width 0.14224)
		(layer "In4.Cu")
		(net "M_H_ODT<2>")
	)
	(segment
		(start 100.252276 -50.50028)
		(end 100.252276 -49.957482)
		(width 0.0889)
		(layer "In4.Cu")
		(net "M_H_ODT<2>")
	)
	(segment
		(start 98.942398 -55.094886)
		(end 99.169728 -54.816502)
		(width 0.0889)
		(layer "In4.Cu")
		(net "M_H_ODT<2>")
	)
	(segment
		(start 100.505768 -50.753772)
		(end 100.252276 -50.50028)
		(width 0.0889)
		(layer "In4.Cu")
		(net "M_H_ODT<2>")
	)
	(segment
		(start 106.644694 -18.452338)
		(end 106.644694 -18.232882)
		(width 0.14224)
		(layer "In4.Cu")
		(net "M_H_ODT<2>")
	)
	(segment
		(start 100.061014 -52.362354)
		(end 100.061268 -52.362354)
		(width 0.0889)
		(layer "In4.Cu")
		(net "M_H_ODT<2>")
	)
	(segment
		(start 100.520246 -49.014888)
		(end 100.520246 -32.259016)
		(width 0.14224)
		(layer "In4.Cu")
		(net "M_H_ODT<2>")
	)
	(segment
		(start 100.061268 -52.362354)
		(end 100.505768 -51.917854)
		(width 0.0889)
		(layer "In4.Cu")
		(net "M_H_ODT<2>")
	)
	(segment
		(start 106.576368 -23.274274)
		(end 106.717846 -23.132796)
		(width 0.14224)
		(layer "In4.Cu")
		(net "M_H_ODT<2>")
	)
	(segment
		(start 100.252276 -49.957482)
		(end 100.520246 -49.689512)
		(width 0.0889)
		(layer "In4.Cu")
		(net "M_H_ODT<2>")
	)
	(segment
		(start 106.644694 -18.232882)
		(end 106.565446 -18.153634)
		(width 0.14224)
		(layer "In4.Cu")
		(net "M_H_ODT<2>")
	)
	(segment
		(start 106.717846 -23.132796)
		(end 106.717846 -19.141186)
		(width 0.14224)
		(layer "In4.Cu")
		(net "M_H_ODT<2>")
	)
	(segment
		(start 106.717846 -19.141186)
		(end 106.640376 -19.063716)
		(width 0.14224)
		(layer "In4.Cu")
		(net "M_H_ODT<2>")
	)
	(segment
		(start 107.7595 -13.929868)
		(end 107.899454 -13.929868)
		(width 0.14224)
		(layer "In4.Cu")
		(net "M_H_ODT<2>")
	)
	(segment
		(start 106.640376 -18.456656)
		(end 106.644694 -18.452338)
		(width 0.14224)
		(layer "In4.Cu")
		(net "M_H_ODT<2>")
	)
	(segment
		(start 100.520246 -49.689512)
		(end 100.520246 -49.014888)
		(width 0.0889)
		(layer "In4.Cu")
		(net "M_H_ODT<2>")
	)
	(segment
		(start 99.591368 -53.158136)
		(end 99.591368 -52.832)
		(width 0.0889)
		(layer "In4.Cu")
		(net "M_H_ODT<2>")
	)
	(segment
		(start 106.639868 -16.4211)
		(end 106.418888 -16.20012)
		(width 0.14224)
		(layer "In4.Cu")
		(net "M_H_ODT<2>")
	)
	(segment
		(start 106.418888 -16.20012)
		(end 106.418888 -15.27048)
		(width 0.14224)
		(layer "In4.Cu")
		(net "M_H_ODT<2>")
	)
	(segment
		(start 99.169728 -54.816502)
		(end 99.374198 -54.54142)
		(width 0.0889)
		(layer "In4.Cu")
		(net "M_H_ODT<2>")
	)
	(segment
		(start 106.576368 -24.2062)
		(end 106.576368 -23.274274)
		(width 0.14224)
		(layer "In4.Cu")
		(net "M_H_ODT<2>")
	)
	(segment
		(start 106.639868 -17.060164)
		(end 106.639868 -16.4211)
		(width 0.14224)
		(layer "In4.Cu")
		(net "M_H_ODT<2>")
	)
	(segment
		(start 99.374198 -54.54142)
		(end 99.454208 -54.399942)
		(width 0.0889)
		(layer "In4.Cu")
		(net "M_H_ODT<2>")
	)
	(segment
		(start 104.798368 -25.9842)
		(end 106.576368 -24.2062)
		(width 0.14224)
		(layer "In4.Cu")
		(net "M_H_ODT<2>")
	)
	(segment
		(start 100.505768 -51.917854)
		(end 100.505768 -50.753772)
		(width 0.0889)
		(layer "In4.Cu")
		(net "M_H_ODT<2>")
	)
	(arc
		(start 99.454208 -53.809138)
		(mid 99.400675 -53.60924)
		(end 99.454208 -53.409342)
		(width 0.0889)
		(layer "In4.Cu")
		(net "M_H_ODT<2>")
	)
	(arc
		(start 99.454208 -54.399942)
		(mid 99.533397 -54.113327)
		(end 99.463098 -53.824378)
		(width 0.0889)
		(layer "In4.Cu")
		(net "M_H_ODT<2>")
	)
	(segment
		(start 111.299498 -7.11708)
		(end 111.300006 -7.117588)
		(width 0.1651)
		(layer "F.Cu")
		(net "M_H_ODT<1>")
	)
	(segment
		(start 111.299498 -5.822442)
		(end 111.299498 -7.11708)
		(width 0.1651)
		(layer "F.Cu")
		(net "M_H_ODT<1>")
	)
	(segment
		(start 100.372164 -56.58104)
		(end 99.800664 -56.58104)
		(width 0.1016)
		(layer "F.Cu")
		(net "M_H_ODT<1>")
	)
	(via
		(at 99.800664 -56.58104)
		(size 0.508)
		(drill 0.254)
		(layers "F.Cu" "B.Cu")
		(net "M_H_ODT<1>")
	)
	(via
		(at 111.300006 -7.117588)
		(size 0.4572)
		(drill 0.2032)
		(layers "F.Cu" "B.Cu")
		(net "M_H_ODT<1>")
	)
	(segment
		(start 109.109764 -22.599396)
		(end 109.109764 -23.132796)
		(width 0.14224)
		(layer "In4.Cu")
		(net "M_H_ODT<1>")
	)
	(segment
		(start 109.084364 -18.302986)
		(end 109.157516 -18.376138)
		(width 0.14224)
		(layer "In4.Cu")
		(net "M_H_ODT<1>")
	)
	(segment
		(start 109.214666 -23.237698)
		(end 109.214666 -24.082502)
		(width 0.14224)
		(layer "In4.Cu")
		(net "M_H_ODT<1>")
	)
	(segment
		(start 109.157516 -18.376138)
		(end 109.157516 -21.129244)
		(width 0.14224)
		(layer "In4.Cu")
		(net "M_H_ODT<1>")
	)
	(segment
		(start 110.040928 -8.90524)
		(end 110.040928 -12.25804)
		(width 0.14224)
		(layer "In4.Cu")
		(net "M_H_ODT<1>")
	)
	(segment
		(start 110.040928 -12.25804)
		(end 109.655102 -12.643866)
		(width 0.14224)
		(layer "In4.Cu")
		(net "M_H_ODT<1>")
	)
	(segment
		(start 107.617768 -25.6794)
		(end 107.617768 -27.3177)
		(width 0.14224)
		(layer "In4.Cu")
		(net "M_H_ODT<1>")
	)
	(segment
		(start 101.9175 -33.017968)
		(end 101.9175 -49.695608)
		(width 0.14224)
		(layer "In4.Cu")
		(net "M_H_ODT<1>")
	)
	(segment
		(start 100.999544 -54.88432)
		(end 101.005894 -54.894988)
		(width 0.0889)
		(layer "In4.Cu")
		(net "M_H_ODT<1>")
	)
	(segment
		(start 100.312474 -55.885588)
		(end 100.29571 -55.915052)
		(width 0.0889)
		(layer "In4.Cu")
		(net "M_H_ODT<1>")
	)
	(segment
		(start 101.9175 -49.695608)
		(end 101.9175 -53.779674)
		(width 0.0889)
		(layer "In4.Cu")
		(net "M_H_ODT<1>")
	)
	(segment
		(start 109.655102 -13.244322)
		(end 110.015274 -13.604494)
		(width 0.14224)
		(layer "In4.Cu")
		(net "M_H_ODT<1>")
	)
	(segment
		(start 109.219238 -21.87067)
		(end 109.219238 -22.489922)
		(width 0.14224)
		(layer "In4.Cu")
		(net "M_H_ODT<1>")
	)
	(segment
		(start 109.162342 -17.742408)
		(end 109.084364 -17.820386)
		(width 0.14224)
		(layer "In4.Cu")
		(net "M_H_ODT<1>")
	)
	(segment
		(start 101.005894 -55.295038)
		(end 100.841302 -55.58028)
		(width 0.0889)
		(layer "In4.Cu")
		(net "M_H_ODT<1>")
	)
	(segment
		(start 109.109764 -23.132796)
		(end 109.214666 -23.237698)
		(width 0.14224)
		(layer "In4.Cu")
		(net "M_H_ODT<1>")
	)
	(segment
		(start 109.157516 -21.129244)
		(end 109.106208 -21.180552)
		(width 0.14224)
		(layer "In4.Cu")
		(net "M_H_ODT<1>")
	)
	(segment
		(start 109.214666 -24.082502)
		(end 107.617768 -25.6794)
		(width 0.14224)
		(layer "In4.Cu")
		(net "M_H_ODT<1>")
	)
	(segment
		(start 110.015274 -13.604494)
		(end 110.015274 -14.471142)
		(width 0.14224)
		(layer "In4.Cu")
		(net "M_H_ODT<1>")
	)
	(segment
		(start 109.219238 -22.489922)
		(end 109.109764 -22.599396)
		(width 0.14224)
		(layer "In4.Cu")
		(net "M_H_ODT<1>")
	)
	(segment
		(start 109.084364 -17.820386)
		(end 109.084364 -18.302986)
		(width 0.14224)
		(layer "In4.Cu")
		(net "M_H_ODT<1>")
	)
	(segment
		(start 100.29571 -55.915052)
		(end 99.800664 -56.58104)
		(width 0.0889)
		(layer "In4.Cu")
		(net "M_H_ODT<1>")
	)
	(segment
		(start 110.015274 -14.471142)
		(end 109.162342 -15.324074)
		(width 0.14224)
		(layer "In4.Cu")
		(net "M_H_ODT<1>")
	)
	(segment
		(start 111.300006 -7.117588)
		(end 111.300006 -7.646162)
		(width 0.14224)
		(layer "In4.Cu")
		(net "M_H_ODT<1>")
	)
	(segment
		(start 101.005894 -54.894988)
		(end 101.01072 -54.903624)
		(width 0.0889)
		(layer "In4.Cu")
		(net "M_H_ODT<1>")
	)
	(segment
		(start 109.106208 -21.75764)
		(end 109.219238 -21.87067)
		(width 0.14224)
		(layer "In4.Cu")
		(net "M_H_ODT<1>")
	)
	(segment
		(start 109.162342 -15.324074)
		(end 109.162342 -17.742408)
		(width 0.14224)
		(layer "In4.Cu")
		(net "M_H_ODT<1>")
	)
	(segment
		(start 100.659184 -55.685436)
		(end 100.648008 -55.685436)
		(width 0.0889)
		(layer "In4.Cu")
		(net "M_H_ODT<1>")
	)
	(segment
		(start 101.9175 -53.779674)
		(end 101.687884 -54.00929)
		(width 0.0889)
		(layer "In4.Cu")
		(net "M_H_ODT<1>")
	)
	(segment
		(start 107.617768 -27.3177)
		(end 101.9175 -33.017968)
		(width 0.14224)
		(layer "In4.Cu")
		(net "M_H_ODT<1>")
	)
	(segment
		(start 111.300006 -7.646162)
		(end 110.040928 -8.90524)
		(width 0.14224)
		(layer "In4.Cu")
		(net "M_H_ODT<1>")
	)
	(segment
		(start 101.687884 -54.00929)
		(end 101.496114 -54.00929)
		(width 0.0889)
		(layer "In4.Cu")
		(net "M_H_ODT<1>")
	)
	(segment
		(start 109.106208 -21.180552)
		(end 109.106208 -21.75764)
		(width 0.14224)
		(layer "In4.Cu")
		(net "M_H_ODT<1>")
	)
	(segment
		(start 109.655102 -12.643866)
		(end 109.655102 -13.244322)
		(width 0.14224)
		(layer "In4.Cu")
		(net "M_H_ODT<1>")
	)
	(arc
		(start 100.841302 -55.58028)
		(mid 100.764329 -55.657249)
		(end 100.659184 -55.685436)
		(width 0.0889)
		(layer "In4.Cu")
		(net "M_H_ODT<1>")
	)
	(arc
		(start 101.496114 -54.00929)
		(mid 101.003724 -54.308223)
		(end 100.999544 -54.88432)
		(width 0.0889)
		(layer "In4.Cu")
		(net "M_H_ODT<1>")
	)
	(arc
		(start 100.648008 -55.685436)
		(mid 100.454158 -55.741786)
		(end 100.312474 -55.885588)
		(width 0.0889)
		(layer "In4.Cu")
		(net "M_H_ODT<1>")
	)
	(arc
		(start 101.01072 -54.903624)
		(mid 101.059475 -55.099976)
		(end 101.005894 -55.295038)
		(width 0.0889)
		(layer "In4.Cu")
		(net "M_H_ODT<1>")
	)
	(segment
		(start 98.655378 -55.59044)
		(end 98.083878 -55.59044)
		(width 0.1016)
		(layer "F.Cu")
		(net "M_H_ODT<0>")
	)
	(segment
		(start 107.899454 -5.822442)
		(end 107.899454 -7.113778)
		(width 0.1651)
		(layer "F.Cu")
		(net "M_H_ODT<0>")
	)
	(via
		(at 107.899454 -7.113778)
		(size 0.508)
		(drill 0.254)
		(layers "F.Cu" "B.Cu")
		(net "M_H_ODT<0>")
	)
	(via
		(at 98.083878 -55.59044)
		(size 0.508)
		(drill 0.254)
		(layers "F.Cu" "B.Cu")
		(net "M_H_ODT<0>")
	)
	(segment
		(start 104.290368 -27.770074)
		(end 104.290368 -25.7556)
		(width 0.14224)
		(layer "In4.Cu")
		(net "M_H_ODT<0>")
	)
	(segment
		(start 105.864152 -24.181816)
		(end 105.864152 -23.345648)
		(width 0.14224)
		(layer "In4.Cu")
		(net "M_H_ODT<0>")
	)
	(segment
		(start 100.057966 -50.632614)
		(end 100.057966 -49.862232)
		(width 0.0889)
		(layer "In4.Cu")
		(net "M_H_ODT<0>")
	)
	(segment
		(start 107.462828 -13.160756)
		(end 107.462828 -8.78586)
		(width 0.14224)
		(layer "In4.Cu")
		(net "M_H_ODT<0>")
	)
	(segment
		(start 104.290368 -25.7556)
		(end 105.864152 -24.181816)
		(width 0.14224)
		(layer "In4.Cu")
		(net "M_H_ODT<0>")
	)
	(segment
		(start 100.230432 -49.393348)
		(end 100.062792 -49.225708)
		(width 0.0889)
		(layer "In4.Cu")
		(net "M_H_ODT<0>")
	)
	(segment
		(start 105.709974 -21.262594)
		(end 105.765092 -21.207476)
		(width 0.14224)
		(layer "In4.Cu")
		(net "M_H_ODT<0>")
	)
	(segment
		(start 99.288854 -53.313584)
		(end 99.296982 -53.29936)
		(width 0.0889)
		(layer "In4.Cu")
		(net "M_H_ODT<0>")
	)
	(segment
		(start 105.765092 -16.406876)
		(end 105.852468 -16.3195)
		(width 0.14224)
		(layer "In4.Cu")
		(net "M_H_ODT<0>")
	)
	(segment
		(start 105.852468 -14.929866)
		(end 106.640376 -14.141958)
		(width 0.14224)
		(layer "In4.Cu")
		(net "M_H_ODT<0>")
	)
	(segment
		(start 100.062792 -49.225708)
		(end 100.062792 -49.017936)
		(width 0.0889)
		(layer "In4.Cu")
		(net "M_H_ODT<0>")
	)
	(segment
		(start 107.219496 -13.404088)
		(end 107.462828 -13.160756)
		(width 0.14224)
		(layer "In4.Cu")
		(net "M_H_ODT<0>")
	)
	(segment
		(start 98.413316 -54.829456)
		(end 98.430588 -54.799738)
		(width 0.0889)
		(layer "In4.Cu")
		(net "M_H_ODT<0>")
	)
	(segment
		(start 99.342194 -52.700174)
		(end 100.230432 -51.811936)
		(width 0.0889)
		(layer "In4.Cu")
		(net "M_H_ODT<0>")
	)
	(segment
		(start 105.833164 -21.938996)
		(end 105.709974 -21.815806)
		(width 0.14224)
		(layer "In4.Cu")
		(net "M_H_ODT<0>")
	)
	(segment
		(start 106.88828 -13.404088)
		(end 107.219496 -13.404088)
		(width 0.14224)
		(layer "In4.Cu")
		(net "M_H_ODT<0>")
	)
	(segment
		(start 99.288854 -53.904388)
		(end 99.279964 -53.889148)
		(width 0.0889)
		(layer "In4.Cu")
		(net "M_H_ODT<0>")
	)
	(segment
		(start 98.924618 -54.504336)
		(end 98.942398 -54.504336)
		(width 0.0889)
		(layer "In4.Cu")
		(net "M_H_ODT<0>")
	)
	(segment
		(start 105.852468 -16.3195)
		(end 105.852468 -14.929866)
		(width 0.14224)
		(layer "In4.Cu")
		(net "M_H_ODT<0>")
	)
	(segment
		(start 105.864152 -23.345648)
		(end 105.654602 -23.136098)
		(width 0.14224)
		(layer "In4.Cu")
		(net "M_H_ODT<0>")
	)
	(segment
		(start 105.654602 -22.625558)
		(end 105.833164 -22.446996)
		(width 0.14224)
		(layer "In4.Cu")
		(net "M_H_ODT<0>")
	)
	(segment
		(start 100.062792 -31.99765)
		(end 104.290368 -27.770074)
		(width 0.14224)
		(layer "In4.Cu")
		(net "M_H_ODT<0>")
	)
	(segment
		(start 99.342194 -53.134514)
		(end 99.342194 -52.700174)
		(width 0.0889)
		(layer "In4.Cu")
		(net "M_H_ODT<0>")
	)
	(segment
		(start 106.640376 -14.141958)
		(end 106.640376 -13.651992)
		(width 0.14224)
		(layer "In4.Cu")
		(net "M_H_ODT<0>")
	)
	(segment
		(start 105.833164 -22.446996)
		(end 105.833164 -21.938996)
		(width 0.14224)
		(layer "In4.Cu")
		(net "M_H_ODT<0>")
	)
	(segment
		(start 106.640376 -13.651992)
		(end 106.88828 -13.404088)
		(width 0.14224)
		(layer "In4.Cu")
		(net "M_H_ODT<0>")
	)
	(segment
		(start 98.083878 -55.59044)
		(end 98.413316 -54.829456)
		(width 0.0889)
		(layer "In4.Cu")
		(net "M_H_ODT<0>")
	)
	(segment
		(start 100.062792 -49.017936)
		(end 100.062792 -31.99765)
		(width 0.14224)
		(layer "In4.Cu")
		(net "M_H_ODT<0>")
	)
	(segment
		(start 100.230432 -49.689766)
		(end 100.230432 -49.393348)
		(width 0.0889)
		(layer "In4.Cu")
		(net "M_H_ODT<0>")
	)
	(segment
		(start 100.230432 -51.811936)
		(end 100.230432 -50.80508)
		(width 0.0889)
		(layer "In4.Cu")
		(net "M_H_ODT<0>")
	)
	(segment
		(start 105.709974 -21.815806)
		(end 105.709974 -21.262594)
		(width 0.14224)
		(layer "In4.Cu")
		(net "M_H_ODT<0>")
	)
	(segment
		(start 105.654602 -23.136098)
		(end 105.654602 -22.625558)
		(width 0.14224)
		(layer "In4.Cu")
		(net "M_H_ODT<0>")
	)
	(segment
		(start 100.230432 -50.80508)
		(end 100.057966 -50.632614)
		(width 0.0889)
		(layer "In4.Cu")
		(net "M_H_ODT<0>")
	)
	(segment
		(start 107.899454 -8.349234)
		(end 107.899454 -7.113778)
		(width 0.14224)
		(layer "In4.Cu")
		(net "M_H_ODT<0>")
	)
	(segment
		(start 100.057966 -49.862232)
		(end 100.230432 -49.689766)
		(width 0.0889)
		(layer "In4.Cu")
		(net "M_H_ODT<0>")
	)
	(segment
		(start 107.462828 -8.78586)
		(end 107.899454 -8.349234)
		(width 0.14224)
		(layer "In4.Cu")
		(net "M_H_ODT<0>")
	)
	(segment
		(start 105.765092 -21.207476)
		(end 105.765092 -16.406876)
		(width 0.14224)
		(layer "In4.Cu")
		(net "M_H_ODT<0>")
	)
	(arc
		(start 98.430588 -54.799738)
		(mid 98.639196 -54.587806)
		(end 98.924618 -54.504336)
		(width 0.0889)
		(layer "In4.Cu")
		(net "M_H_ODT<0>")
	)
	(arc
		(start 99.296982 -53.29936)
		(mid 99.328499 -53.21938)
		(end 99.342194 -53.134514)
		(width 0.0889)
		(layer "In4.Cu")
		(net "M_H_ODT<0>")
	)
	(arc
		(start 99.279964 -53.889148)
		(mid 99.209567 -53.600197)
		(end 99.288854 -53.313584)
		(width 0.0889)
		(layer "In4.Cu")
		(net "M_H_ODT<0>")
	)
	(arc
		(start 98.942398 -54.504336)
		(mid 99.288824 -54.304359)
		(end 99.288854 -53.904388)
		(width 0.0889)
		(layer "In4.Cu")
		(net "M_H_ODT<0>")
	)
	(segment
		(start 84.949538 -5.822442)
		(end 84.949538 -7.115302)
		(width 0.1651)
		(layer "F.Cu")
		(net "M_H_MA<9>")
	)
	(segment
		(start 84.949538 -7.115302)
		(end 84.949284 -7.115556)
		(width 0.1651)
		(layer "F.Cu")
		(net "M_H_MA<9>")
	)
	(segment
		(start 90.928698 -54.104286)
		(end 90.357198 -54.104286)
		(width 0.1016)
		(layer "F.Cu")
		(net "M_H_MA<9>")
	)
	(via
		(at 84.949284 -7.115556)
		(size 0.4572)
		(drill 0.2032)
		(layers "F.Cu" "B.Cu")
		(net "M_H_MA<9>")
	)
	(via
		(at 90.357198 -54.104286)
		(size 0.508)
		(drill 0.254)
		(layers "F.Cu" "B.Cu")
		(net "M_H_MA<9>")
	)
	(via
		(at 84.949538 -13.933678)
		(size 0.4572)
		(drill 0.2032)
		(layers "F.Cu" "B.Cu")
		(net "M_H_MA<9>")
	)
	(segment
		(start 84.949538 -15.222982)
		(end 84.949538 -13.933678)
		(width 0.1651)
		(layer "B.Cu")
		(net "M_H_MA<9>")
	)
	(segment
		(start 88.720168 -22.606)
		(end 88.821768 -22.5044)
		(width 0.14224)
		(layer "In11.Cu")
		(net "M_H_MA<9>")
	)
	(segment
		(start 88.759284 -21.246084)
		(end 88.759284 -18.454116)
		(width 0.14224)
		(layer "In11.Cu")
		(net "M_H_MA<9>")
	)
	(segment
		(start 88.759284 -18.454116)
		(end 88.694768 -18.3896)
		(width 0.14224)
		(layer "In11.Cu")
		(net "M_H_MA<9>")
	)
	(segment
		(start 90.293698 -29.443934)
		(end 90.00617 -29.443934)
		(width 0.14224)
		(layer "In11.Cu")
		(net "M_H_MA<9>")
	)
	(segment
		(start 90.471752 -31.700724)
		(end 89.829132 -31.058104)
		(width 0.14224)
		(layer "In11.Cu")
		(net "M_H_MA<9>")
	)
	(segment
		(start 88.821768 -21.7932)
		(end 88.720168 -21.6916)
		(width 0.14224)
		(layer "In11.Cu")
		(net "M_H_MA<9>")
	)
	(segment
		(start 89.190068 -28.9687)
		(end 89.190068 -28.6893)
		(width 0.14224)
		(layer "In11.Cu")
		(net "M_H_MA<9>")
	)
	(segment
		(start 88.720168 -21.2852)
		(end 88.759284 -21.246084)
		(width 0.14224)
		(layer "In11.Cu")
		(net "M_H_MA<9>")
	)
	(segment
		(start 87.992712 -14.49578)
		(end 85.48624 -14.49578)
		(width 0.14224)
		(layer "In11.Cu")
		(net "M_H_MA<9>")
	)
	(segment
		(start 89.939368 -51.689)
		(end 90.471752 -51.156616)
		(width 0.0889)
		(layer "In11.Cu")
		(net "M_H_MA<9>")
	)
	(segment
		(start 88.566244 -29.592524)
		(end 89.190068 -28.9687)
		(width 0.14224)
		(layer "In11.Cu")
		(net "M_H_MA<9>")
	)
	(segment
		(start 85.48624 -14.49578)
		(end 84.949538 -13.959078)
		(width 0.14224)
		(layer "In11.Cu")
		(net "M_H_MA<9>")
	)
	(segment
		(start 88.929972 -30.232604)
		(end 88.566244 -29.868876)
		(width 0.14224)
		(layer "In11.Cu")
		(net "M_H_MA<9>")
	)
	(segment
		(start 88.786462 -17.662906)
		(end 88.786462 -16.225774)
		(width 0.14224)
		(layer "In11.Cu")
		(net "M_H_MA<9>")
	)
	(segment
		(start 90.027252 -53.34254)
		(end 90.010488 -53.313838)
		(width 0.0889)
		(layer "In11.Cu")
		(net "M_H_MA<9>")
	)
	(segment
		(start 89.829132 -30.770576)
		(end 90.580972 -30.018736)
		(width 0.14224)
		(layer "In11.Cu")
		(net "M_H_MA<9>")
	)
	(segment
		(start 88.821768 -23.241)
		(end 88.720168 -23.1394)
		(width 0.14224)
		(layer "In11.Cu")
		(net "M_H_MA<9>")
	)
	(segment
		(start 88.955372 -26.067004)
		(end 88.63965 -25.751282)
		(width 0.14224)
		(layer "In11.Cu")
		(net "M_H_MA<9>")
	)
	(segment
		(start 90.00617 -29.443934)
		(end 89.2175 -30.232604)
		(width 0.14224)
		(layer "In11.Cu")
		(net "M_H_MA<9>")
	)
	(segment
		(start 88.567768 -15.070836)
		(end 87.992712 -14.49578)
		(width 0.14224)
		(layer "In11.Cu")
		(net "M_H_MA<9>")
	)
	(segment
		(start 90.580972 -30.018736)
		(end 90.580972 -29.731208)
		(width 0.14224)
		(layer "In11.Cu")
		(net "M_H_MA<9>")
	)
	(segment
		(start 88.694768 -17.7546)
		(end 88.786462 -17.662906)
		(width 0.14224)
		(layer "In11.Cu")
		(net "M_H_MA<9>")
	)
	(segment
		(start 88.63965 -23.956518)
		(end 88.821768 -23.7744)
		(width 0.14224)
		(layer "In11.Cu")
		(net "M_H_MA<9>")
	)
	(segment
		(start 88.821768 -22.5044)
		(end 88.821768 -21.7932)
		(width 0.14224)
		(layer "In11.Cu")
		(net "M_H_MA<9>")
	)
	(segment
		(start 88.955372 -28.454604)
		(end 88.955372 -26.067004)
		(width 0.14224)
		(layer "In11.Cu")
		(net "M_H_MA<9>")
	)
	(segment
		(start 90.471752 -51.156616)
		(end 90.471752 -50.820574)
		(width 0.0889)
		(layer "In11.Cu")
		(net "M_H_MA<9>")
	)
	(segment
		(start 90.580972 -29.731208)
		(end 90.293698 -29.443934)
		(width 0.14224)
		(layer "In11.Cu")
		(net "M_H_MA<9>")
	)
	(segment
		(start 88.821768 -23.7744)
		(end 88.821768 -23.241)
		(width 0.14224)
		(layer "In11.Cu")
		(net "M_H_MA<9>")
	)
	(segment
		(start 89.939368 -53.051202)
		(end 89.939368 -51.689)
		(width 0.0889)
		(layer "In11.Cu")
		(net "M_H_MA<9>")
	)
	(segment
		(start 90.357198 -54.104286)
		(end 90.027252 -53.34254)
		(width 0.0889)
		(layer "In11.Cu")
		(net "M_H_MA<9>")
	)
	(segment
		(start 84.949538 -13.933678)
		(end 85.367368 -13.515848)
		(width 0.14224)
		(layer "In11.Cu")
		(net "M_H_MA<9>")
	)
	(segment
		(start 88.566244 -29.868876)
		(end 88.566244 -29.592524)
		(width 0.14224)
		(layer "In11.Cu")
		(net "M_H_MA<9>")
	)
	(segment
		(start 88.63965 -25.751282)
		(end 88.63965 -23.956518)
		(width 0.14224)
		(layer "In11.Cu")
		(net "M_H_MA<9>")
	)
	(segment
		(start 85.367368 -7.53364)
		(end 84.949284 -7.115556)
		(width 0.14224)
		(layer "In11.Cu")
		(net "M_H_MA<9>")
	)
	(segment
		(start 89.190068 -28.6893)
		(end 88.955372 -28.454604)
		(width 0.14224)
		(layer "In11.Cu")
		(net "M_H_MA<9>")
	)
	(segment
		(start 88.694768 -18.3896)
		(end 88.694768 -17.7546)
		(width 0.14224)
		(layer "In11.Cu")
		(net "M_H_MA<9>")
	)
	(segment
		(start 88.720168 -21.6916)
		(end 88.720168 -21.2852)
		(width 0.14224)
		(layer "In11.Cu")
		(net "M_H_MA<9>")
	)
	(segment
		(start 88.786462 -16.225774)
		(end 88.567768 -16.00708)
		(width 0.14224)
		(layer "In11.Cu")
		(net "M_H_MA<9>")
	)
	(segment
		(start 90.471752 -50.820574)
		(end 90.471752 -31.700724)
		(width 0.14224)
		(layer "In11.Cu")
		(net "M_H_MA<9>")
	)
	(segment
		(start 85.367368 -13.515848)
		(end 85.367368 -7.53364)
		(width 0.14224)
		(layer "In11.Cu")
		(net "M_H_MA<9>")
	)
	(segment
		(start 89.2175 -30.232604)
		(end 88.929972 -30.232604)
		(width 0.14224)
		(layer "In11.Cu")
		(net "M_H_MA<9>")
	)
	(segment
		(start 84.949538 -13.959078)
		(end 84.949538 -13.933678)
		(width 0.14224)
		(layer "In11.Cu")
		(net "M_H_MA<9>")
	)
	(segment
		(start 88.567768 -16.00708)
		(end 88.567768 -15.070836)
		(width 0.14224)
		(layer "In11.Cu")
		(net "M_H_MA<9>")
	)
	(segment
		(start 88.720168 -23.1394)
		(end 88.720168 -22.606)
		(width 0.14224)
		(layer "In11.Cu")
		(net "M_H_MA<9>")
	)
	(segment
		(start 89.829132 -31.058104)
		(end 89.829132 -30.770576)
		(width 0.14224)
		(layer "In11.Cu")
		(net "M_H_MA<9>")
	)
	(arc
		(start 90.010488 -53.313838)
		(mid 89.957508 -53.187241)
		(end 89.939368 -53.051202)
		(width 0.0889)
		(layer "In11.Cu")
		(net "M_H_MA<9>")
	)
	(segment
		(start 86.64956 -7.117588)
		(end 86.64956 -5.822442)
		(width 0.1651)
		(layer "F.Cu")
		(net "M_H_MA<8>")
	)
	(segment
		(start 90.070178 -58.561986)
		(end 89.498678 -58.561986)
		(width 0.1016)
		(layer "F.Cu")
		(net "M_H_MA<8>")
	)
	(via
		(at 86.64956 -13.933678)
		(size 0.4572)
		(drill 0.2032)
		(layers "F.Cu" "B.Cu")
		(net "M_H_MA<8>")
	)
	(via
		(at 86.64956 -7.117588)
		(size 0.4572)
		(drill 0.2032)
		(layers "F.Cu" "B.Cu")
		(net "M_H_MA<8>")
	)
	(via
		(at 89.498678 -58.561986)
		(size 0.508)
		(drill 0.254)
		(layers "F.Cu" "B.Cu")
		(net "M_H_MA<8>")
	)
	(segment
		(start 86.64956 -15.222982)
		(end 86.64956 -13.933678)
		(width 0.1651)
		(layer "B.Cu")
		(net "M_H_MA<8>")
	)
	(segment
		(start 85.367368 -21.093684)
		(end 85.367368 -18.443702)
		(width 0.14224)
		(layer "In4.Cu")
		(net "M_H_MA<8>")
	)
	(segment
		(start 85.672168 -23.7744)
		(end 85.672168 -23.552912)
		(width 0.14224)
		(layer "In4.Cu")
		(net "M_H_MA<8>")
	)
	(segment
		(start 85.672168 -23.552912)
		(end 85.302852 -23.183596)
		(width 0.14224)
		(layer "In4.Cu")
		(net "M_H_MA<8>")
	)
	(segment
		(start 85.556852 -21.964396)
		(end 85.302852 -21.710396)
		(width 0.14224)
		(layer "In4.Cu")
		(net "M_H_MA<8>")
	)
	(segment
		(start 85.302852 -22.662896)
		(end 85.556852 -22.408896)
		(width 0.14224)
		(layer "In4.Cu")
		(net "M_H_MA<8>")
	)
	(segment
		(start 85.099906 -14.617954)
		(end 85.29574 -14.42212)
		(width 0.14224)
		(layer "In4.Cu")
		(net "M_H_MA<8>")
	)
	(segment
		(start 86.64956 -13.933678)
		(end 86.209886 -13.494004)
		(width 0.14224)
		(layer "In4.Cu")
		(net "M_H_MA<8>")
	)
	(segment
		(start 85.099906 -16.011652)
		(end 85.099906 -14.617954)
		(width 0.14224)
		(layer "In4.Cu")
		(net "M_H_MA<8>")
	)
	(segment
		(start 86.209886 -8.885936)
		(end 86.357968 -8.737854)
		(width 0.14224)
		(layer "In4.Cu")
		(net "M_H_MA<8>")
	)
	(segment
		(start 89.963752 -50.826416)
		(end 89.963752 -50.478436)
		(width 0.0889)
		(layer "In4.Cu")
		(net "M_H_MA<8>")
	)
	(segment
		(start 89.161112 -56.796178)
		(end 89.152222 -56.780938)
		(width 0.0889)
		(layer "In4.Cu")
		(net "M_H_MA<8>")
	)
	(segment
		(start 86.357968 -8.08736)
		(end 86.64956 -7.795768)
		(width 0.14224)
		(layer "In4.Cu")
		(net "M_H_MA<8>")
	)
	(segment
		(start 85.29574 -14.42212)
		(end 86.455758 -14.42212)
		(width 0.14224)
		(layer "In4.Cu")
		(net "M_H_MA<8>")
	)
	(segment
		(start 85.63356 -18.17751)
		(end 85.63356 -17.236694)
		(width 0.14224)
		(layer "In4.Cu")
		(net "M_H_MA<8>")
	)
	(segment
		(start 86.64956 -14.228318)
		(end 86.64956 -13.933678)
		(width 0.14224)
		(layer "In4.Cu")
		(net "M_H_MA<8>")
	)
	(segment
		(start 89.278968 -52.93614)
		(end 89.278968 -51.5112)
		(width 0.0889)
		(layer "In4.Cu")
		(net "M_H_MA<8>")
	)
	(segment
		(start 89.963752 -50.478436)
		(end 89.963752 -48.719486)
		(width 0.14224)
		(layer "In4.Cu")
		(net "M_H_MA<8>")
	)
	(segment
		(start 86.64956 -7.795768)
		(end 86.64956 -7.117588)
		(width 0.14224)
		(layer "In4.Cu")
		(net "M_H_MA<8>")
	)
	(segment
		(start 90.447368 -48.23587)
		(end 90.447368 -29.7434)
		(width 0.14224)
		(layer "In4.Cu")
		(net "M_H_MA<8>")
	)
	(segment
		(start 89.161112 -53.824378)
		(end 89.152222 -53.809138)
		(width 0.0889)
		(layer "In4.Cu")
		(net "M_H_MA<8>")
	)
	(segment
		(start 90.447368 -29.7434)
		(end 85.219032 -24.515064)
		(width 0.14224)
		(layer "In4.Cu")
		(net "M_H_MA<8>")
	)
	(segment
		(start 85.361018 -16.964152)
		(end 85.361018 -16.272764)
		(width 0.14224)
		(layer "In4.Cu")
		(net "M_H_MA<8>")
	)
	(segment
		(start 86.209886 -13.494004)
		(end 86.209886 -8.885936)
		(width 0.14224)
		(layer "In4.Cu")
		(net "M_H_MA<8>")
	)
	(segment
		(start 89.403682 -58.207402)
		(end 89.152222 -57.771538)
		(width 0.0889)
		(layer "In4.Cu")
		(net "M_H_MA<8>")
	)
	(segment
		(start 85.367368 -18.443702)
		(end 85.63356 -18.17751)
		(width 0.14224)
		(layer "In4.Cu")
		(net "M_H_MA<8>")
	)
	(segment
		(start 86.455758 -14.42212)
		(end 86.64956 -14.228318)
		(width 0.14224)
		(layer "In4.Cu")
		(net "M_H_MA<8>")
	)
	(segment
		(start 89.963752 -48.719486)
		(end 90.447368 -48.23587)
		(width 0.14224)
		(layer "In4.Cu")
		(net "M_H_MA<8>")
	)
	(segment
		(start 86.357968 -8.737854)
		(end 86.357968 -8.08736)
		(width 0.14224)
		(layer "In4.Cu")
		(net "M_H_MA<8>")
	)
	(segment
		(start 89.161112 -55.805578)
		(end 89.152222 -55.790338)
		(width 0.0889)
		(layer "In4.Cu")
		(net "M_H_MA<8>")
	)
	(segment
		(start 89.161112 -54.814978)
		(end 89.152222 -54.799738)
		(width 0.0889)
		(layer "In4.Cu")
		(net "M_H_MA<8>")
	)
	(segment
		(start 89.278968 -51.5112)
		(end 89.963752 -50.826416)
		(width 0.0889)
		(layer "In4.Cu")
		(net "M_H_MA<8>")
	)
	(segment
		(start 85.302852 -23.183596)
		(end 85.302852 -22.662896)
		(width 0.14224)
		(layer "In4.Cu")
		(net "M_H_MA<8>")
	)
	(segment
		(start 85.556852 -22.408896)
		(end 85.556852 -21.964396)
		(width 0.14224)
		(layer "In4.Cu")
		(net "M_H_MA<8>")
	)
	(segment
		(start 85.361018 -16.272764)
		(end 85.099906 -16.011652)
		(width 0.14224)
		(layer "In4.Cu")
		(net "M_H_MA<8>")
	)
	(segment
		(start 85.219032 -24.227536)
		(end 85.672168 -23.7744)
		(width 0.14224)
		(layer "In4.Cu")
		(net "M_H_MA<8>")
	)
	(segment
		(start 85.219032 -24.515064)
		(end 85.219032 -24.227536)
		(width 0.14224)
		(layer "In4.Cu")
		(net "M_H_MA<8>")
	)
	(segment
		(start 85.302852 -21.1582)
		(end 85.367368 -21.093684)
		(width 0.14224)
		(layer "In4.Cu")
		(net "M_H_MA<8>")
	)
	(segment
		(start 85.63356 -17.236694)
		(end 85.361018 -16.964152)
		(width 0.14224)
		(layer "In4.Cu")
		(net "M_H_MA<8>")
	)
	(segment
		(start 85.302852 -21.710396)
		(end 85.302852 -21.1582)
		(width 0.14224)
		(layer "In4.Cu")
		(net "M_H_MA<8>")
	)
	(arc
		(start 89.152222 -56.381142)
		(mid 89.231411 -56.094527)
		(end 89.161112 -55.805578)
		(width 0.0889)
		(layer "In4.Cu")
		(net "M_H_MA<8>")
	)
	(arc
		(start 89.152222 -56.780938)
		(mid 89.098689 -56.58104)
		(end 89.152222 -56.381142)
		(width 0.0889)
		(layer "In4.Cu")
		(net "M_H_MA<8>")
	)
	(arc
		(start 89.152222 -54.399942)
		(mid 89.231411 -54.113327)
		(end 89.161112 -53.824378)
		(width 0.0889)
		(layer "In4.Cu")
		(net "M_H_MA<8>")
	)
	(arc
		(start 89.152222 -55.390542)
		(mid 89.231411 -55.103927)
		(end 89.161112 -54.814978)
		(width 0.0889)
		(layer "In4.Cu")
		(net "M_H_MA<8>")
	)
	(arc
		(start 89.152222 -57.771538)
		(mid 89.098689 -57.57164)
		(end 89.152222 -57.371742)
		(width 0.0889)
		(layer "In4.Cu")
		(net "M_H_MA<8>")
	)
	(arc
		(start 89.152222 -54.799738)
		(mid 89.098689 -54.59984)
		(end 89.152222 -54.399942)
		(width 0.0889)
		(layer "In4.Cu")
		(net "M_H_MA<8>")
	)
	(arc
		(start 89.152222 -55.790338)
		(mid 89.098689 -55.59044)
		(end 89.152222 -55.390542)
		(width 0.0889)
		(layer "In4.Cu")
		(net "M_H_MA<8>")
	)
	(arc
		(start 89.498678 -58.561986)
		(mid 89.474522 -58.378439)
		(end 89.403682 -58.207402)
		(width 0.0889)
		(layer "In4.Cu")
		(net "M_H_MA<8>")
	)
	(arc
		(start 89.152222 -53.409342)
		(mid 89.246713 -53.181078)
		(end 89.278968 -52.93614)
		(width 0.0889)
		(layer "In4.Cu")
		(net "M_H_MA<8>")
	)
	(arc
		(start 89.152222 -57.371742)
		(mid 89.231411 -57.085127)
		(end 89.161112 -56.796178)
		(width 0.0889)
		(layer "In4.Cu")
		(net "M_H_MA<8>")
	)
	(arc
		(start 89.152222 -53.809138)
		(mid 89.098689 -53.60924)
		(end 89.152222 -53.409342)
		(width 0.0889)
		(layer "In4.Cu")
		(net "M_H_MA<8>")
	)
	(segment
		(start 85.799422 -10.422382)
		(end 85.799422 -9.133078)
		(width 0.1651)
		(layer "F.Cu")
		(net "M_H_MA<7>")
	)
	(segment
		(start 89.211912 -58.06694)
		(end 88.640412 -58.06694)
		(width 0.1016)
		(layer "F.Cu")
		(net "M_H_MA<7>")
	)
	(via
		(at 85.799422 -9.133078)
		(size 0.4572)
		(drill 0.2032)
		(layers "F.Cu" "B.Cu")
		(net "M_H_MA<7>")
	)
	(via
		(at 88.640412 -58.06694)
		(size 0.508)
		(drill 0.254)
		(layers "F.Cu" "B.Cu")
		(net "M_H_MA<7>")
	)
	(via
		(at 85.799422 -11.916156)
		(size 0.4572)
		(drill 0.2032)
		(layers "F.Cu" "B.Cu")
		(net "M_H_MA<7>")
	)
	(segment
		(start 85.799422 -10.623042)
		(end 85.799422 -11.916156)
		(width 0.1651)
		(layer "B.Cu")
		(net "M_H_MA<7>")
	)
	(segment
		(start 84.901278 -9.544304)
		(end 85.653372 -9.544304)
		(width 0.14224)
		(layer "In4.Cu")
		(net "M_H_MA<7>")
	)
	(segment
		(start 84.442808 -22.446996)
		(end 84.442808 -21.888196)
		(width 0.14224)
		(layer "In4.Cu")
		(net "M_H_MA<7>")
	)
	(segment
		(start 85.238082 -10.238232)
		(end 85.238082 -11.27125)
		(width 0.14224)
		(layer "In4.Cu")
		(net "M_H_MA<7>")
	)
	(segment
		(start 84.392008 -17.210786)
		(end 84.529168 -17.073626)
		(width 0.14224)
		(layer "In4.Cu")
		(net "M_H_MA<7>")
	)
	(segment
		(start 85.238082 -11.27125)
		(end 85.077808 -11.431524)
		(width 0.14224)
		(layer "In4.Cu")
		(net "M_H_MA<7>")
	)
	(segment
		(start 89.050368 -53.076856)
		(end 89.050368 -52.8574)
		(width 0.0889)
		(layer "In4.Cu")
		(net "M_H_MA<7>")
	)
	(segment
		(start 85.077808 -11.431524)
		(end 84.826348 -11.431524)
		(width 0.14224)
		(layer "In4.Cu")
		(net "M_H_MA<7>")
	)
	(segment
		(start 85.644482 -10.083292)
		(end 85.393022 -10.083292)
		(width 0.14224)
		(layer "In4.Cu")
		(net "M_H_MA<7>")
	)
	(segment
		(start 84.46262 -13.268452)
		(end 84.46262 -12.667488)
		(width 0.14224)
		(layer "In4.Cu")
		(net "M_H_MA<7>")
	)
	(segment
		(start 85.799422 -9.398254)
		(end 85.799422 -9.133078)
		(width 0.14224)
		(layer "In4.Cu")
		(net "M_H_MA<7>")
	)
	(segment
		(start 89.051892 -51.255676)
		(end 89.455752 -50.851816)
		(width 0.0889)
		(layer "In4.Cu")
		(net "M_H_MA<7>")
	)
	(segment
		(start 84.676742 -9.76884)
		(end 84.901278 -9.544304)
		(width 0.14224)
		(layer "In4.Cu")
		(net "M_H_MA<7>")
	)
	(segment
		(start 88.986868 -54.894988)
		(end 88.977978 -54.879748)
		(width 0.0889)
		(layer "In4.Cu")
		(net "M_H_MA<7>")
	)
	(segment
		(start 88.986868 -56.876188)
		(end 88.977978 -56.860948)
		(width 0.0889)
		(layer "In4.Cu")
		(net "M_H_MA<7>")
	)
	(segment
		(start 84.826348 -11.431524)
		(end 84.676742 -11.281918)
		(width 0.14224)
		(layer "In4.Cu")
		(net "M_H_MA<7>")
	)
	(segment
		(start 84.442808 -24.501094)
		(end 84.442808 -23.259796)
		(width 0.14224)
		(layer "In4.Cu")
		(net "M_H_MA<7>")
	)
	(segment
		(start 89.455752 -50.558446)
		(end 89.455752 -29.514038)
		(width 0.14224)
		(layer "In4.Cu")
		(net "M_H_MA<7>")
	)
	(segment
		(start 88.970866 -57.303162)
		(end 88.986868 -57.275984)
		(width 0.0889)
		(layer "In4.Cu")
		(net "M_H_MA<7>")
	)
	(segment
		(start 84.555584 -23.14702)
		(end 84.555584 -22.559772)
		(width 0.14224)
		(layer "In4.Cu")
		(net "M_H_MA<7>")
	)
	(segment
		(start 84.392008 -18.244566)
		(end 84.392008 -17.210786)
		(width 0.14224)
		(layer "In4.Cu")
		(net "M_H_MA<7>")
	)
	(segment
		(start 85.269578 -12.446)
		(end 85.799422 -11.916156)
		(width 0.14224)
		(layer "In4.Cu")
		(net "M_H_MA<7>")
	)
	(segment
		(start 88.640412 -58.06694)
		(end 88.970866 -57.303162)
		(width 0.0889)
		(layer "In4.Cu")
		(net "M_H_MA<7>")
	)
	(segment
		(start 84.529168 -17.073626)
		(end 84.529168 -13.335)
		(width 0.14224)
		(layer "In4.Cu")
		(net "M_H_MA<7>")
	)
	(segment
		(start 84.535518 -21.795486)
		(end 84.535518 -18.388076)
		(width 0.14224)
		(layer "In4.Cu")
		(net "M_H_MA<7>")
	)
	(segment
		(start 85.393022 -10.083292)
		(end 85.238082 -10.238232)
		(width 0.14224)
		(layer "In4.Cu")
		(net "M_H_MA<7>")
	)
	(segment
		(start 89.455752 -29.514038)
		(end 84.442808 -24.501094)
		(width 0.14224)
		(layer "In4.Cu")
		(net "M_H_MA<7>")
	)
	(segment
		(start 84.442808 -23.259796)
		(end 84.555584 -23.14702)
		(width 0.14224)
		(layer "In4.Cu")
		(net "M_H_MA<7>")
	)
	(segment
		(start 85.799422 -10.238232)
		(end 85.644482 -10.083292)
		(width 0.14224)
		(layer "In4.Cu")
		(net "M_H_MA<7>")
	)
	(segment
		(start 84.529168 -13.335)
		(end 84.46262 -13.268452)
		(width 0.14224)
		(layer "In4.Cu")
		(net "M_H_MA<7>")
	)
	(segment
		(start 85.653372 -9.544304)
		(end 85.799422 -9.398254)
		(width 0.14224)
		(layer "In4.Cu")
		(net "M_H_MA<7>")
	)
	(segment
		(start 84.555584 -22.559772)
		(end 84.442808 -22.446996)
		(width 0.14224)
		(layer "In4.Cu")
		(net "M_H_MA<7>")
	)
	(segment
		(start 89.455752 -50.851816)
		(end 89.455752 -50.558446)
		(width 0.0889)
		(layer "In4.Cu")
		(net "M_H_MA<7>")
	)
	(segment
		(start 84.676742 -11.281918)
		(end 84.676742 -9.76884)
		(width 0.14224)
		(layer "In4.Cu")
		(net "M_H_MA<7>")
	)
	(segment
		(start 84.535518 -18.388076)
		(end 84.392008 -18.244566)
		(width 0.14224)
		(layer "In4.Cu")
		(net "M_H_MA<7>")
	)
	(segment
		(start 88.986868 -53.904388)
		(end 88.977978 -53.889148)
		(width 0.0889)
		(layer "In4.Cu")
		(net "M_H_MA<7>")
	)
	(segment
		(start 84.684108 -12.446)
		(end 85.269578 -12.446)
		(width 0.14224)
		(layer "In4.Cu")
		(net "M_H_MA<7>")
	)
	(segment
		(start 89.050368 -52.8574)
		(end 89.051892 -52.855876)
		(width 0.0889)
		(layer "In4.Cu")
		(net "M_H_MA<7>")
	)
	(segment
		(start 85.799422 -11.916156)
		(end 85.799422 -10.238232)
		(width 0.14224)
		(layer "In4.Cu")
		(net "M_H_MA<7>")
	)
	(segment
		(start 84.442808 -21.888196)
		(end 84.535518 -21.795486)
		(width 0.14224)
		(layer "In4.Cu")
		(net "M_H_MA<7>")
	)
	(segment
		(start 84.46262 -12.667488)
		(end 84.684108 -12.446)
		(width 0.14224)
		(layer "In4.Cu")
		(net "M_H_MA<7>")
	)
	(segment
		(start 88.986868 -55.885588)
		(end 88.977978 -55.870348)
		(width 0.0889)
		(layer "In4.Cu")
		(net "M_H_MA<7>")
	)
	(segment
		(start 89.051892 -52.855876)
		(end 89.051892 -51.255676)
		(width 0.0889)
		(layer "In4.Cu")
		(net "M_H_MA<7>")
	)
	(arc
		(start 88.977978 -56.860948)
		(mid 88.907581 -56.571997)
		(end 88.986868 -56.285384)
		(width 0.0889)
		(layer "In4.Cu")
		(net "M_H_MA<7>")
	)
	(arc
		(start 88.986868 -53.313584)
		(mid 89.034173 -53.199397)
		(end 89.050368 -53.076856)
		(width 0.0889)
		(layer "In4.Cu")
		(net "M_H_MA<7>")
	)
	(arc
		(start 88.977978 -53.889148)
		(mid 88.907581 -53.600197)
		(end 88.986868 -53.313584)
		(width 0.0889)
		(layer "In4.Cu")
		(net "M_H_MA<7>")
	)
	(arc
		(start 88.977978 -54.879748)
		(mid 88.907581 -54.590797)
		(end 88.986868 -54.304184)
		(width 0.0889)
		(layer "In4.Cu")
		(net "M_H_MA<7>")
	)
	(arc
		(start 88.986868 -55.294784)
		(mid 89.040401 -55.094886)
		(end 88.986868 -54.894988)
		(width 0.0889)
		(layer "In4.Cu")
		(net "M_H_MA<7>")
	)
	(arc
		(start 88.986868 -57.275984)
		(mid 89.040401 -57.076086)
		(end 88.986868 -56.876188)
		(width 0.0889)
		(layer "In4.Cu")
		(net "M_H_MA<7>")
	)
	(arc
		(start 88.986868 -56.285384)
		(mid 89.040401 -56.085486)
		(end 88.986868 -55.885588)
		(width 0.0889)
		(layer "In4.Cu")
		(net "M_H_MA<7>")
	)
	(arc
		(start 88.977978 -55.870348)
		(mid 88.907581 -55.581397)
		(end 88.986868 -55.294784)
		(width 0.0889)
		(layer "In4.Cu")
		(net "M_H_MA<7>")
	)
	(arc
		(start 88.986868 -54.304184)
		(mid 89.040401 -54.104286)
		(end 88.986868 -53.904388)
		(width 0.0889)
		(layer "In4.Cu")
		(net "M_H_MA<7>")
	)
	(segment
		(start 87.499444 -5.822442)
		(end 87.499444 -7.117588)
		(width 0.1651)
		(layer "F.Cu")
		(net "M_H_MA<6>")
	)
	(segment
		(start 90.928698 -57.076086)
		(end 90.357198 -57.076086)
		(width 0.1016)
		(layer "F.Cu")
		(net "M_H_MA<6>")
	)
	(via
		(at 90.357198 -57.076086)
		(size 0.508)
		(drill 0.254)
		(layers "F.Cu" "B.Cu")
		(net "M_H_MA<6>")
	)
	(via
		(at 87.499444 -13.933678)
		(size 0.4572)
		(drill 0.2032)
		(layers "F.Cu" "B.Cu")
		(net "M_H_MA<6>")
	)
	(via
		(at 87.499444 -7.117588)
		(size 0.4572)
		(drill 0.2032)
		(layers "F.Cu" "B.Cu")
		(net "M_H_MA<6>")
	)
	(segment
		(start 87.499444 -15.222982)
		(end 87.499444 -13.933678)
		(width 0.1651)
		(layer "B.Cu")
		(net "M_H_MA<6>")
	)
	(segment
		(start 85.885782 -15.291562)
		(end 85.885782 -15.543022)
		(width 0.14224)
		(layer "In4.Cu")
		(net "M_H_MA<6>")
	)
	(segment
		(start 87.091266 -8.60298)
		(end 87.091266 -9.308846)
		(width 0.14224)
		(layer "In4.Cu")
		(net "M_H_MA<6>")
	)
	(segment
		(start 87.499444 -13.933678)
		(end 87.499444 -14.213078)
		(width 0.14224)
		(layer "In4.Cu")
		(net "M_H_MA<6>")
	)
	(segment
		(start 86.241636 -17.42313)
		(end 86.461854 -17.643348)
		(width 0.14224)
		(layer "In4.Cu")
		(net "M_H_MA<6>")
	)
	(segment
		(start 86.19236 -24.756364)
		(end 90.955368 -29.519372)
		(width 0.14224)
		(layer "In4.Cu")
		(net "M_H_MA<6>")
	)
	(segment
		(start 89.845388 -56.380888)
		(end 89.911682 -56.495442)
		(width 0.0889)
		(layer "In4.Cu")
		(net "M_H_MA<6>")
	)
	(segment
		(start 86.040722 -15.136622)
		(end 85.885782 -15.291562)
		(width 0.14224)
		(layer "In4.Cu")
		(net "M_H_MA<6>")
	)
	(segment
		(start 86.5759 -15.136622)
		(end 86.040722 -15.136622)
		(width 0.14224)
		(layer "In4.Cu")
		(net "M_H_MA<6>")
	)
	(segment
		(start 86.723728 -9.676384)
		(end 86.723728 -11.379708)
		(width 0.14224)
		(layer "In4.Cu")
		(net "M_H_MA<6>")
	)
	(segment
		(start 86.459568 -23.01748)
		(end 86.19236 -23.284688)
		(width 0.14224)
		(layer "In4.Cu")
		(net "M_H_MA<6>")
	)
	(segment
		(start 86.459568 -22.714712)
		(end 86.459568 -23.01748)
		(width 0.14224)
		(layer "In4.Cu")
		(net "M_H_MA<6>")
	)
	(segment
		(start 85.885782 -15.543022)
		(end 86.040722 -15.697962)
		(width 0.14224)
		(layer "In4.Cu")
		(net "M_H_MA<6>")
	)
	(segment
		(start 89.736168 -51.5874)
		(end 89.736168 -53.00091)
		(width 0.0889)
		(layer "In4.Cu")
		(net "M_H_MA<6>")
	)
	(segment
		(start 86.166452 -22.421596)
		(end 86.459568 -22.714712)
		(width 0.14224)
		(layer "In4.Cu")
		(net "M_H_MA<6>")
	)
	(segment
		(start 86.211664 -18.486374)
		(end 86.211664 -21.084032)
		(width 0.14224)
		(layer "In4.Cu")
		(net "M_H_MA<6>")
	)
	(segment
		(start 87.499444 -7.117588)
		(end 87.348822 -7.874)
		(width 0.14224)
		(layer "In4.Cu")
		(net "M_H_MA<6>")
	)
	(segment
		(start 87.307928 -8.079994)
		(end 87.091266 -8.60298)
		(width 0.14224)
		(layer "In4.Cu")
		(net "M_H_MA<6>")
	)
	(segment
		(start 86.293452 -21.16582)
		(end 86.293452 -21.811996)
		(width 0.14224)
		(layer "In4.Cu")
		(net "M_H_MA<6>")
	)
	(segment
		(start 87.091266 -9.308846)
		(end 86.723728 -9.676384)
		(width 0.14224)
		(layer "In4.Cu")
		(net "M_H_MA<6>")
	)
	(segment
		(start 86.461854 -17.643348)
		(end 86.461854 -18.236184)
		(width 0.14224)
		(layer "In4.Cu")
		(net "M_H_MA<6>")
	)
	(segment
		(start 89.845388 -53.809138)
		(end 89.839038 -53.819806)
		(width 0.0889)
		(layer "In4.Cu")
		(net "M_H_MA<6>")
	)
	(segment
		(start 89.845388 -55.790338)
		(end 89.839038 -55.801006)
		(width 0.0889)
		(layer "In4.Cu")
		(net "M_H_MA<6>")
	)
	(segment
		(start 87.348822 -7.874)
		(end 87.307928 -8.079994)
		(width 0.14224)
		(layer "In4.Cu")
		(net "M_H_MA<6>")
	)
	(segment
		(start 90.955368 -29.519372)
		(end 90.955368 -48.446436)
		(width 0.14224)
		(layer "In4.Cu")
		(net "M_H_MA<6>")
	)
	(segment
		(start 86.293452 -21.811996)
		(end 86.166452 -21.938996)
		(width 0.14224)
		(layer "In4.Cu")
		(net "M_H_MA<6>")
	)
	(segment
		(start 90.471752 -48.930052)
		(end 90.471752 -50.496978)
		(width 0.14224)
		(layer "In4.Cu")
		(net "M_H_MA<6>")
	)
	(segment
		(start 90.471752 -50.851816)
		(end 89.736168 -51.5874)
		(width 0.0889)
		(layer "In4.Cu")
		(net "M_H_MA<6>")
	)
	(segment
		(start 86.723728 -11.379708)
		(end 87.086948 -11.742928)
		(width 0.14224)
		(layer "In4.Cu")
		(net "M_H_MA<6>")
	)
	(segment
		(start 89.850214 -54.791102)
		(end 89.845388 -54.799738)
		(width 0.0889)
		(layer "In4.Cu")
		(net "M_H_MA<6>")
	)
	(segment
		(start 90.955368 -48.446436)
		(end 90.471752 -48.930052)
		(width 0.14224)
		(layer "In4.Cu")
		(net "M_H_MA<6>")
	)
	(segment
		(start 87.086948 -12.937744)
		(end 87.499444 -13.933678)
		(width 0.14224)
		(layer "In4.Cu")
		(net "M_H_MA<6>")
	)
	(segment
		(start 86.619588 -15.887446)
		(end 86.619588 -16.153638)
		(width 0.14224)
		(layer "In4.Cu")
		(net "M_H_MA<6>")
	)
	(segment
		(start 89.850214 -55.781702)
		(end 89.845388 -55.790338)
		(width 0.0889)
		(layer "In4.Cu")
		(net "M_H_MA<6>")
	)
	(segment
		(start 86.241636 -16.53159)
		(end 86.241636 -17.42313)
		(width 0.14224)
		(layer "In4.Cu")
		(net "M_H_MA<6>")
	)
	(segment
		(start 90.471752 -50.496978)
		(end 90.471752 -50.851816)
		(width 0.0889)
		(layer "In4.Cu")
		(net "M_H_MA<6>")
	)
	(segment
		(start 89.845388 -54.799738)
		(end 89.839038 -54.810406)
		(width 0.0889)
		(layer "In4.Cu")
		(net "M_H_MA<6>")
	)
	(segment
		(start 87.086948 -11.742928)
		(end 87.086948 -12.937744)
		(width 0.14224)
		(layer "In4.Cu")
		(net "M_H_MA<6>")
	)
	(segment
		(start 87.499444 -14.213078)
		(end 86.5759 -15.136622)
		(width 0.14224)
		(layer "In4.Cu")
		(net "M_H_MA<6>")
	)
	(segment
		(start 86.19236 -23.284688)
		(end 86.19236 -24.756364)
		(width 0.14224)
		(layer "In4.Cu")
		(net "M_H_MA<6>")
	)
	(segment
		(start 89.850214 -53.800502)
		(end 89.845388 -53.809138)
		(width 0.0889)
		(layer "In4.Cu")
		(net "M_H_MA<6>")
	)
	(segment
		(start 86.430104 -15.697962)
		(end 86.619588 -15.887446)
		(width 0.14224)
		(layer "In4.Cu")
		(net "M_H_MA<6>")
	)
	(segment
		(start 86.211664 -21.084032)
		(end 86.293452 -21.16582)
		(width 0.14224)
		(layer "In4.Cu")
		(net "M_H_MA<6>")
	)
	(segment
		(start 86.461854 -18.236184)
		(end 86.211664 -18.486374)
		(width 0.14224)
		(layer "In4.Cu")
		(net "M_H_MA<6>")
	)
	(segment
		(start 86.166452 -21.938996)
		(end 86.166452 -22.421596)
		(width 0.14224)
		(layer "In4.Cu")
		(net "M_H_MA<6>")
	)
	(segment
		(start 86.619588 -16.153638)
		(end 86.241636 -16.53159)
		(width 0.14224)
		(layer "In4.Cu")
		(net "M_H_MA<6>")
	)
	(segment
		(start 86.040722 -15.697962)
		(end 86.430104 -15.697962)
		(width 0.14224)
		(layer "In4.Cu")
		(net "M_H_MA<6>")
	)
	(arc
		(start 89.839038 -54.810406)
		(mid 89.76624 -55.101169)
		(end 89.845388 -55.390288)
		(width 0.0889)
		(layer "In4.Cu")
		(net "M_H_MA<6>")
	)
	(arc
		(start 89.845388 -53.409088)
		(mid 89.898858 -53.604151)
		(end 89.850214 -53.800502)
		(width 0.0889)
		(layer "In4.Cu")
		(net "M_H_MA<6>")
	)
	(arc
		(start 89.845388 -54.399688)
		(mid 89.898858 -54.594751)
		(end 89.850214 -54.791102)
		(width 0.0889)
		(layer "In4.Cu")
		(net "M_H_MA<6>")
	)
	(arc
		(start 89.911682 -56.495442)
		(mid 90.115429 -56.800351)
		(end 90.357198 -57.076086)
		(width 0.0889)
		(layer "In4.Cu")
		(net "M_H_MA<6>")
	)
	(arc
		(start 89.845388 -55.390288)
		(mid 89.898858 -55.585351)
		(end 89.850214 -55.781702)
		(width 0.0889)
		(layer "In4.Cu")
		(net "M_H_MA<6>")
	)
	(arc
		(start 89.839038 -53.819806)
		(mid 89.76624 -54.110569)
		(end 89.845388 -54.399688)
		(width 0.0889)
		(layer "In4.Cu")
		(net "M_H_MA<6>")
	)
	(arc
		(start 89.839038 -55.801006)
		(mid 89.76624 -56.091769)
		(end 89.845388 -56.380888)
		(width 0.0889)
		(layer "In4.Cu")
		(net "M_H_MA<6>")
	)
	(arc
		(start 89.736168 -53.00091)
		(mid 89.763952 -53.212175)
		(end 89.845388 -53.409088)
		(width 0.0889)
		(layer "In4.Cu")
		(net "M_H_MA<6>")
	)
	(segment
		(start 87.499444 -10.422382)
		(end 87.499444 -9.133078)
		(width 0.1651)
		(layer "F.Cu")
		(net "M_H_MA<5>")
	)
	(segment
		(start 91.787218 -56.58104)
		(end 91.215718 -56.58104)
		(width 0.1016)
		(layer "F.Cu")
		(net "M_H_MA<5>")
	)
	(via
		(at 87.499444 -9.133078)
		(size 0.4572)
		(drill 0.2032)
		(layers "F.Cu" "B.Cu")
		(net "M_H_MA<5>")
	)
	(via
		(at 91.215718 -56.58104)
		(size 0.508)
		(drill 0.254)
		(layers "F.Cu" "B.Cu")
		(net "M_H_MA<5>")
	)
	(via
		(at 87.499444 -11.918188)
		(size 0.4572)
		(drill 0.2032)
		(layers "F.Cu" "B.Cu")
		(net "M_H_MA<5>")
	)
	(segment
		(start 87.499444 -10.623042)
		(end 87.499444 -11.918188)
		(width 0.1651)
		(layer "B.Cu")
		(net "M_H_MA<5>")
	)
	(segment
		(start 90.005662 -53.913024)
		(end 90.010488 -53.904388)
		(width 0.0889)
		(layer "In4.Cu")
		(net "M_H_MA<5>")
	)
	(segment
		(start 87.07628 -15.232634)
		(end 87.913464 -14.39545)
		(width 0.14224)
		(layer "In4.Cu")
		(net "M_H_MA<5>")
	)
	(segment
		(start 87.305896 -11.371072)
		(end 87.137748 -11.202924)
		(width 0.14224)
		(layer "In4.Cu")
		(net "M_H_MA<5>")
	)
	(segment
		(start 87.004652 -21.761196)
		(end 87.004652 -19.08937)
		(width 0.14224)
		(layer "In4.Cu")
		(net "M_H_MA<5>")
	)
	(segment
		(start 91.215718 -56.58104)
		(end 90.88628 -55.820056)
		(width 0.0889)
		(layer "In4.Cu")
		(net "M_H_MA<5>")
	)
	(segment
		(start 87.809578 -11.918188)
		(end 87.936578 -11.791188)
		(width 0.14224)
		(layer "In4.Cu")
		(net "M_H_MA<5>")
	)
	(segment
		(start 87.27948 -10.809732)
		(end 88.079834 -10.809732)
		(width 0.14224)
		(layer "In4.Cu")
		(net "M_H_MA<5>")
	)
	(segment
		(start 87.157052 -21.913596)
		(end 87.004652 -21.761196)
		(width 0.14224)
		(layer "In4.Cu")
		(net "M_H_MA<5>")
	)
	(segment
		(start 87.157052 -22.396196)
		(end 87.157052 -21.913596)
		(width 0.14224)
		(layer "In4.Cu")
		(net "M_H_MA<5>")
	)
	(segment
		(start 90.010488 -54.894988)
		(end 90.016838 -54.88432)
		(width 0.0889)
		(layer "In4.Cu")
		(net "M_H_MA<5>")
	)
	(segment
		(start 90.374978 -55.494936)
		(end 90.342212 -55.494936)
		(width 0.0889)
		(layer "In4.Cu")
		(net "M_H_MA<5>")
	)
	(segment
		(start 87.92337 -9.276842)
		(end 87.779606 -9.133078)
		(width 0.14224)
		(layer "In4.Cu")
		(net "M_H_MA<5>")
	)
	(segment
		(start 87.499444 -12.7)
		(end 87.499444 -11.918188)
		(width 0.14224)
		(layer "In4.Cu")
		(net "M_H_MA<5>")
	)
	(segment
		(start 87.053166 -22.500082)
		(end 87.157052 -22.396196)
		(width 0.14224)
		(layer "In4.Cu")
		(net "M_H_MA<5>")
	)
	(segment
		(start 87.138002 -10.093452)
		(end 87.138002 -9.841992)
		(width 0.14224)
		(layer "In4.Cu")
		(net "M_H_MA<5>")
	)
	(segment
		(start 87.10676 -24.952198)
		(end 87.10676 -23.234904)
		(width 0.14224)
		(layer "In4.Cu")
		(net "M_H_MA<5>")
	)
	(segment
		(start 87.936578 -11.531092)
		(end 87.776558 -11.371072)
		(width 0.14224)
		(layer "In4.Cu")
		(net "M_H_MA<5>")
	)
	(segment
		(start 89.939368 -53.048662)
		(end 89.939368 -51.892454)
		(width 0.0889)
		(layer "In4.Cu")
		(net "M_H_MA<5>")
	)
	(segment
		(start 87.499444 -11.918188)
		(end 87.809578 -11.918188)
		(width 0.14224)
		(layer "In4.Cu")
		(net "M_H_MA<5>")
	)
	(segment
		(start 87.137748 -10.951464)
		(end 87.27948 -10.809732)
		(width 0.14224)
		(layer "In4.Cu")
		(net "M_H_MA<5>")
	)
	(segment
		(start 91.463368 -48.984662)
		(end 91.463368 -29.308806)
		(width 0.14224)
		(layer "In4.Cu")
		(net "M_H_MA<5>")
	)
	(segment
		(start 90.904568 -49.8348)
		(end 91.463368 -49.276)
		(width 0.0889)
		(layer "In4.Cu")
		(net "M_H_MA<5>")
	)
	(segment
		(start 90.005662 -54.903624)
		(end 90.010488 -54.894988)
		(width 0.0889)
		(layer "In4.Cu")
		(net "M_H_MA<5>")
	)
	(segment
		(start 87.292942 -9.687052)
		(end 87.771224 -9.687052)
		(width 0.14224)
		(layer "In4.Cu")
		(net "M_H_MA<5>")
	)
	(segment
		(start 88.079834 -10.248392)
		(end 87.292942 -10.248392)
		(width 0.14224)
		(layer "In4.Cu")
		(net "M_H_MA<5>")
	)
	(segment
		(start 87.913464 -14.39545)
		(end 87.913464 -13.11402)
		(width 0.14224)
		(layer "In4.Cu")
		(net "M_H_MA<5>")
	)
	(segment
		(start 87.089742 -19.00428)
		(end 87.089742 -18.464276)
		(width 0.14224)
		(layer "In4.Cu")
		(net "M_H_MA<5>")
	)
	(segment
		(start 88.079834 -10.809732)
		(end 88.234774 -10.654792)
		(width 0.14224)
		(layer "In4.Cu")
		(net "M_H_MA<5>")
	)
	(segment
		(start 90.010488 -53.904388)
		(end 90.016838 -53.89372)
		(width 0.0889)
		(layer "In4.Cu")
		(net "M_H_MA<5>")
	)
	(segment
		(start 88.234774 -10.403332)
		(end 88.079834 -10.248392)
		(width 0.14224)
		(layer "In4.Cu")
		(net "M_H_MA<5>")
	)
	(segment
		(start 88.234774 -10.654792)
		(end 88.234774 -10.403332)
		(width 0.14224)
		(layer "In4.Cu")
		(net "M_H_MA<5>")
	)
	(segment
		(start 90.88628 -55.820056)
		(end 90.869008 -55.790338)
		(width 0.0889)
		(layer "In4.Cu")
		(net "M_H_MA<5>")
	)
	(segment
		(start 87.053166 -23.18131)
		(end 87.053166 -22.500082)
		(width 0.14224)
		(layer "In4.Cu")
		(net "M_H_MA<5>")
	)
	(segment
		(start 87.936578 -11.791188)
		(end 87.936578 -11.531092)
		(width 0.14224)
		(layer "In4.Cu")
		(net "M_H_MA<5>")
	)
	(segment
		(start 87.779606 -9.133078)
		(end 87.499444 -9.133078)
		(width 0.14224)
		(layer "In4.Cu")
		(net "M_H_MA<5>")
	)
	(segment
		(start 87.089742 -18.464276)
		(end 87.07628 -18.450814)
		(width 0.14224)
		(layer "In4.Cu")
		(net "M_H_MA<5>")
	)
	(segment
		(start 87.292942 -10.248392)
		(end 87.138002 -10.093452)
		(width 0.14224)
		(layer "In4.Cu")
		(net "M_H_MA<5>")
	)
	(segment
		(start 87.771224 -9.687052)
		(end 87.92337 -9.534906)
		(width 0.14224)
		(layer "In4.Cu")
		(net "M_H_MA<5>")
	)
	(segment
		(start 87.004652 -19.08937)
		(end 87.089742 -19.00428)
		(width 0.14224)
		(layer "In4.Cu")
		(net "M_H_MA<5>")
	)
	(segment
		(start 87.138002 -9.841992)
		(end 87.292942 -9.687052)
		(width 0.14224)
		(layer "In4.Cu")
		(net "M_H_MA<5>")
	)
	(segment
		(start 87.776558 -11.371072)
		(end 87.305896 -11.371072)
		(width 0.14224)
		(layer "In4.Cu")
		(net "M_H_MA<5>")
	)
	(segment
		(start 87.92337 -9.534906)
		(end 87.92337 -9.276842)
		(width 0.14224)
		(layer "In4.Cu")
		(net "M_H_MA<5>")
	)
	(segment
		(start 90.904568 -50.927254)
		(end 90.904568 -49.8348)
		(width 0.0889)
		(layer "In4.Cu")
		(net "M_H_MA<5>")
	)
	(segment
		(start 87.913464 -13.11402)
		(end 87.499444 -12.7)
		(width 0.14224)
		(layer "In4.Cu")
		(net "M_H_MA<5>")
	)
	(segment
		(start 91.463368 -29.308806)
		(end 87.10676 -24.952198)
		(width 0.14224)
		(layer "In4.Cu")
		(net "M_H_MA<5>")
	)
	(segment
		(start 89.939368 -51.892454)
		(end 90.904568 -50.927254)
		(width 0.0889)
		(layer "In4.Cu")
		(net "M_H_MA<5>")
	)
	(segment
		(start 91.463368 -49.276)
		(end 91.463368 -48.984662)
		(width 0.0889)
		(layer "In4.Cu")
		(net "M_H_MA<5>")
	)
	(segment
		(start 87.137748 -11.202924)
		(end 87.137748 -10.951464)
		(width 0.14224)
		(layer "In4.Cu")
		(net "M_H_MA<5>")
	)
	(segment
		(start 87.07628 -18.450814)
		(end 87.07628 -15.232634)
		(width 0.14224)
		(layer "In4.Cu")
		(net "M_H_MA<5>")
	)
	(segment
		(start 87.10676 -23.234904)
		(end 87.053166 -23.18131)
		(width 0.14224)
		(layer "In4.Cu")
		(net "M_H_MA<5>")
	)
	(arc
		(start 90.016838 -54.88432)
		(mid 90.089636 -54.593557)
		(end 90.010488 -54.304438)
		(width 0.0889)
		(layer "In4.Cu")
		(net "M_H_MA<5>")
	)
	(arc
		(start 90.010488 -53.313838)
		(mid 89.957499 -53.185928)
		(end 89.939368 -53.048662)
		(width 0.0889)
		(layer "In4.Cu")
		(net "M_H_MA<5>")
	)
	(arc
		(start 90.010488 -54.304438)
		(mid 89.957018 -54.109375)
		(end 90.005662 -53.913024)
		(width 0.0889)
		(layer "In4.Cu")
		(net "M_H_MA<5>")
	)
	(arc
		(start 90.016838 -53.89372)
		(mid 90.089636 -53.602957)
		(end 90.010488 -53.313838)
		(width 0.0889)
		(layer "In4.Cu")
		(net "M_H_MA<5>")
	)
	(arc
		(start 90.869008 -55.790338)
		(mid 90.6604 -55.578406)
		(end 90.374978 -55.494936)
		(width 0.0889)
		(layer "In4.Cu")
		(net "M_H_MA<5>")
	)
	(arc
		(start 90.342212 -55.494936)
		(mid 90.009294 -55.292945)
		(end 90.005662 -54.903624)
		(width 0.0889)
		(layer "In4.Cu")
		(net "M_H_MA<5>")
	)
	(segment
		(start 90.928698 -55.094886)
		(end 90.357198 -55.094886)
		(width 0.1016)
		(layer "F.Cu")
		(net "M_H_MA<4>")
	)
	(segment
		(start 88.349582 -10.422382)
		(end 88.349582 -9.133078)
		(width 0.1651)
		(layer "F.Cu")
		(net "M_H_MA<4>")
	)
	(via
		(at 90.357198 -55.094886)
		(size 0.508)
		(drill 0.254)
		(layers "F.Cu" "B.Cu")
		(net "M_H_MA<4>")
	)
	(via
		(at 88.349582 -9.133078)
		(size 0.4572)
		(drill 0.2032)
		(layers "F.Cu" "B.Cu")
		(net "M_H_MA<4>")
	)
	(via
		(at 88.349582 -11.918188)
		(size 0.4572)
		(drill 0.2032)
		(layers "F.Cu" "B.Cu")
		(net "M_H_MA<4>")
	)
	(segment
		(start 88.349582 -10.623042)
		(end 88.349582 -11.918188)
		(width 0.1651)
		(layer "B.Cu")
		(net "M_H_MA<4>")
	)
	(segment
		(start 87.995252 -18.328386)
		(end 87.920576 -18.403062)
		(width 0.14224)
		(layer "In4.Cu")
		(net "M_H_MA<4>")
	)
	(segment
		(start 88.651842 -11.196828)
		(end 88.349582 -11.499088)
		(width 0.14224)
		(layer "In4.Cu")
		(net "M_H_MA<4>")
	)
	(segment
		(start 91.971368 -48.984662)
		(end 91.971368 -49.2506)
		(width 0.0889)
		(layer "In4.Cu")
		(net "M_H_MA<4>")
	)
	(segment
		(start 87.842852 -21.888196)
		(end 87.842852 -22.446996)
		(width 0.14224)
		(layer "In4.Cu")
		(net "M_H_MA<4>")
	)
	(segment
		(start 90.703908 -53.904388)
		(end 90.708734 -53.913024)
		(width 0.0889)
		(layer "In4.Cu")
		(net "M_H_MA<4>")
	)
	(segment
		(start 88.542368 -12.64158)
		(end 88.542368 -13.50518)
		(width 0.14224)
		(layer "In4.Cu")
		(net "M_H_MA<4>")
	)
	(segment
		(start 88.512396 -25.639014)
		(end 91.971368 -29.097986)
		(width 0.14224)
		(layer "In4.Cu")
		(net "M_H_MA<4>")
	)
	(segment
		(start 87.912956 -17.089882)
		(end 87.792052 -17.210786)
		(width 0.14224)
		(layer "In4.Cu")
		(net "M_H_MA<4>")
	)
	(segment
		(start 87.920576 -21.185124)
		(end 87.995252 -21.2598)
		(width 0.14224)
		(layer "In4.Cu")
		(net "M_H_MA<4>")
	)
	(segment
		(start 87.995252 -22.599396)
		(end 87.995252 -23.107396)
		(width 0.14224)
		(layer "In4.Cu")
		(net "M_H_MA<4>")
	)
	(segment
		(start 88.349582 -11.499088)
		(end 88.349582 -11.918188)
		(width 0.14224)
		(layer "In4.Cu")
		(net "M_H_MA<4>")
	)
	(segment
		(start 88.349582 -9.584944)
		(end 88.651842 -9.887204)
		(width 0.14224)
		(layer "In4.Cu")
		(net "M_H_MA<4>")
	)
	(segment
		(start 87.995252 -23.107396)
		(end 87.842852 -23.259796)
		(width 0.14224)
		(layer "In4.Cu")
		(net "M_H_MA<4>")
	)
	(segment
		(start 88.349582 -9.133078)
		(end 88.349582 -9.584944)
		(width 0.14224)
		(layer "In4.Cu")
		(net "M_H_MA<4>")
	)
	(segment
		(start 87.912956 -15.082012)
		(end 87.912956 -17.089882)
		(width 0.14224)
		(layer "In4.Cu")
		(net "M_H_MA<4>")
	)
	(segment
		(start 87.995252 -17.769586)
		(end 87.995252 -18.328386)
		(width 0.14224)
		(layer "In4.Cu")
		(net "M_H_MA<4>")
	)
	(segment
		(start 87.792052 -17.210786)
		(end 87.792052 -17.566386)
		(width 0.14224)
		(layer "In4.Cu")
		(net "M_H_MA<4>")
	)
	(segment
		(start 87.842852 -23.700232)
		(end 88.512396 -24.369776)
		(width 0.14224)
		(layer "In4.Cu")
		(net "M_H_MA<4>")
	)
	(segment
		(start 90.697558 -53.89372)
		(end 90.703908 -53.904388)
		(width 0.0889)
		(layer "In4.Cu")
		(net "M_H_MA<4>")
	)
	(segment
		(start 88.542368 -13.50518)
		(end 88.783668 -13.74648)
		(width 0.14224)
		(layer "In4.Cu")
		(net "M_H_MA<4>")
	)
	(segment
		(start 87.995252 -21.2598)
		(end 87.995252 -21.735796)
		(width 0.14224)
		(layer "In4.Cu")
		(net "M_H_MA<4>")
	)
	(segment
		(start 91.158568 -50.0634)
		(end 91.158568 -51.29911)
		(width 0.0889)
		(layer "In4.Cu")
		(net "M_H_MA<4>")
	)
	(segment
		(start 87.995252 -21.735796)
		(end 87.842852 -21.888196)
		(width 0.14224)
		(layer "In4.Cu")
		(net "M_H_MA<4>")
	)
	(segment
		(start 87.792052 -17.566386)
		(end 87.995252 -17.769586)
		(width 0.14224)
		(layer "In4.Cu")
		(net "M_H_MA<4>")
	)
	(segment
		(start 88.512396 -24.369776)
		(end 88.512396 -25.639014)
		(width 0.14224)
		(layer "In4.Cu")
		(net "M_H_MA<4>")
	)
	(segment
		(start 87.920576 -18.403062)
		(end 87.920576 -21.185124)
		(width 0.14224)
		(layer "In4.Cu")
		(net "M_H_MA<4>")
	)
	(segment
		(start 88.349582 -11.918188)
		(end 88.349582 -12.448794)
		(width 0.14224)
		(layer "In4.Cu")
		(net "M_H_MA<4>")
	)
	(segment
		(start 88.783668 -13.74648)
		(end 88.783668 -14.2113)
		(width 0.14224)
		(layer "In4.Cu")
		(net "M_H_MA<4>")
	)
	(segment
		(start 90.821002 -51.636676)
		(end 90.821002 -52.876958)
		(width 0.0889)
		(layer "In4.Cu")
		(net "M_H_MA<4>")
	)
	(segment
		(start 91.971368 -49.2506)
		(end 91.158568 -50.0634)
		(width 0.0889)
		(layer "In4.Cu")
		(net "M_H_MA<4>")
	)
	(segment
		(start 87.842852 -23.259796)
		(end 87.842852 -23.700232)
		(width 0.14224)
		(layer "In4.Cu")
		(net "M_H_MA<4>")
	)
	(segment
		(start 88.783668 -14.2113)
		(end 87.912956 -15.082012)
		(width 0.14224)
		(layer "In4.Cu")
		(net "M_H_MA<4>")
	)
	(segment
		(start 88.349582 -12.448794)
		(end 88.542368 -12.64158)
		(width 0.14224)
		(layer "In4.Cu")
		(net "M_H_MA<4>")
	)
	(segment
		(start 88.651842 -9.887204)
		(end 88.651842 -11.196828)
		(width 0.14224)
		(layer "In4.Cu")
		(net "M_H_MA<4>")
	)
	(segment
		(start 87.842852 -22.446996)
		(end 87.995252 -22.599396)
		(width 0.14224)
		(layer "In4.Cu")
		(net "M_H_MA<4>")
	)
	(segment
		(start 90.703908 -54.304438)
		(end 90.687144 -54.33314)
		(width 0.0889)
		(layer "In4.Cu")
		(net "M_H_MA<4>")
	)
	(segment
		(start 91.158568 -51.29911)
		(end 90.821002 -51.636676)
		(width 0.0889)
		(layer "In4.Cu")
		(net "M_H_MA<4>")
	)
	(segment
		(start 91.971368 -29.097986)
		(end 91.971368 -48.984662)
		(width 0.14224)
		(layer "In4.Cu")
		(net "M_H_MA<4>")
	)
	(segment
		(start 90.687144 -54.33314)
		(end 90.357198 -55.094886)
		(width 0.0889)
		(layer "In4.Cu")
		(net "M_H_MA<4>")
	)
	(arc
		(start 90.821002 -52.876958)
		(mid 90.791212 -53.103103)
		(end 90.703908 -53.313838)
		(width 0.0889)
		(layer "In4.Cu")
		(net "M_H_MA<4>")
	)
	(arc
		(start 90.708734 -53.913024)
		(mid 90.757489 -54.109376)
		(end 90.703908 -54.304438)
		(width 0.0889)
		(layer "In4.Cu")
		(net "M_H_MA<4>")
	)
	(arc
		(start 90.703908 -53.313838)
		(mid 90.624686 -53.602956)
		(end 90.697558 -53.89372)
		(width 0.0889)
		(layer "In4.Cu")
		(net "M_H_MA<4>")
	)
	(segment
		(start 91.787218 -55.59044)
		(end 91.215718 -55.59044)
		(width 0.1016)
		(layer "F.Cu")
		(net "M_H_MA<3>")
	)
	(segment
		(start 89.199466 -7.117588)
		(end 89.199466 -5.822442)
		(width 0.1651)
		(layer "F.Cu")
		(net "M_H_MA<3>")
	)
	(via
		(at 89.199466 -13.933678)
		(size 0.4572)
		(drill 0.2032)
		(layers "F.Cu" "B.Cu")
		(net "M_H_MA<3>")
	)
	(via
		(at 89.199466 -7.117588)
		(size 0.4572)
		(drill 0.2032)
		(layers "F.Cu" "B.Cu")
		(net "M_H_MA<3>")
	)
	(via
		(at 91.215718 -55.59044)
		(size 0.508)
		(drill 0.254)
		(layers "F.Cu" "B.Cu")
		(net "M_H_MA<3>")
	)
	(segment
		(start 89.199466 -15.222982)
		(end 89.199466 -13.933678)
		(width 0.1651)
		(layer "B.Cu")
		(net "M_H_MA<3>")
	)
	(segment
		(start 88.742266 -18.418556)
		(end 88.763856 -18.440146)
		(width 0.14224)
		(layer "In4.Cu")
		(net "M_H_MA<3>")
	)
	(segment
		(start 90.88628 -54.829456)
		(end 91.215718 -55.59044)
		(width 0.0889)
		(layer "In4.Cu")
		(net "M_H_MA<3>")
	)
	(segment
		(start 88.742266 -21.749766)
		(end 88.806782 -21.814282)
		(width 0.14224)
		(layer "In4.Cu")
		(net "M_H_MA<3>")
	)
	(segment
		(start 88.742266 -17.806416)
		(end 88.742266 -18.418556)
		(width 0.14224)
		(layer "In4.Cu")
		(net "M_H_MA<3>")
	)
	(segment
		(start 88.742266 -21.212048)
		(end 88.742266 -21.749766)
		(width 0.14224)
		(layer "In4.Cu")
		(net "M_H_MA<3>")
	)
	(segment
		(start 88.742266 -22.623526)
		(end 88.742266 -23.222966)
		(width 0.14224)
		(layer "In4.Cu")
		(net "M_H_MA<3>")
	)
	(segment
		(start 88.78824 -17.760442)
		(end 88.742266 -17.806416)
		(width 0.14224)
		(layer "In4.Cu")
		(net "M_H_MA<3>")
	)
	(segment
		(start 89.199466 -7.592568)
		(end 88.762586 -8.029448)
		(width 0.14224)
		(layer "In4.Cu")
		(net "M_H_MA<3>")
	)
	(segment
		(start 90.869008 -53.809138)
		(end 90.875358 -53.819806)
		(width 0.0889)
		(layer "In4.Cu")
		(net "M_H_MA<3>")
	)
	(segment
		(start 88.763856 -21.190458)
		(end 88.742266 -21.212048)
		(width 0.14224)
		(layer "In4.Cu")
		(net "M_H_MA<3>")
	)
	(segment
		(start 88.806782 -22.55901)
		(end 88.742266 -22.623526)
		(width 0.14224)
		(layer "In4.Cu")
		(net "M_H_MA<3>")
	)
	(segment
		(start 88.760808 -11.678666)
		(end 88.760808 -12.167108)
		(width 0.14224)
		(layer "In4.Cu")
		(net "M_H_MA<3>")
	)
	(segment
		(start 91.13266 -51.689)
		(end 91.13266 -52.6796)
		(width 0.0889)
		(layer "In4.Cu")
		(net "M_H_MA<3>")
	)
	(segment
		(start 89.199466 -13.933678)
		(end 89.355168 -14.08938)
		(width 0.14224)
		(layer "In4.Cu")
		(net "M_H_MA<3>")
	)
	(segment
		(start 91.412568 -50.292)
		(end 91.412568 -51.409092)
		(width 0.0889)
		(layer "In4.Cu")
		(net "M_H_MA<3>")
	)
	(segment
		(start 90.864182 -54.791102)
		(end 90.88628 -54.829456)
		(width 0.0889)
		(layer "In4.Cu")
		(net "M_H_MA<3>")
	)
	(segment
		(start 89.075768 -11.363706)
		(end 88.760808 -11.678666)
		(width 0.14224)
		(layer "In4.Cu")
		(net "M_H_MA<3>")
	)
	(segment
		(start 89.199466 -7.117588)
		(end 89.199466 -7.592568)
		(width 0.14224)
		(layer "In4.Cu")
		(net "M_H_MA<3>")
	)
	(segment
		(start 88.742266 -23.222966)
		(end 89.020396 -23.501096)
		(width 0.14224)
		(layer "In4.Cu")
		(net "M_H_MA<3>")
	)
	(segment
		(start 89.075768 -13.125958)
		(end 89.199466 -13.249656)
		(width 0.14224)
		(layer "In4.Cu")
		(net "M_H_MA<3>")
	)
	(segment
		(start 90.99677 -53.1876)
		(end 90.869008 -53.409088)
		(width 0.0889)
		(layer "In4.Cu")
		(net "M_H_MA<3>")
	)
	(segment
		(start 89.199466 -13.249656)
		(end 89.199466 -13.933678)
		(width 0.14224)
		(layer "In4.Cu")
		(net "M_H_MA<3>")
	)
	(segment
		(start 89.355168 -14.08938)
		(end 89.355168 -14.376654)
		(width 0.14224)
		(layer "In4.Cu")
		(net "M_H_MA<3>")
	)
	(segment
		(start 89.075768 -9.700514)
		(end 89.075768 -11.363706)
		(width 0.14224)
		(layer "In4.Cu")
		(net "M_H_MA<3>")
	)
	(segment
		(start 91.412568 -51.409092)
		(end 91.13266 -51.689)
		(width 0.0889)
		(layer "In4.Cu")
		(net "M_H_MA<3>")
	)
	(segment
		(start 89.020396 -25.428194)
		(end 92.479368 -28.887166)
		(width 0.14224)
		(layer "In4.Cu")
		(net "M_H_MA<3>")
	)
	(segment
		(start 88.78824 -14.943582)
		(end 88.78824 -17.760442)
		(width 0.14224)
		(layer "In4.Cu")
		(net "M_H_MA<3>")
	)
	(segment
		(start 88.763856 -18.440146)
		(end 88.763856 -21.190458)
		(width 0.14224)
		(layer "In4.Cu")
		(net "M_H_MA<3>")
	)
	(segment
		(start 92.479368 -28.887166)
		(end 92.479368 -48.910494)
		(width 0.14224)
		(layer "In4.Cu")
		(net "M_H_MA<3>")
	)
	(segment
		(start 92.479368 -48.910494)
		(end 92.479368 -49.2252)
		(width 0.0889)
		(layer "In4.Cu")
		(net "M_H_MA<3>")
	)
	(segment
		(start 89.020396 -23.501096)
		(end 89.020396 -25.428194)
		(width 0.14224)
		(layer "In4.Cu")
		(net "M_H_MA<3>")
	)
	(segment
		(start 88.762586 -8.029448)
		(end 88.762586 -9.387332)
		(width 0.14224)
		(layer "In4.Cu")
		(net "M_H_MA<3>")
	)
	(segment
		(start 88.806782 -21.814282)
		(end 88.806782 -22.55901)
		(width 0.14224)
		(layer "In4.Cu")
		(net "M_H_MA<3>")
	)
	(segment
		(start 89.075768 -12.482068)
		(end 89.075768 -13.125958)
		(width 0.14224)
		(layer "In4.Cu")
		(net "M_H_MA<3>")
	)
	(segment
		(start 88.760808 -12.167108)
		(end 89.075768 -12.482068)
		(width 0.14224)
		(layer "In4.Cu")
		(net "M_H_MA<3>")
	)
	(segment
		(start 89.355168 -14.376654)
		(end 88.78824 -14.943582)
		(width 0.14224)
		(layer "In4.Cu")
		(net "M_H_MA<3>")
	)
	(segment
		(start 88.762586 -9.387332)
		(end 89.075768 -9.700514)
		(width 0.14224)
		(layer "In4.Cu")
		(net "M_H_MA<3>")
	)
	(segment
		(start 90.864182 -53.800502)
		(end 90.869008 -53.809138)
		(width 0.0889)
		(layer "In4.Cu")
		(net "M_H_MA<3>")
	)
	(segment
		(start 92.479368 -49.2252)
		(end 91.412568 -50.292)
		(width 0.0889)
		(layer "In4.Cu")
		(net "M_H_MA<3>")
	)
	(arc
		(start 90.875358 -53.819806)
		(mid 90.948156 -54.110569)
		(end 90.869008 -54.399688)
		(width 0.0889)
		(layer "In4.Cu")
		(net "M_H_MA<3>")
	)
	(arc
		(start 91.13266 -52.6796)
		(mid 91.098086 -52.942523)
		(end 90.99677 -53.1876)
		(width 0.0889)
		(layer "In4.Cu")
		(net "M_H_MA<3>")
	)
	(arc
		(start 90.869008 -54.399688)
		(mid 90.815538 -54.594751)
		(end 90.864182 -54.791102)
		(width 0.0889)
		(layer "In4.Cu")
		(net "M_H_MA<3>")
	)
	(arc
		(start 90.869008 -53.409088)
		(mid 90.815538 -53.604151)
		(end 90.864182 -53.800502)
		(width 0.0889)
		(layer "In4.Cu")
		(net "M_H_MA<3>")
	)
	(segment
		(start 90.04935 -10.422382)
		(end 90.04935 -9.158732)
		(width 0.1651)
		(layer "F.Cu")
		(net "M_H_MA<2>")
	)
	(segment
		(start 90.049604 -9.158478)
		(end 90.049604 -9.133078)
		(width 0.1651)
		(layer "F.Cu")
		(net "M_H_MA<2>")
	)
	(segment
		(start 92.645738 -54.104286)
		(end 92.074238 -54.104286)
		(width 0.1016)
		(layer "F.Cu")
		(net "M_H_MA<2>")
	)
	(segment
		(start 90.04935 -9.158732)
		(end 90.049604 -9.158478)
		(width 0.1651)
		(layer "F.Cu")
		(net "M_H_MA<2>")
	)
	(via
		(at 90.04935 -11.918188)
		(size 0.4572)
		(drill 0.2032)
		(layers "F.Cu" "B.Cu")
		(net "M_H_MA<2>")
	)
	(via
		(at 90.049604 -9.133078)
		(size 0.4572)
		(drill 0.2032)
		(layers "F.Cu" "B.Cu")
		(net "M_H_MA<2>")
	)
	(via
		(at 92.074238 -54.104286)
		(size 0.508)
		(drill 0.254)
		(layers "F.Cu" "B.Cu")
		(net "M_H_MA<2>")
	)
	(segment
		(start 90.04935 -11.918188)
		(end 90.04935 -10.623042)
		(width 0.1651)
		(layer "B.Cu")
		(net "M_H_MA<2>")
	)
	(segment
		(start 90.557096 -21.06422)
		(end 90.404696 -21.21662)
		(width 0.14224)
		(layer "In4.Cu")
		(net "M_H_MA<2>")
	)
	(segment
		(start 90.466418 -21.822918)
		(end 90.466418 -22.486874)
		(width 0.14224)
		(layer "In4.Cu")
		(net "M_H_MA<2>")
	)
	(segment
		(start 90.474546 -10.259568)
		(end 90.04935 -10.684764)
		(width 0.14224)
		(layer "In4.Cu")
		(net "M_H_MA<2>")
	)
	(segment
		(start 90.329512 -17.05737)
		(end 90.329512 -18.429986)
		(width 0.14224)
		(layer "In4.Cu")
		(net "M_H_MA<2>")
	)
	(segment
		(start 90.329512 -18.429986)
		(end 90.557096 -18.65757)
		(width 0.14224)
		(layer "In4.Cu")
		(net "M_H_MA<2>")
	)
	(segment
		(start 92.615258 -26.467816)
		(end 93.495368 -27.347926)
		(width 0.14224)
		(layer "In4.Cu")
		(net "M_H_MA<2>")
	)
	(segment
		(start 90.470228 -23.198328)
		(end 90.470228 -23.975568)
		(width 0.14224)
		(layer "In4.Cu")
		(net "M_H_MA<2>")
	)
	(segment
		(start 91.920568 -51.696366)
		(end 91.673934 -51.943)
		(width 0.0889)
		(layer "In4.Cu")
		(net "M_H_MA<2>")
	)
	(segment
		(start 90.417396 -14.970252)
		(end 90.417396 -15.344394)
		(width 0.14224)
		(layer "In4.Cu")
		(net "M_H_MA<2>")
	)
	(segment
		(start 93.495368 -49.015396)
		(end 93.495368 -49.2252)
		(width 0.0889)
		(layer "In4.Cu")
		(net "M_H_MA<2>")
	)
	(segment
		(start 90.635582 -13.853414)
		(end 90.635582 -14.752066)
		(width 0.14224)
		(layer "In4.Cu")
		(net "M_H_MA<2>")
	)
	(segment
		(start 92.615258 -26.120598)
		(end 92.615258 -26.467816)
		(width 0.14224)
		(layer "In4.Cu")
		(net "M_H_MA<2>")
	)
	(segment
		(start 93.495368 -27.347926)
		(end 93.495368 -49.015396)
		(width 0.14224)
		(layer "In4.Cu")
		(net "M_H_MA<2>")
	)
	(segment
		(start 90.635582 -14.752066)
		(end 90.417396 -14.970252)
		(width 0.14224)
		(layer "In4.Cu")
		(net "M_H_MA<2>")
	)
	(segment
		(start 90.379296 -22.573996)
		(end 90.379296 -23.107396)
		(width 0.14224)
		(layer "In4.Cu")
		(net "M_H_MA<2>")
	)
	(segment
		(start 90.544396 -15.471394)
		(end 91.124024 -15.471394)
		(width 0.14224)
		(layer "In4.Cu")
		(net "M_H_MA<2>")
	)
	(segment
		(start 90.617802 -16.263874)
		(end 90.462862 -16.418814)
		(width 0.14224)
		(layer "In4.Cu")
		(net "M_H_MA<2>")
	)
	(segment
		(start 90.474546 -9.55802)
		(end 90.474546 -10.259568)
		(width 0.14224)
		(layer "In4.Cu")
		(net "M_H_MA<2>")
	)
	(segment
		(start 91.124024 -15.471394)
		(end 91.278964 -15.626334)
		(width 0.14224)
		(layer "In4.Cu")
		(net "M_H_MA<2>")
	)
	(segment
		(start 91.673934 -51.943)
		(end 91.673934 -53.111146)
		(width 0.0889)
		(layer "In4.Cu")
		(net "M_H_MA<2>")
	)
	(segment
		(start 91.278964 -15.626334)
		(end 91.278964 -16.108934)
		(width 0.14224)
		(layer "In4.Cu")
		(net "M_H_MA<2>")
	)
	(segment
		(start 90.404696 -21.21662)
		(end 90.404696 -21.761196)
		(width 0.14224)
		(layer "In4.Cu")
		(net "M_H_MA<2>")
	)
	(segment
		(start 90.04935 -11.918188)
		(end 90.04935 -13.267182)
		(width 0.14224)
		(layer "In4.Cu")
		(net "M_H_MA<2>")
	)
	(segment
		(start 91.920568 -50.8)
		(end 91.920568 -51.696366)
		(width 0.0889)
		(layer "In4.Cu")
		(net "M_H_MA<2>")
	)
	(segment
		(start 90.470228 -23.975568)
		(end 92.615258 -26.120598)
		(width 0.14224)
		(layer "In4.Cu")
		(net "M_H_MA<2>")
	)
	(segment
		(start 91.278964 -16.108934)
		(end 91.124024 -16.263874)
		(width 0.14224)
		(layer "In4.Cu")
		(net "M_H_MA<2>")
	)
	(segment
		(start 90.462862 -16.92402)
		(end 90.329512 -17.05737)
		(width 0.14224)
		(layer "In4.Cu")
		(net "M_H_MA<2>")
	)
	(segment
		(start 90.04935 -13.267182)
		(end 90.635582 -13.853414)
		(width 0.14224)
		(layer "In4.Cu")
		(net "M_H_MA<2>")
	)
	(segment
		(start 93.495368 -49.2252)
		(end 91.920568 -50.8)
		(width 0.0889)
		(layer "In4.Cu")
		(net "M_H_MA<2>")
	)
	(segment
		(start 90.049604 -9.133078)
		(end 90.474546 -9.55802)
		(width 0.14224)
		(layer "In4.Cu")
		(net "M_H_MA<2>")
	)
	(segment
		(start 90.379296 -23.107396)
		(end 90.470228 -23.198328)
		(width 0.14224)
		(layer "In4.Cu")
		(net "M_H_MA<2>")
	)
	(segment
		(start 90.04935 -10.684764)
		(end 90.04935 -11.918188)
		(width 0.14224)
		(layer "In4.Cu")
		(net "M_H_MA<2>")
	)
	(segment
		(start 91.124024 -16.263874)
		(end 90.617802 -16.263874)
		(width 0.14224)
		(layer "In4.Cu")
		(net "M_H_MA<2>")
	)
	(segment
		(start 90.557096 -18.65757)
		(end 90.557096 -21.06422)
		(width 0.14224)
		(layer "In4.Cu")
		(net "M_H_MA<2>")
	)
	(segment
		(start 90.404696 -21.761196)
		(end 90.466418 -21.822918)
		(width 0.14224)
		(layer "In4.Cu")
		(net "M_H_MA<2>")
	)
	(segment
		(start 90.417396 -15.344394)
		(end 90.544396 -15.471394)
		(width 0.14224)
		(layer "In4.Cu")
		(net "M_H_MA<2>")
	)
	(segment
		(start 90.462862 -16.418814)
		(end 90.462862 -16.92402)
		(width 0.14224)
		(layer "In4.Cu")
		(net "M_H_MA<2>")
	)
	(segment
		(start 90.466418 -22.486874)
		(end 90.379296 -22.573996)
		(width 0.14224)
		(layer "In4.Cu")
		(net "M_H_MA<2>")
	)
	(segment
		(start 91.727528 -53.314092)
		(end 92.074238 -54.104286)
		(width 0.0889)
		(layer "In4.Cu")
		(net "M_H_MA<2>")
	)
	(arc
		(start 91.673934 -53.111146)
		(mid 91.687203 -53.21619)
		(end 91.727528 -53.314092)
		(width 0.0889)
		(layer "In4.Cu")
		(net "M_H_MA<2>")
	)
	(segment
		(start 90.04935 -7.117588)
		(end 90.04935 -5.822442)
		(width 0.1651)
		(layer "F.Cu")
		(net "M_H_MA<1>")
	)
	(segment
		(start 91.787218 -53.60924)
		(end 91.215718 -53.60924)
		(width 0.1016)
		(layer "F.Cu")
		(net "M_H_MA<1>")
	)
	(via
		(at 90.04935 -7.117588)
		(size 0.4572)
		(drill 0.2032)
		(layers "F.Cu" "B.Cu")
		(net "M_H_MA<1>")
	)
	(via
		(at 91.215718 -53.60924)
		(size 0.508)
		(drill 0.254)
		(layers "F.Cu" "B.Cu")
		(net "M_H_MA<1>")
	)
	(via
		(at 90.049604 -13.933678)
		(size 0.4572)
		(drill 0.2032)
		(layers "F.Cu" "B.Cu")
		(net "M_H_MA<1>")
	)
	(segment
		(start 90.04935 -13.959332)
		(end 90.049604 -13.959078)
		(width 0.1651)
		(layer "B.Cu")
		(net "M_H_MA<1>")
	)
	(segment
		(start 90.04935 -15.222982)
		(end 90.04935 -13.959332)
		(width 0.1651)
		(layer "B.Cu")
		(net "M_H_MA<1>")
	)
	(segment
		(start 90.049604 -13.959078)
		(end 90.049604 -13.933678)
		(width 0.1651)
		(layer "B.Cu")
		(net "M_H_MA<1>")
	)
	(segment
		(start 89.634568 -12.196572)
		(end 89.634568 -8.762746)
		(width 0.14224)
		(layer "In4.Cu")
		(net "M_H_MA<1>")
	)
	(segment
		(start 89.634568 -13.1572)
		(end 89.583768 -13.1064)
		(width 0.14224)
		(layer "In4.Cu")
		(net "M_H_MA<1>")
	)
	(segment
		(start 91.214702 -26.616406)
		(end 90.927174 -26.616406)
		(width 0.14224)
		(layer "In4.Cu")
		(net "M_H_MA<1>")
	)
	(segment
		(start 89.558622 -23.31847)
		(end 89.744296 -23.132796)
		(width 0.14224)
		(layer "In4.Cu")
		(net "M_H_MA<1>")
	)
	(segment
		(start 90.049604 -14.418564)
		(end 90.049604 -13.933678)
		(width 0.14224)
		(layer "In4.Cu")
		(net "M_H_MA<1>")
	)
	(segment
		(start 90.624152 -25.195276)
		(end 90.147902 -25.195276)
		(width 0.14224)
		(layer "In4.Cu")
		(net "M_H_MA<1>")
	)
	(segment
		(start 92.06103 -26.919682)
		(end 92.06103 -26.632154)
		(width 0.14224)
		(layer "In4.Cu")
		(net "M_H_MA<1>")
	)
	(segment
		(start 89.541096 -17.617186)
		(end 89.541096 -17.109186)
		(width 0.14224)
		(layer "In4.Cu")
		(net "M_H_MA<1>")
	)
	(segment
		(start 90.147902 -25.195276)
		(end 89.558622 -24.605996)
		(width 0.14224)
		(layer "In4.Cu")
		(net "M_H_MA<1>")
	)
	(segment
		(start 91.412568 -53.101748)
		(end 91.412568 -51.816)
		(width 0.0889)
		(layer "In4.Cu")
		(net "M_H_MA<1>")
	)
	(segment
		(start 89.583768 -12.247372)
		(end 89.634568 -12.196572)
		(width 0.14224)
		(layer "In4.Cu")
		(net "M_H_MA<1>")
	)
	(segment
		(start 90.911426 -25.770078)
		(end 90.911426 -25.48255)
		(width 0.14224)
		(layer "In4.Cu")
		(net "M_H_MA<1>")
	)
	(segment
		(start 90.927174 -26.616406)
		(end 90.6399 -26.329132)
		(width 0.14224)
		(layer "In4.Cu")
		(net "M_H_MA<1>")
	)
	(segment
		(start 91.486228 -26.34488)
		(end 91.214702 -26.616406)
		(width 0.14224)
		(layer "In4.Cu")
		(net "M_H_MA<1>")
	)
	(segment
		(start 89.63787 -21.212302)
		(end 89.63787 -17.71396)
		(width 0.14224)
		(layer "In4.Cu")
		(net "M_H_MA<1>")
	)
	(segment
		(start 89.744296 -23.132796)
		(end 89.744296 -22.599396)
		(width 0.14224)
		(layer "In4.Cu")
		(net "M_H_MA<1>")
	)
	(segment
		(start 89.744296 -22.599396)
		(end 89.380568 -22.235668)
		(width 0.14224)
		(layer "In4.Cu")
		(net "M_H_MA<1>")
	)
	(segment
		(start 92.076778 -27.76601)
		(end 91.789504 -27.478736)
		(width 0.14224)
		(layer "In4.Cu")
		(net "M_H_MA<1>")
	)
	(segment
		(start 92.813886 -27.76601)
		(end 92.076778 -27.76601)
		(width 0.14224)
		(layer "In4.Cu")
		(net "M_H_MA<1>")
	)
	(segment
		(start 89.583768 -13.1064)
		(end 89.583768 -12.247372)
		(width 0.14224)
		(layer "In4.Cu")
		(net "M_H_MA<1>")
	)
	(segment
		(start 90.049604 -13.933678)
		(end 89.634568 -13.518642)
		(width 0.14224)
		(layer "In4.Cu")
		(net "M_H_MA<1>")
	)
	(segment
		(start 89.634568 -14.8336)
		(end 90.049604 -14.418564)
		(width 0.14224)
		(layer "In4.Cu")
		(net "M_H_MA<1>")
	)
	(segment
		(start 91.663012 -51.565556)
		(end 91.663012 -50.549556)
		(width 0.0889)
		(layer "In4.Cu")
		(net "M_H_MA<1>")
	)
	(segment
		(start 89.63787 -17.71396)
		(end 89.541096 -17.617186)
		(width 0.14224)
		(layer "In4.Cu")
		(net "M_H_MA<1>")
	)
	(segment
		(start 91.412568 -51.816)
		(end 91.663012 -51.565556)
		(width 0.0889)
		(layer "In4.Cu")
		(net "M_H_MA<1>")
	)
	(segment
		(start 90.6399 -26.041604)
		(end 90.911426 -25.770078)
		(width 0.14224)
		(layer "In4.Cu")
		(net "M_H_MA<1>")
	)
	(segment
		(start 91.773756 -26.34488)
		(end 91.486228 -26.34488)
		(width 0.14224)
		(layer "In4.Cu")
		(net "M_H_MA<1>")
	)
	(segment
		(start 89.541096 -17.109186)
		(end 89.634568 -17.015714)
		(width 0.14224)
		(layer "In4.Cu")
		(net "M_H_MA<1>")
	)
	(segment
		(start 89.693496 -21.658072)
		(end 89.693496 -21.267928)
		(width 0.14224)
		(layer "In4.Cu")
		(net "M_H_MA<1>")
	)
	(segment
		(start 89.634568 -13.518642)
		(end 89.634568 -13.1572)
		(width 0.14224)
		(layer "In4.Cu")
		(net "M_H_MA<1>")
	)
	(segment
		(start 92.987368 -49.2252)
		(end 92.987368 -48.941482)
		(width 0.0889)
		(layer "In4.Cu")
		(net "M_H_MA<1>")
	)
	(segment
		(start 92.987368 -27.939492)
		(end 92.813886 -27.76601)
		(width 0.14224)
		(layer "In4.Cu")
		(net "M_H_MA<1>")
	)
	(segment
		(start 90.049604 -8.34771)
		(end 90.049604 -7.117842)
		(width 0.14224)
		(layer "In4.Cu")
		(net "M_H_MA<1>")
	)
	(segment
		(start 90.6399 -26.329132)
		(end 90.6399 -26.041604)
		(width 0.14224)
		(layer "In4.Cu")
		(net "M_H_MA<1>")
	)
	(segment
		(start 91.663012 -50.549556)
		(end 92.987368 -49.2252)
		(width 0.0889)
		(layer "In4.Cu")
		(net "M_H_MA<1>")
	)
	(segment
		(start 90.049604 -7.117842)
		(end 90.04935 -7.117588)
		(width 0.14224)
		(layer "In4.Cu")
		(net "M_H_MA<1>")
	)
	(segment
		(start 89.558622 -24.605996)
		(end 89.558622 -23.31847)
		(width 0.14224)
		(layer "In4.Cu")
		(net "M_H_MA<1>")
	)
	(segment
		(start 90.911426 -25.48255)
		(end 90.624152 -25.195276)
		(width 0.14224)
		(layer "In4.Cu")
		(net "M_H_MA<1>")
	)
	(segment
		(start 89.634568 -8.762746)
		(end 90.049604 -8.34771)
		(width 0.14224)
		(layer "In4.Cu")
		(net "M_H_MA<1>")
	)
	(segment
		(start 91.789504 -27.191208)
		(end 92.06103 -26.919682)
		(width 0.14224)
		(layer "In4.Cu")
		(net "M_H_MA<1>")
	)
	(segment
		(start 89.380568 -22.235668)
		(end 89.380568 -21.971)
		(width 0.14224)
		(layer "In4.Cu")
		(net "M_H_MA<1>")
	)
	(segment
		(start 89.380568 -21.971)
		(end 89.693496 -21.658072)
		(width 0.14224)
		(layer "In4.Cu")
		(net "M_H_MA<1>")
	)
	(segment
		(start 89.634568 -17.015714)
		(end 89.634568 -14.8336)
		(width 0.14224)
		(layer "In4.Cu")
		(net "M_H_MA<1>")
	)
	(segment
		(start 89.693496 -21.267928)
		(end 89.63787 -21.212302)
		(width 0.14224)
		(layer "In4.Cu")
		(net "M_H_MA<1>")
	)
	(segment
		(start 91.789504 -27.478736)
		(end 91.789504 -27.191208)
		(width 0.14224)
		(layer "In4.Cu")
		(net "M_H_MA<1>")
	)
	(segment
		(start 92.06103 -26.632154)
		(end 91.773756 -26.34488)
		(width 0.14224)
		(layer "In4.Cu")
		(net "M_H_MA<1>")
	)
	(segment
		(start 92.987368 -48.941482)
		(end 92.987368 -27.939492)
		(width 0.14224)
		(layer "In4.Cu")
		(net "M_H_MA<1>")
	)
	(segment
		(start 91.215718 -53.60924)
		(end 91.412568 -53.101748)
		(width 0.0889)
		(layer "In4.Cu")
		(net "M_H_MA<1>")
	)
	(segment
		(start 100.372164 -55.59044)
		(end 99.800664 -55.59044)
		(width 0.1016)
		(layer "F.Cu")
		(net "M_H_MA<17>")
	)
	(segment
		(start 110.44936 -10.422382)
		(end 110.44936 -9.133586)
		(width 0.1651)
		(layer "F.Cu")
		(net "M_H_MA<17>")
	)
	(segment
		(start 110.44936 -9.133586)
		(end 110.449868 -9.133078)
		(width 0.1651)
		(layer "F.Cu")
		(net "M_H_MA<17>")
	)
	(via
		(at 110.449868 -9.133078)
		(size 0.4572)
		(drill 0.2032)
		(layers "F.Cu" "B.Cu")
		(net "M_H_MA<17>")
	)
	(via
		(at 110.449868 -11.918188)
		(size 0.4572)
		(drill 0.2032)
		(layers "F.Cu" "B.Cu")
		(net "M_H_MA<17>")
	)
	(via
		(at 99.800664 -55.59044)
		(size 0.508)
		(drill 0.254)
		(layers "F.Cu" "B.Cu")
		(net "M_H_MA<17>")
	)
	(segment
		(start 110.44936 -10.623042)
		(end 110.44936 -11.91768)
		(width 0.1651)
		(layer "B.Cu")
		(net "M_H_MA<17>")
	)
	(segment
		(start 110.44936 -11.91768)
		(end 110.449868 -11.918188)
		(width 0.1651)
		(layer "B.Cu")
		(net "M_H_MA<17>")
	)
	(segment
		(start 101.828092 -35.047428)
		(end 101.828092 -48.690276)
		(width 0.14224)
		(layer "In11.Cu")
		(net "M_H_MA<17>")
	)
	(segment
		(start 101.828092 -49.003966)
		(end 101.396292 -49.435766)
		(width 0.0889)
		(layer "In11.Cu")
		(net "M_H_MA<17>")
	)
	(segment
		(start 110.086394 -11.554714)
		(end 110.449868 -11.918188)
		(width 0.14224)
		(layer "In11.Cu")
		(net "M_H_MA<17>")
	)
	(segment
		(start 109.268768 -22.5298)
		(end 109.13745 -22.661118)
		(width 0.14224)
		(layer "In11.Cu")
		(net "M_H_MA<17>")
	)
	(segment
		(start 101.396292 -49.435766)
		(end 100.886768 -51.424078)
		(width 0.0889)
		(layer "In11.Cu")
		(net "M_H_MA<17>")
	)
	(segment
		(start 109.13745 -22.661118)
		(end 109.13745 -23.185882)
		(width 0.14224)
		(layer "In11.Cu")
		(net "M_H_MA<17>")
	)
	(segment
		(start 109.13745 -23.185882)
		(end 109.230668 -23.2791)
		(width 0.14224)
		(layer "In11.Cu")
		(net "M_H_MA<17>")
	)
	(segment
		(start 100.147374 -54.799992)
		(end 100.130864 -54.82844)
		(width 0.0889)
		(layer "In11.Cu")
		(net "M_H_MA<17>")
	)
	(segment
		(start 100.06838 -52.77612)
		(end 100.06838 -53.13172)
		(width 0.0889)
		(layer "In11.Cu")
		(net "M_H_MA<17>")
	)
	(segment
		(start 109.638084 -13.21181)
		(end 110.008924 -13.58265)
		(width 0.14224)
		(layer "In11.Cu")
		(net "M_H_MA<17>")
	)
	(segment
		(start 110.449868 -11.918188)
		(end 109.638084 -12.729972)
		(width 0.14224)
		(layer "In11.Cu")
		(net "M_H_MA<17>")
	)
	(segment
		(start 109.161326 -16.221456)
		(end 109.161326 -19.17065)
		(width 0.14224)
		(layer "In11.Cu")
		(net "M_H_MA<17>")
	)
	(segment
		(start 109.638084 -12.729972)
		(end 109.638084 -13.21181)
		(width 0.14224)
		(layer "In11.Cu")
		(net "M_H_MA<17>")
	)
	(segment
		(start 109.161326 -19.17065)
		(end 109.243368 -19.252692)
		(width 0.14224)
		(layer "In11.Cu")
		(net "M_H_MA<17>")
	)
	(segment
		(start 110.086394 -9.496552)
		(end 110.086394 -11.554714)
		(width 0.14224)
		(layer "In11.Cu")
		(net "M_H_MA<17>")
	)
	(segment
		(start 110.008924 -13.58265)
		(end 110.008924 -15.373858)
		(width 0.14224)
		(layer "In11.Cu")
		(net "M_H_MA<17>")
	)
	(segment
		(start 109.141768 -27.733752)
		(end 101.828092 -35.047428)
		(width 0.14224)
		(layer "In11.Cu")
		(net "M_H_MA<17>")
	)
	(segment
		(start 109.268768 -21.9202)
		(end 109.268768 -22.5298)
		(width 0.14224)
		(layer "In11.Cu")
		(net "M_H_MA<17>")
	)
	(segment
		(start 109.141768 -21.2598)
		(end 109.141768 -21.7932)
		(width 0.14224)
		(layer "In11.Cu")
		(net "M_H_MA<17>")
	)
	(segment
		(start 109.243368 -21.1582)
		(end 109.141768 -21.2598)
		(width 0.14224)
		(layer "In11.Cu")
		(net "M_H_MA<17>")
	)
	(segment
		(start 109.230668 -23.2791)
		(end 109.230668 -23.749)
		(width 0.14224)
		(layer "In11.Cu")
		(net "M_H_MA<17>")
	)
	(segment
		(start 109.230668 -23.749)
		(end 109.141768 -23.8379)
		(width 0.14224)
		(layer "In11.Cu")
		(net "M_H_MA<17>")
	)
	(segment
		(start 100.130864 -54.82844)
		(end 99.800664 -55.59044)
		(width 0.0889)
		(layer "In11.Cu")
		(net "M_H_MA<17>")
	)
	(segment
		(start 109.141768 -21.7932)
		(end 109.268768 -21.9202)
		(width 0.14224)
		(layer "In11.Cu")
		(net "M_H_MA<17>")
	)
	(segment
		(start 100.886768 -51.424078)
		(end 100.06838 -52.77612)
		(width 0.0889)
		(layer "In11.Cu")
		(net "M_H_MA<17>")
	)
	(segment
		(start 109.141768 -23.8379)
		(end 109.141768 -27.733752)
		(width 0.14224)
		(layer "In11.Cu")
		(net "M_H_MA<17>")
	)
	(segment
		(start 110.008924 -15.373858)
		(end 109.161326 -16.221456)
		(width 0.14224)
		(layer "In11.Cu")
		(net "M_H_MA<17>")
	)
	(segment
		(start 110.449868 -9.133078)
		(end 110.086394 -9.496552)
		(width 0.14224)
		(layer "In11.Cu")
		(net "M_H_MA<17>")
	)
	(segment
		(start 101.828092 -48.690276)
		(end 101.828092 -49.003966)
		(width 0.0889)
		(layer "In11.Cu")
		(net "M_H_MA<17>")
	)
	(segment
		(start 109.243368 -19.252692)
		(end 109.243368 -21.1582)
		(width 0.14224)
		(layer "In11.Cu")
		(net "M_H_MA<17>")
	)
	(arc
		(start 100.147374 -53.409596)
		(mid 100.200873 -53.609494)
		(end 100.147374 -53.809392)
		(width 0.0889)
		(layer "In11.Cu")
		(net "M_H_MA<17>")
	)
	(arc
		(start 100.147374 -54.400196)
		(mid 100.200873 -54.600094)
		(end 100.147374 -54.799992)
		(width 0.0889)
		(layer "In11.Cu")
		(net "M_H_MA<17>")
	)
	(arc
		(start 100.06838 -53.13172)
		(mid 100.090638 -53.275559)
		(end 100.147374 -53.409596)
		(width 0.0889)
		(layer "In11.Cu")
		(net "M_H_MA<17>")
	)
	(arc
		(start 100.147374 -53.809392)
		(mid 100.068243 -54.104794)
		(end 100.147374 -54.400196)
		(width 0.0889)
		(layer "In11.Cu")
		(net "M_H_MA<17>")
	)
	(segment
		(start 96.938338 -56.58104)
		(end 96.366838 -56.58104)
		(width 0.1016)
		(layer "F.Cu")
		(net "M_H_MA<16>")
	)
	(segment
		(start 103.649526 -7.113778)
		(end 103.649526 -5.822442)
		(width 0.1651)
		(layer "F.Cu")
		(net "M_H_MA<16>")
	)
	(via
		(at 96.366838 -56.58104)
		(size 0.508)
		(drill 0.254)
		(layers "F.Cu" "B.Cu")
		(net "M_H_MA<16>")
	)
	(via
		(at 103.649526 -13.929868)
		(size 0.4572)
		(drill 0.2032)
		(layers "F.Cu" "B.Cu")
		(net "M_H_MA<16>")
	)
	(via
		(at 103.649526 -7.113778)
		(size 0.508)
		(drill 0.254)
		(layers "F.Cu" "B.Cu")
		(net "M_H_MA<16>")
	)
	(segment
		(start 103.649526 -15.222982)
		(end 103.649526 -13.929868)
		(width 0.1651)
		(layer "B.Cu")
		(net "M_H_MA<16>")
	)
	(segment
		(start 98.423984 -51.179984)
		(end 98.423984 -50.798984)
		(width 0.0889)
		(layer "In4.Cu")
		(net "M_H_MA<16>")
	)
	(segment
		(start 100.242878 -27.152346)
		(end 100.42271 -27.152346)
		(width 0.14224)
		(layer "In4.Cu")
		(net "M_H_MA<16>")
	)
	(segment
		(start 99.453446 -27.48407)
		(end 99.453446 -27.265122)
		(width 0.14224)
		(layer "In4.Cu")
		(net "M_H_MA<16>")
	)
	(segment
		(start 102.385368 -20.414996)
		(end 102.098348 -20.127976)
		(width 0.14224)
		(layer "In4.Cu")
		(net "M_H_MA<16>")
	)
	(segment
		(start 103.2129 -13.493242)
		(end 103.2129 -10.197846)
		(width 0.14224)
		(layer "In4.Cu")
		(net "M_H_MA<16>")
	)
	(segment
		(start 102.504494 -23.912068)
		(end 102.504494 -23.468838)
		(width 0.14224)
		(layer "In4.Cu")
		(net "M_H_MA<16>")
	)
	(segment
		(start 100.803456 -26.591768)
		(end 100.574602 -26.362914)
		(width 0.14224)
		(layer "In4.Cu")
		(net "M_H_MA<16>")
	)
	(segment
		(start 104.086406 -9.32434)
		(end 104.086406 -8.886444)
		(width 0.14224)
		(layer "In4.Cu")
		(net "M_H_MA<16>")
	)
	(segment
		(start 102.385622 -18.549366)
		(end 102.11054 -18.274284)
		(width 0.14224)
		(layer "In4.Cu")
		(net "M_H_MA<16>")
	)
	(segment
		(start 102.098348 -19.431508)
		(end 102.385368 -19.144488)
		(width 0.14224)
		(layer "In4.Cu")
		(net "M_H_MA<16>")
	)
	(segment
		(start 102.159562 -24.257)
		(end 102.504494 -23.912068)
		(width 0.14224)
		(layer "In4.Cu")
		(net "M_H_MA<16>")
	)
	(segment
		(start 96.026478 -55.801006)
		(end 96.020128 -55.790338)
		(width 0.0889)
		(layer "In4.Cu")
		(net "M_H_MA<16>")
	)
	(segment
		(start 102.40645 -22.387052)
		(end 102.40645 -22.008084)
		(width 0.14224)
		(layer "In4.Cu")
		(net "M_H_MA<16>")
	)
	(segment
		(start 96.136968 -56.35117)
		(end 96.136968 -56.23179)
		(width 0.0889)
		(layer "In4.Cu")
		(net "M_H_MA<16>")
	)
	(segment
		(start 102.385368 -21.0566)
		(end 102.385368 -20.414996)
		(width 0.14224)
		(layer "In4.Cu")
		(net "M_H_MA<16>")
	)
	(segment
		(start 102.11054 -18.274284)
		(end 102.11054 -17.400778)
		(width 0.14224)
		(layer "In4.Cu")
		(net "M_H_MA<16>")
	)
	(segment
		(start 99.795076 -26.923492)
		(end 100.014024 -26.923492)
		(width 0.14224)
		(layer "In4.Cu")
		(net "M_H_MA<16>")
	)
	(segment
		(start 102.385368 -19.144488)
		(end 102.385368 -18.550128)
		(width 0.14224)
		(layer "In4.Cu")
		(net "M_H_MA<16>")
	)
	(segment
		(start 98.423984 -28.294584)
		(end 98.67392 -28.044648)
		(width 0.14224)
		(layer "In4.Cu")
		(net "M_H_MA<16>")
	)
	(segment
		(start 102.11054 -17.400778)
		(end 102.37216 -17.139158)
		(width 0.14224)
		(layer "In4.Cu")
		(net "M_H_MA<16>")
	)
	(segment
		(start 100.574602 -26.362914)
		(end 100.574602 -26.143966)
		(width 0.14224)
		(layer "In4.Cu")
		(net "M_H_MA<16>")
	)
	(segment
		(start 102.283768 -22.509734)
		(end 102.40645 -22.387052)
		(width 0.14224)
		(layer "In4.Cu")
		(net "M_H_MA<16>")
	)
	(segment
		(start 96.366838 -56.58104)
		(end 96.136968 -56.35117)
		(width 0.0889)
		(layer "In4.Cu")
		(net "M_H_MA<16>")
	)
	(segment
		(start 103.2129 -10.197846)
		(end 104.086406 -9.32434)
		(width 0.14224)
		(layer "In4.Cu")
		(net "M_H_MA<16>")
	)
	(segment
		(start 97.406968 -52.197)
		(end 98.423984 -51.179984)
		(width 0.0889)
		(layer "In4.Cu")
		(net "M_H_MA<16>")
	)
	(segment
		(start 103.387144 -13.959078)
		(end 103.620316 -13.959078)
		(width 0.14224)
		(layer "In4.Cu")
		(net "M_H_MA<16>")
	)
	(segment
		(start 96.734884 -53.1622)
		(end 96.850962 -52.961794)
		(width 0.0889)
		(layer "In4.Cu")
		(net "M_H_MA<16>")
	)
	(segment
		(start 102.283768 -21.885402)
		(end 102.283768 -21.1582)
		(width 0.14224)
		(layer "In4.Cu")
		(net "M_H_MA<16>")
	)
	(segment
		(start 103.620316 -13.959078)
		(end 103.649526 -13.929868)
		(width 0.14224)
		(layer "In4.Cu")
		(net "M_H_MA<16>")
	)
	(segment
		(start 96.850962 -52.961794)
		(end 96.945958 -52.797456)
		(width 0.0889)
		(layer "In4.Cu")
		(net "M_H_MA<16>")
	)
	(segment
		(start 102.283768 -23.248112)
		(end 102.283768 -22.509734)
		(width 0.14224)
		(layer "In4.Cu")
		(net "M_H_MA<16>")
	)
	(segment
		(start 98.892868 -28.044648)
		(end 99.342448 -28.494228)
		(width 0.14224)
		(layer "In4.Cu")
		(net "M_H_MA<16>")
	)
	(segment
		(start 98.423984 -50.798984)
		(end 98.423984 -28.294584)
		(width 0.14224)
		(layer "In4.Cu")
		(net "M_H_MA<16>")
	)
	(segment
		(start 99.453446 -27.265122)
		(end 99.795076 -26.923492)
		(width 0.14224)
		(layer "In4.Cu")
		(net "M_H_MA<16>")
	)
	(segment
		(start 104.152954 -8.819896)
		(end 104.152954 -7.617206)
		(width 0.14224)
		(layer "In4.Cu")
		(net "M_H_MA<16>")
	)
	(segment
		(start 96.020128 -54.799738)
		(end 96.015302 -54.791102)
		(width 0.0889)
		(layer "In4.Cu")
		(net "M_H_MA<16>")
	)
	(segment
		(start 99.89693 -27.927554)
		(end 99.453446 -27.48407)
		(width 0.14224)
		(layer "In4.Cu")
		(net "M_H_MA<16>")
	)
	(segment
		(start 99.342448 -28.494228)
		(end 99.522534 -28.494228)
		(width 0.14224)
		(layer "In4.Cu")
		(net "M_H_MA<16>")
	)
	(segment
		(start 102.504494 -23.468838)
		(end 102.283768 -23.248112)
		(width 0.14224)
		(layer "In4.Cu")
		(net "M_H_MA<16>")
	)
	(segment
		(start 96.026478 -54.810406)
		(end 96.020128 -54.799738)
		(width 0.0889)
		(layer "In4.Cu")
		(net "M_H_MA<16>")
	)
	(segment
		(start 100.014024 -26.923492)
		(end 100.242878 -27.152346)
		(width 0.14224)
		(layer "In4.Cu")
		(net "M_H_MA<16>")
	)
	(segment
		(start 96.020128 -55.790338)
		(end 96.015302 -55.781702)
		(width 0.0889)
		(layer "In4.Cu")
		(net "M_H_MA<16>")
	)
	(segment
		(start 102.283768 -21.1582)
		(end 102.385368 -21.0566)
		(width 0.14224)
		(layer "In4.Cu")
		(net "M_H_MA<16>")
	)
	(segment
		(start 101.86924 -24.257)
		(end 102.159562 -24.257)
		(width 0.14224)
		(layer "In4.Cu")
		(net "M_H_MA<16>")
	)
	(segment
		(start 104.086406 -8.886444)
		(end 104.152954 -8.819896)
		(width 0.14224)
		(layer "In4.Cu")
		(net "M_H_MA<16>")
	)
	(segment
		(start 103.649526 -13.929868)
		(end 103.2129 -13.493242)
		(width 0.14224)
		(layer "In4.Cu")
		(net "M_H_MA<16>")
	)
	(segment
		(start 100.42271 -27.152346)
		(end 100.803456 -26.7716)
		(width 0.14224)
		(layer "In4.Cu")
		(net "M_H_MA<16>")
	)
	(segment
		(start 102.37216 -17.139158)
		(end 102.37216 -14.974062)
		(width 0.14224)
		(layer "In4.Cu")
		(net "M_H_MA<16>")
	)
	(segment
		(start 96.020128 -54.399688)
		(end 96.50603 -53.556662)
		(width 0.0889)
		(layer "In4.Cu")
		(net "M_H_MA<16>")
	)
	(segment
		(start 100.803456 -26.7716)
		(end 100.803456 -26.591768)
		(width 0.14224)
		(layer "In4.Cu")
		(net "M_H_MA<16>")
	)
	(segment
		(start 101.56825 -24.55799)
		(end 101.86924 -24.257)
		(width 0.14224)
		(layer "In4.Cu")
		(net "M_H_MA<16>")
	)
	(segment
		(start 102.37216 -14.974062)
		(end 103.387144 -13.959078)
		(width 0.14224)
		(layer "In4.Cu")
		(net "M_H_MA<16>")
	)
	(segment
		(start 102.385368 -18.550128)
		(end 102.385622 -18.549366)
		(width 0.14224)
		(layer "In4.Cu")
		(net "M_H_MA<16>")
	)
	(segment
		(start 102.40645 -22.008084)
		(end 102.283768 -21.885402)
		(width 0.14224)
		(layer "In4.Cu")
		(net "M_H_MA<16>")
	)
	(segment
		(start 96.50603 -53.556662)
		(end 96.734884 -53.1622)
		(width 0.0889)
		(layer "In4.Cu")
		(net "M_H_MA<16>")
	)
	(segment
		(start 98.67392 -28.044648)
		(end 98.892868 -28.044648)
		(width 0.14224)
		(layer "In4.Cu")
		(net "M_H_MA<16>")
	)
	(segment
		(start 104.152954 -7.617206)
		(end 103.649526 -7.113778)
		(width 0.14224)
		(layer "In4.Cu")
		(net "M_H_MA<16>")
	)
	(segment
		(start 100.574602 -26.143966)
		(end 101.56825 -25.150318)
		(width 0.14224)
		(layer "In4.Cu")
		(net "M_H_MA<16>")
	)
	(segment
		(start 102.098348 -20.127976)
		(end 102.098348 -19.431508)
		(width 0.14224)
		(layer "In4.Cu")
		(net "M_H_MA<16>")
	)
	(segment
		(start 99.89693 -28.119832)
		(end 99.89693 -27.927554)
		(width 0.14224)
		(layer "In4.Cu")
		(net "M_H_MA<16>")
	)
	(segment
		(start 101.56825 -25.150318)
		(end 101.56825 -24.55799)
		(width 0.14224)
		(layer "In4.Cu")
		(net "M_H_MA<16>")
	)
	(segment
		(start 99.522534 -28.494228)
		(end 99.89693 -28.119832)
		(width 0.14224)
		(layer "In4.Cu")
		(net "M_H_MA<16>")
	)
	(arc
		(start 96.015302 -54.791102)
		(mid 95.966547 -54.59475)
		(end 96.020128 -54.399688)
		(width 0.0889)
		(layer "In4.Cu")
		(net "M_H_MA<16>")
	)
	(arc
		(start 96.136968 -56.23179)
		(mid 96.108908 -56.009425)
		(end 96.026478 -55.801006)
		(width 0.0889)
		(layer "In4.Cu")
		(net "M_H_MA<16>")
	)
	(arc
		(start 96.020128 -55.390288)
		(mid 96.09935 -55.10117)
		(end 96.026478 -54.810406)
		(width 0.0889)
		(layer "In4.Cu")
		(net "M_H_MA<16>")
	)
	(arc
		(start 96.945958 -52.797456)
		(mid 97.156835 -52.482158)
		(end 97.406968 -52.197)
		(width 0.0889)
		(layer "In4.Cu")
		(net "M_H_MA<16>")
	)
	(arc
		(start 96.015302 -55.781702)
		(mid 95.966547 -55.58535)
		(end 96.020128 -55.390288)
		(width 0.0889)
		(layer "In4.Cu")
		(net "M_H_MA<16>")
	)
	(segment
		(start 107.04957 -7.117334)
		(end 107.049824 -7.117588)
		(width 0.1651)
		(layer "F.Cu")
		(net "M_H_MA<15>")
	)
	(segment
		(start 96.938338 -55.59044)
		(end 96.366838 -55.59044)
		(width 0.1016)
		(layer "F.Cu")
		(net "M_H_MA<15>")
	)
	(segment
		(start 107.04957 -5.822442)
		(end 107.04957 -7.117334)
		(width 0.1651)
		(layer "F.Cu")
		(net "M_H_MA<15>")
	)
	(via
		(at 96.366838 -55.59044)
		(size 0.508)
		(drill 0.254)
		(layers "F.Cu" "B.Cu")
		(net "M_H_MA<15>")
	)
	(via
		(at 107.049824 -7.117588)
		(size 0.4572)
		(drill 0.2032)
		(layers "F.Cu" "B.Cu")
		(net "M_H_MA<15>")
	)
	(via
		(at 107.049824 -13.933678)
		(size 0.4572)
		(drill 0.2032)
		(layers "F.Cu" "B.Cu")
		(net "M_H_MA<15>")
	)
	(segment
		(start 107.04957 -13.933932)
		(end 107.049824 -13.933678)
		(width 0.10795)
		(layer "B.Cu")
		(net "M_H_MA<15>")
	)
	(segment
		(start 107.04957 -15.222982)
		(end 107.04957 -13.933932)
		(width 0.10795)
		(layer "B.Cu")
		(net "M_H_MA<15>")
	)
	(segment
		(start 100.449126 -31.499048)
		(end 100.596446 -31.646368)
		(width 0.14224)
		(layer "In11.Cu")
		(net "M_H_MA<15>")
	)
	(segment
		(start 106.52887 -7.638542)
		(end 107.049824 -7.117588)
		(width 0.14224)
		(layer "In11.Cu")
		(net "M_H_MA<15>")
	)
	(segment
		(start 105.026968 -17.787874)
		(end 105.758996 -17.055846)
		(width 0.14224)
		(layer "In11.Cu")
		(net "M_H_MA<15>")
	)
	(segment
		(start 106.635804 -12.495022)
		(end 106.635804 -8.627364)
		(width 0.14224)
		(layer "In11.Cu")
		(net "M_H_MA<15>")
	)
	(segment
		(start 99.173792 -33.35655)
		(end 100.021644 -32.508698)
		(width 0.14224)
		(layer "In11.Cu")
		(net "M_H_MA<15>")
	)
	(segment
		(start 102.320852 -30.20949)
		(end 102.320852 -29.921962)
		(width 0.14224)
		(layer "In11.Cu")
		(net "M_H_MA<15>")
	)
	(segment
		(start 100.983288 -30.601158)
		(end 101.270562 -30.313884)
		(width 0.14224)
		(layer "In11.Cu")
		(net "M_H_MA<15>")
	)
	(segment
		(start 97.381568 -54.5338)
		(end 97.660968 -54.2544)
		(width 0.0889)
		(layer "In11.Cu")
		(net "M_H_MA<15>")
	)
	(segment
		(start 105.839768 -21.8948)
		(end 104.916224 -20.971256)
		(width 0.14224)
		(layer "In11.Cu")
		(net "M_H_MA<15>")
	)
	(segment
		(start 102.150418 -29.751528)
		(end 102.150418 -29.452316)
		(width 0.14224)
		(layer "In11.Cu")
		(net "M_H_MA<15>")
	)
	(segment
		(start 105.758996 -16.317722)
		(end 107.049824 -15.026894)
		(width 0.14224)
		(layer "In11.Cu")
		(net "M_H_MA<15>")
	)
	(segment
		(start 97.660968 -54.2544)
		(end 97.660968 -52.475892)
		(width 0.0889)
		(layer "In11.Cu")
		(net "M_H_MA<15>")
	)
	(segment
		(start 101.171248 -31.359094)
		(end 101.171248 -31.071566)
		(width 0.14224)
		(layer "In11.Cu")
		(net "M_H_MA<15>")
	)
	(segment
		(start 106.519472 -13.403326)
		(end 106.519472 -12.611354)
		(width 0.14224)
		(layer "In11.Cu")
		(net "M_H_MA<15>")
	)
	(segment
		(start 105.839768 -22.4536)
		(end 105.839768 -21.8948)
		(width 0.14224)
		(layer "In11.Cu")
		(net "M_H_MA<15>")
	)
	(segment
		(start 99.85375 -31.786322)
		(end 100.141024 -31.499048)
		(width 0.14224)
		(layer "In11.Cu")
		(net "M_H_MA<15>")
	)
	(segment
		(start 102.320852 -29.921962)
		(end 102.150418 -29.751528)
		(width 0.14224)
		(layer "In11.Cu")
		(net "M_H_MA<15>")
	)
	(segment
		(start 102.033578 -30.496764)
		(end 102.320852 -30.20949)
		(width 0.14224)
		(layer "In11.Cu")
		(net "M_H_MA<15>")
	)
	(segment
		(start 105.738168 -22.5552)
		(end 105.839768 -22.4536)
		(width 0.14224)
		(layer "In11.Cu")
		(net "M_H_MA<15>")
	)
	(segment
		(start 106.52887 -8.52043)
		(end 106.52887 -7.638542)
		(width 0.14224)
		(layer "In11.Cu")
		(net "M_H_MA<15>")
	)
	(segment
		(start 100.596446 -31.646368)
		(end 100.883974 -31.646368)
		(width 0.14224)
		(layer "In11.Cu")
		(net "M_H_MA<15>")
	)
	(segment
		(start 98.194368 -51.942492)
		(end 98.194368 -50.8762)
		(width 0.0889)
		(layer "In11.Cu")
		(net "M_H_MA<15>")
	)
	(segment
		(start 105.026968 -18.288)
		(end 105.026968 -17.787874)
		(width 0.14224)
		(layer "In11.Cu")
		(net "M_H_MA<15>")
	)
	(segment
		(start 101.171248 -31.071566)
		(end 100.983288 -30.883606)
		(width 0.14224)
		(layer "In11.Cu")
		(net "M_H_MA<15>")
	)
	(segment
		(start 104.916224 -20.971256)
		(end 104.916224 -18.398744)
		(width 0.14224)
		(layer "In11.Cu")
		(net "M_H_MA<15>")
	)
	(segment
		(start 105.758996 -17.055846)
		(end 105.758996 -16.317722)
		(width 0.14224)
		(layer "In11.Cu")
		(net "M_H_MA<15>")
	)
	(segment
		(start 102.401878 -29.200856)
		(end 103.776018 -29.200856)
		(width 0.14224)
		(layer "In11.Cu")
		(net "M_H_MA<15>")
	)
	(segment
		(start 106.635804 -8.627364)
		(end 106.52887 -8.52043)
		(width 0.14224)
		(layer "In11.Cu")
		(net "M_H_MA<15>")
	)
	(segment
		(start 100.883974 -31.646368)
		(end 101.171248 -31.359094)
		(width 0.14224)
		(layer "In11.Cu")
		(net "M_H_MA<15>")
	)
	(segment
		(start 107.049824 -15.026894)
		(end 107.049824 -13.933678)
		(width 0.14224)
		(layer "In11.Cu")
		(net "M_H_MA<15>")
	)
	(segment
		(start 107.049824 -13.933678)
		(end 106.519472 -13.403326)
		(width 0.14224)
		(layer "In11.Cu")
		(net "M_H_MA<15>")
	)
	(segment
		(start 97.660968 -52.475892)
		(end 98.194368 -51.942492)
		(width 0.0889)
		(layer "In11.Cu")
		(net "M_H_MA<15>")
	)
	(segment
		(start 100.021644 -32.508698)
		(end 100.021644 -32.22117)
		(width 0.14224)
		(layer "In11.Cu")
		(net "M_H_MA<15>")
	)
	(segment
		(start 101.74605 -30.496764)
		(end 102.033578 -30.496764)
		(width 0.14224)
		(layer "In11.Cu")
		(net "M_H_MA<15>")
	)
	(segment
		(start 105.865168 -23.4188)
		(end 105.738168 -23.2918)
		(width 0.14224)
		(layer "In11.Cu")
		(net "M_H_MA<15>")
	)
	(segment
		(start 98.194368 -50.8762)
		(end 99.173792 -49.896776)
		(width 0.0889)
		(layer "In11.Cu")
		(net "M_H_MA<15>")
	)
	(segment
		(start 100.983288 -30.883606)
		(end 100.983288 -30.601158)
		(width 0.14224)
		(layer "In11.Cu")
		(net "M_H_MA<15>")
	)
	(segment
		(start 102.150418 -29.452316)
		(end 102.401878 -29.200856)
		(width 0.14224)
		(layer "In11.Cu")
		(net "M_H_MA<15>")
	)
	(segment
		(start 101.56317 -30.313884)
		(end 101.74605 -30.496764)
		(width 0.14224)
		(layer "In11.Cu")
		(net "M_H_MA<15>")
	)
	(segment
		(start 105.738168 -23.2918)
		(end 105.738168 -22.5552)
		(width 0.14224)
		(layer "In11.Cu")
		(net "M_H_MA<15>")
	)
	(segment
		(start 101.270562 -30.313884)
		(end 101.56317 -30.313884)
		(width 0.14224)
		(layer "In11.Cu")
		(net "M_H_MA<15>")
	)
	(segment
		(start 97.187766 -54.5338)
		(end 97.381568 -54.5338)
		(width 0.0889)
		(layer "In11.Cu")
		(net "M_H_MA<15>")
	)
	(segment
		(start 106.519472 -12.611354)
		(end 106.635804 -12.495022)
		(width 0.14224)
		(layer "In11.Cu")
		(net "M_H_MA<15>")
	)
	(segment
		(start 96.366838 -55.59044)
		(end 96.574864 -55.146702)
		(width 0.0889)
		(layer "In11.Cu")
		(net "M_H_MA<15>")
	)
	(segment
		(start 104.916224 -18.398744)
		(end 105.026968 -18.288)
		(width 0.14224)
		(layer "In11.Cu")
		(net "M_H_MA<15>")
	)
	(segment
		(start 100.141024 -31.499048)
		(end 100.449126 -31.499048)
		(width 0.14224)
		(layer "In11.Cu")
		(net "M_H_MA<15>")
	)
	(segment
		(start 99.85375 -32.053276)
		(end 99.85375 -31.786322)
		(width 0.14224)
		(layer "In11.Cu")
		(net "M_H_MA<15>")
	)
	(segment
		(start 99.173792 -48.66005)
		(end 99.173792 -33.35655)
		(width 0.14224)
		(layer "In11.Cu")
		(net "M_H_MA<15>")
	)
	(segment
		(start 99.173792 -49.896776)
		(end 99.173792 -48.66005)
		(width 0.0889)
		(layer "In11.Cu")
		(net "M_H_MA<15>")
	)
	(segment
		(start 96.574864 -55.146702)
		(end 97.187766 -54.5338)
		(width 0.0889)
		(layer "In11.Cu")
		(net "M_H_MA<15>")
	)
	(segment
		(start 105.865168 -27.111706)
		(end 105.865168 -23.4188)
		(width 0.14224)
		(layer "In11.Cu")
		(net "M_H_MA<15>")
	)
	(segment
		(start 100.021644 -32.22117)
		(end 99.85375 -32.053276)
		(width 0.14224)
		(layer "In11.Cu")
		(net "M_H_MA<15>")
	)
	(segment
		(start 103.776018 -29.200856)
		(end 105.865168 -27.111706)
		(width 0.14224)
		(layer "In11.Cu")
		(net "M_H_MA<15>")
	)
	(segment
		(start 105.349548 -9.133332)
		(end 105.349802 -9.133078)
		(width 0.1651)
		(layer "F.Cu")
		(net "M_H_MA<14>")
	)
	(segment
		(start 97.796858 -57.076086)
		(end 97.225358 -57.076086)
		(width 0.1016)
		(layer "F.Cu")
		(net "M_H_MA<14>")
	)
	(segment
		(start 105.349548 -10.422382)
		(end 105.349548 -9.133332)
		(width 0.1651)
		(layer "F.Cu")
		(net "M_H_MA<14>")
	)
	(via
		(at 105.349802 -11.918188)
		(size 0.4572)
		(drill 0.2032)
		(layers "F.Cu" "B.Cu")
		(net "M_H_MA<14>")
	)
	(via
		(at 105.349802 -9.133078)
		(size 0.4572)
		(drill 0.2032)
		(layers "F.Cu" "B.Cu")
		(net "M_H_MA<14>")
	)
	(via
		(at 97.225358 -57.076086)
		(size 0.508)
		(drill 0.254)
		(layers "F.Cu" "B.Cu")
		(net "M_H_MA<14>")
	)
	(segment
		(start 105.349548 -11.917934)
		(end 105.349802 -11.918188)
		(width 0.1651)
		(layer "B.Cu")
		(net "M_H_MA<14>")
	)
	(segment
		(start 105.349548 -10.623042)
		(end 105.349548 -11.917934)
		(width 0.1651)
		(layer "B.Cu")
		(net "M_H_MA<14>")
	)
	(segment
		(start 103.908098 -14.467078)
		(end 104.063038 -14.312138)
		(width 0.14224)
		(layer "In4.Cu")
		(net "M_H_MA<14>")
	)
	(segment
		(start 104.430322 -10.203942)
		(end 104.557322 -10.330942)
		(width 0.14224)
		(layer "In4.Cu")
		(net "M_H_MA<14>")
	)
	(segment
		(start 105.349802 -11.739626)
		(end 105.103422 -11.493246)
		(width 0.14224)
		(layer "In4.Cu")
		(net "M_H_MA<14>")
	)
	(segment
		(start 103.172768 -24.27986)
		(end 103.172768 -23.12416)
		(width 0.14224)
		(layer "In4.Cu")
		(net "M_H_MA<14>")
	)
	(segment
		(start 105.349802 -12.417298)
		(end 105.349802 -11.918188)
		(width 0.14224)
		(layer "In4.Cu")
		(net "M_H_MA<14>")
	)
	(segment
		(start 103.256588 -23.04034)
		(end 103.256588 -22.661372)
		(width 0.14224)
		(layer "In4.Cu")
		(net "M_H_MA<14>")
	)
	(segment
		(start 105.506266 -9.731756)
		(end 105.349802 -9.575292)
		(width 0.14224)
		(layer "In4.Cu")
		(net "M_H_MA<14>")
	)
	(segment
		(start 98.807524 -29.993844)
		(end 101.445568 -27.3558)
		(width 0.14224)
		(layer "In4.Cu")
		(net "M_H_MA<14>")
	)
	(segment
		(start 105.103422 -11.493246)
		(end 104.02189 -11.493246)
		(width 0.14224)
		(layer "In4.Cu")
		(net "M_H_MA<14>")
	)
	(segment
		(start 103.214932 -18.990818)
		(end 103.214932 -18.281396)
		(width 0.14224)
		(layer "In4.Cu")
		(net "M_H_MA<14>")
	)
	(segment
		(start 104.063038 -13.704062)
		(end 105.349802 -12.417298)
		(width 0.14224)
		(layer "In4.Cu")
		(net "M_H_MA<14>")
	)
	(segment
		(start 97.470468 -53.4797)
		(end 97.662492 -53.287676)
		(width 0.0889)
		(layer "In4.Cu")
		(net "M_H_MA<14>")
	)
	(segment
		(start 96.797368 -53.9496)
		(end 97.051368 -53.6956)
		(width 0.0889)
		(layer "In4.Cu")
		(net "M_H_MA<14>")
	)
	(segment
		(start 103.256588 -18.23974)
		(end 103.256588 -17.860772)
		(width 0.14224)
		(layer "In4.Cu")
		(net "M_H_MA<14>")
	)
	(segment
		(start 103.256588 -17.860772)
		(end 103.172768 -17.776952)
		(width 0.14224)
		(layer "In4.Cu")
		(net "M_H_MA<14>")
	)
	(segment
		(start 97.225358 -57.076086)
		(end 96.797368 -56.1086)
		(width 0.0889)
		(layer "In4.Cu")
		(net "M_H_MA<14>")
	)
	(segment
		(start 103.172768 -17.776952)
		(end 103.172768 -16.96085)
		(width 0.14224)
		(layer "In4.Cu")
		(net "M_H_MA<14>")
	)
	(segment
		(start 103.764842 -11.236198)
		(end 103.764842 -10.373106)
		(width 0.14224)
		(layer "In4.Cu")
		(net "M_H_MA<14>")
	)
	(segment
		(start 103.934006 -10.203942)
		(end 104.430322 -10.203942)
		(width 0.14224)
		(layer "In4.Cu")
		(net "M_H_MA<14>")
	)
	(segment
		(start 96.797368 -56.1086)
		(end 96.797368 -53.9496)
		(width 0.0889)
		(layer "In4.Cu")
		(net "M_H_MA<14>")
	)
	(segment
		(start 103.764842 -10.373106)
		(end 103.934006 -10.203942)
		(width 0.14224)
		(layer "In4.Cu")
		(net "M_H_MA<14>")
	)
	(segment
		(start 98.807524 -51.304444)
		(end 98.807524 -48.740314)
		(width 0.0889)
		(layer "In4.Cu")
		(net "M_H_MA<14>")
	)
	(segment
		(start 103.172768 -16.96085)
		(end 103.209344 -16.924274)
		(width 0.14224)
		(layer "In4.Cu")
		(net "M_H_MA<14>")
	)
	(segment
		(start 105.349802 -11.918188)
		(end 105.349802 -11.739626)
		(width 0.14224)
		(layer "In4.Cu")
		(net "M_H_MA<14>")
	)
	(segment
		(start 105.838752 -9.731756)
		(end 105.506266 -9.731756)
		(width 0.14224)
		(layer "In4.Cu")
		(net "M_H_MA<14>")
	)
	(segment
		(start 104.02189 -11.493246)
		(end 103.764842 -11.236198)
		(width 0.14224)
		(layer "In4.Cu")
		(net "M_H_MA<14>")
	)
	(segment
		(start 103.256588 -22.661372)
		(end 103.172768 -22.577552)
		(width 0.14224)
		(layer "In4.Cu")
		(net "M_H_MA<14>")
	)
	(segment
		(start 105.349802 -9.575292)
		(end 105.349802 -9.133078)
		(width 0.14224)
		(layer "In4.Cu")
		(net "M_H_MA<14>")
	)
	(segment
		(start 97.662492 -52.449476)
		(end 98.807524 -51.304444)
		(width 0.0889)
		(layer "In4.Cu")
		(net "M_H_MA<14>")
	)
	(segment
		(start 105.946702 -10.700512)
		(end 106.068368 -10.578846)
		(width 0.14224)
		(layer "In4.Cu")
		(net "M_H_MA<14>")
	)
	(segment
		(start 97.051368 -53.6956)
		(end 97.470468 -53.4797)
		(width 0.0889)
		(layer "In4.Cu")
		(net "M_H_MA<14>")
	)
	(segment
		(start 104.557322 -10.330942)
		(end 104.557322 -10.573512)
		(width 0.14224)
		(layer "In4.Cu")
		(net "M_H_MA<14>")
	)
	(segment
		(start 104.557322 -10.573512)
		(end 104.684322 -10.700512)
		(width 0.14224)
		(layer "In4.Cu")
		(net "M_H_MA<14>")
	)
	(segment
		(start 103.299768 -21.63445)
		(end 103.299768 -19.075654)
		(width 0.14224)
		(layer "In4.Cu")
		(net "M_H_MA<14>")
	)
	(segment
		(start 103.299768 -19.075654)
		(end 103.214932 -18.990818)
		(width 0.14224)
		(layer "In4.Cu")
		(net "M_H_MA<14>")
	)
	(segment
		(start 97.662492 -53.287676)
		(end 97.662492 -52.449476)
		(width 0.0889)
		(layer "In4.Cu")
		(net "M_H_MA<14>")
	)
	(segment
		(start 101.445568 -27.3558)
		(end 101.445568 -26.00706)
		(width 0.14224)
		(layer "In4.Cu")
		(net "M_H_MA<14>")
	)
	(segment
		(start 103.53929 -14.467078)
		(end 103.908098 -14.467078)
		(width 0.14224)
		(layer "In4.Cu")
		(net "M_H_MA<14>")
	)
	(segment
		(start 106.068368 -10.578846)
		(end 106.068368 -9.961372)
		(width 0.14224)
		(layer "In4.Cu")
		(net "M_H_MA<14>")
	)
	(segment
		(start 104.684322 -10.700512)
		(end 105.946702 -10.700512)
		(width 0.14224)
		(layer "In4.Cu")
		(net "M_H_MA<14>")
	)
	(segment
		(start 101.445568 -26.00706)
		(end 103.172768 -24.27986)
		(width 0.14224)
		(layer "In4.Cu")
		(net "M_H_MA<14>")
	)
	(segment
		(start 103.172768 -21.76145)
		(end 103.299768 -21.63445)
		(width 0.14224)
		(layer "In4.Cu")
		(net "M_H_MA<14>")
	)
	(segment
		(start 103.209344 -14.797024)
		(end 103.53929 -14.467078)
		(width 0.14224)
		(layer "In4.Cu")
		(net "M_H_MA<14>")
	)
	(segment
		(start 103.172768 -22.577552)
		(end 103.172768 -21.76145)
		(width 0.14224)
		(layer "In4.Cu")
		(net "M_H_MA<14>")
	)
	(segment
		(start 103.214932 -18.281396)
		(end 103.256588 -18.23974)
		(width 0.14224)
		(layer "In4.Cu")
		(net "M_H_MA<14>")
	)
	(segment
		(start 98.807524 -48.740314)
		(end 98.807524 -29.993844)
		(width 0.14224)
		(layer "In4.Cu")
		(net "M_H_MA<14>")
	)
	(segment
		(start 106.068368 -9.961372)
		(end 105.838752 -9.731756)
		(width 0.14224)
		(layer "In4.Cu")
		(net "M_H_MA<14>")
	)
	(segment
		(start 103.172768 -23.12416)
		(end 103.256588 -23.04034)
		(width 0.14224)
		(layer "In4.Cu")
		(net "M_H_MA<14>")
	)
	(segment
		(start 104.063038 -14.312138)
		(end 104.063038 -13.704062)
		(width 0.14224)
		(layer "In4.Cu")
		(net "M_H_MA<14>")
	)
	(segment
		(start 103.209344 -16.924274)
		(end 103.209344 -14.797024)
		(width 0.14224)
		(layer "In4.Cu")
		(net "M_H_MA<14>")
	)
	(segment
		(start 108.749338 -10.422382)
		(end 108.749338 -9.133586)
		(width 0.1651)
		(layer "F.Cu")
		(net "M_H_MA<13>")
	)
	(segment
		(start 108.749338 -9.133586)
		(end 108.749846 -9.133078)
		(width 0.1651)
		(layer "F.Cu")
		(net "M_H_MA<13>")
	)
	(segment
		(start 97.796858 -55.094886)
		(end 97.225358 -55.094886)
		(width 0.1016)
		(layer "F.Cu")
		(net "M_H_MA<13>")
	)
	(via
		(at 108.749846 -9.133078)
		(size 0.4572)
		(drill 0.2032)
		(layers "F.Cu" "B.Cu")
		(net "M_H_MA<13>")
	)
	(via
		(at 108.749846 -11.918188)
		(size 0.4572)
		(drill 0.2032)
		(layers "F.Cu" "B.Cu")
		(net "M_H_MA<13>")
	)
	(via
		(at 97.225358 -55.094886)
		(size 0.508)
		(drill 0.254)
		(layers "F.Cu" "B.Cu")
		(net "M_H_MA<13>")
	)
	(segment
		(start 108.749338 -11.91768)
		(end 108.749846 -11.918188)
		(width 0.1651)
		(layer "B.Cu")
		(net "M_H_MA<13>")
	)
	(segment
		(start 108.749338 -10.623042)
		(end 108.749338 -11.91768)
		(width 0.1651)
		(layer "B.Cu")
		(net "M_H_MA<13>")
	)
	(segment
		(start 108.594906 -10.245598)
		(end 107.58805 -10.245598)
		(width 0.14224)
		(layer "In11.Cu")
		(net "M_H_MA<13>")
	)
	(segment
		(start 108.313982 -13.502386)
		(end 108.749338 -13.06703)
		(width 0.14224)
		(layer "In11.Cu")
		(net "M_H_MA<13>")
	)
	(segment
		(start 107.43311 -11.276838)
		(end 107.43311 -11.014964)
		(width 0.14224)
		(layer "In11.Cu")
		(net "M_H_MA<13>")
	)
	(segment
		(start 107.58805 -10.245598)
		(end 107.43311 -10.090658)
		(width 0.14224)
		(layer "In11.Cu")
		(net "M_H_MA<13>")
	)
	(segment
		(start 106.500168 -23.241)
		(end 106.677968 -23.0632)
		(width 0.14224)
		(layer "In11.Cu")
		(net "M_H_MA<13>")
	)
	(segment
		(start 106.500168 -27.195272)
		(end 106.500168 -23.241)
		(width 0.14224)
		(layer "In11.Cu")
		(net "M_H_MA<13>")
	)
	(segment
		(start 105.758996 -19.290792)
		(end 105.758996 -17.784572)
		(width 0.14224)
		(layer "In11.Cu")
		(net "M_H_MA<13>")
	)
	(segment
		(start 108.749846 -11.918188)
		(end 108.749846 -11.586718)
		(width 0.14224)
		(layer "In11.Cu")
		(net "M_H_MA<13>")
	)
	(segment
		(start 99.681792 -49.005744)
		(end 99.681792 -48.672496)
		(width 0.0889)
		(layer "In11.Cu")
		(net "M_H_MA<13>")
	)
	(segment
		(start 105.758996 -17.784572)
		(end 106.63428 -16.909288)
		(width 0.14224)
		(layer "In11.Cu")
		(net "M_H_MA<13>")
	)
	(segment
		(start 108.594906 -11.431778)
		(end 107.58805 -11.431778)
		(width 0.14224)
		(layer "In11.Cu")
		(net "M_H_MA<13>")
	)
	(segment
		(start 98.499168 -50.927)
		(end 99.388168 -50.038)
		(width 0.0889)
		(layer "In11.Cu")
		(net "M_H_MA<13>")
	)
	(segment
		(start 107.58805 -10.860024)
		(end 108.594906 -10.860024)
		(width 0.14224)
		(layer "In11.Cu")
		(net "M_H_MA<13>")
	)
	(segment
		(start 105.954068 -20.21967)
		(end 105.954068 -19.485864)
		(width 0.14224)
		(layer "In11.Cu")
		(net "M_H_MA<13>")
	)
	(segment
		(start 107.601004 -9.57326)
		(end 108.622846 -9.57326)
		(width 0.14224)
		(layer "In11.Cu")
		(net "M_H_MA<13>")
	)
	(segment
		(start 98.192082 -55.094886)
		(end 98.499168 -54.7878)
		(width 0.0889)
		(layer "In11.Cu")
		(net "M_H_MA<13>")
	)
	(segment
		(start 106.677968 -21.6916)
		(end 106.677968 -20.94357)
		(width 0.14224)
		(layer "In11.Cu")
		(net "M_H_MA<13>")
	)
	(segment
		(start 108.313982 -14.626082)
		(end 108.313982 -13.502386)
		(width 0.14224)
		(layer "In11.Cu")
		(net "M_H_MA<13>")
	)
	(segment
		(start 107.43311 -10.090658)
		(end 107.43311 -9.741154)
		(width 0.14224)
		(layer "In11.Cu")
		(net "M_H_MA<13>")
	)
	(segment
		(start 106.576368 -22.5552)
		(end 106.576368 -21.7932)
		(width 0.14224)
		(layer "In11.Cu")
		(net "M_H_MA<13>")
	)
	(segment
		(start 106.677968 -23.0632)
		(end 106.677968 -22.6568)
		(width 0.14224)
		(layer "In11.Cu")
		(net "M_H_MA<13>")
	)
	(segment
		(start 106.63428 -16.305784)
		(end 108.313982 -14.626082)
		(width 0.14224)
		(layer "In11.Cu")
		(net "M_H_MA<13>")
	)
	(segment
		(start 103.986584 -29.708856)
		(end 106.500168 -27.195272)
		(width 0.14224)
		(layer "In11.Cu")
		(net "M_H_MA<13>")
	)
	(segment
		(start 107.58805 -11.431778)
		(end 107.43311 -11.276838)
		(width 0.14224)
		(layer "In11.Cu")
		(net "M_H_MA<13>")
	)
	(segment
		(start 105.954068 -19.485864)
		(end 105.758996 -19.290792)
		(width 0.14224)
		(layer "In11.Cu")
		(net "M_H_MA<13>")
	)
	(segment
		(start 99.388168 -49.299368)
		(end 99.681792 -49.005744)
		(width 0.0889)
		(layer "In11.Cu")
		(net "M_H_MA<13>")
	)
	(segment
		(start 108.749338 -11.918696)
		(end 108.749846 -11.918188)
		(width 0.14224)
		(layer "In11.Cu")
		(net "M_H_MA<13>")
	)
	(segment
		(start 106.677968 -22.6568)
		(end 106.576368 -22.5552)
		(width 0.14224)
		(layer "In11.Cu")
		(net "M_H_MA<13>")
	)
	(segment
		(start 108.594906 -10.860024)
		(end 108.749846 -10.705084)
		(width 0.14224)
		(layer "In11.Cu")
		(net "M_H_MA<13>")
	)
	(segment
		(start 103.540052 -29.708856)
		(end 103.986584 -29.708856)
		(width 0.14224)
		(layer "In11.Cu")
		(net "M_H_MA<13>")
	)
	(segment
		(start 108.749846 -10.705084)
		(end 108.749846 -10.400538)
		(width 0.14224)
		(layer "In11.Cu")
		(net "M_H_MA<13>")
	)
	(segment
		(start 106.63428 -16.909288)
		(end 106.63428 -16.305784)
		(width 0.14224)
		(layer "In11.Cu")
		(net "M_H_MA<13>")
	)
	(segment
		(start 108.749846 -10.400538)
		(end 108.594906 -10.245598)
		(width 0.14224)
		(layer "In11.Cu")
		(net "M_H_MA<13>")
	)
	(segment
		(start 98.499168 -54.7878)
		(end 98.499168 -50.927)
		(width 0.0889)
		(layer "In11.Cu")
		(net "M_H_MA<13>")
	)
	(segment
		(start 99.388168 -50.038)
		(end 99.388168 -49.299368)
		(width 0.0889)
		(layer "In11.Cu")
		(net "M_H_MA<13>")
	)
	(segment
		(start 108.749338 -13.06703)
		(end 108.749338 -11.918696)
		(width 0.14224)
		(layer "In11.Cu")
		(net "M_H_MA<13>")
	)
	(segment
		(start 107.43311 -11.014964)
		(end 107.58805 -10.860024)
		(width 0.14224)
		(layer "In11.Cu")
		(net "M_H_MA<13>")
	)
	(segment
		(start 107.43311 -9.741154)
		(end 107.601004 -9.57326)
		(width 0.14224)
		(layer "In11.Cu")
		(net "M_H_MA<13>")
	)
	(segment
		(start 108.622846 -9.57326)
		(end 108.749846 -9.44626)
		(width 0.14224)
		(layer "In11.Cu")
		(net "M_H_MA<13>")
	)
	(segment
		(start 99.681792 -33.567116)
		(end 103.540052 -29.708856)
		(width 0.14224)
		(layer "In11.Cu")
		(net "M_H_MA<13>")
	)
	(segment
		(start 108.749846 -9.44626)
		(end 108.749846 -9.133078)
		(width 0.14224)
		(layer "In11.Cu")
		(net "M_H_MA<13>")
	)
	(segment
		(start 108.749846 -11.586718)
		(end 108.594906 -11.431778)
		(width 0.14224)
		(layer "In11.Cu")
		(net "M_H_MA<13>")
	)
	(segment
		(start 106.677968 -20.94357)
		(end 105.954068 -20.21967)
		(width 0.14224)
		(layer "In11.Cu")
		(net "M_H_MA<13>")
	)
	(segment
		(start 106.576368 -21.7932)
		(end 106.677968 -21.6916)
		(width 0.14224)
		(layer "In11.Cu")
		(net "M_H_MA<13>")
	)
	(segment
		(start 99.681792 -48.672496)
		(end 99.681792 -33.567116)
		(width 0.14224)
		(layer "In11.Cu")
		(net "M_H_MA<13>")
	)
	(segment
		(start 97.225358 -55.094886)
		(end 98.192082 -55.094886)
		(width 0.0889)
		(layer "In11.Cu")
		(net "M_H_MA<13>")
	)
	(segment
		(start 89.211912 -57.076086)
		(end 88.640412 -57.076086)
		(width 0.1016)
		(layer "F.Cu")
		(net "M_H_MA<12>")
	)
	(segment
		(start 84.0994 -7.115556)
		(end 84.0994 -5.822442)
		(width 0.1651)
		(layer "F.Cu")
		(net "M_H_MA<12>")
	)
	(via
		(at 84.0994 -13.933678)
		(size 0.4572)
		(drill 0.2032)
		(layers "F.Cu" "B.Cu")
		(net "M_H_MA<12>")
	)
	(via
		(at 84.0994 -7.115556)
		(size 0.4572)
		(drill 0.2032)
		(layers "F.Cu" "B.Cu")
		(net "M_H_MA<12>")
	)
	(via
		(at 88.640412 -57.076086)
		(size 0.508)
		(drill 0.254)
		(layers "F.Cu" "B.Cu")
		(net "M_H_MA<12>")
	)
	(segment
		(start 84.0994 -15.222982)
		(end 84.0994 -13.933678)
		(width 0.1651)
		(layer "B.Cu")
		(net "M_H_MA<12>")
	)
	(segment
		(start 87.084662 -17.688306)
		(end 87.042244 -17.730724)
		(width 0.14224)
		(layer "In11.Cu")
		(net "M_H_MA<12>")
	)
	(segment
		(start 83.657948 -13.32738)
		(end 84.0994 -13.768832)
		(width 0.14224)
		(layer "In11.Cu")
		(net "M_H_MA<12>")
	)
	(segment
		(start 87.042244 -17.730724)
		(end 87.042244 -18.438876)
		(width 0.14224)
		(layer "In11.Cu")
		(net "M_H_MA<12>")
	)
	(segment
		(start 83.409536 -8.67156)
		(end 83.657948 -8.919972)
		(width 0.14224)
		(layer "In11.Cu")
		(net "M_H_MA<12>")
	)
	(segment
		(start 87.084662 -18.481294)
		(end 87.084662 -18.983706)
		(width 0.14224)
		(layer "In11.Cu")
		(net "M_H_MA<12>")
	)
	(segment
		(start 89.185496 -56.234838)
		(end 88.640412 -57.076086)
		(width 0.0889)
		(layer "In11.Cu")
		(net "M_H_MA<12>")
	)
	(segment
		(start 89.36101 -54.975506)
		(end 89.445592 -55.006494)
		(width 0.0889)
		(layer "In11.Cu")
		(net "M_H_MA<12>")
	)
	(segment
		(start 89.455752 -51.04892)
		(end 89.355168 -51.149504)
		(width 0.0889)
		(layer "In11.Cu")
		(net "M_H_MA<12>")
	)
	(segment
		(start 87.510874 -30.507686)
		(end 89.455752 -32.452564)
		(width 0.14224)
		(layer "In11.Cu")
		(net "M_H_MA<12>")
	)
	(segment
		(start 87.04072 -22.583648)
		(end 87.04072 -23.136352)
		(width 0.14224)
		(layer "In11.Cu")
		(net "M_H_MA<12>")
	)
	(segment
		(start 89.355168 -51.149504)
		(end 89.355168 -52.651406)
		(width 0.0889)
		(layer "In11.Cu")
		(net "M_H_MA<12>")
	)
	(segment
		(start 84.692744 -15.555976)
		(end 86.252558 -15.555976)
		(width 0.14224)
		(layer "In11.Cu")
		(net "M_H_MA<12>")
	)
	(segment
		(start 89.152222 -53.809138)
		(end 89.161112 -53.824378)
		(width 0.0889)
		(layer "In11.Cu")
		(net "M_H_MA<12>")
	)
	(segment
		(start 89.832434 -55.36819)
		(end 89.845388 -55.390796)
		(width 0.0889)
		(layer "In11.Cu")
		(net "M_H_MA<12>")
	)
	(segment
		(start 86.252558 -15.555976)
		(end 87.084662 -16.38808)
		(width 0.14224)
		(layer "In11.Cu")
		(net "M_H_MA<12>")
	)
	(segment
		(start 87.084662 -18.983706)
		(end 86.916768 -19.1516)
		(width 0.14224)
		(layer "In11.Cu")
		(net "M_H_MA<12>")
	)
	(segment
		(start 84.0994 -13.933678)
		(end 84.0994 -14.962632)
		(width 0.14224)
		(layer "In11.Cu")
		(net "M_H_MA<12>")
	)
	(segment
		(start 87.04072 -23.136352)
		(end 87.10676 -23.202392)
		(width 0.14224)
		(layer "In11.Cu")
		(net "M_H_MA<12>")
	)
	(segment
		(start 84.0994 -13.768832)
		(end 84.0994 -13.933678)
		(width 0.14224)
		(layer "In11.Cu")
		(net "M_H_MA<12>")
	)
	(segment
		(start 87.510874 -26.273506)
		(end 87.510874 -30.507686)
		(width 0.14224)
		(layer "In11.Cu")
		(net "M_H_MA<12>")
	)
	(segment
		(start 89.455752 -50.749708)
		(end 89.455752 -51.04892)
		(width 0.0889)
		(layer "In11.Cu")
		(net "M_H_MA<12>")
	)
	(segment
		(start 84.0994 -7.115556)
		(end 83.409536 -7.80542)
		(width 0.14224)
		(layer "In11.Cu")
		(net "M_H_MA<12>")
	)
	(segment
		(start 89.455752 -32.452564)
		(end 89.455752 -50.749708)
		(width 0.14224)
		(layer "In11.Cu")
		(net "M_H_MA<12>")
	)
	(segment
		(start 89.643966 -55.963566)
		(end 89.185496 -56.234838)
		(width 0.0889)
		(layer "In11.Cu")
		(net "M_H_MA<12>")
	)
	(segment
		(start 87.10676 -23.202392)
		(end 87.10676 -25.869392)
		(width 0.14224)
		(layer "In11.Cu")
		(net "M_H_MA<12>")
	)
	(segment
		(start 86.916768 -19.1516)
		(end 86.916768 -21.7424)
		(width 0.14224)
		(layer "In11.Cu")
		(net "M_H_MA<12>")
	)
	(segment
		(start 87.042244 -18.438876)
		(end 87.084662 -18.481294)
		(width 0.14224)
		(layer "In11.Cu")
		(net "M_H_MA<12>")
	)
	(segment
		(start 84.0994 -14.962632)
		(end 84.692744 -15.555976)
		(width 0.14224)
		(layer "In11.Cu")
		(net "M_H_MA<12>")
	)
	(segment
		(start 83.409536 -7.80542)
		(end 83.409536 -8.67156)
		(width 0.14224)
		(layer "In11.Cu")
		(net "M_H_MA<12>")
	)
	(segment
		(start 86.916768 -21.7424)
		(end 87.10676 -21.932392)
		(width 0.14224)
		(layer "In11.Cu")
		(net "M_H_MA<12>")
	)
	(segment
		(start 87.10676 -25.869392)
		(end 87.510874 -26.273506)
		(width 0.14224)
		(layer "In11.Cu")
		(net "M_H_MA<12>")
	)
	(segment
		(start 83.657948 -8.919972)
		(end 83.657948 -13.32738)
		(width 0.14224)
		(layer "In11.Cu")
		(net "M_H_MA<12>")
	)
	(segment
		(start 87.10676 -21.932392)
		(end 87.10676 -22.517608)
		(width 0.14224)
		(layer "In11.Cu")
		(net "M_H_MA<12>")
	)
	(segment
		(start 87.084662 -16.38808)
		(end 87.084662 -17.688306)
		(width 0.14224)
		(layer "In11.Cu")
		(net "M_H_MA<12>")
	)
	(segment
		(start 87.10676 -22.517608)
		(end 87.04072 -22.583648)
		(width 0.14224)
		(layer "In11.Cu")
		(net "M_H_MA<12>")
	)
	(arc
		(start 89.355168 -52.651406)
		(mid 89.303541 -53.043717)
		(end 89.152222 -53.409342)
		(width 0.0889)
		(layer "In11.Cu")
		(net "M_H_MA<12>")
	)
	(arc
		(start 89.161112 -53.824378)
		(mid 89.231509 -54.113329)
		(end 89.152222 -54.399942)
		(width 0.0889)
		(layer "In11.Cu")
		(net "M_H_MA<12>")
	)
	(arc
		(start 89.445592 -55.006494)
		(mid 89.560239 -55.063267)
		(end 89.659968 -55.1434)
		(width 0.0889)
		(layer "In11.Cu")
		(net "M_H_MA<12>")
	)
	(arc
		(start 89.845388 -55.390796)
		(mid 89.876227 -55.72345)
		(end 89.643966 -55.963566)
		(width 0.0889)
		(layer "In11.Cu")
		(net "M_H_MA<12>")
	)
	(arc
		(start 89.152222 -54.399942)
		(mid 89.12268 -54.736283)
		(end 89.36101 -54.975506)
		(width 0.0889)
		(layer "In11.Cu")
		(net "M_H_MA<12>")
	)
	(arc
		(start 89.659968 -55.1434)
		(mid 89.753576 -55.250136)
		(end 89.832434 -55.36819)
		(width 0.0889)
		(layer "In11.Cu")
		(net "M_H_MA<12>")
	)
	(arc
		(start 89.152222 -53.409342)
		(mid 89.098689 -53.60924)
		(end 89.152222 -53.809138)
		(width 0.0889)
		(layer "In11.Cu")
		(net "M_H_MA<12>")
	)
	(segment
		(start 84.949538 -10.422382)
		(end 84.949538 -9.133078)
		(width 0.1651)
		(layer "F.Cu")
		(net "M_H_MA<11>")
	)
	(segment
		(start 90.070178 -56.58104)
		(end 89.498678 -56.58104)
		(width 0.1016)
		(layer "F.Cu")
		(net "M_H_MA<11>")
	)
	(via
		(at 84.949284 -11.916156)
		(size 0.4572)
		(drill 0.2032)
		(layers "F.Cu" "B.Cu")
		(net "M_H_MA<11>")
	)
	(via
		(at 84.949538 -9.133078)
		(size 0.4572)
		(drill 0.2032)
		(layers "F.Cu" "B.Cu")
		(net "M_H_MA<11>")
	)
	(via
		(at 89.498678 -56.58104)
		(size 0.508)
		(drill 0.254)
		(layers "F.Cu" "B.Cu")
		(net "M_H_MA<11>")
	)
	(segment
		(start 84.949538 -10.623042)
		(end 84.949538 -11.915902)
		(width 0.1651)
		(layer "B.Cu")
		(net "M_H_MA<11>")
	)
	(segment
		(start 84.949538 -11.915902)
		(end 84.949284 -11.916156)
		(width 0.1651)
		(layer "B.Cu")
		(net "M_H_MA<11>")
	)
	(segment
		(start 84.949284 -11.916156)
		(end 84.651596 -11.618468)
		(width 0.14224)
		(layer "In11.Cu")
		(net "M_H_MA<11>")
	)
	(segment
		(start 86.688168 -15.0622)
		(end 84.986368 -15.0622)
		(width 0.14224)
		(layer "In11.Cu")
		(net "M_H_MA<11>")
	)
	(segment
		(start 88.008968 -18.3134)
		(end 88.008968 -17.8054)
		(width 0.14224)
		(layer "In11.Cu")
		(net "M_H_MA<11>")
	)
	(segment
		(start 87.892382 -21.782786)
		(end 87.958168 -21.717)
		(width 0.14224)
		(layer "In11.Cu")
		(net "M_H_MA<11>")
	)
	(segment
		(start 88.018874 -23.876)
		(end 87.881968 -23.739094)
		(width 0.14224)
		(layer "In11.Cu")
		(net "M_H_MA<11>")
	)
	(segment
		(start 87.881968 -23.739094)
		(end 87.881968 -23.2156)
		(width 0.14224)
		(layer "In11.Cu")
		(net "M_H_MA<11>")
	)
	(segment
		(start 87.892382 -22.514814)
		(end 87.892382 -21.782786)
		(width 0.14224)
		(layer "In11.Cu")
		(net "M_H_MA<11>")
	)
	(segment
		(start 84.651596 -11.618468)
		(end 84.651596 -10.088372)
		(width 0.14224)
		(layer "In11.Cu")
		(net "M_H_MA<11>")
	)
	(segment
		(start 88.008968 -17.8054)
		(end 87.910924 -17.707356)
		(width 0.14224)
		(layer "In11.Cu")
		(net "M_H_MA<11>")
	)
	(segment
		(start 84.986368 -15.0622)
		(end 84.516468 -14.5923)
		(width 0.14224)
		(layer "In11.Cu")
		(net "M_H_MA<11>")
	)
	(segment
		(start 84.516468 -13.2842)
		(end 84.26323 -13.030962)
		(width 0.14224)
		(layer "In11.Cu")
		(net "M_H_MA<11>")
	)
	(segment
		(start 87.958168 -21.336)
		(end 87.932768 -21.3106)
		(width 0.14224)
		(layer "In11.Cu")
		(net "M_H_MA<11>")
	)
	(segment
		(start 88.018874 -30.296866)
		(end 88.018874 -23.876)
		(width 0.14224)
		(layer "In11.Cu")
		(net "M_H_MA<11>")
	)
	(segment
		(start 87.932768 -21.3106)
		(end 87.932768 -18.3896)
		(width 0.14224)
		(layer "In11.Cu")
		(net "M_H_MA<11>")
	)
	(segment
		(start 89.939368 -54.493668)
		(end 89.845388 -54.399688)
		(width 0.0889)
		(layer "In11.Cu")
		(net "M_H_MA<11>")
	)
	(segment
		(start 89.993978 -55.914798)
		(end 90.010488 -55.886096)
		(width 0.0889)
		(layer "In11.Cu")
		(net "M_H_MA<11>")
	)
	(segment
		(start 89.963752 -32.241744)
		(end 88.018874 -30.296866)
		(width 0.14224)
		(layer "In11.Cu")
		(net "M_H_MA<11>")
	)
	(segment
		(start 87.958168 -21.717)
		(end 87.958168 -21.336)
		(width 0.14224)
		(layer "In11.Cu")
		(net "M_H_MA<11>")
	)
	(segment
		(start 84.949538 -9.79043)
		(end 84.949538 -9.133078)
		(width 0.14224)
		(layer "In11.Cu")
		(net "M_H_MA<11>")
	)
	(segment
		(start 84.651596 -10.088372)
		(end 84.949538 -9.79043)
		(width 0.14224)
		(layer "In11.Cu")
		(net "M_H_MA<11>")
	)
	(segment
		(start 89.963752 -51.126644)
		(end 89.963752 -50.842164)
		(width 0.0889)
		(layer "In11.Cu")
		(net "M_H_MA<11>")
	)
	(segment
		(start 89.839038 -53.819806)
		(end 89.845388 -53.809138)
		(width 0.0889)
		(layer "In11.Cu")
		(net "M_H_MA<11>")
	)
	(segment
		(start 89.939368 -55.029862)
		(end 89.939368 -54.493668)
		(width 0.0889)
		(layer "In11.Cu")
		(net "M_H_MA<11>")
	)
	(segment
		(start 89.498678 -56.58104)
		(end 89.993978 -55.914798)
		(width 0.0889)
		(layer "In11.Cu")
		(net "M_H_MA<11>")
	)
	(segment
		(start 89.845388 -53.809138)
		(end 89.850214 -53.800502)
		(width 0.0889)
		(layer "In11.Cu")
		(net "M_H_MA<11>")
	)
	(segment
		(start 84.26323 -12.60221)
		(end 84.949284 -11.916156)
		(width 0.14224)
		(layer "In11.Cu")
		(net "M_H_MA<11>")
	)
	(segment
		(start 87.958168 -22.5806)
		(end 87.892382 -22.514814)
		(width 0.14224)
		(layer "In11.Cu")
		(net "M_H_MA<11>")
	)
	(segment
		(start 87.932768 -18.3896)
		(end 88.008968 -18.3134)
		(width 0.14224)
		(layer "In11.Cu")
		(net "M_H_MA<11>")
	)
	(segment
		(start 89.963752 -50.842164)
		(end 89.963752 -32.241744)
		(width 0.14224)
		(layer "In11.Cu")
		(net "M_H_MA<11>")
	)
	(segment
		(start 84.516468 -14.5923)
		(end 84.516468 -13.2842)
		(width 0.14224)
		(layer "In11.Cu")
		(net "M_H_MA<11>")
	)
	(segment
		(start 87.910924 -17.707356)
		(end 87.910924 -16.284956)
		(width 0.14224)
		(layer "In11.Cu")
		(net "M_H_MA<11>")
	)
	(segment
		(start 89.685368 -52.8574)
		(end 89.685368 -51.405028)
		(width 0.0889)
		(layer "In11.Cu")
		(net "M_H_MA<11>")
	)
	(segment
		(start 89.845388 -53.409088)
		(end 89.822274 -53.368956)
		(width 0.0889)
		(layer "In11.Cu")
		(net "M_H_MA<11>")
	)
	(segment
		(start 87.910924 -16.284956)
		(end 86.688168 -15.0622)
		(width 0.14224)
		(layer "In11.Cu")
		(net "M_H_MA<11>")
	)
	(segment
		(start 87.881968 -23.2156)
		(end 87.958168 -23.1394)
		(width 0.14224)
		(layer "In11.Cu")
		(net "M_H_MA<11>")
	)
	(segment
		(start 84.26323 -13.030962)
		(end 84.26323 -12.60221)
		(width 0.14224)
		(layer "In11.Cu")
		(net "M_H_MA<11>")
	)
	(segment
		(start 89.685368 -51.405028)
		(end 89.963752 -51.126644)
		(width 0.0889)
		(layer "In11.Cu")
		(net "M_H_MA<11>")
	)
	(segment
		(start 87.958168 -23.1394)
		(end 87.958168 -22.5806)
		(width 0.14224)
		(layer "In11.Cu")
		(net "M_H_MA<11>")
	)
	(arc
		(start 90.010488 -55.886096)
		(mid 90.089619 -55.590694)
		(end 90.010488 -55.295292)
		(width 0.0889)
		(layer "In11.Cu")
		(net "M_H_MA<11>")
	)
	(arc
		(start 90.010488 -55.295292)
		(mid 89.95748 -55.167254)
		(end 89.939368 -55.029862)
		(width 0.0889)
		(layer "In11.Cu")
		(net "M_H_MA<11>")
	)
	(arc
		(start 89.822274 -53.368956)
		(mid 89.720206 -53.122176)
		(end 89.685368 -52.8574)
		(width 0.0889)
		(layer "In11.Cu")
		(net "M_H_MA<11>")
	)
	(arc
		(start 89.850214 -53.800502)
		(mid 89.898969 -53.60415)
		(end 89.845388 -53.409088)
		(width 0.0889)
		(layer "In11.Cu")
		(net "M_H_MA<11>")
	)
	(arc
		(start 89.845388 -54.399688)
		(mid 89.766166 -54.11057)
		(end 89.839038 -53.819806)
		(width 0.0889)
		(layer "In11.Cu")
		(net "M_H_MA<11>")
	)
	(segment
		(start 102.799388 -10.422382)
		(end 102.799388 -9.158732)
		(width 0.1651)
		(layer "F.Cu")
		(net "M_H_MA<10>")
	)
	(segment
		(start 102.799388 -9.158732)
		(end 102.799642 -9.158478)
		(width 0.1651)
		(layer "F.Cu")
		(net "M_H_MA<10>")
	)
	(segment
		(start 102.799642 -9.158478)
		(end 102.799642 -9.133078)
		(width 0.1651)
		(layer "F.Cu")
		(net "M_H_MA<10>")
	)
	(segment
		(start 94.362778 -55.094886)
		(end 93.791278 -55.094886)
		(width 0.1016)
		(layer "F.Cu")
		(net "M_H_MA<10>")
	)
	(via
		(at 102.799642 -11.918188)
		(size 0.4572)
		(drill 0.2032)
		(layers "F.Cu" "B.Cu")
		(net "M_H_MA<10>")
	)
	(via
		(at 102.799642 -9.133078)
		(size 0.4572)
		(drill 0.2032)
		(layers "F.Cu" "B.Cu")
		(net "M_H_MA<10>")
	)
	(via
		(at 93.791278 -55.094886)
		(size 0.508)
		(drill 0.254)
		(layers "F.Cu" "B.Cu")
		(net "M_H_MA<10>")
	)
	(segment
		(start 102.799388 -11.917934)
		(end 102.799642 -11.918188)
		(width 0.1651)
		(layer "B.Cu")
		(net "M_H_MA<10>")
	)
	(segment
		(start 102.799388 -10.623042)
		(end 102.799388 -11.917934)
		(width 0.1651)
		(layer "B.Cu")
		(net "M_H_MA<10>")
	)
	(segment
		(start 101.513894 -14.884908)
		(end 101.513894 -13.698474)
		(width 0.14224)
		(layer "In11.Cu")
		(net "M_H_MA<10>")
	)
	(segment
		(start 101.953568 -13.2588)
		(end 102.080568 -13.2588)
		(width 0.14224)
		(layer "In11.Cu")
		(net "M_H_MA<10>")
	)
	(segment
		(start 94.238318 -54.17312)
		(end 94.238318 -51.582574)
		(width 0.0889)
		(layer "In11.Cu")
		(net "M_H_MA<10>")
	)
	(segment
		(start 99.472496 -19.967448)
		(end 99.722432 -19.717512)
		(width 0.14224)
		(layer "In11.Cu")
		(net "M_H_MA<10>")
	)
	(segment
		(start 102.799642 -11.52779)
		(end 103.375968 -10.951464)
		(width 0.14224)
		(layer "In11.Cu")
		(net "M_H_MA<10>")
	)
	(segment
		(start 95.533972 -50.02022)
		(end 95.533972 -30.720792)
		(width 0.14224)
		(layer "In11.Cu")
		(net "M_H_MA<10>")
	)
	(segment
		(start 95.533972 -50.28692)
		(end 95.533972 -50.02022)
		(width 0.0889)
		(layer "In11.Cu")
		(net "M_H_MA<10>")
	)
	(segment
		(start 98.6282 -20.0914)
		(end 98.893376 -19.826224)
		(width 0.14224)
		(layer "In11.Cu")
		(net "M_H_MA<10>")
	)
	(segment
		(start 99.769168 -18.950432)
		(end 99.769168 -16.629634)
		(width 0.14224)
		(layer "In11.Cu")
		(net "M_H_MA<10>")
	)
	(segment
		(start 99.722432 -19.717512)
		(end 99.722432 -19.498564)
		(width 0.14224)
		(layer "In11.Cu")
		(net "M_H_MA<10>")
	)
	(segment
		(start 93.791278 -55.094886)
		(end 94.238318 -54.17312)
		(width 0.0889)
		(layer "In11.Cu")
		(net "M_H_MA<10>")
	)
	(segment
		(start 99.581208 -19.138392)
		(end 99.769168 -18.950432)
		(width 0.14224)
		(layer "In11.Cu")
		(net "M_H_MA<10>")
	)
	(segment
		(start 98.893376 -19.826224)
		(end 99.112324 -19.826224)
		(width 0.14224)
		(layer "In11.Cu")
		(net "M_H_MA<10>")
	)
	(segment
		(start 99.112324 -19.826224)
		(end 99.253548 -19.967448)
		(width 0.14224)
		(layer "In11.Cu")
		(net "M_H_MA<10>")
	)
	(segment
		(start 102.080568 -13.2588)
		(end 102.799388 -12.53998)
		(width 0.14224)
		(layer "In11.Cu")
		(net "M_H_MA<10>")
	)
	(segment
		(start 99.722432 -19.498564)
		(end 99.581208 -19.35734)
		(width 0.14224)
		(layer "In11.Cu")
		(net "M_H_MA<10>")
	)
	(segment
		(start 102.799388 -11.918442)
		(end 102.799642 -11.918188)
		(width 0.14224)
		(layer "In11.Cu")
		(net "M_H_MA<10>")
	)
	(segment
		(start 97.203768 -20.541488)
		(end 97.653856 -20.0914)
		(width 0.14224)
		(layer "In11.Cu")
		(net "M_H_MA<10>")
	)
	(segment
		(start 94.238318 -51.582574)
		(end 95.533972 -50.28692)
		(width 0.0889)
		(layer "In11.Cu")
		(net "M_H_MA<10>")
	)
	(segment
		(start 101.513894 -13.698474)
		(end 101.953568 -13.2588)
		(width 0.14224)
		(layer "In11.Cu")
		(net "M_H_MA<10>")
	)
	(segment
		(start 97.203768 -29.050996)
		(end 97.203768 -20.541488)
		(width 0.14224)
		(layer "In11.Cu")
		(net "M_H_MA<10>")
	)
	(segment
		(start 103.375968 -10.951464)
		(end 103.375968 -9.709404)
		(width 0.14224)
		(layer "In11.Cu")
		(net "M_H_MA<10>")
	)
	(segment
		(start 103.375968 -9.709404)
		(end 102.799642 -9.133078)
		(width 0.14224)
		(layer "In11.Cu")
		(net "M_H_MA<10>")
	)
	(segment
		(start 102.799388 -12.53998)
		(end 102.799388 -11.918442)
		(width 0.14224)
		(layer "In11.Cu")
		(net "M_H_MA<10>")
	)
	(segment
		(start 97.653856 -20.0914)
		(end 98.6282 -20.0914)
		(width 0.14224)
		(layer "In11.Cu")
		(net "M_H_MA<10>")
	)
	(segment
		(start 95.533972 -30.720792)
		(end 97.203768 -29.050996)
		(width 0.14224)
		(layer "In11.Cu")
		(net "M_H_MA<10>")
	)
	(segment
		(start 99.769168 -16.629634)
		(end 101.513894 -14.884908)
		(width 0.14224)
		(layer "In11.Cu")
		(net "M_H_MA<10>")
	)
	(segment
		(start 99.253548 -19.967448)
		(end 99.472496 -19.967448)
		(width 0.14224)
		(layer "In11.Cu")
		(net "M_H_MA<10>")
	)
	(segment
		(start 99.581208 -19.35734)
		(end 99.581208 -19.138392)
		(width 0.14224)
		(layer "In11.Cu")
		(net "M_H_MA<10>")
	)
	(segment
		(start 102.799642 -11.918188)
		(end 102.799642 -11.52779)
		(width 0.14224)
		(layer "In11.Cu")
		(net "M_H_MA<10>")
	)
	(segment
		(start 96.619568 -52.871116)
		(end 96.366838 -52.618386)
		(width 0.0889)
		(layer "F.Cu")
		(net "M_H_MA<0>")
	)
	(segment
		(start 96.938338 -53.60924)
		(end 96.619568 -53.29047)
		(width 0.0889)
		(layer "F.Cu")
		(net "M_H_MA<0>")
	)
	(segment
		(start 101.099366 -7.113778)
		(end 101.099366 -5.822442)
		(width 0.1651)
		(layer "F.Cu")
		(net "M_H_MA<0>")
	)
	(segment
		(start 96.619568 -53.29047)
		(end 96.619568 -52.871116)
		(width 0.0889)
		(layer "F.Cu")
		(net "M_H_MA<0>")
	)
	(via
		(at 101.099366 -7.113778)
		(size 0.508)
		(drill 0.254)
		(layers "F.Cu" "B.Cu")
		(net "M_H_MA<0>")
	)
	(via
		(at 96.366838 -52.618386)
		(size 0.508)
		(drill 0.254)
		(layers "F.Cu" "B.Cu")
		(net "M_H_MA<0>")
	)
	(via
		(at 101.099366 -13.929868)
		(size 0.4572)
		(drill 0.2032)
		(layers "F.Cu" "B.Cu")
		(net "M_H_MA<0>")
	)
	(segment
		(start 101.099366 -15.222982)
		(end 101.099366 -13.929868)
		(width 0.1651)
		(layer "B.Cu")
		(net "M_H_MA<0>")
	)
	(segment
		(start 100.742242 -22.029674)
		(end 100.570538 -21.85797)
		(width 0.14224)
		(layer "In4.Cu")
		(net "M_H_MA<0>")
	)
	(segment
		(start 96.366838 -51.37785)
		(end 97.570544 -50.174144)
		(width 0.0889)
		(layer "In4.Cu")
		(net "M_H_MA<0>")
	)
	(segment
		(start 97.570544 -27.755088)
		(end 98.45802 -26.867612)
		(width 0.14224)
		(layer "In4.Cu")
		(net "M_H_MA<0>")
	)
	(segment
		(start 101.537008 -8.117586)
		(end 101.099366 -7.679944)
		(width 0.14224)
		(layer "In4.Cu")
		(net "M_H_MA<0>")
	)
	(segment
		(start 99.487736 -24.514556)
		(end 99.787964 -24.514556)
		(width 0.14224)
		(layer "In4.Cu")
		(net "M_H_MA<0>")
	)
	(segment
		(start 101.300026 -13.450316)
		(end 101.099366 -13.249656)
		(width 0.14224)
		(layer "In4.Cu")
		(net "M_H_MA<0>")
	)
	(segment
		(start 100.961698 -17.277842)
		(end 100.607368 -16.923512)
		(width 0.14224)
		(layer "In4.Cu")
		(net "M_H_MA<0>")
	)
	(segment
		(start 100.43668 -15.754858)
		(end 99.718368 -15.754858)
		(width 0.14224)
		(layer "In4.Cu")
		(net "M_H_MA<0>")
	)
	(segment
		(start 100.961698 -18.016728)
		(end 100.961698 -17.277842)
		(width 0.14224)
		(layer "In4.Cu")
		(net "M_H_MA<0>")
	)
	(segment
		(start 101.099366 -12.585954)
		(end 101.537008 -12.148312)
		(width 0.14224)
		(layer "In4.Cu")
		(net "M_H_MA<0>")
	)
	(segment
		(start 100.28936 -24.777446)
		(end 100.454968 -24.611838)
		(width 0.14224)
		(layer "In4.Cu")
		(net "M_H_MA<0>")
	)
	(segment
		(start 100.742242 -22.394672)
		(end 100.742242 -22.029674)
		(width 0.14224)
		(layer "In4.Cu")
		(net "M_H_MA<0>")
	)
	(segment
		(start 100.607368 -16.923512)
		(end 100.607368 -15.925546)
		(width 0.14224)
		(layer "In4.Cu")
		(net "M_H_MA<0>")
	)
	(segment
		(start 100.427536 -18.55089)
		(end 100.961698 -18.016728)
		(width 0.14224)
		(layer "In4.Cu")
		(net "M_H_MA<0>")
	)
	(segment
		(start 98.45802 -26.633424)
		(end 98.029776 -26.20518)
		(width 0.14224)
		(layer "In4.Cu")
		(net "M_H_MA<0>")
	)
	(segment
		(start 99.787964 -24.514556)
		(end 100.050854 -24.777446)
		(width 0.14224)
		(layer "In4.Cu")
		(net "M_H_MA<0>")
	)
	(segment
		(start 101.537008 -12.148312)
		(end 101.537008 -8.117586)
		(width 0.14224)
		(layer "In4.Cu")
		(net "M_H_MA<0>")
	)
	(segment
		(start 100.570538 -21.85797)
		(end 100.570538 -21.37029)
		(width 0.14224)
		(layer "In4.Cu")
		(net "M_H_MA<0>")
	)
	(segment
		(start 99.515168 -15.551658)
		(end 99.515168 -15.145258)
		(width 0.14224)
		(layer "In4.Cu")
		(net "M_H_MA<0>")
	)
	(segment
		(start 99.213162 -24.78913)
		(end 99.487736 -24.514556)
		(width 0.14224)
		(layer "In4.Cu")
		(net "M_H_MA<0>")
	)
	(segment
		(start 101.300026 -13.729208)
		(end 101.300026 -13.450316)
		(width 0.14224)
		(layer "In4.Cu")
		(net "M_H_MA<0>")
	)
	(segment
		(start 100.454968 -22.681946)
		(end 100.742242 -22.394672)
		(width 0.14224)
		(layer "In4.Cu")
		(net "M_H_MA<0>")
	)
	(segment
		(start 98.681032 -25.706832)
		(end 98.951542 -25.977342)
		(width 0.14224)
		(layer "In4.Cu")
		(net "M_H_MA<0>")
	)
	(segment
		(start 97.570544 -50.174144)
		(end 97.570544 -49.732692)
		(width 0.0889)
		(layer "In4.Cu")
		(net "M_H_MA<0>")
	)
	(segment
		(start 98.029776 -26.20518)
		(end 98.029776 -25.994106)
		(width 0.14224)
		(layer "In4.Cu")
		(net "M_H_MA<0>")
	)
	(segment
		(start 98.951542 -25.977342)
		(end 99.23907 -25.977342)
		(width 0.14224)
		(layer "In4.Cu")
		(net "M_H_MA<0>")
	)
	(segment
		(start 101.099366 -7.679944)
		(end 101.099366 -7.113778)
		(width 0.14224)
		(layer "In4.Cu")
		(net "M_H_MA<0>")
	)
	(segment
		(start 98.31705 -25.706832)
		(end 98.681032 -25.706832)
		(width 0.14224)
		(layer "In4.Cu")
		(net "M_H_MA<0>")
	)
	(segment
		(start 99.526344 -25.690068)
		(end 99.526344 -25.40254)
		(width 0.14224)
		(layer "In4.Cu")
		(net "M_H_MA<0>")
	)
	(segment
		(start 99.718368 -15.754858)
		(end 99.515168 -15.551658)
		(width 0.14224)
		(layer "In4.Cu")
		(net "M_H_MA<0>")
	)
	(segment
		(start 101.099366 -13.249656)
		(end 101.099366 -12.585954)
		(width 0.14224)
		(layer "In4.Cu")
		(net "M_H_MA<0>")
	)
	(segment
		(start 100.607368 -15.925546)
		(end 100.43668 -15.754858)
		(width 0.14224)
		(layer "In4.Cu")
		(net "M_H_MA<0>")
	)
	(segment
		(start 98.45802 -26.867612)
		(end 98.45802 -26.633424)
		(width 0.14224)
		(layer "In4.Cu")
		(net "M_H_MA<0>")
	)
	(segment
		(start 99.515168 -15.145258)
		(end 99.718368 -14.942058)
		(width 0.14224)
		(layer "In4.Cu")
		(net "M_H_MA<0>")
	)
	(segment
		(start 100.454968 -24.611838)
		(end 100.454968 -22.681946)
		(width 0.14224)
		(layer "In4.Cu")
		(net "M_H_MA<0>")
	)
	(segment
		(start 99.23907 -25.977342)
		(end 99.526344 -25.690068)
		(width 0.14224)
		(layer "In4.Cu")
		(net "M_H_MA<0>")
	)
	(segment
		(start 98.029776 -25.994106)
		(end 98.31705 -25.706832)
		(width 0.14224)
		(layer "In4.Cu")
		(net "M_H_MA<0>")
	)
	(segment
		(start 100.570538 -21.37029)
		(end 100.822252 -21.118576)
		(width 0.14224)
		(layer "In4.Cu")
		(net "M_H_MA<0>")
	)
	(segment
		(start 100.427536 -19.355308)
		(end 100.427536 -18.55089)
		(width 0.14224)
		(layer "In4.Cu")
		(net "M_H_MA<0>")
	)
	(segment
		(start 100.829872 -14.942058)
		(end 101.099366 -14.672564)
		(width 0.14224)
		(layer "In4.Cu")
		(net "M_H_MA<0>")
	)
	(segment
		(start 101.099366 -13.929868)
		(end 101.300026 -13.729208)
		(width 0.14224)
		(layer "In4.Cu")
		(net "M_H_MA<0>")
	)
	(segment
		(start 100.050854 -24.777446)
		(end 100.28936 -24.777446)
		(width 0.14224)
		(layer "In4.Cu")
		(net "M_H_MA<0>")
	)
	(segment
		(start 100.822252 -21.118576)
		(end 100.822252 -19.750024)
		(width 0.14224)
		(layer "In4.Cu")
		(net "M_H_MA<0>")
	)
	(segment
		(start 99.526344 -25.40254)
		(end 99.213162 -25.089358)
		(width 0.14224)
		(layer "In4.Cu")
		(net "M_H_MA<0>")
	)
	(segment
		(start 96.366838 -52.618386)
		(end 96.366838 -51.37785)
		(width 0.0889)
		(layer "In4.Cu")
		(net "M_H_MA<0>")
	)
	(segment
		(start 99.718368 -14.942058)
		(end 100.829872 -14.942058)
		(width 0.14224)
		(layer "In4.Cu")
		(net "M_H_MA<0>")
	)
	(segment
		(start 100.822252 -19.750024)
		(end 100.427536 -19.355308)
		(width 0.14224)
		(layer "In4.Cu")
		(net "M_H_MA<0>")
	)
	(segment
		(start 99.213162 -25.089358)
		(end 99.213162 -24.78913)
		(width 0.14224)
		(layer "In4.Cu")
		(net "M_H_MA<0>")
	)
	(segment
		(start 97.570544 -49.732692)
		(end 97.570544 -27.755088)
		(width 0.14224)
		(layer "In4.Cu")
		(net "M_H_MA<0>")
	)
	(segment
		(start 101.099366 -14.672564)
		(end 101.099366 -13.929868)
		(width 0.14224)
		(layer "In4.Cu")
		(net "M_H_MA<0>")
	)
	(segment
		(start 84.654644 -50.99812)
		(end 84.462366 -50.5333)
		(width 0.0889)
		(layer "F.Cu")
		(net "M_H_ECC<7>")
	)
	(segment
		(start 77.7367 -30.418532)
		(end 77.50302 -30.418532)
		(width 0.1651)
		(layer "F.Cu")
		(net "M_H_ECC<7>")
	)
	(segment
		(start 79.6671 -42.822114)
		(end 79.45374 -42.822114)
		(width 0.1016)
		(layer "F.Cu")
		(net "M_H_ECC<7>")
	)
	(segment
		(start 84.540598 -51.458114)
		(end 84.654644 -51.260502)
		(width 0.0889)
		(layer "F.Cu")
		(net "M_H_ECC<7>")
	)
	(segment
		(start 84.390738 -54.33314)
		(end 84.407502 -54.304438)
		(width 0.0889)
		(layer "F.Cu")
		(net "M_H_ECC<7>")
	)
	(segment
		(start 76.784454 -29.974286)
		(end 76.519278 -29.70911)
		(width 0.1651)
		(layer "F.Cu")
		(net "M_H_ECC<7>")
	)
	(segment
		(start 77.65542 -41.653968)
		(end 77.560932 -41.55948)
		(width 0.1016)
		(layer "F.Cu")
		(net "M_H_ECC<7>")
	)
	(segment
		(start 77.979016 -30.894528)
		(end 77.979016 -30.660848)
		(width 0.1651)
		(layer "F.Cu")
		(net "M_H_ECC<7>")
	)
	(segment
		(start 84.63153 -52.360576)
		(end 84.63153 -51.902614)
		(width 0.0889)
		(layer "F.Cu")
		(net "M_H_ECC<7>")
	)
	(segment
		(start 84.654644 -51.260502)
		(end 84.654644 -50.99812)
		(width 0.0889)
		(layer "F.Cu")
		(net "M_H_ECC<7>")
	)
	(segment
		(start 76.784454 -30.418786)
		(end 76.784454 -29.974286)
		(width 0.1651)
		(layer "F.Cu")
		(net "M_H_ECC<7>")
	)
	(segment
		(start 79.436468 -36.8681)
		(end 79.436468 -34.3281)
		(width 0.1651)
		(layer "F.Cu")
		(net "M_H_ECC<7>")
	)
	(segment
		(start 78.166468 -31.8008)
		(end 77.736446 -31.370778)
		(width 0.1651)
		(layer "F.Cu")
		(net "M_H_ECC<7>")
	)
	(segment
		(start 75.588368 -29.2227)
		(end 75.588368 -28.0924)
		(width 0.1651)
		(layer "F.Cu")
		(net "M_H_ECC<7>")
	)
	(segment
		(start 84.060792 -55.094886)
		(end 84.390738 -54.33314)
		(width 0.0889)
		(layer "F.Cu")
		(net "M_H_ECC<7>")
	)
	(segment
		(start 77.50302 -30.418532)
		(end 77.26045 -30.661102)
		(width 0.1651)
		(layer "F.Cu")
		(net "M_H_ECC<7>")
	)
	(segment
		(start 77.560932 -41.55948)
		(end 77.366368 -41.364916)
		(width 0.1651)
		(layer "F.Cu")
		(net "M_H_ECC<7>")
	)
	(segment
		(start 74.795888 -26.811732)
		(end 74.916284 -26.691336)
		(width 0.1651)
		(layer "F.Cu")
		(net "M_H_ECC<7>")
	)
	(segment
		(start 78.166468 -33.0581)
		(end 78.166468 -31.8008)
		(width 0.1651)
		(layer "F.Cu")
		(net "M_H_ECC<7>")
	)
	(segment
		(start 74.749406 -5.822442)
		(end 74.749406 -7.086346)
		(width 0.1651)
		(layer "F.Cu")
		(net "M_H_ECC<7>")
	)
	(segment
		(start 84.519008 -52.554378)
		(end 84.63153 -52.360576)
		(width 0.0889)
		(layer "F.Cu")
		(net "M_H_ECC<7>")
	)
	(segment
		(start 77.26045 -30.661102)
		(end 77.02677 -30.661102)
		(width 0.1651)
		(layer "F.Cu")
		(net "M_H_ECC<7>")
	)
	(segment
		(start 78.285594 -41.653968)
		(end 77.65542 -41.653968)
		(width 0.1016)
		(layer "F.Cu")
		(net "M_H_ECC<7>")
	)
	(segment
		(start 74.916284 -26.691336)
		(end 75.59929 -26.691336)
		(width 0.1651)
		(layer "F.Cu")
		(net "M_H_ECC<7>")
	)
	(segment
		(start 84.407502 -53.701696)
		(end 84.572602 -53.409088)
		(width 0.0889)
		(layer "F.Cu")
		(net "M_H_ECC<7>")
	)
	(segment
		(start 77.366368 -41.364916)
		(end 77.366368 -38.0238)
		(width 0.1651)
		(layer "F.Cu")
		(net "M_H_ECC<7>")
	)
	(segment
		(start 76.074778 -29.70911)
		(end 75.588368 -29.2227)
		(width 0.1651)
		(layer "F.Cu")
		(net "M_H_ECC<7>")
	)
	(segment
		(start 77.366368 -38.0238)
		(end 77.975968 -37.4142)
		(width 0.1651)
		(layer "F.Cu")
		(net "M_H_ECC<7>")
	)
	(segment
		(start 84.407502 -53.904388)
		(end 84.407502 -53.701696)
		(width 0.0889)
		(layer "F.Cu")
		(net "M_H_ECC<7>")
	)
	(segment
		(start 77.736446 -31.137098)
		(end 77.979016 -30.894528)
		(width 0.1651)
		(layer "F.Cu")
		(net "M_H_ECC<7>")
	)
	(segment
		(start 84.462366 -47.61738)
		(end 79.6671 -42.822114)
		(width 0.1016)
		(layer "F.Cu")
		(net "M_H_ECC<7>")
	)
	(segment
		(start 84.63153 -51.902614)
		(end 84.540598 -51.745134)
		(width 0.0889)
		(layer "F.Cu")
		(net "M_H_ECC<7>")
	)
	(segment
		(start 84.540598 -51.745134)
		(end 84.540598 -51.458114)
		(width 0.0889)
		(layer "F.Cu")
		(net "M_H_ECC<7>")
	)
	(segment
		(start 77.736446 -31.370778)
		(end 77.736446 -31.137098)
		(width 0.1651)
		(layer "F.Cu")
		(net "M_H_ECC<7>")
	)
	(segment
		(start 84.462366 -50.5333)
		(end 84.462366 -50.073814)
		(width 0.0889)
		(layer "F.Cu")
		(net "M_H_ECC<7>")
	)
	(segment
		(start 78.890368 -37.4142)
		(end 79.436468 -36.8681)
		(width 0.1651)
		(layer "F.Cu")
		(net "M_H_ECC<7>")
	)
	(segment
		(start 84.519008 -52.618132)
		(end 84.519008 -52.554378)
		(width 0.0889)
		(layer "F.Cu")
		(net "M_H_ECC<7>")
	)
	(segment
		(start 77.02677 -30.661102)
		(end 76.784454 -30.418786)
		(width 0.1651)
		(layer "F.Cu")
		(net "M_H_ECC<7>")
	)
	(segment
		(start 84.412328 -53.913024)
		(end 84.407502 -53.904388)
		(width 0.0889)
		(layer "F.Cu")
		(net "M_H_ECC<7>")
	)
	(segment
		(start 77.975968 -37.4142)
		(end 78.890368 -37.4142)
		(width 0.1651)
		(layer "F.Cu")
		(net "M_H_ECC<7>")
	)
	(segment
		(start 79.436468 -34.3281)
		(end 78.166468 -33.0581)
		(width 0.1651)
		(layer "F.Cu")
		(net "M_H_ECC<7>")
	)
	(segment
		(start 74.795888 -27.29992)
		(end 74.795888 -26.811732)
		(width 0.1651)
		(layer "F.Cu")
		(net "M_H_ECC<7>")
	)
	(segment
		(start 75.588368 -28.0924)
		(end 74.795888 -27.29992)
		(width 0.1651)
		(layer "F.Cu")
		(net "M_H_ECC<7>")
	)
	(segment
		(start 84.462366 -50.073814)
		(end 84.462366 -47.61738)
		(width 0.1016)
		(layer "F.Cu")
		(net "M_H_ECC<7>")
	)
	(segment
		(start 76.519278 -29.70911)
		(end 76.074778 -29.70911)
		(width 0.1651)
		(layer "F.Cu")
		(net "M_H_ECC<7>")
	)
	(segment
		(start 79.45374 -42.822114)
		(end 78.285594 -41.653968)
		(width 0.1016)
		(layer "F.Cu")
		(net "M_H_ECC<7>")
	)
	(segment
		(start 77.979016 -30.660848)
		(end 77.7367 -30.418532)
		(width 0.1651)
		(layer "F.Cu")
		(net "M_H_ECC<7>")
	)
	(via
		(at 74.749406 -7.086346)
		(size 0.508)
		(drill 0.254)
		(layers "F.Cu" "B.Cu")
		(net "M_H_ECC<7>")
	)
	(via
		(at 75.59929 -26.691336)
		(size 0.508)
		(drill 0.254)
		(layers "F.Cu" "B.Cu")
		(net "M_H_ECC<7>")
	)
	(via
		(at 75.59929 -12.678156)
		(size 0.508)
		(drill 0.254)
		(layers "F.Cu" "B.Cu")
		(net "M_H_ECC<7>")
	)
	(arc
		(start 84.407502 -54.304438)
		(mid 84.460972 -54.109375)
		(end 84.412328 -53.913024)
		(width 0.0889)
		(layer "F.Cu")
		(net "M_H_ECC<7>")
	)
	(arc
		(start 84.572602 -52.818284)
		(mid 84.532615 -52.721738)
		(end 84.519008 -52.618132)
		(width 0.0889)
		(layer "F.Cu")
		(net "M_H_ECC<7>")
	)
	(arc
		(start 84.572602 -53.409088)
		(mid 84.651733 -53.113686)
		(end 84.572602 -52.818284)
		(width 0.0889)
		(layer "F.Cu")
		(net "M_H_ECC<7>")
	)
	(segment
		(start 75.599544 -10.623042)
		(end 75.599544 -11.110722)
		(width 0.1651)
		(layer "B.Cu")
		(net "M_H_ECC<7>")
	)
	(segment
		(start 75.599544 -11.110722)
		(end 75.59929 -11.110976)
		(width 0.1651)
		(layer "B.Cu")
		(net "M_H_ECC<7>")
	)
	(segment
		(start 75.59929 -11.110976)
		(end 75.59929 -12.678156)
		(width 0.1651)
		(layer "B.Cu")
		(net "M_H_ECC<7>")
	)
	(segment
		(start 75.650344 -8.0518)
		(end 75.396344 -8.0518)
		(width 0.14224)
		(layer "In11.Cu")
		(net "M_H_ECC<7>")
	)
	(segment
		(start 75.16622 -13.543534)
		(end 75.16622 -13.111226)
		(width 0.14224)
		(layer "In11.Cu")
		(net "M_H_ECC<7>")
	)
	(segment
		(start 76.107544 -8.8646)
		(end 76.107544 -8.509)
		(width 0.14224)
		(layer "In11.Cu")
		(net "M_H_ECC<7>")
	)
	(segment
		(start 75.396344 -8.0518)
		(end 75.066144 -7.7216)
		(width 0.14224)
		(layer "In11.Cu")
		(net "M_H_ECC<7>")
	)
	(segment
		(start 75.952096 -12.32535)
		(end 75.952096 -9.020048)
		(width 0.14224)
		(layer "In11.Cu")
		(net "M_H_ECC<7>")
	)
	(segment
		(start 75.988164 -21.862796)
		(end 75.988164 -21.317204)
		(width 0.14224)
		(layer "In11.Cu")
		(net "M_H_ECC<7>")
	)
	(segment
		(start 75.59929 -26.691336)
		(end 75.962764 -26.327862)
		(width 0.14224)
		(layer "In11.Cu")
		(net "M_H_ECC<7>")
	)
	(segment
		(start 75.988164 -18.455386)
		(end 76.115164 -18.328386)
		(width 0.14224)
		(layer "In11.Cu")
		(net "M_H_ECC<7>")
	)
	(segment
		(start 75.16622 -13.111226)
		(end 75.59929 -12.678156)
		(width 0.14224)
		(layer "In11.Cu")
		(net "M_H_ECC<7>")
	)
	(segment
		(start 75.066144 -7.7216)
		(end 75.066144 -7.403084)
		(width 0.14224)
		(layer "In11.Cu")
		(net "M_H_ECC<7>")
	)
	(segment
		(start 75.988164 -19.119596)
		(end 75.988164 -18.455386)
		(width 0.14224)
		(layer "In11.Cu")
		(net "M_H_ECC<7>")
	)
	(segment
		(start 75.810364 -14.187678)
		(end 75.16622 -13.543534)
		(width 0.14224)
		(layer "In11.Cu")
		(net "M_H_ECC<7>")
	)
	(segment
		(start 76.107544 -8.509)
		(end 75.650344 -8.0518)
		(width 0.14224)
		(layer "In11.Cu")
		(net "M_H_ECC<7>")
	)
	(segment
		(start 76.140564 -22.015196)
		(end 75.988164 -21.862796)
		(width 0.14224)
		(layer "In11.Cu")
		(net "M_H_ECC<7>")
	)
	(segment
		(start 75.988164 -21.317204)
		(end 76.070968 -21.2344)
		(width 0.14224)
		(layer "In11.Cu")
		(net "M_H_ECC<7>")
	)
	(segment
		(start 76.115164 -17.032986)
		(end 75.810364 -16.728186)
		(width 0.14224)
		(layer "In11.Cu")
		(net "M_H_ECC<7>")
	)
	(segment
		(start 75.810364 -16.728186)
		(end 75.810364 -14.187678)
		(width 0.14224)
		(layer "In11.Cu")
		(net "M_H_ECC<7>")
	)
	(segment
		(start 75.962764 -23.294848)
		(end 76.140564 -23.117048)
		(width 0.14224)
		(layer "In11.Cu")
		(net "M_H_ECC<7>")
	)
	(segment
		(start 76.140564 -23.117048)
		(end 76.140564 -22.015196)
		(width 0.14224)
		(layer "In11.Cu")
		(net "M_H_ECC<7>")
	)
	(segment
		(start 75.066144 -7.403084)
		(end 74.749406 -7.086346)
		(width 0.14224)
		(layer "In11.Cu")
		(net "M_H_ECC<7>")
	)
	(segment
		(start 76.070968 -19.2024)
		(end 75.988164 -19.119596)
		(width 0.14224)
		(layer "In11.Cu")
		(net "M_H_ECC<7>")
	)
	(segment
		(start 75.962764 -26.327862)
		(end 75.962764 -23.294848)
		(width 0.14224)
		(layer "In11.Cu")
		(net "M_H_ECC<7>")
	)
	(segment
		(start 76.070968 -21.2344)
		(end 76.070968 -19.2024)
		(width 0.14224)
		(layer "In11.Cu")
		(net "M_H_ECC<7>")
	)
	(segment
		(start 76.115164 -18.328386)
		(end 76.115164 -17.032986)
		(width 0.14224)
		(layer "In11.Cu")
		(net "M_H_ECC<7>")
	)
	(segment
		(start 75.59929 -12.678156)
		(end 75.952096 -12.32535)
		(width 0.14224)
		(layer "In11.Cu")
		(net "M_H_ECC<7>")
	)
	(segment
		(start 75.952096 -9.020048)
		(end 76.107544 -8.8646)
		(width 0.14224)
		(layer "In11.Cu")
		(net "M_H_ECC<7>")
	)
	(segment
		(start 75.599544 -10.422382)
		(end 75.599544 -9.4488)
		(width 0.1651)
		(layer "F.Cu")
		(net "M_H_ECC<6>")
	)
	(segment
		(start 84.328254 -52.497482)
		(end 84.44103 -52.302156)
		(width 0.0889)
		(layer "F.Cu")
		(net "M_H_ECC<6>")
	)
	(segment
		(start 84.464144 -51.038506)
		(end 84.157566 -50.34661)
		(width 0.0889)
		(layer "F.Cu")
		(net "M_H_ECC<6>")
	)
	(segment
		(start 84.157566 -47.743872)
		(end 79.540608 -43.126914)
		(width 0.1016)
		(layer "F.Cu")
		(net "M_H_ECC<6>")
	)
	(segment
		(start 77.646022 -36.703)
		(end 78.623668 -36.703)
		(width 0.1651)
		(layer "F.Cu")
		(net "M_H_ECC<6>")
	)
	(segment
		(start 76.693268 -37.655754)
		(end 77.646022 -36.703)
		(width 0.1651)
		(layer "F.Cu")
		(net "M_H_ECC<6>")
	)
	(segment
		(start 84.44103 -52.302156)
		(end 84.44103 -51.953922)
		(width 0.0889)
		(layer "F.Cu")
		(net "M_H_ECC<6>")
	)
	(segment
		(start 84.256626 -53.412644)
		(end 84.330032 -53.40096)
		(width 0.0889)
		(layer "F.Cu")
		(net "M_H_ECC<6>")
	)
	(segment
		(start 76.693268 -41.60393)
		(end 76.693268 -37.655754)
		(width 0.1651)
		(layer "F.Cu")
		(net "M_H_ECC<6>")
	)
	(segment
		(start 79.540608 -43.126914)
		(end 79.201772 -43.126914)
		(width 0.1016)
		(layer "F.Cu")
		(net "M_H_ECC<6>")
	)
	(segment
		(start 75.731624 -9.09828)
		(end 75.599544 -8.9662)
		(width 0.1651)
		(layer "F.Cu")
		(net "M_H_ECC<6>")
	)
	(segment
		(start 78.623668 -36.703)
		(end 78.750668 -36.576)
		(width 0.1651)
		(layer "F.Cu")
		(net "M_H_ECC<6>")
	)
	(segment
		(start 77.137006 -42.047668)
		(end 77.027532 -41.938194)
		(width 0.1016)
		(layer "F.Cu")
		(net "M_H_ECC<6>")
	)
	(segment
		(start 74.901806 -29.501338)
		(end 74.901806 -28.175458)
		(width 0.1651)
		(layer "F.Cu")
		(net "M_H_ECC<6>")
	)
	(segment
		(start 77.404468 -32.004)
		(end 74.901806 -29.501338)
		(width 0.1651)
		(layer "F.Cu")
		(net "M_H_ECC<6>")
	)
	(segment
		(start 84.350098 -51.40706)
		(end 84.464144 -51.209194)
		(width 0.0889)
		(layer "F.Cu")
		(net "M_H_ECC<6>")
	)
	(segment
		(start 84.350098 -51.796442)
		(end 84.350098 -51.40706)
		(width 0.0889)
		(layer "F.Cu")
		(net "M_H_ECC<6>")
	)
	(segment
		(start 78.077568 -35.7632)
		(end 77.950568 -35.8902)
		(width 0.1651)
		(layer "F.Cu")
		(net "M_H_ECC<6>")
	)
	(segment
		(start 79.201772 -43.126914)
		(end 78.122526 -42.047668)
		(width 0.1016)
		(layer "F.Cu")
		(net "M_H_ECC<6>")
	)
	(segment
		(start 78.750668 -34.6329)
		(end 78.585568 -34.4678)
		(width 0.1651)
		(layer "F.Cu")
		(net "M_H_ECC<6>")
	)
	(segment
		(start 77.950568 -35.8902)
		(end 77.531468 -35.8902)
		(width 0.1651)
		(layer "F.Cu")
		(net "M_H_ECC<6>")
	)
	(segment
		(start 84.157566 -50.073814)
		(end 84.157566 -47.743872)
		(width 0.1016)
		(layer "F.Cu")
		(net "M_H_ECC<6>")
	)
	(segment
		(start 77.404468 -35.7632)
		(end 77.404468 -32.004)
		(width 0.1651)
		(layer "F.Cu")
		(net "M_H_ECC<6>")
	)
	(segment
		(start 77.027532 -41.938194)
		(end 76.693268 -41.60393)
		(width 0.1651)
		(layer "F.Cu")
		(net "M_H_ECC<6>")
	)
	(segment
		(start 78.077568 -34.6329)
		(end 78.077568 -35.7632)
		(width 0.1651)
		(layer "F.Cu")
		(net "M_H_ECC<6>")
	)
	(segment
		(start 78.122526 -42.047668)
		(end 77.137006 -42.047668)
		(width 0.1016)
		(layer "F.Cu")
		(net "M_H_ECC<6>")
	)
	(segment
		(start 75.599544 -9.4488)
		(end 75.731624 -9.31672)
		(width 0.1651)
		(layer "F.Cu")
		(net "M_H_ECC<6>")
	)
	(segment
		(start 84.464144 -51.209194)
		(end 84.464144 -51.038506)
		(width 0.0889)
		(layer "F.Cu")
		(net "M_H_ECC<6>")
	)
	(segment
		(start 84.44103 -51.953922)
		(end 84.350098 -51.796442)
		(width 0.0889)
		(layer "F.Cu")
		(net "M_H_ECC<6>")
	)
	(segment
		(start 75.731624 -9.31672)
		(end 75.731624 -9.09828)
		(width 0.1651)
		(layer "F.Cu")
		(net "M_H_ECC<6>")
	)
	(segment
		(start 78.750668 -36.576)
		(end 78.750668 -34.6329)
		(width 0.1651)
		(layer "F.Cu")
		(net "M_H_ECC<6>")
	)
	(segment
		(start 78.585568 -34.4678)
		(end 78.242668 -34.4678)
		(width 0.1651)
		(layer "F.Cu")
		(net "M_H_ECC<6>")
	)
	(segment
		(start 84.148168 -53.381656)
		(end 84.256626 -53.412644)
		(width 0.0889)
		(layer "F.Cu")
		(net "M_H_ECC<6>")
	)
	(segment
		(start 75.599544 -8.9662)
		(end 75.599544 -8.661654)
		(width 0.1651)
		(layer "F.Cu")
		(net "M_H_ECC<6>")
	)
	(segment
		(start 77.531468 -35.8902)
		(end 77.404468 -35.7632)
		(width 0.1651)
		(layer "F.Cu")
		(net "M_H_ECC<6>")
	)
	(segment
		(start 84.157566 -50.34661)
		(end 84.157566 -50.073814)
		(width 0.0889)
		(layer "F.Cu")
		(net "M_H_ECC<6>")
	)
	(segment
		(start 84.328254 -52.617624)
		(end 84.328254 -52.497482)
		(width 0.0889)
		(layer "F.Cu")
		(net "M_H_ECC<6>")
	)
	(segment
		(start 75.599544 -8.661654)
		(end 75.59929 -8.6614)
		(width 0.1651)
		(layer "F.Cu")
		(net "M_H_ECC<6>")
	)
	(segment
		(start 78.242668 -34.4678)
		(end 78.077568 -34.6329)
		(width 0.1651)
		(layer "F.Cu")
		(net "M_H_ECC<6>")
	)
	(via
		(at 75.59929 -8.6614)
		(size 0.508)
		(drill 0.254)
		(layers "F.Cu" "B.Cu")
		(net "M_H_ECC<6>")
	)
	(via
		(at 74.749406 -13.959078)
		(size 0.508)
		(drill 0.254)
		(layers "F.Cu" "B.Cu")
		(net "M_H_ECC<6>")
	)
	(via
		(at 74.901806 -28.175458)
		(size 0.508)
		(drill 0.254)
		(layers "F.Cu" "B.Cu")
		(net "M_H_ECC<6>")
	)
	(arc
		(start 84.330032 -53.40096)
		(mid 84.37322 -53.361359)
		(end 84.407502 -53.313838)
		(width 0.0889)
		(layer "F.Cu")
		(net "M_H_ECC<6>")
	)
	(arc
		(start 84.407502 -53.313838)
		(mid 84.461001 -53.11394)
		(end 84.407502 -52.914042)
		(width 0.0889)
		(layer "F.Cu")
		(net "M_H_ECC<6>")
	)
	(arc
		(start 84.060792 -53.113686)
		(mid 84.083235 -53.254595)
		(end 84.148168 -53.381656)
		(width 0.0889)
		(layer "F.Cu")
		(net "M_H_ECC<6>")
	)
	(arc
		(start 84.407502 -52.914042)
		(mid 84.348303 -52.771066)
		(end 84.328254 -52.617624)
		(width 0.0889)
		(layer "F.Cu")
		(net "M_H_ECC<6>")
	)
	(segment
		(start 74.749406 -15.222982)
		(end 74.749406 -13.959078)
		(width 0.1651)
		(layer "B.Cu")
		(net "M_H_ECC<6>")
	)
	(segment
		(start 75.226164 -18.51025)
		(end 75.226164 -18.9992)
		(width 0.14224)
		(layer "In11.Cu")
		(net "M_H_ECC<6>")
	)
	(segment
		(start 75.226164 -21.862796)
		(end 75.048364 -22.040596)
		(width 0.14224)
		(layer "In11.Cu")
		(net "M_H_ECC<6>")
	)
	(segment
		(start 75.099164 -27.9781)
		(end 74.901806 -28.175458)
		(width 0.14224)
		(layer "In11.Cu")
		(net "M_H_ECC<6>")
	)
	(segment
		(start 75.080368 -21.1836)
		(end 75.226164 -21.329396)
		(width 0.14224)
		(layer "In11.Cu")
		(net "M_H_ECC<6>")
	)
	(segment
		(start 75.226164 -18.9992)
		(end 75.080368 -19.144996)
		(width 0.14224)
		(layer "In11.Cu")
		(net "M_H_ECC<6>")
	)
	(segment
		(start 75.327764 -23.412196)
		(end 75.327764 -26.194258)
		(width 0.14224)
		(layer "In11.Cu")
		(net "M_H_ECC<6>")
	)
	(segment
		(start 74.431144 -13.640816)
		(end 74.749406 -13.959078)
		(width 0.14224)
		(layer "In11.Cu")
		(net "M_H_ECC<6>")
	)
	(segment
		(start 75.226164 -21.329396)
		(end 75.226164 -21.862796)
		(width 0.14224)
		(layer "In11.Cu")
		(net "M_H_ECC<6>")
	)
	(segment
		(start 75.251564 -14.461236)
		(end 75.251564 -16.842486)
		(width 0.14224)
		(layer "In11.Cu")
		(net "M_H_ECC<6>")
	)
	(segment
		(start 75.048364 -23.132796)
		(end 75.327764 -23.412196)
		(width 0.14224)
		(layer "In11.Cu")
		(net "M_H_ECC<6>")
	)
	(segment
		(start 75.099164 -26.422858)
		(end 75.099164 -27.9781)
		(width 0.14224)
		(layer "In11.Cu")
		(net "M_H_ECC<6>")
	)
	(segment
		(start 75.048364 -17.045686)
		(end 75.048364 -18.33245)
		(width 0.14224)
		(layer "In11.Cu")
		(net "M_H_ECC<6>")
	)
	(segment
		(start 75.193144 -12.4333)
		(end 74.431144 -13.1953)
		(width 0.14224)
		(layer "In11.Cu")
		(net "M_H_ECC<6>")
	)
	(segment
		(start 75.251564 -16.842486)
		(end 75.048364 -17.045686)
		(width 0.14224)
		(layer "In11.Cu")
		(net "M_H_ECC<6>")
	)
	(segment
		(start 75.193144 -9.067546)
		(end 75.193144 -12.4333)
		(width 0.14224)
		(layer "In11.Cu")
		(net "M_H_ECC<6>")
	)
	(segment
		(start 75.048364 -18.33245)
		(end 75.226164 -18.51025)
		(width 0.14224)
		(layer "In11.Cu")
		(net "M_H_ECC<6>")
	)
	(segment
		(start 75.080368 -19.144996)
		(end 75.080368 -21.1836)
		(width 0.14224)
		(layer "In11.Cu")
		(net "M_H_ECC<6>")
	)
	(segment
		(start 75.59929 -8.6614)
		(end 75.193144 -9.067546)
		(width 0.14224)
		(layer "In11.Cu")
		(net "M_H_ECC<6>")
	)
	(segment
		(start 75.327764 -26.194258)
		(end 75.099164 -26.422858)
		(width 0.14224)
		(layer "In11.Cu")
		(net "M_H_ECC<6>")
	)
	(segment
		(start 74.749406 -13.959078)
		(end 75.251564 -14.461236)
		(width 0.14224)
		(layer "In11.Cu")
		(net "M_H_ECC<6>")
	)
	(segment
		(start 75.048364 -22.040596)
		(end 75.048364 -23.132796)
		(width 0.14224)
		(layer "In11.Cu")
		(net "M_H_ECC<6>")
	)
	(segment
		(start 74.431144 -13.1953)
		(end 74.431144 -13.640816)
		(width 0.14224)
		(layer "In11.Cu")
		(net "M_H_ECC<6>")
	)
	(segment
		(start 77.436218 -45.260514)
		(end 76.979272 -44.803568)
		(width 0.1016)
		(layer "F.Cu")
		(net "M_H_ECC<5>")
	)
	(segment
		(start 81.755488 -51.29403)
		(end 81.755488 -50.963322)
		(width 0.0889)
		(layer "F.Cu")
		(net "M_H_ECC<5>")
	)
	(segment
		(start 69.619368 -28.6258)
		(end 68.838826 -27.845258)
		(width 0.1651)
		(layer "F.Cu")
		(net "M_H_ECC<5>")
	)
	(segment
		(start 82.023966 -48.629316)
		(end 78.655164 -45.260514)
		(width 0.1016)
		(layer "F.Cu")
		(net "M_H_ECC<5>")
	)
	(segment
		(start 68.838826 -27.845258)
		(end 68.838826 -27.415236)
		(width 0.1651)
		(layer "F.Cu")
		(net "M_H_ECC<5>")
	)
	(segment
		(start 70.990968 -32.093154)
		(end 69.619368 -30.721554)
		(width 0.1651)
		(layer "F.Cu")
		(net "M_H_ECC<5>")
	)
	(segment
		(start 74.417428 -44.803568)
		(end 74.377042 -44.763182)
		(width 0.1016)
		(layer "F.Cu")
		(net "M_H_ECC<5>")
	)
	(segment
		(start 81.755488 -50.963322)
		(end 82.023966 -50.498248)
		(width 0.0889)
		(layer "F.Cu")
		(net "M_H_ECC<5>")
	)
	(segment
		(start 82.013806 -54.33314)
		(end 81.997042 -54.304438)
		(width 0.0889)
		(layer "F.Cu")
		(net "M_H_ECC<5>")
	)
	(segment
		(start 81.75244 -52.124356)
		(end 81.75244 -51.917854)
		(width 0.0889)
		(layer "F.Cu")
		(net "M_H_ECC<5>")
	)
	(segment
		(start 81.75244 -51.917854)
		(end 81.88071 -51.695858)
		(width 0.0889)
		(layer "F.Cu")
		(net "M_H_ECC<5>")
	)
	(segment
		(start 70.990968 -41.377108)
		(end 70.990968 -32.093154)
		(width 0.1651)
		(layer "F.Cu")
		(net "M_H_ECC<5>")
	)
	(segment
		(start 82.023966 -50.498248)
		(end 82.023966 -50.073814)
		(width 0.0889)
		(layer "F.Cu")
		(net "M_H_ECC<5>")
	)
	(segment
		(start 74.377042 -44.763182)
		(end 70.990968 -41.377108)
		(width 0.1651)
		(layer "F.Cu")
		(net "M_H_ECC<5>")
	)
	(segment
		(start 68.799456 -5.822442)
		(end 68.799456 -7.086346)
		(width 0.1651)
		(layer "F.Cu")
		(net "M_H_ECC<5>")
	)
	(segment
		(start 69.003926 -27.250136)
		(end 69.57314 -27.250136)
		(width 0.1651)
		(layer "F.Cu")
		(net "M_H_ECC<5>")
	)
	(segment
		(start 81.470246 -53.20919)
		(end 81.596738 -53.20919)
		(width 0.0889)
		(layer "F.Cu")
		(net "M_H_ECC<5>")
	)
	(segment
		(start 81.506822 -54.00929)
		(end 81.474056 -54.00929)
		(width 0.0889)
		(layer "F.Cu")
		(net "M_H_ECC<5>")
	)
	(segment
		(start 82.343752 -55.094886)
		(end 82.013806 -54.33314)
		(width 0.0889)
		(layer "F.Cu")
		(net "M_H_ECC<5>")
	)
	(segment
		(start 82.023966 -50.073814)
		(end 82.023966 -48.629316)
		(width 0.1016)
		(layer "F.Cu")
		(net "M_H_ECC<5>")
	)
	(segment
		(start 81.88071 -51.695858)
		(end 81.88071 -51.510946)
		(width 0.0889)
		(layer "F.Cu")
		(net "M_H_ECC<5>")
	)
	(segment
		(start 81.712562 -53.140102)
		(end 81.785968 -52.926488)
		(width 0.0889)
		(layer "F.Cu")
		(net "M_H_ECC<5>")
	)
	(segment
		(start 69.619368 -30.721554)
		(end 69.619368 -28.6258)
		(width 0.1651)
		(layer "F.Cu")
		(net "M_H_ECC<5>")
	)
	(segment
		(start 81.596738 -53.20919)
		(end 81.712562 -53.140102)
		(width 0.0889)
		(layer "F.Cu")
		(net "M_H_ECC<5>")
	)
	(segment
		(start 68.838826 -27.415236)
		(end 69.003926 -27.250136)
		(width 0.1651)
		(layer "F.Cu")
		(net "M_H_ECC<5>")
	)
	(segment
		(start 78.655164 -45.260514)
		(end 77.436218 -45.260514)
		(width 0.1016)
		(layer "F.Cu")
		(net "M_H_ECC<5>")
	)
	(segment
		(start 81.86801 -52.495958)
		(end 81.824068 -52.412392)
		(width 0.0889)
		(layer "F.Cu")
		(net "M_H_ECC<5>")
	)
	(segment
		(start 81.88071 -51.510946)
		(end 81.755488 -51.29403)
		(width 0.0889)
		(layer "F.Cu")
		(net "M_H_ECC<5>")
	)
	(segment
		(start 76.979272 -44.803568)
		(end 74.417428 -44.803568)
		(width 0.1016)
		(layer "F.Cu")
		(net "M_H_ECC<5>")
	)
	(via
		(at 68.799456 -7.086346)
		(size 0.508)
		(drill 0.254)
		(layers "F.Cu" "B.Cu")
		(net "M_H_ECC<5>")
	)
	(via
		(at 69.57314 -12.678156)
		(size 0.508)
		(drill 0.254)
		(layers "F.Cu" "B.Cu")
		(net "M_H_ECC<5>")
	)
	(via
		(at 69.57314 -27.250136)
		(size 0.508)
		(drill 0.254)
		(layers "F.Cu" "B.Cu")
		(net "M_H_ECC<5>")
	)
	(arc
		(start 81.474056 -54.00929)
		(mid 81.08503 -53.611144)
		(end 81.470246 -53.20919)
		(width 0.0889)
		(layer "F.Cu")
		(net "M_H_ECC<5>")
	)
	(arc
		(start 81.785968 -52.926488)
		(mid 81.823154 -52.827731)
		(end 81.870042 -52.733194)
		(width 0.0889)
		(layer "F.Cu")
		(net "M_H_ECC<5>")
	)
	(arc
		(start 81.899252 -52.621434)
		(mid 81.891304 -52.556783)
		(end 81.86801 -52.495958)
		(width 0.0889)
		(layer "F.Cu")
		(net "M_H_ECC<5>")
	)
	(arc
		(start 81.870042 -52.733194)
		(mid 81.891787 -52.679184)
		(end 81.899252 -52.621434)
		(width 0.0889)
		(layer "F.Cu")
		(net "M_H_ECC<5>")
	)
	(arc
		(start 81.997042 -54.304438)
		(mid 81.790038 -54.093574)
		(end 81.506822 -54.00929)
		(width 0.0889)
		(layer "F.Cu")
		(net "M_H_ECC<5>")
	)
	(arc
		(start 81.824068 -52.412392)
		(mid 81.770791 -52.272716)
		(end 81.75244 -52.124356)
		(width 0.0889)
		(layer "F.Cu")
		(net "M_H_ECC<5>")
	)
	(segment
		(start 69.64934 -12.601956)
		(end 69.57314 -12.678156)
		(width 0.1651)
		(layer "B.Cu")
		(net "M_H_ECC<5>")
	)
	(segment
		(start 69.64934 -10.623042)
		(end 69.64934 -12.601956)
		(width 0.1651)
		(layer "B.Cu")
		(net "M_H_ECC<5>")
	)
	(segment
		(start 69.993764 -26.829512)
		(end 69.57314 -27.250136)
		(width 0.14224)
		(layer "In11.Cu")
		(net "M_H_ECC<5>")
	)
	(segment
		(start 69.968364 -21.3614)
		(end 69.968364 -21.862796)
		(width 0.14224)
		(layer "In11.Cu")
		(net "M_H_ECC<5>")
	)
	(segment
		(start 69.085968 -7.372858)
		(end 69.085968 -7.767574)
		(width 0.14224)
		(layer "In11.Cu")
		(net "M_H_ECC<5>")
	)
	(segment
		(start 70.044564 -17.109186)
		(end 70.044564 -18.455386)
		(width 0.14224)
		(layer "In11.Cu")
		(net "M_H_ECC<5>")
	)
	(segment
		(start 69.884544 -12.366752)
		(end 69.57314 -12.678156)
		(width 0.14224)
		(layer "In11.Cu")
		(net "M_H_ECC<5>")
	)
	(segment
		(start 69.746368 -12.851384)
		(end 69.746368 -13.8938)
		(width 0.14224)
		(layer "In11.Cu")
		(net "M_H_ECC<5>")
	)
	(segment
		(start 70.069964 -23.158196)
		(end 69.993764 -23.234396)
		(width 0.14224)
		(layer "In11.Cu")
		(net "M_H_ECC<5>")
	)
	(segment
		(start 70.069964 -21.964396)
		(end 70.069964 -23.158196)
		(width 0.14224)
		(layer "In11.Cu")
		(net "M_H_ECC<5>")
	)
	(segment
		(start 69.968364 -19.094196)
		(end 70.152768 -19.2786)
		(width 0.14224)
		(layer "In11.Cu")
		(net "M_H_ECC<5>")
	)
	(segment
		(start 69.746368 -13.8938)
		(end 69.949568 -14.097)
		(width 0.14224)
		(layer "In11.Cu")
		(net "M_H_ECC<5>")
	)
	(segment
		(start 69.968364 -21.862796)
		(end 70.069964 -21.964396)
		(width 0.14224)
		(layer "In11.Cu")
		(net "M_H_ECC<5>")
	)
	(segment
		(start 69.884544 -9.06145)
		(end 69.884544 -12.366752)
		(width 0.14224)
		(layer "In11.Cu")
		(net "M_H_ECC<5>")
	)
	(segment
		(start 69.085968 -7.767574)
		(end 69.370194 -8.0518)
		(width 0.14224)
		(layer "In11.Cu")
		(net "M_H_ECC<5>")
	)
	(segment
		(start 70.152768 -19.2786)
		(end 70.152768 -21.176996)
		(width 0.14224)
		(layer "In11.Cu")
		(net "M_H_ECC<5>")
	)
	(segment
		(start 70.081394 -8.8646)
		(end 69.884544 -9.06145)
		(width 0.14224)
		(layer "In11.Cu")
		(net "M_H_ECC<5>")
	)
	(segment
		(start 69.57314 -12.678156)
		(end 69.746368 -12.851384)
		(width 0.14224)
		(layer "In11.Cu")
		(net "M_H_ECC<5>")
	)
	(segment
		(start 69.68109 -8.0518)
		(end 70.081394 -8.452104)
		(width 0.14224)
		(layer "In11.Cu")
		(net "M_H_ECC<5>")
	)
	(segment
		(start 70.081394 -8.452104)
		(end 70.081394 -8.8646)
		(width 0.14224)
		(layer "In11.Cu")
		(net "M_H_ECC<5>")
	)
	(segment
		(start 70.044564 -18.455386)
		(end 69.968364 -18.531586)
		(width 0.14224)
		(layer "In11.Cu")
		(net "M_H_ECC<5>")
	)
	(segment
		(start 69.968364 -18.531586)
		(end 69.968364 -19.094196)
		(width 0.14224)
		(layer "In11.Cu")
		(net "M_H_ECC<5>")
	)
	(segment
		(start 69.370194 -8.0518)
		(end 69.68109 -8.0518)
		(width 0.14224)
		(layer "In11.Cu")
		(net "M_H_ECC<5>")
	)
	(segment
		(start 68.799456 -7.086346)
		(end 69.085968 -7.372858)
		(width 0.14224)
		(layer "In11.Cu")
		(net "M_H_ECC<5>")
	)
	(segment
		(start 69.949568 -14.097)
		(end 69.949568 -17.01419)
		(width 0.14224)
		(layer "In11.Cu")
		(net "M_H_ECC<5>")
	)
	(segment
		(start 69.993764 -23.234396)
		(end 69.993764 -26.829512)
		(width 0.14224)
		(layer "In11.Cu")
		(net "M_H_ECC<5>")
	)
	(segment
		(start 70.152768 -21.176996)
		(end 69.968364 -21.3614)
		(width 0.14224)
		(layer "In11.Cu")
		(net "M_H_ECC<5>")
	)
	(segment
		(start 69.949568 -17.01419)
		(end 70.044564 -17.109186)
		(width 0.14224)
		(layer "In11.Cu")
		(net "M_H_ECC<5>")
	)
	(segment
		(start 81.706466 -50.39741)
		(end 81.706466 -50.073814)
		(width 0.0889)
		(layer "F.Cu")
		(net "M_H_ECC<4>")
	)
	(segment
		(start 81.07807 -51.622452)
		(end 81.07934 -51.56073)
		(width 0.0889)
		(layer "F.Cu")
		(net "M_H_ECC<4>")
	)
	(segment
		(start 69.606668 -35.00501)
		(end 69.803772 -34.807906)
		(width 0.1651)
		(layer "F.Cu")
		(net "M_H_ECC<4>")
	)
	(segment
		(start 80.973422 -53.904388)
		(end 80.967072 -53.89372)
		(width 0.0889)
		(layer "F.Cu")
		(net "M_H_ECC<4>")
	)
	(segment
		(start 81.706466 -50.073814)
		(end 81.706466 -48.760888)
		(width 0.127)
		(layer "F.Cu")
		(net "M_H_ECC<4>")
	)
	(segment
		(start 70.996302 -43.223688)
		(end 70.71741 -43.223688)
		(width 0.1651)
		(layer "F.Cu")
		(net "M_H_ECC<4>")
	)
	(segment
		(start 81.133188 -51.393344)
		(end 81.342992 -51.086512)
		(width 0.0889)
		(layer "F.Cu")
		(net "M_H_ECC<4>")
	)
	(segment
		(start 70.082664 -34.807906)
		(end 70.279768 -34.610802)
		(width 0.1651)
		(layer "F.Cu")
		(net "M_H_ECC<4>")
	)
	(segment
		(start 70.843394 -42.424604)
		(end 70.843394 -42.145712)
		(width 0.1651)
		(layer "F.Cu")
		(net "M_H_ECC<4>")
	)
	(segment
		(start 69.64934 -10.422382)
		(end 69.64934 -9.091168)
		(width 0.1651)
		(layer "F.Cu")
		(net "M_H_ECC<4>")
	)
	(segment
		(start 69.803772 -35.481006)
		(end 69.606668 -35.283902)
		(width 0.1651)
		(layer "F.Cu")
		(net "M_H_ECC<4>")
	)
	(segment
		(start 69.803772 -33.461706)
		(end 70.082664 -33.461706)
		(width 0.1651)
		(layer "F.Cu")
		(net "M_H_ECC<4>")
	)
	(segment
		(start 69.64934 -9.091168)
		(end 69.588888 -8.763)
		(width 0.1651)
		(layer "F.Cu")
		(net "M_H_ECC<4>")
	)
	(segment
		(start 80.973422 -53.313838)
		(end 81.07807 -52.978558)
		(width 0.0889)
		(layer "F.Cu")
		(net "M_H_ECC<4>")
	)
	(segment
		(start 80.990186 -53.933852)
		(end 80.973422 -53.904388)
		(width 0.0889)
		(layer "F.Cu")
		(net "M_H_ECC<4>")
	)
	(segment
		(start 73.90765 -45.209968)
		(end 71.598282 -42.9006)
		(width 0.1651)
		(layer "F.Cu")
		(net "M_H_ECC<4>")
	)
	(segment
		(start 81.07807 -52.978558)
		(end 81.07807 -51.622452)
		(width 0.0889)
		(layer "F.Cu")
		(net "M_H_ECC<4>")
	)
	(segment
		(start 70.082664 -35.481006)
		(end 69.803772 -35.481006)
		(width 0.1651)
		(layer "F.Cu")
		(net "M_H_ECC<4>")
	)
	(segment
		(start 78.523592 -45.578014)
		(end 77.178662 -45.578014)
		(width 0.127)
		(layer "F.Cu")
		(net "M_H_ECC<4>")
	)
	(segment
		(start 81.342992 -51.086512)
		(end 81.706466 -50.39741)
		(width 0.0889)
		(layer "F.Cu")
		(net "M_H_ECC<4>")
	)
	(segment
		(start 70.082664 -33.461706)
		(end 70.279768 -33.264602)
		(width 0.1651)
		(layer "F.Cu")
		(net "M_H_ECC<4>")
	)
	(segment
		(start 70.279768 -41.582086)
		(end 70.279768 -35.67811)
		(width 0.1651)
		(layer "F.Cu")
		(net "M_H_ECC<4>")
	)
	(segment
		(start 71.598282 -42.9006)
		(end 71.31939 -42.9006)
		(width 0.1651)
		(layer "F.Cu")
		(net "M_H_ECC<4>")
	)
	(segment
		(start 68.799456 -30.891734)
		(end 68.799456 -28.531058)
		(width 0.1651)
		(layer "F.Cu")
		(net "M_H_ECC<4>")
	)
	(segment
		(start 70.082664 -34.134806)
		(end 69.803772 -34.134806)
		(width 0.1651)
		(layer "F.Cu")
		(net "M_H_ECC<4>")
	)
	(segment
		(start 70.71741 -43.223688)
		(end 70.520306 -43.026584)
		(width 0.1651)
		(layer "F.Cu")
		(net "M_H_ECC<4>")
	)
	(segment
		(start 70.279768 -32.372046)
		(end 68.799456 -30.891734)
		(width 0.1651)
		(layer "F.Cu")
		(net "M_H_ECC<4>")
	)
	(segment
		(start 70.279768 -34.33191)
		(end 70.082664 -34.134806)
		(width 0.1651)
		(layer "F.Cu")
		(net "M_H_ECC<4>")
	)
	(segment
		(start 70.279768 -33.264602)
		(end 70.279768 -32.372046)
		(width 0.1651)
		(layer "F.Cu")
		(net "M_H_ECC<4>")
	)
	(segment
		(start 81.706466 -48.760888)
		(end 78.523592 -45.578014)
		(width 0.127)
		(layer "F.Cu")
		(net "M_H_ECC<4>")
	)
	(segment
		(start 69.588888 -8.763)
		(end 69.551296 -8.5598)
		(width 0.1651)
		(layer "F.Cu")
		(net "M_H_ECC<4>")
	)
	(segment
		(start 76.810616 -45.209968)
		(end 73.90765 -45.209968)
		(width 0.127)
		(layer "F.Cu")
		(net "M_H_ECC<4>")
	)
	(segment
		(start 69.606668 -33.65881)
		(end 69.803772 -33.461706)
		(width 0.1651)
		(layer "F.Cu")
		(net "M_H_ECC<4>")
	)
	(segment
		(start 70.279768 -34.610802)
		(end 70.279768 -34.33191)
		(width 0.1651)
		(layer "F.Cu")
		(net "M_H_ECC<4>")
	)
	(segment
		(start 77.178662 -45.578014)
		(end 76.810616 -45.209968)
		(width 0.127)
		(layer "F.Cu")
		(net "M_H_ECC<4>")
	)
	(segment
		(start 70.279768 -35.67811)
		(end 70.082664 -35.481006)
		(width 0.1651)
		(layer "F.Cu")
		(net "M_H_ECC<4>")
	)
	(segment
		(start 69.803772 -34.134806)
		(end 69.606668 -33.937702)
		(width 0.1651)
		(layer "F.Cu")
		(net "M_H_ECC<4>")
	)
	(segment
		(start 69.606668 -35.283902)
		(end 69.606668 -35.00501)
		(width 0.1651)
		(layer "F.Cu")
		(net "M_H_ECC<4>")
	)
	(segment
		(start 70.843394 -42.145712)
		(end 70.279768 -41.582086)
		(width 0.1651)
		(layer "F.Cu")
		(net "M_H_ECC<4>")
	)
	(segment
		(start 69.606668 -33.937702)
		(end 69.606668 -33.65881)
		(width 0.1651)
		(layer "F.Cu")
		(net "M_H_ECC<4>")
	)
	(segment
		(start 71.31939 -42.9006)
		(end 70.996302 -43.223688)
		(width 0.1651)
		(layer "F.Cu")
		(net "M_H_ECC<4>")
	)
	(segment
		(start 70.520306 -42.747692)
		(end 70.843394 -42.424604)
		(width 0.1651)
		(layer "F.Cu")
		(net "M_H_ECC<4>")
	)
	(segment
		(start 70.520306 -43.026584)
		(end 70.520306 -42.747692)
		(width 0.1651)
		(layer "F.Cu")
		(net "M_H_ECC<4>")
	)
	(segment
		(start 69.803772 -34.807906)
		(end 70.082664 -34.807906)
		(width 0.1651)
		(layer "F.Cu")
		(net "M_H_ECC<4>")
	)
	(segment
		(start 81.485232 -54.59984)
		(end 80.990186 -53.933852)
		(width 0.0889)
		(layer "F.Cu")
		(net "M_H_ECC<4>")
	)
	(via
		(at 69.551296 -8.5598)
		(size 0.508)
		(drill 0.254)
		(layers "F.Cu" "B.Cu")
		(net "M_H_ECC<4>")
	)
	(via
		(at 68.799456 -13.959078)
		(size 0.508)
		(drill 0.254)
		(layers "F.Cu" "B.Cu")
		(net "M_H_ECC<4>")
	)
	(via
		(at 68.799456 -28.531058)
		(size 0.508)
		(drill 0.254)
		(layers "F.Cu" "B.Cu")
		(net "M_H_ECC<4>")
	)
	(arc
		(start 80.967072 -53.89372)
		(mid 80.894274 -53.602957)
		(end 80.973422 -53.313838)
		(width 0.0889)
		(layer "F.Cu")
		(net "M_H_ECC<4>")
	)
	(arc
		(start 81.07934 -51.56073)
		(mid 81.094121 -51.473131)
		(end 81.133188 -51.393344)
		(width 0.0889)
		(layer "F.Cu")
		(net "M_H_ECC<4>")
	)
	(segment
		(start 68.799456 -15.222982)
		(end 68.799456 -13.959078)
		(width 0.1651)
		(layer "B.Cu")
		(net "M_H_ECC<4>")
	)
	(segment
		(start 69.111368 -12.38123)
		(end 69.111368 -13.647166)
		(width 0.14224)
		(layer "In11.Cu")
		(net "M_H_ECC<4>")
	)
	(segment
		(start 69.282564 -14.442186)
		(end 69.282564 -16.821658)
		(width 0.14224)
		(layer "In11.Cu")
		(net "M_H_ECC<4>")
	)
	(segment
		(start 69.282564 -16.821658)
		(end 69.079364 -17.024858)
		(width 0.14224)
		(layer "In11.Cu")
		(net "M_H_ECC<4>")
	)
	(segment
		(start 69.136768 -21.190204)
		(end 69.282564 -21.336)
		(width 0.14224)
		(layer "In11.Cu")
		(net "M_H_ECC<4>")
	)
	(segment
		(start 68.799456 -13.959078)
		(end 69.282564 -14.442186)
		(width 0.14224)
		(layer "In11.Cu")
		(net "M_H_ECC<4>")
	)
	(segment
		(start 69.079364 -28.25115)
		(end 68.799456 -28.531058)
		(width 0.14224)
		(layer "In11.Cu")
		(net "M_H_ECC<4>")
	)
	(segment
		(start 69.282564 -23.310596)
		(end 69.282564 -26.688796)
		(width 0.14224)
		(layer "In11.Cu")
		(net "M_H_ECC<4>")
	)
	(segment
		(start 69.079364 -26.891996)
		(end 69.079364 -28.25115)
		(width 0.14224)
		(layer "In11.Cu")
		(net "M_H_ECC<4>")
	)
	(segment
		(start 69.274944 -12.217654)
		(end 69.111368 -12.38123)
		(width 0.14224)
		(layer "In11.Cu")
		(net "M_H_ECC<4>")
	)
	(segment
		(start 69.282564 -21.336)
		(end 69.282564 -21.735796)
		(width 0.14224)
		(layer "In11.Cu")
		(net "M_H_ECC<4>")
	)
	(segment
		(start 69.079364 -17.024858)
		(end 69.079364 -18.328386)
		(width 0.14224)
		(layer "In11.Cu")
		(net "M_H_ECC<4>")
	)
	(segment
		(start 69.274944 -8.836152)
		(end 69.274944 -12.217654)
		(width 0.14224)
		(layer "In11.Cu")
		(net "M_H_ECC<4>")
	)
	(segment
		(start 69.282564 -18.531586)
		(end 69.282564 -18.980404)
		(width 0.14224)
		(layer "In11.Cu")
		(net "M_H_ECC<4>")
	)
	(segment
		(start 69.282564 -21.735796)
		(end 69.079364 -21.938996)
		(width 0.14224)
		(layer "In11.Cu")
		(net "M_H_ECC<4>")
	)
	(segment
		(start 69.136768 -19.1262)
		(end 69.136768 -21.190204)
		(width 0.14224)
		(layer "In11.Cu")
		(net "M_H_ECC<4>")
	)
	(segment
		(start 69.282564 -26.688796)
		(end 69.079364 -26.891996)
		(width 0.14224)
		(layer "In11.Cu")
		(net "M_H_ECC<4>")
	)
	(segment
		(start 69.111368 -13.647166)
		(end 68.799456 -13.959078)
		(width 0.14224)
		(layer "In11.Cu")
		(net "M_H_ECC<4>")
	)
	(segment
		(start 69.282564 -18.980404)
		(end 69.136768 -19.1262)
		(width 0.14224)
		(layer "In11.Cu")
		(net "M_H_ECC<4>")
	)
	(segment
		(start 69.551296 -8.5598)
		(end 69.274944 -8.836152)
		(width 0.14224)
		(layer "In11.Cu")
		(net "M_H_ECC<4>")
	)
	(segment
		(start 69.079364 -21.938996)
		(end 69.079364 -23.107396)
		(width 0.14224)
		(layer "In11.Cu")
		(net "M_H_ECC<4>")
	)
	(segment
		(start 69.079364 -18.328386)
		(end 69.282564 -18.531586)
		(width 0.14224)
		(layer "In11.Cu")
		(net "M_H_ECC<4>")
	)
	(segment
		(start 69.079364 -23.107396)
		(end 69.282564 -23.310596)
		(width 0.14224)
		(layer "In11.Cu")
		(net "M_H_ECC<4>")
	)
	(segment
		(start 79.677768 -40.7797)
		(end 79.550768 -40.6527)
		(width 0.1651)
		(layer "F.Cu")
		(net "M_H_ECC<3>")
	)
	(segment
		(start 85.522562 -51.787044)
		(end 85.391498 -52.013104)
		(width 0.0889)
		(layer "F.Cu")
		(net "M_H_ECC<3>")
	)
	(segment
		(start 79.569818 -29.24175)
		(end 79.880968 -29.5529)
		(width 0.1651)
		(layer "F.Cu")
		(net "M_H_ECC<3>")
	)
	(segment
		(start 78.838552 -40.842184)
		(end 78.838552 -41.075102)
		(width 0.127)
		(layer "F.Cu")
		(net "M_H_ECC<3>")
	)
	(segment
		(start 79.550768 -40.6527)
		(end 79.550768 -39.8018)
		(width 0.1651)
		(layer "F.Cu")
		(net "M_H_ECC<3>")
	)
	(segment
		(start 80.084168 -42.358818)
		(end 85.084666 -47.359316)
		(width 0.127)
		(layer "F.Cu")
		(net "M_H_ECC<3>")
	)
	(segment
		(start 79.880968 -29.5529)
		(end 79.880968 -31.5087)
		(width 0.1651)
		(layer "F.Cu")
		(net "M_H_ECC<3>")
	)
	(segment
		(start 85.391498 -52.013104)
		(end 85.391498 -52.215288)
		(width 0.0889)
		(layer "F.Cu")
		(net "M_H_ECC<3>")
	)
	(segment
		(start 79.550768 -39.8018)
		(end 79.296768 -39.5478)
		(width 0.1651)
		(layer "F.Cu")
		(net "M_H_ECC<3>")
	)
	(segment
		(start 85.400642 -51.25212)
		(end 85.522562 -51.463448)
		(width 0.0889)
		(layer "F.Cu")
		(net "M_H_ECC<3>")
	)
	(segment
		(start 85.511894 -50.13198)
		(end 85.511894 -50.76317)
		(width 0.0889)
		(layer "F.Cu")
		(net "M_H_ECC<3>")
	)
	(segment
		(start 84.919312 -54.268116)
		(end 84.919312 -54.59984)
		(width 0.0889)
		(layer "F.Cu")
		(net "M_H_ECC<3>")
	)
	(segment
		(start 77.261212 -27.351736)
		(end 77.679804 -27.351736)
		(width 0.1651)
		(layer "F.Cu")
		(net "M_H_ECC<3>")
	)
	(segment
		(start 84.991702 -54.195726)
		(end 84.919312 -54.268116)
		(width 0.0889)
		(layer "F.Cu")
		(net "M_H_ECC<3>")
	)
	(segment
		(start 85.084666 -47.359316)
		(end 85.084666 -49.492916)
		(width 0.127)
		(layer "F.Cu")
		(net "M_H_ECC<3>")
	)
	(segment
		(start 78.838552 -39.726616)
		(end 78.838552 -40.842184)
		(width 0.1651)
		(layer "F.Cu")
		(net "M_H_ECC<3>")
	)
	(segment
		(start 85.522562 -51.463448)
		(end 85.522562 -51.787044)
		(width 0.0889)
		(layer "F.Cu")
		(net "M_H_ECC<3>")
	)
	(segment
		(start 80.312768 -39.37)
		(end 80.312768 -40.6527)
		(width 0.1651)
		(layer "F.Cu")
		(net "M_H_ECC<3>")
	)
	(segment
		(start 77.679804 -27.351736)
		(end 79.569818 -29.24175)
		(width 0.1651)
		(layer "F.Cu")
		(net "M_H_ECC<3>")
	)
	(segment
		(start 82.090768 -37.592)
		(end 80.312768 -39.37)
		(width 0.1651)
		(layer "F.Cu")
		(net "M_H_ECC<3>")
	)
	(segment
		(start 78.838552 -41.075102)
		(end 80.084168 -42.320718)
		(width 0.127)
		(layer "F.Cu")
		(net "M_H_ECC<3>")
	)
	(segment
		(start 85.400642 -50.955956)
		(end 85.400642 -51.25212)
		(width 0.0889)
		(layer "F.Cu")
		(net "M_H_ECC<3>")
	)
	(segment
		(start 85.511894 -50.76317)
		(end 85.400642 -50.955956)
		(width 0.0889)
		(layer "F.Cu")
		(net "M_H_ECC<3>")
	)
	(segment
		(start 80.084168 -42.320718)
		(end 80.084168 -42.358818)
		(width 0.127)
		(layer "F.Cu")
		(net "M_H_ECC<3>")
	)
	(segment
		(start 85.084666 -49.492916)
		(end 85.511894 -50.13198)
		(width 0.0889)
		(layer "F.Cu")
		(net "M_H_ECC<3>")
	)
	(segment
		(start 82.090768 -33.7185)
		(end 82.090768 -37.592)
		(width 0.1651)
		(layer "F.Cu")
		(net "M_H_ECC<3>")
	)
	(segment
		(start 76.449428 -5.822442)
		(end 76.449428 -7.086346)
		(width 0.1651)
		(layer "F.Cu")
		(net "M_H_ECC<3>")
	)
	(segment
		(start 85.431122 -52.913788)
		(end 85.426296 -52.922424)
		(width 0.0889)
		(layer "F.Cu")
		(net "M_H_ECC<3>")
	)
	(segment
		(start 79.017368 -39.5478)
		(end 78.838552 -39.726616)
		(width 0.1651)
		(layer "F.Cu")
		(net "M_H_ECC<3>")
	)
	(segment
		(start 80.185768 -40.7797)
		(end 79.677768 -40.7797)
		(width 0.1651)
		(layer "F.Cu")
		(net "M_H_ECC<3>")
	)
	(segment
		(start 79.880968 -31.5087)
		(end 82.090768 -33.7185)
		(width 0.1651)
		(layer "F.Cu")
		(net "M_H_ECC<3>")
	)
	(segment
		(start 85.431122 -52.323238)
		(end 85.437472 -52.333906)
		(width 0.0889)
		(layer "F.Cu")
		(net "M_H_ECC<3>")
	)
	(segment
		(start 79.296768 -39.5478)
		(end 79.017368 -39.5478)
		(width 0.1651)
		(layer "F.Cu")
		(net "M_H_ECC<3>")
	)
	(segment
		(start 80.312768 -40.6527)
		(end 80.185768 -40.7797)
		(width 0.1651)
		(layer "F.Cu")
		(net "M_H_ECC<3>")
	)
	(via
		(at 77.299312 -12.678156)
		(size 0.508)
		(drill 0.254)
		(layers "F.Cu" "B.Cu")
		(net "M_H_ECC<3>")
	)
	(via
		(at 76.449428 -7.086346)
		(size 0.508)
		(drill 0.254)
		(layers "F.Cu" "B.Cu")
		(net "M_H_ECC<3>")
	)
	(via
		(at 77.261212 -27.351736)
		(size 0.508)
		(drill 0.254)
		(layers "F.Cu" "B.Cu")
		(net "M_H_ECC<3>")
	)
	(via
		(at 79.569818 -29.24175)
		(size 0.508)
		(drill 0.254)
		(layers "F.Cu" "B.Cu")
		(net "M_H_ECC<3>")
	)
	(arc
		(start 85.431122 -53.313838)
		(mid 85.448232 -53.872784)
		(end 84.991702 -54.195726)
		(width 0.0889)
		(layer "F.Cu")
		(net "M_H_ECC<3>")
	)
	(arc
		(start 85.426296 -52.922424)
		(mid 85.377541 -53.118776)
		(end 85.431122 -53.313838)
		(width 0.0889)
		(layer "F.Cu")
		(net "M_H_ECC<3>")
	)
	(arc
		(start 85.437472 -52.333906)
		(mid 85.51027 -52.624669)
		(end 85.431122 -52.913788)
		(width 0.0889)
		(layer "F.Cu")
		(net "M_H_ECC<3>")
	)
	(arc
		(start 85.391498 -52.215288)
		(mid 85.392513 -52.228779)
		(end 85.395562 -52.241958)
		(width 0.0889)
		(layer "F.Cu")
		(net "M_H_ECC<3>")
	)
	(arc
		(start 85.395562 -52.241958)
		(mid 85.411088 -52.283584)
		(end 85.431122 -52.323238)
		(width 0.0889)
		(layer "F.Cu")
		(net "M_H_ECC<3>")
	)
	(segment
		(start 77.299566 -10.623042)
		(end 77.299312 -10.623296)
		(width 0.1651)
		(layer "B.Cu")
		(net "M_H_ECC<3>")
	)
	(segment
		(start 77.299312 -10.623296)
		(end 77.299312 -12.678156)
		(width 0.1651)
		(layer "B.Cu")
		(net "M_H_ECC<3>")
	)
	(segment
		(start 77.261212 -27.351736)
		(end 77.791564 -26.821384)
		(width 0.14224)
		(layer "In11.Cu")
		(net "M_H_ECC<3>")
	)
	(segment
		(start 77.791564 -19.268186)
		(end 77.613764 -19.090386)
		(width 0.14224)
		(layer "In11.Cu")
		(net "M_H_ECC<3>")
	)
	(segment
		(start 77.613764 -23.285196)
		(end 77.791564 -23.107396)
		(width 0.14224)
		(layer "In11.Cu")
		(net "M_H_ECC<3>")
	)
	(segment
		(start 77.791564 -26.821384)
		(end 77.791564 -26.358596)
		(width 0.14224)
		(layer "In11.Cu")
		(net "M_H_ECC<3>")
	)
	(segment
		(start 77.652118 -12.32535)
		(end 77.652118 -9.020048)
		(width 0.14224)
		(layer "In11.Cu")
		(net "M_H_ECC<3>")
	)
	(segment
		(start 76.832968 -13.5636)
		(end 76.832968 -13.1445)
		(width 0.14224)
		(layer "In11.Cu")
		(net "M_H_ECC<3>")
	)
	(segment
		(start 77.613764 -26.180796)
		(end 77.613764 -23.285196)
		(width 0.14224)
		(layer "In11.Cu")
		(net "M_H_ECC<3>")
	)
	(segment
		(start 77.69225 -14.422882)
		(end 76.832968 -13.5636)
		(width 0.14224)
		(layer "In11.Cu")
		(net "M_H_ECC<3>")
	)
	(segment
		(start 77.807566 -8.509)
		(end 77.350366 -8.0518)
		(width 0.14224)
		(layer "In11.Cu")
		(net "M_H_ECC<3>")
	)
	(segment
		(start 77.613764 -18.599658)
		(end 77.766164 -18.447258)
		(width 0.14224)
		(layer "In11.Cu")
		(net "M_H_ECC<3>")
	)
	(segment
		(start 76.766166 -7.403084)
		(end 76.449428 -7.086346)
		(width 0.14224)
		(layer "In11.Cu")
		(net "M_H_ECC<3>")
	)
	(segment
		(start 77.350366 -8.0518)
		(end 77.096366 -8.0518)
		(width 0.14224)
		(layer "In11.Cu")
		(net "M_H_ECC<3>")
	)
	(segment
		(start 77.791564 -23.107396)
		(end 77.791564 -19.268186)
		(width 0.14224)
		(layer "In11.Cu")
		(net "M_H_ECC<3>")
	)
	(segment
		(start 77.652118 -9.020048)
		(end 77.807566 -8.8646)
		(width 0.14224)
		(layer "In11.Cu")
		(net "M_H_ECC<3>")
	)
	(segment
		(start 77.791564 -26.358596)
		(end 77.613764 -26.180796)
		(width 0.14224)
		(layer "In11.Cu")
		(net "M_H_ECC<3>")
	)
	(segment
		(start 77.096366 -8.0518)
		(end 76.766166 -7.7216)
		(width 0.14224)
		(layer "In11.Cu")
		(net "M_H_ECC<3>")
	)
	(segment
		(start 77.299312 -12.678156)
		(end 77.652118 -12.32535)
		(width 0.14224)
		(layer "In11.Cu")
		(net "M_H_ECC<3>")
	)
	(segment
		(start 77.766164 -18.447258)
		(end 77.766164 -16.604996)
		(width 0.14224)
		(layer "In11.Cu")
		(net "M_H_ECC<3>")
	)
	(segment
		(start 76.766166 -7.7216)
		(end 76.766166 -7.403084)
		(width 0.14224)
		(layer "In11.Cu")
		(net "M_H_ECC<3>")
	)
	(segment
		(start 77.766164 -16.604996)
		(end 77.69225 -16.531082)
		(width 0.14224)
		(layer "In11.Cu")
		(net "M_H_ECC<3>")
	)
	(segment
		(start 77.613764 -19.090386)
		(end 77.613764 -18.599658)
		(width 0.14224)
		(layer "In11.Cu")
		(net "M_H_ECC<3>")
	)
	(segment
		(start 76.832968 -13.1445)
		(end 77.299312 -12.678156)
		(width 0.14224)
		(layer "In11.Cu")
		(net "M_H_ECC<3>")
	)
	(segment
		(start 77.69225 -16.531082)
		(end 77.69225 -14.422882)
		(width 0.14224)
		(layer "In11.Cu")
		(net "M_H_ECC<3>")
	)
	(segment
		(start 77.807566 -8.8646)
		(end 77.807566 -8.509)
		(width 0.14224)
		(layer "In11.Cu")
		(net "M_H_ECC<3>")
	)
	(segment
		(start 85.222842 -52.327048)
		(end 85.212682 -52.299362)
		(width 0.0889)
		(layer "F.Cu")
		(net "M_H_ECC<2>")
	)
	(segment
		(start 85.210142 -51.303428)
		(end 85.210142 -50.904648)
		(width 0.0889)
		(layer "F.Cu")
		(net "M_H_ECC<2>")
	)
	(segment
		(start 77.430884 -9.29386)
		(end 77.430884 -9.07034)
		(width 0.1651)
		(layer "F.Cu")
		(net "M_H_ECC<2>")
	)
	(segment
		(start 85.266022 -52.418488)
		(end 85.259672 -52.40782)
		(width 0.0889)
		(layer "F.Cu")
		(net "M_H_ECC<2>")
	)
	(segment
		(start 77.299312 -9.425432)
		(end 77.430884 -9.29386)
		(width 0.1651)
		(layer "F.Cu")
		(net "M_H_ECC<2>")
	)
	(segment
		(start 78.991968 -32.9311)
		(end 80.096868 -34.036)
		(width 0.1651)
		(layer "F.Cu")
		(net "M_H_ECC<2>")
	)
	(segment
		(start 81.443068 -34.9885)
		(end 81.443068 -37.014658)
		(width 0.1651)
		(layer "F.Cu")
		(net "M_H_ECC<2>")
	)
	(segment
		(start 84.767166 -49.565814)
		(end 84.767166 -47.490888)
		(width 0.1016)
		(layer "F.Cu")
		(net "M_H_ECC<2>")
	)
	(segment
		(start 79.793592 -42.517314)
		(end 84.767166 -47.490888)
		(width 0.1016)
		(layer "F.Cu")
		(net "M_H_ECC<2>")
	)
	(segment
		(start 76.449428 -27.8638)
		(end 77.074268 -27.8638)
		(width 0.1651)
		(layer "F.Cu")
		(net "M_H_ECC<2>")
	)
	(segment
		(start 77.299312 -8.938768)
		(end 77.299312 -8.6614)
		(width 0.1651)
		(layer "F.Cu")
		(net "M_H_ECC<2>")
	)
	(segment
		(start 77.430884 -9.07034)
		(end 77.299312 -8.938768)
		(width 0.1651)
		(layer "F.Cu")
		(net "M_H_ECC<2>")
	)
	(segment
		(start 85.332062 -51.692556)
		(end 85.332062 -51.514756)
		(width 0.0889)
		(layer "F.Cu")
		(net "M_H_ECC<2>")
	)
	(segment
		(start 78.223872 -41.035224)
		(end 79.705962 -42.517314)
		(width 0.1016)
		(layer "F.Cu")
		(net "M_H_ECC<2>")
	)
	(segment
		(start 84.919312 -53.60924)
		(end 84.919312 -53.940964)
		(width 0.0889)
		(layer "F.Cu")
		(net "M_H_ECC<2>")
	)
	(segment
		(start 85.321394 -50.711862)
		(end 85.321394 -50.372772)
		(width 0.0889)
		(layer "F.Cu")
		(net "M_H_ECC<2>")
	)
	(segment
		(start 79.214726 -38.227)
		(end 78.649068 -38.227)
		(width 0.1651)
		(layer "F.Cu")
		(net "M_H_ECC<2>")
	)
	(segment
		(start 78.153768 -40.766238)
		(end 78.223872 -40.836342)
		(width 0.1651)
		(layer "F.Cu")
		(net "M_H_ECC<2>")
	)
	(segment
		(start 78.649068 -38.227)
		(end 78.153768 -38.7223)
		(width 0.1651)
		(layer "F.Cu")
		(net "M_H_ECC<2>")
	)
	(segment
		(start 85.332062 -51.514756)
		(end 85.210142 -51.303428)
		(width 0.0889)
		(layer "F.Cu")
		(net "M_H_ECC<2>")
	)
	(segment
		(start 80.604868 -36.1315)
		(end 80.769968 -35.9664)
		(width 0.1651)
		(layer "F.Cu")
		(net "M_H_ECC<2>")
	)
	(segment
		(start 80.769968 -34.9885)
		(end 80.935068 -34.8234)
		(width 0.1651)
		(layer "F.Cu")
		(net "M_H_ECC<2>")
	)
	(segment
		(start 84.767166 -49.818544)
		(end 84.767166 -49.565814)
		(width 0.0889)
		(layer "F.Cu")
		(net "M_H_ECC<2>")
	)
	(segment
		(start 78.991968 -29.7815)
		(end 78.991968 -32.9311)
		(width 0.1651)
		(layer "F.Cu")
		(net "M_H_ECC<2>")
	)
	(segment
		(start 80.261968 -36.1315)
		(end 80.604868 -36.1315)
		(width 0.1651)
		(layer "F.Cu")
		(net "M_H_ECC<2>")
	)
	(segment
		(start 80.096868 -34.036)
		(end 80.096868 -35.9664)
		(width 0.1651)
		(layer "F.Cu")
		(net "M_H_ECC<2>")
	)
	(segment
		(start 77.677518 -28.46705)
		(end 78.991968 -29.7815)
		(width 0.1651)
		(layer "F.Cu")
		(net "M_H_ECC<2>")
	)
	(segment
		(start 85.210142 -50.904648)
		(end 85.321394 -50.711862)
		(width 0.0889)
		(layer "F.Cu")
		(net "M_H_ECC<2>")
	)
	(segment
		(start 77.299566 -10.422382)
		(end 77.299312 -10.422128)
		(width 0.1651)
		(layer "F.Cu")
		(net "M_H_ECC<2>")
	)
	(segment
		(start 79.705962 -42.517314)
		(end 79.793592 -42.517314)
		(width 0.1016)
		(layer "F.Cu")
		(net "M_H_ECC<2>")
	)
	(segment
		(start 80.769968 -35.9664)
		(end 80.769968 -34.9885)
		(width 0.1651)
		(layer "F.Cu")
		(net "M_H_ECC<2>")
	)
	(segment
		(start 85.321394 -50.372772)
		(end 84.767166 -49.818544)
		(width 0.0889)
		(layer "F.Cu")
		(net "M_H_ECC<2>")
	)
	(segment
		(start 78.223872 -40.836342)
		(end 78.223872 -41.035224)
		(width 0.1016)
		(layer "F.Cu")
		(net "M_H_ECC<2>")
	)
	(segment
		(start 81.277968 -37.179758)
		(end 80.261968 -37.179758)
		(width 0.1651)
		(layer "F.Cu")
		(net "M_H_ECC<2>")
	)
	(segment
		(start 81.277968 -34.8234)
		(end 81.443068 -34.9885)
		(width 0.1651)
		(layer "F.Cu")
		(net "M_H_ECC<2>")
	)
	(segment
		(start 81.443068 -37.014658)
		(end 81.277968 -37.179758)
		(width 0.1651)
		(layer "F.Cu")
		(net "M_H_ECC<2>")
	)
	(segment
		(start 77.074268 -27.8638)
		(end 77.677518 -28.46705)
		(width 0.1651)
		(layer "F.Cu")
		(net "M_H_ECC<2>")
	)
	(segment
		(start 80.935068 -34.8234)
		(end 81.277968 -34.8234)
		(width 0.1651)
		(layer "F.Cu")
		(net "M_H_ECC<2>")
	)
	(segment
		(start 85.197188 -52.212494)
		(end 85.197188 -51.925982)
		(width 0.0889)
		(layer "F.Cu")
		(net "M_H_ECC<2>")
	)
	(segment
		(start 85.197188 -51.925982)
		(end 85.332062 -51.692556)
		(width 0.0889)
		(layer "F.Cu")
		(net "M_H_ECC<2>")
	)
	(segment
		(start 78.153768 -38.7223)
		(end 78.153768 -40.766238)
		(width 0.1651)
		(layer "F.Cu")
		(net "M_H_ECC<2>")
	)
	(segment
		(start 77.299312 -10.422128)
		(end 77.299312 -9.425432)
		(width 0.1651)
		(layer "F.Cu")
		(net "M_H_ECC<2>")
	)
	(segment
		(start 80.096868 -35.9664)
		(end 80.261968 -36.1315)
		(width 0.1651)
		(layer "F.Cu")
		(net "M_H_ECC<2>")
	)
	(segment
		(start 80.261968 -37.179758)
		(end 79.214726 -38.227)
		(width 0.1651)
		(layer "F.Cu")
		(net "M_H_ECC<2>")
	)
	(segment
		(start 84.919312 -53.940964)
		(end 84.982558 -54.00421)
		(width 0.0889)
		(layer "F.Cu")
		(net "M_H_ECC<2>")
	)
	(via
		(at 76.449428 -27.8638)
		(size 0.508)
		(drill 0.254)
		(layers "F.Cu" "B.Cu")
		(net "M_H_ECC<2>")
	)
	(via
		(at 77.299312 -8.6614)
		(size 0.508)
		(drill 0.254)
		(layers "F.Cu" "B.Cu")
		(net "M_H_ECC<2>")
	)
	(via
		(at 76.449428 -13.959078)
		(size 0.508)
		(drill 0.254)
		(layers "F.Cu" "B.Cu")
		(net "M_H_ECC<2>")
	)
	(via
		(at 77.677518 -28.46705)
		(size 0.508)
		(drill 0.254)
		(layers "F.Cu" "B.Cu")
		(net "M_H_ECC<2>")
	)
	(arc
		(start 85.259672 -52.40782)
		(mid 85.239735 -52.368128)
		(end 85.222842 -52.327048)
		(width 0.0889)
		(layer "F.Cu")
		(net "M_H_ECC<2>")
	)
	(arc
		(start 85.266022 -53.409088)
		(mid 85.186891 -53.113686)
		(end 85.266022 -52.818284)
		(width 0.0889)
		(layer "F.Cu")
		(net "M_H_ECC<2>")
	)
	(arc
		(start 85.212682 -52.299362)
		(mid 85.201113 -52.256611)
		(end 85.197188 -52.212494)
		(width 0.0889)
		(layer "F.Cu")
		(net "M_H_ECC<2>")
	)
	(arc
		(start 84.982558 -54.00421)
		(mid 85.280661 -53.781118)
		(end 85.266022 -53.409088)
		(width 0.0889)
		(layer "F.Cu")
		(net "M_H_ECC<2>")
	)
	(arc
		(start 85.266022 -52.818284)
		(mid 85.319521 -52.618386)
		(end 85.266022 -52.418488)
		(width 0.0889)
		(layer "F.Cu")
		(net "M_H_ECC<2>")
	)
	(segment
		(start 76.449428 -15.222982)
		(end 76.449428 -13.959078)
		(width 0.1651)
		(layer "B.Cu")
		(net "M_H_ECC<2>")
	)
	(segment
		(start 77.080364 -14.590014)
		(end 76.449428 -13.959078)
		(width 0.14224)
		(layer "In11.Cu")
		(net "M_H_ECC<2>")
	)
	(segment
		(start 76.807568 -21.164804)
		(end 76.807568 -19.1262)
		(width 0.14224)
		(layer "In11.Cu")
		(net "M_H_ECC<2>")
	)
	(segment
		(start 77.080364 -16.778986)
		(end 77.080364 -14.590014)
		(width 0.14224)
		(layer "In11.Cu")
		(net "M_H_ECC<2>")
	)
	(segment
		(start 76.893166 -9.067546)
		(end 77.299312 -8.6614)
		(width 0.14224)
		(layer "In11.Cu")
		(net "M_H_ECC<2>")
	)
	(segment
		(start 76.893166 -12.320524)
		(end 76.893166 -9.067546)
		(width 0.14224)
		(layer "In11.Cu")
		(net "M_H_ECC<2>")
	)
	(segment
		(start 76.826364 -23.208996)
		(end 76.826364 -21.938996)
		(width 0.14224)
		(layer "In11.Cu")
		(net "M_H_ECC<2>")
	)
	(segment
		(start 76.449428 -13.959078)
		(end 76.132944 -13.642594)
		(width 0.14224)
		(layer "In11.Cu")
		(net "M_H_ECC<2>")
	)
	(segment
		(start 76.132944 -13.080746)
		(end 76.893166 -12.320524)
		(width 0.14224)
		(layer "In11.Cu")
		(net "M_H_ECC<2>")
	)
	(segment
		(start 76.826364 -21.938996)
		(end 76.978764 -21.786596)
		(width 0.14224)
		(layer "In11.Cu")
		(net "M_H_ECC<2>")
	)
	(segment
		(start 76.953364 -26.270204)
		(end 76.953364 -23.335996)
		(width 0.14224)
		(layer "In11.Cu")
		(net "M_H_ECC<2>")
	)
	(segment
		(start 76.449428 -27.8638)
		(end 76.449428 -26.77414)
		(width 0.14224)
		(layer "In11.Cu")
		(net "M_H_ECC<2>")
	)
	(segment
		(start 76.807568 -19.1262)
		(end 76.978764 -18.955004)
		(width 0.14224)
		(layer "In11.Cu")
		(net "M_H_ECC<2>")
	)
	(segment
		(start 76.978764 -18.61185)
		(end 76.775564 -18.40865)
		(width 0.14224)
		(layer "In11.Cu")
		(net "M_H_ECC<2>")
	)
	(segment
		(start 76.775564 -18.40865)
		(end 76.775564 -17.083786)
		(width 0.14224)
		(layer "In11.Cu")
		(net "M_H_ECC<2>")
	)
	(segment
		(start 76.953364 -23.335996)
		(end 76.826364 -23.208996)
		(width 0.14224)
		(layer "In11.Cu")
		(net "M_H_ECC<2>")
	)
	(segment
		(start 76.978764 -21.786596)
		(end 76.978764 -21.336)
		(width 0.14224)
		(layer "In11.Cu")
		(net "M_H_ECC<2>")
	)
	(segment
		(start 76.978764 -18.955004)
		(end 76.978764 -18.61185)
		(width 0.14224)
		(layer "In11.Cu")
		(net "M_H_ECC<2>")
	)
	(segment
		(start 76.775564 -17.083786)
		(end 77.080364 -16.778986)
		(width 0.14224)
		(layer "In11.Cu")
		(net "M_H_ECC<2>")
	)
	(segment
		(start 76.449428 -26.77414)
		(end 76.953364 -26.270204)
		(width 0.14224)
		(layer "In11.Cu")
		(net "M_H_ECC<2>")
	)
	(segment
		(start 76.978764 -21.336)
		(end 76.807568 -21.164804)
		(width 0.14224)
		(layer "In11.Cu")
		(net "M_H_ECC<2>")
	)
	(segment
		(start 76.132944 -13.642594)
		(end 76.132944 -13.080746)
		(width 0.14224)
		(layer "In11.Cu")
		(net "M_H_ECC<2>")
	)
	(segment
		(start 69.924168 -26.162)
		(end 70.101968 -25.9842)
		(width 0.1651)
		(layer "F.Cu")
		(net "M_H_ECC<1>")
	)
	(segment
		(start 77.30617 -44.016168)
		(end 75.51293 -44.016168)
		(width 0.1016)
		(layer "F.Cu")
		(net "M_H_ECC<1>")
	)
	(segment
		(start 70.101968 -25.9842)
		(end 71.006208 -25.9842)
		(width 0.1651)
		(layer "F.Cu")
		(net "M_H_ECC<1>")
	)
	(segment
		(start 70.686168 -28.0162)
		(end 70.406768 -28.0162)
		(width 0.1651)
		(layer "F.Cu")
		(net "M_H_ECC<1>")
	)
	(segment
		(start 82.673444 -52.352448)
		(end 82.690462 -52.323238)
		(width 0.0889)
		(layer "F.Cu")
		(net "M_H_ECC<1>")
	)
	(segment
		(start 78.908148 -44.650914)
		(end 77.940916 -44.650914)
		(width 0.1016)
		(layer "F.Cu")
		(net "M_H_ECC<1>")
	)
	(segment
		(start 82.752692 -50.677064)
		(end 82.633566 -50.557938)
		(width 0.0889)
		(layer "F.Cu")
		(net "M_H_ECC<1>")
	)
	(segment
		(start 82.633566 -48.376332)
		(end 78.908148 -44.650914)
		(width 0.1016)
		(layer "F.Cu")
		(net "M_H_ECC<1>")
	)
	(segment
		(start 73.365868 -32.8676)
		(end 73.365868 -32.486854)
		(width 0.1651)
		(layer "F.Cu")
		(net "M_H_ECC<1>")
	)
	(segment
		(start 75.266804 -43.770042)
		(end 72.972168 -41.475406)
		(width 0.1651)
		(layer "F.Cu")
		(net "M_H_ECC<1>")
	)
	(segment
		(start 72.972168 -35.1028)
		(end 72.972168 -33.2613)
		(width 0.1651)
		(layer "F.Cu")
		(net "M_H_ECC<1>")
	)
	(segment
		(start 70.990968 -28.321)
		(end 70.686168 -28.0162)
		(width 0.1651)
		(layer "F.Cu")
		(net "M_H_ECC<1>")
	)
	(segment
		(start 75.51293 -44.016168)
		(end 75.266804 -43.770042)
		(width 0.1016)
		(layer "F.Cu")
		(net "M_H_ECC<1>")
	)
	(segment
		(start 72.972168 -36.1315)
		(end 73.213468 -35.8902)
		(width 0.1651)
		(layer "F.Cu")
		(net "M_H_ECC<1>")
	)
	(segment
		(start 73.213468 -35.3441)
		(end 72.972168 -35.1028)
		(width 0.1651)
		(layer "F.Cu")
		(net "M_H_ECC<1>")
	)
	(segment
		(start 77.940916 -44.650914)
		(end 77.30617 -44.016168)
		(width 0.1016)
		(layer "F.Cu")
		(net "M_H_ECC<1>")
	)
	(segment
		(start 73.365868 -32.486854)
		(end 70.990968 -30.111954)
		(width 0.1651)
		(layer "F.Cu")
		(net "M_H_ECC<1>")
	)
	(segment
		(start 69.924168 -26.8732)
		(end 69.924168 -26.162)
		(width 0.1651)
		(layer "F.Cu")
		(net "M_H_ECC<1>")
	)
	(segment
		(start 73.213468 -35.8902)
		(end 73.213468 -35.3441)
		(width 0.1651)
		(layer "F.Cu")
		(net "M_H_ECC<1>")
	)
	(segment
		(start 82.633566 -50.557938)
		(end 82.633566 -50.073814)
		(width 0.0889)
		(layer "F.Cu")
		(net "M_H_ECC<1>")
	)
	(segment
		(start 82.343752 -53.113686)
		(end 82.673444 -52.352448)
		(width 0.0889)
		(layer "F.Cu")
		(net "M_H_ECC<1>")
	)
	(segment
		(start 71.171562 -26.149554)
		(end 71.171562 -27.161236)
		(width 0.1651)
		(layer "F.Cu")
		(net "M_H_ECC<1>")
	)
	(segment
		(start 72.972168 -41.475406)
		(end 72.972168 -36.1315)
		(width 0.1651)
		(layer "F.Cu")
		(net "M_H_ECC<1>")
	)
	(segment
		(start 82.752692 -52.084224)
		(end 82.752692 -50.677064)
		(width 0.0889)
		(layer "F.Cu")
		(net "M_H_ECC<1>")
	)
	(segment
		(start 72.972168 -33.2613)
		(end 73.365868 -32.8676)
		(width 0.1651)
		(layer "F.Cu")
		(net "M_H_ECC<1>")
	)
	(segment
		(start 70.076568 -27.0256)
		(end 69.924168 -26.8732)
		(width 0.1651)
		(layer "F.Cu")
		(net "M_H_ECC<1>")
	)
	(segment
		(start 70.076568 -27.686)
		(end 70.076568 -27.0256)
		(width 0.1651)
		(layer "F.Cu")
		(net "M_H_ECC<1>")
	)
	(segment
		(start 70.990968 -30.111954)
		(end 70.990968 -28.321)
		(width 0.1651)
		(layer "F.Cu")
		(net "M_H_ECC<1>")
	)
	(segment
		(start 70.406768 -28.0162)
		(end 70.076568 -27.686)
		(width 0.1651)
		(layer "F.Cu")
		(net "M_H_ECC<1>")
	)
	(segment
		(start 82.633566 -50.073814)
		(end 82.633566 -48.376332)
		(width 0.1016)
		(layer "F.Cu")
		(net "M_H_ECC<1>")
	)
	(segment
		(start 71.006208 -25.9842)
		(end 71.171562 -26.149554)
		(width 0.1651)
		(layer "F.Cu")
		(net "M_H_ECC<1>")
	)
	(segment
		(start 70.499478 -5.822442)
		(end 70.499478 -7.086346)
		(width 0.1651)
		(layer "F.Cu")
		(net "M_H_ECC<1>")
	)
	(via
		(at 71.171562 -12.678156)
		(size 0.508)
		(drill 0.254)
		(layers "F.Cu" "B.Cu")
		(net "M_H_ECC<1>")
	)
	(via
		(at 71.171562 -27.161236)
		(size 0.508)
		(drill 0.254)
		(layers "F.Cu" "B.Cu")
		(net "M_H_ECC<1>")
	)
	(via
		(at 70.499478 -7.086346)
		(size 0.508)
		(drill 0.254)
		(layers "F.Cu" "B.Cu")
		(net "M_H_ECC<1>")
	)
	(arc
		(start 82.690462 -52.323238)
		(mid 82.736918 -52.207722)
		(end 82.752692 -52.084224)
		(width 0.0889)
		(layer "F.Cu")
		(net "M_H_ECC<1>")
	)
	(segment
		(start 71.349362 -10.623042)
		(end 71.349362 -11.997182)
		(width 0.1651)
		(layer "B.Cu")
		(net "M_H_ECC<1>")
	)
	(segment
		(start 71.349362 -11.997182)
		(end 71.171562 -12.174982)
		(width 0.1651)
		(layer "B.Cu")
		(net "M_H_ECC<1>")
	)
	(segment
		(start 71.171562 -12.174982)
		(end 71.171562 -12.678156)
		(width 0.1651)
		(layer "B.Cu")
		(net "M_H_ECC<1>")
	)
	(segment
		(start 71.644764 -19.017996)
		(end 71.829168 -19.2024)
		(width 0.14224)
		(layer "In11.Cu")
		(net "M_H_ECC<1>")
	)
	(segment
		(start 70.736968 -13.11275)
		(end 70.736968 -13.5509)
		(width 0.14224)
		(layer "In11.Cu")
		(net "M_H_ECC<1>")
	)
	(segment
		(start 71.171562 -12.678156)
		(end 70.736968 -13.11275)
		(width 0.14224)
		(layer "In11.Cu")
		(net "M_H_ECC<1>")
	)
	(segment
		(start 71.829168 -19.2024)
		(end 71.829168 -21.151596)
		(width 0.14224)
		(layer "In11.Cu")
		(net "M_H_ECC<1>")
	)
	(segment
		(start 71.702168 -8.8138)
		(end 71.545704 -8.970264)
		(width 0.14224)
		(layer "In11.Cu")
		(net "M_H_ECC<1>")
	)
	(segment
		(start 71.644764 -16.321786)
		(end 71.644764 -19.017996)
		(width 0.14224)
		(layer "In11.Cu")
		(net "M_H_ECC<1>")
	)
	(segment
		(start 70.736968 -13.5509)
		(end 71.022464 -13.836396)
		(width 0.14224)
		(layer "In11.Cu")
		(net "M_H_ECC<1>")
	)
	(segment
		(start 71.022464 -13.836396)
		(end 71.022464 -15.699486)
		(width 0.14224)
		(layer "In11.Cu")
		(net "M_H_ECC<1>")
	)
	(segment
		(start 70.499478 -7.086346)
		(end 70.499478 -7.625334)
		(width 0.14224)
		(layer "In11.Cu")
		(net "M_H_ECC<1>")
	)
	(segment
		(start 71.332344 -8.1026)
		(end 71.702168 -8.472424)
		(width 0.14224)
		(layer "In11.Cu")
		(net "M_H_ECC<1>")
	)
	(segment
		(start 71.545704 -8.970264)
		(end 71.545704 -12.304014)
		(width 0.14224)
		(layer "In11.Cu")
		(net "M_H_ECC<1>")
	)
	(segment
		(start 71.545704 -12.304014)
		(end 71.171562 -12.678156)
		(width 0.14224)
		(layer "In11.Cu")
		(net "M_H_ECC<1>")
	)
	(segment
		(start 71.702168 -8.472424)
		(end 71.702168 -8.8138)
		(width 0.14224)
		(layer "In11.Cu")
		(net "M_H_ECC<1>")
	)
	(segment
		(start 71.022464 -15.699486)
		(end 71.644764 -16.321786)
		(width 0.14224)
		(layer "In11.Cu")
		(net "M_H_ECC<1>")
	)
	(segment
		(start 71.829168 -21.151596)
		(end 71.644764 -21.336)
		(width 0.14224)
		(layer "In11.Cu")
		(net "M_H_ECC<1>")
	)
	(segment
		(start 70.976744 -8.1026)
		(end 71.332344 -8.1026)
		(width 0.14224)
		(layer "In11.Cu")
		(net "M_H_ECC<1>")
	)
	(segment
		(start 71.644764 -26.688034)
		(end 71.171562 -27.161236)
		(width 0.14224)
		(layer "In11.Cu")
		(net "M_H_ECC<1>")
	)
	(segment
		(start 70.499478 -7.625334)
		(end 70.976744 -8.1026)
		(width 0.14224)
		(layer "In11.Cu")
		(net "M_H_ECC<1>")
	)
	(segment
		(start 71.644764 -21.336)
		(end 71.644764 -26.688034)
		(width 0.14224)
		(layer "In11.Cu")
		(net "M_H_ECC<1>")
	)
	(segment
		(start 72.121268 -36.231322)
		(end 71.816468 -36.231322)
		(width 0.1651)
		(layer "F.Cu")
		(net "M_H_ECC<0>")
	)
	(segment
		(start 81.945988 -51.01463)
		(end 82.328766 -50.351182)
		(width 0.0889)
		(layer "F.Cu")
		(net "M_H_ECC<0>")
	)
	(segment
		(start 71.651368 -37.412422)
		(end 71.651368 -37.069522)
		(width 0.1651)
		(layer "F.Cu")
		(net "M_H_ECC<0>")
	)
	(segment
		(start 71.816468 -32.865822)
		(end 72.121268 -32.865822)
		(width 0.1651)
		(layer "F.Cu")
		(net "M_H_ECC<0>")
	)
	(segment
		(start 81.887568 -53.48224)
		(end 81.887568 -53.369972)
		(width 0.0889)
		(layer "F.Cu")
		(net "M_H_ECC<0>")
	)
	(segment
		(start 72.286368 -35.050222)
		(end 72.121268 -34.885122)
		(width 0.1651)
		(layer "F.Cu")
		(net "M_H_ECC<0>")
	)
	(segment
		(start 72.286368 -33.704022)
		(end 72.121268 -33.538922)
		(width 0.1651)
		(layer "F.Cu")
		(net "M_H_ECC<0>")
	)
	(segment
		(start 72.286368 -41.705784)
		(end 72.286368 -39.088822)
		(width 0.1651)
		(layer "F.Cu")
		(net "M_H_ECC<0>")
	)
	(segment
		(start 71.816468 -37.577522)
		(end 71.651368 -37.412422)
		(width 0.1651)
		(layer "F.Cu")
		(net "M_H_ECC<0>")
	)
	(segment
		(start 72.121268 -32.865822)
		(end 72.286368 -32.700722)
		(width 0.1651)
		(layer "F.Cu")
		(net "M_H_ECC<0>")
	)
	(segment
		(start 71.651368 -33.030922)
		(end 71.816468 -32.865822)
		(width 0.1651)
		(layer "F.Cu")
		(net "M_H_ECC<0>")
	)
	(segment
		(start 71.651368 -36.066222)
		(end 71.651368 -35.723322)
		(width 0.1651)
		(layer "F.Cu")
		(net "M_H_ECC<0>")
	)
	(segment
		(start 82.328766 -50.073814)
		(end 82.328766 -48.502824)
		(width 0.1016)
		(layer "F.Cu")
		(net "M_H_ECC<0>")
	)
	(segment
		(start 72.121268 -34.885122)
		(end 71.816468 -34.885122)
		(width 0.1651)
		(layer "F.Cu")
		(net "M_H_ECC<0>")
	)
	(segment
		(start 72.121268 -38.250622)
		(end 72.286368 -38.085522)
		(width 0.1651)
		(layer "F.Cu")
		(net "M_H_ECC<0>")
	)
	(segment
		(start 71.816468 -38.250622)
		(end 72.121268 -38.250622)
		(width 0.1651)
		(layer "F.Cu")
		(net "M_H_ECC<0>")
	)
	(segment
		(start 82.328766 -50.351182)
		(end 82.328766 -50.073814)
		(width 0.0889)
		(layer "F.Cu")
		(net "M_H_ECC<0>")
	)
	(segment
		(start 78.781656 -44.955714)
		(end 77.688694 -44.955714)
		(width 0.1016)
		(layer "F.Cu")
		(net "M_H_ECC<0>")
	)
	(segment
		(start 71.651368 -33.373822)
		(end 71.651368 -33.030922)
		(width 0.1651)
		(layer "F.Cu")
		(net "M_H_ECC<0>")
	)
	(segment
		(start 72.286368 -36.739322)
		(end 72.286368 -36.396422)
		(width 0.1651)
		(layer "F.Cu")
		(net "M_H_ECC<0>")
	)
	(segment
		(start 71.816468 -33.538922)
		(end 71.651368 -33.373822)
		(width 0.1651)
		(layer "F.Cu")
		(net "M_H_ECC<0>")
	)
	(segment
		(start 72.121268 -38.923722)
		(end 71.816468 -38.923722)
		(width 0.1651)
		(layer "F.Cu")
		(net "M_H_ECC<0>")
	)
	(segment
		(start 77.142848 -44.409868)
		(end 74.990452 -44.409868)
		(width 0.1016)
		(layer "F.Cu")
		(net "M_H_ECC<0>")
	)
	(segment
		(start 81.945988 -51.242722)
		(end 81.945988 -51.01463)
		(width 0.0889)
		(layer "F.Cu")
		(net "M_H_ECC<0>")
	)
	(segment
		(start 72.286368 -34.046922)
		(end 72.286368 -33.704022)
		(width 0.1651)
		(layer "F.Cu")
		(net "M_H_ECC<0>")
	)
	(segment
		(start 71.651368 -37.069522)
		(end 71.816468 -36.904422)
		(width 0.1651)
		(layer "F.Cu")
		(net "M_H_ECC<0>")
	)
	(segment
		(start 71.816468 -36.231322)
		(end 71.651368 -36.066222)
		(width 0.1651)
		(layer "F.Cu")
		(net "M_H_ECC<0>")
	)
	(segment
		(start 72.121268 -36.904422)
		(end 72.286368 -36.739322)
		(width 0.1651)
		(layer "F.Cu")
		(net "M_H_ECC<0>")
	)
	(segment
		(start 72.286368 -38.085522)
		(end 72.286368 -37.742622)
		(width 0.1651)
		(layer "F.Cu")
		(net "M_H_ECC<0>")
	)
	(segment
		(start 72.286368 -35.393122)
		(end 72.286368 -35.050222)
		(width 0.1651)
		(layer "F.Cu")
		(net "M_H_ECC<0>")
	)
	(segment
		(start 72.286368 -39.088822)
		(end 72.121268 -38.923722)
		(width 0.1651)
		(layer "F.Cu")
		(net "M_H_ECC<0>")
	)
	(segment
		(start 71.349362 -10.422382)
		(end 71.190866 -8.763)
		(width 0.1651)
		(layer "F.Cu")
		(net "M_H_ECC<0>")
	)
	(segment
		(start 81.943448 -51.989482)
		(end 82.07121 -51.769264)
		(width 0.0889)
		(layer "F.Cu")
		(net "M_H_ECC<0>")
	)
	(segment
		(start 81.485232 -53.60924)
		(end 81.760568 -53.60924)
		(width 0.0889)
		(layer "F.Cu")
		(net "M_H_ECC<0>")
	)
	(segment
		(start 72.286368 -36.396422)
		(end 72.121268 -36.231322)
		(width 0.1651)
		(layer "F.Cu")
		(net "M_H_ECC<0>")
	)
	(segment
		(start 81.760568 -53.60924)
		(end 81.887568 -53.48224)
		(width 0.0889)
		(layer "F.Cu")
		(net "M_H_ECC<0>")
	)
	(segment
		(start 72.121268 -37.577522)
		(end 71.816468 -37.577522)
		(width 0.1651)
		(layer "F.Cu")
		(net "M_H_ECC<0>")
	)
	(segment
		(start 71.651368 -38.758622)
		(end 71.651368 -38.415722)
		(width 0.1651)
		(layer "F.Cu")
		(net "M_H_ECC<0>")
	)
	(segment
		(start 70.305168 -28.725368)
		(end 70.499478 -28.531058)
		(width 0.1651)
		(layer "F.Cu")
		(net "M_H_ECC<0>")
	)
	(segment
		(start 77.688694 -44.955714)
		(end 77.142848 -44.409868)
		(width 0.1016)
		(layer "F.Cu")
		(net "M_H_ECC<0>")
	)
	(segment
		(start 71.816468 -34.212022)
		(end 72.121268 -34.212022)
		(width 0.1651)
		(layer "F.Cu")
		(net "M_H_ECC<0>")
	)
	(segment
		(start 72.286368 -32.700722)
		(end 72.286368 -32.397446)
		(width 0.1651)
		(layer "F.Cu")
		(net "M_H_ECC<0>")
	)
	(segment
		(start 71.816468 -34.885122)
		(end 71.651368 -34.720022)
		(width 0.1651)
		(layer "F.Cu")
		(net "M_H_ECC<0>")
	)
	(segment
		(start 74.832972 -44.252388)
		(end 72.286368 -41.705784)
		(width 0.1651)
		(layer "F.Cu")
		(net "M_H_ECC<0>")
	)
	(segment
		(start 72.121268 -33.538922)
		(end 71.816468 -33.538922)
		(width 0.1651)
		(layer "F.Cu")
		(net "M_H_ECC<0>")
	)
	(segment
		(start 71.816468 -38.923722)
		(end 71.651368 -38.758622)
		(width 0.1651)
		(layer "F.Cu")
		(net "M_H_ECC<0>")
	)
	(segment
		(start 72.286368 -32.397446)
		(end 70.305168 -30.416246)
		(width 0.1651)
		(layer "F.Cu")
		(net "M_H_ECC<0>")
	)
	(segment
		(start 72.121268 -35.558222)
		(end 72.286368 -35.393122)
		(width 0.1651)
		(layer "F.Cu")
		(net "M_H_ECC<0>")
	)
	(segment
		(start 71.651368 -34.377122)
		(end 71.816468 -34.212022)
		(width 0.1651)
		(layer "F.Cu")
		(net "M_H_ECC<0>")
	)
	(segment
		(start 82.07121 -51.769264)
		(end 82.07121 -51.459638)
		(width 0.0889)
		(layer "F.Cu")
		(net "M_H_ECC<0>")
	)
	(segment
		(start 71.816468 -36.904422)
		(end 72.121268 -36.904422)
		(width 0.1651)
		(layer "F.Cu")
		(net "M_H_ECC<0>")
	)
	(segment
		(start 71.651368 -34.720022)
		(end 71.651368 -34.377122)
		(width 0.1651)
		(layer "F.Cu")
		(net "M_H_ECC<0>")
	)
	(segment
		(start 70.305168 -30.416246)
		(end 70.305168 -28.725368)
		(width 0.1651)
		(layer "F.Cu")
		(net "M_H_ECC<0>")
	)
	(segment
		(start 72.286368 -37.742622)
		(end 72.121268 -37.577522)
		(width 0.1651)
		(layer "F.Cu")
		(net "M_H_ECC<0>")
	)
	(segment
		(start 82.07121 -51.459638)
		(end 81.945988 -51.242722)
		(width 0.0889)
		(layer "F.Cu")
		(net "M_H_ECC<0>")
	)
	(segment
		(start 71.816468 -35.558222)
		(end 72.121268 -35.558222)
		(width 0.1651)
		(layer "F.Cu")
		(net "M_H_ECC<0>")
	)
	(segment
		(start 82.328766 -48.502824)
		(end 78.781656 -44.955714)
		(width 0.1016)
		(layer "F.Cu")
		(net "M_H_ECC<0>")
	)
	(segment
		(start 71.651368 -35.723322)
		(end 71.816468 -35.558222)
		(width 0.1651)
		(layer "F.Cu")
		(net "M_H_ECC<0>")
	)
	(segment
		(start 74.990452 -44.409868)
		(end 74.832972 -44.252388)
		(width 0.1016)
		(layer "F.Cu")
		(net "M_H_ECC<0>")
	)
	(segment
		(start 71.190866 -8.763)
		(end 71.171562 -8.5598)
		(width 0.1651)
		(layer "F.Cu")
		(net "M_H_ECC<0>")
	)
	(segment
		(start 72.121268 -34.212022)
		(end 72.286368 -34.046922)
		(width 0.1651)
		(layer "F.Cu")
		(net "M_H_ECC<0>")
	)
	(segment
		(start 81.943448 -52.123594)
		(end 81.943448 -51.989482)
		(width 0.0889)
		(layer "F.Cu")
		(net "M_H_ECC<0>")
	)
	(segment
		(start 71.651368 -38.415722)
		(end 71.816468 -38.250622)
		(width 0.1651)
		(layer "F.Cu")
		(net "M_H_ECC<0>")
	)
	(via
		(at 70.499478 -13.959078)
		(size 0.508)
		(drill 0.254)
		(layers "F.Cu" "B.Cu")
		(net "M_H_ECC<0>")
	)
	(via
		(at 70.499478 -28.531058)
		(size 0.508)
		(drill 0.254)
		(layers "F.Cu" "B.Cu")
		(net "M_H_ECC<0>")
	)
	(via
		(at 71.171562 -8.5598)
		(size 0.508)
		(drill 0.254)
		(layers "F.Cu" "B.Cu")
		(net "M_H_ECC<0>")
	)
	(arc
		(start 82.0039 -52.929282)
		(mid 82.065908 -52.786045)
		(end 82.095848 -52.632864)
		(width 0.0889)
		(layer "F.Cu")
		(net "M_H_ECC<0>")
	)
	(arc
		(start 81.887568 -53.369972)
		(mid 81.917135 -53.142076)
		(end 82.0039 -52.929282)
		(width 0.0889)
		(layer "F.Cu")
		(net "M_H_ECC<0>")
	)
	(arc
		(start 81.992216 -52.314602)
		(mid 81.955883 -52.222148)
		(end 81.943448 -52.123594)
		(width 0.0889)
		(layer "F.Cu")
		(net "M_H_ECC<0>")
	)
	(arc
		(start 82.013552 -52.352194)
		(mid 82.001591 -52.334133)
		(end 81.992216 -52.314602)
		(width 0.0889)
		(layer "F.Cu")
		(net "M_H_ECC<0>")
	)
	(arc
		(start 82.095848 -52.632864)
		(mid 82.081043 -52.484797)
		(end 82.013552 -52.352194)
		(width 0.0889)
		(layer "F.Cu")
		(net "M_H_ECC<0>")
	)
	(segment
		(start 70.499478 -15.222982)
		(end 70.499478 -13.959078)
		(width 0.1651)
		(layer "B.Cu")
		(net "M_H_ECC<0>")
	)
	(segment
		(start 70.499478 -13.959078)
		(end 70.254368 -13.713968)
		(width 0.14224)
		(layer "In11.Cu")
		(net "M_H_ECC<0>")
	)
	(segment
		(start 70.603364 -23.031196)
		(end 70.603364 -22.065996)
		(width 0.14224)
		(layer "In11.Cu")
		(net "M_H_ECC<0>")
	)
	(segment
		(start 70.838568 -21.215604)
		(end 70.838568 -19.2024)
		(width 0.14224)
		(layer "In11.Cu")
		(net "M_H_ECC<0>")
	)
	(segment
		(start 70.738492 -17.067022)
		(end 70.984364 -16.82115)
		(width 0.14224)
		(layer "In11.Cu")
		(net "M_H_ECC<0>")
	)
	(segment
		(start 70.958964 -21.710396)
		(end 70.958964 -21.336)
		(width 0.14224)
		(layer "In11.Cu")
		(net "M_H_ECC<0>")
	)
	(segment
		(start 70.499478 -15.9639)
		(end 70.499478 -13.959078)
		(width 0.14224)
		(layer "In11.Cu")
		(net "M_H_ECC<0>")
	)
	(segment
		(start 70.958964 -18.61185)
		(end 70.704964 -18.35785)
		(width 0.14224)
		(layer "In11.Cu")
		(net "M_H_ECC<0>")
	)
	(segment
		(start 70.704964 -18.35785)
		(end 70.704964 -17.101058)
		(width 0.14224)
		(layer "In11.Cu")
		(net "M_H_ECC<0>")
	)
	(segment
		(start 70.499478 -28.531058)
		(end 70.679564 -28.350972)
		(width 0.14224)
		(layer "In11.Cu")
		(net "M_H_ECC<0>")
	)
	(segment
		(start 70.679564 -26.917396)
		(end 70.958964 -26.637996)
		(width 0.14224)
		(layer "In11.Cu")
		(net "M_H_ECC<0>")
	)
	(segment
		(start 70.679564 -28.350972)
		(end 70.679564 -26.917396)
		(width 0.14224)
		(layer "In11.Cu")
		(net "M_H_ECC<0>")
	)
	(segment
		(start 70.838568 -19.2024)
		(end 70.958964 -19.082004)
		(width 0.14224)
		(layer "In11.Cu")
		(net "M_H_ECC<0>")
	)
	(segment
		(start 70.603364 -22.065996)
		(end 70.958964 -21.710396)
		(width 0.14224)
		(layer "In11.Cu")
		(net "M_H_ECC<0>")
	)
	(segment
		(start 70.984364 -16.82115)
		(end 70.984364 -16.448786)
		(width 0.14224)
		(layer "In11.Cu")
		(net "M_H_ECC<0>")
	)
	(segment
		(start 70.704964 -17.101058)
		(end 70.738492 -17.06753)
		(width 0.14224)
		(layer "In11.Cu")
		(net "M_H_ECC<0>")
	)
	(segment
		(start 70.738492 -17.06753)
		(end 70.738492 -17.067022)
		(width 0.14224)
		(layer "In11.Cu")
		(net "M_H_ECC<0>")
	)
	(segment
		(start 70.958964 -26.637996)
		(end 70.958964 -23.386796)
		(width 0.14224)
		(layer "In11.Cu")
		(net "M_H_ECC<0>")
	)
	(segment
		(start 70.951344 -8.780018)
		(end 71.171562 -8.5598)
		(width 0.14224)
		(layer "In11.Cu")
		(net "M_H_ECC<0>")
	)
	(segment
		(start 70.951344 -12.192)
		(end 70.951344 -8.780018)
		(width 0.14224)
		(layer "In11.Cu")
		(net "M_H_ECC<0>")
	)
	(segment
		(start 70.958964 -19.082004)
		(end 70.958964 -18.61185)
		(width 0.14224)
		(layer "In11.Cu")
		(net "M_H_ECC<0>")
	)
	(segment
		(start 70.958964 -21.336)
		(end 70.838568 -21.215604)
		(width 0.14224)
		(layer "In11.Cu")
		(net "M_H_ECC<0>")
	)
	(segment
		(start 70.254368 -13.713968)
		(end 70.254368 -12.888976)
		(width 0.14224)
		(layer "In11.Cu")
		(net "M_H_ECC<0>")
	)
	(segment
		(start 70.254368 -12.888976)
		(end 70.951344 -12.192)
		(width 0.14224)
		(layer "In11.Cu")
		(net "M_H_ECC<0>")
	)
	(segment
		(start 70.984364 -16.448786)
		(end 70.499478 -15.9639)
		(width 0.14224)
		(layer "In11.Cu")
		(net "M_H_ECC<0>")
	)
	(segment
		(start 70.958964 -23.386796)
		(end 70.603364 -23.031196)
		(width 0.14224)
		(layer "In11.Cu")
		(net "M_H_ECC<0>")
	)
	(segment
		(start 34.363406 -6.875272)
		(end 34.278824 -7.059168)
		(width 0.1651)
		(layer "F.Cu")
		(net "M_H_DQS_DP<9>")
	)
	(segment
		(start 34.278824 -7.059168)
		(end 34.278824 -7.877302)
		(width 0.1651)
		(layer "F.Cu")
		(net "M_H_DQS_DP<9>")
	)
	(segment
		(start 34.799524 -6.439154)
		(end 34.363406 -6.875272)
		(width 0.1651)
		(layer "F.Cu")
		(net "M_H_DQS_DP<9>")
	)
	(segment
		(start 34.360358 -8.101584)
		(end 34.74212 -8.483346)
		(width 0.1651)
		(layer "F.Cu")
		(net "M_H_DQS_DP<9>")
	)
	(segment
		(start 34.799524 -5.822442)
		(end 34.799524 -6.439154)
		(width 0.1651)
		(layer "F.Cu")
		(net "M_H_DQS_DP<9>")
	)
	(segment
		(start 72.041766 -66.982086)
		(end 71.470266 -66.982086)
		(width 0.0889)
		(layer "F.Cu")
		(net "M_H_DQS_DP<9>")
	)
	(segment
		(start 34.278824 -7.877302)
		(end 34.360358 -8.101584)
		(width 0.1651)
		(layer "F.Cu")
		(net "M_H_DQS_DP<9>")
	)
	(via
		(at 34.74212 -8.483346)
		(size 0.508)
		(drill 0.254)
		(layers "F.Cu" "B.Cu")
		(net "M_H_DQS_DP<9>")
	)
	(via
		(at 71.470266 -66.982086)
		(size 0.508)
		(drill 0.254)
		(layers "F.Cu" "B.Cu")
		(net "M_H_DQS_DP<9>")
	)
	(via
		(at 34.74212 -12.573)
		(size 0.508)
		(drill 0.254)
		(layers "F.Cu" "B.Cu")
		(net "M_H_DQS_DP<9>")
	)
	(segment
		(start 34.34334 -14.14907)
		(end 34.266124 -14.016736)
		(width 0.1651)
		(layer "B.Cu")
		(net "M_H_DQS_DP<9>")
	)
	(segment
		(start 34.799524 -15.222982)
		(end 34.799524 -14.605254)
		(width 0.1651)
		(layer "B.Cu")
		(net "M_H_DQS_DP<9>")
	)
	(segment
		(start 34.3535 -12.96162)
		(end 34.74212 -12.573)
		(width 0.1651)
		(layer "B.Cu")
		(net "M_H_DQS_DP<9>")
	)
	(segment
		(start 34.266124 -13.121132)
		(end 34.3535 -12.96162)
		(width 0.1651)
		(layer "B.Cu")
		(net "M_H_DQS_DP<9>")
	)
	(segment
		(start 34.266124 -14.016736)
		(end 34.266124 -13.121132)
		(width 0.1651)
		(layer "B.Cu")
		(net "M_H_DQS_DP<9>")
	)
	(segment
		(start 34.799524 -14.605254)
		(end 34.34334 -14.14907)
		(width 0.1651)
		(layer "B.Cu")
		(net "M_H_DQS_DP<9>")
	)
	(segment
		(start 34.271204 -13.043916)
		(end 34.271204 -15.221712)
		(width 0.14224)
		(layer "In4.Cu")
		(net "M_H_DQS_DP<9>")
	)
	(segment
		(start 35.053524 -10.1854)
		(end 35.261804 -10.39368)
		(width 0.14224)
		(layer "In4.Cu")
		(net "M_H_DQS_DP<9>")
	)
	(segment
		(start 34.898076 -10.8204)
		(end 34.770568 -10.947908)
		(width 0.14224)
		(layer "In4.Cu")
		(net "M_H_DQS_DP<9>")
	)
	(segment
		(start 34.74212 -12.573)
		(end 34.271204 -13.043916)
		(width 0.14224)
		(layer "In4.Cu")
		(net "M_H_DQS_DP<9>")
	)
	(segment
		(start 67.484752 -67.27444)
		(end 67.48399 -67.273678)
		(width 0.0889)
		(layer "In4.Cu")
		(net "M_H_DQS_DP<9>")
	)
	(segment
		(start 35.015424 -11.4427)
		(end 35.261804 -11.68908)
		(width 0.14224)
		(layer "In4.Cu")
		(net "M_H_DQS_DP<9>")
	)
	(segment
		(start 34.770568 -11.286236)
		(end 34.927032 -11.4427)
		(width 0.14224)
		(layer "In4.Cu")
		(net "M_H_DQS_DP<9>")
	)
	(segment
		(start 35.2552 -16.205708)
		(end 35.2552 -27.69108)
		(width 0.14224)
		(layer "In4.Cu")
		(net "M_H_DQS_DP<9>")
	)
	(segment
		(start 68.909692 -68.06819)
		(end 68.876926 -68.06819)
		(width 0.0889)
		(layer "In4.Cu")
		(net "M_H_DQS_DP<9>")
	)
	(segment
		(start 35.563048 -29.800296)
		(end 35.563048 -30.30728)
		(width 0.14224)
		(layer "In4.Cu")
		(net "M_H_DQS_DP<9>")
	)
	(segment
		(start 34.976054 -30.604968)
		(end 34.597848 -30.983174)
		(width 0.14224)
		(layer "In4.Cu")
		(net "M_H_DQS_DP<9>")
	)
	(segment
		(start 34.597848 -30.983174)
		(end 34.597848 -31.842202)
		(width 0.14224)
		(layer "In4.Cu")
		(net "M_H_DQS_DP<9>")
	)
	(segment
		(start 68.047362 -67.572636)
		(end 67.832986 -67.572636)
		(width 0.0889)
		(layer "In4.Cu")
		(net "M_H_DQS_DP<9>")
	)
	(segment
		(start 35.261804 -9.29132)
		(end 34.774124 -9.779)
		(width 0.14224)
		(layer "In4.Cu")
		(net "M_H_DQS_DP<9>")
	)
	(segment
		(start 67.48399 -67.273678)
		(end 67.484498 -67.274694)
		(width 0.0889)
		(layer "In4.Cu")
		(net "M_H_DQS_DP<9>")
	)
	(segment
		(start 39.435532 -41.86301)
		(end 54.293262 -56.72074)
		(width 0.14224)
		(layer "In4.Cu")
		(net "M_H_DQS_DP<9>")
	)
	(segment
		(start 39.435532 -39.90721)
		(end 39.435532 -41.86301)
		(width 0.14224)
		(layer "In4.Cu")
		(net "M_H_DQS_DP<9>")
	)
	(segment
		(start 35.743388 -38.170612)
		(end 36.818062 -39.24554)
		(width 0.14224)
		(layer "In4.Cu")
		(net "M_H_DQS_DP<9>")
	)
	(segment
		(start 34.927032 -11.4427)
		(end 35.015424 -11.4427)
		(width 0.14224)
		(layer "In4.Cu")
		(net "M_H_DQS_DP<9>")
	)
	(segment
		(start 54.737254 -56.72074)
		(end 65.133474 -67.11696)
		(width 0.14224)
		(layer "In4.Cu")
		(net "M_H_DQS_DP<9>")
	)
	(segment
		(start 34.950146 -8.27532)
		(end 35.08121 -8.27532)
		(width 0.14224)
		(layer "In4.Cu")
		(net "M_H_DQS_DP<9>")
	)
	(segment
		(start 67.158108 -67.07759)
		(end 67.157854 -67.077844)
		(width 0.0889)
		(layer "In4.Cu")
		(net "M_H_DQS_DP<9>")
	)
	(segment
		(start 65.133474 -67.11696)
		(end 65.631568 -67.11696)
		(width 0.14224)
		(layer "In4.Cu")
		(net "M_H_DQS_DP<9>")
	)
	(segment
		(start 34.774124 -10.033)
		(end 34.926524 -10.1854)
		(width 0.14224)
		(layer "In4.Cu")
		(net "M_H_DQS_DP<9>")
	)
	(segment
		(start 36.818062 -39.24554)
		(end 38.773862 -39.24554)
		(width 0.14224)
		(layer "In4.Cu")
		(net "M_H_DQS_DP<9>")
	)
	(segment
		(start 35.261804 -11.68908)
		(end 35.261804 -12.332462)
		(width 0.14224)
		(layer "In4.Cu")
		(net "M_H_DQS_DP<9>")
	)
	(segment
		(start 34.597848 -33.965642)
		(end 34.597848 -37.025326)
		(width 0.14224)
		(layer "In4.Cu")
		(net "M_H_DQS_DP<9>")
	)
	(segment
		(start 35.261804 -8.455914)
		(end 35.261804 -9.29132)
		(width 0.14224)
		(layer "In4.Cu")
		(net "M_H_DQS_DP<9>")
	)
	(segment
		(start 35.26536 -32.220408)
		(end 35.486848 -32.441896)
		(width 0.14224)
		(layer "In4.Cu")
		(net "M_H_DQS_DP<9>")
	)
	(segment
		(start 35.563048 -30.30728)
		(end 35.26536 -30.604968)
		(width 0.14224)
		(layer "In4.Cu")
		(net "M_H_DQS_DP<9>")
	)
	(segment
		(start 35.486848 -33.076642)
		(end 34.597848 -33.965642)
		(width 0.14224)
		(layer "In4.Cu")
		(net "M_H_DQS_DP<9>")
	)
	(segment
		(start 34.74212 -8.483346)
		(end 34.950146 -8.27532)
		(width 0.14224)
		(layer "In4.Cu")
		(net "M_H_DQS_DP<9>")
	)
	(segment
		(start 65.693036 -67.07759)
		(end 67.158108 -67.07759)
		(width 0.0889)
		(layer "In4.Cu")
		(net "M_H_DQS_DP<9>")
	)
	(segment
		(start 54.293262 -56.72074)
		(end 54.737254 -56.72074)
		(width 0.14224)
		(layer "In4.Cu")
		(net "M_H_DQS_DP<9>")
	)
	(segment
		(start 69.771514 -68.563236)
		(end 69.734938 -68.563236)
		(width 0.0889)
		(layer "In4.Cu")
		(net "M_H_DQS_DP<9>")
	)
	(segment
		(start 35.486848 -32.441896)
		(end 35.486848 -33.076642)
		(width 0.14224)
		(layer "In4.Cu")
		(net "M_H_DQS_DP<9>")
	)
	(segment
		(start 35.021266 -12.573)
		(end 34.74212 -12.573)
		(width 0.14224)
		(layer "In4.Cu")
		(net "M_H_DQS_DP<9>")
	)
	(segment
		(start 65.653666 -67.11696)
		(end 65.693036 -67.07759)
		(width 0.0889)
		(layer "In4.Cu")
		(net "M_H_DQS_DP<9>")
	)
	(segment
		(start 34.271204 -15.221712)
		(end 35.2552 -16.205708)
		(width 0.14224)
		(layer "In4.Cu")
		(net "M_H_DQS_DP<9>")
	)
	(segment
		(start 34.770568 -10.947908)
		(end 34.770568 -11.286236)
		(width 0.14224)
		(layer "In4.Cu")
		(net "M_H_DQS_DP<9>")
	)
	(segment
		(start 35.261804 -10.39368)
		(end 35.261804 -10.63752)
		(width 0.14224)
		(layer "In4.Cu")
		(net "M_H_DQS_DP<9>")
	)
	(segment
		(start 35.2552 -27.69108)
		(end 34.699448 -28.246832)
		(width 0.14224)
		(layer "In4.Cu")
		(net "M_H_DQS_DP<9>")
	)
	(segment
		(start 35.08121 -8.27532)
		(end 35.261804 -8.455914)
		(width 0.14224)
		(layer "In4.Cu")
		(net "M_H_DQS_DP<9>")
	)
	(segment
		(start 34.926524 -10.1854)
		(end 35.053524 -10.1854)
		(width 0.14224)
		(layer "In4.Cu")
		(net "M_H_DQS_DP<9>")
	)
	(segment
		(start 34.774124 -9.779)
		(end 34.774124 -10.033)
		(width 0.14224)
		(layer "In4.Cu")
		(net "M_H_DQS_DP<9>")
	)
	(segment
		(start 35.078924 -10.8204)
		(end 34.898076 -10.8204)
		(width 0.14224)
		(layer "In4.Cu")
		(net "M_H_DQS_DP<9>")
	)
	(segment
		(start 38.773862 -39.24554)
		(end 39.435532 -39.90721)
		(width 0.14224)
		(layer "In4.Cu")
		(net "M_H_DQS_DP<9>")
	)
	(segment
		(start 34.597848 -31.842202)
		(end 34.976054 -32.220408)
		(width 0.14224)
		(layer "In4.Cu")
		(net "M_H_DQS_DP<9>")
	)
	(segment
		(start 34.699448 -28.246832)
		(end 34.699448 -28.936696)
		(width 0.14224)
		(layer "In4.Cu")
		(net "M_H_DQS_DP<9>")
	)
	(segment
		(start 34.976054 -32.220408)
		(end 35.26536 -32.220408)
		(width 0.14224)
		(layer "In4.Cu")
		(net "M_H_DQS_DP<9>")
	)
	(segment
		(start 34.597848 -37.025326)
		(end 35.743388 -38.170612)
		(width 0.14224)
		(layer "In4.Cu")
		(net "M_H_DQS_DP<9>")
	)
	(segment
		(start 34.699448 -28.936696)
		(end 35.563048 -29.800296)
		(width 0.14224)
		(layer "In4.Cu")
		(net "M_H_DQS_DP<9>")
	)
	(segment
		(start 65.631568 -67.11696)
		(end 65.653666 -67.11696)
		(width 0.0889)
		(layer "In4.Cu")
		(net "M_H_DQS_DP<9>")
	)
	(segment
		(start 35.261804 -10.63752)
		(end 35.078924 -10.8204)
		(width 0.14224)
		(layer "In4.Cu")
		(net "M_H_DQS_DP<9>")
	)
	(segment
		(start 35.26536 -30.604968)
		(end 34.976054 -30.604968)
		(width 0.14224)
		(layer "In4.Cu")
		(net "M_H_DQS_DP<9>")
	)
	(segment
		(start 35.261804 -12.332462)
		(end 35.021266 -12.573)
		(width 0.14224)
		(layer "In4.Cu")
		(net "M_H_DQS_DP<9>")
	)
	(segment
		(start 70.598284 -67.877436)
		(end 70.32498 -68.189094)
		(width 0.0889)
		(layer "In4.Cu")
		(net "M_H_DQS_DP<9>")
	)
	(arc
		(start 69.734938 -68.563236)
		(mid 69.449891 -68.479708)
		(end 69.241416 -68.268088)
		(width 0.0889)
		(layer "In4.Cu")
		(net "M_H_DQS_DP<9>")
	)
	(arc
		(start 71.470266 -66.982086)
		(mid 71.194942 -67.315389)
		(end 70.958456 -67.677284)
		(width 0.0889)
		(layer "In4.Cu")
		(net "M_H_DQS_DP<9>")
	)
	(arc
		(start 68.876926 -68.06819)
		(mid 68.591502 -67.984723)
		(end 68.382896 -67.772788)
		(width 0.0889)
		(layer "In4.Cu")
		(net "M_H_DQS_DP<9>")
	)
	(arc
		(start 67.484498 -67.274694)
		(mid 67.630423 -67.456781)
		(end 67.832986 -67.572636)
		(width 0.0889)
		(layer "In4.Cu")
		(net "M_H_DQS_DP<9>")
	)
	(arc
		(start 68.382896 -67.772788)
		(mid 68.241213 -67.628984)
		(end 68.047362 -67.572636)
		(width 0.0889)
		(layer "In4.Cu")
		(net "M_H_DQS_DP<9>")
	)
	(arc
		(start 70.32498 -68.189094)
		(mid 70.30213 -68.214579)
		(end 70.281546 -68.241926)
		(width 0.0889)
		(layer "In4.Cu")
		(net "M_H_DQS_DP<9>")
	)
	(arc
		(start 69.241416 -68.268088)
		(mid 69.101337 -68.125352)
		(end 68.909692 -68.06819)
		(width 0.0889)
		(layer "In4.Cu")
		(net "M_H_DQS_DP<9>")
	)
	(arc
		(start 70.281546 -68.241926)
		(mid 70.273036 -68.254846)
		(end 70.265036 -68.268088)
		(width 0.0889)
		(layer "In4.Cu")
		(net "M_H_DQS_DP<9>")
	)
	(arc
		(start 70.958456 -67.677284)
		(mid 70.806097 -67.827235)
		(end 70.598284 -67.877436)
		(width 0.0889)
		(layer "In4.Cu")
		(net "M_H_DQS_DP<9>")
	)
	(arc
		(start 67.157854 -67.077844)
		(mid 67.348549 -67.1308)
		(end 67.484752 -67.27444)
		(width 0.0889)
		(layer "In4.Cu")
		(net "M_H_DQS_DP<9>")
	)
	(arc
		(start 70.265036 -68.268088)
		(mid 70.056617 -68.479801)
		(end 69.771514 -68.563236)
		(width 0.0889)
		(layer "In4.Cu")
		(net "M_H_DQS_DP<9>")
	)
	(segment
		(start 73.632568 -29.1592)
		(end 74.165968 -28.6258)
		(width 0.1651)
		(layer "F.Cu")
		(net "M_H_DQS_DP<8>")
	)
	(segment
		(start 76.55306 -42.38371)
		(end 75.931268 -41.761918)
		(width 0.1651)
		(layer "F.Cu")
		(net "M_H_DQS_DP<8>")
	)
	(segment
		(start 76.083668 -33.461706)
		(end 76.083668 -32.263842)
		(width 0.1651)
		(layer "F.Cu")
		(net "M_H_DQS_DP<8>")
	)
	(segment
		(start 75.931268 -41.050718)
		(end 75.448668 -40.568118)
		(width 0.1651)
		(layer "F.Cu")
		(net "M_H_DQS_DP<8>")
	)
	(segment
		(start 76.083668 -33.918398)
		(end 76.185014 -33.817052)
		(width 0.1651)
		(layer "F.Cu")
		(net "M_H_DQS_DP<8>")
	)
	(segment
		(start 77.95895 -42.441368)
		(end 76.610718 -42.441368)
		(width 0.1016)
		(layer "F.Cu")
		(net "M_H_DQS_DP<8>")
	)
	(segment
		(start 83.852766 -50.684176)
		(end 83.852766 -50.073814)
		(width 0.0889)
		(layer "F.Cu")
		(net "M_H_DQS_DP<8>")
	)
	(segment
		(start 76.083668 -36.214558)
		(end 76.210668 -36.087558)
		(width 0.1651)
		(layer "F.Cu")
		(net "M_H_DQS_DP<8>")
	)
	(segment
		(start 75.448668 -39.044118)
		(end 75.448668 -38.790118)
		(width 0.1651)
		(layer "F.Cu")
		(net "M_H_DQS_DP<8>")
	)
	(segment
		(start 83.022186 -54.813708)
		(end 82.891122 -54.813708)
		(width 0.0889)
		(layer "F.Cu")
		(net "M_H_DQS_DP<8>")
	)
	(segment
		(start 75.448668 -39.552118)
		(end 75.575668 -39.425118)
		(width 0.1651)
		(layer "F.Cu")
		(net "M_H_DQS_DP<8>")
	)
	(segment
		(start 75.575668 -39.425118)
		(end 75.575668 -39.171118)
		(width 0.1651)
		(layer "F.Cu")
		(net "M_H_DQS_DP<8>")
	)
	(segment
		(start 73.899522 -9.410446)
		(end 73.937368 -9.3726)
		(width 0.1651)
		(layer "F.Cu")
		(net "M_H_DQS_DP<8>")
	)
	(segment
		(start 73.937368 -9.3726)
		(end 73.937368 -8.001)
		(width 0.1651)
		(layer "F.Cu")
		(net "M_H_DQS_DP<8>")
	)
	(segment
		(start 76.210668 -35.071558)
		(end 76.083668 -34.944558)
		(width 0.1651)
		(layer "F.Cu")
		(net "M_H_DQS_DP<8>")
	)
	(segment
		(start 76.210668 -35.833558)
		(end 76.083668 -35.706558)
		(width 0.1651)
		(layer "F.Cu")
		(net "M_H_DQS_DP<8>")
	)
	(segment
		(start 76.083668 -34.944558)
		(end 76.083668 -34.690558)
		(width 0.1651)
		(layer "F.Cu")
		(net "M_H_DQS_DP<8>")
	)
	(segment
		(start 76.083668 -32.263842)
		(end 75.316588 -31.496762)
		(width 0.1651)
		(layer "F.Cu")
		(net "M_H_DQS_DP<8>")
	)
	(segment
		(start 75.575668 -38.409118)
		(end 75.448668 -38.282118)
		(width 0.1651)
		(layer "F.Cu")
		(net "M_H_DQS_DP<8>")
	)
	(segment
		(start 76.083668 -35.452558)
		(end 76.210668 -35.325558)
		(width 0.1651)
		(layer "F.Cu")
		(net "M_H_DQS_DP<8>")
	)
	(segment
		(start 76.210668 -34.309558)
		(end 76.083668 -34.182558)
		(width 0.1651)
		(layer "F.Cu")
		(net "M_H_DQS_DP<8>")
	)
	(segment
		(start 83.202272 -54.59984)
		(end 83.022186 -54.813708)
		(width 0.0889)
		(layer "F.Cu")
		(net "M_H_DQS_DP<8>")
	)
	(segment
		(start 83.187286 -54.19979)
		(end 83.220052 -54.19979)
		(width 0.0889)
		(layer "F.Cu")
		(net "M_H_DQS_DP<8>")
	)
	(segment
		(start 83.852766 -47.870364)
		(end 79.414116 -43.431714)
		(width 0.1016)
		(layer "F.Cu")
		(net "M_H_DQS_DP<8>")
	)
	(segment
		(start 73.632568 -29.812742)
		(end 73.632568 -29.1592)
		(width 0.1651)
		(layer "F.Cu")
		(net "M_H_DQS_DP<8>")
	)
	(segment
		(start 76.083668 -34.182558)
		(end 76.083668 -33.918398)
		(width 0.1651)
		(layer "F.Cu")
		(net "M_H_DQS_DP<8>")
	)
	(segment
		(start 78.949296 -43.431714)
		(end 77.95895 -42.441368)
		(width 0.1016)
		(layer "F.Cu")
		(net "M_H_DQS_DP<8>")
	)
	(segment
		(start 83.852766 -50.073814)
		(end 83.852766 -47.870364)
		(width 0.1016)
		(layer "F.Cu")
		(net "M_H_DQS_DP<8>")
	)
	(segment
		(start 75.448668 -40.314118)
		(end 75.575668 -40.187118)
		(width 0.1651)
		(layer "F.Cu")
		(net "M_H_DQS_DP<8>")
	)
	(segment
		(start 76.210668 -36.087558)
		(end 76.210668 -35.833558)
		(width 0.1651)
		(layer "F.Cu")
		(net "M_H_DQS_DP<8>")
	)
	(segment
		(start 74.165968 -28.1686)
		(end 74.004424 -28.007056)
		(width 0.1651)
		(layer "F.Cu")
		(net "M_H_DQS_DP<8>")
	)
	(segment
		(start 74.004424 -28.007056)
		(end 73.4441 -28.007056)
		(width 0.1651)
		(layer "F.Cu")
		(net "M_H_DQS_DP<8>")
	)
	(segment
		(start 75.448668 -39.806118)
		(end 75.448668 -39.552118)
		(width 0.1651)
		(layer "F.Cu")
		(net "M_H_DQS_DP<8>")
	)
	(segment
		(start 75.931268 -41.761918)
		(end 75.931268 -41.050718)
		(width 0.1651)
		(layer "F.Cu")
		(net "M_H_DQS_DP<8>")
	)
	(segment
		(start 73.937368 -8.001)
		(end 73.693528 -7.75716)
		(width 0.1651)
		(layer "F.Cu")
		(net "M_H_DQS_DP<8>")
	)
	(segment
		(start 76.210668 -34.563558)
		(end 76.210668 -34.309558)
		(width 0.1651)
		(layer "F.Cu")
		(net "M_H_DQS_DP<8>")
	)
	(segment
		(start 74.565256 -30.559502)
		(end 74.379328 -30.559502)
		(width 0.1651)
		(layer "F.Cu")
		(net "M_H_DQS_DP<8>")
	)
	(segment
		(start 75.448668 -40.568118)
		(end 75.448668 -40.314118)
		(width 0.1651)
		(layer "F.Cu")
		(net "M_H_DQS_DP<8>")
	)
	(segment
		(start 75.931268 -36.620958)
		(end 76.083668 -36.468558)
		(width 0.1651)
		(layer "F.Cu")
		(net "M_H_DQS_DP<8>")
	)
	(segment
		(start 83.720432 -52.333906)
		(end 83.714082 -52.323238)
		(width 0.0889)
		(layer "F.Cu")
		(net "M_H_DQS_DP<8>")
	)
	(segment
		(start 75.316588 -31.496762)
		(end 75.316588 -31.310834)
		(width 0.1651)
		(layer "F.Cu")
		(net "M_H_DQS_DP<8>")
	)
	(segment
		(start 74.165968 -28.6258)
		(end 74.165968 -28.1686)
		(width 0.1651)
		(layer "F.Cu")
		(net "M_H_DQS_DP<8>")
	)
	(segment
		(start 75.575668 -39.933118)
		(end 75.448668 -39.806118)
		(width 0.1651)
		(layer "F.Cu")
		(net "M_H_DQS_DP<8>")
	)
	(segment
		(start 75.931268 -37.481002)
		(end 75.931268 -36.620958)
		(width 0.1651)
		(layer "F.Cu")
		(net "M_H_DQS_DP<8>")
	)
	(segment
		(start 79.414116 -43.431714)
		(end 78.949296 -43.431714)
		(width 0.1016)
		(layer "F.Cu")
		(net "M_H_DQS_DP<8>")
	)
	(segment
		(start 73.899522 -10.422382)
		(end 73.899522 -9.410446)
		(width 0.1651)
		(layer "F.Cu")
		(net "M_H_DQS_DP<8>")
	)
	(segment
		(start 83.716114 -50.929032)
		(end 83.852766 -50.684176)
		(width 0.0889)
		(layer "F.Cu")
		(net "M_H_DQS_DP<8>")
	)
	(segment
		(start 76.083668 -35.706558)
		(end 76.083668 -35.452558)
		(width 0.1651)
		(layer "F.Cu")
		(net "M_H_DQS_DP<8>")
	)
	(segment
		(start 76.610718 -42.441368)
		(end 76.55306 -42.38371)
		(width 0.1016)
		(layer "F.Cu")
		(net "M_H_DQS_DP<8>")
	)
	(segment
		(start 75.448668 -37.963602)
		(end 75.931268 -37.481002)
		(width 0.1651)
		(layer "F.Cu")
		(net "M_H_DQS_DP<8>")
	)
	(segment
		(start 75.448668 -38.282118)
		(end 75.448668 -37.963602)
		(width 0.1651)
		(layer "F.Cu")
		(net "M_H_DQS_DP<8>")
	)
	(segment
		(start 75.575668 -39.171118)
		(end 75.448668 -39.044118)
		(width 0.1651)
		(layer "F.Cu")
		(net "M_H_DQS_DP<8>")
	)
	(segment
		(start 73.693528 -7.75716)
		(end 73.437496 -7.75716)
		(width 0.1651)
		(layer "F.Cu")
		(net "M_H_DQS_DP<8>")
	)
	(segment
		(start 83.660488 -52.124864)
		(end 83.660488 -51.138328)
		(width 0.0889)
		(layer "F.Cu")
		(net "M_H_DQS_DP<8>")
	)
	(segment
		(start 83.709256 -52.922424)
		(end 83.714082 -52.913788)
		(width 0.0889)
		(layer "F.Cu")
		(net "M_H_DQS_DP<8>")
	)
	(segment
		(start 74.379328 -30.559502)
		(end 73.632568 -29.812742)
		(width 0.1651)
		(layer "F.Cu")
		(net "M_H_DQS_DP<8>")
	)
	(segment
		(start 75.575668 -38.663118)
		(end 75.575668 -38.409118)
		(width 0.1651)
		(layer "F.Cu")
		(net "M_H_DQS_DP<8>")
	)
	(segment
		(start 75.316588 -31.310834)
		(end 74.565256 -30.559502)
		(width 0.1651)
		(layer "F.Cu")
		(net "M_H_DQS_DP<8>")
	)
	(segment
		(start 76.185014 -33.817052)
		(end 76.185014 -33.563052)
		(width 0.1651)
		(layer "F.Cu")
		(net "M_H_DQS_DP<8>")
	)
	(segment
		(start 83.714082 -50.932842)
		(end 83.716114 -50.929032)
		(width 0.0889)
		(layer "F.Cu")
		(net "M_H_DQS_DP<8>")
	)
	(segment
		(start 75.575668 -40.187118)
		(end 75.575668 -39.933118)
		(width 0.1651)
		(layer "F.Cu")
		(net "M_H_DQS_DP<8>")
	)
	(segment
		(start 76.083668 -34.690558)
		(end 76.210668 -34.563558)
		(width 0.1651)
		(layer "F.Cu")
		(net "M_H_DQS_DP<8>")
	)
	(segment
		(start 75.448668 -38.790118)
		(end 75.575668 -38.663118)
		(width 0.1651)
		(layer "F.Cu")
		(net "M_H_DQS_DP<8>")
	)
	(segment
		(start 76.185014 -33.563052)
		(end 76.083668 -33.461706)
		(width 0.1651)
		(layer "F.Cu")
		(net "M_H_DQS_DP<8>")
	)
	(segment
		(start 76.210668 -35.325558)
		(end 76.210668 -35.071558)
		(width 0.1651)
		(layer "F.Cu")
		(net "M_H_DQS_DP<8>")
	)
	(segment
		(start 76.083668 -36.468558)
		(end 76.083668 -36.214558)
		(width 0.1651)
		(layer "F.Cu")
		(net "M_H_DQS_DP<8>")
	)
	(via
		(at 73.4441 -28.007056)
		(size 0.508)
		(drill 0.254)
		(layers "F.Cu" "B.Cu")
		(net "M_H_DQS_DP<8>")
	)
	(via
		(at 73.437496 -13.287756)
		(size 0.508)
		(drill 0.254)
		(layers "F.Cu" "B.Cu")
		(net "M_H_DQS_DP<8>")
	)
	(via
		(at 73.437496 -7.75716)
		(size 0.508)
		(drill 0.254)
		(layers "F.Cu" "B.Cu")
		(net "M_H_DQS_DP<8>")
	)
	(arc
		(start 83.660488 -51.138328)
		(mid 83.67341 -51.031966)
		(end 83.714082 -50.932842)
		(width 0.0889)
		(layer "F.Cu")
		(net "M_H_DQS_DP<8>")
	)
	(arc
		(start 83.714082 -53.313838)
		(mid 83.660612 -53.118775)
		(end 83.709256 -52.922424)
		(width 0.0889)
		(layer "F.Cu")
		(net "M_H_DQS_DP<8>")
	)
	(arc
		(start 83.714082 -52.323238)
		(mid 83.674326 -52.22755)
		(end 83.660488 -52.124864)
		(width 0.0889)
		(layer "F.Cu")
		(net "M_H_DQS_DP<8>")
	)
	(arc
		(start 83.220052 -54.19979)
		(mid 83.718303 -53.89695)
		(end 83.714082 -53.313838)
		(width 0.0889)
		(layer "F.Cu")
		(net "M_H_DQS_DP<8>")
	)
	(arc
		(start 82.891122 -54.813708)
		(mid 82.854373 -54.41755)
		(end 83.187286 -54.19979)
		(width 0.0889)
		(layer "F.Cu")
		(net "M_H_DQS_DP<8>")
	)
	(arc
		(start 83.714082 -52.913788)
		(mid 83.793304 -52.62467)
		(end 83.720432 -52.333906)
		(width 0.0889)
		(layer "F.Cu")
		(net "M_H_DQS_DP<8>")
	)
	(segment
		(start 73.937368 -11.811)
		(end 73.937368 -13.0302)
		(width 0.1651)
		(layer "B.Cu")
		(net "M_H_DQS_DP<8>")
	)
	(segment
		(start 73.899522 -11.773154)
		(end 73.937368 -11.811)
		(width 0.1651)
		(layer "B.Cu")
		(net "M_H_DQS_DP<8>")
	)
	(segment
		(start 73.899522 -10.623042)
		(end 73.899522 -11.773154)
		(width 0.1651)
		(layer "B.Cu")
		(net "M_H_DQS_DP<8>")
	)
	(segment
		(start 73.679812 -13.287756)
		(end 73.437496 -13.287756)
		(width 0.1651)
		(layer "B.Cu")
		(net "M_H_DQS_DP<8>")
	)
	(segment
		(start 73.937368 -13.0302)
		(end 73.679812 -13.287756)
		(width 0.1651)
		(layer "B.Cu")
		(net "M_H_DQS_DP<8>")
	)
	(segment
		(start 74.203814 -15.150846)
		(end 73.721214 -14.668246)
		(width 0.14224)
		(layer "In11.Cu")
		(net "M_H_DQS_DP<8>")
	)
	(segment
		(start 73.4441 -28.007056)
		(end 73.4441 -28.000452)
		(width 0.14224)
		(layer "In11.Cu")
		(net "M_H_DQS_DP<8>")
	)
	(segment
		(start 74.248264 -8.567928)
		(end 73.437496 -7.75716)
		(width 0.14224)
		(layer "In11.Cu")
		(net "M_H_DQS_DP<8>")
	)
	(segment
		(start 73.4441 -28.000452)
		(end 74.203814 -27.240738)
		(width 0.14224)
		(layer "In11.Cu")
		(net "M_H_DQS_DP<8>")
	)
	(segment
		(start 73.9013 -14.201394)
		(end 73.9013 -13.75156)
		(width 0.14224)
		(layer "In11.Cu")
		(net "M_H_DQS_DP<8>")
	)
	(segment
		(start 73.437496 -13.287756)
		(end 74.248264 -12.476988)
		(width 0.14224)
		(layer "In11.Cu")
		(net "M_H_DQS_DP<8>")
	)
	(segment
		(start 73.9013 -13.75156)
		(end 73.437496 -13.287756)
		(width 0.14224)
		(layer "In11.Cu")
		(net "M_H_DQS_DP<8>")
	)
	(segment
		(start 74.248264 -12.476988)
		(end 74.248264 -8.567928)
		(width 0.14224)
		(layer "In11.Cu")
		(net "M_H_DQS_DP<8>")
	)
	(segment
		(start 74.203814 -27.240738)
		(end 74.203814 -15.150846)
		(width 0.14224)
		(layer "In11.Cu")
		(net "M_H_DQS_DP<8>")
	)
	(segment
		(start 73.721214 -14.38148)
		(end 73.9013 -14.201394)
		(width 0.14224)
		(layer "In11.Cu")
		(net "M_H_DQS_DP<8>")
	)
	(segment
		(start 73.721214 -14.668246)
		(end 73.721214 -14.38148)
		(width 0.14224)
		(layer "In11.Cu")
		(net "M_H_DQS_DP<8>")
	)
	(segment
		(start 148.071078 -9.10209)
		(end 148.071078 -8.359902)
		(width 0.1651)
		(layer "F.Cu")
		(net "M_H_DQS_DP<7>")
	)
	(segment
		(start 147.661376 -8.146034)
		(end 147.387564 -8.419846)
		(width 0.1651)
		(layer "F.Cu")
		(net "M_H_DQS_DP<7>")
	)
	(segment
		(start 147.849336 -9.323832)
		(end 148.071078 -9.10209)
		(width 0.1651)
		(layer "F.Cu")
		(net "M_H_DQS_DP<7>")
	)
	(segment
		(start 147.85721 -8.146034)
		(end 147.661376 -8.146034)
		(width 0.1651)
		(layer "F.Cu")
		(net "M_H_DQS_DP<7>")
	)
	(segment
		(start 147.849336 -10.422382)
		(end 147.849336 -9.323832)
		(width 0.1651)
		(layer "F.Cu")
		(net "M_H_DQS_DP<7>")
	)
	(segment
		(start 119.929402 -60.857384)
		(end 119.357902 -60.857384)
		(width 0.1016)
		(layer "F.Cu")
		(net "M_H_DQS_DP<7>")
	)
	(segment
		(start 148.071078 -8.359902)
		(end 147.85721 -8.146034)
		(width 0.1651)
		(layer "F.Cu")
		(net "M_H_DQS_DP<7>")
	)
	(via
		(at 147.387564 -8.419846)
		(size 0.508)
		(drill 0.254)
		(layers "F.Cu" "B.Cu")
		(net "M_H_DQS_DP<7>")
	)
	(via
		(at 147.387564 -12.627356)
		(size 0.508)
		(drill 0.254)
		(layers "F.Cu" "B.Cu")
		(net "M_H_DQS_DP<7>")
	)
	(via
		(at 119.357902 -60.857384)
		(size 0.508)
		(drill 0.254)
		(layers "F.Cu" "B.Cu")
		(net "M_H_DQS_DP<7>")
	)
	(segment
		(start 148.029168 -12.319)
		(end 148.029168 -12.76858)
		(width 0.1651)
		(layer "B.Cu")
		(net "M_H_DQS_DP<7>")
	)
	(segment
		(start 147.889468 -12.90828)
		(end 147.668488 -12.90828)
		(width 0.1651)
		(layer "B.Cu")
		(net "M_H_DQS_DP<7>")
	)
	(segment
		(start 147.849336 -10.623042)
		(end 147.849336 -12.139168)
		(width 0.1651)
		(layer "B.Cu")
		(net "M_H_DQS_DP<7>")
	)
	(segment
		(start 147.849336 -12.139168)
		(end 148.029168 -12.319)
		(width 0.1651)
		(layer "B.Cu")
		(net "M_H_DQS_DP<7>")
	)
	(segment
		(start 147.668488 -12.90828)
		(end 147.387564 -12.627356)
		(width 0.1651)
		(layer "B.Cu")
		(net "M_H_DQS_DP<7>")
	)
	(segment
		(start 148.029168 -12.76858)
		(end 147.889468 -12.90828)
		(width 0.1651)
		(layer "B.Cu")
		(net "M_H_DQS_DP<7>")
	)
	(segment
		(start 121.421398 -54.713886)
		(end 121.415048 -54.703218)
		(width 0.0889)
		(layer "In4.Cu")
		(net "M_H_DQS_DP<7>")
	)
	(segment
		(start 147.929092 -9.345422)
		(end 147.929092 -8.679688)
		(width 0.14224)
		(layer "In4.Cu")
		(net "M_H_DQS_DP<7>")
	)
	(segment
		(start 147.900644 -15.95755)
		(end 146.942048 -14.998954)
		(width 0.14224)
		(layer "In4.Cu")
		(net "M_H_DQS_DP<7>")
	)
	(segment
		(start 121.421398 -55.704486)
		(end 121.415048 -55.693818)
		(width 0.0889)
		(layer "In4.Cu")
		(net "M_H_DQS_DP<7>")
	)
	(segment
		(start 147.441412 -11.303)
		(end 147.441412 -11.049)
		(width 0.14224)
		(layer "In4.Cu")
		(net "M_H_DQS_DP<7>")
	)
	(segment
		(start 147.746212 -10.8712)
		(end 147.929092 -10.68832)
		(width 0.14224)
		(layer "In4.Cu")
		(net "M_H_DQS_DP<7>")
	)
	(segment
		(start 147.619212 -11.4808)
		(end 147.441412 -11.303)
		(width 0.14224)
		(layer "In4.Cu")
		(net "M_H_DQS_DP<7>")
	)
	(segment
		(start 147.666456 -12.62761)
		(end 147.929092 -12.364974)
		(width 0.14224)
		(layer "In4.Cu")
		(net "M_H_DQS_DP<7>")
	)
	(segment
		(start 146.306286 -29.452316)
		(end 146.306286 -29.452062)
		(width 0.14224)
		(layer "In4.Cu")
		(net "M_H_DQS_DP<7>")
	)
	(segment
		(start 146.942048 -14.998954)
		(end 146.942048 -13.072872)
		(width 0.14224)
		(layer "In4.Cu")
		(net "M_H_DQS_DP<7>")
	)
	(segment
		(start 145.726912 -30.031944)
		(end 146.306286 -29.452316)
		(width 0.14224)
		(layer "In4.Cu")
		(net "M_H_DQS_DP<7>")
	)
	(segment
		(start 147.900644 -27.857704)
		(end 147.900644 -15.95755)
		(width 0.14224)
		(layer "In4.Cu")
		(net "M_H_DQS_DP<7>")
	)
	(segment
		(start 147.66925 -8.419846)
		(end 147.387564 -8.419846)
		(width 0.14224)
		(layer "In4.Cu")
		(net "M_H_DQS_DP<7>")
	)
	(segment
		(start 144.554448 -33.146238)
		(end 144.554448 -31.204154)
		(width 0.14224)
		(layer "In4.Cu")
		(net "M_H_DQS_DP<7>")
	)
	(segment
		(start 144.554448 -31.204154)
		(end 145.117312 -30.641544)
		(width 0.14224)
		(layer "In4.Cu")
		(net "M_H_DQS_DP<7>")
	)
	(segment
		(start 125.350016 -50.415952)
		(end 125.569726 -50.196242)
		(width 0.14224)
		(layer "In4.Cu")
		(net "M_H_DQS_DP<7>")
	)
	(segment
		(start 121.421398 -56.695086)
		(end 121.415048 -56.684418)
		(width 0.0889)
		(layer "In4.Cu")
		(net "M_H_DQS_DP<7>")
	)
	(segment
		(start 121.426224 -53.731922)
		(end 121.421398 -53.723286)
		(width 0.0889)
		(layer "In4.Cu")
		(net "M_H_DQS_DP<7>")
	)
	(segment
		(start 121.911618 -52.837334)
		(end 121.951242 -52.837334)
		(width 0.0889)
		(layer "In4.Cu")
		(net "M_H_DQS_DP<7>")
	)
	(segment
		(start 125.749558 -49.854866)
		(end 125.911102 -49.854866)
		(width 0.14224)
		(layer "In4.Cu")
		(net "M_H_DQS_DP<7>")
	)
	(segment
		(start 147.387564 -12.62761)
		(end 147.666456 -12.62761)
		(width 0.14224)
		(layer "In4.Cu")
		(net "M_H_DQS_DP<7>")
	)
	(segment
		(start 147.441412 -11.049)
		(end 147.619212 -10.8712)
		(width 0.14224)
		(layer "In4.Cu")
		(net "M_H_DQS_DP<7>")
	)
	(segment
		(start 124.165614 -51.600354)
		(end 124.181362 -51.584606)
		(width 0.0889)
		(layer "In4.Cu")
		(net "M_H_DQS_DP<7>")
	)
	(segment
		(start 147.394168 -9.981946)
		(end 147.394168 -9.677654)
		(width 0.14224)
		(layer "In4.Cu")
		(net "M_H_DQS_DP<7>")
	)
	(segment
		(start 147.929092 -11.660124)
		(end 147.749768 -11.4808)
		(width 0.14224)
		(layer "In4.Cu")
		(net "M_H_DQS_DP<7>")
	)
	(segment
		(start 146.942048 -13.072872)
		(end 147.387564 -12.627356)
		(width 0.14224)
		(layer "In4.Cu")
		(net "M_H_DQS_DP<7>")
	)
	(segment
		(start 122.763534 -52.15382)
		(end 123.668028 -52.15382)
		(width 0.0889)
		(layer "In4.Cu")
		(net "M_H_DQS_DP<7>")
	)
	(segment
		(start 147.546822 -10.1346)
		(end 147.394168 -9.981946)
		(width 0.14224)
		(layer "In4.Cu")
		(net "M_H_DQS_DP<7>")
	)
	(segment
		(start 147.929092 -8.679688)
		(end 147.66925 -8.419846)
		(width 0.14224)
		(layer "In4.Cu")
		(net "M_H_DQS_DP<7>")
	)
	(segment
		(start 147.724114 -10.1346)
		(end 147.546822 -10.1346)
		(width 0.14224)
		(layer "In4.Cu")
		(net "M_H_DQS_DP<7>")
	)
	(segment
		(start 147.387564 -12.627356)
		(end 147.387564 -12.62761)
		(width 0.14224)
		(layer "In4.Cu")
		(net "M_H_DQS_DP<7>")
	)
	(segment
		(start 125.569726 -50.034698)
		(end 125.749558 -49.854866)
		(width 0.14224)
		(layer "In4.Cu")
		(net "M_H_DQS_DP<7>")
	)
	(segment
		(start 124.364496 -51.239674)
		(end 124.544328 -51.059842)
		(width 0.14224)
		(layer "In4.Cu")
		(net "M_H_DQS_DP<7>")
	)
	(segment
		(start 119.357902 -60.857384)
		(end 119.357902 -61.195458)
		(width 0.0889)
		(layer "In4.Cu")
		(net "M_H_DQS_DP<7>")
	)
	(segment
		(start 128.840738 -46.92523)
		(end 130.775456 -46.92523)
		(width 0.14224)
		(layer "In4.Cu")
		(net "M_H_DQS_DP<7>")
	)
	(segment
		(start 121.061734 -58.285634)
		(end 121.089674 -58.285634)
		(width 0.0889)
		(layer "In4.Cu")
		(net "M_H_DQS_DP<7>")
	)
	(segment
		(start 125.911102 -49.854866)
		(end 128.840738 -46.92523)
		(width 0.14224)
		(layer "In4.Cu")
		(net "M_H_DQS_DP<7>")
	)
	(segment
		(start 121.426224 -55.713122)
		(end 121.421398 -55.704486)
		(width 0.0889)
		(layer "In4.Cu")
		(net "M_H_DQS_DP<7>")
	)
	(segment
		(start 121.421398 -57.685686)
		(end 121.415048 -57.675018)
		(width 0.0889)
		(layer "In4.Cu")
		(net "M_H_DQS_DP<7>")
	)
	(segment
		(start 147.546822 -9.525)
		(end 147.749514 -9.525)
		(width 0.14224)
		(layer "In4.Cu")
		(net "M_H_DQS_DP<7>")
	)
	(segment
		(start 124.165614 -51.656234)
		(end 124.165614 -51.600354)
		(width 0.0889)
		(layer "In4.Cu")
		(net "M_H_DQS_DP<7>")
	)
	(segment
		(start 120.198388 -58.780934)
		(end 120.234202 -58.780934)
		(width 0.0889)
		(layer "In4.Cu")
		(net "M_H_DQS_DP<7>")
	)
	(segment
		(start 123.668028 -52.15382)
		(end 124.165614 -51.656234)
		(width 0.0889)
		(layer "In4.Cu")
		(net "M_H_DQS_DP<7>")
	)
	(segment
		(start 130.775456 -46.92523)
		(end 144.554448 -33.146238)
		(width 0.14224)
		(layer "In4.Cu")
		(net "M_H_DQS_DP<7>")
	)
	(segment
		(start 147.619212 -10.8712)
		(end 147.746212 -10.8712)
		(width 0.14224)
		(layer "In4.Cu")
		(net "M_H_DQS_DP<7>")
	)
	(segment
		(start 121.426224 -57.694322)
		(end 121.421398 -57.685686)
		(width 0.0889)
		(layer "In4.Cu")
		(net "M_H_DQS_DP<7>")
	)
	(segment
		(start 124.544328 -51.059842)
		(end 124.706126 -51.059842)
		(width 0.14224)
		(layer "In4.Cu")
		(net "M_H_DQS_DP<7>")
	)
	(segment
		(start 125.008386 -50.757582)
		(end 125.008386 -50.595784)
		(width 0.14224)
		(layer "In4.Cu")
		(net "M_H_DQS_DP<7>")
	)
	(segment
		(start 121.426224 -54.722522)
		(end 121.421398 -54.713886)
		(width 0.0889)
		(layer "In4.Cu")
		(net "M_H_DQS_DP<7>")
	)
	(segment
		(start 147.749768 -11.4808)
		(end 147.619212 -11.4808)
		(width 0.14224)
		(layer "In4.Cu")
		(net "M_H_DQS_DP<7>")
	)
	(segment
		(start 121.426224 -56.703722)
		(end 121.421398 -56.695086)
		(width 0.0889)
		(layer "In4.Cu")
		(net "M_H_DQS_DP<7>")
	)
	(segment
		(start 125.569726 -50.196242)
		(end 125.569726 -50.034698)
		(width 0.14224)
		(layer "In4.Cu")
		(net "M_H_DQS_DP<7>")
	)
	(segment
		(start 124.181362 -51.584606)
		(end 124.364496 -51.401472)
		(width 0.14224)
		(layer "In4.Cu")
		(net "M_H_DQS_DP<7>")
	)
	(segment
		(start 145.117312 -30.641544)
		(end 145.726912 -30.031944)
		(width 0.14224)
		(layer "In4.Cu")
		(net "M_H_DQS_DP<7>")
	)
	(segment
		(start 124.706126 -51.059842)
		(end 125.008386 -50.757582)
		(width 0.14224)
		(layer "In4.Cu")
		(net "M_H_DQS_DP<7>")
	)
	(segment
		(start 125.008386 -50.595784)
		(end 125.188218 -50.415952)
		(width 0.14224)
		(layer "In4.Cu")
		(net "M_H_DQS_DP<7>")
	)
	(segment
		(start 122.279918 -52.637436)
		(end 122.763534 -52.15382)
		(width 0.0889)
		(layer "In4.Cu")
		(net "M_H_DQS_DP<7>")
	)
	(segment
		(start 146.306286 -29.452062)
		(end 147.900644 -27.857704)
		(width 0.14224)
		(layer "In4.Cu")
		(net "M_H_DQS_DP<7>")
	)
	(segment
		(start 147.929092 -12.364974)
		(end 147.929092 -11.660124)
		(width 0.14224)
		(layer "In4.Cu")
		(net "M_H_DQS_DP<7>")
	)
	(segment
		(start 124.364496 -51.401472)
		(end 124.364496 -51.239674)
		(width 0.14224)
		(layer "In4.Cu")
		(net "M_H_DQS_DP<7>")
	)
	(segment
		(start 125.188218 -50.415952)
		(end 125.350016 -50.415952)
		(width 0.14224)
		(layer "In4.Cu")
		(net "M_H_DQS_DP<7>")
	)
	(segment
		(start 119.357902 -61.195458)
		(end 119.41556 -61.253116)
		(width 0.0889)
		(layer "In4.Cu")
		(net "M_H_DQS_DP<7>")
	)
	(segment
		(start 147.929092 -10.68832)
		(end 147.929092 -10.339578)
		(width 0.14224)
		(layer "In4.Cu")
		(net "M_H_DQS_DP<7>")
	)
	(segment
		(start 147.749514 -9.525)
		(end 147.929092 -9.345422)
		(width 0.14224)
		(layer "In4.Cu")
		(net "M_H_DQS_DP<7>")
	)
	(segment
		(start 119.704358 -60.657486)
		(end 119.695468 -60.642246)
		(width 0.0889)
		(layer "In4.Cu")
		(net "M_H_DQS_DP<7>")
	)
	(segment
		(start 147.929092 -10.339578)
		(end 147.724114 -10.1346)
		(width 0.14224)
		(layer "In4.Cu")
		(net "M_H_DQS_DP<7>")
	)
	(segment
		(start 147.394168 -9.677654)
		(end 147.546822 -9.525)
		(width 0.14224)
		(layer "In4.Cu")
		(net "M_H_DQS_DP<7>")
	)
	(arc
		(start 121.415048 -57.675018)
		(mid 121.34225 -57.384255)
		(end 121.421398 -57.095136)
		(width 0.0889)
		(layer "In4.Cu")
		(net "M_H_DQS_DP<7>")
	)
	(arc
		(start 121.951242 -52.837334)
		(mid 122.141171 -52.779464)
		(end 122.279918 -52.637436)
		(width 0.0889)
		(layer "In4.Cu")
		(net "M_H_DQS_DP<7>")
	)
	(arc
		(start 121.421398 -57.095136)
		(mid 121.474868 -56.900073)
		(end 121.426224 -56.703722)
		(width 0.0889)
		(layer "In4.Cu")
		(net "M_H_DQS_DP<7>")
	)
	(arc
		(start 121.415048 -55.693818)
		(mid 121.34225 -55.403055)
		(end 121.421398 -55.113936)
		(width 0.0889)
		(layer "In4.Cu")
		(net "M_H_DQS_DP<7>")
	)
	(arc
		(start 121.421398 -55.113936)
		(mid 121.474868 -54.918873)
		(end 121.426224 -54.722522)
		(width 0.0889)
		(layer "In4.Cu")
		(net "M_H_DQS_DP<7>")
	)
	(arc
		(start 120.234202 -58.780934)
		(mid 120.424131 -58.723064)
		(end 120.562878 -58.581036)
		(width 0.0889)
		(layer "In4.Cu")
		(net "M_H_DQS_DP<7>")
	)
	(arc
		(start 119.695468 -60.642246)
		(mid 119.625071 -60.353295)
		(end 119.704358 -60.066682)
		(width 0.0889)
		(layer "In4.Cu")
		(net "M_H_DQS_DP<7>")
	)
	(arc
		(start 119.704104 -61.057282)
		(mid 119.757798 -60.857413)
		(end 119.704358 -60.657486)
		(width 0.0889)
		(layer "In4.Cu")
		(net "M_H_DQS_DP<7>")
	)
	(arc
		(start 120.562878 -58.581036)
		(mid 120.773591 -58.367957)
		(end 121.061734 -58.285634)
		(width 0.0889)
		(layer "In4.Cu")
		(net "M_H_DQS_DP<7>")
	)
	(arc
		(start 119.704358 -60.066682)
		(mid 119.757891 -59.866784)
		(end 119.704358 -59.666886)
		(width 0.0889)
		(layer "In4.Cu")
		(net "M_H_DQS_DP<7>")
	)
	(arc
		(start 119.41556 -61.253116)
		(mid 119.582283 -61.188287)
		(end 119.704104 -61.057282)
		(width 0.0889)
		(layer "In4.Cu")
		(net "M_H_DQS_DP<7>")
	)
	(arc
		(start 121.421398 -53.723286)
		(mid 121.416144 -53.141778)
		(end 121.911618 -52.837334)
		(width 0.0889)
		(layer "In4.Cu")
		(net "M_H_DQS_DP<7>")
	)
	(arc
		(start 121.421398 -54.123336)
		(mid 121.474868 -53.928273)
		(end 121.426224 -53.731922)
		(width 0.0889)
		(layer "In4.Cu")
		(net "M_H_DQS_DP<7>")
	)
	(arc
		(start 121.415048 -54.703218)
		(mid 121.34225 -54.412455)
		(end 121.421398 -54.123336)
		(width 0.0889)
		(layer "In4.Cu")
		(net "M_H_DQS_DP<7>")
	)
	(arc
		(start 119.704358 -59.666886)
		(mid 119.700029 -59.083714)
		(end 120.198388 -58.780934)
		(width 0.0889)
		(layer "In4.Cu")
		(net "M_H_DQS_DP<7>")
	)
	(arc
		(start 121.421398 -56.104536)
		(mid 121.474868 -55.909473)
		(end 121.426224 -55.713122)
		(width 0.0889)
		(layer "In4.Cu")
		(net "M_H_DQS_DP<7>")
	)
	(arc
		(start 121.415048 -56.684418)
		(mid 121.34225 -56.393655)
		(end 121.421398 -56.104536)
		(width 0.0889)
		(layer "In4.Cu")
		(net "M_H_DQS_DP<7>")
	)
	(arc
		(start 121.089674 -58.285634)
		(mid 121.422592 -58.083643)
		(end 121.426224 -57.694322)
		(width 0.0889)
		(layer "In4.Cu")
		(net "M_H_DQS_DP<7>")
	)
	(segment
		(start 134.420356 -41.176702)
		(end 134.420356 -40.99687)
		(width 0.1651)
		(layer "F.Cu")
		(net "M_H_DQS_DP<6>")
	)
	(segment
		(start 118.920006 -53.69052)
		(end 118.774972 -53.69052)
		(width 0.0889)
		(layer "F.Cu")
		(net "M_H_DQS_DP<6>")
	)
	(segment
		(start 137.885424 -29.473144)
		(end 138.504168 -28.8544)
		(width 0.1651)
		(layer "F.Cu")
		(net "M_H_DQS_DP<6>")
	)
	(segment
		(start 138.504168 -28.8544)
		(end 138.504168 -28.209494)
		(width 0.1651)
		(layer "F.Cu")
		(net "M_H_DQS_DP<6>")
	)
	(segment
		(start 135.537702 -40.059356)
		(end 135.537702 -39.879524)
		(width 0.1651)
		(layer "F.Cu")
		(net "M_H_DQS_DP<6>")
	)
	(segment
		(start 120.443498 -49.6824)
		(end 122.969274 -47.156624)
		(width 0.1016)
		(layer "F.Cu")
		(net "M_H_DQS_DP<6>")
	)
	(segment
		(start 133.881368 -41.535858)
		(end 134.060946 -41.35628)
		(width 0.1651)
		(layer "F.Cu")
		(net "M_H_DQS_DP<6>")
	)
	(segment
		(start 135.896858 -39.699946)
		(end 136.07669 -39.520368)
		(width 0.1651)
		(layer "F.Cu")
		(net "M_H_DQS_DP<6>")
	)
	(segment
		(start 138.381486 -34.29)
		(end 138.381486 -30.33903)
		(width 0.1651)
		(layer "F.Cu")
		(net "M_H_DQS_DP<6>")
	)
	(segment
		(start 120.077992 -49.6824)
		(end 120.443498 -49.6824)
		(width 0.0889)
		(layer "F.Cu")
		(net "M_H_DQS_DP<6>")
	)
	(segment
		(start 133.87324 -41.867328)
		(end 133.881368 -41.8592)
		(width 0.1016)
		(layer "F.Cu")
		(net "M_H_DQS_DP<6>")
	)
	(segment
		(start 119.52097 -51.014884)
		(end 119.52097 -50.239422)
		(width 0.0889)
		(layer "F.Cu")
		(net "M_H_DQS_DP<6>")
	)
	(segment
		(start 138.499596 -9.410446)
		(end 138.537442 -9.3726)
		(width 0.1651)
		(layer "F.Cu")
		(net "M_H_DQS_DP<6>")
	)
	(segment
		(start 133.87324 -43.087798)
		(end 133.87324 -41.867328)
		(width 0.1016)
		(layer "F.Cu")
		(net "M_H_DQS_DP<6>")
	)
	(segment
		(start 118.774972 -53.69052)
		(end 118.745762 -53.66131)
		(width 0.0889)
		(layer "F.Cu")
		(net "M_H_DQS_DP<6>")
	)
	(segment
		(start 134.978902 -40.438324)
		(end 135.178292 -40.238934)
		(width 0.1651)
		(layer "F.Cu")
		(net "M_H_DQS_DP<6>")
	)
	(segment
		(start 119.52097 -50.239422)
		(end 120.077992 -49.6824)
		(width 0.0889)
		(layer "F.Cu")
		(net "M_H_DQS_DP<6>")
	)
	(segment
		(start 119.070882 -53.427884)
		(end 118.920006 -53.69052)
		(width 0.0889)
		(layer "F.Cu")
		(net "M_H_DQS_DP<6>")
	)
	(segment
		(start 137.885424 -29.842968)
		(end 137.885424 -29.473144)
		(width 0.1651)
		(layer "F.Cu")
		(net "M_H_DQS_DP<6>")
	)
	(segment
		(start 134.060946 -41.35628)
		(end 134.240524 -41.35628)
		(width 0.1651)
		(layer "F.Cu")
		(net "M_H_DQS_DP<6>")
	)
	(segment
		(start 135.358124 -40.238934)
		(end 135.537702 -40.059356)
		(width 0.1651)
		(layer "F.Cu")
		(net "M_H_DQS_DP<6>")
	)
	(segment
		(start 134.619492 -40.797734)
		(end 134.799324 -40.797734)
		(width 0.1651)
		(layer "F.Cu")
		(net "M_H_DQS_DP<6>")
	)
	(segment
		(start 136.615678 -38.98138)
		(end 136.615678 -38.801548)
		(width 0.1651)
		(layer "F.Cu")
		(net "M_H_DQS_DP<6>")
	)
	(segment
		(start 122.969274 -47.156624)
		(end 129.804414 -47.156624)
		(width 0.1016)
		(layer "F.Cu")
		(net "M_H_DQS_DP<6>")
	)
	(segment
		(start 138.381486 -37.03574)
		(end 138.381486 -34.29)
		(width 0.1651)
		(layer "F.Cu")
		(net "M_H_DQS_DP<6>")
	)
	(segment
		(start 119.588534 -51.131978)
		(end 119.52097 -51.014884)
		(width 0.0889)
		(layer "F.Cu")
		(net "M_H_DQS_DP<6>")
	)
	(segment
		(start 133.881368 -41.8592)
		(end 133.881368 -41.535858)
		(width 0.1651)
		(layer "F.Cu")
		(net "M_H_DQS_DP<6>")
	)
	(segment
		(start 136.435846 -39.160958)
		(end 136.615678 -38.98138)
		(width 0.1651)
		(layer "F.Cu")
		(net "M_H_DQS_DP<6>")
	)
	(segment
		(start 136.07669 -39.340536)
		(end 136.256268 -39.160958)
		(width 0.1651)
		(layer "F.Cu")
		(net "M_H_DQS_DP<6>")
	)
	(segment
		(start 134.978902 -40.618156)
		(end 134.978902 -40.438324)
		(width 0.1651)
		(layer "F.Cu")
		(net "M_H_DQS_DP<6>")
	)
	(segment
		(start 134.240524 -41.35628)
		(end 134.420356 -41.176702)
		(width 0.1651)
		(layer "F.Cu")
		(net "M_H_DQS_DP<6>")
	)
	(segment
		(start 118.745762 -53.66131)
		(end 118.745762 -53.660548)
		(width 0.0889)
		(layer "F.Cu")
		(net "M_H_DQS_DP<6>")
	)
	(segment
		(start 138.504168 -28.209494)
		(end 138.30173 -28.007056)
		(width 0.1651)
		(layer "F.Cu")
		(net "M_H_DQS_DP<6>")
	)
	(segment
		(start 134.799324 -40.797734)
		(end 134.978902 -40.618156)
		(width 0.1651)
		(layer "F.Cu")
		(net "M_H_DQS_DP<6>")
	)
	(segment
		(start 135.178292 -40.238934)
		(end 135.358124 -40.238934)
		(width 0.1651)
		(layer "F.Cu")
		(net "M_H_DQS_DP<6>")
	)
	(segment
		(start 135.71728 -39.699946)
		(end 135.896858 -39.699946)
		(width 0.1651)
		(layer "F.Cu")
		(net "M_H_DQS_DP<6>")
	)
	(segment
		(start 138.499342 -10.422382)
		(end 138.499596 -10.422128)
		(width 0.1651)
		(layer "F.Cu")
		(net "M_H_DQS_DP<6>")
	)
	(segment
		(start 138.293602 -7.75716)
		(end 138.03757 -7.75716)
		(width 0.1651)
		(layer "F.Cu")
		(net "M_H_DQS_DP<6>")
	)
	(segment
		(start 119.059706 -53.027834)
		(end 119.092472 -53.027834)
		(width 0.0889)
		(layer "F.Cu")
		(net "M_H_DQS_DP<6>")
	)
	(segment
		(start 136.07669 -39.520368)
		(end 136.07669 -39.340536)
		(width 0.1651)
		(layer "F.Cu")
		(net "M_H_DQS_DP<6>")
	)
	(segment
		(start 138.537442 -9.3726)
		(end 138.537442 -8.001)
		(width 0.1651)
		(layer "F.Cu")
		(net "M_H_DQS_DP<6>")
	)
	(segment
		(start 138.499596 -10.422128)
		(end 138.499596 -9.410446)
		(width 0.1651)
		(layer "F.Cu")
		(net "M_H_DQS_DP<6>")
	)
	(segment
		(start 119.582692 -51.742086)
		(end 119.588534 -51.731926)
		(width 0.0889)
		(layer "F.Cu")
		(net "M_H_DQS_DP<6>")
	)
	(segment
		(start 135.537702 -39.879524)
		(end 135.71728 -39.699946)
		(width 0.1651)
		(layer "F.Cu")
		(net "M_H_DQS_DP<6>")
	)
	(segment
		(start 138.30173 -28.007056)
		(end 138.044174 -28.007056)
		(width 0.1651)
		(layer "F.Cu")
		(net "M_H_DQS_DP<6>")
	)
	(segment
		(start 136.256268 -39.160958)
		(end 136.435846 -39.160958)
		(width 0.1651)
		(layer "F.Cu")
		(net "M_H_DQS_DP<6>")
	)
	(segment
		(start 134.420356 -40.99687)
		(end 134.619492 -40.797734)
		(width 0.1651)
		(layer "F.Cu")
		(net "M_H_DQS_DP<6>")
	)
	(segment
		(start 136.615678 -38.801548)
		(end 138.381486 -37.03574)
		(width 0.1651)
		(layer "F.Cu")
		(net "M_H_DQS_DP<6>")
	)
	(segment
		(start 138.381486 -30.33903)
		(end 137.885424 -29.842968)
		(width 0.1651)
		(layer "F.Cu")
		(net "M_H_DQS_DP<6>")
	)
	(segment
		(start 129.804414 -47.156624)
		(end 133.87324 -43.087798)
		(width 0.1016)
		(layer "F.Cu")
		(net "M_H_DQS_DP<6>")
	)
	(segment
		(start 138.537442 -8.001)
		(end 138.293602 -7.75716)
		(width 0.1651)
		(layer "F.Cu")
		(net "M_H_DQS_DP<6>")
	)
	(via
		(at 138.03757 -7.75716)
		(size 0.508)
		(drill 0.254)
		(layers "F.Cu" "B.Cu")
		(net "M_H_DQS_DP<6>")
	)
	(via
		(at 138.044174 -28.007056)
		(size 0.508)
		(drill 0.254)
		(layers "F.Cu" "B.Cu")
		(net "M_H_DQS_DP<6>")
	)
	(via
		(at 138.381486 -34.29)
		(size 0.508)
		(drill 0.254)
		(layers "F.Cu" "B.Cu")
		(net "M_H_DQS_DP<6>")
	)
	(via
		(at 138.03757 -13.287756)
		(size 0.508)
		(drill 0.254)
		(layers "F.Cu" "B.Cu")
		(net "M_H_DQS_DP<6>")
	)
	(arc
		(start 119.588534 -51.731926)
		(mid 119.668897 -51.431952)
		(end 119.588534 -51.131978)
		(width 0.0889)
		(layer "F.Cu")
		(net "M_H_DQS_DP<6>")
	)
	(arc
		(start 119.582692 -52.141882)
		(mid 119.529159 -51.941984)
		(end 119.582692 -51.742086)
		(width 0.0889)
		(layer "F.Cu")
		(net "M_H_DQS_DP<6>")
	)
	(arc
		(start 118.745762 -53.660548)
		(mid 118.712665 -53.249818)
		(end 119.059706 -53.027834)
		(width 0.0889)
		(layer "F.Cu")
		(net "M_H_DQS_DP<6>")
	)
	(arc
		(start 119.092472 -53.027834)
		(mid 119.587949 -52.723391)
		(end 119.582692 -52.141882)
		(width 0.0889)
		(layer "F.Cu")
		(net "M_H_DQS_DP<6>")
	)
	(segment
		(start 138.537442 -13.0302)
		(end 138.279886 -13.287756)
		(width 0.1651)
		(layer "B.Cu")
		(net "M_H_DQS_DP<6>")
	)
	(segment
		(start 138.279886 -13.287756)
		(end 138.03757 -13.287756)
		(width 0.1651)
		(layer "B.Cu")
		(net "M_H_DQS_DP<6>")
	)
	(segment
		(start 138.499596 -11.773154)
		(end 138.537442 -11.811)
		(width 0.1651)
		(layer "B.Cu")
		(net "M_H_DQS_DP<6>")
	)
	(segment
		(start 138.499342 -10.623042)
		(end 138.499596 -10.623296)
		(width 0.1651)
		(layer "B.Cu")
		(net "M_H_DQS_DP<6>")
	)
	(segment
		(start 138.537442 -11.811)
		(end 138.537442 -13.0302)
		(width 0.1651)
		(layer "B.Cu")
		(net "M_H_DQS_DP<6>")
	)
	(segment
		(start 138.499596 -10.623296)
		(end 138.499596 -11.773154)
		(width 0.1651)
		(layer "B.Cu")
		(net "M_H_DQS_DP<6>")
	)
	(segment
		(start 138.501374 -14.201394)
		(end 138.501374 -13.75156)
		(width 0.14224)
		(layer "In4.Cu")
		(net "M_H_DQS_DP<6>")
	)
	(segment
		(start 138.321288 -14.668246)
		(end 138.321288 -14.38148)
		(width 0.14224)
		(layer "In4.Cu")
		(net "M_H_DQS_DP<6>")
	)
	(segment
		(start 138.848338 -12.476988)
		(end 138.848338 -8.567928)
		(width 0.14224)
		(layer "In4.Cu")
		(net "M_H_DQS_DP<6>")
	)
	(segment
		(start 138.321288 -14.38148)
		(end 138.501374 -14.201394)
		(width 0.14224)
		(layer "In4.Cu")
		(net "M_H_DQS_DP<6>")
	)
	(segment
		(start 138.03757 -13.287756)
		(end 138.848338 -12.476988)
		(width 0.14224)
		(layer "In4.Cu")
		(net "M_H_DQS_DP<6>")
	)
	(segment
		(start 138.803888 -27.240738)
		(end 138.803888 -15.150846)
		(width 0.14224)
		(layer "In4.Cu")
		(net "M_H_DQS_DP<6>")
	)
	(segment
		(start 138.044174 -28.007056)
		(end 138.044174 -28.000452)
		(width 0.14224)
		(layer "In4.Cu")
		(net "M_H_DQS_DP<6>")
	)
	(segment
		(start 138.803888 -15.150846)
		(end 138.321288 -14.668246)
		(width 0.14224)
		(layer "In4.Cu")
		(net "M_H_DQS_DP<6>")
	)
	(segment
		(start 138.501374 -13.75156)
		(end 138.03757 -13.287756)
		(width 0.14224)
		(layer "In4.Cu")
		(net "M_H_DQS_DP<6>")
	)
	(segment
		(start 138.044174 -28.000452)
		(end 138.803888 -27.240738)
		(width 0.14224)
		(layer "In4.Cu")
		(net "M_H_DQS_DP<6>")
	)
	(segment
		(start 138.848338 -8.567928)
		(end 138.03757 -7.75716)
		(width 0.14224)
		(layer "In4.Cu")
		(net "M_H_DQS_DP<6>")
	)
	(segment
		(start 114.487452 -51.53279)
		(end 114.487452 -49.696116)
		(width 0.0889)
		(layer "F.Cu")
		(net "M_H_DQS_DP<5>")
	)
	(segment
		(start 128.525016 -32.280098)
		(end 128.525016 -29.536898)
		(width 0.1651)
		(layer "F.Cu")
		(net "M_H_DQS_DP<5>")
	)
	(segment
		(start 119.881904 -40.500554)
		(end 119.881904 -40.320722)
		(width 0.1651)
		(layer "F.Cu")
		(net "M_H_DQS_DP<5>")
	)
	(segment
		(start 122.540014 -38.2651)
		(end 128.525016 -32.280098)
		(width 0.1651)
		(layer "F.Cu")
		(net "M_H_DQS_DP<5>")
	)
	(segment
		(start 121.139458 -39.063168)
		(end 121.319036 -39.063168)
		(width 0.1651)
		(layer "F.Cu")
		(net "M_H_DQS_DP<5>")
	)
	(segment
		(start 119.342916 -41.0718)
		(end 119.342916 -40.85971)
		(width 0.1651)
		(layer "F.Cu")
		(net "M_H_DQS_DP<5>")
	)
	(segment
		(start 120.60047 -39.602156)
		(end 120.780048 -39.602156)
		(width 0.1651)
		(layer "F.Cu")
		(net "M_H_DQS_DP<5>")
	)
	(segment
		(start 129.258568 -28.2956)
		(end 128.970024 -28.007056)
		(width 0.1651)
		(layer "F.Cu")
		(net "M_H_DQS_DP<5>")
	)
	(segment
		(start 120.420892 -39.781734)
		(end 120.60047 -39.602156)
		(width 0.1651)
		(layer "F.Cu")
		(net "M_H_DQS_DP<5>")
	)
	(segment
		(start 120.061482 -40.141144)
		(end 120.24106 -40.141144)
		(width 0.1651)
		(layer "F.Cu")
		(net "M_H_DQS_DP<5>")
	)
	(segment
		(start 128.970024 -28.007056)
		(end 128.69418 -28.007056)
		(width 0.1651)
		(layer "F.Cu")
		(net "M_H_DQS_DP<5>")
	)
	(segment
		(start 129.187194 -8.001)
		(end 128.943354 -7.75716)
		(width 0.1651)
		(layer "F.Cu")
		(net "M_H_DQS_DP<5>")
	)
	(segment
		(start 114.431572 -52.141882)
		(end 114.431318 -52.141882)
		(width 0.0889)
		(layer "F.Cu")
		(net "M_H_DQS_DP<5>")
	)
	(segment
		(start 119.522494 -40.680132)
		(end 119.702072 -40.680132)
		(width 0.1651)
		(layer "F.Cu")
		(net "M_H_DQS_DP<5>")
	)
	(segment
		(start 119.393716 -41.290748)
		(end 119.342916 -41.239948)
		(width 0.1016)
		(layer "F.Cu")
		(net "M_H_DQS_DP<5>")
	)
	(segment
		(start 129.149348 -10.422382)
		(end 129.149348 -9.410446)
		(width 0.1651)
		(layer "F.Cu")
		(net "M_H_DQS_DP<5>")
	)
	(segment
		(start 128.943354 -7.75716)
		(end 128.687322 -7.75716)
		(width 0.1651)
		(layer "F.Cu")
		(net "M_H_DQS_DP<5>")
	)
	(segment
		(start 119.702072 -40.680132)
		(end 119.881904 -40.500554)
		(width 0.1651)
		(layer "F.Cu")
		(net "M_H_DQS_DP<5>")
	)
	(segment
		(start 129.187194 -9.3726)
		(end 129.187194 -8.001)
		(width 0.1651)
		(layer "F.Cu")
		(net "M_H_DQS_DP<5>")
	)
	(segment
		(start 114.487452 -49.696116)
		(end 114.591592 -49.591976)
		(width 0.0889)
		(layer "F.Cu")
		(net "M_H_DQS_DP<5>")
	)
	(segment
		(start 119.393716 -43.044364)
		(end 119.393716 -41.290748)
		(width 0.1016)
		(layer "F.Cu")
		(net "M_H_DQS_DP<5>")
	)
	(segment
		(start 121.498868 -38.703758)
		(end 121.937526 -38.2651)
		(width 0.1651)
		(layer "F.Cu")
		(net "M_H_DQS_DP<5>")
	)
	(segment
		(start 129.149348 -9.410446)
		(end 129.187194 -9.3726)
		(width 0.1651)
		(layer "F.Cu")
		(net "M_H_DQS_DP<5>")
	)
	(segment
		(start 128.525016 -29.536898)
		(end 129.258568 -28.803346)
		(width 0.1651)
		(layer "F.Cu")
		(net "M_H_DQS_DP<5>")
	)
	(segment
		(start 119.342916 -41.239948)
		(end 119.342916 -41.0718)
		(width 0.1016)
		(layer "F.Cu")
		(net "M_H_DQS_DP<5>")
	)
	(segment
		(start 121.498868 -38.88359)
		(end 121.498868 -38.703758)
		(width 0.1651)
		(layer "F.Cu")
		(net "M_H_DQS_DP<5>")
	)
	(segment
		(start 121.937526 -38.2651)
		(end 122.540014 -38.2651)
		(width 0.1651)
		(layer "F.Cu")
		(net "M_H_DQS_DP<5>")
	)
	(segment
		(start 129.258568 -28.803346)
		(end 129.258568 -28.2956)
		(width 0.1651)
		(layer "F.Cu")
		(net "M_H_DQS_DP<5>")
	)
	(segment
		(start 113.919762 -53.427884)
		(end 113.820448 -53.732176)
		(width 0.0889)
		(layer "F.Cu")
		(net "M_H_DQS_DP<5>")
	)
	(segment
		(start 120.420892 -39.961566)
		(end 120.420892 -39.781734)
		(width 0.1651)
		(layer "F.Cu")
		(net "M_H_DQS_DP<5>")
	)
	(segment
		(start 113.820448 -53.732176)
		(end 113.737898 -53.784246)
		(width 0.0889)
		(layer "F.Cu")
		(net "M_H_DQS_DP<5>")
	)
	(segment
		(start 120.95988 -39.242746)
		(end 121.139458 -39.063168)
		(width 0.1651)
		(layer "F.Cu")
		(net "M_H_DQS_DP<5>")
	)
	(segment
		(start 121.319036 -39.063168)
		(end 121.498868 -38.88359)
		(width 0.1651)
		(layer "F.Cu")
		(net "M_H_DQS_DP<5>")
	)
	(segment
		(start 114.591592 -47.846488)
		(end 119.393716 -43.044364)
		(width 0.1016)
		(layer "F.Cu")
		(net "M_H_DQS_DP<5>")
	)
	(segment
		(start 120.95988 -39.422578)
		(end 120.95988 -39.242746)
		(width 0.1651)
		(layer "F.Cu")
		(net "M_H_DQS_DP<5>")
	)
	(segment
		(start 120.780048 -39.602156)
		(end 120.95988 -39.422578)
		(width 0.1651)
		(layer "F.Cu")
		(net "M_H_DQS_DP<5>")
	)
	(segment
		(start 113.908586 -53.027834)
		(end 113.941352 -53.027834)
		(width 0.0889)
		(layer "F.Cu")
		(net "M_H_DQS_DP<5>")
	)
	(segment
		(start 114.591592 -49.591976)
		(end 114.591592 -47.846488)
		(width 0.1016)
		(layer "F.Cu")
		(net "M_H_DQS_DP<5>")
	)
	(segment
		(start 120.24106 -40.141144)
		(end 120.420892 -39.961566)
		(width 0.1651)
		(layer "F.Cu")
		(net "M_H_DQS_DP<5>")
	)
	(segment
		(start 119.881904 -40.320722)
		(end 120.061482 -40.141144)
		(width 0.1651)
		(layer "F.Cu")
		(net "M_H_DQS_DP<5>")
	)
	(segment
		(start 119.342916 -40.85971)
		(end 119.522494 -40.680132)
		(width 0.1651)
		(layer "F.Cu")
		(net "M_H_DQS_DP<5>")
	)
	(via
		(at 128.687322 -13.287756)
		(size 0.508)
		(drill 0.254)
		(layers "F.Cu" "B.Cu")
		(net "M_H_DQS_DP<5>")
	)
	(via
		(at 128.69418 -28.007056)
		(size 0.508)
		(drill 0.254)
		(layers "F.Cu" "B.Cu")
		(net "M_H_DQS_DP<5>")
	)
	(via
		(at 128.687322 -7.75716)
		(size 0.508)
		(drill 0.254)
		(layers "F.Cu" "B.Cu")
		(net "M_H_DQS_DP<5>")
	)
	(arc
		(start 113.737898 -53.784246)
		(mid 113.663787 -53.735427)
		(end 113.602262 -53.67147)
		(width 0.0889)
		(layer "F.Cu")
		(net "M_H_DQS_DP<5>")
	)
	(arc
		(start 113.941352 -53.027834)
		(mid 114.436829 -52.723391)
		(end 114.431572 -52.141882)
		(width 0.0889)
		(layer "F.Cu")
		(net "M_H_DQS_DP<5>")
	)
	(arc
		(start 114.431318 -52.141882)
		(mid 114.37798 -51.941955)
		(end 114.431572 -51.742086)
		(width 0.0889)
		(layer "F.Cu")
		(net "M_H_DQS_DP<5>")
	)
	(arc
		(start 114.431572 -51.742086)
		(mid 114.473297 -51.641119)
		(end 114.487452 -51.53279)
		(width 0.0889)
		(layer "F.Cu")
		(net "M_H_DQS_DP<5>")
	)
	(arc
		(start 113.602262 -53.67147)
		(mid 113.558375 -53.255947)
		(end 113.908586 -53.027834)
		(width 0.0889)
		(layer "F.Cu")
		(net "M_H_DQS_DP<5>")
	)
	(segment
		(start 129.149348 -11.773154)
		(end 129.187194 -11.811)
		(width 0.1651)
		(layer "B.Cu")
		(net "M_H_DQS_DP<5>")
	)
	(segment
		(start 128.929638 -13.287756)
		(end 128.687322 -13.287756)
		(width 0.1651)
		(layer "B.Cu")
		(net "M_H_DQS_DP<5>")
	)
	(segment
		(start 129.149348 -10.623042)
		(end 129.149348 -11.773154)
		(width 0.1651)
		(layer "B.Cu")
		(net "M_H_DQS_DP<5>")
	)
	(segment
		(start 129.187194 -11.811)
		(end 129.187194 -13.0302)
		(width 0.1651)
		(layer "B.Cu")
		(net "M_H_DQS_DP<5>")
	)
	(segment
		(start 129.187194 -13.0302)
		(end 128.929638 -13.287756)
		(width 0.1651)
		(layer "B.Cu")
		(net "M_H_DQS_DP<5>")
	)
	(segment
		(start 128.687576 -7.75716)
		(end 129.498344 -8.567928)
		(width 0.14224)
		(layer "In11.Cu")
		(net "M_H_DQS_DP<5>")
	)
	(segment
		(start 129.453894 -15.150846)
		(end 129.453894 -27.240738)
		(width 0.14224)
		(layer "In11.Cu")
		(net "M_H_DQS_DP<5>")
	)
	(segment
		(start 128.971294 -14.668246)
		(end 129.453894 -15.150846)
		(width 0.14224)
		(layer "In11.Cu")
		(net "M_H_DQS_DP<5>")
	)
	(segment
		(start 129.453894 -27.240738)
		(end 128.69418 -28.000452)
		(width 0.14224)
		(layer "In11.Cu")
		(net "M_H_DQS_DP<5>")
	)
	(segment
		(start 128.971294 -14.38148)
		(end 128.971294 -14.668246)
		(width 0.14224)
		(layer "In11.Cu")
		(net "M_H_DQS_DP<5>")
	)
	(segment
		(start 129.156968 -13.757402)
		(end 129.156968 -14.195806)
		(width 0.14224)
		(layer "In11.Cu")
		(net "M_H_DQS_DP<5>")
	)
	(segment
		(start 128.69418 -28.000452)
		(end 128.69418 -28.007056)
		(width 0.14224)
		(layer "In11.Cu")
		(net "M_H_DQS_DP<5>")
	)
	(segment
		(start 128.687322 -13.287756)
		(end 129.156968 -13.757402)
		(width 0.14224)
		(layer "In11.Cu")
		(net "M_H_DQS_DP<5>")
	)
	(segment
		(start 128.687322 -7.75716)
		(end 128.687576 -7.75716)
		(width 0.14224)
		(layer "In11.Cu")
		(net "M_H_DQS_DP<5>")
	)
	(segment
		(start 129.498344 -8.567928)
		(end 129.498344 -12.476734)
		(width 0.14224)
		(layer "In11.Cu")
		(net "M_H_DQS_DP<5>")
	)
	(segment
		(start 129.156968 -14.195806)
		(end 128.971294 -14.38148)
		(width 0.14224)
		(layer "In11.Cu")
		(net "M_H_DQS_DP<5>")
	)
	(segment
		(start 129.498344 -12.476734)
		(end 128.687322 -13.287756)
		(width 0.14224)
		(layer "In11.Cu")
		(net "M_H_DQS_DP<5>")
	)
	(segment
		(start 119.799354 -10.422382)
		(end 119.799354 -9.410446)
		(width 0.1651)
		(layer "F.Cu")
		(net "M_H_DQS_DP<4>")
	)
	(segment
		(start 107.051856 -58.381138)
		(end 106.480356 -58.381138)
		(width 0.1016)
		(layer "F.Cu")
		(net "M_H_DQS_DP<4>")
	)
	(segment
		(start 119.8372 -8.001)
		(end 119.59336 -7.75716)
		(width 0.1651)
		(layer "F.Cu")
		(net "M_H_DQS_DP<4>")
	)
	(segment
		(start 119.59336 -7.75716)
		(end 119.337328 -7.75716)
		(width 0.1651)
		(layer "F.Cu")
		(net "M_H_DQS_DP<4>")
	)
	(segment
		(start 119.799354 -9.410446)
		(end 119.8372 -9.3726)
		(width 0.1651)
		(layer "F.Cu")
		(net "M_H_DQS_DP<4>")
	)
	(segment
		(start 119.8372 -9.3726)
		(end 119.8372 -8.001)
		(width 0.1651)
		(layer "F.Cu")
		(net "M_H_DQS_DP<4>")
	)
	(via
		(at 119.337328 -13.287756)
		(size 0.508)
		(drill 0.254)
		(layers "F.Cu" "B.Cu")
		(net "M_H_DQS_DP<4>")
	)
	(via
		(at 106.480356 -58.381138)
		(size 0.508)
		(drill 0.254)
		(layers "F.Cu" "B.Cu")
		(net "M_H_DQS_DP<4>")
	)
	(via
		(at 119.337328 -7.75716)
		(size 0.508)
		(drill 0.254)
		(layers "F.Cu" "B.Cu")
		(net "M_H_DQS_DP<4>")
	)
	(segment
		(start 119.8372 -11.811)
		(end 119.8372 -13.0302)
		(width 0.1651)
		(layer "B.Cu")
		(net "M_H_DQS_DP<4>")
	)
	(segment
		(start 119.579644 -13.287756)
		(end 119.337328 -13.287756)
		(width 0.1651)
		(layer "B.Cu")
		(net "M_H_DQS_DP<4>")
	)
	(segment
		(start 119.799354 -11.773154)
		(end 119.8372 -11.811)
		(width 0.1651)
		(layer "B.Cu")
		(net "M_H_DQS_DP<4>")
	)
	(segment
		(start 119.799354 -10.623042)
		(end 119.799354 -11.773154)
		(width 0.1651)
		(layer "B.Cu")
		(net "M_H_DQS_DP<4>")
	)
	(segment
		(start 119.8372 -13.0302)
		(end 119.579644 -13.287756)
		(width 0.1651)
		(layer "B.Cu")
		(net "M_H_DQS_DP<4>")
	)
	(segment
		(start 115.562888 -32.271208)
		(end 115.562888 -31.398718)
		(width 0.14224)
		(layer "In4.Cu")
		(net "M_H_DQS_DP<4>")
	)
	(segment
		(start 119.161052 -14.618716)
		(end 119.352568 -14.4272)
		(width 0.14224)
		(layer "In4.Cu")
		(net "M_H_DQS_DP<4>")
	)
	(segment
		(start 119.352568 -14.4272)
		(end 119.657368 -14.4272)
		(width 0.14224)
		(layer "In4.Cu")
		(net "M_H_DQS_DP<4>")
	)
	(segment
		(start 108.750608 -47.808642)
		(end 109.972856 -46.586394)
		(width 0.0889)
		(layer "In4.Cu")
		(net "M_H_DQS_DP<4>")
	)
	(segment
		(start 119.337328 -13.287756)
		(end 120.148096 -12.476988)
		(width 0.14224)
		(layer "In4.Cu")
		(net "M_H_DQS_DP<4>")
	)
	(segment
		(start 107.3277 -55.504588)
		(end 107.360466 -55.504588)
		(width 0.0889)
		(layer "In4.Cu")
		(net "M_H_DQS_DP<4>")
	)
	(segment
		(start 120.119902 -15.938754)
		(end 119.892826 -15.711678)
		(width 0.14224)
		(layer "In4.Cu")
		(net "M_H_DQS_DP<4>")
	)
	(segment
		(start 120.119902 -26.841704)
		(end 120.119902 -19.58848)
		(width 0.14224)
		(layer "In4.Cu")
		(net "M_H_DQS_DP<4>")
	)
	(segment
		(start 110.012226 -37.82187)
		(end 115.562888 -32.271208)
		(width 0.14224)
		(layer "In4.Cu")
		(net "M_H_DQS_DP<4>")
	)
	(segment
		(start 108.467652 -49.452784)
		(end 108.750608 -49.169828)
		(width 0.0889)
		(layer "In4.Cu")
		(net "M_H_DQS_DP<4>")
	)
	(segment
		(start 109.972856 -45.653198)
		(end 110.012226 -45.613828)
		(width 0.0889)
		(layer "In4.Cu")
		(net "M_H_DQS_DP<4>")
	)
	(segment
		(start 109.972856 -46.586394)
		(end 109.972856 -45.653198)
		(width 0.0889)
		(layer "In4.Cu")
		(net "M_H_DQS_DP<4>")
	)
	(segment
		(start 119.49049 -15.309342)
		(end 119.161052 -14.979904)
		(width 0.14224)
		(layer "In4.Cu")
		(net "M_H_DQS_DP<4>")
	)
	(segment
		(start 120.277382 -19.177)
		(end 120.119902 -19.01952)
		(width 0.14224)
		(layer "In4.Cu")
		(net "M_H_DQS_DP<4>")
	)
	(segment
		(start 120.148096 -8.567928)
		(end 119.337328 -7.75716)
		(width 0.14224)
		(layer "In4.Cu")
		(net "M_H_DQS_DP<4>")
	)
	(segment
		(start 120.119902 -19.01952)
		(end 120.119902 -15.938754)
		(width 0.14224)
		(layer "In4.Cu")
		(net "M_H_DQS_DP<4>")
	)
	(segment
		(start 119.657368 -14.4272)
		(end 119.801132 -14.283436)
		(width 0.14224)
		(layer "In4.Cu")
		(net "M_H_DQS_DP<4>")
	)
	(segment
		(start 107.929426 -52.954174)
		(end 107.753404 -52.778152)
		(width 0.0889)
		(layer "In4.Cu")
		(net "M_H_DQS_DP<4>")
	)
	(segment
		(start 119.712994 -15.309342)
		(end 119.49049 -15.309342)
		(width 0.14224)
		(layer "In4.Cu")
		(net "M_H_DQS_DP<4>")
	)
	(segment
		(start 108.467652 -51.47056)
		(end 108.467652 -49.452784)
		(width 0.0889)
		(layer "In4.Cu")
		(net "M_H_DQS_DP<4>")
	)
	(segment
		(start 120.277382 -19.431)
		(end 120.277382 -19.177)
		(width 0.14224)
		(layer "In4.Cu")
		(net "M_H_DQS_DP<4>")
	)
	(segment
		(start 110.012226 -45.613828)
		(end 110.012226 -45.59173)
		(width 0.0889)
		(layer "In4.Cu")
		(net "M_H_DQS_DP<4>")
	)
	(segment
		(start 119.801132 -14.283436)
		(end 119.801132 -13.75156)
		(width 0.14224)
		(layer "In4.Cu")
		(net "M_H_DQS_DP<4>")
	)
	(segment
		(start 119.161052 -14.979904)
		(end 119.161052 -14.618716)
		(width 0.14224)
		(layer "In4.Cu")
		(net "M_H_DQS_DP<4>")
	)
	(segment
		(start 119.801132 -13.75156)
		(end 119.337328 -13.287756)
		(width 0.14224)
		(layer "In4.Cu")
		(net "M_H_DQS_DP<4>")
	)
	(segment
		(start 107.753404 -52.184808)
		(end 108.467652 -51.47056)
		(width 0.0889)
		(layer "In4.Cu")
		(net "M_H_DQS_DP<4>")
	)
	(segment
		(start 106.480356 -58.381138)
		(end 106.74223 -57.920382)
		(width 0.0889)
		(layer "In4.Cu")
		(net "M_H_DQS_DP<4>")
	)
	(segment
		(start 119.892826 -15.711678)
		(end 119.892826 -15.489174)
		(width 0.14224)
		(layer "In4.Cu")
		(net "M_H_DQS_DP<4>")
	)
	(segment
		(start 108.750608 -49.169828)
		(end 108.750608 -47.808642)
		(width 0.0889)
		(layer "In4.Cu")
		(net "M_H_DQS_DP<4>")
	)
	(segment
		(start 115.562888 -31.398718)
		(end 120.119902 -26.841704)
		(width 0.14224)
		(layer "In4.Cu")
		(net "M_H_DQS_DP<4>")
	)
	(segment
		(start 107.929426 -54.896004)
		(end 107.929426 -52.954174)
		(width 0.0889)
		(layer "In4.Cu")
		(net "M_H_DQS_DP<4>")
	)
	(segment
		(start 107.753404 -52.778152)
		(end 107.753404 -52.184808)
		(width 0.0889)
		(layer "In4.Cu")
		(net "M_H_DQS_DP<4>")
	)
	(segment
		(start 120.148096 -12.476988)
		(end 120.148096 -8.567928)
		(width 0.14224)
		(layer "In4.Cu")
		(net "M_H_DQS_DP<4>")
	)
	(segment
		(start 119.892826 -15.489174)
		(end 119.712994 -15.309342)
		(width 0.14224)
		(layer "In4.Cu")
		(net "M_H_DQS_DP<4>")
	)
	(segment
		(start 110.012226 -45.59173)
		(end 110.012226 -37.82187)
		(width 0.14224)
		(layer "In4.Cu")
		(net "M_H_DQS_DP<4>")
	)
	(segment
		(start 120.119902 -19.58848)
		(end 120.277382 -19.431)
		(width 0.14224)
		(layer "In4.Cu")
		(net "M_H_DQS_DP<4>")
	)
	(arc
		(start 106.992166 -57.095136)
		(mid 106.938667 -56.895238)
		(end 106.992166 -56.69534)
		(width 0.0889)
		(layer "In4.Cu")
		(net "M_H_DQS_DP<4>")
	)
	(arc
		(start 106.74223 -57.920382)
		(mid 107.045998 -57.561891)
		(end 106.992166 -57.095136)
		(width 0.0889)
		(layer "In4.Cu")
		(net "M_H_DQS_DP<4>")
	)
	(arc
		(start 106.992166 -56.69534)
		(mid 107.071297 -56.399938)
		(end 106.992166 -56.104536)
		(width 0.0889)
		(layer "In4.Cu")
		(net "M_H_DQS_DP<4>")
	)
	(arc
		(start 107.360466 -55.504588)
		(mid 107.770512 -55.317653)
		(end 107.929426 -54.896004)
		(width 0.0889)
		(layer "In4.Cu")
		(net "M_H_DQS_DP<4>")
	)
	(arc
		(start 106.992166 -56.104536)
		(mid 106.989583 -55.709289)
		(end 107.3277 -55.504588)
		(width 0.0889)
		(layer "In4.Cu")
		(net "M_H_DQS_DP<4>")
	)
	(segment
		(start 64.549528 -10.422382)
		(end 64.549528 -9.410446)
		(width 0.1651)
		(layer "F.Cu")
		(net "M_H_DQS_DP<3>")
	)
	(segment
		(start 79.427832 -50.436526)
		(end 79.424276 -50.442622)
		(width 0.0889)
		(layer "F.Cu")
		(net "M_H_DQS_DP<3>")
	)
	(segment
		(start 64.587374 -9.3726)
		(end 64.587374 -8.001)
		(width 0.1651)
		(layer "F.Cu")
		(net "M_H_DQS_DP<3>")
	)
	(segment
		(start 79.08925 -52.302918)
		(end 78.909672 -52.12334)
		(width 0.0889)
		(layer "F.Cu")
		(net "M_H_DQS_DP<3>")
	)
	(segment
		(start 64.049148 -29.67482)
		(end 64.049148 -29.92882)
		(width 0.1651)
		(layer "F.Cu")
		(net "M_H_DQS_DP<3>")
	)
	(segment
		(start 72.67702 -46.75759)
		(end 73.29932 -47.37989)
		(width 0.1016)
		(layer "F.Cu")
		(net "M_H_DQS_DP<3>")
	)
	(segment
		(start 64.587374 -8.001)
		(end 64.343534 -7.75716)
		(width 0.1651)
		(layer "F.Cu")
		(net "M_H_DQS_DP<3>")
	)
	(segment
		(start 63.917068 -30.0609)
		(end 63.917068 -30.30474)
		(width 0.1651)
		(layer "F.Cu")
		(net "M_H_DQS_DP<3>")
	)
	(segment
		(start 63.917068 -29.2989)
		(end 63.917068 -29.54274)
		(width 0.1651)
		(layer "F.Cu")
		(net "M_H_DQS_DP<3>")
	)
	(segment
		(start 64.549528 -9.410446)
		(end 64.587374 -9.3726)
		(width 0.1651)
		(layer "F.Cu")
		(net "M_H_DQS_DP<3>")
	)
	(segment
		(start 78.856332 -49.05248)
		(end 79.097632 -49.29378)
		(width 0.0889)
		(layer "F.Cu")
		(net "M_H_DQS_DP<3>")
	)
	(segment
		(start 64.094106 -28.007056)
		(end 64.368426 -28.007056)
		(width 0.1651)
		(layer "F.Cu")
		(net "M_H_DQS_DP<3>")
	)
	(segment
		(start 79.097632 -49.29378)
		(end 79.319628 -49.619154)
		(width 0.0889)
		(layer "F.Cu")
		(net "M_H_DQS_DP<3>")
	)
	(segment
		(start 67.54114 -45.578014)
		(end 67.783964 -45.578014)
		(width 0.1016)
		(layer "F.Cu")
		(net "M_H_DQS_DP<3>")
	)
	(segment
		(start 64.455548 -32.765746)
		(end 64.455548 -42.492422)
		(width 0.1651)
		(layer "F.Cu")
		(net "M_H_DQS_DP<3>")
	)
	(segment
		(start 64.343534 -7.75716)
		(end 64.087502 -7.75716)
		(width 0.1651)
		(layer "F.Cu")
		(net "M_H_DQS_DP<3>")
	)
	(segment
		(start 78.909926 -51.723798)
		(end 78.909926 -51.724052)
		(width 0.0889)
		(layer "F.Cu")
		(net "M_H_DQS_DP<3>")
	)
	(segment
		(start 68.96354 -46.75759)
		(end 72.67702 -46.75759)
		(width 0.1016)
		(layer "F.Cu")
		(net "M_H_DQS_DP<3>")
	)
	(segment
		(start 79.319628 -49.619154)
		(end 79.433928 -49.828958)
		(width 0.0889)
		(layer "F.Cu")
		(net "M_H_DQS_DP<3>")
	)
	(segment
		(start 64.564768 -28.9306)
		(end 64.336168 -29.1592)
		(width 0.1651)
		(layer "F.Cu")
		(net "M_H_DQS_DP<3>")
	)
	(segment
		(start 64.049148 -30.43682)
		(end 64.049148 -30.69082)
		(width 0.1651)
		(layer "F.Cu")
		(net "M_H_DQS_DP<3>")
	)
	(segment
		(start 63.917068 -31.369)
		(end 63.917068 -32.227266)
		(width 0.1651)
		(layer "F.Cu")
		(net "M_H_DQS_DP<3>")
	)
	(segment
		(start 77.28712 -47.37989)
		(end 78.856332 -48.949102)
		(width 0.1016)
		(layer "F.Cu")
		(net "M_H_DQS_DP<3>")
	)
	(segment
		(start 67.783964 -45.578014)
		(end 68.96354 -46.75759)
		(width 0.1016)
		(layer "F.Cu")
		(net "M_H_DQS_DP<3>")
	)
	(segment
		(start 73.29932 -47.37989)
		(end 77.28712 -47.37989)
		(width 0.1016)
		(layer "F.Cu")
		(net "M_H_DQS_DP<3>")
	)
	(segment
		(start 64.049148 -30.69082)
		(end 63.917068 -30.8229)
		(width 0.1651)
		(layer "F.Cu")
		(net "M_H_DQS_DP<3>")
	)
	(segment
		(start 63.917068 -30.8229)
		(end 63.917068 -31.369)
		(width 0.1651)
		(layer "F.Cu")
		(net "M_H_DQS_DP<3>")
	)
	(segment
		(start 78.846172 -52.51831)
		(end 79.002382 -52.51831)
		(width 0.0889)
		(layer "F.Cu")
		(net "M_H_DQS_DP<3>")
	)
	(segment
		(start 64.336168 -29.1592)
		(end 64.056768 -29.1592)
		(width 0.1651)
		(layer "F.Cu")
		(net "M_H_DQS_DP<3>")
	)
	(segment
		(start 63.917068 -32.227266)
		(end 64.455548 -32.765746)
		(width 0.1651)
		(layer "F.Cu")
		(net "M_H_DQS_DP<3>")
	)
	(segment
		(start 63.917068 -29.54274)
		(end 64.049148 -29.67482)
		(width 0.1651)
		(layer "F.Cu")
		(net "M_H_DQS_DP<3>")
	)
	(segment
		(start 79.444088 -50.404522)
		(end 79.427832 -50.436526)
		(width 0.0889)
		(layer "F.Cu")
		(net "M_H_DQS_DP<3>")
	)
	(segment
		(start 67.479926 -45.5168)
		(end 67.54114 -45.578014)
		(width 0.1016)
		(layer "F.Cu")
		(net "M_H_DQS_DP<3>")
	)
	(segment
		(start 78.856332 -48.949102)
		(end 78.856332 -49.05248)
		(width 0.0889)
		(layer "F.Cu")
		(net "M_H_DQS_DP<3>")
	)
	(segment
		(start 64.564768 -28.203398)
		(end 64.564768 -28.9306)
		(width 0.1651)
		(layer "F.Cu")
		(net "M_H_DQS_DP<3>")
	)
	(segment
		(start 63.917068 -30.30474)
		(end 64.049148 -30.43682)
		(width 0.1651)
		(layer "F.Cu")
		(net "M_H_DQS_DP<3>")
	)
	(segment
		(start 79.002382 -52.51831)
		(end 79.08925 -52.431442)
		(width 0.0889)
		(layer "F.Cu")
		(net "M_H_DQS_DP<3>")
	)
	(segment
		(start 64.455548 -42.492422)
		(end 67.479926 -45.5168)
		(width 0.1651)
		(layer "F.Cu")
		(net "M_H_DQS_DP<3>")
	)
	(segment
		(start 79.08925 -52.431442)
		(end 79.08925 -52.302918)
		(width 0.0889)
		(layer "F.Cu")
		(net "M_H_DQS_DP<3>")
	)
	(segment
		(start 64.368426 -28.007056)
		(end 64.564768 -28.203398)
		(width 0.1651)
		(layer "F.Cu")
		(net "M_H_DQS_DP<3>")
	)
	(segment
		(start 64.056768 -29.1592)
		(end 63.917068 -29.2989)
		(width 0.1651)
		(layer "F.Cu")
		(net "M_H_DQS_DP<3>")
	)
	(segment
		(start 64.049148 -29.92882)
		(end 63.917068 -30.0609)
		(width 0.1651)
		(layer "F.Cu")
		(net "M_H_DQS_DP<3>")
	)
	(via
		(at 64.087502 -7.75716)
		(size 0.508)
		(drill 0.254)
		(layers "F.Cu" "B.Cu")
		(net "M_H_DQS_DP<3>")
	)
	(via
		(at 64.087502 -13.287756)
		(size 0.508)
		(drill 0.254)
		(layers "F.Cu" "B.Cu")
		(net "M_H_DQS_DP<3>")
	)
	(via
		(at 63.917068 -31.369)
		(size 0.508)
		(drill 0.254)
		(layers "F.Cu" "B.Cu")
		(net "M_H_DQS_DP<3>")
	)
	(via
		(at 64.094106 -28.007056)
		(size 0.508)
		(drill 0.254)
		(layers "F.Cu" "B.Cu")
		(net "M_H_DQS_DP<3>")
	)
	(arc
		(start 79.421736 -50.837338)
		(mid 79.421645 -51.4283)
		(end 78.909926 -51.723798)
		(width 0.0889)
		(layer "F.Cu")
		(net "M_H_DQS_DP<3>")
	)
	(arc
		(start 79.433928 -49.828958)
		(mid 79.509578 -50.115485)
		(end 79.444088 -50.404522)
		(width 0.0889)
		(layer "F.Cu")
		(net "M_H_DQS_DP<3>")
	)
	(arc
		(start 78.909926 -51.724052)
		(mid 78.511158 -52.09185)
		(end 78.846172 -52.51831)
		(width 0.0889)
		(layer "F.Cu")
		(net "M_H_DQS_DP<3>")
	)
	(arc
		(start 79.424276 -50.442622)
		(mid 79.369346 -50.639651)
		(end 79.421736 -50.837338)
		(width 0.0889)
		(layer "F.Cu")
		(net "M_H_DQS_DP<3>")
	)
	(segment
		(start 64.549528 -11.773154)
		(end 64.587374 -11.811)
		(width 0.1651)
		(layer "B.Cu")
		(net "M_H_DQS_DP<3>")
	)
	(segment
		(start 64.587374 -13.0302)
		(end 64.329818 -13.287756)
		(width 0.1651)
		(layer "B.Cu")
		(net "M_H_DQS_DP<3>")
	)
	(segment
		(start 64.329818 -13.287756)
		(end 64.087502 -13.287756)
		(width 0.1651)
		(layer "B.Cu")
		(net "M_H_DQS_DP<3>")
	)
	(segment
		(start 64.549528 -10.623042)
		(end 64.549528 -11.773154)
		(width 0.1651)
		(layer "B.Cu")
		(net "M_H_DQS_DP<3>")
	)
	(segment
		(start 64.587374 -11.811)
		(end 64.587374 -13.0302)
		(width 0.1651)
		(layer "B.Cu")
		(net "M_H_DQS_DP<3>")
	)
	(segment
		(start 64.89827 -8.567928)
		(end 64.087502 -7.75716)
		(width 0.14224)
		(layer "In4.Cu")
		(net "M_H_DQS_DP<3>")
	)
	(segment
		(start 64.37122 -14.38148)
		(end 64.551306 -14.201394)
		(width 0.14224)
		(layer "In4.Cu")
		(net "M_H_DQS_DP<3>")
	)
	(segment
		(start 64.345566 -28.007056)
		(end 64.85382 -27.498802)
		(width 0.14224)
		(layer "In4.Cu")
		(net "M_H_DQS_DP<3>")
	)
	(segment
		(start 64.087502 -13.287756)
		(end 64.89827 -12.476988)
		(width 0.14224)
		(layer "In4.Cu")
		(net "M_H_DQS_DP<3>")
	)
	(segment
		(start 64.37122 -14.668246)
		(end 64.37122 -14.38148)
		(width 0.14224)
		(layer "In4.Cu")
		(net "M_H_DQS_DP<3>")
	)
	(segment
		(start 64.094106 -28.007056)
		(end 64.345566 -28.007056)
		(width 0.14224)
		(layer "In4.Cu")
		(net "M_H_DQS_DP<3>")
	)
	(segment
		(start 64.551306 -14.201394)
		(end 64.551306 -13.75156)
		(width 0.14224)
		(layer "In4.Cu")
		(net "M_H_DQS_DP<3>")
	)
	(segment
		(start 64.85382 -27.498802)
		(end 64.85382 -15.150846)
		(width 0.14224)
		(layer "In4.Cu")
		(net "M_H_DQS_DP<3>")
	)
	(segment
		(start 64.89827 -12.476988)
		(end 64.89827 -8.567928)
		(width 0.14224)
		(layer "In4.Cu")
		(net "M_H_DQS_DP<3>")
	)
	(segment
		(start 64.551306 -13.75156)
		(end 64.087502 -13.287756)
		(width 0.14224)
		(layer "In4.Cu")
		(net "M_H_DQS_DP<3>")
	)
	(segment
		(start 64.85382 -15.150846)
		(end 64.37122 -14.668246)
		(width 0.14224)
		(layer "In4.Cu")
		(net "M_H_DQS_DP<3>")
	)
	(segment
		(start 55.01132 -8.146034)
		(end 54.737508 -8.419846)
		(width 0.1651)
		(layer "F.Cu")
		(net "M_H_DQS_DP<2>")
	)
	(segment
		(start 73.758806 -53.113686)
		(end 73.187306 -53.113686)
		(width 0.1016)
		(layer "F.Cu")
		(net "M_H_DQS_DP<2>")
	)
	(segment
		(start 55.207154 -8.146034)
		(end 55.01132 -8.146034)
		(width 0.1651)
		(layer "F.Cu")
		(net "M_H_DQS_DP<2>")
	)
	(segment
		(start 55.19928 -10.422128)
		(end 55.19928 -9.323832)
		(width 0.1651)
		(layer "F.Cu")
		(net "M_H_DQS_DP<2>")
	)
	(segment
		(start 55.19928 -9.323832)
		(end 55.421022 -9.10209)
		(width 0.1651)
		(layer "F.Cu")
		(net "M_H_DQS_DP<2>")
	)
	(segment
		(start 55.421022 -8.359902)
		(end 55.207154 -8.146034)
		(width 0.1651)
		(layer "F.Cu")
		(net "M_H_DQS_DP<2>")
	)
	(segment
		(start 55.421022 -9.10209)
		(end 55.421022 -8.359902)
		(width 0.1651)
		(layer "F.Cu")
		(net "M_H_DQS_DP<2>")
	)
	(segment
		(start 55.199534 -10.422382)
		(end 55.19928 -10.422128)
		(width 0.1651)
		(layer "F.Cu")
		(net "M_H_DQS_DP<2>")
	)
	(via
		(at 54.737508 -8.419846)
		(size 0.508)
		(drill 0.254)
		(layers "F.Cu" "B.Cu")
		(net "M_H_DQS_DP<2>")
	)
	(via
		(at 73.187306 -53.113686)
		(size 0.508)
		(drill 0.254)
		(layers "F.Cu" "B.Cu")
		(net "M_H_DQS_DP<2>")
	)
	(via
		(at 54.737508 -12.627356)
		(size 0.508)
		(drill 0.254)
		(layers "F.Cu" "B.Cu")
		(net "M_H_DQS_DP<2>")
	)
	(segment
		(start 55.018432 -12.90828)
		(end 54.737508 -12.627356)
		(width 0.1651)
		(layer "B.Cu")
		(net "M_H_DQS_DP<2>")
	)
	(segment
		(start 55.199534 -10.623042)
		(end 55.199534 -10.972546)
		(width 0.1651)
		(layer "B.Cu")
		(net "M_H_DQS_DP<2>")
	)
	(segment
		(start 55.239412 -12.90828)
		(end 55.018432 -12.90828)
		(width 0.1651)
		(layer "B.Cu")
		(net "M_H_DQS_DP<2>")
	)
	(segment
		(start 55.379112 -12.319)
		(end 55.379112 -12.76858)
		(width 0.1651)
		(layer "B.Cu")
		(net "M_H_DQS_DP<2>")
	)
	(segment
		(start 55.379112 -12.76858)
		(end 55.239412 -12.90828)
		(width 0.1651)
		(layer "B.Cu")
		(net "M_H_DQS_DP<2>")
	)
	(segment
		(start 55.199534 -10.972546)
		(end 55.19928 -10.9728)
		(width 0.1651)
		(layer "B.Cu")
		(net "M_H_DQS_DP<2>")
	)
	(segment
		(start 55.19928 -10.9728)
		(end 55.19928 -12.139168)
		(width 0.1651)
		(layer "B.Cu")
		(net "M_H_DQS_DP<2>")
	)
	(segment
		(start 55.19928 -12.139168)
		(end 55.379112 -12.319)
		(width 0.1651)
		(layer "B.Cu")
		(net "M_H_DQS_DP<2>")
	)
	(segment
		(start 54.299612 -14.663166)
		(end 54.299612 -13.065252)
		(width 0.14224)
		(layer "In4.Cu")
		(net "M_H_DQS_DP<2>")
	)
	(segment
		(start 55.279036 -12.364974)
		(end 55.279036 -11.660124)
		(width 0.14224)
		(layer "In4.Cu")
		(net "M_H_DQS_DP<2>")
	)
	(segment
		(start 54.737508 -12.627356)
		(end 54.737508 -12.62761)
		(width 0.14224)
		(layer "In4.Cu")
		(net "M_H_DQS_DP<2>")
	)
	(segment
		(start 55.250588 -29.388054)
		(end 55.250588 -15.82547)
		(width 0.14224)
		(layer "In4.Cu")
		(net "M_H_DQS_DP<2>")
	)
	(segment
		(start 54.299612 -13.065252)
		(end 54.737508 -12.627356)
		(width 0.14224)
		(layer "In4.Cu")
		(net "M_H_DQS_DP<2>")
	)
	(segment
		(start 54.896766 -9.525)
		(end 55.099458 -9.525)
		(width 0.14224)
		(layer "In4.Cu")
		(net "M_H_DQS_DP<2>")
	)
	(segment
		(start 54.791356 -11.303)
		(end 54.791356 -11.049)
		(width 0.14224)
		(layer "In4.Cu")
		(net "M_H_DQS_DP<2>")
	)
	(segment
		(start 73.187306 -53.113686)
		(end 73.187306 -53.45176)
		(width 0.0889)
		(layer "In4.Cu")
		(net "M_H_DQS_DP<2>")
	)
	(segment
		(start 54.737508 -12.62761)
		(end 55.0164 -12.62761)
		(width 0.14224)
		(layer "In4.Cu")
		(net "M_H_DQS_DP<2>")
	)
	(segment
		(start 55.279036 -10.339578)
		(end 55.074058 -10.1346)
		(width 0.14224)
		(layer "In4.Cu")
		(net "M_H_DQS_DP<2>")
	)
	(segment
		(start 65.128648 -42.644314)
		(end 65.128648 -39.266114)
		(width 0.14224)
		(layer "In4.Cu")
		(net "M_H_DQS_DP<2>")
	)
	(segment
		(start 55.279036 -11.660124)
		(end 55.099712 -11.4808)
		(width 0.14224)
		(layer "In4.Cu")
		(net "M_H_DQS_DP<2>")
	)
	(segment
		(start 55.099712 -11.4808)
		(end 54.969156 -11.4808)
		(width 0.14224)
		(layer "In4.Cu")
		(net "M_H_DQS_DP<2>")
	)
	(segment
		(start 65.129156 -42.64406)
		(end 65.128648 -42.644314)
		(width 0.14224)
		(layer "In4.Cu")
		(net "M_H_DQS_DP<2>")
	)
	(segment
		(start 55.250588 -15.82547)
		(end 54.418992 -14.993874)
		(width 0.14224)
		(layer "In4.Cu")
		(net "M_H_DQS_DP<2>")
	)
	(segment
		(start 54.744112 -9.677654)
		(end 54.896766 -9.525)
		(width 0.14224)
		(layer "In4.Cu")
		(net "M_H_DQS_DP<2>")
	)
	(segment
		(start 54.896766 -10.1346)
		(end 54.744112 -9.981946)
		(width 0.14224)
		(layer "In4.Cu")
		(net "M_H_DQS_DP<2>")
	)
	(segment
		(start 54.969156 -11.4808)
		(end 54.791356 -11.303)
		(width 0.14224)
		(layer "In4.Cu")
		(net "M_H_DQS_DP<2>")
	)
	(segment
		(start 54.969156 -10.8712)
		(end 55.096156 -10.8712)
		(width 0.14224)
		(layer "In4.Cu")
		(net "M_H_DQS_DP<2>")
	)
	(segment
		(start 55.019194 -8.419846)
		(end 54.737508 -8.419846)
		(width 0.14224)
		(layer "In4.Cu")
		(net "M_H_DQS_DP<2>")
	)
	(segment
		(start 55.099458 -9.525)
		(end 55.279036 -9.345422)
		(width 0.14224)
		(layer "In4.Cu")
		(net "M_H_DQS_DP<2>")
	)
	(segment
		(start 73.413366 -49.992026)
		(end 72.44588 -49.02454)
		(width 0.0889)
		(layer "In4.Cu")
		(net "M_H_DQS_DP<2>")
	)
	(segment
		(start 55.279036 -9.345422)
		(end 55.279036 -8.679688)
		(width 0.14224)
		(layer "In4.Cu")
		(net "M_H_DQS_DP<2>")
	)
	(segment
		(start 73.538842 -50.941224)
		(end 73.413366 -50.723546)
		(width 0.0889)
		(layer "In4.Cu")
		(net "M_H_DQS_DP<2>")
	)
	(segment
		(start 54.418992 -14.993874)
		(end 54.418992 -14.782546)
		(width 0.14224)
		(layer "In4.Cu")
		(net "M_H_DQS_DP<2>")
	)
	(segment
		(start 55.096156 -10.8712)
		(end 55.279036 -10.68832)
		(width 0.14224)
		(layer "In4.Cu")
		(net "M_H_DQS_DP<2>")
	)
	(segment
		(start 54.791356 -11.049)
		(end 54.969156 -10.8712)
		(width 0.14224)
		(layer "In4.Cu")
		(net "M_H_DQS_DP<2>")
	)
	(segment
		(start 68.463668 -45.978572)
		(end 65.129156 -42.64406)
		(width 0.14224)
		(layer "In4.Cu")
		(net "M_H_DQS_DP<2>")
	)
	(segment
		(start 55.074058 -10.1346)
		(end 54.896766 -10.1346)
		(width 0.14224)
		(layer "In4.Cu")
		(net "M_H_DQS_DP<2>")
	)
	(segment
		(start 73.538842 -52.922424)
		(end 73.534016 -52.913788)
		(width 0.0889)
		(layer "In4.Cu")
		(net "M_H_DQS_DP<2>")
	)
	(segment
		(start 73.527666 -52.333906)
		(end 73.534016 -52.323238)
		(width 0.0889)
		(layer "In4.Cu")
		(net "M_H_DQS_DP<2>")
	)
	(segment
		(start 73.413366 -50.723546)
		(end 73.413366 -49.992026)
		(width 0.0889)
		(layer "In4.Cu")
		(net "M_H_DQS_DP<2>")
	)
	(segment
		(start 65.128648 -39.266114)
		(end 55.250588 -29.388054)
		(width 0.14224)
		(layer "In4.Cu")
		(net "M_H_DQS_DP<2>")
	)
	(segment
		(start 55.0164 -12.62761)
		(end 55.279036 -12.364974)
		(width 0.14224)
		(layer "In4.Cu")
		(net "M_H_DQS_DP<2>")
	)
	(segment
		(start 54.418992 -14.782546)
		(end 54.299612 -14.663166)
		(width 0.14224)
		(layer "In4.Cu")
		(net "M_H_DQS_DP<2>")
	)
	(segment
		(start 73.187306 -53.45176)
		(end 73.245218 -53.509672)
		(width 0.0889)
		(layer "In4.Cu")
		(net "M_H_DQS_DP<2>")
	)
	(segment
		(start 69.283326 -47.233586)
		(end 68.463668 -46.413928)
		(width 0.14224)
		(layer "In4.Cu")
		(net "M_H_DQS_DP<2>")
	)
	(segment
		(start 55.279036 -8.679688)
		(end 55.019194 -8.419846)
		(width 0.14224)
		(layer "In4.Cu")
		(net "M_H_DQS_DP<2>")
	)
	(segment
		(start 69.3547 -47.249334)
		(end 69.299074 -47.249334)
		(width 0.0889)
		(layer "In4.Cu")
		(net "M_H_DQS_DP<2>")
	)
	(segment
		(start 69.299074 -47.249334)
		(end 69.283326 -47.233586)
		(width 0.0889)
		(layer "In4.Cu")
		(net "M_H_DQS_DP<2>")
	)
	(segment
		(start 68.463668 -46.413928)
		(end 68.463668 -45.978572)
		(width 0.14224)
		(layer "In4.Cu")
		(net "M_H_DQS_DP<2>")
	)
	(segment
		(start 71.129906 -49.02454)
		(end 69.3547 -47.249334)
		(width 0.0889)
		(layer "In4.Cu")
		(net "M_H_DQS_DP<2>")
	)
	(segment
		(start 72.44588 -49.02454)
		(end 71.129906 -49.02454)
		(width 0.0889)
		(layer "In4.Cu")
		(net "M_H_DQS_DP<2>")
	)
	(segment
		(start 55.279036 -10.68832)
		(end 55.279036 -10.339578)
		(width 0.14224)
		(layer "In4.Cu")
		(net "M_H_DQS_DP<2>")
	)
	(segment
		(start 54.744112 -9.981946)
		(end 54.744112 -9.677654)
		(width 0.14224)
		(layer "In4.Cu")
		(net "M_H_DQS_DP<2>")
	)
	(arc
		(start 73.534016 -51.923442)
		(mid 73.454885 -51.62804)
		(end 73.534016 -51.332638)
		(width 0.0889)
		(layer "In4.Cu")
		(net "M_H_DQS_DP<2>")
	)
	(arc
		(start 73.534016 -51.332638)
		(mid 73.587486 -51.137575)
		(end 73.538842 -50.941224)
		(width 0.0889)
		(layer "In4.Cu")
		(net "M_H_DQS_DP<2>")
	)
	(arc
		(start 73.245218 -53.509672)
		(mid 73.545254 -53.29266)
		(end 73.538842 -52.922424)
		(width 0.0889)
		(layer "In4.Cu")
		(net "M_H_DQS_DP<2>")
	)
	(arc
		(start 73.534016 -52.913788)
		(mid 73.454794 -52.62467)
		(end 73.527666 -52.333906)
		(width 0.0889)
		(layer "In4.Cu")
		(net "M_H_DQS_DP<2>")
	)
	(arc
		(start 73.534016 -52.323238)
		(mid 73.587515 -52.12334)
		(end 73.534016 -51.923442)
		(width 0.0889)
		(layer "In4.Cu")
		(net "M_H_DQS_DP<2>")
	)
	(segment
		(start 72.900286 -61.53404)
		(end 72.328786 -61.53404)
		(width 0.1016)
		(layer "F.Cu")
		(net "M_H_DQS_DP<1>")
	)
	(segment
		(start 45.849286 -10.422128)
		(end 45.849286 -9.323832)
		(width 0.1651)
		(layer "F.Cu")
		(net "M_H_DQS_DP<1>")
	)
	(segment
		(start 45.84954 -10.422382)
		(end 45.849286 -10.422128)
		(width 0.1651)
		(layer "F.Cu")
		(net "M_H_DQS_DP<1>")
	)
	(segment
		(start 45.849286 -9.323832)
		(end 46.071028 -9.10209)
		(width 0.1651)
		(layer "F.Cu")
		(net "M_H_DQS_DP<1>")
	)
	(segment
		(start 46.071028 -8.359902)
		(end 45.85716 -8.146034)
		(width 0.1651)
		(layer "F.Cu")
		(net "M_H_DQS_DP<1>")
	)
	(segment
		(start 45.661326 -8.146034)
		(end 45.387514 -8.419846)
		(width 0.1651)
		(layer "F.Cu")
		(net "M_H_DQS_DP<1>")
	)
	(segment
		(start 46.071028 -9.10209)
		(end 46.071028 -8.359902)
		(width 0.1651)
		(layer "F.Cu")
		(net "M_H_DQS_DP<1>")
	)
	(segment
		(start 45.85716 -8.146034)
		(end 45.661326 -8.146034)
		(width 0.1651)
		(layer "F.Cu")
		(net "M_H_DQS_DP<1>")
	)
	(via
		(at 45.387514 -12.627356)
		(size 0.508)
		(drill 0.254)
		(layers "F.Cu" "B.Cu")
		(net "M_H_DQS_DP<1>")
	)
	(via
		(at 72.328786 -61.53404)
		(size 0.508)
		(drill 0.254)
		(layers "F.Cu" "B.Cu")
		(net "M_H_DQS_DP<1>")
	)
	(via
		(at 45.387514 -8.419846)
		(size 0.508)
		(drill 0.254)
		(layers "F.Cu" "B.Cu")
		(net "M_H_DQS_DP<1>")
	)
	(segment
		(start 46.029118 -12.121896)
		(end 46.029118 -12.76858)
		(width 0.1651)
		(layer "B.Cu")
		(net "M_H_DQS_DP<1>")
	)
	(segment
		(start 45.849286 -11.942064)
		(end 46.029118 -12.121896)
		(width 0.1651)
		(layer "B.Cu")
		(net "M_H_DQS_DP<1>")
	)
	(segment
		(start 45.668438 -12.90828)
		(end 45.387514 -12.627356)
		(width 0.1651)
		(layer "B.Cu")
		(net "M_H_DQS_DP<1>")
	)
	(segment
		(start 45.84954 -10.972546)
		(end 45.849286 -10.9728)
		(width 0.1651)
		(layer "B.Cu")
		(net "M_H_DQS_DP<1>")
	)
	(segment
		(start 45.84954 -10.623042)
		(end 45.84954 -10.972546)
		(width 0.1651)
		(layer "B.Cu")
		(net "M_H_DQS_DP<1>")
	)
	(segment
		(start 46.029118 -12.76858)
		(end 45.889418 -12.90828)
		(width 0.1651)
		(layer "B.Cu")
		(net "M_H_DQS_DP<1>")
	)
	(segment
		(start 45.889418 -12.90828)
		(end 45.668438 -12.90828)
		(width 0.1651)
		(layer "B.Cu")
		(net "M_H_DQS_DP<1>")
	)
	(segment
		(start 45.849286 -10.9728)
		(end 45.849286 -11.942064)
		(width 0.1651)
		(layer "B.Cu")
		(net "M_H_DQS_DP<1>")
	)
	(segment
		(start 45.6692 -8.419846)
		(end 45.387514 -8.419846)
		(width 0.14224)
		(layer "In4.Cu")
		(net "M_H_DQS_DP<1>")
	)
	(segment
		(start 44.949618 -14.663166)
		(end 45.068998 -14.782546)
		(width 0.14224)
		(layer "In4.Cu")
		(net "M_H_DQS_DP<1>")
	)
	(segment
		(start 45.387514 -12.627356)
		(end 45.387514 -12.62761)
		(width 0.14224)
		(layer "In4.Cu")
		(net "M_H_DQS_DP<1>")
	)
	(segment
		(start 45.929042 -10.339578)
		(end 45.724064 -10.1346)
		(width 0.14224)
		(layer "In4.Cu")
		(net "M_H_DQS_DP<1>")
	)
	(segment
		(start 44.949618 -13.065252)
		(end 44.949618 -14.663166)
		(width 0.14224)
		(layer "In4.Cu")
		(net "M_H_DQS_DP<1>")
	)
	(segment
		(start 48.378364 -35.845496)
		(end 48.819562 -35.845496)
		(width 0.14224)
		(layer "In4.Cu")
		(net "M_H_DQS_DP<1>")
	)
	(segment
		(start 45.068998 -14.993874)
		(end 45.900594 -15.82547)
		(width 0.14224)
		(layer "In4.Cu")
		(net "M_H_DQS_DP<1>")
	)
	(segment
		(start 46.180248 -24.152352)
		(end 46.180248 -31.552134)
		(width 0.14224)
		(layer "In4.Cu")
		(net "M_H_DQS_DP<1>")
	)
	(segment
		(start 45.929042 -8.679688)
		(end 45.6692 -8.419846)
		(width 0.14224)
		(layer "In4.Cu")
		(net "M_H_DQS_DP<1>")
	)
	(segment
		(start 70.61073 -62.124336)
		(end 70.612254 -62.124336)
		(width 0.0889)
		(layer "In4.Cu")
		(net "M_H_DQS_DP<1>")
	)
	(segment
		(start 45.749718 -11.4808)
		(end 45.619162 -11.4808)
		(width 0.14224)
		(layer "In4.Cu")
		(net "M_H_DQS_DP<1>")
	)
	(segment
		(start 45.900594 -23.872698)
		(end 46.180248 -24.152352)
		(width 0.14224)
		(layer "In4.Cu")
		(net "M_H_DQS_DP<1>")
	)
	(segment
		(start 45.387514 -12.62761)
		(end 45.666406 -12.62761)
		(width 0.14224)
		(layer "In4.Cu")
		(net "M_H_DQS_DP<1>")
	)
	(segment
		(start 69.162676 -59.188096)
		(end 69.162676 -60.207144)
		(width 0.0889)
		(layer "In4.Cu")
		(net "M_H_DQS_DP<1>")
	)
	(segment
		(start 69.162676 -60.207144)
		(end 69.241416 -60.343288)
		(width 0.0889)
		(layer "In4.Cu")
		(net "M_H_DQS_DP<1>")
	)
	(segment
		(start 45.394118 -9.677654)
		(end 45.546772 -9.525)
		(width 0.14224)
		(layer "In4.Cu")
		(net "M_H_DQS_DP<1>")
	)
	(segment
		(start 45.546772 -9.525)
		(end 45.749464 -9.525)
		(width 0.14224)
		(layer "In4.Cu")
		(net "M_H_DQS_DP<1>")
	)
	(segment
		(start 48.68672 -34.058606)
		(end 48.68672 -34.277554)
		(width 0.14224)
		(layer "In4.Cu")
		(net "M_H_DQS_DP<1>")
	)
	(segment
		(start 45.619162 -11.4808)
		(end 45.441362 -11.303)
		(width 0.14224)
		(layer "In4.Cu")
		(net "M_H_DQS_DP<1>")
	)
	(segment
		(start 72.3138 -61.13399)
		(end 72.343772 -61.13399)
		(width 0.0889)
		(layer "In4.Cu")
		(net "M_H_DQS_DP<1>")
	)
	(segment
		(start 68.997322 -58.605674)
		(end 69.036692 -58.645044)
		(width 0.0889)
		(layer "In4.Cu")
		(net "M_H_DQS_DP<1>")
	)
	(segment
		(start 71.45909 -61.629036)
		(end 71.491856 -61.629036)
		(width 0.0889)
		(layer "In4.Cu")
		(net "M_H_DQS_DP<1>")
	)
	(segment
		(start 45.387514 -12.627356)
		(end 44.949618 -13.065252)
		(width 0.14224)
		(layer "In4.Cu")
		(net "M_H_DQS_DP<1>")
	)
	(segment
		(start 69.036692 -58.645044)
		(end 69.036692 -59.062112)
		(width 0.0889)
		(layer "In4.Cu")
		(net "M_H_DQS_DP<1>")
	)
	(segment
		(start 45.929042 -10.68832)
		(end 45.929042 -10.339578)
		(width 0.14224)
		(layer "In4.Cu")
		(net "M_H_DQS_DP<1>")
	)
	(segment
		(start 68.997322 -57.77103)
		(end 68.997322 -58.583576)
		(width 0.14224)
		(layer "In4.Cu")
		(net "M_H_DQS_DP<1>")
	)
	(segment
		(start 45.394118 -9.981946)
		(end 45.394118 -9.677654)
		(width 0.14224)
		(layer "In4.Cu")
		(net "M_H_DQS_DP<1>")
	)
	(segment
		(start 45.749464 -9.525)
		(end 45.929042 -9.345422)
		(width 0.14224)
		(layer "In4.Cu")
		(net "M_H_DQS_DP<1>")
	)
	(segment
		(start 49.75606 -35.127946)
		(end 51.209448 -36.581334)
		(width 0.14224)
		(layer "In4.Cu")
		(net "M_H_DQS_DP<1>")
	)
	(segment
		(start 45.900594 -15.82547)
		(end 45.900594 -23.872698)
		(width 0.14224)
		(layer "In4.Cu")
		(net "M_H_DQS_DP<1>")
	)
	(segment
		(start 50.752248 -38.966648)
		(end 50.752248 -39.526718)
		(width 0.14224)
		(layer "In4.Cu")
		(net "M_H_DQS_DP<1>")
	)
	(segment
		(start 45.929042 -9.345422)
		(end 45.929042 -8.679688)
		(width 0.14224)
		(layer "In4.Cu")
		(net "M_H_DQS_DP<1>")
	)
	(segment
		(start 45.724064 -10.1346)
		(end 45.546772 -10.1346)
		(width 0.14224)
		(layer "In4.Cu")
		(net "M_H_DQS_DP<1>")
	)
	(segment
		(start 68.997322 -58.583576)
		(end 68.997322 -58.605674)
		(width 0.0889)
		(layer "In4.Cu")
		(net "M_H_DQS_DP<1>")
	)
	(segment
		(start 46.180248 -31.552134)
		(end 48.68672 -34.058606)
		(width 0.14224)
		(layer "In4.Cu")
		(net "M_H_DQS_DP<1>")
	)
	(segment
		(start 47.969424 -35.436556)
		(end 48.378364 -35.845496)
		(width 0.14224)
		(layer "In4.Cu")
		(net "M_H_DQS_DP<1>")
	)
	(segment
		(start 72.642984 -61.286136)
		(end 72.621902 -61.364876)
		(width 0.0889)
		(layer "In4.Cu")
		(net "M_H_DQS_DP<1>")
	)
	(segment
		(start 45.929042 -12.364974)
		(end 45.929042 -11.660124)
		(width 0.14224)
		(layer "In4.Cu")
		(net "M_H_DQS_DP<1>")
	)
	(segment
		(start 45.929042 -11.660124)
		(end 45.749718 -11.4808)
		(width 0.14224)
		(layer "In4.Cu")
		(net "M_H_DQS_DP<1>")
	)
	(segment
		(start 51.209448 -36.581334)
		(end 51.209448 -38.509448)
		(width 0.14224)
		(layer "In4.Cu")
		(net "M_H_DQS_DP<1>")
	)
	(segment
		(start 50.752756 -39.526464)
		(end 68.997322 -57.77103)
		(width 0.14224)
		(layer "In4.Cu")
		(net "M_H_DQS_DP<1>")
	)
	(segment
		(start 51.209448 -38.509448)
		(end 50.752248 -38.966648)
		(width 0.14224)
		(layer "In4.Cu")
		(net "M_H_DQS_DP<1>")
	)
	(segment
		(start 45.619162 -10.8712)
		(end 45.746162 -10.8712)
		(width 0.14224)
		(layer "In4.Cu")
		(net "M_H_DQS_DP<1>")
	)
	(segment
		(start 45.546772 -10.1346)
		(end 45.394118 -9.981946)
		(width 0.14224)
		(layer "In4.Cu")
		(net "M_H_DQS_DP<1>")
	)
	(segment
		(start 45.441362 -11.049)
		(end 45.619162 -10.8712)
		(width 0.14224)
		(layer "In4.Cu")
		(net "M_H_DQS_DP<1>")
	)
	(segment
		(start 45.666406 -12.62761)
		(end 45.929042 -12.364974)
		(width 0.14224)
		(layer "In4.Cu")
		(net "M_H_DQS_DP<1>")
	)
	(segment
		(start 48.68672 -34.277554)
		(end 47.969424 -34.99485)
		(width 0.14224)
		(layer "In4.Cu")
		(net "M_H_DQS_DP<1>")
	)
	(segment
		(start 45.068998 -14.782546)
		(end 45.068998 -14.993874)
		(width 0.14224)
		(layer "In4.Cu")
		(net "M_H_DQS_DP<1>")
	)
	(segment
		(start 47.969424 -34.99485)
		(end 47.969424 -35.436556)
		(width 0.14224)
		(layer "In4.Cu")
		(net "M_H_DQS_DP<1>")
	)
	(segment
		(start 69.731636 -61.629036)
		(end 69.764402 -61.629036)
		(width 0.0889)
		(layer "In4.Cu")
		(net "M_H_DQS_DP<1>")
	)
	(segment
		(start 45.746162 -10.8712)
		(end 45.929042 -10.68832)
		(width 0.14224)
		(layer "In4.Cu")
		(net "M_H_DQS_DP<1>")
	)
	(segment
		(start 49.537112 -35.127946)
		(end 49.75606 -35.127946)
		(width 0.14224)
		(layer "In4.Cu")
		(net "M_H_DQS_DP<1>")
	)
	(segment
		(start 72.621902 -61.364876)
		(end 72.328786 -61.53404)
		(width 0.0889)
		(layer "In4.Cu")
		(net "M_H_DQS_DP<1>")
	)
	(segment
		(start 45.441362 -11.303)
		(end 45.441362 -11.049)
		(width 0.14224)
		(layer "In4.Cu")
		(net "M_H_DQS_DP<1>")
	)
	(segment
		(start 48.819562 -35.845496)
		(end 49.537112 -35.127946)
		(width 0.14224)
		(layer "In4.Cu")
		(net "M_H_DQS_DP<1>")
	)
	(segment
		(start 50.752248 -39.526718)
		(end 50.752756 -39.526464)
		(width 0.14224)
		(layer "In4.Cu")
		(net "M_H_DQS_DP<1>")
	)
	(segment
		(start 69.036692 -59.062112)
		(end 69.162676 -59.188096)
		(width 0.0889)
		(layer "In4.Cu")
		(net "M_H_DQS_DP<1>")
	)
	(arc
		(start 69.241416 -60.743084)
		(mid 69.236162 -61.324592)
		(end 69.731636 -61.629036)
		(width 0.0889)
		(layer "In4.Cu")
		(net "M_H_DQS_DP<1>")
	)
	(arc
		(start 70.099936 -61.829188)
		(mid 70.31579 -62.045169)
		(end 70.61073 -62.124336)
		(width 0.0889)
		(layer "In4.Cu")
		(net "M_H_DQS_DP<1>")
	)
	(arc
		(start 71.982076 -61.333888)
		(mid 72.122155 -61.191152)
		(end 72.3138 -61.13399)
		(width 0.0889)
		(layer "In4.Cu")
		(net "M_H_DQS_DP<1>")
	)
	(arc
		(start 69.241416 -60.343288)
		(mid 69.294915 -60.543186)
		(end 69.241416 -60.743084)
		(width 0.0889)
		(layer "In4.Cu")
		(net "M_H_DQS_DP<1>")
	)
	(arc
		(start 69.764402 -61.629036)
		(mid 69.958252 -61.685386)
		(end 70.099936 -61.829188)
		(width 0.0889)
		(layer "In4.Cu")
		(net "M_H_DQS_DP<1>")
	)
	(arc
		(start 71.123556 -61.829188)
		(mid 71.265239 -61.685384)
		(end 71.45909 -61.629036)
		(width 0.0889)
		(layer "In4.Cu")
		(net "M_H_DQS_DP<1>")
	)
	(arc
		(start 71.491856 -61.629036)
		(mid 71.775073 -61.544755)
		(end 71.982076 -61.333888)
		(width 0.0889)
		(layer "In4.Cu")
		(net "M_H_DQS_DP<1>")
	)
	(arc
		(start 70.612254 -62.124336)
		(mid 70.907536 -62.045389)
		(end 71.123556 -61.829188)
		(width 0.0889)
		(layer "In4.Cu")
		(net "M_H_DQS_DP<1>")
	)
	(arc
		(start 72.343772 -61.13399)
		(mid 72.510066 -61.177224)
		(end 72.642984 -61.286136)
		(width 0.0889)
		(layer "In4.Cu")
		(net "M_H_DQS_DP<1>")
	)
	(segment
		(start 73.861168 -34.700718)
		(end 73.861168 -34.039302)
		(width 0.1651)
		(layer "F.Cu")
		(net "M_H_DQS_DP<17>")
	)
	(segment
		(start 82.938366 -48.24984)
		(end 79.03464 -44.346114)
		(width 0.1016)
		(layer "F.Cu")
		(net "M_H_DQS_DP<17>")
	)
	(segment
		(start 83.013042 -50.277014)
		(end 82.938366 -50.202338)
		(width 0.0889)
		(layer "F.Cu")
		(net "M_H_DQS_DP<17>")
	)
	(segment
		(start 73.619868 -36.547806)
		(end 74.061574 -36.1061)
		(width 0.1651)
		(layer "F.Cu")
		(net "M_H_DQS_DP<17>")
	)
	(segment
		(start 74.813668 -35.924236)
		(end 74.813668 -35.16376)
		(width 0.1651)
		(layer "F.Cu")
		(net "M_H_DQS_DP<17>")
	)
	(segment
		(start 74.15911 -33.74136)
		(end 74.648568 -33.74136)
		(width 0.1651)
		(layer "F.Cu")
		(net "M_H_DQS_DP<17>")
	)
	(segment
		(start 71.776082 -29.030168)
		(end 71.676768 -28.930854)
		(width 0.1651)
		(layer "F.Cu")
		(net "M_H_DQS_DP<17>")
	)
	(segment
		(start 71.6788 -7.059168)
		(end 71.6788 -7.877302)
		(width 0.1651)
		(layer "F.Cu")
		(net "M_H_DQS_DP<17>")
	)
	(segment
		(start 74.813668 -32.968946)
		(end 71.747634 -29.902912)
		(width 0.1651)
		(layer "F.Cu")
		(net "M_H_DQS_DP<17>")
	)
	(segment
		(start 71.676768 -27.869642)
		(end 72.1487 -27.39771)
		(width 0.1651)
		(layer "F.Cu")
		(net "M_H_DQS_DP<17>")
	)
	(segment
		(start 73.861168 -34.039302)
		(end 74.15911 -33.74136)
		(width 0.1651)
		(layer "F.Cu")
		(net "M_H_DQS_DP<17>")
	)
	(segment
		(start 71.676768 -28.930854)
		(end 71.676768 -27.869642)
		(width 0.1651)
		(layer "F.Cu")
		(net "M_H_DQS_DP<17>")
	)
	(segment
		(start 79.03464 -44.346114)
		(end 78.192884 -44.346114)
		(width 0.1016)
		(layer "F.Cu")
		(net "M_H_DQS_DP<17>")
	)
	(segment
		(start 71.776082 -29.263848)
		(end 71.776082 -29.030168)
		(width 0.1651)
		(layer "F.Cu")
		(net "M_H_DQS_DP<17>")
	)
	(segment
		(start 75.701144 -43.288204)
		(end 73.619868 -41.206928)
		(width 0.1651)
		(layer "F.Cu")
		(net "M_H_DQS_DP<17>")
	)
	(segment
		(start 71.747634 -29.292296)
		(end 71.776082 -29.263848)
		(width 0.1651)
		(layer "F.Cu")
		(net "M_H_DQS_DP<17>")
	)
	(segment
		(start 83.202272 -53.60924)
		(end 82.855308 -52.818538)
		(width 0.0889)
		(layer "F.Cu")
		(net "M_H_DQS_DP<17>")
	)
	(segment
		(start 74.813668 -35.16376)
		(end 74.648568 -34.99866)
		(width 0.1651)
		(layer "F.Cu")
		(net "M_H_DQS_DP<17>")
	)
	(segment
		(start 74.631804 -36.1061)
		(end 74.813668 -35.924236)
		(width 0.1651)
		(layer "F.Cu")
		(net "M_H_DQS_DP<17>")
	)
	(segment
		(start 74.648568 -34.99866)
		(end 74.15911 -34.99866)
		(width 0.1651)
		(layer "F.Cu")
		(net "M_H_DQS_DP<17>")
	)
	(segment
		(start 71.747634 -29.902912)
		(end 71.747634 -29.292296)
		(width 0.1651)
		(layer "F.Cu")
		(net "M_H_DQS_DP<17>")
	)
	(segment
		(start 82.938366 -50.202338)
		(end 82.938366 -50.073814)
		(width 0.0889)
		(layer "F.Cu")
		(net "M_H_DQS_DP<17>")
	)
	(segment
		(start 74.061574 -36.1061)
		(end 74.631804 -36.1061)
		(width 0.1651)
		(layer "F.Cu")
		(net "M_H_DQS_DP<17>")
	)
	(segment
		(start 71.763382 -6.875272)
		(end 71.6788 -7.059168)
		(width 0.1651)
		(layer "F.Cu")
		(net "M_H_DQS_DP<17>")
	)
	(segment
		(start 74.813668 -33.57626)
		(end 74.813668 -32.968946)
		(width 0.1651)
		(layer "F.Cu")
		(net "M_H_DQS_DP<17>")
	)
	(segment
		(start 73.619868 -41.206928)
		(end 73.619868 -36.547806)
		(width 0.1651)
		(layer "F.Cu")
		(net "M_H_DQS_DP<17>")
	)
	(segment
		(start 71.760334 -8.101584)
		(end 72.142096 -8.483346)
		(width 0.1651)
		(layer "F.Cu")
		(net "M_H_DQS_DP<17>")
	)
	(segment
		(start 74.15911 -34.99866)
		(end 73.861168 -34.700718)
		(width 0.1651)
		(layer "F.Cu")
		(net "M_H_DQS_DP<17>")
	)
	(segment
		(start 83.013042 -51.812952)
		(end 83.013042 -50.277014)
		(width 0.0889)
		(layer "F.Cu")
		(net "M_H_DQS_DP<17>")
	)
	(segment
		(start 74.648568 -33.74136)
		(end 74.813668 -33.57626)
		(width 0.1651)
		(layer "F.Cu")
		(net "M_H_DQS_DP<17>")
	)
	(segment
		(start 72.1995 -6.439154)
		(end 71.763382 -6.875272)
		(width 0.1651)
		(layer "F.Cu")
		(net "M_H_DQS_DP<17>")
	)
	(segment
		(start 71.6788 -7.877302)
		(end 71.760334 -8.101584)
		(width 0.1651)
		(layer "F.Cu")
		(net "M_H_DQS_DP<17>")
	)
	(segment
		(start 72.1995 -5.822442)
		(end 72.1995 -6.439154)
		(width 0.1651)
		(layer "F.Cu")
		(net "M_H_DQS_DP<17>")
	)
	(segment
		(start 76.035408 -43.622468)
		(end 75.701144 -43.288204)
		(width 0.1016)
		(layer "F.Cu")
		(net "M_H_DQS_DP<17>")
	)
	(segment
		(start 82.938366 -50.073814)
		(end 82.938366 -48.24984)
		(width 0.1016)
		(layer "F.Cu")
		(net "M_H_DQS_DP<17>")
	)
	(segment
		(start 77.469238 -43.622468)
		(end 76.035408 -43.622468)
		(width 0.1016)
		(layer "F.Cu")
		(net "M_H_DQS_DP<17>")
	)
	(segment
		(start 78.192884 -44.346114)
		(end 77.469238 -43.622468)
		(width 0.1016)
		(layer "F.Cu")
		(net "M_H_DQS_DP<17>")
	)
	(segment
		(start 82.850482 -52.427124)
		(end 82.855308 -52.418488)
		(width 0.0889)
		(layer "F.Cu")
		(net "M_H_DQS_DP<17>")
	)
	(via
		(at 72.1487 -27.39771)
		(size 0.508)
		(drill 0.254)
		(layers "F.Cu" "B.Cu")
		(net "M_H_DQS_DP<17>")
	)
	(via
		(at 72.142096 -8.483346)
		(size 0.508)
		(drill 0.254)
		(layers "F.Cu" "B.Cu")
		(net "M_H_DQS_DP<17>")
	)
	(via
		(at 72.142096 -12.573)
		(size 0.508)
		(drill 0.254)
		(layers "F.Cu" "B.Cu")
		(net "M_H_DQS_DP<17>")
	)
	(arc
		(start 82.921348 -52.281328)
		(mid 82.989932 -52.051589)
		(end 83.013042 -51.812952)
		(width 0.0889)
		(layer "F.Cu")
		(net "M_H_DQS_DP<17>")
	)
	(arc
		(start 82.855308 -52.418488)
		(mid 82.890437 -52.350923)
		(end 82.921348 -52.281328)
		(width 0.0889)
		(layer "F.Cu")
		(net "M_H_DQS_DP<17>")
	)
	(arc
		(start 82.855308 -52.818538)
		(mid 82.801872 -52.623475)
		(end 82.850482 -52.427124)
		(width 0.0889)
		(layer "F.Cu")
		(net "M_H_DQS_DP<17>")
	)
	(segment
		(start 71.743316 -14.14907)
		(end 71.6661 -14.016736)
		(width 0.1651)
		(layer "B.Cu")
		(net "M_H_DQS_DP<17>")
	)
	(segment
		(start 71.753476 -12.96162)
		(end 72.142096 -12.573)
		(width 0.1651)
		(layer "B.Cu")
		(net "M_H_DQS_DP<17>")
	)
	(segment
		(start 72.1995 -14.605254)
		(end 71.743316 -14.14907)
		(width 0.1651)
		(layer "B.Cu")
		(net "M_H_DQS_DP<17>")
	)
	(segment
		(start 71.6661 -13.121132)
		(end 71.753476 -12.96162)
		(width 0.1651)
		(layer "B.Cu")
		(net "M_H_DQS_DP<17>")
	)
	(segment
		(start 71.6661 -14.016736)
		(end 71.6661 -13.121132)
		(width 0.1651)
		(layer "B.Cu")
		(net "M_H_DQS_DP<17>")
	)
	(segment
		(start 72.1995 -15.222982)
		(end 72.1995 -14.605254)
		(width 0.1651)
		(layer "B.Cu")
		(net "M_H_DQS_DP<17>")
	)
	(segment
		(start 72.3265 -10.1854)
		(end 72.1741 -10.033)
		(width 0.14224)
		(layer "In11.Cu")
		(net "M_H_DQS_DP<17>")
	)
	(segment
		(start 72.1741 -10.033)
		(end 72.1741 -9.779)
		(width 0.14224)
		(layer "In11.Cu")
		(net "M_H_DQS_DP<17>")
	)
	(segment
		(start 72.131174 -14.55928)
		(end 71.6407 -14.068806)
		(width 0.14224)
		(layer "In11.Cu")
		(net "M_H_DQS_DP<17>")
	)
	(segment
		(start 72.639174 -15.79626)
		(end 72.131174 -15.28826)
		(width 0.14224)
		(layer "In11.Cu")
		(net "M_H_DQS_DP<17>")
	)
	(segment
		(start 72.170544 -10.947908)
		(end 72.298052 -10.8204)
		(width 0.14224)
		(layer "In11.Cu")
		(net "M_H_DQS_DP<17>")
	)
	(segment
		(start 72.66178 -8.455914)
		(end 72.481186 -8.27532)
		(width 0.14224)
		(layer "In11.Cu")
		(net "M_H_DQS_DP<17>")
	)
	(segment
		(start 72.142096 -12.573)
		(end 72.421242 -12.573)
		(width 0.14224)
		(layer "In11.Cu")
		(net "M_H_DQS_DP<17>")
	)
	(segment
		(start 72.66178 -10.39368)
		(end 72.4535 -10.1854)
		(width 0.14224)
		(layer "In11.Cu")
		(net "M_H_DQS_DP<17>")
	)
	(segment
		(start 71.6407 -14.068806)
		(end 71.6407 -13.074396)
		(width 0.14224)
		(layer "In11.Cu")
		(net "M_H_DQS_DP<17>")
	)
	(segment
		(start 71.6407 -13.074396)
		(end 72.142096 -12.573)
		(width 0.14224)
		(layer "In11.Cu")
		(net "M_H_DQS_DP<17>")
	)
	(segment
		(start 72.66178 -12.332462)
		(end 72.66178 -11.68908)
		(width 0.14224)
		(layer "In11.Cu")
		(net "M_H_DQS_DP<17>")
	)
	(segment
		(start 72.639174 -26.907236)
		(end 72.639174 -15.79626)
		(width 0.14224)
		(layer "In11.Cu")
		(net "M_H_DQS_DP<17>")
	)
	(segment
		(start 72.1741 -9.779)
		(end 72.66178 -9.29132)
		(width 0.14224)
		(layer "In11.Cu")
		(net "M_H_DQS_DP<17>")
	)
	(segment
		(start 72.1487 -27.39771)
		(end 72.639174 -26.907236)
		(width 0.14224)
		(layer "In11.Cu")
		(net "M_H_DQS_DP<17>")
	)
	(segment
		(start 72.66178 -10.63752)
		(end 72.66178 -10.39368)
		(width 0.14224)
		(layer "In11.Cu")
		(net "M_H_DQS_DP<17>")
	)
	(segment
		(start 72.4154 -11.4427)
		(end 72.327008 -11.4427)
		(width 0.14224)
		(layer "In11.Cu")
		(net "M_H_DQS_DP<17>")
	)
	(segment
		(start 72.66178 -9.29132)
		(end 72.66178 -8.455914)
		(width 0.14224)
		(layer "In11.Cu")
		(net "M_H_DQS_DP<17>")
	)
	(segment
		(start 72.66178 -11.68908)
		(end 72.4154 -11.4427)
		(width 0.14224)
		(layer "In11.Cu")
		(net "M_H_DQS_DP<17>")
	)
	(segment
		(start 72.350122 -8.27532)
		(end 72.142096 -8.483346)
		(width 0.14224)
		(layer "In11.Cu")
		(net "M_H_DQS_DP<17>")
	)
	(segment
		(start 72.170544 -11.286236)
		(end 72.170544 -10.947908)
		(width 0.14224)
		(layer "In11.Cu")
		(net "M_H_DQS_DP<17>")
	)
	(segment
		(start 72.481186 -8.27532)
		(end 72.350122 -8.27532)
		(width 0.14224)
		(layer "In11.Cu")
		(net "M_H_DQS_DP<17>")
	)
	(segment
		(start 72.298052 -10.8204)
		(end 72.4789 -10.8204)
		(width 0.14224)
		(layer "In11.Cu")
		(net "M_H_DQS_DP<17>")
	)
	(segment
		(start 72.327008 -11.4427)
		(end 72.170544 -11.286236)
		(width 0.14224)
		(layer "In11.Cu")
		(net "M_H_DQS_DP<17>")
	)
	(segment
		(start 72.131174 -15.28826)
		(end 72.131174 -14.55928)
		(width 0.14224)
		(layer "In11.Cu")
		(net "M_H_DQS_DP<17>")
	)
	(segment
		(start 72.4789 -10.8204)
		(end 72.66178 -10.63752)
		(width 0.14224)
		(layer "In11.Cu")
		(net "M_H_DQS_DP<17>")
	)
	(segment
		(start 72.421242 -12.573)
		(end 72.66178 -12.332462)
		(width 0.14224)
		(layer "In11.Cu")
		(net "M_H_DQS_DP<17>")
	)
	(segment
		(start 72.4535 -10.1854)
		(end 72.3265 -10.1854)
		(width 0.14224)
		(layer "In11.Cu")
		(net "M_H_DQS_DP<17>")
	)
	(segment
		(start 119.929402 -59.866784)
		(end 119.357902 -59.866784)
		(width 0.1016)
		(layer "F.Cu")
		(net "M_H_DQS_DP<16>")
	)
	(segment
		(start 145.628868 -7.059168)
		(end 145.628868 -7.877302)
		(width 0.1651)
		(layer "F.Cu")
		(net "M_H_DQS_DP<16>")
	)
	(segment
		(start 145.710402 -8.101584)
		(end 146.092164 -8.483346)
		(width 0.1651)
		(layer "F.Cu")
		(net "M_H_DQS_DP<16>")
	)
	(segment
		(start 145.71345 -6.875272)
		(end 145.628868 -7.059168)
		(width 0.1651)
		(layer "F.Cu")
		(net "M_H_DQS_DP<16>")
	)
	(segment
		(start 146.149568 -5.822442)
		(end 146.149568 -6.439154)
		(width 0.1651)
		(layer "F.Cu")
		(net "M_H_DQS_DP<16>")
	)
	(segment
		(start 145.628868 -7.877302)
		(end 145.710402 -8.101584)
		(width 0.1651)
		(layer "F.Cu")
		(net "M_H_DQS_DP<16>")
	)
	(segment
		(start 146.149568 -6.439154)
		(end 145.71345 -6.875272)
		(width 0.1651)
		(layer "F.Cu")
		(net "M_H_DQS_DP<16>")
	)
	(via
		(at 146.092164 -8.483346)
		(size 0.508)
		(drill 0.254)
		(layers "F.Cu" "B.Cu")
		(net "M_H_DQS_DP<16>")
	)
	(via
		(at 119.357902 -59.866784)
		(size 0.508)
		(drill 0.254)
		(layers "F.Cu" "B.Cu")
		(net "M_H_DQS_DP<16>")
	)
	(via
		(at 146.092164 -12.573)
		(size 0.508)
		(drill 0.254)
		(layers "F.Cu" "B.Cu")
		(net "M_H_DQS_DP<16>")
	)
	(segment
		(start 145.616168 -14.016736)
		(end 145.616168 -13.121132)
		(width 0.1651)
		(layer "B.Cu")
		(net "M_H_DQS_DP<16>")
	)
	(segment
		(start 146.149568 -14.605254)
		(end 145.693384 -14.14907)
		(width 0.1651)
		(layer "B.Cu")
		(net "M_H_DQS_DP<16>")
	)
	(segment
		(start 145.693384 -14.14907)
		(end 145.616168 -14.016736)
		(width 0.1651)
		(layer "B.Cu")
		(net "M_H_DQS_DP<16>")
	)
	(segment
		(start 146.149568 -15.222982)
		(end 146.149568 -14.605254)
		(width 0.1651)
		(layer "B.Cu")
		(net "M_H_DQS_DP<16>")
	)
	(segment
		(start 145.703544 -12.96162)
		(end 146.092164 -12.573)
		(width 0.1651)
		(layer "B.Cu")
		(net "M_H_DQS_DP<16>")
	)
	(segment
		(start 145.616168 -13.121132)
		(end 145.703544 -12.96162)
		(width 0.1651)
		(layer "B.Cu")
		(net "M_H_DQS_DP<16>")
	)
	(segment
		(start 123.3805 -50.622708)
		(end 123.3805 -50.566828)
		(width 0.0889)
		(layer "In4.Cu")
		(net "M_H_DQS_DP<16>")
	)
	(segment
		(start 141.054582 -33.737042)
		(end 141.054582 -33.227264)
		(width 0.14224)
		(layer "In4.Cu")
		(net "M_H_DQS_DP<16>")
	)
	(segment
		(start 121.684034 -51.79314)
		(end 122.210068 -51.79314)
		(width 0.0889)
		(layer "In4.Cu")
		(net "M_H_DQS_DP<16>")
	)
	(segment
		(start 146.092164 -12.573)
		(end 146.37131 -12.573)
		(width 0.14224)
		(layer "In4.Cu")
		(net "M_H_DQS_DP<16>")
	)
	(segment
		(start 119.701056 -58.091324)
		(end 119.704358 -58.085482)
		(width 0.0889)
		(layer "In4.Cu")
		(net "M_H_DQS_DP<16>")
	)
	(segment
		(start 146.124168 -10.033)
		(end 146.124168 -9.779)
		(width 0.14224)
		(layer "In4.Cu")
		(net "M_H_DQS_DP<16>")
	)
	(segment
		(start 120.191276 -57.790588)
		(end 120.227344 -57.790588)
		(width 0.0889)
		(layer "In4.Cu")
		(net "M_H_DQS_DP<16>")
	)
	(segment
		(start 146.431254 -8.27532)
		(end 146.30019 -8.27532)
		(width 0.14224)
		(layer "In4.Cu")
		(net "M_H_DQS_DP<16>")
	)
	(segment
		(start 123.3805 -50.566828)
		(end 123.396248 -50.55108)
		(width 0.0889)
		(layer "In4.Cu")
		(net "M_H_DQS_DP<16>")
	)
	(segment
		(start 146.37131 -12.573)
		(end 146.611848 -12.332462)
		(width 0.14224)
		(layer "In4.Cu")
		(net "M_H_DQS_DP<16>")
	)
	(segment
		(start 146.611848 -8.455914)
		(end 146.431254 -8.27532)
		(width 0.14224)
		(layer "In4.Cu")
		(net "M_H_DQS_DP<16>")
	)
	(segment
		(start 146.611848 -10.63752)
		(end 146.611848 -10.39368)
		(width 0.14224)
		(layer "In4.Cu")
		(net "M_H_DQS_DP<16>")
	)
	(segment
		(start 120.556528 -54.629304)
		(end 120.562878 -54.618636)
		(width 0.0889)
		(layer "In4.Cu")
		(net "M_H_DQS_DP<16>")
	)
	(segment
		(start 141.054582 -33.227264)
		(end 141.664944 -32.616902)
		(width 0.14224)
		(layer "In4.Cu")
		(net "M_H_DQS_DP<16>")
	)
	(segment
		(start 121.056908 -52.342034)
		(end 121.089674 -52.342034)
		(width 0.0889)
		(layer "In4.Cu")
		(net "M_H_DQS_DP<16>")
	)
	(segment
		(start 146.611848 -10.39368)
		(end 146.403568 -10.1854)
		(width 0.14224)
		(layer "In4.Cu")
		(net "M_H_DQS_DP<16>")
	)
	(segment
		(start 143.502126 -32.375348)
		(end 143.024606 -31.897828)
		(width 0.14224)
		(layer "In4.Cu")
		(net "M_H_DQS_DP<16>")
	)
	(segment
		(start 122.210068 -51.79314)
		(end 123.3805 -50.622708)
		(width 0.0889)
		(layer "In4.Cu")
		(net "M_H_DQS_DP<16>")
	)
	(segment
		(start 145.621248 -13.043916)
		(end 146.092164 -12.573)
		(width 0.14224)
		(layer "In4.Cu")
		(net "M_H_DQS_DP<16>")
	)
	(segment
		(start 146.611848 -9.29132)
		(end 146.611848 -8.455914)
		(width 0.14224)
		(layer "In4.Cu")
		(net "M_H_DQS_DP<16>")
	)
	(segment
		(start 121.539254 -51.93792)
		(end 121.684034 -51.79314)
		(width 0.0889)
		(layer "In4.Cu")
		(net "M_H_DQS_DP<16>")
	)
	(segment
		(start 143.024606 -31.36138)
		(end 146.605244 -27.780742)
		(width 0.14224)
		(layer "In4.Cu")
		(net "M_H_DQS_DP<16>")
	)
	(segment
		(start 119.357902 -59.866784)
		(end 119.224298 -59.467496)
		(width 0.0889)
		(layer "In4.Cu")
		(net "M_H_DQS_DP<16>")
	)
	(segment
		(start 142.740888 -33.136586)
		(end 143.053054 -33.136586)
		(width 0.14224)
		(layer "In4.Cu")
		(net "M_H_DQS_DP<16>")
	)
	(segment
		(start 146.276568 -10.1854)
		(end 146.124168 -10.033)
		(width 0.14224)
		(layer "In4.Cu")
		(net "M_H_DQS_DP<16>")
	)
	(segment
		(start 119.224298 -59.467496)
		(end 119.017542 -59.087004)
		(width 0.0889)
		(layer "In4.Cu")
		(net "M_H_DQS_DP<16>")
	)
	(segment
		(start 120.556528 -56.610504)
		(end 120.562878 -56.599836)
		(width 0.0889)
		(layer "In4.Cu")
		(net "M_H_DQS_DP<16>")
	)
	(segment
		(start 120.556528 -55.619904)
		(end 120.562878 -55.609236)
		(width 0.0889)
		(layer "In4.Cu")
		(net "M_H_DQS_DP<16>")
	)
	(segment
		(start 141.666976 -34.66211)
		(end 141.666976 -34.349436)
		(width 0.14224)
		(layer "In4.Cu")
		(net "M_H_DQS_DP<16>")
	)
	(segment
		(start 121.421398 -52.142136)
		(end 121.539254 -51.93792)
		(width 0.0889)
		(layer "In4.Cu")
		(net "M_H_DQS_DP<16>")
	)
	(segment
		(start 143.024606 -31.897828)
		(end 143.024606 -31.36138)
		(width 0.14224)
		(layer "In4.Cu")
		(net "M_H_DQS_DP<16>")
	)
	(segment
		(start 120.562878 -53.628036)
		(end 120.567704 -53.6194)
		(width 0.0889)
		(layer "In4.Cu")
		(net "M_H_DQS_DP<16>")
	)
	(segment
		(start 141.666976 -34.349436)
		(end 141.054582 -33.737042)
		(width 0.14224)
		(layer "In4.Cu")
		(net "M_H_DQS_DP<16>")
	)
	(segment
		(start 127.770128 -46.1772)
		(end 130.151886 -46.1772)
		(width 0.14224)
		(layer "In4.Cu")
		(net "M_H_DQS_DP<16>")
	)
	(segment
		(start 120.556528 -53.638704)
		(end 120.562878 -53.628036)
		(width 0.0889)
		(layer "In4.Cu")
		(net "M_H_DQS_DP<16>")
	)
	(segment
		(start 146.365468 -11.4427)
		(end 146.277076 -11.4427)
		(width 0.14224)
		(layer "In4.Cu")
		(net "M_H_DQS_DP<16>")
	)
	(segment
		(start 120.562878 -54.618636)
		(end 120.567704 -54.61)
		(width 0.0889)
		(layer "In4.Cu")
		(net "M_H_DQS_DP<16>")
	)
	(segment
		(start 146.605244 -16.14551)
		(end 145.621248 -15.161514)
		(width 0.14224)
		(layer "In4.Cu")
		(net "M_H_DQS_DP<16>")
	)
	(segment
		(start 146.277076 -11.4427)
		(end 146.120612 -11.286236)
		(width 0.14224)
		(layer "In4.Cu")
		(net "M_H_DQS_DP<16>")
	)
	(segment
		(start 146.124168 -9.779)
		(end 146.611848 -9.29132)
		(width 0.14224)
		(layer "In4.Cu")
		(net "M_H_DQS_DP<16>")
	)
	(segment
		(start 119.017542 -59.087004)
		(end 119.011192 -59.076336)
		(width 0.0889)
		(layer "In4.Cu")
		(net "M_H_DQS_DP<16>")
	)
	(segment
		(start 145.621248 -15.161514)
		(end 145.621248 -13.043916)
		(width 0.14224)
		(layer "In4.Cu")
		(net "M_H_DQS_DP<16>")
	)
	(segment
		(start 143.053054 -33.136586)
		(end 143.502126 -32.687514)
		(width 0.14224)
		(layer "In4.Cu")
		(net "M_H_DQS_DP<16>")
	)
	(segment
		(start 142.221204 -32.616902)
		(end 142.740888 -33.136586)
		(width 0.14224)
		(layer "In4.Cu")
		(net "M_H_DQS_DP<16>")
	)
	(segment
		(start 123.396248 -50.55108)
		(end 127.770128 -46.1772)
		(width 0.14224)
		(layer "In4.Cu")
		(net "M_H_DQS_DP<16>")
	)
	(segment
		(start 146.403568 -10.1854)
		(end 146.276568 -10.1854)
		(width 0.14224)
		(layer "In4.Cu")
		(net "M_H_DQS_DP<16>")
	)
	(segment
		(start 146.24812 -10.8204)
		(end 146.428968 -10.8204)
		(width 0.14224)
		(layer "In4.Cu")
		(net "M_H_DQS_DP<16>")
	)
	(segment
		(start 143.502126 -32.687514)
		(end 143.502126 -32.375348)
		(width 0.14224)
		(layer "In4.Cu")
		(net "M_H_DQS_DP<16>")
	)
	(segment
		(start 146.605244 -27.780742)
		(end 146.605244 -16.14551)
		(width 0.14224)
		(layer "In4.Cu")
		(net "M_H_DQS_DP<16>")
	)
	(segment
		(start 120.562878 -56.599836)
		(end 120.567704 -56.5912)
		(width 0.0889)
		(layer "In4.Cu")
		(net "M_H_DQS_DP<16>")
	)
	(segment
		(start 146.120612 -11.286236)
		(end 146.120612 -10.947908)
		(width 0.14224)
		(layer "In4.Cu")
		(net "M_H_DQS_DP<16>")
	)
	(segment
		(start 146.428968 -10.8204)
		(end 146.611848 -10.63752)
		(width 0.14224)
		(layer "In4.Cu")
		(net "M_H_DQS_DP<16>")
	)
	(segment
		(start 130.151886 -46.1772)
		(end 141.666976 -34.66211)
		(width 0.14224)
		(layer "In4.Cu")
		(net "M_H_DQS_DP<16>")
	)
	(segment
		(start 146.611848 -12.332462)
		(end 146.611848 -11.68908)
		(width 0.14224)
		(layer "In4.Cu")
		(net "M_H_DQS_DP<16>")
	)
	(segment
		(start 146.30019 -8.27532)
		(end 146.092164 -8.483346)
		(width 0.14224)
		(layer "In4.Cu")
		(net "M_H_DQS_DP<16>")
	)
	(segment
		(start 146.120612 -10.947908)
		(end 146.24812 -10.8204)
		(width 0.14224)
		(layer "In4.Cu")
		(net "M_H_DQS_DP<16>")
	)
	(segment
		(start 146.611848 -11.68908)
		(end 146.365468 -11.4427)
		(width 0.14224)
		(layer "In4.Cu")
		(net "M_H_DQS_DP<16>")
	)
	(segment
		(start 119.011192 -59.076336)
		(end 118.994428 -59.046872)
		(width 0.0889)
		(layer "In4.Cu")
		(net "M_H_DQS_DP<16>")
	)
	(segment
		(start 141.664944 -32.616902)
		(end 142.221204 -32.616902)
		(width 0.14224)
		(layer "In4.Cu")
		(net "M_H_DQS_DP<16>")
	)
	(segment
		(start 120.562878 -55.609236)
		(end 120.567704 -55.6006)
		(width 0.0889)
		(layer "In4.Cu")
		(net "M_H_DQS_DP<16>")
	)
	(arc
		(start 120.567704 -56.5912)
		(mid 120.616459 -56.394848)
		(end 120.562878 -56.199786)
		(width 0.0889)
		(layer "In4.Cu")
		(net "M_H_DQS_DP<16>")
	)
	(arc
		(start 118.994428 -59.046872)
		(mid 118.955554 -58.970093)
		(end 118.924324 -58.8899)
		(width 0.0889)
		(layer "In4.Cu")
		(net "M_H_DQS_DP<16>")
	)
	(arc
		(start 121.089674 -52.342034)
		(mid 121.281316 -52.284868)
		(end 121.421398 -52.142136)
		(width 0.0889)
		(layer "In4.Cu")
		(net "M_H_DQS_DP<16>")
	)
	(arc
		(start 120.567704 -55.6006)
		(mid 120.616459 -55.404248)
		(end 120.562878 -55.209186)
		(width 0.0889)
		(layer "In4.Cu")
		(net "M_H_DQS_DP<16>")
	)
	(arc
		(start 120.562878 -56.199786)
		(mid 120.483656 -55.910668)
		(end 120.556528 -55.619904)
		(width 0.0889)
		(layer "In4.Cu")
		(net "M_H_DQS_DP<16>")
	)
	(arc
		(start 120.567704 -53.6194)
		(mid 120.616459 -53.423048)
		(end 120.562878 -53.227986)
		(width 0.0889)
		(layer "In4.Cu")
		(net "M_H_DQS_DP<16>")
	)
	(arc
		(start 120.562878 -57.190386)
		(mid 120.483656 -56.901268)
		(end 120.556528 -56.610504)
		(width 0.0889)
		(layer "In4.Cu")
		(net "M_H_DQS_DP<16>")
	)
	(arc
		(start 120.562878 -53.227986)
		(mid 120.558549 -52.644814)
		(end 121.056908 -52.342034)
		(width 0.0889)
		(layer "In4.Cu")
		(net "M_H_DQS_DP<16>")
	)
	(arc
		(start 120.562878 -54.218586)
		(mid 120.483656 -53.929468)
		(end 120.556528 -53.638704)
		(width 0.0889)
		(layer "In4.Cu")
		(net "M_H_DQS_DP<16>")
	)
	(arc
		(start 120.562878 -55.209186)
		(mid 120.483656 -54.920068)
		(end 120.556528 -54.629304)
		(width 0.0889)
		(layer "In4.Cu")
		(net "M_H_DQS_DP<16>")
	)
	(arc
		(start 119.357902 -58.285634)
		(mid 119.555063 -58.233675)
		(end 119.701056 -58.091324)
		(width 0.0889)
		(layer "In4.Cu")
		(net "M_H_DQS_DP<16>")
	)
	(arc
		(start 118.924324 -58.8899)
		(mid 118.986644 -58.476908)
		(end 119.357902 -58.285634)
		(width 0.0889)
		(layer "In4.Cu")
		(net "M_H_DQS_DP<16>")
	)
	(arc
		(start 119.704358 -58.085482)
		(mid 119.909979 -57.875559)
		(end 120.191276 -57.790588)
		(width 0.0889)
		(layer "In4.Cu")
		(net "M_H_DQS_DP<16>")
	)
	(arc
		(start 120.567704 -54.61)
		(mid 120.616459 -54.413648)
		(end 120.562878 -54.218586)
		(width 0.0889)
		(layer "In4.Cu")
		(net "M_H_DQS_DP<16>")
	)
	(arc
		(start 120.227344 -57.790588)
		(mid 120.565513 -57.58579)
		(end 120.562878 -57.190386)
		(width 0.0889)
		(layer "In4.Cu")
		(net "M_H_DQS_DP<16>")
	)
	(segment
		(start 136.527794 -34.840926)
		(end 136.527794 -34.417)
		(width 0.1651)
		(layer "F.Cu")
		(net "M_H_DQS_DP<15>")
	)
	(segment
		(start 136.96696 -31.3944)
		(end 137.145268 -31.216092)
		(width 0.1651)
		(layer "F.Cu")
		(net "M_H_DQS_DP<15>")
	)
	(segment
		(start 136.422638 -32.7787)
		(end 136.073388 -32.42945)
		(width 0.1651)
		(layer "F.Cu")
		(net "M_H_DQS_DP<15>")
	)
	(segment
		(start 118.659656 -51.871372)
		(end 118.642892 -51.855116)
		(width 0.0889)
		(layer "F.Cu")
		(net "M_H_DQS_DP<15>")
	)
	(segment
		(start 137.119868 -36.2839)
		(end 137.119868 -35.433)
		(width 0.1651)
		(layer "F.Cu")
		(net "M_H_DQS_DP<15>")
	)
	(segment
		(start 136.363456 -6.875272)
		(end 136.278874 -7.059168)
		(width 0.1651)
		(layer "F.Cu")
		(net "M_H_DQS_DP<15>")
	)
	(segment
		(start 119.555768 -49.032922)
		(end 119.555768 -48.899318)
		(width 0.0889)
		(layer "F.Cu")
		(net "M_H_DQS_DP<15>")
	)
	(segment
		(start 136.37133 -30.656022)
		(end 136.073388 -30.35808)
		(width 0.1651)
		(layer "F.Cu")
		(net "M_H_DQS_DP<15>")
	)
	(segment
		(start 136.799574 -6.439154)
		(end 136.363456 -6.875272)
		(width 0.1651)
		(layer "F.Cu")
		(net "M_H_DQS_DP<15>")
	)
	(segment
		(start 136.073388 -32.42945)
		(end 136.073388 -31.74365)
		(width 0.1651)
		(layer "F.Cu")
		(net "M_H_DQS_DP<15>")
	)
	(segment
		(start 118.625112 -49.963578)
		(end 119.555768 -49.032922)
		(width 0.0889)
		(layer "F.Cu")
		(net "M_H_DQS_DP<15>")
	)
	(segment
		(start 136.94156 -32.7787)
		(end 136.422638 -32.7787)
		(width 0.1651)
		(layer "F.Cu")
		(net "M_H_DQS_DP<15>")
	)
	(segment
		(start 118.625112 -50.969418)
		(end 118.625112 -49.963578)
		(width 0.0889)
		(layer "F.Cu")
		(net "M_H_DQS_DP<15>")
	)
	(segment
		(start 136.073388 -30.35808)
		(end 136.073388 -29.297122)
		(width 0.1651)
		(layer "F.Cu")
		(net "M_H_DQS_DP<15>")
	)
	(segment
		(start 132.395468 -41.8846)
		(end 132.395468 -41.0083)
		(width 0.1651)
		(layer "F.Cu")
		(net "M_H_DQS_DP<15>")
	)
	(segment
		(start 136.278874 -7.877302)
		(end 136.360408 -8.101584)
		(width 0.1651)
		(layer "F.Cu")
		(net "M_H_DQS_DP<15>")
	)
	(segment
		(start 118.539768 -51.116484)
		(end 118.625112 -50.969418)
		(width 0.0889)
		(layer "F.Cu")
		(net "M_H_DQS_DP<15>")
	)
	(segment
		(start 136.073388 -29.297122)
		(end 136.243568 -29.126942)
		(width 0.1651)
		(layer "F.Cu")
		(net "M_H_DQS_DP<15>")
	)
	(segment
		(start 132.38734 -42.902632)
		(end 132.38734 -41.892728)
		(width 0.1016)
		(layer "F.Cu")
		(net "M_H_DQS_DP<15>")
	)
	(segment
		(start 136.799574 -5.822442)
		(end 136.799574 -6.439154)
		(width 0.1651)
		(layer "F.Cu")
		(net "M_H_DQS_DP<15>")
	)
	(segment
		(start 122.479562 -45.975524)
		(end 129.314448 -45.975524)
		(width 0.1016)
		(layer "F.Cu")
		(net "M_H_DQS_DP<15>")
	)
	(segment
		(start 137.145268 -30.83433)
		(end 136.96696 -30.656022)
		(width 0.1651)
		(layer "F.Cu")
		(net "M_H_DQS_DP<15>")
	)
	(segment
		(start 136.243568 -27.902916)
		(end 136.748774 -27.39771)
		(width 0.1651)
		(layer "F.Cu")
		(net "M_H_DQS_DP<15>")
	)
	(segment
		(start 136.278874 -7.059168)
		(end 136.278874 -7.877302)
		(width 0.1651)
		(layer "F.Cu")
		(net "M_H_DQS_DP<15>")
	)
	(segment
		(start 132.395468 -41.0083)
		(end 137.119868 -36.2839)
		(width 0.1651)
		(layer "F.Cu")
		(net "M_H_DQS_DP<15>")
	)
	(segment
		(start 136.527794 -33.777174)
		(end 137.119868 -33.1851)
		(width 0.1651)
		(layer "F.Cu")
		(net "M_H_DQS_DP<15>")
	)
	(segment
		(start 137.119868 -35.433)
		(end 136.527794 -34.840926)
		(width 0.1651)
		(layer "F.Cu")
		(net "M_H_DQS_DP<15>")
	)
	(segment
		(start 136.96696 -30.656022)
		(end 136.37133 -30.656022)
		(width 0.1651)
		(layer "F.Cu")
		(net "M_H_DQS_DP<15>")
	)
	(segment
		(start 136.243568 -29.126942)
		(end 136.243568 -27.902916)
		(width 0.1651)
		(layer "F.Cu")
		(net "M_H_DQS_DP<15>")
	)
	(segment
		(start 137.119868 -32.957008)
		(end 136.94156 -32.7787)
		(width 0.1651)
		(layer "F.Cu")
		(net "M_H_DQS_DP<15>")
	)
	(segment
		(start 119.555768 -48.899318)
		(end 122.479562 -45.975524)
		(width 0.1016)
		(layer "F.Cu")
		(net "M_H_DQS_DP<15>")
	)
	(segment
		(start 136.073388 -31.74365)
		(end 136.422638 -31.3944)
		(width 0.1651)
		(layer "F.Cu")
		(net "M_H_DQS_DP<15>")
	)
	(segment
		(start 136.527794 -34.417)
		(end 136.527794 -33.777174)
		(width 0.1651)
		(layer "F.Cu")
		(net "M_H_DQS_DP<15>")
	)
	(segment
		(start 132.38734 -41.892728)
		(end 132.395468 -41.8846)
		(width 0.1016)
		(layer "F.Cu")
		(net "M_H_DQS_DP<15>")
	)
	(segment
		(start 136.360408 -8.101584)
		(end 136.74217 -8.483346)
		(width 0.1651)
		(layer "F.Cu")
		(net "M_H_DQS_DP<15>")
	)
	(segment
		(start 129.314448 -45.975524)
		(end 132.38734 -42.902632)
		(width 0.1016)
		(layer "F.Cu")
		(net "M_H_DQS_DP<15>")
	)
	(segment
		(start 137.145268 -31.216092)
		(end 137.145268 -30.83433)
		(width 0.1651)
		(layer "F.Cu")
		(net "M_H_DQS_DP<15>")
	)
	(segment
		(start 137.119868 -33.1851)
		(end 137.119868 -32.957008)
		(width 0.1651)
		(layer "F.Cu")
		(net "M_H_DQS_DP<15>")
	)
	(segment
		(start 136.422638 -31.3944)
		(end 136.96696 -31.3944)
		(width 0.1651)
		(layer "F.Cu")
		(net "M_H_DQS_DP<15>")
	)
	(via
		(at 136.527794 -34.417)
		(size 0.508)
		(drill 0.254)
		(layers "F.Cu" "B.Cu")
		(net "M_H_DQS_DP<15>")
	)
	(via
		(at 136.748774 -27.39771)
		(size 0.508)
		(drill 0.254)
		(layers "F.Cu" "B.Cu")
		(net "M_H_DQS_DP<15>")
	)
	(via
		(at 136.74217 -8.483346)
		(size 0.508)
		(drill 0.254)
		(layers "F.Cu" "B.Cu")
		(net "M_H_DQS_DP<15>")
	)
	(via
		(at 136.74217 -12.573)
		(size 0.508)
		(drill 0.254)
		(layers "F.Cu" "B.Cu")
		(net "M_H_DQS_DP<15>")
	)
	(arc
		(start 119.070882 -52.437538)
		(mid 118.887567 -52.138259)
		(end 118.659656 -51.871372)
		(width 0.0889)
		(layer "F.Cu")
		(net "M_H_DQS_DP<15>")
	)
	(arc
		(start 118.642892 -51.855116)
		(mid 118.464361 -51.50354)
		(end 118.539768 -51.116484)
		(width 0.0889)
		(layer "F.Cu")
		(net "M_H_DQS_DP<15>")
	)
	(segment
		(start 136.34339 -14.14907)
		(end 136.266174 -14.016736)
		(width 0.1651)
		(layer "B.Cu")
		(net "M_H_DQS_DP<15>")
	)
	(segment
		(start 136.799574 -15.222982)
		(end 136.799574 -14.605254)
		(width 0.1651)
		(layer "B.Cu")
		(net "M_H_DQS_DP<15>")
	)
	(segment
		(start 136.35355 -12.96162)
		(end 136.74217 -12.573)
		(width 0.1651)
		(layer "B.Cu")
		(net "M_H_DQS_DP<15>")
	)
	(segment
		(start 136.266174 -14.016736)
		(end 136.266174 -13.121132)
		(width 0.1651)
		(layer "B.Cu")
		(net "M_H_DQS_DP<15>")
	)
	(segment
		(start 136.799574 -14.605254)
		(end 136.34339 -14.14907)
		(width 0.1651)
		(layer "B.Cu")
		(net "M_H_DQS_DP<15>")
	)
	(segment
		(start 136.266174 -13.121132)
		(end 136.35355 -12.96162)
		(width 0.1651)
		(layer "B.Cu")
		(net "M_H_DQS_DP<15>")
	)
	(segment
		(start 136.926574 -10.1854)
		(end 136.774174 -10.033)
		(width 0.14224)
		(layer "In4.Cu")
		(net "M_H_DQS_DP<15>")
	)
	(segment
		(start 136.74217 -12.573)
		(end 137.021316 -12.573)
		(width 0.14224)
		(layer "In4.Cu")
		(net "M_H_DQS_DP<15>")
	)
	(segment
		(start 137.08126 -8.27532)
		(end 136.950196 -8.27532)
		(width 0.14224)
		(layer "In4.Cu")
		(net "M_H_DQS_DP<15>")
	)
	(segment
		(start 137.021316 -12.573)
		(end 137.261854 -12.332462)
		(width 0.14224)
		(layer "In4.Cu")
		(net "M_H_DQS_DP<15>")
	)
	(segment
		(start 136.774174 -10.033)
		(end 136.774174 -9.779)
		(width 0.14224)
		(layer "In4.Cu")
		(net "M_H_DQS_DP<15>")
	)
	(segment
		(start 137.261854 -12.332462)
		(end 137.261854 -11.68908)
		(width 0.14224)
		(layer "In4.Cu")
		(net "M_H_DQS_DP<15>")
	)
	(segment
		(start 137.239248 -15.79626)
		(end 136.731248 -15.28826)
		(width 0.14224)
		(layer "In4.Cu")
		(net "M_H_DQS_DP<15>")
	)
	(segment
		(start 136.774174 -9.779)
		(end 137.261854 -9.29132)
		(width 0.14224)
		(layer "In4.Cu")
		(net "M_H_DQS_DP<15>")
	)
	(segment
		(start 136.731248 -14.55928)
		(end 136.240774 -14.068806)
		(width 0.14224)
		(layer "In4.Cu")
		(net "M_H_DQS_DP<15>")
	)
	(segment
		(start 136.731248 -15.28826)
		(end 136.731248 -14.55928)
		(width 0.14224)
		(layer "In4.Cu")
		(net "M_H_DQS_DP<15>")
	)
	(segment
		(start 136.770618 -10.947908)
		(end 136.898126 -10.8204)
		(width 0.14224)
		(layer "In4.Cu")
		(net "M_H_DQS_DP<15>")
	)
	(segment
		(start 137.261854 -11.68908)
		(end 137.015474 -11.4427)
		(width 0.14224)
		(layer "In4.Cu")
		(net "M_H_DQS_DP<15>")
	)
	(segment
		(start 137.015474 -11.4427)
		(end 136.927082 -11.4427)
		(width 0.14224)
		(layer "In4.Cu")
		(net "M_H_DQS_DP<15>")
	)
	(segment
		(start 136.748774 -27.39771)
		(end 137.239248 -26.907236)
		(width 0.14224)
		(layer "In4.Cu")
		(net "M_H_DQS_DP<15>")
	)
	(segment
		(start 136.240774 -13.074396)
		(end 136.74217 -12.573)
		(width 0.14224)
		(layer "In4.Cu")
		(net "M_H_DQS_DP<15>")
	)
	(segment
		(start 137.239248 -26.907236)
		(end 137.239248 -15.79626)
		(width 0.14224)
		(layer "In4.Cu")
		(net "M_H_DQS_DP<15>")
	)
	(segment
		(start 137.053574 -10.1854)
		(end 136.926574 -10.1854)
		(width 0.14224)
		(layer "In4.Cu")
		(net "M_H_DQS_DP<15>")
	)
	(segment
		(start 137.261854 -9.29132)
		(end 137.261854 -8.455914)
		(width 0.14224)
		(layer "In4.Cu")
		(net "M_H_DQS_DP<15>")
	)
	(segment
		(start 137.261854 -10.39368)
		(end 137.053574 -10.1854)
		(width 0.14224)
		(layer "In4.Cu")
		(net "M_H_DQS_DP<15>")
	)
	(segment
		(start 136.240774 -14.068806)
		(end 136.240774 -13.074396)
		(width 0.14224)
		(layer "In4.Cu")
		(net "M_H_DQS_DP<15>")
	)
	(segment
		(start 137.261854 -10.63752)
		(end 137.261854 -10.39368)
		(width 0.14224)
		(layer "In4.Cu")
		(net "M_H_DQS_DP<15>")
	)
	(segment
		(start 137.078974 -10.8204)
		(end 137.261854 -10.63752)
		(width 0.14224)
		(layer "In4.Cu")
		(net "M_H_DQS_DP<15>")
	)
	(segment
		(start 136.898126 -10.8204)
		(end 137.078974 -10.8204)
		(width 0.14224)
		(layer "In4.Cu")
		(net "M_H_DQS_DP<15>")
	)
	(segment
		(start 136.950196 -8.27532)
		(end 136.74217 -8.483346)
		(width 0.14224)
		(layer "In4.Cu")
		(net "M_H_DQS_DP<15>")
	)
	(segment
		(start 137.261854 -8.455914)
		(end 137.08126 -8.27532)
		(width 0.14224)
		(layer "In4.Cu")
		(net "M_H_DQS_DP<15>")
	)
	(segment
		(start 136.927082 -11.4427)
		(end 136.770618 -11.286236)
		(width 0.14224)
		(layer "In4.Cu")
		(net "M_H_DQS_DP<15>")
	)
	(segment
		(start 136.770618 -11.286236)
		(end 136.770618 -10.947908)
		(width 0.14224)
		(layer "In4.Cu")
		(net "M_H_DQS_DP<15>")
	)
	(segment
		(start 117.958616 -41.0464)
		(end 117.958616 -40.103298)
		(width 0.1651)
		(layer "F.Cu")
		(net "M_H_DQS_DP<14>")
	)
	(segment
		(start 127.44958 -5.822442)
		(end 127.44958 -6.439154)
		(width 0.1651)
		(layer "F.Cu")
		(net "M_H_DQS_DP<14>")
	)
	(segment
		(start 126.941326 -27.855164)
		(end 127.39878 -27.39771)
		(width 0.1651)
		(layer "F.Cu")
		(net "M_H_DQS_DP<14>")
	)
	(segment
		(start 121.104914 -36.957)
		(end 122.095768 -36.957)
		(width 0.1651)
		(layer "F.Cu")
		(net "M_H_DQS_DP<14>")
	)
	(segment
		(start 117.907816 -41.246552)
		(end 117.958616 -41.195752)
		(width 0.1016)
		(layer "F.Cu")
		(net "M_H_DQS_DP<14>")
	)
	(segment
		(start 127.150368 -31.7627)
		(end 127.277368 -31.6357)
		(width 0.1651)
		(layer "F.Cu")
		(net "M_H_DQS_DP<14>")
	)
	(segment
		(start 113.510568 -49.707546)
		(end 113.410492 -49.60747)
		(width 0.0889)
		(layer "F.Cu")
		(net "M_H_DQS_DP<14>")
	)
	(segment
		(start 113.410492 -47.356522)
		(end 117.907816 -42.859198)
		(width 0.1016)
		(layer "F.Cu")
		(net "M_H_DQS_DP<14>")
	)
	(segment
		(start 124.263658 -33.56991)
		(end 124.685298 -33.56991)
		(width 0.1651)
		(layer "F.Cu")
		(net "M_H_DQS_DP<14>")
	)
	(segment
		(start 125.77191 -33.280858)
		(end 125.77191 -33.047178)
		(width 0.1651)
		(layer "F.Cu")
		(net "M_H_DQS_DP<14>")
	)
	(segment
		(start 113.510568 -50.900584)
		(end 113.510568 -49.707546)
		(width 0.0889)
		(layer "F.Cu")
		(net "M_H_DQS_DP<14>")
	)
	(segment
		(start 123.795536 -34.459672)
		(end 123.795536 -34.038032)
		(width 0.1651)
		(layer "F.Cu")
		(net "M_H_DQS_DP<14>")
	)
	(segment
		(start 126.941326 -29.838904)
		(end 126.941326 -27.855164)
		(width 0.1651)
		(layer "F.Cu")
		(net "M_H_DQS_DP<14>")
	)
	(segment
		(start 113.919762 -52.437538)
		(end 113.919762 -52.10556)
		(width 0.0889)
		(layer "F.Cu")
		(net "M_H_DQS_DP<14>")
	)
	(segment
		(start 125.626368 -32.901636)
		(end 125.626368 -32.327088)
		(width 0.1651)
		(layer "F.Cu")
		(net "M_H_DQS_DP<14>")
	)
	(segment
		(start 124.967238 -33.85185)
		(end 125.200918 -33.85185)
		(width 0.1651)
		(layer "F.Cu")
		(net "M_H_DQS_DP<14>")
	)
	(segment
		(start 122.095768 -36.957)
		(end 124.077476 -34.975292)
		(width 0.1651)
		(layer "F.Cu")
		(net "M_H_DQS_DP<14>")
	)
	(segment
		(start 113.919762 -52.10556)
		(end 113.826544 -52.029868)
		(width 0.0889)
		(layer "F.Cu")
		(net "M_H_DQS_DP<14>")
	)
	(segment
		(start 117.958616 -41.195752)
		(end 117.958616 -41.0464)
		(width 0.1016)
		(layer "F.Cu")
		(net "M_H_DQS_DP<14>")
	)
	(segment
		(start 124.685298 -33.56991)
		(end 124.967238 -33.85185)
		(width 0.1651)
		(layer "F.Cu")
		(net "M_H_DQS_DP<14>")
	)
	(segment
		(start 117.907816 -42.859198)
		(end 117.907816 -41.246552)
		(width 0.1016)
		(layer "F.Cu")
		(net "M_H_DQS_DP<14>")
	)
	(segment
		(start 113.345722 -51.06543)
		(end 113.510568 -50.900584)
		(width 0.0889)
		(layer "F.Cu")
		(net "M_H_DQS_DP<14>")
	)
	(segment
		(start 113.345722 -51.466242)
		(end 113.345722 -51.06543)
		(width 0.0889)
		(layer "F.Cu")
		(net "M_H_DQS_DP<14>")
	)
	(segment
		(start 113.410492 -49.60747)
		(end 113.410492 -47.356522)
		(width 0.1016)
		(layer "F.Cu")
		(net "M_H_DQS_DP<14>")
	)
	(segment
		(start 127.277368 -30.174946)
		(end 126.941326 -29.838904)
		(width 0.1651)
		(layer "F.Cu")
		(net "M_H_DQS_DP<14>")
	)
	(segment
		(start 124.077476 -34.975292)
		(end 124.077476 -34.741612)
		(width 0.1651)
		(layer "F.Cu")
		(net "M_H_DQS_DP<14>")
	)
	(segment
		(start 127.277368 -31.6357)
		(end 127.277368 -30.174946)
		(width 0.1651)
		(layer "F.Cu")
		(net "M_H_DQS_DP<14>")
	)
	(segment
		(start 125.200918 -33.85185)
		(end 125.77191 -33.280858)
		(width 0.1651)
		(layer "F.Cu")
		(net "M_H_DQS_DP<14>")
	)
	(segment
		(start 125.626368 -32.327088)
		(end 126.190756 -31.7627)
		(width 0.1651)
		(layer "F.Cu")
		(net "M_H_DQS_DP<14>")
	)
	(segment
		(start 127.010414 -8.101584)
		(end 127.010414 -8.101838)
		(width 0.1651)
		(layer "F.Cu")
		(net "M_H_DQS_DP<14>")
	)
	(segment
		(start 126.190756 -31.7627)
		(end 127.150368 -31.7627)
		(width 0.1651)
		(layer "F.Cu")
		(net "M_H_DQS_DP<14>")
	)
	(segment
		(start 126.92888 -7.059168)
		(end 126.92888 -7.877302)
		(width 0.1651)
		(layer "F.Cu")
		(net "M_H_DQS_DP<14>")
	)
	(segment
		(start 127.010414 -8.101838)
		(end 127.391922 -8.483346)
		(width 0.1651)
		(layer "F.Cu")
		(net "M_H_DQS_DP<14>")
	)
	(segment
		(start 123.795536 -34.038032)
		(end 124.263658 -33.56991)
		(width 0.1651)
		(layer "F.Cu")
		(net "M_H_DQS_DP<14>")
	)
	(segment
		(start 127.013462 -6.875272)
		(end 126.92888 -7.059168)
		(width 0.1651)
		(layer "F.Cu")
		(net "M_H_DQS_DP<14>")
	)
	(segment
		(start 126.92888 -7.877302)
		(end 127.010414 -8.101584)
		(width 0.1651)
		(layer "F.Cu")
		(net "M_H_DQS_DP<14>")
	)
	(segment
		(start 125.77191 -33.047178)
		(end 125.626368 -32.901636)
		(width 0.1651)
		(layer "F.Cu")
		(net "M_H_DQS_DP<14>")
	)
	(segment
		(start 117.958616 -40.103298)
		(end 121.104914 -36.957)
		(width 0.1651)
		(layer "F.Cu")
		(net "M_H_DQS_DP<14>")
	)
	(segment
		(start 124.077476 -34.741612)
		(end 123.795536 -34.459672)
		(width 0.1651)
		(layer "F.Cu")
		(net "M_H_DQS_DP<14>")
	)
	(segment
		(start 127.44958 -6.439154)
		(end 127.013462 -6.875272)
		(width 0.1651)
		(layer "F.Cu")
		(net "M_H_DQS_DP<14>")
	)
	(via
		(at 127.391922 -8.483346)
		(size 0.508)
		(drill 0.254)
		(layers "F.Cu" "B.Cu")
		(net "M_H_DQS_DP<14>")
	)
	(via
		(at 127.39878 -27.39771)
		(size 0.508)
		(drill 0.254)
		(layers "F.Cu" "B.Cu")
		(net "M_H_DQS_DP<14>")
	)
	(via
		(at 127.391922 -12.573)
		(size 0.508)
		(drill 0.254)
		(layers "F.Cu" "B.Cu")
		(net "M_H_DQS_DP<14>")
	)
	(arc
		(start 113.826544 -52.029868)
		(mid 113.482295 -51.836625)
		(end 113.345722 -51.466242)
		(width 0.0889)
		(layer "F.Cu")
		(net "M_H_DQS_DP<14>")
	)
	(segment
		(start 126.91618 -13.121132)
		(end 127.003556 -12.96162)
		(width 0.1651)
		(layer "B.Cu")
		(net "M_H_DQS_DP<14>")
	)
	(segment
		(start 127.391922 -12.573254)
		(end 127.391922 -12.573)
		(width 0.1651)
		(layer "B.Cu")
		(net "M_H_DQS_DP<14>")
	)
	(segment
		(start 127.003556 -12.96162)
		(end 127.391922 -12.573254)
		(width 0.1651)
		(layer "B.Cu")
		(net "M_H_DQS_DP<14>")
	)
	(segment
		(start 127.44958 -15.222982)
		(end 127.44958 -14.605254)
		(width 0.1651)
		(layer "B.Cu")
		(net "M_H_DQS_DP<14>")
	)
	(segment
		(start 127.44958 -14.605254)
		(end 126.993396 -14.14907)
		(width 0.1651)
		(layer "B.Cu")
		(net "M_H_DQS_DP<14>")
	)
	(segment
		(start 126.91618 -14.016736)
		(end 126.91618 -13.121132)
		(width 0.1651)
		(layer "B.Cu")
		(net "M_H_DQS_DP<14>")
	)
	(segment
		(start 126.993396 -14.14907)
		(end 126.91618 -14.016736)
		(width 0.1651)
		(layer "B.Cu")
		(net "M_H_DQS_DP<14>")
	)
	(segment
		(start 127.391922 -8.483346)
		(end 127.599948 -8.27532)
		(width 0.14224)
		(layer "In11.Cu")
		(net "M_H_DQS_DP<14>")
	)
	(segment
		(start 127.381254 -15.394686)
		(end 127.381254 -14.55928)
		(width 0.14224)
		(layer "In11.Cu")
		(net "M_H_DQS_DP<14>")
	)
	(segment
		(start 127.42418 -10.033)
		(end 127.57658 -10.1854)
		(width 0.14224)
		(layer "In11.Cu")
		(net "M_H_DQS_DP<14>")
	)
	(segment
		(start 127.548132 -10.8204)
		(end 127.420624 -10.947908)
		(width 0.14224)
		(layer "In11.Cu")
		(net "M_H_DQS_DP<14>")
	)
	(segment
		(start 127.643128 -21.11756)
		(end 127.643128 -19.192494)
		(width 0.14224)
		(layer "In11.Cu")
		(net "M_H_DQS_DP<14>")
	)
	(segment
		(start 127.91186 -9.29132)
		(end 127.42418 -9.779)
		(width 0.14224)
		(layer "In11.Cu")
		(net "M_H_DQS_DP<14>")
	)
	(segment
		(start 127.643128 -19.192494)
		(end 127.889254 -18.946368)
		(width 0.14224)
		(layer "In11.Cu")
		(net "M_H_DQS_DP<14>")
	)
	(segment
		(start 127.577088 -11.4427)
		(end 127.66548 -11.4427)
		(width 0.14224)
		(layer "In11.Cu")
		(net "M_H_DQS_DP<14>")
	)
	(segment
		(start 127.381254 -14.55928)
		(end 126.89078 -14.068806)
		(width 0.14224)
		(layer "In11.Cu")
		(net "M_H_DQS_DP<14>")
	)
	(segment
		(start 127.420624 -11.286236)
		(end 127.577088 -11.4427)
		(width 0.14224)
		(layer "In11.Cu")
		(net "M_H_DQS_DP<14>")
	)
	(segment
		(start 127.42418 -9.779)
		(end 127.42418 -10.033)
		(width 0.14224)
		(layer "In11.Cu")
		(net "M_H_DQS_DP<14>")
	)
	(segment
		(start 127.91186 -8.455914)
		(end 127.91186 -9.29132)
		(width 0.14224)
		(layer "In11.Cu")
		(net "M_H_DQS_DP<14>")
	)
	(segment
		(start 127.889254 -26.907236)
		(end 127.889254 -21.363686)
		(width 0.14224)
		(layer "In11.Cu")
		(net "M_H_DQS_DP<14>")
	)
	(segment
		(start 127.671068 -12.573)
		(end 127.392176 -12.573)
		(width 0.14224)
		(layer "In11.Cu")
		(net "M_H_DQS_DP<14>")
	)
	(segment
		(start 127.731266 -8.27532)
		(end 127.91186 -8.455914)
		(width 0.14224)
		(layer "In11.Cu")
		(net "M_H_DQS_DP<14>")
	)
	(segment
		(start 127.66548 -11.4427)
		(end 127.91186 -11.68908)
		(width 0.14224)
		(layer "In11.Cu")
		(net "M_H_DQS_DP<14>")
	)
	(segment
		(start 126.89078 -14.068806)
		(end 126.89078 -13.074396)
		(width 0.14224)
		(layer "In11.Cu")
		(net "M_H_DQS_DP<14>")
	)
	(segment
		(start 127.91186 -11.68908)
		(end 127.91186 -12.332208)
		(width 0.14224)
		(layer "In11.Cu")
		(net "M_H_DQS_DP<14>")
	)
	(segment
		(start 127.889254 -15.902686)
		(end 127.381254 -15.394686)
		(width 0.14224)
		(layer "In11.Cu")
		(net "M_H_DQS_DP<14>")
	)
	(segment
		(start 127.70358 -10.1854)
		(end 127.91186 -10.39368)
		(width 0.14224)
		(layer "In11.Cu")
		(net "M_H_DQS_DP<14>")
	)
	(segment
		(start 127.91186 -10.39368)
		(end 127.91186 -10.63752)
		(width 0.14224)
		(layer "In11.Cu")
		(net "M_H_DQS_DP<14>")
	)
	(segment
		(start 127.91186 -12.332208)
		(end 127.671068 -12.573)
		(width 0.14224)
		(layer "In11.Cu")
		(net "M_H_DQS_DP<14>")
	)
	(segment
		(start 127.72898 -10.8204)
		(end 127.548132 -10.8204)
		(width 0.14224)
		(layer "In11.Cu")
		(net "M_H_DQS_DP<14>")
	)
	(segment
		(start 127.392176 -12.573)
		(end 127.391922 -12.573)
		(width 0.14224)
		(layer "In11.Cu")
		(net "M_H_DQS_DP<14>")
	)
	(segment
		(start 126.89078 -13.074396)
		(end 127.392176 -12.573)
		(width 0.14224)
		(layer "In11.Cu")
		(net "M_H_DQS_DP<14>")
	)
	(segment
		(start 127.39878 -27.39771)
		(end 127.889254 -26.907236)
		(width 0.14224)
		(layer "In11.Cu")
		(net "M_H_DQS_DP<14>")
	)
	(segment
		(start 127.420624 -10.947908)
		(end 127.420624 -11.286236)
		(width 0.14224)
		(layer "In11.Cu")
		(net "M_H_DQS_DP<14>")
	)
	(segment
		(start 127.889254 -18.946368)
		(end 127.889254 -15.902686)
		(width 0.14224)
		(layer "In11.Cu")
		(net "M_H_DQS_DP<14>")
	)
	(segment
		(start 127.889254 -21.363686)
		(end 127.643128 -21.11756)
		(width 0.14224)
		(layer "In11.Cu")
		(net "M_H_DQS_DP<14>")
	)
	(segment
		(start 127.57658 -10.1854)
		(end 127.70358 -10.1854)
		(width 0.14224)
		(layer "In11.Cu")
		(net "M_H_DQS_DP<14>")
	)
	(segment
		(start 127.599948 -8.27532)
		(end 127.731266 -8.27532)
		(width 0.14224)
		(layer "In11.Cu")
		(net "M_H_DQS_DP<14>")
	)
	(segment
		(start 127.91186 -10.63752)
		(end 127.72898 -10.8204)
		(width 0.14224)
		(layer "In11.Cu")
		(net "M_H_DQS_DP<14>")
	)
	(segment
		(start 117.549168 -7.004558)
		(end 117.549168 -7.796022)
		(width 0.1651)
		(layer "F.Cu")
		(net "M_H_DQS_DP<13>")
	)
	(segment
		(start 118.099332 -6.454394)
		(end 117.549168 -7.004558)
		(width 0.1651)
		(layer "F.Cu")
		(net "M_H_DQS_DP<13>")
	)
	(segment
		(start 117.549168 -7.796022)
		(end 117.660166 -8.101584)
		(width 0.1651)
		(layer "F.Cu")
		(net "M_H_DQS_DP<13>")
	)
	(segment
		(start 107.051856 -56.399938)
		(end 106.480356 -56.399938)
		(width 0.1016)
		(layer "F.Cu")
		(net "M_H_DQS_DP<13>")
	)
	(segment
		(start 118.099332 -5.822442)
		(end 118.099332 -6.454394)
		(width 0.1651)
		(layer "F.Cu")
		(net "M_H_DQS_DP<13>")
	)
	(segment
		(start 117.660166 -8.101584)
		(end 118.041928 -8.483346)
		(width 0.1651)
		(layer "F.Cu")
		(net "M_H_DQS_DP<13>")
	)
	(via
		(at 118.041928 -8.483346)
		(size 0.508)
		(drill 0.254)
		(layers "F.Cu" "B.Cu")
		(net "M_H_DQS_DP<13>")
	)
	(via
		(at 106.480356 -56.399938)
		(size 0.508)
		(drill 0.254)
		(layers "F.Cu" "B.Cu")
		(net "M_H_DQS_DP<13>")
	)
	(via
		(at 118.041928 -12.573)
		(size 0.508)
		(drill 0.254)
		(layers "F.Cu" "B.Cu")
		(net "M_H_DQS_DP<13>")
	)
	(segment
		(start 117.565932 -13.121132)
		(end 117.653308 -12.96162)
		(width 0.1651)
		(layer "B.Cu")
		(net "M_H_DQS_DP<13>")
	)
	(segment
		(start 118.099332 -14.605254)
		(end 117.643148 -14.14907)
		(width 0.1651)
		(layer "B.Cu")
		(net "M_H_DQS_DP<13>")
	)
	(segment
		(start 117.565932 -14.016736)
		(end 117.565932 -13.121132)
		(width 0.1651)
		(layer "B.Cu")
		(net "M_H_DQS_DP<13>")
	)
	(segment
		(start 117.653308 -12.96162)
		(end 118.041928 -12.573)
		(width 0.1651)
		(layer "B.Cu")
		(net "M_H_DQS_DP<13>")
	)
	(segment
		(start 117.643148 -14.14907)
		(end 117.565932 -14.016736)
		(width 0.1651)
		(layer "B.Cu")
		(net "M_H_DQS_DP<13>")
	)
	(segment
		(start 118.099332 -15.222982)
		(end 118.099332 -14.605254)
		(width 0.1651)
		(layer "B.Cu")
		(net "M_H_DQS_DP<13>")
	)
	(segment
		(start 118.561612 -11.68908)
		(end 118.315232 -11.4427)
		(width 0.14224)
		(layer "In4.Cu")
		(net "M_H_DQS_DP<13>")
	)
	(segment
		(start 118.561612 -8.455914)
		(end 118.381018 -8.27532)
		(width 0.14224)
		(layer "In4.Cu")
		(net "M_H_DQS_DP<13>")
	)
	(segment
		(start 118.561612 -12.332462)
		(end 118.561612 -11.68908)
		(width 0.14224)
		(layer "In4.Cu")
		(net "M_H_DQS_DP<13>")
	)
	(segment
		(start 118.555008 -24.843486)
		(end 118.555008 -16.238474)
		(width 0.14224)
		(layer "In4.Cu")
		(net "M_H_DQS_DP<13>")
	)
	(segment
		(start 118.073932 -9.779)
		(end 118.561612 -9.29132)
		(width 0.14224)
		(layer "In4.Cu")
		(net "M_H_DQS_DP<13>")
	)
	(segment
		(start 108.641134 -45.476414)
		(end 108.641134 -37.399722)
		(width 0.14224)
		(layer "In4.Cu")
		(net "M_H_DQS_DP<13>")
	)
	(segment
		(start 118.321074 -12.573)
		(end 118.561612 -12.332462)
		(width 0.14224)
		(layer "In4.Cu")
		(net "M_H_DQS_DP<13>")
	)
	(segment
		(start 118.315232 -11.4427)
		(end 118.22684 -11.4427)
		(width 0.14224)
		(layer "In4.Cu")
		(net "M_H_DQS_DP<13>")
	)
	(segment
		(start 118.197884 -10.8204)
		(end 118.378732 -10.8204)
		(width 0.14224)
		(layer "In4.Cu")
		(net "M_H_DQS_DP<13>")
	)
	(segment
		(start 114.836448 -30.354778)
		(end 114.836448 -29.488638)
		(width 0.14224)
		(layer "In4.Cu")
		(net "M_H_DQS_DP<13>")
	)
	(segment
		(start 118.070376 -10.947908)
		(end 118.197884 -10.8204)
		(width 0.14224)
		(layer "In4.Cu")
		(net "M_H_DQS_DP<13>")
	)
	(segment
		(start 108.641134 -45.498512)
		(end 108.641134 -45.476414)
		(width 0.0889)
		(layer "In4.Cu")
		(net "M_H_DQS_DP<13>")
	)
	(segment
		(start 106.880406 -54.526688)
		(end 106.880406 -53.195728)
		(width 0.0889)
		(layer "In4.Cu")
		(net "M_H_DQS_DP<13>")
	)
	(segment
		(start 118.62816 -26.563066)
		(end 118.62816 -26.252424)
		(width 0.14224)
		(layer "In4.Cu")
		(net "M_H_DQS_DP<13>")
	)
	(segment
		(start 118.353332 -10.1854)
		(end 118.226332 -10.1854)
		(width 0.14224)
		(layer "In4.Cu")
		(net "M_H_DQS_DP<13>")
	)
	(segment
		(start 118.264432 -25.888696)
		(end 118.264432 -25.134062)
		(width 0.14224)
		(layer "In4.Cu")
		(net "M_H_DQS_DP<13>")
	)
	(segment
		(start 118.561612 -9.29132)
		(end 118.561612 -8.455914)
		(width 0.14224)
		(layer "In4.Cu")
		(net "M_H_DQS_DP<13>")
	)
	(segment
		(start 116.668804 -28.103068)
		(end 116.359432 -27.793696)
		(width 0.14224)
		(layer "In4.Cu")
		(net "M_H_DQS_DP<13>")
	)
	(segment
		(start 118.62816 -26.252424)
		(end 118.264432 -25.888696)
		(width 0.14224)
		(layer "In4.Cu")
		(net "M_H_DQS_DP<13>")
	)
	(segment
		(start 114.226848 -31.814008)
		(end 114.226848 -30.96514)
		(width 0.14224)
		(layer "In4.Cu")
		(net "M_H_DQS_DP<13>")
	)
	(segment
		(start 106.757724 -51.82616)
		(end 107.510072 -51.073812)
		(width 0.0889)
		(layer "In4.Cu")
		(net "M_H_DQS_DP<13>")
	)
	(segment
		(start 107.510072 -49.009554)
		(end 107.793028 -48.726598)
		(width 0.0889)
		(layer "In4.Cu")
		(net "M_H_DQS_DP<13>")
	)
	(segment
		(start 118.264432 -25.134062)
		(end 118.555008 -24.843486)
		(width 0.14224)
		(layer "In4.Cu")
		(net "M_H_DQS_DP<13>")
	)
	(segment
		(start 108.680504 -46.51248)
		(end 108.680504 -45.537882)
		(width 0.0889)
		(layer "In4.Cu")
		(net "M_H_DQS_DP<13>")
	)
	(segment
		(start 116.668804 -28.41371)
		(end 116.668804 -28.103068)
		(width 0.14224)
		(layer "In4.Cu")
		(net "M_H_DQS_DP<13>")
	)
	(segment
		(start 117.502686 -26.65095)
		(end 117.865906 -27.01417)
		(width 0.14224)
		(layer "In4.Cu")
		(net "M_H_DQS_DP<13>")
	)
	(segment
		(start 116.96573 -26.65095)
		(end 117.502686 -26.65095)
		(width 0.14224)
		(layer "In4.Cu")
		(net "M_H_DQS_DP<13>")
	)
	(segment
		(start 117.571012 -13.043916)
		(end 118.041928 -12.573)
		(width 0.14224)
		(layer "In4.Cu")
		(net "M_H_DQS_DP<13>")
	)
	(segment
		(start 114.226848 -30.96514)
		(end 114.610388 -30.5816)
		(width 0.14224)
		(layer "In4.Cu")
		(net "M_H_DQS_DP<13>")
	)
	(segment
		(start 118.555008 -16.238474)
		(end 117.571012 -15.254478)
		(width 0.14224)
		(layer "In4.Cu")
		(net "M_H_DQS_DP<13>")
	)
	(segment
		(start 118.226332 -10.1854)
		(end 118.073932 -10.033)
		(width 0.14224)
		(layer "In4.Cu")
		(net "M_H_DQS_DP<13>")
	)
	(segment
		(start 118.073932 -10.033)
		(end 118.073932 -9.779)
		(width 0.14224)
		(layer "In4.Cu")
		(net "M_H_DQS_DP<13>")
	)
	(segment
		(start 118.378732 -10.8204)
		(end 118.561612 -10.63752)
		(width 0.14224)
		(layer "In4.Cu")
		(net "M_H_DQS_DP<13>")
	)
	(segment
		(start 118.249954 -8.27532)
		(end 118.041928 -8.483346)
		(width 0.14224)
		(layer "In4.Cu")
		(net "M_H_DQS_DP<13>")
	)
	(segment
		(start 116.32819 -28.754324)
		(end 116.668804 -28.41371)
		(width 0.14224)
		(layer "In4.Cu")
		(net "M_H_DQS_DP<13>")
	)
	(segment
		(start 107.510072 -51.073812)
		(end 107.510072 -49.009554)
		(width 0.0889)
		(layer "In4.Cu")
		(net "M_H_DQS_DP<13>")
	)
	(segment
		(start 114.610388 -30.5816)
		(end 114.610388 -30.580838)
		(width 0.14224)
		(layer "In4.Cu")
		(net "M_H_DQS_DP<13>")
	)
	(segment
		(start 118.22684 -11.4427)
		(end 118.070376 -11.286236)
		(width 0.14224)
		(layer "In4.Cu")
		(net "M_H_DQS_DP<13>")
	)
	(segment
		(start 118.381018 -8.27532)
		(end 118.249954 -8.27532)
		(width 0.14224)
		(layer "In4.Cu")
		(net "M_H_DQS_DP<13>")
	)
	(segment
		(start 118.041928 -12.573)
		(end 118.321074 -12.573)
		(width 0.14224)
		(layer "In4.Cu")
		(net "M_H_DQS_DP<13>")
	)
	(segment
		(start 118.561612 -10.39368)
		(end 118.353332 -10.1854)
		(width 0.14224)
		(layer "In4.Cu")
		(net "M_H_DQS_DP<13>")
	)
	(segment
		(start 107.793028 -48.726598)
		(end 107.793028 -47.399956)
		(width 0.0889)
		(layer "In4.Cu")
		(net "M_H_DQS_DP<13>")
	)
	(segment
		(start 108.680504 -45.537882)
		(end 108.641134 -45.498512)
		(width 0.0889)
		(layer "In4.Cu")
		(net "M_H_DQS_DP<13>")
	)
	(segment
		(start 107.793028 -47.399956)
		(end 108.680504 -46.51248)
		(width 0.0889)
		(layer "In4.Cu")
		(net "M_H_DQS_DP<13>")
	)
	(segment
		(start 114.836448 -29.488638)
		(end 115.570762 -28.754324)
		(width 0.14224)
		(layer "In4.Cu")
		(net "M_H_DQS_DP<13>")
	)
	(segment
		(start 106.880406 -53.195728)
		(end 106.757724 -53.073046)
		(width 0.0889)
		(layer "In4.Cu")
		(net "M_H_DQS_DP<13>")
	)
	(segment
		(start 115.570762 -28.754324)
		(end 116.32819 -28.754324)
		(width 0.14224)
		(layer "In4.Cu")
		(net "M_H_DQS_DP<13>")
	)
	(segment
		(start 117.865906 -27.01417)
		(end 118.177056 -27.01417)
		(width 0.14224)
		(layer "In4.Cu")
		(net "M_H_DQS_DP<13>")
	)
	(segment
		(start 106.458766 -54.818788)
		(end 106.497882 -54.818788)
		(width 0.0889)
		(layer "In4.Cu")
		(net "M_H_DQS_DP<13>")
	)
	(segment
		(start 118.070376 -11.286236)
		(end 118.070376 -10.947908)
		(width 0.14224)
		(layer "In4.Cu")
		(net "M_H_DQS_DP<13>")
	)
	(segment
		(start 117.571012 -15.254478)
		(end 117.571012 -13.043916)
		(width 0.14224)
		(layer "In4.Cu")
		(net "M_H_DQS_DP<13>")
	)
	(segment
		(start 118.561612 -10.63752)
		(end 118.561612 -10.39368)
		(width 0.14224)
		(layer "In4.Cu")
		(net "M_H_DQS_DP<13>")
	)
	(segment
		(start 116.359432 -27.257248)
		(end 116.96573 -26.65095)
		(width 0.14224)
		(layer "In4.Cu")
		(net "M_H_DQS_DP<13>")
	)
	(segment
		(start 106.757724 -53.073046)
		(end 106.757724 -51.82616)
		(width 0.0889)
		(layer "In4.Cu")
		(net "M_H_DQS_DP<13>")
	)
	(segment
		(start 114.610388 -30.580838)
		(end 114.836448 -30.354778)
		(width 0.14224)
		(layer "In4.Cu")
		(net "M_H_DQS_DP<13>")
	)
	(segment
		(start 118.177056 -27.01417)
		(end 118.62816 -26.563066)
		(width 0.14224)
		(layer "In4.Cu")
		(net "M_H_DQS_DP<13>")
	)
	(segment
		(start 108.641134 -37.399722)
		(end 114.226848 -31.814008)
		(width 0.14224)
		(layer "In4.Cu")
		(net "M_H_DQS_DP<13>")
	)
	(segment
		(start 116.359432 -27.793696)
		(end 116.359432 -27.257248)
		(width 0.14224)
		(layer "In4.Cu")
		(net "M_H_DQS_DP<13>")
	)
	(segment
		(start 106.827066 -54.61889)
		(end 106.880406 -54.526688)
		(width 0.0889)
		(layer "In4.Cu")
		(net "M_H_DQS_DP<13>")
	)
	(arc
		(start 106.497882 -54.818788)
		(mid 106.688124 -54.761053)
		(end 106.827066 -54.61889)
		(width 0.0889)
		(layer "In4.Cu")
		(net "M_H_DQS_DP<13>")
	)
	(arc
		(start 106.058208 -55.825644)
		(mid 105.917025 -55.186422)
		(end 106.458766 -54.818788)
		(width 0.0889)
		(layer "In4.Cu")
		(net "M_H_DQS_DP<13>")
	)
	(arc
		(start 106.480356 -56.399938)
		(mid 106.292529 -56.095703)
		(end 106.058208 -55.825644)
		(width 0.0889)
		(layer "In4.Cu")
		(net "M_H_DQS_DP<13>")
	)
	(segment
		(start 78.31836 -50.135282)
		(end 78.318868 -50.134774)
		(width 0.0889)
		(layer "F.Cu")
		(net "M_H_DQS_DP<12>")
	)
	(segment
		(start 62.304168 -35.18408)
		(end 62.653418 -35.53333)
		(width 0.1651)
		(layer "F.Cu")
		(net "M_H_DQS_DP<12>")
	)
	(segment
		(start 78.105508 -49.492154)
		(end 76.907644 -48.29429)
		(width 0.1016)
		(layer "F.Cu")
		(net "M_H_DQS_DP<12>")
	)
	(segment
		(start 62.304168 -34.41192)
		(end 62.304168 -35.18408)
		(width 0.1651)
		(layer "F.Cu")
		(net "M_H_DQS_DP<12>")
	)
	(segment
		(start 62.328806 -7.877302)
		(end 62.41034 -8.101584)
		(width 0.1651)
		(layer "F.Cu")
		(net "M_H_DQS_DP<12>")
	)
	(segment
		(start 63.175388 -36.241482)
		(end 62.99708 -36.41979)
		(width 0.1651)
		(layer "F.Cu")
		(net "M_H_DQS_DP<12>")
	)
	(segment
		(start 62.798706 -27.39771)
		(end 62.304168 -27.892248)
		(width 0.1651)
		(layer "F.Cu")
		(net "M_H_DQS_DP<12>")
	)
	(segment
		(start 62.653418 -34.06267)
		(end 62.304168 -34.41192)
		(width 0.1651)
		(layer "F.Cu")
		(net "M_H_DQS_DP<12>")
	)
	(segment
		(start 62.304168 -32.82696)
		(end 62.653418 -33.17621)
		(width 0.1651)
		(layer "F.Cu")
		(net "M_H_DQS_DP<12>")
	)
	(segment
		(start 68.473574 -47.93869)
		(end 67.293998 -46.759114)
		(width 0.1016)
		(layer "F.Cu")
		(net "M_H_DQS_DP<12>")
	)
	(segment
		(start 62.304168 -27.892248)
		(end 62.304168 -31.877)
		(width 0.1651)
		(layer "F.Cu")
		(net "M_H_DQS_DP<12>")
	)
	(segment
		(start 63.167768 -42.949368)
		(end 66.60642 -46.38802)
		(width 0.1651)
		(layer "F.Cu")
		(net "M_H_DQS_DP<12>")
	)
	(segment
		(start 63.167768 -38.14699)
		(end 63.167768 -42.949368)
		(width 0.1651)
		(layer "F.Cu")
		(net "M_H_DQS_DP<12>")
	)
	(segment
		(start 66.977514 -46.759114)
		(end 67.293998 -46.759114)
		(width 0.1016)
		(layer "F.Cu")
		(net "M_H_DQS_DP<12>")
	)
	(segment
		(start 62.41034 -8.101584)
		(end 62.792102 -8.483346)
		(width 0.1651)
		(layer "F.Cu")
		(net "M_H_DQS_DP<12>")
	)
	(segment
		(start 62.99708 -36.41979)
		(end 62.71641 -36.41979)
		(width 0.1651)
		(layer "F.Cu")
		(net "M_H_DQS_DP<12>")
	)
	(segment
		(start 62.653418 -35.53333)
		(end 62.99708 -35.53333)
		(width 0.1651)
		(layer "F.Cu")
		(net "M_H_DQS_DP<12>")
	)
	(segment
		(start 62.380368 -37.35959)
		(end 63.167768 -38.14699)
		(width 0.1651)
		(layer "F.Cu")
		(net "M_H_DQS_DP<12>")
	)
	(segment
		(start 62.71641 -36.41979)
		(end 62.380368 -36.755832)
		(width 0.1651)
		(layer "F.Cu")
		(net "M_H_DQS_DP<12>")
	)
	(segment
		(start 72.564244 -47.93869)
		(end 68.473574 -47.93869)
		(width 0.1016)
		(layer "F.Cu")
		(net "M_H_DQS_DP<12>")
	)
	(segment
		(start 63.193168 -33.89757)
		(end 63.028068 -34.06267)
		(width 0.1651)
		(layer "F.Cu")
		(net "M_H_DQS_DP<12>")
	)
	(segment
		(start 63.175388 -35.711638)
		(end 63.175388 -36.241482)
		(width 0.1651)
		(layer "F.Cu")
		(net "M_H_DQS_DP<12>")
	)
	(segment
		(start 63.028068 -34.06267)
		(end 62.653418 -34.06267)
		(width 0.1651)
		(layer "F.Cu")
		(net "M_H_DQS_DP<12>")
	)
	(segment
		(start 63.193168 -33.34131)
		(end 63.193168 -33.89757)
		(width 0.1651)
		(layer "F.Cu")
		(net "M_H_DQS_DP<12>")
	)
	(segment
		(start 62.99708 -35.53333)
		(end 63.175388 -35.711638)
		(width 0.1651)
		(layer "F.Cu")
		(net "M_H_DQS_DP<12>")
	)
	(segment
		(start 62.380368 -36.755832)
		(end 62.380368 -37.35959)
		(width 0.1651)
		(layer "F.Cu")
		(net "M_H_DQS_DP<12>")
	)
	(segment
		(start 62.328806 -7.059168)
		(end 62.328806 -7.877302)
		(width 0.1651)
		(layer "F.Cu")
		(net "M_H_DQS_DP<12>")
	)
	(segment
		(start 78.909672 -50.800762)
		(end 78.837536 -50.728626)
		(width 0.0889)
		(layer "F.Cu")
		(net "M_H_DQS_DP<12>")
	)
	(segment
		(start 62.849506 -5.822442)
		(end 62.849506 -6.439154)
		(width 0.1651)
		(layer "F.Cu")
		(net "M_H_DQS_DP<12>")
	)
	(segment
		(start 76.907644 -48.29429)
		(end 72.919844 -48.29429)
		(width 0.1016)
		(layer "F.Cu")
		(net "M_H_DQS_DP<12>")
	)
	(segment
		(start 62.849506 -6.439154)
		(end 62.413388 -6.875272)
		(width 0.1651)
		(layer "F.Cu")
		(net "M_H_DQS_DP<12>")
	)
	(segment
		(start 78.318868 -49.61509)
		(end 78.195932 -49.492154)
		(width 0.0889)
		(layer "F.Cu")
		(net "M_H_DQS_DP<12>")
	)
	(segment
		(start 66.60642 -46.38802)
		(end 66.977514 -46.759114)
		(width 0.1016)
		(layer "F.Cu")
		(net "M_H_DQS_DP<12>")
	)
	(segment
		(start 78.318868 -50.134774)
		(end 78.318868 -49.61509)
		(width 0.0889)
		(layer "F.Cu")
		(net "M_H_DQS_DP<12>")
	)
	(segment
		(start 72.919844 -48.29429)
		(end 72.564244 -47.93869)
		(width 0.1016)
		(layer "F.Cu")
		(net "M_H_DQS_DP<12>")
	)
	(segment
		(start 62.413388 -6.875272)
		(end 62.328806 -7.059168)
		(width 0.1651)
		(layer "F.Cu")
		(net "M_H_DQS_DP<12>")
	)
	(segment
		(start 78.909672 -51.132486)
		(end 78.909672 -50.800762)
		(width 0.0889)
		(layer "F.Cu")
		(net "M_H_DQS_DP<12>")
	)
	(segment
		(start 63.028068 -33.17621)
		(end 63.193168 -33.34131)
		(width 0.1651)
		(layer "F.Cu")
		(net "M_H_DQS_DP<12>")
	)
	(segment
		(start 62.304168 -31.877)
		(end 62.304168 -32.82696)
		(width 0.1651)
		(layer "F.Cu")
		(net "M_H_DQS_DP<12>")
	)
	(segment
		(start 78.195932 -49.492154)
		(end 78.105508 -49.492154)
		(width 0.0889)
		(layer "F.Cu")
		(net "M_H_DQS_DP<12>")
	)
	(segment
		(start 62.653418 -33.17621)
		(end 63.028068 -33.17621)
		(width 0.1651)
		(layer "F.Cu")
		(net "M_H_DQS_DP<12>")
	)
	(via
		(at 62.792102 -12.573)
		(size 0.508)
		(drill 0.254)
		(layers "F.Cu" "B.Cu")
		(net "M_H_DQS_DP<12>")
	)
	(via
		(at 62.304168 -31.877)
		(size 0.508)
		(drill 0.254)
		(layers "F.Cu" "B.Cu")
		(net "M_H_DQS_DP<12>")
	)
	(via
		(at 62.792102 -8.483346)
		(size 0.508)
		(drill 0.254)
		(layers "F.Cu" "B.Cu")
		(net "M_H_DQS_DP<12>")
	)
	(via
		(at 62.798706 -27.39771)
		(size 0.508)
		(drill 0.254)
		(layers "F.Cu" "B.Cu")
		(net "M_H_DQS_DP<12>")
	)
	(arc
		(start 78.837536 -50.728626)
		(mid 78.826854 -50.727199)
		(end 78.8162 -50.725578)
		(width 0.0889)
		(layer "F.Cu")
		(net "M_H_DQS_DP<12>")
	)
	(arc
		(start 78.8162 -50.725578)
		(mid 78.574494 -50.628804)
		(end 78.397862 -50.437542)
		(width 0.0889)
		(layer "F.Cu")
		(net "M_H_DQS_DP<12>")
	)
	(arc
		(start 78.397862 -50.437542)
		(mid 78.337765 -50.291763)
		(end 78.31836 -50.135282)
		(width 0.0889)
		(layer "F.Cu")
		(net "M_H_DQS_DP<12>")
	)
	(segment
		(start 62.849506 -14.605254)
		(end 62.393322 -14.14907)
		(width 0.1651)
		(layer "B.Cu")
		(net "M_H_DQS_DP<12>")
	)
	(segment
		(start 62.403482 -12.96162)
		(end 62.792102 -12.573)
		(width 0.1651)
		(layer "B.Cu")
		(net "M_H_DQS_DP<12>")
	)
	(segment
		(start 62.849506 -15.222982)
		(end 62.849506 -14.605254)
		(width 0.1651)
		(layer "B.Cu")
		(net "M_H_DQS_DP<12>")
	)
	(segment
		(start 62.316106 -13.121132)
		(end 62.403482 -12.96162)
		(width 0.1651)
		(layer "B.Cu")
		(net "M_H_DQS_DP<12>")
	)
	(segment
		(start 62.393322 -14.14907)
		(end 62.316106 -14.016736)
		(width 0.1651)
		(layer "B.Cu")
		(net "M_H_DQS_DP<12>")
	)
	(segment
		(start 62.316106 -14.016736)
		(end 62.316106 -13.121132)
		(width 0.1651)
		(layer "B.Cu")
		(net "M_H_DQS_DP<12>")
	)
	(segment
		(start 62.792102 -8.483346)
		(end 63.000128 -8.27532)
		(width 0.14224)
		(layer "In4.Cu")
		(net "M_H_DQS_DP<12>")
	)
	(segment
		(start 63.131192 -8.27532)
		(end 63.311786 -8.455914)
		(width 0.14224)
		(layer "In4.Cu")
		(net "M_H_DQS_DP<12>")
	)
	(segment
		(start 63.311786 -11.68908)
		(end 63.311786 -12.332462)
		(width 0.14224)
		(layer "In4.Cu")
		(net "M_H_DQS_DP<12>")
	)
	(segment
		(start 62.290706 -14.068806)
		(end 62.78118 -14.55928)
		(width 0.14224)
		(layer "In4.Cu")
		(net "M_H_DQS_DP<12>")
	)
	(segment
		(start 63.311786 -10.39368)
		(end 63.311786 -10.63752)
		(width 0.14224)
		(layer "In4.Cu")
		(net "M_H_DQS_DP<12>")
	)
	(segment
		(start 62.290706 -13.074396)
		(end 62.290706 -14.068806)
		(width 0.14224)
		(layer "In4.Cu")
		(net "M_H_DQS_DP<12>")
	)
	(segment
		(start 62.948058 -10.8204)
		(end 62.82055 -10.947908)
		(width 0.14224)
		(layer "In4.Cu")
		(net "M_H_DQS_DP<12>")
	)
	(segment
		(start 63.311786 -10.63752)
		(end 63.128906 -10.8204)
		(width 0.14224)
		(layer "In4.Cu")
		(net "M_H_DQS_DP<12>")
	)
	(segment
		(start 63.103506 -10.1854)
		(end 63.311786 -10.39368)
		(width 0.14224)
		(layer "In4.Cu")
		(net "M_H_DQS_DP<12>")
	)
	(segment
		(start 63.28918 -15.79626)
		(end 63.28918 -26.907236)
		(width 0.14224)
		(layer "In4.Cu")
		(net "M_H_DQS_DP<12>")
	)
	(segment
		(start 63.000128 -8.27532)
		(end 63.131192 -8.27532)
		(width 0.14224)
		(layer "In4.Cu")
		(net "M_H_DQS_DP<12>")
	)
	(segment
		(start 63.311786 -9.29132)
		(end 62.824106 -9.779)
		(width 0.14224)
		(layer "In4.Cu")
		(net "M_H_DQS_DP<12>")
	)
	(segment
		(start 62.976506 -10.1854)
		(end 63.103506 -10.1854)
		(width 0.14224)
		(layer "In4.Cu")
		(net "M_H_DQS_DP<12>")
	)
	(segment
		(start 63.28918 -26.907236)
		(end 62.798706 -27.39771)
		(width 0.14224)
		(layer "In4.Cu")
		(net "M_H_DQS_DP<12>")
	)
	(segment
		(start 63.311786 -8.455914)
		(end 63.311786 -9.29132)
		(width 0.14224)
		(layer "In4.Cu")
		(net "M_H_DQS_DP<12>")
	)
	(segment
		(start 62.977014 -11.4427)
		(end 63.065406 -11.4427)
		(width 0.14224)
		(layer "In4.Cu")
		(net "M_H_DQS_DP<12>")
	)
	(segment
		(start 63.065406 -11.4427)
		(end 63.311786 -11.68908)
		(width 0.14224)
		(layer "In4.Cu")
		(net "M_H_DQS_DP<12>")
	)
	(segment
		(start 62.824106 -10.033)
		(end 62.976506 -10.1854)
		(width 0.14224)
		(layer "In4.Cu")
		(net "M_H_DQS_DP<12>")
	)
	(segment
		(start 62.78118 -15.28826)
		(end 63.28918 -15.79626)
		(width 0.14224)
		(layer "In4.Cu")
		(net "M_H_DQS_DP<12>")
	)
	(segment
		(start 63.311786 -12.332462)
		(end 63.071248 -12.573)
		(width 0.14224)
		(layer "In4.Cu")
		(net "M_H_DQS_DP<12>")
	)
	(segment
		(start 62.824106 -9.779)
		(end 62.824106 -10.033)
		(width 0.14224)
		(layer "In4.Cu")
		(net "M_H_DQS_DP<12>")
	)
	(segment
		(start 63.128906 -10.8204)
		(end 62.948058 -10.8204)
		(width 0.14224)
		(layer "In4.Cu")
		(net "M_H_DQS_DP<12>")
	)
	(segment
		(start 62.78118 -14.55928)
		(end 62.78118 -15.28826)
		(width 0.14224)
		(layer "In4.Cu")
		(net "M_H_DQS_DP<12>")
	)
	(segment
		(start 62.82055 -10.947908)
		(end 62.82055 -11.286236)
		(width 0.14224)
		(layer "In4.Cu")
		(net "M_H_DQS_DP<12>")
	)
	(segment
		(start 62.792102 -12.573)
		(end 62.290706 -13.074396)
		(width 0.14224)
		(layer "In4.Cu")
		(net "M_H_DQS_DP<12>")
	)
	(segment
		(start 63.071248 -12.573)
		(end 62.792102 -12.573)
		(width 0.14224)
		(layer "In4.Cu")
		(net "M_H_DQS_DP<12>")
	)
	(segment
		(start 62.82055 -11.286236)
		(end 62.977014 -11.4427)
		(width 0.14224)
		(layer "In4.Cu")
		(net "M_H_DQS_DP<12>")
	)
	(segment
		(start 53.063394 -6.875272)
		(end 52.978812 -7.059168)
		(width 0.1651)
		(layer "F.Cu")
		(net "M_H_DQS_DP<11>")
	)
	(segment
		(start 53.499512 -6.439154)
		(end 53.063394 -6.875272)
		(width 0.1651)
		(layer "F.Cu")
		(net "M_H_DQS_DP<11>")
	)
	(segment
		(start 52.978812 -7.059168)
		(end 52.978812 -7.877302)
		(width 0.1651)
		(layer "F.Cu")
		(net "M_H_DQS_DP<11>")
	)
	(segment
		(start 53.060346 -8.101584)
		(end 53.442108 -8.483346)
		(width 0.1651)
		(layer "F.Cu")
		(net "M_H_DQS_DP<11>")
	)
	(segment
		(start 73.758806 -52.12334)
		(end 73.187306 -52.12334)
		(width 0.1016)
		(layer "F.Cu")
		(net "M_H_DQS_DP<11>")
	)
	(segment
		(start 53.499512 -5.822442)
		(end 53.499512 -6.439154)
		(width 0.1651)
		(layer "F.Cu")
		(net "M_H_DQS_DP<11>")
	)
	(segment
		(start 52.978812 -7.877302)
		(end 53.060346 -8.101584)
		(width 0.1651)
		(layer "F.Cu")
		(net "M_H_DQS_DP<11>")
	)
	(via
		(at 53.442108 -8.483346)
		(size 0.508)
		(drill 0.254)
		(layers "F.Cu" "B.Cu")
		(net "M_H_DQS_DP<11>")
	)
	(via
		(at 53.442108 -12.573)
		(size 0.508)
		(drill 0.254)
		(layers "F.Cu" "B.Cu")
		(net "M_H_DQS_DP<11>")
	)
	(via
		(at 73.187306 -52.12334)
		(size 0.508)
		(drill 0.254)
		(layers "F.Cu" "B.Cu")
		(net "M_H_DQS_DP<11>")
	)
	(segment
		(start 53.499512 -15.222982)
		(end 53.499512 -14.605254)
		(width 0.1651)
		(layer "B.Cu")
		(net "M_H_DQS_DP<11>")
	)
	(segment
		(start 52.966112 -14.016736)
		(end 52.966112 -13.121132)
		(width 0.1651)
		(layer "B.Cu")
		(net "M_H_DQS_DP<11>")
	)
	(segment
		(start 53.499512 -14.605254)
		(end 53.043328 -14.14907)
		(width 0.1651)
		(layer "B.Cu")
		(net "M_H_DQS_DP<11>")
	)
	(segment
		(start 53.053488 -12.96162)
		(end 53.442108 -12.573)
		(width 0.1651)
		(layer "B.Cu")
		(net "M_H_DQS_DP<11>")
	)
	(segment
		(start 52.966112 -13.121132)
		(end 53.053488 -12.96162)
		(width 0.1651)
		(layer "B.Cu")
		(net "M_H_DQS_DP<11>")
	)
	(segment
		(start 53.043328 -14.14907)
		(end 52.966112 -14.016736)
		(width 0.1651)
		(layer "B.Cu")
		(net "M_H_DQS_DP<11>")
	)
	(segment
		(start 53.961792 -12.332462)
		(end 53.961792 -11.68908)
		(width 0.14224)
		(layer "In4.Cu")
		(net "M_H_DQS_DP<11>")
	)
	(segment
		(start 64.016636 -39.525702)
		(end 63.264288 -39.525702)
		(width 0.14224)
		(layer "In4.Cu")
		(net "M_H_DQS_DP<11>")
	)
	(segment
		(start 59.95162 -36.212272)
		(end 59.51855 -35.779202)
		(width 0.14224)
		(layer "In4.Cu")
		(net "M_H_DQS_DP<11>")
	)
	(segment
		(start 60.7822 -36.291266)
		(end 60.029852 -36.291266)
		(width 0.14224)
		(layer "In4.Cu")
		(net "M_H_DQS_DP<11>")
	)
	(segment
		(start 53.650134 -8.27532)
		(end 53.442108 -8.483346)
		(width 0.14224)
		(layer "In4.Cu")
		(net "M_H_DQS_DP<11>")
	)
	(segment
		(start 53.961792 -11.68908)
		(end 53.715412 -11.4427)
		(width 0.14224)
		(layer "In4.Cu")
		(net "M_H_DQS_DP<11>")
	)
	(segment
		(start 72.13854 -49.835054)
		(end 70.248272 -49.835054)
		(width 0.0889)
		(layer "In4.Cu")
		(net "M_H_DQS_DP<11>")
	)
	(segment
		(start 68.126102 -47.76851)
		(end 67.445128 -47.087536)
		(width 0.14224)
		(layer "In4.Cu")
		(net "M_H_DQS_DP<11>")
	)
	(segment
		(start 72.58558 -50.282094)
		(end 72.13854 -49.835054)
		(width 0.0889)
		(layer "In4.Cu")
		(net "M_H_DQS_DP<11>")
	)
	(segment
		(start 64.163448 -39.672514)
		(end 64.016636 -39.525702)
		(width 0.14224)
		(layer "In4.Cu")
		(net "M_H_DQS_DP<11>")
	)
	(segment
		(start 63.264288 -39.525702)
		(end 62.752986 -39.0144)
		(width 0.14224)
		(layer "In4.Cu")
		(net "M_H_DQS_DP<11>")
	)
	(segment
		(start 68.14185 -47.784258)
		(end 68.126102 -47.76851)
		(width 0.0889)
		(layer "In4.Cu")
		(net "M_H_DQS_DP<11>")
	)
	(segment
		(start 52.971192 -15.171674)
		(end 52.971192 -13.043916)
		(width 0.14224)
		(layer "In4.Cu")
		(net "M_H_DQS_DP<11>")
	)
	(segment
		(start 59.51855 -35.026854)
		(end 53.955188 -29.463492)
		(width 0.14224)
		(layer "In4.Cu")
		(net "M_H_DQS_DP<11>")
	)
	(segment
		(start 53.442108 -12.573)
		(end 53.721254 -12.573)
		(width 0.14224)
		(layer "In4.Cu")
		(net "M_H_DQS_DP<11>")
	)
	(segment
		(start 53.955188 -29.463492)
		(end 53.955188 -16.15567)
		(width 0.14224)
		(layer "In4.Cu")
		(net "M_H_DQS_DP<11>")
	)
	(segment
		(start 53.753512 -10.1854)
		(end 53.626512 -10.1854)
		(width 0.14224)
		(layer "In4.Cu")
		(net "M_H_DQS_DP<11>")
	)
	(segment
		(start 67.445128 -47.087536)
		(end 67.445128 -46.357032)
		(width 0.14224)
		(layer "In4.Cu")
		(net "M_H_DQS_DP<11>")
	)
	(segment
		(start 53.961792 -8.455914)
		(end 53.781198 -8.27532)
		(width 0.14224)
		(layer "In4.Cu")
		(net "M_H_DQS_DP<11>")
	)
	(segment
		(start 53.955188 -16.15567)
		(end 52.971192 -15.171674)
		(width 0.14224)
		(layer "In4.Cu")
		(net "M_H_DQS_DP<11>")
	)
	(segment
		(start 53.474112 -9.779)
		(end 53.961792 -9.29132)
		(width 0.14224)
		(layer "In4.Cu")
		(net "M_H_DQS_DP<11>")
	)
	(segment
		(start 53.626512 -10.1854)
		(end 53.474112 -10.033)
		(width 0.14224)
		(layer "In4.Cu")
		(net "M_H_DQS_DP<11>")
	)
	(segment
		(start 53.715412 -11.4427)
		(end 53.62702 -11.4427)
		(width 0.14224)
		(layer "In4.Cu")
		(net "M_H_DQS_DP<11>")
	)
	(segment
		(start 60.029852 -36.291266)
		(end 59.95162 -36.213034)
		(width 0.14224)
		(layer "In4.Cu")
		(net "M_H_DQS_DP<11>")
	)
	(segment
		(start 73.187306 -52.12334)
		(end 73.011792 -51.597814)
		(width 0.0889)
		(layer "In4.Cu")
		(net "M_H_DQS_DP<11>")
	)
	(segment
		(start 52.971192 -13.043916)
		(end 53.442108 -12.573)
		(width 0.14224)
		(layer "In4.Cu")
		(net "M_H_DQS_DP<11>")
	)
	(segment
		(start 62.752986 -39.0144)
		(end 62.752986 -38.262052)
		(width 0.14224)
		(layer "In4.Cu")
		(net "M_H_DQS_DP<11>")
	)
	(segment
		(start 53.598064 -10.8204)
		(end 53.778912 -10.8204)
		(width 0.14224)
		(layer "In4.Cu")
		(net "M_H_DQS_DP<11>")
	)
	(segment
		(start 61.135768 -36.644834)
		(end 60.7822 -36.291266)
		(width 0.14224)
		(layer "In4.Cu")
		(net "M_H_DQS_DP<11>")
	)
	(segment
		(start 53.470556 -11.286236)
		(end 53.470556 -10.947908)
		(width 0.14224)
		(layer "In4.Cu")
		(net "M_H_DQS_DP<11>")
	)
	(segment
		(start 61.135768 -37.397182)
		(end 61.135768 -36.644834)
		(width 0.14224)
		(layer "In4.Cu")
		(net "M_H_DQS_DP<11>")
	)
	(segment
		(start 53.778912 -10.8204)
		(end 53.961792 -10.63752)
		(width 0.14224)
		(layer "In4.Cu")
		(net "M_H_DQS_DP<11>")
	)
	(segment
		(start 62.399418 -37.908484)
		(end 61.64707 -37.908484)
		(width 0.14224)
		(layer "In4.Cu")
		(net "M_H_DQS_DP<11>")
	)
	(segment
		(start 73.011792 -51.597814)
		(end 72.840596 -51.332638)
		(width 0.0889)
		(layer "In4.Cu")
		(net "M_H_DQS_DP<11>")
	)
	(segment
		(start 61.64707 -37.908484)
		(end 61.135768 -37.397182)
		(width 0.14224)
		(layer "In4.Cu")
		(net "M_H_DQS_DP<11>")
	)
	(segment
		(start 53.474112 -10.033)
		(end 53.474112 -9.779)
		(width 0.14224)
		(layer "In4.Cu")
		(net "M_H_DQS_DP<11>")
	)
	(segment
		(start 59.51855 -35.779202)
		(end 59.51855 -35.026854)
		(width 0.14224)
		(layer "In4.Cu")
		(net "M_H_DQS_DP<11>")
	)
	(segment
		(start 59.95162 -36.213034)
		(end 59.95162 -36.212272)
		(width 0.14224)
		(layer "In4.Cu")
		(net "M_H_DQS_DP<11>")
	)
	(segment
		(start 70.248272 -49.835054)
		(end 68.197476 -47.784258)
		(width 0.0889)
		(layer "In4.Cu")
		(net "M_H_DQS_DP<11>")
	)
	(segment
		(start 53.470556 -10.947908)
		(end 53.598064 -10.8204)
		(width 0.14224)
		(layer "In4.Cu")
		(net "M_H_DQS_DP<11>")
	)
	(segment
		(start 53.961792 -10.39368)
		(end 53.753512 -10.1854)
		(width 0.14224)
		(layer "In4.Cu")
		(net "M_H_DQS_DP<11>")
	)
	(segment
		(start 62.752986 -38.262052)
		(end 62.399418 -37.908484)
		(width 0.14224)
		(layer "In4.Cu")
		(net "M_H_DQS_DP<11>")
	)
	(segment
		(start 64.163448 -43.076114)
		(end 64.163448 -39.672514)
		(width 0.14224)
		(layer "In4.Cu")
		(net "M_H_DQS_DP<11>")
	)
	(segment
		(start 67.444366 -46.357032)
		(end 64.163448 -43.076114)
		(width 0.14224)
		(layer "In4.Cu")
		(net "M_H_DQS_DP<11>")
	)
	(segment
		(start 53.961792 -10.63752)
		(end 53.961792 -10.39368)
		(width 0.14224)
		(layer "In4.Cu")
		(net "M_H_DQS_DP<11>")
	)
	(segment
		(start 53.781198 -8.27532)
		(end 53.650134 -8.27532)
		(width 0.14224)
		(layer "In4.Cu")
		(net "M_H_DQS_DP<11>")
	)
	(segment
		(start 72.675496 -50.437542)
		(end 72.58558 -50.282094)
		(width 0.0889)
		(layer "In4.Cu")
		(net "M_H_DQS_DP<11>")
	)
	(segment
		(start 53.62702 -11.4427)
		(end 53.470556 -11.286236)
		(width 0.14224)
		(layer "In4.Cu")
		(net "M_H_DQS_DP<11>")
	)
	(segment
		(start 68.197476 -47.784258)
		(end 68.14185 -47.784258)
		(width 0.0889)
		(layer "In4.Cu")
		(net "M_H_DQS_DP<11>")
	)
	(segment
		(start 53.721254 -12.573)
		(end 53.961792 -12.332462)
		(width 0.14224)
		(layer "In4.Cu")
		(net "M_H_DQS_DP<11>")
	)
	(segment
		(start 53.961792 -9.29132)
		(end 53.961792 -8.455914)
		(width 0.14224)
		(layer "In4.Cu")
		(net "M_H_DQS_DP<11>")
	)
	(segment
		(start 67.445128 -46.357032)
		(end 67.444366 -46.357032)
		(width 0.14224)
		(layer "In4.Cu")
		(net "M_H_DQS_DP<11>")
	)
	(arc
		(start 72.706992 -51.013614)
		(mid 72.68991 -50.899698)
		(end 72.700642 -50.785014)
		(width 0.0889)
		(layer "In4.Cu")
		(net "M_H_DQS_DP<11>")
	)
	(arc
		(start 72.700642 -50.785014)
		(mid 72.722018 -50.710938)
		(end 72.728836 -50.634138)
		(width 0.0889)
		(layer "In4.Cu")
		(net "M_H_DQS_DP<11>")
	)
	(arc
		(start 72.840596 -51.332638)
		(mid 72.763667 -51.177368)
		(end 72.706992 -51.013614)
		(width 0.0889)
		(layer "In4.Cu")
		(net "M_H_DQS_DP<11>")
	)
	(arc
		(start 72.728836 -50.634138)
		(mid 72.714895 -50.532383)
		(end 72.675496 -50.437542)
		(width 0.0889)
		(layer "In4.Cu")
		(net "M_H_DQS_DP<11>")
	)
	(segment
		(start 43.628818 -7.877302)
		(end 43.710352 -8.101584)
		(width 0.1651)
		(layer "F.Cu")
		(net "M_H_DQS_DP<10>")
	)
	(segment
		(start 44.149518 -6.439154)
		(end 43.7134 -6.875272)
		(width 0.1651)
		(layer "F.Cu")
		(net "M_H_DQS_DP<10>")
	)
	(segment
		(start 43.710352 -8.101584)
		(end 44.092114 -8.483346)
		(width 0.1651)
		(layer "F.Cu")
		(net "M_H_DQS_DP<10>")
	)
	(segment
		(start 43.628818 -7.059168)
		(end 43.628818 -7.877302)
		(width 0.1651)
		(layer "F.Cu")
		(net "M_H_DQS_DP<10>")
	)
	(segment
		(start 43.7134 -6.875272)
		(end 43.628818 -7.059168)
		(width 0.1651)
		(layer "F.Cu")
		(net "M_H_DQS_DP<10>")
	)
	(segment
		(start 72.041766 -62.029086)
		(end 71.470266 -62.029086)
		(width 0.1016)
		(layer "F.Cu")
		(net "M_H_DQS_DP<10>")
	)
	(segment
		(start 44.149518 -5.822442)
		(end 44.149518 -6.439154)
		(width 0.1651)
		(layer "F.Cu")
		(net "M_H_DQS_DP<10>")
	)
	(via
		(at 44.092114 -12.573)
		(size 0.508)
		(drill 0.254)
		(layers "F.Cu" "B.Cu")
		(net "M_H_DQS_DP<10>")
	)
	(via
		(at 44.092114 -8.483346)
		(size 0.508)
		(drill 0.254)
		(layers "F.Cu" "B.Cu")
		(net "M_H_DQS_DP<10>")
	)
	(via
		(at 71.470266 -62.029086)
		(size 0.508)
		(drill 0.254)
		(layers "F.Cu" "B.Cu")
		(net "M_H_DQS_DP<10>")
	)
	(segment
		(start 43.616118 -14.016736)
		(end 43.616118 -13.121132)
		(width 0.1651)
		(layer "B.Cu")
		(net "M_H_DQS_DP<10>")
	)
	(segment
		(start 43.693334 -14.14907)
		(end 43.616118 -14.016736)
		(width 0.1651)
		(layer "B.Cu")
		(net "M_H_DQS_DP<10>")
	)
	(segment
		(start 44.149518 -14.605254)
		(end 43.693334 -14.14907)
		(width 0.1651)
		(layer "B.Cu")
		(net "M_H_DQS_DP<10>")
	)
	(segment
		(start 43.703494 -12.96162)
		(end 44.092114 -12.573)
		(width 0.1651)
		(layer "B.Cu")
		(net "M_H_DQS_DP<10>")
	)
	(segment
		(start 43.616118 -13.121132)
		(end 43.703494 -12.96162)
		(width 0.1651)
		(layer "B.Cu")
		(net "M_H_DQS_DP<10>")
	)
	(segment
		(start 44.149518 -15.222982)
		(end 44.149518 -14.605254)
		(width 0.1651)
		(layer "B.Cu")
		(net "M_H_DQS_DP<10>")
	)
	(segment
		(start 65.937384 -57.002426)
		(end 65.993264 -57.002426)
		(width 0.0889)
		(layer "In4.Cu")
		(net "M_H_DQS_DP<10>")
	)
	(segment
		(start 66.372232 -57.789318)
		(end 66.734436 -58.151522)
		(width 0.0889)
		(layer "In4.Cu")
		(net "M_H_DQS_DP<10>")
	)
	(segment
		(start 44.277026 -11.4427)
		(end 44.120562 -11.286236)
		(width 0.14224)
		(layer "In4.Cu")
		(net "M_H_DQS_DP<10>")
	)
	(segment
		(start 44.403518 -10.1854)
		(end 44.276518 -10.1854)
		(width 0.14224)
		(layer "In4.Cu")
		(net "M_H_DQS_DP<10>")
	)
	(segment
		(start 48.938942 -39.09314)
		(end 65.070228 -55.224426)
		(width 0.14224)
		(layer "In4.Cu")
		(net "M_H_DQS_DP<10>")
	)
	(segment
		(start 44.124118 -9.779)
		(end 44.611798 -9.29132)
		(width 0.14224)
		(layer "In4.Cu")
		(net "M_H_DQS_DP<10>")
	)
	(segment
		(start 44.611798 -11.68908)
		(end 44.365418 -11.4427)
		(width 0.14224)
		(layer "In4.Cu")
		(net "M_H_DQS_DP<10>")
	)
	(segment
		(start 44.611798 -9.29132)
		(end 44.611798 -8.455914)
		(width 0.14224)
		(layer "In4.Cu")
		(net "M_H_DQS_DP<10>")
	)
	(segment
		(start 47.023528 -33.77946)
		(end 47.023528 -37.177726)
		(width 0.14224)
		(layer "In4.Cu")
		(net "M_H_DQS_DP<10>")
	)
	(segment
		(start 65.070228 -56.13527)
		(end 65.921636 -56.986678)
		(width 0.14224)
		(layer "In4.Cu")
		(net "M_H_DQS_DP<10>")
	)
	(segment
		(start 45.215048 -31.97098)
		(end 47.023528 -33.77946)
		(width 0.14224)
		(layer "In4.Cu")
		(net "M_H_DQS_DP<10>")
	)
	(segment
		(start 44.611798 -12.332462)
		(end 44.611798 -11.68908)
		(width 0.14224)
		(layer "In4.Cu")
		(net "M_H_DQS_DP<10>")
	)
	(segment
		(start 49.516284 -37.313616)
		(end 49.806606 -37.603938)
		(width 0.14224)
		(layer "In4.Cu")
		(net "M_H_DQS_DP<10>")
	)
	(segment
		(start 68.873116 -62.124336)
		(end 68.905882 -62.124336)
		(width 0.0889)
		(layer "In4.Cu")
		(net "M_H_DQS_DP<10>")
	)
	(segment
		(start 43.621198 -14.968474)
		(end 44.605194 -15.95247)
		(width 0.14224)
		(layer "In4.Cu")
		(net "M_H_DQS_DP<10>")
	)
	(segment
		(start 48.72863 -37.9222)
		(end 49.337214 -37.313616)
		(width 0.14224)
		(layer "In4.Cu")
		(net "M_H_DQS_DP<10>")
	)
	(segment
		(start 44.30014 -8.27532)
		(end 44.092114 -8.483346)
		(width 0.14224)
		(layer "In4.Cu")
		(net "M_H_DQS_DP<10>")
	)
	(segment
		(start 49.806606 -37.783008)
		(end 48.938942 -38.650672)
		(width 0.14224)
		(layer "In4.Cu")
		(net "M_H_DQS_DP<10>")
	)
	(segment
		(start 44.611798 -10.63752)
		(end 44.611798 -10.39368)
		(width 0.14224)
		(layer "In4.Cu")
		(net "M_H_DQS_DP<10>")
	)
	(segment
		(start 44.37126 -12.573)
		(end 44.611798 -12.332462)
		(width 0.14224)
		(layer "In4.Cu")
		(net "M_H_DQS_DP<10>")
	)
	(segment
		(start 49.337214 -37.313616)
		(end 49.516284 -37.313616)
		(width 0.14224)
		(layer "In4.Cu")
		(net "M_H_DQS_DP<10>")
	)
	(segment
		(start 48.938942 -38.650672)
		(end 48.938942 -39.09314)
		(width 0.14224)
		(layer "In4.Cu")
		(net "M_H_DQS_DP<10>")
	)
	(segment
		(start 44.365418 -11.4427)
		(end 44.277026 -11.4427)
		(width 0.14224)
		(layer "In4.Cu")
		(net "M_H_DQS_DP<10>")
	)
	(segment
		(start 44.124118 -10.033)
		(end 44.124118 -9.779)
		(width 0.14224)
		(layer "In4.Cu")
		(net "M_H_DQS_DP<10>")
	)
	(segment
		(start 44.431204 -8.27532)
		(end 44.30014 -8.27532)
		(width 0.14224)
		(layer "In4.Cu")
		(net "M_H_DQS_DP<10>")
	)
	(segment
		(start 44.605194 -26.285952)
		(end 45.215048 -26.895806)
		(width 0.14224)
		(layer "In4.Cu")
		(net "M_H_DQS_DP<10>")
	)
	(segment
		(start 47.023528 -37.177726)
		(end 47.768002 -37.9222)
		(width 0.14224)
		(layer "In4.Cu")
		(net "M_H_DQS_DP<10>")
	)
	(segment
		(start 66.734436 -58.151522)
		(end 66.8909 -58.151522)
		(width 0.0889)
		(layer "In4.Cu")
		(net "M_H_DQS_DP<10>")
	)
	(segment
		(start 65.070228 -55.224426)
		(end 65.070228 -56.13527)
		(width 0.14224)
		(layer "In4.Cu")
		(net "M_H_DQS_DP<10>")
	)
	(segment
		(start 65.921636 -56.986678)
		(end 65.937384 -57.002426)
		(width 0.0889)
		(layer "In4.Cu")
		(net "M_H_DQS_DP<10>")
	)
	(segment
		(start 69.731636 -62.619636)
		(end 69.764402 -62.619636)
		(width 0.0889)
		(layer "In4.Cu")
		(net "M_H_DQS_DP<10>")
	)
	(segment
		(start 45.215048 -26.895806)
		(end 45.215048 -31.97098)
		(width 0.14224)
		(layer "In4.Cu")
		(net "M_H_DQS_DP<10>")
	)
	(segment
		(start 44.092114 -12.573)
		(end 44.37126 -12.573)
		(width 0.14224)
		(layer "In4.Cu")
		(net "M_H_DQS_DP<10>")
	)
	(segment
		(start 44.605194 -15.95247)
		(end 44.605194 -26.285952)
		(width 0.14224)
		(layer "In4.Cu")
		(net "M_H_DQS_DP<10>")
	)
	(segment
		(start 65.993264 -57.002426)
		(end 66.372232 -57.381394)
		(width 0.0889)
		(layer "In4.Cu")
		(net "M_H_DQS_DP<10>")
	)
	(segment
		(start 44.611798 -10.39368)
		(end 44.403518 -10.1854)
		(width 0.14224)
		(layer "In4.Cu")
		(net "M_H_DQS_DP<10>")
	)
	(segment
		(start 44.24807 -10.8204)
		(end 44.428918 -10.8204)
		(width 0.14224)
		(layer "In4.Cu")
		(net "M_H_DQS_DP<10>")
	)
	(segment
		(start 44.611798 -8.455914)
		(end 44.431204 -8.27532)
		(width 0.14224)
		(layer "In4.Cu")
		(net "M_H_DQS_DP<10>")
	)
	(segment
		(start 44.120562 -11.286236)
		(end 44.120562 -10.947908)
		(width 0.14224)
		(layer "In4.Cu")
		(net "M_H_DQS_DP<10>")
	)
	(segment
		(start 43.621198 -13.043916)
		(end 43.621198 -14.968474)
		(width 0.14224)
		(layer "In4.Cu")
		(net "M_H_DQS_DP<10>")
	)
	(segment
		(start 44.428918 -10.8204)
		(end 44.611798 -10.63752)
		(width 0.14224)
		(layer "In4.Cu")
		(net "M_H_DQS_DP<10>")
	)
	(segment
		(start 47.768002 -37.9222)
		(end 48.72863 -37.9222)
		(width 0.14224)
		(layer "In4.Cu")
		(net "M_H_DQS_DP<10>")
	)
	(segment
		(start 66.8909 -58.151522)
		(end 68.135246 -59.395868)
		(width 0.0889)
		(layer "In4.Cu")
		(net "M_H_DQS_DP<10>")
	)
	(segment
		(start 68.135246 -59.395868)
		(end 68.382896 -59.834018)
		(width 0.0889)
		(layer "In4.Cu")
		(net "M_H_DQS_DP<10>")
	)
	(segment
		(start 49.806606 -37.603938)
		(end 49.806606 -37.783008)
		(width 0.14224)
		(layer "In4.Cu")
		(net "M_H_DQS_DP<10>")
	)
	(segment
		(start 44.092114 -12.573)
		(end 43.621198 -13.043916)
		(width 0.14224)
		(layer "In4.Cu")
		(net "M_H_DQS_DP<10>")
	)
	(segment
		(start 66.372232 -57.381394)
		(end 66.372232 -57.789318)
		(width 0.0889)
		(layer "In4.Cu")
		(net "M_H_DQS_DP<10>")
	)
	(segment
		(start 44.276518 -10.1854)
		(end 44.124118 -10.033)
		(width 0.14224)
		(layer "In4.Cu")
		(net "M_H_DQS_DP<10>")
	)
	(segment
		(start 44.120562 -10.947908)
		(end 44.24807 -10.8204)
		(width 0.14224)
		(layer "In4.Cu")
		(net "M_H_DQS_DP<10>")
	)
	(arc
		(start 68.382896 -60.247784)
		(mid 68.303765 -60.543186)
		(end 68.382896 -60.838588)
		(width 0.0889)
		(layer "In4.Cu")
		(net "M_H_DQS_DP<10>")
	)
	(arc
		(start 68.382896 -59.834018)
		(mid 68.439994 -60.040919)
		(end 68.382896 -60.247784)
		(width 0.0889)
		(layer "In4.Cu")
		(net "M_H_DQS_DP<10>")
	)
	(arc
		(start 70.958456 -62.724284)
		(mid 71.194944 -62.36239)
		(end 71.470266 -62.029086)
		(width 0.0889)
		(layer "In4.Cu")
		(net "M_H_DQS_DP<10>")
	)
	(arc
		(start 69.241416 -62.324488)
		(mid 69.44842 -62.535352)
		(end 69.731636 -62.619636)
		(width 0.0889)
		(layer "In4.Cu")
		(net "M_H_DQS_DP<10>")
	)
	(arc
		(start 69.997828 -62.702948)
		(mid 70.227984 -62.798374)
		(end 70.458076 -62.893956)
		(width 0.0889)
		(layer "In4.Cu")
		(net "M_H_DQS_DP<10>")
	)
	(arc
		(start 70.458076 -62.893956)
		(mid 70.740256 -62.90344)
		(end 70.958456 -62.724284)
		(width 0.0889)
		(layer "In4.Cu")
		(net "M_H_DQS_DP<10>")
	)
	(arc
		(start 69.764402 -62.619636)
		(mid 69.840969 -62.629267)
		(end 69.914262 -62.653418)
		(width 0.0889)
		(layer "In4.Cu")
		(net "M_H_DQS_DP<10>")
	)
	(arc
		(start 68.382896 -61.238384)
		(mid 68.377642 -61.819892)
		(end 68.873116 -62.124336)
		(width 0.0889)
		(layer "In4.Cu")
		(net "M_H_DQS_DP<10>")
	)
	(arc
		(start 68.382896 -60.838588)
		(mid 68.436395 -61.038486)
		(end 68.382896 -61.238384)
		(width 0.0889)
		(layer "In4.Cu")
		(net "M_H_DQS_DP<10>")
	)
	(arc
		(start 68.905882 -62.124336)
		(mid 69.101221 -62.17818)
		(end 69.241416 -62.324488)
		(width 0.0889)
		(layer "In4.Cu")
		(net "M_H_DQS_DP<10>")
	)
	(arc
		(start 69.914262 -62.653418)
		(mid 69.957553 -62.675639)
		(end 69.997828 -62.702948)
		(width 0.0889)
		(layer "In4.Cu")
		(net "M_H_DQS_DP<10>")
	)
	(segment
		(start 36.721034 -9.10209)
		(end 36.721034 -8.359902)
		(width 0.1651)
		(layer "F.Cu")
		(net "M_H_DQS_DP<0>")
	)
	(segment
		(start 36.499292 -10.422128)
		(end 36.499292 -9.323832)
		(width 0.1651)
		(layer "F.Cu")
		(net "M_H_DQS_DP<0>")
	)
	(segment
		(start 36.721034 -8.359902)
		(end 36.507166 -8.146034)
		(width 0.1651)
		(layer "F.Cu")
		(net "M_H_DQS_DP<0>")
	)
	(segment
		(start 36.499292 -9.323832)
		(end 36.721034 -9.10209)
		(width 0.1651)
		(layer "F.Cu")
		(net "M_H_DQS_DP<0>")
	)
	(segment
		(start 36.499546 -10.422382)
		(end 36.499292 -10.422128)
		(width 0.1651)
		(layer "F.Cu")
		(net "M_H_DQS_DP<0>")
	)
	(segment
		(start 72.900286 -66.48704)
		(end 72.328786 -66.48704)
		(width 0.0889)
		(layer "F.Cu")
		(net "M_H_DQS_DP<0>")
	)
	(segment
		(start 36.507166 -8.146034)
		(end 36.311332 -8.146034)
		(width 0.1651)
		(layer "F.Cu")
		(net "M_H_DQS_DP<0>")
	)
	(segment
		(start 36.311332 -8.146034)
		(end 36.03752 -8.419846)
		(width 0.1651)
		(layer "F.Cu")
		(net "M_H_DQS_DP<0>")
	)
	(via
		(at 36.03752 -8.419846)
		(size 0.508)
		(drill 0.254)
		(layers "F.Cu" "B.Cu")
		(net "M_H_DQS_DP<0>")
	)
	(via
		(at 72.328786 -66.48704)
		(size 0.508)
		(drill 0.254)
		(layers "F.Cu" "B.Cu")
		(net "M_H_DQS_DP<0>")
	)
	(via
		(at 36.03752 -12.627356)
		(size 0.508)
		(drill 0.254)
		(layers "F.Cu" "B.Cu")
		(net "M_H_DQS_DP<0>")
	)
	(segment
		(start 36.318444 -12.90828)
		(end 36.03752 -12.627356)
		(width 0.1651)
		(layer "B.Cu")
		(net "M_H_DQS_DP<0>")
	)
	(segment
		(start 36.499292 -10.9728)
		(end 36.499292 -12.139168)
		(width 0.1651)
		(layer "B.Cu")
		(net "M_H_DQS_DP<0>")
	)
	(segment
		(start 36.539424 -12.90828)
		(end 36.318444 -12.90828)
		(width 0.1651)
		(layer "B.Cu")
		(net "M_H_DQS_DP<0>")
	)
	(segment
		(start 36.499546 -10.623042)
		(end 36.499546 -10.972546)
		(width 0.1651)
		(layer "B.Cu")
		(net "M_H_DQS_DP<0>")
	)
	(segment
		(start 36.499546 -10.972546)
		(end 36.499292 -10.9728)
		(width 0.1651)
		(layer "B.Cu")
		(net "M_H_DQS_DP<0>")
	)
	(segment
		(start 36.679124 -12.319)
		(end 36.679124 -12.76858)
		(width 0.1651)
		(layer "B.Cu")
		(net "M_H_DQS_DP<0>")
	)
	(segment
		(start 36.499292 -12.139168)
		(end 36.679124 -12.319)
		(width 0.1651)
		(layer "B.Cu")
		(net "M_H_DQS_DP<0>")
	)
	(segment
		(start 36.679124 -12.76858)
		(end 36.539424 -12.90828)
		(width 0.1651)
		(layer "B.Cu")
		(net "M_H_DQS_DP<0>")
	)
	(segment
		(start 35.563048 -35.3949)
		(end 35.941254 -35.773106)
		(width 0.14224)
		(layer "In4.Cu")
		(net "M_H_DQS_DP<0>")
	)
	(segment
		(start 36.579048 -12.364974)
		(end 36.316412 -12.62761)
		(width 0.14224)
		(layer "In4.Cu")
		(net "M_H_DQS_DP<0>")
	)
	(segment
		(start 36.396168 -10.8712)
		(end 36.269168 -10.8712)
		(width 0.14224)
		(layer "In4.Cu")
		(net "M_H_DQS_DP<0>")
	)
	(segment
		(start 66.48577 -66.12636)
		(end 66.507868 -66.12636)
		(width 0.0889)
		(layer "In4.Cu")
		(net "M_H_DQS_DP<0>")
	)
	(segment
		(start 36.096448 -11.04392)
		(end 36.096448 -11.30808)
		(width 0.14224)
		(layer "In4.Cu")
		(net "M_H_DQS_DP<0>")
	)
	(segment
		(start 40.533828 -41.53916)
		(end 54.737508 -55.74284)
		(width 0.14224)
		(layer "In4.Cu")
		(net "M_H_DQS_DP<0>")
	)
	(segment
		(start 65.456308 -66.12636)
		(end 66.48577 -66.12636)
		(width 0.14224)
		(layer "In4.Cu")
		(net "M_H_DQS_DP<0>")
	)
	(segment
		(start 36.044124 -9.677654)
		(end 36.044124 -9.981946)
		(width 0.14224)
		(layer "In4.Cu")
		(net "M_H_DQS_DP<0>")
	)
	(segment
		(start 35.60445 -13.060426)
		(end 35.60445 -15.142464)
		(width 0.14224)
		(layer "In4.Cu")
		(net "M_H_DQS_DP<0>")
	)
	(segment
		(start 36.329112 -35.773106)
		(end 36.5506 -35.994594)
		(width 0.14224)
		(layer "In4.Cu")
		(net "M_H_DQS_DP<0>")
	)
	(segment
		(start 40.533828 -39.65956)
		(end 40.533828 -41.53916)
		(width 0.14224)
		(layer "In4.Cu")
		(net "M_H_DQS_DP<0>")
	)
	(segment
		(start 36.329112 -34.157666)
		(end 35.941254 -34.157666)
		(width 0.14224)
		(layer "In4.Cu")
		(net "M_H_DQS_DP<0>")
	)
	(segment
		(start 35.97783 -37.211508)
		(end 36.340288 -37.573712)
		(width 0.14224)
		(layer "In4.Cu")
		(net "M_H_DQS_DP<0>")
	)
	(segment
		(start 72.3138 -66.08699)
		(end 72.343772 -66.08699)
		(width 0.0889)
		(layer "In4.Cu")
		(net "M_H_DQS_DP<0>")
	)
	(segment
		(start 36.269168 -10.8712)
		(end 36.096448 -11.04392)
		(width 0.14224)
		(layer "In4.Cu")
		(net "M_H_DQS_DP<0>")
	)
	(segment
		(start 36.03752 -12.627356)
		(end 35.60445 -13.060426)
		(width 0.14224)
		(layer "In4.Cu")
		(net "M_H_DQS_DP<0>")
	)
	(segment
		(start 39.018718 -38.14445)
		(end 40.533828 -39.65956)
		(width 0.14224)
		(layer "In4.Cu")
		(net "M_H_DQS_DP<0>")
	)
	(segment
		(start 36.196778 -10.1346)
		(end 36.37407 -10.1346)
		(width 0.14224)
		(layer "In4.Cu")
		(net "M_H_DQS_DP<0>")
	)
	(segment
		(start 36.096448 -11.30808)
		(end 36.269168 -11.4808)
		(width 0.14224)
		(layer "In4.Cu")
		(net "M_H_DQS_DP<0>")
	)
	(segment
		(start 36.579048 -9.345422)
		(end 36.39947 -9.525)
		(width 0.14224)
		(layer "In4.Cu")
		(net "M_H_DQS_DP<0>")
	)
	(segment
		(start 67.832986 -66.582036)
		(end 68.047362 -66.582036)
		(width 0.0889)
		(layer "In4.Cu")
		(net "M_H_DQS_DP<0>")
	)
	(segment
		(start 54.737508 -55.74284)
		(end 55.410608 -55.74284)
		(width 0.14224)
		(layer "In4.Cu")
		(net "M_H_DQS_DP<0>")
	)
	(segment
		(start 36.5506 -29.33954)
		(end 36.5506 -33.936178)
		(width 0.14224)
		(layer "In4.Cu")
		(net "M_H_DQS_DP<0>")
	)
	(segment
		(start 36.37407 -10.1346)
		(end 36.579048 -10.339578)
		(width 0.14224)
		(layer "In4.Cu")
		(net "M_H_DQS_DP<0>")
	)
	(segment
		(start 36.5506 -35.994594)
		(end 36.5506 -36.235894)
		(width 0.14224)
		(layer "In4.Cu")
		(net "M_H_DQS_DP<0>")
	)
	(segment
		(start 66.507868 -66.12636)
		(end 66.547238 -66.08699)
		(width 0.0889)
		(layer "In4.Cu")
		(net "M_H_DQS_DP<0>")
	)
	(segment
		(start 35.941254 -35.773106)
		(end 36.329112 -35.773106)
		(width 0.14224)
		(layer "In4.Cu")
		(net "M_H_DQS_DP<0>")
	)
	(segment
		(start 36.977828 -25.240488)
		(end 36.977828 -25.89784)
		(width 0.14224)
		(layer "In4.Cu")
		(net "M_H_DQS_DP<0>")
	)
	(segment
		(start 36.269168 -11.4808)
		(end 36.399724 -11.4808)
		(width 0.14224)
		(layer "In4.Cu")
		(net "M_H_DQS_DP<0>")
	)
	(segment
		(start 61.730128 -62.40018)
		(end 65.456308 -66.12636)
		(width 0.14224)
		(layer "In4.Cu")
		(net "M_H_DQS_DP<0>")
	)
	(segment
		(start 36.579048 -10.68832)
		(end 36.396168 -10.8712)
		(width 0.14224)
		(layer "In4.Cu")
		(net "M_H_DQS_DP<0>")
	)
	(segment
		(start 36.5506 -26.325068)
		(end 36.5506 -27.69616)
		(width 0.14224)
		(layer "In4.Cu")
		(net "M_H_DQS_DP<0>")
	)
	(segment
		(start 36.901628 -28.988512)
		(end 36.5506 -29.33954)
		(width 0.14224)
		(layer "In4.Cu")
		(net "M_H_DQS_DP<0>")
	)
	(segment
		(start 36.977828 -25.89784)
		(end 36.5506 -26.325068)
		(width 0.14224)
		(layer "In4.Cu")
		(net "M_H_DQS_DP<0>")
	)
	(segment
		(start 55.410608 -55.74284)
		(end 61.730128 -62.06236)
		(width 0.14224)
		(layer "In4.Cu")
		(net "M_H_DQS_DP<0>")
	)
	(segment
		(start 72.642984 -66.239136)
		(end 72.621902 -66.317876)
		(width 0.0889)
		(layer "In4.Cu")
		(net "M_H_DQS_DP<0>")
	)
	(segment
		(start 36.5506 -33.936178)
		(end 36.329112 -34.157666)
		(width 0.14224)
		(layer "In4.Cu")
		(net "M_H_DQS_DP<0>")
	)
	(segment
		(start 36.579048 -11.660124)
		(end 36.579048 -12.364974)
		(width 0.14224)
		(layer "In4.Cu")
		(net "M_H_DQS_DP<0>")
	)
	(segment
		(start 36.579048 -10.339578)
		(end 36.579048 -10.68832)
		(width 0.14224)
		(layer "In4.Cu")
		(net "M_H_DQS_DP<0>")
	)
	(segment
		(start 36.5506 -24.81326)
		(end 36.977828 -25.240488)
		(width 0.14224)
		(layer "In4.Cu")
		(net "M_H_DQS_DP<0>")
	)
	(segment
		(start 36.03752 -12.62761)
		(end 36.03752 -12.627356)
		(width 0.14224)
		(layer "In4.Cu")
		(net "M_H_DQS_DP<0>")
	)
	(segment
		(start 70.59676 -67.07759)
		(end 70.625462 -67.07759)
		(width 0.0889)
		(layer "In4.Cu")
		(net "M_H_DQS_DP<0>")
	)
	(segment
		(start 36.5506 -27.69616)
		(end 36.901628 -28.047188)
		(width 0.14224)
		(layer "In4.Cu")
		(net "M_H_DQS_DP<0>")
	)
	(segment
		(start 36.901628 -28.047188)
		(end 36.901628 -28.988512)
		(width 0.14224)
		(layer "In4.Cu")
		(net "M_H_DQS_DP<0>")
	)
	(segment
		(start 35.60445 -15.142464)
		(end 36.5506 -16.088614)
		(width 0.14224)
		(layer "In4.Cu")
		(net "M_H_DQS_DP<0>")
	)
	(segment
		(start 36.579048 -8.679688)
		(end 36.579048 -9.345422)
		(width 0.14224)
		(layer "In4.Cu")
		(net "M_H_DQS_DP<0>")
	)
	(segment
		(start 36.196778 -9.525)
		(end 36.044124 -9.677654)
		(width 0.14224)
		(layer "In4.Cu")
		(net "M_H_DQS_DP<0>")
	)
	(segment
		(start 69.731636 -67.572636)
		(end 69.774816 -67.572636)
		(width 0.0889)
		(layer "In4.Cu")
		(net "M_H_DQS_DP<0>")
	)
	(segment
		(start 36.316412 -12.62761)
		(end 36.03752 -12.62761)
		(width 0.14224)
		(layer "In4.Cu")
		(net "M_H_DQS_DP<0>")
	)
	(segment
		(start 36.399724 -11.4808)
		(end 36.579048 -11.660124)
		(width 0.14224)
		(layer "In4.Cu")
		(net "M_H_DQS_DP<0>")
	)
	(segment
		(start 36.5506 -16.088614)
		(end 36.5506 -24.81326)
		(width 0.14224)
		(layer "In4.Cu")
		(net "M_H_DQS_DP<0>")
	)
	(segment
		(start 36.319206 -8.419846)
		(end 36.579048 -8.679688)
		(width 0.14224)
		(layer "In4.Cu")
		(net "M_H_DQS_DP<0>")
	)
	(segment
		(start 35.563048 -34.535872)
		(end 35.563048 -35.3949)
		(width 0.14224)
		(layer "In4.Cu")
		(net "M_H_DQS_DP<0>")
	)
	(segment
		(start 68.876926 -67.07759)
		(end 68.909692 -67.07759)
		(width 0.0889)
		(layer "In4.Cu")
		(net "M_H_DQS_DP<0>")
	)
	(segment
		(start 35.97783 -36.808664)
		(end 35.97783 -37.211508)
		(width 0.14224)
		(layer "In4.Cu")
		(net "M_H_DQS_DP<0>")
	)
	(segment
		(start 36.5506 -36.235894)
		(end 35.97783 -36.808664)
		(width 0.14224)
		(layer "In4.Cu")
		(net "M_H_DQS_DP<0>")
	)
	(segment
		(start 35.941254 -34.157666)
		(end 35.563048 -34.535872)
		(width 0.14224)
		(layer "In4.Cu")
		(net "M_H_DQS_DP<0>")
	)
	(segment
		(start 36.044124 -9.981946)
		(end 36.196778 -10.1346)
		(width 0.14224)
		(layer "In4.Cu")
		(net "M_H_DQS_DP<0>")
	)
	(segment
		(start 36.910772 -38.14445)
		(end 39.018718 -38.14445)
		(width 0.14224)
		(layer "In4.Cu")
		(net "M_H_DQS_DP<0>")
	)
	(segment
		(start 71.45909 -66.582036)
		(end 71.491856 -66.582036)
		(width 0.0889)
		(layer "In4.Cu")
		(net "M_H_DQS_DP<0>")
	)
	(segment
		(start 36.39947 -9.525)
		(end 36.196778 -9.525)
		(width 0.14224)
		(layer "In4.Cu")
		(net "M_H_DQS_DP<0>")
	)
	(segment
		(start 36.03752 -8.419846)
		(end 36.319206 -8.419846)
		(width 0.14224)
		(layer "In4.Cu")
		(net "M_H_DQS_DP<0>")
	)
	(segment
		(start 36.340288 -37.573712)
		(end 36.910772 -38.14445)
		(width 0.14224)
		(layer "In4.Cu")
		(net "M_H_DQS_DP<0>")
	)
	(segment
		(start 61.730128 -62.06236)
		(end 61.730128 -62.40018)
		(width 0.14224)
		(layer "In4.Cu")
		(net "M_H_DQS_DP<0>")
	)
	(segment
		(start 66.547238 -66.08699)
		(end 67.268344 -66.08699)
		(width 0.0889)
		(layer "In4.Cu")
		(net "M_H_DQS_DP<0>")
	)
	(segment
		(start 72.621902 -66.317876)
		(end 72.328786 -66.48704)
		(width 0.0889)
		(layer "In4.Cu")
		(net "M_H_DQS_DP<0>")
	)
	(arc
		(start 69.241416 -67.277488)
		(mid 69.44842 -67.488352)
		(end 69.731636 -67.572636)
		(width 0.0889)
		(layer "In4.Cu")
		(net "M_H_DQS_DP<0>")
	)
	(arc
		(start 69.774816 -67.572636)
		(mid 70.058033 -67.488355)
		(end 70.265036 -67.277488)
		(width 0.0889)
		(layer "In4.Cu")
		(net "M_H_DQS_DP<0>")
	)
	(arc
		(start 68.909692 -67.07759)
		(mid 69.101334 -67.134756)
		(end 69.241416 -67.277488)
		(width 0.0889)
		(layer "In4.Cu")
		(net "M_H_DQS_DP<0>")
	)
	(arc
		(start 67.268344 -66.08699)
		(mid 67.393545 -66.166761)
		(end 67.484498 -66.284094)
		(width 0.0889)
		(layer "In4.Cu")
		(net "M_H_DQS_DP<0>")
	)
	(arc
		(start 72.343772 -66.08699)
		(mid 72.510066 -66.130224)
		(end 72.642984 -66.239136)
		(width 0.0889)
		(layer "In4.Cu")
		(net "M_H_DQS_DP<0>")
	)
	(arc
		(start 67.484498 -66.284094)
		(mid 67.630423 -66.466181)
		(end 67.832986 -66.582036)
		(width 0.0889)
		(layer "In4.Cu")
		(net "M_H_DQS_DP<0>")
	)
	(arc
		(start 71.123556 -66.782188)
		(mid 71.265239 -66.638384)
		(end 71.45909 -66.582036)
		(width 0.0889)
		(layer "In4.Cu")
		(net "M_H_DQS_DP<0>")
	)
	(arc
		(start 70.625462 -67.07759)
		(mid 70.913149 -66.995069)
		(end 71.123556 -66.782188)
		(width 0.0889)
		(layer "In4.Cu")
		(net "M_H_DQS_DP<0>")
	)
	(arc
		(start 68.382896 -66.782188)
		(mid 68.591504 -66.99412)
		(end 68.876926 -67.07759)
		(width 0.0889)
		(layer "In4.Cu")
		(net "M_H_DQS_DP<0>")
	)
	(arc
		(start 70.265036 -67.277488)
		(mid 70.405115 -67.134752)
		(end 70.59676 -67.07759)
		(width 0.0889)
		(layer "In4.Cu")
		(net "M_H_DQS_DP<0>")
	)
	(arc
		(start 71.491856 -66.582036)
		(mid 71.775073 -66.497755)
		(end 71.982076 -66.286888)
		(width 0.0889)
		(layer "In4.Cu")
		(net "M_H_DQS_DP<0>")
	)
	(arc
		(start 71.982076 -66.286888)
		(mid 72.122155 -66.144152)
		(end 72.3138 -66.08699)
		(width 0.0889)
		(layer "In4.Cu")
		(net "M_H_DQS_DP<0>")
	)
	(arc
		(start 68.047362 -66.582036)
		(mid 68.241212 -66.638386)
		(end 68.382896 -66.782188)
		(width 0.0889)
		(layer "In4.Cu")
		(net "M_H_DQS_DP<0>")
	)
	(segment
		(start 35.649408 -5.822442)
		(end 35.649408 -6.66496)
		(width 0.1651)
		(layer "F.Cu")
		(net "M_H_DQS_DN<9>")
	)
	(segment
		(start 35.649408 -6.66496)
		(end 35.231324 -7.083044)
		(width 0.1651)
		(layer "F.Cu")
		(net "M_H_DQS_DN<9>")
	)
	(segment
		(start 35.417252 -7.747762)
		(end 35.165284 -7.99973)
		(width 0.1651)
		(layer "F.Cu")
		(net "M_H_DQS_DN<9>")
	)
	(segment
		(start 71.183246 -67.47764)
		(end 70.611746 -67.47764)
		(width 0.0889)
		(layer "F.Cu")
		(net "M_H_DQS_DN<9>")
	)
	(segment
		(start 35.417252 -7.501128)
		(end 35.417252 -7.747762)
		(width 0.1651)
		(layer "F.Cu")
		(net "M_H_DQS_DN<9>")
	)
	(segment
		(start 35.231324 -7.3152)
		(end 35.417252 -7.501128)
		(width 0.1651)
		(layer "F.Cu")
		(net "M_H_DQS_DN<9>")
	)
	(segment
		(start 34.937954 -7.99973)
		(end 34.748724 -7.8105)
		(width 0.1651)
		(layer "F.Cu")
		(net "M_H_DQS_DN<9>")
	)
	(segment
		(start 35.231324 -7.083044)
		(end 35.231324 -7.3152)
		(width 0.1651)
		(layer "F.Cu")
		(net "M_H_DQS_DN<9>")
	)
	(segment
		(start 35.165284 -7.99973)
		(end 34.937954 -7.99973)
		(width 0.1651)
		(layer "F.Cu")
		(net "M_H_DQS_DN<9>")
	)
	(via
		(at 34.748724 -7.8105)
		(size 0.508)
		(drill 0.254)
		(layers "F.Cu" "B.Cu")
		(net "M_H_DQS_DN<9>")
	)
	(via
		(at 34.74212 -13.2334)
		(size 0.508)
		(drill 0.254)
		(layers "F.Cu" "B.Cu")
		(net "M_H_DQS_DN<9>")
	)
	(via
		(at 70.611746 -67.47764)
		(size 0.508)
		(drill 0.254)
		(layers "F.Cu" "B.Cu")
		(net "M_H_DQS_DN<9>")
	)
	(segment
		(start 35.205924 -13.7668)
		(end 35.383724 -13.589)
		(width 0.1651)
		(layer "B.Cu")
		(net "M_H_DQS_DN<9>")
	)
	(segment
		(start 35.383724 -13.589)
		(end 35.383724 -13.2588)
		(width 0.1651)
		(layer "B.Cu")
		(net "M_H_DQS_DN<9>")
	)
	(segment
		(start 34.936684 -13.038836)
		(end 34.74212 -13.2334)
		(width 0.1651)
		(layer "B.Cu")
		(net "M_H_DQS_DN<9>")
	)
	(segment
		(start 35.649408 -15.222982)
		(end 35.649408 -14.566138)
		(width 0.1651)
		(layer "B.Cu")
		(net "M_H_DQS_DN<9>")
	)
	(segment
		(start 35.649408 -14.566138)
		(end 35.205924 -14.122654)
		(width 0.1651)
		(layer "B.Cu")
		(net "M_H_DQS_DN<9>")
	)
	(segment
		(start 35.383724 -13.2588)
		(end 35.16376 -13.038836)
		(width 0.1651)
		(layer "B.Cu")
		(net "M_H_DQS_DN<9>")
	)
	(segment
		(start 35.16376 -13.038836)
		(end 34.936684 -13.038836)
		(width 0.1651)
		(layer "B.Cu")
		(net "M_H_DQS_DN<9>")
	)
	(segment
		(start 35.205924 -14.122654)
		(end 35.205924 -13.7668)
		(width 0.1651)
		(layer "B.Cu")
		(net "M_H_DQS_DN<9>")
	)
	(segment
		(start 54.849014 -56.4515)
		(end 55.550816 -57.153302)
		(width 0.14224)
		(layer "In4.Cu")
		(net "M_H_DQS_DN<9>")
	)
	(segment
		(start 60.07481 -61.677296)
		(end 60.236354 -61.677296)
		(width 0.14224)
		(layer "In4.Cu")
		(net "M_H_DQS_DN<9>")
	)
	(segment
		(start 63.710566 -65.151508)
		(end 63.710566 -65.313052)
		(width 0.14224)
		(layer "In4.Cu")
		(net "M_H_DQS_DN<9>")
	)
	(segment
		(start 59.186318 -60.788804)
		(end 59.428634 -61.03112)
		(width 0.14224)
		(layer "In4.Cu")
		(net "M_H_DQS_DN<9>")
	)
	(segment
		(start 65.003172 -66.605658)
		(end 65.245234 -66.84772)
		(width 0.14224)
		(layer "In4.Cu")
		(net "M_H_DQS_DN<9>")
	)
	(segment
		(start 35.933888 -37.980112)
		(end 36.929822 -38.9763)
		(width 0.14224)
		(layer "In4.Cu")
		(net "M_H_DQS_DN<9>")
	)
	(segment
		(start 38.885622 -38.9763)
		(end 39.704772 -39.79545)
		(width 0.14224)
		(layer "In4.Cu")
		(net "M_H_DQS_DN<9>")
	)
	(segment
		(start 63.952628 -65.555114)
		(end 64.114172 -65.555114)
		(width 0.14224)
		(layer "In4.Cu")
		(net "M_H_DQS_DN<9>")
	)
	(segment
		(start 59.832748 -61.27369)
		(end 59.832748 -61.435234)
		(width 0.14224)
		(layer "In4.Cu")
		(net "M_H_DQS_DN<9>")
	)
	(segment
		(start 64.114172 -65.555114)
		(end 64.356742 -65.797684)
		(width 0.14224)
		(layer "In4.Cu")
		(net "M_H_DQS_DN<9>")
	)
	(segment
		(start 68.88353 -67.87769)
		(end 68.916296 -67.87769)
		(width 0.0889)
		(layer "In4.Cu")
		(net "M_H_DQS_DN<9>")
	)
	(segment
		(start 62.41796 -63.858902)
		(end 62.41796 -64.020446)
		(width 0.14224)
		(layer "In4.Cu")
		(net "M_H_DQS_DN<9>")
	)
	(segment
		(start 64.356742 -65.959228)
		(end 64.599058 -66.201544)
		(width 0.14224)
		(layer "In4.Cu")
		(net "M_H_DQS_DN<9>")
	)
	(segment
		(start 55.71236 -57.153302)
		(end 55.95493 -57.395872)
		(width 0.14224)
		(layer "In4.Cu")
		(net "M_H_DQS_DN<9>")
	)
	(segment
		(start 56.601106 -58.203592)
		(end 56.843422 -58.445908)
		(width 0.14224)
		(layer "In4.Cu")
		(net "M_H_DQS_DN<9>")
	)
	(segment
		(start 61.125354 -62.566296)
		(end 61.125354 -62.72784)
		(width 0.14224)
		(layer "In4.Cu")
		(net "M_H_DQS_DN<9>")
	)
	(segment
		(start 56.196992 -57.799478)
		(end 56.358536 -57.799478)
		(width 0.14224)
		(layer "In4.Cu")
		(net "M_H_DQS_DN<9>")
	)
	(segment
		(start 35.832288 -29.687774)
		(end 35.832288 -30.419802)
		(width 0.14224)
		(layer "In4.Cu")
		(net "M_H_DQS_DN<9>")
	)
	(segment
		(start 63.064136 -64.666622)
		(end 63.306452 -64.908938)
		(width 0.14224)
		(layer "In4.Cu")
		(net "M_H_DQS_DN<9>")
	)
	(segment
		(start 35.52444 -21.03628)
		(end 35.52444 -23.74392)
		(width 0.14224)
		(layer "In4.Cu")
		(net "M_H_DQS_DN<9>")
	)
	(segment
		(start 58.540142 -60.142628)
		(end 58.782204 -60.38469)
		(width 0.14224)
		(layer "In4.Cu")
		(net "M_H_DQS_DN<9>")
	)
	(segment
		(start 35.193224 -14.1859)
		(end 34.977324 -14.4018)
		(width 0.14224)
		(layer "In4.Cu")
		(net "M_H_DQS_DN<9>")
	)
	(segment
		(start 35.68192 -20.1168)
		(end 35.52444 -20.27428)
		(width 0.14224)
		(layer "In4.Cu")
		(net "M_H_DQS_DN<9>")
	)
	(segment
		(start 57.247536 -58.850022)
		(end 57.489598 -59.092084)
		(width 0.14224)
		(layer "In4.Cu")
		(net "M_H_DQS_DN<9>")
	)
	(segment
		(start 57.489598 -59.092084)
		(end 57.651142 -59.092084)
		(width 0.14224)
		(layer "In4.Cu")
		(net "M_H_DQS_DN<9>")
	)
	(segment
		(start 65.693036 -66.88709)
		(end 67.157854 -66.88709)
		(width 0.0889)
		(layer "In4.Cu")
		(net "M_H_DQS_DN<9>")
	)
	(segment
		(start 67.869308 -67.382136)
		(end 68.053966 -67.382136)
		(width 0.0889)
		(layer "In4.Cu")
		(net "M_H_DQS_DN<9>")
	)
	(segment
		(start 55.550816 -57.153302)
		(end 55.71236 -57.153302)
		(width 0.14224)
		(layer "In4.Cu")
		(net "M_H_DQS_DN<9>")
	)
	(segment
		(start 35.52444 -16.093948)
		(end 35.52444 -19.70532)
		(width 0.14224)
		(layer "In4.Cu")
		(net "M_H_DQS_DN<9>")
	)
	(segment
		(start 35.088576 -30.874208)
		(end 34.867088 -31.095696)
		(width 0.14224)
		(layer "In4.Cu")
		(net "M_H_DQS_DN<9>")
	)
	(segment
		(start 56.358536 -57.799478)
		(end 56.601106 -58.042048)
		(width 0.14224)
		(layer "In4.Cu")
		(net "M_H_DQS_DN<9>")
	)
	(segment
		(start 34.723324 -14.4018)
		(end 34.540444 -14.58468)
		(width 0.14224)
		(layer "In4.Cu")
		(net "M_H_DQS_DN<9>")
	)
	(segment
		(start 34.74212 -13.2334)
		(end 35.193224 -13.684504)
		(width 0.14224)
		(layer "In4.Cu")
		(net "M_H_DQS_DN<9>")
	)
	(segment
		(start 60.478924 -61.919866)
		(end 60.478924 -62.08141)
		(width 0.14224)
		(layer "In4.Cu")
		(net "M_H_DQS_DN<9>")
	)
	(segment
		(start 64.356742 -65.797684)
		(end 64.356742 -65.959228)
		(width 0.14224)
		(layer "In4.Cu")
		(net "M_H_DQS_DN<9>")
	)
	(segment
		(start 70.198234 -68.019422)
		(end 70.329552 -67.834256)
		(width 0.0889)
		(layer "In4.Cu")
		(net "M_H_DQS_DN<9>")
	)
	(segment
		(start 35.52444 -24.31288)
		(end 35.52444 -27.803602)
		(width 0.14224)
		(layer "In4.Cu")
		(net "M_H_DQS_DN<9>")
	)
	(segment
		(start 35.52444 -23.74392)
		(end 35.68192 -23.9014)
		(width 0.14224)
		(layer "In4.Cu")
		(net "M_H_DQS_DN<9>")
	)
	(segment
		(start 35.68192 -19.8628)
		(end 35.68192 -20.1168)
		(width 0.14224)
		(layer "In4.Cu")
		(net "M_H_DQS_DN<9>")
	)
	(segment
		(start 65.245234 -66.84772)
		(end 65.631568 -66.84772)
		(width 0.14224)
		(layer "In4.Cu")
		(net "M_H_DQS_DN<9>")
	)
	(segment
		(start 55.95493 -57.395872)
		(end 55.95493 -57.557416)
		(width 0.14224)
		(layer "In4.Cu")
		(net "M_H_DQS_DN<9>")
	)
	(segment
		(start 36.929822 -38.9763)
		(end 38.885622 -38.9763)
		(width 0.14224)
		(layer "In4.Cu")
		(net "M_H_DQS_DN<9>")
	)
	(segment
		(start 35.531044 -12.444476)
		(end 34.74212 -13.2334)
		(width 0.14224)
		(layer "In4.Cu")
		(net "M_H_DQS_DN<9>")
	)
	(segment
		(start 63.467996 -64.908938)
		(end 63.710566 -65.151508)
		(width 0.14224)
		(layer "In4.Cu")
		(net "M_H_DQS_DN<9>")
	)
	(segment
		(start 56.601106 -58.042048)
		(end 56.601106 -58.203592)
		(width 0.14224)
		(layer "In4.Cu")
		(net "M_H_DQS_DN<9>")
	)
	(segment
		(start 35.68192 -20.6248)
		(end 35.68192 -20.8788)
		(width 0.14224)
		(layer "In4.Cu")
		(net "M_H_DQS_DN<9>")
	)
	(segment
		(start 34.867088 -31.095696)
		(end 34.867088 -31.72968)
		(width 0.14224)
		(layer "In4.Cu")
		(net "M_H_DQS_DN<9>")
	)
	(segment
		(start 54.405022 -56.4515)
		(end 54.849014 -56.4515)
		(width 0.14224)
		(layer "In4.Cu")
		(net "M_H_DQS_DN<9>")
	)
	(segment
		(start 59.186318 -60.62726)
		(end 59.186318 -60.788804)
		(width 0.14224)
		(layer "In4.Cu")
		(net "M_H_DQS_DN<9>")
	)
	(segment
		(start 35.377882 -31.951168)
		(end 35.756088 -32.329374)
		(width 0.14224)
		(layer "In4.Cu")
		(net "M_H_DQS_DN<9>")
	)
	(segment
		(start 35.68192 -24.1554)
		(end 35.52444 -24.31288)
		(width 0.14224)
		(layer "In4.Cu")
		(net "M_H_DQS_DN<9>")
	)
	(segment
		(start 70.329552 -67.834256)
		(end 70.611746 -67.47764)
		(width 0.0889)
		(layer "In4.Cu")
		(net "M_H_DQS_DN<9>")
	)
	(segment
		(start 64.760602 -66.201544)
		(end 65.003172 -66.444114)
		(width 0.14224)
		(layer "In4.Cu")
		(net "M_H_DQS_DN<9>")
	)
	(segment
		(start 61.77153 -63.212472)
		(end 61.77153 -63.374016)
		(width 0.14224)
		(layer "In4.Cu")
		(net "M_H_DQS_DN<9>")
	)
	(segment
		(start 35.377882 -30.874208)
		(end 35.088576 -30.874208)
		(width 0.14224)
		(layer "In4.Cu")
		(net "M_H_DQS_DN<9>")
	)
	(segment
		(start 35.756088 -33.188402)
		(end 34.867088 -34.077402)
		(width 0.14224)
		(layer "In4.Cu")
		(net "M_H_DQS_DN<9>")
	)
	(segment
		(start 34.748724 -7.8105)
		(end 34.944304 -8.00608)
		(width 0.14224)
		(layer "In4.Cu")
		(net "M_H_DQS_DN<9>")
	)
	(segment
		(start 58.136028 -59.738514)
		(end 58.297572 -59.738514)
		(width 0.14224)
		(layer "In4.Cu")
		(net "M_H_DQS_DN<9>")
	)
	(segment
		(start 58.943748 -60.38469)
		(end 59.186318 -60.62726)
		(width 0.14224)
		(layer "In4.Cu")
		(net "M_H_DQS_DN<9>")
	)
	(segment
		(start 34.540444 -15.109952)
		(end 35.52444 -16.093948)
		(width 0.14224)
		(layer "In4.Cu")
		(net "M_H_DQS_DN<9>")
	)
	(segment
		(start 60.236354 -61.677296)
		(end 60.478924 -61.919866)
		(width 0.14224)
		(layer "In4.Cu")
		(net "M_H_DQS_DN<9>")
	)
	(segment
		(start 57.651142 -59.092084)
		(end 57.893712 -59.334654)
		(width 0.14224)
		(layer "In4.Cu")
		(net "M_H_DQS_DN<9>")
	)
	(segment
		(start 35.531044 -8.343392)
		(end 35.531044 -12.444476)
		(width 0.14224)
		(layer "In4.Cu")
		(net "M_H_DQS_DN<9>")
	)
	(segment
		(start 57.893712 -59.334654)
		(end 57.893712 -59.496198)
		(width 0.14224)
		(layer "In4.Cu")
		(net "M_H_DQS_DN<9>")
	)
	(segment
		(start 63.710566 -65.313052)
		(end 63.952628 -65.555114)
		(width 0.14224)
		(layer "In4.Cu")
		(net "M_H_DQS_DN<9>")
	)
	(segment
		(start 58.540142 -59.981084)
		(end 58.540142 -60.142628)
		(width 0.14224)
		(layer "In4.Cu")
		(net "M_H_DQS_DN<9>")
	)
	(segment
		(start 65.631568 -66.84772)
		(end 65.653666 -66.84772)
		(width 0.0889)
		(layer "In4.Cu")
		(net "M_H_DQS_DN<9>")
	)
	(segment
		(start 61.125354 -62.72784)
		(end 61.367416 -62.969902)
		(width 0.14224)
		(layer "In4.Cu")
		(net "M_H_DQS_DN<9>")
	)
	(segment
		(start 62.17539 -63.616332)
		(end 62.41796 -63.858902)
		(width 0.14224)
		(layer "In4.Cu")
		(net "M_H_DQS_DN<9>")
	)
	(segment
		(start 59.590178 -61.03112)
		(end 59.832748 -61.27369)
		(width 0.14224)
		(layer "In4.Cu")
		(net "M_H_DQS_DN<9>")
	)
	(segment
		(start 61.52896 -62.969902)
		(end 61.77153 -63.212472)
		(width 0.14224)
		(layer "In4.Cu")
		(net "M_H_DQS_DN<9>")
	)
	(segment
		(start 35.68192 -20.8788)
		(end 35.52444 -21.03628)
		(width 0.14224)
		(layer "In4.Cu")
		(net "M_H_DQS_DN<9>")
	)
	(segment
		(start 39.704772 -39.79545)
		(end 39.704772 -41.75125)
		(width 0.14224)
		(layer "In4.Cu")
		(net "M_H_DQS_DN<9>")
	)
	(segment
		(start 34.944304 -8.00608)
		(end 35.193732 -8.00608)
		(width 0.14224)
		(layer "In4.Cu")
		(net "M_H_DQS_DN<9>")
	)
	(segment
		(start 64.599058 -66.201544)
		(end 64.760602 -66.201544)
		(width 0.14224)
		(layer "In4.Cu")
		(net "M_H_DQS_DN<9>")
	)
	(segment
		(start 35.52444 -19.70532)
		(end 35.68192 -19.8628)
		(width 0.14224)
		(layer "In4.Cu")
		(net "M_H_DQS_DN<9>")
	)
	(segment
		(start 34.968688 -28.824174)
		(end 35.832288 -29.687774)
		(width 0.14224)
		(layer "In4.Cu")
		(net "M_H_DQS_DN<9>")
	)
	(segment
		(start 35.088576 -31.951168)
		(end 35.377882 -31.951168)
		(width 0.14224)
		(layer "In4.Cu")
		(net "M_H_DQS_DN<9>")
	)
	(segment
		(start 58.297572 -59.738514)
		(end 58.540142 -59.981084)
		(width 0.14224)
		(layer "In4.Cu")
		(net "M_H_DQS_DN<9>")
	)
	(segment
		(start 35.52444 -27.803602)
		(end 34.968688 -28.359354)
		(width 0.14224)
		(layer "In4.Cu")
		(net "M_H_DQS_DN<9>")
	)
	(segment
		(start 60.478924 -62.08141)
		(end 60.72124 -62.323726)
		(width 0.14224)
		(layer "In4.Cu")
		(net "M_H_DQS_DN<9>")
	)
	(segment
		(start 56.843422 -58.445908)
		(end 57.004966 -58.445908)
		(width 0.14224)
		(layer "In4.Cu")
		(net "M_H_DQS_DN<9>")
	)
	(segment
		(start 35.68192 -23.9014)
		(end 35.68192 -24.1554)
		(width 0.14224)
		(layer "In4.Cu")
		(net "M_H_DQS_DN<9>")
	)
	(segment
		(start 39.704772 -41.75125)
		(end 54.405022 -56.4515)
		(width 0.14224)
		(layer "In4.Cu")
		(net "M_H_DQS_DN<9>")
	)
	(segment
		(start 61.367416 -62.969902)
		(end 61.52896 -62.969902)
		(width 0.14224)
		(layer "In4.Cu")
		(net "M_H_DQS_DN<9>")
	)
	(segment
		(start 57.247536 -58.688478)
		(end 57.247536 -58.850022)
		(width 0.14224)
		(layer "In4.Cu")
		(net "M_H_DQS_DN<9>")
	)
	(segment
		(start 59.832748 -61.435234)
		(end 60.07481 -61.677296)
		(width 0.14224)
		(layer "In4.Cu")
		(net "M_H_DQS_DN<9>")
	)
	(segment
		(start 34.968688 -28.359354)
		(end 34.968688 -28.824174)
		(width 0.14224)
		(layer "In4.Cu")
		(net "M_H_DQS_DN<9>")
	)
	(segment
		(start 62.821566 -64.262508)
		(end 63.064136 -64.505078)
		(width 0.14224)
		(layer "In4.Cu")
		(net "M_H_DQS_DN<9>")
	)
	(segment
		(start 35.52444 -20.27428)
		(end 35.52444 -20.46732)
		(width 0.14224)
		(layer "In4.Cu")
		(net "M_H_DQS_DN<9>")
	)
	(segment
		(start 65.653666 -66.84772)
		(end 65.693036 -66.88709)
		(width 0.0889)
		(layer "In4.Cu")
		(net "M_H_DQS_DN<9>")
	)
	(segment
		(start 34.867088 -34.077402)
		(end 34.867088 -36.913566)
		(width 0.14224)
		(layer "In4.Cu")
		(net "M_H_DQS_DN<9>")
	)
	(segment
		(start 35.193732 -8.00608)
		(end 35.531044 -8.343392)
		(width 0.14224)
		(layer "In4.Cu")
		(net "M_H_DQS_DN<9>")
	)
	(segment
		(start 63.306452 -64.908938)
		(end 63.467996 -64.908938)
		(width 0.14224)
		(layer "In4.Cu")
		(net "M_H_DQS_DN<9>")
	)
	(segment
		(start 57.004966 -58.445908)
		(end 57.247536 -58.688478)
		(width 0.14224)
		(layer "In4.Cu")
		(net "M_H_DQS_DN<9>")
	)
	(segment
		(start 34.867088 -36.913566)
		(end 35.933888 -37.980112)
		(width 0.14224)
		(layer "In4.Cu")
		(net "M_H_DQS_DN<9>")
	)
	(segment
		(start 58.782204 -60.38469)
		(end 58.943748 -60.38469)
		(width 0.14224)
		(layer "In4.Cu")
		(net "M_H_DQS_DN<9>")
	)
	(segment
		(start 69.73824 -68.372736)
		(end 69.768212 -68.372736)
		(width 0.0889)
		(layer "In4.Cu")
		(net "M_H_DQS_DN<9>")
	)
	(segment
		(start 35.193224 -13.684504)
		(end 35.193224 -14.1859)
		(width 0.14224)
		(layer "In4.Cu")
		(net "M_H_DQS_DN<9>")
	)
	(segment
		(start 57.893712 -59.496198)
		(end 58.136028 -59.738514)
		(width 0.14224)
		(layer "In4.Cu")
		(net "M_H_DQS_DN<9>")
	)
	(segment
		(start 62.41796 -64.020446)
		(end 62.660022 -64.262508)
		(width 0.14224)
		(layer "In4.Cu")
		(net "M_H_DQS_DN<9>")
	)
	(segment
		(start 62.013846 -63.616332)
		(end 62.17539 -63.616332)
		(width 0.14224)
		(layer "In4.Cu")
		(net "M_H_DQS_DN<9>")
	)
	(segment
		(start 34.977324 -14.4018)
		(end 34.723324 -14.4018)
		(width 0.14224)
		(layer "In4.Cu")
		(net "M_H_DQS_DN<9>")
	)
	(segment
		(start 65.003172 -66.444114)
		(end 65.003172 -66.605658)
		(width 0.14224)
		(layer "In4.Cu")
		(net "M_H_DQS_DN<9>")
	)
	(segment
		(start 62.660022 -64.262508)
		(end 62.821566 -64.262508)
		(width 0.14224)
		(layer "In4.Cu")
		(net "M_H_DQS_DN<9>")
	)
	(segment
		(start 35.832288 -30.419802)
		(end 35.377882 -30.874208)
		(width 0.14224)
		(layer "In4.Cu")
		(net "M_H_DQS_DN<9>")
	)
	(segment
		(start 61.77153 -63.374016)
		(end 62.013846 -63.616332)
		(width 0.14224)
		(layer "In4.Cu")
		(net "M_H_DQS_DN<9>")
	)
	(segment
		(start 63.064136 -64.505078)
		(end 63.064136 -64.666622)
		(width 0.14224)
		(layer "In4.Cu")
		(net "M_H_DQS_DN<9>")
	)
	(segment
		(start 35.52444 -20.46732)
		(end 35.68192 -20.6248)
		(width 0.14224)
		(layer "In4.Cu")
		(net "M_H_DQS_DN<9>")
	)
	(segment
		(start 60.882784 -62.323726)
		(end 61.125354 -62.566296)
		(width 0.14224)
		(layer "In4.Cu")
		(net "M_H_DQS_DN<9>")
	)
	(segment
		(start 34.540444 -14.58468)
		(end 34.540444 -15.109952)
		(width 0.14224)
		(layer "In4.Cu")
		(net "M_H_DQS_DN<9>")
	)
	(segment
		(start 35.756088 -32.329374)
		(end 35.756088 -33.188402)
		(width 0.14224)
		(layer "In4.Cu")
		(net "M_H_DQS_DN<9>")
	)
	(segment
		(start 59.428634 -61.03112)
		(end 59.590178 -61.03112)
		(width 0.14224)
		(layer "In4.Cu")
		(net "M_H_DQS_DN<9>")
	)
	(segment
		(start 55.95493 -57.557416)
		(end 56.196992 -57.799478)
		(width 0.14224)
		(layer "In4.Cu")
		(net "M_H_DQS_DN<9>")
	)
	(segment
		(start 34.867088 -31.72968)
		(end 35.088576 -31.951168)
		(width 0.14224)
		(layer "In4.Cu")
		(net "M_H_DQS_DN<9>")
	)
	(segment
		(start 60.72124 -62.323726)
		(end 60.882784 -62.323726)
		(width 0.14224)
		(layer "In4.Cu")
		(net "M_H_DQS_DN<9>")
	)
	(arc
		(start 69.406516 -68.172838)
		(mid 69.546595 -68.315574)
		(end 69.73824 -68.372736)
		(width 0.0889)
		(layer "In4.Cu")
		(net "M_H_DQS_DN<9>")
	)
	(arc
		(start 68.053966 -67.382136)
		(mid 68.33939 -67.465603)
		(end 68.547996 -67.677538)
		(width 0.0889)
		(layer "In4.Cu")
		(net "M_H_DQS_DN<9>")
	)
	(arc
		(start 70.099936 -68.172838)
		(mid 70.147272 -68.094968)
		(end 70.198234 -68.019422)
		(width 0.0889)
		(layer "In4.Cu")
		(net "M_H_DQS_DN<9>")
	)
	(arc
		(start 67.157854 -66.88709)
		(mid 67.446845 -66.967323)
		(end 67.653154 -67.185032)
		(width 0.0889)
		(layer "In4.Cu")
		(net "M_H_DQS_DN<9>")
	)
	(arc
		(start 67.653154 -67.185032)
		(mid 67.744098 -67.302375)
		(end 67.869308 -67.382136)
		(width 0.0889)
		(layer "In4.Cu")
		(net "M_H_DQS_DN<9>")
	)
	(arc
		(start 68.547996 -67.677538)
		(mid 68.689679 -67.821342)
		(end 68.88353 -67.87769)
		(width 0.0889)
		(layer "In4.Cu")
		(net "M_H_DQS_DN<9>")
	)
	(arc
		(start 69.768212 -68.372736)
		(mid 69.959854 -68.31557)
		(end 70.099936 -68.172838)
		(width 0.0889)
		(layer "In4.Cu")
		(net "M_H_DQS_DN<9>")
	)
	(arc
		(start 68.916296 -67.87769)
		(mid 69.199513 -67.961971)
		(end 69.406516 -68.172838)
		(width 0.0889)
		(layer "In4.Cu")
		(net "M_H_DQS_DN<9>")
	)
	(segment
		(start 76.590906 -42.835068)
		(end 76.346304 -42.590466)
		(width 0.1016)
		(layer "F.Cu")
		(net "M_H_DQS_DN<8>")
	)
	(segment
		(start 79.287624 -43.736514)
		(end 78.697074 -43.736514)
		(width 0.1016)
		(layer "F.Cu")
		(net "M_H_DQS_DN<8>")
	)
	(segment
		(start 75.639168 -41.88333)
		(end 75.639168 -41.171876)
		(width 0.1651)
		(layer "F.Cu")
		(net "M_H_DQS_DN<8>")
	)
	(segment
		(start 83.202272 -55.59044)
		(end 83.202272 -55.258716)
		(width 0.0889)
		(layer "F.Cu")
		(net "M_H_DQS_DN<8>")
	)
	(segment
		(start 75.639168 -41.171876)
		(end 75.156568 -40.689276)
		(width 0.1651)
		(layer "F.Cu")
		(net "M_H_DQS_DN<8>")
	)
	(segment
		(start 78.697074 -43.736514)
		(end 77.795628 -42.835068)
		(width 0.1016)
		(layer "F.Cu")
		(net "M_H_DQS_DN<8>")
	)
	(segment
		(start 74.25817 -30.851602)
		(end 72.98817 -29.581602)
		(width 0.1651)
		(layer "F.Cu")
		(net "M_H_DQS_DN<8>")
	)
	(segment
		(start 75.024488 -31.61792)
		(end 75.024488 -31.431992)
		(width 0.1651)
		(layer "F.Cu")
		(net "M_H_DQS_DN<8>")
	)
	(segment
		(start 83.652868 -50.32629)
		(end 83.547966 -50.221388)
		(width 0.0889)
		(layer "F.Cu")
		(net "M_H_DQS_DN<8>")
	)
	(segment
		(start 83.547966 -50.073814)
		(end 83.547966 -47.996856)
		(width 0.1016)
		(layer "F.Cu")
		(net "M_H_DQS_DN<8>")
	)
	(segment
		(start 72.65035 -8.551672)
		(end 72.997822 -8.2042)
		(width 0.1651)
		(layer "F.Cu")
		(net "M_H_DQS_DN<8>")
	)
	(segment
		(start 83.547966 -47.996856)
		(end 79.287624 -43.736514)
		(width 0.1016)
		(layer "F.Cu")
		(net "M_H_DQS_DN<8>")
	)
	(segment
		(start 75.156568 -40.689276)
		(end 75.156568 -37.842444)
		(width 0.1651)
		(layer "F.Cu")
		(net "M_H_DQS_DN<8>")
	)
	(segment
		(start 83.469734 -51.141122)
		(end 83.469988 -51.140868)
		(width 0.0889)
		(layer "F.Cu")
		(net "M_H_DQS_DN<8>")
	)
	(segment
		(start 72.65035 -8.949436)
		(end 72.65035 -8.551672)
		(width 0.1651)
		(layer "F.Cu")
		(net "M_H_DQS_DN<8>")
	)
	(segment
		(start 72.98817 -29.581602)
		(end 72.98817 -27.793696)
		(width 0.1651)
		(layer "F.Cu")
		(net "M_H_DQS_DN<8>")
	)
	(segment
		(start 83.180682 -54.00929)
		(end 83.213448 -54.00929)
		(width 0.0889)
		(layer "F.Cu")
		(net "M_H_DQS_DN<8>")
	)
	(segment
		(start 83.54949 -50.836322)
		(end 83.652868 -50.651156)
		(width 0.0889)
		(layer "F.Cu")
		(net "M_H_DQS_DN<8>")
	)
	(segment
		(start 83.547966 -50.221388)
		(end 83.547966 -50.073814)
		(width 0.0889)
		(layer "F.Cu")
		(net "M_H_DQS_DN<8>")
	)
	(segment
		(start 75.639168 -36.4998)
		(end 75.791568 -36.3474)
		(width 0.1651)
		(layer "F.Cu")
		(net "M_H_DQS_DN<8>")
	)
	(segment
		(start 73.049384 -9.34847)
		(end 72.65035 -8.949436)
		(width 0.1651)
		(layer "F.Cu")
		(net "M_H_DQS_DN<8>")
	)
	(segment
		(start 72.98817 -27.793696)
		(end 73.437496 -27.34437)
		(width 0.1651)
		(layer "F.Cu")
		(net "M_H_DQS_DN<8>")
	)
	(segment
		(start 83.548728 -50.837084)
		(end 83.54949 -50.836322)
		(width 0.0889)
		(layer "F.Cu")
		(net "M_H_DQS_DN<8>")
	)
	(segment
		(start 83.202272 -55.258716)
		(end 83.129882 -55.186326)
		(width 0.0889)
		(layer "F.Cu")
		(net "M_H_DQS_DN<8>")
	)
	(segment
		(start 73.22185 -8.2042)
		(end 73.437496 -8.419846)
		(width 0.1651)
		(layer "F.Cu")
		(net "M_H_DQS_DN<8>")
	)
	(segment
		(start 72.997822 -8.2042)
		(end 73.22185 -8.2042)
		(width 0.1651)
		(layer "F.Cu")
		(net "M_H_DQS_DN<8>")
	)
	(segment
		(start 75.791568 -32.385)
		(end 75.024488 -31.61792)
		(width 0.1651)
		(layer "F.Cu")
		(net "M_H_DQS_DN<8>")
	)
	(segment
		(start 75.791568 -36.3474)
		(end 75.791568 -32.385)
		(width 0.1651)
		(layer "F.Cu")
		(net "M_H_DQS_DN<8>")
	)
	(segment
		(start 74.444098 -30.851602)
		(end 74.25817 -30.851602)
		(width 0.1651)
		(layer "F.Cu")
		(net "M_H_DQS_DN<8>")
	)
	(segment
		(start 83.548728 -50.837592)
		(end 83.548728 -50.837084)
		(width 0.0889)
		(layer "F.Cu")
		(net "M_H_DQS_DN<8>")
	)
	(segment
		(start 75.156568 -37.842444)
		(end 75.639168 -37.359844)
		(width 0.1651)
		(layer "F.Cu")
		(net "M_H_DQS_DN<8>")
	)
	(segment
		(start 76.346304 -42.590466)
		(end 75.639168 -41.88333)
		(width 0.1651)
		(layer "F.Cu")
		(net "M_H_DQS_DN<8>")
	)
	(segment
		(start 75.639168 -37.359844)
		(end 75.639168 -36.4998)
		(width 0.1651)
		(layer "F.Cu")
		(net "M_H_DQS_DN<8>")
	)
	(segment
		(start 77.795628 -42.835068)
		(end 76.590906 -42.835068)
		(width 0.1016)
		(layer "F.Cu")
		(net "M_H_DQS_DN<8>")
	)
	(segment
		(start 75.024488 -31.431992)
		(end 74.444098 -30.851602)
		(width 0.1651)
		(layer "F.Cu")
		(net "M_H_DQS_DN<8>")
	)
	(segment
		(start 83.469734 -52.12588)
		(end 83.469734 -51.141122)
		(width 0.0889)
		(layer "F.Cu")
		(net "M_H_DQS_DN<8>")
	)
	(segment
		(start 83.652868 -50.651156)
		(end 83.652868 -50.32629)
		(width 0.0889)
		(layer "F.Cu")
		(net "M_H_DQS_DN<8>")
	)
	(segment
		(start 73.049384 -10.422382)
		(end 73.049384 -9.34847)
		(width 0.1651)
		(layer "F.Cu")
		(net "M_H_DQS_DN<8>")
	)
	(via
		(at 73.437496 -12.627356)
		(size 0.508)
		(drill 0.254)
		(layers "F.Cu" "B.Cu")
		(net "M_H_DQS_DN<8>")
	)
	(via
		(at 73.437496 -8.419846)
		(size 0.508)
		(drill 0.254)
		(layers "F.Cu" "B.Cu")
		(net "M_H_DQS_DN<8>")
	)
	(via
		(at 73.437496 -27.34437)
		(size 0.508)
		(drill 0.254)
		(layers "F.Cu" "B.Cu")
		(net "M_H_DQS_DN<8>")
	)
	(arc
		(start 83.213448 -54.00929)
		(mid 83.551617 -53.804492)
		(end 83.548982 -53.409088)
		(width 0.0889)
		(layer "F.Cu")
		(net "M_H_DQS_DN<8>")
	)
	(arc
		(start 83.548982 -53.409088)
		(mid 83.469851 -53.113686)
		(end 83.548982 -52.818284)
		(width 0.0889)
		(layer "F.Cu")
		(net "M_H_DQS_DN<8>")
	)
	(arc
		(start 83.548982 -52.418488)
		(mid 83.490278 -52.277351)
		(end 83.469734 -52.12588)
		(width 0.0889)
		(layer "F.Cu")
		(net "M_H_DQS_DN<8>")
	)
	(arc
		(start 83.129882 -55.186326)
		(mid 83.119327 -55.184898)
		(end 83.1088 -55.183278)
		(width 0.0889)
		(layer "F.Cu")
		(net "M_H_DQS_DN<8>")
	)
	(arc
		(start 83.469988 -51.140868)
		(mid 83.48891 -50.983924)
		(end 83.548728 -50.837592)
		(width 0.0889)
		(layer "F.Cu")
		(net "M_H_DQS_DN<8>")
	)
	(arc
		(start 83.1088 -55.183278)
		(mid 82.612499 -54.563726)
		(end 83.180682 -54.00929)
		(width 0.0889)
		(layer "F.Cu")
		(net "M_H_DQS_DN<8>")
	)
	(arc
		(start 83.548982 -52.818284)
		(mid 83.602481 -52.618386)
		(end 83.548982 -52.418488)
		(width 0.0889)
		(layer "F.Cu")
		(net "M_H_DQS_DN<8>")
	)
	(segment
		(start 73.049384 -10.623042)
		(end 73.049384 -11.53033)
		(width 0.1651)
		(layer "B.Cu")
		(net "M_H_DQS_DN<8>")
	)
	(segment
		(start 72.667368 -12.166346)
		(end 72.667368 -12.4968)
		(width 0.1651)
		(layer "B.Cu")
		(net "M_H_DQS_DN<8>")
	)
	(segment
		(start 73.212452 -12.8524)
		(end 73.437496 -12.627356)
		(width 0.1651)
		(layer "B.Cu")
		(net "M_H_DQS_DN<8>")
	)
	(segment
		(start 73.022968 -12.8524)
		(end 73.212452 -12.8524)
		(width 0.1651)
		(layer "B.Cu")
		(net "M_H_DQS_DN<8>")
	)
	(segment
		(start 73.049384 -11.53033)
		(end 72.921368 -11.658346)
		(width 0.1651)
		(layer "B.Cu")
		(net "M_H_DQS_DN<8>")
	)
	(segment
		(start 72.921368 -11.658346)
		(end 72.921368 -11.912346)
		(width 0.1651)
		(layer "B.Cu")
		(net "M_H_DQS_DN<8>")
	)
	(segment
		(start 72.667368 -12.4968)
		(end 73.022968 -12.8524)
		(width 0.1651)
		(layer "B.Cu")
		(net "M_H_DQS_DN<8>")
	)
	(segment
		(start 72.921368 -11.912346)
		(end 72.667368 -12.166346)
		(width 0.1651)
		(layer "B.Cu")
		(net "M_H_DQS_DN<8>")
	)
	(segment
		(start 73.437496 -12.627356)
		(end 73.437496 -12.62761)
		(width 0.14224)
		(layer "In11.Cu")
		(net "M_H_DQS_DN<8>")
	)
	(segment
		(start 73.979024 -8.679688)
		(end 73.719182 -8.419846)
		(width 0.14224)
		(layer "In11.Cu")
		(net "M_H_DQS_DN<8>")
	)
	(segment
		(start 73.437496 -12.62761)
		(end 73.716388 -12.62761)
		(width 0.14224)
		(layer "In11.Cu")
		(net "M_H_DQS_DN<8>")
	)
	(segment
		(start 73.719182 -8.419846)
		(end 73.437496 -8.419846)
		(width 0.14224)
		(layer "In11.Cu")
		(net "M_H_DQS_DN<8>")
	)
	(segment
		(start 73.934574 -15.263368)
		(end 73.451974 -14.780768)
		(width 0.14224)
		(layer "In11.Cu")
		(net "M_H_DQS_DN<8>")
	)
	(segment
		(start 73.979024 -10.68832)
		(end 73.979024 -10.339578)
		(width 0.14224)
		(layer "In11.Cu")
		(net "M_H_DQS_DN<8>")
	)
	(segment
		(start 73.796144 -10.8712)
		(end 73.979024 -10.68832)
		(width 0.14224)
		(layer "In11.Cu")
		(net "M_H_DQS_DN<8>")
	)
	(segment
		(start 72.9996 -13.065252)
		(end 73.437496 -12.627356)
		(width 0.14224)
		(layer "In11.Cu")
		(net "M_H_DQS_DN<8>")
	)
	(segment
		(start 73.979024 -12.364974)
		(end 73.979024 -11.660124)
		(width 0.14224)
		(layer "In11.Cu")
		(net "M_H_DQS_DN<8>")
	)
	(segment
		(start 73.716388 -12.62761)
		(end 73.979024 -12.364974)
		(width 0.14224)
		(layer "In11.Cu")
		(net "M_H_DQS_DN<8>")
	)
	(segment
		(start 73.669144 -11.4808)
		(end 73.491344 -11.303)
		(width 0.14224)
		(layer "In11.Cu")
		(net "M_H_DQS_DN<8>")
	)
	(segment
		(start 73.485502 -9.981946)
		(end 73.485502 -9.677654)
		(width 0.14224)
		(layer "In11.Cu")
		(net "M_H_DQS_DN<8>")
	)
	(segment
		(start 73.485502 -9.677654)
		(end 73.638156 -9.525)
		(width 0.14224)
		(layer "In11.Cu")
		(net "M_H_DQS_DN<8>")
	)
	(segment
		(start 73.451974 -14.61008)
		(end 72.9996 -14.157706)
		(width 0.14224)
		(layer "In11.Cu")
		(net "M_H_DQS_DN<8>")
	)
	(segment
		(start 72.9996 -14.157706)
		(end 72.9996 -13.065252)
		(width 0.14224)
		(layer "In11.Cu")
		(net "M_H_DQS_DN<8>")
	)
	(segment
		(start 73.437496 -27.34437)
		(end 73.934574 -26.847292)
		(width 0.14224)
		(layer "In11.Cu")
		(net "M_H_DQS_DN<8>")
	)
	(segment
		(start 73.451974 -14.780768)
		(end 73.451974 -14.61008)
		(width 0.14224)
		(layer "In11.Cu")
		(net "M_H_DQS_DN<8>")
	)
	(segment
		(start 73.7997 -11.4808)
		(end 73.669144 -11.4808)
		(width 0.14224)
		(layer "In11.Cu")
		(net "M_H_DQS_DN<8>")
	)
	(segment
		(start 73.491344 -11.303)
		(end 73.491344 -11.049)
		(width 0.14224)
		(layer "In11.Cu")
		(net "M_H_DQS_DN<8>")
	)
	(segment
		(start 73.638156 -9.525)
		(end 73.799446 -9.525)
		(width 0.14224)
		(layer "In11.Cu")
		(net "M_H_DQS_DN<8>")
	)
	(segment
		(start 73.669144 -10.8712)
		(end 73.796144 -10.8712)
		(width 0.14224)
		(layer "In11.Cu")
		(net "M_H_DQS_DN<8>")
	)
	(segment
		(start 73.799446 -9.525)
		(end 73.979024 -9.345422)
		(width 0.14224)
		(layer "In11.Cu")
		(net "M_H_DQS_DN<8>")
	)
	(segment
		(start 73.979024 -11.660124)
		(end 73.7997 -11.4808)
		(width 0.14224)
		(layer "In11.Cu")
		(net "M_H_DQS_DN<8>")
	)
	(segment
		(start 73.491344 -11.049)
		(end 73.669144 -10.8712)
		(width 0.14224)
		(layer "In11.Cu")
		(net "M_H_DQS_DN<8>")
	)
	(segment
		(start 73.934574 -26.847292)
		(end 73.934574 -15.263368)
		(width 0.14224)
		(layer "In11.Cu")
		(net "M_H_DQS_DN<8>")
	)
	(segment
		(start 73.979024 -9.345422)
		(end 73.979024 -8.679688)
		(width 0.14224)
		(layer "In11.Cu")
		(net "M_H_DQS_DN<8>")
	)
	(segment
		(start 73.979024 -10.339578)
		(end 73.774046 -10.1346)
		(width 0.14224)
		(layer "In11.Cu")
		(net "M_H_DQS_DN<8>")
	)
	(segment
		(start 73.774046 -10.1346)
		(end 73.638156 -10.1346)
		(width 0.14224)
		(layer "In11.Cu")
		(net "M_H_DQS_DN<8>")
	)
	(segment
		(start 73.638156 -10.1346)
		(end 73.485502 -9.981946)
		(width 0.14224)
		(layer "In11.Cu")
		(net "M_H_DQS_DN<8>")
	)
	(segment
		(start 146.999452 -10.422382)
		(end 146.999452 -9.40943)
		(width 0.1651)
		(layer "F.Cu")
		(net "M_H_DQS_DN<7>")
	)
	(segment
		(start 146.733768 -9.143746)
		(end 146.733768 -8.410956)
		(width 0.1651)
		(layer "F.Cu")
		(net "M_H_DQS_DN<7>")
	)
	(segment
		(start 146.999452 -9.40943)
		(end 146.733768 -9.143746)
		(width 0.1651)
		(layer "F.Cu")
		(net "M_H_DQS_DN<7>")
	)
	(segment
		(start 119.929402 -61.847984)
		(end 119.357902 -61.847984)
		(width 0.1016)
		(layer "F.Cu")
		(net "M_H_DQS_DN<7>")
	)
	(segment
		(start 146.733768 -8.410956)
		(end 147.387564 -7.75716)
		(width 0.1651)
		(layer "F.Cu")
		(net "M_H_DQS_DN<7>")
	)
	(via
		(at 119.357902 -61.847984)
		(size 0.508)
		(drill 0.254)
		(layers "F.Cu" "B.Cu")
		(net "M_H_DQS_DN<7>")
	)
	(via
		(at 147.387564 -13.287756)
		(size 0.508)
		(drill 0.254)
		(layers "F.Cu" "B.Cu")
		(net "M_H_DQS_DN<7>")
	)
	(via
		(at 147.387564 -7.75716)
		(size 0.508)
		(drill 0.254)
		(layers "F.Cu" "B.Cu")
		(net "M_H_DQS_DN<7>")
	)
	(segment
		(start 146.746468 -11.773154)
		(end 146.746468 -12.64666)
		(width 0.1651)
		(layer "B.Cu")
		(net "M_H_DQS_DN<7>")
	)
	(segment
		(start 146.999452 -11.52017)
		(end 146.746468 -11.773154)
		(width 0.1651)
		(layer "B.Cu")
		(net "M_H_DQS_DN<7>")
	)
	(segment
		(start 146.999452 -10.623042)
		(end 146.999452 -11.52017)
		(width 0.1651)
		(layer "B.Cu")
		(net "M_H_DQS_DN<7>")
	)
	(segment
		(start 146.746468 -12.64666)
		(end 147.387564 -13.287756)
		(width 0.1651)
		(layer "B.Cu")
		(net "M_H_DQS_DN<7>")
	)
	(segment
		(start 121.592848 -54.629304)
		(end 121.586498 -54.618636)
		(width 0.0889)
		(layer "In4.Cu")
		(net "M_H_DQS_DN<7>")
	)
	(segment
		(start 122.842528 -52.34432)
		(end 123.747022 -52.34432)
		(width 0.0889)
		(layer "In4.Cu")
		(net "M_H_DQS_DN<7>")
	)
	(segment
		(start 119.876062 -59.58205)
		(end 119.869712 -59.571382)
		(width 0.0889)
		(layer "In4.Cu")
		(net "M_H_DQS_DN<7>")
	)
	(segment
		(start 148.198332 -12.476988)
		(end 148.198332 -8.567928)
		(width 0.14224)
		(layer "In4.Cu")
		(net "M_H_DQS_DN<7>")
	)
	(segment
		(start 148.169884 -17.62252)
		(end 148.169884 -17.42948)
		(width 0.14224)
		(layer "In4.Cu")
		(net "M_H_DQS_DN<7>")
	)
	(segment
		(start 148.169884 -18.19148)
		(end 148.327364 -18.034)
		(width 0.14224)
		(layer "In4.Cu")
		(net "M_H_DQS_DN<7>")
	)
	(segment
		(start 121.592848 -55.619904)
		(end 121.586498 -55.609236)
		(width 0.0889)
		(layer "In4.Cu")
		(net "M_H_DQS_DN<7>")
	)
	(segment
		(start 148.198332 -8.567928)
		(end 147.387564 -7.75716)
		(width 0.14224)
		(layer "In4.Cu")
		(net "M_H_DQS_DN<7>")
	)
	(segment
		(start 124.300742 -51.7906)
		(end 124.356114 -51.790854)
		(width 0.0889)
		(layer "In4.Cu")
		(net "M_H_DQS_DN<7>")
	)
	(segment
		(start 147.851368 -14.2748)
		(end 147.851368 -13.75156)
		(width 0.14224)
		(layer "In4.Cu")
		(net "M_H_DQS_DN<7>")
	)
	(segment
		(start 130.887216 -47.19447)
		(end 144.823688 -33.257998)
		(width 0.14224)
		(layer "In4.Cu")
		(net "M_H_DQS_DN<7>")
	)
	(segment
		(start 124.356114 -51.790854)
		(end 124.371608 -51.77536)
		(width 0.0889)
		(layer "In4.Cu")
		(net "M_H_DQS_DN<7>")
	)
	(segment
		(start 144.823688 -31.315914)
		(end 145.307812 -30.832044)
		(width 0.14224)
		(layer "In4.Cu")
		(net "M_H_DQS_DN<7>")
	)
	(segment
		(start 147.851368 -13.75156)
		(end 147.387564 -13.287756)
		(width 0.14224)
		(layer "In4.Cu")
		(net "M_H_DQS_DN<7>")
	)
	(segment
		(start 148.327364 -17.272)
		(end 148.327364 -17.018)
		(width 0.14224)
		(layer "In4.Cu")
		(net "M_H_DQS_DN<7>")
	)
	(segment
		(start 121.586498 -57.590436)
		(end 121.581672 -57.5818)
		(width 0.0889)
		(layer "In4.Cu")
		(net "M_H_DQS_DN<7>")
	)
	(segment
		(start 147.419568 -14.4272)
		(end 147.698968 -14.4272)
		(width 0.14224)
		(layer "In4.Cu")
		(net "M_H_DQS_DN<7>")
	)
	(segment
		(start 121.915174 -53.028088)
		(end 121.920762 -53.027834)
		(width 0.0889)
		(layer "In4.Cu")
		(net "M_H_DQS_DN<7>")
	)
	(segment
		(start 121.592848 -57.601104)
		(end 121.586498 -57.590436)
		(width 0.0889)
		(layer "In4.Cu")
		(net "M_H_DQS_DN<7>")
	)
	(segment
		(start 147.387564 -13.287756)
		(end 148.198332 -12.476988)
		(width 0.14224)
		(layer "In4.Cu")
		(net "M_H_DQS_DN<7>")
	)
	(segment
		(start 148.327364 -17.78)
		(end 148.169884 -17.62252)
		(width 0.14224)
		(layer "In4.Cu")
		(net "M_H_DQS_DN<7>")
	)
	(segment
		(start 119.878602 -60.577476)
		(end 119.869712 -60.562236)
		(width 0.0889)
		(layer "In4.Cu")
		(net "M_H_DQS_DN<7>")
	)
	(segment
		(start 147.698968 -14.4272)
		(end 147.851368 -14.2748)
		(width 0.14224)
		(layer "In4.Cu")
		(net "M_H_DQS_DN<7>")
	)
	(segment
		(start 148.169884 -27.969718)
		(end 148.169884 -18.19148)
		(width 0.14224)
		(layer "In4.Cu")
		(net "M_H_DQS_DN<7>")
	)
	(segment
		(start 121.592848 -56.610504)
		(end 121.586498 -56.599836)
		(width 0.0889)
		(layer "In4.Cu")
		(net "M_H_DQS_DN<7>")
	)
	(segment
		(start 147.211288 -14.63548)
		(end 147.419568 -14.4272)
		(width 0.14224)
		(layer "In4.Cu")
		(net "M_H_DQS_DN<7>")
	)
	(segment
		(start 121.586498 -56.599836)
		(end 121.581672 -56.5912)
		(width 0.0889)
		(layer "In4.Cu")
		(net "M_H_DQS_DN<7>")
	)
	(segment
		(start 121.063512 -58.476388)
		(end 121.087642 -58.476388)
		(width 0.0889)
		(layer "In4.Cu")
		(net "M_H_DQS_DN<7>")
	)
	(segment
		(start 120.203976 -58.971688)
		(end 120.237758 -58.971688)
		(width 0.0889)
		(layer "In4.Cu")
		(net "M_H_DQS_DN<7>")
	)
	(segment
		(start 119.80418 -61.266578)
		(end 119.869712 -61.15304)
		(width 0.0889)
		(layer "In4.Cu")
		(net "M_H_DQS_DN<7>")
	)
	(segment
		(start 128.952498 -47.19447)
		(end 130.887216 -47.19447)
		(width 0.14224)
		(layer "In4.Cu")
		(net "M_H_DQS_DN<7>")
	)
	(segment
		(start 148.169884 -17.42948)
		(end 148.327364 -17.272)
		(width 0.14224)
		(layer "In4.Cu")
		(net "M_H_DQS_DN<7>")
	)
	(segment
		(start 148.327364 -18.034)
		(end 148.327364 -17.78)
		(width 0.14224)
		(layer "In4.Cu")
		(net "M_H_DQS_DN<7>")
	)
	(segment
		(start 123.747022 -52.34432)
		(end 124.300742 -51.7906)
		(width 0.0889)
		(layer "In4.Cu")
		(net "M_H_DQS_DN<7>")
	)
	(segment
		(start 121.586498 -54.618636)
		(end 121.581672 -54.61)
		(width 0.0889)
		(layer "In4.Cu")
		(net "M_H_DQS_DN<7>")
	)
	(segment
		(start 148.169884 -15.845028)
		(end 147.211288 -14.886432)
		(width 0.14224)
		(layer "In4.Cu")
		(net "M_H_DQS_DN<7>")
	)
	(segment
		(start 147.211288 -14.886432)
		(end 147.211288 -14.63548)
		(width 0.14224)
		(layer "In4.Cu")
		(net "M_H_DQS_DN<7>")
	)
	(segment
		(start 148.169884 -16.86052)
		(end 148.169884 -15.845028)
		(width 0.14224)
		(layer "In4.Cu")
		(net "M_H_DQS_DN<7>")
	)
	(segment
		(start 145.307812 -30.832044)
		(end 148.169884 -27.969718)
		(width 0.14224)
		(layer "In4.Cu")
		(net "M_H_DQS_DN<7>")
	)
	(segment
		(start 122.430794 -52.756308)
		(end 122.842528 -52.34432)
		(width 0.0889)
		(layer "In4.Cu")
		(net "M_H_DQS_DN<7>")
	)
	(segment
		(start 121.586498 -55.609236)
		(end 121.581672 -55.6006)
		(width 0.0889)
		(layer "In4.Cu")
		(net "M_H_DQS_DN<7>")
	)
	(segment
		(start 124.371608 -51.77536)
		(end 128.952498 -47.19447)
		(width 0.14224)
		(layer "In4.Cu")
		(net "M_H_DQS_DN<7>")
	)
	(segment
		(start 148.327364 -17.018)
		(end 148.169884 -16.86052)
		(width 0.14224)
		(layer "In4.Cu")
		(net "M_H_DQS_DN<7>")
	)
	(segment
		(start 121.920762 -53.027834)
		(end 121.955306 -53.027834)
		(width 0.0889)
		(layer "In4.Cu")
		(net "M_H_DQS_DN<7>")
	)
	(segment
		(start 144.823688 -33.257998)
		(end 144.823688 -31.315914)
		(width 0.14224)
		(layer "In4.Cu")
		(net "M_H_DQS_DN<7>")
	)
	(arc
		(start 121.581672 -54.61)
		(mid 121.532917 -54.413648)
		(end 121.586498 -54.218586)
		(width 0.0889)
		(layer "In4.Cu")
		(net "M_H_DQS_DN<7>")
	)
	(arc
		(start 121.955306 -53.027834)
		(mid 122.226403 -52.950483)
		(end 122.430794 -52.756308)
		(width 0.0889)
		(layer "In4.Cu")
		(net "M_H_DQS_DN<7>")
	)
	(arc
		(start 121.586498 -53.627782)
		(mid 121.582253 -53.235537)
		(end 121.915174 -53.028088)
		(width 0.0889)
		(layer "In4.Cu")
		(net "M_H_DQS_DN<7>")
	)
	(arc
		(start 120.727978 -58.67654)
		(mid 120.869661 -58.532736)
		(end 121.063512 -58.476388)
		(width 0.0889)
		(layer "In4.Cu")
		(net "M_H_DQS_DN<7>")
	)
	(arc
		(start 121.586498 -56.199786)
		(mid 121.66572 -55.910668)
		(end 121.592848 -55.619904)
		(width 0.0889)
		(layer "In4.Cu")
		(net "M_H_DQS_DN<7>")
	)
	(arc
		(start 121.586498 -57.190386)
		(mid 121.66572 -56.901268)
		(end 121.592848 -56.610504)
		(width 0.0889)
		(layer "In4.Cu")
		(net "M_H_DQS_DN<7>")
	)
	(arc
		(start 121.586498 -55.209186)
		(mid 121.66572 -54.920068)
		(end 121.592848 -54.629304)
		(width 0.0889)
		(layer "In4.Cu")
		(net "M_H_DQS_DN<7>")
	)
	(arc
		(start 121.581672 -55.6006)
		(mid 121.532917 -55.404248)
		(end 121.586498 -55.209186)
		(width 0.0889)
		(layer "In4.Cu")
		(net "M_H_DQS_DN<7>")
	)
	(arc
		(start 119.357902 -61.847984)
		(mid 119.600082 -61.571896)
		(end 119.80418 -61.266578)
		(width 0.0889)
		(layer "In4.Cu")
		(net "M_H_DQS_DN<7>")
	)
	(arc
		(start 121.087642 -58.476388)
		(mid 121.586523 -58.180951)
		(end 121.592848 -57.601104)
		(width 0.0889)
		(layer "In4.Cu")
		(net "M_H_DQS_DN<7>")
	)
	(arc
		(start 119.869712 -60.16244)
		(mid 119.949061 -59.873068)
		(end 119.876062 -59.58205)
		(width 0.0889)
		(layer "In4.Cu")
		(net "M_H_DQS_DN<7>")
	)
	(arc
		(start 121.581672 -57.5818)
		(mid 121.532917 -57.385448)
		(end 121.586498 -57.190386)
		(width 0.0889)
		(layer "In4.Cu")
		(net "M_H_DQS_DN<7>")
	)
	(arc
		(start 119.869712 -60.562236)
		(mid 119.816179 -60.362338)
		(end 119.869712 -60.16244)
		(width 0.0889)
		(layer "In4.Cu")
		(net "M_H_DQS_DN<7>")
	)
	(arc
		(start 120.237758 -58.971688)
		(mid 120.520975 -58.887407)
		(end 120.727978 -58.67654)
		(width 0.0889)
		(layer "In4.Cu")
		(net "M_H_DQS_DN<7>")
	)
	(arc
		(start 121.581672 -56.5912)
		(mid 121.532917 -56.394848)
		(end 121.586498 -56.199786)
		(width 0.0889)
		(layer "In4.Cu")
		(net "M_H_DQS_DN<7>")
	)
	(arc
		(start 119.869712 -59.571382)
		(mid 119.866787 -59.176744)
		(end 120.203976 -58.971688)
		(width 0.0889)
		(layer "In4.Cu")
		(net "M_H_DQS_DN<7>")
	)
	(arc
		(start 121.586498 -54.218586)
		(mid 121.665629 -53.923184)
		(end 121.586498 -53.627782)
		(width 0.0889)
		(layer "In4.Cu")
		(net "M_H_DQS_DN<7>")
	)
	(arc
		(start 119.869712 -61.15304)
		(mid 119.948901 -60.866425)
		(end 119.878602 -60.577476)
		(width 0.0889)
		(layer "In4.Cu")
		(net "M_H_DQS_DN<7>")
	)
	(segment
		(start 120.19153 -49.377346)
		(end 122.805952 -46.762924)
		(width 0.1016)
		(layer "F.Cu")
		(net "M_H_DQS_DN<6>")
	)
	(segment
		(start 119.423434 -51.227228)
		(end 119.33047 -51.065938)
		(width 0.0889)
		(layer "F.Cu")
		(net "M_H_DQS_DN<6>")
	)
	(segment
		(start 137.267442 -8.534654)
		(end 137.597896 -8.2042)
		(width 0.1651)
		(layer "F.Cu")
		(net "M_H_DQS_DN<6>")
	)
	(segment
		(start 119.417338 -51.646582)
		(end 119.417592 -51.646836)
		(width 0.0889)
		(layer "F.Cu")
		(net "M_H_DQS_DN<6>")
	)
	(segment
		(start 119.42318 -51.227482)
		(end 119.423434 -51.227228)
		(width 0.0889)
		(layer "F.Cu")
		(net "M_H_DQS_DN<6>")
	)
	(segment
		(start 137.593324 -27.788616)
		(end 138.03757 -27.34437)
		(width 0.1651)
		(layer "F.Cu")
		(net "M_H_DQS_DN<6>")
	)
	(segment
		(start 129.641092 -46.762924)
		(end 133.58114 -42.822876)
		(width 0.1016)
		(layer "F.Cu")
		(net "M_H_DQS_DN<6>")
	)
	(segment
		(start 137.649458 -10.422382)
		(end 137.649458 -9.34847)
		(width 0.1651)
		(layer "F.Cu")
		(net "M_H_DQS_DN<6>")
	)
	(segment
		(start 118.695978 -53.88102)
		(end 118.596918 -53.78196)
		(width 0.0889)
		(layer "F.Cu")
		(net "M_H_DQS_DN<6>")
	)
	(segment
		(start 120.037098 -49.4538)
		(end 120.115076 -49.4538)
		(width 0.0889)
		(layer "F.Cu")
		(net "M_H_DQS_DN<6>")
	)
	(segment
		(start 119.417592 -51.646836)
		(end 119.423434 -51.636676)
		(width 0.0889)
		(layer "F.Cu")
		(net "M_H_DQS_DN<6>")
	)
	(segment
		(start 133.589268 -41.8592)
		(end 133.589268 -41.4147)
		(width 0.1651)
		(layer "F.Cu")
		(net "M_H_DQS_DN<6>")
	)
	(segment
		(start 122.805952 -46.762924)
		(end 129.641092 -46.762924)
		(width 0.1016)
		(layer "F.Cu")
		(net "M_H_DQS_DN<6>")
	)
	(segment
		(start 133.589268 -41.4147)
		(end 138.089386 -36.914582)
		(width 0.1651)
		(layer "F.Cu")
		(net "M_H_DQS_DN<6>")
	)
	(segment
		(start 118.817136 -53.88102)
		(end 118.695978 -53.88102)
		(width 0.0889)
		(layer "F.Cu")
		(net "M_H_DQS_DN<6>")
	)
	(segment
		(start 119.049292 -52.837334)
		(end 119.070882 -52.837334)
		(width 0.0889)
		(layer "F.Cu")
		(net "M_H_DQS_DN<6>")
	)
	(segment
		(start 138.089386 -30.460188)
		(end 137.593324 -29.964126)
		(width 0.1651)
		(layer "F.Cu")
		(net "M_H_DQS_DN<6>")
	)
	(segment
		(start 138.089386 -36.914582)
		(end 138.089386 -32.131)
		(width 0.1651)
		(layer "F.Cu")
		(net "M_H_DQS_DN<6>")
	)
	(segment
		(start 119.33047 -51.065938)
		(end 119.33047 -50.160428)
		(width 0.0889)
		(layer "F.Cu")
		(net "M_H_DQS_DN<6>")
	)
	(segment
		(start 119.070882 -54.418738)
		(end 118.817136 -53.88102)
		(width 0.0889)
		(layer "F.Cu")
		(net "M_H_DQS_DN<6>")
	)
	(segment
		(start 118.596918 -53.78196)
		(end 118.589806 -53.772054)
		(width 0.0889)
		(layer "F.Cu")
		(net "M_H_DQS_DN<6>")
	)
	(segment
		(start 120.115076 -49.4538)
		(end 120.19153 -49.377346)
		(width 0.0889)
		(layer "F.Cu")
		(net "M_H_DQS_DN<6>")
	)
	(segment
		(start 137.267442 -8.966454)
		(end 137.267442 -8.534654)
		(width 0.1651)
		(layer "F.Cu")
		(net "M_H_DQS_DN<6>")
	)
	(segment
		(start 133.58114 -41.867328)
		(end 133.589268 -41.8592)
		(width 0.1016)
		(layer "F.Cu")
		(net "M_H_DQS_DN<6>")
	)
	(segment
		(start 137.597896 -8.2042)
		(end 137.821924 -8.2042)
		(width 0.1651)
		(layer "F.Cu")
		(net "M_H_DQS_DN<6>")
	)
	(segment
		(start 119.33047 -50.160428)
		(end 120.037098 -49.4538)
		(width 0.0889)
		(layer "F.Cu")
		(net "M_H_DQS_DN<6>")
	)
	(segment
		(start 137.821924 -8.2042)
		(end 138.03757 -8.419846)
		(width 0.1651)
		(layer "F.Cu")
		(net "M_H_DQS_DN<6>")
	)
	(segment
		(start 133.58114 -42.822876)
		(end 133.58114 -41.867328)
		(width 0.1016)
		(layer "F.Cu")
		(net "M_H_DQS_DN<6>")
	)
	(segment
		(start 137.593324 -29.964126)
		(end 137.593324 -27.788616)
		(width 0.1651)
		(layer "F.Cu")
		(net "M_H_DQS_DN<6>")
	)
	(segment
		(start 137.649458 -9.34847)
		(end 137.267442 -8.966454)
		(width 0.1651)
		(layer "F.Cu")
		(net "M_H_DQS_DN<6>")
	)
	(segment
		(start 138.089386 -32.131)
		(end 138.089386 -30.460188)
		(width 0.1651)
		(layer "F.Cu")
		(net "M_H_DQS_DN<6>")
	)
	(via
		(at 138.03757 -12.627356)
		(size 0.508)
		(drill 0.254)
		(layers "F.Cu" "B.Cu")
		(net "M_H_DQS_DN<6>")
	)
	(via
		(at 138.03757 -27.34437)
		(size 0.508)
		(drill 0.254)
		(layers "F.Cu" "B.Cu")
		(net "M_H_DQS_DN<6>")
	)
	(via
		(at 138.03757 -8.419846)
		(size 0.508)
		(drill 0.254)
		(layers "F.Cu" "B.Cu")
		(net "M_H_DQS_DN<6>")
	)
	(via
		(at 138.089386 -32.131)
		(size 0.508)
		(drill 0.254)
		(layers "F.Cu" "B.Cu")
		(net "M_H_DQS_DN<6>")
	)
	(arc
		(start 119.423434 -51.636676)
		(mid 119.478164 -51.432032)
		(end 119.42318 -51.227482)
		(width 0.0889)
		(layer "F.Cu")
		(net "M_H_DQS_DN<6>")
	)
	(arc
		(start 118.589806 -53.772054)
		(mid 118.540108 -53.167338)
		(end 119.049292 -52.837334)
		(width 0.0889)
		(layer "F.Cu")
		(net "M_H_DQS_DN<6>")
	)
	(arc
		(start 119.070882 -52.837334)
		(mid 119.417308 -52.637357)
		(end 119.417338 -52.237386)
		(width 0.0889)
		(layer "F.Cu")
		(net "M_H_DQS_DN<6>")
	)
	(arc
		(start 119.417338 -52.237386)
		(mid 119.338207 -51.941984)
		(end 119.417338 -51.646582)
		(width 0.0889)
		(layer "F.Cu")
		(net "M_H_DQS_DN<6>")
	)
	(segment
		(start 137.812526 -12.8524)
		(end 138.03757 -12.627356)
		(width 0.1651)
		(layer "B.Cu")
		(net "M_H_DQS_DN<6>")
	)
	(segment
		(start 137.521442 -11.912346)
		(end 137.267442 -12.166346)
		(width 0.1651)
		(layer "B.Cu")
		(net "M_H_DQS_DN<6>")
	)
	(segment
		(start 137.623042 -12.8524)
		(end 137.812526 -12.8524)
		(width 0.1651)
		(layer "B.Cu")
		(net "M_H_DQS_DN<6>")
	)
	(segment
		(start 137.649458 -11.53033)
		(end 137.521442 -11.658346)
		(width 0.1651)
		(layer "B.Cu")
		(net "M_H_DQS_DN<6>")
	)
	(segment
		(start 137.267442 -12.4968)
		(end 137.623042 -12.8524)
		(width 0.1651)
		(layer "B.Cu")
		(net "M_H_DQS_DN<6>")
	)
	(segment
		(start 137.649458 -10.623042)
		(end 137.649458 -11.53033)
		(width 0.1651)
		(layer "B.Cu")
		(net "M_H_DQS_DN<6>")
	)
	(segment
		(start 137.521442 -11.658346)
		(end 137.521442 -11.912346)
		(width 0.1651)
		(layer "B.Cu")
		(net "M_H_DQS_DN<6>")
	)
	(segment
		(start 137.267442 -12.166346)
		(end 137.267442 -12.4968)
		(width 0.1651)
		(layer "B.Cu")
		(net "M_H_DQS_DN<6>")
	)
	(segment
		(start 138.579098 -12.364974)
		(end 138.579098 -11.660124)
		(width 0.14224)
		(layer "In4.Cu")
		(net "M_H_DQS_DN<6>")
	)
	(segment
		(start 138.03757 -27.34437)
		(end 138.534648 -26.847292)
		(width 0.14224)
		(layer "In4.Cu")
		(net "M_H_DQS_DN<6>")
	)
	(segment
		(start 138.03757 -12.627356)
		(end 138.03757 -12.62761)
		(width 0.14224)
		(layer "In4.Cu")
		(net "M_H_DQS_DN<6>")
	)
	(segment
		(start 138.534648 -15.263368)
		(end 138.052048 -14.780768)
		(width 0.14224)
		(layer "In4.Cu")
		(net "M_H_DQS_DN<6>")
	)
	(segment
		(start 138.579098 -10.339578)
		(end 138.37412 -10.1346)
		(width 0.14224)
		(layer "In4.Cu")
		(net "M_H_DQS_DN<6>")
	)
	(segment
		(start 138.37412 -10.1346)
		(end 138.196828 -10.1346)
		(width 0.14224)
		(layer "In4.Cu")
		(net "M_H_DQS_DN<6>")
	)
	(segment
		(start 138.579098 -9.345422)
		(end 138.579098 -8.679688)
		(width 0.14224)
		(layer "In4.Cu")
		(net "M_H_DQS_DN<6>")
	)
	(segment
		(start 138.316462 -12.62761)
		(end 138.579098 -12.364974)
		(width 0.14224)
		(layer "In4.Cu")
		(net "M_H_DQS_DN<6>")
	)
	(segment
		(start 138.269218 -10.8712)
		(end 138.396218 -10.8712)
		(width 0.14224)
		(layer "In4.Cu")
		(net "M_H_DQS_DN<6>")
	)
	(segment
		(start 138.399774 -11.4808)
		(end 138.269218 -11.4808)
		(width 0.14224)
		(layer "In4.Cu")
		(net "M_H_DQS_DN<6>")
	)
	(segment
		(start 138.196828 -9.525)
		(end 138.39952 -9.525)
		(width 0.14224)
		(layer "In4.Cu")
		(net "M_H_DQS_DN<6>")
	)
	(segment
		(start 138.091418 -11.049)
		(end 138.269218 -10.8712)
		(width 0.14224)
		(layer "In4.Cu")
		(net "M_H_DQS_DN<6>")
	)
	(segment
		(start 138.579098 -11.660124)
		(end 138.399774 -11.4808)
		(width 0.14224)
		(layer "In4.Cu")
		(net "M_H_DQS_DN<6>")
	)
	(segment
		(start 138.044174 -9.981946)
		(end 138.044174 -9.677654)
		(width 0.14224)
		(layer "In4.Cu")
		(net "M_H_DQS_DN<6>")
	)
	(segment
		(start 138.03757 -12.62761)
		(end 138.316462 -12.62761)
		(width 0.14224)
		(layer "In4.Cu")
		(net "M_H_DQS_DN<6>")
	)
	(segment
		(start 138.044174 -9.677654)
		(end 138.196828 -9.525)
		(width 0.14224)
		(layer "In4.Cu")
		(net "M_H_DQS_DN<6>")
	)
	(segment
		(start 138.39952 -9.525)
		(end 138.579098 -9.345422)
		(width 0.14224)
		(layer "In4.Cu")
		(net "M_H_DQS_DN<6>")
	)
	(segment
		(start 137.599674 -14.157706)
		(end 137.599674 -13.065252)
		(width 0.14224)
		(layer "In4.Cu")
		(net "M_H_DQS_DN<6>")
	)
	(segment
		(start 138.534648 -26.847292)
		(end 138.534648 -15.263368)
		(width 0.14224)
		(layer "In4.Cu")
		(net "M_H_DQS_DN<6>")
	)
	(segment
		(start 138.269218 -11.4808)
		(end 138.091418 -11.303)
		(width 0.14224)
		(layer "In4.Cu")
		(net "M_H_DQS_DN<6>")
	)
	(segment
		(start 138.091418 -11.303)
		(end 138.091418 -11.049)
		(width 0.14224)
		(layer "In4.Cu")
		(net "M_H_DQS_DN<6>")
	)
	(segment
		(start 138.319256 -8.419846)
		(end 138.03757 -8.419846)
		(width 0.14224)
		(layer "In4.Cu")
		(net "M_H_DQS_DN<6>")
	)
	(segment
		(start 137.599674 -13.065252)
		(end 138.03757 -12.627356)
		(width 0.14224)
		(layer "In4.Cu")
		(net "M_H_DQS_DN<6>")
	)
	(segment
		(start 138.579098 -8.679688)
		(end 138.319256 -8.419846)
		(width 0.14224)
		(layer "In4.Cu")
		(net "M_H_DQS_DN<6>")
	)
	(segment
		(start 138.052048 -14.780768)
		(end 138.052048 -14.61008)
		(width 0.14224)
		(layer "In4.Cu")
		(net "M_H_DQS_DN<6>")
	)
	(segment
		(start 138.396218 -10.8712)
		(end 138.579098 -10.68832)
		(width 0.14224)
		(layer "In4.Cu")
		(net "M_H_DQS_DN<6>")
	)
	(segment
		(start 138.052048 -14.61008)
		(end 137.599674 -14.157706)
		(width 0.14224)
		(layer "In4.Cu")
		(net "M_H_DQS_DN<6>")
	)
	(segment
		(start 138.196828 -10.1346)
		(end 138.044174 -9.981946)
		(width 0.14224)
		(layer "In4.Cu")
		(net "M_H_DQS_DN<6>")
	)
	(segment
		(start 138.579098 -10.68832)
		(end 138.579098 -10.339578)
		(width 0.14224)
		(layer "In4.Cu")
		(net "M_H_DQS_DN<6>")
	)
	(segment
		(start 128.471676 -8.2042)
		(end 128.687322 -8.419846)
		(width 0.1651)
		(layer "F.Cu")
		(net "M_H_DQS_DN<5>")
	)
	(segment
		(start 113.898172 -52.837334)
		(end 113.930938 -52.837334)
		(width 0.0889)
		(layer "F.Cu")
		(net "M_H_DQS_DN<5>")
	)
	(segment
		(start 128.29921 -9.34847)
		(end 127.912622 -8.961882)
		(width 0.1651)
		(layer "F.Cu")
		(net "M_H_DQS_DN<5>")
	)
	(segment
		(start 127.912622 -8.539226)
		(end 128.247648 -8.2042)
		(width 0.1651)
		(layer "F.Cu")
		(net "M_H_DQS_DN<5>")
	)
	(segment
		(start 114.296952 -51.533044)
		(end 114.296952 -49.70653)
		(width 0.0889)
		(layer "F.Cu")
		(net "M_H_DQS_DN<5>")
	)
	(segment
		(start 119.050816 -41.0718)
		(end 119.050816 -40.738552)
		(width 0.1651)
		(layer "F.Cu")
		(net "M_H_DQS_DN<5>")
	)
	(segment
		(start 114.197892 -47.683166)
		(end 119.000016 -42.881042)
		(width 0.1016)
		(layer "F.Cu")
		(net "M_H_DQS_DN<5>")
	)
	(segment
		(start 128.232916 -32.15894)
		(end 128.232916 -29.25572)
		(width 0.1651)
		(layer "F.Cu")
		(net "M_H_DQS_DN<5>")
	)
	(segment
		(start 114.266472 -52.237386)
		(end 114.266472 -52.23764)
		(width 0.0889)
		(layer "F.Cu")
		(net "M_H_DQS_DN<5>")
	)
	(segment
		(start 114.296952 -49.70653)
		(end 114.197892 -49.60747)
		(width 0.0889)
		(layer "F.Cu")
		(net "M_H_DQS_DN<5>")
	)
	(segment
		(start 119.050816 -41.246552)
		(end 119.050816 -41.0718)
		(width 0.1016)
		(layer "F.Cu")
		(net "M_H_DQS_DN<5>")
	)
	(segment
		(start 128.299464 -10.422382)
		(end 128.29921 -10.422128)
		(width 0.1651)
		(layer "F.Cu")
		(net "M_H_DQS_DN<5>")
	)
	(segment
		(start 119.000016 -42.881042)
		(end 119.000016 -41.297352)
		(width 0.1016)
		(layer "F.Cu")
		(net "M_H_DQS_DN<5>")
	)
	(segment
		(start 128.29921 -10.422128)
		(end 128.29921 -9.34847)
		(width 0.1651)
		(layer "F.Cu")
		(net "M_H_DQS_DN<5>")
	)
	(segment
		(start 127.912622 -8.961882)
		(end 127.912622 -8.539226)
		(width 0.1651)
		(layer "F.Cu")
		(net "M_H_DQS_DN<5>")
	)
	(segment
		(start 128.232916 -29.25572)
		(end 128.23825 -29.250386)
		(width 0.1651)
		(layer "F.Cu")
		(net "M_H_DQS_DN<5>")
	)
	(segment
		(start 113.919762 -54.418738)
		(end 113.45037 -53.788056)
		(width 0.0889)
		(layer "F.Cu")
		(net "M_H_DQS_DN<5>")
	)
	(segment
		(start 119.000016 -41.297352)
		(end 119.050816 -41.246552)
		(width 0.1016)
		(layer "F.Cu")
		(net "M_H_DQS_DN<5>")
	)
	(segment
		(start 122.418856 -37.973)
		(end 128.232916 -32.15894)
		(width 0.1651)
		(layer "F.Cu")
		(net "M_H_DQS_DN<5>")
	)
	(segment
		(start 114.197892 -49.60747)
		(end 114.197892 -47.683166)
		(width 0.1016)
		(layer "F.Cu")
		(net "M_H_DQS_DN<5>")
	)
	(segment
		(start 121.816368 -37.973)
		(end 122.418856 -37.973)
		(width 0.1651)
		(layer "F.Cu")
		(net "M_H_DQS_DN<5>")
	)
	(segment
		(start 128.23825 -29.250386)
		(end 128.23825 -27.793696)
		(width 0.1651)
		(layer "F.Cu")
		(net "M_H_DQS_DN<5>")
	)
	(segment
		(start 119.050816 -40.738552)
		(end 121.816368 -37.973)
		(width 0.1651)
		(layer "F.Cu")
		(net "M_H_DQS_DN<5>")
	)
	(segment
		(start 128.247648 -8.2042)
		(end 128.471676 -8.2042)
		(width 0.1651)
		(layer "F.Cu")
		(net "M_H_DQS_DN<5>")
	)
	(segment
		(start 128.23825 -27.793696)
		(end 128.687576 -27.34437)
		(width 0.1651)
		(layer "F.Cu")
		(net "M_H_DQS_DN<5>")
	)
	(via
		(at 128.687322 -12.627356)
		(size 0.508)
		(drill 0.254)
		(layers "F.Cu" "B.Cu")
		(net "M_H_DQS_DN<5>")
	)
	(via
		(at 128.687322 -8.419846)
		(size 0.508)
		(drill 0.254)
		(layers "F.Cu" "B.Cu")
		(net "M_H_DQS_DN<5>")
	)
	(via
		(at 128.687576 -27.34437)
		(size 0.508)
		(drill 0.254)
		(layers "F.Cu" "B.Cu")
		(net "M_H_DQS_DN<5>")
	)
	(arc
		(start 113.930938 -52.837334)
		(mid 114.269053 -52.632632)
		(end 114.266472 -52.237386)
		(width 0.0889)
		(layer "F.Cu")
		(net "M_H_DQS_DN<5>")
	)
	(arc
		(start 114.266472 -52.23764)
		(mid 114.187341 -51.942238)
		(end 114.266472 -51.646836)
		(width 0.0889)
		(layer "F.Cu")
		(net "M_H_DQS_DN<5>")
	)
	(arc
		(start 114.266472 -51.646836)
		(mid 114.289207 -51.591947)
		(end 114.296952 -51.533044)
		(width 0.0889)
		(layer "F.Cu")
		(net "M_H_DQS_DN<5>")
	)
	(arc
		(start 113.45037 -53.788056)
		(mid 113.384517 -53.176246)
		(end 113.898172 -52.837334)
		(width 0.0889)
		(layer "F.Cu")
		(net "M_H_DQS_DN<5>")
	)
	(segment
		(start 128.171194 -11.658346)
		(end 128.171194 -11.912346)
		(width 0.1651)
		(layer "B.Cu")
		(net "M_H_DQS_DN<5>")
	)
	(segment
		(start 128.299464 -11.530076)
		(end 128.171194 -11.658346)
		(width 0.1651)
		(layer "B.Cu")
		(net "M_H_DQS_DN<5>")
	)
	(segment
		(start 128.462278 -12.8524)
		(end 128.687322 -12.627356)
		(width 0.1651)
		(layer "B.Cu")
		(net "M_H_DQS_DN<5>")
	)
	(segment
		(start 128.171194 -11.912346)
		(end 127.917194 -12.166346)
		(width 0.1651)
		(layer "B.Cu")
		(net "M_H_DQS_DN<5>")
	)
	(segment
		(start 128.299464 -10.623042)
		(end 128.299464 -11.530076)
		(width 0.1651)
		(layer "B.Cu")
		(net "M_H_DQS_DN<5>")
	)
	(segment
		(start 128.272794 -12.8524)
		(end 128.462278 -12.8524)
		(width 0.1651)
		(layer "B.Cu")
		(net "M_H_DQS_DN<5>")
	)
	(segment
		(start 127.917194 -12.4968)
		(end 128.272794 -12.8524)
		(width 0.1651)
		(layer "B.Cu")
		(net "M_H_DQS_DN<5>")
	)
	(segment
		(start 127.917194 -12.166346)
		(end 127.917194 -12.4968)
		(width 0.1651)
		(layer "B.Cu")
		(net "M_H_DQS_DN<5>")
	)
	(segment
		(start 128.741424 -11.303)
		(end 128.919224 -11.4808)
		(width 0.14224)
		(layer "In11.Cu")
		(net "M_H_DQS_DN<5>")
	)
	(segment
		(start 128.702054 -14.61008)
		(end 128.702054 -14.780768)
		(width 0.14224)
		(layer "In11.Cu")
		(net "M_H_DQS_DN<5>")
	)
	(segment
		(start 129.229104 -8.679688)
		(end 129.229104 -9.345422)
		(width 0.14224)
		(layer "In11.Cu")
		(net "M_H_DQS_DN<5>")
	)
	(segment
		(start 129.229104 -10.339578)
		(end 129.229104 -10.68832)
		(width 0.14224)
		(layer "In11.Cu")
		(net "M_H_DQS_DN<5>")
	)
	(segment
		(start 128.69418 -9.981946)
		(end 128.846834 -10.1346)
		(width 0.14224)
		(layer "In11.Cu")
		(net "M_H_DQS_DN<5>")
	)
	(segment
		(start 128.846834 -9.525)
		(end 128.69418 -9.677654)
		(width 0.14224)
		(layer "In11.Cu")
		(net "M_H_DQS_DN<5>")
	)
	(segment
		(start 128.687322 -8.419846)
		(end 128.969262 -8.419846)
		(width 0.14224)
		(layer "In11.Cu")
		(net "M_H_DQS_DN<5>")
	)
	(segment
		(start 128.24968 -14.157706)
		(end 128.702054 -14.61008)
		(width 0.14224)
		(layer "In11.Cu")
		(net "M_H_DQS_DN<5>")
	)
	(segment
		(start 128.69418 -9.677654)
		(end 128.69418 -9.981946)
		(width 0.14224)
		(layer "In11.Cu")
		(net "M_H_DQS_DN<5>")
	)
	(segment
		(start 129.229104 -9.345422)
		(end 129.049526 -9.525)
		(width 0.14224)
		(layer "In11.Cu")
		(net "M_H_DQS_DN<5>")
	)
	(segment
		(start 128.687322 -12.62761)
		(end 128.24968 -13.065252)
		(width 0.14224)
		(layer "In11.Cu")
		(net "M_H_DQS_DN<5>")
	)
	(segment
		(start 129.229104 -11.660124)
		(end 129.229104 -12.364974)
		(width 0.14224)
		(layer "In11.Cu")
		(net "M_H_DQS_DN<5>")
	)
	(segment
		(start 129.184654 -15.263368)
		(end 129.184654 -26.847292)
		(width 0.14224)
		(layer "In11.Cu")
		(net "M_H_DQS_DN<5>")
	)
	(segment
		(start 128.24968 -13.065252)
		(end 128.24968 -14.157706)
		(width 0.14224)
		(layer "In11.Cu")
		(net "M_H_DQS_DN<5>")
	)
	(segment
		(start 128.969262 -8.419846)
		(end 129.229104 -8.679688)
		(width 0.14224)
		(layer "In11.Cu")
		(net "M_H_DQS_DN<5>")
	)
	(segment
		(start 128.702054 -14.780768)
		(end 129.184654 -15.263368)
		(width 0.14224)
		(layer "In11.Cu")
		(net "M_H_DQS_DN<5>")
	)
	(segment
		(start 128.966468 -12.62761)
		(end 128.687322 -12.62761)
		(width 0.14224)
		(layer "In11.Cu")
		(net "M_H_DQS_DN<5>")
	)
	(segment
		(start 129.229104 -12.364974)
		(end 128.966468 -12.62761)
		(width 0.14224)
		(layer "In11.Cu")
		(net "M_H_DQS_DN<5>")
	)
	(segment
		(start 128.846834 -10.1346)
		(end 129.024126 -10.1346)
		(width 0.14224)
		(layer "In11.Cu")
		(net "M_H_DQS_DN<5>")
	)
	(segment
		(start 129.184654 -26.847292)
		(end 128.687576 -27.34437)
		(width 0.14224)
		(layer "In11.Cu")
		(net "M_H_DQS_DN<5>")
	)
	(segment
		(start 128.687322 -12.627356)
		(end 128.687322 -12.62761)
		(width 0.14224)
		(layer "In11.Cu")
		(net "M_H_DQS_DN<5>")
	)
	(segment
		(start 129.046224 -10.8712)
		(end 128.919224 -10.8712)
		(width 0.14224)
		(layer "In11.Cu")
		(net "M_H_DQS_DN<5>")
	)
	(segment
		(start 129.229104 -10.68832)
		(end 129.046224 -10.8712)
		(width 0.14224)
		(layer "In11.Cu")
		(net "M_H_DQS_DN<5>")
	)
	(segment
		(start 129.024126 -10.1346)
		(end 129.229104 -10.339578)
		(width 0.14224)
		(layer "In11.Cu")
		(net "M_H_DQS_DN<5>")
	)
	(segment
		(start 128.919224 -11.4808)
		(end 129.04978 -11.4808)
		(width 0.14224)
		(layer "In11.Cu")
		(net "M_H_DQS_DN<5>")
	)
	(segment
		(start 129.04978 -11.4808)
		(end 129.229104 -11.660124)
		(width 0.14224)
		(layer "In11.Cu")
		(net "M_H_DQS_DN<5>")
	)
	(segment
		(start 128.741424 -11.049)
		(end 128.741424 -11.303)
		(width 0.14224)
		(layer "In11.Cu")
		(net "M_H_DQS_DN<5>")
	)
	(segment
		(start 129.049526 -9.525)
		(end 128.846834 -9.525)
		(width 0.14224)
		(layer "In11.Cu")
		(net "M_H_DQS_DN<5>")
	)
	(segment
		(start 128.919224 -10.8712)
		(end 128.741424 -11.049)
		(width 0.14224)
		(layer "In11.Cu")
		(net "M_H_DQS_DN<5>")
	)
	(segment
		(start 118.949216 -9.34847)
		(end 118.5672 -8.966454)
		(width 0.1651)
		(layer "F.Cu")
		(net "M_H_DQS_DN<4>")
	)
	(segment
		(start 119.121682 -8.2042)
		(end 119.337328 -8.419846)
		(width 0.1651)
		(layer "F.Cu")
		(net "M_H_DQS_DN<4>")
	)
	(segment
		(start 118.5672 -8.534654)
		(end 118.897654 -8.2042)
		(width 0.1651)
		(layer "F.Cu")
		(net "M_H_DQS_DN<4>")
	)
	(segment
		(start 118.94947 -10.422382)
		(end 118.949216 -10.422128)
		(width 0.1651)
		(layer "F.Cu")
		(net "M_H_DQS_DN<4>")
	)
	(segment
		(start 118.949216 -10.422128)
		(end 118.949216 -9.34847)
		(width 0.1651)
		(layer "F.Cu")
		(net "M_H_DQS_DN<4>")
	)
	(segment
		(start 118.897654 -8.2042)
		(end 119.121682 -8.2042)
		(width 0.1651)
		(layer "F.Cu")
		(net "M_H_DQS_DN<4>")
	)
	(segment
		(start 118.5672 -8.966454)
		(end 118.5672 -8.534654)
		(width 0.1651)
		(layer "F.Cu")
		(net "M_H_DQS_DN<4>")
	)
	(segment
		(start 107.051856 -57.390538)
		(end 106.480356 -57.390538)
		(width 0.1016)
		(layer "F.Cu")
		(net "M_H_DQS_DN<4>")
	)
	(via
		(at 119.337328 -12.627356)
		(size 0.508)
		(drill 0.254)
		(layers "F.Cu" "B.Cu")
		(net "M_H_DQS_DN<4>")
	)
	(via
		(at 106.480356 -57.390538)
		(size 0.508)
		(drill 0.254)
		(layers "F.Cu" "B.Cu")
		(net "M_H_DQS_DN<4>")
	)
	(via
		(at 119.337328 -8.419846)
		(size 0.508)
		(drill 0.254)
		(layers "F.Cu" "B.Cu")
		(net "M_H_DQS_DN<4>")
	)
	(segment
		(start 118.94947 -11.530076)
		(end 118.8212 -11.658346)
		(width 0.1651)
		(layer "B.Cu")
		(net "M_H_DQS_DN<4>")
	)
	(segment
		(start 118.8212 -11.658346)
		(end 118.8212 -11.912346)
		(width 0.1651)
		(layer "B.Cu")
		(net "M_H_DQS_DN<4>")
	)
	(segment
		(start 118.8212 -11.912346)
		(end 118.5672 -12.166346)
		(width 0.1651)
		(layer "B.Cu")
		(net "M_H_DQS_DN<4>")
	)
	(segment
		(start 118.5672 -12.4968)
		(end 118.9228 -12.8524)
		(width 0.1651)
		(layer "B.Cu")
		(net "M_H_DQS_DN<4>")
	)
	(segment
		(start 119.112284 -12.8524)
		(end 119.337328 -12.627356)
		(width 0.1651)
		(layer "B.Cu")
		(net "M_H_DQS_DN<4>")
	)
	(segment
		(start 118.94947 -10.623042)
		(end 118.94947 -11.530076)
		(width 0.1651)
		(layer "B.Cu")
		(net "M_H_DQS_DN<4>")
	)
	(segment
		(start 118.5672 -12.166346)
		(end 118.5672 -12.4968)
		(width 0.1651)
		(layer "B.Cu")
		(net "M_H_DQS_DN<4>")
	)
	(segment
		(start 118.9228 -12.8524)
		(end 119.112284 -12.8524)
		(width 0.1651)
		(layer "B.Cu")
		(net "M_H_DQS_DN<4>")
	)
	(segment
		(start 109.615986 -44.61637)
		(end 109.742986 -44.48937)
		(width 0.14224)
		(layer "In4.Cu")
		(net "M_H_DQS_DN<4>")
	)
	(segment
		(start 107.738926 -54.899306)
		(end 107.738926 -53.033168)
		(width 0.0889)
		(layer "In4.Cu")
		(net "M_H_DQS_DN<4>")
	)
	(segment
		(start 107.738926 -53.033168)
		(end 107.562904 -52.857146)
		(width 0.0889)
		(layer "In4.Cu")
		(net "M_H_DQS_DN<4>")
	)
	(segment
		(start 109.742986 -45.59173)
		(end 109.742986 -44.99737)
		(width 0.14224)
		(layer "In4.Cu")
		(net "M_H_DQS_DN<4>")
	)
	(segment
		(start 108.560108 -49.090834)
		(end 108.560108 -47.729648)
		(width 0.0889)
		(layer "In4.Cu")
		(net "M_H_DQS_DN<4>")
	)
	(segment
		(start 106.480356 -57.728612)
		(end 106.538268 -57.786524)
		(width 0.0889)
		(layer "In4.Cu")
		(net "M_H_DQS_DN<4>")
	)
	(segment
		(start 119.850662 -16.051276)
		(end 118.891812 -15.092426)
		(width 0.14224)
		(layer "In4.Cu")
		(net "M_H_DQS_DN<4>")
	)
	(segment
		(start 109.742986 -44.99737)
		(end 109.615986 -44.87037)
		(width 0.14224)
		(layer "In4.Cu")
		(net "M_H_DQS_DN<4>")
	)
	(segment
		(start 119.496586 -9.525)
		(end 119.699278 -9.525)
		(width 0.14224)
		(layer "In4.Cu")
		(net "M_H_DQS_DN<4>")
	)
	(segment
		(start 107.317286 -55.314088)
		(end 107.350052 -55.314088)
		(width 0.0889)
		(layer "In4.Cu")
		(net "M_H_DQS_DN<4>")
	)
	(segment
		(start 119.878856 -11.660124)
		(end 119.699532 -11.4808)
		(width 0.14224)
		(layer "In4.Cu")
		(net "M_H_DQS_DN<4>")
	)
	(segment
		(start 119.619014 -8.419846)
		(end 119.337328 -8.419846)
		(width 0.14224)
		(layer "In4.Cu")
		(net "M_H_DQS_DN<4>")
	)
	(segment
		(start 106.480356 -57.390538)
		(end 106.480356 -57.728612)
		(width 0.0889)
		(layer "In4.Cu")
		(net "M_H_DQS_DN<4>")
	)
	(segment
		(start 119.496586 -10.1346)
		(end 119.343932 -9.981946)
		(width 0.14224)
		(layer "In4.Cu")
		(net "M_H_DQS_DN<4>")
	)
	(segment
		(start 119.878856 -9.345422)
		(end 119.878856 -8.679688)
		(width 0.14224)
		(layer "In4.Cu")
		(net "M_H_DQS_DN<4>")
	)
	(segment
		(start 119.878856 -10.339578)
		(end 119.673878 -10.1346)
		(width 0.14224)
		(layer "In4.Cu")
		(net "M_H_DQS_DN<4>")
	)
	(segment
		(start 119.391176 -11.049)
		(end 119.568976 -10.8712)
		(width 0.14224)
		(layer "In4.Cu")
		(net "M_H_DQS_DN<4>")
	)
	(segment
		(start 119.878856 -10.68832)
		(end 119.878856 -10.339578)
		(width 0.14224)
		(layer "In4.Cu")
		(net "M_H_DQS_DN<4>")
	)
	(segment
		(start 108.277152 -51.391566)
		(end 108.277152 -49.37379)
		(width 0.0889)
		(layer "In4.Cu")
		(net "M_H_DQS_DN<4>")
	)
	(segment
		(start 119.343932 -9.981946)
		(end 119.343932 -9.677654)
		(width 0.14224)
		(layer "In4.Cu")
		(net "M_H_DQS_DN<4>")
	)
	(segment
		(start 109.742986 -45.613828)
		(end 109.742986 -45.59173)
		(width 0.0889)
		(layer "In4.Cu")
		(net "M_H_DQS_DN<4>")
	)
	(segment
		(start 115.293648 -32.159448)
		(end 115.293648 -31.286196)
		(width 0.14224)
		(layer "In4.Cu")
		(net "M_H_DQS_DN<4>")
	)
	(segment
		(start 109.615986 -43.791124)
		(end 109.742986 -43.664124)
		(width 0.14224)
		(layer "In4.Cu")
		(net "M_H_DQS_DN<4>")
	)
	(segment
		(start 119.673878 -10.1346)
		(end 119.496586 -10.1346)
		(width 0.14224)
		(layer "In4.Cu")
		(net "M_H_DQS_DN<4>")
	)
	(segment
		(start 109.782356 -46.5074)
		(end 109.782356 -45.653198)
		(width 0.0889)
		(layer "In4.Cu")
		(net "M_H_DQS_DN<4>")
	)
	(segment
		(start 119.699532 -11.4808)
		(end 119.568976 -11.4808)
		(width 0.14224)
		(layer "In4.Cu")
		(net "M_H_DQS_DN<4>")
	)
	(segment
		(start 109.615986 -44.045124)
		(end 109.615986 -43.791124)
		(width 0.14224)
		(layer "In4.Cu")
		(net "M_H_DQS_DN<4>")
	)
	(segment
		(start 119.343932 -9.677654)
		(end 119.496586 -9.525)
		(width 0.14224)
		(layer "In4.Cu")
		(net "M_H_DQS_DN<4>")
	)
	(segment
		(start 107.562904 -52.857146)
		(end 107.562904 -52.105814)
		(width 0.0889)
		(layer "In4.Cu")
		(net "M_H_DQS_DN<4>")
	)
	(segment
		(start 119.337328 -12.627356)
		(end 119.337328 -12.62761)
		(width 0.14224)
		(layer "In4.Cu")
		(net "M_H_DQS_DN<4>")
	)
	(segment
		(start 108.277152 -49.37379)
		(end 108.560108 -49.090834)
		(width 0.0889)
		(layer "In4.Cu")
		(net "M_H_DQS_DN<4>")
	)
	(segment
		(start 115.293648 -31.286196)
		(end 119.850662 -26.729182)
		(width 0.14224)
		(layer "In4.Cu")
		(net "M_H_DQS_DN<4>")
	)
	(segment
		(start 119.699278 -9.525)
		(end 119.878856 -9.345422)
		(width 0.14224)
		(layer "In4.Cu")
		(net "M_H_DQS_DN<4>")
	)
	(segment
		(start 119.61622 -12.62761)
		(end 119.878856 -12.364974)
		(width 0.14224)
		(layer "In4.Cu")
		(net "M_H_DQS_DN<4>")
	)
	(segment
		(start 109.742986 -37.71011)
		(end 115.293648 -32.159448)
		(width 0.14224)
		(layer "In4.Cu")
		(net "M_H_DQS_DN<4>")
	)
	(segment
		(start 109.615986 -44.87037)
		(end 109.615986 -44.61637)
		(width 0.14224)
		(layer "In4.Cu")
		(net "M_H_DQS_DN<4>")
	)
	(segment
		(start 119.850662 -26.729182)
		(end 119.850662 -16.051276)
		(width 0.14224)
		(layer "In4.Cu")
		(net "M_H_DQS_DN<4>")
	)
	(segment
		(start 107.562904 -52.105814)
		(end 108.277152 -51.391566)
		(width 0.0889)
		(layer "In4.Cu")
		(net "M_H_DQS_DN<4>")
	)
	(segment
		(start 119.878856 -8.679688)
		(end 119.619014 -8.419846)
		(width 0.14224)
		(layer "In4.Cu")
		(net "M_H_DQS_DN<4>")
	)
	(segment
		(start 109.742986 -44.48937)
		(end 109.742986 -44.172124)
		(width 0.14224)
		(layer "In4.Cu")
		(net "M_H_DQS_DN<4>")
	)
	(segment
		(start 119.568976 -11.4808)
		(end 119.391176 -11.303)
		(width 0.14224)
		(layer "In4.Cu")
		(net "M_H_DQS_DN<4>")
	)
	(segment
		(start 119.391176 -11.303)
		(end 119.391176 -11.049)
		(width 0.14224)
		(layer "In4.Cu")
		(net "M_H_DQS_DN<4>")
	)
	(segment
		(start 109.742986 -43.664124)
		(end 109.742986 -37.71011)
		(width 0.14224)
		(layer "In4.Cu")
		(net "M_H_DQS_DN<4>")
	)
	(segment
		(start 109.742986 -44.172124)
		(end 109.615986 -44.045124)
		(width 0.14224)
		(layer "In4.Cu")
		(net "M_H_DQS_DN<4>")
	)
	(segment
		(start 119.337328 -12.62761)
		(end 119.61622 -12.62761)
		(width 0.14224)
		(layer "In4.Cu")
		(net "M_H_DQS_DN<4>")
	)
	(segment
		(start 109.782356 -45.653198)
		(end 109.742986 -45.613828)
		(width 0.0889)
		(layer "In4.Cu")
		(net "M_H_DQS_DN<4>")
	)
	(segment
		(start 119.878856 -12.364974)
		(end 119.878856 -11.660124)
		(width 0.14224)
		(layer "In4.Cu")
		(net "M_H_DQS_DN<4>")
	)
	(segment
		(start 119.695976 -10.8712)
		(end 119.878856 -10.68832)
		(width 0.14224)
		(layer "In4.Cu")
		(net "M_H_DQS_DN<4>")
	)
	(segment
		(start 119.568976 -10.8712)
		(end 119.695976 -10.8712)
		(width 0.14224)
		(layer "In4.Cu")
		(net "M_H_DQS_DN<4>")
	)
	(segment
		(start 108.560108 -47.729648)
		(end 109.782356 -46.5074)
		(width 0.0889)
		(layer "In4.Cu")
		(net "M_H_DQS_DN<4>")
	)
	(segment
		(start 118.891812 -13.072872)
		(end 119.337328 -12.627356)
		(width 0.14224)
		(layer "In4.Cu")
		(net "M_H_DQS_DN<4>")
	)
	(segment
		(start 118.891812 -15.092426)
		(end 118.891812 -13.072872)
		(width 0.14224)
		(layer "In4.Cu")
		(net "M_H_DQS_DN<4>")
	)
	(arc
		(start 107.350052 -55.314088)
		(mid 107.630875 -55.18772)
		(end 107.738926 -54.899306)
		(width 0.0889)
		(layer "In4.Cu")
		(net "M_H_DQS_DN<4>")
	)
	(arc
		(start 106.657648 -57.749186)
		(mid 106.863226 -57.506605)
		(end 106.827066 -57.19064)
		(width 0.0889)
		(layer "In4.Cu")
		(net "M_H_DQS_DN<4>")
	)
	(arc
		(start 106.827066 -56.599836)
		(mid 106.880565 -56.399938)
		(end 106.827066 -56.20004)
		(width 0.0889)
		(layer "In4.Cu")
		(net "M_H_DQS_DN<4>")
	)
	(arc
		(start 106.827066 -56.20004)
		(mid 106.821812 -55.618532)
		(end 107.317286 -55.314088)
		(width 0.0889)
		(layer "In4.Cu")
		(net "M_H_DQS_DN<4>")
	)
	(arc
		(start 106.827066 -57.19064)
		(mid 106.747935 -56.895238)
		(end 106.827066 -56.599836)
		(width 0.0889)
		(layer "In4.Cu")
		(net "M_H_DQS_DN<4>")
	)
	(arc
		(start 106.538268 -57.786524)
		(mid 106.599434 -57.772569)
		(end 106.657648 -57.749186)
		(width 0.0889)
		(layer "In4.Cu")
		(net "M_H_DQS_DN<4>")
	)
	(segment
		(start 79.156814 -49.718722)
		(end 78.950312 -49.415954)
		(width 0.0889)
		(layer "F.Cu")
		(net "M_H_DQS_DN<3>")
	)
	(segment
		(start 68.800218 -47.15129)
		(end 67.519042 -45.870114)
		(width 0.1016)
		(layer "F.Cu")
		(net "M_H_DQS_DN<3>")
	)
	(segment
		(start 63.69939 -9.34847)
		(end 63.300356 -8.949436)
		(width 0.1651)
		(layer "F.Cu")
		(net "M_H_DQS_DN<3>")
	)
	(segment
		(start 79.260446 -50.345086)
		(end 79.2734 -50.319178)
		(width 0.0889)
		(layer "F.Cu")
		(net "M_H_DQS_DN<3>")
	)
	(segment
		(start 63.638176 -29.064712)
		(end 63.638176 -27.793696)
		(width 0.1651)
		(layer "F.Cu")
		(net "M_H_DQS_DN<3>")
	)
	(segment
		(start 73.172828 -47.68469)
		(end 72.639428 -47.15129)
		(width 0.1016)
		(layer "F.Cu")
		(net "M_H_DQS_DN<3>")
	)
	(segment
		(start 72.639428 -47.15129)
		(end 68.800218 -47.15129)
		(width 0.1016)
		(layer "F.Cu")
		(net "M_H_DQS_DN<3>")
	)
	(segment
		(start 64.163448 -32.886904)
		(end 63.624968 -32.348424)
		(width 0.1651)
		(layer "F.Cu")
		(net "M_H_DQS_DN<3>")
	)
	(segment
		(start 78.673452 -49.197514)
		(end 77.160628 -47.68469)
		(width 0.1016)
		(layer "F.Cu")
		(net "M_H_DQS_DN<3>")
	)
	(segment
		(start 63.300356 -8.949436)
		(end 63.300356 -8.551672)
		(width 0.1651)
		(layer "F.Cu")
		(net "M_H_DQS_DN<3>")
	)
	(segment
		(start 78.909672 -53.113686)
		(end 78.909672 -52.782216)
		(width 0.0889)
		(layer "F.Cu")
		(net "M_H_DQS_DN<3>")
	)
	(segment
		(start 64.163448 -42.61358)
		(end 64.163448 -34.417)
		(width 0.1651)
		(layer "F.Cu")
		(net "M_H_DQS_DN<3>")
	)
	(segment
		(start 78.950312 -49.415954)
		(end 78.731872 -49.197514)
		(width 0.0889)
		(layer "F.Cu")
		(net "M_H_DQS_DN<3>")
	)
	(segment
		(start 67.519042 -45.870114)
		(end 67.419982 -45.870114)
		(width 0.1016)
		(layer "F.Cu")
		(net "M_H_DQS_DN<3>")
	)
	(segment
		(start 79.266542 -49.920144)
		(end 79.156814 -49.718722)
		(width 0.0889)
		(layer "F.Cu")
		(net "M_H_DQS_DN<3>")
	)
	(segment
		(start 78.909672 -52.782216)
		(end 78.837028 -52.709572)
		(width 0.0889)
		(layer "F.Cu")
		(net "M_H_DQS_DN<3>")
	)
	(segment
		(start 63.69939 -10.422382)
		(end 63.69939 -9.34847)
		(width 0.1651)
		(layer "F.Cu")
		(net "M_H_DQS_DN<3>")
	)
	(segment
		(start 63.647828 -8.2042)
		(end 63.871856 -8.2042)
		(width 0.1651)
		(layer "F.Cu")
		(net "M_H_DQS_DN<3>")
	)
	(segment
		(start 63.638176 -27.793696)
		(end 64.087502 -27.34437)
		(width 0.1651)
		(layer "F.Cu")
		(net "M_H_DQS_DN<3>")
	)
	(segment
		(start 63.624968 -29.07792)
		(end 63.638176 -29.064712)
		(width 0.1651)
		(layer "F.Cu")
		(net "M_H_DQS_DN<3>")
	)
	(segment
		(start 77.160628 -47.68469)
		(end 73.172828 -47.68469)
		(width 0.1016)
		(layer "F.Cu")
		(net "M_H_DQS_DN<3>")
	)
	(segment
		(start 64.163448 -34.417)
		(end 64.163448 -32.886904)
		(width 0.1651)
		(layer "F.Cu")
		(net "M_H_DQS_DN<3>")
	)
	(segment
		(start 67.419982 -45.870114)
		(end 67.273424 -45.723556)
		(width 0.1016)
		(layer "F.Cu")
		(net "M_H_DQS_DN<3>")
	)
	(segment
		(start 78.731872 -49.197514)
		(end 78.673452 -49.197514)
		(width 0.0889)
		(layer "F.Cu")
		(net "M_H_DQS_DN<3>")
	)
	(segment
		(start 63.871856 -8.2042)
		(end 64.087502 -8.419846)
		(width 0.1651)
		(layer "F.Cu")
		(net "M_H_DQS_DN<3>")
	)
	(segment
		(start 67.273424 -45.723556)
		(end 64.163448 -42.61358)
		(width 0.1651)
		(layer "F.Cu")
		(net "M_H_DQS_DN<3>")
	)
	(segment
		(start 63.624968 -32.348424)
		(end 63.624968 -29.07792)
		(width 0.1651)
		(layer "F.Cu")
		(net "M_H_DQS_DN<3>")
	)
	(segment
		(start 63.300356 -8.551672)
		(end 63.647828 -8.2042)
		(width 0.1651)
		(layer "F.Cu")
		(net "M_H_DQS_DN<3>")
	)
	(via
		(at 64.087502 -12.627356)
		(size 0.508)
		(drill 0.254)
		(layers "F.Cu" "B.Cu")
		(net "M_H_DQS_DN<3>")
	)
	(via
		(at 64.163448 -34.417)
		(size 0.508)
		(drill 0.254)
		(layers "F.Cu" "B.Cu")
		(net "M_H_DQS_DN<3>")
	)
	(via
		(at 64.087502 -8.419846)
		(size 0.508)
		(drill 0.254)
		(layers "F.Cu" "B.Cu")
		(net "M_H_DQS_DN<3>")
	)
	(via
		(at 64.087502 -27.34437)
		(size 0.508)
		(drill 0.254)
		(layers "F.Cu" "B.Cu")
		(net "M_H_DQS_DN<3>")
	)
	(arc
		(start 79.256636 -50.932588)
		(mid 79.178738 -50.638309)
		(end 79.260446 -50.345086)
		(width 0.0889)
		(layer "F.Cu")
		(net "M_H_DQS_DN<3>")
	)
	(arc
		(start 78.815946 -52.706524)
		(mid 78.321344 -52.07658)
		(end 78.909672 -51.533298)
		(width 0.0889)
		(layer "F.Cu")
		(net "M_H_DQS_DN<3>")
	)
	(arc
		(start 78.909672 -51.533298)
		(mid 79.256529 -51.333082)
		(end 79.256636 -50.932588)
		(width 0.0889)
		(layer "F.Cu")
		(net "M_H_DQS_DN<3>")
	)
	(arc
		(start 79.2734 -50.319178)
		(mid 79.318935 -50.118809)
		(end 79.266542 -49.920144)
		(width 0.0889)
		(layer "F.Cu")
		(net "M_H_DQS_DN<3>")
	)
	(arc
		(start 78.837028 -52.709572)
		(mid 78.826473 -52.708143)
		(end 78.815946 -52.706524)
		(width 0.0889)
		(layer "F.Cu")
		(net "M_H_DQS_DN<3>")
	)
	(segment
		(start 63.69939 -10.623042)
		(end 63.69939 -11.53033)
		(width 0.1651)
		(layer "B.Cu")
		(net "M_H_DQS_DN<3>")
	)
	(segment
		(start 63.571374 -11.658346)
		(end 63.571374 -11.912346)
		(width 0.1651)
		(layer "B.Cu")
		(net "M_H_DQS_DN<3>")
	)
	(segment
		(start 63.571374 -11.912346)
		(end 63.317374 -12.166346)
		(width 0.1651)
		(layer "B.Cu")
		(net "M_H_DQS_DN<3>")
	)
	(segment
		(start 63.862458 -12.8524)
		(end 64.087502 -12.627356)
		(width 0.1651)
		(layer "B.Cu")
		(net "M_H_DQS_DN<3>")
	)
	(segment
		(start 63.69939 -11.53033)
		(end 63.571374 -11.658346)
		(width 0.1651)
		(layer "B.Cu")
		(net "M_H_DQS_DN<3>")
	)
	(segment
		(start 63.317374 -12.166346)
		(end 63.317374 -12.4968)
		(width 0.1651)
		(layer "B.Cu")
		(net "M_H_DQS_DN<3>")
	)
	(segment
		(start 63.317374 -12.4968)
		(end 63.672974 -12.8524)
		(width 0.1651)
		(layer "B.Cu")
		(net "M_H_DQS_DN<3>")
	)
	(segment
		(start 63.672974 -12.8524)
		(end 63.862458 -12.8524)
		(width 0.1651)
		(layer "B.Cu")
		(net "M_H_DQS_DN<3>")
	)
	(segment
		(start 64.62903 -10.339578)
		(end 64.424052 -10.1346)
		(width 0.14224)
		(layer "In4.Cu")
		(net "M_H_DQS_DN<3>")
	)
	(segment
		(start 64.62903 -8.679688)
		(end 64.369188 -8.419846)
		(width 0.14224)
		(layer "In4.Cu")
		(net "M_H_DQS_DN<3>")
	)
	(segment
		(start 64.44615 -10.8712)
		(end 64.62903 -10.68832)
		(width 0.14224)
		(layer "In4.Cu")
		(net "M_H_DQS_DN<3>")
	)
	(segment
		(start 63.649606 -14.157706)
		(end 63.649606 -13.065252)
		(width 0.14224)
		(layer "In4.Cu")
		(net "M_H_DQS_DN<3>")
	)
	(segment
		(start 64.087502 -12.62761)
		(end 64.366394 -12.62761)
		(width 0.14224)
		(layer "In4.Cu")
		(net "M_H_DQS_DN<3>")
	)
	(segment
		(start 64.424052 -10.1346)
		(end 64.24676 -10.1346)
		(width 0.14224)
		(layer "In4.Cu")
		(net "M_H_DQS_DN<3>")
	)
	(segment
		(start 63.649606 -13.065252)
		(end 64.087502 -12.627356)
		(width 0.14224)
		(layer "In4.Cu")
		(net "M_H_DQS_DN<3>")
	)
	(segment
		(start 64.347598 -27.34437)
		(end 64.58458 -27.107388)
		(width 0.14224)
		(layer "In4.Cu")
		(net "M_H_DQS_DN<3>")
	)
	(segment
		(start 64.58458 -15.263368)
		(end 64.10198 -14.780768)
		(width 0.14224)
		(layer "In4.Cu")
		(net "M_H_DQS_DN<3>")
	)
	(segment
		(start 64.094106 -9.677654)
		(end 64.24676 -9.525)
		(width 0.14224)
		(layer "In4.Cu")
		(net "M_H_DQS_DN<3>")
	)
	(segment
		(start 64.087502 -27.34437)
		(end 64.347598 -27.34437)
		(width 0.14224)
		(layer "In4.Cu")
		(net "M_H_DQS_DN<3>")
	)
	(segment
		(start 64.62903 -9.345422)
		(end 64.62903 -8.679688)
		(width 0.14224)
		(layer "In4.Cu")
		(net "M_H_DQS_DN<3>")
	)
	(segment
		(start 64.087502 -12.627356)
		(end 64.087502 -12.62761)
		(width 0.14224)
		(layer "In4.Cu")
		(net "M_H_DQS_DN<3>")
	)
	(segment
		(start 64.62903 -12.364974)
		(end 64.62903 -11.660124)
		(width 0.14224)
		(layer "In4.Cu")
		(net "M_H_DQS_DN<3>")
	)
	(segment
		(start 64.14135 -11.303)
		(end 64.14135 -11.049)
		(width 0.14224)
		(layer "In4.Cu")
		(net "M_H_DQS_DN<3>")
	)
	(segment
		(start 64.369188 -8.419846)
		(end 64.087502 -8.419846)
		(width 0.14224)
		(layer "In4.Cu")
		(net "M_H_DQS_DN<3>")
	)
	(segment
		(start 64.10198 -14.61008)
		(end 63.649606 -14.157706)
		(width 0.14224)
		(layer "In4.Cu")
		(net "M_H_DQS_DN<3>")
	)
	(segment
		(start 64.10198 -14.780768)
		(end 64.10198 -14.61008)
		(width 0.14224)
		(layer "In4.Cu")
		(net "M_H_DQS_DN<3>")
	)
	(segment
		(start 64.094106 -9.981946)
		(end 64.094106 -9.677654)
		(width 0.14224)
		(layer "In4.Cu")
		(net "M_H_DQS_DN<3>")
	)
	(segment
		(start 64.62903 -10.68832)
		(end 64.62903 -10.339578)
		(width 0.14224)
		(layer "In4.Cu")
		(net "M_H_DQS_DN<3>")
	)
	(segment
		(start 64.58458 -27.107388)
		(end 64.58458 -15.263368)
		(width 0.14224)
		(layer "In4.Cu")
		(net "M_H_DQS_DN<3>")
	)
	(segment
		(start 64.31915 -10.8712)
		(end 64.44615 -10.8712)
		(width 0.14224)
		(layer "In4.Cu")
		(net "M_H_DQS_DN<3>")
	)
	(segment
		(start 64.449452 -9.525)
		(end 64.62903 -9.345422)
		(width 0.14224)
		(layer "In4.Cu")
		(net "M_H_DQS_DN<3>")
	)
	(segment
		(start 64.449706 -11.4808)
		(end 64.31915 -11.4808)
		(width 0.14224)
		(layer "In4.Cu")
		(net "M_H_DQS_DN<3>")
	)
	(segment
		(start 64.62903 -11.660124)
		(end 64.449706 -11.4808)
		(width 0.14224)
		(layer "In4.Cu")
		(net "M_H_DQS_DN<3>")
	)
	(segment
		(start 64.24676 -10.1346)
		(end 64.094106 -9.981946)
		(width 0.14224)
		(layer "In4.Cu")
		(net "M_H_DQS_DN<3>")
	)
	(segment
		(start 64.24676 -9.525)
		(end 64.449452 -9.525)
		(width 0.14224)
		(layer "In4.Cu")
		(net "M_H_DQS_DN<3>")
	)
	(segment
		(start 64.366394 -12.62761)
		(end 64.62903 -12.364974)
		(width 0.14224)
		(layer "In4.Cu")
		(net "M_H_DQS_DN<3>")
	)
	(segment
		(start 64.14135 -11.049)
		(end 64.31915 -10.8712)
		(width 0.14224)
		(layer "In4.Cu")
		(net "M_H_DQS_DN<3>")
	)
	(segment
		(start 64.31915 -11.4808)
		(end 64.14135 -11.303)
		(width 0.14224)
		(layer "In4.Cu")
		(net "M_H_DQS_DN<3>")
	)
	(segment
		(start 54.349396 -9.40943)
		(end 54.083712 -9.143746)
		(width 0.1651)
		(layer "F.Cu")
		(net "M_H_DQS_DN<2>")
	)
	(segment
		(start 54.083712 -8.410956)
		(end 54.737508 -7.75716)
		(width 0.1651)
		(layer "F.Cu")
		(net "M_H_DQS_DN<2>")
	)
	(segment
		(start 73.758806 -54.104286)
		(end 73.187306 -54.104286)
		(width 0.1016)
		(layer "F.Cu")
		(net "M_H_DQS_DN<2>")
	)
	(segment
		(start 54.349396 -10.422382)
		(end 54.349396 -9.40943)
		(width 0.1651)
		(layer "F.Cu")
		(net "M_H_DQS_DN<2>")
	)
	(segment
		(start 54.083712 -9.143746)
		(end 54.083712 -8.410956)
		(width 0.1651)
		(layer "F.Cu")
		(net "M_H_DQS_DN<2>")
	)
	(via
		(at 73.187306 -54.104286)
		(size 0.508)
		(drill 0.254)
		(layers "F.Cu" "B.Cu")
		(net "M_H_DQS_DN<2>")
	)
	(via
		(at 54.737508 -13.287756)
		(size 0.508)
		(drill 0.254)
		(layers "F.Cu" "B.Cu")
		(net "M_H_DQS_DN<2>")
	)
	(via
		(at 54.737508 -7.75716)
		(size 0.508)
		(drill 0.254)
		(layers "F.Cu" "B.Cu")
		(net "M_H_DQS_DN<2>")
	)
	(segment
		(start 54.096412 -12.64666)
		(end 54.737508 -13.287756)
		(width 0.1651)
		(layer "B.Cu")
		(net "M_H_DQS_DN<2>")
	)
	(segment
		(start 54.349396 -10.623042)
		(end 54.349396 -11.52017)
		(width 0.1651)
		(layer "B.Cu")
		(net "M_H_DQS_DN<2>")
	)
	(segment
		(start 54.096412 -11.773154)
		(end 54.096412 -12.64666)
		(width 0.1651)
		(layer "B.Cu")
		(net "M_H_DQS_DN<2>")
	)
	(segment
		(start 54.349396 -11.52017)
		(end 54.096412 -11.773154)
		(width 0.1651)
		(layer "B.Cu")
		(net "M_H_DQS_DN<2>")
	)
	(segment
		(start 54.688232 -14.651736)
		(end 55.201312 -14.138656)
		(width 0.14224)
		(layer "In4.Cu")
		(net "M_H_DQS_DN<2>")
	)
	(segment
		(start 55.519828 -15.712948)
		(end 54.688232 -14.881352)
		(width 0.14224)
		(layer "In4.Cu")
		(net "M_H_DQS_DN<2>")
	)
	(segment
		(start 68.490592 -45.624496)
		(end 68.490592 -45.462952)
		(width 0.14224)
		(layer "In4.Cu")
		(net "M_H_DQS_DN<2>")
	)
	(segment
		(start 73.699116 -52.418488)
		(end 73.705466 -52.40782)
		(width 0.0889)
		(layer "In4.Cu")
		(net "M_H_DQS_DN<2>")
	)
	(segment
		(start 68.490592 -45.462952)
		(end 68.248022 -45.220382)
		(width 0.14224)
		(layer "In4.Cu")
		(net "M_H_DQS_DN<2>")
	)
	(segment
		(start 71.2089 -48.83404)
		(end 69.489574 -47.114714)
		(width 0.0889)
		(layer "In4.Cu")
		(net "M_H_DQS_DN<2>")
	)
	(segment
		(start 73.187306 -53.766212)
		(end 73.25233 -53.701188)
		(width 0.0889)
		(layer "In4.Cu")
		(net "M_H_DQS_DN<2>")
	)
	(segment
		(start 67.844416 -44.97832)
		(end 67.844416 -44.816776)
		(width 0.14224)
		(layer "In4.Cu")
		(net "M_H_DQS_DN<2>")
	)
	(segment
		(start 55.548276 -12.476988)
		(end 55.548276 -8.567928)
		(width 0.14224)
		(layer "In4.Cu")
		(net "M_H_DQS_DN<2>")
	)
	(segment
		(start 55.519828 -29.275532)
		(end 55.519828 -15.712948)
		(width 0.14224)
		(layer "In4.Cu")
		(net "M_H_DQS_DN<2>")
	)
	(segment
		(start 65.397888 -42.531792)
		(end 65.397888 -39.153592)
		(width 0.14224)
		(layer "In4.Cu")
		(net "M_H_DQS_DN<2>")
	)
	(segment
		(start 73.603866 -49.913032)
		(end 72.524874 -48.83404)
		(width 0.0889)
		(layer "In4.Cu")
		(net "M_H_DQS_DN<2>")
	)
	(segment
		(start 69.473826 -47.043086)
		(end 68.732908 -46.302168)
		(width 0.14224)
		(layer "In4.Cu")
		(net "M_H_DQS_DN<2>")
	)
	(segment
		(start 67.440302 -44.574206)
		(end 67.197986 -44.33189)
		(width 0.14224)
		(layer "In4.Cu")
		(net "M_H_DQS_DN<2>")
	)
	(segment
		(start 54.737508 -13.287756)
		(end 55.548276 -12.476988)
		(width 0.14224)
		(layer "In4.Cu")
		(net "M_H_DQS_DN<2>")
	)
	(segment
		(start 68.248022 -45.220382)
		(end 68.086478 -45.220382)
		(width 0.14224)
		(layer "In4.Cu")
		(net "M_H_DQS_DN<2>")
	)
	(segment
		(start 55.201312 -13.75156)
		(end 54.737508 -13.287756)
		(width 0.14224)
		(layer "In4.Cu")
		(net "M_H_DQS_DN<2>")
	)
	(segment
		(start 67.197986 -44.33189)
		(end 67.197986 -44.200318)
		(width 0.14224)
		(layer "In4.Cu")
		(net "M_H_DQS_DN<2>")
	)
	(segment
		(start 66.925444 -43.927776)
		(end 66.793872 -43.927776)
		(width 0.14224)
		(layer "In4.Cu")
		(net "M_H_DQS_DN<2>")
	)
	(segment
		(start 55.201312 -14.138656)
		(end 55.201312 -13.75156)
		(width 0.14224)
		(layer "In4.Cu")
		(net "M_H_DQS_DN<2>")
	)
	(segment
		(start 72.524874 -48.83404)
		(end 71.2089 -48.83404)
		(width 0.0889)
		(layer "In4.Cu")
		(net "M_H_DQS_DN<2>")
	)
	(segment
		(start 69.489574 -47.114714)
		(end 69.489574 -47.058834)
		(width 0.0889)
		(layer "In4.Cu")
		(net "M_H_DQS_DN<2>")
	)
	(segment
		(start 65.397888 -39.153592)
		(end 55.519828 -29.275532)
		(width 0.14224)
		(layer "In4.Cu")
		(net "M_H_DQS_DN<2>")
	)
	(segment
		(start 67.601846 -44.574206)
		(end 67.440302 -44.574206)
		(width 0.14224)
		(layer "In4.Cu")
		(net "M_H_DQS_DN<2>")
	)
	(segment
		(start 68.732908 -46.302168)
		(end 68.732908 -45.866812)
		(width 0.14224)
		(layer "In4.Cu")
		(net "M_H_DQS_DN<2>")
	)
	(segment
		(start 73.603866 -50.672238)
		(end 73.603866 -49.913032)
		(width 0.0889)
		(layer "In4.Cu")
		(net "M_H_DQS_DN<2>")
	)
	(segment
		(start 73.705466 -50.848006)
		(end 73.603866 -50.672238)
		(width 0.0889)
		(layer "In4.Cu")
		(net "M_H_DQS_DN<2>")
	)
	(segment
		(start 68.732908 -45.866812)
		(end 68.490592 -45.624496)
		(width 0.14224)
		(layer "In4.Cu")
		(net "M_H_DQS_DN<2>")
	)
	(segment
		(start 73.699116 -51.827938)
		(end 73.69429 -51.819302)
		(width 0.0889)
		(layer "In4.Cu")
		(net "M_H_DQS_DN<2>")
	)
	(segment
		(start 55.548276 -8.567928)
		(end 54.737508 -7.75716)
		(width 0.14224)
		(layer "In4.Cu")
		(net "M_H_DQS_DN<2>")
	)
	(segment
		(start 67.844416 -44.816776)
		(end 67.601846 -44.574206)
		(width 0.14224)
		(layer "In4.Cu")
		(net "M_H_DQS_DN<2>")
	)
	(segment
		(start 67.197986 -44.200318)
		(end 66.925444 -43.927776)
		(width 0.14224)
		(layer "In4.Cu")
		(net "M_H_DQS_DN<2>")
	)
	(segment
		(start 69.489574 -47.058834)
		(end 69.473826 -47.043086)
		(width 0.0889)
		(layer "In4.Cu")
		(net "M_H_DQS_DN<2>")
	)
	(segment
		(start 68.086478 -45.220382)
		(end 67.844416 -44.97832)
		(width 0.14224)
		(layer "In4.Cu")
		(net "M_H_DQS_DN<2>")
	)
	(segment
		(start 54.688232 -14.881352)
		(end 54.688232 -14.651736)
		(width 0.14224)
		(layer "In4.Cu")
		(net "M_H_DQS_DN<2>")
	)
	(segment
		(start 73.187306 -54.104286)
		(end 73.187306 -53.766212)
		(width 0.0889)
		(layer "In4.Cu")
		(net "M_H_DQS_DN<2>")
	)
	(segment
		(start 66.793872 -43.927776)
		(end 65.397888 -42.531792)
		(width 0.14224)
		(layer "In4.Cu")
		(net "M_H_DQS_DN<2>")
	)
	(arc
		(start 73.69429 -51.819302)
		(mid 73.645535 -51.62295)
		(end 73.699116 -51.427888)
		(width 0.0889)
		(layer "In4.Cu")
		(net "M_H_DQS_DN<2>")
	)
	(arc
		(start 73.699116 -51.427888)
		(mid 73.778338 -51.13877)
		(end 73.705466 -50.848006)
		(width 0.0889)
		(layer "In4.Cu")
		(net "M_H_DQS_DN<2>")
	)
	(arc
		(start 73.705466 -52.40782)
		(mid 73.778264 -52.117057)
		(end 73.699116 -51.827938)
		(width 0.0889)
		(layer "In4.Cu")
		(net "M_H_DQS_DN<2>")
	)
	(arc
		(start 73.699116 -52.818284)
		(mid 73.645617 -52.618386)
		(end 73.699116 -52.418488)
		(width 0.0889)
		(layer "In4.Cu")
		(net "M_H_DQS_DN<2>")
	)
	(arc
		(start 73.25233 -53.701188)
		(mid 73.71469 -53.380618)
		(end 73.699116 -52.818284)
		(width 0.0889)
		(layer "In4.Cu")
		(net "M_H_DQS_DN<2>")
	)
	(segment
		(start 44.999402 -10.422382)
		(end 44.999402 -9.40943)
		(width 0.1651)
		(layer "F.Cu")
		(net "M_H_DQS_DN<1>")
	)
	(segment
		(start 44.999402 -9.40943)
		(end 44.733718 -9.143746)
		(width 0.1651)
		(layer "F.Cu")
		(net "M_H_DQS_DN<1>")
	)
	(segment
		(start 44.733718 -8.410956)
		(end 45.387514 -7.75716)
		(width 0.1651)
		(layer "F.Cu")
		(net "M_H_DQS_DN<1>")
	)
	(segment
		(start 44.733718 -9.143746)
		(end 44.733718 -8.410956)
		(width 0.1651)
		(layer "F.Cu")
		(net "M_H_DQS_DN<1>")
	)
	(segment
		(start 73.758806 -61.038486)
		(end 73.187306 -61.038486)
		(width 0.1016)
		(layer "F.Cu")
		(net "M_H_DQS_DN<1>")
	)
	(via
		(at 45.387514 -13.287756)
		(size 0.508)
		(drill 0.254)
		(layers "F.Cu" "B.Cu")
		(net "M_H_DQS_DN<1>")
	)
	(via
		(at 45.387514 -7.75716)
		(size 0.508)
		(drill 0.254)
		(layers "F.Cu" "B.Cu")
		(net "M_H_DQS_DN<1>")
	)
	(via
		(at 73.187306 -61.038486)
		(size 0.508)
		(drill 0.254)
		(layers "F.Cu" "B.Cu")
		(net "M_H_DQS_DN<1>")
	)
	(segment
		(start 44.746418 -12.64666)
		(end 45.387514 -13.287756)
		(width 0.1651)
		(layer "B.Cu")
		(net "M_H_DQS_DN<1>")
	)
	(segment
		(start 44.746418 -11.773154)
		(end 44.746418 -12.64666)
		(width 0.1651)
		(layer "B.Cu")
		(net "M_H_DQS_DN<1>")
	)
	(segment
		(start 44.999402 -10.623042)
		(end 44.999402 -11.52017)
		(width 0.1651)
		(layer "B.Cu")
		(net "M_H_DQS_DN<1>")
	)
	(segment
		(start 44.999402 -11.52017)
		(end 44.746418 -11.773154)
		(width 0.1651)
		(layer "B.Cu")
		(net "M_H_DQS_DN<1>")
	)
	(segment
		(start 45.98797 -15.30858)
		(end 45.98797 -15.531084)
		(width 0.14224)
		(layer "In4.Cu")
		(net "M_H_DQS_DN<1>")
	)
	(segment
		(start 69.353176 -60.155836)
		(end 69.406516 -60.247784)
		(width 0.0889)
		(layer "In4.Cu")
		(net "M_H_DQS_DN<1>")
	)
	(segment
		(start 68.774564 -57.005728)
		(end 68.774564 -57.167272)
		(width 0.14224)
		(layer "In4.Cu")
		(net "M_H_DQS_DN<1>")
	)
	(segment
		(start 48.490124 -35.576256)
		(end 48.707802 -35.576256)
		(width 0.14224)
		(layer "In4.Cu")
		(net "M_H_DQS_DN<1>")
	)
	(segment
		(start 48.95596 -34.389314)
		(end 48.238664 -35.10661)
		(width 0.14224)
		(layer "In4.Cu")
		(net "M_H_DQS_DN<1>")
	)
	(segment
		(start 46.169834 -19.70532)
		(end 46.327314 -19.8628)
		(width 0.14224)
		(layer "In4.Cu")
		(net "M_H_DQS_DN<1>")
	)
	(segment
		(start 46.327314 -16.081756)
		(end 46.169834 -16.239236)
		(width 0.14224)
		(layer "In4.Cu")
		(net "M_H_DQS_DN<1>")
	)
	(segment
		(start 46.198282 -12.476988)
		(end 46.198282 -8.567928)
		(width 0.14224)
		(layer "In4.Cu")
		(net "M_H_DQS_DN<1>")
	)
	(segment
		(start 46.327314 -19.1008)
		(end 46.327314 -19.3548)
		(width 0.14224)
		(layer "In4.Cu")
		(net "M_H_DQS_DN<1>")
	)
	(segment
		(start 45.851318 -13.75156)
		(end 45.851318 -14.1478)
		(width 0.14224)
		(layer "In4.Cu")
		(net "M_H_DQS_DN<1>")
	)
	(segment
		(start 46.169834 -20.27428)
		(end 46.169834 -23.760938)
		(width 0.14224)
		(layer "In4.Cu")
		(net "M_H_DQS_DN<1>")
	)
	(segment
		(start 45.585634 -15.128748)
		(end 45.808138 -15.128748)
		(width 0.14224)
		(layer "In4.Cu")
		(net "M_H_DQS_DN<1>")
	)
	(segment
		(start 46.169834 -19.51228)
		(end 46.169834 -19.70532)
		(width 0.14224)
		(layer "In4.Cu")
		(net "M_H_DQS_DN<1>")
	)
	(segment
		(start 46.327314 -20.1168)
		(end 46.169834 -20.27428)
		(width 0.14224)
		(layer "In4.Cu")
		(net "M_H_DQS_DN<1>")
	)
	(segment
		(start 46.169834 -23.760938)
		(end 46.449488 -24.040592)
		(width 0.14224)
		(layer "In4.Cu")
		(net "M_H_DQS_DN<1>")
	)
	(segment
		(start 72.310498 -60.94349)
		(end 72.347074 -60.94349)
		(width 0.0889)
		(layer "In4.Cu")
		(net "M_H_DQS_DN<1>")
	)
	(segment
		(start 45.851318 -14.1478)
		(end 45.338238 -14.66088)
		(width 0.14224)
		(layer "In4.Cu")
		(net "M_H_DQS_DN<1>")
	)
	(segment
		(start 51.478688 -36.469574)
		(end 51.478688 -38.621208)
		(width 0.14224)
		(layer "In4.Cu")
		(net "M_H_DQS_DN<1>")
	)
	(segment
		(start 46.169834 -18.94332)
		(end 46.327314 -19.1008)
		(width 0.14224)
		(layer "In4.Cu")
		(net "M_H_DQS_DN<1>")
	)
	(segment
		(start 45.98797 -15.531084)
		(end 46.327314 -15.870428)
		(width 0.14224)
		(layer "In4.Cu")
		(net "M_H_DQS_DN<1>")
	)
	(segment
		(start 46.449488 -31.440374)
		(end 48.95596 -33.946846)
		(width 0.14224)
		(layer "In4.Cu")
		(net "M_H_DQS_DN<1>")
	)
	(segment
		(start 46.327314 -19.3548)
		(end 46.169834 -19.51228)
		(width 0.14224)
		(layer "In4.Cu")
		(net "M_H_DQS_DN<1>")
	)
	(segment
		(start 68.774564 -57.167272)
		(end 69.266562 -57.65927)
		(width 0.14224)
		(layer "In4.Cu")
		(net "M_H_DQS_DN<1>")
	)
	(segment
		(start 68.531994 -56.763158)
		(end 68.774564 -57.005728)
		(width 0.14224)
		(layer "In4.Cu")
		(net "M_H_DQS_DN<1>")
	)
	(segment
		(start 46.327314 -15.870428)
		(end 46.327314 -16.081756)
		(width 0.14224)
		(layer "In4.Cu")
		(net "M_H_DQS_DN<1>")
	)
	(segment
		(start 69.227192 -58.645044)
		(end 69.227192 -58.983118)
		(width 0.0889)
		(layer "In4.Cu")
		(net "M_H_DQS_DN<1>")
	)
	(segment
		(start 51.478688 -38.621208)
		(end 51.021488 -39.078408)
		(width 0.14224)
		(layer "In4.Cu")
		(net "M_H_DQS_DN<1>")
	)
	(segment
		(start 69.7357 -61.438536)
		(end 69.766942 -61.438536)
		(width 0.0889)
		(layer "In4.Cu")
		(net "M_H_DQS_DN<1>")
	)
	(segment
		(start 45.338238 -14.66088)
		(end 45.338238 -14.881352)
		(width 0.14224)
		(layer "In4.Cu")
		(net "M_H_DQS_DN<1>")
	)
	(segment
		(start 51.021488 -39.078408)
		(end 51.021488 -39.414196)
		(width 0.14224)
		(layer "In4.Cu")
		(net "M_H_DQS_DN<1>")
	)
	(segment
		(start 46.449488 -24.040592)
		(end 46.449488 -31.440374)
		(width 0.14224)
		(layer "In4.Cu")
		(net "M_H_DQS_DN<1>")
	)
	(segment
		(start 45.387514 -13.287756)
		(end 46.198282 -12.476988)
		(width 0.14224)
		(layer "In4.Cu")
		(net "M_H_DQS_DN<1>")
	)
	(segment
		(start 46.198282 -8.567928)
		(end 45.387514 -7.75716)
		(width 0.14224)
		(layer "In4.Cu")
		(net "M_H_DQS_DN<1>")
	)
	(segment
		(start 51.021488 -39.414196)
		(end 68.37045 -56.763158)
		(width 0.14224)
		(layer "In4.Cu")
		(net "M_H_DQS_DN<1>")
	)
	(segment
		(start 48.238664 -35.10661)
		(end 48.238664 -35.324796)
		(width 0.14224)
		(layer "In4.Cu")
		(net "M_H_DQS_DN<1>")
	)
	(segment
		(start 48.707802 -35.576256)
		(end 49.425352 -34.858706)
		(width 0.14224)
		(layer "In4.Cu")
		(net "M_H_DQS_DN<1>")
	)
	(segment
		(start 45.338238 -14.881352)
		(end 45.585634 -15.128748)
		(width 0.14224)
		(layer "In4.Cu")
		(net "M_H_DQS_DN<1>")
	)
	(segment
		(start 45.808138 -15.128748)
		(end 45.98797 -15.30858)
		(width 0.14224)
		(layer "In4.Cu")
		(net "M_H_DQS_DN<1>")
	)
	(segment
		(start 72.89419 -61.20765)
		(end 73.187306 -61.038486)
		(width 0.0889)
		(layer "In4.Cu")
		(net "M_H_DQS_DN<1>")
	)
	(segment
		(start 68.37045 -56.763158)
		(end 68.531994 -56.763158)
		(width 0.14224)
		(layer "In4.Cu")
		(net "M_H_DQS_DN<1>")
	)
	(segment
		(start 70.610984 -61.933836)
		(end 70.612508 -61.933836)
		(width 0.0889)
		(layer "In4.Cu")
		(net "M_H_DQS_DN<1>")
	)
	(segment
		(start 48.238664 -35.324796)
		(end 48.490124 -35.576256)
		(width 0.14224)
		(layer "In4.Cu")
		(net "M_H_DQS_DN<1>")
	)
	(segment
		(start 46.327314 -19.8628)
		(end 46.327314 -20.1168)
		(width 0.14224)
		(layer "In4.Cu")
		(net "M_H_DQS_DN<1>")
	)
	(segment
		(start 69.266562 -58.605674)
		(end 69.227192 -58.645044)
		(width 0.0889)
		(layer "In4.Cu")
		(net "M_H_DQS_DN<1>")
	)
	(segment
		(start 72.804782 -61.18352)
		(end 72.89419 -61.20765)
		(width 0.0889)
		(layer "In4.Cu")
		(net "M_H_DQS_DN<1>")
	)
	(segment
		(start 49.425352 -34.858706)
		(end 49.86782 -34.858706)
		(width 0.14224)
		(layer "In4.Cu")
		(net "M_H_DQS_DN<1>")
	)
	(segment
		(start 48.95596 -33.946846)
		(end 48.95596 -34.389314)
		(width 0.14224)
		(layer "In4.Cu")
		(net "M_H_DQS_DN<1>")
	)
	(segment
		(start 69.266562 -57.65927)
		(end 69.266562 -58.583576)
		(width 0.14224)
		(layer "In4.Cu")
		(net "M_H_DQS_DN<1>")
	)
	(segment
		(start 49.86782 -34.858706)
		(end 51.478688 -36.469574)
		(width 0.14224)
		(layer "In4.Cu")
		(net "M_H_DQS_DN<1>")
	)
	(segment
		(start 69.266562 -58.583576)
		(end 69.266562 -58.605674)
		(width 0.0889)
		(layer "In4.Cu")
		(net "M_H_DQS_DN<1>")
	)
	(segment
		(start 69.353176 -59.109102)
		(end 69.353176 -60.155836)
		(width 0.0889)
		(layer "In4.Cu")
		(net "M_H_DQS_DN<1>")
	)
	(segment
		(start 46.169834 -16.239236)
		(end 46.169834 -18.94332)
		(width 0.14224)
		(layer "In4.Cu")
		(net "M_H_DQS_DN<1>")
	)
	(segment
		(start 71.45655 -61.438536)
		(end 71.487792 -61.438536)
		(width 0.0889)
		(layer "In4.Cu")
		(net "M_H_DQS_DN<1>")
	)
	(segment
		(start 45.387514 -13.287756)
		(end 45.851318 -13.75156)
		(width 0.14224)
		(layer "In4.Cu")
		(net "M_H_DQS_DN<1>")
	)
	(segment
		(start 69.227192 -58.983118)
		(end 69.353176 -59.109102)
		(width 0.0889)
		(layer "In4.Cu")
		(net "M_H_DQS_DN<1>")
	)
	(arc
		(start 70.265036 -61.733938)
		(mid 70.411208 -61.880273)
		(end 70.610984 -61.933836)
		(width 0.0889)
		(layer "In4.Cu")
		(net "M_H_DQS_DN<1>")
	)
	(arc
		(start 70.612508 -61.933836)
		(mid 70.812281 -61.880267)
		(end 70.958456 -61.733938)
		(width 0.0889)
		(layer "In4.Cu")
		(net "M_H_DQS_DN<1>")
	)
	(arc
		(start 69.766942 -61.438536)
		(mid 70.054629 -61.521057)
		(end 70.265036 -61.733938)
		(width 0.0889)
		(layer "In4.Cu")
		(net "M_H_DQS_DN<1>")
	)
	(arc
		(start 71.816976 -61.238638)
		(mid 72.025395 -61.026925)
		(end 72.310498 -60.94349)
		(width 0.0889)
		(layer "In4.Cu")
		(net "M_H_DQS_DN<1>")
	)
	(arc
		(start 70.958456 -61.733938)
		(mid 71.168809 -61.520966)
		(end 71.45655 -61.438536)
		(width 0.0889)
		(layer "In4.Cu")
		(net "M_H_DQS_DN<1>")
	)
	(arc
		(start 71.487792 -61.438536)
		(mid 71.678034 -61.380801)
		(end 71.816976 -61.238638)
		(width 0.0889)
		(layer "In4.Cu")
		(net "M_H_DQS_DN<1>")
	)
	(arc
		(start 69.406516 -60.838334)
		(mid 69.402231 -61.231025)
		(end 69.7357 -61.438536)
		(width 0.0889)
		(layer "In4.Cu")
		(net "M_H_DQS_DN<1>")
	)
	(arc
		(start 72.347074 -60.94349)
		(mid 72.603553 -61.010828)
		(end 72.804782 -61.18352)
		(width 0.0889)
		(layer "In4.Cu")
		(net "M_H_DQS_DN<1>")
	)
	(arc
		(start 69.406516 -60.247784)
		(mid 69.485647 -60.543076)
		(end 69.406516 -60.838334)
		(width 0.0889)
		(layer "In4.Cu")
		(net "M_H_DQS_DN<1>")
	)
	(segment
		(start 74.038968 -39.8526)
		(end 74.038968 -39.5986)
		(width 0.1651)
		(layer "F.Cu")
		(net "M_H_DQS_DN<17>")
	)
	(segment
		(start 73.911968 -38.7096)
		(end 73.911968 -38.354)
		(width 0.1651)
		(layer "F.Cu")
		(net "M_H_DQS_DN<17>")
	)
	(segment
		(start 72.7583 -30.50032)
		(end 72.578722 -30.320742)
		(width 0.1651)
		(layer "F.Cu")
		(net "M_H_DQS_DN<17>")
	)
	(segment
		(start 74.375264 -32.117284)
		(end 74.195686 -31.937706)
		(width 0.1651)
		(layer "F.Cu")
		(net "M_H_DQS_DN<17>")
	)
	(segment
		(start 74.630534 -41.804336)
		(end 74.450956 -41.624758)
		(width 0.1651)
		(layer "F.Cu")
		(net "M_H_DQS_DN<17>")
	)
	(segment
		(start 74.734674 -32.296862)
		(end 74.554842 -32.117284)
		(width 0.1651)
		(layer "F.Cu")
		(net "M_H_DQS_DN<17>")
	)
	(segment
		(start 73.911968 -37.0586)
		(end 73.911968 -36.668964)
		(width 0.1651)
		(layer "F.Cu")
		(net "M_H_DQS_DN<17>")
	)
	(segment
		(start 74.195686 -31.937706)
		(end 74.195686 -31.757874)
		(width 0.1651)
		(layer "F.Cu")
		(net "M_H_DQS_DN<17>")
	)
	(segment
		(start 78.445106 -44.041314)
		(end 77.63256 -43.228768)
		(width 0.1016)
		(layer "F.Cu")
		(net "M_H_DQS_DN<17>")
	)
	(segment
		(start 74.153268 -34.57956)
		(end 74.153268 -34.16046)
		(width 0.1651)
		(layer "F.Cu")
		(net "M_H_DQS_DN<17>")
	)
	(segment
		(start 83.097878 -52.513992)
		(end 83.097878 -52.35321)
		(width 0.0889)
		(layer "F.Cu")
		(net "M_H_DQS_DN<17>")
	)
	(segment
		(start 77.63256 -43.228768)
		(end 76.054966 -43.228768)
		(width 0.1016)
		(layer "F.Cu")
		(net "M_H_DQS_DN<17>")
	)
	(segment
		(start 73.911968 -37.846)
		(end 73.911968 -37.5666)
		(width 0.1651)
		(layer "F.Cu")
		(net "M_H_DQS_DN<17>")
	)
	(segment
		(start 74.038968 -38.8366)
		(end 73.911968 -38.7096)
		(width 0.1651)
		(layer "F.Cu")
		(net "M_H_DQS_DN<17>")
	)
	(segment
		(start 83.202272 -52.618386)
		(end 83.097878 -52.513992)
		(width 0.0889)
		(layer "F.Cu")
		(net "M_H_DQS_DN<17>")
	)
	(segment
		(start 83.203542 -50.83175)
		(end 83.291172 -50.74412)
		(width 0.0889)
		(layer "F.Cu")
		(net "M_H_DQS_DN<17>")
	)
	(segment
		(start 83.203542 -50.503836)
		(end 83.203542 -50.276506)
		(width 0.0889)
		(layer "F.Cu")
		(net "M_H_DQS_DN<17>")
	)
	(segment
		(start 74.038968 -40.45077)
		(end 73.911968 -40.32377)
		(width 0.1651)
		(layer "F.Cu")
		(net "M_H_DQS_DN<17>")
	)
	(segment
		(start 74.195686 -31.757874)
		(end 74.015854 -31.578296)
		(width 0.1651)
		(layer "F.Cu")
		(net "M_H_DQS_DN<17>")
	)
	(segment
		(start 73.911968 -41.08577)
		(end 73.911968 -40.83177)
		(width 0.1651)
		(layer "F.Cu")
		(net "M_H_DQS_DN<17>")
	)
	(segment
		(start 83.291172 -50.74412)
		(end 83.291172 -50.591466)
		(width 0.0889)
		(layer "F.Cu")
		(net "M_H_DQS_DN<17>")
	)
	(segment
		(start 73.911968 -40.32377)
		(end 73.911968 -39.9796)
		(width 0.1651)
		(layer "F.Cu")
		(net "M_H_DQS_DN<17>")
	)
	(segment
		(start 74.038968 -38.227)
		(end 74.038968 -37.973)
		(width 0.1651)
		(layer "F.Cu")
		(net "M_H_DQS_DN<17>")
	)
	(segment
		(start 72.598026 -28.213558)
		(end 72.455024 -28.070556)
		(width 0.1651)
		(layer "F.Cu")
		(net "M_H_DQS_DN<17>")
	)
	(segment
		(start 72.937878 -30.50032)
		(end 72.7583 -30.50032)
		(width 0.1651)
		(layer "F.Cu")
		(net "M_H_DQS_DN<17>")
	)
	(segment
		(start 74.038968 -37.973)
		(end 73.911968 -37.846)
		(width 0.1651)
		(layer "F.Cu")
		(net "M_H_DQS_DN<17>")
	)
	(segment
		(start 83.243166 -50.236882)
		(end 83.243166 -50.073814)
		(width 0.0889)
		(layer "F.Cu")
		(net "M_H_DQS_DN<17>")
	)
	(segment
		(start 75.105768 -35.042602)
		(end 74.769726 -34.70656)
		(width 0.1651)
		(layer "F.Cu")
		(net "M_H_DQS_DN<17>")
	)
	(segment
		(start 74.810112 -41.804336)
		(end 74.630534 -41.804336)
		(width 0.1651)
		(layer "F.Cu")
		(net "M_H_DQS_DN<17>")
	)
	(segment
		(start 72.817228 -7.501128)
		(end 72.817228 -7.747762)
		(width 0.1651)
		(layer "F.Cu")
		(net "M_H_DQS_DN<17>")
	)
	(segment
		(start 73.836276 -31.578296)
		(end 73.656698 -31.398718)
		(width 0.1651)
		(layer "F.Cu")
		(net "M_H_DQS_DN<17>")
	)
	(segment
		(start 79.161132 -44.041314)
		(end 78.445106 -44.041314)
		(width 0.1016)
		(layer "F.Cu")
		(net "M_H_DQS_DN<17>")
	)
	(segment
		(start 72.039734 -29.781754)
		(end 72.039734 -29.413454)
		(width 0.1651)
		(layer "F.Cu")
		(net "M_H_DQS_DN<17>")
	)
	(segment
		(start 73.11771 -30.85973)
		(end 73.11771 -30.679898)
		(width 0.1651)
		(layer "F.Cu")
		(net "M_H_DQS_DN<17>")
	)
	(segment
		(start 74.280268 -34.70656)
		(end 74.153268 -34.57956)
		(width 0.1651)
		(layer "F.Cu")
		(net "M_H_DQS_DN<17>")
	)
	(segment
		(start 73.911968 -39.4716)
		(end 73.911968 -39.2176)
		(width 0.1651)
		(layer "F.Cu")
		(net "M_H_DQS_DN<17>")
	)
	(segment
		(start 74.038968 -39.5986)
		(end 73.911968 -39.4716)
		(width 0.1651)
		(layer "F.Cu")
		(net "M_H_DQS_DN<17>")
	)
	(segment
		(start 74.015854 -31.578296)
		(end 73.836276 -31.578296)
		(width 0.1651)
		(layer "F.Cu")
		(net "M_H_DQS_DN<17>")
	)
	(segment
		(start 75.907646 -43.081448)
		(end 74.989944 -42.163746)
		(width 0.1651)
		(layer "F.Cu")
		(net "M_H_DQS_DN<17>")
	)
	(segment
		(start 72.337168 -29.21)
		(end 72.598026 -28.949142)
		(width 0.1651)
		(layer "F.Cu")
		(net "M_H_DQS_DN<17>")
	)
	(segment
		(start 72.039734 -29.413454)
		(end 72.243188 -29.21)
		(width 0.1651)
		(layer "F.Cu")
		(net "M_H_DQS_DN<17>")
	)
	(segment
		(start 74.989944 -42.163746)
		(end 74.989944 -41.983914)
		(width 0.1651)
		(layer "F.Cu")
		(net "M_H_DQS_DN<17>")
	)
	(segment
		(start 74.450956 -41.444926)
		(end 74.271124 -41.265348)
		(width 0.1651)
		(layer "F.Cu")
		(net "M_H_DQS_DN<17>")
	)
	(segment
		(start 72.598026 -28.949142)
		(end 72.598026 -28.213558)
		(width 0.1651)
		(layer "F.Cu")
		(net "M_H_DQS_DN<17>")
	)
	(segment
		(start 72.219312 -29.961332)
		(end 72.039734 -29.781754)
		(width 0.1651)
		(layer "F.Cu")
		(net "M_H_DQS_DN<17>")
	)
	(segment
		(start 75.105768 -32.847788)
		(end 74.734674 -32.476694)
		(width 0.1651)
		(layer "F.Cu")
		(net "M_H_DQS_DN<17>")
	)
	(segment
		(start 74.989944 -41.983914)
		(end 74.810112 -41.804336)
		(width 0.1651)
		(layer "F.Cu")
		(net "M_H_DQS_DN<17>")
	)
	(segment
		(start 83.243166 -48.123348)
		(end 79.161132 -44.041314)
		(width 0.1016)
		(layer "F.Cu")
		(net "M_H_DQS_DN<17>")
	)
	(segment
		(start 73.911968 -40.83177)
		(end 74.038968 -40.70477)
		(width 0.1651)
		(layer "F.Cu")
		(net "M_H_DQS_DN<17>")
	)
	(segment
		(start 72.817228 -7.747762)
		(end 72.56526 -7.99973)
		(width 0.1651)
		(layer "F.Cu")
		(net "M_H_DQS_DN<17>")
	)
	(segment
		(start 74.450956 -41.624758)
		(end 74.450956 -41.444926)
		(width 0.1651)
		(layer "F.Cu")
		(net "M_H_DQS_DN<17>")
	)
	(segment
		(start 74.271124 -41.265348)
		(end 74.091546 -41.265348)
		(width 0.1651)
		(layer "F.Cu")
		(net "M_H_DQS_DN<17>")
	)
	(segment
		(start 83.291172 -50.591466)
		(end 83.203542 -50.503836)
		(width 0.0889)
		(layer "F.Cu")
		(net "M_H_DQS_DN<17>")
	)
	(segment
		(start 73.656698 -31.398718)
		(end 73.656698 -31.218886)
		(width 0.1651)
		(layer "F.Cu")
		(net "M_H_DQS_DN<17>")
	)
	(segment
		(start 75.105768 -36.045394)
		(end 75.105768 -35.042602)
		(width 0.1651)
		(layer "F.Cu")
		(net "M_H_DQS_DN<17>")
	)
	(segment
		(start 72.243188 -29.21)
		(end 72.337168 -29.21)
		(width 0.1651)
		(layer "F.Cu")
		(net "M_H_DQS_DN<17>")
	)
	(segment
		(start 74.038968 -37.1856)
		(end 73.911968 -37.0586)
		(width 0.1651)
		(layer "F.Cu")
		(net "M_H_DQS_DN<17>")
	)
	(segment
		(start 74.038968 -39.0906)
		(end 74.038968 -38.8366)
		(width 0.1651)
		(layer "F.Cu")
		(net "M_H_DQS_DN<17>")
	)
	(segment
		(start 73.049384 -6.66496)
		(end 72.6313 -7.083044)
		(width 0.1651)
		(layer "F.Cu")
		(net "M_H_DQS_DN<17>")
	)
	(segment
		(start 72.56526 -7.99973)
		(end 72.33793 -7.99973)
		(width 0.1651)
		(layer "F.Cu")
		(net "M_H_DQS_DN<17>")
	)
	(segment
		(start 73.911968 -39.2176)
		(end 74.038968 -39.0906)
		(width 0.1651)
		(layer "F.Cu")
		(net "M_H_DQS_DN<17>")
	)
	(segment
		(start 73.911968 -39.9796)
		(end 74.038968 -39.8526)
		(width 0.1651)
		(layer "F.Cu")
		(net "M_H_DQS_DN<17>")
	)
	(segment
		(start 72.578722 -30.320742)
		(end 72.578722 -30.14091)
		(width 0.1651)
		(layer "F.Cu")
		(net "M_H_DQS_DN<17>")
	)
	(segment
		(start 74.769726 -34.03346)
		(end 75.105768 -33.697418)
		(width 0.1651)
		(layer "F.Cu")
		(net "M_H_DQS_DN<17>")
	)
	(segment
		(start 73.297288 -31.039308)
		(end 73.11771 -30.85973)
		(width 0.1651)
		(layer "F.Cu")
		(net "M_H_DQS_DN<17>")
	)
	(segment
		(start 74.554842 -32.117284)
		(end 74.375264 -32.117284)
		(width 0.1651)
		(layer "F.Cu")
		(net "M_H_DQS_DN<17>")
	)
	(segment
		(start 74.038968 -40.70477)
		(end 74.038968 -40.45077)
		(width 0.1651)
		(layer "F.Cu")
		(net "M_H_DQS_DN<17>")
	)
	(segment
		(start 73.911968 -37.5666)
		(end 74.038968 -37.4396)
		(width 0.1651)
		(layer "F.Cu")
		(net "M_H_DQS_DN<17>")
	)
	(segment
		(start 73.656698 -31.218886)
		(end 73.476866 -31.039308)
		(width 0.1651)
		(layer "F.Cu")
		(net "M_H_DQS_DN<17>")
	)
	(segment
		(start 74.091546 -41.265348)
		(end 73.911968 -41.08577)
		(width 0.1651)
		(layer "F.Cu")
		(net "M_H_DQS_DN<17>")
	)
	(segment
		(start 74.769726 -34.70656)
		(end 74.280268 -34.70656)
		(width 0.1651)
		(layer "F.Cu")
		(net "M_H_DQS_DN<17>")
	)
	(segment
		(start 73.476866 -31.039308)
		(end 73.297288 -31.039308)
		(width 0.1651)
		(layer "F.Cu")
		(net "M_H_DQS_DN<17>")
	)
	(segment
		(start 75.105768 -33.697418)
		(end 75.105768 -32.847788)
		(width 0.1651)
		(layer "F.Cu")
		(net "M_H_DQS_DN<17>")
	)
	(segment
		(start 83.203542 -51.813206)
		(end 83.203542 -50.83175)
		(width 0.0889)
		(layer "F.Cu")
		(net "M_H_DQS_DN<17>")
	)
	(segment
		(start 73.049384 -5.822442)
		(end 73.049384 -6.66496)
		(width 0.1651)
		(layer "F.Cu")
		(net "M_H_DQS_DN<17>")
	)
	(segment
		(start 72.6313 -7.3152)
		(end 72.817228 -7.501128)
		(width 0.1651)
		(layer "F.Cu")
		(net "M_H_DQS_DN<17>")
	)
	(segment
		(start 74.182732 -36.3982)
		(end 74.752962 -36.3982)
		(width 0.1651)
		(layer "F.Cu")
		(net "M_H_DQS_DN<17>")
	)
	(segment
		(start 72.455024 -28.070556)
		(end 72.142096 -28.070556)
		(width 0.1651)
		(layer "F.Cu")
		(net "M_H_DQS_DN<17>")
	)
	(segment
		(start 73.911968 -38.354)
		(end 74.038968 -38.227)
		(width 0.1651)
		(layer "F.Cu")
		(net "M_H_DQS_DN<17>")
	)
	(segment
		(start 72.6313 -7.083044)
		(end 72.6313 -7.3152)
		(width 0.1651)
		(layer "F.Cu")
		(net "M_H_DQS_DN<17>")
	)
	(segment
		(start 76.054966 -43.228768)
		(end 75.907646 -43.081448)
		(width 0.1016)
		(layer "F.Cu")
		(net "M_H_DQS_DN<17>")
	)
	(segment
		(start 74.153268 -34.16046)
		(end 74.280268 -34.03346)
		(width 0.1651)
		(layer "F.Cu")
		(net "M_H_DQS_DN<17>")
	)
	(segment
		(start 72.33793 -7.99973)
		(end 72.1487 -7.8105)
		(width 0.1651)
		(layer "F.Cu")
		(net "M_H_DQS_DN<17>")
	)
	(segment
		(start 74.752962 -36.3982)
		(end 75.105768 -36.045394)
		(width 0.1651)
		(layer "F.Cu")
		(net "M_H_DQS_DN<17>")
	)
	(segment
		(start 74.038968 -37.4396)
		(end 74.038968 -37.1856)
		(width 0.1651)
		(layer "F.Cu")
		(net "M_H_DQS_DN<17>")
	)
	(segment
		(start 73.11771 -30.679898)
		(end 72.937878 -30.50032)
		(width 0.1651)
		(layer "F.Cu")
		(net "M_H_DQS_DN<17>")
	)
	(segment
		(start 83.243166 -50.073814)
		(end 83.243166 -48.123348)
		(width 0.1016)
		(layer "F.Cu")
		(net "M_H_DQS_DN<17>")
	)
	(segment
		(start 74.734674 -32.476694)
		(end 74.734674 -32.296862)
		(width 0.1651)
		(layer "F.Cu")
		(net "M_H_DQS_DN<17>")
	)
	(segment
		(start 74.280268 -34.03346)
		(end 74.769726 -34.03346)
		(width 0.1651)
		(layer "F.Cu")
		(net "M_H_DQS_DN<17>")
	)
	(segment
		(start 73.911968 -36.668964)
		(end 74.182732 -36.3982)
		(width 0.1651)
		(layer "F.Cu")
		(net "M_H_DQS_DN<17>")
	)
	(segment
		(start 83.203542 -50.276506)
		(end 83.243166 -50.236882)
		(width 0.0889)
		(layer "F.Cu")
		(net "M_H_DQS_DN<17>")
	)
	(segment
		(start 72.578722 -30.14091)
		(end 72.39889 -29.961332)
		(width 0.1651)
		(layer "F.Cu")
		(net "M_H_DQS_DN<17>")
	)
	(segment
		(start 72.39889 -29.961332)
		(end 72.219312 -29.961332)
		(width 0.1651)
		(layer "F.Cu")
		(net "M_H_DQS_DN<17>")
	)
	(via
		(at 72.142096 -28.070556)
		(size 0.508)
		(drill 0.254)
		(layers "F.Cu" "B.Cu")
		(net "M_H_DQS_DN<17>")
	)
	(via
		(at 72.142096 -13.2334)
		(size 0.508)
		(drill 0.254)
		(layers "F.Cu" "B.Cu")
		(net "M_H_DQS_DN<17>")
	)
	(via
		(at 72.1487 -7.8105)
		(size 0.508)
		(drill 0.254)
		(layers "F.Cu" "B.Cu")
		(net "M_H_DQS_DN<17>")
	)
	(arc
		(start 83.097878 -52.35321)
		(mid 83.176913 -52.088333)
		(end 83.203542 -51.813206)
		(width 0.0889)
		(layer "F.Cu")
		(net "M_H_DQS_DN<17>")
	)
	(segment
		(start 73.049638 -15.222728)
		(end 73.049638 -14.566392)
		(width 0.1651)
		(layer "B.Cu")
		(net "M_H_DQS_DN<17>")
	)
	(segment
		(start 72.33666 -13.038836)
		(end 72.142096 -13.2334)
		(width 0.1651)
		(layer "B.Cu")
		(net "M_H_DQS_DN<17>")
	)
	(segment
		(start 73.049638 -14.566392)
		(end 72.6059 -14.122654)
		(width 0.1651)
		(layer "B.Cu")
		(net "M_H_DQS_DN<17>")
	)
	(segment
		(start 72.7837 -13.2588)
		(end 72.563736 -13.038836)
		(width 0.1651)
		(layer "B.Cu")
		(net "M_H_DQS_DN<17>")
	)
	(segment
		(start 72.563736 -13.038836)
		(end 72.33666 -13.038836)
		(width 0.1651)
		(layer "B.Cu")
		(net "M_H_DQS_DN<17>")
	)
	(segment
		(start 72.7837 -13.589)
		(end 72.7837 -13.2588)
		(width 0.1651)
		(layer "B.Cu")
		(net "M_H_DQS_DN<17>")
	)
	(segment
		(start 72.6059 -14.122654)
		(end 72.6059 -13.7668)
		(width 0.1651)
		(layer "B.Cu")
		(net "M_H_DQS_DN<17>")
	)
	(segment
		(start 73.049384 -15.222982)
		(end 73.049638 -15.222728)
		(width 0.1651)
		(layer "B.Cu")
		(net "M_H_DQS_DN<17>")
	)
	(segment
		(start 72.6059 -13.7668)
		(end 72.7837 -13.589)
		(width 0.1651)
		(layer "B.Cu")
		(net "M_H_DQS_DN<17>")
	)
	(segment
		(start 72.93102 -8.343392)
		(end 72.593708 -8.00608)
		(width 0.14224)
		(layer "In11.Cu")
		(net "M_H_DQS_DN<17>")
	)
	(segment
		(start 72.142096 -13.2334)
		(end 72.93102 -12.444476)
		(width 0.14224)
		(layer "In11.Cu")
		(net "M_H_DQS_DN<17>")
	)
	(segment
		(start 72.400414 -15.175738)
		(end 72.400414 -14.338554)
		(width 0.14224)
		(layer "In11.Cu")
		(net "M_H_DQS_DN<17>")
	)
	(segment
		(start 72.142096 -28.070556)
		(end 72.908414 -27.304238)
		(width 0.14224)
		(layer "In11.Cu")
		(net "M_H_DQS_DN<17>")
	)
	(segment
		(start 72.593708 -8.00608)
		(end 72.34428 -8.00608)
		(width 0.14224)
		(layer "In11.Cu")
		(net "M_H_DQS_DN<17>")
	)
	(segment
		(start 72.908414 -27.304238)
		(end 72.908414 -15.683738)
		(width 0.14224)
		(layer "In11.Cu")
		(net "M_H_DQS_DN<17>")
	)
	(segment
		(start 72.908414 -15.683738)
		(end 72.400414 -15.175738)
		(width 0.14224)
		(layer "In11.Cu")
		(net "M_H_DQS_DN<17>")
	)
	(segment
		(start 72.400414 -14.338554)
		(end 72.5805 -14.158468)
		(width 0.14224)
		(layer "In11.Cu")
		(net "M_H_DQS_DN<17>")
	)
	(segment
		(start 72.5805 -14.158468)
		(end 72.5805 -13.671804)
		(width 0.14224)
		(layer "In11.Cu")
		(net "M_H_DQS_DN<17>")
	)
	(segment
		(start 72.5805 -13.671804)
		(end 72.142096 -13.2334)
		(width 0.14224)
		(layer "In11.Cu")
		(net "M_H_DQS_DN<17>")
	)
	(segment
		(start 72.93102 -12.444476)
		(end 72.93102 -8.343392)
		(width 0.14224)
		(layer "In11.Cu")
		(net "M_H_DQS_DN<17>")
	)
	(segment
		(start 72.34428 -8.00608)
		(end 72.1487 -7.8105)
		(width 0.14224)
		(layer "In11.Cu")
		(net "M_H_DQS_DN<17>")
	)
	(segment
		(start 146.515328 -7.99973)
		(end 146.307048 -7.99973)
		(width 0.1651)
		(layer "F.Cu")
		(net "M_H_DQS_DN<16>")
	)
	(segment
		(start 146.581368 -7.3152)
		(end 146.767296 -7.501128)
		(width 0.1651)
		(layer "F.Cu")
		(net "M_H_DQS_DN<16>")
	)
	(segment
		(start 119.929402 -58.876438)
		(end 119.357902 -58.876438)
		(width 0.1016)
		(layer "F.Cu")
		(net "M_H_DQS_DN<16>")
	)
	(segment
		(start 146.767296 -7.747762)
		(end 146.515328 -7.99973)
		(width 0.1651)
		(layer "F.Cu")
		(net "M_H_DQS_DN<16>")
	)
	(segment
		(start 146.767296 -7.501128)
		(end 146.767296 -7.747762)
		(width 0.1651)
		(layer "F.Cu")
		(net "M_H_DQS_DN<16>")
	)
	(segment
		(start 146.581368 -7.083044)
		(end 146.581368 -7.3152)
		(width 0.1651)
		(layer "F.Cu")
		(net "M_H_DQS_DN<16>")
	)
	(segment
		(start 146.307048 -7.99973)
		(end 146.117818 -7.8105)
		(width 0.1651)
		(layer "F.Cu")
		(net "M_H_DQS_DN<16>")
	)
	(segment
		(start 146.999452 -6.66496)
		(end 146.581368 -7.083044)
		(width 0.1651)
		(layer "F.Cu")
		(net "M_H_DQS_DN<16>")
	)
	(segment
		(start 146.999452 -5.822442)
		(end 146.999452 -6.66496)
		(width 0.1651)
		(layer "F.Cu")
		(net "M_H_DQS_DN<16>")
	)
	(segment
		(start 146.117818 -7.8105)
		(end 146.098768 -7.8105)
		(width 0.1651)
		(layer "F.Cu")
		(net "M_H_DQS_DN<16>")
	)
	(via
		(at 119.357902 -58.876438)
		(size 0.508)
		(drill 0.254)
		(layers "F.Cu" "B.Cu")
		(net "M_H_DQS_DN<16>")
	)
	(via
		(at 146.092164 -13.2334)
		(size 0.508)
		(drill 0.254)
		(layers "F.Cu" "B.Cu")
		(net "M_H_DQS_DN<16>")
	)
	(via
		(at 146.098768 -7.8105)
		(size 0.508)
		(drill 0.254)
		(layers "F.Cu" "B.Cu")
		(net "M_H_DQS_DN<16>")
	)
	(segment
		(start 146.733768 -13.2588)
		(end 146.513804 -13.038836)
		(width 0.1651)
		(layer "B.Cu")
		(net "M_H_DQS_DN<16>")
	)
	(segment
		(start 146.999452 -14.566138)
		(end 146.555968 -14.122654)
		(width 0.1651)
		(layer "B.Cu")
		(net "M_H_DQS_DN<16>")
	)
	(segment
		(start 146.555968 -13.7668)
		(end 146.733768 -13.589)
		(width 0.1651)
		(layer "B.Cu")
		(net "M_H_DQS_DN<16>")
	)
	(segment
		(start 146.513804 -13.038836)
		(end 146.286728 -13.038836)
		(width 0.1651)
		(layer "B.Cu")
		(net "M_H_DQS_DN<16>")
	)
	(segment
		(start 146.733768 -13.589)
		(end 146.733768 -13.2588)
		(width 0.1651)
		(layer "B.Cu")
		(net "M_H_DQS_DN<16>")
	)
	(segment
		(start 146.555968 -14.122654)
		(end 146.555968 -13.7668)
		(width 0.1651)
		(layer "B.Cu")
		(net "M_H_DQS_DN<16>")
	)
	(segment
		(start 146.286728 -13.038836)
		(end 146.092164 -13.2334)
		(width 0.1651)
		(layer "B.Cu")
		(net "M_H_DQS_DN<16>")
	)
	(segment
		(start 146.999452 -15.222982)
		(end 146.999452 -14.566138)
		(width 0.1651)
		(layer "B.Cu")
		(net "M_H_DQS_DN<16>")
	)
	(segment
		(start 145.890488 -15.048992)
		(end 145.890488 -14.58468)
		(width 0.14224)
		(layer "In4.Cu")
		(net "M_H_DQS_DN<16>")
	)
	(segment
		(start 146.881088 -12.444476)
		(end 146.881088 -8.343392)
		(width 0.14224)
		(layer "In4.Cu")
		(net "M_H_DQS_DN<16>")
	)
	(segment
		(start 123.515628 -50.757074)
		(end 123.571 -50.757328)
		(width 0.0889)
		(layer "In4.Cu")
		(net "M_H_DQS_DN<16>")
	)
	(segment
		(start 124.302012 -50.026316)
		(end 124.463556 -50.026316)
		(width 0.14224)
		(layer "In4.Cu")
		(net "M_H_DQS_DN<16>")
	)
	(segment
		(start 147.031964 -23.9776)
		(end 146.874484 -23.82012)
		(width 0.14224)
		(layer "In4.Cu")
		(net "M_H_DQS_DN<16>")
	)
	(segment
		(start 120.723152 -53.731922)
		(end 120.727978 -53.723286)
		(width 0.0889)
		(layer "In4.Cu")
		(net "M_H_DQS_DN<16>")
	)
	(segment
		(start 146.874484 -21.16328)
		(end 147.031964 -21.0058)
		(width 0.14224)
		(layer "In4.Cu")
		(net "M_H_DQS_DN<16>")
	)
	(segment
		(start 146.327368 -14.4018)
		(end 146.530568 -14.1986)
		(width 0.14224)
		(layer "In4.Cu")
		(net "M_H_DQS_DN<16>")
	)
	(segment
		(start 146.874484 -24.38908)
		(end 147.031964 -24.2316)
		(width 0.14224)
		(layer "In4.Cu")
		(net "M_H_DQS_DN<16>")
	)
	(segment
		(start 121.586498 -52.237386)
		(end 121.691908 -52.055014)
		(width 0.0889)
		(layer "In4.Cu")
		(net "M_H_DQS_DN<16>")
	)
	(segment
		(start 120.216168 -57.981088)
		(end 120.233948 -57.981088)
		(width 0.0889)
		(layer "In4.Cu")
		(net "M_H_DQS_DN<16>")
	)
	(segment
		(start 125.70841 -48.619918)
		(end 125.92812 -48.400208)
		(width 0.14224)
		(layer "In4.Cu")
		(net "M_H_DQS_DN<16>")
	)
	(segment
		(start 119.869712 -58.18124)
		(end 119.873014 -58.175398)
		(width 0.0889)
		(layer "In4.Cu")
		(net "M_H_DQS_DN<16>")
	)
	(segment
		(start 123.571 -50.757328)
		(end 123.586494 -50.741834)
		(width 0.0889)
		(layer "In4.Cu")
		(net "M_H_DQS_DN<16>")
	)
	(segment
		(start 125.164342 -49.32553)
		(end 125.164342 -49.163986)
		(width 0.14224)
		(layer "In4.Cu")
		(net "M_H_DQS_DN<16>")
	)
	(segment
		(start 124.463556 -50.026316)
		(end 124.643388 -49.846484)
		(width 0.14224)
		(layer "In4.Cu")
		(net "M_H_DQS_DN<16>")
	)
	(segment
		(start 142.629128 -33.405826)
		(end 143.164814 -33.405826)
		(width 0.14224)
		(layer "In4.Cu")
		(net "M_H_DQS_DN<16>")
	)
	(segment
		(start 146.874484 -16.032988)
		(end 145.890488 -15.048992)
		(width 0.14224)
		(layer "In4.Cu")
		(net "M_H_DQS_DN<16>")
	)
	(segment
		(start 125.36678 -48.961548)
		(end 125.528578 -48.961548)
		(width 0.14224)
		(layer "In4.Cu")
		(net "M_H_DQS_DN<16>")
	)
	(segment
		(start 127.030226 -47.298102)
		(end 127.19177 -47.298102)
		(width 0.14224)
		(layer "In4.Cu")
		(net "M_H_DQS_DN<16>")
	)
	(segment
		(start 124.107448 -50.382424)
		(end 124.107448 -50.22088)
		(width 0.14224)
		(layer "In4.Cu")
		(net "M_H_DQS_DN<16>")
	)
	(segment
		(start 123.927616 -50.562256)
		(end 124.107448 -50.382424)
		(width 0.14224)
		(layer "In4.Cu")
		(net "M_H_DQS_DN<16>")
	)
	(segment
		(start 147.031964 -20.7518)
		(end 146.874484 -20.59432)
		(width 0.14224)
		(layer "In4.Cu")
		(net "M_H_DQS_DN<16>")
	)
	(segment
		(start 146.294348 -8.00608)
		(end 146.098768 -7.8105)
		(width 0.14224)
		(layer "In4.Cu")
		(net "M_H_DQS_DN<16>")
	)
	(segment
		(start 124.643388 -49.846484)
		(end 124.643388 -49.68494)
		(width 0.14224)
		(layer "In4.Cu")
		(net "M_H_DQS_DN<16>")
	)
	(segment
		(start 141.936216 -34.237676)
		(end 141.323822 -33.625282)
		(width 0.14224)
		(layer "In4.Cu")
		(net "M_H_DQS_DN<16>")
	)
	(segment
		(start 147.031964 -21.0058)
		(end 147.031964 -20.7518)
		(width 0.14224)
		(layer "In4.Cu")
		(net "M_H_DQS_DN<16>")
	)
	(segment
		(start 141.776704 -32.886142)
		(end 142.109444 -32.886142)
		(width 0.14224)
		(layer "In4.Cu")
		(net "M_H_DQS_DN<16>")
	)
	(segment
		(start 143.164814 -33.405826)
		(end 143.771366 -32.799274)
		(width 0.14224)
		(layer "In4.Cu")
		(net "M_H_DQS_DN<16>")
	)
	(segment
		(start 145.890488 -14.58468)
		(end 146.073368 -14.4018)
		(width 0.14224)
		(layer "In4.Cu")
		(net "M_H_DQS_DN<16>")
	)
	(segment
		(start 120.723152 -55.713122)
		(end 120.727978 -55.704486)
		(width 0.0889)
		(layer "In4.Cu")
		(net "M_H_DQS_DN<16>")
	)
	(segment
		(start 119.357902 -58.476388)
		(end 119.375682 -58.476388)
		(width 0.0889)
		(layer "In4.Cu")
		(net "M_H_DQS_DN<16>")
	)
	(segment
		(start 120.727978 -55.704486)
		(end 120.734328 -55.693818)
		(width 0.0889)
		(layer "In4.Cu")
		(net "M_H_DQS_DN<16>")
	)
	(segment
		(start 124.98451 -49.505362)
		(end 125.164342 -49.32553)
		(width 0.14224)
		(layer "In4.Cu")
		(net "M_H_DQS_DN<16>")
	)
	(segment
		(start 124.822966 -49.505362)
		(end 124.98451 -49.505362)
		(width 0.14224)
		(layer "In4.Cu")
		(net "M_H_DQS_DN<16>")
	)
	(segment
		(start 122.289062 -51.98364)
		(end 123.515628 -50.757074)
		(width 0.0889)
		(layer "In4.Cu")
		(net "M_H_DQS_DN<16>")
	)
	(segment
		(start 120.727978 -54.713886)
		(end 120.734328 -54.703218)
		(width 0.0889)
		(layer "In4.Cu")
		(net "M_H_DQS_DN<16>")
	)
	(segment
		(start 141.323822 -33.339024)
		(end 141.776704 -32.886142)
		(width 0.14224)
		(layer "In4.Cu")
		(net "M_H_DQS_DN<16>")
	)
	(segment
		(start 127.19177 -47.298102)
		(end 127.371602 -47.11827)
		(width 0.14224)
		(layer "In4.Cu")
		(net "M_H_DQS_DN<16>")
	)
	(segment
		(start 125.92812 -48.400208)
		(end 126.089664 -48.400208)
		(width 0.14224)
		(layer "In4.Cu")
		(net "M_H_DQS_DN<16>")
	)
	(segment
		(start 147.031964 -24.2316)
		(end 147.031964 -23.9776)
		(width 0.14224)
		(layer "In4.Cu")
		(net "M_H_DQS_DN<16>")
	)
	(segment
		(start 126.610618 -47.879254)
		(end 126.79045 -47.699422)
		(width 0.14224)
		(layer "In4.Cu")
		(net "M_H_DQS_DN<16>")
	)
	(segment
		(start 120.723152 -54.722522)
		(end 120.727978 -54.713886)
		(width 0.0889)
		(layer "In4.Cu")
		(net "M_H_DQS_DN<16>")
	)
	(segment
		(start 127.371602 -46.956726)
		(end 127.881888 -46.44644)
		(width 0.14224)
		(layer "In4.Cu")
		(net "M_H_DQS_DN<16>")
	)
	(segment
		(start 125.164342 -49.163986)
		(end 125.36678 -48.961548)
		(width 0.14224)
		(layer "In4.Cu")
		(net "M_H_DQS_DN<16>")
	)
	(segment
		(start 147.031964 -19.2278)
		(end 146.874484 -19.07032)
		(width 0.14224)
		(layer "In4.Cu")
		(net "M_H_DQS_DN<16>")
	)
	(segment
		(start 121.691908 -52.055014)
		(end 121.763028 -51.98364)
		(width 0.0889)
		(layer "In4.Cu")
		(net "M_H_DQS_DN<16>")
	)
	(segment
		(start 146.881088 -8.343392)
		(end 146.543776 -8.00608)
		(width 0.14224)
		(layer "In4.Cu")
		(net "M_H_DQS_DN<16>")
	)
	(segment
		(start 147.031964 -20.2438)
		(end 147.031964 -19.9898)
		(width 0.14224)
		(layer "In4.Cu")
		(net "M_H_DQS_DN<16>")
	)
	(segment
		(start 125.528578 -48.961548)
		(end 125.70841 -48.781716)
		(width 0.14224)
		(layer "In4.Cu")
		(net "M_H_DQS_DN<16>")
	)
	(segment
		(start 121.063512 -52.532534)
		(end 121.096278 -52.532534)
		(width 0.0889)
		(layer "In4.Cu")
		(net "M_H_DQS_DN<16>")
	)
	(segment
		(start 143.771366 -32.799274)
		(end 143.771366 -32.262826)
		(width 0.14224)
		(layer "In4.Cu")
		(net "M_H_DQS_DN<16>")
	)
	(segment
		(start 143.293846 -31.785306)
		(end 143.293846 -31.473902)
		(width 0.14224)
		(layer "In4.Cu")
		(net "M_H_DQS_DN<16>")
	)
	(segment
		(start 124.107448 -50.22088)
		(end 124.302012 -50.026316)
		(width 0.14224)
		(layer "In4.Cu")
		(net "M_H_DQS_DN<16>")
	)
	(segment
		(start 147.031964 -19.9898)
		(end 146.874484 -19.83232)
		(width 0.14224)
		(layer "In4.Cu")
		(net "M_H_DQS_DN<16>")
	)
	(segment
		(start 126.79045 -47.699422)
		(end 126.79045 -47.537878)
		(width 0.14224)
		(layer "In4.Cu")
		(net "M_H_DQS_DN<16>")
	)
	(segment
		(start 141.323822 -33.625282)
		(end 141.323822 -33.339024)
		(width 0.14224)
		(layer "In4.Cu")
		(net "M_H_DQS_DN<16>")
	)
	(segment
		(start 126.269496 -48.220376)
		(end 126.269496 -48.058832)
		(width 0.14224)
		(layer "In4.Cu")
		(net "M_H_DQS_DN<16>")
	)
	(segment
		(start 130.263646 -46.44644)
		(end 141.936216 -34.77387)
		(width 0.14224)
		(layer "In4.Cu")
		(net "M_H_DQS_DN<16>")
	)
	(segment
		(start 146.874484 -20.59432)
		(end 146.874484 -20.40128)
		(width 0.14224)
		(layer "In4.Cu")
		(net "M_H_DQS_DN<16>")
	)
	(segment
		(start 124.643388 -49.68494)
		(end 124.822966 -49.505362)
		(width 0.14224)
		(layer "In4.Cu")
		(net "M_H_DQS_DN<16>")
	)
	(segment
		(start 120.723152 -56.703722)
		(end 120.727978 -56.695086)
		(width 0.0889)
		(layer "In4.Cu")
		(net "M_H_DQS_DN<16>")
	)
	(segment
		(start 146.073368 -14.4018)
		(end 146.327368 -14.4018)
		(width 0.14224)
		(layer "In4.Cu")
		(net "M_H_DQS_DN<16>")
	)
	(segment
		(start 121.763028 -51.98364)
		(end 122.289062 -51.98364)
		(width 0.0889)
		(layer "In4.Cu")
		(net "M_H_DQS_DN<16>")
	)
	(segment
		(start 146.092164 -13.2334)
		(end 146.881088 -12.444476)
		(width 0.14224)
		(layer "In4.Cu")
		(net "M_H_DQS_DN<16>")
	)
	(segment
		(start 146.874484 -23.82012)
		(end 146.874484 -21.16328)
		(width 0.14224)
		(layer "In4.Cu")
		(net "M_H_DQS_DN<16>")
	)
	(segment
		(start 146.543776 -8.00608)
		(end 146.294348 -8.00608)
		(width 0.14224)
		(layer "In4.Cu")
		(net "M_H_DQS_DN<16>")
	)
	(segment
		(start 123.586494 -50.741834)
		(end 123.766072 -50.562256)
		(width 0.14224)
		(layer "In4.Cu")
		(net "M_H_DQS_DN<16>")
	)
	(segment
		(start 126.449074 -47.879254)
		(end 126.610618 -47.879254)
		(width 0.14224)
		(layer "In4.Cu")
		(net "M_H_DQS_DN<16>")
	)
	(segment
		(start 143.771366 -32.262826)
		(end 143.293846 -31.785306)
		(width 0.14224)
		(layer "In4.Cu")
		(net "M_H_DQS_DN<16>")
	)
	(segment
		(start 146.874484 -19.07032)
		(end 146.874484 -16.032988)
		(width 0.14224)
		(layer "In4.Cu")
		(net "M_H_DQS_DN<16>")
	)
	(segment
		(start 147.031964 -19.4818)
		(end 147.031964 -19.2278)
		(width 0.14224)
		(layer "In4.Cu")
		(net "M_H_DQS_DN<16>")
	)
	(segment
		(start 141.936216 -34.77387)
		(end 141.936216 -34.237676)
		(width 0.14224)
		(layer "In4.Cu")
		(net "M_H_DQS_DN<16>")
	)
	(segment
		(start 146.874484 -19.63928)
		(end 147.031964 -19.4818)
		(width 0.14224)
		(layer "In4.Cu")
		(net "M_H_DQS_DN<16>")
	)
	(segment
		(start 143.293846 -31.473902)
		(end 146.874484 -27.893264)
		(width 0.14224)
		(layer "In4.Cu")
		(net "M_H_DQS_DN<16>")
	)
	(segment
		(start 146.530568 -14.1986)
		(end 146.530568 -13.671804)
		(width 0.14224)
		(layer "In4.Cu")
		(net "M_H_DQS_DN<16>")
	)
	(segment
		(start 146.874484 -19.83232)
		(end 146.874484 -19.63928)
		(width 0.14224)
		(layer "In4.Cu")
		(net "M_H_DQS_DN<16>")
	)
	(segment
		(start 125.70841 -48.781716)
		(end 125.70841 -48.619918)
		(width 0.14224)
		(layer "In4.Cu")
		(net "M_H_DQS_DN<16>")
	)
	(segment
		(start 146.530568 -13.671804)
		(end 146.092164 -13.2334)
		(width 0.14224)
		(layer "In4.Cu")
		(net "M_H_DQS_DN<16>")
	)
	(segment
		(start 123.766072 -50.562256)
		(end 123.927616 -50.562256)
		(width 0.14224)
		(layer "In4.Cu")
		(net "M_H_DQS_DN<16>")
	)
	(segment
		(start 127.371602 -47.11827)
		(end 127.371602 -46.956726)
		(width 0.14224)
		(layer "In4.Cu")
		(net "M_H_DQS_DN<16>")
	)
	(segment
		(start 126.269496 -48.058832)
		(end 126.449074 -47.879254)
		(width 0.14224)
		(layer "In4.Cu")
		(net "M_H_DQS_DN<16>")
	)
	(segment
		(start 126.089664 -48.400208)
		(end 126.269496 -48.220376)
		(width 0.14224)
		(layer "In4.Cu")
		(net "M_H_DQS_DN<16>")
	)
	(segment
		(start 120.727978 -56.695086)
		(end 120.734328 -56.684418)
		(width 0.0889)
		(layer "In4.Cu")
		(net "M_H_DQS_DN<16>")
	)
	(segment
		(start 146.874484 -27.893264)
		(end 146.874484 -24.38908)
		(width 0.14224)
		(layer "In4.Cu")
		(net "M_H_DQS_DN<16>")
	)
	(segment
		(start 120.727978 -53.723286)
		(end 120.734328 -53.712618)
		(width 0.0889)
		(layer "In4.Cu")
		(net "M_H_DQS_DN<16>")
	)
	(segment
		(start 146.874484 -20.40128)
		(end 147.031964 -20.2438)
		(width 0.14224)
		(layer "In4.Cu")
		(net "M_H_DQS_DN<16>")
	)
	(segment
		(start 127.881888 -46.44644)
		(end 130.263646 -46.44644)
		(width 0.14224)
		(layer "In4.Cu")
		(net "M_H_DQS_DN<16>")
	)
	(segment
		(start 142.109444 -32.886142)
		(end 142.629128 -33.405826)
		(width 0.14224)
		(layer "In4.Cu")
		(net "M_H_DQS_DN<16>")
	)
	(segment
		(start 126.79045 -47.537878)
		(end 127.030226 -47.298102)
		(width 0.14224)
		(layer "In4.Cu")
		(net "M_H_DQS_DN<16>")
	)
	(arc
		(start 120.734328 -53.712618)
		(mid 120.807126 -53.421855)
		(end 120.727978 -53.132736)
		(width 0.0889)
		(layer "In4.Cu")
		(net "M_H_DQS_DN<16>")
	)
	(arc
		(start 120.734328 -56.684418)
		(mid 120.807126 -56.393655)
		(end 120.727978 -56.104536)
		(width 0.0889)
		(layer "In4.Cu")
		(net "M_H_DQS_DN<16>")
	)
	(arc
		(start 120.734328 -55.693818)
		(mid 120.807126 -55.403055)
		(end 120.727978 -55.113936)
		(width 0.0889)
		(layer "In4.Cu")
		(net "M_H_DQS_DN<16>")
	)
	(arc
		(start 120.727978 -55.113936)
		(mid 120.674508 -54.918873)
		(end 120.723152 -54.722522)
		(width 0.0889)
		(layer "In4.Cu")
		(net "M_H_DQS_DN<16>")
	)
	(arc
		(start 121.096278 -52.532534)
		(mid 121.379495 -52.448253)
		(end 121.586498 -52.237386)
		(width 0.0889)
		(layer "In4.Cu")
		(net "M_H_DQS_DN<16>")
	)
	(arc
		(start 120.233948 -57.981088)
		(mid 120.732199 -57.678248)
		(end 120.727978 -57.095136)
		(width 0.0889)
		(layer "In4.Cu")
		(net "M_H_DQS_DN<16>")
	)
	(arc
		(start 119.357902 -58.876438)
		(mid 119.158004 -58.67654)
		(end 119.357902 -58.476388)
		(width 0.0889)
		(layer "In4.Cu")
		(net "M_H_DQS_DN<16>")
	)
	(arc
		(start 120.727978 -54.123336)
		(mid 120.674508 -53.928273)
		(end 120.723152 -53.731922)
		(width 0.0889)
		(layer "In4.Cu")
		(net "M_H_DQS_DN<16>")
	)
	(arc
		(start 120.734328 -54.703218)
		(mid 120.807126 -54.412455)
		(end 120.727978 -54.123336)
		(width 0.0889)
		(layer "In4.Cu")
		(net "M_H_DQS_DN<16>")
	)
	(arc
		(start 120.727978 -56.104536)
		(mid 120.674508 -55.909473)
		(end 120.723152 -55.713122)
		(width 0.0889)
		(layer "In4.Cu")
		(net "M_H_DQS_DN<16>")
	)
	(arc
		(start 119.375682 -58.476388)
		(mid 119.661044 -58.393)
		(end 119.869712 -58.18124)
		(width 0.0889)
		(layer "In4.Cu")
		(net "M_H_DQS_DN<16>")
	)
	(arc
		(start 120.727978 -53.132736)
		(mid 120.72523 -52.737269)
		(end 121.063512 -52.532534)
		(width 0.0889)
		(layer "In4.Cu")
		(net "M_H_DQS_DN<16>")
	)
	(arc
		(start 120.727978 -57.095136)
		(mid 120.674508 -56.900073)
		(end 120.723152 -56.703722)
		(width 0.0889)
		(layer "In4.Cu")
		(net "M_H_DQS_DN<16>")
	)
	(arc
		(start 119.873014 -58.175398)
		(mid 120.01898 -58.032999)
		(end 120.216168 -57.981088)
		(width 0.0889)
		(layer "In4.Cu")
		(net "M_H_DQS_DN<16>")
	)
	(segment
		(start 136.365488 -29.41828)
		(end 136.573768 -29.21)
		(width 0.1651)
		(layer "F.Cu")
		(net "M_H_DQS_DN<15>")
	)
	(segment
		(start 137.062718 -32.4866)
		(end 136.543796 -32.4866)
		(width 0.1651)
		(layer "F.Cu")
		(net "M_H_DQS_DN<15>")
	)
	(segment
		(start 132.687568 -41.129458)
		(end 132.867146 -40.94988)
		(width 0.1651)
		(layer "F.Cu")
		(net "M_H_DQS_DN<15>")
	)
	(segment
		(start 137.437368 -30.713172)
		(end 137.088118 -30.363922)
		(width 0.1651)
		(layer "F.Cu")
		(net "M_H_DQS_DN<15>")
	)
	(segment
		(start 137.197592 -28.525978)
		(end 136.74217 -28.070556)
		(width 0.1651)
		(layer "F.Cu")
		(net "M_H_DQS_DN<15>")
	)
	(segment
		(start 119.070882 -51.778408)
		(end 119.007636 -51.841654)
		(width 0.0889)
		(layer "F.Cu")
		(net "M_H_DQS_DN<15>")
	)
	(segment
		(start 136.543796 -31.6865)
		(end 137.088118 -31.6865)
		(width 0.1651)
		(layer "F.Cu")
		(net "M_H_DQS_DN<15>")
	)
	(segment
		(start 119.709184 -49.149)
		(end 119.862854 -49.149)
		(width 0.0889)
		(layer "F.Cu")
		(net "M_H_DQS_DN<15>")
	)
	(segment
		(start 122.64263 -46.369224)
		(end 129.47777 -46.369224)
		(width 0.1016)
		(layer "F.Cu")
		(net "M_H_DQS_DN<15>")
	)
	(segment
		(start 136.819894 -34.719768)
		(end 136.819894 -33.898332)
		(width 0.1651)
		(layer "F.Cu")
		(net "M_H_DQS_DN<15>")
	)
	(segment
		(start 132.67944 -41.892728)
		(end 132.687568 -41.8846)
		(width 0.1016)
		(layer "F.Cu")
		(net "M_H_DQS_DN<15>")
	)
	(segment
		(start 136.365488 -30.236922)
		(end 136.365488 -29.41828)
		(width 0.1651)
		(layer "F.Cu")
		(net "M_H_DQS_DN<15>")
	)
	(segment
		(start 133.656324 -40.340534)
		(end 133.835902 -40.160956)
		(width 0.1651)
		(layer "F.Cu")
		(net "M_H_DQS_DN<15>")
	)
	(segment
		(start 137.649458 -5.822442)
		(end 137.649458 -6.475984)
		(width 0.1651)
		(layer "F.Cu")
		(net "M_H_DQS_DN<15>")
	)
	(segment
		(start 136.365488 -32.308292)
		(end 136.365488 -31.864808)
		(width 0.1651)
		(layer "F.Cu")
		(net "M_H_DQS_DN<15>")
	)
	(segment
		(start 137.411968 -35.814)
		(end 137.411968 -35.311842)
		(width 0.1651)
		(layer "F.Cu")
		(net "M_H_DQS_DN<15>")
	)
	(segment
		(start 137.088118 -31.6865)
		(end 137.437368 -31.33725)
		(width 0.1651)
		(layer "F.Cu")
		(net "M_H_DQS_DN<15>")
	)
	(segment
		(start 118.792244 -51.734466)
		(end 118.77548 -51.71821)
		(width 0.0889)
		(layer "F.Cu")
		(net "M_H_DQS_DN<15>")
	)
	(segment
		(start 136.573768 -29.21)
		(end 137.081514 -29.21)
		(width 0.1651)
		(layer "F.Cu")
		(net "M_H_DQS_DN<15>")
	)
	(segment
		(start 132.867146 -40.94988)
		(end 133.046724 -40.94988)
		(width 0.1651)
		(layer "F.Cu")
		(net "M_H_DQS_DN<15>")
	)
	(segment
		(start 136.957054 -7.99973)
		(end 136.767824 -7.8105)
		(width 0.1651)
		(layer "F.Cu")
		(net "M_H_DQS_DN<15>")
	)
	(segment
		(start 137.165334 -7.99973)
		(end 136.957054 -7.99973)
		(width 0.1651)
		(layer "F.Cu")
		(net "M_H_DQS_DN<15>")
	)
	(segment
		(start 118.704868 -51.211988)
		(end 118.815612 -51.020726)
		(width 0.0889)
		(layer "F.Cu")
		(net "M_H_DQS_DN<15>")
	)
	(segment
		(start 137.417302 -7.747762)
		(end 137.165334 -7.99973)
		(width 0.1651)
		(layer "F.Cu")
		(net "M_H_DQS_DN<15>")
	)
	(segment
		(start 132.687568 -41.8846)
		(end 132.687568 -41.129458)
		(width 0.1651)
		(layer "F.Cu")
		(net "M_H_DQS_DN<15>")
	)
	(segment
		(start 136.543796 -32.4866)
		(end 136.365488 -32.308292)
		(width 0.1651)
		(layer "F.Cu")
		(net "M_H_DQS_DN<15>")
	)
	(segment
		(start 137.649458 -6.475984)
		(end 137.231374 -6.894068)
		(width 0.1651)
		(layer "F.Cu")
		(net "M_H_DQS_DN<15>")
	)
	(segment
		(start 136.819894 -33.898332)
		(end 137.411968 -33.306258)
		(width 0.1651)
		(layer "F.Cu")
		(net "M_H_DQS_DN<15>")
	)
	(segment
		(start 118.815612 -51.020726)
		(end 118.815612 -50.042572)
		(width 0.0889)
		(layer "F.Cu")
		(net "M_H_DQS_DN<15>")
	)
	(segment
		(start 137.197592 -29.093922)
		(end 137.197592 -28.525978)
		(width 0.1651)
		(layer "F.Cu")
		(net "M_H_DQS_DN<15>")
	)
	(segment
		(start 137.081514 -29.21)
		(end 137.197592 -29.093922)
		(width 0.1651)
		(layer "F.Cu")
		(net "M_H_DQS_DN<15>")
	)
	(segment
		(start 133.226556 -40.59047)
		(end 133.476492 -40.340534)
		(width 0.1651)
		(layer "F.Cu")
		(net "M_H_DQS_DN<15>")
	)
	(segment
		(start 137.437368 -31.33725)
		(end 137.437368 -30.713172)
		(width 0.1651)
		(layer "F.Cu")
		(net "M_H_DQS_DN<15>")
	)
	(segment
		(start 133.226556 -40.770302)
		(end 133.226556 -40.59047)
		(width 0.1651)
		(layer "F.Cu")
		(net "M_H_DQS_DN<15>")
	)
	(segment
		(start 137.231374 -7.3152)
		(end 137.417302 -7.501128)
		(width 0.1651)
		(layer "F.Cu")
		(net "M_H_DQS_DN<15>")
	)
	(segment
		(start 136.492488 -30.363922)
		(end 136.365488 -30.236922)
		(width 0.1651)
		(layer "F.Cu")
		(net "M_H_DQS_DN<15>")
	)
	(segment
		(start 137.417302 -7.501128)
		(end 137.417302 -7.747762)
		(width 0.1651)
		(layer "F.Cu")
		(net "M_H_DQS_DN<15>")
	)
	(segment
		(start 137.411968 -36.405058)
		(end 137.411968 -35.814)
		(width 0.1651)
		(layer "F.Cu")
		(net "M_H_DQS_DN<15>")
	)
	(segment
		(start 129.47777 -46.369224)
		(end 132.67944 -43.167554)
		(width 0.1016)
		(layer "F.Cu")
		(net "M_H_DQS_DN<15>")
	)
	(segment
		(start 133.835902 -39.981124)
		(end 137.411968 -36.405058)
		(width 0.1651)
		(layer "F.Cu")
		(net "M_H_DQS_DN<15>")
	)
	(segment
		(start 137.088118 -30.363922)
		(end 136.492488 -30.363922)
		(width 0.1651)
		(layer "F.Cu")
		(net "M_H_DQS_DN<15>")
	)
	(segment
		(start 132.67944 -43.167554)
		(end 132.67944 -41.892728)
		(width 0.1016)
		(layer "F.Cu")
		(net "M_H_DQS_DN<15>")
	)
	(segment
		(start 119.862854 -49.149)
		(end 122.64263 -46.369224)
		(width 0.1016)
		(layer "F.Cu")
		(net "M_H_DQS_DN<15>")
	)
	(segment
		(start 118.792498 -51.733958)
		(end 118.792244 -51.734466)
		(width 0.0889)
		(layer "F.Cu")
		(net "M_H_DQS_DN<15>")
	)
	(segment
		(start 118.815612 -50.042572)
		(end 119.709184 -49.149)
		(width 0.0889)
		(layer "F.Cu")
		(net "M_H_DQS_DN<15>")
	)
	(segment
		(start 133.835902 -40.160956)
		(end 133.835902 -39.981124)
		(width 0.1651)
		(layer "F.Cu")
		(net "M_H_DQS_DN<15>")
	)
	(segment
		(start 119.070882 -51.446938)
		(end 119.070882 -51.778408)
		(width 0.0889)
		(layer "F.Cu")
		(net "M_H_DQS_DN<15>")
	)
	(segment
		(start 137.411968 -32.83585)
		(end 137.062718 -32.4866)
		(width 0.1651)
		(layer "F.Cu")
		(net "M_H_DQS_DN<15>")
	)
	(segment
		(start 133.046724 -40.94988)
		(end 133.226556 -40.770302)
		(width 0.1651)
		(layer "F.Cu")
		(net "M_H_DQS_DN<15>")
	)
	(segment
		(start 136.365488 -31.864808)
		(end 136.543796 -31.6865)
		(width 0.1651)
		(layer "F.Cu")
		(net "M_H_DQS_DN<15>")
	)
	(segment
		(start 137.411968 -35.311842)
		(end 136.819894 -34.719768)
		(width 0.1651)
		(layer "F.Cu")
		(net "M_H_DQS_DN<15>")
	)
	(segment
		(start 137.411968 -33.306258)
		(end 137.411968 -32.83585)
		(width 0.1651)
		(layer "F.Cu")
		(net "M_H_DQS_DN<15>")
	)
	(segment
		(start 137.231374 -6.894068)
		(end 137.231374 -7.3152)
		(width 0.1651)
		(layer "F.Cu")
		(net "M_H_DQS_DN<15>")
	)
	(segment
		(start 136.767824 -7.8105)
		(end 136.748774 -7.8105)
		(width 0.1651)
		(layer "F.Cu")
		(net "M_H_DQS_DN<15>")
	)
	(segment
		(start 133.476492 -40.340534)
		(end 133.656324 -40.340534)
		(width 0.1651)
		(layer "F.Cu")
		(net "M_H_DQS_DN<15>")
	)
	(via
		(at 136.74217 -13.2334)
		(size 0.508)
		(drill 0.254)
		(layers "F.Cu" "B.Cu")
		(net "M_H_DQS_DN<15>")
	)
	(via
		(at 136.74217 -28.070556)
		(size 0.508)
		(drill 0.254)
		(layers "F.Cu" "B.Cu")
		(net "M_H_DQS_DN<15>")
	)
	(via
		(at 136.748774 -7.8105)
		(size 0.508)
		(drill 0.254)
		(layers "F.Cu" "B.Cu")
		(net "M_H_DQS_DN<15>")
	)
	(via
		(at 137.411968 -35.814)
		(size 0.508)
		(drill 0.254)
		(layers "F.Cu" "B.Cu")
		(net "M_H_DQS_DN<15>")
	)
	(arc
		(start 118.77548 -51.71821)
		(mid 118.653122 -51.477229)
		(end 118.704868 -51.211988)
		(width 0.0889)
		(layer "F.Cu")
		(net "M_H_DQS_DN<15>")
	)
	(arc
		(start 119.007636 -51.841654)
		(mid 118.891771 -51.804371)
		(end 118.792498 -51.733958)
		(width 0.0889)
		(layer "F.Cu")
		(net "M_H_DQS_DN<15>")
	)
	(segment
		(start 137.383774 -13.2588)
		(end 137.16381 -13.038836)
		(width 0.1651)
		(layer "B.Cu")
		(net "M_H_DQS_DN<15>")
	)
	(segment
		(start 137.383774 -13.589)
		(end 137.383774 -13.2588)
		(width 0.1651)
		(layer "B.Cu")
		(net "M_H_DQS_DN<15>")
	)
	(segment
		(start 137.649712 -14.566392)
		(end 137.205974 -14.122654)
		(width 0.1651)
		(layer "B.Cu")
		(net "M_H_DQS_DN<15>")
	)
	(segment
		(start 137.649712 -15.222728)
		(end 137.649712 -14.566392)
		(width 0.1651)
		(layer "B.Cu")
		(net "M_H_DQS_DN<15>")
	)
	(segment
		(start 137.205974 -13.7668)
		(end 137.383774 -13.589)
		(width 0.1651)
		(layer "B.Cu")
		(net "M_H_DQS_DN<15>")
	)
	(segment
		(start 137.16381 -13.038836)
		(end 136.936734 -13.038836)
		(width 0.1651)
		(layer "B.Cu")
		(net "M_H_DQS_DN<15>")
	)
	(segment
		(start 137.205974 -14.122654)
		(end 137.205974 -13.7668)
		(width 0.1651)
		(layer "B.Cu")
		(net "M_H_DQS_DN<15>")
	)
	(segment
		(start 137.649458 -15.222982)
		(end 137.649712 -15.222728)
		(width 0.1651)
		(layer "B.Cu")
		(net "M_H_DQS_DN<15>")
	)
	(segment
		(start 136.936734 -13.038836)
		(end 136.74217 -13.2334)
		(width 0.1651)
		(layer "B.Cu")
		(net "M_H_DQS_DN<15>")
	)
	(segment
		(start 137.180574 -14.242288)
		(end 137.180574 -13.671804)
		(width 0.14224)
		(layer "In4.Cu")
		(net "M_H_DQS_DN<15>")
	)
	(segment
		(start 137.531094 -12.444476)
		(end 137.531094 -8.344154)
		(width 0.14224)
		(layer "In4.Cu")
		(net "M_H_DQS_DN<15>")
	)
	(segment
		(start 136.944354 -8.00608)
		(end 136.748774 -7.8105)
		(width 0.14224)
		(layer "In4.Cu")
		(net "M_H_DQS_DN<15>")
	)
	(segment
		(start 137.19302 -8.00608)
		(end 136.944354 -8.00608)
		(width 0.14224)
		(layer "In4.Cu")
		(net "M_H_DQS_DN<15>")
	)
	(segment
		(start 136.74217 -13.2334)
		(end 137.531094 -12.444476)
		(width 0.14224)
		(layer "In4.Cu")
		(net "M_H_DQS_DN<15>")
	)
	(segment
		(start 137.180574 -13.671804)
		(end 136.74217 -13.2334)
		(width 0.14224)
		(layer "In4.Cu")
		(net "M_H_DQS_DN<15>")
	)
	(segment
		(start 137.508488 -15.683738)
		(end 137.000488 -15.175738)
		(width 0.14224)
		(layer "In4.Cu")
		(net "M_H_DQS_DN<15>")
	)
	(segment
		(start 137.000488 -14.422374)
		(end 137.180574 -14.242288)
		(width 0.14224)
		(layer "In4.Cu")
		(net "M_H_DQS_DN<15>")
	)
	(segment
		(start 137.000488 -15.175738)
		(end 137.000488 -14.422374)
		(width 0.14224)
		(layer "In4.Cu")
		(net "M_H_DQS_DN<15>")
	)
	(segment
		(start 136.74217 -28.070556)
		(end 137.508488 -27.304238)
		(width 0.14224)
		(layer "In4.Cu")
		(net "M_H_DQS_DN<15>")
	)
	(segment
		(start 137.508488 -27.304238)
		(end 137.508488 -15.683738)
		(width 0.14224)
		(layer "In4.Cu")
		(net "M_H_DQS_DN<15>")
	)
	(segment
		(start 137.531094 -8.344154)
		(end 137.19302 -8.00608)
		(width 0.14224)
		(layer "In4.Cu")
		(net "M_H_DQS_DN<15>")
	)
	(segment
		(start 122.216926 -37.2491)
		(end 124.369576 -35.09645)
		(width 0.1651)
		(layer "F.Cu")
		(net "M_H_DQS_DN<14>")
	)
	(segment
		(start 113.536222 -51.144424)
		(end 113.701068 -50.979578)
		(width 0.0889)
		(layer "F.Cu")
		(net "M_H_DQS_DN<14>")
	)
	(segment
		(start 118.250716 -41.214548)
		(end 118.250716 -41.0464)
		(width 0.1016)
		(layer "F.Cu")
		(net "M_H_DQS_DN<14>")
	)
	(segment
		(start 127.271526 -32.0548)
		(end 127.569468 -31.756858)
		(width 0.1651)
		(layer "F.Cu")
		(net "M_H_DQS_DN<14>")
	)
	(segment
		(start 118.789704 -39.685468)
		(end 118.969282 -39.50589)
		(width 0.1651)
		(layer "F.Cu")
		(net "M_H_DQS_DN<14>")
	)
	(segment
		(start 126.06401 -32.92602)
		(end 125.918468 -32.780478)
		(width 0.1651)
		(layer "F.Cu")
		(net "M_H_DQS_DN<14>")
	)
	(segment
		(start 128.067054 -7.747762)
		(end 127.815086 -7.99973)
		(width 0.1651)
		(layer "F.Cu")
		(net "M_H_DQS_DN<14>")
	)
	(segment
		(start 118.301516 -43.02252)
		(end 118.301516 -41.265348)
		(width 0.1016)
		(layer "F.Cu")
		(net "M_H_DQS_DN<14>")
	)
	(segment
		(start 119.328692 -39.14648)
		(end 119.633238 -38.841934)
		(width 0.1651)
		(layer "F.Cu")
		(net "M_H_DQS_DN<14>")
	)
	(segment
		(start 124.84608 -34.14395)
		(end 125.322076 -34.14395)
		(width 0.1651)
		(layer "F.Cu")
		(net "M_H_DQS_DN<14>")
	)
	(segment
		(start 113.804192 -49.617122)
		(end 113.804192 -47.519844)
		(width 0.1016)
		(layer "F.Cu")
		(net "M_H_DQS_DN<14>")
	)
	(segment
		(start 127.417576 -7.8105)
		(end 127.398526 -7.8105)
		(width 0.1651)
		(layer "F.Cu")
		(net "M_H_DQS_DN<14>")
	)
	(segment
		(start 124.384816 -33.86201)
		(end 124.56414 -33.86201)
		(width 0.1651)
		(layer "F.Cu")
		(net "M_H_DQS_DN<14>")
	)
	(segment
		(start 118.250716 -41.0464)
		(end 118.250716 -40.224456)
		(width 0.1651)
		(layer "F.Cu")
		(net "M_H_DQS_DN<14>")
	)
	(segment
		(start 127.848106 -28.307538)
		(end 127.611124 -28.070556)
		(width 0.1651)
		(layer "F.Cu")
		(net "M_H_DQS_DN<14>")
	)
	(segment
		(start 118.250716 -40.224456)
		(end 118.430294 -40.044878)
		(width 0.1651)
		(layer "F.Cu")
		(net "M_H_DQS_DN<14>")
	)
	(segment
		(start 127.815086 -7.99973)
		(end 127.606806 -7.99973)
		(width 0.1651)
		(layer "F.Cu")
		(net "M_H_DQS_DN<14>")
	)
	(segment
		(start 119.14886 -39.50589)
		(end 119.328692 -39.326312)
		(width 0.1651)
		(layer "F.Cu")
		(net "M_H_DQS_DN<14>")
	)
	(segment
		(start 119.328692 -39.326312)
		(end 119.328692 -39.14648)
		(width 0.1651)
		(layer "F.Cu")
		(net "M_H_DQS_DN<14>")
	)
	(segment
		(start 124.087636 -34.15919)
		(end 124.384816 -33.86201)
		(width 0.1651)
		(layer "F.Cu")
		(net "M_H_DQS_DN<14>")
	)
	(segment
		(start 127.881126 -6.894068)
		(end 127.881126 -7.3152)
		(width 0.1651)
		(layer "F.Cu")
		(net "M_H_DQS_DN<14>")
	)
	(segment
		(start 113.701068 -49.720246)
		(end 113.804192 -49.617122)
		(width 0.0889)
		(layer "F.Cu")
		(net "M_H_DQS_DN<14>")
	)
	(segment
		(start 127.606806 -7.99973)
		(end 127.417576 -7.8105)
		(width 0.1651)
		(layer "F.Cu")
		(net "M_H_DQS_DN<14>")
	)
	(segment
		(start 119.992902 -38.662102)
		(end 119.992902 -38.48227)
		(width 0.1651)
		(layer "F.Cu")
		(net "M_H_DQS_DN<14>")
	)
	(segment
		(start 124.087636 -34.338514)
		(end 124.087636 -34.15919)
		(width 0.1651)
		(layer "F.Cu")
		(net "M_H_DQS_DN<14>")
	)
	(segment
		(start 118.430294 -40.044878)
		(end 118.609872 -40.044878)
		(width 0.1651)
		(layer "F.Cu")
		(net "M_H_DQS_DN<14>")
	)
	(segment
		(start 118.969282 -39.50589)
		(end 119.14886 -39.50589)
		(width 0.1651)
		(layer "F.Cu")
		(net "M_H_DQS_DN<14>")
	)
	(segment
		(start 113.919762 -51.446938)
		(end 113.919762 -51.778408)
		(width 0.0889)
		(layer "F.Cu")
		(net "M_H_DQS_DN<14>")
	)
	(segment
		(start 120.53189 -37.943282)
		(end 121.226072 -37.2491)
		(width 0.1651)
		(layer "F.Cu")
		(net "M_H_DQS_DN<14>")
	)
	(segment
		(start 120.53189 -38.123114)
		(end 120.53189 -37.943282)
		(width 0.1651)
		(layer "F.Cu")
		(net "M_H_DQS_DN<14>")
	)
	(segment
		(start 119.992902 -38.48227)
		(end 120.17248 -38.302692)
		(width 0.1651)
		(layer "F.Cu")
		(net "M_H_DQS_DN<14>")
	)
	(segment
		(start 127.848106 -29.071062)
		(end 127.848106 -28.307538)
		(width 0.1651)
		(layer "F.Cu")
		(net "M_H_DQS_DN<14>")
	)
	(segment
		(start 127.233426 -29.355542)
		(end 127.378968 -29.21)
		(width 0.1651)
		(layer "F.Cu")
		(net "M_H_DQS_DN<14>")
	)
	(segment
		(start 119.81307 -38.841934)
		(end 119.992902 -38.662102)
		(width 0.1651)
		(layer "F.Cu")
		(net "M_H_DQS_DN<14>")
	)
	(segment
		(start 127.569468 -30.053788)
		(end 127.233426 -29.717746)
		(width 0.1651)
		(layer "F.Cu")
		(net "M_H_DQS_DN<14>")
	)
	(segment
		(start 127.233426 -29.717746)
		(end 127.233426 -29.355542)
		(width 0.1651)
		(layer "F.Cu")
		(net "M_H_DQS_DN<14>")
	)
	(segment
		(start 127.378968 -29.21)
		(end 127.709168 -29.21)
		(width 0.1651)
		(layer "F.Cu")
		(net "M_H_DQS_DN<14>")
	)
	(segment
		(start 124.369576 -35.09645)
		(end 124.369576 -34.620454)
		(width 0.1651)
		(layer "F.Cu")
		(net "M_H_DQS_DN<14>")
	)
	(segment
		(start 124.369576 -34.620454)
		(end 124.087636 -34.338514)
		(width 0.1651)
		(layer "F.Cu")
		(net "M_H_DQS_DN<14>")
	)
	(segment
		(start 120.17248 -38.302692)
		(end 120.352058 -38.302692)
		(width 0.1651)
		(layer "F.Cu")
		(net "M_H_DQS_DN<14>")
	)
	(segment
		(start 113.919762 -51.778408)
		(end 113.856516 -51.841654)
		(width 0.0889)
		(layer "F.Cu")
		(net "M_H_DQS_DN<14>")
	)
	(segment
		(start 118.789704 -39.8653)
		(end 118.789704 -39.685468)
		(width 0.1651)
		(layer "F.Cu")
		(net "M_H_DQS_DN<14>")
	)
	(segment
		(start 125.918468 -32.780478)
		(end 125.918468 -32.448246)
		(width 0.1651)
		(layer "F.Cu")
		(net "M_H_DQS_DN<14>")
	)
	(segment
		(start 119.633238 -38.841934)
		(end 119.81307 -38.841934)
		(width 0.1651)
		(layer "F.Cu")
		(net "M_H_DQS_DN<14>")
	)
	(segment
		(start 121.226072 -37.2491)
		(end 122.216926 -37.2491)
		(width 0.1651)
		(layer "F.Cu")
		(net "M_H_DQS_DN<14>")
	)
	(segment
		(start 127.709168 -29.21)
		(end 127.848106 -29.071062)
		(width 0.1651)
		(layer "F.Cu")
		(net "M_H_DQS_DN<14>")
	)
	(segment
		(start 125.918468 -32.448246)
		(end 126.311914 -32.0548)
		(width 0.1651)
		(layer "F.Cu")
		(net "M_H_DQS_DN<14>")
	)
	(segment
		(start 124.56414 -33.86201)
		(end 124.84608 -34.14395)
		(width 0.1651)
		(layer "F.Cu")
		(net "M_H_DQS_DN<14>")
	)
	(segment
		(start 118.609872 -40.044878)
		(end 118.789704 -39.8653)
		(width 0.1651)
		(layer "F.Cu")
		(net "M_H_DQS_DN<14>")
	)
	(segment
		(start 113.804192 -47.519844)
		(end 118.301516 -43.02252)
		(width 0.1016)
		(layer "F.Cu")
		(net "M_H_DQS_DN<14>")
	)
	(segment
		(start 128.29921 -5.822442)
		(end 128.29921 -6.475984)
		(width 0.1651)
		(layer "F.Cu")
		(net "M_H_DQS_DN<14>")
	)
	(segment
		(start 126.06401 -33.402016)
		(end 126.06401 -32.92602)
		(width 0.1651)
		(layer "F.Cu")
		(net "M_H_DQS_DN<14>")
	)
	(segment
		(start 118.301516 -41.265348)
		(end 118.250716 -41.214548)
		(width 0.1016)
		(layer "F.Cu")
		(net "M_H_DQS_DN<14>")
	)
	(segment
		(start 128.067054 -7.501128)
		(end 128.067054 -7.747762)
		(width 0.1651)
		(layer "F.Cu")
		(net "M_H_DQS_DN<14>")
	)
	(segment
		(start 120.352058 -38.302692)
		(end 120.53189 -38.123114)
		(width 0.1651)
		(layer "F.Cu")
		(net "M_H_DQS_DN<14>")
	)
	(segment
		(start 113.536222 -51.465988)
		(end 113.536222 -51.144424)
		(width 0.0889)
		(layer "F.Cu")
		(net "M_H_DQS_DN<14>")
	)
	(segment
		(start 128.299464 -5.822442)
		(end 128.29921 -5.822442)
		(width 0.1651)
		(layer "F.Cu")
		(net "M_H_DQS_DN<14>")
	)
	(segment
		(start 125.322076 -34.14395)
		(end 126.06401 -33.402016)
		(width 0.1651)
		(layer "F.Cu")
		(net "M_H_DQS_DN<14>")
	)
	(segment
		(start 126.311914 -32.0548)
		(end 127.271526 -32.0548)
		(width 0.1651)
		(layer "F.Cu")
		(net "M_H_DQS_DN<14>")
	)
	(segment
		(start 127.881126 -7.3152)
		(end 128.067054 -7.501128)
		(width 0.1651)
		(layer "F.Cu")
		(net "M_H_DQS_DN<14>")
	)
	(segment
		(start 127.569468 -31.756858)
		(end 127.569468 -30.053788)
		(width 0.1651)
		(layer "F.Cu")
		(net "M_H_DQS_DN<14>")
	)
	(segment
		(start 128.29921 -6.475984)
		(end 127.881126 -6.894068)
		(width 0.1651)
		(layer "F.Cu")
		(net "M_H_DQS_DN<14>")
	)
	(segment
		(start 127.611124 -28.070556)
		(end 127.392176 -28.070556)
		(width 0.1651)
		(layer "F.Cu")
		(net "M_H_DQS_DN<14>")
	)
	(segment
		(start 113.701068 -50.979578)
		(end 113.701068 -49.720246)
		(width 0.0889)
		(layer "F.Cu")
		(net "M_H_DQS_DN<14>")
	)
	(via
		(at 127.392176 -28.070556)
		(size 0.508)
		(drill 0.254)
		(layers "F.Cu" "B.Cu")
		(net "M_H_DQS_DN<14>")
	)
	(via
		(at 127.398526 -7.8105)
		(size 0.508)
		(drill 0.254)
		(layers "F.Cu" "B.Cu")
		(net "M_H_DQS_DN<14>")
	)
	(via
		(at 127.391922 -13.2334)
		(size 0.508)
		(drill 0.254)
		(layers "F.Cu" "B.Cu")
		(net "M_H_DQS_DN<14>")
	)
	(arc
		(start 113.856516 -51.841654)
		(mid 113.627187 -51.712814)
		(end 113.536222 -51.465988)
		(width 0.0889)
		(layer "F.Cu")
		(net "M_H_DQS_DN<14>")
	)
	(segment
		(start 128.033526 -13.2588)
		(end 127.813562 -13.038836)
		(width 0.1651)
		(layer "B.Cu")
		(net "M_H_DQS_DN<14>")
	)
	(segment
		(start 128.299464 -15.222982)
		(end 128.299464 -14.566392)
		(width 0.1651)
		(layer "B.Cu")
		(net "M_H_DQS_DN<14>")
	)
	(segment
		(start 127.855726 -13.7668)
		(end 128.033526 -13.589)
		(width 0.1651)
		(layer "B.Cu")
		(net "M_H_DQS_DN<14>")
	)
	(segment
		(start 128.033526 -13.589)
		(end 128.033526 -13.2588)
		(width 0.1651)
		(layer "B.Cu")
		(net "M_H_DQS_DN<14>")
	)
	(segment
		(start 128.299464 -14.566392)
		(end 127.855726 -14.122654)
		(width 0.1651)
		(layer "B.Cu")
		(net "M_H_DQS_DN<14>")
	)
	(segment
		(start 127.855726 -14.122654)
		(end 127.855726 -13.7668)
		(width 0.1651)
		(layer "B.Cu")
		(net "M_H_DQS_DN<14>")
	)
	(segment
		(start 127.586486 -13.038836)
		(end 127.391922 -13.2334)
		(width 0.1651)
		(layer "B.Cu")
		(net "M_H_DQS_DN<14>")
	)
	(segment
		(start 127.813562 -13.038836)
		(end 127.586486 -13.038836)
		(width 0.1651)
		(layer "B.Cu")
		(net "M_H_DQS_DN<14>")
	)
	(segment
		(start 127.843788 -8.00608)
		(end 127.594106 -8.00608)
		(width 0.14224)
		(layer "In11.Cu")
		(net "M_H_DQS_DN<14>")
	)
	(segment
		(start 128.158494 -27.304238)
		(end 128.158494 -21.251926)
		(width 0.14224)
		(layer "In11.Cu")
		(net "M_H_DQS_DN<14>")
	)
	(segment
		(start 128.158494 -19.058128)
		(end 128.158494 -15.790926)
		(width 0.14224)
		(layer "In11.Cu")
		(net "M_H_DQS_DN<14>")
	)
	(segment
		(start 127.391922 -13.2334)
		(end 128.1811 -12.444222)
		(width 0.14224)
		(layer "In11.Cu")
		(net "M_H_DQS_DN<14>")
	)
	(segment
		(start 128.158494 -15.790926)
		(end 127.650494 -15.282926)
		(width 0.14224)
		(layer "In11.Cu")
		(net "M_H_DQS_DN<14>")
	)
	(segment
		(start 128.1811 -8.343392)
		(end 127.843788 -8.00608)
		(width 0.14224)
		(layer "In11.Cu")
		(net "M_H_DQS_DN<14>")
	)
	(segment
		(start 127.392176 -28.070556)
		(end 128.158494 -27.304238)
		(width 0.14224)
		(layer "In11.Cu")
		(net "M_H_DQS_DN<14>")
	)
	(segment
		(start 127.912368 -21.0058)
		(end 127.912368 -19.304254)
		(width 0.14224)
		(layer "In11.Cu")
		(net "M_H_DQS_DN<14>")
	)
	(segment
		(start 127.650494 -15.282926)
		(end 127.650494 -14.422374)
		(width 0.14224)
		(layer "In11.Cu")
		(net "M_H_DQS_DN<14>")
	)
	(segment
		(start 127.650494 -14.422374)
		(end 127.83058 -14.242288)
		(width 0.14224)
		(layer "In11.Cu")
		(net "M_H_DQS_DN<14>")
	)
	(segment
		(start 128.1811 -12.444222)
		(end 128.1811 -8.343392)
		(width 0.14224)
		(layer "In11.Cu")
		(net "M_H_DQS_DN<14>")
	)
	(segment
		(start 127.83058 -14.242288)
		(end 127.83058 -13.672058)
		(width 0.14224)
		(layer "In11.Cu")
		(net "M_H_DQS_DN<14>")
	)
	(segment
		(start 127.83058 -13.672058)
		(end 127.391922 -13.2334)
		(width 0.14224)
		(layer "In11.Cu")
		(net "M_H_DQS_DN<14>")
	)
	(segment
		(start 128.158494 -21.251926)
		(end 127.912368 -21.0058)
		(width 0.14224)
		(layer "In11.Cu")
		(net "M_H_DQS_DN<14>")
	)
	(segment
		(start 127.912368 -19.304254)
		(end 128.158494 -19.058128)
		(width 0.14224)
		(layer "In11.Cu")
		(net "M_H_DQS_DN<14>")
	)
	(segment
		(start 127.594106 -8.00608)
		(end 127.398526 -7.8105)
		(width 0.14224)
		(layer "In11.Cu")
		(net "M_H_DQS_DN<14>")
	)
	(segment
		(start 118.531132 -7.3152)
		(end 118.71706 -7.501128)
		(width 0.1651)
		(layer "F.Cu")
		(net "M_H_DQS_DN<13>")
	)
	(segment
		(start 118.71706 -7.501128)
		(end 118.71706 -7.747762)
		(width 0.1651)
		(layer "F.Cu")
		(net "M_H_DQS_DN<13>")
	)
	(segment
		(start 107.051856 -55.409338)
		(end 106.480356 -55.409338)
		(width 0.1016)
		(layer "F.Cu")
		(net "M_H_DQS_DN<13>")
	)
	(segment
		(start 118.94947 -5.822442)
		(end 118.94947 -6.47573)
		(width 0.1651)
		(layer "F.Cu")
		(net "M_H_DQS_DN<13>")
	)
	(segment
		(start 118.94947 -6.47573)
		(end 118.531132 -6.894068)
		(width 0.1651)
		(layer "F.Cu")
		(net "M_H_DQS_DN<13>")
	)
	(segment
		(start 118.237762 -7.99973)
		(end 118.048532 -7.8105)
		(width 0.1651)
		(layer "F.Cu")
		(net "M_H_DQS_DN<13>")
	)
	(segment
		(start 118.531132 -6.894068)
		(end 118.531132 -7.3152)
		(width 0.1651)
		(layer "F.Cu")
		(net "M_H_DQS_DN<13>")
	)
	(segment
		(start 118.71706 -7.747762)
		(end 118.465092 -7.99973)
		(width 0.1651)
		(layer "F.Cu")
		(net "M_H_DQS_DN<13>")
	)
	(segment
		(start 118.465092 -7.99973)
		(end 118.237762 -7.99973)
		(width 0.1651)
		(layer "F.Cu")
		(net "M_H_DQS_DN<13>")
	)
	(via
		(at 118.048532 -7.8105)
		(size 0.508)
		(drill 0.254)
		(layers "F.Cu" "B.Cu")
		(net "M_H_DQS_DN<13>")
	)
	(via
		(at 118.041928 -13.2334)
		(size 0.508)
		(drill 0.254)
		(layers "F.Cu" "B.Cu")
		(net "M_H_DQS_DN<13>")
	)
	(via
		(at 106.480356 -55.409338)
		(size 0.508)
		(drill 0.254)
		(layers "F.Cu" "B.Cu")
		(net "M_H_DQS_DN<13>")
	)
	(segment
		(start 118.463568 -13.038836)
		(end 118.236492 -13.038836)
		(width 0.1651)
		(layer "B.Cu")
		(net "M_H_DQS_DN<13>")
	)
	(segment
		(start 118.94947 -15.222982)
		(end 118.94947 -14.566392)
		(width 0.1651)
		(layer "B.Cu")
		(net "M_H_DQS_DN<13>")
	)
	(segment
		(start 118.505732 -13.7668)
		(end 118.683532 -13.589)
		(width 0.1651)
		(layer "B.Cu")
		(net "M_H_DQS_DN<13>")
	)
	(segment
		(start 118.505732 -14.122654)
		(end 118.505732 -13.7668)
		(width 0.1651)
		(layer "B.Cu")
		(net "M_H_DQS_DN<13>")
	)
	(segment
		(start 118.683532 -13.589)
		(end 118.683532 -13.2588)
		(width 0.1651)
		(layer "B.Cu")
		(net "M_H_DQS_DN<13>")
	)
	(segment
		(start 118.236492 -13.038836)
		(end 118.041928 -13.2334)
		(width 0.1651)
		(layer "B.Cu")
		(net "M_H_DQS_DN<13>")
	)
	(segment
		(start 118.94947 -14.566392)
		(end 118.505732 -14.122654)
		(width 0.1651)
		(layer "B.Cu")
		(net "M_H_DQS_DN<13>")
	)
	(segment
		(start 118.683532 -13.2588)
		(end 118.463568 -13.038836)
		(width 0.1651)
		(layer "B.Cu")
		(net "M_H_DQS_DN<13>")
	)
	(segment
		(start 106.948224 -51.905154)
		(end 107.700572 -51.152806)
		(width 0.0889)
		(layer "In4.Cu")
		(net "M_H_DQS_DN<13>")
	)
	(segment
		(start 118.8974 -26.139648)
		(end 118.533672 -25.776174)
		(width 0.14224)
		(layer "In4.Cu")
		(net "M_H_DQS_DN<13>")
	)
	(segment
		(start 107.700572 -49.088548)
		(end 107.983528 -48.805592)
		(width 0.0889)
		(layer "In4.Cu")
		(net "M_H_DQS_DN<13>")
	)
	(segment
		(start 118.830852 -12.444476)
		(end 118.830852 -8.343392)
		(width 0.14224)
		(layer "In4.Cu")
		(net "M_H_DQS_DN<13>")
	)
	(segment
		(start 116.628672 -27.681936)
		(end 116.628672 -27.369008)
		(width 0.14224)
		(layer "In4.Cu")
		(net "M_H_DQS_DN<13>")
	)
	(segment
		(start 118.824502 -19.51228)
		(end 118.981982 -19.3548)
		(width 0.14224)
		(layer "In4.Cu")
		(net "M_H_DQS_DN<13>")
	)
	(segment
		(start 118.824248 -18.943066)
		(end 118.824248 -16.125952)
		(width 0.14224)
		(layer "In4.Cu")
		(net "M_H_DQS_DN<13>")
	)
	(segment
		(start 116.938044 -27.991308)
		(end 116.628672 -27.681936)
		(width 0.14224)
		(layer "In4.Cu")
		(net "M_H_DQS_DN<13>")
	)
	(segment
		(start 108.871004 -45.537882)
		(end 108.910374 -45.498512)
		(width 0.0889)
		(layer "In4.Cu")
		(net "M_H_DQS_DN<13>")
	)
	(segment
		(start 118.289578 -27.28341)
		(end 118.8974 -26.675588)
		(width 0.14224)
		(layer "In4.Cu")
		(net "M_H_DQS_DN<13>")
	)
	(segment
		(start 117.390164 -26.92019)
		(end 117.753384 -27.28341)
		(width 0.14224)
		(layer "In4.Cu")
		(net "M_H_DQS_DN<13>")
	)
	(segment
		(start 117.07749 -26.92019)
		(end 117.390164 -26.92019)
		(width 0.14224)
		(layer "In4.Cu")
		(net "M_H_DQS_DN<13>")
	)
	(segment
		(start 118.981982 -19.1008)
		(end 118.824248 -18.943066)
		(width 0.14224)
		(layer "In4.Cu")
		(net "M_H_DQS_DN<13>")
	)
	(segment
		(start 115.682522 -29.023564)
		(end 116.43995 -29.023564)
		(width 0.14224)
		(layer "In4.Cu")
		(net "M_H_DQS_DN<13>")
	)
	(segment
		(start 107.070906 -54.577996)
		(end 107.070906 -53.116734)
		(width 0.0889)
		(layer "In4.Cu")
		(net "M_H_DQS_DN<13>")
	)
	(segment
		(start 108.910374 -45.498512)
		(end 108.910374 -45.476414)
		(width 0.0889)
		(layer "In4.Cu")
		(net "M_H_DQS_DN<13>")
	)
	(segment
		(start 107.700572 -51.152806)
		(end 107.700572 -49.088548)
		(width 0.0889)
		(layer "In4.Cu")
		(net "M_H_DQS_DN<13>")
	)
	(segment
		(start 108.910374 -44.947586)
		(end 109.037374 -44.820586)
		(width 0.14224)
		(layer "In4.Cu")
		(net "M_H_DQS_DN<13>")
	)
	(segment
		(start 106.480356 -55.747412)
		(end 106.422444 -55.805324)
		(width 0.0889)
		(layer "In4.Cu")
		(net "M_H_DQS_DN<13>")
	)
	(segment
		(start 115.105688 -29.600398)
		(end 115.682522 -29.023564)
		(width 0.14224)
		(layer "In4.Cu")
		(net "M_H_DQS_DN<13>")
	)
	(segment
		(start 106.992166 -54.714394)
		(end 107.070906 -54.577996)
		(width 0.0889)
		(layer "In4.Cu")
		(net "M_H_DQS_DN<13>")
	)
	(segment
		(start 118.041928 -13.2334)
		(end 118.830852 -12.444476)
		(width 0.14224)
		(layer "In4.Cu")
		(net "M_H_DQS_DN<13>")
	)
	(segment
		(start 118.244112 -8.00608)
		(end 118.048532 -7.8105)
		(width 0.14224)
		(layer "In4.Cu")
		(net "M_H_DQS_DN<13>")
	)
	(segment
		(start 108.910374 -44.439586)
		(end 108.910374 -37.511482)
		(width 0.14224)
		(layer "In4.Cu")
		(net "M_H_DQS_DN<13>")
	)
	(segment
		(start 114.801142 -30.771084)
		(end 115.105688 -30.466538)
		(width 0.14224)
		(layer "In4.Cu")
		(net "M_H_DQS_DN<13>")
	)
	(segment
		(start 108.910374 -37.511482)
		(end 114.496088 -31.925768)
		(width 0.14224)
		(layer "In4.Cu")
		(net "M_H_DQS_DN<13>")
	)
	(segment
		(start 118.981982 -20.1168)
		(end 118.981982 -19.8628)
		(width 0.14224)
		(layer "In4.Cu")
		(net "M_H_DQS_DN<13>")
	)
	(segment
		(start 118.533672 -25.776174)
		(end 118.533672 -25.246584)
		(width 0.14224)
		(layer "In4.Cu")
		(net "M_H_DQS_DN<13>")
	)
	(segment
		(start 118.023132 -14.4018)
		(end 118.277132 -14.4018)
		(width 0.14224)
		(layer "In4.Cu")
		(net "M_H_DQS_DN<13>")
	)
	(segment
		(start 118.533672 -25.246584)
		(end 118.824502 -24.955754)
		(width 0.14224)
		(layer "In4.Cu")
		(net "M_H_DQS_DN<13>")
	)
	(segment
		(start 118.981982 -19.3548)
		(end 118.981982 -19.1008)
		(width 0.14224)
		(layer "In4.Cu")
		(net "M_H_DQS_DN<13>")
	)
	(segment
		(start 118.981982 -20.6248)
		(end 118.824502 -20.46732)
		(width 0.14224)
		(layer "In4.Cu")
		(net "M_H_DQS_DN<13>")
	)
	(segment
		(start 118.277132 -14.4018)
		(end 118.480332 -14.1986)
		(width 0.14224)
		(layer "In4.Cu")
		(net "M_H_DQS_DN<13>")
	)
	(segment
		(start 118.824502 -20.46732)
		(end 118.824502 -20.27428)
		(width 0.14224)
		(layer "In4.Cu")
		(net "M_H_DQS_DN<13>")
	)
	(segment
		(start 107.983528 -47.47895)
		(end 108.871004 -46.591474)
		(width 0.0889)
		(layer "In4.Cu")
		(net "M_H_DQS_DN<13>")
	)
	(segment
		(start 118.480332 -14.1986)
		(end 118.480332 -13.671804)
		(width 0.14224)
		(layer "In4.Cu")
		(net "M_H_DQS_DN<13>")
	)
	(segment
		(start 118.824502 -20.27428)
		(end 118.981982 -20.1168)
		(width 0.14224)
		(layer "In4.Cu")
		(net "M_H_DQS_DN<13>")
	)
	(segment
		(start 118.981982 -20.8788)
		(end 118.981982 -20.6248)
		(width 0.14224)
		(layer "In4.Cu")
		(net "M_H_DQS_DN<13>")
	)
	(segment
		(start 118.824502 -24.955754)
		(end 118.824502 -21.03628)
		(width 0.14224)
		(layer "In4.Cu")
		(net "M_H_DQS_DN<13>")
	)
	(segment
		(start 118.49354 -8.00608)
		(end 118.244112 -8.00608)
		(width 0.14224)
		(layer "In4.Cu")
		(net "M_H_DQS_DN<13>")
	)
	(segment
		(start 108.910374 -45.476414)
		(end 108.910374 -44.947586)
		(width 0.14224)
		(layer "In4.Cu")
		(net "M_H_DQS_DN<13>")
	)
	(segment
		(start 107.070906 -53.116734)
		(end 106.948224 -52.994052)
		(width 0.0889)
		(layer "In4.Cu")
		(net "M_H_DQS_DN<13>")
	)
	(segment
		(start 114.801142 -30.771846)
		(end 114.801142 -30.771084)
		(width 0.14224)
		(layer "In4.Cu")
		(net "M_H_DQS_DN<13>")
	)
	(segment
		(start 114.496088 -31.0769)
		(end 114.801142 -30.771846)
		(width 0.14224)
		(layer "In4.Cu")
		(net "M_H_DQS_DN<13>")
	)
	(segment
		(start 118.8974 -26.675588)
		(end 118.8974 -26.139648)
		(width 0.14224)
		(layer "In4.Cu")
		(net "M_H_DQS_DN<13>")
	)
	(segment
		(start 118.824248 -16.125952)
		(end 117.840252 -15.141956)
		(width 0.14224)
		(layer "In4.Cu")
		(net "M_H_DQS_DN<13>")
	)
	(segment
		(start 115.105688 -30.466538)
		(end 115.105688 -29.600398)
		(width 0.14224)
		(layer "In4.Cu")
		(net "M_H_DQS_DN<13>")
	)
	(segment
		(start 118.480332 -13.671804)
		(end 118.041928 -13.2334)
		(width 0.14224)
		(layer "In4.Cu")
		(net "M_H_DQS_DN<13>")
	)
	(segment
		(start 106.480356 -55.409338)
		(end 106.480356 -55.747412)
		(width 0.0889)
		(layer "In4.Cu")
		(net "M_H_DQS_DN<13>")
	)
	(segment
		(start 118.824502 -21.03628)
		(end 118.981982 -20.8788)
		(width 0.14224)
		(layer "In4.Cu")
		(net "M_H_DQS_DN<13>")
	)
	(segment
		(start 108.871004 -46.591474)
		(end 108.871004 -45.537882)
		(width 0.0889)
		(layer "In4.Cu")
		(net "M_H_DQS_DN<13>")
	)
	(segment
		(start 118.824502 -19.70532)
		(end 118.824502 -19.51228)
		(width 0.14224)
		(layer "In4.Cu")
		(net "M_H_DQS_DN<13>")
	)
	(segment
		(start 107.983528 -48.805592)
		(end 107.983528 -47.47895)
		(width 0.0889)
		(layer "In4.Cu")
		(net "M_H_DQS_DN<13>")
	)
	(segment
		(start 106.46537 -55.009288)
		(end 106.501692 -55.009288)
		(width 0.0889)
		(layer "In4.Cu")
		(net "M_H_DQS_DN<13>")
	)
	(segment
		(start 117.840252 -14.58468)
		(end 118.023132 -14.4018)
		(width 0.14224)
		(layer "In4.Cu")
		(net "M_H_DQS_DN<13>")
	)
	(segment
		(start 117.753384 -27.28341)
		(end 118.289578 -27.28341)
		(width 0.14224)
		(layer "In4.Cu")
		(net "M_H_DQS_DN<13>")
	)
	(segment
		(start 118.981982 -19.8628)
		(end 118.824502 -19.70532)
		(width 0.14224)
		(layer "In4.Cu")
		(net "M_H_DQS_DN<13>")
	)
	(segment
		(start 116.938044 -28.52547)
		(end 116.938044 -27.991308)
		(width 0.14224)
		(layer "In4.Cu")
		(net "M_H_DQS_DN<13>")
	)
	(segment
		(start 118.830852 -8.343392)
		(end 118.49354 -8.00608)
		(width 0.14224)
		(layer "In4.Cu")
		(net "M_H_DQS_DN<13>")
	)
	(segment
		(start 116.628672 -27.369008)
		(end 117.07749 -26.92019)
		(width 0.14224)
		(layer "In4.Cu")
		(net "M_H_DQS_DN<13>")
	)
	(segment
		(start 114.496088 -31.925768)
		(end 114.496088 -31.0769)
		(width 0.14224)
		(layer "In4.Cu")
		(net "M_H_DQS_DN<13>")
	)
	(segment
		(start 106.948224 -52.994052)
		(end 106.948224 -51.905154)
		(width 0.0889)
		(layer "In4.Cu")
		(net "M_H_DQS_DN<13>")
	)
	(segment
		(start 117.840252 -15.141956)
		(end 117.840252 -14.58468)
		(width 0.14224)
		(layer "In4.Cu")
		(net "M_H_DQS_DN<13>")
	)
	(segment
		(start 109.037374 -44.820586)
		(end 109.037374 -44.566586)
		(width 0.14224)
		(layer "In4.Cu")
		(net "M_H_DQS_DN<13>")
	)
	(segment
		(start 116.43995 -29.023564)
		(end 116.938044 -28.52547)
		(width 0.14224)
		(layer "In4.Cu")
		(net "M_H_DQS_DN<13>")
	)
	(segment
		(start 109.037374 -44.566586)
		(end 108.910374 -44.439586)
		(width 0.14224)
		(layer "In4.Cu")
		(net "M_H_DQS_DN<13>")
	)
	(arc
		(start 106.501692 -55.009288)
		(mid 106.785042 -54.925211)
		(end 106.992166 -54.714394)
		(width 0.0889)
		(layer "In4.Cu")
		(net "M_H_DQS_DN<13>")
	)
	(arc
		(start 106.422444 -55.805324)
		(mid 106.080521 -55.387783)
		(end 106.46537 -55.009288)
		(width 0.0889)
		(layer "In4.Cu")
		(net "M_H_DQS_DN<13>")
	)
	(segment
		(start 78.310232 -49.33696)
		(end 78.310232 -49.265586)
		(width 0.0889)
		(layer "F.Cu")
		(net "M_H_DQS_DN<12>")
	)
	(segment
		(start 63.248032 -29.041598)
		(end 63.248032 -28.264358)
		(width 0.1651)
		(layer "F.Cu")
		(net "M_H_DQS_DN<12>")
	)
	(segment
		(start 63.467234 -7.501128)
		(end 63.467234 -7.747762)
		(width 0.1651)
		(layer "F.Cu")
		(net "M_H_DQS_DN<12>")
	)
	(segment
		(start 62.672468 -37.238432)
		(end 62.672468 -36.87699)
		(width 0.1651)
		(layer "F.Cu")
		(net "M_H_DQS_DN<12>")
	)
	(segment
		(start 62.596268 -30.35554)
		(end 62.596268 -30.1117)
		(width 0.1651)
		(layer "F.Cu")
		(net "M_H_DQS_DN<12>")
	)
	(segment
		(start 62.596268 -35.062922)
		(end 62.596268 -34.533078)
		(width 0.1651)
		(layer "F.Cu")
		(net "M_H_DQS_DN<12>")
	)
	(segment
		(start 62.728348 -31.50362)
		(end 62.728348 -31.24962)
		(width 0.1651)
		(layer "F.Cu")
		(net "M_H_DQS_DN<12>")
	)
	(segment
		(start 62.596268 -32.705802)
		(end 62.596268 -32.3977)
		(width 0.1651)
		(layer "F.Cu")
		(net "M_H_DQS_DN<12>")
	)
	(segment
		(start 78.509368 -49.536096)
		(end 78.310232 -49.33696)
		(width 0.0889)
		(layer "F.Cu")
		(net "M_H_DQS_DN<12>")
	)
	(segment
		(start 63.05423 -29.2354)
		(end 63.248032 -29.041598)
		(width 0.1651)
		(layer "F.Cu")
		(net "M_H_DQS_DN<12>")
	)
	(segment
		(start 63.485268 -33.220152)
		(end 63.149226 -32.88411)
		(width 0.1651)
		(layer "F.Cu")
		(net "M_H_DQS_DN<12>")
	)
	(segment
		(start 77.034136 -47.98949)
		(end 73.046336 -47.98949)
		(width 0.1016)
		(layer "F.Cu")
		(net "M_H_DQS_DN<12>")
	)
	(segment
		(start 63.467488 -36.36264)
		(end 63.467488 -35.941)
		(width 0.1651)
		(layer "F.Cu")
		(net "M_H_DQS_DN<12>")
	)
	(segment
		(start 62.728348 -31.24962)
		(end 62.596268 -31.11754)
		(width 0.1651)
		(layer "F.Cu")
		(net "M_H_DQS_DN<12>")
	)
	(segment
		(start 66.812922 -46.181264)
		(end 63.459868 -42.82821)
		(width 0.1651)
		(layer "F.Cu")
		(net "M_H_DQS_DN<12>")
	)
	(segment
		(start 73.046336 -47.98949)
		(end 72.601836 -47.54499)
		(width 0.1016)
		(layer "F.Cu")
		(net "M_H_DQS_DN<12>")
	)
	(segment
		(start 67.45732 -46.365414)
		(end 66.997072 -46.365414)
		(width 0.1016)
		(layer "F.Cu")
		(net "M_H_DQS_DN<12>")
	)
	(segment
		(start 78.909672 -50.47361)
		(end 78.846426 -50.536856)
		(width 0.0889)
		(layer "F.Cu")
		(net "M_H_DQS_DN<12>")
	)
	(segment
		(start 62.596268 -30.8737)
		(end 62.728348 -30.74162)
		(width 0.1651)
		(layer "F.Cu")
		(net "M_H_DQS_DN<12>")
	)
	(segment
		(start 62.728348 -32.01162)
		(end 62.596268 -31.87954)
		(width 0.1651)
		(layer "F.Cu")
		(net "M_H_DQS_DN<12>")
	)
	(segment
		(start 63.69939 -6.66496)
		(end 63.281306 -7.083044)
		(width 0.1651)
		(layer "F.Cu")
		(net "M_H_DQS_DN<12>")
	)
	(segment
		(start 62.774576 -32.88411)
		(end 62.596268 -32.705802)
		(width 0.1651)
		(layer "F.Cu")
		(net "M_H_DQS_DN<12>")
	)
	(segment
		(start 72.601836 -47.54499)
		(end 68.636896 -47.54499)
		(width 0.1016)
		(layer "F.Cu")
		(net "M_H_DQS_DN<12>")
	)
	(segment
		(start 62.728348 -29.72562)
		(end 62.596268 -29.59354)
		(width 0.1651)
		(layer "F.Cu")
		(net "M_H_DQS_DN<12>")
	)
	(segment
		(start 62.596268 -34.533078)
		(end 62.774576 -34.35477)
		(width 0.1651)
		(layer "F.Cu")
		(net "M_H_DQS_DN<12>")
	)
	(segment
		(start 62.728348 -32.26562)
		(end 62.728348 -32.01162)
		(width 0.1651)
		(layer "F.Cu")
		(net "M_H_DQS_DN<12>")
	)
	(segment
		(start 63.459868 -38.025832)
		(end 62.672468 -37.238432)
		(width 0.1651)
		(layer "F.Cu")
		(net "M_H_DQS_DN<12>")
	)
	(segment
		(start 63.149226 -32.88411)
		(end 62.774576 -32.88411)
		(width 0.1651)
		(layer "F.Cu")
		(net "M_H_DQS_DN<12>")
	)
	(segment
		(start 62.596268 -29.59354)
		(end 62.596268 -29.3497)
		(width 0.1651)
		(layer "F.Cu")
		(net "M_H_DQS_DN<12>")
	)
	(segment
		(start 63.215266 -7.99973)
		(end 62.987936 -7.99973)
		(width 0.1651)
		(layer "F.Cu")
		(net "M_H_DQS_DN<12>")
	)
	(segment
		(start 63.118238 -36.71189)
		(end 63.467488 -36.36264)
		(width 0.1651)
		(layer "F.Cu")
		(net "M_H_DQS_DN<12>")
	)
	(segment
		(start 63.485268 -34.018728)
		(end 63.485268 -33.220152)
		(width 0.1651)
		(layer "F.Cu")
		(net "M_H_DQS_DN<12>")
	)
	(segment
		(start 62.774576 -35.24123)
		(end 62.596268 -35.062922)
		(width 0.1651)
		(layer "F.Cu")
		(net "M_H_DQS_DN<12>")
	)
	(segment
		(start 62.774576 -34.35477)
		(end 63.149226 -34.35477)
		(width 0.1651)
		(layer "F.Cu")
		(net "M_H_DQS_DN<12>")
	)
	(segment
		(start 63.248032 -28.264358)
		(end 63.05423 -28.070556)
		(width 0.1651)
		(layer "F.Cu")
		(net "M_H_DQS_DN<12>")
	)
	(segment
		(start 63.149226 -34.35477)
		(end 63.485268 -34.018728)
		(width 0.1651)
		(layer "F.Cu")
		(net "M_H_DQS_DN<12>")
	)
	(segment
		(start 63.118238 -35.24123)
		(end 62.774576 -35.24123)
		(width 0.1651)
		(layer "F.Cu")
		(net "M_H_DQS_DN<12>")
	)
	(segment
		(start 63.281306 -7.083044)
		(end 63.281306 -7.3152)
		(width 0.1651)
		(layer "F.Cu")
		(net "M_H_DQS_DN<12>")
	)
	(segment
		(start 78.310232 -49.265586)
		(end 77.034136 -47.98949)
		(width 0.1016)
		(layer "F.Cu")
		(net "M_H_DQS_DN<12>")
	)
	(segment
		(start 62.596268 -30.1117)
		(end 62.728348 -29.97962)
		(width 0.1651)
		(layer "F.Cu")
		(net "M_H_DQS_DN<12>")
	)
	(segment
		(start 62.596268 -31.87954)
		(end 62.596268 -31.6357)
		(width 0.1651)
		(layer "F.Cu")
		(net "M_H_DQS_DN<12>")
	)
	(segment
		(start 63.459868 -42.82821)
		(end 63.459868 -38.025832)
		(width 0.1651)
		(layer "F.Cu")
		(net "M_H_DQS_DN<12>")
	)
	(segment
		(start 62.710568 -29.2354)
		(end 63.05423 -29.2354)
		(width 0.1651)
		(layer "F.Cu")
		(net "M_H_DQS_DN<12>")
	)
	(segment
		(start 63.467234 -7.747762)
		(end 63.215266 -7.99973)
		(width 0.1651)
		(layer "F.Cu")
		(net "M_H_DQS_DN<12>")
	)
	(segment
		(start 63.69939 -5.822442)
		(end 63.69939 -6.66496)
		(width 0.1651)
		(layer "F.Cu")
		(net "M_H_DQS_DN<12>")
	)
	(segment
		(start 66.997072 -46.365414)
		(end 66.812922 -46.181264)
		(width 0.1016)
		(layer "F.Cu")
		(net "M_H_DQS_DN<12>")
	)
	(segment
		(start 78.909672 -50.141886)
		(end 78.909672 -50.47361)
		(width 0.0889)
		(layer "F.Cu")
		(net "M_H_DQS_DN<12>")
	)
	(segment
		(start 78.509368 -50.137314)
		(end 78.509368 -49.536096)
		(width 0.0889)
		(layer "F.Cu")
		(net "M_H_DQS_DN<12>")
	)
	(segment
		(start 62.596268 -32.3977)
		(end 62.728348 -32.26562)
		(width 0.1651)
		(layer "F.Cu")
		(net "M_H_DQS_DN<12>")
	)
	(segment
		(start 62.728348 -30.48762)
		(end 62.596268 -30.35554)
		(width 0.1651)
		(layer "F.Cu")
		(net "M_H_DQS_DN<12>")
	)
	(segment
		(start 62.596268 -29.3497)
		(end 62.710568 -29.2354)
		(width 0.1651)
		(layer "F.Cu")
		(net "M_H_DQS_DN<12>")
	)
	(segment
		(start 62.987936 -7.99973)
		(end 62.798706 -7.8105)
		(width 0.1651)
		(layer "F.Cu")
		(net "M_H_DQS_DN<12>")
	)
	(segment
		(start 62.672468 -36.87699)
		(end 62.837568 -36.71189)
		(width 0.1651)
		(layer "F.Cu")
		(net "M_H_DQS_DN<12>")
	)
	(segment
		(start 62.837568 -36.71189)
		(end 63.118238 -36.71189)
		(width 0.1651)
		(layer "F.Cu")
		(net "M_H_DQS_DN<12>")
	)
	(segment
		(start 68.636896 -47.54499)
		(end 67.45732 -46.365414)
		(width 0.1016)
		(layer "F.Cu")
		(net "M_H_DQS_DN<12>")
	)
	(segment
		(start 63.281306 -7.3152)
		(end 63.467234 -7.501128)
		(width 0.1651)
		(layer "F.Cu")
		(net "M_H_DQS_DN<12>")
	)
	(segment
		(start 63.467488 -35.59048)
		(end 63.118238 -35.24123)
		(width 0.1651)
		(layer "F.Cu")
		(net "M_H_DQS_DN<12>")
	)
	(segment
		(start 62.596268 -31.11754)
		(end 62.596268 -30.8737)
		(width 0.1651)
		(layer "F.Cu")
		(net "M_H_DQS_DN<12>")
	)
	(segment
		(start 62.728348 -29.97962)
		(end 62.728348 -29.72562)
		(width 0.1651)
		(layer "F.Cu")
		(net "M_H_DQS_DN<12>")
	)
	(segment
		(start 62.728348 -30.74162)
		(end 62.728348 -30.48762)
		(width 0.1651)
		(layer "F.Cu")
		(net "M_H_DQS_DN<12>")
	)
	(segment
		(start 63.467488 -35.941)
		(end 63.467488 -35.59048)
		(width 0.1651)
		(layer "F.Cu")
		(net "M_H_DQS_DN<12>")
	)
	(segment
		(start 63.05423 -28.070556)
		(end 62.792102 -28.070556)
		(width 0.1651)
		(layer "F.Cu")
		(net "M_H_DQS_DN<12>")
	)
	(segment
		(start 62.596268 -31.6357)
		(end 62.728348 -31.50362)
		(width 0.1651)
		(layer "F.Cu")
		(net "M_H_DQS_DN<12>")
	)
	(via
		(at 63.467488 -35.941)
		(size 0.508)
		(drill 0.254)
		(layers "F.Cu" "B.Cu")
		(net "M_H_DQS_DN<12>")
	)
	(via
		(at 62.792102 -28.070556)
		(size 0.508)
		(drill 0.254)
		(layers "F.Cu" "B.Cu")
		(net "M_H_DQS_DN<12>")
	)
	(via
		(at 62.798706 -7.8105)
		(size 0.508)
		(drill 0.254)
		(layers "F.Cu" "B.Cu")
		(net "M_H_DQS_DN<12>")
	)
	(via
		(at 62.792102 -13.2334)
		(size 0.508)
		(drill 0.254)
		(layers "F.Cu" "B.Cu")
		(net "M_H_DQS_DN<12>")
	)
	(arc
		(start 78.562962 -50.342038)
		(mid 78.522339 -50.24329)
		(end 78.509368 -50.137314)
		(width 0.0889)
		(layer "F.Cu")
		(net "M_H_DQS_DN<12>")
	)
	(arc
		(start 78.846426 -50.536856)
		(mid 78.682669 -50.471488)
		(end 78.562962 -50.342038)
		(width 0.0889)
		(layer "F.Cu")
		(net "M_H_DQS_DN<12>")
	)
	(segment
		(start 63.213742 -13.038836)
		(end 62.986666 -13.038836)
		(width 0.1651)
		(layer "B.Cu")
		(net "M_H_DQS_DN<12>")
	)
	(segment
		(start 63.255906 -13.7668)
		(end 63.433706 -13.589)
		(width 0.1651)
		(layer "B.Cu")
		(net "M_H_DQS_DN<12>")
	)
	(segment
		(start 63.699644 -15.222728)
		(end 63.699644 -14.566392)
		(width 0.1651)
		(layer "B.Cu")
		(net "M_H_DQS_DN<12>")
	)
	(segment
		(start 62.986666 -13.038836)
		(end 62.792102 -13.2334)
		(width 0.1651)
		(layer "B.Cu")
		(net "M_H_DQS_DN<12>")
	)
	(segment
		(start 63.255906 -14.122654)
		(end 63.255906 -13.7668)
		(width 0.1651)
		(layer "B.Cu")
		(net "M_H_DQS_DN<12>")
	)
	(segment
		(start 63.433706 -13.589)
		(end 63.433706 -13.2588)
		(width 0.1651)
		(layer "B.Cu")
		(net "M_H_DQS_DN<12>")
	)
	(segment
		(start 63.699644 -14.566392)
		(end 63.255906 -14.122654)
		(width 0.1651)
		(layer "B.Cu")
		(net "M_H_DQS_DN<12>")
	)
	(segment
		(start 63.433706 -13.2588)
		(end 63.213742 -13.038836)
		(width 0.1651)
		(layer "B.Cu")
		(net "M_H_DQS_DN<12>")
	)
	(segment
		(start 63.69939 -15.222982)
		(end 63.699644 -15.222728)
		(width 0.1651)
		(layer "B.Cu")
		(net "M_H_DQS_DN<12>")
	)
	(segment
		(start 62.994286 -8.00608)
		(end 63.243714 -8.00608)
		(width 0.14224)
		(layer "In4.Cu")
		(net "M_H_DQS_DN<12>")
	)
	(segment
		(start 62.792102 -13.2334)
		(end 63.230506 -13.671804)
		(width 0.14224)
		(layer "In4.Cu")
		(net "M_H_DQS_DN<12>")
	)
	(segment
		(start 63.230506 -14.242288)
		(end 63.05042 -14.422374)
		(width 0.14224)
		(layer "In4.Cu")
		(net "M_H_DQS_DN<12>")
	)
	(segment
		(start 63.581026 -12.444476)
		(end 62.792102 -13.2334)
		(width 0.14224)
		(layer "In4.Cu")
		(net "M_H_DQS_DN<12>")
	)
	(segment
		(start 63.581026 -8.343392)
		(end 63.581026 -12.444476)
		(width 0.14224)
		(layer "In4.Cu")
		(net "M_H_DQS_DN<12>")
	)
	(segment
		(start 63.05042 -14.422374)
		(end 63.05042 -15.175738)
		(width 0.14224)
		(layer "In4.Cu")
		(net "M_H_DQS_DN<12>")
	)
	(segment
		(start 63.243714 -8.00608)
		(end 63.581026 -8.343392)
		(width 0.14224)
		(layer "In4.Cu")
		(net "M_H_DQS_DN<12>")
	)
	(segment
		(start 63.55842 -15.683738)
		(end 63.55842 -27.304238)
		(width 0.14224)
		(layer "In4.Cu")
		(net "M_H_DQS_DN<12>")
	)
	(segment
		(start 63.05042 -15.175738)
		(end 63.55842 -15.683738)
		(width 0.14224)
		(layer "In4.Cu")
		(net "M_H_DQS_DN<12>")
	)
	(segment
		(start 63.55842 -27.304238)
		(end 62.792102 -28.070556)
		(width 0.14224)
		(layer "In4.Cu")
		(net "M_H_DQS_DN<12>")
	)
	(segment
		(start 62.798706 -7.8105)
		(end 62.994286 -8.00608)
		(width 0.14224)
		(layer "In4.Cu")
		(net "M_H_DQS_DN<12>")
	)
	(segment
		(start 63.230506 -13.671804)
		(end 63.230506 -14.242288)
		(width 0.14224)
		(layer "In4.Cu")
		(net "M_H_DQS_DN<12>")
	)
	(segment
		(start 54.349396 -6.66496)
		(end 53.931312 -7.083044)
		(width 0.1651)
		(layer "F.Cu")
		(net "M_H_DQS_DN<11>")
	)
	(segment
		(start 73.758806 -51.132486)
		(end 73.187306 -51.132486)
		(width 0.1016)
		(layer "F.Cu")
		(net "M_H_DQS_DN<11>")
	)
	(segment
		(start 53.931312 -7.3152)
		(end 54.11724 -7.501128)
		(width 0.1651)
		(layer "F.Cu")
		(net "M_H_DQS_DN<11>")
	)
	(segment
		(start 54.349396 -5.822442)
		(end 54.349396 -6.66496)
		(width 0.1651)
		(layer "F.Cu")
		(net "M_H_DQS_DN<11>")
	)
	(segment
		(start 53.931312 -7.083044)
		(end 53.931312 -7.3152)
		(width 0.1651)
		(layer "F.Cu")
		(net "M_H_DQS_DN<11>")
	)
	(segment
		(start 54.11724 -7.747762)
		(end 53.865272 -7.99973)
		(width 0.1651)
		(layer "F.Cu")
		(net "M_H_DQS_DN<11>")
	)
	(segment
		(start 53.865272 -7.99973)
		(end 53.637942 -7.99973)
		(width 0.1651)
		(layer "F.Cu")
		(net "M_H_DQS_DN<11>")
	)
	(segment
		(start 54.11724 -7.501128)
		(end 54.11724 -7.747762)
		(width 0.1651)
		(layer "F.Cu")
		(net "M_H_DQS_DN<11>")
	)
	(segment
		(start 53.637942 -7.99973)
		(end 53.448712 -7.8105)
		(width 0.1651)
		(layer "F.Cu")
		(net "M_H_DQS_DN<11>")
	)
	(via
		(at 53.442108 -13.2334)
		(size 0.508)
		(drill 0.254)
		(layers "F.Cu" "B.Cu")
		(net "M_H_DQS_DN<11>")
	)
	(via
		(at 73.187306 -51.132486)
		(size 0.508)
		(drill 0.254)
		(layers "F.Cu" "B.Cu")
		(net "M_H_DQS_DN<11>")
	)
	(via
		(at 53.448712 -7.8105)
		(size 0.508)
		(drill 0.254)
		(layers "F.Cu" "B.Cu")
		(net "M_H_DQS_DN<11>")
	)
	(segment
		(start 53.905912 -14.122654)
		(end 53.905912 -13.7668)
		(width 0.1651)
		(layer "B.Cu")
		(net "M_H_DQS_DN<11>")
	)
	(segment
		(start 54.349396 -15.222982)
		(end 54.349396 -14.566138)
		(width 0.1651)
		(layer "B.Cu")
		(net "M_H_DQS_DN<11>")
	)
	(segment
		(start 53.863748 -13.038836)
		(end 53.636672 -13.038836)
		(width 0.1651)
		(layer "B.Cu")
		(net "M_H_DQS_DN<11>")
	)
	(segment
		(start 54.083712 -13.589)
		(end 54.083712 -13.2588)
		(width 0.1651)
		(layer "B.Cu")
		(net "M_H_DQS_DN<11>")
	)
	(segment
		(start 54.083712 -13.2588)
		(end 53.863748 -13.038836)
		(width 0.1651)
		(layer "B.Cu")
		(net "M_H_DQS_DN<11>")
	)
	(segment
		(start 53.636672 -13.038836)
		(end 53.442108 -13.2334)
		(width 0.1651)
		(layer "B.Cu")
		(net "M_H_DQS_DN<11>")
	)
	(segment
		(start 54.349396 -14.566138)
		(end 53.905912 -14.122654)
		(width 0.1651)
		(layer "B.Cu")
		(net "M_H_DQS_DN<11>")
	)
	(segment
		(start 53.905912 -13.7668)
		(end 54.083712 -13.589)
		(width 0.1651)
		(layer "B.Cu")
		(net "M_H_DQS_DN<11>")
	)
	(segment
		(start 61.759592 -37.639244)
		(end 61.405008 -37.28466)
		(width 0.14224)
		(layer "In4.Cu")
		(net "M_H_DQS_DN<11>")
	)
	(segment
		(start 66.179446 -44.548806)
		(end 65.936876 -44.306236)
		(width 0.14224)
		(layer "In4.Cu")
		(net "M_H_DQS_DN<11>")
	)
	(segment
		(start 54.381908 -24.7904)
		(end 54.224428 -24.63292)
		(width 0.14224)
		(layer "In4.Cu")
		(net "M_H_DQS_DN<11>")
	)
	(segment
		(start 67.472052 -45.841412)
		(end 67.229482 -45.598842)
		(width 0.14224)
		(layer "In4.Cu")
		(net "M_H_DQS_DN<11>")
	)
	(segment
		(start 54.338728 -19.322796)
		(end 54.338728 -18.98015)
		(width 0.14224)
		(layer "In4.Cu")
		(net "M_H_DQS_DN<11>")
	)
	(segment
		(start 54.224428 -19.818604)
		(end 54.224428 -19.437096)
		(width 0.14224)
		(layer "In4.Cu")
		(net "M_H_DQS_DN<11>")
	)
	(segment
		(start 53.423312 -14.4018)
		(end 53.591968 -14.4018)
		(width 0.14224)
		(layer "In4.Cu")
		(net "M_H_DQS_DN<11>")
	)
	(segment
		(start 54.224428 -20.38985)
		(end 54.338728 -20.27555)
		(width 0.14224)
		(layer "In4.Cu")
		(net "M_H_DQS_DN<11>")
	)
	(segment
		(start 66.825876 -45.195236)
		(end 66.583306 -44.952666)
		(width 0.14224)
		(layer "In4.Cu")
		(net "M_H_DQS_DN<11>")
	)
	(segment
		(start 54.224428 -18.86585)
		(end 54.224428 -16.043148)
		(width 0.14224)
		(layer "In4.Cu")
		(net "M_H_DQS_DN<11>")
	)
	(segment
		(start 54.338728 -20.27555)
		(end 54.338728 -19.932904)
		(width 0.14224)
		(layer "In4.Cu")
		(net "M_H_DQS_DN<11>")
	)
	(segment
		(start 60.142374 -36.022026)
		(end 59.78779 -35.667442)
		(width 0.14224)
		(layer "In4.Cu")
		(net "M_H_DQS_DN<11>")
	)
	(segment
		(start 62.51194 -37.639244)
		(end 61.759592 -37.639244)
		(width 0.14224)
		(layer "In4.Cu")
		(net "M_H_DQS_DN<11>")
	)
	(segment
		(start 54.338728 -26.420572)
		(end 54.224428 -26.306272)
		(width 0.14224)
		(layer "In4.Cu")
		(net "M_H_DQS_DN<11>")
	)
	(segment
		(start 73.187306 -51.132486)
		(end 72.919844 -50.632614)
		(width 0.0889)
		(layer "In4.Cu")
		(net "M_H_DQS_DN<11>")
	)
	(segment
		(start 67.714368 -46.245272)
		(end 67.472052 -46.002956)
		(width 0.14224)
		(layer "In4.Cu")
		(net "M_H_DQS_DN<11>")
	)
	(segment
		(start 64.546988 -40.678608)
		(end 64.546988 -40.335708)
		(width 0.14224)
		(layer "In4.Cu")
		(net "M_H_DQS_DN<11>")
	)
	(segment
		(start 64.432688 -40.221408)
		(end 64.432688 -39.559992)
		(width 0.14224)
		(layer "In4.Cu")
		(net "M_H_DQS_DN<11>")
	)
	(segment
		(start 53.591968 -14.4018)
		(end 53.871368 -14.1224)
		(width 0.14224)
		(layer "In4.Cu")
		(net "M_H_DQS_DN<11>")
	)
	(segment
		(start 64.129158 -39.256462)
		(end 63.37681 -39.256462)
		(width 0.14224)
		(layer "In4.Cu")
		(net "M_H_DQS_DN<11>")
	)
	(segment
		(start 53.442108 -13.2334)
		(end 54.231032 -12.444476)
		(width 0.14224)
		(layer "In4.Cu")
		(net "M_H_DQS_DN<11>")
	)
	(segment
		(start 54.224428 -26.877772)
		(end 54.338728 -26.763472)
		(width 0.14224)
		(layer "In4.Cu")
		(net "M_H_DQS_DN<11>")
	)
	(segment
		(start 66.825876 -45.35678)
		(end 66.825876 -45.195236)
		(width 0.14224)
		(layer "In4.Cu")
		(net "M_H_DQS_DN<11>")
	)
	(segment
		(start 64.546988 -42.506646)
		(end 64.546988 -42.163746)
		(width 0.14224)
		(layer "In4.Cu")
		(net "M_H_DQS_DN<11>")
	)
	(segment
		(start 67.472052 -46.002956)
		(end 67.472052 -45.841412)
		(width 0.14224)
		(layer "In4.Cu")
		(net "M_H_DQS_DN<11>")
	)
	(segment
		(start 54.224428 -19.437096)
		(end 54.338728 -19.322796)
		(width 0.14224)
		(layer "In4.Cu")
		(net "M_H_DQS_DN<11>")
	)
	(segment
		(start 67.229482 -45.598842)
		(end 67.067938 -45.598842)
		(width 0.14224)
		(layer "In4.Cu")
		(net "M_H_DQS_DN<11>")
	)
	(segment
		(start 54.224428 -16.043148)
		(end 53.886862 -15.705582)
		(width 0.14224)
		(layer "In4.Cu")
		(net "M_H_DQS_DN<11>")
	)
	(segment
		(start 53.871368 -13.66266)
		(end 53.442108 -13.2334)
		(width 0.14224)
		(layer "In4.Cu")
		(net "M_H_DQS_DN<11>")
	)
	(segment
		(start 54.224428 -23.87092)
		(end 54.224428 -20.38985)
		(width 0.14224)
		(layer "In4.Cu")
		(net "M_H_DQS_DN<11>")
	)
	(segment
		(start 64.432688 -41.135554)
		(end 64.432688 -40.792908)
		(width 0.14224)
		(layer "In4.Cu")
		(net "M_H_DQS_DN<11>")
	)
	(segment
		(start 65.53327 -43.90263)
		(end 65.2907 -43.66006)
		(width 0.14224)
		(layer "In4.Cu")
		(net "M_H_DQS_DN<11>")
	)
	(segment
		(start 53.886862 -15.705582)
		(end 53.886862 -15.544038)
		(width 0.14224)
		(layer "In4.Cu")
		(net "M_H_DQS_DN<11>")
	)
	(segment
		(start 53.886862 -15.544038)
		(end 53.644292 -15.301468)
		(width 0.14224)
		(layer "In4.Cu")
		(net "M_H_DQS_DN<11>")
	)
	(segment
		(start 64.432688 -40.792908)
		(end 64.546988 -40.678608)
		(width 0.14224)
		(layer "In4.Cu")
		(net "M_H_DQS_DN<11>")
	)
	(segment
		(start 64.546988 -41.249854)
		(end 64.432688 -41.135554)
		(width 0.14224)
		(layer "In4.Cu")
		(net "M_H_DQS_DN<11>")
	)
	(segment
		(start 72.840596 -50.342038)
		(end 72.73798 -50.165)
		(width 0.0889)
		(layer "In4.Cu")
		(net "M_H_DQS_DN<11>")
	)
	(segment
		(start 67.067938 -45.598842)
		(end 66.825876 -45.35678)
		(width 0.14224)
		(layer "In4.Cu")
		(net "M_H_DQS_DN<11>")
	)
	(segment
		(start 61.405008 -37.28466)
		(end 61.405008 -36.532312)
		(width 0.14224)
		(layer "In4.Cu")
		(net "M_H_DQS_DN<11>")
	)
	(segment
		(start 67.714368 -46.975776)
		(end 67.714368 -46.245272)
		(width 0.14224)
		(layer "In4.Cu")
		(net "M_H_DQS_DN<11>")
	)
	(segment
		(start 54.381908 -25.5524)
		(end 54.224428 -25.39492)
		(width 0.14224)
		(layer "In4.Cu")
		(net "M_H_DQS_DN<11>")
	)
	(segment
		(start 65.775332 -44.306236)
		(end 65.53327 -44.064174)
		(width 0.14224)
		(layer "In4.Cu")
		(net "M_H_DQS_DN<11>")
	)
	(segment
		(start 64.432688 -42.049446)
		(end 64.432688 -41.707054)
		(width 0.14224)
		(layer "In4.Cu")
		(net "M_H_DQS_DN<11>")
	)
	(segment
		(start 54.338728 -19.932904)
		(end 54.224428 -19.818604)
		(width 0.14224)
		(layer "In4.Cu")
		(net "M_H_DQS_DN<11>")
	)
	(segment
		(start 65.53327 -44.064174)
		(end 65.53327 -43.90263)
		(width 0.14224)
		(layer "In4.Cu")
		(net "M_H_DQS_DN<11>")
	)
	(segment
		(start 66.179446 -44.71035)
		(end 66.179446 -44.548806)
		(width 0.14224)
		(layer "In4.Cu")
		(net "M_H_DQS_DN<11>")
	)
	(segment
		(start 68.316856 -47.578264)
		(end 67.714368 -46.975776)
		(width 0.14224)
		(layer "In4.Cu")
		(net "M_H_DQS_DN<11>")
	)
	(segment
		(start 66.421762 -44.952666)
		(end 66.179446 -44.71035)
		(width 0.14224)
		(layer "In4.Cu")
		(net "M_H_DQS_DN<11>")
	)
	(segment
		(start 54.224428 -24.63292)
		(end 54.224428 -24.43988)
		(width 0.14224)
		(layer "In4.Cu")
		(net "M_H_DQS_DN<11>")
	)
	(segment
		(start 54.224428 -29.351732)
		(end 54.224428 -26.877772)
		(width 0.14224)
		(layer "In4.Cu")
		(net "M_H_DQS_DN<11>")
	)
	(segment
		(start 53.240432 -14.58468)
		(end 53.423312 -14.4018)
		(width 0.14224)
		(layer "In4.Cu")
		(net "M_H_DQS_DN<11>")
	)
	(segment
		(start 64.432688 -42.620946)
		(end 64.546988 -42.506646)
		(width 0.14224)
		(layer "In4.Cu")
		(net "M_H_DQS_DN<11>")
	)
	(segment
		(start 72.73798 -50.165)
		(end 72.217534 -49.644554)
		(width 0.0889)
		(layer "In4.Cu")
		(net "M_H_DQS_DN<11>")
	)
	(segment
		(start 59.78779 -35.667442)
		(end 59.78779 -34.915094)
		(width 0.14224)
		(layer "In4.Cu")
		(net "M_H_DQS_DN<11>")
	)
	(segment
		(start 53.482748 -15.301468)
		(end 53.240432 -15.059152)
		(width 0.14224)
		(layer "In4.Cu")
		(net "M_H_DQS_DN<11>")
	)
	(segment
		(start 61.405008 -36.532312)
		(end 60.894722 -36.022026)
		(width 0.14224)
		(layer "In4.Cu")
		(net "M_H_DQS_DN<11>")
	)
	(segment
		(start 54.338728 -18.98015)
		(end 54.224428 -18.86585)
		(width 0.14224)
		(layer "In4.Cu")
		(net "M_H_DQS_DN<11>")
	)
	(segment
		(start 53.644292 -8.00608)
		(end 53.448712 -7.8105)
		(width 0.14224)
		(layer "In4.Cu")
		(net "M_H_DQS_DN<11>")
	)
	(segment
		(start 63.37681 -39.256462)
		(end 63.022226 -38.901878)
		(width 0.14224)
		(layer "In4.Cu")
		(net "M_H_DQS_DN<11>")
	)
	(segment
		(start 65.129156 -43.66006)
		(end 64.432688 -42.963592)
		(width 0.14224)
		(layer "In4.Cu")
		(net "M_H_DQS_DN<11>")
	)
	(segment
		(start 64.546988 -42.163746)
		(end 64.432688 -42.049446)
		(width 0.14224)
		(layer "In4.Cu")
		(net "M_H_DQS_DN<11>")
	)
	(segment
		(start 53.871368 -14.1224)
		(end 53.871368 -13.66266)
		(width 0.14224)
		(layer "In4.Cu")
		(net "M_H_DQS_DN<11>")
	)
	(segment
		(start 70.327266 -49.644554)
		(end 68.332604 -47.649892)
		(width 0.0889)
		(layer "In4.Cu")
		(net "M_H_DQS_DN<11>")
	)
	(segment
		(start 64.546988 -40.335708)
		(end 64.432688 -40.221408)
		(width 0.14224)
		(layer "In4.Cu")
		(net "M_H_DQS_DN<11>")
	)
	(segment
		(start 65.936876 -44.306236)
		(end 65.775332 -44.306236)
		(width 0.14224)
		(layer "In4.Cu")
		(net "M_H_DQS_DN<11>")
	)
	(segment
		(start 64.432688 -39.559992)
		(end 64.129158 -39.256462)
		(width 0.14224)
		(layer "In4.Cu")
		(net "M_H_DQS_DN<11>")
	)
	(segment
		(start 63.022226 -38.901878)
		(end 63.022226 -38.14953)
		(width 0.14224)
		(layer "In4.Cu")
		(net "M_H_DQS_DN<11>")
	)
	(segment
		(start 64.432688 -41.707054)
		(end 64.546988 -41.592754)
		(width 0.14224)
		(layer "In4.Cu")
		(net "M_H_DQS_DN<11>")
	)
	(segment
		(start 59.78779 -34.915094)
		(end 54.224428 -29.351732)
		(width 0.14224)
		(layer "In4.Cu")
		(net "M_H_DQS_DN<11>")
	)
	(segment
		(start 53.89372 -8.00608)
		(end 53.644292 -8.00608)
		(width 0.14224)
		(layer "In4.Cu")
		(net "M_H_DQS_DN<11>")
	)
	(segment
		(start 54.231032 -8.343392)
		(end 53.89372 -8.00608)
		(width 0.14224)
		(layer "In4.Cu")
		(net "M_H_DQS_DN<11>")
	)
	(segment
		(start 54.224428 -25.20188)
		(end 54.381908 -25.0444)
		(width 0.14224)
		(layer "In4.Cu")
		(net "M_H_DQS_DN<11>")
	)
	(segment
		(start 54.224428 -25.39492)
		(end 54.224428 -25.20188)
		(width 0.14224)
		(layer "In4.Cu")
		(net "M_H_DQS_DN<11>")
	)
	(segment
		(start 68.332604 -47.594012)
		(end 68.316856 -47.578264)
		(width 0.0889)
		(layer "In4.Cu")
		(net "M_H_DQS_DN<11>")
	)
	(segment
		(start 65.2907 -43.66006)
		(end 65.129156 -43.66006)
		(width 0.14224)
		(layer "In4.Cu")
		(net "M_H_DQS_DN<11>")
	)
	(segment
		(start 54.224428 -26.306272)
		(end 54.224428 -25.96388)
		(width 0.14224)
		(layer "In4.Cu")
		(net "M_H_DQS_DN<11>")
	)
	(segment
		(start 54.224428 -24.43988)
		(end 54.381908 -24.2824)
		(width 0.14224)
		(layer "In4.Cu")
		(net "M_H_DQS_DN<11>")
	)
	(segment
		(start 66.583306 -44.952666)
		(end 66.421762 -44.952666)
		(width 0.14224)
		(layer "In4.Cu")
		(net "M_H_DQS_DN<11>")
	)
	(segment
		(start 54.231032 -12.444476)
		(end 54.231032 -8.343392)
		(width 0.14224)
		(layer "In4.Cu")
		(net "M_H_DQS_DN<11>")
	)
	(segment
		(start 54.381908 -24.2824)
		(end 54.381908 -24.0284)
		(width 0.14224)
		(layer "In4.Cu")
		(net "M_H_DQS_DN<11>")
	)
	(segment
		(start 54.224428 -25.96388)
		(end 54.381908 -25.8064)
		(width 0.14224)
		(layer "In4.Cu")
		(net "M_H_DQS_DN<11>")
	)
	(segment
		(start 64.546988 -41.592754)
		(end 64.546988 -41.249854)
		(width 0.14224)
		(layer "In4.Cu")
		(net "M_H_DQS_DN<11>")
	)
	(segment
		(start 64.432688 -42.963592)
		(end 64.432688 -42.620946)
		(width 0.14224)
		(layer "In4.Cu")
		(net "M_H_DQS_DN<11>")
	)
	(segment
		(start 53.644292 -15.301468)
		(end 53.482748 -15.301468)
		(width 0.14224)
		(layer "In4.Cu")
		(net "M_H_DQS_DN<11>")
	)
	(segment
		(start 60.894722 -36.022026)
		(end 60.142374 -36.022026)
		(width 0.14224)
		(layer "In4.Cu")
		(net "M_H_DQS_DN<11>")
	)
	(segment
		(start 68.332604 -47.649892)
		(end 68.332604 -47.594012)
		(width 0.0889)
		(layer "In4.Cu")
		(net "M_H_DQS_DN<11>")
	)
	(segment
		(start 54.381908 -25.8064)
		(end 54.381908 -25.5524)
		(width 0.14224)
		(layer "In4.Cu")
		(net "M_H_DQS_DN<11>")
	)
	(segment
		(start 54.338728 -26.763472)
		(end 54.338728 -26.420572)
		(width 0.14224)
		(layer "In4.Cu")
		(net "M_H_DQS_DN<11>")
	)
	(segment
		(start 53.240432 -15.059152)
		(end 53.240432 -14.58468)
		(width 0.14224)
		(layer "In4.Cu")
		(net "M_H_DQS_DN<11>")
	)
	(segment
		(start 54.381908 -24.0284)
		(end 54.224428 -23.87092)
		(width 0.14224)
		(layer "In4.Cu")
		(net "M_H_DQS_DN<11>")
	)
	(segment
		(start 72.217534 -49.644554)
		(end 70.327266 -49.644554)
		(width 0.0889)
		(layer "In4.Cu")
		(net "M_H_DQS_DN<11>")
	)
	(segment
		(start 54.381908 -25.0444)
		(end 54.381908 -24.7904)
		(width 0.14224)
		(layer "In4.Cu")
		(net "M_H_DQS_DN<11>")
	)
	(segment
		(start 63.022226 -38.14953)
		(end 62.51194 -37.639244)
		(width 0.14224)
		(layer "In4.Cu")
		(net "M_H_DQS_DN<11>")
	)
	(arc
		(start 72.919844 -50.632614)
		(mid 72.899036 -50.482196)
		(end 72.840596 -50.342038)
		(width 0.0889)
		(layer "In4.Cu")
		(net "M_H_DQS_DN<11>")
	)
	(segment
		(start 44.581318 -7.083044)
		(end 44.581318 -7.3152)
		(width 0.1651)
		(layer "F.Cu")
		(net "M_H_DQS_DN<10>")
	)
	(segment
		(start 71.183246 -62.52464)
		(end 70.611746 -62.52464)
		(width 0.1016)
		(layer "F.Cu")
		(net "M_H_DQS_DN<10>")
	)
	(segment
		(start 44.767246 -7.501128)
		(end 44.767246 -7.747762)
		(width 0.1651)
		(layer "F.Cu")
		(net "M_H_DQS_DN<10>")
	)
	(segment
		(start 44.767246 -7.747762)
		(end 44.515278 -7.99973)
		(width 0.1651)
		(layer "F.Cu")
		(net "M_H_DQS_DN<10>")
	)
	(segment
		(start 44.999402 -5.822442)
		(end 44.999402 -6.66496)
		(width 0.1651)
		(layer "F.Cu")
		(net "M_H_DQS_DN<10>")
	)
	(segment
		(start 44.287948 -7.99973)
		(end 44.098718 -7.8105)
		(width 0.1651)
		(layer "F.Cu")
		(net "M_H_DQS_DN<10>")
	)
	(segment
		(start 44.999402 -6.66496)
		(end 44.581318 -7.083044)
		(width 0.1651)
		(layer "F.Cu")
		(net "M_H_DQS_DN<10>")
	)
	(segment
		(start 44.515278 -7.99973)
		(end 44.287948 -7.99973)
		(width 0.1651)
		(layer "F.Cu")
		(net "M_H_DQS_DN<10>")
	)
	(segment
		(start 44.581318 -7.3152)
		(end 44.767246 -7.501128)
		(width 0.1651)
		(layer "F.Cu")
		(net "M_H_DQS_DN<10>")
	)
	(via
		(at 70.611746 -62.52464)
		(size 0.508)
		(drill 0.254)
		(layers "F.Cu" "B.Cu")
		(net "M_H_DQS_DN<10>")
	)
	(via
		(at 44.098718 -7.8105)
		(size 0.508)
		(drill 0.254)
		(layers "F.Cu" "B.Cu")
		(net "M_H_DQS_DN<10>")
	)
	(via
		(at 44.092114 -13.2334)
		(size 0.508)
		(drill 0.254)
		(layers "F.Cu" "B.Cu")
		(net "M_H_DQS_DN<10>")
	)
	(segment
		(start 44.999402 -15.222982)
		(end 44.999402 -14.566138)
		(width 0.1651)
		(layer "B.Cu")
		(net "M_H_DQS_DN<10>")
	)
	(segment
		(start 44.513754 -13.038836)
		(end 44.286678 -13.038836)
		(width 0.1651)
		(layer "B.Cu")
		(net "M_H_DQS_DN<10>")
	)
	(segment
		(start 44.286678 -13.038836)
		(end 44.092114 -13.2334)
		(width 0.1651)
		(layer "B.Cu")
		(net "M_H_DQS_DN<10>")
	)
	(segment
		(start 44.555918 -13.7668)
		(end 44.733718 -13.589)
		(width 0.1651)
		(layer "B.Cu")
		(net "M_H_DQS_DN<10>")
	)
	(segment
		(start 44.733718 -13.589)
		(end 44.733718 -13.2588)
		(width 0.1651)
		(layer "B.Cu")
		(net "M_H_DQS_DN<10>")
	)
	(segment
		(start 44.555918 -14.122654)
		(end 44.555918 -13.7668)
		(width 0.1651)
		(layer "B.Cu")
		(net "M_H_DQS_DN<10>")
	)
	(segment
		(start 44.999402 -14.566138)
		(end 44.555918 -14.122654)
		(width 0.1651)
		(layer "B.Cu")
		(net "M_H_DQS_DN<10>")
	)
	(segment
		(start 44.733718 -13.2588)
		(end 44.513754 -13.038836)
		(width 0.1651)
		(layer "B.Cu")
		(net "M_H_DQS_DN<10>")
	)
	(segment
		(start 63.735966 -53.34762)
		(end 63.735966 -53.509164)
		(width 0.14224)
		(layer "In4.Cu")
		(net "M_H_DQS_DN<10>")
	)
	(segment
		(start 57.919112 -47.69231)
		(end 58.161428 -47.934626)
		(width 0.14224)
		(layer "In4.Cu")
		(net "M_H_DQS_DN<10>")
	)
	(segment
		(start 58.969148 -48.580802)
		(end 59.211718 -48.823372)
		(width 0.14224)
		(layer "In4.Cu")
		(net "M_H_DQS_DN<10>")
	)
	(segment
		(start 45.031914 -20.066)
		(end 45.031914 -20.32)
		(width 0.14224)
		(layer "In4.Cu")
		(net "M_H_DQS_DN<10>")
	)
	(segment
		(start 44.327318 -14.4018)
		(end 44.073318 -14.4018)
		(width 0.14224)
		(layer "In4.Cu")
		(net "M_H_DQS_DN<10>")
	)
	(segment
		(start 57.919112 -47.530766)
		(end 57.919112 -47.69231)
		(width 0.14224)
		(layer "In4.Cu")
		(net "M_H_DQS_DN<10>")
	)
	(segment
		(start 44.520358 -14.20876)
		(end 44.327318 -14.4018)
		(width 0.14224)
		(layer "In4.Cu")
		(net "M_H_DQS_DN<10>")
	)
	(segment
		(start 59.211718 -48.984916)
		(end 59.454034 -49.227232)
		(width 0.14224)
		(layer "In4.Cu")
		(net "M_H_DQS_DN<10>")
	)
	(segment
		(start 68.87718 -61.933836)
		(end 68.905882 -61.933836)
		(width 0.0889)
		(layer "In4.Cu")
		(net "M_H_DQS_DN<10>")
	)
	(segment
		(start 44.988734 -19.259296)
		(end 44.874434 -19.373596)
		(width 0.14224)
		(layer "In4.Cu")
		(net "M_H_DQS_DN<10>")
	)
	(segment
		(start 43.890438 -14.58468)
		(end 43.890438 -14.855952)
		(width 0.14224)
		(layer "In4.Cu")
		(net "M_H_DQS_DN<10>")
	)
	(segment
		(start 61.55436 -51.166014)
		(end 61.79693 -51.408584)
		(width 0.14224)
		(layer "In4.Cu")
		(net "M_H_DQS_DN<10>")
	)
	(segment
		(start 59.858148 -49.631346)
		(end 60.10021 -49.873408)
		(width 0.14224)
		(layer "In4.Cu")
		(net "M_H_DQS_DN<10>")
	)
	(segment
		(start 44.073318 -14.4018)
		(end 43.890438 -14.58468)
		(width 0.14224)
		(layer "In4.Cu")
		(net "M_H_DQS_DN<10>")
	)
	(segment
		(start 69.7357 -62.429136)
		(end 69.766942 -62.429136)
		(width 0.0889)
		(layer "In4.Cu")
		(net "M_H_DQS_DN<10>")
	)
	(segment
		(start 49.208182 -38.762432)
		(end 49.208182 -38.98138)
		(width 0.14224)
		(layer "In4.Cu")
		(net "M_H_DQS_DN<10>")
	)
	(segment
		(start 44.874434 -25.83688)
		(end 44.874434 -26.174192)
		(width 0.14224)
		(layer "In4.Cu")
		(net "M_H_DQS_DN<10>")
	)
	(segment
		(start 50.075846 -37.894768)
		(end 49.208182 -38.762432)
		(width 0.14224)
		(layer "In4.Cu")
		(net "M_H_DQS_DN<10>")
	)
	(segment
		(start 44.092114 -13.2334)
		(end 44.520358 -13.661644)
		(width 0.14224)
		(layer "In4.Cu")
		(net "M_H_DQS_DN<10>")
	)
	(segment
		(start 62.039246 -51.812444)
		(end 62.20079 -51.812444)
		(width 0.14224)
		(layer "In4.Cu")
		(net "M_H_DQS_DN<10>")
	)
	(segment
		(start 47.292768 -33.6677)
		(end 47.292768 -37.065966)
		(width 0.14224)
		(layer "In4.Cu")
		(net "M_H_DQS_DN<10>")
	)
	(segment
		(start 44.536868 -15.340838)
		(end 44.536868 -15.502382)
		(width 0.14224)
		(layer "In4.Cu")
		(net "M_H_DQS_DN<10>")
	)
	(segment
		(start 44.881038 -12.444476)
		(end 44.881038 -8.343392)
		(width 0.14224)
		(layer "In4.Cu")
		(net "M_H_DQS_DN<10>")
	)
	(segment
		(start 62.44336 -52.055014)
		(end 62.44336 -52.216558)
		(width 0.14224)
		(layer "In4.Cu")
		(net "M_H_DQS_DN<10>")
	)
	(segment
		(start 66.81343 -57.961022)
		(end 66.969894 -57.961022)
		(width 0.0889)
		(layer "In4.Cu")
		(net "M_H_DQS_DN<10>")
	)
	(segment
		(start 48.61687 -37.65296)
		(end 49.225454 -37.044376)
		(width 0.14224)
		(layer "In4.Cu")
		(net "M_H_DQS_DN<10>")
	)
	(segment
		(start 58.161428 -47.934626)
		(end 58.322972 -47.934626)
		(width 0.14224)
		(layer "In4.Cu")
		(net "M_H_DQS_DN<10>")
	)
	(segment
		(start 43.890438 -14.855952)
		(end 44.132754 -15.098268)
		(width 0.14224)
		(layer "In4.Cu")
		(net "M_H_DQS_DN<10>")
	)
	(segment
		(start 57.272936 -46.88459)
		(end 57.272936 -47.046134)
		(width 0.14224)
		(layer "In4.Cu")
		(net "M_H_DQS_DN<10>")
	)
	(segment
		(start 64.689228 -54.462426)
		(end 64.851026 -54.462426)
		(width 0.14224)
		(layer "In4.Cu")
		(net "M_H_DQS_DN<10>")
	)
	(segment
		(start 47.879762 -37.65296)
		(end 48.61687 -37.65296)
		(width 0.14224)
		(layer "In4.Cu")
		(net "M_H_DQS_DN<10>")
	)
	(segment
		(start 44.520358 -13.661644)
		(end 44.520358 -14.20876)
		(width 0.14224)
		(layer "In4.Cu")
		(net "M_H_DQS_DN<10>")
	)
	(segment
		(start 44.543726 -8.00608)
		(end 44.294298 -8.00608)
		(width 0.14224)
		(layer "In4.Cu")
		(net "M_H_DQS_DN<10>")
	)
	(segment
		(start 58.322972 -47.934626)
		(end 58.565542 -48.177196)
		(width 0.14224)
		(layer "In4.Cu")
		(net "M_H_DQS_DN<10>")
	)
	(segment
		(start 58.565542 -48.177196)
		(end 58.565542 -48.33874)
		(width 0.14224)
		(layer "In4.Cu")
		(net "M_H_DQS_DN<10>")
	)
	(segment
		(start 49.225454 -37.044376)
		(end 49.628044 -37.044376)
		(width 0.14224)
		(layer "In4.Cu")
		(net "M_H_DQS_DN<10>")
	)
	(segment
		(start 59.858148 -49.469802)
		(end 59.858148 -49.631346)
		(width 0.14224)
		(layer "In4.Cu")
		(net "M_H_DQS_DN<10>")
	)
	(segment
		(start 65.093342 -54.704996)
		(end 65.093342 -54.86654)
		(width 0.14224)
		(layer "In4.Cu")
		(net "M_H_DQS_DN<10>")
	)
	(segment
		(start 70.091808 -62.535308)
		(end 70.091808 -62.535562)
		(width 0.0889)
		(layer "In4.Cu")
		(net "M_H_DQS_DN<10>")
	)
	(segment
		(start 60.504324 -50.115978)
		(end 60.504324 -50.277522)
		(width 0.14224)
		(layer "In4.Cu")
		(net "M_H_DQS_DN<10>")
	)
	(segment
		(start 45.484288 -26.784046)
		(end 45.484288 -31.85922)
		(width 0.14224)
		(layer "In4.Cu")
		(net "M_H_DQS_DN<10>")
	)
	(segment
		(start 63.493396 -53.10505)
		(end 63.735966 -53.34762)
		(width 0.14224)
		(layer "In4.Cu")
		(net "M_H_DQS_DN<10>")
	)
	(segment
		(start 70.301358 -62.62243)
		(end 70.611746 -62.52464)
		(width 0.0889)
		(layer "In4.Cu")
		(net "M_H_DQS_DN<10>")
	)
	(segment
		(start 45.031914 -24.6634)
		(end 45.031914 -24.9174)
		(width 0.14224)
		(layer "In4.Cu")
		(net "M_H_DQS_DN<10>")
	)
	(segment
		(start 44.874434 -24.31288)
		(end 44.874434 -24.50592)
		(width 0.14224)
		(layer "In4.Cu")
		(net "M_H_DQS_DN<10>")
	)
	(segment
		(start 44.874434 -19.373596)
		(end 44.874434 -19.90852)
		(width 0.14224)
		(layer "In4.Cu")
		(net "M_H_DQS_DN<10>")
	)
	(segment
		(start 44.874434 -24.50592)
		(end 45.031914 -24.6634)
		(width 0.14224)
		(layer "In4.Cu")
		(net "M_H_DQS_DN<10>")
	)
	(segment
		(start 70.21322 -62.585854)
		(end 70.301358 -62.62243)
		(width 0.0889)
		(layer "In4.Cu")
		(net "M_H_DQS_DN<10>")
	)
	(segment
		(start 66.562732 -57.710324)
		(end 66.81343 -57.961022)
		(width 0.0889)
		(layer "In4.Cu")
		(net "M_H_DQS_DN<10>")
	)
	(segment
		(start 61.150754 -50.923952)
		(end 61.392816 -51.166014)
		(width 0.14224)
		(layer "In4.Cu")
		(net "M_H_DQS_DN<10>")
	)
	(segment
		(start 66.562732 -57.302146)
		(end 66.562732 -57.710324)
		(width 0.0889)
		(layer "In4.Cu")
		(net "M_H_DQS_DN<10>")
	)
	(segment
		(start 57.514998 -47.288196)
		(end 57.676542 -47.288196)
		(width 0.14224)
		(layer "In4.Cu")
		(net "M_H_DQS_DN<10>")
	)
	(segment
		(start 64.382142 -54.15534)
		(end 64.689228 -54.462426)
		(width 0.14224)
		(layer "In4.Cu")
		(net "M_H_DQS_DN<10>")
	)
	(segment
		(start 65.093342 -54.86654)
		(end 65.339468 -55.112666)
		(width 0.14224)
		(layer "In4.Cu")
		(net "M_H_DQS_DN<10>")
	)
	(segment
		(start 65.339468 -56.02351)
		(end 66.112136 -56.796178)
		(width 0.14224)
		(layer "In4.Cu")
		(net "M_H_DQS_DN<10>")
	)
	(segment
		(start 66.969894 -57.961022)
		(end 68.288408 -59.279536)
		(width 0.0889)
		(layer "In4.Cu")
		(net "M_H_DQS_DN<10>")
	)
	(segment
		(start 66.127884 -56.867298)
		(end 66.562732 -57.302146)
		(width 0.0889)
		(layer "In4.Cu")
		(net "M_H_DQS_DN<10>")
	)
	(segment
		(start 66.127884 -56.811926)
		(end 66.127884 -56.867298)
		(width 0.0889)
		(layer "In4.Cu")
		(net "M_H_DQS_DN<10>")
	)
	(segment
		(start 58.565542 -48.33874)
		(end 58.807604 -48.580802)
		(width 0.14224)
		(layer "In4.Cu")
		(net "M_H_DQS_DN<10>")
	)
	(segment
		(start 59.454034 -49.227232)
		(end 59.615578 -49.227232)
		(width 0.14224)
		(layer "In4.Cu")
		(net "M_H_DQS_DN<10>")
	)
	(segment
		(start 61.79693 -51.408584)
		(end 61.79693 -51.570128)
		(width 0.14224)
		(layer "In4.Cu")
		(net "M_H_DQS_DN<10>")
	)
	(segment
		(start 44.874434 -23.74392)
		(end 45.031914 -23.9014)
		(width 0.14224)
		(layer "In4.Cu")
		(net "M_H_DQS_DN<10>")
	)
	(segment
		(start 61.150754 -50.762408)
		(end 61.150754 -50.923952)
		(width 0.14224)
		(layer "In4.Cu")
		(net "M_H_DQS_DN<10>")
	)
	(segment
		(start 63.978028 -53.751226)
		(end 64.139572 -53.751226)
		(width 0.14224)
		(layer "In4.Cu")
		(net "M_H_DQS_DN<10>")
	)
	(segment
		(start 44.874434 -15.839948)
		(end 44.874434 -18.80235)
		(width 0.14224)
		(layer "In4.Cu")
		(net "M_H_DQS_DN<10>")
	)
	(segment
		(start 44.874434 -20.47748)
		(end 44.874434 -23.74392)
		(width 0.14224)
		(layer "In4.Cu")
		(net "M_H_DQS_DN<10>")
	)
	(segment
		(start 44.092114 -13.2334)
		(end 44.881038 -12.444476)
		(width 0.14224)
		(layer "In4.Cu")
		(net "M_H_DQS_DN<10>")
	)
	(segment
		(start 44.988734 -18.91665)
		(end 44.988734 -19.259296)
		(width 0.14224)
		(layer "In4.Cu")
		(net "M_H_DQS_DN<10>")
	)
	(segment
		(start 49.208182 -38.98138)
		(end 56.868822 -46.64202)
		(width 0.14224)
		(layer "In4.Cu")
		(net "M_H_DQS_DN<10>")
	)
	(segment
		(start 61.392816 -51.166014)
		(end 61.55436 -51.166014)
		(width 0.14224)
		(layer "In4.Cu")
		(net "M_H_DQS_DN<10>")
	)
	(segment
		(start 63.331852 -53.10505)
		(end 63.493396 -53.10505)
		(width 0.14224)
		(layer "In4.Cu")
		(net "M_H_DQS_DN<10>")
	)
	(segment
		(start 45.031914 -25.4254)
		(end 45.031914 -25.6794)
		(width 0.14224)
		(layer "In4.Cu")
		(net "M_H_DQS_DN<10>")
	)
	(segment
		(start 58.807604 -48.580802)
		(end 58.969148 -48.580802)
		(width 0.14224)
		(layer "In4.Cu")
		(net "M_H_DQS_DN<10>")
	)
	(segment
		(start 57.676542 -47.288196)
		(end 57.919112 -47.530766)
		(width 0.14224)
		(layer "In4.Cu")
		(net "M_H_DQS_DN<10>")
	)
	(segment
		(start 50.075846 -37.492178)
		(end 50.075846 -37.894768)
		(width 0.14224)
		(layer "In4.Cu")
		(net "M_H_DQS_DN<10>")
	)
	(segment
		(start 45.031914 -24.9174)
		(end 44.874434 -25.07488)
		(width 0.14224)
		(layer "In4.Cu")
		(net "M_H_DQS_DN<10>")
	)
	(segment
		(start 44.294298 -8.00608)
		(end 44.098718 -7.8105)
		(width 0.14224)
		(layer "In4.Cu")
		(net "M_H_DQS_DN<10>")
	)
	(segment
		(start 61.79693 -51.570128)
		(end 62.039246 -51.812444)
		(width 0.14224)
		(layer "In4.Cu")
		(net "M_H_DQS_DN<10>")
	)
	(segment
		(start 59.615578 -49.227232)
		(end 59.858148 -49.469802)
		(width 0.14224)
		(layer "In4.Cu")
		(net "M_H_DQS_DN<10>")
	)
	(segment
		(start 56.868822 -46.64202)
		(end 57.030366 -46.64202)
		(width 0.14224)
		(layer "In4.Cu")
		(net "M_H_DQS_DN<10>")
	)
	(segment
		(start 44.874434 -18.80235)
		(end 44.988734 -18.91665)
		(width 0.14224)
		(layer "In4.Cu")
		(net "M_H_DQS_DN<10>")
	)
	(segment
		(start 63.735966 -53.509164)
		(end 63.978028 -53.751226)
		(width 0.14224)
		(layer "In4.Cu")
		(net "M_H_DQS_DN<10>")
	)
	(segment
		(start 44.132754 -15.098268)
		(end 44.294298 -15.098268)
		(width 0.14224)
		(layer "In4.Cu")
		(net "M_H_DQS_DN<10>")
	)
	(segment
		(start 60.74664 -50.519838)
		(end 60.908184 -50.519838)
		(width 0.14224)
		(layer "In4.Cu")
		(net "M_H_DQS_DN<10>")
	)
	(segment
		(start 60.504324 -50.277522)
		(end 60.74664 -50.519838)
		(width 0.14224)
		(layer "In4.Cu")
		(net "M_H_DQS_DN<10>")
	)
	(segment
		(start 44.536868 -15.502382)
		(end 44.874434 -15.839948)
		(width 0.14224)
		(layer "In4.Cu")
		(net "M_H_DQS_DN<10>")
	)
	(segment
		(start 63.089536 -52.70119)
		(end 63.089536 -52.862734)
		(width 0.14224)
		(layer "In4.Cu")
		(net "M_H_DQS_DN<10>")
	)
	(segment
		(start 44.874434 -25.26792)
		(end 45.031914 -25.4254)
		(width 0.14224)
		(layer "In4.Cu")
		(net "M_H_DQS_DN<10>")
	)
	(segment
		(start 47.292768 -37.065966)
		(end 47.879762 -37.65296)
		(width 0.14224)
		(layer "In4.Cu")
		(net "M_H_DQS_DN<10>")
	)
	(segment
		(start 44.874434 -25.07488)
		(end 44.874434 -25.26792)
		(width 0.14224)
		(layer "In4.Cu")
		(net "M_H_DQS_DN<10>")
	)
	(segment
		(start 62.44336 -52.216558)
		(end 62.685422 -52.45862)
		(width 0.14224)
		(layer "In4.Cu")
		(net "M_H_DQS_DN<10>")
	)
	(segment
		(start 68.288408 -59.279536)
		(end 68.547742 -59.738514)
		(width 0.0889)
		(layer "In4.Cu")
		(net "M_H_DQS_DN<10>")
	)
	(segment
		(start 62.846966 -52.45862)
		(end 63.089536 -52.70119)
		(width 0.14224)
		(layer "In4.Cu")
		(net "M_H_DQS_DN<10>")
	)
	(segment
		(start 59.211718 -48.823372)
		(end 59.211718 -48.984916)
		(width 0.14224)
		(layer "In4.Cu")
		(net "M_H_DQS_DN<10>")
	)
	(segment
		(start 60.908184 -50.519838)
		(end 61.150754 -50.762408)
		(width 0.14224)
		(layer "In4.Cu")
		(net "M_H_DQS_DN<10>")
	)
	(segment
		(start 45.031914 -24.1554)
		(end 44.874434 -24.31288)
		(width 0.14224)
		(layer "In4.Cu")
		(net "M_H_DQS_DN<10>")
	)
	(segment
		(start 64.139572 -53.751226)
		(end 64.382142 -53.993542)
		(width 0.14224)
		(layer "In4.Cu")
		(net "M_H_DQS_DN<10>")
	)
	(segment
		(start 62.685422 -52.45862)
		(end 62.846966 -52.45862)
		(width 0.14224)
		(layer "In4.Cu")
		(net "M_H_DQS_DN<10>")
	)
	(segment
		(start 57.030366 -46.64202)
		(end 57.272936 -46.88459)
		(width 0.14224)
		(layer "In4.Cu")
		(net "M_H_DQS_DN<10>")
	)
	(segment
		(start 64.851026 -54.462426)
		(end 65.093342 -54.704996)
		(width 0.14224)
		(layer "In4.Cu")
		(net "M_H_DQS_DN<10>")
	)
	(segment
		(start 44.874434 -19.90852)
		(end 45.031914 -20.066)
		(width 0.14224)
		(layer "In4.Cu")
		(net "M_H_DQS_DN<10>")
	)
	(segment
		(start 45.031914 -25.6794)
		(end 44.874434 -25.83688)
		(width 0.14224)
		(layer "In4.Cu")
		(net "M_H_DQS_DN<10>")
	)
	(segment
		(start 65.339468 -55.112666)
		(end 65.339468 -56.02351)
		(width 0.14224)
		(layer "In4.Cu")
		(net "M_H_DQS_DN<10>")
	)
	(segment
		(start 49.628044 -37.044376)
		(end 50.075846 -37.492178)
		(width 0.14224)
		(layer "In4.Cu")
		(net "M_H_DQS_DN<10>")
	)
	(segment
		(start 66.112136 -56.796178)
		(end 66.127884 -56.811926)
		(width 0.0889)
		(layer "In4.Cu")
		(net "M_H_DQS_DN<10>")
	)
	(segment
		(start 60.10021 -49.873408)
		(end 60.261754 -49.873408)
		(width 0.14224)
		(layer "In4.Cu")
		(net "M_H_DQS_DN<10>")
	)
	(segment
		(start 45.031914 -20.32)
		(end 44.874434 -20.47748)
		(width 0.14224)
		(layer "In4.Cu")
		(net "M_H_DQS_DN<10>")
	)
	(segment
		(start 44.294298 -15.098268)
		(end 44.536868 -15.340838)
		(width 0.14224)
		(layer "In4.Cu")
		(net "M_H_DQS_DN<10>")
	)
	(segment
		(start 57.272936 -47.046134)
		(end 57.514998 -47.288196)
		(width 0.14224)
		(layer "In4.Cu")
		(net "M_H_DQS_DN<10>")
	)
	(segment
		(start 63.089536 -52.862734)
		(end 63.331852 -53.10505)
		(width 0.14224)
		(layer "In4.Cu")
		(net "M_H_DQS_DN<10>")
	)
	(segment
		(start 45.031914 -23.9014)
		(end 45.031914 -24.1554)
		(width 0.14224)
		(layer "In4.Cu")
		(net "M_H_DQS_DN<10>")
	)
	(segment
		(start 60.261754 -49.873408)
		(end 60.504324 -50.115978)
		(width 0.14224)
		(layer "In4.Cu")
		(net "M_H_DQS_DN<10>")
	)
	(segment
		(start 64.382142 -53.993542)
		(end 64.382142 -54.15534)
		(width 0.14224)
		(layer "In4.Cu")
		(net "M_H_DQS_DN<10>")
	)
	(segment
		(start 44.874434 -26.174192)
		(end 45.484288 -26.784046)
		(width 0.14224)
		(layer "In4.Cu")
		(net "M_H_DQS_DN<10>")
	)
	(segment
		(start 62.20079 -51.812444)
		(end 62.44336 -52.055014)
		(width 0.14224)
		(layer "In4.Cu")
		(net "M_H_DQS_DN<10>")
	)
	(segment
		(start 44.881038 -8.343392)
		(end 44.543726 -8.00608)
		(width 0.14224)
		(layer "In4.Cu")
		(net "M_H_DQS_DN<10>")
	)
	(segment
		(start 45.484288 -31.85922)
		(end 47.292768 -33.6677)
		(width 0.14224)
		(layer "In4.Cu")
		(net "M_H_DQS_DN<10>")
	)
	(arc
		(start 69.99097 -62.47892)
		(mid 70.042772 -62.504641)
		(end 70.091808 -62.535308)
		(width 0.0889)
		(layer "In4.Cu")
		(net "M_H_DQS_DN<10>")
	)
	(arc
		(start 69.766942 -62.429136)
		(mid 69.881395 -62.443049)
		(end 69.99097 -62.47892)
		(width 0.0889)
		(layer "In4.Cu")
		(net "M_H_DQS_DN<10>")
	)
	(arc
		(start 68.547996 -60.743338)
		(mid 68.627001 -61.038486)
		(end 68.547996 -61.333634)
		(width 0.0889)
		(layer "In4.Cu")
		(net "M_H_DQS_DN<10>")
	)
	(arc
		(start 68.905882 -61.933836)
		(mid 69.197418 -62.013706)
		(end 69.407532 -62.231016)
		(width 0.0889)
		(layer "In4.Cu")
		(net "M_H_DQS_DN<10>")
	)
	(arc
		(start 69.407532 -62.231016)
		(mid 69.546378 -62.37186)
		(end 69.7357 -62.429136)
		(width 0.0889)
		(layer "In4.Cu")
		(net "M_H_DQS_DN<10>")
	)
	(arc
		(start 70.091808 -62.535562)
		(mid 70.152516 -62.560703)
		(end 70.21322 -62.585854)
		(width 0.0889)
		(layer "In4.Cu")
		(net "M_H_DQS_DN<10>")
	)
	(arc
		(start 68.547488 -60.34405)
		(mid 68.494437 -60.543753)
		(end 68.547996 -60.743338)
		(width 0.0889)
		(layer "In4.Cu")
		(net "M_H_DQS_DN<10>")
	)
	(arc
		(start 68.547742 -59.738514)
		(mid 68.630496 -60.041311)
		(end 68.547488 -60.34405)
		(width 0.0889)
		(layer "In4.Cu")
		(net "M_H_DQS_DN<10>")
	)
	(arc
		(start 68.547996 -61.333634)
		(mid 68.543711 -61.726325)
		(end 68.87718 -61.933836)
		(width 0.0889)
		(layer "In4.Cu")
		(net "M_H_DQS_DN<10>")
	)
	(segment
		(start 35.649408 -9.40943)
		(end 35.383724 -9.143746)
		(width 0.1651)
		(layer "F.Cu")
		(net "M_H_DQS_DN<0>")
	)
	(segment
		(start 73.758806 -65.991486)
		(end 73.187306 -65.991486)
		(width 0.0889)
		(layer "F.Cu")
		(net "M_H_DQS_DN<0>")
	)
	(segment
		(start 35.649408 -10.422382)
		(end 35.649408 -9.40943)
		(width 0.1651)
		(layer "F.Cu")
		(net "M_H_DQS_DN<0>")
	)
	(segment
		(start 35.383724 -8.410956)
		(end 36.03752 -7.75716)
		(width 0.1651)
		(layer "F.Cu")
		(net "M_H_DQS_DN<0>")
	)
	(segment
		(start 35.383724 -9.143746)
		(end 35.383724 -8.410956)
		(width 0.1651)
		(layer "F.Cu")
		(net "M_H_DQS_DN<0>")
	)
	(via
		(at 73.187306 -65.991486)
		(size 0.508)
		(drill 0.254)
		(layers "F.Cu" "B.Cu")
		(net "M_H_DQS_DN<0>")
	)
	(via
		(at 36.03752 -13.287756)
		(size 0.508)
		(drill 0.254)
		(layers "F.Cu" "B.Cu")
		(net "M_H_DQS_DN<0>")
	)
	(via
		(at 36.03752 -7.75716)
		(size 0.508)
		(drill 0.254)
		(layers "F.Cu" "B.Cu")
		(net "M_H_DQS_DN<0>")
	)
	(segment
		(start 35.649408 -11.52017)
		(end 35.396424 -11.773154)
		(width 0.1651)
		(layer "B.Cu")
		(net "M_H_DQS_DN<0>")
	)
	(segment
		(start 35.396424 -11.773154)
		(end 35.396424 -12.64666)
		(width 0.1651)
		(layer "B.Cu")
		(net "M_H_DQS_DN<0>")
	)
	(segment
		(start 35.649408 -10.623042)
		(end 35.649408 -11.52017)
		(width 0.1651)
		(layer "B.Cu")
		(net "M_H_DQS_DN<0>")
	)
	(segment
		(start 35.396424 -12.64666)
		(end 36.03752 -13.287756)
		(width 0.1651)
		(layer "B.Cu")
		(net "M_H_DQS_DN<0>")
	)
	(segment
		(start 36.24707 -36.920424)
		(end 36.24707 -37.099748)
		(width 0.14224)
		(layer "In4.Cu")
		(net "M_H_DQS_DN<0>")
	)
	(segment
		(start 36.81984 -15.976854)
		(end 36.81984 -24.7015)
		(width 0.14224)
		(layer "In4.Cu")
		(net "M_H_DQS_DN<0>")
	)
	(segment
		(start 36.440872 -34.426906)
		(end 36.053776 -34.426906)
		(width 0.14224)
		(layer "In4.Cu")
		(net "M_H_DQS_DN<0>")
	)
	(segment
		(start 64.0334 -64.160908)
		(end 64.0334 -64.322452)
		(width 0.14224)
		(layer "In4.Cu")
		(net "M_H_DQS_DN<0>")
	)
	(segment
		(start 36.040568 -14.4272)
		(end 35.87369 -14.594078)
		(width 0.14224)
		(layer "In4.Cu")
		(net "M_H_DQS_DN<0>")
	)
	(segment
		(start 36.81984 -36.347654)
		(end 36.24707 -36.920424)
		(width 0.14224)
		(layer "In4.Cu")
		(net "M_H_DQS_DN<0>")
	)
	(segment
		(start 36.03752 -7.75716)
		(end 36.848288 -8.567928)
		(width 0.14224)
		(layer "In4.Cu")
		(net "M_H_DQS_DN<0>")
	)
	(segment
		(start 36.501324 -14.296644)
		(end 36.370768 -14.4272)
		(width 0.14224)
		(layer "In4.Cu")
		(net "M_H_DQS_DN<0>")
	)
	(segment
		(start 36.81984 -24.7015)
		(end 37.247068 -25.128728)
		(width 0.14224)
		(layer "In4.Cu")
		(net "M_H_DQS_DN<0>")
	)
	(segment
		(start 36.441634 -35.503866)
		(end 36.81984 -35.882072)
		(width 0.14224)
		(layer "In4.Cu")
		(net "M_H_DQS_DN<0>")
	)
	(segment
		(start 72.804782 -66.13652)
		(end 72.89419 -66.16065)
		(width 0.0889)
		(layer "In4.Cu")
		(net "M_H_DQS_DN<0>")
	)
	(segment
		(start 64.921892 -65.210944)
		(end 65.083436 -65.210944)
		(width 0.14224)
		(layer "In4.Cu")
		(net "M_H_DQS_DN<0>")
	)
	(segment
		(start 65.326006 -65.453514)
		(end 65.326006 -65.615058)
		(width 0.14224)
		(layer "In4.Cu")
		(net "M_H_DQS_DN<0>")
	)
	(segment
		(start 69.73824 -67.382136)
		(end 69.768212 -67.382136)
		(width 0.0889)
		(layer "In4.Cu")
		(net "M_H_DQS_DN<0>")
	)
	(segment
		(start 67.869308 -66.391536)
		(end 68.053966 -66.391536)
		(width 0.0889)
		(layer "In4.Cu")
		(net "M_H_DQS_DN<0>")
	)
	(segment
		(start 36.81984 -27.5844)
		(end 37.170868 -27.935428)
		(width 0.14224)
		(layer "In4.Cu")
		(net "M_H_DQS_DN<0>")
	)
	(segment
		(start 62.33668 -62.625732)
		(end 62.498224 -62.625732)
		(width 0.14224)
		(layer "In4.Cu")
		(net "M_H_DQS_DN<0>")
	)
	(segment
		(start 66.547238 -65.89649)
		(end 67.304666 -65.89649)
		(width 0.0889)
		(layer "In4.Cu")
		(net "M_H_DQS_DN<0>")
	)
	(segment
		(start 40.803068 -39.5478)
		(end 40.803068 -41.4274)
		(width 0.14224)
		(layer "In4.Cu")
		(net "M_H_DQS_DN<0>")
	)
	(segment
		(start 65.083436 -65.210944)
		(end 65.326006 -65.453514)
		(width 0.14224)
		(layer "In4.Cu")
		(net "M_H_DQS_DN<0>")
	)
	(segment
		(start 40.803068 -41.4274)
		(end 54.849268 -55.4736)
		(width 0.14224)
		(layer "In4.Cu")
		(net "M_H_DQS_DN<0>")
	)
	(segment
		(start 61.999368 -62.28842)
		(end 62.33668 -62.625732)
		(width 0.14224)
		(layer "In4.Cu")
		(net "M_H_DQS_DN<0>")
	)
	(segment
		(start 36.053776 -34.426906)
		(end 35.832288 -34.648394)
		(width 0.14224)
		(layer "In4.Cu")
		(net "M_H_DQS_DN<0>")
	)
	(segment
		(start 37.247068 -26.0096)
		(end 36.81984 -26.436828)
		(width 0.14224)
		(layer "In4.Cu")
		(net "M_H_DQS_DN<0>")
	)
	(segment
		(start 62.98311 -63.272162)
		(end 63.144654 -63.272162)
		(width 0.14224)
		(layer "In4.Cu")
		(net "M_H_DQS_DN<0>")
	)
	(segment
		(start 62.740794 -62.868302)
		(end 62.740794 -63.029846)
		(width 0.14224)
		(layer "In4.Cu")
		(net "M_H_DQS_DN<0>")
	)
	(segment
		(start 37.247068 -25.128728)
		(end 37.247068 -26.0096)
		(width 0.14224)
		(layer "In4.Cu")
		(net "M_H_DQS_DN<0>")
	)
	(segment
		(start 63.387224 -63.676276)
		(end 63.629286 -63.918338)
		(width 0.14224)
		(layer "In4.Cu")
		(net "M_H_DQS_DN<0>")
	)
	(segment
		(start 35.87369 -15.030704)
		(end 36.81984 -15.976854)
		(width 0.14224)
		(layer "In4.Cu")
		(net "M_H_DQS_DN<0>")
	)
	(segment
		(start 61.999368 -61.9506)
		(end 61.999368 -62.28842)
		(width 0.14224)
		(layer "In4.Cu")
		(net "M_H_DQS_DN<0>")
	)
	(segment
		(start 55.522368 -55.4736)
		(end 61.999368 -61.9506)
		(width 0.14224)
		(layer "In4.Cu")
		(net "M_H_DQS_DN<0>")
	)
	(segment
		(start 63.144654 -63.272162)
		(end 63.387224 -63.514732)
		(width 0.14224)
		(layer "In4.Cu")
		(net "M_H_DQS_DN<0>")
	)
	(segment
		(start 37.022532 -37.87521)
		(end 39.130478 -37.87521)
		(width 0.14224)
		(layer "In4.Cu")
		(net "M_H_DQS_DN<0>")
	)
	(segment
		(start 66.48577 -65.85712)
		(end 66.507868 -65.85712)
		(width 0.0889)
		(layer "In4.Cu")
		(net "M_H_DQS_DN<0>")
	)
	(segment
		(start 54.849268 -55.4736)
		(end 55.522368 -55.4736)
		(width 0.14224)
		(layer "In4.Cu")
		(net "M_H_DQS_DN<0>")
	)
	(segment
		(start 36.370768 -14.4272)
		(end 36.040568 -14.4272)
		(width 0.14224)
		(layer "In4.Cu")
		(net "M_H_DQS_DN<0>")
	)
	(segment
		(start 36.03752 -13.287756)
		(end 36.501324 -13.75156)
		(width 0.14224)
		(layer "In4.Cu")
		(net "M_H_DQS_DN<0>")
	)
	(segment
		(start 36.501324 -13.75156)
		(end 36.501324 -14.296644)
		(width 0.14224)
		(layer "In4.Cu")
		(net "M_H_DQS_DN<0>")
	)
	(segment
		(start 36.81984 -35.882072)
		(end 36.81984 -36.347654)
		(width 0.14224)
		(layer "In4.Cu")
		(net "M_H_DQS_DN<0>")
	)
	(segment
		(start 35.832288 -34.648394)
		(end 35.832288 -35.282378)
		(width 0.14224)
		(layer "In4.Cu")
		(net "M_H_DQS_DN<0>")
	)
	(segment
		(start 66.507868 -65.85712)
		(end 66.547238 -65.89649)
		(width 0.0889)
		(layer "In4.Cu")
		(net "M_H_DQS_DN<0>")
	)
	(segment
		(start 64.0334 -64.322452)
		(end 64.275462 -64.564514)
		(width 0.14224)
		(layer "In4.Cu")
		(net "M_H_DQS_DN<0>")
	)
	(segment
		(start 64.437006 -64.564514)
		(end 64.679576 -64.807084)
		(width 0.14224)
		(layer "In4.Cu")
		(net "M_H_DQS_DN<0>")
	)
	(segment
		(start 35.832288 -35.282378)
		(end 36.053776 -35.503866)
		(width 0.14224)
		(layer "In4.Cu")
		(net "M_H_DQS_DN<0>")
	)
	(segment
		(start 36.530788 -37.383212)
		(end 37.022532 -37.87521)
		(width 0.14224)
		(layer "In4.Cu")
		(net "M_H_DQS_DN<0>")
	)
	(segment
		(start 36.848288 -8.567928)
		(end 36.848288 -12.476988)
		(width 0.14224)
		(layer "In4.Cu")
		(net "M_H_DQS_DN<0>")
	)
	(segment
		(start 64.275462 -64.564514)
		(end 64.437006 -64.564514)
		(width 0.14224)
		(layer "In4.Cu")
		(net "M_H_DQS_DN<0>")
	)
	(segment
		(start 68.88353 -66.88709)
		(end 68.916296 -66.88709)
		(width 0.0889)
		(layer "In4.Cu")
		(net "M_H_DQS_DN<0>")
	)
	(segment
		(start 35.87369 -14.594078)
		(end 35.87369 -15.030704)
		(width 0.14224)
		(layer "In4.Cu")
		(net "M_H_DQS_DN<0>")
	)
	(segment
		(start 64.679576 -64.807084)
		(end 64.679576 -64.968628)
		(width 0.14224)
		(layer "In4.Cu")
		(net "M_H_DQS_DN<0>")
	)
	(segment
		(start 36.81984 -26.436828)
		(end 36.81984 -27.5844)
		(width 0.14224)
		(layer "In4.Cu")
		(net "M_H_DQS_DN<0>")
	)
	(segment
		(start 63.79083 -63.918338)
		(end 64.0334 -64.160908)
		(width 0.14224)
		(layer "In4.Cu")
		(net "M_H_DQS_DN<0>")
	)
	(segment
		(start 36.81984 -34.047938)
		(end 36.440872 -34.426906)
		(width 0.14224)
		(layer "In4.Cu")
		(net "M_H_DQS_DN<0>")
	)
	(segment
		(start 70.590156 -66.88709)
		(end 70.622922 -66.88709)
		(width 0.0889)
		(layer "In4.Cu")
		(net "M_H_DQS_DN<0>")
	)
	(segment
		(start 37.170868 -29.100272)
		(end 36.81984 -29.4513)
		(width 0.14224)
		(layer "In4.Cu")
		(net "M_H_DQS_DN<0>")
	)
	(segment
		(start 36.81984 -29.4513)
		(end 36.81984 -34.047938)
		(width 0.14224)
		(layer "In4.Cu")
		(net "M_H_DQS_DN<0>")
	)
	(segment
		(start 37.170868 -27.935428)
		(end 37.170868 -29.100272)
		(width 0.14224)
		(layer "In4.Cu")
		(net "M_H_DQS_DN<0>")
	)
	(segment
		(start 71.452486 -66.391536)
		(end 71.485252 -66.391536)
		(width 0.0889)
		(layer "In4.Cu")
		(net "M_H_DQS_DN<0>")
	)
	(segment
		(start 65.568068 -65.85712)
		(end 66.48577 -65.85712)
		(width 0.14224)
		(layer "In4.Cu")
		(net "M_H_DQS_DN<0>")
	)
	(segment
		(start 36.848288 -12.476988)
		(end 36.03752 -13.287756)
		(width 0.14224)
		(layer "In4.Cu")
		(net "M_H_DQS_DN<0>")
	)
	(segment
		(start 39.130478 -37.87521)
		(end 40.803068 -39.5478)
		(width 0.14224)
		(layer "In4.Cu")
		(net "M_H_DQS_DN<0>")
	)
	(segment
		(start 63.629286 -63.918338)
		(end 63.79083 -63.918338)
		(width 0.14224)
		(layer "In4.Cu")
		(net "M_H_DQS_DN<0>")
	)
	(segment
		(start 63.387224 -63.514732)
		(end 63.387224 -63.676276)
		(width 0.14224)
		(layer "In4.Cu")
		(net "M_H_DQS_DN<0>")
	)
	(segment
		(start 62.498224 -62.625732)
		(end 62.740794 -62.868302)
		(width 0.14224)
		(layer "In4.Cu")
		(net "M_H_DQS_DN<0>")
	)
	(segment
		(start 64.679576 -64.968628)
		(end 64.921892 -65.210944)
		(width 0.14224)
		(layer "In4.Cu")
		(net "M_H_DQS_DN<0>")
	)
	(segment
		(start 72.89419 -66.16065)
		(end 73.187306 -65.991486)
		(width 0.0889)
		(layer "In4.Cu")
		(net "M_H_DQS_DN<0>")
	)
	(segment
		(start 36.053776 -35.503866)
		(end 36.441634 -35.503866)
		(width 0.14224)
		(layer "In4.Cu")
		(net "M_H_DQS_DN<0>")
	)
	(segment
		(start 65.326006 -65.615058)
		(end 65.568068 -65.85712)
		(width 0.14224)
		(layer "In4.Cu")
		(net "M_H_DQS_DN<0>")
	)
	(segment
		(start 36.24707 -37.099748)
		(end 36.530788 -37.383212)
		(width 0.14224)
		(layer "In4.Cu")
		(net "M_H_DQS_DN<0>")
	)
	(segment
		(start 72.307196 -65.89649)
		(end 72.350376 -65.89649)
		(width 0.0889)
		(layer "In4.Cu")
		(net "M_H_DQS_DN<0>")
	)
	(segment
		(start 62.740794 -63.029846)
		(end 62.98311 -63.272162)
		(width 0.14224)
		(layer "In4.Cu")
		(net "M_H_DQS_DN<0>")
	)
	(arc
		(start 70.622922 -66.88709)
		(mid 70.816772 -66.83074)
		(end 70.958456 -66.686938)
		(width 0.0889)
		(layer "In4.Cu")
		(net "M_H_DQS_DN<0>")
	)
	(arc
		(start 68.916296 -66.88709)
		(mid 69.199513 -66.971371)
		(end 69.406516 -67.182238)
		(width 0.0889)
		(layer "In4.Cu")
		(net "M_H_DQS_DN<0>")
	)
	(arc
		(start 69.406516 -67.182238)
		(mid 69.546595 -67.324974)
		(end 69.73824 -67.382136)
		(width 0.0889)
		(layer "In4.Cu")
		(net "M_H_DQS_DN<0>")
	)
	(arc
		(start 67.304666 -65.89649)
		(mid 67.50726 -66.012308)
		(end 67.653154 -66.194432)
		(width 0.0889)
		(layer "In4.Cu")
		(net "M_H_DQS_DN<0>")
	)
	(arc
		(start 70.958456 -66.686938)
		(mid 71.167064 -66.475006)
		(end 71.452486 -66.391536)
		(width 0.0889)
		(layer "In4.Cu")
		(net "M_H_DQS_DN<0>")
	)
	(arc
		(start 71.816976 -66.191638)
		(mid 72.02398 -65.980774)
		(end 72.307196 -65.89649)
		(width 0.0889)
		(layer "In4.Cu")
		(net "M_H_DQS_DN<0>")
	)
	(arc
		(start 68.053966 -66.391536)
		(mid 68.33939 -66.475003)
		(end 68.547996 -66.686938)
		(width 0.0889)
		(layer "In4.Cu")
		(net "M_H_DQS_DN<0>")
	)
	(arc
		(start 69.768212 -67.382136)
		(mid 69.959854 -67.32497)
		(end 70.099936 -67.182238)
		(width 0.0889)
		(layer "In4.Cu")
		(net "M_H_DQS_DN<0>")
	)
	(arc
		(start 71.485252 -66.391536)
		(mid 71.676894 -66.33437)
		(end 71.816976 -66.191638)
		(width 0.0889)
		(layer "In4.Cu")
		(net "M_H_DQS_DN<0>")
	)
	(arc
		(start 68.547996 -66.686938)
		(mid 68.689679 -66.830742)
		(end 68.88353 -66.88709)
		(width 0.0889)
		(layer "In4.Cu")
		(net "M_H_DQS_DN<0>")
	)
	(arc
		(start 67.653154 -66.194432)
		(mid 67.744098 -66.311775)
		(end 67.869308 -66.391536)
		(width 0.0889)
		(layer "In4.Cu")
		(net "M_H_DQS_DN<0>")
	)
	(arc
		(start 72.350376 -65.89649)
		(mid 72.605041 -65.964519)
		(end 72.804782 -66.13652)
		(width 0.0889)
		(layer "In4.Cu")
		(net "M_H_DQS_DN<0>")
	)
	(arc
		(start 70.099936 -67.182238)
		(mid 70.30694 -66.971374)
		(end 70.590156 -66.88709)
		(width 0.0889)
		(layer "In4.Cu")
		(net "M_H_DQS_DN<0>")
	)
	(segment
		(start 42.449496 -5.822442)
		(end 42.449496 -7.086346)
		(width 0.1651)
		(layer "F.Cu")
		(net "M_H_DQ<9>")
	)
	(segment
		(start 73.758806 -62.029086)
		(end 73.187306 -62.029086)
		(width 0.1016)
		(layer "F.Cu")
		(net "M_H_DQ<9>")
	)
	(via
		(at 73.187306 -62.029086)
		(size 0.508)
		(drill 0.254)
		(layers "F.Cu" "B.Cu")
		(net "M_H_DQ<9>")
	)
	(via
		(at 43.12158 -12.678156)
		(size 0.508)
		(drill 0.254)
		(layers "F.Cu" "B.Cu")
		(net "M_H_DQ<9>")
	)
	(via
		(at 42.449496 -7.086346)
		(size 0.508)
		(drill 0.254)
		(layers "F.Cu" "B.Cu")
		(net "M_H_DQ<9>")
	)
	(segment
		(start 43.29938 -10.623042)
		(end 43.29938 -11.969242)
		(width 0.1651)
		(layer "B.Cu")
		(net "M_H_DQ<9>")
	)
	(segment
		(start 43.29938 -11.969242)
		(end 43.12158 -12.147042)
		(width 0.1651)
		(layer "B.Cu")
		(net "M_H_DQ<9>")
	)
	(segment
		(start 43.12158 -12.147042)
		(end 43.12158 -12.678156)
		(width 0.1651)
		(layer "B.Cu")
		(net "M_H_DQ<9>")
	)
	(segment
		(start 42.974514 -13.842492)
		(end 42.974514 -15.434564)
		(width 0.14224)
		(layer "In4.Cu")
		(net "M_H_DQ<9>")
	)
	(segment
		(start 43.652186 -8.8138)
		(end 43.495722 -8.970264)
		(width 0.14224)
		(layer "In4.Cu")
		(net "M_H_DQ<9>")
	)
	(segment
		(start 43.914568 -26.5684)
		(end 44.549568 -27.2034)
		(width 0.14224)
		(layer "In4.Cu")
		(net "M_H_DQ<9>")
	)
	(segment
		(start 72.675496 -62.724538)
		(end 72.69226 -62.695074)
		(width 0.0889)
		(layer "In4.Cu")
		(net "M_H_DQ<9>")
	)
	(segment
		(start 71.736204 -62.691518)
		(end 72.134222 -62.904624)
		(width 0.0889)
		(layer "In4.Cu")
		(net "M_H_DQ<9>")
	)
	(segment
		(start 42.449496 -7.086346)
		(end 42.449496 -7.625334)
		(width 0.14224)
		(layer "In4.Cu")
		(net "M_H_DQ<9>")
	)
	(segment
		(start 71.45909 -62.619636)
		(end 71.589392 -62.619636)
		(width 0.0889)
		(layer "In4.Cu")
		(net "M_H_DQ<9>")
	)
	(segment
		(start 45.750988 -34.192464)
		(end 46.026832 -33.916366)
		(width 0.14224)
		(layer "In4.Cu")
		(net "M_H_DQ<9>")
	)
	(segment
		(start 46.24578 -33.916366)
		(end 46.492668 -34.163254)
		(width 0.14224)
		(layer "In4.Cu")
		(net "M_H_DQ<9>")
	)
	(segment
		(start 66.692018 -58.99785)
		(end 66.894456 -58.99785)
		(width 0.14224)
		(layer "In4.Cu")
		(net "M_H_DQ<9>")
	)
	(segment
		(start 67.695826 -60.82792)
		(end 67.689476 -60.838588)
		(width 0.0889)
		(layer "In4.Cu")
		(net "M_H_DQ<9>")
	)
	(segment
		(start 43.609514 -23.612856)
		(end 43.914568 -24.425656)
		(width 0.14224)
		(layer "In4.Cu")
		(net "M_H_DQ<9>")
	)
	(segment
		(start 46.492668 -37.6301)
		(end 64.221868 -55.3593)
		(width 0.14224)
		(layer "In4.Cu")
		(net "M_H_DQ<9>")
	)
	(segment
		(start 70.280784 -63.280544)
		(end 70.339712 -63.221616)
		(width 0.0889)
		(layer "In4.Cu")
		(net "M_H_DQ<9>")
	)
	(segment
		(start 67.533774 -59.979306)
		(end 67.688968 -60.248292)
		(width 0.0889)
		(layer "In4.Cu")
		(net "M_H_DQ<9>")
	)
	(segment
		(start 72.69226 -62.695074)
		(end 73.187306 -62.029086)
		(width 0.0889)
		(layer "In4.Cu")
		(net "M_H_DQ<9>")
	)
	(segment
		(start 67.695826 -61.81852)
		(end 67.689476 -61.829188)
		(width 0.0889)
		(layer "In4.Cu")
		(net "M_H_DQ<9>")
	)
	(segment
		(start 67.688968 -60.248292)
		(end 67.689476 -60.248038)
		(width 0.0889)
		(layer "In4.Cu")
		(net "M_H_DQ<9>")
	)
	(segment
		(start 45.282104 -33.72358)
		(end 45.282104 -33.942528)
		(width 0.14224)
		(layer "In4.Cu")
		(net "M_H_DQ<9>")
	)
	(segment
		(start 43.652186 -8.472424)
		(end 43.652186 -8.8138)
		(width 0.14224)
		(layer "In4.Cu")
		(net "M_H_DQ<9>")
	)
	(segment
		(start 66.894456 -58.99785)
		(end 67.300856 -59.40425)
		(width 0.14224)
		(layer "In4.Cu")
		(net "M_H_DQ<9>")
	)
	(segment
		(start 43.495722 -8.970264)
		(end 43.495722 -12.304014)
		(width 0.14224)
		(layer "In4.Cu")
		(net "M_H_DQ<9>")
	)
	(segment
		(start 64.221868 -56.5277)
		(end 66.692018 -58.99785)
		(width 0.14224)
		(layer "In4.Cu")
		(net "M_H_DQ<9>")
	)
	(segment
		(start 71.589392 -62.619636)
		(end 71.736204 -62.691518)
		(width 0.0889)
		(layer "In4.Cu")
		(net "M_H_DQ<9>")
	)
	(segment
		(start 70.59676 -63.11519)
		(end 70.629526 -63.11519)
		(width 0.0889)
		(layer "In4.Cu")
		(net "M_H_DQ<9>")
	)
	(segment
		(start 45.557948 -33.228534)
		(end 45.557948 -33.447482)
		(width 0.14224)
		(layer "In4.Cu")
		(net "M_H_DQ<9>")
	)
	(segment
		(start 43.282362 -8.1026)
		(end 43.652186 -8.472424)
		(width 0.14224)
		(layer "In4.Cu")
		(net "M_H_DQ<9>")
	)
	(segment
		(start 43.12158 -12.678156)
		(end 42.644568 -13.155168)
		(width 0.14224)
		(layer "In4.Cu")
		(net "M_H_DQ<9>")
	)
	(segment
		(start 67.689476 -61.829188)
		(end 67.68465 -61.837824)
		(width 0.0889)
		(layer "In4.Cu")
		(net "M_H_DQ<9>")
	)
	(segment
		(start 42.644568 -13.155168)
		(end 42.644568 -13.512546)
		(width 0.14224)
		(layer "In4.Cu")
		(net "M_H_DQ<9>")
	)
	(segment
		(start 42.644568 -13.512546)
		(end 42.974514 -13.842492)
		(width 0.14224)
		(layer "In4.Cu")
		(net "M_H_DQ<9>")
	)
	(segment
		(start 42.926762 -8.1026)
		(end 43.282362 -8.1026)
		(width 0.14224)
		(layer "In4.Cu")
		(net "M_H_DQ<9>")
	)
	(segment
		(start 46.026832 -33.916366)
		(end 46.24578 -33.916366)
		(width 0.14224)
		(layer "In4.Cu")
		(net "M_H_DQ<9>")
	)
	(segment
		(start 72.251062 -62.92469)
		(end 72.339962 -62.92469)
		(width 0.0889)
		(layer "In4.Cu")
		(net "M_H_DQ<9>")
	)
	(segment
		(start 67.300856 -59.746388)
		(end 67.533774 -59.979306)
		(width 0.0889)
		(layer "In4.Cu")
		(net "M_H_DQ<9>")
	)
	(segment
		(start 42.974514 -15.434564)
		(end 43.609514 -16.069564)
		(width 0.14224)
		(layer "In4.Cu")
		(net "M_H_DQ<9>")
	)
	(segment
		(start 42.449496 -7.625334)
		(end 42.926762 -8.1026)
		(width 0.14224)
		(layer "In4.Cu")
		(net "M_H_DQ<9>")
	)
	(segment
		(start 43.609514 -16.069564)
		(end 43.609514 -23.612856)
		(width 0.14224)
		(layer "In4.Cu")
		(net "M_H_DQ<9>")
	)
	(segment
		(start 67.300856 -59.40425)
		(end 67.300856 -59.746388)
		(width 0.0889)
		(layer "In4.Cu")
		(net "M_H_DQ<9>")
	)
	(segment
		(start 44.549568 -27.2034)
		(end 44.549568 -32.220154)
		(width 0.14224)
		(layer "In4.Cu")
		(net "M_H_DQ<9>")
	)
	(segment
		(start 69.73824 -63.419736)
		(end 69.944742 -63.419736)
		(width 0.0889)
		(layer "In4.Cu")
		(net "M_H_DQ<9>")
	)
	(segment
		(start 45.53204 -34.192464)
		(end 45.750988 -34.192464)
		(width 0.14224)
		(layer "In4.Cu")
		(net "M_H_DQ<9>")
	)
	(segment
		(start 64.221868 -55.3593)
		(end 64.221868 -56.5277)
		(width 0.14224)
		(layer "In4.Cu")
		(net "M_H_DQ<9>")
	)
	(segment
		(start 68.0212 -62.429136)
		(end 68.053966 -62.429136)
		(width 0.0889)
		(layer "In4.Cu")
		(net "M_H_DQ<9>")
	)
	(segment
		(start 67.689476 -60.838588)
		(end 67.68465 -60.847224)
		(width 0.0889)
		(layer "In4.Cu")
		(net "M_H_DQ<9>")
	)
	(segment
		(start 46.492668 -34.163254)
		(end 46.492668 -37.6301)
		(width 0.14224)
		(layer "In4.Cu")
		(net "M_H_DQ<9>")
	)
	(segment
		(start 43.495722 -12.304014)
		(end 43.12158 -12.678156)
		(width 0.14224)
		(layer "In4.Cu")
		(net "M_H_DQ<9>")
	)
	(segment
		(start 44.549568 -32.220154)
		(end 45.557948 -33.228534)
		(width 0.14224)
		(layer "In4.Cu")
		(net "M_H_DQ<9>")
	)
	(segment
		(start 45.557948 -33.447482)
		(end 45.282104 -33.72358)
		(width 0.14224)
		(layer "In4.Cu")
		(net "M_H_DQ<9>")
	)
	(segment
		(start 45.282104 -33.942528)
		(end 45.53204 -34.192464)
		(width 0.14224)
		(layer "In4.Cu")
		(net "M_H_DQ<9>")
	)
	(segment
		(start 68.88353 -62.92469)
		(end 68.916296 -62.92469)
		(width 0.0889)
		(layer "In4.Cu")
		(net "M_H_DQ<9>")
	)
	(segment
		(start 43.914568 -24.425656)
		(end 43.914568 -26.5684)
		(width 0.14224)
		(layer "In4.Cu")
		(net "M_H_DQ<9>")
	)
	(arc
		(start 68.916296 -62.92469)
		(mid 69.199513 -63.008971)
		(end 69.406516 -63.219838)
		(width 0.0889)
		(layer "In4.Cu")
		(net "M_H_DQ<9>")
	)
	(arc
		(start 70.339712 -63.221616)
		(mid 70.458699 -63.145383)
		(end 70.59676 -63.11519)
		(width 0.0889)
		(layer "In4.Cu")
		(net "M_H_DQ<9>")
	)
	(arc
		(start 68.053966 -62.429136)
		(mid 68.33939 -62.512603)
		(end 68.547996 -62.724538)
		(width 0.0889)
		(layer "In4.Cu")
		(net "M_H_DQ<9>")
	)
	(arc
		(start 67.68465 -61.837824)
		(mid 67.688397 -62.22708)
		(end 68.0212 -62.429136)
		(width 0.0889)
		(layer "In4.Cu")
		(net "M_H_DQ<9>")
	)
	(arc
		(start 69.406516 -63.219838)
		(mid 69.546595 -63.362574)
		(end 69.73824 -63.419736)
		(width 0.0889)
		(layer "In4.Cu")
		(net "M_H_DQ<9>")
	)
	(arc
		(start 72.134222 -62.904624)
		(mid 72.191788 -62.919633)
		(end 72.251062 -62.92469)
		(width 0.0889)
		(layer "In4.Cu")
		(net "M_H_DQ<9>")
	)
	(arc
		(start 72.339962 -62.92469)
		(mid 72.533812 -62.86834)
		(end 72.675496 -62.724538)
		(width 0.0889)
		(layer "In4.Cu")
		(net "M_H_DQ<9>")
	)
	(arc
		(start 67.689476 -61.238638)
		(mid 67.768698 -61.527756)
		(end 67.695826 -61.81852)
		(width 0.0889)
		(layer "In4.Cu")
		(net "M_H_DQ<9>")
	)
	(arc
		(start 67.689476 -60.248038)
		(mid 67.768698 -60.537156)
		(end 67.695826 -60.82792)
		(width 0.0889)
		(layer "In4.Cu")
		(net "M_H_DQ<9>")
	)
	(arc
		(start 71.123556 -62.819788)
		(mid 71.265239 -62.675984)
		(end 71.45909 -62.619636)
		(width 0.0889)
		(layer "In4.Cu")
		(net "M_H_DQ<9>")
	)
	(arc
		(start 69.944742 -63.419736)
		(mid 70.126606 -63.383561)
		(end 70.280784 -63.280544)
		(width 0.0889)
		(layer "In4.Cu")
		(net "M_H_DQ<9>")
	)
	(arc
		(start 70.629526 -63.11519)
		(mid 70.91495 -63.031723)
		(end 71.123556 -62.819788)
		(width 0.0889)
		(layer "In4.Cu")
		(net "M_H_DQ<9>")
	)
	(arc
		(start 67.68465 -60.847224)
		(mid 67.635895 -61.043576)
		(end 67.689476 -61.238638)
		(width 0.0889)
		(layer "In4.Cu")
		(net "M_H_DQ<9>")
	)
	(arc
		(start 68.547996 -62.724538)
		(mid 68.689679 -62.868342)
		(end 68.88353 -62.92469)
		(width 0.0889)
		(layer "In4.Cu")
		(net "M_H_DQ<9>")
	)
	(segment
		(start 72.041766 -63.019686)
		(end 71.470266 -63.019686)
		(width 0.1016)
		(layer "F.Cu")
		(net "M_H_DQ<8>")
	)
	(segment
		(start 43.140884 -8.763)
		(end 43.12158 -8.5598)
		(width 0.1651)
		(layer "F.Cu")
		(net "M_H_DQ<8>")
	)
	(segment
		(start 43.29938 -10.422382)
		(end 43.140884 -8.763)
		(width 0.1651)
		(layer "F.Cu")
		(net "M_H_DQ<8>")
	)
	(via
		(at 43.12158 -8.5598)
		(size 0.508)
		(drill 0.254)
		(layers "F.Cu" "B.Cu")
		(net "M_H_DQ<8>")
	)
	(via
		(at 42.449496 -13.959078)
		(size 0.508)
		(drill 0.254)
		(layers "F.Cu" "B.Cu")
		(net "M_H_DQ<8>")
	)
	(via
		(at 71.470266 -63.019686)
		(size 0.508)
		(drill 0.254)
		(layers "F.Cu" "B.Cu")
		(net "M_H_DQ<8>")
	)
	(segment
		(start 42.449496 -15.222982)
		(end 42.449496 -13.959078)
		(width 0.1651)
		(layer "B.Cu")
		(net "M_H_DQ<8>")
	)
	(segment
		(start 63.586868 -56.790844)
		(end 66.369946 -59.573922)
		(width 0.14224)
		(layer "In4.Cu")
		(net "M_H_DQ<8>")
	)
	(segment
		(start 45.971968 -36.34994)
		(end 45.971968 -38.007544)
		(width 0.14224)
		(layer "In4.Cu")
		(net "M_H_DQ<8>")
	)
	(segment
		(start 42.82948 -10.6807)
		(end 42.82948 -10.4521)
		(width 0.14224)
		(layer "In4.Cu")
		(net "M_H_DQ<8>")
	)
	(segment
		(start 67.529202 -60.734702)
		(end 67.524376 -60.743338)
		(width 0.0889)
		(layer "In4.Cu")
		(net "M_H_DQ<8>")
	)
	(segment
		(start 66.369946 -59.573922)
		(end 66.568828 -59.573922)
		(width 0.14224)
		(layer "In4.Cu")
		(net "M_H_DQ<8>")
	)
	(segment
		(start 42.164762 -12.9286)
		(end 42.901362 -12.192)
		(width 0.14224)
		(layer "In4.Cu")
		(net "M_H_DQ<8>")
	)
	(segment
		(start 63.586868 -55.622444)
		(end 63.586868 -56.790844)
		(width 0.14224)
		(layer "In4.Cu")
		(net "M_H_DQ<8>")
	)
	(segment
		(start 67.381628 -60.095892)
		(end 67.524376 -60.343288)
		(width 0.0889)
		(layer "In4.Cu")
		(net "M_H_DQ<8>")
	)
	(segment
		(start 42.82948 -10.4521)
		(end 42.48658 -10.1092)
		(width 0.14224)
		(layer "In4.Cu")
		(net "M_H_DQ<8>")
	)
	(segment
		(start 66.568828 -59.573922)
		(end 67.036696 -60.04179)
		(width 0.14224)
		(layer "In4.Cu")
		(net "M_H_DQ<8>")
	)
	(segment
		(start 42.923714 -16.433292)
		(end 42.923714 -16.827754)
		(width 0.14224)
		(layer "In4.Cu")
		(net "M_H_DQ<8>")
	)
	(segment
		(start 42.974514 -21.683472)
		(end 42.631614 -22.026372)
		(width 0.14224)
		(layer "In4.Cu")
		(net "M_H_DQ<8>")
	)
	(segment
		(start 70.306692 -63.776098)
		(end 70.32117 -63.790322)
		(width 0.0889)
		(layer "In4.Cu")
		(net "M_H_DQ<8>")
	)
	(segment
		(start 43.914568 -27.6606)
		(end 43.914568 -32.677354)
		(width 0.14224)
		(layer "In4.Cu")
		(net "M_H_DQ<8>")
	)
	(segment
		(start 45.971968 -38.007544)
		(end 63.586868 -55.622444)
		(width 0.14224)
		(layer "In4.Cu")
		(net "M_H_DQ<8>")
	)
	(segment
		(start 42.901362 -12.192)
		(end 42.901362 -11.692128)
		(width 0.14224)
		(layer "In4.Cu")
		(net "M_H_DQ<8>")
	)
	(segment
		(start 67.327526 -60.04179)
		(end 67.381628 -60.095892)
		(width 0.0889)
		(layer "In4.Cu")
		(net "M_H_DQ<8>")
	)
	(segment
		(start 44.460668 -33.223454)
		(end 44.460668 -34.5567)
		(width 0.14224)
		(layer "In4.Cu")
		(net "M_H_DQ<8>")
	)
	(segment
		(start 44.460668 -34.5567)
		(end 44.727368 -34.8234)
		(width 0.14224)
		(layer "In4.Cu")
		(net "M_H_DQ<8>")
	)
	(segment
		(start 42.631614 -22.026372)
		(end 42.631614 -23.113492)
		(width 0.14224)
		(layer "In4.Cu")
		(net "M_H_DQ<8>")
	)
	(segment
		(start 45.817028 -35.4711)
		(end 44.717208 -35.4711)
		(width 0.14224)
		(layer "In4.Cu")
		(net "M_H_DQ<8>")
	)
	(segment
		(start 42.449496 -13.959078)
		(end 42.449496 -15.959074)
		(width 0.14224)
		(layer "In4.Cu")
		(net "M_H_DQ<8>")
	)
	(segment
		(start 45.971968 -35.31616)
		(end 45.817028 -35.4711)
		(width 0.14224)
		(layer "In4.Cu")
		(net "M_H_DQ<8>")
	)
	(segment
		(start 69.731636 -63.610236)
		(end 69.906642 -63.610236)
		(width 0.0889)
		(layer "In4.Cu")
		(net "M_H_DQ<8>")
	)
	(segment
		(start 42.449496 -13.959078)
		(end 42.164762 -13.674344)
		(width 0.14224)
		(layer "In4.Cu")
		(net "M_H_DQ<8>")
	)
	(segment
		(start 45.819568 -34.8234)
		(end 45.971968 -34.9758)
		(width 0.14224)
		(layer "In4.Cu")
		(net "M_H_DQ<8>")
	)
	(segment
		(start 70.958456 -63.715138)
		(end 70.97522 -63.685674)
		(width 0.0889)
		(layer "In4.Cu")
		(net "M_H_DQ<8>")
	)
	(segment
		(start 43.914568 -32.677354)
		(end 44.460668 -33.223454)
		(width 0.14224)
		(layer "In4.Cu")
		(net "M_H_DQ<8>")
	)
	(segment
		(start 42.901362 -11.692128)
		(end 42.51198 -11.302746)
		(width 0.14224)
		(layer "In4.Cu")
		(net "M_H_DQ<8>")
	)
	(segment
		(start 68.014596 -62.619636)
		(end 68.047362 -62.619636)
		(width 0.0889)
		(layer "In4.Cu")
		(net "M_H_DQ<8>")
	)
	(segment
		(start 42.51198 -10.9982)
		(end 42.82948 -10.6807)
		(width 0.14224)
		(layer "In4.Cu")
		(net "M_H_DQ<8>")
	)
	(segment
		(start 42.164762 -13.674344)
		(end 42.164762 -12.9286)
		(width 0.14224)
		(layer "In4.Cu")
		(net "M_H_DQ<8>")
	)
	(segment
		(start 42.972228 -23.454106)
		(end 42.972228 -24.12746)
		(width 0.14224)
		(layer "In4.Cu")
		(net "M_H_DQ<8>")
	)
	(segment
		(start 42.48658 -9.779254)
		(end 42.901362 -9.364472)
		(width 0.14224)
		(layer "In4.Cu")
		(net "M_H_DQ<8>")
	)
	(segment
		(start 45.817028 -36.195)
		(end 45.971968 -36.34994)
		(width 0.14224)
		(layer "In4.Cu")
		(net "M_H_DQ<8>")
	)
	(segment
		(start 42.631614 -18.325846)
		(end 42.974514 -18.668746)
		(width 0.14224)
		(layer "In4.Cu")
		(net "M_H_DQ<8>")
	)
	(segment
		(start 42.449496 -15.959074)
		(end 42.923714 -16.433292)
		(width 0.14224)
		(layer "In4.Cu")
		(net "M_H_DQ<8>")
	)
	(segment
		(start 70.97522 -63.685674)
		(end 71.470266 -63.019686)
		(width 0.0889)
		(layer "In4.Cu")
		(net "M_H_DQ<8>")
	)
	(segment
		(start 67.524376 -60.743338)
		(end 67.518026 -60.754006)
		(width 0.0889)
		(layer "In4.Cu")
		(net "M_H_DQ<8>")
	)
	(segment
		(start 42.51198 -11.302746)
		(end 42.51198 -10.9982)
		(width 0.14224)
		(layer "In4.Cu")
		(net "M_H_DQ<8>")
	)
	(segment
		(start 44.717208 -36.195)
		(end 45.817028 -36.195)
		(width 0.14224)
		(layer "In4.Cu")
		(net "M_H_DQ<8>")
	)
	(segment
		(start 68.876926 -63.11519)
		(end 68.909692 -63.11519)
		(width 0.0889)
		(layer "In4.Cu")
		(net "M_H_DQ<8>")
	)
	(segment
		(start 43.279568 -27.0256)
		(end 43.914568 -27.6606)
		(width 0.14224)
		(layer "In4.Cu")
		(net "M_H_DQ<8>")
	)
	(segment
		(start 67.036696 -60.04179)
		(end 67.327526 -60.04179)
		(width 0.0889)
		(layer "In4.Cu")
		(net "M_H_DQ<8>")
	)
	(segment
		(start 42.48658 -10.1092)
		(end 42.48658 -9.779254)
		(width 0.14224)
		(layer "In4.Cu")
		(net "M_H_DQ<8>")
	)
	(segment
		(start 67.524376 -61.733938)
		(end 67.518026 -61.744606)
		(width 0.0889)
		(layer "In4.Cu")
		(net "M_H_DQ<8>")
	)
	(segment
		(start 42.923714 -16.827754)
		(end 42.631614 -17.119854)
		(width 0.14224)
		(layer "In4.Cu")
		(net "M_H_DQ<8>")
	)
	(segment
		(start 44.727368 -34.8234)
		(end 45.819568 -34.8234)
		(width 0.14224)
		(layer "In4.Cu")
		(net "M_H_DQ<8>")
	)
	(segment
		(start 42.631614 -23.113492)
		(end 42.972228 -23.454106)
		(width 0.14224)
		(layer "In4.Cu")
		(net "M_H_DQ<8>")
	)
	(segment
		(start 42.901362 -8.780018)
		(end 43.12158 -8.5598)
		(width 0.14224)
		(layer "In4.Cu")
		(net "M_H_DQ<8>")
	)
	(segment
		(start 42.972228 -24.12746)
		(end 43.279568 -24.4348)
		(width 0.14224)
		(layer "In4.Cu")
		(net "M_H_DQ<8>")
	)
	(segment
		(start 43.279568 -24.4348)
		(end 43.279568 -27.0256)
		(width 0.14224)
		(layer "In4.Cu")
		(net "M_H_DQ<8>")
	)
	(segment
		(start 44.717208 -35.4711)
		(end 44.562268 -35.62604)
		(width 0.14224)
		(layer "In4.Cu")
		(net "M_H_DQ<8>")
	)
	(segment
		(start 42.901362 -9.364472)
		(end 42.901362 -8.780018)
		(width 0.14224)
		(layer "In4.Cu")
		(net "M_H_DQ<8>")
	)
	(segment
		(start 45.971968 -34.9758)
		(end 45.971968 -35.31616)
		(width 0.14224)
		(layer "In4.Cu")
		(net "M_H_DQ<8>")
	)
	(segment
		(start 44.562268 -35.62604)
		(end 44.562268 -36.04006)
		(width 0.14224)
		(layer "In4.Cu")
		(net "M_H_DQ<8>")
	)
	(segment
		(start 67.529202 -61.725302)
		(end 67.524376 -61.733938)
		(width 0.0889)
		(layer "In4.Cu")
		(net "M_H_DQ<8>")
	)
	(segment
		(start 42.974514 -18.668746)
		(end 42.974514 -21.683472)
		(width 0.14224)
		(layer "In4.Cu")
		(net "M_H_DQ<8>")
	)
	(segment
		(start 44.562268 -36.04006)
		(end 44.717208 -36.195)
		(width 0.14224)
		(layer "In4.Cu")
		(net "M_H_DQ<8>")
	)
	(segment
		(start 42.631614 -17.119854)
		(end 42.631614 -18.325846)
		(width 0.14224)
		(layer "In4.Cu")
		(net "M_H_DQ<8>")
	)
	(arc
		(start 68.382896 -62.819788)
		(mid 68.591504 -63.03172)
		(end 68.876926 -63.11519)
		(width 0.0889)
		(layer "In4.Cu")
		(net "M_H_DQ<8>")
	)
	(arc
		(start 67.518026 -61.744606)
		(mid 67.522057 -62.320788)
		(end 68.014596 -62.619636)
		(width 0.0889)
		(layer "In4.Cu")
		(net "M_H_DQ<8>")
	)
	(arc
		(start 67.524376 -60.343288)
		(mid 67.577846 -60.538351)
		(end 67.529202 -60.734702)
		(width 0.0889)
		(layer "In4.Cu")
		(net "M_H_DQ<8>")
	)
	(arc
		(start 68.909692 -63.11519)
		(mid 69.101334 -63.172356)
		(end 69.241416 -63.315088)
		(width 0.0889)
		(layer "In4.Cu")
		(net "M_H_DQ<8>")
	)
	(arc
		(start 68.047362 -62.619636)
		(mid 68.241212 -62.675986)
		(end 68.382896 -62.819788)
		(width 0.0889)
		(layer "In4.Cu")
		(net "M_H_DQ<8>")
	)
	(arc
		(start 69.241416 -63.315088)
		(mid 69.44842 -63.525952)
		(end 69.731636 -63.610236)
		(width 0.0889)
		(layer "In4.Cu")
		(net "M_H_DQ<8>")
	)
	(arc
		(start 67.518026 -60.754006)
		(mid 67.445228 -61.044769)
		(end 67.524376 -61.333888)
		(width 0.0889)
		(layer "In4.Cu")
		(net "M_H_DQ<8>")
	)
	(arc
		(start 70.32117 -63.790322)
		(mid 70.658655 -63.912611)
		(end 70.958456 -63.715138)
		(width 0.0889)
		(layer "In4.Cu")
		(net "M_H_DQ<8>")
	)
	(arc
		(start 67.524376 -61.333888)
		(mid 67.577846 -61.528951)
		(end 67.529202 -61.725302)
		(width 0.0889)
		(layer "In4.Cu")
		(net "M_H_DQ<8>")
	)
	(arc
		(start 69.906642 -63.610236)
		(mid 70.123153 -63.653396)
		(end 70.306692 -63.776098)
		(width 0.0889)
		(layer "In4.Cu")
		(net "M_H_DQ<8>")
	)
	(segment
		(start 37.34943 -5.822442)
		(end 37.34943 -7.086346)
		(width 0.1651)
		(layer "F.Cu")
		(net "M_H_DQ<7>")
	)
	(segment
		(start 72.900286 -65.49644)
		(end 72.328786 -65.49644)
		(width 0.0889)
		(layer "F.Cu")
		(net "M_H_DQ<7>")
	)
	(via
		(at 72.328786 -65.49644)
		(size 0.508)
		(drill 0.254)
		(layers "F.Cu" "B.Cu")
		(net "M_H_DQ<7>")
	)
	(via
		(at 38.199314 -12.678156)
		(size 0.508)
		(drill 0.254)
		(layers "F.Cu" "B.Cu")
		(net "M_H_DQ<7>")
	)
	(via
		(at 37.34943 -7.086346)
		(size 0.508)
		(drill 0.254)
		(layers "F.Cu" "B.Cu")
		(net "M_H_DQ<7>")
	)
	(segment
		(start 38.199568 -11.110722)
		(end 38.199314 -11.110976)
		(width 0.1651)
		(layer "B.Cu")
		(net "M_H_DQ<7>")
	)
	(segment
		(start 38.199568 -10.623042)
		(end 38.199568 -11.110722)
		(width 0.1651)
		(layer "B.Cu")
		(net "M_H_DQ<7>")
	)
	(segment
		(start 38.199314 -11.110976)
		(end 38.199314 -12.678156)
		(width 0.1651)
		(layer "B.Cu")
		(net "M_H_DQ<7>")
	)
	(segment
		(start 49.672748 -47.690532)
		(end 50.039524 -47.323756)
		(width 0.14224)
		(layer "In4.Cu")
		(net "M_H_DQ<7>")
	)
	(segment
		(start 68.88353 -65.89649)
		(end 68.916296 -65.89649)
		(width 0.0889)
		(layer "In4.Cu")
		(net "M_H_DQ<7>")
	)
	(segment
		(start 47.578264 -45.814996)
		(end 47.797212 -45.814996)
		(width 0.14224)
		(layer "In4.Cu")
		(net "M_H_DQ<7>")
	)
	(segment
		(start 59.824366 -56.537098)
		(end 59.824366 -57.877202)
		(width 0.14224)
		(layer "In4.Cu")
		(net "M_H_DQ<7>")
	)
	(segment
		(start 47.695104 -44.760388)
		(end 47.695104 -44.979336)
		(width 0.14224)
		(layer "In4.Cu")
		(net "M_H_DQ<7>")
	)
	(segment
		(start 48.266096 -46.28388)
		(end 48.266096 -46.502828)
		(width 0.14224)
		(layer "In4.Cu")
		(net "M_H_DQ<7>")
	)
	(segment
		(start 64.940942 -63.377826)
		(end 66.469006 -64.90589)
		(width 0.0889)
		(layer "In4.Cu")
		(net "M_H_DQ<7>")
	)
	(segment
		(start 45.921676 -43.93946)
		(end 46.288452 -43.572684)
		(width 0.14224)
		(layer "In4.Cu")
		(net "M_H_DQ<7>")
	)
	(segment
		(start 49.101756 -46.385988)
		(end 49.320704 -46.385988)
		(width 0.14224)
		(layer "In4.Cu")
		(net "M_H_DQ<7>")
	)
	(segment
		(start 50.258472 -47.323756)
		(end 50.681128 -47.746412)
		(width 0.14224)
		(layer "In4.Cu")
		(net "M_H_DQ<7>")
	)
	(segment
		(start 38.453568 -23.420324)
		(end 38.453568 -28.0035)
		(width 0.14224)
		(layer "In4.Cu")
		(net "M_H_DQ<7>")
	)
	(segment
		(start 37.666168 -7.7216)
		(end 37.666168 -7.403084)
		(width 0.14224)
		(layer "In4.Cu")
		(net "M_H_DQ<7>")
	)
	(segment
		(start 38.75532 -21.975572)
		(end 38.75532 -23.118572)
		(width 0.14224)
		(layer "In4.Cu")
		(net "M_H_DQ<7>")
	)
	(segment
		(start 46.757336 -43.82262)
		(end 46.757336 -44.041568)
		(width 0.14224)
		(layer "In4.Cu")
		(net "M_H_DQ<7>")
	)
	(segment
		(start 69.73824 -66.391536)
		(end 69.768212 -66.391536)
		(width 0.0889)
		(layer "In4.Cu")
		(net "M_H_DQ<7>")
	)
	(segment
		(start 38.707568 -8.509)
		(end 38.250368 -8.0518)
		(width 0.14224)
		(layer "In4.Cu")
		(net "M_H_DQ<7>")
	)
	(segment
		(start 38.55212 -9.020048)
		(end 38.707568 -8.8646)
		(width 0.14224)
		(layer "In4.Cu")
		(net "M_H_DQ<7>")
	)
	(segment
		(start 45.452792 -43.689524)
		(end 45.702728 -43.93946)
		(width 0.14224)
		(layer "In4.Cu")
		(net "M_H_DQ<7>")
	)
	(segment
		(start 45.819568 -42.884852)
		(end 45.819568 -43.1038)
		(width 0.14224)
		(layer "In4.Cu")
		(net "M_H_DQ<7>")
	)
	(segment
		(start 38.10762 -13.972032)
		(end 38.10762 -14.384528)
		(width 0.14224)
		(layer "In4.Cu")
		(net "M_H_DQ<7>")
	)
	(segment
		(start 64.940942 -62.993778)
		(end 64.940942 -63.377826)
		(width 0.0889)
		(layer "In4.Cu")
		(net "M_H_DQ<7>")
	)
	(segment
		(start 45.819568 -43.1038)
		(end 45.452792 -43.470576)
		(width 0.14224)
		(layer "In4.Cu")
		(net "M_H_DQ<7>")
	)
	(segment
		(start 47.22622 -44.510452)
		(end 47.445168 -44.510452)
		(width 0.14224)
		(layer "In4.Cu")
		(net "M_H_DQ<7>")
	)
	(segment
		(start 38.50132 -14.778228)
		(end 38.50132 -16.802862)
		(width 0.14224)
		(layer "In4.Cu")
		(net "M_H_DQ<7>")
	)
	(segment
		(start 48.632872 -45.917104)
		(end 48.266096 -46.28388)
		(width 0.14224)
		(layer "In4.Cu")
		(net "M_H_DQ<7>")
	)
	(segment
		(start 46.859444 -44.877228)
		(end 47.22622 -44.510452)
		(width 0.14224)
		(layer "In4.Cu")
		(net "M_H_DQ<7>")
	)
	(segment
		(start 38.250368 -8.0518)
		(end 37.996368 -8.0518)
		(width 0.14224)
		(layer "In4.Cu")
		(net "M_H_DQ<7>")
	)
	(segment
		(start 47.797212 -45.814996)
		(end 48.163988 -45.44822)
		(width 0.14224)
		(layer "In4.Cu")
		(net "M_H_DQ<7>")
	)
	(segment
		(start 37.73932 -13.603732)
		(end 38.10762 -13.972032)
		(width 0.14224)
		(layer "In4.Cu")
		(net "M_H_DQ<7>")
	)
	(segment
		(start 49.4538 -47.690532)
		(end 49.672748 -47.690532)
		(width 0.14224)
		(layer "In4.Cu")
		(net "M_H_DQ<7>")
	)
	(segment
		(start 37.996368 -8.0518)
		(end 37.666168 -7.7216)
		(width 0.14224)
		(layer "In4.Cu")
		(net "M_H_DQ<7>")
	)
	(segment
		(start 70.281292 -66.08699)
		(end 70.629526 -66.08699)
		(width 0.0889)
		(layer "In4.Cu")
		(net "M_H_DQ<7>")
	)
	(segment
		(start 50.681128 -48.21174)
		(end 50.221134 -48.671734)
		(width 0.14224)
		(layer "In4.Cu")
		(net "M_H_DQ<7>")
	)
	(segment
		(start 66.469006 -64.90589)
		(end 67.304666 -64.90589)
		(width 0.0889)
		(layer "In4.Cu")
		(net "M_H_DQ<7>")
	)
	(segment
		(start 46.39056 -44.408344)
		(end 46.39056 -44.627292)
		(width 0.14224)
		(layer "In4.Cu")
		(net "M_H_DQ<7>")
	)
	(segment
		(start 46.5074 -43.572684)
		(end 46.757336 -43.82262)
		(width 0.14224)
		(layer "In4.Cu")
		(net "M_H_DQ<7>")
	)
	(segment
		(start 38.78072 -18.316194)
		(end 38.55212 -18.544794)
		(width 0.14224)
		(layer "In4.Cu")
		(net "M_H_DQ<7>")
	)
	(segment
		(start 47.445168 -44.510452)
		(end 47.695104 -44.760388)
		(width 0.14224)
		(layer "In4.Cu")
		(net "M_H_DQ<7>")
	)
	(segment
		(start 67.869308 -65.400936)
		(end 68.053966 -65.400936)
		(width 0.0889)
		(layer "In4.Cu")
		(net "M_H_DQ<7>")
	)
	(segment
		(start 71.45909 -65.591436)
		(end 71.50735 -65.591436)
		(width 0.0889)
		(layer "In4.Cu")
		(net "M_H_DQ<7>")
	)
	(segment
		(start 48.163988 -45.44822)
		(end 48.382936 -45.44822)
		(width 0.14224)
		(layer "In4.Cu")
		(net "M_H_DQ<7>")
	)
	(segment
		(start 49.57064 -46.854872)
		(end 49.203864 -47.221648)
		(width 0.14224)
		(layer "In4.Cu")
		(net "M_H_DQ<7>")
	)
	(segment
		(start 50.221134 -48.851566)
		(end 55.230268 -53.8607)
		(width 0.14224)
		(layer "In4.Cu")
		(net "M_H_DQ<7>")
	)
	(segment
		(start 71.50735 -65.591436)
		(end 72.328786 -65.49644)
		(width 0.0889)
		(layer "In4.Cu")
		(net "M_H_DQ<7>")
	)
	(segment
		(start 48.73498 -46.752764)
		(end 49.101756 -46.385988)
		(width 0.14224)
		(layer "In4.Cu")
		(net "M_H_DQ<7>")
	)
	(segment
		(start 38.78072 -17.082262)
		(end 38.78072 -18.316194)
		(width 0.14224)
		(layer "In4.Cu")
		(net "M_H_DQ<7>")
	)
	(segment
		(start 38.75532 -23.118572)
		(end 38.453568 -23.420324)
		(width 0.14224)
		(layer "In4.Cu")
		(net "M_H_DQ<7>")
	)
	(segment
		(start 38.847268 -35.912552)
		(end 45.819568 -42.884852)
		(width 0.14224)
		(layer "In4.Cu")
		(net "M_H_DQ<7>")
	)
	(segment
		(start 46.640496 -44.877228)
		(end 46.859444 -44.877228)
		(width 0.14224)
		(layer "In4.Cu")
		(net "M_H_DQ<7>")
	)
	(segment
		(start 38.707568 -8.8646)
		(end 38.707568 -8.509)
		(width 0.14224)
		(layer "In4.Cu")
		(net "M_H_DQ<7>")
	)
	(segment
		(start 46.757336 -44.041568)
		(end 46.39056 -44.408344)
		(width 0.14224)
		(layer "In4.Cu")
		(net "M_H_DQ<7>")
	)
	(segment
		(start 38.55212 -12.32535)
		(end 38.55212 -9.020048)
		(width 0.14224)
		(layer "In4.Cu")
		(net "M_H_DQ<7>")
	)
	(segment
		(start 47.328328 -45.56506)
		(end 47.578264 -45.814996)
		(width 0.14224)
		(layer "In4.Cu")
		(net "M_H_DQ<7>")
	)
	(segment
		(start 48.382936 -45.44822)
		(end 48.632872 -45.698156)
		(width 0.14224)
		(layer "In4.Cu")
		(net "M_H_DQ<7>")
	)
	(segment
		(start 38.453568 -28.0035)
		(end 38.847268 -28.3972)
		(width 0.14224)
		(layer "In4.Cu")
		(net "M_H_DQ<7>")
	)
	(segment
		(start 38.55212 -21.772372)
		(end 38.75532 -21.975572)
		(width 0.14224)
		(layer "In4.Cu")
		(net "M_H_DQ<7>")
	)
	(segment
		(start 50.221134 -48.671734)
		(end 50.221134 -48.851566)
		(width 0.14224)
		(layer "In4.Cu")
		(net "M_H_DQ<7>")
	)
	(segment
		(start 38.847268 -28.3972)
		(end 38.847268 -35.912552)
		(width 0.14224)
		(layer "In4.Cu")
		(net "M_H_DQ<7>")
	)
	(segment
		(start 46.39056 -44.627292)
		(end 46.640496 -44.877228)
		(width 0.14224)
		(layer "In4.Cu")
		(net "M_H_DQ<7>")
	)
	(segment
		(start 49.57064 -46.635924)
		(end 49.57064 -46.854872)
		(width 0.14224)
		(layer "In4.Cu")
		(net "M_H_DQ<7>")
	)
	(segment
		(start 45.452792 -43.470576)
		(end 45.452792 -43.689524)
		(width 0.14224)
		(layer "In4.Cu")
		(net "M_H_DQ<7>")
	)
	(segment
		(start 47.695104 -44.979336)
		(end 47.328328 -45.346112)
		(width 0.14224)
		(layer "In4.Cu")
		(net "M_H_DQ<7>")
	)
	(segment
		(start 48.516032 -46.752764)
		(end 48.73498 -46.752764)
		(width 0.14224)
		(layer "In4.Cu")
		(net "M_H_DQ<7>")
	)
	(segment
		(start 47.328328 -45.346112)
		(end 47.328328 -45.56506)
		(width 0.14224)
		(layer "In4.Cu")
		(net "M_H_DQ<7>")
	)
	(segment
		(start 50.039524 -47.323756)
		(end 50.258472 -47.323756)
		(width 0.14224)
		(layer "In4.Cu")
		(net "M_H_DQ<7>")
	)
	(segment
		(start 49.203864 -47.440596)
		(end 49.4538 -47.690532)
		(width 0.14224)
		(layer "In4.Cu")
		(net "M_H_DQ<7>")
	)
	(segment
		(start 49.320704 -46.385988)
		(end 49.57064 -46.635924)
		(width 0.14224)
		(layer "In4.Cu")
		(net "M_H_DQ<7>")
	)
	(segment
		(start 37.666168 -7.403084)
		(end 37.34943 -7.086346)
		(width 0.14224)
		(layer "In4.Cu")
		(net "M_H_DQ<7>")
	)
	(segment
		(start 55.230268 -53.8607)
		(end 57.147968 -53.8607)
		(width 0.14224)
		(layer "In4.Cu")
		(net "M_H_DQ<7>")
	)
	(segment
		(start 46.288452 -43.572684)
		(end 46.5074 -43.572684)
		(width 0.14224)
		(layer "In4.Cu")
		(net "M_H_DQ<7>")
	)
	(segment
		(start 38.199314 -12.678156)
		(end 38.55212 -12.32535)
		(width 0.14224)
		(layer "In4.Cu")
		(net "M_H_DQ<7>")
	)
	(segment
		(start 38.55212 -18.544794)
		(end 38.55212 -21.772372)
		(width 0.14224)
		(layer "In4.Cu")
		(net "M_H_DQ<7>")
	)
	(segment
		(start 59.824366 -57.877202)
		(end 64.940942 -62.993778)
		(width 0.14224)
		(layer "In4.Cu")
		(net "M_H_DQ<7>")
	)
	(segment
		(start 48.632872 -45.698156)
		(end 48.632872 -45.917104)
		(width 0.14224)
		(layer "In4.Cu")
		(net "M_H_DQ<7>")
	)
	(segment
		(start 38.10762 -14.384528)
		(end 38.50132 -14.778228)
		(width 0.14224)
		(layer "In4.Cu")
		(net "M_H_DQ<7>")
	)
	(segment
		(start 49.203864 -47.221648)
		(end 49.203864 -47.440596)
		(width 0.14224)
		(layer "In4.Cu")
		(net "M_H_DQ<7>")
	)
	(segment
		(start 37.73932 -13.13815)
		(end 37.73932 -13.603732)
		(width 0.14224)
		(layer "In4.Cu")
		(net "M_H_DQ<7>")
	)
	(segment
		(start 45.702728 -43.93946)
		(end 45.921676 -43.93946)
		(width 0.14224)
		(layer "In4.Cu")
		(net "M_H_DQ<7>")
	)
	(segment
		(start 48.266096 -46.502828)
		(end 48.516032 -46.752764)
		(width 0.14224)
		(layer "In4.Cu")
		(net "M_H_DQ<7>")
	)
	(segment
		(start 38.199314 -12.678156)
		(end 37.73932 -13.13815)
		(width 0.14224)
		(layer "In4.Cu")
		(net "M_H_DQ<7>")
	)
	(segment
		(start 38.50132 -16.802862)
		(end 38.78072 -17.082262)
		(width 0.14224)
		(layer "In4.Cu")
		(net "M_H_DQ<7>")
	)
	(segment
		(start 50.681128 -47.746412)
		(end 50.681128 -48.21174)
		(width 0.14224)
		(layer "In4.Cu")
		(net "M_H_DQ<7>")
	)
	(segment
		(start 57.147968 -53.8607)
		(end 59.824366 -56.537098)
		(width 0.14224)
		(layer "In4.Cu")
		(net "M_H_DQ<7>")
	)
	(arc
		(start 68.053966 -65.400936)
		(mid 68.33939 -65.484403)
		(end 68.547996 -65.696338)
		(width 0.0889)
		(layer "In4.Cu")
		(net "M_H_DQ<7>")
	)
	(arc
		(start 70.099936 -66.191638)
		(mid 70.176611 -66.115057)
		(end 70.281292 -66.08699)
		(width 0.0889)
		(layer "In4.Cu")
		(net "M_H_DQ<7>")
	)
	(arc
		(start 67.653154 -65.203832)
		(mid 67.744098 -65.321175)
		(end 67.869308 -65.400936)
		(width 0.0889)
		(layer "In4.Cu")
		(net "M_H_DQ<7>")
	)
	(arc
		(start 70.629526 -66.08699)
		(mid 70.91495 -66.003523)
		(end 71.123556 -65.791588)
		(width 0.0889)
		(layer "In4.Cu")
		(net "M_H_DQ<7>")
	)
	(arc
		(start 69.406516 -66.191638)
		(mid 69.546595 -66.334374)
		(end 69.73824 -66.391536)
		(width 0.0889)
		(layer "In4.Cu")
		(net "M_H_DQ<7>")
	)
	(arc
		(start 71.123556 -65.791588)
		(mid 71.265239 -65.647784)
		(end 71.45909 -65.591436)
		(width 0.0889)
		(layer "In4.Cu")
		(net "M_H_DQ<7>")
	)
	(arc
		(start 67.304666 -64.90589)
		(mid 67.50726 -65.021708)
		(end 67.653154 -65.203832)
		(width 0.0889)
		(layer "In4.Cu")
		(net "M_H_DQ<7>")
	)
	(arc
		(start 68.547996 -65.696338)
		(mid 68.689679 -65.840142)
		(end 68.88353 -65.89649)
		(width 0.0889)
		(layer "In4.Cu")
		(net "M_H_DQ<7>")
	)
	(arc
		(start 68.916296 -65.89649)
		(mid 69.199513 -65.980771)
		(end 69.406516 -66.191638)
		(width 0.0889)
		(layer "In4.Cu")
		(net "M_H_DQ<7>")
	)
	(arc
		(start 69.768212 -66.391536)
		(mid 69.959854 -66.33437)
		(end 70.099936 -66.191638)
		(width 0.0889)
		(layer "In4.Cu")
		(net "M_H_DQ<7>")
	)
	(segment
		(start 38.199568 -9.4488)
		(end 38.331648 -9.31672)
		(width 0.1651)
		(layer "F.Cu")
		(net "M_H_DQ<6>")
	)
	(segment
		(start 38.331648 -9.09828)
		(end 38.199568 -8.9662)
		(width 0.1651)
		(layer "F.Cu")
		(net "M_H_DQ<6>")
	)
	(segment
		(start 38.199568 -10.422382)
		(end 38.199568 -9.4488)
		(width 0.1651)
		(layer "F.Cu")
		(net "M_H_DQ<6>")
	)
	(segment
		(start 71.183246 -66.48704)
		(end 70.611746 -66.48704)
		(width 0.0889)
		(layer "F.Cu")
		(net "M_H_DQ<6>")
	)
	(segment
		(start 38.331648 -9.31672)
		(end 38.331648 -9.09828)
		(width 0.1651)
		(layer "F.Cu")
		(net "M_H_DQ<6>")
	)
	(segment
		(start 38.199568 -8.9662)
		(end 38.199568 -8.661654)
		(width 0.1651)
		(layer "F.Cu")
		(net "M_H_DQ<6>")
	)
	(segment
		(start 38.199568 -8.661654)
		(end 38.199314 -8.6614)
		(width 0.1651)
		(layer "F.Cu")
		(net "M_H_DQ<6>")
	)
	(via
		(at 38.199314 -8.6614)
		(size 0.508)
		(drill 0.254)
		(layers "F.Cu" "B.Cu")
		(net "M_H_DQ<6>")
	)
	(via
		(at 70.611746 -66.48704)
		(size 0.508)
		(drill 0.254)
		(layers "F.Cu" "B.Cu")
		(net "M_H_DQ<6>")
	)
	(via
		(at 37.34943 -13.959078)
		(size 0.508)
		(drill 0.254)
		(layers "F.Cu" "B.Cu")
		(net "M_H_DQ<6>")
	)
	(segment
		(start 37.34943 -15.222982)
		(end 37.34943 -13.959078)
		(width 0.1651)
		(layer "B.Cu")
		(net "M_H_DQ<6>")
	)
	(segment
		(start 37.450268 -34.953194)
		(end 37.605208 -35.108134)
		(width 0.14224)
		(layer "In4.Cu")
		(net "M_H_DQ<6>")
	)
	(segment
		(start 42.897044 -42.376344)
		(end 42.897044 -42.556176)
		(width 0.14224)
		(layer "In4.Cu")
		(net "M_H_DQ<6>")
	)
	(segment
		(start 37.886386 -12.156186)
		(end 37.886386 -11.804396)
		(width 0.14224)
		(layer "In4.Cu")
		(net "M_H_DQ<6>")
	)
	(segment
		(start 37.450268 -34.600134)
		(end 37.450268 -34.953194)
		(width 0.14224)
		(layer "In4.Cu")
		(net "M_H_DQ<6>")
	)
	(segment
		(start 38.146228 -31.793434)
		(end 37.579808 -31.793434)
		(width 0.14224)
		(layer "In4.Cu")
		(net "M_H_DQ<6>")
	)
	(segment
		(start 69.731636 -66.582036)
		(end 69.79031 -66.582036)
		(width 0.0889)
		(layer "In4.Cu")
		(net "M_H_DQ<6>")
	)
	(segment
		(start 38.146228 -33.782254)
		(end 38.301168 -33.937194)
		(width 0.14224)
		(layer "In4.Cu")
		(net "M_H_DQ<6>")
	)
	(segment
		(start 37.824918 -9.313672)
		(end 37.824918 -9.035796)
		(width 0.14224)
		(layer "In4.Cu")
		(net "M_H_DQ<6>")
	)
	(segment
		(start 37.86632 -15.041372)
		(end 37.86632 -16.840962)
		(width 0.14224)
		(layer "In4.Cu")
		(net "M_H_DQ<6>")
	)
	(segment
		(start 37.71392 -21.975572)
		(end 37.71392 -23.169372)
		(width 0.14224)
		(layer "In4.Cu")
		(net "M_H_DQ<6>")
	)
	(segment
		(start 37.579808 -32.456374)
		(end 38.146228 -32.456374)
		(width 0.14224)
		(layer "In4.Cu")
		(net "M_H_DQ<6>")
	)
	(segment
		(start 37.460936 -11.378946)
		(end 37.460936 -11.093704)
		(width 0.14224)
		(layer "In4.Cu")
		(net "M_H_DQ<6>")
	)
	(segment
		(start 44.526454 -42.669714)
		(end 43.915584 -43.280584)
		(width 0.14224)
		(layer "In4.Cu")
		(net "M_H_DQ<6>")
	)
	(segment
		(start 37.579808 -33.782254)
		(end 38.146228 -33.782254)
		(width 0.14224)
		(layer "In4.Cu")
		(net "M_H_DQ<6>")
	)
	(segment
		(start 38.301168 -32.611314)
		(end 38.301168 -32.964374)
		(width 0.14224)
		(layer "In4.Cu")
		(net "M_H_DQ<6>")
	)
	(segment
		(start 38.301168 -32.964374)
		(end 38.146228 -33.119314)
		(width 0.14224)
		(layer "In4.Cu")
		(net "M_H_DQ<6>")
	)
	(segment
		(start 58.337704 -57.293764)
		(end 64.43853 -63.39459)
		(width 0.14224)
		(layer "In4.Cu")
		(net "M_H_DQ<6>")
	)
	(segment
		(start 43.545506 -41.508934)
		(end 43.545506 -41.727882)
		(width 0.14224)
		(layer "In4.Cu")
		(net "M_H_DQ<6>")
	)
	(segment
		(start 66.390774 -65.09639)
		(end 67.268344 -65.09639)
		(width 0.0889)
		(layer "In4.Cu")
		(net "M_H_DQ<6>")
	)
	(segment
		(start 38.146228 -34.445194)
		(end 37.605208 -34.445194)
		(width 0.14224)
		(layer "In4.Cu")
		(net "M_H_DQ<6>")
	)
	(segment
		(start 44.01439 -42.196766)
		(end 44.233338 -42.196766)
		(width 0.14224)
		(layer "In4.Cu")
		(net "M_H_DQ<6>")
	)
	(segment
		(start 69.79031 -66.582036)
		(end 70.611746 -66.48704)
		(width 0.0889)
		(layer "In4.Cu")
		(net "M_H_DQ<6>")
	)
	(segment
		(start 37.841936 -10.369296)
		(end 37.460936 -9.988296)
		(width 0.14224)
		(layer "In4.Cu")
		(net "M_H_DQ<6>")
	)
	(segment
		(start 37.605208 -34.445194)
		(end 37.450268 -34.600134)
		(width 0.14224)
		(layer "In4.Cu")
		(net "M_H_DQ<6>")
	)
	(segment
		(start 38.301168 -34.290254)
		(end 38.146228 -34.445194)
		(width 0.14224)
		(layer "In4.Cu")
		(net "M_H_DQ<6>")
	)
	(segment
		(start 43.915584 -43.280584)
		(end 43.915584 -43.460416)
		(width 0.14224)
		(layer "In4.Cu")
		(net "M_H_DQ<6>")
	)
	(segment
		(start 38.146228 -35.108134)
		(end 38.301168 -35.263074)
		(width 0.14224)
		(layer "In4.Cu")
		(net "M_H_DQ<6>")
	)
	(segment
		(start 38.301168 -28.8671)
		(end 38.301168 -30.312614)
		(width 0.14224)
		(layer "In4.Cu")
		(net "M_H_DQ<6>")
	)
	(segment
		(start 37.34943 -13.959078)
		(end 37.113718 -13.723366)
		(width 0.14224)
		(layer "In4.Cu")
		(net "M_H_DQ<6>")
	)
	(segment
		(start 68.876926 -66.08699)
		(end 68.909692 -66.08699)
		(width 0.0889)
		(layer "In4.Cu")
		(net "M_H_DQ<6>")
	)
	(segment
		(start 37.34943 -14.524482)
		(end 37.86632 -15.041372)
		(width 0.14224)
		(layer "In4.Cu")
		(net "M_H_DQ<6>")
	)
	(segment
		(start 42.607738 -40.571166)
		(end 42.607738 -40.790114)
		(width 0.14224)
		(layer "In4.Cu")
		(net "M_H_DQ<6>")
	)
	(segment
		(start 37.91712 -18.614898)
		(end 37.91712 -21.772372)
		(width 0.14224)
		(layer "In4.Cu")
		(net "M_H_DQ<6>")
	)
	(segment
		(start 37.113718 -13.723366)
		(end 37.113718 -12.928854)
		(width 0.14224)
		(layer "In4.Cu")
		(net "M_H_DQ<6>")
	)
	(segment
		(start 37.460936 -11.093704)
		(end 37.841936 -10.712704)
		(width 0.14224)
		(layer "In4.Cu")
		(net "M_H_DQ<6>")
	)
	(segment
		(start 43.076622 -41.258998)
		(end 43.29557 -41.258998)
		(width 0.14224)
		(layer "In4.Cu")
		(net "M_H_DQ<6>")
	)
	(segment
		(start 37.113718 -12.928854)
		(end 37.886386 -12.156186)
		(width 0.14224)
		(layer "In4.Cu")
		(net "M_H_DQ<6>")
	)
	(segment
		(start 37.71392 -16.993362)
		(end 37.71392 -18.411698)
		(width 0.14224)
		(layer "In4.Cu")
		(net "M_H_DQ<6>")
	)
	(segment
		(start 38.301168 -31.285434)
		(end 38.301168 -31.638494)
		(width 0.14224)
		(layer "In4.Cu")
		(net "M_H_DQ<6>")
	)
	(segment
		(start 42.43451 -41.90111)
		(end 43.076622 -41.258998)
		(width 0.14224)
		(layer "In4.Cu")
		(net "M_H_DQ<6>")
	)
	(segment
		(start 38.301168 -31.638494)
		(end 38.146228 -31.793434)
		(width 0.14224)
		(layer "In4.Cu")
		(net "M_H_DQ<6>")
	)
	(segment
		(start 37.424868 -30.975554)
		(end 37.579808 -31.130494)
		(width 0.14224)
		(layer "In4.Cu")
		(net "M_H_DQ<6>")
	)
	(segment
		(start 37.424868 -33.274254)
		(end 37.424868 -33.627314)
		(width 0.14224)
		(layer "In4.Cu")
		(net "M_H_DQ<6>")
	)
	(segment
		(start 37.424868 -31.948374)
		(end 37.424868 -32.301434)
		(width 0.14224)
		(layer "In4.Cu")
		(net "M_H_DQ<6>")
	)
	(segment
		(start 37.460936 -9.677654)
		(end 37.824918 -9.313672)
		(width 0.14224)
		(layer "In4.Cu")
		(net "M_H_DQ<6>")
	)
	(segment
		(start 42.254678 -41.90111)
		(end 42.43451 -41.90111)
		(width 0.14224)
		(layer "In4.Cu")
		(net "M_H_DQ<6>")
	)
	(segment
		(start 64.688974 -63.39459)
		(end 66.390774 -65.09639)
		(width 0.0889)
		(layer "In4.Cu")
		(net "M_H_DQ<6>")
	)
	(segment
		(start 42.897044 -42.556176)
		(end 43.186096 -42.845228)
		(width 0.14224)
		(layer "In4.Cu")
		(net "M_H_DQ<6>")
	)
	(segment
		(start 43.915584 -43.460416)
		(end 55.293768 -54.8386)
		(width 0.14224)
		(layer "In4.Cu")
		(net "M_H_DQ<6>")
	)
	(segment
		(start 37.886386 -11.804396)
		(end 37.460936 -11.378946)
		(width 0.14224)
		(layer "In4.Cu")
		(net "M_H_DQ<6>")
	)
	(segment
		(start 37.81552 -28.381452)
		(end 38.301168 -28.8671)
		(width 0.14224)
		(layer "In4.Cu")
		(net "M_H_DQ<6>")
	)
	(segment
		(start 58.337704 -56.561736)
		(end 58.337704 -57.293764)
		(width 0.14224)
		(layer "In4.Cu")
		(net "M_H_DQ<6>")
	)
	(segment
		(start 38.146228 -32.456374)
		(end 38.301168 -32.611314)
		(width 0.14224)
		(layer "In4.Cu")
		(net "M_H_DQ<6>")
	)
	(segment
		(start 41.965626 -41.432226)
		(end 41.965626 -41.612058)
		(width 0.14224)
		(layer "In4.Cu")
		(net "M_H_DQ<6>")
	)
	(segment
		(start 38.301168 -35.263074)
		(end 38.301168 -36.264596)
		(width 0.14224)
		(layer "In4.Cu")
		(net "M_H_DQ<6>")
	)
	(segment
		(start 37.579808 -31.793434)
		(end 37.424868 -31.948374)
		(width 0.14224)
		(layer "In4.Cu")
		(net "M_H_DQ<6>")
	)
	(segment
		(start 37.579808 -30.467554)
		(end 37.424868 -30.622494)
		(width 0.14224)
		(layer "In4.Cu")
		(net "M_H_DQ<6>")
	)
	(segment
		(start 38.146228 -33.119314)
		(end 37.579808 -33.119314)
		(width 0.14224)
		(layer "In4.Cu")
		(net "M_H_DQ<6>")
	)
	(segment
		(start 38.146228 -30.467554)
		(end 37.579808 -30.467554)
		(width 0.14224)
		(layer "In4.Cu")
		(net "M_H_DQ<6>")
	)
	(segment
		(start 37.34943 -13.959078)
		(end 37.34943 -14.524482)
		(width 0.14224)
		(layer "In4.Cu")
		(net "M_H_DQ<6>")
	)
	(segment
		(start 43.29557 -41.258998)
		(end 43.545506 -41.508934)
		(width 0.14224)
		(layer "In4.Cu")
		(net "M_H_DQ<6>")
	)
	(segment
		(start 37.86632 -16.840962)
		(end 37.71392 -16.993362)
		(width 0.14224)
		(layer "In4.Cu")
		(net "M_H_DQ<6>")
	)
	(segment
		(start 43.186096 -42.845228)
		(end 43.365928 -42.845228)
		(width 0.14224)
		(layer "In4.Cu")
		(net "M_H_DQ<6>")
	)
	(segment
		(start 56.915304 -55.871364)
		(end 57.647332 -55.871364)
		(width 0.14224)
		(layer "In4.Cu")
		(net "M_H_DQ<6>")
	)
	(segment
		(start 37.81552 -23.270972)
		(end 37.81552 -28.381452)
		(width 0.14224)
		(layer "In4.Cu")
		(net "M_H_DQ<6>")
	)
	(segment
		(start 43.365928 -42.845228)
		(end 44.01439 -42.196766)
		(width 0.14224)
		(layer "In4.Cu")
		(net "M_H_DQ<6>")
	)
	(segment
		(start 37.605208 -35.108134)
		(end 38.146228 -35.108134)
		(width 0.14224)
		(layer "In4.Cu")
		(net "M_H_DQ<6>")
	)
	(segment
		(start 57.647332 -55.871364)
		(end 58.337704 -56.561736)
		(width 0.14224)
		(layer "In4.Cu")
		(net "M_H_DQ<6>")
	)
	(segment
		(start 37.579808 -33.119314)
		(end 37.424868 -33.274254)
		(width 0.14224)
		(layer "In4.Cu")
		(net "M_H_DQ<6>")
	)
	(segment
		(start 67.832986 -65.591436)
		(end 68.047362 -65.591436)
		(width 0.0889)
		(layer "In4.Cu")
		(net "M_H_DQ<6>")
	)
	(segment
		(start 43.545506 -41.727882)
		(end 42.897044 -42.376344)
		(width 0.14224)
		(layer "In4.Cu")
		(net "M_H_DQ<6>")
	)
	(segment
		(start 41.965626 -41.612058)
		(end 42.254678 -41.90111)
		(width 0.14224)
		(layer "In4.Cu")
		(net "M_H_DQ<6>")
	)
	(segment
		(start 37.91712 -21.772372)
		(end 37.71392 -21.975572)
		(width 0.14224)
		(layer "In4.Cu")
		(net "M_H_DQ<6>")
	)
	(segment
		(start 55.88254 -54.8386)
		(end 56.915304 -55.871364)
		(width 0.14224)
		(layer "In4.Cu")
		(net "M_H_DQ<6>")
	)
	(segment
		(start 38.146228 -31.130494)
		(end 38.301168 -31.285434)
		(width 0.14224)
		(layer "In4.Cu")
		(net "M_H_DQ<6>")
	)
	(segment
		(start 38.301168 -30.312614)
		(end 38.146228 -30.467554)
		(width 0.14224)
		(layer "In4.Cu")
		(net "M_H_DQ<6>")
	)
	(segment
		(start 44.526454 -42.489882)
		(end 44.526454 -42.669714)
		(width 0.14224)
		(layer "In4.Cu")
		(net "M_H_DQ<6>")
	)
	(segment
		(start 37.424868 -33.627314)
		(end 37.579808 -33.782254)
		(width 0.14224)
		(layer "In4.Cu")
		(net "M_H_DQ<6>")
	)
	(segment
		(start 37.71392 -23.169372)
		(end 37.81552 -23.270972)
		(width 0.14224)
		(layer "In4.Cu")
		(net "M_H_DQ<6>")
	)
	(segment
		(start 38.301168 -33.937194)
		(end 38.301168 -34.290254)
		(width 0.14224)
		(layer "In4.Cu")
		(net "M_H_DQ<6>")
	)
	(segment
		(start 37.579808 -31.130494)
		(end 38.146228 -31.130494)
		(width 0.14224)
		(layer "In4.Cu")
		(net "M_H_DQ<6>")
	)
	(segment
		(start 42.607738 -40.790114)
		(end 41.965626 -41.432226)
		(width 0.14224)
		(layer "In4.Cu")
		(net "M_H_DQ<6>")
	)
	(segment
		(start 38.301168 -36.264596)
		(end 42.607738 -40.571166)
		(width 0.14224)
		(layer "In4.Cu")
		(net "M_H_DQ<6>")
	)
	(segment
		(start 37.71392 -18.411698)
		(end 37.91712 -18.614898)
		(width 0.14224)
		(layer "In4.Cu")
		(net "M_H_DQ<6>")
	)
	(segment
		(start 37.424868 -32.301434)
		(end 37.579808 -32.456374)
		(width 0.14224)
		(layer "In4.Cu")
		(net "M_H_DQ<6>")
	)
	(segment
		(start 37.824918 -9.035796)
		(end 38.199314 -8.6614)
		(width 0.14224)
		(layer "In4.Cu")
		(net "M_H_DQ<6>")
	)
	(segment
		(start 37.424868 -30.622494)
		(end 37.424868 -30.975554)
		(width 0.14224)
		(layer "In4.Cu")
		(net "M_H_DQ<6>")
	)
	(segment
		(start 64.43853 -63.39459)
		(end 64.688974 -63.39459)
		(width 0.0889)
		(layer "In4.Cu")
		(net "M_H_DQ<6>")
	)
	(segment
		(start 44.233338 -42.196766)
		(end 44.526454 -42.489882)
		(width 0.14224)
		(layer "In4.Cu")
		(net "M_H_DQ<6>")
	)
	(segment
		(start 37.460936 -9.988296)
		(end 37.460936 -9.677654)
		(width 0.14224)
		(layer "In4.Cu")
		(net "M_H_DQ<6>")
	)
	(segment
		(start 37.841936 -10.712704)
		(end 37.841936 -10.369296)
		(width 0.14224)
		(layer "In4.Cu")
		(net "M_H_DQ<6>")
	)
	(segment
		(start 55.293768 -54.8386)
		(end 55.88254 -54.8386)
		(width 0.14224)
		(layer "In4.Cu")
		(net "M_H_DQ<6>")
	)
	(arc
		(start 67.484498 -65.293494)
		(mid 67.630423 -65.475581)
		(end 67.832986 -65.591436)
		(width 0.0889)
		(layer "In4.Cu")
		(net "M_H_DQ<6>")
	)
	(arc
		(start 68.909692 -66.08699)
		(mid 69.101334 -66.144156)
		(end 69.241416 -66.286888)
		(width 0.0889)
		(layer "In4.Cu")
		(net "M_H_DQ<6>")
	)
	(arc
		(start 69.241416 -66.286888)
		(mid 69.44842 -66.497752)
		(end 69.731636 -66.582036)
		(width 0.0889)
		(layer "In4.Cu")
		(net "M_H_DQ<6>")
	)
	(arc
		(start 67.268344 -65.09639)
		(mid 67.393545 -65.176161)
		(end 67.484498 -65.293494)
		(width 0.0889)
		(layer "In4.Cu")
		(net "M_H_DQ<6>")
	)
	(arc
		(start 68.047362 -65.591436)
		(mid 68.241212 -65.647786)
		(end 68.382896 -65.791588)
		(width 0.0889)
		(layer "In4.Cu")
		(net "M_H_DQ<6>")
	)
	(arc
		(start 68.382896 -65.791588)
		(mid 68.591504 -66.00352)
		(end 68.876926 -66.08699)
		(width 0.0889)
		(layer "In4.Cu")
		(net "M_H_DQ<6>")
	)
	(segment
		(start 148.699474 -5.822442)
		(end 148.699474 -7.086346)
		(width 0.1651)
		(layer "F.Cu")
		(net "M_H_DQ<63>")
	)
	(segment
		(start 120.216168 -61.352938)
		(end 120.787668 -61.352938)
		(width 0.1016)
		(layer "F.Cu")
		(net "M_H_DQ<63>")
	)
	(via
		(at 148.699474 -7.086346)
		(size 0.508)
		(drill 0.254)
		(layers "F.Cu" "B.Cu")
		(net "M_H_DQ<63>")
	)
	(via
		(at 120.216168 -61.352938)
		(size 0.508)
		(drill 0.254)
		(layers "F.Cu" "B.Cu")
		(net "M_H_DQ<63>")
	)
	(via
		(at 149.549358 -12.678156)
		(size 0.508)
		(drill 0.254)
		(layers "F.Cu" "B.Cu")
		(net "M_H_DQ<63>")
	)
	(segment
		(start 149.549358 -10.623042)
		(end 149.549358 -12.678156)
		(width 0.1651)
		(layer "B.Cu")
		(net "M_H_DQ<63>")
	)
	(segment
		(start 149.902164 -21.772372)
		(end 149.902164 -18.574258)
		(width 0.14224)
		(layer "In4.Cu")
		(net "M_H_DQ<63>")
	)
	(segment
		(start 149.908768 -16.860266)
		(end 149.908768 -14.835632)
		(width 0.14224)
		(layer "In4.Cu")
		(net "M_H_DQ<63>")
	)
	(segment
		(start 120.622568 -60.56249)
		(end 120.642126 -59.811666)
		(width 0.0889)
		(layer "In4.Cu")
		(net "M_H_DQ<63>")
	)
	(segment
		(start 150.105364 -21.975572)
		(end 149.902164 -21.772372)
		(width 0.14224)
		(layer "In4.Cu")
		(net "M_H_DQ<63>")
	)
	(segment
		(start 149.346412 -8.0518)
		(end 149.016212 -7.7216)
		(width 0.14224)
		(layer "In4.Cu")
		(net "M_H_DQ<63>")
	)
	(segment
		(start 149.063964 -13.625576)
		(end 149.063964 -13.16355)
		(width 0.14224)
		(layer "In4.Cu")
		(net "M_H_DQ<63>")
	)
	(segment
		(start 124.518928 -53.027834)
		(end 125.451362 -52.0954)
		(width 0.0889)
		(layer "In4.Cu")
		(net "M_H_DQ<63>")
	)
	(segment
		(start 129.802382 -48.15205)
		(end 131.78917 -48.15205)
		(width 0.14224)
		(layer "In4.Cu")
		(net "M_H_DQ<63>")
	)
	(segment
		(start 131.78917 -48.15205)
		(end 149.476968 -30.464252)
		(width 0.14224)
		(layer "In4.Cu")
		(net "M_H_DQ<63>")
	)
	(segment
		(start 123.639072 -53.027834)
		(end 124.518928 -53.027834)
		(width 0.0889)
		(layer "In4.Cu")
		(net "M_H_DQ<63>")
	)
	(segment
		(start 149.600412 -8.0518)
		(end 149.346412 -8.0518)
		(width 0.14224)
		(layer "In4.Cu")
		(net "M_H_DQ<63>")
	)
	(segment
		(start 149.934168 -27.965146)
		(end 149.934168 -23.289768)
		(width 0.14224)
		(layer "In4.Cu")
		(net "M_H_DQ<63>")
	)
	(segment
		(start 149.476968 -28.854146)
		(end 149.476968 -28.422346)
		(width 0.14224)
		(layer "In4.Cu")
		(net "M_H_DQ<63>")
	)
	(segment
		(start 150.010368 -16.961866)
		(end 149.908768 -16.860266)
		(width 0.14224)
		(layer "In4.Cu")
		(net "M_H_DQ<63>")
	)
	(segment
		(start 149.476968 -30.464252)
		(end 149.476968 -30.047946)
		(width 0.14224)
		(layer "In4.Cu")
		(net "M_H_DQ<63>")
	)
	(segment
		(start 122.440192 -57.694322)
		(end 122.445018 -57.685686)
		(width 0.0889)
		(layer "In4.Cu")
		(net "M_H_DQ<63>")
	)
	(segment
		(start 122.445018 -57.685686)
		(end 122.451368 -57.675018)
		(width 0.0889)
		(layer "In4.Cu")
		(net "M_H_DQ<63>")
	)
	(segment
		(start 149.063964 -13.16355)
		(end 149.549358 -12.678156)
		(width 0.14224)
		(layer "In4.Cu")
		(net "M_H_DQ<63>")
	)
	(segment
		(start 149.705568 -29.082746)
		(end 149.476968 -28.854146)
		(width 0.14224)
		(layer "In4.Cu")
		(net "M_H_DQ<63>")
	)
	(segment
		(start 149.902164 -9.020048)
		(end 150.057612 -8.8646)
		(width 0.14224)
		(layer "In4.Cu")
		(net "M_H_DQ<63>")
	)
	(segment
		(start 122.445018 -55.704486)
		(end 122.451368 -55.693818)
		(width 0.0889)
		(layer "In4.Cu")
		(net "M_H_DQ<63>")
	)
	(segment
		(start 149.902164 -12.32535)
		(end 149.902164 -9.020048)
		(width 0.14224)
		(layer "In4.Cu")
		(net "M_H_DQ<63>")
	)
	(segment
		(start 120.216168 -61.352938)
		(end 120.622568 -60.56249)
		(width 0.0889)
		(layer "In4.Cu")
		(net "M_H_DQ<63>")
	)
	(segment
		(start 149.457664 -14.384528)
		(end 149.457664 -14.019276)
		(width 0.14224)
		(layer "In4.Cu")
		(net "M_H_DQ<63>")
	)
	(segment
		(start 122.780552 -53.523134)
		(end 122.813318 -53.523134)
		(width 0.0889)
		(layer "In4.Cu")
		(net "M_H_DQ<63>")
	)
	(segment
		(start 149.016212 -7.403084)
		(end 148.699474 -7.086346)
		(width 0.14224)
		(layer "In4.Cu")
		(net "M_H_DQ<63>")
	)
	(segment
		(start 122.440192 -56.703722)
		(end 122.445018 -56.695086)
		(width 0.0889)
		(layer "In4.Cu")
		(net "M_H_DQ<63>")
	)
	(segment
		(start 149.457664 -14.019276)
		(end 149.063964 -13.625576)
		(width 0.14224)
		(layer "In4.Cu")
		(net "M_H_DQ<63>")
	)
	(segment
		(start 149.476968 -30.047946)
		(end 149.705568 -29.819346)
		(width 0.14224)
		(layer "In4.Cu")
		(net "M_H_DQ<63>")
	)
	(segment
		(start 122.445018 -54.713886)
		(end 122.451368 -54.703218)
		(width 0.0889)
		(layer "In4.Cu")
		(net "M_H_DQ<63>")
	)
	(segment
		(start 122.445018 -56.695086)
		(end 122.451368 -56.684418)
		(width 0.0889)
		(layer "In4.Cu")
		(net "M_H_DQ<63>")
	)
	(segment
		(start 149.908768 -14.835632)
		(end 149.457664 -14.384528)
		(width 0.14224)
		(layer "In4.Cu")
		(net "M_H_DQ<63>")
	)
	(segment
		(start 125.859032 -52.0954)
		(end 129.802382 -48.15205)
		(width 0.14224)
		(layer "In4.Cu")
		(net "M_H_DQ<63>")
	)
	(segment
		(start 149.476968 -28.422346)
		(end 149.934168 -27.965146)
		(width 0.14224)
		(layer "In4.Cu")
		(net "M_H_DQ<63>")
	)
	(segment
		(start 121.915174 -58.971688)
		(end 121.954798 -58.971688)
		(width 0.0889)
		(layer "In4.Cu")
		(net "M_H_DQ<63>")
	)
	(segment
		(start 149.934168 -23.289768)
		(end 150.105364 -23.118572)
		(width 0.14224)
		(layer "In4.Cu")
		(net "M_H_DQ<63>")
	)
	(segment
		(start 122.440192 -55.713122)
		(end 122.445018 -55.704486)
		(width 0.0889)
		(layer "In4.Cu")
		(net "M_H_DQ<63>")
	)
	(segment
		(start 121.056654 -59.466988)
		(end 121.092468 -59.466988)
		(width 0.0889)
		(layer "In4.Cu")
		(net "M_H_DQ<63>")
	)
	(segment
		(start 150.057612 -8.8646)
		(end 150.057612 -8.509)
		(width 0.14224)
		(layer "In4.Cu")
		(net "M_H_DQ<63>")
	)
	(segment
		(start 125.451362 -52.0954)
		(end 125.859032 -52.0954)
		(width 0.0889)
		(layer "In4.Cu")
		(net "M_H_DQ<63>")
	)
	(segment
		(start 120.642126 -59.811666)
		(end 120.727978 -59.666886)
		(width 0.0889)
		(layer "In4.Cu")
		(net "M_H_DQ<63>")
	)
	(segment
		(start 150.057612 -8.509)
		(end 149.600412 -8.0518)
		(width 0.14224)
		(layer "In4.Cu")
		(net "M_H_DQ<63>")
	)
	(segment
		(start 149.705568 -29.819346)
		(end 149.705568 -29.082746)
		(width 0.14224)
		(layer "In4.Cu")
		(net "M_H_DQ<63>")
	)
	(segment
		(start 149.549358 -12.678156)
		(end 149.902164 -12.32535)
		(width 0.14224)
		(layer "In4.Cu")
		(net "M_H_DQ<63>")
	)
	(segment
		(start 149.016212 -7.7216)
		(end 149.016212 -7.403084)
		(width 0.14224)
		(layer "In4.Cu")
		(net "M_H_DQ<63>")
	)
	(segment
		(start 149.902164 -18.574258)
		(end 150.010368 -18.466054)
		(width 0.14224)
		(layer "In4.Cu")
		(net "M_H_DQ<63>")
	)
	(segment
		(start 150.105364 -23.118572)
		(end 150.105364 -21.975572)
		(width 0.14224)
		(layer "In4.Cu")
		(net "M_H_DQ<63>")
	)
	(segment
		(start 150.010368 -18.466054)
		(end 150.010368 -16.961866)
		(width 0.14224)
		(layer "In4.Cu")
		(net "M_H_DQ<63>")
	)
	(segment
		(start 122.440192 -54.722522)
		(end 122.445018 -54.713886)
		(width 0.0889)
		(layer "In4.Cu")
		(net "M_H_DQ<63>")
	)
	(arc
		(start 122.451368 -56.684418)
		(mid 122.524166 -56.393655)
		(end 122.445018 -56.104536)
		(width 0.0889)
		(layer "In4.Cu")
		(net "M_H_DQ<63>")
	)
	(arc
		(start 122.813318 -53.523134)
		(mid 123.096535 -53.438853)
		(end 123.303538 -53.227986)
		(width 0.0889)
		(layer "In4.Cu")
		(net "M_H_DQ<63>")
	)
	(arc
		(start 122.445018 -54.123336)
		(mid 122.44227 -53.727869)
		(end 122.780552 -53.523134)
		(width 0.0889)
		(layer "In4.Cu")
		(net "M_H_DQ<63>")
	)
	(arc
		(start 122.451368 -54.703218)
		(mid 122.524166 -54.412455)
		(end 122.445018 -54.123336)
		(width 0.0889)
		(layer "In4.Cu")
		(net "M_H_DQ<63>")
	)
	(arc
		(start 122.445018 -55.113936)
		(mid 122.391548 -54.918873)
		(end 122.440192 -54.722522)
		(width 0.0889)
		(layer "In4.Cu")
		(net "M_H_DQ<63>")
	)
	(arc
		(start 122.445018 -57.095136)
		(mid 122.391548 -56.900073)
		(end 122.440192 -56.703722)
		(width 0.0889)
		(layer "In4.Cu")
		(net "M_H_DQ<63>")
	)
	(arc
		(start 123.303538 -53.227986)
		(mid 123.445221 -53.084182)
		(end 123.639072 -53.027834)
		(width 0.0889)
		(layer "In4.Cu")
		(net "M_H_DQ<63>")
	)
	(arc
		(start 122.451368 -55.693818)
		(mid 122.524166 -55.403055)
		(end 122.445018 -55.113936)
		(width 0.0889)
		(layer "In4.Cu")
		(net "M_H_DQ<63>")
	)
	(arc
		(start 122.445018 -56.104536)
		(mid 122.391548 -55.909473)
		(end 122.440192 -55.713122)
		(width 0.0889)
		(layer "In4.Cu")
		(net "M_H_DQ<63>")
	)
	(arc
		(start 122.451368 -57.675018)
		(mid 122.524166 -57.384255)
		(end 122.445018 -57.095136)
		(width 0.0889)
		(layer "In4.Cu")
		(net "M_H_DQ<63>")
	)
	(arc
		(start 121.954798 -58.971688)
		(mid 122.450275 -58.667245)
		(end 122.445018 -58.085736)
		(width 0.0889)
		(layer "In4.Cu")
		(net "M_H_DQ<63>")
	)
	(arc
		(start 120.727978 -59.666886)
		(mid 120.866722 -59.524853)
		(end 121.056654 -59.466988)
		(width 0.0889)
		(layer "In4.Cu")
		(net "M_H_DQ<63>")
	)
	(arc
		(start 122.445018 -58.085736)
		(mid 122.391548 -57.890673)
		(end 122.440192 -57.694322)
		(width 0.0889)
		(layer "In4.Cu")
		(net "M_H_DQ<63>")
	)
	(arc
		(start 121.092468 -59.466988)
		(mid 121.377892 -59.383521)
		(end 121.586498 -59.171586)
		(width 0.0889)
		(layer "In4.Cu")
		(net "M_H_DQ<63>")
	)
	(arc
		(start 121.586498 -59.171586)
		(mid 121.725242 -59.029553)
		(end 121.915174 -58.971688)
		(width 0.0889)
		(layer "In4.Cu")
		(net "M_H_DQ<63>")
	)
	(segment
		(start 149.549612 -10.422128)
		(end 149.549612 -9.4488)
		(width 0.1651)
		(layer "F.Cu")
		(net "M_H_DQ<62>")
	)
	(segment
		(start 149.549612 -8.9662)
		(end 149.549612 -8.661654)
		(width 0.1651)
		(layer "F.Cu")
		(net "M_H_DQ<62>")
	)
	(segment
		(start 149.549358 -10.422382)
		(end 149.549612 -10.422128)
		(width 0.1651)
		(layer "F.Cu")
		(net "M_H_DQ<62>")
	)
	(segment
		(start 149.549612 -9.4488)
		(end 149.681692 -9.31672)
		(width 0.1651)
		(layer "F.Cu")
		(net "M_H_DQ<62>")
	)
	(segment
		(start 120.216168 -59.371484)
		(end 120.787668 -59.371484)
		(width 0.1016)
		(layer "F.Cu")
		(net "M_H_DQ<62>")
	)
	(segment
		(start 149.681692 -9.31672)
		(end 149.681692 -9.09828)
		(width 0.1651)
		(layer "F.Cu")
		(net "M_H_DQ<62>")
	)
	(segment
		(start 149.681692 -9.09828)
		(end 149.549612 -8.9662)
		(width 0.1651)
		(layer "F.Cu")
		(net "M_H_DQ<62>")
	)
	(segment
		(start 149.549612 -8.661654)
		(end 149.549358 -8.6614)
		(width 0.1651)
		(layer "F.Cu")
		(net "M_H_DQ<62>")
	)
	(via
		(at 148.699474 -13.959078)
		(size 0.508)
		(drill 0.254)
		(layers "F.Cu" "B.Cu")
		(net "M_H_DQ<62>")
	)
	(via
		(at 120.216168 -59.371484)
		(size 0.508)
		(drill 0.254)
		(layers "F.Cu" "B.Cu")
		(net "M_H_DQ<62>")
	)
	(via
		(at 149.549358 -8.6614)
		(size 0.508)
		(drill 0.254)
		(layers "F.Cu" "B.Cu")
		(net "M_H_DQ<62>")
	)
	(segment
		(start 148.699474 -15.222982)
		(end 148.699474 -13.959078)
		(width 0.1651)
		(layer "B.Cu")
		(net "M_H_DQ<62>")
	)
	(segment
		(start 148.841968 -28.238704)
		(end 148.841968 -24.250396)
		(width 0.14224)
		(layer "In4.Cu")
		(net "M_H_DQ<62>")
	)
	(segment
		(start 148.699474 -13.959078)
		(end 148.463762 -13.723366)
		(width 0.14224)
		(layer "In4.Cu")
		(net "M_H_DQ<62>")
	)
	(segment
		(start 122.279918 -55.609236)
		(end 122.284744 -55.6006)
		(width 0.0889)
		(layer "In4.Cu")
		(net "M_H_DQ<62>")
	)
	(segment
		(start 148.699474 -14.524482)
		(end 148.699474 -13.959078)
		(width 0.14224)
		(layer "In4.Cu")
		(net "M_H_DQ<62>")
	)
	(segment
		(start 120.216168 -59.371484)
		(end 120.756934 -59.274202)
		(width 0.0889)
		(layer "In4.Cu")
		(net "M_H_DQ<62>")
	)
	(segment
		(start 149.174962 -9.035796)
		(end 149.549358 -8.6614)
		(width 0.14224)
		(layer "In4.Cu")
		(net "M_H_DQ<62>")
	)
	(segment
		(start 122.279918 -54.618636)
		(end 122.284744 -54.61)
		(width 0.0889)
		(layer "In4.Cu")
		(net "M_H_DQ<62>")
	)
	(segment
		(start 125.863858 -51.41341)
		(end 129.604008 -47.67326)
		(width 0.14224)
		(layer "In4.Cu")
		(net "M_H_DQ<62>")
	)
	(segment
		(start 129.604008 -47.67326)
		(end 131.322064 -47.67326)
		(width 0.14224)
		(layer "In4.Cu")
		(net "M_H_DQ<62>")
	)
	(segment
		(start 149.063964 -18.43405)
		(end 149.063964 -16.993362)
		(width 0.14224)
		(layer "In4.Cu")
		(net "M_H_DQ<62>")
	)
	(segment
		(start 149.174962 -9.313672)
		(end 149.174962 -9.035796)
		(width 0.14224)
		(layer "In4.Cu")
		(net "M_H_DQ<62>")
	)
	(segment
		(start 148.463762 -12.928854)
		(end 149.23643 -12.156186)
		(width 0.14224)
		(layer "In4.Cu")
		(net "M_H_DQ<62>")
	)
	(segment
		(start 123.628658 -52.837334)
		(end 124.439934 -52.837334)
		(width 0.0889)
		(layer "In4.Cu")
		(net "M_H_DQ<62>")
	)
	(segment
		(start 122.273568 -55.619904)
		(end 122.279918 -55.609236)
		(width 0.0889)
		(layer "In4.Cu")
		(net "M_H_DQ<62>")
	)
	(segment
		(start 131.519168 -47.476918)
		(end 145.489168 -33.553654)
		(width 0.14224)
		(layer "In4.Cu")
		(net "M_H_DQ<62>")
	)
	(segment
		(start 149.172168 -16.885158)
		(end 149.172168 -14.997176)
		(width 0.14224)
		(layer "In4.Cu")
		(net "M_H_DQ<62>")
	)
	(segment
		(start 149.156674 -23.93569)
		(end 149.156674 -23.262082)
		(width 0.14224)
		(layer "In4.Cu")
		(net "M_H_DQ<62>")
	)
	(segment
		(start 124.439934 -52.837334)
		(end 125.863858 -51.41341)
		(width 0.0889)
		(layer "In4.Cu")
		(net "M_H_DQ<62>")
	)
	(segment
		(start 146.548348 -30.532324)
		(end 146.835622 -30.24505)
		(width 0.14224)
		(layer "In4.Cu")
		(net "M_H_DQ<62>")
	)
	(segment
		(start 149.23643 -11.804396)
		(end 148.81098 -11.378946)
		(width 0.14224)
		(layer "In4.Cu")
		(net "M_H_DQ<62>")
	)
	(segment
		(start 149.063964 -21.975572)
		(end 149.267164 -21.772372)
		(width 0.14224)
		(layer "In4.Cu")
		(net "M_H_DQ<62>")
	)
	(segment
		(start 148.81098 -9.988296)
		(end 148.81098 -9.677654)
		(width 0.14224)
		(layer "In4.Cu")
		(net "M_H_DQ<62>")
	)
	(segment
		(start 121.915428 -58.780934)
		(end 121.951242 -58.780934)
		(width 0.0889)
		(layer "In4.Cu")
		(net "M_H_DQ<62>")
	)
	(segment
		(start 145.489168 -33.553654)
		(end 145.489168 -31.591504)
		(width 0.14224)
		(layer "In4.Cu")
		(net "M_H_DQ<62>")
	)
	(segment
		(start 122.273568 -57.601104)
		(end 122.279918 -57.590436)
		(width 0.0889)
		(layer "In4.Cu")
		(net "M_H_DQ<62>")
	)
	(segment
		(start 131.322064 -47.67326)
		(end 131.519168 -47.476918)
		(width 0.14224)
		(layer "In4.Cu")
		(net "M_H_DQ<62>")
	)
	(segment
		(start 149.063964 -23.169372)
		(end 149.063964 -21.975572)
		(width 0.14224)
		(layer "In4.Cu")
		(net "M_H_DQ<62>")
	)
	(segment
		(start 148.81098 -11.093704)
		(end 149.19198 -10.712704)
		(width 0.14224)
		(layer "In4.Cu")
		(net "M_H_DQ<62>")
	)
	(segment
		(start 122.279918 -57.590436)
		(end 122.284744 -57.5818)
		(width 0.0889)
		(layer "In4.Cu")
		(net "M_H_DQ<62>")
	)
	(segment
		(start 148.199602 -30.171898)
		(end 147.697952 -29.670248)
		(width 0.14224)
		(layer "In4.Cu")
		(net "M_H_DQ<62>")
	)
	(segment
		(start 120.756934 -59.274202)
		(end 121.053098 -59.276234)
		(width 0.0889)
		(layer "In4.Cu")
		(net "M_H_DQ<62>")
	)
	(segment
		(start 147.697952 -29.670248)
		(end 147.697952 -29.38272)
		(width 0.14224)
		(layer "In4.Cu")
		(net "M_H_DQ<62>")
	)
	(segment
		(start 149.267164 -21.772372)
		(end 149.267164 -18.63725)
		(width 0.14224)
		(layer "In4.Cu")
		(net "M_H_DQ<62>")
	)
	(segment
		(start 122.273568 -54.629304)
		(end 122.279918 -54.618636)
		(width 0.0889)
		(layer "In4.Cu")
		(net "M_H_DQ<62>")
	)
	(segment
		(start 149.172168 -14.997176)
		(end 148.699474 -14.524482)
		(width 0.14224)
		(layer "In4.Cu")
		(net "M_H_DQ<62>")
	)
	(segment
		(start 148.199602 -30.373066)
		(end 148.199602 -30.171898)
		(width 0.14224)
		(layer "In4.Cu")
		(net "M_H_DQ<62>")
	)
	(segment
		(start 147.697952 -29.38272)
		(end 148.841968 -28.238704)
		(width 0.14224)
		(layer "In4.Cu")
		(net "M_H_DQ<62>")
	)
	(segment
		(start 122.279918 -56.599836)
		(end 122.284744 -56.5912)
		(width 0.0889)
		(layer "In4.Cu")
		(net "M_H_DQ<62>")
	)
	(segment
		(start 148.463762 -13.723366)
		(end 148.463762 -12.928854)
		(width 0.14224)
		(layer "In4.Cu")
		(net "M_H_DQ<62>")
	)
	(segment
		(start 149.063964 -16.993362)
		(end 149.172168 -16.885158)
		(width 0.14224)
		(layer "In4.Cu")
		(net "M_H_DQ<62>")
	)
	(segment
		(start 145.686018 -31.394654)
		(end 145.973546 -31.394654)
		(width 0.14224)
		(layer "In4.Cu")
		(net "M_H_DQ<62>")
	)
	(segment
		(start 147.825968 -30.7467)
		(end 148.199602 -30.373066)
		(width 0.14224)
		(layer "In4.Cu")
		(net "M_H_DQ<62>")
	)
	(segment
		(start 146.562064 -31.782004)
		(end 146.935698 -31.40837)
		(width 0.14224)
		(layer "In4.Cu")
		(net "M_H_DQ<62>")
	)
	(segment
		(start 147.6248 -30.7467)
		(end 147.825968 -30.7467)
		(width 0.14224)
		(layer "In4.Cu")
		(net "M_H_DQ<62>")
	)
	(segment
		(start 146.835622 -30.24505)
		(end 147.12315 -30.24505)
		(width 0.14224)
		(layer "In4.Cu")
		(net "M_H_DQ<62>")
	)
	(segment
		(start 149.23643 -12.156186)
		(end 149.23643 -11.804396)
		(width 0.14224)
		(layer "In4.Cu")
		(net "M_H_DQ<62>")
	)
	(segment
		(start 122.273568 -56.610504)
		(end 122.279918 -56.599836)
		(width 0.0889)
		(layer "In4.Cu")
		(net "M_H_DQ<62>")
	)
	(segment
		(start 149.19198 -10.712704)
		(end 149.19198 -10.369296)
		(width 0.14224)
		(layer "In4.Cu")
		(net "M_H_DQ<62>")
	)
	(segment
		(start 122.770138 -53.332634)
		(end 122.802904 -53.332634)
		(width 0.0889)
		(layer "In4.Cu")
		(net "M_H_DQ<62>")
	)
	(segment
		(start 149.267164 -18.63725)
		(end 149.063964 -18.43405)
		(width 0.14224)
		(layer "In4.Cu")
		(net "M_H_DQ<62>")
	)
	(segment
		(start 121.053098 -59.276234)
		(end 121.092722 -59.276234)
		(width 0.0889)
		(layer "In4.Cu")
		(net "M_H_DQ<62>")
	)
	(segment
		(start 149.156674 -23.262082)
		(end 149.063964 -23.169372)
		(width 0.14224)
		(layer "In4.Cu")
		(net "M_H_DQ<62>")
	)
	(segment
		(start 147.12315 -30.24505)
		(end 147.6248 -30.7467)
		(width 0.14224)
		(layer "In4.Cu")
		(net "M_H_DQ<62>")
	)
	(segment
		(start 146.360896 -31.782004)
		(end 146.562064 -31.782004)
		(width 0.14224)
		(layer "In4.Cu")
		(net "M_H_DQ<62>")
	)
	(segment
		(start 145.973546 -31.394654)
		(end 146.360896 -31.782004)
		(width 0.14224)
		(layer "In4.Cu")
		(net "M_H_DQ<62>")
	)
	(segment
		(start 149.19198 -10.369296)
		(end 148.81098 -9.988296)
		(width 0.14224)
		(layer "In4.Cu")
		(net "M_H_DQ<62>")
	)
	(segment
		(start 148.81098 -9.677654)
		(end 149.174962 -9.313672)
		(width 0.14224)
		(layer "In4.Cu")
		(net "M_H_DQ<62>")
	)
	(segment
		(start 146.935698 -31.207202)
		(end 146.548348 -30.819852)
		(width 0.14224)
		(layer "In4.Cu")
		(net "M_H_DQ<62>")
	)
	(segment
		(start 146.548348 -30.819852)
		(end 146.548348 -30.532324)
		(width 0.14224)
		(layer "In4.Cu")
		(net "M_H_DQ<62>")
	)
	(segment
		(start 146.935698 -31.40837)
		(end 146.935698 -31.207202)
		(width 0.14224)
		(layer "In4.Cu")
		(net "M_H_DQ<62>")
	)
	(segment
		(start 148.841968 -24.250396)
		(end 149.156674 -23.93569)
		(width 0.14224)
		(layer "In4.Cu")
		(net "M_H_DQ<62>")
	)
	(segment
		(start 148.81098 -11.378946)
		(end 148.81098 -11.093704)
		(width 0.14224)
		(layer "In4.Cu")
		(net "M_H_DQ<62>")
	)
	(segment
		(start 145.489168 -31.591504)
		(end 145.686018 -31.394654)
		(width 0.14224)
		(layer "In4.Cu")
		(net "M_H_DQ<62>")
	)
	(arc
		(start 122.279918 -54.218586)
		(mid 122.274664 -53.637078)
		(end 122.770138 -53.332634)
		(width 0.0889)
		(layer "In4.Cu")
		(net "M_H_DQ<62>")
	)
	(arc
		(start 123.138438 -53.132482)
		(mid 123.345442 -52.921618)
		(end 123.628658 -52.837334)
		(width 0.0889)
		(layer "In4.Cu")
		(net "M_H_DQ<62>")
	)
	(arc
		(start 122.284744 -57.5818)
		(mid 122.333499 -57.385448)
		(end 122.279918 -57.190386)
		(width 0.0889)
		(layer "In4.Cu")
		(net "M_H_DQ<62>")
	)
	(arc
		(start 122.284744 -54.61)
		(mid 122.333499 -54.413648)
		(end 122.279918 -54.218586)
		(width 0.0889)
		(layer "In4.Cu")
		(net "M_H_DQ<62>")
	)
	(arc
		(start 121.951242 -58.780934)
		(mid 122.284211 -58.573386)
		(end 122.279918 -58.180986)
		(width 0.0889)
		(layer "In4.Cu")
		(net "M_H_DQ<62>")
	)
	(arc
		(start 122.279918 -56.199786)
		(mid 122.200696 -55.910668)
		(end 122.273568 -55.619904)
		(width 0.0889)
		(layer "In4.Cu")
		(net "M_H_DQ<62>")
	)
	(arc
		(start 122.279918 -58.180986)
		(mid 122.200696 -57.891868)
		(end 122.273568 -57.601104)
		(width 0.0889)
		(layer "In4.Cu")
		(net "M_H_DQ<62>")
	)
	(arc
		(start 121.092722 -59.276234)
		(mid 121.282651 -59.218364)
		(end 121.421398 -59.076336)
		(width 0.0889)
		(layer "In4.Cu")
		(net "M_H_DQ<62>")
	)
	(arc
		(start 122.284744 -55.6006)
		(mid 122.333499 -55.404248)
		(end 122.279918 -55.209186)
		(width 0.0889)
		(layer "In4.Cu")
		(net "M_H_DQ<62>")
	)
	(arc
		(start 122.279918 -55.209186)
		(mid 122.200696 -54.920068)
		(end 122.273568 -54.629304)
		(width 0.0889)
		(layer "In4.Cu")
		(net "M_H_DQ<62>")
	)
	(arc
		(start 122.802904 -53.332634)
		(mid 122.996754 -53.276284)
		(end 123.138438 -53.132482)
		(width 0.0889)
		(layer "In4.Cu")
		(net "M_H_DQ<62>")
	)
	(arc
		(start 122.284744 -56.5912)
		(mid 122.333499 -56.394848)
		(end 122.279918 -56.199786)
		(width 0.0889)
		(layer "In4.Cu")
		(net "M_H_DQ<62>")
	)
	(arc
		(start 122.279918 -57.190386)
		(mid 122.200696 -56.901268)
		(end 122.273568 -56.610504)
		(width 0.0889)
		(layer "In4.Cu")
		(net "M_H_DQ<62>")
	)
	(arc
		(start 121.421398 -59.076336)
		(mid 121.630006 -58.864404)
		(end 121.915428 -58.780934)
		(width 0.0889)
		(layer "In4.Cu")
		(net "M_H_DQ<62>")
	)
	(segment
		(start 142.749524 -5.822442)
		(end 142.749524 -7.086346)
		(width 0.1651)
		(layer "F.Cu")
		(net "M_H_DQ<61>")
	)
	(segment
		(start 118.212362 -60.857384)
		(end 117.640862 -60.857384)
		(width 0.1016)
		(layer "F.Cu")
		(net "M_H_DQ<61>")
	)
	(via
		(at 117.640862 -60.857384)
		(size 0.508)
		(drill 0.254)
		(layers "F.Cu" "B.Cu")
		(net "M_H_DQ<61>")
	)
	(via
		(at 143.523208 -12.678156)
		(size 0.508)
		(drill 0.254)
		(layers "F.Cu" "B.Cu")
		(net "M_H_DQ<61>")
	)
	(via
		(at 142.749524 -7.086346)
		(size 0.508)
		(drill 0.254)
		(layers "F.Cu" "B.Cu")
		(net "M_H_DQ<61>")
	)
	(segment
		(start 143.599408 -12.601956)
		(end 143.523208 -12.678156)
		(width 0.1651)
		(layer "B.Cu")
		(net "M_H_DQ<61>")
	)
	(segment
		(start 143.599408 -10.623042)
		(end 143.599408 -12.601956)
		(width 0.1651)
		(layer "B.Cu")
		(net "M_H_DQ<61>")
	)
	(segment
		(start 117.640862 -60.857384)
		(end 117.970808 -60.095638)
		(width 0.0889)
		(layer "In4.Cu")
		(net "M_H_DQ<61>")
	)
	(segment
		(start 143.787368 -14.311376)
		(end 143.018764 -13.542772)
		(width 0.14224)
		(layer "In4.Cu")
		(net "M_H_DQ<61>")
	)
	(segment
		(start 119.011192 -54.713886)
		(end 119.020082 -54.698646)
		(width 0.0889)
		(layer "In4.Cu")
		(net "M_H_DQ<61>")
	)
	(segment
		(start 143.996664 -16.929862)
		(end 143.787368 -16.720566)
		(width 0.14224)
		(layer "In4.Cu")
		(net "M_H_DQ<61>")
	)
	(segment
		(start 143.260064 -12.895072)
		(end 143.306292 -12.895072)
		(width 0.14224)
		(layer "In4.Cu")
		(net "M_H_DQ<61>")
	)
	(segment
		(start 121.70156 -49.88052)
		(end 122.14479 -49.43729)
		(width 0.0889)
		(layer "In4.Cu")
		(net "M_H_DQ<61>")
	)
	(segment
		(start 119.540782 -51.541934)
		(end 120.231408 -50.851308)
		(width 0.0889)
		(layer "In4.Cu")
		(net "M_H_DQ<61>")
	)
	(segment
		(start 118.484396 -56.990488)
		(end 118.517162 -56.990488)
		(width 0.0889)
		(layer "In4.Cu")
		(net "M_H_DQ<61>")
	)
	(segment
		(start 120.991122 -49.88052)
		(end 121.70156 -49.88052)
		(width 0.0889)
		(layer "In4.Cu")
		(net "M_H_DQ<61>")
	)
	(segment
		(start 119.357648 -51.541934)
		(end 119.540782 -51.541934)
		(width 0.0889)
		(layer "In4.Cu")
		(net "M_H_DQ<61>")
	)
	(segment
		(start 117.629686 -57.485534)
		(end 117.662452 -57.485534)
		(width 0.0889)
		(layer "In4.Cu")
		(net "M_H_DQ<61>")
	)
	(segment
		(start 137.31494 -36.18992)
		(end 137.602214 -35.902646)
		(width 0.14224)
		(layer "In4.Cu")
		(net "M_H_DQ<61>")
	)
	(segment
		(start 118.055136 -59.81446)
		(end 118.055136 -59.728608)
		(width 0.0889)
		(layer "In4.Cu")
		(net "M_H_DQ<61>")
	)
	(segment
		(start 144.031462 -8.8646)
		(end 144.031462 -8.452104)
		(width 0.14224)
		(layer "In4.Cu")
		(net "M_H_DQ<61>")
	)
	(segment
		(start 143.787368 -16.720566)
		(end 143.787368 -14.311376)
		(width 0.14224)
		(layer "In4.Cu")
		(net "M_H_DQ<61>")
	)
	(segment
		(start 117.310916 -58.114692)
		(end 117.294152 -58.085736)
		(width 0.0889)
		(layer "In4.Cu")
		(net "M_H_DQ<61>")
	)
	(segment
		(start 143.523208 -12.678156)
		(end 143.834612 -12.366752)
		(width 0.14224)
		(layer "In4.Cu")
		(net "M_H_DQ<61>")
	)
	(segment
		(start 126.84125 -44.74083)
		(end 128.836674 -44.74083)
		(width 0.14224)
		(layer "In4.Cu")
		(net "M_H_DQ<61>")
	)
	(segment
		(start 144.161764 -21.938996)
		(end 143.907764 -21.684996)
		(width 0.14224)
		(layer "In4.Cu")
		(net "M_H_DQ<61>")
	)
	(segment
		(start 119.011192 -55.704486)
		(end 119.017542 -55.693818)
		(width 0.0889)
		(layer "In4.Cu")
		(net "M_H_DQ<61>")
	)
	(segment
		(start 120.231408 -50.640234)
		(end 120.991122 -49.88052)
		(width 0.0889)
		(layer "In4.Cu")
		(net "M_H_DQ<61>")
	)
	(segment
		(start 122.14479 -49.43729)
		(end 126.84125 -44.74083)
		(width 0.14224)
		(layer "In4.Cu")
		(net "M_H_DQ<61>")
	)
	(segment
		(start 119.011192 -53.723286)
		(end 119.020082 -53.708046)
		(width 0.0889)
		(layer "In4.Cu")
		(net "M_H_DQ<61>")
	)
	(segment
		(start 136.918446 -34.643822)
		(end 143.863568 -27.6987)
		(width 0.14224)
		(layer "In4.Cu")
		(net "M_H_DQ<61>")
	)
	(segment
		(start 137.602214 -35.615118)
		(end 136.918446 -34.93135)
		(width 0.14224)
		(layer "In4.Cu")
		(net "M_H_DQ<61>")
	)
	(segment
		(start 119.006366 -55.713122)
		(end 119.011192 -55.704486)
		(width 0.0889)
		(layer "In4.Cu")
		(net "M_H_DQ<61>")
	)
	(segment
		(start 144.031462 -8.452104)
		(end 143.631158 -8.0518)
		(width 0.14224)
		(layer "In4.Cu")
		(net "M_H_DQ<61>")
	)
	(segment
		(start 136.543796 -35.907472)
		(end 136.744964 -35.907472)
		(width 0.14224)
		(layer "In4.Cu")
		(net "M_H_DQ<61>")
	)
	(segment
		(start 128.836674 -44.74083)
		(end 135.811768 -37.765736)
		(width 0.14224)
		(layer "In4.Cu")
		(net "M_H_DQ<61>")
	)
	(segment
		(start 120.231408 -50.851308)
		(end 120.231408 -50.640234)
		(width 0.0889)
		(layer "In4.Cu")
		(net "M_H_DQ<61>")
	)
	(segment
		(start 143.834612 -12.366752)
		(end 143.834612 -9.06145)
		(width 0.14224)
		(layer "In4.Cu")
		(net "M_H_DQ<61>")
	)
	(segment
		(start 136.744964 -35.907472)
		(end 137.027412 -36.18992)
		(width 0.14224)
		(layer "In4.Cu")
		(net "M_H_DQ<61>")
	)
	(segment
		(start 137.602214 -35.902646)
		(end 137.602214 -35.615118)
		(width 0.14224)
		(layer "In4.Cu")
		(net "M_H_DQ<61>")
	)
	(segment
		(start 143.834612 -9.06145)
		(end 144.031462 -8.8646)
		(width 0.14224)
		(layer "In4.Cu")
		(net "M_H_DQ<61>")
	)
	(segment
		(start 143.863568 -27.6987)
		(end 143.863568 -23.353268)
		(width 0.14224)
		(layer "In4.Cu")
		(net "M_H_DQ<61>")
	)
	(segment
		(start 144.161764 -23.055072)
		(end 144.161764 -21.938996)
		(width 0.14224)
		(layer "In4.Cu")
		(net "M_H_DQ<61>")
	)
	(segment
		(start 142.749524 -7.481062)
		(end 142.749524 -7.086346)
		(width 0.14224)
		(layer "In4.Cu")
		(net "M_H_DQ<61>")
	)
	(segment
		(start 135.811768 -36.6395)
		(end 136.543796 -35.907472)
		(width 0.14224)
		(layer "In4.Cu")
		(net "M_H_DQ<61>")
	)
	(segment
		(start 143.907764 -21.684996)
		(end 143.907764 -18.593562)
		(width 0.14224)
		(layer "In4.Cu")
		(net "M_H_DQ<61>")
	)
	(segment
		(start 143.996664 -18.504662)
		(end 143.996664 -16.929862)
		(width 0.14224)
		(layer "In4.Cu")
		(net "M_H_DQ<61>")
	)
	(segment
		(start 143.320262 -8.0518)
		(end 142.749524 -7.481062)
		(width 0.14224)
		(layer "In4.Cu")
		(net "M_H_DQ<61>")
	)
	(segment
		(start 143.018764 -13.136372)
		(end 143.260064 -12.895072)
		(width 0.14224)
		(layer "In4.Cu")
		(net "M_H_DQ<61>")
	)
	(segment
		(start 137.027412 -36.18992)
		(end 137.31494 -36.18992)
		(width 0.14224)
		(layer "In4.Cu")
		(net "M_H_DQ<61>")
	)
	(segment
		(start 143.631158 -8.0518)
		(end 143.320262 -8.0518)
		(width 0.14224)
		(layer "In4.Cu")
		(net "M_H_DQ<61>")
	)
	(segment
		(start 117.970808 -60.095638)
		(end 117.987572 -60.066936)
		(width 0.0889)
		(layer "In4.Cu")
		(net "M_H_DQ<61>")
	)
	(segment
		(start 135.811768 -37.765736)
		(end 135.811768 -36.6395)
		(width 0.14224)
		(layer "In4.Cu")
		(net "M_H_DQ<61>")
	)
	(segment
		(start 143.306292 -12.895072)
		(end 143.523208 -12.678156)
		(width 0.14224)
		(layer "In4.Cu")
		(net "M_H_DQ<61>")
	)
	(segment
		(start 119.006366 -54.722522)
		(end 119.011192 -54.713886)
		(width 0.0889)
		(layer "In4.Cu")
		(net "M_H_DQ<61>")
	)
	(segment
		(start 143.907764 -18.593562)
		(end 143.996664 -18.504662)
		(width 0.14224)
		(layer "In4.Cu")
		(net "M_H_DQ<61>")
	)
	(segment
		(start 143.863568 -23.353268)
		(end 144.161764 -23.055072)
		(width 0.14224)
		(layer "In4.Cu")
		(net "M_H_DQ<61>")
	)
	(segment
		(start 143.018764 -13.542772)
		(end 143.018764 -13.136372)
		(width 0.14224)
		(layer "In4.Cu")
		(net "M_H_DQ<61>")
	)
	(segment
		(start 136.918446 -34.93135)
		(end 136.918446 -34.643822)
		(width 0.14224)
		(layer "In4.Cu")
		(net "M_H_DQ<61>")
	)
	(arc
		(start 117.987572 -60.066936)
		(mid 118.037933 -59.945137)
		(end 118.055136 -59.81446)
		(width 0.0889)
		(layer "In4.Cu")
		(net "M_H_DQ<61>")
	)
	(arc
		(start 119.011192 -54.123082)
		(mid 118.957659 -53.923184)
		(end 119.011192 -53.723286)
		(width 0.0889)
		(layer "In4.Cu")
		(net "M_H_DQ<61>")
	)
	(arc
		(start 117.662452 -57.485534)
		(mid 117.945669 -57.401253)
		(end 118.152672 -57.190386)
		(width 0.0889)
		(layer "In4.Cu")
		(net "M_H_DQ<61>")
	)
	(arc
		(start 118.517162 -56.990488)
		(mid 119.015413 -56.687648)
		(end 119.011192 -56.104536)
		(width 0.0889)
		(layer "In4.Cu")
		(net "M_H_DQ<61>")
	)
	(arc
		(start 117.294152 -58.085736)
		(mid 117.291404 -57.690269)
		(end 117.629686 -57.485534)
		(width 0.0889)
		(layer "In4.Cu")
		(net "M_H_DQ<61>")
	)
	(arc
		(start 119.017542 -55.693818)
		(mid 119.09034 -55.403055)
		(end 119.011192 -55.113936)
		(width 0.0889)
		(layer "In4.Cu")
		(net "M_H_DQ<61>")
	)
	(arc
		(start 119.011192 -55.113936)
		(mid 118.957722 -54.918873)
		(end 119.006366 -54.722522)
		(width 0.0889)
		(layer "In4.Cu")
		(net "M_H_DQ<61>")
	)
	(arc
		(start 119.011192 -52.732686)
		(mid 119.090323 -52.437284)
		(end 119.011192 -52.141882)
		(width 0.0889)
		(layer "In4.Cu")
		(net "M_H_DQ<61>")
	)
	(arc
		(start 117.622828 -59.276234)
		(mid 117.289912 -59.068782)
		(end 117.294152 -58.67654)
		(width 0.0889)
		(layer "In4.Cu")
		(net "M_H_DQ<61>")
	)
	(arc
		(start 119.011192 -52.141882)
		(mid 119.011275 -51.741941)
		(end 119.357648 -51.541934)
		(width 0.0889)
		(layer "In4.Cu")
		(net "M_H_DQ<61>")
	)
	(arc
		(start 118.055136 -59.728608)
		(mid 117.929684 -59.415731)
		(end 117.622828 -59.276234)
		(width 0.0889)
		(layer "In4.Cu")
		(net "M_H_DQ<61>")
	)
	(arc
		(start 119.020082 -54.698646)
		(mid 119.090479 -54.409695)
		(end 119.011192 -54.123082)
		(width 0.0889)
		(layer "In4.Cu")
		(net "M_H_DQ<61>")
	)
	(arc
		(start 119.011192 -56.104536)
		(mid 118.957722 -55.909473)
		(end 119.006366 -55.713122)
		(width 0.0889)
		(layer "In4.Cu")
		(net "M_H_DQ<61>")
	)
	(arc
		(start 118.152672 -57.190386)
		(mid 118.292751 -57.04765)
		(end 118.484396 -56.990488)
		(width 0.0889)
		(layer "In4.Cu")
		(net "M_H_DQ<61>")
	)
	(arc
		(start 119.020082 -53.708046)
		(mid 119.090479 -53.419095)
		(end 119.011192 -53.132482)
		(width 0.0889)
		(layer "In4.Cu")
		(net "M_H_DQ<61>")
	)
	(arc
		(start 117.294152 -58.67654)
		(mid 117.37319 -58.397736)
		(end 117.310916 -58.114692)
		(width 0.0889)
		(layer "In4.Cu")
		(net "M_H_DQ<61>")
	)
	(arc
		(start 119.011192 -53.132482)
		(mid 118.957659 -52.932584)
		(end 119.011192 -52.732686)
		(width 0.0889)
		(layer "In4.Cu")
		(net "M_H_DQ<61>")
	)
	(segment
		(start 143.538956 -8.763)
		(end 143.501364 -8.5598)
		(width 0.1651)
		(layer "F.Cu")
		(net "M_H_DQ<60>")
	)
	(segment
		(start 143.599408 -10.422382)
		(end 143.599408 -9.091168)
		(width 0.1651)
		(layer "F.Cu")
		(net "M_H_DQ<60>")
	)
	(segment
		(start 143.562324 -8.89)
		(end 143.538956 -8.763)
		(width 0.1651)
		(layer "F.Cu")
		(net "M_H_DQ<60>")
	)
	(segment
		(start 118.212362 -59.866784)
		(end 117.640862 -59.866784)
		(width 0.1016)
		(layer "F.Cu")
		(net "M_H_DQ<60>")
	)
	(segment
		(start 143.599408 -9.091168)
		(end 143.562324 -8.89)
		(width 0.1651)
		(layer "F.Cu")
		(net "M_H_DQ<60>")
	)
	(via
		(at 142.749524 -13.959078)
		(size 0.508)
		(drill 0.254)
		(layers "F.Cu" "B.Cu")
		(net "M_H_DQ<60>")
	)
	(via
		(at 143.501364 -8.5598)
		(size 0.508)
		(drill 0.254)
		(layers "F.Cu" "B.Cu")
		(net "M_H_DQ<60>")
	)
	(via
		(at 117.640862 -59.866784)
		(size 0.508)
		(drill 0.254)
		(layers "F.Cu" "B.Cu")
		(net "M_H_DQ<60>")
	)
	(segment
		(start 142.749524 -15.222982)
		(end 142.749524 -13.959078)
		(width 0.1651)
		(layer "B.Cu")
		(net "M_H_DQ<60>")
	)
	(segment
		(start 143.24203 -10.3632)
		(end 142.86103 -9.9822)
		(width 0.14224)
		(layer "In4.Cu")
		(net "M_H_DQ<60>")
	)
	(segment
		(start 119.336058 -51.351434)
		(end 119.461788 -51.351434)
		(width 0.0889)
		(layer "In4.Cu")
		(net "M_H_DQ<60>")
	)
	(segment
		(start 128.41732 -44.26204)
		(end 135.176768 -37.502592)
		(width 0.14224)
		(layer "In4.Cu")
		(net "M_H_DQ<60>")
	)
	(segment
		(start 138.141964 -31.663132)
		(end 138.427714 -31.948882)
		(width 0.14224)
		(layer "In4.Cu")
		(net "M_H_DQ<60>")
	)
	(segment
		(start 137.852912 -32.523684)
		(end 137.567162 -32.237934)
		(width 0.14224)
		(layer "In4.Cu")
		(net "M_H_DQ<60>")
	)
	(segment
		(start 135.176768 -35.487356)
		(end 136.703308 -33.960816)
		(width 0.14224)
		(layer "In4.Cu")
		(net "M_H_DQ<60>")
	)
	(segment
		(start 139.00404 -30.513528)
		(end 139.291568 -30.513528)
		(width 0.14224)
		(layer "In4.Cu")
		(net "M_H_DQ<60>")
	)
	(segment
		(start 136.417558 -33.387538)
		(end 136.417558 -33.10001)
		(width 0.14224)
		(layer "In4.Cu")
		(net "M_H_DQ<60>")
	)
	(segment
		(start 120.040908 -50.56124)
		(end 121.116598 -49.48555)
		(width 0.0889)
		(layer "In4.Cu")
		(net "M_H_DQ<60>")
	)
	(segment
		(start 117.623082 -57.295034)
		(end 117.655848 -57.295034)
		(width 0.0889)
		(layer "In4.Cu")
		(net "M_H_DQ<60>")
	)
	(segment
		(start 118.846092 -55.609236)
		(end 118.850918 -55.6006)
		(width 0.0889)
		(layer "In4.Cu")
		(net "M_H_DQ<60>")
	)
	(segment
		(start 139.002516 -31.661608)
		(end 139.002516 -31.37408)
		(width 0.14224)
		(layer "In4.Cu")
		(net "M_H_DQ<60>")
	)
	(segment
		(start 143.272764 -21.659596)
		(end 143.272764 -18.568162)
		(width 0.14224)
		(layer "In4.Cu")
		(net "M_H_DQ<60>")
	)
	(segment
		(start 143.206724 -23.357332)
		(end 143.018764 -23.169372)
		(width 0.14224)
		(layer "In4.Cu")
		(net "M_H_DQ<60>")
	)
	(segment
		(start 136.703308 -33.673288)
		(end 136.417558 -33.387538)
		(width 0.14224)
		(layer "In4.Cu")
		(net "M_H_DQ<60>")
	)
	(segment
		(start 136.703308 -33.960816)
		(end 136.703308 -33.673288)
		(width 0.14224)
		(layer "In4.Cu")
		(net "M_H_DQ<60>")
	)
	(segment
		(start 143.018764 -17.050258)
		(end 143.247364 -16.821658)
		(width 0.14224)
		(layer "In4.Cu")
		(net "M_H_DQ<60>")
	)
	(segment
		(start 126.642876 -44.26204)
		(end 128.41732 -44.26204)
		(width 0.14224)
		(layer "In4.Cu")
		(net "M_H_DQ<60>")
	)
	(segment
		(start 141.01445 -29.649674)
		(end 143.206724 -27.4574)
		(width 0.14224)
		(layer "In4.Cu")
		(net "M_H_DQ<60>")
	)
	(segment
		(start 140.15212 -30.224476)
		(end 139.86637 -29.938726)
		(width 0.14224)
		(layer "In4.Cu")
		(net "M_H_DQ<60>")
	)
	(segment
		(start 137.27811 -33.098486)
		(end 137.565638 -33.098486)
		(width 0.14224)
		(layer "In4.Cu")
		(net "M_H_DQ<60>")
	)
	(segment
		(start 137.852912 -32.811212)
		(end 137.852912 -32.523684)
		(width 0.14224)
		(layer "In4.Cu")
		(net "M_H_DQ<60>")
	)
	(segment
		(start 137.565638 -33.098486)
		(end 137.852912 -32.811212)
		(width 0.14224)
		(layer "In4.Cu")
		(net "M_H_DQ<60>")
	)
	(segment
		(start 140.441172 -29.363924)
		(end 140.726922 -29.649674)
		(width 0.14224)
		(layer "In4.Cu")
		(net "M_H_DQ<60>")
	)
	(segment
		(start 138.716766 -31.08833)
		(end 138.716766 -30.800802)
		(width 0.14224)
		(layer "In4.Cu")
		(net "M_H_DQ<60>")
	)
	(segment
		(start 117.640862 -59.866784)
		(end 117.145816 -59.20105)
		(width 0.0889)
		(layer "In4.Cu")
		(net "M_H_DQ<60>")
	)
	(segment
		(start 143.225012 -11.742928)
		(end 142.87373 -11.391646)
		(width 0.14224)
		(layer "In4.Cu")
		(net "M_H_DQ<60>")
	)
	(segment
		(start 118.839488 -52.64785)
		(end 118.845838 -52.637182)
		(width 0.0889)
		(layer "In4.Cu")
		(net "M_H_DQ<60>")
	)
	(segment
		(start 138.427714 -31.948882)
		(end 138.715242 -31.948882)
		(width 0.14224)
		(layer "In4.Cu")
		(net "M_H_DQ<60>")
	)
	(segment
		(start 143.018764 -23.169372)
		(end 143.018764 -21.913596)
		(width 0.14224)
		(layer "In4.Cu")
		(net "M_H_DQ<60>")
	)
	(segment
		(start 118.839742 -54.629304)
		(end 118.846092 -54.618636)
		(width 0.0889)
		(layer "In4.Cu")
		(net "M_H_DQ<60>")
	)
	(segment
		(start 140.726922 -29.649674)
		(end 141.01445 -29.649674)
		(width 0.14224)
		(layer "In4.Cu")
		(net "M_H_DQ<60>")
	)
	(segment
		(start 139.864846 -30.799278)
		(end 140.15212 -30.512004)
		(width 0.14224)
		(layer "In4.Cu")
		(net "M_H_DQ<60>")
	)
	(segment
		(start 137.567162 -31.950406)
		(end 137.854436 -31.663132)
		(width 0.14224)
		(layer "In4.Cu")
		(net "M_H_DQ<60>")
	)
	(segment
		(start 142.749524 -13.959078)
		(end 142.513812 -13.723366)
		(width 0.14224)
		(layer "In4.Cu")
		(net "M_H_DQ<60>")
	)
	(segment
		(start 119.461788 -51.351434)
		(end 120.040908 -50.772314)
		(width 0.0889)
		(layer "In4.Cu")
		(net "M_H_DQ<60>")
	)
	(segment
		(start 117.129052 -59.171586)
		(end 117.122702 -59.160918)
		(width 0.0889)
		(layer "In4.Cu")
		(net "M_H_DQ<60>")
	)
	(segment
		(start 118.477792 -56.799988)
		(end 118.510558 -56.799988)
		(width 0.0889)
		(layer "In4.Cu")
		(net "M_H_DQ<60>")
	)
	(segment
		(start 121.116598 -49.48555)
		(end 121.419366 -49.48555)
		(width 0.0889)
		(layer "In4.Cu")
		(net "M_H_DQ<60>")
	)
	(segment
		(start 117.145816 -59.20105)
		(end 117.129052 -59.171586)
		(width 0.0889)
		(layer "In4.Cu")
		(net "M_H_DQ<60>")
	)
	(segment
		(start 143.272764 -18.568162)
		(end 143.018764 -18.314162)
		(width 0.14224)
		(layer "In4.Cu")
		(net "M_H_DQ<60>")
	)
	(segment
		(start 142.86103 -9.677654)
		(end 143.225012 -9.313672)
		(width 0.14224)
		(layer "In4.Cu")
		(net "M_H_DQ<60>")
	)
	(segment
		(start 143.247364 -14.456918)
		(end 142.749524 -13.959078)
		(width 0.14224)
		(layer "In4.Cu")
		(net "M_H_DQ<60>")
	)
	(segment
		(start 143.225012 -9.313672)
		(end 143.225012 -8.836152)
		(width 0.14224)
		(layer "In4.Cu")
		(net "M_H_DQ<60>")
	)
	(segment
		(start 143.018764 -21.913596)
		(end 143.272764 -21.659596)
		(width 0.14224)
		(layer "In4.Cu")
		(net "M_H_DQ<60>")
	)
	(segment
		(start 135.176768 -37.502592)
		(end 135.176768 -35.487356)
		(width 0.14224)
		(layer "In4.Cu")
		(net "M_H_DQ<60>")
	)
	(segment
		(start 142.86103 -9.9822)
		(end 142.86103 -9.677654)
		(width 0.14224)
		(layer "In4.Cu")
		(net "M_H_DQ<60>")
	)
	(segment
		(start 143.225012 -8.836152)
		(end 143.501364 -8.5598)
		(width 0.14224)
		(layer "In4.Cu")
		(net "M_H_DQ<60>")
	)
	(segment
		(start 142.513812 -12.928854)
		(end 143.225012 -12.217654)
		(width 0.14224)
		(layer "In4.Cu")
		(net "M_H_DQ<60>")
	)
	(segment
		(start 139.291568 -30.513528)
		(end 139.577318 -30.799278)
		(width 0.14224)
		(layer "In4.Cu")
		(net "M_H_DQ<60>")
	)
	(segment
		(start 143.24203 -10.668)
		(end 143.24203 -10.3632)
		(width 0.14224)
		(layer "In4.Cu")
		(net "M_H_DQ<60>")
	)
	(segment
		(start 121.806208 -49.098708)
		(end 126.642876 -44.26204)
		(width 0.14224)
		(layer "In4.Cu")
		(net "M_H_DQ<60>")
	)
	(segment
		(start 143.206724 -27.4574)
		(end 143.206724 -23.357332)
		(width 0.14224)
		(layer "In4.Cu")
		(net "M_H_DQ<60>")
	)
	(segment
		(start 142.87373 -11.391646)
		(end 142.87373 -11.0363)
		(width 0.14224)
		(layer "In4.Cu")
		(net "M_H_DQ<60>")
	)
	(segment
		(start 139.86637 -29.651198)
		(end 140.153644 -29.363924)
		(width 0.14224)
		(layer "In4.Cu")
		(net "M_H_DQ<60>")
	)
	(segment
		(start 143.225012 -12.217654)
		(end 143.225012 -11.742928)
		(width 0.14224)
		(layer "In4.Cu")
		(net "M_H_DQ<60>")
	)
	(segment
		(start 136.417558 -33.10001)
		(end 136.704832 -32.812736)
		(width 0.14224)
		(layer "In4.Cu")
		(net "M_H_DQ<60>")
	)
	(segment
		(start 140.153644 -29.363924)
		(end 140.441172 -29.363924)
		(width 0.14224)
		(layer "In4.Cu")
		(net "M_H_DQ<60>")
	)
	(segment
		(start 118.836948 -53.643276)
		(end 118.845838 -53.628036)
		(width 0.0889)
		(layer "In4.Cu")
		(net "M_H_DQ<60>")
	)
	(segment
		(start 118.839742 -55.619904)
		(end 118.846092 -55.609236)
		(width 0.0889)
		(layer "In4.Cu")
		(net "M_H_DQ<60>")
	)
	(segment
		(start 138.716766 -30.800802)
		(end 139.00404 -30.513528)
		(width 0.14224)
		(layer "In4.Cu")
		(net "M_H_DQ<60>")
	)
	(segment
		(start 143.247364 -16.821658)
		(end 143.247364 -14.456918)
		(width 0.14224)
		(layer "In4.Cu")
		(net "M_H_DQ<60>")
	)
	(segment
		(start 138.715242 -31.948882)
		(end 139.002516 -31.661608)
		(width 0.14224)
		(layer "In4.Cu")
		(net "M_H_DQ<60>")
	)
	(segment
		(start 121.419366 -49.48555)
		(end 121.806208 -49.098708)
		(width 0.0889)
		(layer "In4.Cu")
		(net "M_H_DQ<60>")
	)
	(segment
		(start 120.040908 -50.772314)
		(end 120.040908 -50.56124)
		(width 0.0889)
		(layer "In4.Cu")
		(net "M_H_DQ<60>")
	)
	(segment
		(start 139.002516 -31.37408)
		(end 138.716766 -31.08833)
		(width 0.14224)
		(layer "In4.Cu")
		(net "M_H_DQ<60>")
	)
	(segment
		(start 142.87373 -11.0363)
		(end 143.24203 -10.668)
		(width 0.14224)
		(layer "In4.Cu")
		(net "M_H_DQ<60>")
	)
	(segment
		(start 142.513812 -13.723366)
		(end 142.513812 -12.928854)
		(width 0.14224)
		(layer "In4.Cu")
		(net "M_H_DQ<60>")
	)
	(segment
		(start 143.018764 -18.314162)
		(end 143.018764 -17.050258)
		(width 0.14224)
		(layer "In4.Cu")
		(net "M_H_DQ<60>")
	)
	(segment
		(start 136.99236 -32.812736)
		(end 137.27811 -33.098486)
		(width 0.14224)
		(layer "In4.Cu")
		(net "M_H_DQ<60>")
	)
	(segment
		(start 139.86637 -29.938726)
		(end 139.86637 -29.651198)
		(width 0.14224)
		(layer "In4.Cu")
		(net "M_H_DQ<60>")
	)
	(segment
		(start 137.567162 -32.237934)
		(end 137.567162 -31.950406)
		(width 0.14224)
		(layer "In4.Cu")
		(net "M_H_DQ<60>")
	)
	(segment
		(start 137.854436 -31.663132)
		(end 138.141964 -31.663132)
		(width 0.14224)
		(layer "In4.Cu")
		(net "M_H_DQ<60>")
	)
	(segment
		(start 139.577318 -30.799278)
		(end 139.864846 -30.799278)
		(width 0.14224)
		(layer "In4.Cu")
		(net "M_H_DQ<60>")
	)
	(segment
		(start 136.704832 -32.812736)
		(end 136.99236 -32.812736)
		(width 0.14224)
		(layer "In4.Cu")
		(net "M_H_DQ<60>")
	)
	(segment
		(start 140.15212 -30.512004)
		(end 140.15212 -30.224476)
		(width 0.14224)
		(layer "In4.Cu")
		(net "M_H_DQ<60>")
	)
	(segment
		(start 118.852442 -54.23027)
		(end 118.845838 -54.21884)
		(width 0.0889)
		(layer "In4.Cu")
		(net "M_H_DQ<60>")
	)
	(arc
		(start 117.987572 -57.095136)
		(mid 118.194576 -56.884272)
		(end 118.477792 -56.799988)
		(width 0.0889)
		(layer "In4.Cu")
		(net "M_H_DQ<60>")
	)
	(arc
		(start 118.846092 -55.209186)
		(mid 118.76687 -54.920068)
		(end 118.839742 -54.629304)
		(width 0.0889)
		(layer "In4.Cu")
		(net "M_H_DQ<60>")
	)
	(arc
		(start 118.845838 -53.628036)
		(mid 118.899371 -53.428138)
		(end 118.845838 -53.22824)
		(width 0.0889)
		(layer "In4.Cu")
		(net "M_H_DQ<60>")
	)
	(arc
		(start 118.845838 -52.637182)
		(mid 118.899371 -52.437284)
		(end 118.845838 -52.237386)
		(width 0.0889)
		(layer "In4.Cu")
		(net "M_H_DQ<60>")
	)
	(arc
		(start 117.129052 -58.180986)
		(mid 117.124723 -57.597814)
		(end 117.623082 -57.295034)
		(width 0.0889)
		(layer "In4.Cu")
		(net "M_H_DQ<60>")
	)
	(arc
		(start 118.850918 -55.6006)
		(mid 118.899673 -55.404248)
		(end 118.846092 -55.209186)
		(width 0.0889)
		(layer "In4.Cu")
		(net "M_H_DQ<60>")
	)
	(arc
		(start 118.846092 -56.199786)
		(mid 118.76687 -55.910668)
		(end 118.839742 -55.619904)
		(width 0.0889)
		(layer "In4.Cu")
		(net "M_H_DQ<60>")
	)
	(arc
		(start 118.845838 -53.22824)
		(mid 118.766489 -52.938868)
		(end 118.839488 -52.64785)
		(width 0.0889)
		(layer "In4.Cu")
		(net "M_H_DQ<60>")
	)
	(arc
		(start 118.845838 -54.21884)
		(mid 118.766649 -53.932225)
		(end 118.836948 -53.643276)
		(width 0.0889)
		(layer "In4.Cu")
		(net "M_H_DQ<60>")
	)
	(arc
		(start 117.129052 -58.581036)
		(mid 117.182619 -58.381028)
		(end 117.129052 -58.180986)
		(width 0.0889)
		(layer "In4.Cu")
		(net "M_H_DQ<60>")
	)
	(arc
		(start 118.845838 -52.237386)
		(mid 118.840584 -51.655878)
		(end 119.336058 -51.351434)
		(width 0.0889)
		(layer "In4.Cu")
		(net "M_H_DQ<60>")
	)
	(arc
		(start 118.510558 -56.799988)
		(mid 118.848727 -56.59519)
		(end 118.846092 -56.199786)
		(width 0.0889)
		(layer "In4.Cu")
		(net "M_H_DQ<60>")
	)
	(arc
		(start 118.846092 -54.618636)
		(mid 118.899537 -54.425276)
		(end 118.852442 -54.23027)
		(width 0.0889)
		(layer "In4.Cu")
		(net "M_H_DQ<60>")
	)
	(arc
		(start 117.122702 -59.160918)
		(mid 117.049904 -58.870155)
		(end 117.129052 -58.581036)
		(width 0.0889)
		(layer "In4.Cu")
		(net "M_H_DQ<60>")
	)
	(arc
		(start 117.655848 -57.295034)
		(mid 117.84749 -57.237868)
		(end 117.987572 -57.095136)
		(width 0.0889)
		(layer "In4.Cu")
		(net "M_H_DQ<60>")
	)
	(segment
		(start 31.39948 -5.822442)
		(end 31.39948 -7.086346)
		(width 0.1651)
		(layer "F.Cu")
		(net "M_H_DQ<5>")
	)
	(segment
		(start 73.758806 -67.972686)
		(end 73.187306 -67.972686)
		(width 0.0889)
		(layer "F.Cu")
		(net "M_H_DQ<5>")
	)
	(via
		(at 31.39948 -7.086346)
		(size 0.508)
		(drill 0.254)
		(layers "F.Cu" "B.Cu")
		(net "M_H_DQ<5>")
	)
	(via
		(at 32.173164 -12.678156)
		(size 0.508)
		(drill 0.254)
		(layers "F.Cu" "B.Cu")
		(net "M_H_DQ<5>")
	)
	(via
		(at 73.187306 -67.972686)
		(size 0.508)
		(drill 0.254)
		(layers "F.Cu" "B.Cu")
		(net "M_H_DQ<5>")
	)
	(segment
		(start 32.249364 -12.071858)
		(end 32.173164 -12.148058)
		(width 0.1651)
		(layer "B.Cu")
		(net "M_H_DQ<5>")
	)
	(segment
		(start 32.249364 -10.623042)
		(end 32.249364 -12.071858)
		(width 0.1651)
		(layer "B.Cu")
		(net "M_H_DQ<5>")
	)
	(segment
		(start 32.173164 -12.148058)
		(end 32.173164 -12.678156)
		(width 0.1651)
		(layer "B.Cu")
		(net "M_H_DQ<5>")
	)
	(segment
		(start 72.365362 -68.068444)
		(end 73.187306 -67.972686)
		(width 0.0889)
		(layer "In4.Cu")
		(net "M_H_DQ<5>")
	)
	(segment
		(start 32.484568 -9.06145)
		(end 32.484568 -12.366752)
		(width 0.14224)
		(layer "In4.Cu")
		(net "M_H_DQ<5>")
	)
	(segment
		(start 31.970218 -8.0518)
		(end 32.281114 -8.0518)
		(width 0.14224)
		(layer "In4.Cu")
		(net "M_H_DQ<5>")
	)
	(segment
		(start 31.39948 -7.086346)
		(end 31.39948 -7.481062)
		(width 0.14224)
		(layer "In4.Cu")
		(net "M_H_DQ<5>")
	)
	(segment
		(start 53.693568 -58.2803)
		(end 53.972968 -58.2803)
		(width 0.14224)
		(layer "In4.Cu")
		(net "M_H_DQ<5>")
	)
	(segment
		(start 71.821802 -68.772024)
		(end 71.816976 -68.763388)
		(width 0.0889)
		(layer "In4.Cu")
		(net "M_H_DQ<5>")
	)
	(segment
		(start 31.66872 -13.1826)
		(end 31.66872 -13.542772)
		(width 0.14224)
		(layer "In4.Cu")
		(net "M_H_DQ<5>")
	)
	(segment
		(start 70.590156 -69.85889)
		(end 70.622922 -69.85889)
		(width 0.0889)
		(layer "In4.Cu")
		(net "M_H_DQ<5>")
	)
	(segment
		(start 72.31761 -68.068444)
		(end 72.365362 -68.068444)
		(width 0.0889)
		(layer "In4.Cu")
		(net "M_H_DQ<5>")
	)
	(segment
		(start 32.681418 -8.8646)
		(end 32.484568 -9.06145)
		(width 0.14224)
		(layer "In4.Cu")
		(net "M_H_DQ<5>")
	)
	(segment
		(start 32.681418 -8.452104)
		(end 32.681418 -8.8646)
		(width 0.14224)
		(layer "In4.Cu")
		(net "M_H_DQ<5>")
	)
	(segment
		(start 53.972968 -58.2803)
		(end 64.691768 -68.9991)
		(width 0.14224)
		(layer "In4.Cu")
		(net "M_H_DQ<5>")
	)
	(segment
		(start 31.66872 -13.542772)
		(end 32.484568 -14.35862)
		(width 0.14224)
		(layer "In4.Cu")
		(net "M_H_DQ<5>")
	)
	(segment
		(start 32.173164 -12.678156)
		(end 31.66872 -13.1826)
		(width 0.14224)
		(layer "In4.Cu")
		(net "M_H_DQ<5>")
	)
	(segment
		(start 68.697856 -69.85889)
		(end 68.916296 -69.85889)
		(width 0.0889)
		(layer "In4.Cu")
		(net "M_H_DQ<5>")
	)
	(segment
		(start 32.484568 -16.891)
		(end 32.611568 -17.018)
		(width 0.14224)
		(layer "In4.Cu")
		(net "M_H_DQ<5>")
	)
	(segment
		(start 32.484568 -12.366752)
		(end 32.173164 -12.678156)
		(width 0.14224)
		(layer "In4.Cu")
		(net "M_H_DQ<5>")
	)
	(segment
		(start 71.816976 -68.763388)
		(end 71.810626 -68.75272)
		(width 0.0889)
		(layer "In4.Cu")
		(net "M_H_DQ<5>")
	)
	(segment
		(start 32.611568 -17.018)
		(end 32.611568 -18.3642)
		(width 0.14224)
		(layer "In4.Cu")
		(net "M_H_DQ<5>")
	)
	(segment
		(start 64.691768 -68.9991)
		(end 67.414394 -68.9991)
		(width 0.14224)
		(layer "In4.Cu")
		(net "M_H_DQ<5>")
	)
	(segment
		(start 32.611568 -18.3642)
		(end 32.586168 -18.3896)
		(width 0.14224)
		(layer "In4.Cu")
		(net "M_H_DQ<5>")
	)
	(segment
		(start 32.281114 -8.0518)
		(end 32.681418 -8.452104)
		(width 0.14224)
		(layer "In4.Cu")
		(net "M_H_DQ<5>")
	)
	(segment
		(start 67.63766 -69.222366)
		(end 67.80403 -69.388736)
		(width 0.0889)
		(layer "In4.Cu")
		(net "M_H_DQ<5>")
	)
	(segment
		(start 67.414394 -68.9991)
		(end 67.63766 -69.222366)
		(width 0.14224)
		(layer "In4.Cu")
		(net "M_H_DQ<5>")
	)
	(segment
		(start 32.636968 -37.2237)
		(end 53.693568 -58.2803)
		(width 0.14224)
		(layer "In4.Cu")
		(net "M_H_DQ<5>")
	)
	(segment
		(start 31.39948 -7.481062)
		(end 31.970218 -8.0518)
		(width 0.14224)
		(layer "In4.Cu")
		(net "M_H_DQ<5>")
	)
	(segment
		(start 69.73824 -70.353936)
		(end 69.768212 -70.353936)
		(width 0.0889)
		(layer "In4.Cu")
		(net "M_H_DQ<5>")
	)
	(segment
		(start 32.586168 -18.3896)
		(end 32.586168 -21.8948)
		(width 0.14224)
		(layer "In4.Cu")
		(net "M_H_DQ<5>")
	)
	(segment
		(start 32.484568 -14.35862)
		(end 32.484568 -16.891)
		(width 0.14224)
		(layer "In4.Cu")
		(net "M_H_DQ<5>")
	)
	(segment
		(start 32.586168 -21.8948)
		(end 32.636968 -21.9456)
		(width 0.14224)
		(layer "In4.Cu")
		(net "M_H_DQ<5>")
	)
	(segment
		(start 68.005198 -69.388736)
		(end 68.159122 -69.400166)
		(width 0.0889)
		(layer "In4.Cu")
		(net "M_H_DQ<5>")
	)
	(segment
		(start 71.452486 -69.363336)
		(end 71.485252 -69.363336)
		(width 0.0889)
		(layer "In4.Cu")
		(net "M_H_DQ<5>")
	)
	(segment
		(start 67.80403 -69.388736)
		(end 68.005198 -69.388736)
		(width 0.0889)
		(layer "In4.Cu")
		(net "M_H_DQ<5>")
	)
	(segment
		(start 32.636968 -21.9456)
		(end 32.636968 -37.2237)
		(width 0.14224)
		(layer "In4.Cu")
		(net "M_H_DQ<5>")
	)
	(arc
		(start 68.916296 -69.85889)
		(mid 69.199513 -69.943171)
		(end 69.406516 -70.154038)
		(width 0.0889)
		(layer "In4.Cu")
		(net "M_H_DQ<5>")
	)
	(arc
		(start 68.509642 -69.68363)
		(mid 68.590834 -69.785132)
		(end 68.697856 -69.85889)
		(width 0.0889)
		(layer "In4.Cu")
		(net "M_H_DQ<5>")
	)
	(arc
		(start 69.768212 -70.353936)
		(mid 69.959854 -70.29677)
		(end 70.099936 -70.154038)
		(width 0.0889)
		(layer "In4.Cu")
		(net "M_H_DQ<5>")
	)
	(arc
		(start 70.622922 -69.85889)
		(mid 70.816772 -69.80254)
		(end 70.958456 -69.658738)
		(width 0.0889)
		(layer "In4.Cu")
		(net "M_H_DQ<5>")
	)
	(arc
		(start 71.830692 -68.285614)
		(mid 71.980941 -68.153221)
		(end 72.173846 -68.099432)
		(width 0.0889)
		(layer "In4.Cu")
		(net "M_H_DQ<5>")
	)
	(arc
		(start 68.159122 -69.400166)
		(mid 68.360287 -69.509854)
		(end 68.509642 -69.68363)
		(width 0.0889)
		(layer "In4.Cu")
		(net "M_H_DQ<5>")
	)
	(arc
		(start 69.406516 -70.154038)
		(mid 69.546595 -70.296774)
		(end 69.73824 -70.353936)
		(width 0.0889)
		(layer "In4.Cu")
		(net "M_H_DQ<5>")
	)
	(arc
		(start 71.485252 -69.363336)
		(mid 71.81817 -69.161345)
		(end 71.821802 -68.772024)
		(width 0.0889)
		(layer "In4.Cu")
		(net "M_H_DQ<5>")
	)
	(arc
		(start 72.173846 -68.099432)
		(mid 72.244294 -68.077293)
		(end 72.31761 -68.068444)
		(width 0.0889)
		(layer "In4.Cu")
		(net "M_H_DQ<5>")
	)
	(arc
		(start 70.958456 -69.658738)
		(mid 71.167064 -69.446806)
		(end 71.452486 -69.363336)
		(width 0.0889)
		(layer "In4.Cu")
		(net "M_H_DQ<5>")
	)
	(arc
		(start 71.810626 -68.75272)
		(mid 71.750995 -68.516183)
		(end 71.830692 -68.285614)
		(width 0.0889)
		(layer "In4.Cu")
		(net "M_H_DQ<5>")
	)
	(arc
		(start 70.099936 -70.154038)
		(mid 70.30694 -69.943174)
		(end 70.590156 -69.85889)
		(width 0.0889)
		(layer "In4.Cu")
		(net "M_H_DQ<5>")
	)
	(segment
		(start 121.646188 -60.857384)
		(end 121.074688 -60.857384)
		(width 0.1016)
		(layer "F.Cu")
		(net "M_H_DQ<59>")
	)
	(segment
		(start 150.399496 -5.822442)
		(end 150.399496 -7.086346)
		(width 0.1651)
		(layer "F.Cu")
		(net "M_H_DQ<59>")
	)
	(via
		(at 150.399496 -7.086346)
		(size 0.508)
		(drill 0.254)
		(layers "F.Cu" "B.Cu")
		(net "M_H_DQ<59>")
	)
	(via
		(at 151.24938 -12.678156)
		(size 0.508)
		(drill 0.254)
		(layers "F.Cu" "B.Cu")
		(net "M_H_DQ<59>")
	)
	(via
		(at 121.074688 -60.857384)
		(size 0.508)
		(drill 0.254)
		(layers "F.Cu" "B.Cu")
		(net "M_H_DQ<59>")
	)
	(segment
		(start 151.24938 -10.623042)
		(end 151.24938 -12.678156)
		(width 0.1651)
		(layer "B.Cu")
		(net "M_H_DQ<59>")
	)
	(segment
		(start 126.616714 -52.6923)
		(end 130.199384 -49.10963)
		(width 0.14224)
		(layer "In4.Cu")
		(net "M_H_DQ<59>")
	)
	(segment
		(start 132.627878 -49.10963)
		(end 151.642318 -30.09519)
		(width 0.14224)
		(layer "In4.Cu")
		(net "M_H_DQ<59>")
	)
	(segment
		(start 121.918222 -59.962288)
		(end 121.946162 -59.962288)
		(width 0.0889)
		(layer "In4.Cu")
		(net "M_H_DQ<59>")
	)
	(segment
		(start 151.603964 -18.599658)
		(end 151.756364 -18.447258)
		(width 0.14224)
		(layer "In4.Cu")
		(net "M_H_DQ<59>")
	)
	(segment
		(start 150.765764 -13.568172)
		(end 150.765764 -13.161772)
		(width 0.14224)
		(layer "In4.Cu")
		(net "M_H_DQ<59>")
	)
	(segment
		(start 151.757634 -8.509)
		(end 151.300434 -8.0518)
		(width 0.14224)
		(layer "In4.Cu")
		(net "M_H_DQ<59>")
	)
	(segment
		(start 121.074688 -60.51931)
		(end 121.139712 -60.454286)
		(width 0.0889)
		(layer "In4.Cu")
		(net "M_H_DQ<59>")
	)
	(segment
		(start 123.309888 -56.610504)
		(end 123.303538 -56.599836)
		(width 0.0889)
		(layer "In4.Cu")
		(net "M_H_DQ<59>")
	)
	(segment
		(start 124.70384 -54.018688)
		(end 126.030228 -52.6923)
		(width 0.0889)
		(layer "In4.Cu")
		(net "M_H_DQ<59>")
	)
	(segment
		(start 150.765764 -13.161772)
		(end 151.24938 -12.678156)
		(width 0.14224)
		(layer "In4.Cu")
		(net "M_H_DQ<59>")
	)
	(segment
		(start 151.757634 -8.8646)
		(end 151.757634 -8.509)
		(width 0.14224)
		(layer "In4.Cu")
		(net "M_H_DQ<59>")
	)
	(segment
		(start 123.303538 -56.599836)
		(end 123.298712 -56.5912)
		(width 0.0889)
		(layer "In4.Cu")
		(net "M_H_DQ<59>")
	)
	(segment
		(start 123.309888 -55.619904)
		(end 123.303538 -55.609236)
		(width 0.0889)
		(layer "In4.Cu")
		(net "M_H_DQ<59>")
	)
	(segment
		(start 151.300434 -8.0518)
		(end 151.046434 -8.0518)
		(width 0.14224)
		(layer "In4.Cu")
		(net "M_H_DQ<59>")
	)
	(segment
		(start 123.303538 -54.618636)
		(end 123.298712 -54.61)
		(width 0.0889)
		(layer "In4.Cu")
		(net "M_H_DQ<59>")
	)
	(segment
		(start 151.616664 -14.419072)
		(end 150.765764 -13.568172)
		(width 0.14224)
		(layer "In4.Cu")
		(net "M_H_DQ<59>")
	)
	(segment
		(start 151.781764 -22.000972)
		(end 151.603964 -21.823172)
		(width 0.14224)
		(layer "In4.Cu")
		(net "M_H_DQ<59>")
	)
	(segment
		(start 123.303538 -55.609236)
		(end 123.298712 -55.6006)
		(width 0.0889)
		(layer "In4.Cu")
		(net "M_H_DQ<59>")
	)
	(segment
		(start 123.309888 -54.629304)
		(end 123.303538 -54.618636)
		(width 0.0889)
		(layer "In4.Cu")
		(net "M_H_DQ<59>")
	)
	(segment
		(start 151.642318 -23.258018)
		(end 151.781764 -23.118572)
		(width 0.14224)
		(layer "In4.Cu")
		(net "M_H_DQ<59>")
	)
	(segment
		(start 123.635262 -54.018688)
		(end 124.70384 -54.018688)
		(width 0.0889)
		(layer "In4.Cu")
		(net "M_H_DQ<59>")
	)
	(segment
		(start 151.756364 -17.031462)
		(end 151.616664 -16.891762)
		(width 0.14224)
		(layer "In4.Cu")
		(net "M_H_DQ<59>")
	)
	(segment
		(start 150.716234 -7.7216)
		(end 150.716234 -7.403084)
		(width 0.14224)
		(layer "In4.Cu")
		(net "M_H_DQ<59>")
	)
	(segment
		(start 123.303538 -57.590436)
		(end 123.298712 -57.5818)
		(width 0.0889)
		(layer "In4.Cu")
		(net "M_H_DQ<59>")
	)
	(segment
		(start 151.642318 -30.09519)
		(end 151.642318 -23.258018)
		(width 0.14224)
		(layer "In4.Cu")
		(net "M_H_DQ<59>")
	)
	(segment
		(start 130.199384 -49.10963)
		(end 132.627878 -49.10963)
		(width 0.14224)
		(layer "In4.Cu")
		(net "M_H_DQ<59>")
	)
	(segment
		(start 150.716234 -7.403084)
		(end 150.399496 -7.086346)
		(width 0.14224)
		(layer "In4.Cu")
		(net "M_H_DQ<59>")
	)
	(segment
		(start 122.773694 -59.466988)
		(end 122.809508 -59.466988)
		(width 0.0889)
		(layer "In4.Cu")
		(net "M_H_DQ<59>")
	)
	(segment
		(start 123.309888 -57.601104)
		(end 123.303538 -57.590436)
		(width 0.0889)
		(layer "In4.Cu")
		(net "M_H_DQ<59>")
	)
	(segment
		(start 123.303538 -58.581036)
		(end 123.298712 -58.5724)
		(width 0.0889)
		(layer "In4.Cu")
		(net "M_H_DQ<59>")
	)
	(segment
		(start 151.781764 -23.118572)
		(end 151.781764 -22.000972)
		(width 0.14224)
		(layer "In4.Cu")
		(net "M_H_DQ<59>")
	)
	(segment
		(start 151.756364 -18.447258)
		(end 151.756364 -17.031462)
		(width 0.14224)
		(layer "In4.Cu")
		(net "M_H_DQ<59>")
	)
	(segment
		(start 126.030228 -52.6923)
		(end 126.616714 -52.6923)
		(width 0.0889)
		(layer "In4.Cu")
		(net "M_H_DQ<59>")
	)
	(segment
		(start 151.24938 -12.678156)
		(end 151.602186 -12.32535)
		(width 0.14224)
		(layer "In4.Cu")
		(net "M_H_DQ<59>")
	)
	(segment
		(start 121.074688 -60.857384)
		(end 121.074688 -60.51931)
		(width 0.0889)
		(layer "In4.Cu")
		(net "M_H_DQ<59>")
	)
	(segment
		(start 151.616664 -16.891762)
		(end 151.616664 -14.419072)
		(width 0.14224)
		(layer "In4.Cu")
		(net "M_H_DQ<59>")
	)
	(segment
		(start 151.602186 -12.32535)
		(end 151.602186 -9.020048)
		(width 0.14224)
		(layer "In4.Cu")
		(net "M_H_DQ<59>")
	)
	(segment
		(start 151.046434 -8.0518)
		(end 150.716234 -7.7216)
		(width 0.14224)
		(layer "In4.Cu")
		(net "M_H_DQ<59>")
	)
	(segment
		(start 151.602186 -9.020048)
		(end 151.757634 -8.8646)
		(width 0.14224)
		(layer "In4.Cu")
		(net "M_H_DQ<59>")
	)
	(segment
		(start 151.603964 -21.823172)
		(end 151.603964 -18.599658)
		(width 0.14224)
		(layer "In4.Cu")
		(net "M_H_DQ<59>")
	)
	(arc
		(start 122.809508 -59.466988)
		(mid 123.307759 -59.164148)
		(end 123.303538 -58.581036)
		(width 0.0889)
		(layer "In4.Cu")
		(net "M_H_DQ<59>")
	)
	(arc
		(start 123.303538 -58.180986)
		(mid 123.38276 -57.891868)
		(end 123.309888 -57.601104)
		(width 0.0889)
		(layer "In4.Cu")
		(net "M_H_DQ<59>")
	)
	(arc
		(start 123.303538 -55.209186)
		(mid 123.38276 -54.920068)
		(end 123.309888 -54.629304)
		(width 0.0889)
		(layer "In4.Cu")
		(net "M_H_DQ<59>")
	)
	(arc
		(start 123.298712 -54.61)
		(mid 123.302459 -54.220744)
		(end 123.635262 -54.018688)
		(width 0.0889)
		(layer "In4.Cu")
		(net "M_H_DQ<59>")
	)
	(arc
		(start 123.298712 -57.5818)
		(mid 123.249957 -57.385448)
		(end 123.303538 -57.190386)
		(width 0.0889)
		(layer "In4.Cu")
		(net "M_H_DQ<59>")
	)
	(arc
		(start 123.298712 -58.5724)
		(mid 123.249957 -58.376048)
		(end 123.303538 -58.180986)
		(width 0.0889)
		(layer "In4.Cu")
		(net "M_H_DQ<59>")
	)
	(arc
		(start 123.303538 -57.190386)
		(mid 123.38276 -56.901268)
		(end 123.309888 -56.610504)
		(width 0.0889)
		(layer "In4.Cu")
		(net "M_H_DQ<59>")
	)
	(arc
		(start 123.303538 -56.199786)
		(mid 123.38276 -55.910668)
		(end 123.309888 -55.619904)
		(width 0.0889)
		(layer "In4.Cu")
		(net "M_H_DQ<59>")
	)
	(arc
		(start 121.946162 -59.962288)
		(mid 122.234307 -59.879969)
		(end 122.445018 -59.666886)
		(width 0.0889)
		(layer "In4.Cu")
		(net "M_H_DQ<59>")
	)
	(arc
		(start 123.298712 -55.6006)
		(mid 123.249957 -55.404248)
		(end 123.303538 -55.209186)
		(width 0.0889)
		(layer "In4.Cu")
		(net "M_H_DQ<59>")
	)
	(arc
		(start 121.586498 -60.162186)
		(mid 121.726577 -60.01945)
		(end 121.918222 -59.962288)
		(width 0.0889)
		(layer "In4.Cu")
		(net "M_H_DQ<59>")
	)
	(arc
		(start 122.445018 -59.666886)
		(mid 122.583762 -59.524853)
		(end 122.773694 -59.466988)
		(width 0.0889)
		(layer "In4.Cu")
		(net "M_H_DQ<59>")
	)
	(arc
		(start 121.139712 -60.454286)
		(mid 121.397982 -60.361578)
		(end 121.586498 -60.162186)
		(width 0.0889)
		(layer "In4.Cu")
		(net "M_H_DQ<59>")
	)
	(arc
		(start 123.298712 -56.5912)
		(mid 123.249957 -56.394848)
		(end 123.303538 -56.199786)
		(width 0.0889)
		(layer "In4.Cu")
		(net "M_H_DQ<59>")
	)
	(segment
		(start 151.380952 -9.29386)
		(end 151.380952 -9.07034)
		(width 0.1651)
		(layer "F.Cu")
		(net "M_H_DQ<58>")
	)
	(segment
		(start 151.24938 -10.422382)
		(end 151.24938 -9.425432)
		(width 0.1651)
		(layer "F.Cu")
		(net "M_H_DQ<58>")
	)
	(segment
		(start 151.24938 -9.425432)
		(end 151.380952 -9.29386)
		(width 0.1651)
		(layer "F.Cu")
		(net "M_H_DQ<58>")
	)
	(segment
		(start 151.380952 -9.07034)
		(end 151.24938 -8.938768)
		(width 0.1651)
		(layer "F.Cu")
		(net "M_H_DQ<58>")
	)
	(segment
		(start 121.646188 -59.866784)
		(end 121.074688 -59.866784)
		(width 0.1016)
		(layer "F.Cu")
		(net "M_H_DQ<58>")
	)
	(segment
		(start 151.24938 -8.938768)
		(end 151.24938 -8.6614)
		(width 0.1651)
		(layer "F.Cu")
		(net "M_H_DQ<58>")
	)
	(via
		(at 121.074688 -59.866784)
		(size 0.4826)
		(drill 0.254)
		(layers "F.Cu" "B.Cu")
		(net "M_H_DQ<58>")
	)
	(via
		(at 151.24938 -8.6614)
		(size 0.508)
		(drill 0.254)
		(layers "F.Cu" "B.Cu")
		(net "M_H_DQ<58>")
	)
	(via
		(at 150.399496 -13.959078)
		(size 0.508)
		(drill 0.254)
		(layers "F.Cu" "B.Cu")
		(net "M_H_DQ<58>")
	)
	(segment
		(start 150.399496 -15.222982)
		(end 150.399496 -13.959078)
		(width 0.1651)
		(layer "B.Cu")
		(net "M_H_DQ<58>")
	)
	(segment
		(start 150.619968 -25.645872)
		(end 150.762208 -25.503632)
		(width 0.14224)
		(layer "In4.Cu")
		(net "M_H_DQ<58>")
	)
	(segment
		(start 150.968964 -16.764762)
		(end 150.968964 -14.82725)
		(width 0.14224)
		(layer "In4.Cu")
		(net "M_H_DQ<58>")
	)
	(segment
		(start 150.96363 -12.079732)
		(end 150.96363 -11.811)
		(width 0.14224)
		(layer "In4.Cu")
		(net "M_H_DQ<58>")
	)
	(segment
		(start 150.892764 -21.797772)
		(end 150.892764 -18.56105)
		(width 0.14224)
		(layer "In4.Cu")
		(net "M_H_DQ<58>")
	)
	(segment
		(start 121.074688 -59.866784)
		(end 121.074688 -60.204858)
		(width 0.0889)
		(layer "In4.Cu")
		(net "M_H_DQ<58>")
	)
	(segment
		(start 123.143264 -55.713122)
		(end 123.138438 -55.704486)
		(width 0.0889)
		(layer "In4.Cu")
		(net "M_H_DQ<58>")
	)
	(segment
		(start 123.143264 -57.694322)
		(end 123.138438 -57.685686)
		(width 0.0889)
		(layer "In4.Cu")
		(net "M_H_DQ<58>")
	)
	(segment
		(start 150.81123 -10.362946)
		(end 150.50643 -10.058146)
		(width 0.14224)
		(layer "In4.Cu")
		(net "M_H_DQ<58>")
	)
	(segment
		(start 150.518368 -28.958032)
		(end 150.721568 -28.754832)
		(width 0.14224)
		(layer "In4.Cu")
		(net "M_H_DQ<58>")
	)
	(segment
		(start 150.892764 -18.56105)
		(end 150.765764 -18.43405)
		(width 0.14224)
		(layer "In4.Cu")
		(net "M_H_DQ<58>")
	)
	(segment
		(start 150.81123 -10.64895)
		(end 150.81123 -10.362946)
		(width 0.14224)
		(layer "In4.Cu")
		(net "M_H_DQ<58>")
	)
	(segment
		(start 123.138438 -55.704486)
		(end 123.132088 -55.693818)
		(width 0.0889)
		(layer "In4.Cu")
		(net "M_H_DQ<58>")
	)
	(segment
		(start 150.399496 -13.959078)
		(end 150.114762 -13.674344)
		(width 0.14224)
		(layer "In4.Cu")
		(net "M_H_DQ<58>")
	)
	(segment
		(start 123.637294 -53.827934)
		(end 124.6251 -53.827934)
		(width 0.0889)
		(layer "In4.Cu")
		(net "M_H_DQ<58>")
	)
	(segment
		(start 150.114762 -13.674344)
		(end 150.114762 -12.9286)
		(width 0.14224)
		(layer "In4.Cu")
		(net "M_H_DQ<58>")
	)
	(segment
		(start 150.765764 -18.43405)
		(end 150.765764 -16.967962)
		(width 0.14224)
		(layer "In4.Cu")
		(net "M_H_DQ<58>")
	)
	(segment
		(start 150.762208 -26.316432)
		(end 150.619968 -26.174192)
		(width 0.14224)
		(layer "In4.Cu")
		(net "M_H_DQ<58>")
	)
	(segment
		(start 150.50643 -10.95375)
		(end 150.81123 -10.64895)
		(width 0.14224)
		(layer "In4.Cu")
		(net "M_H_DQ<58>")
	)
	(segment
		(start 122.770138 -59.276234)
		(end 122.809762 -59.276234)
		(width 0.0889)
		(layer "In4.Cu")
		(net "M_H_DQ<58>")
	)
	(segment
		(start 126.59614 -52.03571)
		(end 130.00101 -48.63084)
		(width 0.14224)
		(layer "In4.Cu")
		(net "M_H_DQ<58>")
	)
	(segment
		(start 150.740364 -23.143972)
		(end 150.740364 -21.950172)
		(width 0.14224)
		(layer "In4.Cu")
		(net "M_H_DQ<58>")
	)
	(segment
		(start 151.077168 -28.084272)
		(end 150.934928 -27.942032)
		(width 0.14224)
		(layer "In4.Cu")
		(net "M_H_DQ<58>")
	)
	(segment
		(start 151.089868 -25.361392)
		(end 151.089868 -24.833072)
		(width 0.14224)
		(layer "In4.Cu")
		(net "M_H_DQ<58>")
	)
	(segment
		(start 150.851362 -9.364472)
		(end 150.851362 -9.059418)
		(width 0.14224)
		(layer "In4.Cu")
		(net "M_H_DQ<58>")
	)
	(segment
		(start 151.039068 -26.458672)
		(end 150.896828 -26.316432)
		(width 0.14224)
		(layer "In4.Cu")
		(net "M_H_DQ<58>")
	)
	(segment
		(start 121.074688 -60.204858)
		(end 121.1326 -60.26277)
		(width 0.0889)
		(layer "In4.Cu")
		(net "M_H_DQ<58>")
	)
	(segment
		(start 150.947628 -25.503632)
		(end 151.089868 -25.361392)
		(width 0.14224)
		(layer "In4.Cu")
		(net "M_H_DQ<58>")
	)
	(segment
		(start 151.089868 -24.833072)
		(end 150.873968 -24.617172)
		(width 0.14224)
		(layer "In4.Cu")
		(net "M_H_DQ<58>")
	)
	(segment
		(start 150.968964 -14.82725)
		(end 150.399496 -14.257782)
		(width 0.14224)
		(layer "In4.Cu")
		(net "M_H_DQ<58>")
	)
	(segment
		(start 124.6251 -53.827934)
		(end 126.075948 -52.377086)
		(width 0.0889)
		(layer "In4.Cu")
		(net "M_H_DQ<58>")
	)
	(segment
		(start 150.518368 -30.320996)
		(end 150.518368 -28.958032)
		(width 0.14224)
		(layer "In4.Cu")
		(net "M_H_DQ<58>")
	)
	(segment
		(start 121.920254 -59.771534)
		(end 121.944384 -59.771534)
		(width 0.0889)
		(layer "In4.Cu")
		(net "M_H_DQ<58>")
	)
	(segment
		(start 150.50643 -11.3538)
		(end 150.50643 -10.95375)
		(width 0.14224)
		(layer "In4.Cu")
		(net "M_H_DQ<58>")
	)
	(segment
		(start 123.138438 -56.695086)
		(end 123.132088 -56.684418)
		(width 0.0889)
		(layer "In4.Cu")
		(net "M_H_DQ<58>")
	)
	(segment
		(start 150.518368 -27.332432)
		(end 150.721568 -27.129232)
		(width 0.14224)
		(layer "In4.Cu")
		(net "M_H_DQ<58>")
	)
	(segment
		(start 126.075948 -52.377086)
		(end 126.254764 -52.377086)
		(width 0.0889)
		(layer "In4.Cu")
		(net "M_H_DQ<58>")
	)
	(segment
		(start 150.114762 -12.9286)
		(end 150.96363 -12.079732)
		(width 0.14224)
		(layer "In4.Cu")
		(net "M_H_DQ<58>")
	)
	(segment
		(start 150.96363 -11.811)
		(end 150.50643 -11.3538)
		(width 0.14224)
		(layer "In4.Cu")
		(net "M_H_DQ<58>")
	)
	(segment
		(start 151.077168 -28.612592)
		(end 151.077168 -28.084272)
		(width 0.14224)
		(layer "In4.Cu")
		(net "M_H_DQ<58>")
	)
	(segment
		(start 150.934928 -28.754832)
		(end 151.077168 -28.612592)
		(width 0.14224)
		(layer "In4.Cu")
		(net "M_H_DQ<58>")
	)
	(segment
		(start 150.50643 -9.709404)
		(end 150.851362 -9.364472)
		(width 0.14224)
		(layer "In4.Cu")
		(net "M_H_DQ<58>")
	)
	(segment
		(start 150.399496 -14.257782)
		(end 150.399496 -13.959078)
		(width 0.14224)
		(layer "In4.Cu")
		(net "M_H_DQ<58>")
	)
	(segment
		(start 150.873968 -23.277576)
		(end 150.740364 -23.143972)
		(width 0.14224)
		(layer "In4.Cu")
		(net "M_H_DQ<58>")
	)
	(segment
		(start 150.721568 -28.754832)
		(end 150.934928 -28.754832)
		(width 0.14224)
		(layer "In4.Cu")
		(net "M_H_DQ<58>")
	)
	(segment
		(start 123.143264 -56.703722)
		(end 123.138438 -56.695086)
		(width 0.0889)
		(layer "In4.Cu")
		(net "M_H_DQ<58>")
	)
	(segment
		(start 150.934928 -27.942032)
		(end 150.721568 -27.942032)
		(width 0.14224)
		(layer "In4.Cu")
		(net "M_H_DQ<58>")
	)
	(segment
		(start 150.851362 -9.059418)
		(end 151.24938 -8.6614)
		(width 0.14224)
		(layer "In4.Cu")
		(net "M_H_DQ<58>")
	)
	(segment
		(start 130.00101 -48.63084)
		(end 132.208524 -48.63084)
		(width 0.14224)
		(layer "In4.Cu")
		(net "M_H_DQ<58>")
	)
	(segment
		(start 150.518368 -27.738832)
		(end 150.518368 -27.332432)
		(width 0.14224)
		(layer "In4.Cu")
		(net "M_H_DQ<58>")
	)
	(segment
		(start 150.721568 -27.942032)
		(end 150.518368 -27.738832)
		(width 0.14224)
		(layer "In4.Cu")
		(net "M_H_DQ<58>")
	)
	(segment
		(start 132.208524 -48.63084)
		(end 150.518368 -30.320996)
		(width 0.14224)
		(layer "In4.Cu")
		(net "M_H_DQ<58>")
	)
	(segment
		(start 150.896828 -27.129232)
		(end 151.039068 -26.986992)
		(width 0.14224)
		(layer "In4.Cu")
		(net "M_H_DQ<58>")
	)
	(segment
		(start 150.50643 -10.058146)
		(end 150.50643 -9.709404)
		(width 0.14224)
		(layer "In4.Cu")
		(net "M_H_DQ<58>")
	)
	(segment
		(start 150.740364 -21.950172)
		(end 150.892764 -21.797772)
		(width 0.14224)
		(layer "In4.Cu")
		(net "M_H_DQ<58>")
	)
	(segment
		(start 150.765764 -16.967962)
		(end 150.968964 -16.764762)
		(width 0.14224)
		(layer "In4.Cu")
		(net "M_H_DQ<58>")
	)
	(segment
		(start 150.619968 -26.174192)
		(end 150.619968 -25.645872)
		(width 0.14224)
		(layer "In4.Cu")
		(net "M_H_DQ<58>")
	)
	(segment
		(start 126.254764 -52.377086)
		(end 126.59614 -52.03571)
		(width 0.0889)
		(layer "In4.Cu")
		(net "M_H_DQ<58>")
	)
	(segment
		(start 150.873968 -24.617172)
		(end 150.873968 -23.277576)
		(width 0.14224)
		(layer "In4.Cu")
		(net "M_H_DQ<58>")
	)
	(segment
		(start 150.721568 -27.129232)
		(end 150.896828 -27.129232)
		(width 0.14224)
		(layer "In4.Cu")
		(net "M_H_DQ<58>")
	)
	(segment
		(start 123.138438 -54.713886)
		(end 123.132088 -54.703218)
		(width 0.0889)
		(layer "In4.Cu")
		(net "M_H_DQ<58>")
	)
	(segment
		(start 123.138438 -57.685686)
		(end 123.132088 -57.675018)
		(width 0.0889)
		(layer "In4.Cu")
		(net "M_H_DQ<58>")
	)
	(segment
		(start 151.039068 -26.986992)
		(end 151.039068 -26.458672)
		(width 0.14224)
		(layer "In4.Cu")
		(net "M_H_DQ<58>")
	)
	(segment
		(start 123.143264 -54.722522)
		(end 123.138438 -54.713886)
		(width 0.0889)
		(layer "In4.Cu")
		(net "M_H_DQ<58>")
	)
	(segment
		(start 150.896828 -26.316432)
		(end 150.762208 -26.316432)
		(width 0.14224)
		(layer "In4.Cu")
		(net "M_H_DQ<58>")
	)
	(segment
		(start 150.762208 -25.503632)
		(end 150.947628 -25.503632)
		(width 0.14224)
		(layer "In4.Cu")
		(net "M_H_DQ<58>")
	)
	(arc
		(start 121.1326 -60.26277)
		(mid 121.299445 -60.197957)
		(end 121.421398 -60.066936)
		(width 0.0889)
		(layer "In4.Cu")
		(net "M_H_DQ<58>")
	)
	(arc
		(start 123.138438 -58.085736)
		(mid 123.191908 -57.890673)
		(end 123.143264 -57.694322)
		(width 0.0889)
		(layer "In4.Cu")
		(net "M_H_DQ<58>")
	)
	(arc
		(start 123.132088 -57.675018)
		(mid 123.05929 -57.384255)
		(end 123.138438 -57.095136)
		(width 0.0889)
		(layer "In4.Cu")
		(net "M_H_DQ<58>")
	)
	(arc
		(start 123.138438 -58.67654)
		(mid 123.059307 -58.381138)
		(end 123.138438 -58.085736)
		(width 0.0889)
		(layer "In4.Cu")
		(net "M_H_DQ<58>")
	)
	(arc
		(start 121.421398 -60.066936)
		(mid 121.632111 -59.853857)
		(end 121.920254 -59.771534)
		(width 0.0889)
		(layer "In4.Cu")
		(net "M_H_DQ<58>")
	)
	(arc
		(start 123.132088 -54.703218)
		(mid 123.138265 -54.123286)
		(end 123.637294 -53.827934)
		(width 0.0889)
		(layer "In4.Cu")
		(net "M_H_DQ<58>")
	)
	(arc
		(start 122.809762 -59.276234)
		(mid 123.142678 -59.068782)
		(end 123.138438 -58.67654)
		(width 0.0889)
		(layer "In4.Cu")
		(net "M_H_DQ<58>")
	)
	(arc
		(start 123.138438 -57.095136)
		(mid 123.191908 -56.900073)
		(end 123.143264 -56.703722)
		(width 0.0889)
		(layer "In4.Cu")
		(net "M_H_DQ<58>")
	)
	(arc
		(start 123.138438 -55.113936)
		(mid 123.191908 -54.918873)
		(end 123.143264 -54.722522)
		(width 0.0889)
		(layer "In4.Cu")
		(net "M_H_DQ<58>")
	)
	(arc
		(start 122.279918 -59.571382)
		(mid 122.486922 -59.360518)
		(end 122.770138 -59.276234)
		(width 0.0889)
		(layer "In4.Cu")
		(net "M_H_DQ<58>")
	)
	(arc
		(start 123.138438 -56.104536)
		(mid 123.191908 -55.909473)
		(end 123.143264 -55.713122)
		(width 0.0889)
		(layer "In4.Cu")
		(net "M_H_DQ<58>")
	)
	(arc
		(start 123.132088 -55.693818)
		(mid 123.05929 -55.403055)
		(end 123.138438 -55.113936)
		(width 0.0889)
		(layer "In4.Cu")
		(net "M_H_DQ<58>")
	)
	(arc
		(start 123.132088 -56.684418)
		(mid 123.05929 -56.393655)
		(end 123.138438 -56.104536)
		(width 0.0889)
		(layer "In4.Cu")
		(net "M_H_DQ<58>")
	)
	(arc
		(start 121.944384 -59.771534)
		(mid 122.138234 -59.715184)
		(end 122.279918 -59.571382)
		(width 0.0889)
		(layer "In4.Cu")
		(net "M_H_DQ<58>")
	)
	(segment
		(start 119.070882 -61.352938)
		(end 118.499382 -61.352938)
		(width 0.1016)
		(layer "F.Cu")
		(net "M_H_DQ<57>")
	)
	(segment
		(start 144.449546 -5.822442)
		(end 144.449546 -7.086346)
		(width 0.1651)
		(layer "F.Cu")
		(net "M_H_DQ<57>")
	)
	(via
		(at 118.499382 -61.352938)
		(size 0.508)
		(drill 0.254)
		(layers "F.Cu" "B.Cu")
		(net "M_H_DQ<57>")
	)
	(via
		(at 145.12163 -12.678156)
		(size 0.508)
		(drill 0.254)
		(layers "F.Cu" "B.Cu")
		(net "M_H_DQ<57>")
	)
	(via
		(at 144.449546 -7.086346)
		(size 0.508)
		(drill 0.254)
		(layers "F.Cu" "B.Cu")
		(net "M_H_DQ<57>")
	)
	(segment
		(start 145.29943 -11.997182)
		(end 145.12163 -12.174982)
		(width 0.1651)
		(layer "B.Cu")
		(net "M_H_DQ<57>")
	)
	(segment
		(start 145.29943 -10.623042)
		(end 145.29943 -11.997182)
		(width 0.1651)
		(layer "B.Cu")
		(net "M_H_DQ<57>")
	)
	(segment
		(start 145.12163 -12.174982)
		(end 145.12163 -12.678156)
		(width 0.1651)
		(layer "B.Cu")
		(net "M_H_DQ<57>")
	)
	(segment
		(start 144.926812 -8.1026)
		(end 144.449546 -7.625334)
		(width 0.14224)
		(layer "In4.Cu")
		(net "M_H_DQ<57>")
	)
	(segment
		(start 145.920968 -27.437588)
		(end 145.920968 -24.2062)
		(width 0.14224)
		(layer "In4.Cu")
		(net "M_H_DQ<57>")
	)
	(segment
		(start 121.016268 -51.48326)
		(end 121.440448 -51.48326)
		(width 0.0889)
		(layer "In4.Cu")
		(net "M_H_DQ<57>")
	)
	(segment
		(start 145.12163 -12.678156)
		(end 145.495772 -12.304014)
		(width 0.14224)
		(layer "In4.Cu")
		(net "M_H_DQ<57>")
	)
	(segment
		(start 119.346726 -57.485534)
		(end 119.382794 -57.485534)
		(width 0.0889)
		(layer "In4.Cu")
		(net "M_H_DQ<57>")
	)
	(segment
		(start 118.169944 -60.591954)
		(end 118.147846 -60.5536)
		(width 0.0889)
		(layer "In4.Cu")
		(net "M_H_DQ<57>")
	)
	(segment
		(start 140.01115 -33.635188)
		(end 140.01115 -33.347406)
		(width 0.14224)
		(layer "In4.Cu")
		(net "M_H_DQ<57>")
	)
	(segment
		(start 120.201182 -52.037488)
		(end 120.233948 -52.037488)
		(width 0.0889)
		(layer "In4.Cu")
		(net "M_H_DQ<57>")
	)
	(segment
		(start 122.869198 -50.05451)
		(end 122.881898 -50.05451)
		(width 0.0889)
		(layer "In4.Cu")
		(net "M_H_DQ<57>")
	)
	(segment
		(start 119.878602 -55.624476)
		(end 119.869712 -55.609236)
		(width 0.0889)
		(layer "In4.Cu")
		(net "M_H_DQ<57>")
	)
	(segment
		(start 145.495772 -12.304014)
		(end 145.495772 -8.970264)
		(width 0.14224)
		(layer "In4.Cu")
		(net "M_H_DQ<57>")
	)
	(segment
		(start 144.595088 -13.48232)
		(end 144.595088 -13.204698)
		(width 0.14224)
		(layer "In4.Cu")
		(net "M_H_DQ<57>")
	)
	(segment
		(start 118.484396 -57.981088)
		(end 118.517162 -57.981088)
		(width 0.0889)
		(layer "In4.Cu")
		(net "M_H_DQ<57>")
	)
	(segment
		(start 119.878602 -54.633876)
		(end 119.861584 -54.604412)
		(width 0.0889)
		(layer "In4.Cu")
		(net "M_H_DQ<57>")
	)
	(segment
		(start 129.675382 -45.69841)
		(end 140.282168 -35.091624)
		(width 0.14224)
		(layer "In4.Cu")
		(net "M_H_DQ<57>")
	)
	(segment
		(start 118.846092 -59.171586)
		(end 118.839742 -59.160918)
		(width 0.0889)
		(layer "In4.Cu")
		(net "M_H_DQ<57>")
	)
	(segment
		(start 122.881898 -50.05451)
		(end 127.237998 -45.69841)
		(width 0.14224)
		(layer "In4.Cu")
		(net "M_H_DQ<57>")
	)
	(segment
		(start 145.609564 -16.300196)
		(end 144.974564 -15.665196)
		(width 0.14224)
		(layer "In4.Cu")
		(net "M_H_DQ<57>")
	)
	(segment
		(start 144.449546 -7.625334)
		(end 144.449546 -7.086346)
		(width 0.14224)
		(layer "In4.Cu")
		(net "M_H_DQ<57>")
	)
	(segment
		(start 144.974564 -15.665196)
		(end 144.974564 -13.861796)
		(width 0.14224)
		(layer "In4.Cu")
		(net "M_H_DQ<57>")
	)
	(segment
		(start 119.869458 -52.637436)
		(end 119.864632 -52.6288)
		(width 0.0889)
		(layer "In4.Cu")
		(net "M_H_DQ<57>")
	)
	(segment
		(start 145.652236 -8.8138)
		(end 145.652236 -8.472424)
		(width 0.14224)
		(layer "In4.Cu")
		(net "M_H_DQ<57>")
	)
	(segment
		(start 127.237998 -45.69841)
		(end 129.675382 -45.69841)
		(width 0.14224)
		(layer "In4.Cu")
		(net "M_H_DQ<57>")
	)
	(segment
		(start 118.499382 -61.352938)
		(end 118.169944 -60.591954)
		(width 0.0889)
		(layer "In4.Cu")
		(net "M_H_DQ<57>")
	)
	(segment
		(start 140.01115 -33.347406)
		(end 145.920968 -27.437588)
		(width 0.14224)
		(layer "In4.Cu")
		(net "M_H_DQ<57>")
	)
	(segment
		(start 121.440448 -51.48326)
		(end 122.869198 -50.05451)
		(width 0.0889)
		(layer "In4.Cu")
		(net "M_H_DQ<57>")
	)
	(segment
		(start 144.974564 -13.861796)
		(end 144.595088 -13.48232)
		(width 0.14224)
		(layer "In4.Cu")
		(net "M_H_DQ<57>")
	)
	(segment
		(start 145.609564 -23.894796)
		(end 145.609564 -16.300196)
		(width 0.14224)
		(layer "In4.Cu")
		(net "M_H_DQ<57>")
	)
	(segment
		(start 119.875808 -52.648104)
		(end 119.869458 -52.637436)
		(width 0.0889)
		(layer "In4.Cu")
		(net "M_H_DQ<57>")
	)
	(segment
		(start 140.282168 -33.906206)
		(end 140.01115 -33.635188)
		(width 0.14224)
		(layer "In4.Cu")
		(net "M_H_DQ<57>")
	)
	(segment
		(start 145.282412 -8.1026)
		(end 144.926812 -8.1026)
		(width 0.14224)
		(layer "In4.Cu")
		(net "M_H_DQ<57>")
	)
	(segment
		(start 145.495772 -8.970264)
		(end 145.652236 -8.8138)
		(width 0.14224)
		(layer "In4.Cu")
		(net "M_H_DQ<57>")
	)
	(segment
		(start 119.878602 -56.615076)
		(end 119.869712 -56.599836)
		(width 0.0889)
		(layer "In4.Cu")
		(net "M_H_DQ<57>")
	)
	(segment
		(start 140.282168 -35.091624)
		(end 140.282168 -33.906206)
		(width 0.14224)
		(layer "In4.Cu")
		(net "M_H_DQ<57>")
	)
	(segment
		(start 120.635522 -51.864006)
		(end 121.016268 -51.48326)
		(width 0.0889)
		(layer "In4.Cu")
		(net "M_H_DQ<57>")
	)
	(segment
		(start 145.920968 -24.2062)
		(end 145.609564 -23.894796)
		(width 0.14224)
		(layer "In4.Cu")
		(net "M_H_DQ<57>")
	)
	(segment
		(start 119.875808 -53.638704)
		(end 119.869458 -53.628036)
		(width 0.0889)
		(layer "In4.Cu")
		(net "M_H_DQ<57>")
	)
	(segment
		(start 144.595088 -13.204698)
		(end 145.12163 -12.678156)
		(width 0.14224)
		(layer "In4.Cu")
		(net "M_H_DQ<57>")
	)
	(segment
		(start 145.652236 -8.472424)
		(end 145.282412 -8.1026)
		(width 0.14224)
		(layer "In4.Cu")
		(net "M_H_DQ<57>")
	)
	(segment
		(start 119.869458 -53.628036)
		(end 119.864632 -53.6194)
		(width 0.0889)
		(layer "In4.Cu")
		(net "M_H_DQ<57>")
	)
	(arc
		(start 118.364508 -59.985402)
		(mid 118.605857 -59.857869)
		(end 118.801642 -59.667648)
		(width 0.0889)
		(layer "In4.Cu")
		(net "M_H_DQ<57>")
	)
	(arc
		(start 119.864632 -53.6194)
		(mid 119.815877 -53.423048)
		(end 119.869458 -53.227986)
		(width 0.0889)
		(layer "In4.Cu")
		(net "M_H_DQ<57>")
	)
	(arc
		(start 119.869458 -54.218586)
		(mid 119.94868 -53.929468)
		(end 119.875808 -53.638704)
		(width 0.0889)
		(layer "In4.Cu")
		(net "M_H_DQ<57>")
	)
	(arc
		(start 119.869712 -56.599836)
		(mid 119.816179 -56.399938)
		(end 119.869712 -56.20004)
		(width 0.0889)
		(layer "In4.Cu")
		(net "M_H_DQ<57>")
	)
	(arc
		(start 119.864632 -52.6288)
		(mid 119.868379 -52.239544)
		(end 120.201182 -52.037488)
		(width 0.0889)
		(layer "In4.Cu")
		(net "M_H_DQ<57>")
	)
	(arc
		(start 119.382794 -57.485534)
		(mid 119.871518 -57.187504)
		(end 119.878602 -56.615076)
		(width 0.0889)
		(layer "In4.Cu")
		(net "M_H_DQ<57>")
	)
	(arc
		(start 118.517162 -57.981088)
		(mid 118.802586 -57.897621)
		(end 119.011192 -57.685686)
		(width 0.0889)
		(layer "In4.Cu")
		(net "M_H_DQ<57>")
	)
	(arc
		(start 118.839742 -59.160918)
		(mid 118.642635 -58.925276)
		(end 118.381526 -58.763408)
		(width 0.0889)
		(layer "In4.Cu")
		(net "M_H_DQ<57>")
	)
	(arc
		(start 119.869712 -55.20944)
		(mid 119.948901 -54.922825)
		(end 119.878602 -54.633876)
		(width 0.0889)
		(layer "In4.Cu")
		(net "M_H_DQ<57>")
	)
	(arc
		(start 118.381526 -58.763408)
		(mid 118.102349 -58.328721)
		(end 118.484396 -57.981088)
		(width 0.0889)
		(layer "In4.Cu")
		(net "M_H_DQ<57>")
	)
	(arc
		(start 119.861584 -54.604412)
		(mid 119.815997 -54.410499)
		(end 119.869458 -54.218586)
		(width 0.0889)
		(layer "In4.Cu")
		(net "M_H_DQ<57>")
	)
	(arc
		(start 119.011192 -57.685686)
		(mid 119.152875 -57.541882)
		(end 119.346726 -57.485534)
		(width 0.0889)
		(layer "In4.Cu")
		(net "M_H_DQ<57>")
	)
	(arc
		(start 118.801642 -59.667648)
		(mid 118.821708 -59.618518)
		(end 118.846092 -59.571382)
		(width 0.0889)
		(layer "In4.Cu")
		(net "M_H_DQ<57>")
	)
	(arc
		(start 118.147846 -60.5536)
		(mid 118.125468 -60.219695)
		(end 118.364508 -59.985402)
		(width 0.0889)
		(layer "In4.Cu")
		(net "M_H_DQ<57>")
	)
	(arc
		(start 119.869712 -56.20004)
		(mid 119.948901 -55.913425)
		(end 119.878602 -55.624476)
		(width 0.0889)
		(layer "In4.Cu")
		(net "M_H_DQ<57>")
	)
	(arc
		(start 119.869458 -53.227986)
		(mid 119.94868 -52.938868)
		(end 119.875808 -52.648104)
		(width 0.0889)
		(layer "In4.Cu")
		(net "M_H_DQ<57>")
	)
	(arc
		(start 120.233948 -52.037488)
		(mid 120.451327 -51.989143)
		(end 120.635522 -51.864006)
		(width 0.0889)
		(layer "In4.Cu")
		(net "M_H_DQ<57>")
	)
	(arc
		(start 118.846092 -59.571382)
		(mid 118.899591 -59.371484)
		(end 118.846092 -59.171586)
		(width 0.0889)
		(layer "In4.Cu")
		(net "M_H_DQ<57>")
	)
	(arc
		(start 119.869712 -55.609236)
		(mid 119.816179 -55.409338)
		(end 119.869712 -55.20944)
		(width 0.0889)
		(layer "In4.Cu")
		(net "M_H_DQ<57>")
	)
	(segment
		(start 119.070882 -59.371484)
		(end 118.499382 -59.371484)
		(width 0.1016)
		(layer "F.Cu")
		(net "M_H_DQ<56>")
	)
	(segment
		(start 145.29943 -10.422382)
		(end 145.153126 -8.89)
		(width 0.1651)
		(layer "F.Cu")
		(net "M_H_DQ<56>")
	)
	(segment
		(start 145.153126 -8.89)
		(end 145.140934 -8.763)
		(width 0.1651)
		(layer "F.Cu")
		(net "M_H_DQ<56>")
	)
	(segment
		(start 145.140934 -8.763)
		(end 145.12163 -8.5598)
		(width 0.1651)
		(layer "F.Cu")
		(net "M_H_DQ<56>")
	)
	(via
		(at 118.499382 -59.371484)
		(size 0.508)
		(drill 0.254)
		(layers "F.Cu" "B.Cu")
		(net "M_H_DQ<56>")
	)
	(via
		(at 145.12163 -8.5598)
		(size 0.508)
		(drill 0.254)
		(layers "F.Cu" "B.Cu")
		(net "M_H_DQ<56>")
	)
	(via
		(at 144.449546 -13.959078)
		(size 0.508)
		(drill 0.254)
		(layers "F.Cu" "B.Cu")
		(net "M_H_DQ<56>")
	)
	(segment
		(start 144.449546 -15.222982)
		(end 144.449546 -13.959078)
		(width 0.1651)
		(layer "B.Cu")
		(net "M_H_DQ<56>")
	)
	(segment
		(start 127.039624 -45.21962)
		(end 129.256028 -45.21962)
		(width 0.14224)
		(layer "In4.Cu")
		(net "M_H_DQ<56>")
	)
	(segment
		(start 145.082768 -25.740106)
		(end 145.285968 -25.536906)
		(width 0.14224)
		(layer "In4.Cu")
		(net "M_H_DQ<56>")
	)
	(segment
		(start 144.449546 -13.959078)
		(end 144.164812 -13.674344)
		(width 0.14224)
		(layer "In4.Cu")
		(net "M_H_DQ<56>")
	)
	(segment
		(start 145.285968 -25.130506)
		(end 145.082768 -24.927306)
		(width 0.14224)
		(layer "In4.Cu")
		(net "M_H_DQ<56>")
	)
	(segment
		(start 144.51203 -11.302746)
		(end 144.51203 -10.9982)
		(width 0.14224)
		(layer "In4.Cu")
		(net "M_H_DQ<56>")
	)
	(segment
		(start 139.113768 -33.346644)
		(end 145.285968 -27.174444)
		(width 0.14224)
		(layer "In4.Cu")
		(net "M_H_DQ<56>")
	)
	(segment
		(start 138.488674 -34.259266)
		(end 138.887454 -34.658046)
		(width 0.14224)
		(layer "In4.Cu")
		(net "M_H_DQ<56>")
	)
	(segment
		(start 144.923764 -16.427196)
		(end 144.449546 -15.952978)
		(width 0.14224)
		(layer "In4.Cu")
		(net "M_H_DQ<56>")
	)
	(segment
		(start 145.285968 -27.174444)
		(end 145.285968 -26.756106)
		(width 0.14224)
		(layer "In4.Cu")
		(net "M_H_DQ<56>")
	)
	(segment
		(start 144.631664 -22.026372)
		(end 144.974564 -21.683472)
		(width 0.14224)
		(layer "In4.Cu")
		(net "M_H_DQ<56>")
	)
	(segment
		(start 122.502168 -49.757076)
		(end 127.039624 -45.21962)
		(width 0.14224)
		(layer "In4.Cu")
		(net "M_H_DQ<56>")
	)
	(segment
		(start 144.923764 -16.825976)
		(end 144.923764 -16.427196)
		(width 0.14224)
		(layer "In4.Cu")
		(net "M_H_DQ<56>")
	)
	(segment
		(start 144.48663 -9.779254)
		(end 144.901412 -9.364472)
		(width 0.14224)
		(layer "In4.Cu")
		(net "M_H_DQ<56>")
	)
	(segment
		(start 144.752568 -26.552906)
		(end 144.549368 -26.349706)
		(width 0.14224)
		(layer "In4.Cu")
		(net "M_H_DQ<56>")
	)
	(segment
		(start 119.709184 -53.731922)
		(end 119.704358 -53.723286)
		(width 0.0889)
		(layer "In4.Cu")
		(net "M_H_DQ<56>")
	)
	(segment
		(start 119.704358 -52.732686)
		(end 119.698008 -52.722018)
		(width 0.0889)
		(layer "In4.Cu")
		(net "M_H_DQ<56>")
	)
	(segment
		(start 145.285968 -25.536906)
		(end 145.285968 -25.130506)
		(width 0.14224)
		(layer "In4.Cu")
		(net "M_H_DQ<56>")
	)
	(segment
		(start 144.549368 -24.317706)
		(end 144.943068 -23.924006)
		(width 0.14224)
		(layer "In4.Cu")
		(net "M_H_DQ<56>")
	)
	(segment
		(start 145.285968 -26.756106)
		(end 145.082768 -26.552906)
		(width 0.14224)
		(layer "In4.Cu")
		(net "M_H_DQ<56>")
	)
	(segment
		(start 137.913872 -34.834068)
		(end 137.913872 -34.54654)
		(width 0.14224)
		(layer "In4.Cu")
		(net "M_H_DQ<56>")
	)
	(segment
		(start 144.752568 -25.740106)
		(end 145.082768 -25.740106)
		(width 0.14224)
		(layer "In4.Cu")
		(net "M_H_DQ<56>")
	)
	(segment
		(start 120.916954 -51.29276)
		(end 121.3612 -51.29276)
		(width 0.0889)
		(layer "In4.Cu")
		(net "M_H_DQ<56>")
	)
	(segment
		(start 121.3612 -51.29276)
		(end 122.502168 -50.151792)
		(width 0.0889)
		(layer "In4.Cu")
		(net "M_H_DQ<56>")
	)
	(segment
		(start 144.164812 -13.674344)
		(end 144.164812 -12.9286)
		(width 0.14224)
		(layer "In4.Cu")
		(net "M_H_DQ<56>")
	)
	(segment
		(start 118.004082 -58.705496)
		(end 117.987572 -58.67654)
		(width 0.0889)
		(layer "In4.Cu")
		(net "M_H_DQ<56>")
	)
	(segment
		(start 144.943068 -23.924006)
		(end 144.943068 -23.398226)
		(width 0.14224)
		(layer "In4.Cu")
		(net "M_H_DQ<56>")
	)
	(segment
		(start 144.82953 -10.4521)
		(end 144.48663 -10.1092)
		(width 0.14224)
		(layer "In4.Cu")
		(net "M_H_DQ<56>")
	)
	(segment
		(start 144.942052 -23.398226)
		(end 144.631664 -23.087838)
		(width 0.14224)
		(layer "In4.Cu")
		(net "M_H_DQ<56>")
	)
	(segment
		(start 119.709184 -52.741322)
		(end 119.704358 -52.732686)
		(width 0.0889)
		(layer "In4.Cu")
		(net "M_H_DQ<56>")
	)
	(segment
		(start 144.449546 -15.952978)
		(end 144.449546 -13.959078)
		(width 0.14224)
		(layer "In4.Cu")
		(net "M_H_DQ<56>")
	)
	(segment
		(start 139.113768 -33.635696)
		(end 139.113768 -33.346644)
		(width 0.14224)
		(layer "In4.Cu")
		(net "M_H_DQ<56>")
	)
	(segment
		(start 144.901412 -11.692128)
		(end 144.51203 -11.302746)
		(width 0.14224)
		(layer "In4.Cu")
		(net "M_H_DQ<56>")
	)
	(segment
		(start 144.51203 -10.9982)
		(end 144.82953 -10.6807)
		(width 0.14224)
		(layer "In4.Cu")
		(net "M_H_DQ<56>")
	)
	(segment
		(start 122.502168 -50.151792)
		(end 122.502168 -49.757076)
		(width 0.0889)
		(layer "In4.Cu")
		(net "M_H_DQ<56>")
	)
	(segment
		(start 138.201146 -34.259266)
		(end 138.488674 -34.259266)
		(width 0.14224)
		(layer "In4.Cu")
		(net "M_H_DQ<56>")
	)
	(segment
		(start 119.704358 -53.723286)
		(end 119.698008 -53.712618)
		(width 0.0889)
		(layer "In4.Cu")
		(net "M_H_DQ<56>")
	)
	(segment
		(start 144.901412 -8.780018)
		(end 145.12163 -8.5598)
		(width 0.14224)
		(layer "In4.Cu")
		(net "M_H_DQ<56>")
	)
	(segment
		(start 120.562878 -51.646836)
		(end 120.916954 -51.29276)
		(width 0.0889)
		(layer "In4.Cu")
		(net "M_H_DQ<56>")
	)
	(segment
		(start 137.913872 -34.54654)
		(end 138.201146 -34.259266)
		(width 0.14224)
		(layer "In4.Cu")
		(net "M_H_DQ<56>")
	)
	(segment
		(start 144.631664 -18.319242)
		(end 144.631664 -17.118076)
		(width 0.14224)
		(layer "In4.Cu")
		(net "M_H_DQ<56>")
	)
	(segment
		(start 118.477792 -57.790588)
		(end 118.510558 -57.790588)
		(width 0.0889)
		(layer "In4.Cu")
		(net "M_H_DQ<56>")
	)
	(segment
		(start 120.194578 -51.846988)
		(end 120.227344 -51.846988)
		(width 0.0889)
		(layer "In4.Cu")
		(net "M_H_DQ<56>")
	)
	(segment
		(start 145.082768 -26.552906)
		(end 144.752568 -26.552906)
		(width 0.14224)
		(layer "In4.Cu")
		(net "M_H_DQ<56>")
	)
	(segment
		(start 145.082768 -24.927306)
		(end 144.752568 -24.927306)
		(width 0.14224)
		(layer "In4.Cu")
		(net "M_H_DQ<56>")
	)
	(segment
		(start 119.340122 -57.295034)
		(end 119.357902 -57.295034)
		(width 0.0889)
		(layer "In4.Cu")
		(net "M_H_DQ<56>")
	)
	(segment
		(start 144.549368 -25.943306)
		(end 144.752568 -25.740106)
		(width 0.14224)
		(layer "In4.Cu")
		(net "M_H_DQ<56>")
	)
	(segment
		(start 139.088622 -34.658046)
		(end 139.511786 -34.234882)
		(width 0.14224)
		(layer "In4.Cu")
		(net "M_H_DQ<56>")
	)
	(segment
		(start 144.549368 -24.724106)
		(end 144.549368 -24.317706)
		(width 0.14224)
		(layer "In4.Cu")
		(net "M_H_DQ<56>")
	)
	(segment
		(start 138.568684 -35.48888)
		(end 137.913872 -34.834068)
		(width 0.14224)
		(layer "In4.Cu")
		(net "M_H_DQ<56>")
	)
	(segment
		(start 139.511786 -34.234882)
		(end 139.511786 -34.033714)
		(width 0.14224)
		(layer "In4.Cu")
		(net "M_H_DQ<56>")
	)
	(segment
		(start 144.901412 -9.364472)
		(end 144.901412 -8.780018)
		(width 0.14224)
		(layer "In4.Cu")
		(net "M_H_DQ<56>")
	)
	(segment
		(start 119.704358 -54.713886)
		(end 119.698008 -54.703218)
		(width 0.0889)
		(layer "In4.Cu")
		(net "M_H_DQ<56>")
	)
	(segment
		(start 144.901412 -12.192)
		(end 144.901412 -11.692128)
		(width 0.14224)
		(layer "In4.Cu")
		(net "M_H_DQ<56>")
	)
	(segment
		(start 119.704358 -55.704486)
		(end 119.695468 -55.689246)
		(width 0.0889)
		(layer "In4.Cu")
		(net "M_H_DQ<56>")
	)
	(segment
		(start 144.631664 -23.087838)
		(end 144.631664 -22.026372)
		(width 0.14224)
		(layer "In4.Cu")
		(net "M_H_DQ<56>")
	)
	(segment
		(start 138.887454 -34.658046)
		(end 139.088622 -34.658046)
		(width 0.14224)
		(layer "In4.Cu")
		(net "M_H_DQ<56>")
	)
	(segment
		(start 144.752568 -24.927306)
		(end 144.549368 -24.724106)
		(width 0.14224)
		(layer "In4.Cu")
		(net "M_H_DQ<56>")
	)
	(segment
		(start 129.256028 -45.21962)
		(end 138.568684 -35.906964)
		(width 0.14224)
		(layer "In4.Cu")
		(net "M_H_DQ<56>")
	)
	(segment
		(start 144.974564 -18.662142)
		(end 144.631664 -18.319242)
		(width 0.14224)
		(layer "In4.Cu")
		(net "M_H_DQ<56>")
	)
	(segment
		(start 138.568684 -35.906964)
		(end 138.568684 -35.48888)
		(width 0.14224)
		(layer "In4.Cu")
		(net "M_H_DQ<56>")
	)
	(segment
		(start 144.164812 -12.9286)
		(end 144.901412 -12.192)
		(width 0.14224)
		(layer "In4.Cu")
		(net "M_H_DQ<56>")
	)
	(segment
		(start 144.549368 -26.349706)
		(end 144.549368 -25.943306)
		(width 0.14224)
		(layer "In4.Cu")
		(net "M_H_DQ<56>")
	)
	(segment
		(start 144.48663 -10.1092)
		(end 144.48663 -9.779254)
		(width 0.14224)
		(layer "In4.Cu")
		(net "M_H_DQ<56>")
	)
	(segment
		(start 119.704358 -56.695086)
		(end 119.695468 -56.679846)
		(width 0.0889)
		(layer "In4.Cu")
		(net "M_H_DQ<56>")
	)
	(segment
		(start 144.974564 -21.683472)
		(end 144.974564 -18.662142)
		(width 0.14224)
		(layer "In4.Cu")
		(net "M_H_DQ<56>")
	)
	(segment
		(start 118.499382 -59.371484)
		(end 118.004082 -58.705496)
		(width 0.0889)
		(layer "In4.Cu")
		(net "M_H_DQ<56>")
	)
	(segment
		(start 144.943068 -23.398226)
		(end 144.942052 -23.398226)
		(width 0.14224)
		(layer "In4.Cu")
		(net "M_H_DQ<56>")
	)
	(segment
		(start 139.511786 -34.033714)
		(end 139.113768 -33.635696)
		(width 0.14224)
		(layer "In4.Cu")
		(net "M_H_DQ<56>")
	)
	(segment
		(start 144.631664 -17.118076)
		(end 144.923764 -16.825976)
		(width 0.14224)
		(layer "In4.Cu")
		(net "M_H_DQ<56>")
	)
	(segment
		(start 144.82953 -10.6807)
		(end 144.82953 -10.4521)
		(width 0.14224)
		(layer "In4.Cu")
		(net "M_H_DQ<56>")
	)
	(arc
		(start 119.357902 -57.295034)
		(mid 119.704328 -57.095057)
		(end 119.704358 -56.695086)
		(width 0.0889)
		(layer "In4.Cu")
		(net "M_H_DQ<56>")
	)
	(arc
		(start 119.704358 -54.123336)
		(mid 119.757828 -53.928273)
		(end 119.709184 -53.731922)
		(width 0.0889)
		(layer "In4.Cu")
		(net "M_H_DQ<56>")
	)
	(arc
		(start 119.695468 -56.679846)
		(mid 119.625071 -56.390895)
		(end 119.704358 -56.104282)
		(width 0.0889)
		(layer "In4.Cu")
		(net "M_H_DQ<56>")
	)
	(arc
		(start 120.227344 -51.846988)
		(mid 120.421194 -51.790638)
		(end 120.562878 -51.646836)
		(width 0.0889)
		(layer "In4.Cu")
		(net "M_H_DQ<56>")
	)
	(arc
		(start 119.698008 -53.712618)
		(mid 119.62521 -53.421855)
		(end 119.704358 -53.132736)
		(width 0.0889)
		(layer "In4.Cu")
		(net "M_H_DQ<56>")
	)
	(arc
		(start 119.704358 -55.113682)
		(mid 119.757891 -54.913784)
		(end 119.704358 -54.713886)
		(width 0.0889)
		(layer "In4.Cu")
		(net "M_H_DQ<56>")
	)
	(arc
		(start 119.698008 -52.722018)
		(mid 119.702039 -52.145836)
		(end 120.194578 -51.846988)
		(width 0.0889)
		(layer "In4.Cu")
		(net "M_H_DQ<56>")
	)
	(arc
		(start 118.846092 -57.590436)
		(mid 119.0547 -57.378504)
		(end 119.340122 -57.295034)
		(width 0.0889)
		(layer "In4.Cu")
		(net "M_H_DQ<56>")
	)
	(arc
		(start 117.987572 -58.67654)
		(mid 117.982318 -58.095032)
		(end 118.477792 -57.790588)
		(width 0.0889)
		(layer "In4.Cu")
		(net "M_H_DQ<56>")
	)
	(arc
		(start 119.695468 -55.689246)
		(mid 119.625071 -55.400295)
		(end 119.704358 -55.113682)
		(width 0.0889)
		(layer "In4.Cu")
		(net "M_H_DQ<56>")
	)
	(arc
		(start 118.510558 -57.790588)
		(mid 118.704408 -57.734238)
		(end 118.846092 -57.590436)
		(width 0.0889)
		(layer "In4.Cu")
		(net "M_H_DQ<56>")
	)
	(arc
		(start 119.704358 -53.132736)
		(mid 119.757828 -52.937673)
		(end 119.709184 -52.741322)
		(width 0.0889)
		(layer "In4.Cu")
		(net "M_H_DQ<56>")
	)
	(arc
		(start 119.704358 -56.104282)
		(mid 119.757891 -55.904384)
		(end 119.704358 -55.704486)
		(width 0.0889)
		(layer "In4.Cu")
		(net "M_H_DQ<56>")
	)
	(arc
		(start 119.698008 -54.703218)
		(mid 119.62521 -54.412455)
		(end 119.704358 -54.123336)
		(width 0.0889)
		(layer "In4.Cu")
		(net "M_H_DQ<56>")
	)
	(segment
		(start 123.295918 -47.944024)
		(end 130.131058 -47.944024)
		(width 0.1016)
		(layer "F.Cu")
		(net "M_H_DQ<55>")
	)
	(segment
		(start 139.743434 -28.163266)
		(end 139.743434 -27.713686)
		(width 0.1651)
		(layer "F.Cu")
		(net "M_H_DQ<55>")
	)
	(segment
		(start 135.024368 -43.050714)
		(end 135.024368 -42.921428)
		(width 0.1016)
		(layer "F.Cu")
		(net "M_H_DQ<55>")
	)
	(segment
		(start 141.007338 -36.938458)
		(end 141.007338 -35.306)
		(width 0.1651)
		(layer "F.Cu")
		(net "M_H_DQ<55>")
	)
	(segment
		(start 130.131058 -47.944024)
		(end 135.024368 -43.050714)
		(width 0.1016)
		(layer "F.Cu")
		(net "M_H_DQ<55>")
	)
	(segment
		(start 135.024368 -42.921428)
		(end 141.007338 -36.938458)
		(width 0.1651)
		(layer "F.Cu")
		(net "M_H_DQ<55>")
	)
	(segment
		(start 139.743434 -27.713686)
		(end 140.199364 -27.257756)
		(width 0.1651)
		(layer "F.Cu")
		(net "M_H_DQ<55>")
	)
	(segment
		(start 141.007338 -35.306)
		(end 141.007338 -33.36417)
		(width 0.1651)
		(layer "F.Cu")
		(net "M_H_DQ<55>")
	)
	(segment
		(start 141.007338 -33.36417)
		(end 139.977368 -32.3342)
		(width 0.1651)
		(layer "F.Cu")
		(net "M_H_DQ<55>")
	)
	(segment
		(start 139.977368 -28.3972)
		(end 139.743434 -28.163266)
		(width 0.1651)
		(layer "F.Cu")
		(net "M_H_DQ<55>")
	)
	(segment
		(start 120.304052 -53.548534)
		(end 120.304052 -50.505868)
		(width 0.0889)
		(layer "F.Cu")
		(net "M_H_DQ<55>")
	)
	(segment
		(start 120.304052 -50.505868)
		(end 120.619266 -50.190654)
		(width 0.0889)
		(layer "F.Cu")
		(net "M_H_DQ<55>")
	)
	(segment
		(start 121.049288 -50.190654)
		(end 121.12371 -50.116232)
		(width 0.0889)
		(layer "F.Cu")
		(net "M_H_DQ<55>")
	)
	(segment
		(start 121.12371 -50.116232)
		(end 123.295918 -47.944024)
		(width 0.1016)
		(layer "F.Cu")
		(net "M_H_DQ<55>")
	)
	(segment
		(start 119.929402 -53.923184)
		(end 120.304052 -53.548534)
		(width 0.0889)
		(layer "F.Cu")
		(net "M_H_DQ<55>")
	)
	(segment
		(start 139.34948 -5.822442)
		(end 139.34948 -7.086346)
		(width 0.1651)
		(layer "F.Cu")
		(net "M_H_DQ<55>")
	)
	(segment
		(start 139.977368 -32.3342)
		(end 139.977368 -28.3972)
		(width 0.1651)
		(layer "F.Cu")
		(net "M_H_DQ<55>")
	)
	(segment
		(start 120.619266 -50.190654)
		(end 121.049288 -50.190654)
		(width 0.0889)
		(layer "F.Cu")
		(net "M_H_DQ<55>")
	)
	(via
		(at 141.007338 -35.306)
		(size 0.508)
		(drill 0.254)
		(layers "F.Cu" "B.Cu")
		(net "M_H_DQ<55>")
	)
	(via
		(at 139.34948 -7.086346)
		(size 0.508)
		(drill 0.254)
		(layers "F.Cu" "B.Cu")
		(net "M_H_DQ<55>")
	)
	(via
		(at 140.199364 -27.257756)
		(size 0.508)
		(drill 0.254)
		(layers "F.Cu" "B.Cu")
		(net "M_H_DQ<55>")
	)
	(via
		(at 140.199364 -12.678156)
		(size 0.508)
		(drill 0.254)
		(layers "F.Cu" "B.Cu")
		(net "M_H_DQ<55>")
	)
	(segment
		(start 140.199364 -10.623042)
		(end 140.199364 -12.678156)
		(width 0.1651)
		(layer "B.Cu")
		(net "M_H_DQ<55>")
	)
	(segment
		(start 140.410438 -16.710914)
		(end 140.715238 -17.015714)
		(width 0.14224)
		(layer "In4.Cu")
		(net "M_H_DQ<55>")
	)
	(segment
		(start 139.666218 -7.403084)
		(end 139.666218 -7.7216)
		(width 0.14224)
		(layer "In4.Cu")
		(net "M_H_DQ<55>")
	)
	(segment
		(start 140.740638 -23.117048)
		(end 140.562838 -23.294848)
		(width 0.14224)
		(layer "In4.Cu")
		(net "M_H_DQ<55>")
	)
	(segment
		(start 140.715238 -17.015714)
		(end 140.715238 -18.38833)
		(width 0.14224)
		(layer "In4.Cu")
		(net "M_H_DQ<55>")
	)
	(segment
		(start 139.996418 -8.0518)
		(end 140.250418 -8.0518)
		(width 0.14224)
		(layer "In4.Cu")
		(net "M_H_DQ<55>")
	)
	(segment
		(start 140.562838 -23.294848)
		(end 140.562838 -26.894282)
		(width 0.14224)
		(layer "In4.Cu")
		(net "M_H_DQ<55>")
	)
	(segment
		(start 140.707618 -8.8646)
		(end 140.55217 -9.020048)
		(width 0.14224)
		(layer "In4.Cu")
		(net "M_H_DQ<55>")
	)
	(segment
		(start 140.529564 -21.804122)
		(end 140.740638 -22.015196)
		(width 0.14224)
		(layer "In4.Cu")
		(net "M_H_DQ<55>")
	)
	(segment
		(start 139.666218 -7.7216)
		(end 139.996418 -8.0518)
		(width 0.14224)
		(layer "In4.Cu")
		(net "M_H_DQ<55>")
	)
	(segment
		(start 140.55217 -12.32535)
		(end 140.199364 -12.678156)
		(width 0.14224)
		(layer "In4.Cu")
		(net "M_H_DQ<55>")
	)
	(segment
		(start 140.562838 -26.894282)
		(end 140.199364 -27.257756)
		(width 0.14224)
		(layer "In4.Cu")
		(net "M_H_DQ<55>")
	)
	(segment
		(start 140.529564 -18.574004)
		(end 140.529564 -21.804122)
		(width 0.14224)
		(layer "In4.Cu")
		(net "M_H_DQ<55>")
	)
	(segment
		(start 140.740638 -22.015196)
		(end 140.740638 -23.117048)
		(width 0.14224)
		(layer "In4.Cu")
		(net "M_H_DQ<55>")
	)
	(segment
		(start 140.707618 -8.509)
		(end 140.707618 -8.8646)
		(width 0.14224)
		(layer "In4.Cu")
		(net "M_H_DQ<55>")
	)
	(segment
		(start 140.55217 -9.020048)
		(end 140.55217 -12.32535)
		(width 0.14224)
		(layer "In4.Cu")
		(net "M_H_DQ<55>")
	)
	(segment
		(start 139.742164 -13.135356)
		(end 139.742164 -13.60043)
		(width 0.14224)
		(layer "In4.Cu")
		(net "M_H_DQ<55>")
	)
	(segment
		(start 140.715238 -18.38833)
		(end 140.529564 -18.574004)
		(width 0.14224)
		(layer "In4.Cu")
		(net "M_H_DQ<55>")
	)
	(segment
		(start 140.410438 -14.268704)
		(end 140.410438 -16.710914)
		(width 0.14224)
		(layer "In4.Cu")
		(net "M_H_DQ<55>")
	)
	(segment
		(start 139.742164 -13.60043)
		(end 140.410438 -14.268704)
		(width 0.14224)
		(layer "In4.Cu")
		(net "M_H_DQ<55>")
	)
	(segment
		(start 140.199364 -12.678156)
		(end 139.742164 -13.135356)
		(width 0.14224)
		(layer "In4.Cu")
		(net "M_H_DQ<55>")
	)
	(segment
		(start 139.34948 -7.086346)
		(end 139.666218 -7.403084)
		(width 0.14224)
		(layer "In4.Cu")
		(net "M_H_DQ<55>")
	)
	(segment
		(start 140.250418 -8.0518)
		(end 140.707618 -8.509)
		(width 0.14224)
		(layer "In4.Cu")
		(net "M_H_DQ<55>")
	)
	(segment
		(start 140.199618 -9.4488)
		(end 140.331698 -9.31672)
		(width 0.1651)
		(layer "F.Cu")
		(net "M_H_DQ<54>")
	)
	(segment
		(start 120.113552 -50.426874)
		(end 120.540272 -50.000154)
		(width 0.0889)
		(layer "F.Cu")
		(net "M_H_DQ<54>")
	)
	(segment
		(start 140.199364 -10.422382)
		(end 140.199618 -10.422128)
		(width 0.1651)
		(layer "F.Cu")
		(net "M_H_DQ<54>")
	)
	(segment
		(start 120.682766 -50.000154)
		(end 120.888506 -49.794414)
		(width 0.0889)
		(layer "F.Cu")
		(net "M_H_DQ<54>")
	)
	(segment
		(start 140.331698 -9.09828)
		(end 140.199618 -8.9662)
		(width 0.1651)
		(layer "F.Cu")
		(net "M_H_DQ<54>")
	)
	(segment
		(start 139.186412 -36.542726)
		(end 140.202412 -36.542726)
		(width 0.1651)
		(layer "F.Cu")
		(net "M_H_DQ<54>")
	)
	(segment
		(start 123.132596 -47.550324)
		(end 129.967736 -47.550324)
		(width 0.1016)
		(layer "F.Cu")
		(net "M_H_DQ<54>")
	)
	(segment
		(start 140.199618 -8.661654)
		(end 140.199364 -8.6614)
		(width 0.1651)
		(layer "F.Cu")
		(net "M_H_DQ<54>")
	)
	(segment
		(start 140.367512 -34.1249)
		(end 140.202412 -33.9598)
		(width 0.1651)
		(layer "F.Cu")
		(net "M_H_DQ<54>")
	)
	(segment
		(start 140.331698 -9.31672)
		(end 140.331698 -9.09828)
		(width 0.1651)
		(layer "F.Cu")
		(net "M_H_DQ<54>")
	)
	(segment
		(start 140.202412 -36.542726)
		(end 140.367512 -36.377626)
		(width 0.1651)
		(layer "F.Cu")
		(net "M_H_DQ<54>")
	)
	(segment
		(start 139.021312 -36.707826)
		(end 139.186412 -36.542726)
		(width 0.1651)
		(layer "F.Cu")
		(net "M_H_DQ<54>")
	)
	(segment
		(start 140.202412 -33.9598)
		(end 139.859512 -33.9598)
		(width 0.1651)
		(layer "F.Cu")
		(net "M_H_DQ<54>")
	)
	(segment
		(start 139.021312 -30.607)
		(end 139.021312 -29.27731)
		(width 0.1651)
		(layer "F.Cu")
		(net "M_H_DQ<54>")
	)
	(segment
		(start 139.021312 -29.27731)
		(end 139.34948 -28.949142)
		(width 0.1651)
		(layer "F.Cu")
		(net "M_H_DQ<54>")
	)
	(segment
		(start 134.541768 -42.976292)
		(end 134.541768 -42.499026)
		(width 0.1016)
		(layer "F.Cu")
		(net "M_H_DQ<54>")
	)
	(segment
		(start 120.540272 -50.000154)
		(end 120.682766 -50.000154)
		(width 0.0889)
		(layer "F.Cu")
		(net "M_H_DQ<54>")
	)
	(segment
		(start 140.199618 -8.9662)
		(end 140.199618 -8.661654)
		(width 0.1651)
		(layer "F.Cu")
		(net "M_H_DQ<54>")
	)
	(segment
		(start 140.367512 -36.377626)
		(end 140.367512 -34.1249)
		(width 0.1651)
		(layer "F.Cu")
		(net "M_H_DQ<54>")
	)
	(segment
		(start 140.199618 -10.422128)
		(end 140.199618 -9.4488)
		(width 0.1651)
		(layer "F.Cu")
		(net "M_H_DQ<54>")
	)
	(segment
		(start 139.859512 -33.9598)
		(end 139.694412 -34.1249)
		(width 0.1651)
		(layer "F.Cu")
		(net "M_H_DQ<54>")
	)
	(segment
		(start 139.694412 -34.1249)
		(end 139.694412 -34.8361)
		(width 0.1651)
		(layer "F.Cu")
		(net "M_H_DQ<54>")
	)
	(segment
		(start 129.967736 -47.550324)
		(end 134.541768 -42.976292)
		(width 0.1016)
		(layer "F.Cu")
		(net "M_H_DQ<54>")
	)
	(segment
		(start 139.694412 -34.8361)
		(end 139.529312 -35.0012)
		(width 0.1651)
		(layer "F.Cu")
		(net "M_H_DQ<54>")
	)
	(segment
		(start 139.186412 -35.0012)
		(end 139.021312 -34.8361)
		(width 0.1651)
		(layer "F.Cu")
		(net "M_H_DQ<54>")
	)
	(segment
		(start 139.021312 -38.019482)
		(end 139.021312 -36.707826)
		(width 0.1651)
		(layer "F.Cu")
		(net "M_H_DQ<54>")
	)
	(segment
		(start 134.541768 -42.499026)
		(end 139.021312 -38.019482)
		(width 0.1651)
		(layer "F.Cu")
		(net "M_H_DQ<54>")
	)
	(segment
		(start 120.888506 -49.794414)
		(end 123.132596 -47.550324)
		(width 0.1016)
		(layer "F.Cu")
		(net "M_H_DQ<54>")
	)
	(segment
		(start 119.929402 -51.941984)
		(end 120.113552 -51.757834)
		(width 0.0889)
		(layer "F.Cu")
		(net "M_H_DQ<54>")
	)
	(segment
		(start 120.113552 -51.757834)
		(end 120.113552 -50.426874)
		(width 0.0889)
		(layer "F.Cu")
		(net "M_H_DQ<54>")
	)
	(segment
		(start 139.021312 -34.8361)
		(end 139.021312 -30.607)
		(width 0.1651)
		(layer "F.Cu")
		(net "M_H_DQ<54>")
	)
	(segment
		(start 139.529312 -35.0012)
		(end 139.186412 -35.0012)
		(width 0.1651)
		(layer "F.Cu")
		(net "M_H_DQ<54>")
	)
	(segment
		(start 139.34948 -28.949142)
		(end 139.34948 -28.538678)
		(width 0.1651)
		(layer "F.Cu")
		(net "M_H_DQ<54>")
	)
	(via
		(at 139.021312 -30.607)
		(size 0.508)
		(drill 0.254)
		(layers "F.Cu" "B.Cu")
		(net "M_H_DQ<54>")
	)
	(via
		(at 140.199364 -8.6614)
		(size 0.508)
		(drill 0.254)
		(layers "F.Cu" "B.Cu")
		(net "M_H_DQ<54>")
	)
	(via
		(at 139.34948 -13.959078)
		(size 0.508)
		(drill 0.254)
		(layers "F.Cu" "B.Cu")
		(net "M_H_DQ<54>")
	)
	(via
		(at 139.34948 -28.538678)
		(size 0.508)
		(drill 0.254)
		(layers "F.Cu" "B.Cu")
		(net "M_H_DQ<54>")
	)
	(segment
		(start 139.34948 -15.222982)
		(end 139.34948 -13.959078)
		(width 0.1651)
		(layer "B.Cu")
		(net "M_H_DQ<54>")
	)
	(segment
		(start 139.34948 -13.959078)
		(end 139.851638 -14.461236)
		(width 0.14224)
		(layer "In4.Cu")
		(net "M_H_DQ<54>")
	)
	(segment
		(start 139.841986 -10.369296)
		(end 139.841986 -10.712704)
		(width 0.14224)
		(layer "In4.Cu")
		(net "M_H_DQ<54>")
	)
	(segment
		(start 139.648438 -18.41627)
		(end 139.843764 -18.611596)
		(width 0.14224)
		(layer "In4.Cu")
		(net "M_H_DQ<54>")
	)
	(segment
		(start 139.460986 -11.093704)
		(end 139.460986 -11.378946)
		(width 0.14224)
		(layer "In4.Cu")
		(net "M_H_DQ<54>")
	)
	(segment
		(start 139.34948 -27.970734)
		(end 139.34948 -28.538678)
		(width 0.14224)
		(layer "In4.Cu")
		(net "M_H_DQ<54>")
	)
	(segment
		(start 139.648438 -23.132796)
		(end 139.927838 -23.412196)
		(width 0.14224)
		(layer "In4.Cu")
		(net "M_H_DQ<54>")
	)
	(segment
		(start 139.886436 -12.156186)
		(end 139.113768 -12.928854)
		(width 0.14224)
		(layer "In4.Cu")
		(net "M_H_DQ<54>")
	)
	(segment
		(start 139.843764 -18.611596)
		(end 139.843764 -21.84527)
		(width 0.14224)
		(layer "In4.Cu")
		(net "M_H_DQ<54>")
	)
	(segment
		(start 139.617958 -26.92273)
		(end 139.617958 -27.702256)
		(width 0.14224)
		(layer "In4.Cu")
		(net "M_H_DQ<54>")
	)
	(segment
		(start 139.113768 -13.723366)
		(end 139.34948 -13.959078)
		(width 0.14224)
		(layer "In4.Cu")
		(net "M_H_DQ<54>")
	)
	(segment
		(start 139.927838 -23.412196)
		(end 139.927838 -26.61285)
		(width 0.14224)
		(layer "In4.Cu")
		(net "M_H_DQ<54>")
	)
	(segment
		(start 139.460986 -9.677654)
		(end 139.460986 -9.988296)
		(width 0.14224)
		(layer "In4.Cu")
		(net "M_H_DQ<54>")
	)
	(segment
		(start 139.851638 -14.461236)
		(end 139.851638 -16.850106)
		(width 0.14224)
		(layer "In4.Cu")
		(net "M_H_DQ<54>")
	)
	(segment
		(start 139.460986 -9.988296)
		(end 139.841986 -10.369296)
		(width 0.14224)
		(layer "In4.Cu")
		(net "M_H_DQ<54>")
	)
	(segment
		(start 140.199364 -8.6614)
		(end 139.824968 -9.035796)
		(width 0.14224)
		(layer "In4.Cu")
		(net "M_H_DQ<54>")
	)
	(segment
		(start 139.551664 -27.768296)
		(end 139.34948 -27.970734)
		(width 0.14224)
		(layer "In4.Cu")
		(net "M_H_DQ<54>")
	)
	(segment
		(start 139.841986 -10.712704)
		(end 139.460986 -11.093704)
		(width 0.14224)
		(layer "In4.Cu")
		(net "M_H_DQ<54>")
	)
	(segment
		(start 139.648438 -22.040596)
		(end 139.648438 -23.132796)
		(width 0.14224)
		(layer "In4.Cu")
		(net "M_H_DQ<54>")
	)
	(segment
		(start 139.851638 -16.850106)
		(end 139.648438 -17.053306)
		(width 0.14224)
		(layer "In4.Cu")
		(net "M_H_DQ<54>")
	)
	(segment
		(start 139.824968 -9.313672)
		(end 139.460986 -9.677654)
		(width 0.14224)
		(layer "In4.Cu")
		(net "M_H_DQ<54>")
	)
	(segment
		(start 139.617958 -27.702256)
		(end 139.551664 -27.768296)
		(width 0.14224)
		(layer "In4.Cu")
		(net "M_H_DQ<54>")
	)
	(segment
		(start 139.824968 -9.035796)
		(end 139.824968 -9.313672)
		(width 0.14224)
		(layer "In4.Cu")
		(net "M_H_DQ<54>")
	)
	(segment
		(start 139.113768 -12.928854)
		(end 139.113768 -13.723366)
		(width 0.14224)
		(layer "In4.Cu")
		(net "M_H_DQ<54>")
	)
	(segment
		(start 139.927838 -26.61285)
		(end 139.617958 -26.92273)
		(width 0.14224)
		(layer "In4.Cu")
		(net "M_H_DQ<54>")
	)
	(segment
		(start 139.648438 -17.053306)
		(end 139.648438 -18.41627)
		(width 0.14224)
		(layer "In4.Cu")
		(net "M_H_DQ<54>")
	)
	(segment
		(start 139.843764 -21.84527)
		(end 139.648438 -22.040596)
		(width 0.14224)
		(layer "In4.Cu")
		(net "M_H_DQ<54>")
	)
	(segment
		(start 139.460986 -11.378946)
		(end 139.886436 -11.804396)
		(width 0.14224)
		(layer "In4.Cu")
		(net "M_H_DQ<54>")
	)
	(segment
		(start 139.886436 -11.804396)
		(end 139.886436 -12.156186)
		(width 0.14224)
		(layer "In4.Cu")
		(net "M_H_DQ<54>")
	)
	(segment
		(start 133.39953 -5.822442)
		(end 133.39953 -7.086346)
		(width 0.1651)
		(layer "F.Cu")
		(net "M_H_DQ<53>")
	)
	(segment
		(start 132.457952 -38.177216)
		(end 132.457952 -37.997384)
		(width 0.1651)
		(layer "F.Cu")
		(net "M_H_DQ<53>")
	)
	(segment
		(start 130.44424 -42.359072)
		(end 130.44424 -40.190928)
		(width 0.1651)
		(layer "F.Cu")
		(net "M_H_DQ<53>")
	)
	(segment
		(start 121.989342 -44.794424)
		(end 128.824482 -44.794424)
		(width 0.1016)
		(layer "F.Cu")
		(net "M_H_DQ<53>")
	)
	(segment
		(start 133.835394 -29.408374)
		(end 134.105142 -29.138626)
		(width 0.1651)
		(layer "F.Cu")
		(net "M_H_DQ<53>")
	)
	(segment
		(start 117.08511 -51.086004)
		(end 117.08511 -50.769266)
		(width 0.0889)
		(layer "F.Cu")
		(net "M_H_DQ<53>")
	)
	(segment
		(start 131.47548 -37.862256)
		(end 131.172712 -37.559488)
		(width 0.1651)
		(layer "F.Cu")
		(net "M_H_DQ<53>")
	)
	(segment
		(start 130.44424 -40.190928)
		(end 132.457952 -38.177216)
		(width 0.1651)
		(layer "F.Cu")
		(net "M_H_DQ<53>")
	)
	(segment
		(start 117.08638 -51.757326)
		(end 117.08638 -51.940714)
		(width 0.0889)
		(layer "F.Cu")
		(net "M_H_DQ<53>")
	)
	(segment
		(start 131.172712 -37.344096)
		(end 133.835394 -34.681414)
		(width 0.1651)
		(layer "F.Cu")
		(net "M_H_DQ<53>")
	)
	(segment
		(start 117.454172 -49.538382)
		(end 117.454172 -49.217834)
		(width 0.0889)
		(layer "F.Cu")
		(net "M_H_DQ<53>")
	)
	(segment
		(start 117.642132 -49.141634)
		(end 121.989342 -44.794424)
		(width 0.1016)
		(layer "F.Cu")
		(net "M_H_DQ<53>")
	)
	(segment
		(start 134.105142 -29.138626)
		(end 134.105142 -28.519374)
		(width 0.1651)
		(layer "F.Cu")
		(net "M_H_DQ<53>")
	)
	(segment
		(start 116.929916 -50.062638)
		(end 117.454172 -49.538382)
		(width 0.0889)
		(layer "F.Cu")
		(net "M_H_DQ<53>")
	)
	(segment
		(start 117.530372 -49.141634)
		(end 117.642132 -49.141634)
		(width 0.0889)
		(layer "F.Cu")
		(net "M_H_DQ<53>")
	)
	(segment
		(start 133.671564 -28.085796)
		(end 133.671564 -27.759406)
		(width 0.1651)
		(layer "F.Cu")
		(net "M_H_DQ<53>")
	)
	(segment
		(start 133.835394 -34.681414)
		(end 133.835394 -31.75)
		(width 0.1651)
		(layer "F.Cu")
		(net "M_H_DQ<53>")
	)
	(segment
		(start 132.457952 -37.997384)
		(end 132.078984 -37.618416)
		(width 0.1651)
		(layer "F.Cu")
		(net "M_H_DQ<53>")
	)
	(segment
		(start 116.929916 -50.50028)
		(end 116.929916 -50.062638)
		(width 0.0889)
		(layer "F.Cu")
		(net "M_H_DQ<53>")
	)
	(segment
		(start 128.824482 -44.794424)
		(end 130.44424 -43.174666)
		(width 0.1016)
		(layer "F.Cu")
		(net "M_H_DQ<53>")
	)
	(segment
		(start 132.078984 -37.618416)
		(end 131.899152 -37.618416)
		(width 0.1651)
		(layer "F.Cu")
		(net "M_H_DQ<53>")
	)
	(segment
		(start 116.967254 -51.290474)
		(end 117.08511 -51.086004)
		(width 0.0889)
		(layer "F.Cu")
		(net "M_H_DQ<53>")
	)
	(segment
		(start 131.899152 -37.618416)
		(end 131.655312 -37.862256)
		(width 0.1651)
		(layer "F.Cu")
		(net "M_H_DQ<53>")
	)
	(segment
		(start 131.172712 -37.559488)
		(end 131.172712 -37.344096)
		(width 0.1651)
		(layer "F.Cu")
		(net "M_H_DQ<53>")
	)
	(segment
		(start 134.105142 -28.519374)
		(end 133.671564 -28.085796)
		(width 0.1651)
		(layer "F.Cu")
		(net "M_H_DQ<53>")
	)
	(segment
		(start 118.212362 -53.923184)
		(end 117.88267 -53.161946)
		(width 0.0889)
		(layer "F.Cu")
		(net "M_H_DQ<53>")
	)
	(segment
		(start 130.44424 -43.174666)
		(end 130.44424 -42.359072)
		(width 0.1016)
		(layer "F.Cu")
		(net "M_H_DQ<53>")
	)
	(segment
		(start 131.655312 -37.862256)
		(end 131.47548 -37.862256)
		(width 0.1651)
		(layer "F.Cu")
		(net "M_H_DQ<53>")
	)
	(segment
		(start 117.88267 -53.161946)
		(end 117.865652 -53.132736)
		(width 0.0889)
		(layer "F.Cu")
		(net "M_H_DQ<53>")
	)
	(segment
		(start 133.835394 -31.75)
		(end 133.835394 -29.408374)
		(width 0.1651)
		(layer "F.Cu")
		(net "M_H_DQ<53>")
	)
	(segment
		(start 133.671564 -27.759406)
		(end 134.173214 -27.257756)
		(width 0.1651)
		(layer "F.Cu")
		(net "M_H_DQ<53>")
	)
	(segment
		(start 117.08511 -50.769266)
		(end 116.929916 -50.50028)
		(width 0.0889)
		(layer "F.Cu")
		(net "M_H_DQ<53>")
	)
	(segment
		(start 117.454172 -49.217834)
		(end 117.530372 -49.141634)
		(width 0.0889)
		(layer "F.Cu")
		(net "M_H_DQ<53>")
	)
	(segment
		(start 116.967254 -51.550824)
		(end 116.967254 -51.290474)
		(width 0.0889)
		(layer "F.Cu")
		(net "M_H_DQ<53>")
	)
	(segment
		(start 117.08638 -51.757326)
		(end 116.967254 -51.550824)
		(width 0.0889)
		(layer "F.Cu")
		(net "M_H_DQ<53>")
	)
	(segment
		(start 117.371622 -52.837334)
		(end 117.335808 -52.837334)
		(width 0.0889)
		(layer "F.Cu")
		(net "M_H_DQ<53>")
	)
	(via
		(at 134.173214 -12.678156)
		(size 0.508)
		(drill 0.254)
		(layers "F.Cu" "B.Cu")
		(net "M_H_DQ<53>")
	)
	(via
		(at 133.39953 -7.086346)
		(size 0.508)
		(drill 0.254)
		(layers "F.Cu" "B.Cu")
		(net "M_H_DQ<53>")
	)
	(via
		(at 133.835394 -31.75)
		(size 0.508)
		(drill 0.254)
		(layers "F.Cu" "B.Cu")
		(net "M_H_DQ<53>")
	)
	(via
		(at 134.173214 -27.257756)
		(size 0.508)
		(drill 0.254)
		(layers "F.Cu" "B.Cu")
		(net "M_H_DQ<53>")
	)
	(arc
		(start 117.865652 -53.132736)
		(mid 117.657044 -52.920804)
		(end 117.371622 -52.837334)
		(width 0.0889)
		(layer "F.Cu")
		(net "M_H_DQ<53>")
	)
	(arc
		(start 117.007132 -52.237386)
		(mid 117.066363 -52.094287)
		(end 117.08638 -51.940714)
		(width 0.0889)
		(layer "F.Cu")
		(net "M_H_DQ<53>")
	)
	(arc
		(start 117.335808 -52.837334)
		(mid 117.002839 -52.629786)
		(end 117.007132 -52.237386)
		(width 0.0889)
		(layer "F.Cu")
		(net "M_H_DQ<53>")
	)
	(segment
		(start 134.249414 -10.623042)
		(end 134.249414 -12.601956)
		(width 0.1651)
		(layer "B.Cu")
		(net "M_H_DQ<53>")
	)
	(segment
		(start 134.249414 -12.601956)
		(end 134.173214 -12.678156)
		(width 0.1651)
		(layer "B.Cu")
		(net "M_H_DQ<53>")
	)
	(segment
		(start 134.681468 -8.8646)
		(end 134.484618 -9.06145)
		(width 0.14224)
		(layer "In4.Cu")
		(net "M_H_DQ<53>")
	)
	(segment
		(start 134.593838 -26.837132)
		(end 134.173214 -27.257756)
		(width 0.14224)
		(layer "In4.Cu")
		(net "M_H_DQ<53>")
	)
	(segment
		(start 133.652768 -7.339584)
		(end 133.652768 -7.7343)
		(width 0.14224)
		(layer "In4.Cu")
		(net "M_H_DQ<53>")
	)
	(segment
		(start 134.568438 -21.862796)
		(end 134.670038 -21.964396)
		(width 0.14224)
		(layer "In4.Cu")
		(net "M_H_DQ<53>")
	)
	(segment
		(start 134.484618 -9.06145)
		(end 134.484618 -12.366752)
		(width 0.14224)
		(layer "In4.Cu")
		(net "M_H_DQ<53>")
	)
	(segment
		(start 134.568438 -18.531586)
		(end 134.568438 -21.862796)
		(width 0.14224)
		(layer "In4.Cu")
		(net "M_H_DQ<53>")
	)
	(segment
		(start 133.970268 -8.0518)
		(end 134.281164 -8.0518)
		(width 0.14224)
		(layer "In4.Cu")
		(net "M_H_DQ<53>")
	)
	(segment
		(start 134.484618 -12.366752)
		(end 134.173214 -12.678156)
		(width 0.14224)
		(layer "In4.Cu")
		(net "M_H_DQ<53>")
	)
	(segment
		(start 134.440168 -14.5542)
		(end 134.440168 -16.7894)
		(width 0.14224)
		(layer "In4.Cu")
		(net "M_H_DQ<53>")
	)
	(segment
		(start 134.173214 -14.287246)
		(end 134.440168 -14.5542)
		(width 0.14224)
		(layer "In4.Cu")
		(net "M_H_DQ<53>")
	)
	(segment
		(start 134.681468 -8.452104)
		(end 134.681468 -8.8646)
		(width 0.14224)
		(layer "In4.Cu")
		(net "M_H_DQ<53>")
	)
	(segment
		(start 134.644638 -18.455386)
		(end 134.568438 -18.531586)
		(width 0.14224)
		(layer "In4.Cu")
		(net "M_H_DQ<53>")
	)
	(segment
		(start 133.652768 -7.7343)
		(end 133.970268 -8.0518)
		(width 0.14224)
		(layer "In4.Cu")
		(net "M_H_DQ<53>")
	)
	(segment
		(start 134.644638 -16.99387)
		(end 134.644638 -18.455386)
		(width 0.14224)
		(layer "In4.Cu")
		(net "M_H_DQ<53>")
	)
	(segment
		(start 134.670038 -23.158196)
		(end 134.593838 -23.234396)
		(width 0.14224)
		(layer "In4.Cu")
		(net "M_H_DQ<53>")
	)
	(segment
		(start 133.39953 -7.086346)
		(end 133.652768 -7.339584)
		(width 0.14224)
		(layer "In4.Cu")
		(net "M_H_DQ<53>")
	)
	(segment
		(start 134.173214 -12.678156)
		(end 134.173214 -14.287246)
		(width 0.14224)
		(layer "In4.Cu")
		(net "M_H_DQ<53>")
	)
	(segment
		(start 134.593838 -23.234396)
		(end 134.593838 -26.837132)
		(width 0.14224)
		(layer "In4.Cu")
		(net "M_H_DQ<53>")
	)
	(segment
		(start 134.670038 -21.964396)
		(end 134.670038 -23.158196)
		(width 0.14224)
		(layer "In4.Cu")
		(net "M_H_DQ<53>")
	)
	(segment
		(start 134.440168 -16.7894)
		(end 134.644638 -16.99387)
		(width 0.14224)
		(layer "In4.Cu")
		(net "M_H_DQ<53>")
	)
	(segment
		(start 134.281164 -8.0518)
		(end 134.681468 -8.452104)
		(width 0.14224)
		(layer "In4.Cu")
		(net "M_H_DQ<53>")
	)
	(segment
		(start 129.7559 -39.513256)
		(end 129.98958 -39.513256)
		(width 0.1651)
		(layer "F.Cu")
		(net "M_H_DQ<52>")
	)
	(segment
		(start 117.263672 -49.138586)
		(end 117.367812 -49.034446)
		(width 0.0889)
		(layer "F.Cu")
		(net "M_H_DQ<52>")
	)
	(segment
		(start 134.21233 -8.89)
		(end 134.188962 -8.763)
		(width 0.1651)
		(layer "F.Cu")
		(net "M_H_DQ<52>")
	)
	(segment
		(start 116.776754 -51.236626)
		(end 116.89461 -51.032156)
		(width 0.0889)
		(layer "F.Cu")
		(net "M_H_DQ<52>")
	)
	(segment
		(start 116.739416 -49.98339)
		(end 117.263672 -49.459134)
		(width 0.0889)
		(layer "F.Cu")
		(net "M_H_DQ<52>")
	)
	(segment
		(start 130.532124 -38.057836)
		(end 129.98958 -38.60038)
		(width 0.1651)
		(layer "F.Cu")
		(net "M_H_DQ<52>")
	)
	(segment
		(start 129.79654 -40.466772)
		(end 129.069084 -39.739316)
		(width 0.1651)
		(layer "F.Cu")
		(net "M_H_DQ<52>")
	)
	(segment
		(start 134.249414 -10.422382)
		(end 134.249414 -9.091168)
		(width 0.1651)
		(layer "F.Cu")
		(net "M_H_DQ<52>")
	)
	(segment
		(start 129.7559 -38.60038)
		(end 129.513584 -38.358064)
		(width 0.1651)
		(layer "F.Cu")
		(net "M_H_DQ<52>")
	)
	(segment
		(start 134.249414 -9.091168)
		(end 134.21233 -8.89)
		(width 0.1651)
		(layer "F.Cu")
		(net "M_H_DQ<52>")
	)
	(segment
		(start 116.89461 -50.82032)
		(end 116.739416 -50.551588)
		(width 0.0889)
		(layer "F.Cu")
		(net "M_H_DQ<52>")
	)
	(segment
		(start 129.513584 -38.358064)
		(end 129.513584 -38.097968)
		(width 0.1651)
		(layer "F.Cu")
		(net "M_H_DQ<52>")
	)
	(segment
		(start 134.188962 -8.763)
		(end 134.15137 -8.5598)
		(width 0.1651)
		(layer "F.Cu")
		(net "M_H_DQ<52>")
	)
	(segment
		(start 133.195568 -28.727146)
		(end 133.384036 -28.538678)
		(width 0.1651)
		(layer "F.Cu")
		(net "M_H_DQ<52>")
	)
	(segment
		(start 130.765804 -38.057836)
		(end 130.532124 -38.057836)
		(width 0.1651)
		(layer "F.Cu")
		(net "M_H_DQ<52>")
	)
	(segment
		(start 116.776754 -51.608482)
		(end 116.776754 -51.236626)
		(width 0.0889)
		(layer "F.Cu")
		(net "M_H_DQ<52>")
	)
	(segment
		(start 128.66116 -44.400724)
		(end 129.79654 -43.265344)
		(width 0.1016)
		(layer "F.Cu")
		(net "M_H_DQ<52>")
	)
	(segment
		(start 129.98958 -38.60038)
		(end 129.7559 -38.60038)
		(width 0.1651)
		(layer "F.Cu")
		(net "M_H_DQ<52>")
	)
	(segment
		(start 116.89461 -51.032156)
		(end 116.89461 -50.82032)
		(width 0.0889)
		(layer "F.Cu")
		(net "M_H_DQ<52>")
	)
	(segment
		(start 130.988562 -38.280594)
		(end 130.765804 -38.057836)
		(width 0.1651)
		(layer "F.Cu")
		(net "M_H_DQ<52>")
	)
	(segment
		(start 129.069084 -39.739316)
		(end 129.069084 -39.559484)
		(width 0.1651)
		(layer "F.Cu")
		(net "M_H_DQ<52>")
	)
	(segment
		(start 129.552446 -39.309802)
		(end 129.7559 -39.513256)
		(width 0.1651)
		(layer "F.Cu")
		(net "M_H_DQ<52>")
	)
	(segment
		(start 116.858542 -52.761896)
		(end 116.842032 -52.73294)
		(width 0.0889)
		(layer "F.Cu")
		(net "M_H_DQ<52>")
	)
	(segment
		(start 133.195568 -33.655)
		(end 133.195568 -28.727146)
		(width 0.1651)
		(layer "F.Cu")
		(net "M_H_DQ<52>")
	)
	(segment
		(start 129.79654 -43.265344)
		(end 129.79654 -42.498772)
		(width 0.1016)
		(layer "F.Cu")
		(net "M_H_DQ<52>")
	)
	(segment
		(start 117.367812 -49.034446)
		(end 117.367812 -48.858932)
		(width 0.0889)
		(layer "F.Cu")
		(net "M_H_DQ<52>")
	)
	(segment
		(start 117.263672 -49.459134)
		(end 117.263672 -49.138586)
		(width 0.0889)
		(layer "F.Cu")
		(net "M_H_DQ<52>")
	)
	(segment
		(start 129.318766 -39.309802)
		(end 129.552446 -39.309802)
		(width 0.1651)
		(layer "F.Cu")
		(net "M_H_DQ<52>")
	)
	(segment
		(start 117.367812 -48.858932)
		(end 121.82602 -44.400724)
		(width 0.1016)
		(layer "F.Cu")
		(net "M_H_DQ<52>")
	)
	(segment
		(start 130.988562 -38.514274)
		(end 130.988562 -38.280594)
		(width 0.1651)
		(layer "F.Cu")
		(net "M_H_DQ<52>")
	)
	(segment
		(start 129.79654 -42.498772)
		(end 129.79654 -40.466772)
		(width 0.1651)
		(layer "F.Cu")
		(net "M_H_DQ<52>")
	)
	(segment
		(start 116.895626 -51.814222)
		(end 116.776754 -51.608482)
		(width 0.0889)
		(layer "F.Cu")
		(net "M_H_DQ<52>")
	)
	(segment
		(start 121.82602 -44.400724)
		(end 128.66116 -44.400724)
		(width 0.1016)
		(layer "F.Cu")
		(net "M_H_DQ<52>")
	)
	(segment
		(start 129.513584 -38.097968)
		(end 133.195568 -34.415984)
		(width 0.1651)
		(layer "F.Cu")
		(net "M_H_DQ<52>")
	)
	(segment
		(start 116.895626 -51.941476)
		(end 116.895626 -51.814222)
		(width 0.0889)
		(layer "F.Cu")
		(net "M_H_DQ<52>")
	)
	(segment
		(start 133.195568 -34.415984)
		(end 133.195568 -33.655)
		(width 0.1651)
		(layer "F.Cu")
		(net "M_H_DQ<52>")
	)
	(segment
		(start 116.739416 -50.551588)
		(end 116.739416 -49.98339)
		(width 0.0889)
		(layer "F.Cu")
		(net "M_H_DQ<52>")
	)
	(segment
		(start 129.98958 -39.513256)
		(end 130.988562 -38.514274)
		(width 0.1651)
		(layer "F.Cu")
		(net "M_H_DQ<52>")
	)
	(segment
		(start 129.069084 -39.559484)
		(end 129.318766 -39.309802)
		(width 0.1651)
		(layer "F.Cu")
		(net "M_H_DQ<52>")
	)
	(segment
		(start 117.353842 -53.427884)
		(end 116.858542 -52.761896)
		(width 0.0889)
		(layer "F.Cu")
		(net "M_H_DQ<52>")
	)
	(via
		(at 133.384036 -28.538678)
		(size 0.508)
		(drill 0.254)
		(layers "F.Cu" "B.Cu")
		(net "M_H_DQ<52>")
	)
	(via
		(at 134.15137 -8.5598)
		(size 0.508)
		(drill 0.254)
		(layers "F.Cu" "B.Cu")
		(net "M_H_DQ<52>")
	)
	(via
		(at 133.39953 -13.959078)
		(size 0.508)
		(drill 0.254)
		(layers "F.Cu" "B.Cu")
		(net "M_H_DQ<52>")
	)
	(via
		(at 133.195568 -33.655)
		(size 0.508)
		(drill 0.254)
		(layers "F.Cu" "B.Cu")
		(net "M_H_DQ<52>")
	)
	(arc
		(start 116.842032 -52.142136)
		(mid 116.882085 -52.045344)
		(end 116.895626 -51.941476)
		(width 0.0889)
		(layer "F.Cu")
		(net "M_H_DQ<52>")
	)
	(arc
		(start 116.842032 -52.73294)
		(mid 116.762901 -52.437538)
		(end 116.842032 -52.142136)
		(width 0.0889)
		(layer "F.Cu")
		(net "M_H_DQ<52>")
	)
	(segment
		(start 133.39953 -15.222982)
		(end 133.39953 -13.959078)
		(width 0.1651)
		(layer "B.Cu")
		(net "M_H_DQ<52>")
	)
	(segment
		(start 133.875018 -12.217654)
		(end 133.875018 -11.652504)
		(width 0.14224)
		(layer "In4.Cu")
		(net "M_H_DQ<52>")
	)
	(segment
		(start 133.671564 -26.89987)
		(end 133.882638 -26.688796)
		(width 0.14224)
		(layer "In4.Cu")
		(net "M_H_DQ<52>")
	)
	(segment
		(start 133.666738 -21.951696)
		(end 133.701028 -21.91766)
		(width 0.14224)
		(layer "In4.Cu")
		(net "M_H_DQ<52>")
	)
	(segment
		(start 133.875018 -8.836152)
		(end 134.15137 -8.5598)
		(width 0.14224)
		(layer "In4.Cu")
		(net "M_H_DQ<52>")
	)
	(segment
		(start 133.882638 -23.369524)
		(end 133.666738 -23.153624)
		(width 0.14224)
		(layer "In4.Cu")
		(net "M_H_DQ<52>")
	)
	(segment
		(start 133.39953 -14.453362)
		(end 133.39953 -13.959078)
		(width 0.14224)
		(layer "In4.Cu")
		(net "M_H_DQ<52>")
	)
	(segment
		(start 133.511036 -10.069068)
		(end 133.511036 -9.793478)
		(width 0.14224)
		(layer "In4.Cu")
		(net "M_H_DQ<52>")
	)
	(segment
		(start 133.666738 -23.153624)
		(end 133.666738 -21.951696)
		(width 0.14224)
		(layer "In4.Cu")
		(net "M_H_DQ<52>")
	)
	(segment
		(start 133.39953 -13.959078)
		(end 133.678168 -13.68044)
		(width 0.14224)
		(layer "In4.Cu")
		(net "M_H_DQ<52>")
	)
	(segment
		(start 133.701028 -21.91766)
		(end 133.882638 -21.735796)
		(width 0.14224)
		(layer "In4.Cu")
		(net "M_H_DQ<52>")
	)
	(segment
		(start 133.671564 -28.266644)
		(end 133.671564 -26.89987)
		(width 0.14224)
		(layer "In4.Cu")
		(net "M_H_DQ<52>")
	)
	(segment
		(start 133.892036 -10.297668)
		(end 133.749034 -10.154666)
		(width 0.14224)
		(layer "In4.Cu")
		(net "M_H_DQ<52>")
	)
	(segment
		(start 133.875018 -11.652504)
		(end 133.523736 -11.301222)
		(width 0.14224)
		(layer "In4.Cu")
		(net "M_H_DQ<52>")
	)
	(segment
		(start 133.678168 -12.414504)
		(end 133.875018 -12.217654)
		(width 0.14224)
		(layer "In4.Cu")
		(net "M_H_DQ<52>")
	)
	(segment
		(start 133.678168 -13.68044)
		(end 133.678168 -12.414504)
		(width 0.14224)
		(layer "In4.Cu")
		(net "M_H_DQ<52>")
	)
	(segment
		(start 133.787134 -10.838434)
		(end 133.892036 -10.733532)
		(width 0.14224)
		(layer "In4.Cu")
		(net "M_H_DQ<52>")
	)
	(segment
		(start 133.523736 -11.301222)
		(end 133.523736 -10.924032)
		(width 0.14224)
		(layer "In4.Cu")
		(net "M_H_DQ<52>")
	)
	(segment
		(start 133.39953 -28.538678)
		(end 133.671564 -28.266644)
		(width 0.14224)
		(layer "In4.Cu")
		(net "M_H_DQ<52>")
	)
	(segment
		(start 133.882638 -18.531586)
		(end 133.666738 -18.315686)
		(width 0.14224)
		(layer "In4.Cu")
		(net "M_H_DQ<52>")
	)
	(segment
		(start 133.882638 -14.93647)
		(end 133.39953 -14.453362)
		(width 0.14224)
		(layer "In4.Cu")
		(net "M_H_DQ<52>")
	)
	(segment
		(start 133.511036 -9.793478)
		(end 133.875018 -9.429496)
		(width 0.14224)
		(layer "In4.Cu")
		(net "M_H_DQ<52>")
	)
	(segment
		(start 133.882638 -21.735796)
		(end 133.882638 -18.531586)
		(width 0.14224)
		(layer "In4.Cu")
		(net "M_H_DQ<52>")
	)
	(segment
		(start 133.892036 -10.733532)
		(end 133.892036 -10.297668)
		(width 0.14224)
		(layer "In4.Cu")
		(net "M_H_DQ<52>")
	)
	(segment
		(start 133.666738 -17.05483)
		(end 133.882638 -16.83893)
		(width 0.14224)
		(layer "In4.Cu")
		(net "M_H_DQ<52>")
	)
	(segment
		(start 133.596634 -10.154666)
		(end 133.511036 -10.069068)
		(width 0.14224)
		(layer "In4.Cu")
		(net "M_H_DQ<52>")
	)
	(segment
		(start 133.882638 -26.688796)
		(end 133.882638 -23.369524)
		(width 0.14224)
		(layer "In4.Cu")
		(net "M_H_DQ<52>")
	)
	(segment
		(start 133.523736 -10.924032)
		(end 133.609334 -10.838434)
		(width 0.14224)
		(layer "In4.Cu")
		(net "M_H_DQ<52>")
	)
	(segment
		(start 133.384036 -28.538678)
		(end 133.39953 -28.538678)
		(width 0.14224)
		(layer "In4.Cu")
		(net "M_H_DQ<52>")
	)
	(segment
		(start 133.882638 -16.83893)
		(end 133.882638 -14.93647)
		(width 0.14224)
		(layer "In4.Cu")
		(net "M_H_DQ<52>")
	)
	(segment
		(start 133.666738 -18.315686)
		(end 133.666738 -17.05483)
		(width 0.14224)
		(layer "In4.Cu")
		(net "M_H_DQ<52>")
	)
	(segment
		(start 133.875018 -9.429496)
		(end 133.875018 -8.836152)
		(width 0.14224)
		(layer "In4.Cu")
		(net "M_H_DQ<52>")
	)
	(segment
		(start 133.609334 -10.838434)
		(end 133.787134 -10.838434)
		(width 0.14224)
		(layer "In4.Cu")
		(net "M_H_DQ<52>")
	)
	(segment
		(start 133.749034 -10.154666)
		(end 133.596634 -10.154666)
		(width 0.14224)
		(layer "In4.Cu")
		(net "M_H_DQ<52>")
	)
	(segment
		(start 141.48308 -27.257756)
		(end 141.899386 -27.257756)
		(width 0.1651)
		(layer "F.Cu")
		(net "M_H_DQ<51>")
	)
	(segment
		(start 123.622562 -48.731424)
		(end 130.457702 -48.731424)
		(width 0.1016)
		(layer "F.Cu")
		(net "M_H_DQ<51>")
	)
	(segment
		(start 142.293594 -35.687)
		(end 142.293594 -33.386522)
		(width 0.1651)
		(layer "F.Cu")
		(net "M_H_DQ<51>")
	)
	(segment
		(start 141.049502 -5.822442)
		(end 141.049502 -7.086346)
		(width 0.1651)
		(layer "F.Cu")
		(net "M_H_DQ<51>")
	)
	(segment
		(start 142.54734 -30.531054)
		(end 141.577568 -29.561282)
		(width 0.1651)
		(layer "F.Cu")
		(net "M_H_DQ<51>")
	)
	(segment
		(start 142.293594 -37.462714)
		(end 142.293594 -35.687)
		(width 0.1651)
		(layer "F.Cu")
		(net "M_H_DQ<51>")
	)
	(segment
		(start 120.787668 -53.427884)
		(end 121.117868 -52.665884)
		(width 0.0889)
		(layer "F.Cu")
		(net "M_H_DQ<51>")
	)
	(segment
		(start 121.664476 -50.589434)
		(end 121.80951 -50.4444)
		(width 0.0889)
		(layer "F.Cu")
		(net "M_H_DQ<51>")
	)
	(segment
		(start 141.196568 -27.544268)
		(end 141.48308 -27.257756)
		(width 0.1651)
		(layer "F.Cu")
		(net "M_H_DQ<51>")
	)
	(segment
		(start 121.909586 -50.4444)
		(end 123.622562 -48.731424)
		(width 0.1016)
		(layer "F.Cu")
		(net "M_H_DQ<51>")
	)
	(segment
		(start 142.293594 -33.386522)
		(end 142.54734 -33.132776)
		(width 0.1651)
		(layer "F.Cu")
		(net "M_H_DQ<51>")
	)
	(segment
		(start 141.577568 -29.561282)
		(end 141.577568 -28.372054)
		(width 0.1651)
		(layer "F.Cu")
		(net "M_H_DQ<51>")
	)
	(segment
		(start 135.094726 -44.0944)
		(end 135.661908 -44.0944)
		(width 0.1016)
		(layer "F.Cu")
		(net "M_H_DQ<51>")
	)
	(segment
		(start 121.664476 -51.10861)
		(end 121.664476 -50.589434)
		(width 0.0889)
		(layer "F.Cu")
		(net "M_H_DQ<51>")
	)
	(segment
		(start 142.54734 -33.132776)
		(end 142.54734 -30.531054)
		(width 0.1651)
		(layer "F.Cu")
		(net "M_H_DQ<51>")
	)
	(segment
		(start 121.117868 -52.665884)
		(end 121.139204 -52.6288)
		(width 0.0889)
		(layer "F.Cu")
		(net "M_H_DQ<51>")
	)
	(segment
		(start 130.457702 -48.731424)
		(end 135.094726 -44.0944)
		(width 0.1016)
		(layer "F.Cu")
		(net "M_H_DQ<51>")
	)
	(segment
		(start 135.661908 -44.0944)
		(end 142.293594 -37.462714)
		(width 0.1651)
		(layer "F.Cu")
		(net "M_H_DQ<51>")
	)
	(segment
		(start 141.196568 -27.991054)
		(end 141.196568 -27.544268)
		(width 0.1651)
		(layer "F.Cu")
		(net "M_H_DQ<51>")
	)
	(segment
		(start 141.577568 -28.372054)
		(end 141.196568 -27.991054)
		(width 0.1651)
		(layer "F.Cu")
		(net "M_H_DQ<51>")
	)
	(segment
		(start 121.80951 -50.4444)
		(end 121.909586 -50.4444)
		(width 0.0889)
		(layer "F.Cu")
		(net "M_H_DQ<51>")
	)
	(segment
		(start 121.134378 -52.237386)
		(end 121.299478 -51.742086)
		(width 0.0889)
		(layer "F.Cu")
		(net "M_H_DQ<51>")
	)
	(segment
		(start 121.299478 -51.742086)
		(end 121.664476 -51.10861)
		(width 0.0889)
		(layer "F.Cu")
		(net "M_H_DQ<51>")
	)
	(via
		(at 141.049502 -7.086346)
		(size 0.508)
		(drill 0.254)
		(layers "F.Cu" "B.Cu")
		(net "M_H_DQ<51>")
	)
	(via
		(at 141.899386 -27.257756)
		(size 0.508)
		(drill 0.254)
		(layers "F.Cu" "B.Cu")
		(net "M_H_DQ<51>")
	)
	(via
		(at 141.899386 -12.678156)
		(size 0.508)
		(drill 0.254)
		(layers "F.Cu" "B.Cu")
		(net "M_H_DQ<51>")
	)
	(via
		(at 142.293594 -35.687)
		(size 0.508)
		(drill 0.254)
		(layers "F.Cu" "B.Cu")
		(net "M_H_DQ<51>")
	)
	(arc
		(start 121.139204 -52.6288)
		(mid 121.187959 -52.432448)
		(end 121.134378 -52.237386)
		(width 0.0889)
		(layer "F.Cu")
		(net "M_H_DQ<51>")
	)
	(segment
		(start 141.899386 -10.623042)
		(end 141.899386 -12.678156)
		(width 0.1651)
		(layer "B.Cu")
		(net "M_H_DQ<51>")
	)
	(segment
		(start 142.40764 -8.509)
		(end 142.40764 -8.8646)
		(width 0.14224)
		(layer "In4.Cu")
		(net "M_H_DQ<51>")
	)
	(segment
		(start 142.213838 -26.943304)
		(end 141.899386 -27.257756)
		(width 0.14224)
		(layer "In4.Cu")
		(net "M_H_DQ<51>")
	)
	(segment
		(start 141.354302 -13.22324)
		(end 141.354302 -13.510768)
		(width 0.14224)
		(layer "In4.Cu")
		(net "M_H_DQ<51>")
	)
	(segment
		(start 142.391638 -18.38833)
		(end 142.213838 -18.56613)
		(width 0.14224)
		(layer "In4.Cu")
		(net "M_H_DQ<51>")
	)
	(segment
		(start 142.292324 -16.913352)
		(end 142.391638 -17.012666)
		(width 0.14224)
		(layer "In4.Cu")
		(net "M_H_DQ<51>")
	)
	(segment
		(start 142.252192 -12.32535)
		(end 141.899386 -12.678156)
		(width 0.14224)
		(layer "In4.Cu")
		(net "M_H_DQ<51>")
	)
	(segment
		(start 142.40764 -8.8646)
		(end 142.252192 -9.020048)
		(width 0.14224)
		(layer "In4.Cu")
		(net "M_H_DQ<51>")
	)
	(segment
		(start 141.354302 -13.510768)
		(end 141.809724 -13.96619)
		(width 0.14224)
		(layer "In4.Cu")
		(net "M_H_DQ<51>")
	)
	(segment
		(start 142.391638 -17.012666)
		(end 142.391638 -18.38833)
		(width 0.14224)
		(layer "In4.Cu")
		(net "M_H_DQ<51>")
	)
	(segment
		(start 141.899386 -12.678156)
		(end 141.354302 -13.22324)
		(width 0.14224)
		(layer "In4.Cu")
		(net "M_H_DQ<51>")
	)
	(segment
		(start 141.809724 -15.70101)
		(end 142.292324 -16.18361)
		(width 0.14224)
		(layer "In4.Cu")
		(net "M_H_DQ<51>")
	)
	(segment
		(start 142.213838 -21.791676)
		(end 142.391638 -21.969476)
		(width 0.14224)
		(layer "In4.Cu")
		(net "M_H_DQ<51>")
	)
	(segment
		(start 142.252192 -9.020048)
		(end 142.252192 -12.32535)
		(width 0.14224)
		(layer "In4.Cu")
		(net "M_H_DQ<51>")
	)
	(segment
		(start 141.049502 -7.086346)
		(end 141.36624 -7.403084)
		(width 0.14224)
		(layer "In4.Cu")
		(net "M_H_DQ<51>")
	)
	(segment
		(start 141.36624 -7.403084)
		(end 141.36624 -7.7216)
		(width 0.14224)
		(layer "In4.Cu")
		(net "M_H_DQ<51>")
	)
	(segment
		(start 141.69644 -8.0518)
		(end 141.95044 -8.0518)
		(width 0.14224)
		(layer "In4.Cu")
		(net "M_H_DQ<51>")
	)
	(segment
		(start 142.391638 -23.200868)
		(end 142.213838 -23.378668)
		(width 0.14224)
		(layer "In4.Cu")
		(net "M_H_DQ<51>")
	)
	(segment
		(start 141.809724 -13.96619)
		(end 141.809724 -15.70101)
		(width 0.14224)
		(layer "In4.Cu")
		(net "M_H_DQ<51>")
	)
	(segment
		(start 142.292324 -16.18361)
		(end 142.292324 -16.913352)
		(width 0.14224)
		(layer "In4.Cu")
		(net "M_H_DQ<51>")
	)
	(segment
		(start 141.95044 -8.0518)
		(end 142.40764 -8.509)
		(width 0.14224)
		(layer "In4.Cu")
		(net "M_H_DQ<51>")
	)
	(segment
		(start 142.391638 -21.969476)
		(end 142.391638 -23.200868)
		(width 0.14224)
		(layer "In4.Cu")
		(net "M_H_DQ<51>")
	)
	(segment
		(start 142.213838 -18.56613)
		(end 142.213838 -21.791676)
		(width 0.14224)
		(layer "In4.Cu")
		(net "M_H_DQ<51>")
	)
	(segment
		(start 142.213838 -23.378668)
		(end 142.213838 -26.943304)
		(width 0.14224)
		(layer "In4.Cu")
		(net "M_H_DQ<51>")
	)
	(segment
		(start 141.36624 -7.7216)
		(end 141.69644 -8.0518)
		(width 0.14224)
		(layer "In4.Cu")
		(net "M_H_DQ<51>")
	)
	(segment
		(start 140.779246 -32.1818)
		(end 140.617194 -32.019748)
		(width 0.1651)
		(layer "F.Cu")
		(net "M_H_DQ<50>")
	)
	(segment
		(start 141.653768 -33.909)
		(end 141.653768 -33.121346)
		(width 0.1651)
		(layer "F.Cu")
		(net "M_H_DQ<50>")
	)
	(segment
		(start 141.907514 -31.2166)
		(end 141.780514 -31.0896)
		(width 0.1651)
		(layer "F.Cu")
		(net "M_H_DQ<50>")
	)
	(segment
		(start 141.653768 -37.197284)
		(end 141.653768 -33.909)
		(width 0.1651)
		(layer "F.Cu")
		(net "M_H_DQ<50>")
	)
	(segment
		(start 141.262354 -31.2166)
		(end 141.262354 -32.0548)
		(width 0.1651)
		(layer "F.Cu")
		(net "M_H_DQ<50>")
	)
	(segment
		(start 140.617194 -32.019748)
		(end 140.617194 -28.970986)
		(width 0.1651)
		(layer "F.Cu")
		(net "M_H_DQ<50>")
	)
	(segment
		(start 135.366252 -43.4848)
		(end 141.653768 -37.197284)
		(width 0.1651)
		(layer "F.Cu")
		(net "M_H_DQ<50>")
	)
	(segment
		(start 142.030958 -9.29386)
		(end 142.030958 -9.07034)
		(width 0.1651)
		(layer "F.Cu")
		(net "M_H_DQ<50>")
	)
	(segment
		(start 140.617194 -28.970986)
		(end 141.049502 -28.538678)
		(width 0.1651)
		(layer "F.Cu")
		(net "M_H_DQ<50>")
	)
	(segment
		(start 141.899386 -8.938768)
		(end 141.899386 -8.6614)
		(width 0.1651)
		(layer "F.Cu")
		(net "M_H_DQ<50>")
	)
	(segment
		(start 141.780514 -31.0896)
		(end 141.389354 -31.0896)
		(width 0.1651)
		(layer "F.Cu")
		(net "M_H_DQ<50>")
	)
	(segment
		(start 141.389354 -31.0896)
		(end 141.262354 -31.2166)
		(width 0.1651)
		(layer "F.Cu")
		(net "M_H_DQ<50>")
	)
	(segment
		(start 130.29438 -48.337724)
		(end 134.958836 -43.673268)
		(width 0.1016)
		(layer "F.Cu")
		(net "M_H_DQ<50>")
	)
	(segment
		(start 141.899386 -10.422382)
		(end 141.899386 -9.425432)
		(width 0.1651)
		(layer "F.Cu")
		(net "M_H_DQ<50>")
	)
	(segment
		(start 141.653768 -33.121346)
		(end 141.907514 -32.8676)
		(width 0.1651)
		(layer "F.Cu")
		(net "M_H_DQ<50>")
	)
	(segment
		(start 121.473976 -50.322988)
		(end 121.711466 -50.085498)
		(width 0.0889)
		(layer "F.Cu")
		(net "M_H_DQ<50>")
	)
	(segment
		(start 142.030958 -9.07034)
		(end 141.899386 -8.938768)
		(width 0.1651)
		(layer "F.Cu")
		(net "M_H_DQ<50>")
	)
	(segment
		(start 141.262354 -32.0548)
		(end 141.135354 -32.1818)
		(width 0.1651)
		(layer "F.Cu")
		(net "M_H_DQ<50>")
	)
	(segment
		(start 120.787668 -52.437538)
		(end 121.100342 -51.715416)
		(width 0.0889)
		(layer "F.Cu")
		(net "M_H_DQ<50>")
	)
	(segment
		(start 141.135354 -32.1818)
		(end 140.779246 -32.1818)
		(width 0.1651)
		(layer "F.Cu")
		(net "M_H_DQ<50>")
	)
	(segment
		(start 135.177784 -43.673268)
		(end 135.366252 -43.4848)
		(width 0.1016)
		(layer "F.Cu")
		(net "M_H_DQ<50>")
	)
	(segment
		(start 141.899386 -9.425432)
		(end 142.030958 -9.29386)
		(width 0.1651)
		(layer "F.Cu")
		(net "M_H_DQ<50>")
	)
	(segment
		(start 121.473976 -51.055524)
		(end 121.473976 -50.322988)
		(width 0.0889)
		(layer "F.Cu")
		(net "M_H_DQ<50>")
	)
	(segment
		(start 123.45924 -48.337724)
		(end 130.29438 -48.337724)
		(width 0.1016)
		(layer "F.Cu")
		(net "M_H_DQ<50>")
	)
	(segment
		(start 141.907514 -32.8676)
		(end 141.907514 -31.2166)
		(width 0.1651)
		(layer "F.Cu")
		(net "M_H_DQ<50>")
	)
	(segment
		(start 121.134378 -51.646582)
		(end 121.473976 -51.055524)
		(width 0.0889)
		(layer "F.Cu")
		(net "M_H_DQ<50>")
	)
	(segment
		(start 134.958836 -43.673268)
		(end 135.177784 -43.673268)
		(width 0.1016)
		(layer "F.Cu")
		(net "M_H_DQ<50>")
	)
	(segment
		(start 121.711466 -50.085498)
		(end 123.45924 -48.337724)
		(width 0.1016)
		(layer "F.Cu")
		(net "M_H_DQ<50>")
	)
	(via
		(at 141.653768 -33.909)
		(size 0.508)
		(drill 0.254)
		(layers "F.Cu" "B.Cu")
		(net "M_H_DQ<50>")
	)
	(via
		(at 141.049502 -28.538678)
		(size 0.508)
		(drill 0.254)
		(layers "F.Cu" "B.Cu")
		(net "M_H_DQ<50>")
	)
	(via
		(at 141.899386 -8.6614)
		(size 0.508)
		(drill 0.254)
		(layers "F.Cu" "B.Cu")
		(net "M_H_DQ<50>")
	)
	(via
		(at 141.049502 -13.959078)
		(size 0.508)
		(drill 0.254)
		(layers "F.Cu" "B.Cu")
		(net "M_H_DQ<50>")
	)
	(arc
		(start 121.100342 -51.715416)
		(mid 121.116248 -51.680449)
		(end 121.134378 -51.646582)
		(width 0.0889)
		(layer "F.Cu")
		(net "M_H_DQ<50>")
	)
	(segment
		(start 141.049502 -15.222982)
		(end 141.049502 -13.959078)
		(width 0.1651)
		(layer "B.Cu")
		(net "M_H_DQ<50>")
	)
	(segment
		(start 141.553438 -23.344124)
		(end 141.553438 -26.658316)
		(width 0.14224)
		(layer "In4.Cu")
		(net "M_H_DQ<50>")
	)
	(segment
		(start 141.393164 -21.97227)
		(end 141.393164 -23.18385)
		(width 0.14224)
		(layer "In4.Cu")
		(net "M_H_DQ<50>")
	)
	(segment
		(start 141.049502 -28.124658)
		(end 141.049502 -28.538678)
		(width 0.14224)
		(layer "In4.Cu")
		(net "M_H_DQ<50>")
	)
	(segment
		(start 141.393164 -26.81859)
		(end 141.393164 -27.780996)
		(width 0.14224)
		(layer "In4.Cu")
		(net "M_H_DQ<50>")
	)
	(segment
		(start 141.501368 -9.059418)
		(end 141.501368 -9.364472)
		(width 0.14224)
		(layer "In4.Cu")
		(net "M_H_DQ<50>")
	)
	(segment
		(start 141.156436 -10.95375)
		(end 141.156436 -11.3538)
		(width 0.14224)
		(layer "In4.Cu")
		(net "M_H_DQ<50>")
	)
	(segment
		(start 140.764768 -12.9286)
		(end 140.764768 -13.674344)
		(width 0.14224)
		(layer "In4.Cu")
		(net "M_H_DQ<50>")
	)
	(segment
		(start 141.506702 -16.893794)
		(end 141.375638 -17.024858)
		(width 0.14224)
		(layer "In4.Cu")
		(net "M_H_DQ<50>")
	)
	(segment
		(start 141.461236 -10.64895)
		(end 141.156436 -10.95375)
		(width 0.14224)
		(layer "In4.Cu")
		(net "M_H_DQ<50>")
	)
	(segment
		(start 141.501368 -9.364472)
		(end 141.156436 -9.709404)
		(width 0.14224)
		(layer "In4.Cu")
		(net "M_H_DQ<50>")
	)
	(segment
		(start 141.375638 -18.39087)
		(end 141.578838 -18.59407)
		(width 0.14224)
		(layer "In4.Cu")
		(net "M_H_DQ<50>")
	)
	(segment
		(start 141.899386 -8.6614)
		(end 141.501368 -9.059418)
		(width 0.14224)
		(layer "In4.Cu")
		(net "M_H_DQ<50>")
	)
	(segment
		(start 141.461236 -10.362946)
		(end 141.461236 -10.64895)
		(width 0.14224)
		(layer "In4.Cu")
		(net "M_H_DQ<50>")
	)
	(segment
		(start 141.156436 -11.3538)
		(end 141.613636 -11.811)
		(width 0.14224)
		(layer "In4.Cu")
		(net "M_H_DQ<50>")
	)
	(segment
		(start 141.156436 -9.709404)
		(end 141.156436 -10.058146)
		(width 0.14224)
		(layer "In4.Cu")
		(net "M_H_DQ<50>")
	)
	(segment
		(start 141.613636 -11.811)
		(end 141.613636 -12.079732)
		(width 0.14224)
		(layer "In4.Cu")
		(net "M_H_DQ<50>")
	)
	(segment
		(start 141.049502 -13.959078)
		(end 141.049502 -16.040608)
		(width 0.14224)
		(layer "In4.Cu")
		(net "M_H_DQ<50>")
	)
	(segment
		(start 141.393164 -27.780996)
		(end 141.049502 -28.124658)
		(width 0.14224)
		(layer "In4.Cu")
		(net "M_H_DQ<50>")
	)
	(segment
		(start 141.393164 -23.18385)
		(end 141.553438 -23.344124)
		(width 0.14224)
		(layer "In4.Cu")
		(net "M_H_DQ<50>")
	)
	(segment
		(start 141.049502 -16.040608)
		(end 141.506702 -16.497808)
		(width 0.14224)
		(layer "In4.Cu")
		(net "M_H_DQ<50>")
	)
	(segment
		(start 141.375638 -17.024858)
		(end 141.375638 -18.39087)
		(width 0.14224)
		(layer "In4.Cu")
		(net "M_H_DQ<50>")
	)
	(segment
		(start 141.553438 -26.658316)
		(end 141.393164 -26.81859)
		(width 0.14224)
		(layer "In4.Cu")
		(net "M_H_DQ<50>")
	)
	(segment
		(start 140.764768 -13.674344)
		(end 141.049502 -13.959078)
		(width 0.14224)
		(layer "In4.Cu")
		(net "M_H_DQ<50>")
	)
	(segment
		(start 141.578838 -21.786596)
		(end 141.393164 -21.97227)
		(width 0.14224)
		(layer "In4.Cu")
		(net "M_H_DQ<50>")
	)
	(segment
		(start 141.578838 -18.59407)
		(end 141.578838 -21.786596)
		(width 0.14224)
		(layer "In4.Cu")
		(net "M_H_DQ<50>")
	)
	(segment
		(start 141.506702 -16.497808)
		(end 141.506702 -16.893794)
		(width 0.14224)
		(layer "In4.Cu")
		(net "M_H_DQ<50>")
	)
	(segment
		(start 141.156436 -10.058146)
		(end 141.461236 -10.362946)
		(width 0.14224)
		(layer "In4.Cu")
		(net "M_H_DQ<50>")
	)
	(segment
		(start 141.613636 -12.079732)
		(end 140.764768 -12.9286)
		(width 0.14224)
		(layer "In4.Cu")
		(net "M_H_DQ<50>")
	)
	(segment
		(start 32.249364 -9.091168)
		(end 32.188912 -8.763)
		(width 0.1651)
		(layer "F.Cu")
		(net "M_H_DQ<4>")
	)
	(segment
		(start 32.188912 -8.763)
		(end 32.15132 -8.5598)
		(width 0.1651)
		(layer "F.Cu")
		(net "M_H_DQ<4>")
	)
	(segment
		(start 32.249364 -10.422382)
		(end 32.249364 -9.091168)
		(width 0.1651)
		(layer "F.Cu")
		(net "M_H_DQ<4>")
	)
	(segment
		(start 72.900286 -68.46824)
		(end 72.328786 -68.46824)
		(width 0.0889)
		(layer "F.Cu")
		(net "M_H_DQ<4>")
	)
	(via
		(at 72.328786 -68.46824)
		(size 0.508)
		(drill 0.254)
		(layers "F.Cu" "B.Cu")
		(net "M_H_DQ<4>")
	)
	(via
		(at 31.39948 -13.959078)
		(size 0.508)
		(drill 0.254)
		(layers "F.Cu" "B.Cu")
		(net "M_H_DQ<4>")
	)
	(via
		(at 32.15132 -8.5598)
		(size 0.508)
		(drill 0.254)
		(layers "F.Cu" "B.Cu")
		(net "M_H_DQ<4>")
	)
	(segment
		(start 31.39948 -15.222982)
		(end 31.39948 -13.959078)
		(width 0.1651)
		(layer "B.Cu")
		(net "M_H_DQ<4>")
	)
	(segment
		(start 31.163768 -12.928854)
		(end 31.874968 -12.217654)
		(width 0.14224)
		(layer "In4.Cu")
		(net "M_H_DQ<4>")
	)
	(segment
		(start 31.891986 -10.668)
		(end 31.891986 -10.3632)
		(width 0.14224)
		(layer "In4.Cu")
		(net "M_H_DQ<4>")
	)
	(segment
		(start 71.45909 -69.553836)
		(end 71.491856 -69.553836)
		(width 0.0889)
		(layer "In4.Cu")
		(net "M_H_DQ<4>")
	)
	(segment
		(start 31.39948 -13.959078)
		(end 31.163768 -13.723366)
		(width 0.14224)
		(layer "In4.Cu")
		(net "M_H_DQ<4>")
	)
	(segment
		(start 67.609212 -69.662294)
		(end 67.692016 -69.57949)
		(width 0.0889)
		(layer "In4.Cu")
		(net "M_H_DQ<4>")
	)
	(segment
		(start 31.874968 -11.742928)
		(end 31.523686 -11.391646)
		(width 0.14224)
		(layer "In4.Cu")
		(net "M_H_DQ<4>")
	)
	(segment
		(start 67.692016 -69.57949)
		(end 67.90817 -69.579236)
		(width 0.0889)
		(layer "In4.Cu")
		(net "M_H_DQ<4>")
	)
	(segment
		(start 31.874968 -8.836152)
		(end 32.15132 -8.5598)
		(width 0.14224)
		(layer "In4.Cu")
		(net "M_H_DQ<4>")
	)
	(segment
		(start 31.523686 -11.0363)
		(end 31.891986 -10.668)
		(width 0.14224)
		(layer "In4.Cu")
		(net "M_H_DQ<4>")
	)
	(segment
		(start 67.319906 -69.9516)
		(end 67.609212 -69.662294)
		(width 0.14224)
		(layer "In4.Cu")
		(net "M_H_DQ<4>")
	)
	(segment
		(start 31.646368 -17.0688)
		(end 31.646368 -18.3134)
		(width 0.14224)
		(layer "In4.Cu")
		(net "M_H_DQ<4>")
	)
	(segment
		(start 31.874968 -37.211)
		(end 53.591968 -58.928)
		(width 0.14224)
		(layer "In4.Cu")
		(net "M_H_DQ<4>")
	)
	(segment
		(start 31.646368 -18.3134)
		(end 31.874968 -18.542)
		(width 0.14224)
		(layer "In4.Cu")
		(net "M_H_DQ<4>")
	)
	(segment
		(start 53.858668 -58.928)
		(end 64.882268 -69.9516)
		(width 0.14224)
		(layer "In4.Cu")
		(net "M_H_DQ<4>")
	)
	(segment
		(start 31.39948 -13.959078)
		(end 31.39948 -15.018512)
		(width 0.14224)
		(layer "In4.Cu")
		(net "M_H_DQ<4>")
	)
	(segment
		(start 31.874968 -21.7678)
		(end 31.697168 -21.9456)
		(width 0.14224)
		(layer "In4.Cu")
		(net "M_H_DQ<4>")
	)
	(segment
		(start 31.697168 -23.1648)
		(end 31.874968 -23.3426)
		(width 0.14224)
		(layer "In4.Cu")
		(net "M_H_DQ<4>")
	)
	(segment
		(start 72.051926 -69.06768)
		(end 72.328786 -68.46824)
		(width 0.0889)
		(layer "In4.Cu")
		(net "M_H_DQ<4>")
	)
	(segment
		(start 31.510986 -9.677654)
		(end 31.874968 -9.313672)
		(width 0.14224)
		(layer "In4.Cu")
		(net "M_H_DQ<4>")
	)
	(segment
		(start 70.59676 -70.04939)
		(end 70.629526 -70.04939)
		(width 0.0889)
		(layer "In4.Cu")
		(net "M_H_DQ<4>")
	)
	(segment
		(start 53.591968 -58.928)
		(end 53.858668 -58.928)
		(width 0.14224)
		(layer "In4.Cu")
		(net "M_H_DQ<4>")
	)
	(segment
		(start 31.697168 -21.9456)
		(end 31.697168 -23.1648)
		(width 0.14224)
		(layer "In4.Cu")
		(net "M_H_DQ<4>")
	)
	(segment
		(start 67.90817 -69.579236)
		(end 67.990974 -69.579236)
		(width 0.0889)
		(layer "In4.Cu")
		(net "M_H_DQ<4>")
	)
	(segment
		(start 31.874968 -23.3426)
		(end 31.874968 -37.211)
		(width 0.14224)
		(layer "In4.Cu")
		(net "M_H_DQ<4>")
	)
	(segment
		(start 64.882268 -69.9516)
		(end 67.319906 -69.9516)
		(width 0.14224)
		(layer "In4.Cu")
		(net "M_H_DQ<4>")
	)
	(segment
		(start 31.874968 -12.217654)
		(end 31.874968 -11.742928)
		(width 0.14224)
		(layer "In4.Cu")
		(net "M_H_DQ<4>")
	)
	(segment
		(start 31.163768 -13.723366)
		(end 31.163768 -12.928854)
		(width 0.14224)
		(layer "In4.Cu")
		(net "M_H_DQ<4>")
	)
	(segment
		(start 68.656962 -70.04939)
		(end 68.909692 -70.04939)
		(width 0.0889)
		(layer "In4.Cu")
		(net "M_H_DQ<4>")
	)
	(segment
		(start 31.523686 -11.391646)
		(end 31.523686 -11.0363)
		(width 0.14224)
		(layer "In4.Cu")
		(net "M_H_DQ<4>")
	)
	(segment
		(start 31.39948 -15.018512)
		(end 31.874968 -15.494)
		(width 0.14224)
		(layer "In4.Cu")
		(net "M_H_DQ<4>")
	)
	(segment
		(start 31.874968 -18.542)
		(end 31.874968 -21.7678)
		(width 0.14224)
		(layer "In4.Cu")
		(net "M_H_DQ<4>")
	)
	(segment
		(start 67.990974 -69.579236)
		(end 68.12026 -69.588634)
		(width 0.0889)
		(layer "In4.Cu")
		(net "M_H_DQ<4>")
	)
	(segment
		(start 31.874968 -16.8402)
		(end 31.646368 -17.0688)
		(width 0.14224)
		(layer "In4.Cu")
		(net "M_H_DQ<4>")
	)
	(segment
		(start 31.891986 -10.3632)
		(end 31.510986 -9.9822)
		(width 0.14224)
		(layer "In4.Cu")
		(net "M_H_DQ<4>")
	)
	(segment
		(start 31.874968 -9.313672)
		(end 31.874968 -8.836152)
		(width 0.14224)
		(layer "In4.Cu")
		(net "M_H_DQ<4>")
	)
	(segment
		(start 31.510986 -9.9822)
		(end 31.510986 -9.677654)
		(width 0.14224)
		(layer "In4.Cu")
		(net "M_H_DQ<4>")
	)
	(segment
		(start 31.874968 -15.494)
		(end 31.874968 -16.8402)
		(width 0.14224)
		(layer "In4.Cu")
		(net "M_H_DQ<4>")
	)
	(arc
		(start 70.629526 -70.04939)
		(mid 70.91495 -69.965923)
		(end 71.123556 -69.753988)
		(width 0.0889)
		(layer "In4.Cu")
		(net "M_H_DQ<4>")
	)
	(arc
		(start 68.34505 -69.779896)
		(mid 68.478604 -69.940564)
		(end 68.656962 -70.04939)
		(width 0.0889)
		(layer "In4.Cu")
		(net "M_H_DQ<4>")
	)
	(arc
		(start 70.265036 -70.249288)
		(mid 70.405115 -70.106552)
		(end 70.59676 -70.04939)
		(width 0.0889)
		(layer "In4.Cu")
		(net "M_H_DQ<4>")
	)
	(arc
		(start 68.909692 -70.04939)
		(mid 69.101334 -70.106556)
		(end 69.241416 -70.249288)
		(width 0.0889)
		(layer "In4.Cu")
		(net "M_H_DQ<4>")
	)
	(arc
		(start 68.12026 -69.588634)
		(mid 68.248932 -69.665132)
		(end 68.34505 -69.779896)
		(width 0.0889)
		(layer "In4.Cu")
		(net "M_H_DQ<4>")
	)
	(arc
		(start 71.123556 -69.753988)
		(mid 71.265239 -69.610184)
		(end 71.45909 -69.553836)
		(width 0.0889)
		(layer "In4.Cu")
		(net "M_H_DQ<4>")
	)
	(arc
		(start 71.491856 -69.553836)
		(mid 71.857645 -69.409552)
		(end 72.051926 -69.06768)
		(width 0.0889)
		(layer "In4.Cu")
		(net "M_H_DQ<4>")
	)
	(arc
		(start 69.241416 -70.249288)
		(mid 69.753226 -70.544827)
		(end 70.265036 -70.249288)
		(width 0.0889)
		(layer "In4.Cu")
		(net "M_H_DQ<4>")
	)
	(segment
		(start 134.656068 -25.9588)
		(end 135.291068 -25.9588)
		(width 0.1651)
		(layer "F.Cu")
		(net "M_H_DQ<49>")
	)
	(segment
		(start 135.887968 -35.106356)
		(end 135.887968 -33.149286)
		(width 0.1651)
		(layer "F.Cu")
		(net "M_H_DQ<49>")
	)
	(segment
		(start 118.272814 -49.624996)
		(end 122.315986 -45.581824)
		(width 0.1016)
		(layer "F.Cu")
		(net "M_H_DQ<49>")
	)
	(segment
		(start 118.109492 -51.839114)
		(end 118.109492 -49.788318)
		(width 0.0889)
		(layer "F.Cu")
		(net "M_H_DQ<49>")
	)
	(segment
		(start 135.049768 -27.3304)
		(end 134.490968 -26.7716)
		(width 0.1651)
		(layer "F.Cu")
		(net "M_H_DQ<49>")
	)
	(segment
		(start 136.256268 -35.474656)
		(end 135.887968 -35.106356)
		(width 0.1651)
		(layer "F.Cu")
		(net "M_H_DQ<49>")
	)
	(segment
		(start 135.557768 -28.321)
		(end 135.049768 -27.813)
		(width 0.1651)
		(layer "F.Cu")
		(net "M_H_DQ<49>")
	)
	(segment
		(start 135.557768 -28.7528)
		(end 135.557768 -28.321)
		(width 0.1651)
		(layer "F.Cu")
		(net "M_H_DQ<49>")
	)
	(segment
		(start 122.315986 -45.581824)
		(end 129.151126 -45.581824)
		(width 0.1016)
		(layer "F.Cu")
		(net "M_H_DQ<49>")
	)
	(segment
		(start 136.256268 -36.2331)
		(end 136.256268 -35.474656)
		(width 0.1651)
		(layer "F.Cu")
		(net "M_H_DQ<49>")
	)
	(segment
		(start 134.490968 -26.1239)
		(end 134.656068 -25.9588)
		(width 0.1651)
		(layer "F.Cu")
		(net "M_H_DQ<49>")
	)
	(segment
		(start 134.490968 -26.7716)
		(end 134.490968 -26.1239)
		(width 0.1651)
		(layer "F.Cu")
		(net "M_H_DQ<49>")
	)
	(segment
		(start 135.433562 -32.69488)
		(end 135.433562 -30.353)
		(width 0.1651)
		(layer "F.Cu")
		(net "M_H_DQ<49>")
	)
	(segment
		(start 135.291068 -25.9588)
		(end 135.771636 -26.439368)
		(width 0.1651)
		(layer "F.Cu")
		(net "M_H_DQ<49>")
	)
	(segment
		(start 129.151126 -45.581824)
		(end 131.73964 -42.99331)
		(width 0.1016)
		(layer "F.Cu")
		(net "M_H_DQ<49>")
	)
	(segment
		(start 118.109492 -49.788318)
		(end 118.272814 -49.624996)
		(width 0.0889)
		(layer "F.Cu")
		(net "M_H_DQ<49>")
	)
	(segment
		(start 131.73964 -42.021252)
		(end 131.747768 -42.013124)
		(width 0.1651)
		(layer "F.Cu")
		(net "M_H_DQ<49>")
	)
	(segment
		(start 135.049768 -27.813)
		(end 135.049768 -27.3304)
		(width 0.1651)
		(layer "F.Cu")
		(net "M_H_DQ<49>")
	)
	(segment
		(start 135.887968 -33.149286)
		(end 135.433562 -32.69488)
		(width 0.1651)
		(layer "F.Cu")
		(net "M_H_DQ<49>")
	)
	(segment
		(start 131.747768 -40.7416)
		(end 136.256268 -36.2331)
		(width 0.1651)
		(layer "F.Cu")
		(net "M_H_DQ<49>")
	)
	(segment
		(start 135.433562 -28.877006)
		(end 135.557768 -28.7528)
		(width 0.1651)
		(layer "F.Cu")
		(net "M_H_DQ<49>")
	)
	(segment
		(start 135.099552 -5.822442)
		(end 135.099552 -7.086346)
		(width 0.1651)
		(layer "F.Cu")
		(net "M_H_DQ<49>")
	)
	(segment
		(start 131.73964 -42.99331)
		(end 131.73964 -42.021252)
		(width 0.1016)
		(layer "F.Cu")
		(net "M_H_DQ<49>")
	)
	(segment
		(start 135.771636 -26.439368)
		(end 135.771636 -27.168856)
		(width 0.1651)
		(layer "F.Cu")
		(net "M_H_DQ<49>")
	)
	(segment
		(start 135.433562 -30.353)
		(end 135.433562 -28.877006)
		(width 0.1651)
		(layer "F.Cu")
		(net "M_H_DQ<49>")
	)
	(segment
		(start 118.212362 -51.941984)
		(end 118.109492 -51.839114)
		(width 0.0889)
		(layer "F.Cu")
		(net "M_H_DQ<49>")
	)
	(segment
		(start 131.747768 -42.013124)
		(end 131.747768 -40.7416)
		(width 0.1651)
		(layer "F.Cu")
		(net "M_H_DQ<49>")
	)
	(via
		(at 135.099552 -7.086346)
		(size 0.508)
		(drill 0.254)
		(layers "F.Cu" "B.Cu")
		(net "M_H_DQ<49>")
	)
	(via
		(at 135.433562 -30.353)
		(size 0.508)
		(drill 0.254)
		(layers "F.Cu" "B.Cu")
		(net "M_H_DQ<49>")
	)
	(via
		(at 135.771636 -27.168856)
		(size 0.508)
		(drill 0.254)
		(layers "F.Cu" "B.Cu")
		(net "M_H_DQ<49>")
	)
	(via
		(at 135.771636 -12.678156)
		(size 0.508)
		(drill 0.254)
		(layers "F.Cu" "B.Cu")
		(net "M_H_DQ<49>")
	)
	(segment
		(start 135.949436 -10.623042)
		(end 135.949436 -11.997182)
		(width 0.1651)
		(layer "B.Cu")
		(net "M_H_DQ<49>")
	)
	(segment
		(start 135.771636 -12.174982)
		(end 135.771636 -12.678156)
		(width 0.1651)
		(layer "B.Cu")
		(net "M_H_DQ<49>")
	)
	(segment
		(start 135.949436 -11.997182)
		(end 135.771636 -12.174982)
		(width 0.1651)
		(layer "B.Cu")
		(net "M_H_DQ<49>")
	)
	(segment
		(start 136.145778 -8.970264)
		(end 136.145778 -12.304014)
		(width 0.14224)
		(layer "In4.Cu")
		(net "M_H_DQ<49>")
	)
	(segment
		(start 135.576818 -8.1026)
		(end 135.932418 -8.1026)
		(width 0.14224)
		(layer "In4.Cu")
		(net "M_H_DQ<49>")
	)
	(segment
		(start 136.257538 -16.069564)
		(end 136.257538 -26.682954)
		(width 0.14224)
		(layer "In4.Cu")
		(net "M_H_DQ<49>")
	)
	(segment
		(start 136.257538 -26.682954)
		(end 135.771636 -27.168856)
		(width 0.14224)
		(layer "In4.Cu")
		(net "M_H_DQ<49>")
	)
	(segment
		(start 135.716264 -13.950696)
		(end 135.716264 -15.52829)
		(width 0.14224)
		(layer "In4.Cu")
		(net "M_H_DQ<49>")
	)
	(segment
		(start 136.302242 -8.8138)
		(end 136.145778 -8.970264)
		(width 0.14224)
		(layer "In4.Cu")
		(net "M_H_DQ<49>")
	)
	(segment
		(start 135.329168 -13.120624)
		(end 135.329168 -13.5636)
		(width 0.14224)
		(layer "In4.Cu")
		(net "M_H_DQ<49>")
	)
	(segment
		(start 135.099552 -7.086346)
		(end 135.099552 -7.625334)
		(width 0.14224)
		(layer "In4.Cu")
		(net "M_H_DQ<49>")
	)
	(segment
		(start 135.771636 -12.678156)
		(end 135.329168 -13.120624)
		(width 0.14224)
		(layer "In4.Cu")
		(net "M_H_DQ<49>")
	)
	(segment
		(start 136.302242 -8.472424)
		(end 136.302242 -8.8138)
		(width 0.14224)
		(layer "In4.Cu")
		(net "M_H_DQ<49>")
	)
	(segment
		(start 135.716264 -15.52829)
		(end 136.257538 -16.069564)
		(width 0.14224)
		(layer "In4.Cu")
		(net "M_H_DQ<49>")
	)
	(segment
		(start 135.932418 -8.1026)
		(end 136.302242 -8.472424)
		(width 0.14224)
		(layer "In4.Cu")
		(net "M_H_DQ<49>")
	)
	(segment
		(start 136.145778 -12.304014)
		(end 135.771636 -12.678156)
		(width 0.14224)
		(layer "In4.Cu")
		(net "M_H_DQ<49>")
	)
	(segment
		(start 135.099552 -7.625334)
		(end 135.576818 -8.1026)
		(width 0.14224)
		(layer "In4.Cu")
		(net "M_H_DQ<49>")
	)
	(segment
		(start 135.329168 -13.5636)
		(end 135.716264 -13.950696)
		(width 0.14224)
		(layer "In4.Cu")
		(net "M_H_DQ<49>")
	)
	(segment
		(start 133.140196 -36.68395)
		(end 133.93039 -37.474144)
		(width 0.1651)
		(layer "F.Cu")
		(net "M_H_DQ<48>")
	)
	(segment
		(start 117.353842 -52.437538)
		(end 117.751352 -52.040028)
		(width 0.0889)
		(layer "F.Cu")
		(net "M_H_DQ<48>")
	)
	(segment
		(start 134.110222 -37.474144)
		(end 134.469378 -37.114988)
		(width 0.1651)
		(layer "F.Cu")
		(net "M_H_DQ<48>")
	)
	(segment
		(start 133.39445 -38.180264)
		(end 133.39445 -37.85108)
		(width 0.1651)
		(layer "F.Cu")
		(net "M_H_DQ<48>")
	)
	(segment
		(start 132.685536 -36.958778)
		(end 132.960364 -36.68395)
		(width 0.1651)
		(layer "F.Cu")
		(net "M_H_DQ<48>")
	)
	(segment
		(start 135.571738 -35.832796)
		(end 134.668768 -34.929826)
		(width 0.1651)
		(layer "F.Cu")
		(net "M_H_DQ<48>")
	)
	(segment
		(start 135.949436 -10.422382)
		(end 135.803132 -8.89)
		(width 0.1651)
		(layer "F.Cu")
		(net "M_H_DQ<48>")
	)
	(segment
		(start 131.087368 -42.116248)
		(end 131.087368 -40.487346)
		(width 0.1651)
		(layer "F.Cu")
		(net "M_H_DQ<48>")
	)
	(segment
		(start 132.960364 -36.68395)
		(end 133.140196 -36.68395)
		(width 0.1651)
		(layer "F.Cu")
		(net "M_H_DQ<48>")
	)
	(segment
		(start 134.744968 -28.893262)
		(end 135.099552 -28.538678)
		(width 0.1651)
		(layer "F.Cu")
		(net "M_H_DQ<48>")
	)
	(segment
		(start 134.668768 -34.929826)
		(end 134.668768 -34.348674)
		(width 0.1651)
		(layer "F.Cu")
		(net "M_H_DQ<48>")
	)
	(segment
		(start 117.751352 -52.040028)
		(end 117.751352 -51.783488)
		(width 0.0889)
		(layer "F.Cu")
		(net "M_H_DQ<48>")
	)
	(segment
		(start 131.09194 -42.12082)
		(end 131.087368 -42.116248)
		(width 0.1651)
		(layer "F.Cu")
		(net "M_H_DQ<48>")
	)
	(segment
		(start 134.136638 -36.602416)
		(end 134.136638 -36.422076)
		(width 0.1651)
		(layer "F.Cu")
		(net "M_H_DQ<48>")
	)
	(segment
		(start 135.248142 -33.7693)
		(end 135.248142 -33.414462)
		(width 0.1651)
		(layer "F.Cu")
		(net "M_H_DQ<48>")
	)
	(segment
		(start 135.248142 -33.414462)
		(end 134.744968 -32.911288)
		(width 0.1651)
		(layer "F.Cu")
		(net "M_H_DQ<48>")
	)
	(segment
		(start 134.469378 -36.935156)
		(end 134.136638 -36.602416)
		(width 0.1651)
		(layer "F.Cu")
		(net "M_H_DQ<48>")
	)
	(segment
		(start 134.668768 -34.348674)
		(end 135.248142 -33.7693)
		(width 0.1651)
		(layer "F.Cu")
		(net "M_H_DQ<48>")
	)
	(segment
		(start 134.971028 -36.433506)
		(end 135.15086 -36.433506)
		(width 0.1651)
		(layer "F.Cu")
		(net "M_H_DQ<48>")
	)
	(segment
		(start 134.744968 -32.911288)
		(end 134.744968 -28.893262)
		(width 0.1651)
		(layer "F.Cu")
		(net "M_H_DQ<48>")
	)
	(segment
		(start 131.087368 -40.487346)
		(end 133.39445 -38.180264)
		(width 0.1651)
		(layer "F.Cu")
		(net "M_H_DQ<48>")
	)
	(segment
		(start 134.136638 -36.422076)
		(end 134.458202 -36.100512)
		(width 0.1651)
		(layer "F.Cu")
		(net "M_H_DQ<48>")
	)
	(segment
		(start 122.152664 -45.188124)
		(end 128.987804 -45.188124)
		(width 0.1016)
		(layer "F.Cu")
		(net "M_H_DQ<48>")
	)
	(segment
		(start 134.458202 -36.100512)
		(end 134.638034 -36.100512)
		(width 0.1651)
		(layer "F.Cu")
		(net "M_H_DQ<48>")
	)
	(segment
		(start 134.638034 -36.100512)
		(end 134.971028 -36.433506)
		(width 0.1651)
		(layer "F.Cu")
		(net "M_H_DQ<48>")
	)
	(segment
		(start 134.469378 -37.114988)
		(end 134.469378 -36.935156)
		(width 0.1651)
		(layer "F.Cu")
		(net "M_H_DQ<48>")
	)
	(segment
		(start 135.79094 -8.763)
		(end 135.771636 -8.5598)
		(width 0.1651)
		(layer "F.Cu")
		(net "M_H_DQ<48>")
	)
	(segment
		(start 135.15086 -36.433506)
		(end 135.571738 -36.012628)
		(width 0.1651)
		(layer "F.Cu")
		(net "M_H_DQ<48>")
	)
	(segment
		(start 131.09194 -43.083988)
		(end 131.09194 -42.12082)
		(width 0.1016)
		(layer "F.Cu")
		(net "M_H_DQ<48>")
	)
	(segment
		(start 133.93039 -37.474144)
		(end 134.110222 -37.474144)
		(width 0.1651)
		(layer "F.Cu")
		(net "M_H_DQ<48>")
	)
	(segment
		(start 117.751352 -51.783488)
		(end 117.918992 -51.615848)
		(width 0.0889)
		(layer "F.Cu")
		(net "M_H_DQ<48>")
	)
	(segment
		(start 132.685536 -37.142166)
		(end 132.685536 -36.958778)
		(width 0.1651)
		(layer "F.Cu")
		(net "M_H_DQ<48>")
	)
	(segment
		(start 117.918992 -49.421796)
		(end 122.152664 -45.188124)
		(width 0.1016)
		(layer "F.Cu")
		(net "M_H_DQ<48>")
	)
	(segment
		(start 128.987804 -45.188124)
		(end 131.09194 -43.083988)
		(width 0.1016)
		(layer "F.Cu")
		(net "M_H_DQ<48>")
	)
	(segment
		(start 135.803132 -8.89)
		(end 135.79094 -8.763)
		(width 0.1651)
		(layer "F.Cu")
		(net "M_H_DQ<48>")
	)
	(segment
		(start 117.918992 -51.615848)
		(end 117.918992 -49.421796)
		(width 0.0889)
		(layer "F.Cu")
		(net "M_H_DQ<48>")
	)
	(segment
		(start 135.571738 -36.012628)
		(end 135.571738 -35.832796)
		(width 0.1651)
		(layer "F.Cu")
		(net "M_H_DQ<48>")
	)
	(segment
		(start 133.39445 -37.85108)
		(end 132.685536 -37.142166)
		(width 0.1651)
		(layer "F.Cu")
		(net "M_H_DQ<48>")
	)
	(via
		(at 135.771636 -8.5598)
		(size 0.508)
		(drill 0.254)
		(layers "F.Cu" "B.Cu")
		(net "M_H_DQ<48>")
	)
	(via
		(at 135.099552 -13.959078)
		(size 0.508)
		(drill 0.254)
		(layers "F.Cu" "B.Cu")
		(net "M_H_DQ<48>")
	)
	(via
		(at 135.099552 -28.538678)
		(size 0.508)
		(drill 0.254)
		(layers "F.Cu" "B.Cu")
		(net "M_H_DQ<48>")
	)
	(segment
		(start 135.099552 -15.222982)
		(end 135.099552 -13.959078)
		(width 0.1651)
		(layer "B.Cu")
		(net "M_H_DQ<48>")
	)
	(segment
		(start 135.584438 -16.815308)
		(end 135.584438 -16.069564)
		(width 0.14224)
		(layer "In4.Cu")
		(net "M_H_DQ<48>")
	)
	(segment
		(start 135.551418 -11.692128)
		(end 135.162036 -11.302746)
		(width 0.14224)
		(layer "In4.Cu")
		(net "M_H_DQ<48>")
	)
	(segment
		(start 135.099552 -15.584678)
		(end 135.099552 -13.959078)
		(width 0.14224)
		(layer "In4.Cu")
		(net "M_H_DQ<48>")
	)
	(segment
		(start 135.559038 -26.650696)
		(end 135.559038 -23.394416)
		(width 0.14224)
		(layer "In4.Cu")
		(net "M_H_DQ<48>")
	)
	(segment
		(start 135.303768 -23.139146)
		(end 135.303768 -21.965666)
		(width 0.14224)
		(layer "In4.Cu")
		(net "M_H_DQ<48>")
	)
	(segment
		(start 135.551418 -9.364472)
		(end 135.551418 -8.780018)
		(width 0.14224)
		(layer "In4.Cu")
		(net "M_H_DQ<48>")
	)
	(segment
		(start 135.559038 -23.394416)
		(end 135.303768 -23.139146)
		(width 0.14224)
		(layer "In4.Cu")
		(net "M_H_DQ<48>")
	)
	(segment
		(start 135.271764 -17.127982)
		(end 135.584438 -16.815308)
		(width 0.14224)
		(layer "In4.Cu")
		(net "M_H_DQ<48>")
	)
	(segment
		(start 134.814818 -13.674344)
		(end 134.814818 -12.9286)
		(width 0.14224)
		(layer "In4.Cu")
		(net "M_H_DQ<48>")
	)
	(segment
		(start 135.162036 -10.9982)
		(end 135.479536 -10.6807)
		(width 0.14224)
		(layer "In4.Cu")
		(net "M_H_DQ<48>")
	)
	(segment
		(start 135.136636 -9.779254)
		(end 135.551418 -9.364472)
		(width 0.14224)
		(layer "In4.Cu")
		(net "M_H_DQ<48>")
	)
	(segment
		(start 135.099552 -27.110182)
		(end 135.559038 -26.650696)
		(width 0.14224)
		(layer "In4.Cu")
		(net "M_H_DQ<48>")
	)
	(segment
		(start 135.271764 -18.306796)
		(end 135.271764 -17.127982)
		(width 0.14224)
		(layer "In4.Cu")
		(net "M_H_DQ<48>")
	)
	(segment
		(start 135.099552 -13.959078)
		(end 134.814818 -13.674344)
		(width 0.14224)
		(layer "In4.Cu")
		(net "M_H_DQ<48>")
	)
	(segment
		(start 135.551418 -12.192)
		(end 135.551418 -11.692128)
		(width 0.14224)
		(layer "In4.Cu")
		(net "M_H_DQ<48>")
	)
	(segment
		(start 135.601964 -21.66747)
		(end 135.601964 -18.636996)
		(width 0.14224)
		(layer "In4.Cu")
		(net "M_H_DQ<48>")
	)
	(segment
		(start 135.099552 -28.538678)
		(end 135.099552 -27.110182)
		(width 0.14224)
		(layer "In4.Cu")
		(net "M_H_DQ<48>")
	)
	(segment
		(start 135.479536 -10.6807)
		(end 135.479536 -10.4521)
		(width 0.14224)
		(layer "In4.Cu")
		(net "M_H_DQ<48>")
	)
	(segment
		(start 135.601964 -18.636996)
		(end 135.271764 -18.306796)
		(width 0.14224)
		(layer "In4.Cu")
		(net "M_H_DQ<48>")
	)
	(segment
		(start 135.162036 -11.302746)
		(end 135.162036 -10.9982)
		(width 0.14224)
		(layer "In4.Cu")
		(net "M_H_DQ<48>")
	)
	(segment
		(start 135.479536 -10.4521)
		(end 135.136636 -10.1092)
		(width 0.14224)
		(layer "In4.Cu")
		(net "M_H_DQ<48>")
	)
	(segment
		(start 135.584438 -16.069564)
		(end 135.099552 -15.584678)
		(width 0.14224)
		(layer "In4.Cu")
		(net "M_H_DQ<48>")
	)
	(segment
		(start 135.551418 -8.780018)
		(end 135.771636 -8.5598)
		(width 0.14224)
		(layer "In4.Cu")
		(net "M_H_DQ<48>")
	)
	(segment
		(start 135.136636 -10.1092)
		(end 135.136636 -9.779254)
		(width 0.14224)
		(layer "In4.Cu")
		(net "M_H_DQ<48>")
	)
	(segment
		(start 135.303768 -21.965666)
		(end 135.601964 -21.66747)
		(width 0.14224)
		(layer "In4.Cu")
		(net "M_H_DQ<48>")
	)
	(segment
		(start 134.814818 -12.9286)
		(end 135.551418 -12.192)
		(width 0.14224)
		(layer "In4.Cu")
		(net "M_H_DQ<48>")
	)
	(segment
		(start 129.999486 -5.822442)
		(end 129.999486 -7.086346)
		(width 0.1651)
		(layer "F.Cu")
		(net "M_H_DQ<47>")
	)
	(segment
		(start 129.918968 -30.301946)
		(end 130.728974 -29.49194)
		(width 0.1651)
		(layer "F.Cu")
		(net "M_H_DQ<47>")
	)
	(segment
		(start 115.213892 -50.39233)
		(end 115.213892 -50.137822)
		(width 0.0889)
		(layer "F.Cu")
		(net "M_H_DQ<47>")
	)
	(segment
		(start 130.728974 -28.533598)
		(end 130.223768 -28.028392)
		(width 0.1651)
		(layer "F.Cu")
		(net "M_H_DQ<47>")
	)
	(segment
		(start 115.129818 -51.750722)
		(end 115.099592 -51.69662)
		(width 0.0889)
		(layer "F.Cu")
		(net "M_H_DQ<47>")
	)
	(segment
		(start 115.378992 -49.972722)
		(end 115.378992 -48.173132)
		(width 0.1016)
		(layer "F.Cu")
		(net "M_H_DQ<47>")
	)
	(segment
		(start 115.107974 -53.161946)
		(end 115.124992 -53.132736)
		(width 0.0889)
		(layer "F.Cu")
		(net "M_H_DQ<47>")
	)
	(segment
		(start 122.527568 -40.1066)
		(end 125.448568 -37.1856)
		(width 0.1651)
		(layer "F.Cu")
		(net "M_H_DQ<47>")
	)
	(segment
		(start 125.448568 -37.1856)
		(end 127.215392 -37.1856)
		(width 0.1651)
		(layer "F.Cu")
		(net "M_H_DQ<47>")
	)
	(segment
		(start 115.099592 -50.50663)
		(end 115.213892 -50.39233)
		(width 0.0889)
		(layer "F.Cu")
		(net "M_H_DQ<47>")
	)
	(segment
		(start 122.527568 -40.6654)
		(end 122.527568 -40.1066)
		(width 0.1651)
		(layer "F.Cu")
		(net "M_H_DQ<47>")
	)
	(segment
		(start 121.867168 -41.684956)
		(end 121.867168 -41.3258)
		(width 0.1016)
		(layer "F.Cu")
		(net "M_H_DQ<47>")
	)
	(segment
		(start 130.223768 -27.3304)
		(end 130.385312 -27.168856)
		(width 0.1651)
		(layer "F.Cu")
		(net "M_H_DQ<47>")
	)
	(segment
		(start 127.215392 -37.1856)
		(end 129.918968 -34.46145)
		(width 0.1651)
		(layer "F.Cu")
		(net "M_H_DQ<47>")
	)
	(segment
		(start 130.385312 -27.168856)
		(end 130.76428 -27.168856)
		(width 0.1651)
		(layer "F.Cu")
		(net "M_H_DQ<47>")
	)
	(segment
		(start 121.867168 -41.3258)
		(end 122.527568 -40.6654)
		(width 0.1651)
		(layer "F.Cu")
		(net "M_H_DQ<47>")
	)
	(segment
		(start 115.213892 -50.137822)
		(end 115.378992 -49.972722)
		(width 0.0889)
		(layer "F.Cu")
		(net "M_H_DQ<47>")
	)
	(segment
		(start 114.778282 -53.923184)
		(end 115.107974 -53.161946)
		(width 0.0889)
		(layer "F.Cu")
		(net "M_H_DQ<47>")
	)
	(segment
		(start 130.223768 -28.028392)
		(end 130.223768 -27.3304)
		(width 0.1651)
		(layer "F.Cu")
		(net "M_H_DQ<47>")
	)
	(segment
		(start 115.099592 -51.69662)
		(end 115.099592 -50.50663)
		(width 0.0889)
		(layer "F.Cu")
		(net "M_H_DQ<47>")
	)
	(segment
		(start 129.918968 -34.46145)
		(end 129.918968 -33.782)
		(width 0.1651)
		(layer "F.Cu")
		(net "M_H_DQ<47>")
	)
	(segment
		(start 129.918968 -33.782)
		(end 129.918968 -30.301946)
		(width 0.1651)
		(layer "F.Cu")
		(net "M_H_DQ<47>")
	)
	(segment
		(start 130.728974 -29.49194)
		(end 130.728974 -28.533598)
		(width 0.1651)
		(layer "F.Cu")
		(net "M_H_DQ<47>")
	)
	(segment
		(start 115.378992 -48.173132)
		(end 121.867168 -41.684956)
		(width 0.1016)
		(layer "F.Cu")
		(net "M_H_DQ<47>")
	)
	(via
		(at 129.918968 -33.782)
		(size 0.508)
		(drill 0.254)
		(layers "F.Cu" "B.Cu")
		(net "M_H_DQ<47>")
	)
	(via
		(at 130.84937 -12.678156)
		(size 0.508)
		(drill 0.254)
		(layers "F.Cu" "B.Cu")
		(net "M_H_DQ<47>")
	)
	(via
		(at 129.999486 -7.086346)
		(size 0.508)
		(drill 0.254)
		(layers "F.Cu" "B.Cu")
		(net "M_H_DQ<47>")
	)
	(via
		(at 130.76428 -27.168856)
		(size 0.508)
		(drill 0.254)
		(layers "F.Cu" "B.Cu")
		(net "M_H_DQ<47>")
	)
	(arc
		(start 115.124992 -53.132736)
		(mid 115.178491 -52.932838)
		(end 115.124992 -52.73294)
		(width 0.0889)
		(layer "F.Cu")
		(net "M_H_DQ<47>")
	)
	(arc
		(start 115.124992 -52.142136)
		(mid 115.178462 -51.947073)
		(end 115.129818 -51.750722)
		(width 0.0889)
		(layer "F.Cu")
		(net "M_H_DQ<47>")
	)
	(arc
		(start 115.124992 -52.73294)
		(mid 115.045861 -52.437538)
		(end 115.124992 -52.142136)
		(width 0.0889)
		(layer "F.Cu")
		(net "M_H_DQ<47>")
	)
	(segment
		(start 130.84937 -10.623042)
		(end 130.84937 -12.678156)
		(width 0.1651)
		(layer "B.Cu")
		(net "M_H_DQ<47>")
	)
	(segment
		(start 130.316224 -7.403084)
		(end 130.316224 -7.7216)
		(width 0.14224)
		(layer "In11.Cu")
		(net "M_H_DQ<47>")
	)
	(segment
		(start 131.365244 -18.328386)
		(end 131.238244 -18.455386)
		(width 0.14224)
		(layer "In11.Cu")
		(net "M_H_DQ<47>")
	)
	(segment
		(start 131.060444 -16.728186)
		(end 131.365244 -17.032986)
		(width 0.14224)
		(layer "In11.Cu")
		(net "M_H_DQ<47>")
	)
	(segment
		(start 130.84937 -12.678156)
		(end 130.382264 -13.145262)
		(width 0.14224)
		(layer "In11.Cu")
		(net "M_H_DQ<47>")
	)
	(segment
		(start 130.316224 -7.7216)
		(end 130.646424 -8.0518)
		(width 0.14224)
		(layer "In11.Cu")
		(net "M_H_DQ<47>")
	)
	(segment
		(start 131.341368 -21.207476)
		(end 131.238244 -21.3106)
		(width 0.14224)
		(layer "In11.Cu")
		(net "M_H_DQ<47>")
	)
	(segment
		(start 129.999486 -7.086346)
		(end 130.316224 -7.403084)
		(width 0.14224)
		(layer "In11.Cu")
		(net "M_H_DQ<47>")
	)
	(segment
		(start 130.646424 -8.0518)
		(end 130.900424 -8.0518)
		(width 0.14224)
		(layer "In11.Cu")
		(net "M_H_DQ<47>")
	)
	(segment
		(start 131.202176 -9.020048)
		(end 131.202176 -12.32535)
		(width 0.14224)
		(layer "In11.Cu")
		(net "M_H_DQ<47>")
	)
	(segment
		(start 131.365244 -17.032986)
		(end 131.365244 -18.328386)
		(width 0.14224)
		(layer "In11.Cu")
		(net "M_H_DQ<47>")
	)
	(segment
		(start 131.390644 -23.117048)
		(end 131.138168 -23.369524)
		(width 0.14224)
		(layer "In11.Cu")
		(net "M_H_DQ<47>")
	)
	(segment
		(start 131.357624 -8.8646)
		(end 131.202176 -9.020048)
		(width 0.14224)
		(layer "In11.Cu")
		(net "M_H_DQ<47>")
	)
	(segment
		(start 131.202176 -12.32535)
		(end 130.84937 -12.678156)
		(width 0.14224)
		(layer "In11.Cu")
		(net "M_H_DQ<47>")
	)
	(segment
		(start 131.390644 -22.015196)
		(end 131.390644 -23.117048)
		(width 0.14224)
		(layer "In11.Cu")
		(net "M_H_DQ<47>")
	)
	(segment
		(start 131.238244 -21.862796)
		(end 131.390644 -22.015196)
		(width 0.14224)
		(layer "In11.Cu")
		(net "M_H_DQ<47>")
	)
	(segment
		(start 131.238244 -21.3106)
		(end 131.238244 -21.862796)
		(width 0.14224)
		(layer "In11.Cu")
		(net "M_H_DQ<47>")
	)
	(segment
		(start 130.382264 -13.612876)
		(end 131.060444 -14.291056)
		(width 0.14224)
		(layer "In11.Cu")
		(net "M_H_DQ<47>")
	)
	(segment
		(start 131.238244 -19.023076)
		(end 131.341368 -19.1262)
		(width 0.14224)
		(layer "In11.Cu")
		(net "M_H_DQ<47>")
	)
	(segment
		(start 131.138168 -26.794968)
		(end 130.76428 -27.168856)
		(width 0.14224)
		(layer "In11.Cu")
		(net "M_H_DQ<47>")
	)
	(segment
		(start 131.357624 -8.509)
		(end 131.357624 -8.8646)
		(width 0.14224)
		(layer "In11.Cu")
		(net "M_H_DQ<47>")
	)
	(segment
		(start 131.341368 -19.1262)
		(end 131.341368 -21.207476)
		(width 0.14224)
		(layer "In11.Cu")
		(net "M_H_DQ<47>")
	)
	(segment
		(start 130.382264 -13.145262)
		(end 130.382264 -13.612876)
		(width 0.14224)
		(layer "In11.Cu")
		(net "M_H_DQ<47>")
	)
	(segment
		(start 131.238244 -18.455386)
		(end 131.238244 -19.023076)
		(width 0.14224)
		(layer "In11.Cu")
		(net "M_H_DQ<47>")
	)
	(segment
		(start 131.060444 -14.291056)
		(end 131.060444 -16.728186)
		(width 0.14224)
		(layer "In11.Cu")
		(net "M_H_DQ<47>")
	)
	(segment
		(start 131.138168 -23.369524)
		(end 131.138168 -26.794968)
		(width 0.14224)
		(layer "In11.Cu")
		(net "M_H_DQ<47>")
	)
	(segment
		(start 130.900424 -8.0518)
		(end 131.357624 -8.509)
		(width 0.14224)
		(layer "In11.Cu")
		(net "M_H_DQ<47>")
	)
	(segment
		(start 127.35814 -34.361628)
		(end 127.600456 -34.119312)
		(width 0.1651)
		(layer "F.Cu")
		(net "M_H_DQ<46>")
	)
	(segment
		(start 129.258568 -32.4612)
		(end 129.258568 -31.115)
		(width 0.1651)
		(layer "F.Cu")
		(net "M_H_DQ<46>")
	)
	(segment
		(start 126.407672 -36.500816)
		(end 126.641352 -36.500816)
		(width 0.1651)
		(layer "F.Cu")
		(net "M_H_DQ<46>")
	)
	(segment
		(start 129.258568 -31.115)
		(end 129.258568 -29.9212)
		(width 0.1651)
		(layer "F.Cu")
		(net "M_H_DQ<46>")
	)
	(segment
		(start 126.882144 -35.071304)
		(end 127.359664 -35.548824)
		(width 0.1651)
		(layer "F.Cu")
		(net "M_H_DQ<46>")
	)
	(segment
		(start 126.406148 -35.31362)
		(end 126.648464 -35.071304)
		(width 0.1651)
		(layer "F.Cu")
		(net "M_H_DQ<46>")
	)
	(segment
		(start 114.909092 -50.036476)
		(end 114.985292 -49.960276)
		(width 0.0889)
		(layer "F.Cu")
		(net "M_H_DQ<46>")
	)
	(segment
		(start 130.84937 -10.422382)
		(end 130.849624 -10.422128)
		(width 0.1651)
		(layer "F.Cu")
		(net "M_H_DQ<46>")
	)
	(segment
		(start 121.155968 -41.839134)
		(end 121.155968 -41.1226)
		(width 0.1016)
		(layer "F.Cu")
		(net "M_H_DQ<46>")
	)
	(segment
		(start 126.641352 -36.500816)
		(end 126.883668 -36.2585)
		(width 0.1651)
		(layer "F.Cu")
		(net "M_H_DQ<46>")
	)
	(segment
		(start 129.258568 -29.9212)
		(end 130.054096 -29.125672)
		(width 0.1651)
		(layer "F.Cu")
		(net "M_H_DQ<46>")
	)
	(segment
		(start 130.849624 -10.422128)
		(end 130.849624 -9.4488)
		(width 0.1651)
		(layer "F.Cu")
		(net "M_H_DQ<46>")
	)
	(segment
		(start 114.778282 -51.941984)
		(end 114.909092 -51.811174)
		(width 0.0889)
		(layer "F.Cu")
		(net "M_H_DQ<46>")
	)
	(segment
		(start 127.600456 -34.119312)
		(end 127.834136 -34.119312)
		(width 0.1651)
		(layer "F.Cu")
		(net "M_H_DQ<46>")
	)
	(segment
		(start 128.310132 -33.643316)
		(end 128.310132 -33.409636)
		(width 0.1651)
		(layer "F.Cu")
		(net "M_H_DQ<46>")
	)
	(segment
		(start 125.930152 -36.023296)
		(end 126.407672 -36.500816)
		(width 0.1651)
		(layer "F.Cu")
		(net "M_H_DQ<46>")
	)
	(segment
		(start 127.359664 -35.548824)
		(end 127.593344 -35.548824)
		(width 0.1651)
		(layer "F.Cu")
		(net "M_H_DQ<46>")
	)
	(segment
		(start 130.054096 -29.125672)
		(end 130.054096 -28.538678)
		(width 0.1651)
		(layer "F.Cu")
		(net "M_H_DQ<46>")
	)
	(segment
		(start 126.406148 -35.5473)
		(end 126.406148 -35.31362)
		(width 0.1651)
		(layer "F.Cu")
		(net "M_H_DQ<46>")
	)
	(segment
		(start 127.83566 -35.306508)
		(end 127.83566 -35.072828)
		(width 0.1651)
		(layer "F.Cu")
		(net "M_H_DQ<46>")
	)
	(segment
		(start 127.593344 -35.548824)
		(end 127.83566 -35.306508)
		(width 0.1651)
		(layer "F.Cu")
		(net "M_H_DQ<46>")
	)
	(segment
		(start 128.787652 -34.354516)
		(end 128.787652 -34.120836)
		(width 0.1651)
		(layer "F.Cu")
		(net "M_H_DQ<46>")
	)
	(segment
		(start 130.981704 -9.31672)
		(end 130.981704 -9.09828)
		(width 0.1651)
		(layer "F.Cu")
		(net "M_H_DQ<46>")
	)
	(segment
		(start 126.883668 -36.02482)
		(end 126.406148 -35.5473)
		(width 0.1651)
		(layer "F.Cu")
		(net "M_H_DQ<46>")
	)
	(segment
		(start 125.696472 -36.023296)
		(end 125.930152 -36.023296)
		(width 0.1651)
		(layer "F.Cu")
		(net "M_H_DQ<46>")
	)
	(segment
		(start 114.985292 -49.960276)
		(end 114.985292 -48.00981)
		(width 0.1016)
		(layer "F.Cu")
		(net "M_H_DQ<46>")
	)
	(segment
		(start 128.310132 -33.409636)
		(end 129.258568 -32.4612)
		(width 0.1651)
		(layer "F.Cu")
		(net "M_H_DQ<46>")
	)
	(segment
		(start 128.545336 -34.596832)
		(end 128.787652 -34.354516)
		(width 0.1651)
		(layer "F.Cu")
		(net "M_H_DQ<46>")
	)
	(segment
		(start 121.689368 -40.5892)
		(end 121.689368 -40.0304)
		(width 0.1651)
		(layer "F.Cu")
		(net "M_H_DQ<46>")
	)
	(segment
		(start 130.849624 -9.4488)
		(end 130.981704 -9.31672)
		(width 0.1651)
		(layer "F.Cu")
		(net "M_H_DQ<46>")
	)
	(segment
		(start 127.834136 -34.119312)
		(end 128.311656 -34.596832)
		(width 0.1651)
		(layer "F.Cu")
		(net "M_H_DQ<46>")
	)
	(segment
		(start 121.155968 -41.1226)
		(end 121.689368 -40.5892)
		(width 0.1651)
		(layer "F.Cu")
		(net "M_H_DQ<46>")
	)
	(segment
		(start 127.35814 -34.595308)
		(end 127.35814 -34.361628)
		(width 0.1651)
		(layer "F.Cu")
		(net "M_H_DQ<46>")
	)
	(segment
		(start 130.981704 -9.09828)
		(end 130.849624 -8.9662)
		(width 0.1651)
		(layer "F.Cu")
		(net "M_H_DQ<46>")
	)
	(segment
		(start 127.83566 -35.072828)
		(end 127.35814 -34.595308)
		(width 0.1651)
		(layer "F.Cu")
		(net "M_H_DQ<46>")
	)
	(segment
		(start 126.648464 -35.071304)
		(end 126.882144 -35.071304)
		(width 0.1651)
		(layer "F.Cu")
		(net "M_H_DQ<46>")
	)
	(segment
		(start 128.311656 -34.596832)
		(end 128.545336 -34.596832)
		(width 0.1651)
		(layer "F.Cu")
		(net "M_H_DQ<46>")
	)
	(segment
		(start 130.849624 -8.9662)
		(end 130.849624 -8.661654)
		(width 0.1651)
		(layer "F.Cu")
		(net "M_H_DQ<46>")
	)
	(segment
		(start 121.689368 -40.0304)
		(end 125.696472 -36.023296)
		(width 0.1651)
		(layer "F.Cu")
		(net "M_H_DQ<46>")
	)
	(segment
		(start 128.787652 -34.120836)
		(end 128.310132 -33.643316)
		(width 0.1651)
		(layer "F.Cu")
		(net "M_H_DQ<46>")
	)
	(segment
		(start 114.985292 -48.00981)
		(end 121.155968 -41.839134)
		(width 0.1016)
		(layer "F.Cu")
		(net "M_H_DQ<46>")
	)
	(segment
		(start 114.909092 -51.811174)
		(end 114.909092 -50.036476)
		(width 0.0889)
		(layer "F.Cu")
		(net "M_H_DQ<46>")
	)
	(segment
		(start 126.883668 -36.2585)
		(end 126.883668 -36.02482)
		(width 0.1651)
		(layer "F.Cu")
		(net "M_H_DQ<46>")
	)
	(segment
		(start 130.849624 -8.661654)
		(end 130.84937 -8.6614)
		(width 0.1651)
		(layer "F.Cu")
		(net "M_H_DQ<46>")
	)
	(via
		(at 129.999486 -13.959078)
		(size 0.508)
		(drill 0.254)
		(layers "F.Cu" "B.Cu")
		(net "M_H_DQ<46>")
	)
	(via
		(at 130.84937 -8.6614)
		(size 0.508)
		(drill 0.254)
		(layers "F.Cu" "B.Cu")
		(net "M_H_DQ<46>")
	)
	(via
		(at 130.054096 -28.538678)
		(size 0.508)
		(drill 0.254)
		(layers "F.Cu" "B.Cu")
		(net "M_H_DQ<46>")
	)
	(via
		(at 129.258568 -31.115)
		(size 0.508)
		(drill 0.254)
		(layers "F.Cu" "B.Cu")
		(net "M_H_DQ<46>")
	)
	(segment
		(start 129.999486 -15.222982)
		(end 129.999486 -13.959078)
		(width 0.1651)
		(layer "B.Cu")
		(net "M_H_DQ<46>")
	)
	(segment
		(start 129.763774 -13.723366)
		(end 129.999486 -13.959078)
		(width 0.14224)
		(layer "In11.Cu")
		(net "M_H_DQ<46>")
	)
	(segment
		(start 130.299968 -19.2024)
		(end 130.299968 -21.134324)
		(width 0.14224)
		(layer "In11.Cu")
		(net "M_H_DQ<46>")
	)
	(segment
		(start 130.298444 -18.36293)
		(end 130.476244 -18.54073)
		(width 0.14224)
		(layer "In11.Cu")
		(net "M_H_DQ<46>")
	)
	(segment
		(start 130.054096 -27.170126)
		(end 130.054096 -28.538678)
		(width 0.14224)
		(layer "In11.Cu")
		(net "M_H_DQ<46>")
	)
	(segment
		(start 130.476244 -19.026124)
		(end 130.299968 -19.2024)
		(width 0.14224)
		(layer "In11.Cu")
		(net "M_H_DQ<46>")
	)
	(segment
		(start 130.110992 -11.093704)
		(end 130.110992 -11.378946)
		(width 0.14224)
		(layer "In11.Cu")
		(net "M_H_DQ<46>")
	)
	(segment
		(start 129.999486 -13.959078)
		(end 130.501644 -14.461236)
		(width 0.14224)
		(layer "In11.Cu")
		(net "M_H_DQ<46>")
	)
	(segment
		(start 130.476244 -21.3106)
		(end 130.476244 -21.862796)
		(width 0.14224)
		(layer "In11.Cu")
		(net "M_H_DQ<46>")
	)
	(segment
		(start 130.476244 -21.862796)
		(end 130.298444 -22.040596)
		(width 0.14224)
		(layer "In11.Cu")
		(net "M_H_DQ<46>")
	)
	(segment
		(start 130.536442 -12.156186)
		(end 129.763774 -12.928854)
		(width 0.14224)
		(layer "In11.Cu")
		(net "M_H_DQ<46>")
	)
	(segment
		(start 130.110992 -11.378946)
		(end 130.536442 -11.804396)
		(width 0.14224)
		(layer "In11.Cu")
		(net "M_H_DQ<46>")
	)
	(segment
		(start 130.501644 -14.461236)
		(end 130.501644 -16.850106)
		(width 0.14224)
		(layer "In11.Cu")
		(net "M_H_DQ<46>")
	)
	(segment
		(start 130.110992 -9.988296)
		(end 130.491992 -10.369296)
		(width 0.14224)
		(layer "In11.Cu")
		(net "M_H_DQ<46>")
	)
	(segment
		(start 130.476244 -18.54073)
		(end 130.476244 -19.026124)
		(width 0.14224)
		(layer "In11.Cu")
		(net "M_H_DQ<46>")
	)
	(segment
		(start 130.84937 -8.6614)
		(end 130.474974 -9.035796)
		(width 0.14224)
		(layer "In11.Cu")
		(net "M_H_DQ<46>")
	)
	(segment
		(start 130.491992 -10.712704)
		(end 130.110992 -11.093704)
		(width 0.14224)
		(layer "In11.Cu")
		(net "M_H_DQ<46>")
	)
	(segment
		(start 130.536442 -11.804396)
		(end 130.536442 -12.156186)
		(width 0.14224)
		(layer "In11.Cu")
		(net "M_H_DQ<46>")
	)
	(segment
		(start 130.501644 -16.850106)
		(end 130.298444 -17.053306)
		(width 0.14224)
		(layer "In11.Cu")
		(net "M_H_DQ<46>")
	)
	(segment
		(start 130.110992 -9.677654)
		(end 130.110992 -9.988296)
		(width 0.14224)
		(layer "In11.Cu")
		(net "M_H_DQ<46>")
	)
	(segment
		(start 130.298444 -23.132796)
		(end 130.577844 -23.412196)
		(width 0.14224)
		(layer "In11.Cu")
		(net "M_H_DQ<46>")
	)
	(segment
		(start 130.474974 -9.313672)
		(end 130.110992 -9.677654)
		(width 0.14224)
		(layer "In11.Cu")
		(net "M_H_DQ<46>")
	)
	(segment
		(start 130.577844 -26.646378)
		(end 130.054096 -27.170126)
		(width 0.14224)
		(layer "In11.Cu")
		(net "M_H_DQ<46>")
	)
	(segment
		(start 130.491992 -10.369296)
		(end 130.491992 -10.712704)
		(width 0.14224)
		(layer "In11.Cu")
		(net "M_H_DQ<46>")
	)
	(segment
		(start 130.298444 -22.040596)
		(end 130.298444 -23.132796)
		(width 0.14224)
		(layer "In11.Cu")
		(net "M_H_DQ<46>")
	)
	(segment
		(start 130.299968 -21.134324)
		(end 130.476244 -21.3106)
		(width 0.14224)
		(layer "In11.Cu")
		(net "M_H_DQ<46>")
	)
	(segment
		(start 130.298444 -17.053306)
		(end 130.298444 -18.36293)
		(width 0.14224)
		(layer "In11.Cu")
		(net "M_H_DQ<46>")
	)
	(segment
		(start 130.474974 -9.035796)
		(end 130.474974 -9.313672)
		(width 0.14224)
		(layer "In11.Cu")
		(net "M_H_DQ<46>")
	)
	(segment
		(start 130.577844 -23.412196)
		(end 130.577844 -26.646378)
		(width 0.14224)
		(layer "In11.Cu")
		(net "M_H_DQ<46>")
	)
	(segment
		(start 129.763774 -12.928854)
		(end 129.763774 -13.723366)
		(width 0.14224)
		(layer "In11.Cu")
		(net "M_H_DQ<46>")
	)
	(segment
		(start 115.796568 -41.0718)
		(end 114.907568 -40.1828)
		(width 0.1651)
		(layer "F.Cu")
		(net "M_H_DQ<45>")
	)
	(segment
		(start 114.907568 -40.1828)
		(end 114.907568 -39.7002)
		(width 0.1651)
		(layer "F.Cu")
		(net "M_H_DQ<45>")
	)
	(segment
		(start 123.467368 -30.099)
		(end 124.013468 -29.5529)
		(width 0.1651)
		(layer "F.Cu")
		(net "M_H_DQ<45>")
	)
	(segment
		(start 113.061242 -53.923184)
		(end 112.643412 -53.271928)
		(width 0.0889)
		(layer "F.Cu")
		(net "M_H_DQ<45>")
	)
	(segment
		(start 124.356368 -28.0416)
		(end 124.013976 -28.0416)
		(width 0.1651)
		(layer "F.Cu")
		(net "M_H_DQ<45>")
	)
	(segment
		(start 123.467368 -31.1404)
		(end 123.467368 -30.099)
		(width 0.1651)
		(layer "F.Cu")
		(net "M_H_DQ<45>")
	)
	(segment
		(start 114.907568 -39.7002)
		(end 123.467368 -31.1404)
		(width 0.1651)
		(layer "F.Cu")
		(net "M_H_DQ<45>")
	)
	(segment
		(start 111.797592 -51.428396)
		(end 111.797592 -50.599086)
		(width 0.0889)
		(layer "F.Cu")
		(net "M_H_DQ<45>")
	)
	(segment
		(start 124.049536 -5.822442)
		(end 124.049536 -7.086346)
		(width 0.1651)
		(layer "F.Cu")
		(net "M_H_DQ<45>")
	)
	(segment
		(start 112.229392 -49.84623)
		(end 112.229392 -46.866556)
		(width 0.1016)
		(layer "F.Cu")
		(net "M_H_DQ<45>")
	)
	(segment
		(start 115.948968 -41.2242)
		(end 115.796568 -41.0718)
		(width 0.1016)
		(layer "F.Cu")
		(net "M_H_DQ<45>")
	)
	(segment
		(start 124.208032 -26.9748)
		(end 124.629164 -26.9748)
		(width 0.1651)
		(layer "F.Cu")
		(net "M_H_DQ<45>")
	)
	(segment
		(start 124.013468 -29.5529)
		(end 124.711968 -28.8544)
		(width 0.1651)
		(layer "F.Cu")
		(net "M_H_DQ<45>")
	)
	(segment
		(start 112.224312 -52.837334)
		(end 112.191546 -52.837334)
		(width 0.0889)
		(layer "F.Cu")
		(net "M_H_DQ<45>")
	)
	(segment
		(start 124.711968 -28.8544)
		(end 124.711968 -28.3972)
		(width 0.1651)
		(layer "F.Cu")
		(net "M_H_DQ<45>")
	)
	(segment
		(start 112.112044 -49.963578)
		(end 112.229392 -49.84623)
		(width 0.0889)
		(layer "F.Cu")
		(net "M_H_DQ<45>")
	)
	(segment
		(start 123.848876 -27.333956)
		(end 124.208032 -26.9748)
		(width 0.1651)
		(layer "F.Cu")
		(net "M_H_DQ<45>")
	)
	(segment
		(start 112.229392 -46.866556)
		(end 115.948968 -43.14698)
		(width 0.1016)
		(layer "F.Cu")
		(net "M_H_DQ<45>")
	)
	(segment
		(start 123.848876 -27.8765)
		(end 123.848876 -27.333956)
		(width 0.1651)
		(layer "F.Cu")
		(net "M_H_DQ<45>")
	)
	(segment
		(start 124.013976 -28.0416)
		(end 123.848876 -27.8765)
		(width 0.1651)
		(layer "F.Cu")
		(net "M_H_DQ<45>")
	)
	(segment
		(start 115.948968 -43.14698)
		(end 115.948968 -41.2242)
		(width 0.1016)
		(layer "F.Cu")
		(net "M_H_DQ<45>")
	)
	(segment
		(start 111.797592 -50.599086)
		(end 112.112044 -50.284634)
		(width 0.0889)
		(layer "F.Cu")
		(net "M_H_DQ<45>")
	)
	(segment
		(start 124.711968 -28.3972)
		(end 124.356368 -28.0416)
		(width 0.1651)
		(layer "F.Cu")
		(net "M_H_DQ<45>")
	)
	(segment
		(start 124.629164 -26.9748)
		(end 124.82322 -27.168856)
		(width 0.1651)
		(layer "F.Cu")
		(net "M_H_DQ<45>")
	)
	(segment
		(start 112.112044 -50.284634)
		(end 112.112044 -49.963578)
		(width 0.0889)
		(layer "F.Cu")
		(net "M_H_DQ<45>")
	)
	(via
		(at 124.013468 -29.5529)
		(size 0.508)
		(drill 0.254)
		(layers "F.Cu" "B.Cu")
		(net "M_H_DQ<45>")
	)
	(via
		(at 124.82322 -27.168856)
		(size 0.508)
		(drill 0.254)
		(layers "F.Cu" "B.Cu")
		(net "M_H_DQ<45>")
	)
	(via
		(at 124.049536 -7.086346)
		(size 0.508)
		(drill 0.254)
		(layers "F.Cu" "B.Cu")
		(net "M_H_DQ<45>")
	)
	(via
		(at 124.82322 -12.678156)
		(size 0.508)
		(drill 0.254)
		(layers "F.Cu" "B.Cu")
		(net "M_H_DQ<45>")
	)
	(arc
		(start 112.643412 -53.271928)
		(mid 112.521583 -52.969978)
		(end 112.224312 -52.837334)
		(width 0.0889)
		(layer "F.Cu")
		(net "M_H_DQ<45>")
	)
	(arc
		(start 111.856012 -52.237386)
		(mid 111.935143 -51.941984)
		(end 111.856012 -51.646582)
		(width 0.0889)
		(layer "F.Cu")
		(net "M_H_DQ<45>")
	)
	(arc
		(start 111.856012 -51.646582)
		(mid 111.812422 -51.541337)
		(end 111.797592 -51.428396)
		(width 0.0889)
		(layer "F.Cu")
		(net "M_H_DQ<45>")
	)
	(arc
		(start 112.191546 -52.837334)
		(mid 111.853431 -52.632632)
		(end 111.856012 -52.237386)
		(width 0.0889)
		(layer "F.Cu")
		(net "M_H_DQ<45>")
	)
	(segment
		(start 124.89942 -10.623042)
		(end 124.89942 -12.601956)
		(width 0.1651)
		(layer "B.Cu")
		(net "M_H_DQ<45>")
	)
	(segment
		(start 124.89942 -12.601956)
		(end 124.82322 -12.678156)
		(width 0.1651)
		(layer "B.Cu")
		(net "M_H_DQ<45>")
	)
	(segment
		(start 124.781564 -15.570708)
		(end 124.781564 -14.510004)
		(width 0.14224)
		(layer "In11.Cu")
		(net "M_H_DQ<45>")
	)
	(segment
		(start 124.82322 -27.168856)
		(end 125.243844 -26.748232)
		(width 0.14224)
		(layer "In11.Cu")
		(net "M_H_DQ<45>")
	)
	(segment
		(start 125.243844 -23.234396)
		(end 125.320044 -23.158196)
		(width 0.14224)
		(layer "In11.Cu")
		(net "M_H_DQ<45>")
	)
	(segment
		(start 125.218444 -18.531586)
		(end 125.294644 -18.455386)
		(width 0.14224)
		(layer "In11.Cu")
		(net "M_H_DQ<45>")
	)
	(segment
		(start 124.82322 -14.468348)
		(end 124.82322 -12.678156)
		(width 0.14224)
		(layer "In11.Cu")
		(net "M_H_DQ<45>")
	)
	(segment
		(start 125.294644 -18.455386)
		(end 125.294644 -17.109186)
		(width 0.14224)
		(layer "In11.Cu")
		(net "M_H_DQ<45>")
	)
	(segment
		(start 125.218444 -16.007588)
		(end 124.781564 -15.570708)
		(width 0.14224)
		(layer "In11.Cu")
		(net "M_H_DQ<45>")
	)
	(segment
		(start 125.218444 -21.862796)
		(end 125.218444 -21.337524)
		(width 0.14224)
		(layer "In11.Cu")
		(net "M_H_DQ<45>")
	)
	(segment
		(start 124.620274 -8.0518)
		(end 124.330968 -7.762494)
		(width 0.14224)
		(layer "In11.Cu")
		(net "M_H_DQ<45>")
	)
	(segment
		(start 125.331474 -8.452104)
		(end 124.93117 -8.0518)
		(width 0.14224)
		(layer "In11.Cu")
		(net "M_H_DQ<45>")
	)
	(segment
		(start 124.330968 -7.762494)
		(end 124.330968 -7.367778)
		(width 0.14224)
		(layer "In11.Cu")
		(net "M_H_DQ<45>")
	)
	(segment
		(start 125.218444 -18.972276)
		(end 125.218444 -18.531586)
		(width 0.14224)
		(layer "In11.Cu")
		(net "M_H_DQ<45>")
	)
	(segment
		(start 125.331474 -8.8646)
		(end 125.331474 -8.452104)
		(width 0.14224)
		(layer "In11.Cu")
		(net "M_H_DQ<45>")
	)
	(segment
		(start 125.320044 -23.158196)
		(end 125.320044 -21.964396)
		(width 0.14224)
		(layer "In11.Cu")
		(net "M_H_DQ<45>")
	)
	(segment
		(start 125.294644 -17.109186)
		(end 125.218444 -17.032986)
		(width 0.14224)
		(layer "In11.Cu")
		(net "M_H_DQ<45>")
	)
	(segment
		(start 125.346968 -19.1008)
		(end 125.218444 -18.972276)
		(width 0.14224)
		(layer "In11.Cu")
		(net "M_H_DQ<45>")
	)
	(segment
		(start 125.134624 -9.06145)
		(end 125.331474 -8.8646)
		(width 0.14224)
		(layer "In11.Cu")
		(net "M_H_DQ<45>")
	)
	(segment
		(start 125.218444 -17.032986)
		(end 125.218444 -16.007588)
		(width 0.14224)
		(layer "In11.Cu")
		(net "M_H_DQ<45>")
	)
	(segment
		(start 125.320044 -21.964396)
		(end 125.218444 -21.862796)
		(width 0.14224)
		(layer "In11.Cu")
		(net "M_H_DQ<45>")
	)
	(segment
		(start 125.134624 -12.366752)
		(end 125.134624 -9.06145)
		(width 0.14224)
		(layer "In11.Cu")
		(net "M_H_DQ<45>")
	)
	(segment
		(start 124.330968 -7.367778)
		(end 124.049536 -7.086346)
		(width 0.14224)
		(layer "In11.Cu")
		(net "M_H_DQ<45>")
	)
	(segment
		(start 125.243844 -26.748232)
		(end 125.243844 -23.234396)
		(width 0.14224)
		(layer "In11.Cu")
		(net "M_H_DQ<45>")
	)
	(segment
		(start 124.781564 -14.510004)
		(end 124.82322 -14.468348)
		(width 0.14224)
		(layer "In11.Cu")
		(net "M_H_DQ<45>")
	)
	(segment
		(start 124.82322 -12.678156)
		(end 125.134624 -12.366752)
		(width 0.14224)
		(layer "In11.Cu")
		(net "M_H_DQ<45>")
	)
	(segment
		(start 125.346968 -21.209)
		(end 125.346968 -19.1008)
		(width 0.14224)
		(layer "In11.Cu")
		(net "M_H_DQ<45>")
	)
	(segment
		(start 124.93117 -8.0518)
		(end 124.620274 -8.0518)
		(width 0.14224)
		(layer "In11.Cu")
		(net "M_H_DQ<45>")
	)
	(segment
		(start 125.218444 -21.337524)
		(end 125.346968 -21.209)
		(width 0.14224)
		(layer "In11.Cu")
		(net "M_H_DQ<45>")
	)
	(segment
		(start 111.835692 -49.88687)
		(end 111.835692 -46.703234)
		(width 0.1016)
		(layer "F.Cu")
		(net "M_H_DQ<44>")
	)
	(segment
		(start 115.288568 -41.402)
		(end 114.805968 -41.402)
		(width 0.1016)
		(layer "F.Cu")
		(net "M_H_DQ<44>")
	)
	(segment
		(start 111.607092 -51.429412)
		(end 111.607092 -50.520854)
		(width 0.0889)
		(layer "F.Cu")
		(net "M_H_DQ<44>")
	)
	(segment
		(start 114.805968 -41.402)
		(end 114.247168 -41.402)
		(width 0.1651)
		(layer "F.Cu")
		(net "M_H_DQ<44>")
	)
	(segment
		(start 124.862336 -8.89)
		(end 124.838968 -8.763)
		(width 0.1651)
		(layer "F.Cu")
		(net "M_H_DQ<44>")
	)
	(segment
		(start 112.202722 -53.427884)
		(end 111.707422 -52.761388)
		(width 0.0889)
		(layer "F.Cu")
		(net "M_H_DQ<44>")
	)
	(segment
		(start 113.993168 -41.7576)
		(end 113.421668 -41.7576)
		(width 0.1651)
		(layer "F.Cu")
		(net "M_H_DQ<44>")
	)
	(segment
		(start 124.89942 -10.422382)
		(end 124.89942 -9.091168)
		(width 0.1651)
		(layer "F.Cu")
		(net "M_H_DQ<44>")
	)
	(segment
		(start 122.756168 -29.895546)
		(end 124.113036 -28.538678)
		(width 0.1651)
		(layer "F.Cu")
		(net "M_H_DQ<44>")
	)
	(segment
		(start 111.835692 -46.703234)
		(end 115.555268 -42.983658)
		(width 0.1016)
		(layer "F.Cu")
		(net "M_H_DQ<44>")
	)
	(segment
		(start 113.256568 -40.386254)
		(end 122.756168 -30.886654)
		(width 0.1651)
		(layer "F.Cu")
		(net "M_H_DQ<44>")
	)
	(segment
		(start 114.120168 -41.529)
		(end 114.120168 -41.6306)
		(width 0.1651)
		(layer "F.Cu")
		(net "M_H_DQ<44>")
	)
	(segment
		(start 111.922052 -49.97323)
		(end 111.835692 -49.88687)
		(width 0.0889)
		(layer "F.Cu")
		(net "M_H_DQ<44>")
	)
	(segment
		(start 115.555268 -42.983658)
		(end 115.555268 -41.6687)
		(width 0.1016)
		(layer "F.Cu")
		(net "M_H_DQ<44>")
	)
	(segment
		(start 115.555268 -41.6687)
		(end 115.288568 -41.402)
		(width 0.1016)
		(layer "F.Cu")
		(net "M_H_DQ<44>")
	)
	(segment
		(start 124.838968 -8.763)
		(end 124.801376 -8.5598)
		(width 0.1651)
		(layer "F.Cu")
		(net "M_H_DQ<44>")
	)
	(segment
		(start 122.756168 -30.886654)
		(end 122.756168 -29.895546)
		(width 0.1651)
		(layer "F.Cu")
		(net "M_H_DQ<44>")
	)
	(segment
		(start 111.607092 -50.520854)
		(end 111.922052 -50.205894)
		(width 0.0889)
		(layer "F.Cu")
		(net "M_H_DQ<44>")
	)
	(segment
		(start 124.89942 -9.091168)
		(end 124.862336 -8.89)
		(width 0.1651)
		(layer "F.Cu")
		(net "M_H_DQ<44>")
	)
	(segment
		(start 113.421668 -41.7576)
		(end 113.256568 -41.5925)
		(width 0.1651)
		(layer "F.Cu")
		(net "M_H_DQ<44>")
	)
	(segment
		(start 111.922052 -50.205894)
		(end 111.922052 -49.97323)
		(width 0.0889)
		(layer "F.Cu")
		(net "M_H_DQ<44>")
	)
	(segment
		(start 114.120168 -41.6306)
		(end 113.993168 -41.7576)
		(width 0.1651)
		(layer "F.Cu")
		(net "M_H_DQ<44>")
	)
	(segment
		(start 111.707422 -52.761388)
		(end 111.690912 -52.732686)
		(width 0.0889)
		(layer "F.Cu")
		(net "M_H_DQ<44>")
	)
	(segment
		(start 114.247168 -41.402)
		(end 114.120168 -41.529)
		(width 0.1651)
		(layer "F.Cu")
		(net "M_H_DQ<44>")
	)
	(segment
		(start 113.256568 -41.5925)
		(end 113.256568 -40.386254)
		(width 0.1651)
		(layer "F.Cu")
		(net "M_H_DQ<44>")
	)
	(via
		(at 124.801376 -8.5598)
		(size 0.508)
		(drill 0.254)
		(layers "F.Cu" "B.Cu")
		(net "M_H_DQ<44>")
	)
	(via
		(at 124.113036 -28.538678)
		(size 0.508)
		(drill 0.254)
		(layers "F.Cu" "B.Cu")
		(net "M_H_DQ<44>")
	)
	(via
		(at 124.049536 -13.959078)
		(size 0.508)
		(drill 0.254)
		(layers "F.Cu" "B.Cu")
		(net "M_H_DQ<44>")
	)
	(arc
		(start 111.690912 -51.742086)
		(mid 111.62841 -51.591269)
		(end 111.607092 -51.429412)
		(width 0.0889)
		(layer "F.Cu")
		(net "M_H_DQ<44>")
	)
	(arc
		(start 111.690912 -52.732686)
		(mid 111.611781 -52.437284)
		(end 111.690912 -52.141882)
		(width 0.0889)
		(layer "F.Cu")
		(net "M_H_DQ<44>")
	)
	(arc
		(start 111.690912 -52.141882)
		(mid 111.744411 -51.941984)
		(end 111.690912 -51.742086)
		(width 0.0889)
		(layer "F.Cu")
		(net "M_H_DQ<44>")
	)
	(segment
		(start 124.049536 -15.222982)
		(end 124.049536 -13.959078)
		(width 0.1651)
		(layer "B.Cu")
		(net "M_H_DQ<44>")
	)
	(segment
		(start 124.329444 -23.107396)
		(end 124.584968 -23.36292)
		(width 0.14224)
		(layer "In11.Cu")
		(net "M_H_DQ<44>")
	)
	(segment
		(start 124.381768 -21.185124)
		(end 124.532644 -21.336)
		(width 0.14224)
		(layer "In11.Cu")
		(net "M_H_DQ<44>")
	)
	(segment
		(start 124.051568 -11.303)
		(end 124.525024 -11.776456)
		(width 0.14224)
		(layer "In11.Cu")
		(net "M_H_DQ<44>")
	)
	(segment
		(start 124.051568 -9.779)
		(end 124.051568 -9.982454)
		(width 0.14224)
		(layer "In11.Cu")
		(net "M_H_DQ<44>")
	)
	(segment
		(start 124.532644 -18.975324)
		(end 124.381768 -19.1262)
		(width 0.14224)
		(layer "In11.Cu")
		(net "M_H_DQ<44>")
	)
	(segment
		(start 124.113036 -27.218132)
		(end 124.113036 -28.538678)
		(width 0.14224)
		(layer "In11.Cu")
		(net "M_H_DQ<44>")
	)
	(segment
		(start 124.532644 -18.531586)
		(end 124.532644 -18.975324)
		(width 0.14224)
		(layer "In11.Cu")
		(net "M_H_DQ<44>")
	)
	(segment
		(start 124.525024 -12.217654)
		(end 124.229368 -12.51331)
		(width 0.14224)
		(layer "In11.Cu")
		(net "M_H_DQ<44>")
	)
	(segment
		(start 124.381768 -19.1262)
		(end 124.381768 -21.185124)
		(width 0.14224)
		(layer "In11.Cu")
		(net "M_H_DQ<44>")
	)
	(segment
		(start 124.049536 -15.610078)
		(end 124.532644 -16.093186)
		(width 0.14224)
		(layer "In11.Cu")
		(net "M_H_DQ<44>")
	)
	(segment
		(start 124.329444 -21.938996)
		(end 124.329444 -23.107396)
		(width 0.14224)
		(layer "In11.Cu")
		(net "M_H_DQ<44>")
	)
	(segment
		(start 124.525024 -9.305544)
		(end 124.051568 -9.779)
		(width 0.14224)
		(layer "In11.Cu")
		(net "M_H_DQ<44>")
	)
	(segment
		(start 124.532644 -16.841978)
		(end 124.329444 -17.045178)
		(width 0.14224)
		(layer "In11.Cu")
		(net "M_H_DQ<44>")
	)
	(segment
		(start 124.329444 -18.328386)
		(end 124.532644 -18.531586)
		(width 0.14224)
		(layer "In11.Cu")
		(net "M_H_DQ<44>")
	)
	(segment
		(start 124.525024 -11.776456)
		(end 124.525024 -12.217654)
		(width 0.14224)
		(layer "In11.Cu")
		(net "M_H_DQ<44>")
	)
	(segment
		(start 124.532644 -16.093186)
		(end 124.532644 -16.841978)
		(width 0.14224)
		(layer "In11.Cu")
		(net "M_H_DQ<44>")
	)
	(segment
		(start 124.051568 -9.982454)
		(end 124.542042 -10.472928)
		(width 0.14224)
		(layer "In11.Cu")
		(net "M_H_DQ<44>")
	)
	(segment
		(start 124.584968 -23.36292)
		(end 124.584968 -26.7462)
		(width 0.14224)
		(layer "In11.Cu")
		(net "M_H_DQ<44>")
	)
	(segment
		(start 124.542042 -10.659872)
		(end 124.051568 -11.150346)
		(width 0.14224)
		(layer "In11.Cu")
		(net "M_H_DQ<44>")
	)
	(segment
		(start 124.532644 -21.735796)
		(end 124.329444 -21.938996)
		(width 0.14224)
		(layer "In11.Cu")
		(net "M_H_DQ<44>")
	)
	(segment
		(start 124.049536 -13.959078)
		(end 124.049536 -15.610078)
		(width 0.14224)
		(layer "In11.Cu")
		(net "M_H_DQ<44>")
	)
	(segment
		(start 124.229368 -12.51331)
		(end 124.229368 -13.779246)
		(width 0.14224)
		(layer "In11.Cu")
		(net "M_H_DQ<44>")
	)
	(segment
		(start 124.532644 -21.336)
		(end 124.532644 -21.735796)
		(width 0.14224)
		(layer "In11.Cu")
		(net "M_H_DQ<44>")
	)
	(segment
		(start 124.542042 -10.472928)
		(end 124.542042 -10.659872)
		(width 0.14224)
		(layer "In11.Cu")
		(net "M_H_DQ<44>")
	)
	(segment
		(start 124.329444 -17.045178)
		(end 124.329444 -18.328386)
		(width 0.14224)
		(layer "In11.Cu")
		(net "M_H_DQ<44>")
	)
	(segment
		(start 124.051568 -11.150346)
		(end 124.051568 -11.303)
		(width 0.14224)
		(layer "In11.Cu")
		(net "M_H_DQ<44>")
	)
	(segment
		(start 124.229368 -13.779246)
		(end 124.049536 -13.959078)
		(width 0.14224)
		(layer "In11.Cu")
		(net "M_H_DQ<44>")
	)
	(segment
		(start 124.584968 -26.7462)
		(end 124.113036 -27.218132)
		(width 0.14224)
		(layer "In11.Cu")
		(net "M_H_DQ<44>")
	)
	(segment
		(start 124.525024 -8.836152)
		(end 124.525024 -9.305544)
		(width 0.14224)
		(layer "In11.Cu")
		(net "M_H_DQ<44>")
	)
	(segment
		(start 124.801376 -8.5598)
		(end 124.525024 -8.836152)
		(width 0.14224)
		(layer "In11.Cu")
		(net "M_H_DQ<44>")
	)
	(segment
		(start 125.931168 -38.5572)
		(end 127.861568 -38.5572)
		(width 0.1651)
		(layer "F.Cu")
		(net "M_H_DQ<43>")
	)
	(segment
		(start 131.699508 -5.822442)
		(end 131.699508 -7.086346)
		(width 0.1651)
		(layer "F.Cu")
		(net "M_H_DQ<43>")
	)
	(segment
		(start 116.143786 -51.750722)
		(end 116.202714 -51.645566)
		(width 0.0889)
		(layer "F.Cu")
		(net "M_H_DQ<43>")
	)
	(segment
		(start 116.354352 -49.630584)
		(end 116.166392 -49.442624)
		(width 0.1016)
		(layer "F.Cu")
		(net "M_H_DQ<43>")
	)
	(segment
		(start 116.354352 -50.358548)
		(end 116.354352 -50.139854)
		(width 0.0889)
		(layer "F.Cu")
		(net "M_H_DQ<43>")
	)
	(segment
		(start 124.005594 -40.482774)
		(end 125.931168 -38.5572)
		(width 0.1651)
		(layer "F.Cu")
		(net "M_H_DQ<43>")
	)
	(segment
		(start 132.347208 -34.07156)
		(end 132.347208 -29.718)
		(width 0.1651)
		(layer "F.Cu")
		(net "M_H_DQ<43>")
	)
	(segment
		(start 116.166392 -49.442624)
		(end 116.166392 -48.499776)
		(width 0.1016)
		(layer "F.Cu")
		(net "M_H_DQ<43>")
	)
	(segment
		(start 124.005594 -41.168574)
		(end 124.005594 -40.482774)
		(width 0.1651)
		(layer "F.Cu")
		(net "M_H_DQ<43>")
	)
	(segment
		(start 132.347208 -28.53944)
		(end 132.865368 -28.02128)
		(width 0.1651)
		(layer "F.Cu")
		(net "M_H_DQ<43>")
	)
	(segment
		(start 122.527568 -42.1386)
		(end 123.035568 -42.1386)
		(width 0.1016)
		(layer "F.Cu")
		(net "M_H_DQ<43>")
	)
	(segment
		(start 116.166392 -48.499776)
		(end 122.527568 -42.1386)
		(width 0.1016)
		(layer "F.Cu")
		(net "M_H_DQ<43>")
	)
	(segment
		(start 116.09451 -50.809144)
		(end 116.354352 -50.358548)
		(width 0.0889)
		(layer "F.Cu")
		(net "M_H_DQ<43>")
	)
	(segment
		(start 115.967002 -52.665884)
		(end 115.983512 -52.637436)
		(width 0.0889)
		(layer "F.Cu")
		(net "M_H_DQ<43>")
	)
	(segment
		(start 116.09451 -51.03241)
		(end 116.09451 -50.809144)
		(width 0.0889)
		(layer "F.Cu")
		(net "M_H_DQ<43>")
	)
	(segment
		(start 116.354352 -50.139854)
		(end 116.354352 -49.630584)
		(width 0.1016)
		(layer "F.Cu")
		(net "M_H_DQ<43>")
	)
	(segment
		(start 132.347208 -29.718)
		(end 132.347208 -28.53944)
		(width 0.1651)
		(layer "F.Cu")
		(net "M_H_DQ<43>")
	)
	(segment
		(start 127.861568 -38.5572)
		(end 132.347208 -34.07156)
		(width 0.1651)
		(layer "F.Cu")
		(net "M_H_DQ<43>")
	)
	(segment
		(start 115.636802 -53.427884)
		(end 115.967002 -52.665884)
		(width 0.0889)
		(layer "F.Cu")
		(net "M_H_DQ<43>")
	)
	(segment
		(start 123.035568 -42.1386)
		(end 124.005594 -41.168574)
		(width 0.1651)
		(layer "F.Cu")
		(net "M_H_DQ<43>")
	)
	(segment
		(start 116.202714 -51.219862)
		(end 116.09451 -51.03241)
		(width 0.0889)
		(layer "F.Cu")
		(net "M_H_DQ<43>")
	)
	(segment
		(start 132.865368 -28.02128)
		(end 132.865368 -27.671522)
		(width 0.1651)
		(layer "F.Cu")
		(net "M_H_DQ<43>")
	)
	(segment
		(start 116.202714 -51.645566)
		(end 116.202714 -51.219862)
		(width 0.0889)
		(layer "F.Cu")
		(net "M_H_DQ<43>")
	)
	(segment
		(start 132.865368 -27.671522)
		(end 132.362702 -27.168856)
		(width 0.1651)
		(layer "F.Cu")
		(net "M_H_DQ<43>")
	)
	(via
		(at 132.549392 -12.678156)
		(size 0.508)
		(drill 0.254)
		(layers "F.Cu" "B.Cu")
		(net "M_H_DQ<43>")
	)
	(via
		(at 132.347208 -29.718)
		(size 0.508)
		(drill 0.254)
		(layers "F.Cu" "B.Cu")
		(net "M_H_DQ<43>")
	)
	(via
		(at 132.362702 -27.168856)
		(size 0.508)
		(drill 0.254)
		(layers "F.Cu" "B.Cu")
		(net "M_H_DQ<43>")
	)
	(via
		(at 131.699508 -7.086346)
		(size 0.508)
		(drill 0.254)
		(layers "F.Cu" "B.Cu")
		(net "M_H_DQ<43>")
	)
	(arc
		(start 116.095018 -51.940714)
		(mid 116.107591 -51.842687)
		(end 116.143786 -51.750722)
		(width 0.0889)
		(layer "F.Cu")
		(net "M_H_DQ<43>")
	)
	(arc
		(start 115.983512 -52.637436)
		(mid 116.066966 -52.293508)
		(end 116.095018 -51.940714)
		(width 0.0889)
		(layer "F.Cu")
		(net "M_H_DQ<43>")
	)
	(segment
		(start 132.549392 -10.623042)
		(end 132.549392 -12.678156)
		(width 0.1651)
		(layer "B.Cu")
		(net "M_H_DQ<43>")
	)
	(segment
		(start 133.057646 -8.8646)
		(end 133.057646 -8.509)
		(width 0.14224)
		(layer "In11.Cu")
		(net "M_H_DQ<43>")
	)
	(segment
		(start 132.863844 -18.619978)
		(end 133.016244 -18.467578)
		(width 0.14224)
		(layer "In11.Cu")
		(net "M_H_DQ<43>")
	)
	(segment
		(start 132.600446 -8.0518)
		(end 132.346446 -8.0518)
		(width 0.14224)
		(layer "In11.Cu")
		(net "M_H_DQ<43>")
	)
	(segment
		(start 132.863844 -21.3868)
		(end 133.017768 -21.232876)
		(width 0.14224)
		(layer "In11.Cu")
		(net "M_H_DQ<43>")
	)
	(segment
		(start 132.346446 -8.0518)
		(end 132.016246 -7.7216)
		(width 0.14224)
		(layer "In11.Cu")
		(net "M_H_DQ<43>")
	)
	(segment
		(start 132.362702 -27.168856)
		(end 132.863844 -26.667714)
		(width 0.14224)
		(layer "In11.Cu")
		(net "M_H_DQ<43>")
	)
	(segment
		(start 132.902198 -9.020048)
		(end 133.057646 -8.8646)
		(width 0.14224)
		(layer "In11.Cu")
		(net "M_H_DQ<43>")
	)
	(segment
		(start 132.863844 -26.667714)
		(end 132.863844 -23.330916)
		(width 0.14224)
		(layer "In11.Cu")
		(net "M_H_DQ<43>")
	)
	(segment
		(start 132.016246 -7.403084)
		(end 131.699508 -7.086346)
		(width 0.14224)
		(layer "In11.Cu")
		(net "M_H_DQ<43>")
	)
	(segment
		(start 133.017768 -19.2024)
		(end 132.863844 -19.048476)
		(width 0.14224)
		(layer "In11.Cu")
		(net "M_H_DQ<43>")
	)
	(segment
		(start 132.87248 -14.426692)
		(end 132.052568 -13.60678)
		(width 0.14224)
		(layer "In11.Cu")
		(net "M_H_DQ<43>")
	)
	(segment
		(start 133.057646 -8.509)
		(end 132.600446 -8.0518)
		(width 0.14224)
		(layer "In11.Cu")
		(net "M_H_DQ<43>")
	)
	(segment
		(start 133.041644 -21.969476)
		(end 132.863844 -21.791676)
		(width 0.14224)
		(layer "In11.Cu")
		(net "M_H_DQ<43>")
	)
	(segment
		(start 133.016244 -16.987266)
		(end 132.87248 -16.843502)
		(width 0.14224)
		(layer "In11.Cu")
		(net "M_H_DQ<43>")
	)
	(segment
		(start 132.052568 -13.60678)
		(end 132.052568 -13.17498)
		(width 0.14224)
		(layer "In11.Cu")
		(net "M_H_DQ<43>")
	)
	(segment
		(start 133.041644 -23.153116)
		(end 133.041644 -21.969476)
		(width 0.14224)
		(layer "In11.Cu")
		(net "M_H_DQ<43>")
	)
	(segment
		(start 132.549392 -12.678156)
		(end 132.902198 -12.32535)
		(width 0.14224)
		(layer "In11.Cu")
		(net "M_H_DQ<43>")
	)
	(segment
		(start 132.863844 -23.330916)
		(end 133.041644 -23.153116)
		(width 0.14224)
		(layer "In11.Cu")
		(net "M_H_DQ<43>")
	)
	(segment
		(start 132.016246 -7.7216)
		(end 132.016246 -7.403084)
		(width 0.14224)
		(layer "In11.Cu")
		(net "M_H_DQ<43>")
	)
	(segment
		(start 132.052568 -13.17498)
		(end 132.549392 -12.678156)
		(width 0.14224)
		(layer "In11.Cu")
		(net "M_H_DQ<43>")
	)
	(segment
		(start 132.902198 -12.32535)
		(end 132.902198 -9.020048)
		(width 0.14224)
		(layer "In11.Cu")
		(net "M_H_DQ<43>")
	)
	(segment
		(start 132.863844 -21.791676)
		(end 132.863844 -21.3868)
		(width 0.14224)
		(layer "In11.Cu")
		(net "M_H_DQ<43>")
	)
	(segment
		(start 133.017768 -21.232876)
		(end 133.017768 -19.2024)
		(width 0.14224)
		(layer "In11.Cu")
		(net "M_H_DQ<43>")
	)
	(segment
		(start 133.016244 -18.467578)
		(end 133.016244 -16.987266)
		(width 0.14224)
		(layer "In11.Cu")
		(net "M_H_DQ<43>")
	)
	(segment
		(start 132.87248 -16.843502)
		(end 132.87248 -14.426692)
		(width 0.14224)
		(layer "In11.Cu")
		(net "M_H_DQ<43>")
	)
	(segment
		(start 132.863844 -19.048476)
		(end 132.863844 -18.619978)
		(width 0.14224)
		(layer "In11.Cu")
		(net "M_H_DQ<43>")
	)
	(segment
		(start 125.651768 -37.8968)
		(end 127.531368 -37.8968)
		(width 0.1651)
		(layer "F.Cu")
		(net "M_H_DQ<42>")
	)
	(segment
		(start 132.549392 -8.938768)
		(end 132.549392 -8.6614)
		(width 0.1651)
		(layer "F.Cu")
		(net "M_H_DQ<42>")
	)
	(segment
		(start 130.769868 -31.877)
		(end 131.487418 -31.877)
		(width 0.1651)
		(layer "F.Cu")
		(net "M_H_DQ<42>")
	)
	(segment
		(start 123.365768 -40.1828)
		(end 125.651768 -37.8968)
		(width 0.1651)
		(layer "F.Cu")
		(net "M_H_DQ<42>")
	)
	(segment
		(start 116.036852 -50.52822)
		(end 116.036852 -50.062384)
		(width 0.0889)
		(layer "F.Cu")
		(net "M_H_DQ<42>")
	)
	(segment
		(start 131.652518 -30.124146)
		(end 131.652518 -28.538678)
		(width 0.1651)
		(layer "F.Cu")
		(net "M_H_DQ<42>")
	)
	(segment
		(start 130.846068 -30.289246)
		(end 131.487418 -30.289246)
		(width 0.1651)
		(layer "F.Cu")
		(net "M_H_DQ<42>")
	)
	(segment
		(start 131.652518 -31.7119)
		(end 131.652518 -31.127446)
		(width 0.1651)
		(layer "F.Cu")
		(net "M_H_DQ<42>")
	)
	(segment
		(start 127.531368 -37.8968)
		(end 131.176268 -34.2519)
		(width 0.1651)
		(layer "F.Cu")
		(net "M_H_DQ<42>")
	)
	(segment
		(start 131.487418 -30.962346)
		(end 130.846068 -30.962346)
		(width 0.1651)
		(layer "F.Cu")
		(net "M_H_DQ<42>")
	)
	(segment
		(start 130.604768 -32.390842)
		(end 130.604768 -32.0421)
		(width 0.1651)
		(layer "F.Cu")
		(net "M_H_DQ<42>")
	)
	(segment
		(start 115.636802 -52.437538)
		(end 116.012214 -51.570382)
		(width 0.0889)
		(layer "F.Cu")
		(net "M_H_DQ<42>")
	)
	(segment
		(start 122.503184 -41.605962)
		(end 123.365768 -40.743378)
		(width 0.1651)
		(layer "F.Cu")
		(net "M_H_DQ<42>")
	)
	(segment
		(start 130.846068 -30.962346)
		(end 130.680968 -30.797246)
		(width 0.1651)
		(layer "F.Cu")
		(net "M_H_DQ<42>")
	)
	(segment
		(start 116.012214 -51.270916)
		(end 115.90401 -51.083718)
		(width 0.0889)
		(layer "F.Cu")
		(net "M_H_DQ<42>")
	)
	(segment
		(start 115.90401 -50.758344)
		(end 116.036852 -50.52822)
		(width 0.0889)
		(layer "F.Cu")
		(net "M_H_DQ<42>")
	)
	(segment
		(start 131.487418 -30.289246)
		(end 131.652518 -30.124146)
		(width 0.1651)
		(layer "F.Cu")
		(net "M_H_DQ<42>")
	)
	(segment
		(start 131.176268 -34.2519)
		(end 131.176268 -33.147)
		(width 0.1651)
		(layer "F.Cu")
		(net "M_H_DQ<42>")
	)
	(segment
		(start 115.772692 -48.336454)
		(end 122.503184 -41.605962)
		(width 0.1016)
		(layer "F.Cu")
		(net "M_H_DQ<42>")
	)
	(segment
		(start 116.012214 -51.570382)
		(end 116.012214 -51.270916)
		(width 0.0889)
		(layer "F.Cu")
		(net "M_H_DQ<42>")
	)
	(segment
		(start 115.90401 -51.083718)
		(end 115.90401 -50.758344)
		(width 0.0889)
		(layer "F.Cu")
		(net "M_H_DQ<42>")
	)
	(segment
		(start 115.772692 -49.798224)
		(end 115.772692 -48.336454)
		(width 0.1016)
		(layer "F.Cu")
		(net "M_H_DQ<42>")
	)
	(segment
		(start 130.604768 -32.0421)
		(end 130.769868 -31.877)
		(width 0.1651)
		(layer "F.Cu")
		(net "M_H_DQ<42>")
	)
	(segment
		(start 116.036852 -50.062384)
		(end 115.772692 -49.798224)
		(width 0.0889)
		(layer "F.Cu")
		(net "M_H_DQ<42>")
	)
	(segment
		(start 130.680968 -30.797246)
		(end 130.680968 -30.454346)
		(width 0.1651)
		(layer "F.Cu")
		(net "M_H_DQ<42>")
	)
	(segment
		(start 130.680968 -30.454346)
		(end 130.846068 -30.289246)
		(width 0.1651)
		(layer "F.Cu")
		(net "M_H_DQ<42>")
	)
	(segment
		(start 132.549392 -9.425432)
		(end 132.680964 -9.29386)
		(width 0.1651)
		(layer "F.Cu")
		(net "M_H_DQ<42>")
	)
	(segment
		(start 123.365768 -40.743378)
		(end 123.365768 -40.1828)
		(width 0.1651)
		(layer "F.Cu")
		(net "M_H_DQ<42>")
	)
	(segment
		(start 131.487418 -31.877)
		(end 131.652518 -31.7119)
		(width 0.1651)
		(layer "F.Cu")
		(net "M_H_DQ<42>")
	)
	(segment
		(start 131.652518 -31.127446)
		(end 131.487418 -30.962346)
		(width 0.1651)
		(layer "F.Cu")
		(net "M_H_DQ<42>")
	)
	(segment
		(start 132.549392 -10.422382)
		(end 132.549392 -9.425432)
		(width 0.1651)
		(layer "F.Cu")
		(net "M_H_DQ<42>")
	)
	(segment
		(start 130.769868 -32.555942)
		(end 130.604768 -32.390842)
		(width 0.1651)
		(layer "F.Cu")
		(net "M_H_DQ<42>")
	)
	(segment
		(start 132.680964 -9.07034)
		(end 132.549392 -8.938768)
		(width 0.1651)
		(layer "F.Cu")
		(net "M_H_DQ<42>")
	)
	(segment
		(start 131.176268 -33.147)
		(end 131.176268 -32.721042)
		(width 0.1651)
		(layer "F.Cu")
		(net "M_H_DQ<42>")
	)
	(segment
		(start 132.680964 -9.29386)
		(end 132.680964 -9.07034)
		(width 0.1651)
		(layer "F.Cu")
		(net "M_H_DQ<42>")
	)
	(segment
		(start 131.176268 -32.721042)
		(end 131.011168 -32.555942)
		(width 0.1651)
		(layer "F.Cu")
		(net "M_H_DQ<42>")
	)
	(segment
		(start 131.011168 -32.555942)
		(end 130.769868 -32.555942)
		(width 0.1651)
		(layer "F.Cu")
		(net "M_H_DQ<42>")
	)
	(via
		(at 131.699508 -13.959078)
		(size 0.508)
		(drill 0.254)
		(layers "F.Cu" "B.Cu")
		(net "M_H_DQ<42>")
	)
	(via
		(at 132.549392 -8.6614)
		(size 0.508)
		(drill 0.254)
		(layers "F.Cu" "B.Cu")
		(net "M_H_DQ<42>")
	)
	(via
		(at 131.176268 -33.147)
		(size 0.508)
		(drill 0.254)
		(layers "F.Cu" "B.Cu")
		(net "M_H_DQ<42>")
	)
	(via
		(at 131.652518 -28.538678)
		(size 0.508)
		(drill 0.254)
		(layers "F.Cu" "B.Cu")
		(net "M_H_DQ<42>")
	)
	(segment
		(start 131.699508 -15.222982)
		(end 131.699508 -13.959078)
		(width 0.1651)
		(layer "B.Cu")
		(net "M_H_DQ<42>")
	)
	(segment
		(start 132.111242 -10.362946)
		(end 132.111242 -10.64895)
		(width 0.14224)
		(layer "In11.Cu")
		(net "M_H_DQ<42>")
	)
	(segment
		(start 132.263642 -11.811)
		(end 132.263642 -12.079732)
		(width 0.14224)
		(layer "In11.Cu")
		(net "M_H_DQ<42>")
	)
	(segment
		(start 132.203444 -23.335996)
		(end 132.203444 -26.646124)
		(width 0.14224)
		(layer "In11.Cu")
		(net "M_H_DQ<42>")
	)
	(segment
		(start 131.806442 -10.95375)
		(end 131.806442 -11.3538)
		(width 0.14224)
		(layer "In11.Cu")
		(net "M_H_DQ<42>")
	)
	(segment
		(start 131.699508 -13.959078)
		(end 132.198364 -14.457934)
		(width 0.14224)
		(layer "In11.Cu")
		(net "M_H_DQ<42>")
	)
	(segment
		(start 132.228844 -21.786596)
		(end 132.076444 -21.938996)
		(width 0.14224)
		(layer "In11.Cu")
		(net "M_H_DQ<42>")
	)
	(segment
		(start 131.806442 -10.058146)
		(end 132.111242 -10.362946)
		(width 0.14224)
		(layer "In11.Cu")
		(net "M_H_DQ<42>")
	)
	(segment
		(start 132.549392 -8.6614)
		(end 132.151374 -9.059418)
		(width 0.14224)
		(layer "In11.Cu")
		(net "M_H_DQ<42>")
	)
	(segment
		(start 132.151374 -9.059418)
		(end 132.151374 -9.364472)
		(width 0.14224)
		(layer "In11.Cu")
		(net "M_H_DQ<42>")
	)
	(segment
		(start 132.076444 -21.938996)
		(end 132.076444 -23.208996)
		(width 0.14224)
		(layer "In11.Cu")
		(net "M_H_DQ<42>")
	)
	(segment
		(start 131.806442 -11.3538)
		(end 132.263642 -11.811)
		(width 0.14224)
		(layer "In11.Cu")
		(net "M_H_DQ<42>")
	)
	(segment
		(start 132.263642 -12.079732)
		(end 131.414774 -12.9286)
		(width 0.14224)
		(layer "In11.Cu")
		(net "M_H_DQ<42>")
	)
	(segment
		(start 132.025644 -18.43913)
		(end 132.228844 -18.64233)
		(width 0.14224)
		(layer "In11.Cu")
		(net "M_H_DQ<42>")
	)
	(segment
		(start 132.228844 -18.64233)
		(end 132.228844 -18.975324)
		(width 0.14224)
		(layer "In11.Cu")
		(net "M_H_DQ<42>")
	)
	(segment
		(start 132.198364 -16.911066)
		(end 132.025644 -17.083786)
		(width 0.14224)
		(layer "In11.Cu")
		(net "M_H_DQ<42>")
	)
	(segment
		(start 132.228844 -18.975324)
		(end 132.027168 -19.177)
		(width 0.14224)
		(layer "In11.Cu")
		(net "M_H_DQ<42>")
	)
	(segment
		(start 132.198364 -14.457934)
		(end 132.198364 -16.911066)
		(width 0.14224)
		(layer "In11.Cu")
		(net "M_H_DQ<42>")
	)
	(segment
		(start 131.652518 -27.19705)
		(end 131.652518 -28.538678)
		(width 0.14224)
		(layer "In11.Cu")
		(net "M_H_DQ<42>")
	)
	(segment
		(start 132.025644 -17.083786)
		(end 132.025644 -18.43913)
		(width 0.14224)
		(layer "In11.Cu")
		(net "M_H_DQ<42>")
	)
	(segment
		(start 132.076444 -23.208996)
		(end 132.203444 -23.335996)
		(width 0.14224)
		(layer "In11.Cu")
		(net "M_H_DQ<42>")
	)
	(segment
		(start 132.027168 -19.177)
		(end 132.027168 -21.159724)
		(width 0.14224)
		(layer "In11.Cu")
		(net "M_H_DQ<42>")
	)
	(segment
		(start 131.414774 -12.9286)
		(end 131.414774 -13.674344)
		(width 0.14224)
		(layer "In11.Cu")
		(net "M_H_DQ<42>")
	)
	(segment
		(start 132.111242 -10.64895)
		(end 131.806442 -10.95375)
		(width 0.14224)
		(layer "In11.Cu")
		(net "M_H_DQ<42>")
	)
	(segment
		(start 131.806442 -9.709404)
		(end 131.806442 -10.058146)
		(width 0.14224)
		(layer "In11.Cu")
		(net "M_H_DQ<42>")
	)
	(segment
		(start 132.203444 -26.646124)
		(end 131.652518 -27.19705)
		(width 0.14224)
		(layer "In11.Cu")
		(net "M_H_DQ<42>")
	)
	(segment
		(start 132.027168 -21.159724)
		(end 132.228844 -21.3614)
		(width 0.14224)
		(layer "In11.Cu")
		(net "M_H_DQ<42>")
	)
	(segment
		(start 131.414774 -13.674344)
		(end 131.699508 -13.959078)
		(width 0.14224)
		(layer "In11.Cu")
		(net "M_H_DQ<42>")
	)
	(segment
		(start 132.151374 -9.364472)
		(end 131.806442 -9.709404)
		(width 0.14224)
		(layer "In11.Cu")
		(net "M_H_DQ<42>")
	)
	(segment
		(start 132.228844 -21.3614)
		(end 132.228844 -21.786596)
		(width 0.14224)
		(layer "In11.Cu")
		(net "M_H_DQ<42>")
	)
	(segment
		(start 112.97539 -50.103024)
		(end 113.016792 -50.061622)
		(width 0.0889)
		(layer "F.Cu")
		(net "M_H_DQ<41>")
	)
	(segment
		(start 126.337568 -30.9626)
		(end 126.464568 -30.8356)
		(width 0.1651)
		(layer "F.Cu")
		(net "M_H_DQ<41>")
	)
	(segment
		(start 126.256542 -25.781)
		(end 126.421642 -25.9461)
		(width 0.1651)
		(layer "F.Cu")
		(net "M_H_DQ<41>")
	)
	(segment
		(start 117.269768 -40.9956)
		(end 117.269768 -39.881048)
		(width 0.1651)
		(layer "F.Cu")
		(net "M_H_DQ<41>")
	)
	(segment
		(start 113.061242 -51.941984)
		(end 112.97539 -51.856132)
		(width 0.0889)
		(layer "F.Cu")
		(net "M_H_DQ<41>")
	)
	(segment
		(start 125.651768 -27.1272)
		(end 125.245368 -26.7208)
		(width 0.1651)
		(layer "F.Cu")
		(net "M_H_DQ<41>")
	)
	(segment
		(start 126.213108 -30.22854)
		(end 126.213108 -29.464)
		(width 0.1651)
		(layer "F.Cu")
		(net "M_H_DQ<41>")
	)
	(segment
		(start 123.078494 -33.840674)
		(end 125.956568 -30.9626)
		(width 0.1651)
		(layer "F.Cu")
		(net "M_H_DQ<41>")
	)
	(segment
		(start 125.651768 -27.742896)
		(end 125.651768 -27.1272)
		(width 0.1651)
		(layer "F.Cu")
		(net "M_H_DQ<41>")
	)
	(segment
		(start 126.421642 -25.9461)
		(end 126.421642 -27.168856)
		(width 0.1651)
		(layer "F.Cu")
		(net "M_H_DQ<41>")
	)
	(segment
		(start 113.016792 -47.1932)
		(end 116.736368 -43.473624)
		(width 0.1016)
		(layer "F.Cu")
		(net "M_H_DQ<41>")
	)
	(segment
		(start 121.740168 -36.2204)
		(end 123.078494 -34.882074)
		(width 0.1651)
		(layer "F.Cu")
		(net "M_H_DQ<41>")
	)
	(segment
		(start 113.016792 -50.061622)
		(end 113.016792 -49.959514)
		(width 0.0889)
		(layer "F.Cu")
		(net "M_H_DQ<41>")
	)
	(segment
		(start 126.464568 -30.8356)
		(end 126.464568 -30.48)
		(width 0.1651)
		(layer "F.Cu")
		(net "M_H_DQ<41>")
	)
	(segment
		(start 125.245368 -26.7208)
		(end 125.245368 -26.2382)
		(width 0.1651)
		(layer "F.Cu")
		(net "M_H_DQ<41>")
	)
	(segment
		(start 125.245368 -26.2382)
		(end 125.702568 -25.781)
		(width 0.1651)
		(layer "F.Cu")
		(net "M_H_DQ<41>")
	)
	(segment
		(start 116.736368 -41.529)
		(end 117.269768 -40.9956)
		(width 0.1016)
		(layer "F.Cu")
		(net "M_H_DQ<41>")
	)
	(segment
		(start 112.97539 -51.856132)
		(end 112.97539 -50.103024)
		(width 0.0889)
		(layer "F.Cu")
		(net "M_H_DQ<41>")
	)
	(segment
		(start 113.016792 -49.959514)
		(end 113.016792 -47.1932)
		(width 0.1016)
		(layer "F.Cu")
		(net "M_H_DQ<41>")
	)
	(segment
		(start 126.464568 -30.48)
		(end 126.213108 -30.22854)
		(width 0.1651)
		(layer "F.Cu")
		(net "M_H_DQ<41>")
	)
	(segment
		(start 117.269768 -39.881048)
		(end 120.930416 -36.2204)
		(width 0.1651)
		(layer "F.Cu")
		(net "M_H_DQ<41>")
	)
	(segment
		(start 116.736368 -43.473624)
		(end 116.736368 -41.529)
		(width 0.1016)
		(layer "F.Cu")
		(net "M_H_DQ<41>")
	)
	(segment
		(start 123.078494 -34.882074)
		(end 123.078494 -33.840674)
		(width 0.1651)
		(layer "F.Cu")
		(net "M_H_DQ<41>")
	)
	(segment
		(start 120.930416 -36.2204)
		(end 121.740168 -36.2204)
		(width 0.1651)
		(layer "F.Cu")
		(net "M_H_DQ<41>")
	)
	(segment
		(start 126.213108 -28.304236)
		(end 125.651768 -27.742896)
		(width 0.1651)
		(layer "F.Cu")
		(net "M_H_DQ<41>")
	)
	(segment
		(start 125.749558 -5.822442)
		(end 125.749558 -7.086346)
		(width 0.1651)
		(layer "F.Cu")
		(net "M_H_DQ<41>")
	)
	(segment
		(start 126.213108 -29.464)
		(end 126.213108 -28.304236)
		(width 0.1651)
		(layer "F.Cu")
		(net "M_H_DQ<41>")
	)
	(segment
		(start 125.956568 -30.9626)
		(end 126.337568 -30.9626)
		(width 0.1651)
		(layer "F.Cu")
		(net "M_H_DQ<41>")
	)
	(segment
		(start 125.702568 -25.781)
		(end 126.256542 -25.781)
		(width 0.1651)
		(layer "F.Cu")
		(net "M_H_DQ<41>")
	)
	(via
		(at 126.421642 -27.168856)
		(size 0.508)
		(drill 0.254)
		(layers "F.Cu" "B.Cu")
		(net "M_H_DQ<41>")
	)
	(via
		(at 126.213108 -29.464)
		(size 0.508)
		(drill 0.254)
		(layers "F.Cu" "B.Cu")
		(net "M_H_DQ<41>")
	)
	(via
		(at 126.421642 -12.678156)
		(size 0.508)
		(drill 0.254)
		(layers "F.Cu" "B.Cu")
		(net "M_H_DQ<41>")
	)
	(via
		(at 125.749558 -7.086346)
		(size 0.508)
		(drill 0.254)
		(layers "F.Cu" "B.Cu")
		(net "M_H_DQ<41>")
	)
	(segment
		(start 126.599442 -10.623042)
		(end 126.599442 -11.997182)
		(width 0.1651)
		(layer "B.Cu")
		(net "M_H_DQ<41>")
	)
	(segment
		(start 126.421642 -12.174982)
		(end 126.421642 -12.678156)
		(width 0.1651)
		(layer "B.Cu")
		(net "M_H_DQ<41>")
	)
	(segment
		(start 126.599442 -11.997182)
		(end 126.421642 -12.174982)
		(width 0.1651)
		(layer "B.Cu")
		(net "M_H_DQ<41>")
	)
	(segment
		(start 126.795784 -12.304014)
		(end 126.421642 -12.678156)
		(width 0.14224)
		(layer "In11.Cu")
		(net "M_H_DQ<41>")
	)
	(segment
		(start 126.226824 -8.1026)
		(end 126.582424 -8.1026)
		(width 0.14224)
		(layer "In11.Cu")
		(net "M_H_DQ<41>")
	)
	(segment
		(start 126.894844 -26.695654)
		(end 126.421642 -27.168856)
		(width 0.14224)
		(layer "In11.Cu")
		(net "M_H_DQ<41>")
	)
	(segment
		(start 126.894844 -21.3106)
		(end 126.894844 -26.695654)
		(width 0.14224)
		(layer "In11.Cu")
		(net "M_H_DQ<41>")
	)
	(segment
		(start 126.254764 -13.810996)
		(end 126.254764 -15.580106)
		(width 0.14224)
		(layer "In11.Cu")
		(net "M_H_DQ<41>")
	)
	(segment
		(start 126.894844 -16.220186)
		(end 126.894844 -18.946876)
		(width 0.14224)
		(layer "In11.Cu")
		(net "M_H_DQ<41>")
	)
	(segment
		(start 125.981968 -13.5382)
		(end 126.254764 -13.810996)
		(width 0.14224)
		(layer "In11.Cu")
		(net "M_H_DQ<41>")
	)
	(segment
		(start 126.952248 -8.472424)
		(end 126.952248 -8.8138)
		(width 0.14224)
		(layer "In11.Cu")
		(net "M_H_DQ<41>")
	)
	(segment
		(start 127.048768 -21.156676)
		(end 126.894844 -21.3106)
		(width 0.14224)
		(layer "In11.Cu")
		(net "M_H_DQ<41>")
	)
	(segment
		(start 126.582424 -8.1026)
		(end 126.952248 -8.472424)
		(width 0.14224)
		(layer "In11.Cu")
		(net "M_H_DQ<41>")
	)
	(segment
		(start 126.421642 -12.678156)
		(end 125.981968 -13.11783)
		(width 0.14224)
		(layer "In11.Cu")
		(net "M_H_DQ<41>")
	)
	(segment
		(start 126.795784 -8.970264)
		(end 126.795784 -12.304014)
		(width 0.14224)
		(layer "In11.Cu")
		(net "M_H_DQ<41>")
	)
	(segment
		(start 126.952248 -8.8138)
		(end 126.795784 -8.970264)
		(width 0.14224)
		(layer "In11.Cu")
		(net "M_H_DQ<41>")
	)
	(segment
		(start 125.749558 -7.086346)
		(end 125.749558 -7.625334)
		(width 0.14224)
		(layer "In11.Cu")
		(net "M_H_DQ<41>")
	)
	(segment
		(start 126.254764 -15.580106)
		(end 126.894844 -16.220186)
		(width 0.14224)
		(layer "In11.Cu")
		(net "M_H_DQ<41>")
	)
	(segment
		(start 125.981968 -13.11783)
		(end 125.981968 -13.5382)
		(width 0.14224)
		(layer "In11.Cu")
		(net "M_H_DQ<41>")
	)
	(segment
		(start 126.894844 -18.946876)
		(end 127.048768 -19.1008)
		(width 0.14224)
		(layer "In11.Cu")
		(net "M_H_DQ<41>")
	)
	(segment
		(start 127.048768 -19.1008)
		(end 127.048768 -21.156676)
		(width 0.14224)
		(layer "In11.Cu")
		(net "M_H_DQ<41>")
	)
	(segment
		(start 125.749558 -7.625334)
		(end 126.226824 -8.1026)
		(width 0.14224)
		(layer "In11.Cu")
		(net "M_H_DQ<41>")
	)
	(segment
		(start 116.831618 -39.40175)
		(end 117.19179 -39.041578)
		(width 0.1651)
		(layer "F.Cu")
		(net "M_H_DQ<40>")
	)
	(segment
		(start 115.847368 -40.07485)
		(end 115.847368 -39.73195)
		(width 0.1651)
		(layer "F.Cu")
		(net "M_H_DQ<40>")
	)
	(segment
		(start 117.19179 -38.807898)
		(end 117.095524 -38.711632)
		(width 0.1651)
		(layer "F.Cu")
		(net "M_H_DQ<40>")
	)
	(segment
		(start 118.047516 -37.75964)
		(end 118.047516 -37.52596)
		(width 0.1651)
		(layer "F.Cu")
		(net "M_H_DQ<40>")
	)
	(segment
		(start 118.047516 -37.52596)
		(end 119.992902 -35.580574)
		(width 0.1651)
		(layer "F.Cu")
		(net "M_H_DQ<40>")
	)
	(segment
		(start 117.57152 -38.235636)
		(end 117.667786 -38.331902)
		(width 0.1651)
		(layer "F.Cu")
		(net "M_H_DQ<40>")
	)
	(segment
		(start 126.453138 -8.89)
		(end 126.440946 -8.763)
		(width 0.1651)
		(layer "F.Cu")
		(net "M_H_DQ<40>")
	)
	(segment
		(start 125.397768 -28.852368)
		(end 125.711458 -28.538678)
		(width 0.1651)
		(layer "F.Cu")
		(net "M_H_DQ<40>")
	)
	(segment
		(start 117.095524 -38.711632)
		(end 117.095524 -38.477952)
		(width 0.1651)
		(layer "F.Cu")
		(net "M_H_DQ<40>")
	)
	(segment
		(start 112.78489 -51.561492)
		(end 112.78489 -50.729896)
		(width 0.0889)
		(layer "F.Cu")
		(net "M_H_DQ<40>")
	)
	(segment
		(start 125.042168 -29.7688)
		(end 125.042168 -29.5402)
		(width 0.1651)
		(layer "F.Cu")
		(net "M_H_DQ<40>")
	)
	(segment
		(start 117.33784 -38.235636)
		(end 117.57152 -38.235636)
		(width 0.1651)
		(layer "F.Cu")
		(net "M_H_DQ<40>")
	)
	(segment
		(start 126.440946 -8.763)
		(end 126.421642 -8.5598)
		(width 0.1651)
		(layer "F.Cu")
		(net "M_H_DQ<40>")
	)
	(segment
		(start 124.318776 -30.36824)
		(end 124.498608 -30.36824)
		(width 0.1651)
		(layer "F.Cu")
		(net "M_H_DQ<40>")
	)
	(segment
		(start 116.482368 -40.894)
		(end 116.482368 -40.40505)
		(width 0.1651)
		(layer "F.Cu")
		(net "M_H_DQ<40>")
	)
	(segment
		(start 117.901466 -38.331902)
		(end 118.143782 -38.089586)
		(width 0.1651)
		(layer "F.Cu")
		(net "M_H_DQ<40>")
	)
	(segment
		(start 116.012468 -39.56685)
		(end 116.317268 -39.56685)
		(width 0.1651)
		(layer "F.Cu")
		(net "M_H_DQ<40>")
	)
	(segment
		(start 122.438668 -33.5153)
		(end 124.449332 -31.504636)
		(width 0.1651)
		(layer "F.Cu")
		(net "M_H_DQ<40>")
	)
	(segment
		(start 116.317268 -40.23995)
		(end 116.012468 -40.23995)
		(width 0.1651)
		(layer "F.Cu")
		(net "M_H_DQ<40>")
	)
	(segment
		(start 116.342668 -43.310302)
		(end 116.342668 -41.0337)
		(width 0.1016)
		(layer "F.Cu")
		(net "M_H_DQ<40>")
	)
	(segment
		(start 124.925328 -30.79496)
		(end 125.159008 -30.79496)
		(width 0.1651)
		(layer "F.Cu")
		(net "M_H_DQ<40>")
	)
	(segment
		(start 112.628172 -52.335938)
		(end 112.628172 -51.71821)
		(width 0.0889)
		(layer "F.Cu")
		(net "M_H_DQ<40>")
	)
	(segment
		(start 115.847368 -39.73195)
		(end 116.012468 -39.56685)
		(width 0.1651)
		(layer "F.Cu")
		(net "M_H_DQ<40>")
	)
	(segment
		(start 116.012468 -40.23995)
		(end 115.847368 -40.07485)
		(width 0.1651)
		(layer "F.Cu")
		(net "M_H_DQ<40>")
	)
	(segment
		(start 116.342668 -41.0337)
		(end 116.482368 -40.894)
		(width 0.1016)
		(layer "F.Cu")
		(net "M_H_DQ<40>")
	)
	(segment
		(start 116.482368 -40.40505)
		(end 116.317268 -40.23995)
		(width 0.1651)
		(layer "F.Cu")
		(net "M_H_DQ<40>")
	)
	(segment
		(start 112.623092 -49.857914)
		(end 112.623092 -47.029878)
		(width 0.1016)
		(layer "F.Cu")
		(net "M_H_DQ<40>")
	)
	(segment
		(start 112.202722 -52.437538)
		(end 112.526572 -52.437538)
		(width 0.0889)
		(layer "F.Cu")
		(net "M_H_DQ<40>")
	)
	(segment
		(start 112.78489 -50.729896)
		(end 112.623092 -50.568098)
		(width 0.0889)
		(layer "F.Cu")
		(net "M_H_DQ<40>")
	)
	(segment
		(start 122.438668 -34.5821)
		(end 122.438668 -33.5153)
		(width 0.1651)
		(layer "F.Cu")
		(net "M_H_DQ<40>")
	)
	(segment
		(start 125.397768 -29.1846)
		(end 125.397768 -28.852368)
		(width 0.1651)
		(layer "F.Cu")
		(net "M_H_DQ<40>")
	)
	(segment
		(start 125.042168 -29.5402)
		(end 125.397768 -29.1846)
		(width 0.1651)
		(layer "F.Cu")
		(net "M_H_DQ<40>")
	)
	(segment
		(start 121.440194 -35.580574)
		(end 122.438668 -34.5821)
		(width 0.1651)
		(layer "F.Cu")
		(net "M_H_DQ<40>")
	)
	(segment
		(start 119.992902 -35.580574)
		(end 121.440194 -35.580574)
		(width 0.1651)
		(layer "F.Cu")
		(net "M_H_DQ<40>")
	)
	(segment
		(start 116.317268 -39.56685)
		(end 116.482368 -39.40175)
		(width 0.1651)
		(layer "F.Cu")
		(net "M_H_DQ<40>")
	)
	(segment
		(start 118.143782 -37.855906)
		(end 118.047516 -37.75964)
		(width 0.1651)
		(layer "F.Cu")
		(net "M_H_DQ<40>")
	)
	(segment
		(start 124.107194 -30.579822)
		(end 124.318776 -30.36824)
		(width 0.1651)
		(layer "F.Cu")
		(net "M_H_DQ<40>")
	)
	(segment
		(start 116.482368 -39.40175)
		(end 116.831618 -39.40175)
		(width 0.1651)
		(layer "F.Cu")
		(net "M_H_DQ<40>")
	)
	(segment
		(start 117.095524 -38.477952)
		(end 117.33784 -38.235636)
		(width 0.1651)
		(layer "F.Cu")
		(net "M_H_DQ<40>")
	)
	(segment
		(start 118.143782 -38.089586)
		(end 118.143782 -37.855906)
		(width 0.1651)
		(layer "F.Cu")
		(net "M_H_DQ<40>")
	)
	(segment
		(start 124.498608 -30.36824)
		(end 124.925328 -30.79496)
		(width 0.1651)
		(layer "F.Cu")
		(net "M_H_DQ<40>")
	)
	(segment
		(start 112.623092 -50.568098)
		(end 112.623092 -49.857914)
		(width 0.0889)
		(layer "F.Cu")
		(net "M_H_DQ<40>")
	)
	(segment
		(start 124.449332 -31.504636)
		(end 124.449332 -31.270956)
		(width 0.1651)
		(layer "F.Cu")
		(net "M_H_DQ<40>")
	)
	(segment
		(start 125.159008 -30.79496)
		(end 125.523752 -30.430216)
		(width 0.1651)
		(layer "F.Cu")
		(net "M_H_DQ<40>")
	)
	(segment
		(start 124.449332 -31.270956)
		(end 124.107194 -30.928818)
		(width 0.1651)
		(layer "F.Cu")
		(net "M_H_DQ<40>")
	)
	(segment
		(start 124.107194 -30.928818)
		(end 124.107194 -30.579822)
		(width 0.1651)
		(layer "F.Cu")
		(net "M_H_DQ<40>")
	)
	(segment
		(start 125.523752 -30.430216)
		(end 125.523752 -30.250384)
		(width 0.1651)
		(layer "F.Cu")
		(net "M_H_DQ<40>")
	)
	(segment
		(start 125.523752 -30.250384)
		(end 125.042168 -29.7688)
		(width 0.1651)
		(layer "F.Cu")
		(net "M_H_DQ<40>")
	)
	(segment
		(start 117.667786 -38.331902)
		(end 117.901466 -38.331902)
		(width 0.1651)
		(layer "F.Cu")
		(net "M_H_DQ<40>")
	)
	(segment
		(start 117.19179 -39.041578)
		(end 117.19179 -38.807898)
		(width 0.1651)
		(layer "F.Cu")
		(net "M_H_DQ<40>")
	)
	(segment
		(start 112.623092 -47.029878)
		(end 116.342668 -43.310302)
		(width 0.1016)
		(layer "F.Cu")
		(net "M_H_DQ<40>")
	)
	(segment
		(start 112.526572 -52.437538)
		(end 112.628172 -52.335938)
		(width 0.0889)
		(layer "F.Cu")
		(net "M_H_DQ<40>")
	)
	(segment
		(start 126.599442 -10.422382)
		(end 126.453138 -8.89)
		(width 0.1651)
		(layer "F.Cu")
		(net "M_H_DQ<40>")
	)
	(segment
		(start 112.628172 -51.71821)
		(end 112.78489 -51.561492)
		(width 0.0889)
		(layer "F.Cu")
		(net "M_H_DQ<40>")
	)
	(via
		(at 125.749558 -13.959078)
		(size 0.508)
		(drill 0.254)
		(layers "F.Cu" "B.Cu")
		(net "M_H_DQ<40>")
	)
	(via
		(at 125.711458 -28.538678)
		(size 0.508)
		(drill 0.254)
		(layers "F.Cu" "B.Cu")
		(net "M_H_DQ<40>")
	)
	(via
		(at 126.421642 -8.5598)
		(size 0.508)
		(drill 0.254)
		(layers "F.Cu" "B.Cu")
		(net "M_H_DQ<40>")
	)
	(segment
		(start 125.749558 -15.222982)
		(end 125.749558 -13.959078)
		(width 0.1651)
		(layer "B.Cu")
		(net "M_H_DQ<40>")
	)
	(segment
		(start 125.749558 -28.500578)
		(end 125.749558 -27.15641)
		(width 0.14224)
		(layer "In11.Cu")
		(net "M_H_DQ<40>")
	)
	(segment
		(start 125.812042 -10.9982)
		(end 126.129542 -10.6807)
		(width 0.14224)
		(layer "In11.Cu")
		(net "M_H_DQ<40>")
	)
	(segment
		(start 125.955044 -18.33753)
		(end 125.955044 -17.095978)
		(width 0.14224)
		(layer "In11.Cu")
		(net "M_H_DQ<40>")
	)
	(segment
		(start 125.853444 -23.036276)
		(end 125.853444 -22.065996)
		(width 0.14224)
		(layer "In11.Cu")
		(net "M_H_DQ<40>")
	)
	(segment
		(start 126.209044 -21.336)
		(end 126.134368 -21.261324)
		(width 0.14224)
		(layer "In11.Cu")
		(net "M_H_DQ<40>")
	)
	(segment
		(start 126.134368 -19.1008)
		(end 126.209044 -19.026124)
		(width 0.14224)
		(layer "In11.Cu")
		(net "M_H_DQ<40>")
	)
	(segment
		(start 126.209044 -21.710396)
		(end 126.209044 -21.336)
		(width 0.14224)
		(layer "In11.Cu")
		(net "M_H_DQ<40>")
	)
	(segment
		(start 126.201424 -9.364472)
		(end 126.201424 -8.780018)
		(width 0.14224)
		(layer "In11.Cu")
		(net "M_H_DQ<40>")
	)
	(segment
		(start 125.464824 -13.674344)
		(end 125.464824 -12.9286)
		(width 0.14224)
		(layer "In11.Cu")
		(net "M_H_DQ<40>")
	)
	(segment
		(start 125.955044 -17.095978)
		(end 126.234444 -16.816578)
		(width 0.14224)
		(layer "In11.Cu")
		(net "M_H_DQ<40>")
	)
	(segment
		(start 126.129542 -10.6807)
		(end 126.129542 -10.4521)
		(width 0.14224)
		(layer "In11.Cu")
		(net "M_H_DQ<40>")
	)
	(segment
		(start 126.209044 -18.59153)
		(end 125.955044 -18.33753)
		(width 0.14224)
		(layer "In11.Cu")
		(net "M_H_DQ<40>")
	)
	(segment
		(start 125.749558 -15.91818)
		(end 125.749558 -13.959078)
		(width 0.14224)
		(layer "In11.Cu")
		(net "M_H_DQ<40>")
	)
	(segment
		(start 125.464824 -12.9286)
		(end 126.201424 -12.192)
		(width 0.14224)
		(layer "In11.Cu")
		(net "M_H_DQ<40>")
	)
	(segment
		(start 125.786642 -10.1092)
		(end 125.786642 -9.779254)
		(width 0.14224)
		(layer "In11.Cu")
		(net "M_H_DQ<40>")
	)
	(segment
		(start 126.234444 -16.816578)
		(end 126.234444 -16.403066)
		(width 0.14224)
		(layer "In11.Cu")
		(net "M_H_DQ<40>")
	)
	(segment
		(start 126.209044 -23.391876)
		(end 125.853444 -23.036276)
		(width 0.14224)
		(layer "In11.Cu")
		(net "M_H_DQ<40>")
	)
	(segment
		(start 125.812042 -11.302746)
		(end 125.812042 -10.9982)
		(width 0.14224)
		(layer "In11.Cu")
		(net "M_H_DQ<40>")
	)
	(segment
		(start 126.209044 -26.696924)
		(end 126.209044 -23.391876)
		(width 0.14224)
		(layer "In11.Cu")
		(net "M_H_DQ<40>")
	)
	(segment
		(start 126.134368 -21.261324)
		(end 126.134368 -19.1008)
		(width 0.14224)
		(layer "In11.Cu")
		(net "M_H_DQ<40>")
	)
	(segment
		(start 126.201424 -8.780018)
		(end 126.421642 -8.5598)
		(width 0.14224)
		(layer "In11.Cu")
		(net "M_H_DQ<40>")
	)
	(segment
		(start 126.234444 -16.403066)
		(end 125.749558 -15.91818)
		(width 0.14224)
		(layer "In11.Cu")
		(net "M_H_DQ<40>")
	)
	(segment
		(start 126.209044 -19.026124)
		(end 126.209044 -18.59153)
		(width 0.14224)
		(layer "In11.Cu")
		(net "M_H_DQ<40>")
	)
	(segment
		(start 125.853444 -22.065996)
		(end 126.209044 -21.710396)
		(width 0.14224)
		(layer "In11.Cu")
		(net "M_H_DQ<40>")
	)
	(segment
		(start 125.711458 -28.538678)
		(end 125.749558 -28.500578)
		(width 0.14224)
		(layer "In11.Cu")
		(net "M_H_DQ<40>")
	)
	(segment
		(start 125.749558 -13.959078)
		(end 125.464824 -13.674344)
		(width 0.14224)
		(layer "In11.Cu")
		(net "M_H_DQ<40>")
	)
	(segment
		(start 125.786642 -9.779254)
		(end 126.201424 -9.364472)
		(width 0.14224)
		(layer "In11.Cu")
		(net "M_H_DQ<40>")
	)
	(segment
		(start 126.201424 -12.192)
		(end 126.201424 -11.692128)
		(width 0.14224)
		(layer "In11.Cu")
		(net "M_H_DQ<40>")
	)
	(segment
		(start 125.749558 -27.15641)
		(end 126.209044 -26.696924)
		(width 0.14224)
		(layer "In11.Cu")
		(net "M_H_DQ<40>")
	)
	(segment
		(start 126.201424 -11.692128)
		(end 125.812042 -11.302746)
		(width 0.14224)
		(layer "In11.Cu")
		(net "M_H_DQ<40>")
	)
	(segment
		(start 126.129542 -10.4521)
		(end 125.786642 -10.1092)
		(width 0.14224)
		(layer "In11.Cu")
		(net "M_H_DQ<40>")
	)
	(segment
		(start 72.041766 -65.000886)
		(end 71.470266 -65.000886)
		(width 0.0889)
		(layer "F.Cu")
		(net "M_H_DQ<3>")
	)
	(segment
		(start 39.049452 -5.822442)
		(end 39.049452 -7.086346)
		(width 0.1651)
		(layer "F.Cu")
		(net "M_H_DQ<3>")
	)
	(via
		(at 39.899336 -12.678156)
		(size 0.508)
		(drill 0.254)
		(layers "F.Cu" "B.Cu")
		(net "M_H_DQ<3>")
	)
	(via
		(at 39.049452 -7.086346)
		(size 0.508)
		(drill 0.254)
		(layers "F.Cu" "B.Cu")
		(net "M_H_DQ<3>")
	)
	(via
		(at 71.470266 -65.000886)
		(size 0.508)
		(drill 0.254)
		(layers "F.Cu" "B.Cu")
		(net "M_H_DQ<3>")
	)
	(segment
		(start 39.899336 -10.623042)
		(end 39.899336 -12.678156)
		(width 0.1651)
		(layer "B.Cu")
		(net "M_H_DQ<3>")
	)
	(segment
		(start 39.41572 -13.161772)
		(end 39.41572 -13.568172)
		(width 0.14224)
		(layer "In4.Cu")
		(net "M_H_DQ<3>")
	)
	(segment
		(start 65.635886 -62.194948)
		(end 65.810892 -62.369954)
		(width 0.0889)
		(layer "In4.Cu")
		(net "M_H_DQ<3>")
	)
	(segment
		(start 41.819068 -31.886652)
		(end 41.664128 -32.041592)
		(width 0.14224)
		(layer "In4.Cu")
		(net "M_H_DQ<3>")
	)
	(segment
		(start 41.533572 -28.39085)
		(end 41.819068 -28.676346)
		(width 0.14224)
		(layer "In4.Cu")
		(net "M_H_DQ<3>")
	)
	(segment
		(start 40.551608 -30.715712)
		(end 40.396668 -30.870652)
		(width 0.14224)
		(layer "In4.Cu")
		(net "M_H_DQ<3>")
	)
	(segment
		(start 40.252142 -12.32535)
		(end 39.899336 -12.678156)
		(width 0.14224)
		(layer "In4.Cu")
		(net "M_H_DQ<3>")
	)
	(segment
		(start 40.26662 -23.283672)
		(end 40.26662 -24.406606)
		(width 0.14224)
		(layer "In4.Cu")
		(net "M_H_DQ<3>")
	)
	(segment
		(start 41.664128 -32.704532)
		(end 41.819068 -32.859472)
		(width 0.14224)
		(layer "In4.Cu")
		(net "M_H_DQ<3>")
	)
	(segment
		(start 40.396668 -29.897832)
		(end 40.551608 -30.052772)
		(width 0.14224)
		(layer "In4.Cu")
		(net "M_H_DQ<3>")
	)
	(segment
		(start 40.40632 -17.031462)
		(end 40.40632 -18.417794)
		(width 0.14224)
		(layer "In4.Cu")
		(net "M_H_DQ<3>")
	)
	(segment
		(start 41.819068 -32.859472)
		(end 41.819068 -36.8554)
		(width 0.14224)
		(layer "In4.Cu")
		(net "M_H_DQ<3>")
	)
	(segment
		(start 40.396668 -30.870652)
		(end 40.396668 -31.223712)
		(width 0.14224)
		(layer "In4.Cu")
		(net "M_H_DQ<3>")
	)
	(segment
		(start 40.26662 -16.891762)
		(end 40.40632 -17.031462)
		(width 0.14224)
		(layer "In4.Cu")
		(net "M_H_DQ<3>")
	)
	(segment
		(start 41.819068 -31.533592)
		(end 41.819068 -31.886652)
		(width 0.14224)
		(layer "In4.Cu")
		(net "M_H_DQ<3>")
	)
	(segment
		(start 39.748968 -27.217624)
		(end 39.903908 -27.372564)
		(width 0.14224)
		(layer "In4.Cu")
		(net "M_H_DQ<3>")
	)
	(segment
		(start 41.664128 -32.041592)
		(end 40.551608 -32.041592)
		(width 0.14224)
		(layer "In4.Cu")
		(net "M_H_DQ<3>")
	)
	(segment
		(start 65.810892 -63.159894)
		(end 66.566288 -63.91529)
		(width 0.0889)
		(layer "In4.Cu")
		(net "M_H_DQ<3>")
	)
	(segment
		(start 67.869308 -64.410336)
		(end 68.053966 -64.410336)
		(width 0.0889)
		(layer "In4.Cu")
		(net "M_H_DQ<3>")
	)
	(segment
		(start 66.566288 -63.91529)
		(end 67.304666 -63.91529)
		(width 0.0889)
		(layer "In4.Cu")
		(net "M_H_DQ<3>")
	)
	(segment
		(start 40.866568 -27.527504)
		(end 40.866568 -28.26385)
		(width 0.14224)
		(layer "In4.Cu")
		(net "M_H_DQ<3>")
	)
	(segment
		(start 39.41572 -13.568172)
		(end 40.26662 -14.419072)
		(width 0.14224)
		(layer "In4.Cu")
		(net "M_H_DQ<3>")
	)
	(segment
		(start 40.40759 -8.8646)
		(end 40.252142 -9.020048)
		(width 0.14224)
		(layer "In4.Cu")
		(net "M_H_DQ<3>")
	)
	(segment
		(start 41.819068 -29.234892)
		(end 41.664128 -29.389832)
		(width 0.14224)
		(layer "In4.Cu")
		(net "M_H_DQ<3>")
	)
	(segment
		(start 40.396668 -32.549592)
		(end 40.551608 -32.704532)
		(width 0.14224)
		(layer "In4.Cu")
		(net "M_H_DQ<3>")
	)
	(segment
		(start 41.819068 -30.207712)
		(end 41.819068 -30.560772)
		(width 0.14224)
		(layer "In4.Cu")
		(net "M_H_DQ<3>")
	)
	(segment
		(start 39.36619 -7.403084)
		(end 39.36619 -7.7216)
		(width 0.14224)
		(layer "In4.Cu")
		(net "M_H_DQ<3>")
	)
	(segment
		(start 39.69639 -8.0518)
		(end 39.95039 -8.0518)
		(width 0.14224)
		(layer "In4.Cu")
		(net "M_H_DQ<3>")
	)
	(segment
		(start 40.25392 -18.570194)
		(end 40.25392 -21.823172)
		(width 0.14224)
		(layer "In4.Cu")
		(net "M_H_DQ<3>")
	)
	(segment
		(start 40.993568 -28.39085)
		(end 41.533572 -28.39085)
		(width 0.14224)
		(layer "In4.Cu")
		(net "M_H_DQ<3>")
	)
	(segment
		(start 40.676068 -25.228804)
		(end 40.521128 -25.383744)
		(width 0.14224)
		(layer "In4.Cu")
		(net "M_H_DQ<3>")
	)
	(segment
		(start 39.903908 -26.709624)
		(end 39.748968 -26.864564)
		(width 0.14224)
		(layer "In4.Cu")
		(net "M_H_DQ<3>")
	)
	(segment
		(start 39.748968 -25.538684)
		(end 39.748968 -25.891744)
		(width 0.14224)
		(layer "In4.Cu")
		(net "M_H_DQ<3>")
	)
	(segment
		(start 41.819068 -28.676346)
		(end 41.819068 -29.234892)
		(width 0.14224)
		(layer "In4.Cu")
		(net "M_H_DQ<3>")
	)
	(segment
		(start 40.396668 -29.544772)
		(end 40.396668 -29.897832)
		(width 0.14224)
		(layer "In4.Cu")
		(net "M_H_DQ<3>")
	)
	(segment
		(start 70.59676 -65.09639)
		(end 70.647814 -65.09639)
		(width 0.0889)
		(layer "In4.Cu")
		(net "M_H_DQ<3>")
	)
	(segment
		(start 65.635886 -61.892434)
		(end 65.635886 -62.194948)
		(width 0.0889)
		(layer "In4.Cu")
		(net "M_H_DQ<3>")
	)
	(segment
		(start 40.866568 -28.26385)
		(end 40.993568 -28.39085)
		(width 0.14224)
		(layer "In4.Cu")
		(net "M_H_DQ<3>")
	)
	(segment
		(start 40.26662 -14.419072)
		(end 40.26662 -16.891762)
		(width 0.14224)
		(layer "In4.Cu")
		(net "M_H_DQ<3>")
	)
	(segment
		(start 40.43172 -22.000972)
		(end 40.43172 -23.118572)
		(width 0.14224)
		(layer "In4.Cu")
		(net "M_H_DQ<3>")
	)
	(segment
		(start 40.551608 -32.704532)
		(end 41.664128 -32.704532)
		(width 0.14224)
		(layer "In4.Cu")
		(net "M_H_DQ<3>")
	)
	(segment
		(start 40.676068 -24.816054)
		(end 40.676068 -25.228804)
		(width 0.14224)
		(layer "In4.Cu")
		(net "M_H_DQ<3>")
	)
	(segment
		(start 40.521128 -25.383744)
		(end 39.903908 -25.383744)
		(width 0.14224)
		(layer "In4.Cu")
		(net "M_H_DQ<3>")
	)
	(segment
		(start 70.647814 -65.09639)
		(end 71.470266 -65.000886)
		(width 0.0889)
		(layer "In4.Cu")
		(net "M_H_DQ<3>")
	)
	(segment
		(start 39.903908 -26.046684)
		(end 40.711628 -26.046684)
		(width 0.14224)
		(layer "In4.Cu")
		(net "M_H_DQ<3>")
	)
	(segment
		(start 39.903908 -27.372564)
		(end 40.711628 -27.372564)
		(width 0.14224)
		(layer "In4.Cu")
		(net "M_H_DQ<3>")
	)
	(segment
		(start 39.049452 -7.086346)
		(end 39.36619 -7.403084)
		(width 0.14224)
		(layer "In4.Cu")
		(net "M_H_DQ<3>")
	)
	(segment
		(start 41.819068 -36.8554)
		(end 61.491368 -56.5277)
		(width 0.14224)
		(layer "In4.Cu")
		(net "M_H_DQ<3>")
	)
	(segment
		(start 39.748968 -25.891744)
		(end 39.903908 -26.046684)
		(width 0.14224)
		(layer "In4.Cu")
		(net "M_H_DQ<3>")
	)
	(segment
		(start 41.819068 -30.560772)
		(end 41.664128 -30.715712)
		(width 0.14224)
		(layer "In4.Cu")
		(net "M_H_DQ<3>")
	)
	(segment
		(start 41.664128 -30.052772)
		(end 41.819068 -30.207712)
		(width 0.14224)
		(layer "In4.Cu")
		(net "M_H_DQ<3>")
	)
	(segment
		(start 39.748968 -26.864564)
		(end 39.748968 -27.217624)
		(width 0.14224)
		(layer "In4.Cu")
		(net "M_H_DQ<3>")
	)
	(segment
		(start 65.810892 -62.369954)
		(end 65.810892 -63.159894)
		(width 0.0889)
		(layer "In4.Cu")
		(net "M_H_DQ<3>")
	)
	(segment
		(start 40.40632 -18.417794)
		(end 40.25392 -18.570194)
		(width 0.14224)
		(layer "In4.Cu")
		(net "M_H_DQ<3>")
	)
	(segment
		(start 41.664128 -30.715712)
		(end 40.551608 -30.715712)
		(width 0.14224)
		(layer "In4.Cu")
		(net "M_H_DQ<3>")
	)
	(segment
		(start 40.711628 -27.372564)
		(end 40.866568 -27.527504)
		(width 0.14224)
		(layer "In4.Cu")
		(net "M_H_DQ<3>")
	)
	(segment
		(start 40.551608 -29.389832)
		(end 40.396668 -29.544772)
		(width 0.14224)
		(layer "In4.Cu")
		(net "M_H_DQ<3>")
	)
	(segment
		(start 40.43172 -23.118572)
		(end 40.26662 -23.283672)
		(width 0.14224)
		(layer "In4.Cu")
		(net "M_H_DQ<3>")
	)
	(segment
		(start 39.903908 -25.383744)
		(end 39.748968 -25.538684)
		(width 0.14224)
		(layer "In4.Cu")
		(net "M_H_DQ<3>")
	)
	(segment
		(start 68.88353 -64.90589)
		(end 68.916296 -64.90589)
		(width 0.0889)
		(layer "In4.Cu")
		(net "M_H_DQ<3>")
	)
	(segment
		(start 39.36619 -7.7216)
		(end 39.69639 -8.0518)
		(width 0.14224)
		(layer "In4.Cu")
		(net "M_H_DQ<3>")
	)
	(segment
		(start 39.95039 -8.0518)
		(end 40.40759 -8.509)
		(width 0.14224)
		(layer "In4.Cu")
		(net "M_H_DQ<3>")
	)
	(segment
		(start 40.866568 -26.554684)
		(end 40.711628 -26.709624)
		(width 0.14224)
		(layer "In4.Cu")
		(net "M_H_DQ<3>")
	)
	(segment
		(start 40.40759 -8.509)
		(end 40.40759 -8.8646)
		(width 0.14224)
		(layer "In4.Cu")
		(net "M_H_DQ<3>")
	)
	(segment
		(start 40.252142 -9.020048)
		(end 40.252142 -12.32535)
		(width 0.14224)
		(layer "In4.Cu")
		(net "M_H_DQ<3>")
	)
	(segment
		(start 61.491368 -56.5277)
		(end 61.491368 -57.747916)
		(width 0.14224)
		(layer "In4.Cu")
		(net "M_H_DQ<3>")
	)
	(segment
		(start 40.396668 -32.196532)
		(end 40.396668 -32.549592)
		(width 0.14224)
		(layer "In4.Cu")
		(net "M_H_DQ<3>")
	)
	(segment
		(start 61.491368 -57.747916)
		(end 65.635886 -61.892434)
		(width 0.14224)
		(layer "In4.Cu")
		(net "M_H_DQ<3>")
	)
	(segment
		(start 41.664128 -31.378652)
		(end 41.819068 -31.533592)
		(width 0.14224)
		(layer "In4.Cu")
		(net "M_H_DQ<3>")
	)
	(segment
		(start 40.26662 -24.406606)
		(end 40.676068 -24.816054)
		(width 0.14224)
		(layer "In4.Cu")
		(net "M_H_DQ<3>")
	)
	(segment
		(start 40.25392 -21.823172)
		(end 40.43172 -22.000972)
		(width 0.14224)
		(layer "In4.Cu")
		(net "M_H_DQ<3>")
	)
	(segment
		(start 40.551608 -32.041592)
		(end 40.396668 -32.196532)
		(width 0.14224)
		(layer "In4.Cu")
		(net "M_H_DQ<3>")
	)
	(segment
		(start 40.551608 -31.378652)
		(end 41.664128 -31.378652)
		(width 0.14224)
		(layer "In4.Cu")
		(net "M_H_DQ<3>")
	)
	(segment
		(start 41.664128 -29.389832)
		(end 40.551608 -29.389832)
		(width 0.14224)
		(layer "In4.Cu")
		(net "M_H_DQ<3>")
	)
	(segment
		(start 69.73824 -65.400936)
		(end 69.86905 -65.400936)
		(width 0.0889)
		(layer "In4.Cu")
		(net "M_H_DQ<3>")
	)
	(segment
		(start 40.551608 -30.052772)
		(end 41.664128 -30.052772)
		(width 0.14224)
		(layer "In4.Cu")
		(net "M_H_DQ<3>")
	)
	(segment
		(start 40.711628 -26.709624)
		(end 39.903908 -26.709624)
		(width 0.14224)
		(layer "In4.Cu")
		(net "M_H_DQ<3>")
	)
	(segment
		(start 40.711628 -26.046684)
		(end 40.866568 -26.201624)
		(width 0.14224)
		(layer "In4.Cu")
		(net "M_H_DQ<3>")
	)
	(segment
		(start 39.899336 -12.678156)
		(end 39.41572 -13.161772)
		(width 0.14224)
		(layer "In4.Cu")
		(net "M_H_DQ<3>")
	)
	(segment
		(start 40.866568 -26.201624)
		(end 40.866568 -26.554684)
		(width 0.14224)
		(layer "In4.Cu")
		(net "M_H_DQ<3>")
	)
	(segment
		(start 40.396668 -31.223712)
		(end 40.551608 -31.378652)
		(width 0.14224)
		(layer "In4.Cu")
		(net "M_H_DQ<3>")
	)
	(arc
		(start 70.33387 -65.208404)
		(mid 70.454974 -65.128114)
		(end 70.59676 -65.09639)
		(width 0.0889)
		(layer "In4.Cu")
		(net "M_H_DQ<3>")
	)
	(arc
		(start 68.916296 -64.90589)
		(mid 69.199513 -64.990171)
		(end 69.406516 -65.201038)
		(width 0.0889)
		(layer "In4.Cu")
		(net "M_H_DQ<3>")
	)
	(arc
		(start 69.86905 -65.400936)
		(mid 70.120608 -65.350898)
		(end 70.33387 -65.208404)
		(width 0.0889)
		(layer "In4.Cu")
		(net "M_H_DQ<3>")
	)
	(arc
		(start 67.653154 -64.213232)
		(mid 67.744098 -64.330575)
		(end 67.869308 -64.410336)
		(width 0.0889)
		(layer "In4.Cu")
		(net "M_H_DQ<3>")
	)
	(arc
		(start 69.406516 -65.201038)
		(mid 69.546595 -65.343774)
		(end 69.73824 -65.400936)
		(width 0.0889)
		(layer "In4.Cu")
		(net "M_H_DQ<3>")
	)
	(arc
		(start 67.304666 -63.91529)
		(mid 67.50726 -64.031108)
		(end 67.653154 -64.213232)
		(width 0.0889)
		(layer "In4.Cu")
		(net "M_H_DQ<3>")
	)
	(arc
		(start 68.053966 -64.410336)
		(mid 68.33939 -64.493803)
		(end 68.547996 -64.705738)
		(width 0.0889)
		(layer "In4.Cu")
		(net "M_H_DQ<3>")
	)
	(arc
		(start 68.547996 -64.705738)
		(mid 68.689679 -64.849542)
		(end 68.88353 -64.90589)
		(width 0.0889)
		(layer "In4.Cu")
		(net "M_H_DQ<3>")
	)
	(segment
		(start 120.649492 -5.822442)
		(end 120.649492 -7.086346)
		(width 0.1651)
		(layer "F.Cu")
		(net "M_H_DQ<39>")
	)
	(segment
		(start 107.910376 -57.885584)
		(end 107.338876 -57.885584)
		(width 0.1016)
		(layer "F.Cu")
		(net "M_H_DQ<39>")
	)
	(via
		(at 120.649492 -7.086346)
		(size 0.508)
		(drill 0.254)
		(layers "F.Cu" "B.Cu")
		(net "M_H_DQ<39>")
	)
	(via
		(at 121.499376 -12.678156)
		(size 0.508)
		(drill 0.254)
		(layers "F.Cu" "B.Cu")
		(net "M_H_DQ<39>")
	)
	(via
		(at 107.338876 -57.885584)
		(size 0.508)
		(drill 0.254)
		(layers "F.Cu" "B.Cu")
		(net "M_H_DQ<39>")
	)
	(segment
		(start 121.499376 -10.623042)
		(end 121.499376 -12.678156)
		(width 0.1651)
		(layer "B.Cu")
		(net "M_H_DQ<39>")
	)
	(segment
		(start 108.709206 -53.722524)
		(end 108.881926 -53.423058)
		(width 0.0889)
		(layer "In4.Cu")
		(net "M_H_DQ<39>")
	)
	(segment
		(start 121.892314 -16.893794)
		(end 121.892314 -14.64056)
		(width 0.14224)
		(layer "In4.Cu")
		(net "M_H_DQ<39>")
	)
	(segment
		(start 121.852182 -18.556986)
		(end 122.080782 -18.328386)
		(width 0.14224)
		(layer "In4.Cu")
		(net "M_H_DQ<39>")
	)
	(segment
		(start 121.816368 -27.914854)
		(end 121.816368 -27.5082)
		(width 0.14224)
		(layer "In4.Cu")
		(net "M_H_DQ<39>")
	)
	(segment
		(start 109.51718 -49.425606)
		(end 109.51718 -48.126142)
		(width 0.0889)
		(layer "In4.Cu")
		(net "M_H_DQ<39>")
	)
	(segment
		(start 108.18241 -55.999888)
		(end 108.215176 -55.999888)
		(width 0.0889)
		(layer "In4.Cu")
		(net "M_H_DQ<39>")
	)
	(segment
		(start 121.013982 -13.61694)
		(end 121.013982 -13.16355)
		(width 0.14224)
		(layer "In4.Cu")
		(net "M_H_DQ<39>")
	)
	(segment
		(start 111.319818 -45.662596)
		(end 111.319818 -38.411404)
		(width 0.14224)
		(layer "In4.Cu")
		(net "M_H_DQ<39>")
	)
	(segment
		(start 121.407682 -14.01064)
		(end 121.013982 -13.61694)
		(width 0.14224)
		(layer "In4.Cu")
		(net "M_H_DQ<39>")
	)
	(segment
		(start 120.96623 -7.403084)
		(end 120.649492 -7.086346)
		(width 0.14224)
		(layer "In4.Cu")
		(net "M_H_DQ<39>")
	)
	(segment
		(start 121.511568 -24.384)
		(end 121.892314 -24.003254)
		(width 0.14224)
		(layer "In4.Cu")
		(net "M_H_DQ<39>")
	)
	(segment
		(start 107.834176 -57.219342)
		(end 107.850686 -57.19064)
		(width 0.0889)
		(layer "In4.Cu")
		(net "M_H_DQ<39>")
	)
	(segment
		(start 120.96623 -7.7216)
		(end 120.96623 -7.403084)
		(width 0.14224)
		(layer "In4.Cu")
		(net "M_H_DQ<39>")
	)
	(segment
		(start 111.30534 -45.677074)
		(end 111.319818 -45.662596)
		(width 0.14224)
		(layer "In4.Cu")
		(net "M_H_DQ<39>")
	)
	(segment
		(start 121.892314 -14.64056)
		(end 121.407682 -14.155928)
		(width 0.14224)
		(layer "In4.Cu")
		(net "M_H_DQ<39>")
	)
	(segment
		(start 111.319818 -38.411404)
		(end 121.816368 -27.914854)
		(width 0.14224)
		(layer "In4.Cu")
		(net "M_H_DQ<39>")
	)
	(segment
		(start 122.080782 -17.082262)
		(end 121.892314 -16.893794)
		(width 0.14224)
		(layer "In4.Cu")
		(net "M_H_DQ<39>")
	)
	(segment
		(start 121.852182 -21.772372)
		(end 121.852182 -18.556986)
		(width 0.14224)
		(layer "In4.Cu")
		(net "M_H_DQ<39>")
	)
	(segment
		(start 107.338876 -57.885584)
		(end 107.338876 -57.885838)
		(width 0.0889)
		(layer "In4.Cu")
		(net "M_H_DQ<39>")
	)
	(segment
		(start 111.040164 -45.94225)
		(end 111.30534 -45.677074)
		(width 0.0889)
		(layer "In4.Cu")
		(net "M_H_DQ<39>")
	)
	(segment
		(start 109.234732 -49.708054)
		(end 109.51718 -49.425606)
		(width 0.0889)
		(layer "In4.Cu")
		(net "M_H_DQ<39>")
	)
	(segment
		(start 121.407682 -14.155928)
		(end 121.407682 -14.01064)
		(width 0.14224)
		(layer "In4.Cu")
		(net "M_H_DQ<39>")
	)
	(segment
		(start 122.00763 -8.509)
		(end 121.55043 -8.0518)
		(width 0.14224)
		(layer "In4.Cu")
		(net "M_H_DQ<39>")
	)
	(segment
		(start 122.080782 -18.328386)
		(end 122.080782 -17.082262)
		(width 0.14224)
		(layer "In4.Cu")
		(net "M_H_DQ<39>")
	)
	(segment
		(start 107.338876 -57.885838)
		(end 107.834176 -57.219342)
		(width 0.0889)
		(layer "In4.Cu")
		(net "M_H_DQ<39>")
	)
	(segment
		(start 108.881926 -52.217574)
		(end 109.234732 -51.864768)
		(width 0.0889)
		(layer "In4.Cu")
		(net "M_H_DQ<39>")
	)
	(segment
		(start 121.852182 -9.020048)
		(end 122.00763 -8.8646)
		(width 0.14224)
		(layer "In4.Cu")
		(net "M_H_DQ<39>")
	)
	(segment
		(start 122.055382 -21.975572)
		(end 121.852182 -21.772372)
		(width 0.14224)
		(layer "In4.Cu")
		(net "M_H_DQ<39>")
	)
	(segment
		(start 121.816368 -27.5082)
		(end 121.511568 -27.2034)
		(width 0.14224)
		(layer "In4.Cu")
		(net "M_H_DQ<39>")
	)
	(segment
		(start 121.013982 -13.16355)
		(end 121.499376 -12.678156)
		(width 0.14224)
		(layer "In4.Cu")
		(net "M_H_DQ<39>")
	)
	(segment
		(start 121.892314 -23.28164)
		(end 122.055382 -23.118572)
		(width 0.14224)
		(layer "In4.Cu")
		(net "M_H_DQ<39>")
	)
	(segment
		(start 111.040164 -46.603158)
		(end 111.040164 -45.94225)
		(width 0.0889)
		(layer "In4.Cu")
		(net "M_H_DQ<39>")
	)
	(segment
		(start 121.55043 -8.0518)
		(end 121.29643 -8.0518)
		(width 0.14224)
		(layer "In4.Cu")
		(net "M_H_DQ<39>")
	)
	(segment
		(start 121.852182 -12.32535)
		(end 121.852182 -9.020048)
		(width 0.14224)
		(layer "In4.Cu")
		(net "M_H_DQ<39>")
	)
	(segment
		(start 121.511568 -27.2034)
		(end 121.511568 -24.384)
		(width 0.14224)
		(layer "In4.Cu")
		(net "M_H_DQ<39>")
	)
	(segment
		(start 121.892314 -24.003254)
		(end 121.892314 -23.28164)
		(width 0.14224)
		(layer "In4.Cu")
		(net "M_H_DQ<39>")
	)
	(segment
		(start 122.055382 -23.118572)
		(end 122.055382 -21.975572)
		(width 0.14224)
		(layer "In4.Cu")
		(net "M_H_DQ<39>")
	)
	(segment
		(start 109.234732 -51.864768)
		(end 109.234732 -49.708054)
		(width 0.0889)
		(layer "In4.Cu")
		(net "M_H_DQ<39>")
	)
	(segment
		(start 108.881926 -53.423058)
		(end 108.881926 -52.217574)
		(width 0.0889)
		(layer "In4.Cu")
		(net "M_H_DQ<39>")
	)
	(segment
		(start 121.499376 -12.678156)
		(end 121.852182 -12.32535)
		(width 0.14224)
		(layer "In4.Cu")
		(net "M_H_DQ<39>")
	)
	(segment
		(start 109.51718 -48.126142)
		(end 111.040164 -46.603158)
		(width 0.0889)
		(layer "In4.Cu")
		(net "M_H_DQ<39>")
	)
	(segment
		(start 121.29643 -8.0518)
		(end 120.96623 -7.7216)
		(width 0.14224)
		(layer "In4.Cu")
		(net "M_H_DQ<39>")
	)
	(segment
		(start 122.00763 -8.8646)
		(end 122.00763 -8.509)
		(width 0.14224)
		(layer "In4.Cu")
		(net "M_H_DQ<39>")
	)
	(arc
		(start 108.709206 -55.113936)
		(mid 108.65558 -54.913784)
		(end 108.709206 -54.713632)
		(width 0.0889)
		(layer "In4.Cu")
		(net "M_H_DQ<39>")
	)
	(arc
		(start 107.850686 -56.599836)
		(mid 107.84698 -56.206089)
		(end 108.18241 -55.999888)
		(width 0.0889)
		(layer "In4.Cu")
		(net "M_H_DQ<39>")
	)
	(arc
		(start 108.215176 -55.999888)
		(mid 108.713427 -55.697048)
		(end 108.709206 -55.113936)
		(width 0.0889)
		(layer "In4.Cu")
		(net "M_H_DQ<39>")
	)
	(arc
		(start 108.709206 -54.713632)
		(mid 108.788337 -54.41823)
		(end 108.709206 -54.122828)
		(width 0.0889)
		(layer "In4.Cu")
		(net "M_H_DQ<39>")
	)
	(arc
		(start 108.709206 -54.122828)
		(mid 108.65558 -53.922676)
		(end 108.709206 -53.722524)
		(width 0.0889)
		(layer "In4.Cu")
		(net "M_H_DQ<39>")
	)
	(arc
		(start 107.850686 -57.19064)
		(mid 107.929817 -56.895238)
		(end 107.850686 -56.599836)
		(width 0.0889)
		(layer "In4.Cu")
		(net "M_H_DQ<39>")
	)
	(segment
		(start 121.49963 -8.9662)
		(end 121.49963 -8.661654)
		(width 0.1651)
		(layer "F.Cu")
		(net "M_H_DQ<38>")
	)
	(segment
		(start 121.49963 -9.4488)
		(end 121.63171 -9.31672)
		(width 0.1651)
		(layer "F.Cu")
		(net "M_H_DQ<38>")
	)
	(segment
		(start 121.63171 -9.31672)
		(end 121.63171 -9.09828)
		(width 0.1651)
		(layer "F.Cu")
		(net "M_H_DQ<38>")
	)
	(segment
		(start 107.910376 -55.904384)
		(end 107.338876 -55.904384)
		(width 0.1016)
		(layer "F.Cu")
		(net "M_H_DQ<38>")
	)
	(segment
		(start 121.63171 -9.09828)
		(end 121.49963 -8.9662)
		(width 0.1651)
		(layer "F.Cu")
		(net "M_H_DQ<38>")
	)
	(segment
		(start 121.49963 -8.661654)
		(end 121.499376 -8.6614)
		(width 0.1651)
		(layer "F.Cu")
		(net "M_H_DQ<38>")
	)
	(segment
		(start 121.49963 -10.422128)
		(end 121.49963 -9.4488)
		(width 0.1651)
		(layer "F.Cu")
		(net "M_H_DQ<38>")
	)
	(segment
		(start 121.499376 -10.422382)
		(end 121.49963 -10.422128)
		(width 0.1651)
		(layer "F.Cu")
		(net "M_H_DQ<38>")
	)
	(via
		(at 121.499376 -8.6614)
		(size 0.508)
		(drill 0.254)
		(layers "F.Cu" "B.Cu")
		(net "M_H_DQ<38>")
	)
	(via
		(at 120.649492 -13.959078)
		(size 0.508)
		(drill 0.254)
		(layers "F.Cu" "B.Cu")
		(net "M_H_DQ<38>")
	)
	(via
		(at 107.338876 -55.904384)
		(size 0.508)
		(drill 0.254)
		(layers "F.Cu" "B.Cu")
		(net "M_H_DQ<38>")
	)
	(segment
		(start 120.649492 -15.222982)
		(end 120.649492 -13.959078)
		(width 0.1651)
		(layer "B.Cu")
		(net "M_H_DQ<38>")
	)
	(segment
		(start 120.901968 -16.129)
		(end 120.901968 -15.6718)
		(width 0.14224)
		(layer "In4.Cu")
		(net "M_H_DQ<38>")
	)
	(segment
		(start 120.456706 -14.439392)
		(end 120.456706 -14.151864)
		(width 0.14224)
		(layer "In4.Cu")
		(net "M_H_DQ<38>")
	)
	(segment
		(start 119.317262 -29.21254)
		(end 119.604282 -29.21254)
		(width 0.14224)
		(layer "In4.Cu")
		(net "M_H_DQ<38>")
	)
	(segment
		(start 121.013982 -16.993362)
		(end 121.106692 -16.900652)
		(width 0.14224)
		(layer "In4.Cu")
		(net "M_H_DQ<38>")
	)
	(segment
		(start 116.443252 -32.086296)
		(end 116.273326 -31.91637)
		(width 0.14224)
		(layer "In4.Cu")
		(net "M_H_DQ<38>")
	)
	(segment
		(start 118.572534 -29.617162)
		(end 118.572534 -29.330142)
		(width 0.14224)
		(layer "In4.Cu")
		(net "M_H_DQ<38>")
	)
	(segment
		(start 120.29694 -27.892756)
		(end 120.466866 -28.062936)
		(width 0.14224)
		(layer "In4.Cu")
		(net "M_H_DQ<38>")
	)
	(segment
		(start 118.860316 -29.04236)
		(end 119.147336 -29.04236)
		(width 0.14224)
		(layer "In4.Cu")
		(net "M_H_DQ<38>")
	)
	(segment
		(start 110.850172 -46.524418)
		(end 110.850172 -45.859954)
		(width 0.0889)
		(layer "In4.Cu")
		(net "M_H_DQ<38>")
	)
	(segment
		(start 121.115582 -23.789386)
		(end 121.115582 -23.270972)
		(width 0.14224)
		(layer "In4.Cu")
		(net "M_H_DQ<38>")
	)
	(segment
		(start 108.691426 -53.37175)
		(end 108.691426 -52.13858)
		(width 0.0889)
		(layer "In4.Cu")
		(net "M_H_DQ<38>")
	)
	(segment
		(start 121.217182 -21.772372)
		(end 121.217182 -18.628614)
		(width 0.14224)
		(layer "In4.Cu")
		(net "M_H_DQ<38>")
	)
	(segment
		(start 121.106692 -15.467076)
		(end 121.106692 -15.089378)
		(width 0.14224)
		(layer "In4.Cu")
		(net "M_H_DQ<38>")
	)
	(segment
		(start 120.876568 -24.0284)
		(end 121.115582 -23.789386)
		(width 0.14224)
		(layer "In4.Cu")
		(net "M_H_DQ<38>")
	)
	(segment
		(start 120.760998 -9.988296)
		(end 120.760998 -9.677654)
		(width 0.14224)
		(layer "In4.Cu")
		(net "M_H_DQ<38>")
	)
	(segment
		(start 121.106692 -16.333724)
		(end 120.901968 -16.129)
		(width 0.14224)
		(layer "In4.Cu")
		(net "M_H_DQ<38>")
	)
	(segment
		(start 109.044232 -49.629822)
		(end 109.327188 -49.346866)
		(width 0.0889)
		(layer "In4.Cu")
		(net "M_H_DQ<38>")
	)
	(segment
		(start 120.466866 -28.062936)
		(end 120.753886 -28.062936)
		(width 0.14224)
		(layer "In4.Cu")
		(net "M_H_DQ<38>")
	)
	(segment
		(start 117.997732 -30.191964)
		(end 118.167658 -30.362144)
		(width 0.14224)
		(layer "In4.Cu")
		(net "M_H_DQ<38>")
	)
	(segment
		(start 120.41378 -12.928854)
		(end 121.186448 -12.156186)
		(width 0.14224)
		(layer "In4.Cu")
		(net "M_H_DQ<38>")
	)
	(segment
		(start 120.00992 -27.892756)
		(end 120.29694 -27.892756)
		(width 0.14224)
		(layer "In4.Cu")
		(net "M_H_DQ<38>")
	)
	(segment
		(start 120.901968 -15.6718)
		(end 121.106692 -15.467076)
		(width 0.14224)
		(layer "In4.Cu")
		(net "M_H_DQ<38>")
	)
	(segment
		(start 118.167658 -30.362144)
		(end 118.454678 -30.362144)
		(width 0.14224)
		(layer "In4.Cu")
		(net "M_H_DQ<38>")
	)
	(segment
		(start 121.12498 -9.035796)
		(end 121.499376 -8.6614)
		(width 0.14224)
		(layer "In4.Cu")
		(net "M_H_DQ<38>")
	)
	(segment
		(start 119.147336 -29.04236)
		(end 119.317262 -29.21254)
		(width 0.14224)
		(layer "In4.Cu")
		(net "M_H_DQ<38>")
	)
	(segment
		(start 118.74246 -30.074362)
		(end 118.74246 -29.787088)
		(width 0.14224)
		(layer "In4.Cu")
		(net "M_H_DQ<38>")
	)
	(segment
		(start 121.013982 -18.425414)
		(end 121.013982 -16.993362)
		(width 0.14224)
		(layer "In4.Cu")
		(net "M_H_DQ<38>")
	)
	(segment
		(start 117.710712 -30.191964)
		(end 117.997732 -30.191964)
		(width 0.14224)
		(layer "In4.Cu")
		(net "M_H_DQ<38>")
	)
	(segment
		(start 121.217182 -18.628614)
		(end 121.013982 -18.425414)
		(width 0.14224)
		(layer "In4.Cu")
		(net "M_H_DQ<38>")
	)
	(segment
		(start 120.760998 -11.378946)
		(end 120.760998 -11.093704)
		(width 0.14224)
		(layer "In4.Cu")
		(net "M_H_DQ<38>")
	)
	(segment
		(start 108.691426 -52.13858)
		(end 109.044232 -51.785774)
		(width 0.0889)
		(layer "In4.Cu")
		(net "M_H_DQ<38>")
	)
	(segment
		(start 116.443252 -32.37357)
		(end 116.443252 -32.086296)
		(width 0.14224)
		(layer "In4.Cu")
		(net "M_H_DQ<38>")
	)
	(segment
		(start 120.753886 -28.062936)
		(end 120.876568 -27.940254)
		(width 0.14224)
		(layer "In4.Cu")
		(net "M_H_DQ<38>")
	)
	(segment
		(start 119.604282 -29.21254)
		(end 119.892064 -28.924758)
		(width 0.14224)
		(layer "In4.Cu")
		(net "M_H_DQ<38>")
	)
	(segment
		(start 117.42293 -30.479746)
		(end 117.710712 -30.191964)
		(width 0.14224)
		(layer "In4.Cu")
		(net "M_H_DQ<38>")
	)
	(segment
		(start 116.273326 -31.91637)
		(end 116.273326 -31.62935)
		(width 0.14224)
		(layer "In4.Cu")
		(net "M_H_DQ<38>")
	)
	(segment
		(start 118.572534 -29.330142)
		(end 118.860316 -29.04236)
		(width 0.14224)
		(layer "In4.Cu")
		(net "M_H_DQ<38>")
	)
	(segment
		(start 107.338876 -55.904384)
		(end 107.338876 -56.242458)
		(width 0.0889)
		(layer "In4.Cu")
		(net "M_H_DQ<38>")
	)
	(segment
		(start 116.561108 -31.341568)
		(end 117.043454 -31.341568)
		(width 0.14224)
		(layer "In4.Cu")
		(net "M_H_DQ<38>")
	)
	(segment
		(start 108.544106 -53.627274)
		(end 108.691426 -53.37175)
		(width 0.0889)
		(layer "In4.Cu")
		(net "M_H_DQ<38>")
	)
	(segment
		(start 121.186448 -12.156186)
		(end 121.186448 -11.804396)
		(width 0.14224)
		(layer "In4.Cu")
		(net "M_H_DQ<38>")
	)
	(segment
		(start 110.667292 -38.14953)
		(end 116.443252 -32.37357)
		(width 0.14224)
		(layer "In4.Cu")
		(net "M_H_DQ<38>")
	)
	(segment
		(start 120.41378 -13.723366)
		(end 120.41378 -12.928854)
		(width 0.14224)
		(layer "In4.Cu")
		(net "M_H_DQ<38>")
	)
	(segment
		(start 120.456706 -14.151864)
		(end 120.649492 -13.959078)
		(width 0.14224)
		(layer "In4.Cu")
		(net "M_H_DQ<38>")
	)
	(segment
		(start 110.667292 -45.677074)
		(end 110.667292 -38.14953)
		(width 0.14224)
		(layer "In4.Cu")
		(net "M_H_DQ<38>")
	)
	(segment
		(start 108.175806 -55.809388)
		(end 108.208572 -55.809388)
		(width 0.0889)
		(layer "In4.Cu")
		(net "M_H_DQ<38>")
	)
	(segment
		(start 118.74246 -29.787088)
		(end 118.572534 -29.617162)
		(width 0.14224)
		(layer "In4.Cu")
		(net "M_H_DQ<38>")
	)
	(segment
		(start 109.327188 -48.047402)
		(end 110.850172 -46.524418)
		(width 0.0889)
		(layer "In4.Cu")
		(net "M_H_DQ<38>")
	)
	(segment
		(start 121.141998 -10.369296)
		(end 120.760998 -9.988296)
		(width 0.14224)
		(layer "In4.Cu")
		(net "M_H_DQ<38>")
	)
	(segment
		(start 117.043454 -31.341568)
		(end 117.42293 -30.962092)
		(width 0.14224)
		(layer "In4.Cu")
		(net "M_H_DQ<38>")
	)
	(segment
		(start 120.876568 -27.940254)
		(end 120.876568 -24.0284)
		(width 0.14224)
		(layer "In4.Cu")
		(net "M_H_DQ<38>")
	)
	(segment
		(start 120.760998 -11.093704)
		(end 121.141998 -10.712704)
		(width 0.14224)
		(layer "In4.Cu")
		(net "M_H_DQ<38>")
	)
	(segment
		(start 119.722138 -28.467558)
		(end 119.722138 -28.180538)
		(width 0.14224)
		(layer "In4.Cu")
		(net "M_H_DQ<38>")
	)
	(segment
		(start 110.850172 -45.859954)
		(end 110.667292 -45.677074)
		(width 0.0889)
		(layer "In4.Cu")
		(net "M_H_DQ<38>")
	)
	(segment
		(start 121.106692 -15.089378)
		(end 120.456706 -14.439392)
		(width 0.14224)
		(layer "In4.Cu")
		(net "M_H_DQ<38>")
	)
	(segment
		(start 121.106692 -16.900652)
		(end 121.106692 -16.333724)
		(width 0.14224)
		(layer "In4.Cu")
		(net "M_H_DQ<38>")
	)
	(segment
		(start 120.760998 -9.677654)
		(end 121.12498 -9.313672)
		(width 0.14224)
		(layer "In4.Cu")
		(net "M_H_DQ<38>")
	)
	(segment
		(start 121.141998 -10.712704)
		(end 121.141998 -10.369296)
		(width 0.14224)
		(layer "In4.Cu")
		(net "M_H_DQ<38>")
	)
	(segment
		(start 107.338876 -56.242458)
		(end 107.396788 -56.30037)
		(width 0.0889)
		(layer "In4.Cu")
		(net "M_H_DQ<38>")
	)
	(segment
		(start 121.186448 -11.804396)
		(end 120.760998 -11.378946)
		(width 0.14224)
		(layer "In4.Cu")
		(net "M_H_DQ<38>")
	)
	(segment
		(start 119.722138 -28.180538)
		(end 120.00992 -27.892756)
		(width 0.14224)
		(layer "In4.Cu")
		(net "M_H_DQ<38>")
	)
	(segment
		(start 118.454678 -30.362144)
		(end 118.74246 -30.074362)
		(width 0.14224)
		(layer "In4.Cu")
		(net "M_H_DQ<38>")
	)
	(segment
		(start 109.327188 -49.346866)
		(end 109.327188 -48.047402)
		(width 0.0889)
		(layer "In4.Cu")
		(net "M_H_DQ<38>")
	)
	(segment
		(start 117.42293 -30.962092)
		(end 117.42293 -30.479746)
		(width 0.14224)
		(layer "In4.Cu")
		(net "M_H_DQ<38>")
	)
	(segment
		(start 120.649492 -13.959078)
		(end 120.41378 -13.723366)
		(width 0.14224)
		(layer "In4.Cu")
		(net "M_H_DQ<38>")
	)
	(segment
		(start 109.044232 -51.785774)
		(end 109.044232 -49.629822)
		(width 0.0889)
		(layer "In4.Cu")
		(net "M_H_DQ<38>")
	)
	(segment
		(start 121.115582 -23.270972)
		(end 121.013982 -23.169372)
		(width 0.14224)
		(layer "In4.Cu")
		(net "M_H_DQ<38>")
	)
	(segment
		(start 121.013982 -21.975572)
		(end 121.217182 -21.772372)
		(width 0.14224)
		(layer "In4.Cu")
		(net "M_H_DQ<38>")
	)
	(segment
		(start 119.892064 -28.924758)
		(end 119.892064 -28.637484)
		(width 0.14224)
		(layer "In4.Cu")
		(net "M_H_DQ<38>")
	)
	(segment
		(start 121.013982 -23.169372)
		(end 121.013982 -21.975572)
		(width 0.14224)
		(layer "In4.Cu")
		(net "M_H_DQ<38>")
	)
	(segment
		(start 116.273326 -31.62935)
		(end 116.561108 -31.341568)
		(width 0.14224)
		(layer "In4.Cu")
		(net "M_H_DQ<38>")
	)
	(segment
		(start 119.892064 -28.637484)
		(end 119.722138 -28.467558)
		(width 0.14224)
		(layer "In4.Cu")
		(net "M_H_DQ<38>")
	)
	(segment
		(start 121.12498 -9.313672)
		(end 121.12498 -9.035796)
		(width 0.14224)
		(layer "In4.Cu")
		(net "M_H_DQ<38>")
	)
	(arc
		(start 107.396788 -56.30037)
		(mid 107.563633 -56.235557)
		(end 107.685586 -56.104536)
		(width 0.0889)
		(layer "In4.Cu")
		(net "M_H_DQ<38>")
	)
	(arc
		(start 107.685586 -56.104536)
		(mid 107.89259 -55.893672)
		(end 108.175806 -55.809388)
		(width 0.0889)
		(layer "In4.Cu")
		(net "M_H_DQ<38>")
	)
	(arc
		(start 108.544106 -55.209186)
		(mid 108.464975 -54.913784)
		(end 108.544106 -54.618382)
		(width 0.0889)
		(layer "In4.Cu")
		(net "M_H_DQ<38>")
	)
	(arc
		(start 108.544106 -54.618382)
		(mid 108.597732 -54.41823)
		(end 108.544106 -54.218078)
		(width 0.0889)
		(layer "In4.Cu")
		(net "M_H_DQ<38>")
	)
	(arc
		(start 108.208572 -55.809388)
		(mid 108.546741 -55.60459)
		(end 108.544106 -55.209186)
		(width 0.0889)
		(layer "In4.Cu")
		(net "M_H_DQ<38>")
	)
	(arc
		(start 108.544106 -54.218078)
		(mid 108.464975 -53.922676)
		(end 108.544106 -53.627274)
		(width 0.0889)
		(layer "In4.Cu")
		(net "M_H_DQ<38>")
	)
	(segment
		(start 114.699542 -5.822442)
		(end 114.699542 -7.086346)
		(width 0.1651)
		(layer "F.Cu")
		(net "M_H_DQ<37>")
	)
	(segment
		(start 106.193336 -58.876438)
		(end 105.571036 -58.876438)
		(width 0.1651)
		(layer "F.Cu")
		(net "M_H_DQ<37>")
	)
	(via
		(at 105.571036 -58.876438)
		(size 0.508)
		(drill 0.254)
		(layers "F.Cu" "B.Cu")
		(net "M_H_DQ<37>")
	)
	(via
		(at 115.473226 -12.589256)
		(size 0.508)
		(drill 0.254)
		(layers "F.Cu" "B.Cu")
		(net "M_H_DQ<37>")
	)
	(via
		(at 114.699542 -7.086346)
		(size 0.508)
		(drill 0.254)
		(layers "F.Cu" "B.Cu")
		(net "M_H_DQ<37>")
	)
	(segment
		(start 115.549426 -12.513056)
		(end 115.473226 -12.589256)
		(width 0.1651)
		(layer "B.Cu")
		(net "M_H_DQ<37>")
	)
	(segment
		(start 115.549426 -10.623042)
		(end 115.549426 -12.513056)
		(width 0.1651)
		(layer "B.Cu")
		(net "M_H_DQ<37>")
	)
	(segment
		(start 115.942364 -16.37665)
		(end 115.942364 -16.925544)
		(width 0.14224)
		(layer "In4.Cu")
		(net "M_H_DQ<37>")
	)
	(segment
		(start 115.78463 -12.280392)
		(end 115.475766 -12.589256)
		(width 0.14224)
		(layer "In4.Cu")
		(net "M_H_DQ<37>")
	)
	(segment
		(start 106.65206 -36.65093)
		(end 106.65206 -45.339254)
		(width 0.14224)
		(layer "In4.Cu")
		(net "M_H_DQ<37>")
	)
	(segment
		(start 106.437684 -45.55363)
		(end 106.437684 -48.26381)
		(width 0.0889)
		(layer "In4.Cu")
		(net "M_H_DQ<37>")
	)
	(segment
		(start 105.5878 -57.317894)
		(end 105.955846 -57.68594)
		(width 0.0889)
		(layer "In4.Cu")
		(net "M_H_DQ<37>")
	)
	(segment
		(start 114.699542 -7.086346)
		(end 114.699542 -7.481062)
		(width 0.14224)
		(layer "In4.Cu")
		(net "M_H_DQ<37>")
	)
	(segment
		(start 108.151168 -32.833056)
		(end 108.151168 -33.20669)
		(width 0.14224)
		(layer "In4.Cu")
		(net "M_H_DQ<37>")
	)
	(segment
		(start 104.634284 -52.260754)
		(end 104.634792 -52.261262)
		(width 0.0889)
		(layer "In4.Cu")
		(net "M_H_DQ<37>")
	)
	(segment
		(start 115.946682 -16.929862)
		(end 115.946682 -18.504662)
		(width 0.14224)
		(layer "In4.Cu")
		(net "M_H_DQ<37>")
	)
	(segment
		(start 115.946682 -18.504662)
		(end 115.857782 -18.593562)
		(width 0.14224)
		(layer "In4.Cu")
		(net "M_H_DQ<37>")
	)
	(segment
		(start 106.153458 -49.929288)
		(end 106.15295 -49.929288)
		(width 0.0889)
		(layer "In4.Cu")
		(net "M_H_DQ<37>")
	)
	(segment
		(start 115.942364 -23.14067)
		(end 115.942364 -25.04186)
		(width 0.14224)
		(layer "In4.Cu")
		(net "M_H_DQ<37>")
	)
	(segment
		(start 115.003326 -13.059156)
		(end 115.003326 -13.507212)
		(width 0.14224)
		(layer "In4.Cu")
		(net "M_H_DQ<37>")
	)
	(segment
		(start 115.946682 -21.962872)
		(end 115.946682 -22.823678)
		(width 0.14224)
		(layer "In4.Cu")
		(net "M_H_DQ<37>")
	)
	(segment
		(start 106.153458 -48.548036)
		(end 106.153458 -49.929288)
		(width 0.0889)
		(layer "In4.Cu")
		(net "M_H_DQ<37>")
	)
	(segment
		(start 105.395776 -50.686208)
		(end 105.394506 -50.687732)
		(width 0.0889)
		(layer "In4.Cu")
		(net "M_H_DQ<37>")
	)
	(segment
		(start 106.15295 -49.929288)
		(end 105.395776 -50.686208)
		(width 0.0889)
		(layer "In4.Cu")
		(net "M_H_DQ<37>")
	)
	(segment
		(start 105.394506 -50.687732)
		(end 105.394506 -51.500532)
		(width 0.0889)
		(layer "In4.Cu")
		(net "M_H_DQ<37>")
	)
	(segment
		(start 115.857782 -18.593562)
		(end 115.857782 -21.873972)
		(width 0.14224)
		(layer "In4.Cu")
		(net "M_H_DQ<37>")
	)
	(segment
		(start 105.394506 -51.500532)
		(end 104.634284 -52.260754)
		(width 0.0889)
		(layer "In4.Cu")
		(net "M_H_DQ<37>")
	)
	(segment
		(start 106.65206 -45.339254)
		(end 106.437684 -45.55363)
		(width 0.0889)
		(layer "In4.Cu")
		(net "M_H_DQ<37>")
	)
	(segment
		(start 104.634792 -56.678322)
		(end 105.274364 -57.317894)
		(width 0.0889)
		(layer "In4.Cu")
		(net "M_H_DQ<37>")
	)
	(segment
		(start 114.699542 -7.481062)
		(end 115.27028 -8.0518)
		(width 0.14224)
		(layer "In4.Cu")
		(net "M_H_DQ<37>")
	)
	(segment
		(start 115.942364 -25.04186)
		(end 108.151168 -32.833056)
		(width 0.14224)
		(layer "In4.Cu")
		(net "M_H_DQ<37>")
	)
	(segment
		(start 108.963968 -34.339022)
		(end 106.65206 -36.65093)
		(width 0.14224)
		(layer "In4.Cu")
		(net "M_H_DQ<37>")
	)
	(segment
		(start 115.943126 -23.139908)
		(end 115.942364 -23.14067)
		(width 0.14224)
		(layer "In4.Cu")
		(net "M_H_DQ<37>")
	)
	(segment
		(start 115.475766 -12.589256)
		(end 115.473226 -12.589256)
		(width 0.14224)
		(layer "In4.Cu")
		(net "M_H_DQ<37>")
	)
	(segment
		(start 108.151168 -33.20669)
		(end 108.963968 -34.01949)
		(width 0.14224)
		(layer "In4.Cu")
		(net "M_H_DQ<37>")
	)
	(segment
		(start 115.003326 -13.507212)
		(end 115.390168 -13.894054)
		(width 0.14224)
		(layer "In4.Cu")
		(net "M_H_DQ<37>")
	)
	(segment
		(start 106.437684 -48.26381)
		(end 106.153458 -48.548036)
		(width 0.0889)
		(layer "In4.Cu")
		(net "M_H_DQ<37>")
	)
	(segment
		(start 115.78463 -9.06145)
		(end 115.78463 -12.280392)
		(width 0.14224)
		(layer "In4.Cu")
		(net "M_H_DQ<37>")
	)
	(segment
		(start 115.98148 -8.452104)
		(end 115.98148 -8.8646)
		(width 0.14224)
		(layer "In4.Cu")
		(net "M_H_DQ<37>")
	)
	(segment
		(start 108.963968 -34.01949)
		(end 108.963968 -34.339022)
		(width 0.14224)
		(layer "In4.Cu")
		(net "M_H_DQ<37>")
	)
	(segment
		(start 115.98148 -8.8646)
		(end 115.78463 -9.06145)
		(width 0.14224)
		(layer "In4.Cu")
		(net "M_H_DQ<37>")
	)
	(segment
		(start 115.473226 -12.589256)
		(end 115.003326 -13.059156)
		(width 0.14224)
		(layer "In4.Cu")
		(net "M_H_DQ<37>")
	)
	(segment
		(start 115.390168 -13.894054)
		(end 115.390168 -15.824454)
		(width 0.14224)
		(layer "In4.Cu")
		(net "M_H_DQ<37>")
	)
	(segment
		(start 105.274364 -57.317894)
		(end 105.5878 -57.317894)
		(width 0.0889)
		(layer "In4.Cu")
		(net "M_H_DQ<37>")
	)
	(segment
		(start 115.943126 -22.827234)
		(end 115.943126 -23.139908)
		(width 0.14224)
		(layer "In4.Cu")
		(net "M_H_DQ<37>")
	)
	(segment
		(start 115.857782 -21.873972)
		(end 115.946682 -21.962872)
		(width 0.14224)
		(layer "In4.Cu")
		(net "M_H_DQ<37>")
	)
	(segment
		(start 115.946682 -22.823678)
		(end 115.943126 -22.827234)
		(width 0.14224)
		(layer "In4.Cu")
		(net "M_H_DQ<37>")
	)
	(segment
		(start 115.942364 -16.925544)
		(end 115.946682 -16.929862)
		(width 0.14224)
		(layer "In4.Cu")
		(net "M_H_DQ<37>")
	)
	(segment
		(start 104.634792 -52.261262)
		(end 104.634792 -56.678322)
		(width 0.0889)
		(layer "In4.Cu")
		(net "M_H_DQ<37>")
	)
	(segment
		(start 115.581176 -8.0518)
		(end 115.98148 -8.452104)
		(width 0.14224)
		(layer "In4.Cu")
		(net "M_H_DQ<37>")
	)
	(segment
		(start 115.27028 -8.0518)
		(end 115.581176 -8.0518)
		(width 0.14224)
		(layer "In4.Cu")
		(net "M_H_DQ<37>")
	)
	(segment
		(start 115.390168 -15.824454)
		(end 115.942364 -16.37665)
		(width 0.14224)
		(layer "In4.Cu")
		(net "M_H_DQ<37>")
	)
	(arc
		(start 105.955846 -57.68594)
		(mid 106.009345 -57.885838)
		(end 105.955846 -58.085736)
		(width 0.0889)
		(layer "In4.Cu")
		(net "M_H_DQ<37>")
	)
	(arc
		(start 105.955846 -58.085736)
		(mid 105.749577 -58.47434)
		(end 105.571036 -58.876438)
		(width 0.0889)
		(layer "In4.Cu")
		(net "M_H_DQ<37>")
	)
	(segment
		(start 115.549426 -10.422382)
		(end 115.549426 -9.091168)
		(width 0.1651)
		(layer "F.Cu")
		(net "M_H_DQ<36>")
	)
	(segment
		(start 106.193336 -57.885584)
		(end 105.571036 -57.885584)
		(width 0.1651)
		(layer "F.Cu")
		(net "M_H_DQ<36>")
	)
	(segment
		(start 115.512342 -8.89)
		(end 115.488974 -8.763)
		(width 0.1651)
		(layer "F.Cu")
		(net "M_H_DQ<36>")
	)
	(segment
		(start 115.488974 -8.763)
		(end 115.451382 -8.5598)
		(width 0.1651)
		(layer "F.Cu")
		(net "M_H_DQ<36>")
	)
	(segment
		(start 115.549426 -9.091168)
		(end 115.512342 -8.89)
		(width 0.1651)
		(layer "F.Cu")
		(net "M_H_DQ<36>")
	)
	(via
		(at 115.451382 -8.5598)
		(size 0.508)
		(drill 0.254)
		(layers "F.Cu" "B.Cu")
		(net "M_H_DQ<36>")
	)
	(via
		(at 105.571036 -57.885584)
		(size 0.508)
		(drill 0.254)
		(layers "F.Cu" "B.Cu")
		(net "M_H_DQ<36>")
	)
	(via
		(at 114.699542 -13.959078)
		(size 0.508)
		(drill 0.254)
		(layers "F.Cu" "B.Cu")
		(net "M_H_DQ<36>")
	)
	(segment
		(start 114.699542 -15.222982)
		(end 114.699542 -13.959078)
		(width 0.1651)
		(layer "B.Cu")
		(net "M_H_DQ<36>")
	)
	(segment
		(start 114.968782 -21.950172)
		(end 115.222782 -21.696172)
		(width 0.14224)
		(layer "In4.Cu")
		(net "M_H_DQ<36>")
	)
	(segment
		(start 114.983768 -24.0284)
		(end 115.313968 -23.6982)
		(width 0.14224)
		(layer "In4.Cu")
		(net "M_H_DQ<36>")
	)
	(segment
		(start 114.983768 -24.2062)
		(end 114.983768 -24.0284)
		(width 0.14224)
		(layer "In4.Cu")
		(net "M_H_DQ<36>")
	)
	(segment
		(start 105.204514 -50.597308)
		(end 105.963212 -49.83861)
		(width 0.0889)
		(layer "In4.Cu")
		(net "M_H_DQ<36>")
	)
	(segment
		(start 115.222782 -21.696172)
		(end 115.222782 -18.568162)
		(width 0.14224)
		(layer "In4.Cu")
		(net "M_H_DQ<36>")
	)
	(segment
		(start 115.17503 -9.313672)
		(end 115.17503 -8.836152)
		(width 0.14224)
		(layer "In4.Cu")
		(net "M_H_DQ<36>")
	)
	(segment
		(start 114.823748 -11.0363)
		(end 115.192048 -10.668)
		(width 0.14224)
		(layer "In4.Cu")
		(net "M_H_DQ<36>")
	)
	(segment
		(start 114.811048 -9.9822)
		(end 114.811048 -9.677654)
		(width 0.14224)
		(layer "In4.Cu")
		(net "M_H_DQ<36>")
	)
	(segment
		(start 115.222782 -18.568162)
		(end 114.968782 -18.314162)
		(width 0.14224)
		(layer "In4.Cu")
		(net "M_H_DQ<36>")
	)
	(segment
		(start 114.968782 -17.058386)
		(end 115.156742 -16.870426)
		(width 0.14224)
		(layer "In4.Cu")
		(net "M_H_DQ<36>")
	)
	(segment
		(start 115.17503 -8.836152)
		(end 115.451382 -8.5598)
		(width 0.14224)
		(layer "In4.Cu")
		(net "M_H_DQ<36>")
	)
	(segment
		(start 107.659678 -33.727898)
		(end 107.403138 -33.727898)
		(width 0.14224)
		(layer "In4.Cu")
		(net "M_H_DQ<36>")
	)
	(segment
		(start 105.204514 -51.421792)
		(end 105.204514 -50.597308)
		(width 0.0889)
		(layer "In4.Cu")
		(net "M_H_DQ<36>")
	)
	(segment
		(start 104.444292 -52.182014)
		(end 105.204514 -51.421792)
		(width 0.0889)
		(layer "In4.Cu")
		(net "M_H_DQ<36>")
	)
	(segment
		(start 107.97794 -34.04616)
		(end 107.659678 -33.727898)
		(width 0.14224)
		(layer "In4.Cu")
		(net "M_H_DQ<36>")
	)
	(segment
		(start 106.636058 -33.61309)
		(end 106.636058 -33.411922)
		(width 0.14224)
		(layer "In4.Cu")
		(net "M_H_DQ<36>")
	)
	(segment
		(start 105.571036 -57.885584)
		(end 104.444292 -56.75884)
		(width 0.0889)
		(layer "In4.Cu")
		(net "M_H_DQ<36>")
	)
	(segment
		(start 115.313968 -23.514558)
		(end 114.968782 -23.169372)
		(width 0.14224)
		(layer "In4.Cu")
		(net "M_H_DQ<36>")
	)
	(segment
		(start 115.156742 -16.378428)
		(end 114.699542 -15.921228)
		(width 0.14224)
		(layer "In4.Cu")
		(net "M_H_DQ<36>")
	)
	(segment
		(start 114.811048 -9.677654)
		(end 115.17503 -9.313672)
		(width 0.14224)
		(layer "In4.Cu")
		(net "M_H_DQ<36>")
	)
	(segment
		(start 114.968782 -23.169372)
		(end 114.968782 -21.950172)
		(width 0.14224)
		(layer "In4.Cu")
		(net "M_H_DQ<36>")
	)
	(segment
		(start 106.247692 -48.18507)
		(end 106.247692 -45.569124)
		(width 0.0889)
		(layer "In4.Cu")
		(net "M_H_DQ<36>")
	)
	(segment
		(start 115.192048 -10.668)
		(end 115.192048 -10.3632)
		(width 0.14224)
		(layer "In4.Cu")
		(net "M_H_DQ<36>")
	)
	(segment
		(start 107.97794 -34.3027)
		(end 107.97794 -34.04616)
		(width 0.14224)
		(layer "In4.Cu")
		(net "M_H_DQ<36>")
	)
	(segment
		(start 106.636058 -33.411922)
		(end 115.313968 -24.734012)
		(width 0.14224)
		(layer "In4.Cu")
		(net "M_H_DQ<36>")
	)
	(segment
		(start 115.313968 -23.6982)
		(end 115.313968 -23.514558)
		(width 0.14224)
		(layer "In4.Cu")
		(net "M_H_DQ<36>")
	)
	(segment
		(start 114.699542 -13.959078)
		(end 114.46383 -13.723366)
		(width 0.14224)
		(layer "In4.Cu")
		(net "M_H_DQ<36>")
	)
	(segment
		(start 104.444292 -56.75884)
		(end 104.444292 -52.182014)
		(width 0.0889)
		(layer "In4.Cu")
		(net "M_H_DQ<36>")
	)
	(segment
		(start 114.46383 -13.723366)
		(end 114.46383 -12.928854)
		(width 0.14224)
		(layer "In4.Cu")
		(net "M_H_DQ<36>")
	)
	(segment
		(start 105.963212 -48.46955)
		(end 106.247692 -48.18507)
		(width 0.0889)
		(layer "In4.Cu")
		(net "M_H_DQ<36>")
	)
	(segment
		(start 115.17503 -12.217654)
		(end 115.17503 -11.742928)
		(width 0.14224)
		(layer "In4.Cu")
		(net "M_H_DQ<36>")
	)
	(segment
		(start 115.156742 -16.870426)
		(end 115.156742 -16.378428)
		(width 0.14224)
		(layer "In4.Cu")
		(net "M_H_DQ<36>")
	)
	(segment
		(start 114.699542 -15.921228)
		(end 114.699542 -13.959078)
		(width 0.14224)
		(layer "In4.Cu")
		(net "M_H_DQ<36>")
	)
	(segment
		(start 115.192048 -10.3632)
		(end 114.811048 -9.9822)
		(width 0.14224)
		(layer "In4.Cu")
		(net "M_H_DQ<36>")
	)
	(segment
		(start 115.313968 -24.5364)
		(end 114.983768 -24.2062)
		(width 0.14224)
		(layer "In4.Cu")
		(net "M_H_DQ<36>")
	)
	(segment
		(start 107.403138 -33.727898)
		(end 107.177586 -33.95345)
		(width 0.14224)
		(layer "In4.Cu")
		(net "M_H_DQ<36>")
	)
	(segment
		(start 106.087164 -36.193476)
		(end 107.97794 -34.3027)
		(width 0.14224)
		(layer "In4.Cu")
		(net "M_H_DQ<36>")
	)
	(segment
		(start 115.17503 -11.742928)
		(end 114.823748 -11.391646)
		(width 0.14224)
		(layer "In4.Cu")
		(net "M_H_DQ<36>")
	)
	(segment
		(start 107.177586 -33.95345)
		(end 106.976418 -33.95345)
		(width 0.14224)
		(layer "In4.Cu")
		(net "M_H_DQ<36>")
	)
	(segment
		(start 114.823748 -11.391646)
		(end 114.823748 -11.0363)
		(width 0.14224)
		(layer "In4.Cu")
		(net "M_H_DQ<36>")
	)
	(segment
		(start 115.313968 -24.734012)
		(end 115.313968 -24.5364)
		(width 0.14224)
		(layer "In4.Cu")
		(net "M_H_DQ<36>")
	)
	(segment
		(start 114.46383 -12.928854)
		(end 115.17503 -12.217654)
		(width 0.14224)
		(layer "In4.Cu")
		(net "M_H_DQ<36>")
	)
	(segment
		(start 106.087164 -45.408596)
		(end 106.087164 -36.193476)
		(width 0.14224)
		(layer "In4.Cu")
		(net "M_H_DQ<36>")
	)
	(segment
		(start 114.968782 -18.314162)
		(end 114.968782 -17.058386)
		(width 0.14224)
		(layer "In4.Cu")
		(net "M_H_DQ<36>")
	)
	(segment
		(start 106.247692 -45.569124)
		(end 106.087164 -45.408596)
		(width 0.0889)
		(layer "In4.Cu")
		(net "M_H_DQ<36>")
	)
	(segment
		(start 105.963212 -49.83861)
		(end 105.963212 -48.46955)
		(width 0.0889)
		(layer "In4.Cu")
		(net "M_H_DQ<36>")
	)
	(segment
		(start 106.976418 -33.95345)
		(end 106.636058 -33.61309)
		(width 0.14224)
		(layer "In4.Cu")
		(net "M_H_DQ<36>")
	)
	(segment
		(start 108.768896 -57.390538)
		(end 108.197396 -57.390538)
		(width 0.1016)
		(layer "F.Cu")
		(net "M_H_DQ<35>")
	)
	(segment
		(start 122.349514 -5.822442)
		(end 122.349514 -7.086346)
		(width 0.1651)
		(layer "F.Cu")
		(net "M_H_DQ<35>")
	)
	(via
		(at 122.349514 -7.086346)
		(size 0.508)
		(drill 0.254)
		(layers "F.Cu" "B.Cu")
		(net "M_H_DQ<35>")
	)
	(via
		(at 108.197396 -57.390538)
		(size 0.508)
		(drill 0.254)
		(layers "F.Cu" "B.Cu")
		(net "M_H_DQ<35>")
	)
	(via
		(at 123.199398 -12.678156)
		(size 0.508)
		(drill 0.254)
		(layers "F.Cu" "B.Cu")
		(net "M_H_DQ<35>")
	)
	(segment
		(start 123.199398 -10.623042)
		(end 123.199398 -12.678156)
		(width 0.1651)
		(layer "B.Cu")
		(net "M_H_DQ<35>")
	)
	(segment
		(start 109.645958 -54.08295)
		(end 109.645958 -52.477416)
		(width 0.0889)
		(layer "In4.Cu")
		(net "M_H_DQ<35>")
	)
	(segment
		(start 109.576616 -55.624476)
		(end 109.567726 -55.609236)
		(width 0.0889)
		(layer "In4.Cu")
		(net "M_H_DQ<35>")
	)
	(segment
		(start 112.350296 -45.902118)
		(end 112.57534 -45.677074)
		(width 0.0889)
		(layer "In4.Cu")
		(net "M_H_DQ<35>")
	)
	(segment
		(start 109.567726 -54.618636)
		(end 109.5629 -54.61)
		(width 0.0889)
		(layer "In4.Cu")
		(net "M_H_DQ<35>")
	)
	(segment
		(start 112.589818 -41.233344)
		(end 112.589818 -38.96995)
		(width 0.14224)
		(layer "In4.Cu")
		(net "M_H_DQ<35>")
	)
	(segment
		(start 109.576616 -54.633876)
		(end 109.567726 -54.618636)
		(width 0.0889)
		(layer "In4.Cu")
		(net "M_H_DQ<35>")
	)
	(segment
		(start 112.350296 -46.377098)
		(end 112.350296 -45.902118)
		(width 0.0889)
		(layer "In4.Cu")
		(net "M_H_DQ<35>")
	)
	(segment
		(start 123.566682 -16.891762)
		(end 123.566682 -14.419072)
		(width 0.14224)
		(layer "In4.Cu")
		(net "M_H_DQ<35>")
	)
	(segment
		(start 110.001812 -49.760886)
		(end 110.283752 -49.478946)
		(width 0.0889)
		(layer "In4.Cu")
		(net "M_H_DQ<35>")
	)
	(segment
		(start 123.552204 -9.020048)
		(end 123.707652 -8.8646)
		(width 0.14224)
		(layer "In4.Cu")
		(net "M_H_DQ<35>")
	)
	(segment
		(start 112.589818 -44.759626)
		(end 113.27638 -44.073064)
		(width 0.14224)
		(layer "In4.Cu")
		(net "M_H_DQ<35>")
	)
	(segment
		(start 122.996452 -8.0518)
		(end 122.666252 -7.7216)
		(width 0.14224)
		(layer "In4.Cu")
		(net "M_H_DQ<35>")
	)
	(segment
		(start 123.731782 -22.000972)
		(end 123.553982 -21.823172)
		(width 0.14224)
		(layer "In4.Cu")
		(net "M_H_DQ<35>")
	)
	(segment
		(start 123.566682 -27.993086)
		(end 123.566682 -23.283672)
		(width 0.14224)
		(layer "In4.Cu")
		(net "M_H_DQ<35>")
	)
	(segment
		(start 122.666252 -7.403084)
		(end 122.349514 -7.086346)
		(width 0.14224)
		(layer "In4.Cu")
		(net "M_H_DQ<35>")
	)
	(segment
		(start 109.645958 -52.477416)
		(end 110.001812 -52.121562)
		(width 0.0889)
		(layer "In4.Cu")
		(net "M_H_DQ<35>")
	)
	(segment
		(start 123.706382 -17.031462)
		(end 123.566682 -16.891762)
		(width 0.14224)
		(layer "In4.Cu")
		(net "M_H_DQ<35>")
	)
	(segment
		(start 108.197396 -57.052464)
		(end 108.262674 -56.987186)
		(width 0.0889)
		(layer "In4.Cu")
		(net "M_H_DQ<35>")
	)
	(segment
		(start 122.715782 -13.161772)
		(end 123.199398 -12.678156)
		(width 0.14224)
		(layer "In4.Cu")
		(net "M_H_DQ<35>")
	)
	(segment
		(start 123.707652 -8.509)
		(end 123.250452 -8.0518)
		(width 0.14224)
		(layer "In4.Cu")
		(net "M_H_DQ<35>")
	)
	(segment
		(start 113.27638 -41.919906)
		(end 112.589818 -41.233344)
		(width 0.14224)
		(layer "In4.Cu")
		(net "M_H_DQ<35>")
	)
	(segment
		(start 123.707652 -8.8646)
		(end 123.707652 -8.509)
		(width 0.14224)
		(layer "In4.Cu")
		(net "M_H_DQ<35>")
	)
	(segment
		(start 123.566682 -23.283672)
		(end 123.731782 -23.118572)
		(width 0.14224)
		(layer "In4.Cu")
		(net "M_H_DQ<35>")
	)
	(segment
		(start 122.666252 -7.7216)
		(end 122.666252 -7.403084)
		(width 0.14224)
		(layer "In4.Cu")
		(net "M_H_DQ<35>")
	)
	(segment
		(start 123.553982 -18.556986)
		(end 123.706382 -18.404586)
		(width 0.14224)
		(layer "In4.Cu")
		(net "M_H_DQ<35>")
	)
	(segment
		(start 108.197396 -57.390538)
		(end 108.197396 -57.052464)
		(width 0.0889)
		(layer "In4.Cu")
		(net "M_H_DQ<35>")
	)
	(segment
		(start 123.731782 -23.118572)
		(end 123.731782 -22.000972)
		(width 0.14224)
		(layer "In4.Cu")
		(net "M_H_DQ<35>")
	)
	(segment
		(start 123.250452 -8.0518)
		(end 122.996452 -8.0518)
		(width 0.14224)
		(layer "In4.Cu")
		(net "M_H_DQ<35>")
	)
	(segment
		(start 123.553982 -21.823172)
		(end 123.553982 -18.556986)
		(width 0.14224)
		(layer "In4.Cu")
		(net "M_H_DQ<35>")
	)
	(segment
		(start 110.001812 -52.121562)
		(end 110.001812 -49.760886)
		(width 0.0889)
		(layer "In4.Cu")
		(net "M_H_DQ<35>")
	)
	(segment
		(start 112.589818 -38.96995)
		(end 123.566682 -27.993086)
		(width 0.14224)
		(layer "In4.Cu")
		(net "M_H_DQ<35>")
	)
	(segment
		(start 113.27638 -44.073064)
		(end 113.27638 -41.919906)
		(width 0.14224)
		(layer "In4.Cu")
		(net "M_H_DQ<35>")
	)
	(segment
		(start 109.04474 -56.494934)
		(end 109.080808 -56.494934)
		(width 0.0889)
		(layer "In4.Cu")
		(net "M_H_DQ<35>")
	)
	(segment
		(start 123.199398 -12.678156)
		(end 123.552204 -12.32535)
		(width 0.14224)
		(layer "In4.Cu")
		(net "M_H_DQ<35>")
	)
	(segment
		(start 122.715782 -13.568172)
		(end 122.715782 -13.161772)
		(width 0.14224)
		(layer "In4.Cu")
		(net "M_H_DQ<35>")
	)
	(segment
		(start 110.283752 -48.443642)
		(end 112.350296 -46.377098)
		(width 0.0889)
		(layer "In4.Cu")
		(net "M_H_DQ<35>")
	)
	(segment
		(start 123.552204 -12.32535)
		(end 123.552204 -9.020048)
		(width 0.14224)
		(layer "In4.Cu")
		(net "M_H_DQ<35>")
	)
	(segment
		(start 112.57534 -45.677074)
		(end 112.589818 -45.662596)
		(width 0.14224)
		(layer "In4.Cu")
		(net "M_H_DQ<35>")
	)
	(segment
		(start 109.567726 -54.218586)
		(end 109.645958 -54.08295)
		(width 0.0889)
		(layer "In4.Cu")
		(net "M_H_DQ<35>")
	)
	(segment
		(start 112.589818 -45.662596)
		(end 112.589818 -44.759626)
		(width 0.14224)
		(layer "In4.Cu")
		(net "M_H_DQ<35>")
	)
	(segment
		(start 123.566682 -14.419072)
		(end 122.715782 -13.568172)
		(width 0.14224)
		(layer "In4.Cu")
		(net "M_H_DQ<35>")
	)
	(segment
		(start 110.283752 -49.478946)
		(end 110.283752 -48.443642)
		(width 0.0889)
		(layer "In4.Cu")
		(net "M_H_DQ<35>")
	)
	(segment
		(start 123.706382 -18.404586)
		(end 123.706382 -17.031462)
		(width 0.14224)
		(layer "In4.Cu")
		(net "M_H_DQ<35>")
	)
	(arc
		(start 109.5629 -54.61)
		(mid 109.514114 -54.413648)
		(end 109.567726 -54.218586)
		(width 0.0889)
		(layer "In4.Cu")
		(net "M_H_DQ<35>")
	)
	(arc
		(start 108.709206 -56.695086)
		(mid 108.850889 -56.551282)
		(end 109.04474 -56.494934)
		(width 0.0889)
		(layer "In4.Cu")
		(net "M_H_DQ<35>")
	)
	(arc
		(start 109.080808 -56.494934)
		(mid 109.569532 -56.196904)
		(end 109.576616 -55.624476)
		(width 0.0889)
		(layer "In4.Cu")
		(net "M_H_DQ<35>")
	)
	(arc
		(start 109.567726 -55.20944)
		(mid 109.646915 -54.922825)
		(end 109.576616 -54.633876)
		(width 0.0889)
		(layer "In4.Cu")
		(net "M_H_DQ<35>")
	)
	(arc
		(start 109.567726 -55.609236)
		(mid 109.514193 -55.409338)
		(end 109.567726 -55.20944)
		(width 0.0889)
		(layer "In4.Cu")
		(net "M_H_DQ<35>")
	)
	(arc
		(start 108.262674 -56.987186)
		(mid 108.520811 -56.894432)
		(end 108.709206 -56.695086)
		(width 0.0889)
		(layer "In4.Cu")
		(net "M_H_DQ<35>")
	)
	(segment
		(start 123.33097 -9.29386)
		(end 123.33097 -9.07034)
		(width 0.1651)
		(layer "F.Cu")
		(net "M_H_DQ<34>")
	)
	(segment
		(start 108.768896 -56.399938)
		(end 108.197396 -56.399938)
		(width 0.1016)
		(layer "F.Cu")
		(net "M_H_DQ<34>")
	)
	(segment
		(start 123.199398 -10.422382)
		(end 123.199398 -9.425432)
		(width 0.1651)
		(layer "F.Cu")
		(net "M_H_DQ<34>")
	)
	(segment
		(start 123.199398 -8.938768)
		(end 123.199398 -8.6614)
		(width 0.1651)
		(layer "F.Cu")
		(net "M_H_DQ<34>")
	)
	(segment
		(start 123.33097 -9.07034)
		(end 123.199398 -8.938768)
		(width 0.1651)
		(layer "F.Cu")
		(net "M_H_DQ<34>")
	)
	(segment
		(start 123.199398 -9.425432)
		(end 123.33097 -9.29386)
		(width 0.1651)
		(layer "F.Cu")
		(net "M_H_DQ<34>")
	)
	(via
		(at 123.199398 -8.6614)
		(size 0.508)
		(drill 0.254)
		(layers "F.Cu" "B.Cu")
		(net "M_H_DQ<34>")
	)
	(via
		(at 122.349514 -13.959078)
		(size 0.508)
		(drill 0.254)
		(layers "F.Cu" "B.Cu")
		(net "M_H_DQ<34>")
	)
	(via
		(at 108.197396 -56.399938)
		(size 0.508)
		(drill 0.254)
		(layers "F.Cu" "B.Cu")
		(net "M_H_DQ<34>")
	)
	(segment
		(start 122.349514 -15.222982)
		(end 122.349514 -13.959078)
		(width 0.1651)
		(layer "B.Cu")
		(net "M_H_DQ<34>")
	)
	(segment
		(start 122.349514 -13.959078)
		(end 122.06478 -13.674344)
		(width 0.14224)
		(layer "In4.Cu")
		(net "M_H_DQ<34>")
	)
	(segment
		(start 122.913648 -11.811)
		(end 122.456448 -11.3538)
		(width 0.14224)
		(layer "In4.Cu")
		(net "M_H_DQ<34>")
	)
	(segment
		(start 122.311668 -24.75611)
		(end 122.453908 -24.61387)
		(width 0.14224)
		(layer "In4.Cu")
		(net "M_H_DQ<34>")
	)
	(segment
		(start 109.455966 -54.030118)
		(end 109.455966 -52.397914)
		(width 0.0889)
		(layer "In4.Cu")
		(net "M_H_DQ<34>")
	)
	(segment
		(start 122.311668 -25.28443)
		(end 122.311668 -24.75611)
		(width 0.14224)
		(layer "In4.Cu")
		(net "M_H_DQ<34>")
	)
	(segment
		(start 112.545368 -42.834306)
		(end 112.403128 -42.692066)
		(width 0.14224)
		(layer "In4.Cu")
		(net "M_H_DQ<34>")
	)
	(segment
		(start 122.842782 -21.797772)
		(end 122.842782 -18.552414)
		(width 0.14224)
		(layer "In4.Cu")
		(net "M_H_DQ<34>")
	)
	(segment
		(start 122.842782 -18.552414)
		(end 122.715782 -18.425414)
		(width 0.14224)
		(layer "In4.Cu")
		(net "M_H_DQ<34>")
	)
	(segment
		(start 108.197396 -56.399938)
		(end 108.197396 -56.738012)
		(width 0.0889)
		(layer "In4.Cu")
		(net "M_H_DQ<34>")
	)
	(segment
		(start 109.402372 -54.713886)
		(end 109.391704 -54.695344)
		(width 0.0889)
		(layer "In4.Cu")
		(net "M_H_DQ<34>")
	)
	(segment
		(start 122.06478 -13.674344)
		(end 122.06478 -12.9286)
		(width 0.14224)
		(layer "In4.Cu")
		(net "M_H_DQ<34>")
	)
	(segment
		(start 122.456448 -11.3538)
		(end 122.456448 -10.95375)
		(width 0.14224)
		(layer "In4.Cu")
		(net "M_H_DQ<34>")
	)
	(segment
		(start 112.109758 -42.692066)
		(end 111.954818 -42.537126)
		(width 0.14224)
		(layer "In4.Cu")
		(net "M_H_DQ<34>")
	)
	(segment
		(start 111.954818 -42.537126)
		(end 111.954818 -38.69055)
		(width 0.14224)
		(layer "In4.Cu")
		(net "M_H_DQ<34>")
	)
	(segment
		(start 122.690382 -21.950172)
		(end 122.842782 -21.797772)
		(width 0.14224)
		(layer "In4.Cu")
		(net "M_H_DQ<34>")
	)
	(segment
		(start 112.160304 -45.897038)
		(end 111.94034 -45.677074)
		(width 0.0889)
		(layer "In4.Cu")
		(net "M_H_DQ<34>")
	)
	(segment
		(start 122.918982 -16.764762)
		(end 122.918982 -14.686026)
		(width 0.14224)
		(layer "In4.Cu")
		(net "M_H_DQ<34>")
	)
	(segment
		(start 122.931682 -27.713686)
		(end 122.931682 -25.62987)
		(width 0.14224)
		(layer "In4.Cu")
		(net "M_H_DQ<34>")
	)
	(segment
		(start 122.931682 -25.62987)
		(end 122.728482 -25.42667)
		(width 0.14224)
		(layer "In4.Cu")
		(net "M_H_DQ<34>")
	)
	(segment
		(start 109.811312 -49.682654)
		(end 110.09376 -49.400206)
		(width 0.0889)
		(layer "In4.Cu")
		(net "M_H_DQ<34>")
	)
	(segment
		(start 122.456448 -10.95375)
		(end 122.761248 -10.64895)
		(width 0.14224)
		(layer "In4.Cu")
		(net "M_H_DQ<34>")
	)
	(segment
		(start 111.954818 -45.662596)
		(end 111.954818 -43.636946)
		(width 0.14224)
		(layer "In4.Cu")
		(net "M_H_DQ<34>")
	)
	(segment
		(start 110.09376 -49.400206)
		(end 110.09376 -48.364902)
		(width 0.0889)
		(layer "In4.Cu")
		(net "M_H_DQ<34>")
	)
	(segment
		(start 111.954818 -38.69055)
		(end 122.931682 -27.713686)
		(width 0.14224)
		(layer "In4.Cu")
		(net "M_H_DQ<34>")
	)
	(segment
		(start 122.80138 -9.059418)
		(end 123.199398 -8.6614)
		(width 0.14224)
		(layer "In4.Cu")
		(net "M_H_DQ<34>")
	)
	(segment
		(start 109.402372 -55.704486)
		(end 109.393482 -55.689246)
		(width 0.0889)
		(layer "In4.Cu")
		(net "M_H_DQ<34>")
	)
	(segment
		(start 122.918982 -14.686026)
		(end 122.349514 -14.116558)
		(width 0.14224)
		(layer "In4.Cu")
		(net "M_H_DQ<34>")
	)
	(segment
		(start 122.80138 -9.364472)
		(end 122.80138 -9.059418)
		(width 0.14224)
		(layer "In4.Cu")
		(net "M_H_DQ<34>")
	)
	(segment
		(start 122.931682 -24.41067)
		(end 122.931682 -23.385272)
		(width 0.14224)
		(layer "In4.Cu")
		(net "M_H_DQ<34>")
	)
	(segment
		(start 122.931682 -23.385272)
		(end 122.690382 -23.143972)
		(width 0.14224)
		(layer "In4.Cu")
		(net "M_H_DQ<34>")
	)
	(segment
		(start 109.038136 -56.304434)
		(end 109.055916 -56.304434)
		(width 0.0889)
		(layer "In4.Cu")
		(net "M_H_DQ<34>")
	)
	(segment
		(start 112.160304 -46.298358)
		(end 112.160304 -45.897038)
		(width 0.0889)
		(layer "In4.Cu")
		(net "M_H_DQ<34>")
	)
	(segment
		(start 122.761248 -10.64895)
		(end 122.761248 -10.362946)
		(width 0.14224)
		(layer "In4.Cu")
		(net "M_H_DQ<34>")
	)
	(segment
		(start 110.09376 -48.364902)
		(end 112.160304 -46.298358)
		(width 0.0889)
		(layer "In4.Cu")
		(net "M_H_DQ<34>")
	)
	(segment
		(start 122.715782 -18.425414)
		(end 122.715782 -16.967962)
		(width 0.14224)
		(layer "In4.Cu")
		(net "M_H_DQ<34>")
	)
	(segment
		(start 122.728482 -24.61387)
		(end 122.931682 -24.41067)
		(width 0.14224)
		(layer "In4.Cu")
		(net "M_H_DQ<34>")
	)
	(segment
		(start 122.728482 -25.42667)
		(end 122.453908 -25.42667)
		(width 0.14224)
		(layer "In4.Cu")
		(net "M_H_DQ<34>")
	)
	(segment
		(start 122.453908 -25.42667)
		(end 122.311668 -25.28443)
		(width 0.14224)
		(layer "In4.Cu")
		(net "M_H_DQ<34>")
	)
	(segment
		(start 122.690382 -23.143972)
		(end 122.690382 -21.950172)
		(width 0.14224)
		(layer "In4.Cu")
		(net "M_H_DQ<34>")
	)
	(segment
		(start 109.811312 -52.042568)
		(end 109.811312 -49.682654)
		(width 0.0889)
		(layer "In4.Cu")
		(net "M_H_DQ<34>")
	)
	(segment
		(start 109.402372 -54.122828)
		(end 109.455966 -54.030118)
		(width 0.0889)
		(layer "In4.Cu")
		(net "M_H_DQ<34>")
	)
	(segment
		(start 112.109758 -43.482006)
		(end 112.403128 -43.482006)
		(width 0.14224)
		(layer "In4.Cu")
		(net "M_H_DQ<34>")
	)
	(segment
		(start 109.455966 -52.397914)
		(end 109.811312 -52.042568)
		(width 0.0889)
		(layer "In4.Cu")
		(net "M_H_DQ<34>")
	)
	(segment
		(start 122.456448 -9.709404)
		(end 122.80138 -9.364472)
		(width 0.14224)
		(layer "In4.Cu")
		(net "M_H_DQ<34>")
	)
	(segment
		(start 122.349514 -14.116558)
		(end 122.349514 -13.959078)
		(width 0.14224)
		(layer "In4.Cu")
		(net "M_H_DQ<34>")
	)
	(segment
		(start 122.715782 -16.967962)
		(end 122.918982 -16.764762)
		(width 0.14224)
		(layer "In4.Cu")
		(net "M_H_DQ<34>")
	)
	(segment
		(start 108.197396 -56.738012)
		(end 108.255308 -56.795924)
		(width 0.0889)
		(layer "In4.Cu")
		(net "M_H_DQ<34>")
	)
	(segment
		(start 112.403128 -42.692066)
		(end 112.109758 -42.692066)
		(width 0.14224)
		(layer "In4.Cu")
		(net "M_H_DQ<34>")
	)
	(segment
		(start 111.94034 -45.677074)
		(end 111.954818 -45.662596)
		(width 0.14224)
		(layer "In4.Cu")
		(net "M_H_DQ<34>")
	)
	(segment
		(start 122.06478 -12.9286)
		(end 122.913648 -12.079732)
		(width 0.14224)
		(layer "In4.Cu")
		(net "M_H_DQ<34>")
	)
	(segment
		(start 122.913648 -12.079732)
		(end 122.913648 -11.811)
		(width 0.14224)
		(layer "In4.Cu")
		(net "M_H_DQ<34>")
	)
	(segment
		(start 122.456448 -10.058146)
		(end 122.456448 -9.709404)
		(width 0.14224)
		(layer "In4.Cu")
		(net "M_H_DQ<34>")
	)
	(segment
		(start 122.761248 -10.362946)
		(end 122.456448 -10.058146)
		(width 0.14224)
		(layer "In4.Cu")
		(net "M_H_DQ<34>")
	)
	(segment
		(start 112.545368 -43.339766)
		(end 112.545368 -42.834306)
		(width 0.14224)
		(layer "In4.Cu")
		(net "M_H_DQ<34>")
	)
	(segment
		(start 112.403128 -43.482006)
		(end 112.545368 -43.339766)
		(width 0.14224)
		(layer "In4.Cu")
		(net "M_H_DQ<34>")
	)
	(segment
		(start 122.453908 -24.61387)
		(end 122.728482 -24.61387)
		(width 0.14224)
		(layer "In4.Cu")
		(net "M_H_DQ<34>")
	)
	(segment
		(start 111.954818 -43.636946)
		(end 112.109758 -43.482006)
		(width 0.14224)
		(layer "In4.Cu")
		(net "M_H_DQ<34>")
	)
	(arc
		(start 108.255308 -56.795924)
		(mid 108.422209 -56.731024)
		(end 108.544106 -56.599836)
		(width 0.0889)
		(layer "In4.Cu")
		(net "M_H_DQ<34>")
	)
	(arc
		(start 109.391704 -54.695344)
		(mid 109.323105 -54.40771)
		(end 109.402372 -54.122828)
		(width 0.0889)
		(layer "In4.Cu")
		(net "M_H_DQ<34>")
	)
	(arc
		(start 109.055916 -56.304434)
		(mid 109.402342 -56.104457)
		(end 109.402372 -55.704486)
		(width 0.0889)
		(layer "In4.Cu")
		(net "M_H_DQ<34>")
	)
	(arc
		(start 109.402372 -55.113682)
		(mid 109.455905 -54.913784)
		(end 109.402372 -54.713886)
		(width 0.0889)
		(layer "In4.Cu")
		(net "M_H_DQ<34>")
	)
	(arc
		(start 108.544106 -56.599836)
		(mid 108.752714 -56.387904)
		(end 109.038136 -56.304434)
		(width 0.0889)
		(layer "In4.Cu")
		(net "M_H_DQ<34>")
	)
	(arc
		(start 109.393482 -55.689246)
		(mid 109.323085 -55.400295)
		(end 109.402372 -55.113682)
		(width 0.0889)
		(layer "In4.Cu")
		(net "M_H_DQ<34>")
	)
	(segment
		(start 116.399564 -5.822442)
		(end 116.399564 -7.086346)
		(width 0.1651)
		(layer "F.Cu")
		(net "M_H_DQ<33>")
	)
	(segment
		(start 106.193336 -54.913784)
		(end 105.571036 -54.913784)
		(width 0.1651)
		(layer "F.Cu")
		(net "M_H_DQ<33>")
	)
	(via
		(at 117.071648 -12.678156)
		(size 0.508)
		(drill 0.254)
		(layers "F.Cu" "B.Cu")
		(net "M_H_DQ<33>")
	)
	(via
		(at 116.399564 -7.086346)
		(size 0.508)
		(drill 0.254)
		(layers "F.Cu" "B.Cu")
		(net "M_H_DQ<33>")
	)
	(via
		(at 105.571036 -54.913784)
		(size 0.508)
		(drill 0.254)
		(layers "F.Cu" "B.Cu")
		(net "M_H_DQ<33>")
	)
	(segment
		(start 117.071648 -12.174982)
		(end 117.071648 -12.678156)
		(width 0.1651)
		(layer "B.Cu")
		(net "M_H_DQ<33>")
	)
	(segment
		(start 117.249448 -10.623042)
		(end 117.249448 -11.997182)
		(width 0.1651)
		(layer "B.Cu")
		(net "M_H_DQ<33>")
	)
	(segment
		(start 117.249448 -11.997182)
		(end 117.071648 -12.174982)
		(width 0.1651)
		(layer "B.Cu")
		(net "M_H_DQ<33>")
	)
	(segment
		(start 112.276382 -31.673546)
		(end 112.075214 -31.673546)
		(width 0.14224)
		(layer "In4.Cu")
		(net "M_H_DQ<33>")
	)
	(segment
		(start 106.102912 -53.226716)
		(end 106.161078 -53.121814)
		(width 0.0889)
		(layer "In4.Cu")
		(net "M_H_DQ<33>")
	)
	(segment
		(start 105.571036 -54.513734)
		(end 105.714292 -54.513734)
		(width 0.0889)
		(layer "In4.Cu")
		(net "M_H_DQ<33>")
	)
	(segment
		(start 116.87683 -8.1026)
		(end 116.399564 -7.625334)
		(width 0.14224)
		(layer "In4.Cu")
		(net "M_H_DQ<33>")
	)
	(segment
		(start 117.559582 -25.367742)
		(end 117.559582 -16.368268)
		(width 0.14224)
		(layer "In4.Cu")
		(net "M_H_DQ<33>")
	)
	(segment
		(start 105.22077 -54.722776)
		(end 105.240074 -54.688994)
		(width 0.0889)
		(layer "In4.Cu")
		(net "M_H_DQ<33>")
	)
	(segment
		(start 117.44579 -12.304014)
		(end 117.44579 -8.970264)
		(width 0.14224)
		(layer "In4.Cu")
		(net "M_H_DQ<33>")
	)
	(segment
		(start 111.76508 -31.162244)
		(end 117.559582 -25.367742)
		(width 0.14224)
		(layer "In4.Cu")
		(net "M_H_DQ<33>")
	)
	(segment
		(start 107.92206 -45.339254)
		(end 107.92206 -37.177218)
		(width 0.14224)
		(layer "In4.Cu")
		(net "M_H_DQ<33>")
	)
	(segment
		(start 107.646724 -45.61459)
		(end 107.92206 -45.339254)
		(width 0.0889)
		(layer "In4.Cu")
		(net "M_H_DQ<33>")
	)
	(segment
		(start 107.204256 -48.656494)
		(end 107.204256 -46.371002)
		(width 0.0889)
		(layer "In4.Cu")
		(net "M_H_DQ<33>")
	)
	(segment
		(start 113.25352 -30.967426)
		(end 112.982502 -30.967426)
		(width 0.14224)
		(layer "In4.Cu")
		(net "M_H_DQ<33>")
	)
	(segment
		(start 116.924582 -15.733268)
		(end 116.924582 -13.853668)
		(width 0.14224)
		(layer "In4.Cu")
		(net "M_H_DQ<33>")
	)
	(segment
		(start 106.109008 -53.640482)
		(end 106.102912 -53.62956)
		(width 0.0889)
		(layer "In4.Cu")
		(net "M_H_DQ<33>")
	)
	(segment
		(start 117.44579 -8.970264)
		(end 117.602254 -8.8138)
		(width 0.14224)
		(layer "In4.Cu")
		(net "M_H_DQ<33>")
	)
	(segment
		(start 111.76508 -31.363412)
		(end 111.76508 -31.162244)
		(width 0.14224)
		(layer "In4.Cu")
		(net "M_H_DQ<33>")
	)
	(segment
		(start 107.646724 -45.928534)
		(end 107.646724 -45.61459)
		(width 0.0889)
		(layer "In4.Cu")
		(net "M_H_DQ<33>")
	)
	(segment
		(start 117.559582 -16.368268)
		(end 116.924582 -15.733268)
		(width 0.14224)
		(layer "In4.Cu")
		(net "M_H_DQ<33>")
	)
	(segment
		(start 116.545106 -13.474192)
		(end 116.545106 -13.204698)
		(width 0.14224)
		(layer "In4.Cu")
		(net "M_H_DQ<33>")
	)
	(segment
		(start 106.920284 -48.940974)
		(end 106.920792 -48.940466)
		(width 0.0889)
		(layer "In4.Cu")
		(net "M_H_DQ<33>")
	)
	(segment
		(start 116.924582 -13.853668)
		(end 116.545106 -13.474192)
		(width 0.14224)
		(layer "In4.Cu")
		(net "M_H_DQ<33>")
	)
	(segment
		(start 112.075214 -31.673546)
		(end 111.76508 -31.363412)
		(width 0.14224)
		(layer "In4.Cu")
		(net "M_H_DQ<33>")
	)
	(segment
		(start 106.161078 -53.121814)
		(end 106.161078 -51.006502)
		(width 0.0889)
		(layer "In4.Cu")
		(net "M_H_DQ<33>")
	)
	(segment
		(start 116.545106 -13.204698)
		(end 117.071648 -12.678156)
		(width 0.14224)
		(layer "In4.Cu")
		(net "M_H_DQ<33>")
	)
	(segment
		(start 105.571036 -54.913784)
		(end 105.571036 -55.251858)
		(width 0.0889)
		(layer "In4.Cu")
		(net "M_H_DQ<33>")
	)
	(segment
		(start 117.23243 -8.1026)
		(end 116.87683 -8.1026)
		(width 0.14224)
		(layer "In4.Cu")
		(net "M_H_DQ<33>")
	)
	(segment
		(start 117.602254 -8.472424)
		(end 117.23243 -8.1026)
		(width 0.14224)
		(layer "In4.Cu")
		(net "M_H_DQ<33>")
	)
	(segment
		(start 106.920284 -50.247296)
		(end 106.920284 -48.940974)
		(width 0.0889)
		(layer "In4.Cu")
		(net "M_H_DQ<33>")
	)
	(segment
		(start 105.239312 -55.137304)
		(end 105.225596 -55.113682)
		(width 0.0889)
		(layer "In4.Cu")
		(net "M_H_DQ<33>")
	)
	(segment
		(start 117.071648 -12.678156)
		(end 117.44579 -12.304014)
		(width 0.14224)
		(layer "In4.Cu")
		(net "M_H_DQ<33>")
	)
	(segment
		(start 116.399564 -7.625334)
		(end 116.399564 -7.086346)
		(width 0.14224)
		(layer "In4.Cu")
		(net "M_H_DQ<33>")
	)
	(segment
		(start 107.204256 -46.371002)
		(end 107.646724 -45.928534)
		(width 0.0889)
		(layer "In4.Cu")
		(net "M_H_DQ<33>")
	)
	(segment
		(start 117.602254 -8.8138)
		(end 117.602254 -8.472424)
		(width 0.14224)
		(layer "In4.Cu")
		(net "M_H_DQ<33>")
	)
	(segment
		(start 112.982502 -30.967426)
		(end 112.276382 -31.673546)
		(width 0.14224)
		(layer "In4.Cu")
		(net "M_H_DQ<33>")
	)
	(segment
		(start 106.920792 -48.939958)
		(end 107.204256 -48.656494)
		(width 0.0889)
		(layer "In4.Cu")
		(net "M_H_DQ<33>")
	)
	(segment
		(start 105.571036 -55.251858)
		(end 105.513378 -55.309516)
		(width 0.0889)
		(layer "In4.Cu")
		(net "M_H_DQ<33>")
	)
	(segment
		(start 113.55705 -31.270956)
		(end 113.25352 -30.967426)
		(width 0.14224)
		(layer "In4.Cu")
		(net "M_H_DQ<33>")
	)
	(segment
		(start 113.55705 -31.542228)
		(end 113.55705 -31.270956)
		(width 0.14224)
		(layer "In4.Cu")
		(net "M_H_DQ<33>")
	)
	(segment
		(start 107.92206 -37.177218)
		(end 113.55705 -31.542228)
		(width 0.14224)
		(layer "In4.Cu")
		(net "M_H_DQ<33>")
	)
	(segment
		(start 106.161078 -51.006502)
		(end 106.920284 -50.247296)
		(width 0.0889)
		(layer "In4.Cu")
		(net "M_H_DQ<33>")
	)
	(segment
		(start 106.920792 -48.940466)
		(end 106.920792 -48.939958)
		(width 0.0889)
		(layer "In4.Cu")
		(net "M_H_DQ<33>")
	)
	(arc
		(start 105.240074 -54.688994)
		(mid 105.383777 -54.56023)
		(end 105.571036 -54.513734)
		(width 0.0889)
		(layer "In4.Cu")
		(net "M_H_DQ<33>")
	)
	(arc
		(start 105.714292 -54.513734)
		(mid 105.786841 -54.491241)
		(end 105.856024 -54.459886)
		(width 0.0889)
		(layer "In4.Cu")
		(net "M_H_DQ<33>")
	)
	(arc
		(start 105.920032 -54.420516)
		(mid 106.161543 -54.066149)
		(end 106.109008 -53.640482)
		(width 0.0889)
		(layer "In4.Cu")
		(net "M_H_DQ<33>")
	)
	(arc
		(start 106.102912 -53.62956)
		(mid 106.050992 -53.428138)
		(end 106.102912 -53.226716)
		(width 0.0889)
		(layer "In4.Cu")
		(net "M_H_DQ<33>")
	)
	(arc
		(start 105.225596 -55.113682)
		(mid 105.172083 -54.918873)
		(end 105.22077 -54.722776)
		(width 0.0889)
		(layer "In4.Cu")
		(net "M_H_DQ<33>")
	)
	(arc
		(start 105.513378 -55.309516)
		(mid 105.358149 -55.252364)
		(end 105.239312 -55.137304)
		(width 0.0889)
		(layer "In4.Cu")
		(net "M_H_DQ<33>")
	)
	(arc
		(start 105.856024 -54.459886)
		(mid 105.888647 -54.441208)
		(end 105.920032 -54.420516)
		(width 0.0889)
		(layer "In4.Cu")
		(net "M_H_DQ<33>")
	)
	(segment
		(start 117.249448 -10.422382)
		(end 117.103144 -8.89)
		(width 0.1651)
		(layer "F.Cu")
		(net "M_H_DQ<32>")
	)
	(segment
		(start 117.103144 -8.89)
		(end 117.090952 -8.763)
		(width 0.1651)
		(layer "F.Cu")
		(net "M_H_DQ<32>")
	)
	(segment
		(start 117.090952 -8.763)
		(end 117.071648 -8.5598)
		(width 0.1651)
		(layer "F.Cu")
		(net "M_H_DQ<32>")
	)
	(segment
		(start 106.193336 -55.904384)
		(end 105.571036 -55.904384)
		(width 0.1651)
		(layer "F.Cu")
		(net "M_H_DQ<32>")
	)
	(via
		(at 116.399564 -13.959078)
		(size 0.508)
		(drill 0.254)
		(layers "F.Cu" "B.Cu")
		(net "M_H_DQ<32>")
	)
	(via
		(at 117.071648 -8.5598)
		(size 0.508)
		(drill 0.254)
		(layers "F.Cu" "B.Cu")
		(net "M_H_DQ<32>")
	)
	(via
		(at 105.571036 -55.904384)
		(size 0.508)
		(drill 0.254)
		(layers "F.Cu" "B.Cu")
		(net "M_H_DQ<32>")
	)
	(segment
		(start 116.399564 -15.222982)
		(end 116.399564 -13.959078)
		(width 0.1651)
		(layer "B.Cu")
		(net "M_H_DQ<32>")
	)
	(segment
		(start 116.924582 -21.683472)
		(end 116.924582 -18.628614)
		(width 0.14224)
		(layer "In4.Cu")
		(net "M_H_DQ<32>")
	)
	(segment
		(start 109.261148 -32.620966)
		(end 116.856764 -25.02535)
		(width 0.14224)
		(layer "In4.Cu")
		(net "M_H_DQ<32>")
	)
	(segment
		(start 106.730038 -50.167794)
		(end 106.730038 -48.86198)
		(width 0.0889)
		(layer "In4.Cu")
		(net "M_H_DQ<32>")
	)
	(segment
		(start 105.054146 -54.62905)
		(end 105.060496 -54.618382)
		(width 0.0889)
		(layer "In4.Cu")
		(net "M_H_DQ<32>")
	)
	(segment
		(start 116.581682 -23.095712)
		(end 116.581682 -22.026372)
		(width 0.14224)
		(layer "In4.Cu")
		(net "M_H_DQ<32>")
	)
	(segment
		(start 116.85143 -12.192)
		(end 116.85143 -11.692128)
		(width 0.14224)
		(layer "In4.Cu")
		(net "M_H_DQ<32>")
	)
	(segment
		(start 106.730038 -48.86198)
		(end 107.014264 -48.577754)
		(width 0.0889)
		(layer "In4.Cu")
		(net "M_H_DQ<32>")
	)
	(segment
		(start 107.28706 -36.914074)
		(end 111.203994 -32.99714)
		(width 0.14224)
		(layer "In4.Cu")
		(net "M_H_DQ<32>")
	)
	(segment
		(start 116.85143 -8.780018)
		(end 117.071648 -8.5598)
		(width 0.14224)
		(layer "In4.Cu")
		(net "M_H_DQ<32>")
	)
	(segment
		(start 116.11483 -13.674344)
		(end 116.11483 -12.9286)
		(width 0.14224)
		(layer "In4.Cu")
		(net "M_H_DQ<32>")
	)
	(segment
		(start 107.014264 -48.577754)
		(end 107.014264 -46.292262)
		(width 0.0889)
		(layer "In4.Cu")
		(net "M_H_DQ<32>")
	)
	(segment
		(start 116.075968 -15.717266)
		(end 116.075968 -14.282674)
		(width 0.14224)
		(layer "In4.Cu")
		(net "M_H_DQ<32>")
	)
	(segment
		(start 105.971086 -50.926746)
		(end 106.730038 -50.167794)
		(width 0.0889)
		(layer "In4.Cu")
		(net "M_H_DQ<32>")
	)
	(segment
		(start 116.581682 -18.285714)
		(end 116.581682 -17.121886)
		(width 0.14224)
		(layer "In4.Cu")
		(net "M_H_DQ<32>")
	)
	(segment
		(start 116.779548 -10.6807)
		(end 116.779548 -10.4521)
		(width 0.14224)
		(layer "In4.Cu")
		(net "M_H_DQ<32>")
	)
	(segment
		(start 105.571036 -55.904384)
		(end 105.571036 -55.56631)
		(width 0.0889)
		(layer "In4.Cu")
		(net "M_H_DQ<32>")
	)
	(segment
		(start 116.85143 -11.692128)
		(end 116.462048 -11.302746)
		(width 0.14224)
		(layer "In4.Cu")
		(net "M_H_DQ<32>")
	)
	(segment
		(start 111.203994 -32.99714)
		(end 111.203994 -32.795972)
		(width 0.14224)
		(layer "In4.Cu")
		(net "M_H_DQ<32>")
	)
	(segment
		(start 116.924582 -18.628614)
		(end 116.581682 -18.285714)
		(width 0.14224)
		(layer "In4.Cu")
		(net "M_H_DQ<32>")
	)
	(segment
		(start 116.462048 -10.9982)
		(end 116.779548 -10.6807)
		(width 0.14224)
		(layer "In4.Cu")
		(net "M_H_DQ<32>")
	)
	(segment
		(start 105.940606 -53.730398)
		(end 105.929684 -53.71084)
		(width 0.0889)
		(layer "In4.Cu")
		(net "M_H_DQ<32>")
	)
	(segment
		(start 109.845856 -33.205674)
		(end 109.644688 -33.205674)
		(width 0.14224)
		(layer "In4.Cu")
		(net "M_H_DQ<32>")
	)
	(segment
		(start 116.581682 -22.026372)
		(end 116.924582 -21.683472)
		(width 0.14224)
		(layer "In4.Cu")
		(net "M_H_DQ<32>")
	)
	(segment
		(start 105.971086 -53.07076)
		(end 105.971086 -50.926746)
		(width 0.0889)
		(layer "In4.Cu")
		(net "M_H_DQ<32>")
	)
	(segment
		(start 107.456732 -45.508164)
		(end 107.28706 -45.338492)
		(width 0.0889)
		(layer "In4.Cu")
		(net "M_H_DQ<32>")
	)
	(segment
		(start 105.571036 -54.323234)
		(end 105.687876 -54.323234)
		(width 0.0889)
		(layer "In4.Cu")
		(net "M_H_DQ<32>")
	)
	(segment
		(start 116.462048 -11.302746)
		(end 116.462048 -10.9982)
		(width 0.14224)
		(layer "In4.Cu")
		(net "M_H_DQ<32>")
	)
	(segment
		(start 107.456732 -45.849794)
		(end 107.456732 -45.508164)
		(width 0.0889)
		(layer "In4.Cu")
		(net "M_H_DQ<32>")
	)
	(segment
		(start 116.856764 -23.370794)
		(end 116.581682 -23.095712)
		(width 0.14224)
		(layer "In4.Cu")
		(net "M_H_DQ<32>")
	)
	(segment
		(start 116.075968 -14.282674)
		(end 116.399564 -13.959078)
		(width 0.14224)
		(layer "In4.Cu")
		(net "M_H_DQ<32>")
	)
	(segment
		(start 105.060496 -54.618382)
		(end 105.075228 -54.593236)
		(width 0.0889)
		(layer "In4.Cu")
		(net "M_H_DQ<32>")
	)
	(segment
		(start 116.856764 -25.02535)
		(end 116.856764 -23.370794)
		(width 0.14224)
		(layer "In4.Cu")
		(net "M_H_DQ<32>")
	)
	(segment
		(start 116.779548 -10.4521)
		(end 116.436648 -10.1092)
		(width 0.14224)
		(layer "In4.Cu")
		(net "M_H_DQ<32>")
	)
	(segment
		(start 116.436648 -9.779254)
		(end 116.85143 -9.364472)
		(width 0.14224)
		(layer "In4.Cu")
		(net "M_H_DQ<32>")
	)
	(segment
		(start 116.581682 -17.121886)
		(end 116.873782 -16.829786)
		(width 0.14224)
		(layer "In4.Cu")
		(net "M_H_DQ<32>")
	)
	(segment
		(start 105.93578 -53.13426)
		(end 105.971086 -53.07076)
		(width 0.0889)
		(layer "In4.Cu")
		(net "M_H_DQ<32>")
	)
	(segment
		(start 110.83036 -32.422338)
		(end 110.629192 -32.422338)
		(width 0.14224)
		(layer "In4.Cu")
		(net "M_H_DQ<32>")
	)
	(segment
		(start 116.11483 -12.9286)
		(end 116.85143 -12.192)
		(width 0.14224)
		(layer "In4.Cu")
		(net "M_H_DQ<32>")
	)
	(segment
		(start 105.571036 -55.56631)
		(end 105.505504 -55.500778)
		(width 0.0889)
		(layer "In4.Cu")
		(net "M_H_DQ<32>")
	)
	(segment
		(start 111.203994 -32.795972)
		(end 110.83036 -32.422338)
		(width 0.14224)
		(layer "In4.Cu")
		(net "M_H_DQ<32>")
	)
	(segment
		(start 116.873782 -16.829786)
		(end 116.873782 -16.51508)
		(width 0.14224)
		(layer "In4.Cu")
		(net "M_H_DQ<32>")
	)
	(segment
		(start 110.629192 -32.422338)
		(end 109.845856 -33.205674)
		(width 0.14224)
		(layer "In4.Cu")
		(net "M_H_DQ<32>")
	)
	(segment
		(start 105.073704 -55.2323)
		(end 105.060496 -55.20944)
		(width 0.0889)
		(layer "In4.Cu")
		(net "M_H_DQ<32>")
	)
	(segment
		(start 109.644688 -33.205674)
		(end 109.261148 -32.822134)
		(width 0.14224)
		(layer "In4.Cu")
		(net "M_H_DQ<32>")
	)
	(segment
		(start 116.399564 -13.959078)
		(end 116.11483 -13.674344)
		(width 0.14224)
		(layer "In4.Cu")
		(net "M_H_DQ<32>")
	)
	(segment
		(start 109.261148 -32.822134)
		(end 109.261148 -32.620966)
		(width 0.14224)
		(layer "In4.Cu")
		(net "M_H_DQ<32>")
	)
	(segment
		(start 116.436648 -10.1092)
		(end 116.436648 -9.779254)
		(width 0.14224)
		(layer "In4.Cu")
		(net "M_H_DQ<32>")
	)
	(segment
		(start 107.014264 -46.292262)
		(end 107.456732 -45.849794)
		(width 0.0889)
		(layer "In4.Cu")
		(net "M_H_DQ<32>")
	)
	(segment
		(start 107.28706 -45.338492)
		(end 107.28706 -36.914074)
		(width 0.14224)
		(layer "In4.Cu")
		(net "M_H_DQ<32>")
	)
	(segment
		(start 116.873782 -16.51508)
		(end 116.075968 -15.717266)
		(width 0.14224)
		(layer "In4.Cu")
		(net "M_H_DQ<32>")
	)
	(segment
		(start 116.85143 -9.364472)
		(end 116.85143 -8.780018)
		(width 0.14224)
		(layer "In4.Cu")
		(net "M_H_DQ<32>")
	)
	(arc
		(start 105.505504 -55.500778)
		(mid 105.259214 -55.415405)
		(end 105.073704 -55.2323)
		(width 0.0889)
		(layer "In4.Cu")
		(net "M_H_DQ<32>")
	)
	(arc
		(start 105.687876 -54.323234)
		(mid 105.831449 -54.248571)
		(end 105.93578 -54.12486)
		(width 0.0889)
		(layer "In4.Cu")
		(net "M_H_DQ<32>")
	)
	(arc
		(start 105.93578 -54.12486)
		(mid 105.987792 -53.928241)
		(end 105.940606 -53.730398)
		(width 0.0889)
		(layer "In4.Cu")
		(net "M_H_DQ<32>")
	)
	(arc
		(start 105.929684 -53.71084)
		(mid 105.859961 -53.421773)
		(end 105.93578 -53.13426)
		(width 0.0889)
		(layer "In4.Cu")
		(net "M_H_DQ<32>")
	)
	(arc
		(start 105.075228 -54.593236)
		(mid 105.288764 -54.395132)
		(end 105.571036 -54.323234)
		(width 0.0889)
		(layer "In4.Cu")
		(net "M_H_DQ<32>")
	)
	(arc
		(start 105.060496 -55.20944)
		(mid 104.980976 -54.920068)
		(end 105.054146 -54.62905)
		(width 0.0889)
		(layer "In4.Cu")
		(net "M_H_DQ<32>")
	)
	(segment
		(start 65.399412 -5.822442)
		(end 65.399412 -7.086346)
		(width 0.1651)
		(layer "F.Cu")
		(net "M_H_DQ<31>")
	)
	(segment
		(start 66.249296 -27.250136)
		(end 65.783968 -27.715464)
		(width 0.1651)
		(layer "F.Cu")
		(net "M_H_DQ<31>")
	)
	(segment
		(start 65.823846 -35.687)
		(end 65.823846 -37.30244)
		(width 0.1651)
		(layer "F.Cu")
		(net "M_H_DQ<31>")
	)
	(segment
		(start 67.190366 -43.392344)
		(end 68.399914 -44.601892)
		(width 0.1651)
		(layer "F.Cu")
		(net "M_H_DQ<31>")
	)
	(segment
		(start 66.672206 -36.576)
		(end 67.025266 -36.576)
		(width 0.1651)
		(layer "F.Cu")
		(net "M_H_DQ<31>")
	)
	(segment
		(start 65.823846 -28.9814)
		(end 65.823846 -35.687)
		(width 0.1651)
		(layer "F.Cu")
		(net "M_H_DQ<31>")
	)
	(segment
		(start 67.190366 -36.7411)
		(end 67.190366 -43.392344)
		(width 0.1651)
		(layer "F.Cu")
		(net "M_H_DQ<31>")
	)
	(segment
		(start 65.783968 -28.230322)
		(end 65.961768 -28.408122)
		(width 0.1651)
		(layer "F.Cu")
		(net "M_H_DQ<31>")
	)
	(segment
		(start 80.174592 -49.404778)
		(end 80.174592 -49.455578)
		(width 0.1016)
		(layer "F.Cu")
		(net "M_H_DQ<31>")
	)
	(segment
		(start 65.961768 -28.843478)
		(end 65.823846 -28.9814)
		(width 0.1651)
		(layer "F.Cu")
		(net "M_H_DQ<31>")
	)
	(segment
		(start 66.507106 -37.30244)
		(end 66.507106 -36.7411)
		(width 0.1651)
		(layer "F.Cu")
		(net "M_H_DQ<31>")
	)
	(segment
		(start 68.399914 -44.601892)
		(end 68.59143 -44.793408)
		(width 0.1016)
		(layer "F.Cu")
		(net "M_H_DQ<31>")
	)
	(segment
		(start 68.59143 -45.271436)
		(end 69.290184 -45.97019)
		(width 0.1016)
		(layer "F.Cu")
		(net "M_H_DQ<31>")
	)
	(segment
		(start 68.59143 -44.793408)
		(end 68.59143 -45.271436)
		(width 0.1016)
		(layer "F.Cu")
		(net "M_H_DQ<31>")
	)
	(segment
		(start 65.999106 -37.4777)
		(end 66.331846 -37.4777)
		(width 0.1651)
		(layer "F.Cu")
		(net "M_H_DQ<31>")
	)
	(segment
		(start 80.174592 -52.211986)
		(end 79.768192 -52.618386)
		(width 0.0889)
		(layer "F.Cu")
		(net "M_H_DQ<31>")
	)
	(segment
		(start 80.174592 -49.455578)
		(end 80.174592 -52.211986)
		(width 0.0889)
		(layer "F.Cu")
		(net "M_H_DQ<31>")
	)
	(segment
		(start 72.752204 -45.97019)
		(end 73.552304 -46.77029)
		(width 0.1016)
		(layer "F.Cu")
		(net "M_H_DQ<31>")
	)
	(segment
		(start 65.783968 -27.715464)
		(end 65.783968 -28.230322)
		(width 0.1651)
		(layer "F.Cu")
		(net "M_H_DQ<31>")
	)
	(segment
		(start 69.290184 -45.97019)
		(end 72.752204 -45.97019)
		(width 0.1016)
		(layer "F.Cu")
		(net "M_H_DQ<31>")
	)
	(segment
		(start 73.552304 -46.77029)
		(end 77.540104 -46.77029)
		(width 0.1016)
		(layer "F.Cu")
		(net "M_H_DQ<31>")
	)
	(segment
		(start 65.823846 -37.30244)
		(end 65.999106 -37.4777)
		(width 0.1651)
		(layer "F.Cu")
		(net "M_H_DQ<31>")
	)
	(segment
		(start 77.540104 -46.77029)
		(end 80.174592 -49.404778)
		(width 0.1016)
		(layer "F.Cu")
		(net "M_H_DQ<31>")
	)
	(segment
		(start 66.331846 -37.4777)
		(end 66.507106 -37.30244)
		(width 0.1651)
		(layer "F.Cu")
		(net "M_H_DQ<31>")
	)
	(segment
		(start 65.961768 -28.408122)
		(end 65.961768 -28.843478)
		(width 0.1651)
		(layer "F.Cu")
		(net "M_H_DQ<31>")
	)
	(segment
		(start 66.507106 -36.7411)
		(end 66.672206 -36.576)
		(width 0.1651)
		(layer "F.Cu")
		(net "M_H_DQ<31>")
	)
	(segment
		(start 67.025266 -36.576)
		(end 67.190366 -36.7411)
		(width 0.1651)
		(layer "F.Cu")
		(net "M_H_DQ<31>")
	)
	(via
		(at 66.249296 -27.250136)
		(size 0.508)
		(drill 0.254)
		(layers "F.Cu" "B.Cu")
		(net "M_H_DQ<31>")
	)
	(via
		(at 66.249296 -12.678156)
		(size 0.508)
		(drill 0.254)
		(layers "F.Cu" "B.Cu")
		(net "M_H_DQ<31>")
	)
	(via
		(at 65.823846 -35.687)
		(size 0.508)
		(drill 0.254)
		(layers "F.Cu" "B.Cu")
		(net "M_H_DQ<31>")
	)
	(via
		(at 65.399412 -7.086346)
		(size 0.508)
		(drill 0.254)
		(layers "F.Cu" "B.Cu")
		(net "M_H_DQ<31>")
	)
	(segment
		(start 66.249296 -10.623042)
		(end 66.249296 -12.678156)
		(width 0.1651)
		(layer "B.Cu")
		(net "M_H_DQ<31>")
	)
	(segment
		(start 66.24955 -10.623042)
		(end 66.249296 -10.623042)
		(width 0.1651)
		(layer "B.Cu")
		(net "M_H_DQ<31>")
	)
	(segment
		(start 66.75755 -8.8646)
		(end 66.602102 -9.020048)
		(width 0.14224)
		(layer "In4.Cu")
		(net "M_H_DQ<31>")
	)
	(segment
		(start 66.30035 -8.0518)
		(end 66.75755 -8.509)
		(width 0.14224)
		(layer "In4.Cu")
		(net "M_H_DQ<31>")
	)
	(segment
		(start 66.602102 -12.32535)
		(end 66.249296 -12.678156)
		(width 0.14224)
		(layer "In4.Cu")
		(net "M_H_DQ<31>")
	)
	(segment
		(start 65.792096 -13.135356)
		(end 65.792096 -13.640054)
		(width 0.14224)
		(layer "In4.Cu")
		(net "M_H_DQ<31>")
	)
	(segment
		(start 66.602102 -9.020048)
		(end 66.602102 -12.32535)
		(width 0.14224)
		(layer "In4.Cu")
		(net "M_H_DQ<31>")
	)
	(segment
		(start 66.79057 -22.015196)
		(end 66.79057 -23.117048)
		(width 0.14224)
		(layer "In4.Cu")
		(net "M_H_DQ<31>")
	)
	(segment
		(start 66.61277 -26.886662)
		(end 66.249296 -27.250136)
		(width 0.14224)
		(layer "In4.Cu")
		(net "M_H_DQ<31>")
	)
	(segment
		(start 66.75755 -8.509)
		(end 66.75755 -8.8646)
		(width 0.14224)
		(layer "In4.Cu")
		(net "M_H_DQ<31>")
	)
	(segment
		(start 66.04635 -8.0518)
		(end 66.30035 -8.0518)
		(width 0.14224)
		(layer "In4.Cu")
		(net "M_H_DQ<31>")
	)
	(segment
		(start 66.76517 -17.004538)
		(end 66.76517 -18.424398)
		(width 0.14224)
		(layer "In4.Cu")
		(net "M_H_DQ<31>")
	)
	(segment
		(start 66.61277 -23.294848)
		(end 66.61277 -26.886662)
		(width 0.14224)
		(layer "In4.Cu")
		(net "M_H_DQ<31>")
	)
	(segment
		(start 66.249296 -12.678156)
		(end 65.792096 -13.135356)
		(width 0.14224)
		(layer "In4.Cu")
		(net "M_H_DQ<31>")
	)
	(segment
		(start 66.79057 -23.117048)
		(end 66.61277 -23.294848)
		(width 0.14224)
		(layer "In4.Cu")
		(net "M_H_DQ<31>")
	)
	(segment
		(start 66.76517 -18.424398)
		(end 66.615564 -18.574004)
		(width 0.14224)
		(layer "In4.Cu")
		(net "M_H_DQ<31>")
	)
	(segment
		(start 65.399412 -7.086346)
		(end 65.71615 -7.403084)
		(width 0.14224)
		(layer "In4.Cu")
		(net "M_H_DQ<31>")
	)
	(segment
		(start 66.615564 -18.574004)
		(end 66.615564 -21.84019)
		(width 0.14224)
		(layer "In4.Cu")
		(net "M_H_DQ<31>")
	)
	(segment
		(start 65.71615 -7.403084)
		(end 65.71615 -7.7216)
		(width 0.14224)
		(layer "In4.Cu")
		(net "M_H_DQ<31>")
	)
	(segment
		(start 66.615564 -21.84019)
		(end 66.79057 -22.015196)
		(width 0.14224)
		(layer "In4.Cu")
		(net "M_H_DQ<31>")
	)
	(segment
		(start 66.46037 -16.699738)
		(end 66.76517 -17.004538)
		(width 0.14224)
		(layer "In4.Cu")
		(net "M_H_DQ<31>")
	)
	(segment
		(start 66.46037 -14.308328)
		(end 66.46037 -16.699738)
		(width 0.14224)
		(layer "In4.Cu")
		(net "M_H_DQ<31>")
	)
	(segment
		(start 65.71615 -7.7216)
		(end 66.04635 -8.0518)
		(width 0.14224)
		(layer "In4.Cu")
		(net "M_H_DQ<31>")
	)
	(segment
		(start 65.792096 -13.640054)
		(end 66.46037 -14.308328)
		(width 0.14224)
		(layer "In4.Cu")
		(net "M_H_DQ<31>")
	)
	(segment
		(start 73.425812 -47.07509)
		(end 72.714612 -46.36389)
		(width 0.1016)
		(layer "F.Cu")
		(net "M_H_DQ<30>")
	)
	(segment
		(start 65.148968 -41.4909)
		(end 65.275968 -41.6179)
		(width 0.1651)
		(layer "F.Cu")
		(net "M_H_DQ<30>")
	)
	(segment
		(start 64.968628 -30.689804)
		(end 64.973708 -30.689804)
		(width 0.1651)
		(layer "F.Cu")
		(net "M_H_DQ<30>")
	)
	(segment
		(start 79.804768 -49.57699)
		(end 79.804768 -49.466246)
		(width 0.1016)
		(layer "F.Cu")
		(net "M_H_DQ<30>")
	)
	(segment
		(start 66.24955 -10.422382)
		(end 66.24955 -9.4488)
		(width 0.1651)
		(layer "F.Cu")
		(net "M_H_DQ<30>")
	)
	(segment
		(start 68.127626 -45.364654)
		(end 69.126862 -46.36389)
		(width 0.1016)
		(layer "F.Cu")
		(net "M_H_DQ<30>")
	)
	(segment
		(start 65.959228 -39.3954)
		(end 66.388488 -39.3954)
		(width 0.1651)
		(layer "F.Cu")
		(net "M_H_DQ<30>")
	)
	(segment
		(start 65.705228 -41.6179)
		(end 65.832228 -41.4909)
		(width 0.1651)
		(layer "F.Cu")
		(net "M_H_DQ<30>")
	)
	(segment
		(start 65.399412 -28.531058)
		(end 65.148968 -28.781502)
		(width 0.1651)
		(layer "F.Cu")
		(net "M_H_DQ<30>")
	)
	(segment
		(start 72.714612 -46.36389)
		(end 69.126862 -46.36389)
		(width 0.1016)
		(layer "F.Cu")
		(net "M_H_DQ<30>")
	)
	(segment
		(start 64.793368 -31.548324)
		(end 64.793368 -31.881064)
		(width 0.1651)
		(layer "F.Cu")
		(net "M_H_DQ<30>")
	)
	(segment
		(start 66.24955 -8.9662)
		(end 66.24955 -8.661654)
		(width 0.1651)
		(layer "F.Cu")
		(net "M_H_DQ<30>")
	)
	(segment
		(start 64.793368 -30.181804)
		(end 64.793368 -30.514544)
		(width 0.1651)
		(layer "F.Cu")
		(net "M_H_DQ<30>")
	)
	(segment
		(start 65.832228 -39.5224)
		(end 65.959228 -39.3954)
		(width 0.1651)
		(layer "F.Cu")
		(net "M_H_DQ<30>")
	)
	(segment
		(start 64.793368 -31.881064)
		(end 64.968628 -32.056324)
		(width 0.1651)
		(layer "F.Cu")
		(net "M_H_DQ<30>")
	)
	(segment
		(start 64.968628 -31.373064)
		(end 64.793368 -31.548324)
		(width 0.1651)
		(layer "F.Cu")
		(net "M_H_DQ<30>")
	)
	(segment
		(start 64.973708 -30.006544)
		(end 64.968628 -30.006544)
		(width 0.1651)
		(layer "F.Cu")
		(net "M_H_DQ<30>")
	)
	(segment
		(start 65.832228 -41.4909)
		(end 65.832228 -39.5224)
		(width 0.1651)
		(layer "F.Cu")
		(net "M_H_DQ<30>")
	)
	(segment
		(start 66.24955 -8.661654)
		(end 66.249296 -8.6614)
		(width 0.1651)
		(layer "F.Cu")
		(net "M_H_DQ<30>")
	)
	(segment
		(start 79.768192 -50.63744)
		(end 79.768192 -50.277776)
		(width 0.0889)
		(layer "F.Cu")
		(net "M_H_DQ<30>")
	)
	(segment
		(start 67.941698 -45.060108)
		(end 68.127626 -45.246036)
		(width 0.1016)
		(layer "F.Cu")
		(net "M_H_DQ<30>")
	)
	(segment
		(start 65.275968 -41.6179)
		(end 65.705228 -41.6179)
		(width 0.1651)
		(layer "F.Cu")
		(net "M_H_DQ<30>")
	)
	(segment
		(start 65.148968 -30.865064)
		(end 65.148968 -31.197804)
		(width 0.1651)
		(layer "F.Cu")
		(net "M_H_DQ<30>")
	)
	(segment
		(start 65.148968 -32.231584)
		(end 65.148968 -33.02)
		(width 0.1651)
		(layer "F.Cu")
		(net "M_H_DQ<30>")
	)
	(segment
		(start 79.804768 -50.2412)
		(end 79.804768 -49.57699)
		(width 0.0889)
		(layer "F.Cu")
		(net "M_H_DQ<30>")
	)
	(segment
		(start 66.515488 -39.5224)
		(end 66.515488 -43.633898)
		(width 0.1651)
		(layer "F.Cu")
		(net "M_H_DQ<30>")
	)
	(segment
		(start 65.148968 -33.02)
		(end 65.148968 -41.4909)
		(width 0.1651)
		(layer "F.Cu")
		(net "M_H_DQ<30>")
	)
	(segment
		(start 79.804768 -49.466246)
		(end 77.413612 -47.07509)
		(width 0.1016)
		(layer "F.Cu")
		(net "M_H_DQ<30>")
	)
	(segment
		(start 66.38163 -9.09828)
		(end 66.24955 -8.9662)
		(width 0.1651)
		(layer "F.Cu")
		(net "M_H_DQ<30>")
	)
	(segment
		(start 66.38163 -9.31672)
		(end 66.38163 -9.09828)
		(width 0.1651)
		(layer "F.Cu")
		(net "M_H_DQ<30>")
	)
	(segment
		(start 64.973708 -30.689804)
		(end 65.148968 -30.865064)
		(width 0.1651)
		(layer "F.Cu")
		(net "M_H_DQ<30>")
	)
	(segment
		(start 64.968628 -30.006544)
		(end 64.793368 -30.181804)
		(width 0.1651)
		(layer "F.Cu")
		(net "M_H_DQ<30>")
	)
	(segment
		(start 64.793368 -30.514544)
		(end 64.968628 -30.689804)
		(width 0.1651)
		(layer "F.Cu")
		(net "M_H_DQ<30>")
	)
	(segment
		(start 66.24955 -9.4488)
		(end 66.38163 -9.31672)
		(width 0.1651)
		(layer "F.Cu")
		(net "M_H_DQ<30>")
	)
	(segment
		(start 65.148968 -28.781502)
		(end 65.148968 -29.831284)
		(width 0.1651)
		(layer "F.Cu")
		(net "M_H_DQ<30>")
	)
	(segment
		(start 65.148968 -29.831284)
		(end 64.973708 -30.006544)
		(width 0.1651)
		(layer "F.Cu")
		(net "M_H_DQ<30>")
	)
	(segment
		(start 79.768192 -50.277776)
		(end 79.804768 -50.2412)
		(width 0.0889)
		(layer "F.Cu")
		(net "M_H_DQ<30>")
	)
	(segment
		(start 64.973708 -31.373064)
		(end 64.968628 -31.373064)
		(width 0.1651)
		(layer "F.Cu")
		(net "M_H_DQ<30>")
	)
	(segment
		(start 64.968628 -32.056324)
		(end 64.973708 -32.056324)
		(width 0.1651)
		(layer "F.Cu")
		(net "M_H_DQ<30>")
	)
	(segment
		(start 77.413612 -47.07509)
		(end 73.425812 -47.07509)
		(width 0.1016)
		(layer "F.Cu")
		(net "M_H_DQ<30>")
	)
	(segment
		(start 64.973708 -32.056324)
		(end 65.148968 -32.231584)
		(width 0.1651)
		(layer "F.Cu")
		(net "M_H_DQ<30>")
	)
	(segment
		(start 66.388488 -39.3954)
		(end 66.515488 -39.5224)
		(width 0.1651)
		(layer "F.Cu")
		(net "M_H_DQ<30>")
	)
	(segment
		(start 65.148968 -31.197804)
		(end 64.973708 -31.373064)
		(width 0.1651)
		(layer "F.Cu")
		(net "M_H_DQ<30>")
	)
	(segment
		(start 68.127626 -45.246036)
		(end 68.127626 -45.364654)
		(width 0.1016)
		(layer "F.Cu")
		(net "M_H_DQ<30>")
	)
	(segment
		(start 66.515488 -43.633898)
		(end 67.941698 -45.060108)
		(width 0.1651)
		(layer "F.Cu")
		(net "M_H_DQ<30>")
	)
	(via
		(at 66.249296 -8.6614)
		(size 0.508)
		(drill 0.254)
		(layers "F.Cu" "B.Cu")
		(net "M_H_DQ<30>")
	)
	(via
		(at 65.148968 -33.02)
		(size 0.508)
		(drill 0.254)
		(layers "F.Cu" "B.Cu")
		(net "M_H_DQ<30>")
	)
	(via
		(at 65.399412 -28.531058)
		(size 0.508)
		(drill 0.254)
		(layers "F.Cu" "B.Cu")
		(net "M_H_DQ<30>")
	)
	(via
		(at 65.399412 -13.959078)
		(size 0.508)
		(drill 0.254)
		(layers "F.Cu" "B.Cu")
		(net "M_H_DQ<30>")
	)
	(segment
		(start 65.399412 -15.222982)
		(end 65.399412 -13.959078)
		(width 0.1651)
		(layer "B.Cu")
		(net "M_H_DQ<30>")
	)
	(segment
		(start 65.891918 -10.712704)
		(end 65.891918 -10.369296)
		(width 0.14224)
		(layer "In4.Cu")
		(net "M_H_DQ<30>")
	)
	(segment
		(start 65.510918 -9.988296)
		(end 65.510918 -9.677654)
		(width 0.14224)
		(layer "In4.Cu")
		(net "M_H_DQ<30>")
	)
	(segment
		(start 65.97777 -26.61285)
		(end 65.97777 -23.412196)
		(width 0.14224)
		(layer "In4.Cu")
		(net "M_H_DQ<30>")
	)
	(segment
		(start 65.74917 -28.1813)
		(end 65.74917 -26.84145)
		(width 0.14224)
		(layer "In4.Cu")
		(net "M_H_DQ<30>")
	)
	(segment
		(start 65.69837 -23.132796)
		(end 65.69837 -22.040596)
		(width 0.14224)
		(layer "In4.Cu")
		(net "M_H_DQ<30>")
	)
	(segment
		(start 65.69837 -22.040596)
		(end 65.904364 -21.834602)
		(width 0.14224)
		(layer "In4.Cu")
		(net "M_H_DQ<30>")
	)
	(segment
		(start 65.1637 -13.723366)
		(end 65.1637 -12.928854)
		(width 0.14224)
		(layer "In4.Cu")
		(net "M_H_DQ<30>")
	)
	(segment
		(start 65.510918 -11.378946)
		(end 65.510918 -11.093704)
		(width 0.14224)
		(layer "In4.Cu")
		(net "M_H_DQ<30>")
	)
	(segment
		(start 65.399412 -13.959078)
		(end 65.1637 -13.723366)
		(width 0.14224)
		(layer "In4.Cu")
		(net "M_H_DQ<30>")
	)
	(segment
		(start 65.97777 -23.412196)
		(end 65.69837 -23.132796)
		(width 0.14224)
		(layer "In4.Cu")
		(net "M_H_DQ<30>")
	)
	(segment
		(start 65.936368 -11.804396)
		(end 65.510918 -11.378946)
		(width 0.14224)
		(layer "In4.Cu")
		(net "M_H_DQ<30>")
	)
	(segment
		(start 65.399412 -28.531058)
		(end 65.74917 -28.1813)
		(width 0.14224)
		(layer "In4.Cu")
		(net "M_H_DQ<30>")
	)
	(segment
		(start 65.904364 -21.834602)
		(end 65.904364 -18.586196)
		(width 0.14224)
		(layer "In4.Cu")
		(net "M_H_DQ<30>")
	)
	(segment
		(start 65.69837 -17.036034)
		(end 65.90157 -16.832834)
		(width 0.14224)
		(layer "In4.Cu")
		(net "M_H_DQ<30>")
	)
	(segment
		(start 65.69837 -18.380202)
		(end 65.69837 -17.036034)
		(width 0.14224)
		(layer "In4.Cu")
		(net "M_H_DQ<30>")
	)
	(segment
		(start 65.8749 -9.313672)
		(end 65.8749 -9.035796)
		(width 0.14224)
		(layer "In4.Cu")
		(net "M_H_DQ<30>")
	)
	(segment
		(start 65.1637 -12.928854)
		(end 65.936368 -12.156186)
		(width 0.14224)
		(layer "In4.Cu")
		(net "M_H_DQ<30>")
	)
	(segment
		(start 65.904364 -18.586196)
		(end 65.69837 -18.380202)
		(width 0.14224)
		(layer "In4.Cu")
		(net "M_H_DQ<30>")
	)
	(segment
		(start 65.90157 -14.461236)
		(end 65.399412 -13.959078)
		(width 0.14224)
		(layer "In4.Cu")
		(net "M_H_DQ<30>")
	)
	(segment
		(start 65.936368 -12.156186)
		(end 65.936368 -11.804396)
		(width 0.14224)
		(layer "In4.Cu")
		(net "M_H_DQ<30>")
	)
	(segment
		(start 65.90157 -16.832834)
		(end 65.90157 -14.461236)
		(width 0.14224)
		(layer "In4.Cu")
		(net "M_H_DQ<30>")
	)
	(segment
		(start 65.510918 -11.093704)
		(end 65.891918 -10.712704)
		(width 0.14224)
		(layer "In4.Cu")
		(net "M_H_DQ<30>")
	)
	(segment
		(start 65.891918 -10.369296)
		(end 65.510918 -9.988296)
		(width 0.14224)
		(layer "In4.Cu")
		(net "M_H_DQ<30>")
	)
	(segment
		(start 65.8749 -9.035796)
		(end 66.249296 -8.6614)
		(width 0.14224)
		(layer "In4.Cu")
		(net "M_H_DQ<30>")
	)
	(segment
		(start 65.510918 -9.677654)
		(end 65.8749 -9.313672)
		(width 0.14224)
		(layer "In4.Cu")
		(net "M_H_DQ<30>")
	)
	(segment
		(start 65.74917 -26.84145)
		(end 65.97777 -26.61285)
		(width 0.14224)
		(layer "In4.Cu")
		(net "M_H_DQ<30>")
	)
	(segment
		(start 39.899336 -9.425432)
		(end 40.030908 -9.29386)
		(width 0.1651)
		(layer "F.Cu")
		(net "M_H_DQ<2>")
	)
	(segment
		(start 40.030908 -9.07034)
		(end 39.899336 -8.938768)
		(width 0.1651)
		(layer "F.Cu")
		(net "M_H_DQ<2>")
	)
	(segment
		(start 39.899336 -8.938768)
		(end 39.899336 -8.6614)
		(width 0.1651)
		(layer "F.Cu")
		(net "M_H_DQ<2>")
	)
	(segment
		(start 39.899336 -10.422382)
		(end 39.899336 -9.425432)
		(width 0.1651)
		(layer "F.Cu")
		(net "M_H_DQ<2>")
	)
	(segment
		(start 71.183246 -65.49644)
		(end 70.611746 -65.49644)
		(width 0.0889)
		(layer "F.Cu")
		(net "M_H_DQ<2>")
	)
	(segment
		(start 40.030908 -9.29386)
		(end 40.030908 -9.07034)
		(width 0.1651)
		(layer "F.Cu")
		(net "M_H_DQ<2>")
	)
	(via
		(at 70.611746 -65.49644)
		(size 0.508)
		(drill 0.254)
		(layers "F.Cu" "B.Cu")
		(net "M_H_DQ<2>")
	)
	(via
		(at 39.899336 -8.6614)
		(size 0.508)
		(drill 0.254)
		(layers "F.Cu" "B.Cu")
		(net "M_H_DQ<2>")
	)
	(via
		(at 39.049452 -13.959078)
		(size 0.508)
		(drill 0.254)
		(layers "F.Cu" "B.Cu")
		(net "M_H_DQ<2>")
	)
	(segment
		(start 39.049452 -15.222982)
		(end 39.049452 -13.959078)
		(width 0.1651)
		(layer "B.Cu")
		(net "M_H_DQ<2>")
	)
	(segment
		(start 39.967408 -34.038794)
		(end 39.812468 -34.193734)
		(width 0.14224)
		(layer "In4.Cu")
		(net "M_H_DQ<2>")
	)
	(segment
		(start 39.54272 -21.797772)
		(end 39.39032 -21.950172)
		(width 0.14224)
		(layer "In4.Cu")
		(net "M_H_DQ<2>")
	)
	(segment
		(start 54.801008 -50.77714)
		(end 55.050944 -51.027076)
		(width 0.14224)
		(layer "In4.Cu")
		(net "M_H_DQ<2>")
	)
	(segment
		(start 55.519828 -51.714908)
		(end 55.738776 -51.714908)
		(width 0.14224)
		(layer "In4.Cu")
		(net "M_H_DQ<2>")
	)
	(segment
		(start 39.967408 -34.701734)
		(end 40.940228 -34.701734)
		(width 0.14224)
		(layer "In4.Cu")
		(net "M_H_DQ<2>")
	)
	(segment
		(start 52.23764 -48.213772)
		(end 52.23764 -48.43272)
		(width 0.14224)
		(layer "In4.Cu")
		(net "M_H_DQ<2>")
	)
	(segment
		(start 55.738776 -51.714908)
		(end 55.988712 -51.964844)
		(width 0.14224)
		(layer "In4.Cu")
		(net "M_H_DQ<2>")
	)
	(segment
		(start 65.412112 -62.239906)
		(end 65.620392 -62.448186)
		(width 0.0889)
		(layer "In4.Cu")
		(net "M_H_DQ<2>")
	)
	(segment
		(start 52.925472 -48.901604)
		(end 53.175408 -49.15154)
		(width 0.14224)
		(layer "In4.Cu")
		(net "M_H_DQ<2>")
	)
	(segment
		(start 39.39032 -21.950172)
		(end 39.39032 -23.143972)
		(width 0.14224)
		(layer "In4.Cu")
		(net "M_H_DQ<2>")
	)
	(segment
		(start 39.049452 -14.116558)
		(end 39.61892 -14.686026)
		(width 0.14224)
		(layer "In4.Cu")
		(net "M_H_DQ<2>")
	)
	(segment
		(start 39.61892 -14.686026)
		(end 39.61892 -16.764762)
		(width 0.14224)
		(layer "In4.Cu")
		(net "M_H_DQ<2>")
	)
	(segment
		(start 55.988712 -52.183792)
		(end 55.41391 -52.758594)
		(width 0.14224)
		(layer "In4.Cu")
		(net "M_H_DQ<2>")
	)
	(segment
		(start 39.461186 -10.362946)
		(end 39.461186 -10.64895)
		(width 0.14224)
		(layer "In4.Cu")
		(net "M_H_DQ<2>")
	)
	(segment
		(start 39.507668 -28.0289)
		(end 39.507668 -33.1089)
		(width 0.14224)
		(layer "In4.Cu")
		(net "M_H_DQ<2>")
	)
	(segment
		(start 54.726078 -52.28971)
		(end 54.945026 -52.28971)
		(width 0.14224)
		(layer "In4.Cu")
		(net "M_H_DQ<2>")
	)
	(segment
		(start 52.706524 -48.901604)
		(end 52.925472 -48.901604)
		(width 0.14224)
		(layer "In4.Cu")
		(net "M_H_DQ<2>")
	)
	(segment
		(start 54.113176 -50.089308)
		(end 54.113176 -50.308256)
		(width 0.14224)
		(layer "In4.Cu")
		(net "M_H_DQ<2>")
	)
	(segment
		(start 52.131722 -49.476406)
		(end 52.706524 -48.901604)
		(width 0.14224)
		(layer "In4.Cu")
		(net "M_H_DQ<2>")
	)
	(segment
		(start 53.86324 -49.839372)
		(end 54.113176 -50.089308)
		(width 0.14224)
		(layer "In4.Cu")
		(net "M_H_DQ<2>")
	)
	(segment
		(start 39.049452 -13.959078)
		(end 39.049452 -14.116558)
		(width 0.14224)
		(layer "In4.Cu")
		(net "M_H_DQ<2>")
	)
	(segment
		(start 67.832986 -64.600836)
		(end 68.047362 -64.600836)
		(width 0.0889)
		(layer "In4.Cu")
		(net "M_H_DQ<2>")
	)
	(segment
		(start 39.812468 -34.546794)
		(end 39.967408 -34.701734)
		(width 0.14224)
		(layer "In4.Cu")
		(net "M_H_DQ<2>")
	)
	(segment
		(start 39.156386 -9.709404)
		(end 39.156386 -10.058146)
		(width 0.14224)
		(layer "In4.Cu")
		(net "M_H_DQ<2>")
	)
	(segment
		(start 53.538374 -51.102006)
		(end 53.78831 -51.351942)
		(width 0.14224)
		(layer "In4.Cu")
		(net "M_H_DQ<2>")
	)
	(segment
		(start 55.988712 -51.964844)
		(end 55.988712 -52.183792)
		(width 0.14224)
		(layer "In4.Cu")
		(net "M_H_DQ<2>")
	)
	(segment
		(start 53.538374 -50.883058)
		(end 53.538374 -51.102006)
		(width 0.14224)
		(layer "In4.Cu")
		(net "M_H_DQ<2>")
	)
	(segment
		(start 39.812468 -34.193734)
		(end 39.812468 -34.546794)
		(width 0.14224)
		(layer "In4.Cu")
		(net "M_H_DQ<2>")
	)
	(segment
		(start 39.088568 -27.6098)
		(end 39.507668 -28.0289)
		(width 0.14224)
		(layer "In4.Cu")
		(net "M_H_DQ<2>")
	)
	(segment
		(start 55.050944 -51.246024)
		(end 54.476142 -51.820826)
		(width 0.14224)
		(layer "In4.Cu")
		(net "M_H_DQ<2>")
	)
	(segment
		(start 41.095168 -33.883854)
		(end 40.940228 -34.038794)
		(width 0.14224)
		(layer "In4.Cu")
		(net "M_H_DQ<2>")
	)
	(segment
		(start 68.876926 -65.09639)
		(end 68.909692 -65.09639)
		(width 0.0889)
		(layer "In4.Cu")
		(net "M_H_DQ<2>")
	)
	(segment
		(start 40.891968 -33.2359)
		(end 41.095168 -33.4391)
		(width 0.14224)
		(layer "In4.Cu")
		(net "M_H_DQ<2>")
	)
	(segment
		(start 39.501318 -9.059418)
		(end 39.501318 -9.364472)
		(width 0.14224)
		(layer "In4.Cu")
		(net "M_H_DQ<2>")
	)
	(segment
		(start 53.175408 -49.15154)
		(end 53.175408 -49.370488)
		(width 0.14224)
		(layer "In4.Cu")
		(net "M_H_DQ<2>")
	)
	(segment
		(start 39.156386 -10.95375)
		(end 39.156386 -11.3538)
		(width 0.14224)
		(layer "In4.Cu")
		(net "M_H_DQ<2>")
	)
	(segment
		(start 53.644292 -49.839372)
		(end 53.86324 -49.839372)
		(width 0.14224)
		(layer "In4.Cu")
		(net "M_H_DQ<2>")
	)
	(segment
		(start 69.921628 -65.591436)
		(end 70.598538 -65.513204)
		(width 0.0889)
		(layer "In4.Cu")
		(net "M_H_DQ<2>")
	)
	(segment
		(start 41.095168 -33.4391)
		(end 41.095168 -33.883854)
		(width 0.14224)
		(layer "In4.Cu")
		(net "M_H_DQ<2>")
	)
	(segment
		(start 54.476142 -51.820826)
		(end 54.476142 -52.039774)
		(width 0.14224)
		(layer "In4.Cu")
		(net "M_H_DQ<2>")
	)
	(segment
		(start 40.940228 -34.701734)
		(end 41.095168 -34.856674)
		(width 0.14224)
		(layer "In4.Cu")
		(net "M_H_DQ<2>")
	)
	(segment
		(start 54.007258 -51.351942)
		(end 54.58206 -50.77714)
		(width 0.14224)
		(layer "In4.Cu")
		(net "M_H_DQ<2>")
	)
	(segment
		(start 54.58206 -50.77714)
		(end 54.801008 -50.77714)
		(width 0.14224)
		(layer "In4.Cu")
		(net "M_H_DQ<2>")
	)
	(segment
		(start 41.095168 -37.0713)
		(end 52.23764 -48.213772)
		(width 0.14224)
		(layer "In4.Cu")
		(net "M_H_DQ<2>")
	)
	(segment
		(start 38.764718 -13.674344)
		(end 39.049452 -13.959078)
		(width 0.14224)
		(layer "In4.Cu")
		(net "M_H_DQ<2>")
	)
	(segment
		(start 70.598538 -65.513204)
		(end 70.611746 -65.49644)
		(width 0.0889)
		(layer "In4.Cu")
		(net "M_H_DQ<2>")
	)
	(segment
		(start 39.41572 -16.967962)
		(end 39.41572 -18.437098)
		(width 0.14224)
		(layer "In4.Cu")
		(net "M_H_DQ<2>")
	)
	(segment
		(start 53.175408 -49.370488)
		(end 52.600606 -49.94529)
		(width 0.14224)
		(layer "In4.Cu")
		(net "M_H_DQ<2>")
	)
	(segment
		(start 65.620392 -63.238888)
		(end 66.487294 -64.10579)
		(width 0.0889)
		(layer "In4.Cu")
		(net "M_H_DQ<2>")
	)
	(segment
		(start 52.850542 -50.414174)
		(end 53.06949 -50.414174)
		(width 0.14224)
		(layer "In4.Cu")
		(net "M_H_DQ<2>")
	)
	(segment
		(start 51.662838 -49.007522)
		(end 51.662838 -49.22647)
		(width 0.14224)
		(layer "In4.Cu")
		(net "M_H_DQ<2>")
	)
	(segment
		(start 55.050944 -51.027076)
		(end 55.050944 -51.246024)
		(width 0.14224)
		(layer "In4.Cu")
		(net "M_H_DQ<2>")
	)
	(segment
		(start 39.613586 -11.811)
		(end 39.613586 -12.079732)
		(width 0.14224)
		(layer "In4.Cu")
		(net "M_H_DQ<2>")
	)
	(segment
		(start 53.06949 -50.414174)
		(end 53.644292 -49.839372)
		(width 0.14224)
		(layer "In4.Cu")
		(net "M_H_DQ<2>")
	)
	(segment
		(start 52.23764 -48.43272)
		(end 51.662838 -49.007522)
		(width 0.14224)
		(layer "In4.Cu")
		(net "M_H_DQ<2>")
	)
	(segment
		(start 39.63162 -23.739602)
		(end 39.088568 -24.282654)
		(width 0.14224)
		(layer "In4.Cu")
		(net "M_H_DQ<2>")
	)
	(segment
		(start 56.457596 -52.652676)
		(end 56.676544 -52.652676)
		(width 0.14224)
		(layer "In4.Cu")
		(net "M_H_DQ<2>")
	)
	(segment
		(start 54.476142 -52.039774)
		(end 54.726078 -52.28971)
		(width 0.14224)
		(layer "In4.Cu")
		(net "M_H_DQ<2>")
	)
	(segment
		(start 66.487294 -64.10579)
		(end 67.268344 -64.10579)
		(width 0.0889)
		(layer "In4.Cu")
		(net "M_H_DQ<2>")
	)
	(segment
		(start 39.39032 -23.143972)
		(end 39.63162 -23.385272)
		(width 0.14224)
		(layer "In4.Cu")
		(net "M_H_DQ<2>")
	)
	(segment
		(start 51.662838 -49.22647)
		(end 51.912774 -49.476406)
		(width 0.14224)
		(layer "In4.Cu")
		(net "M_H_DQ<2>")
	)
	(segment
		(start 39.41572 -18.437098)
		(end 39.54272 -18.564098)
		(width 0.14224)
		(layer "In4.Cu")
		(net "M_H_DQ<2>")
	)
	(segment
		(start 55.41391 -52.758594)
		(end 55.41391 -52.977542)
		(width 0.14224)
		(layer "In4.Cu")
		(net "M_H_DQ<2>")
	)
	(segment
		(start 39.54272 -18.564098)
		(end 39.54272 -21.797772)
		(width 0.14224)
		(layer "In4.Cu")
		(net "M_H_DQ<2>")
	)
	(segment
		(start 52.600606 -50.164238)
		(end 52.850542 -50.414174)
		(width 0.14224)
		(layer "In4.Cu")
		(net "M_H_DQ<2>")
	)
	(segment
		(start 65.620392 -62.448186)
		(end 65.620392 -63.238888)
		(width 0.0889)
		(layer "In4.Cu")
		(net "M_H_DQ<2>")
	)
	(segment
		(start 40.940228 -34.038794)
		(end 39.967408 -34.038794)
		(width 0.14224)
		(layer "In4.Cu")
		(net "M_H_DQ<2>")
	)
	(segment
		(start 39.156386 -11.3538)
		(end 39.613586 -11.811)
		(width 0.14224)
		(layer "In4.Cu")
		(net "M_H_DQ<2>")
	)
	(segment
		(start 51.912774 -49.476406)
		(end 52.131722 -49.476406)
		(width 0.14224)
		(layer "In4.Cu")
		(net "M_H_DQ<2>")
	)
	(segment
		(start 39.634668 -33.2359)
		(end 40.891968 -33.2359)
		(width 0.14224)
		(layer "In4.Cu")
		(net "M_H_DQ<2>")
	)
	(segment
		(start 39.088568 -24.282654)
		(end 39.088568 -27.6098)
		(width 0.14224)
		(layer "In4.Cu")
		(net "M_H_DQ<2>")
	)
	(segment
		(start 53.78831 -51.351942)
		(end 54.007258 -51.351942)
		(width 0.14224)
		(layer "In4.Cu")
		(net "M_H_DQ<2>")
	)
	(segment
		(start 39.501318 -9.364472)
		(end 39.156386 -9.709404)
		(width 0.14224)
		(layer "In4.Cu")
		(net "M_H_DQ<2>")
	)
	(segment
		(start 65.085214 -62.239906)
		(end 65.412112 -62.239906)
		(width 0.0889)
		(layer "In4.Cu")
		(net "M_H_DQ<2>")
	)
	(segment
		(start 39.461186 -10.64895)
		(end 39.156386 -10.95375)
		(width 0.14224)
		(layer "In4.Cu")
		(net "M_H_DQ<2>")
	)
	(segment
		(start 39.63162 -23.385272)
		(end 39.63162 -23.739602)
		(width 0.14224)
		(layer "In4.Cu")
		(net "M_H_DQ<2>")
	)
	(segment
		(start 54.113176 -50.308256)
		(end 53.538374 -50.883058)
		(width 0.14224)
		(layer "In4.Cu")
		(net "M_H_DQ<2>")
	)
	(segment
		(start 55.41391 -52.977542)
		(end 55.663846 -53.227478)
		(width 0.14224)
		(layer "In4.Cu")
		(net "M_H_DQ<2>")
	)
	(segment
		(start 60.653168 -56.6293)
		(end 60.653168 -57.80786)
		(width 0.14224)
		(layer "In4.Cu")
		(net "M_H_DQ<2>")
	)
	(segment
		(start 56.676544 -52.652676)
		(end 60.653168 -56.6293)
		(width 0.14224)
		(layer "In4.Cu")
		(net "M_H_DQ<2>")
	)
	(segment
		(start 55.882794 -53.227478)
		(end 56.457596 -52.652676)
		(width 0.14224)
		(layer "In4.Cu")
		(net "M_H_DQ<2>")
	)
	(segment
		(start 55.663846 -53.227478)
		(end 55.882794 -53.227478)
		(width 0.14224)
		(layer "In4.Cu")
		(net "M_H_DQ<2>")
	)
	(segment
		(start 41.095168 -34.856674)
		(end 41.095168 -37.0713)
		(width 0.14224)
		(layer "In4.Cu")
		(net "M_H_DQ<2>")
	)
	(segment
		(start 39.899336 -8.6614)
		(end 39.501318 -9.059418)
		(width 0.14224)
		(layer "In4.Cu")
		(net "M_H_DQ<2>")
	)
	(segment
		(start 69.731636 -65.591436)
		(end 69.921628 -65.591436)
		(width 0.0889)
		(layer "In4.Cu")
		(net "M_H_DQ<2>")
	)
	(segment
		(start 39.507668 -33.1089)
		(end 39.634668 -33.2359)
		(width 0.14224)
		(layer "In4.Cu")
		(net "M_H_DQ<2>")
	)
	(segment
		(start 38.764718 -12.9286)
		(end 38.764718 -13.674344)
		(width 0.14224)
		(layer "In4.Cu")
		(net "M_H_DQ<2>")
	)
	(segment
		(start 39.613586 -12.079732)
		(end 38.764718 -12.9286)
		(width 0.14224)
		(layer "In4.Cu")
		(net "M_H_DQ<2>")
	)
	(segment
		(start 39.156386 -10.058146)
		(end 39.461186 -10.362946)
		(width 0.14224)
		(layer "In4.Cu")
		(net "M_H_DQ<2>")
	)
	(segment
		(start 54.945026 -52.28971)
		(end 55.519828 -51.714908)
		(width 0.14224)
		(layer "In4.Cu")
		(net "M_H_DQ<2>")
	)
	(segment
		(start 60.653168 -57.80786)
		(end 65.085214 -62.239906)
		(width 0.14224)
		(layer "In4.Cu")
		(net "M_H_DQ<2>")
	)
	(segment
		(start 39.61892 -16.764762)
		(end 39.41572 -16.967962)
		(width 0.14224)
		(layer "In4.Cu")
		(net "M_H_DQ<2>")
	)
	(segment
		(start 52.600606 -49.94529)
		(end 52.600606 -50.164238)
		(width 0.14224)
		(layer "In4.Cu")
		(net "M_H_DQ<2>")
	)
	(arc
		(start 67.268344 -64.10579)
		(mid 67.393545 -64.185561)
		(end 67.484498 -64.302894)
		(width 0.0889)
		(layer "In4.Cu")
		(net "M_H_DQ<2>")
	)
	(arc
		(start 68.047362 -64.600836)
		(mid 68.241212 -64.657186)
		(end 68.382896 -64.800988)
		(width 0.0889)
		(layer "In4.Cu")
		(net "M_H_DQ<2>")
	)
	(arc
		(start 69.241416 -65.296288)
		(mid 69.44842 -65.507152)
		(end 69.731636 -65.591436)
		(width 0.0889)
		(layer "In4.Cu")
		(net "M_H_DQ<2>")
	)
	(arc
		(start 68.909692 -65.09639)
		(mid 69.101334 -65.153556)
		(end 69.241416 -65.296288)
		(width 0.0889)
		(layer "In4.Cu")
		(net "M_H_DQ<2>")
	)
	(arc
		(start 67.484498 -64.302894)
		(mid 67.630423 -64.484981)
		(end 67.832986 -64.600836)
		(width 0.0889)
		(layer "In4.Cu")
		(net "M_H_DQ<2>")
	)
	(arc
		(start 68.382896 -64.800988)
		(mid 68.591504 -65.01292)
		(end 68.876926 -65.09639)
		(width 0.0889)
		(layer "In4.Cu")
		(net "M_H_DQ<2>")
	)
	(segment
		(start 72.451468 -49.11979)
		(end 67.983608 -49.11979)
		(width 0.1016)
		(layer "F.Cu")
		(net "M_H_DQ<29>")
	)
	(segment
		(start 78.051406 -52.618386)
		(end 77.704696 -51.827938)
		(width 0.0889)
		(layer "F.Cu")
		(net "M_H_DQ<29>")
	)
	(segment
		(start 59.484768 -34.036)
		(end 59.484768 -35.0012)
		(width 0.1651)
		(layer "F.Cu")
		(net "M_H_DQ<29>")
	)
	(segment
		(start 59.913012 -28.317444)
		(end 59.913012 -29.048456)
		(width 0.1651)
		(layer "F.Cu")
		(net "M_H_DQ<29>")
	)
	(segment
		(start 59.484768 -29.4767)
		(end 59.484768 -34.036)
		(width 0.1651)
		(layer "F.Cu")
		(net "M_H_DQ<29>")
	)
	(segment
		(start 59.913012 -29.048456)
		(end 59.484768 -29.4767)
		(width 0.1651)
		(layer "F.Cu")
		(net "M_H_DQ<29>")
	)
	(segment
		(start 72.540368 -49.20869)
		(end 72.451468 -49.11979)
		(width 0.1016)
		(layer "F.Cu")
		(net "M_H_DQ<29>")
	)
	(segment
		(start 76.322682 -49.816004)
		(end 75.715368 -49.20869)
		(width 0.1016)
		(layer "F.Cu")
		(net "M_H_DQ<29>")
	)
	(segment
		(start 60.223146 -27.250136)
		(end 60.215018 -27.250136)
		(width 0.1651)
		(layer "F.Cu")
		(net "M_H_DQ<29>")
	)
	(segment
		(start 76.846176 -50.932588)
		(end 76.852526 -50.92192)
		(width 0.0889)
		(layer "F.Cu")
		(net "M_H_DQ<29>")
	)
	(segment
		(start 59.449462 -5.822442)
		(end 59.449462 -7.086346)
		(width 0.1651)
		(layer "F.Cu")
		(net "M_H_DQ<29>")
	)
	(segment
		(start 60.068968 -42.5958)
		(end 65.225168 -47.752)
		(width 0.1651)
		(layer "F.Cu")
		(net "M_H_DQ<29>")
	)
	(segment
		(start 59.738768 -27.726386)
		(end 59.738768 -28.1432)
		(width 0.1651)
		(layer "F.Cu")
		(net "M_H_DQ<29>")
	)
	(segment
		(start 60.215018 -27.250136)
		(end 59.738768 -27.726386)
		(width 0.1651)
		(layer "F.Cu")
		(net "M_H_DQ<29>")
	)
	(segment
		(start 59.484768 -35.0012)
		(end 60.068968 -35.5854)
		(width 0.1651)
		(layer "F.Cu")
		(net "M_H_DQ<29>")
	)
	(segment
		(start 75.715368 -49.20869)
		(end 72.540368 -49.20869)
		(width 0.1016)
		(layer "F.Cu")
		(net "M_H_DQ<29>")
	)
	(segment
		(start 76.84135 -50.941224)
		(end 76.846176 -50.932588)
		(width 0.0889)
		(layer "F.Cu")
		(net "M_H_DQ<29>")
	)
	(segment
		(start 59.738768 -28.1432)
		(end 59.913012 -28.317444)
		(width 0.1651)
		(layer "F.Cu")
		(net "M_H_DQ<29>")
	)
	(segment
		(start 60.068968 -35.5854)
		(end 60.068968 -42.5958)
		(width 0.1651)
		(layer "F.Cu")
		(net "M_H_DQ<29>")
	)
	(segment
		(start 65.403476 -47.930308)
		(end 65.403476 -47.940214)
		(width 0.1016)
		(layer "F.Cu")
		(net "M_H_DQ<29>")
	)
	(segment
		(start 76.79309 -50.162206)
		(end 76.559918 -49.929034)
		(width 0.0889)
		(layer "F.Cu")
		(net "M_H_DQ<29>")
	)
	(segment
		(start 67.983608 -49.11979)
		(end 66.804032 -47.940214)
		(width 0.1016)
		(layer "F.Cu")
		(net "M_H_DQ<29>")
	)
	(segment
		(start 76.559918 -49.929034)
		(end 76.322682 -49.816004)
		(width 0.0889)
		(layer "F.Cu")
		(net "M_H_DQ<29>")
	)
	(segment
		(start 77.210666 -51.532536)
		(end 77.1779 -51.532536)
		(width 0.0889)
		(layer "F.Cu")
		(net "M_H_DQ<29>")
	)
	(segment
		(start 66.804032 -47.940214)
		(end 65.403476 -47.940214)
		(width 0.1016)
		(layer "F.Cu")
		(net "M_H_DQ<29>")
	)
	(segment
		(start 65.225168 -47.752)
		(end 65.403476 -47.930308)
		(width 0.1016)
		(layer "F.Cu")
		(net "M_H_DQ<29>")
	)
	(via
		(at 60.223146 -12.678156)
		(size 0.508)
		(drill 0.254)
		(layers "F.Cu" "B.Cu")
		(net "M_H_DQ<29>")
	)
	(via
		(at 60.223146 -27.250136)
		(size 0.508)
		(drill 0.254)
		(layers "F.Cu" "B.Cu")
		(net "M_H_DQ<29>")
	)
	(via
		(at 59.449462 -7.086346)
		(size 0.508)
		(drill 0.254)
		(layers "F.Cu" "B.Cu")
		(net "M_H_DQ<29>")
	)
	(via
		(at 59.484768 -34.036)
		(size 0.508)
		(drill 0.254)
		(layers "F.Cu" "B.Cu")
		(net "M_H_DQ<29>")
	)
	(arc
		(start 76.846176 -50.342038)
		(mid 76.808944 -50.255276)
		(end 76.79309 -50.162206)
		(width 0.0889)
		(layer "F.Cu")
		(net "M_H_DQ<29>")
	)
	(arc
		(start 76.852526 -50.92192)
		(mid 76.925324 -50.631157)
		(end 76.846176 -50.342038)
		(width 0.0889)
		(layer "F.Cu")
		(net "M_H_DQ<29>")
	)
	(arc
		(start 77.704696 -51.827938)
		(mid 77.496088 -51.616006)
		(end 77.210666 -51.532536)
		(width 0.0889)
		(layer "F.Cu")
		(net "M_H_DQ<29>")
	)
	(arc
		(start 77.1779 -51.532536)
		(mid 76.844982 -51.330545)
		(end 76.84135 -50.941224)
		(width 0.0889)
		(layer "F.Cu")
		(net "M_H_DQ<29>")
	)
	(segment
		(start 60.299346 -10.623042)
		(end 60.299346 -12.601956)
		(width 0.1651)
		(layer "B.Cu")
		(net "M_H_DQ<29>")
	)
	(segment
		(start 60.299346 -12.601956)
		(end 60.223146 -12.678156)
		(width 0.1651)
		(layer "B.Cu")
		(net "M_H_DQ<29>")
	)
	(segment
		(start 59.706764 -13.066522)
		(end 60.09513 -12.678156)
		(width 0.14224)
		(layer "In4.Cu")
		(net "M_H_DQ<29>")
	)
	(segment
		(start 60.53455 -12.366752)
		(end 60.53455 -9.06145)
		(width 0.14224)
		(layer "In4.Cu")
		(net "M_H_DQ<29>")
	)
	(segment
		(start 60.61837 -18.531586)
		(end 60.69457 -18.455386)
		(width 0.14224)
		(layer "In4.Cu")
		(net "M_H_DQ<29>")
	)
	(segment
		(start 60.09513 -12.678156)
		(end 60.223146 -12.678156)
		(width 0.14224)
		(layer "In4.Cu")
		(net "M_H_DQ<29>")
	)
	(segment
		(start 60.71997 -21.964396)
		(end 60.61837 -21.862796)
		(width 0.14224)
		(layer "In4.Cu")
		(net "M_H_DQ<29>")
	)
	(segment
		(start 60.223146 -12.678156)
		(end 60.53455 -12.366752)
		(width 0.14224)
		(layer "In4.Cu")
		(net "M_H_DQ<29>")
	)
	(segment
		(start 60.331096 -8.0518)
		(end 60.0202 -8.0518)
		(width 0.14224)
		(layer "In4.Cu")
		(net "M_H_DQ<29>")
	)
	(segment
		(start 60.61837 -17.032986)
		(end 60.61837 -14.435582)
		(width 0.14224)
		(layer "In4.Cu")
		(net "M_H_DQ<29>")
	)
	(segment
		(start 60.7314 -8.8646)
		(end 60.7314 -8.452104)
		(width 0.14224)
		(layer "In4.Cu")
		(net "M_H_DQ<29>")
	)
	(segment
		(start 60.61837 -14.435582)
		(end 59.706764 -13.523976)
		(width 0.14224)
		(layer "In4.Cu")
		(net "M_H_DQ<29>")
	)
	(segment
		(start 60.69457 -18.455386)
		(end 60.69457 -17.109186)
		(width 0.14224)
		(layer "In4.Cu")
		(net "M_H_DQ<29>")
	)
	(segment
		(start 60.0202 -8.0518)
		(end 59.449462 -7.481062)
		(width 0.14224)
		(layer "In4.Cu")
		(net "M_H_DQ<29>")
	)
	(segment
		(start 59.449462 -7.481062)
		(end 59.449462 -7.086346)
		(width 0.14224)
		(layer "In4.Cu")
		(net "M_H_DQ<29>")
	)
	(segment
		(start 60.223146 -27.250136)
		(end 60.64377 -26.829512)
		(width 0.14224)
		(layer "In4.Cu")
		(net "M_H_DQ<29>")
	)
	(segment
		(start 59.706764 -13.523976)
		(end 59.706764 -13.066522)
		(width 0.14224)
		(layer "In4.Cu")
		(net "M_H_DQ<29>")
	)
	(segment
		(start 60.53455 -9.06145)
		(end 60.7314 -8.8646)
		(width 0.14224)
		(layer "In4.Cu")
		(net "M_H_DQ<29>")
	)
	(segment
		(start 60.64377 -26.829512)
		(end 60.64377 -23.234396)
		(width 0.14224)
		(layer "In4.Cu")
		(net "M_H_DQ<29>")
	)
	(segment
		(start 60.61837 -21.862796)
		(end 60.61837 -18.531586)
		(width 0.14224)
		(layer "In4.Cu")
		(net "M_H_DQ<29>")
	)
	(segment
		(start 60.7314 -8.452104)
		(end 60.331096 -8.0518)
		(width 0.14224)
		(layer "In4.Cu")
		(net "M_H_DQ<29>")
	)
	(segment
		(start 60.64377 -23.234396)
		(end 60.71997 -23.158196)
		(width 0.14224)
		(layer "In4.Cu")
		(net "M_H_DQ<29>")
	)
	(segment
		(start 60.71997 -23.158196)
		(end 60.71997 -21.964396)
		(width 0.14224)
		(layer "In4.Cu")
		(net "M_H_DQ<29>")
	)
	(segment
		(start 60.69457 -17.109186)
		(end 60.61837 -17.032986)
		(width 0.14224)
		(layer "In4.Cu")
		(net "M_H_DQ<29>")
	)
	(segment
		(start 60.095384 -44.423838)
		(end 60.3377 -44.666154)
		(width 0.1651)
		(layer "F.Cu")
		(net "M_H_DQ<28>")
	)
	(segment
		(start 64.893444 -48.346614)
		(end 66.63563 -48.346614)
		(width 0.127)
		(layer "F.Cu")
		(net "M_H_DQ<28>")
	)
	(segment
		(start 61.96076 -45.414438)
		(end 64.774064 -48.227742)
		(width 0.1651)
		(layer "F.Cu")
		(net "M_H_DQ<28>")
	)
	(segment
		(start 61.289692 -45.618146)
		(end 61.523372 -45.618146)
		(width 0.1651)
		(layer "F.Cu")
		(net "M_H_DQ<28>")
	)
	(segment
		(start 60.299346 -10.422382)
		(end 60.299346 -9.091168)
		(width 0.1651)
		(layer "F.Cu")
		(net "M_H_DQ<28>")
	)
	(segment
		(start 61.523372 -45.618146)
		(end 61.72708 -45.414438)
		(width 0.1651)
		(layer "F.Cu")
		(net "M_H_DQ<28>")
	)
	(segment
		(start 60.238894 -8.763)
		(end 60.201302 -8.5598)
		(width 0.1651)
		(layer "F.Cu")
		(net "M_H_DQ<28>")
	)
	(segment
		(start 76.10348 -50.045874)
		(end 75.583796 -49.52619)
		(width 0.127)
		(layer "F.Cu")
		(net "M_H_DQ<28>")
	)
	(segment
		(start 59.449462 -28.531058)
		(end 58.798968 -29.181552)
		(width 0.1651)
		(layer "F.Cu")
		(net "M_H_DQ<28>")
	)
	(segment
		(start 61.047376 -45.14215)
		(end 61.047376 -45.37583)
		(width 0.1651)
		(layer "F.Cu")
		(net "M_H_DQ<28>")
	)
	(segment
		(start 76.550774 -50.286158)
		(end 76.10348 -50.045874)
		(width 0.0889)
		(layer "F.Cu")
		(net "M_H_DQ<28>")
	)
	(segment
		(start 60.3377 -44.666154)
		(end 60.57138 -44.666154)
		(width 0.1651)
		(layer "F.Cu")
		(net "M_H_DQ<28>")
	)
	(segment
		(start 60.095384 -44.190158)
		(end 60.095384 -44.423838)
		(width 0.1651)
		(layer "F.Cu")
		(net "M_H_DQ<28>")
	)
	(segment
		(start 60.775088 -44.462446)
		(end 61.008768 -44.462446)
		(width 0.1651)
		(layer "F.Cu")
		(net "M_H_DQ<28>")
	)
	(segment
		(start 61.008768 -44.462446)
		(end 61.251084 -44.704762)
		(width 0.1651)
		(layer "F.Cu")
		(net "M_H_DQ<28>")
	)
	(segment
		(start 76.639166 -50.388774)
		(end 76.550774 -50.286158)
		(width 0.0889)
		(layer "F.Cu")
		(net "M_H_DQ<28>")
	)
	(segment
		(start 77.192886 -52.12334)
		(end 76.830174 -51.634898)
		(width 0.0889)
		(layer "F.Cu")
		(net "M_H_DQ<28>")
	)
	(segment
		(start 61.251084 -44.704762)
		(end 61.251084 -44.938442)
		(width 0.1651)
		(layer "F.Cu")
		(net "M_H_DQ<28>")
	)
	(segment
		(start 76.681076 -50.837338)
		(end 76.685902 -50.828702)
		(width 0.0889)
		(layer "F.Cu")
		(net "M_H_DQ<28>")
	)
	(segment
		(start 60.299346 -9.091168)
		(end 60.238894 -8.763)
		(width 0.1651)
		(layer "F.Cu")
		(net "M_H_DQ<28>")
	)
	(segment
		(start 60.299092 -43.98645)
		(end 60.095384 -44.190158)
		(width 0.1651)
		(layer "F.Cu")
		(net "M_H_DQ<28>")
	)
	(segment
		(start 76.674726 -50.848006)
		(end 76.681076 -50.837338)
		(width 0.0889)
		(layer "F.Cu")
		(net "M_H_DQ<28>")
	)
	(segment
		(start 59.332368 -36.802568)
		(end 59.332368 -42.786046)
		(width 0.1651)
		(layer "F.Cu")
		(net "M_H_DQ<28>")
	)
	(segment
		(start 61.047376 -45.37583)
		(end 61.289692 -45.618146)
		(width 0.1651)
		(layer "F.Cu")
		(net "M_H_DQ<28>")
	)
	(segment
		(start 67.815206 -49.52619)
		(end 66.63563 -48.346614)
		(width 0.127)
		(layer "F.Cu")
		(net "M_H_DQ<28>")
	)
	(segment
		(start 58.798968 -36.269168)
		(end 59.332368 -36.802568)
		(width 0.1651)
		(layer "F.Cu")
		(net "M_H_DQ<28>")
	)
	(segment
		(start 60.57138 -44.666154)
		(end 60.775088 -44.462446)
		(width 0.1651)
		(layer "F.Cu")
		(net "M_H_DQ<28>")
	)
	(segment
		(start 64.774064 -48.227742)
		(end 64.774572 -48.227742)
		(width 0.1651)
		(layer "F.Cu")
		(net "M_H_DQ<28>")
	)
	(segment
		(start 58.798968 -29.181552)
		(end 58.798968 -35.687)
		(width 0.1651)
		(layer "F.Cu")
		(net "M_H_DQ<28>")
	)
	(segment
		(start 64.774572 -48.227742)
		(end 64.893444 -48.346614)
		(width 0.127)
		(layer "F.Cu")
		(net "M_H_DQ<28>")
	)
	(segment
		(start 58.798968 -35.687)
		(end 58.798968 -36.269168)
		(width 0.1651)
		(layer "F.Cu")
		(net "M_H_DQ<28>")
	)
	(segment
		(start 75.583796 -49.52619)
		(end 67.815206 -49.52619)
		(width 0.127)
		(layer "F.Cu")
		(net "M_H_DQ<28>")
	)
	(segment
		(start 61.251084 -44.938442)
		(end 61.047376 -45.14215)
		(width 0.1651)
		(layer "F.Cu")
		(net "M_H_DQ<28>")
	)
	(segment
		(start 60.299092 -43.75277)
		(end 60.299092 -43.98645)
		(width 0.1651)
		(layer "F.Cu")
		(net "M_H_DQ<28>")
	)
	(segment
		(start 59.332368 -42.786046)
		(end 60.299092 -43.75277)
		(width 0.1651)
		(layer "F.Cu")
		(net "M_H_DQ<28>")
	)
	(segment
		(start 61.72708 -45.414438)
		(end 61.96076 -45.414438)
		(width 0.1651)
		(layer "F.Cu")
		(net "M_H_DQ<28>")
	)
	(segment
		(start 76.830174 -51.634898)
		(end 76.727812 -51.496976)
		(width 0.0889)
		(layer "F.Cu")
		(net "M_H_DQ<28>")
	)
	(via
		(at 59.449462 -13.959078)
		(size 0.508)
		(drill 0.254)
		(layers "F.Cu" "B.Cu")
		(net "M_H_DQ<28>")
	)
	(via
		(at 60.201302 -8.5598)
		(size 0.508)
		(drill 0.254)
		(layers "F.Cu" "B.Cu")
		(net "M_H_DQ<28>")
	)
	(via
		(at 58.798968 -35.687)
		(size 0.508)
		(drill 0.254)
		(layers "F.Cu" "B.Cu")
		(net "M_H_DQ<28>")
	)
	(via
		(at 59.449462 -28.531058)
		(size 0.508)
		(drill 0.254)
		(layers "F.Cu" "B.Cu")
		(net "M_H_DQ<28>")
	)
	(arc
		(start 76.685902 -50.828702)
		(mid 76.731137 -50.60144)
		(end 76.639166 -50.388774)
		(width 0.0889)
		(layer "F.Cu")
		(net "M_H_DQ<28>")
	)
	(arc
		(start 76.727812 -51.496976)
		(mid 76.603813 -51.180456)
		(end 76.674726 -50.848006)
		(width 0.0889)
		(layer "F.Cu")
		(net "M_H_DQ<28>")
	)
	(segment
		(start 59.449462 -15.222982)
		(end 59.449462 -13.959078)
		(width 0.1651)
		(layer "B.Cu")
		(net "M_H_DQ<28>")
	)
	(segment
		(start 59.706764 -18.30578)
		(end 59.706764 -17.050004)
		(width 0.14224)
		(layer "In4.Cu")
		(net "M_H_DQ<28>")
	)
	(segment
		(start 59.560968 -9.9822)
		(end 59.560968 -9.677654)
		(width 0.14224)
		(layer "In4.Cu")
		(net "M_H_DQ<28>")
	)
	(segment
		(start 59.573668 -11.0363)
		(end 59.941968 -10.668)
		(width 0.14224)
		(layer "In4.Cu")
		(net "M_H_DQ<28>")
	)
	(segment
		(start 59.21375 -13.723366)
		(end 59.21375 -12.928854)
		(width 0.14224)
		(layer "In4.Cu")
		(net "M_H_DQ<28>")
	)
	(segment
		(start 59.449462 -13.959078)
		(end 59.21375 -13.723366)
		(width 0.14224)
		(layer "In4.Cu")
		(net "M_H_DQ<28>")
	)
	(segment
		(start 59.92495 -8.836152)
		(end 60.201302 -8.5598)
		(width 0.14224)
		(layer "In4.Cu")
		(net "M_H_DQ<28>")
	)
	(segment
		(start 59.449462 -15.610078)
		(end 59.449462 -13.959078)
		(width 0.14224)
		(layer "In4.Cu")
		(net "M_H_DQ<28>")
	)
	(segment
		(start 59.93257 -23.383748)
		(end 59.706764 -23.157942)
		(width 0.14224)
		(layer "In4.Cu")
		(net "M_H_DQ<28>")
	)
	(segment
		(start 59.706764 -23.157942)
		(end 59.706764 -21.961602)
		(width 0.14224)
		(layer "In4.Cu")
		(net "M_H_DQ<28>")
	)
	(segment
		(start 59.941968 -10.668)
		(end 59.941968 -10.3632)
		(width 0.14224)
		(layer "In4.Cu")
		(net "M_H_DQ<28>")
	)
	(segment
		(start 59.92495 -11.742928)
		(end 59.573668 -11.391646)
		(width 0.14224)
		(layer "In4.Cu")
		(net "M_H_DQ<28>")
	)
	(segment
		(start 59.21375 -12.928854)
		(end 59.92495 -12.217654)
		(width 0.14224)
		(layer "In4.Cu")
		(net "M_H_DQ<28>")
	)
	(segment
		(start 59.92495 -12.217654)
		(end 59.92495 -11.742928)
		(width 0.14224)
		(layer "In4.Cu")
		(net "M_H_DQ<28>")
	)
	(segment
		(start 59.93257 -16.824198)
		(end 59.93257 -16.093186)
		(width 0.14224)
		(layer "In4.Cu")
		(net "M_H_DQ<28>")
	)
	(segment
		(start 59.92495 -9.313672)
		(end 59.92495 -8.836152)
		(width 0.14224)
		(layer "In4.Cu")
		(net "M_H_DQ<28>")
	)
	(segment
		(start 59.93257 -18.531586)
		(end 59.706764 -18.30578)
		(width 0.14224)
		(layer "In4.Cu")
		(net "M_H_DQ<28>")
	)
	(segment
		(start 59.573668 -11.391646)
		(end 59.573668 -11.0363)
		(width 0.14224)
		(layer "In4.Cu")
		(net "M_H_DQ<28>")
	)
	(segment
		(start 59.93257 -26.742644)
		(end 59.93257 -23.383748)
		(width 0.14224)
		(layer "In4.Cu")
		(net "M_H_DQ<28>")
	)
	(segment
		(start 59.70397 -26.971244)
		(end 59.93257 -26.742644)
		(width 0.14224)
		(layer "In4.Cu")
		(net "M_H_DQ<28>")
	)
	(segment
		(start 59.93257 -21.735796)
		(end 59.93257 -18.531586)
		(width 0.14224)
		(layer "In4.Cu")
		(net "M_H_DQ<28>")
	)
	(segment
		(start 59.70397 -28.27655)
		(end 59.70397 -26.971244)
		(width 0.14224)
		(layer "In4.Cu")
		(net "M_H_DQ<28>")
	)
	(segment
		(start 59.706764 -21.961602)
		(end 59.93257 -21.735796)
		(width 0.14224)
		(layer "In4.Cu")
		(net "M_H_DQ<28>")
	)
	(segment
		(start 59.93257 -16.093186)
		(end 59.449462 -15.610078)
		(width 0.14224)
		(layer "In4.Cu")
		(net "M_H_DQ<28>")
	)
	(segment
		(start 59.449462 -28.531058)
		(end 59.70397 -28.27655)
		(width 0.14224)
		(layer "In4.Cu")
		(net "M_H_DQ<28>")
	)
	(segment
		(start 59.560968 -9.677654)
		(end 59.92495 -9.313672)
		(width 0.14224)
		(layer "In4.Cu")
		(net "M_H_DQ<28>")
	)
	(segment
		(start 59.706764 -17.050004)
		(end 59.93257 -16.824198)
		(width 0.14224)
		(layer "In4.Cu")
		(net "M_H_DQ<28>")
	)
	(segment
		(start 59.941968 -10.3632)
		(end 59.560968 -9.9822)
		(width 0.14224)
		(layer "In4.Cu")
		(net "M_H_DQ<28>")
	)
	(segment
		(start 68.867782 -36.81857)
		(end 68.702682 -36.98367)
		(width 0.1651)
		(layer "F.Cu")
		(net "M_H_DQ<27>")
	)
	(segment
		(start 68.702682 -35.98037)
		(end 68.867782 -36.14547)
		(width 0.1651)
		(layer "F.Cu")
		(net "M_H_DQ<27>")
	)
	(segment
		(start 69.225668 -38.16477)
		(end 68.867782 -38.16477)
		(width 0.1651)
		(layer "F.Cu")
		(net "M_H_DQ<27>")
	)
	(segment
		(start 68.708016 -35.7886)
		(end 68.702682 -35.793934)
		(width 0.1651)
		(layer "F.Cu")
		(net "M_H_DQ<27>")
	)
	(segment
		(start 67.358768 -27.9908)
		(end 67.561968 -28.194)
		(width 0.1651)
		(layer "F.Cu")
		(net "M_H_DQ<27>")
	)
	(segment
		(start 68.708016 -34.544)
		(end 68.708016 -35.7886)
		(width 0.1651)
		(layer "F.Cu")
		(net "M_H_DQ<27>")
	)
	(segment
		(start 68.702682 -36.98367)
		(end 68.702682 -37.32657)
		(width 0.1651)
		(layer "F.Cu")
		(net "M_H_DQ<27>")
	)
	(segment
		(start 69.390768 -37.99967)
		(end 69.225668 -38.16477)
		(width 0.1651)
		(layer "F.Cu")
		(net "M_H_DQ<27>")
	)
	(segment
		(start 68.702682 -38.67277)
		(end 68.867782 -38.83787)
		(width 0.1651)
		(layer "F.Cu")
		(net "M_H_DQ<27>")
	)
	(segment
		(start 77.798168 -46.14799)
		(end 73.810368 -46.14799)
		(width 0.127)
		(layer "F.Cu")
		(net "M_H_DQ<27>")
	)
	(segment
		(start 68.702682 -38.32987)
		(end 68.702682 -38.67277)
		(width 0.1651)
		(layer "F.Cu")
		(net "M_H_DQ<27>")
	)
	(segment
		(start 67.561968 -28.194)
		(end 67.561968 -30.886654)
		(width 0.1651)
		(layer "F.Cu")
		(net "M_H_DQ<27>")
	)
	(segment
		(start 68.702682 -37.32657)
		(end 68.867782 -37.49167)
		(width 0.1651)
		(layer "F.Cu")
		(net "M_H_DQ<27>")
	)
	(segment
		(start 68.867782 -40.85717)
		(end 68.702682 -41.02227)
		(width 0.1651)
		(layer "F.Cu")
		(net "M_H_DQ<27>")
	)
	(segment
		(start 67.358768 -27.840686)
		(end 67.358768 -27.9908)
		(width 0.1651)
		(layer "F.Cu")
		(net "M_H_DQ<27>")
	)
	(segment
		(start 69.060568 -40.69207)
		(end 68.895468 -40.85717)
		(width 0.1651)
		(layer "F.Cu")
		(net "M_H_DQ<27>")
	)
	(segment
		(start 67.099434 -5.822442)
		(end 67.099434 -7.086346)
		(width 0.1651)
		(layer "F.Cu")
		(net "M_H_DQ<27>")
	)
	(segment
		(start 68.702682 -43.069764)
		(end 69.317362 -43.684444)
		(width 0.1651)
		(layer "F.Cu")
		(net "M_H_DQ<27>")
	)
	(segment
		(start 68.867782 -37.49167)
		(end 69.225668 -37.49167)
		(width 0.1651)
		(layer "F.Cu")
		(net "M_H_DQ<27>")
	)
	(segment
		(start 80.914494 -51.383692)
		(end 81.0006 -51.234848)
		(width 0.0889)
		(layer "F.Cu")
		(net "M_H_DQ<27>")
	)
	(segment
		(start 69.390768 -36.31057)
		(end 69.390768 -36.65347)
		(width 0.1651)
		(layer "F.Cu")
		(net "M_H_DQ<27>")
	)
	(segment
		(start 81.229962 -48.827944)
		(end 80.807052 -48.405034)
		(width 0.0889)
		(layer "F.Cu")
		(net "M_H_DQ<27>")
	)
	(segment
		(start 69.317362 -43.684444)
		(end 69.408802 -43.775884)
		(width 0.127)
		(layer "F.Cu")
		(net "M_H_DQ<27>")
	)
	(segment
		(start 68.867782 -36.14547)
		(end 69.225668 -36.14547)
		(width 0.1651)
		(layer "F.Cu")
		(net "M_H_DQ<27>")
	)
	(segment
		(start 68.867782 -38.83787)
		(end 69.225668 -38.83787)
		(width 0.1651)
		(layer "F.Cu")
		(net "M_H_DQ<27>")
	)
	(segment
		(start 81.229962 -50.31232)
		(end 81.229962 -48.827944)
		(width 0.0889)
		(layer "F.Cu")
		(net "M_H_DQ<27>")
	)
	(segment
		(start 80.626712 -52.12334)
		(end 80.626712 -51.791616)
		(width 0.0889)
		(layer "F.Cu")
		(net "M_H_DQ<27>")
	)
	(segment
		(start 69.408802 -44.956984)
		(end 69.621908 -45.17009)
		(width 0.127)
		(layer "F.Cu")
		(net "M_H_DQ<27>")
	)
	(segment
		(start 67.561968 -30.886654)
		(end 68.708016 -32.032702)
		(width 0.1651)
		(layer "F.Cu")
		(net "M_H_DQ<27>")
	)
	(segment
		(start 69.390768 -36.65347)
		(end 69.225668 -36.81857)
		(width 0.1651)
		(layer "F.Cu")
		(net "M_H_DQ<27>")
	)
	(segment
		(start 69.390768 -37.65677)
		(end 69.390768 -37.99967)
		(width 0.1651)
		(layer "F.Cu")
		(net "M_H_DQ<27>")
	)
	(segment
		(start 69.408802 -43.775884)
		(end 69.408802 -44.956984)
		(width 0.127)
		(layer "F.Cu")
		(net "M_H_DQ<27>")
	)
	(segment
		(start 67.949318 -27.250136)
		(end 67.358768 -27.840686)
		(width 0.1651)
		(layer "F.Cu")
		(net "M_H_DQ<27>")
	)
	(segment
		(start 68.895468 -40.85717)
		(end 68.867782 -40.85717)
		(width 0.1651)
		(layer "F.Cu")
		(net "M_H_DQ<27>")
	)
	(segment
		(start 69.225668 -37.49167)
		(end 69.390768 -37.65677)
		(width 0.1651)
		(layer "F.Cu")
		(net "M_H_DQ<27>")
	)
	(segment
		(start 68.708016 -32.032702)
		(end 68.708016 -34.544)
		(width 0.1651)
		(layer "F.Cu")
		(net "M_H_DQ<27>")
	)
	(segment
		(start 80.807052 -48.405034)
		(end 80.580992 -48.405034)
		(width 0.0889)
		(layer "F.Cu")
		(net "M_H_DQ<27>")
	)
	(segment
		(start 68.702682 -39.67607)
		(end 68.702682 -40.01897)
		(width 0.1651)
		(layer "F.Cu")
		(net "M_H_DQ<27>")
	)
	(segment
		(start 68.702682 -40.01897)
		(end 68.867782 -40.18407)
		(width 0.1651)
		(layer "F.Cu")
		(net "M_H_DQ<27>")
	)
	(segment
		(start 69.225668 -36.14547)
		(end 69.390768 -36.31057)
		(width 0.1651)
		(layer "F.Cu")
		(net "M_H_DQ<27>")
	)
	(segment
		(start 68.702682 -41.02227)
		(end 68.702682 -43.069764)
		(width 0.1651)
		(layer "F.Cu")
		(net "M_H_DQ<27>")
	)
	(segment
		(start 68.867782 -39.51097)
		(end 68.702682 -39.67607)
		(width 0.1651)
		(layer "F.Cu")
		(net "M_H_DQ<27>")
	)
	(segment
		(start 72.832468 -45.17009)
		(end 73.810368 -46.14799)
		(width 0.127)
		(layer "F.Cu")
		(net "M_H_DQ<27>")
	)
	(segment
		(start 68.867782 -38.16477)
		(end 68.702682 -38.32987)
		(width 0.1651)
		(layer "F.Cu")
		(net "M_H_DQ<27>")
	)
	(segment
		(start 69.621908 -45.17009)
		(end 72.832468 -45.17009)
		(width 0.127)
		(layer "F.Cu")
		(net "M_H_DQ<27>")
	)
	(segment
		(start 80.580992 -48.405034)
		(end 80.055212 -48.405034)
		(width 0.127)
		(layer "F.Cu")
		(net "M_H_DQ<27>")
	)
	(segment
		(start 68.867782 -40.18407)
		(end 68.895468 -40.18407)
		(width 0.1651)
		(layer "F.Cu")
		(net "M_H_DQ<27>")
	)
	(segment
		(start 68.895468 -40.18407)
		(end 69.060568 -40.34917)
		(width 0.1651)
		(layer "F.Cu")
		(net "M_H_DQ<27>")
	)
	(segment
		(start 69.390768 -39.00297)
		(end 69.390768 -39.34587)
		(width 0.1651)
		(layer "F.Cu")
		(net "M_H_DQ<27>")
	)
	(segment
		(start 69.225668 -36.81857)
		(end 68.867782 -36.81857)
		(width 0.1651)
		(layer "F.Cu")
		(net "M_H_DQ<27>")
	)
	(segment
		(start 68.702682 -35.793934)
		(end 68.702682 -35.98037)
		(width 0.1651)
		(layer "F.Cu")
		(net "M_H_DQ<27>")
	)
	(segment
		(start 80.055212 -48.405034)
		(end 77.798168 -46.14799)
		(width 0.127)
		(layer "F.Cu")
		(net "M_H_DQ<27>")
	)
	(segment
		(start 69.225668 -39.51097)
		(end 68.867782 -39.51097)
		(width 0.1651)
		(layer "F.Cu")
		(net "M_H_DQ<27>")
	)
	(segment
		(start 69.390768 -39.34587)
		(end 69.225668 -39.51097)
		(width 0.1651)
		(layer "F.Cu")
		(net "M_H_DQ<27>")
	)
	(segment
		(start 69.060568 -40.34917)
		(end 69.060568 -40.69207)
		(width 0.1651)
		(layer "F.Cu")
		(net "M_H_DQ<27>")
	)
	(segment
		(start 69.225668 -38.83787)
		(end 69.390768 -39.00297)
		(width 0.1651)
		(layer "F.Cu")
		(net "M_H_DQ<27>")
	)
	(via
		(at 67.949318 -12.678156)
		(size 0.508)
		(drill 0.254)
		(layers "F.Cu" "B.Cu")
		(net "M_H_DQ<27>")
	)
	(via
		(at 68.708016 -34.544)
		(size 0.508)
		(drill 0.254)
		(layers "F.Cu" "B.Cu")
		(net "M_H_DQ<27>")
	)
	(via
		(at 67.949318 -27.250136)
		(size 0.508)
		(drill 0.254)
		(layers "F.Cu" "B.Cu")
		(net "M_H_DQ<27>")
	)
	(via
		(at 67.099434 -7.086346)
		(size 0.508)
		(drill 0.254)
		(layers "F.Cu" "B.Cu")
		(net "M_H_DQ<27>")
	)
	(arc
		(start 81.026762 -51.14036)
		(mid 81.038558 -50.924026)
		(end 81.065624 -50.709068)
		(width 0.0889)
		(layer "F.Cu")
		(net "M_H_DQ<27>")
	)
	(arc
		(start 80.707992 -51.623214)
		(mid 80.822492 -51.513153)
		(end 80.914494 -51.383692)
		(width 0.0889)
		(layer "F.Cu")
		(net "M_H_DQ<27>")
	)
	(arc
		(start 81.065624 -50.709068)
		(mid 81.187252 -50.527038)
		(end 81.229962 -50.31232)
		(width 0.0889)
		(layer "F.Cu")
		(net "M_H_DQ<27>")
	)
	(arc
		(start 80.626712 -51.791616)
		(mid 80.648092 -51.698117)
		(end 80.707992 -51.623214)
		(width 0.0889)
		(layer "F.Cu")
		(net "M_H_DQ<27>")
	)
	(arc
		(start 81.0006 -51.234848)
		(mid 81.019672 -51.18926)
		(end 81.026762 -51.14036)
		(width 0.0889)
		(layer "F.Cu")
		(net "M_H_DQ<27>")
	)
	(segment
		(start 67.949318 -10.755376)
		(end 67.949318 -12.678156)
		(width 0.1651)
		(layer "B.Cu")
		(net "M_H_DQ<27>")
	)
	(segment
		(start 67.949572 -10.755122)
		(end 67.949318 -10.755376)
		(width 0.1651)
		(layer "B.Cu")
		(net "M_H_DQ<27>")
	)
	(segment
		(start 67.949572 -10.623042)
		(end 67.949572 -10.755122)
		(width 0.1651)
		(layer "B.Cu")
		(net "M_H_DQ<27>")
	)
	(segment
		(start 67.099434 -7.086346)
		(end 67.416172 -7.403084)
		(width 0.14224)
		(layer "In4.Cu")
		(net "M_H_DQ<27>")
	)
	(segment
		(start 68.28917 -13.752576)
		(end 68.28917 -16.855186)
		(width 0.14224)
		(layer "In4.Cu")
		(net "M_H_DQ<27>")
	)
	(segment
		(start 68.28917 -16.855186)
		(end 68.444364 -17.01038)
		(width 0.14224)
		(layer "In4.Cu")
		(net "M_H_DQ<27>")
	)
	(segment
		(start 68.44157 -21.986748)
		(end 68.44157 -23.186644)
		(width 0.14224)
		(layer "In4.Cu")
		(net "M_H_DQ<27>")
	)
	(segment
		(start 68.302124 -12.32535)
		(end 67.949318 -12.678156)
		(width 0.14224)
		(layer "In4.Cu")
		(net "M_H_DQ<27>")
	)
	(segment
		(start 67.949318 -12.678156)
		(end 68.49237 -13.221208)
		(width 0.14224)
		(layer "In4.Cu")
		(net "M_H_DQ<27>")
	)
	(segment
		(start 67.746372 -8.0518)
		(end 68.000372 -8.0518)
		(width 0.14224)
		(layer "In4.Cu")
		(net "M_H_DQ<27>")
	)
	(segment
		(start 68.444364 -18.421604)
		(end 68.26377 -18.602198)
		(width 0.14224)
		(layer "In4.Cu")
		(net "M_H_DQ<27>")
	)
	(segment
		(start 68.26377 -26.935684)
		(end 67.949318 -27.250136)
		(width 0.14224)
		(layer "In4.Cu")
		(net "M_H_DQ<27>")
	)
	(segment
		(start 68.49237 -13.221208)
		(end 68.49237 -13.549376)
		(width 0.14224)
		(layer "In4.Cu")
		(net "M_H_DQ<27>")
	)
	(segment
		(start 68.26377 -18.602198)
		(end 68.26377 -21.808948)
		(width 0.14224)
		(layer "In4.Cu")
		(net "M_H_DQ<27>")
	)
	(segment
		(start 68.444364 -17.01038)
		(end 68.444364 -18.421604)
		(width 0.14224)
		(layer "In4.Cu")
		(net "M_H_DQ<27>")
	)
	(segment
		(start 68.302124 -9.020048)
		(end 68.302124 -12.32535)
		(width 0.14224)
		(layer "In4.Cu")
		(net "M_H_DQ<27>")
	)
	(segment
		(start 67.416172 -7.403084)
		(end 67.416172 -7.7216)
		(width 0.14224)
		(layer "In4.Cu")
		(net "M_H_DQ<27>")
	)
	(segment
		(start 68.26377 -21.808948)
		(end 68.44157 -21.986748)
		(width 0.14224)
		(layer "In4.Cu")
		(net "M_H_DQ<27>")
	)
	(segment
		(start 68.49237 -13.549376)
		(end 68.28917 -13.752576)
		(width 0.14224)
		(layer "In4.Cu")
		(net "M_H_DQ<27>")
	)
	(segment
		(start 67.416172 -7.7216)
		(end 67.746372 -8.0518)
		(width 0.14224)
		(layer "In4.Cu")
		(net "M_H_DQ<27>")
	)
	(segment
		(start 68.000372 -8.0518)
		(end 68.457572 -8.509)
		(width 0.14224)
		(layer "In4.Cu")
		(net "M_H_DQ<27>")
	)
	(segment
		(start 68.44157 -23.186644)
		(end 68.26377 -23.364444)
		(width 0.14224)
		(layer "In4.Cu")
		(net "M_H_DQ<27>")
	)
	(segment
		(start 68.26377 -23.364444)
		(end 68.26377 -26.935684)
		(width 0.14224)
		(layer "In4.Cu")
		(net "M_H_DQ<27>")
	)
	(segment
		(start 68.457572 -8.8646)
		(end 68.302124 -9.020048)
		(width 0.14224)
		(layer "In4.Cu")
		(net "M_H_DQ<27>")
	)
	(segment
		(start 68.457572 -8.509)
		(end 68.457572 -8.8646)
		(width 0.14224)
		(layer "In4.Cu")
		(net "M_H_DQ<27>")
	)
	(segment
		(start 67.949318 -10.422128)
		(end 67.949318 -9.425432)
		(width 0.1651)
		(layer "F.Cu")
		(net "M_H_DQ<26>")
	)
	(segment
		(start 67.949318 -9.425432)
		(end 68.08089 -9.29386)
		(width 0.1651)
		(layer "F.Cu")
		(net "M_H_DQ<26>")
	)
	(segment
		(start 68.859146 -44.14266)
		(end 69.002402 -44.285916)
		(width 0.1016)
		(layer "F.Cu")
		(net "M_H_DQ<26>")
	)
	(segment
		(start 67.949318 -8.938768)
		(end 67.949318 -8.6614)
		(width 0.1651)
		(layer "F.Cu")
		(net "M_H_DQ<26>")
	)
	(segment
		(start 67.099434 -28.531058)
		(end 66.520568 -29.109924)
		(width 0.1651)
		(layer "F.Cu")
		(net "M_H_DQ<26>")
	)
	(segment
		(start 67.865244 -32.665416)
		(end 67.865244 -35.814)
		(width 0.1651)
		(layer "F.Cu")
		(net "M_H_DQ<26>")
	)
	(segment
		(start 67.865244 -43.148758)
		(end 68.859146 -44.14266)
		(width 0.1651)
		(layer "F.Cu")
		(net "M_H_DQ<26>")
	)
	(segment
		(start 69.002402 -45.125386)
		(end 69.453506 -45.57649)
		(width 0.1016)
		(layer "F.Cu")
		(net "M_H_DQ<26>")
	)
	(segment
		(start 67.686428 -32.4866)
		(end 67.865244 -32.665416)
		(width 0.1651)
		(layer "F.Cu")
		(net "M_H_DQ<26>")
	)
	(segment
		(start 66.695828 -30.497526)
		(end 66.520568 -30.672786)
		(width 0.1651)
		(layer "F.Cu")
		(net "M_H_DQ<26>")
	)
	(segment
		(start 67.203828 -32.63646)
		(end 67.353688 -32.4866)
		(width 0.1651)
		(layer "F.Cu")
		(net "M_H_DQ<26>")
	)
	(segment
		(start 66.520568 -30.672786)
		(end 66.520568 -34.4043)
		(width 0.1651)
		(layer "F.Cu")
		(net "M_H_DQ<26>")
	)
	(segment
		(start 68.08089 -9.07034)
		(end 67.949318 -8.938768)
		(width 0.1651)
		(layer "F.Cu")
		(net "M_H_DQ<26>")
	)
	(segment
		(start 66.685668 -34.5694)
		(end 67.038728 -34.5694)
		(width 0.1651)
		(layer "F.Cu")
		(net "M_H_DQ<26>")
	)
	(segment
		(start 80.555592 -48.722534)
		(end 80.784192 -48.722534)
		(width 0.0889)
		(layer "F.Cu")
		(net "M_H_DQ<26>")
	)
	(segment
		(start 80.784192 -48.722534)
		(end 81.039462 -48.977804)
		(width 0.0889)
		(layer "F.Cu")
		(net "M_H_DQ<26>")
	)
	(segment
		(start 69.453506 -45.57649)
		(end 72.789796 -45.57649)
		(width 0.1016)
		(layer "F.Cu")
		(net "M_H_DQ<26>")
	)
	(segment
		(start 68.08089 -9.29386)
		(end 68.08089 -9.07034)
		(width 0.1651)
		(layer "F.Cu")
		(net "M_H_DQ<26>")
	)
	(segment
		(start 67.949572 -10.422382)
		(end 67.949318 -10.422128)
		(width 0.1651)
		(layer "F.Cu")
		(net "M_H_DQ<26>")
	)
	(segment
		(start 69.002402 -44.285916)
		(end 69.002402 -45.125386)
		(width 0.1016)
		(layer "F.Cu")
		(net "M_H_DQ<26>")
	)
	(segment
		(start 67.865244 -35.814)
		(end 67.865244 -43.148758)
		(width 0.1651)
		(layer "F.Cu")
		(net "M_H_DQ<26>")
	)
	(segment
		(start 79.92364 -48.722534)
		(end 80.555592 -48.722534)
		(width 0.1016)
		(layer "F.Cu")
		(net "M_H_DQ<26>")
	)
	(segment
		(start 66.520568 -29.639006)
		(end 66.695828 -29.814266)
		(width 0.1651)
		(layer "F.Cu")
		(net "M_H_DQ<26>")
	)
	(segment
		(start 66.520568 -34.4043)
		(end 66.685668 -34.5694)
		(width 0.1651)
		(layer "F.Cu")
		(net "M_H_DQ<26>")
	)
	(segment
		(start 72.789796 -45.57649)
		(end 73.678796 -46.46549)
		(width 0.1016)
		(layer "F.Cu")
		(net "M_H_DQ<26>")
	)
	(segment
		(start 67.353688 -32.4866)
		(end 67.686428 -32.4866)
		(width 0.1651)
		(layer "F.Cu")
		(net "M_H_DQ<26>")
	)
	(segment
		(start 67.038728 -34.5694)
		(end 67.203828 -34.4043)
		(width 0.1651)
		(layer "F.Cu")
		(net "M_H_DQ<26>")
	)
	(segment
		(start 73.678796 -46.46549)
		(end 77.666596 -46.46549)
		(width 0.1016)
		(layer "F.Cu")
		(net "M_H_DQ<26>")
	)
	(segment
		(start 66.695828 -29.814266)
		(end 66.695828 -30.497526)
		(width 0.1651)
		(layer "F.Cu")
		(net "M_H_DQ<26>")
	)
	(segment
		(start 66.520568 -29.109924)
		(end 66.520568 -29.639006)
		(width 0.1651)
		(layer "F.Cu")
		(net "M_H_DQ<26>")
	)
	(segment
		(start 67.203828 -34.4043)
		(end 67.203828 -32.63646)
		(width 0.1651)
		(layer "F.Cu")
		(net "M_H_DQ<26>")
	)
	(segment
		(start 81.039462 -48.977804)
		(end 81.039462 -50.072544)
		(width 0.0889)
		(layer "F.Cu")
		(net "M_H_DQ<26>")
	)
	(segment
		(start 77.666596 -46.46549)
		(end 79.92364 -48.722534)
		(width 0.1016)
		(layer "F.Cu")
		(net "M_H_DQ<26>")
	)
	(via
		(at 67.099434 -28.531058)
		(size 0.508)
		(drill 0.254)
		(layers "F.Cu" "B.Cu")
		(net "M_H_DQ<26>")
	)
	(via
		(at 67.865244 -35.814)
		(size 0.508)
		(drill 0.254)
		(layers "F.Cu" "B.Cu")
		(net "M_H_DQ<26>")
	)
	(via
		(at 67.099434 -13.959078)
		(size 0.508)
		(drill 0.254)
		(layers "F.Cu" "B.Cu")
		(net "M_H_DQ<26>")
	)
	(via
		(at 67.949318 -8.6614)
		(size 0.508)
		(drill 0.254)
		(layers "F.Cu" "B.Cu")
		(net "M_H_DQ<26>")
	)
	(arc
		(start 81.039462 -50.072544)
		(mid 81.003863 -50.270135)
		(end 80.90154 -50.442876)
		(width 0.0889)
		(layer "F.Cu")
		(net "M_H_DQ<26>")
	)
	(arc
		(start 80.90154 -50.442876)
		(mid 80.70601 -50.764521)
		(end 80.626712 -51.132486)
		(width 0.0889)
		(layer "F.Cu")
		(net "M_H_DQ<26>")
	)
	(segment
		(start 67.099434 -15.222982)
		(end 67.099434 -13.959078)
		(width 0.1651)
		(layer "B.Cu")
		(net "M_H_DQ<26>")
	)
	(segment
		(start 66.8147 -12.9286)
		(end 66.8147 -13.674344)
		(width 0.14224)
		(layer "In4.Cu")
		(net "M_H_DQ<26>")
	)
	(segment
		(start 67.511168 -10.362946)
		(end 67.511168 -10.64895)
		(width 0.14224)
		(layer "In4.Cu")
		(net "M_H_DQ<26>")
	)
	(segment
		(start 67.42557 -18.405602)
		(end 67.62877 -18.608802)
		(width 0.14224)
		(layer "In4.Cu")
		(net "M_H_DQ<26>")
	)
	(segment
		(start 67.099434 -13.959078)
		(end 67.099434 -15.082266)
		(width 0.14224)
		(layer "In4.Cu")
		(net "M_H_DQ<26>")
	)
	(segment
		(start 67.206368 -9.709404)
		(end 67.206368 -10.058146)
		(width 0.14224)
		(layer "In4.Cu")
		(net "M_H_DQ<26>")
	)
	(segment
		(start 67.42557 -17.036034)
		(end 67.42557 -18.405602)
		(width 0.14224)
		(layer "In4.Cu")
		(net "M_H_DQ<26>")
	)
	(segment
		(start 67.580764 -16.88084)
		(end 67.42557 -17.036034)
		(width 0.14224)
		(layer "In4.Cu")
		(net "M_H_DQ<26>")
	)
	(segment
		(start 67.60337 -23.335996)
		(end 67.60337 -26.742644)
		(width 0.14224)
		(layer "In4.Cu")
		(net "M_H_DQ<26>")
	)
	(segment
		(start 67.5513 -9.364472)
		(end 67.206368 -9.709404)
		(width 0.14224)
		(layer "In4.Cu")
		(net "M_H_DQ<26>")
	)
	(segment
		(start 67.511168 -10.64895)
		(end 67.206368 -10.95375)
		(width 0.14224)
		(layer "In4.Cu")
		(net "M_H_DQ<26>")
	)
	(segment
		(start 67.206368 -11.3538)
		(end 67.663568 -11.811)
		(width 0.14224)
		(layer "In4.Cu")
		(net "M_H_DQ<26>")
	)
	(segment
		(start 67.206368 -10.95375)
		(end 67.206368 -11.3538)
		(width 0.14224)
		(layer "In4.Cu")
		(net "M_H_DQ<26>")
	)
	(segment
		(start 66.8147 -13.674344)
		(end 67.099434 -13.959078)
		(width 0.14224)
		(layer "In4.Cu")
		(net "M_H_DQ<26>")
	)
	(segment
		(start 67.949318 -8.6614)
		(end 67.5513 -9.059418)
		(width 0.14224)
		(layer "In4.Cu")
		(net "M_H_DQ<26>")
	)
	(segment
		(start 67.60337 -26.742644)
		(end 67.099434 -27.24658)
		(width 0.14224)
		(layer "In4.Cu")
		(net "M_H_DQ<26>")
	)
	(segment
		(start 67.453764 -23.18639)
		(end 67.60337 -23.335996)
		(width 0.14224)
		(layer "In4.Cu")
		(net "M_H_DQ<26>")
	)
	(segment
		(start 67.62877 -18.608802)
		(end 67.62877 -21.786596)
		(width 0.14224)
		(layer "In4.Cu")
		(net "M_H_DQ<26>")
	)
	(segment
		(start 67.663568 -12.079732)
		(end 66.8147 -12.9286)
		(width 0.14224)
		(layer "In4.Cu")
		(net "M_H_DQ<26>")
	)
	(segment
		(start 67.453764 -21.961602)
		(end 67.453764 -23.18639)
		(width 0.14224)
		(layer "In4.Cu")
		(net "M_H_DQ<26>")
	)
	(segment
		(start 67.663568 -11.811)
		(end 67.663568 -12.079732)
		(width 0.14224)
		(layer "In4.Cu")
		(net "M_H_DQ<26>")
	)
	(segment
		(start 67.62877 -21.786596)
		(end 67.453764 -21.961602)
		(width 0.14224)
		(layer "In4.Cu")
		(net "M_H_DQ<26>")
	)
	(segment
		(start 67.206368 -10.058146)
		(end 67.511168 -10.362946)
		(width 0.14224)
		(layer "In4.Cu")
		(net "M_H_DQ<26>")
	)
	(segment
		(start 67.099434 -15.082266)
		(end 67.580764 -15.563596)
		(width 0.14224)
		(layer "In4.Cu")
		(net "M_H_DQ<26>")
	)
	(segment
		(start 67.099434 -27.24658)
		(end 67.099434 -28.531058)
		(width 0.14224)
		(layer "In4.Cu")
		(net "M_H_DQ<26>")
	)
	(segment
		(start 67.5513 -9.059418)
		(end 67.5513 -9.364472)
		(width 0.14224)
		(layer "In4.Cu")
		(net "M_H_DQ<26>")
	)
	(segment
		(start 67.580764 -15.563596)
		(end 67.580764 -16.88084)
		(width 0.14224)
		(layer "In4.Cu")
		(net "M_H_DQ<26>")
	)
	(segment
		(start 61.618368 -28.321)
		(end 61.618368 -36.068)
		(width 0.1651)
		(layer "F.Cu")
		(net "M_H_DQ<25>")
	)
	(segment
		(start 61.065664 -27.161236)
		(end 60.900564 -27.326336)
		(width 0.1651)
		(layer "F.Cu")
		(net "M_H_DQ<25>")
	)
	(segment
		(start 61.872368 -39.110412)
		(end 61.872368 -39.453312)
		(width 0.1651)
		(layer "F.Cu")
		(net "M_H_DQ<25>")
	)
	(segment
		(start 61.618368 -36.068)
		(end 61.618368 -37.617654)
		(width 0.1651)
		(layer "F.Cu")
		(net "M_H_DQ<25>")
	)
	(segment
		(start 61.465968 -40.799512)
		(end 61.631068 -40.964612)
		(width 0.1651)
		(layer "F.Cu")
		(net "M_H_DQ<25>")
	)
	(segment
		(start 60.900564 -27.603196)
		(end 61.618368 -28.321)
		(width 0.1651)
		(layer "F.Cu")
		(net "M_H_DQ<25>")
	)
	(segment
		(start 66.453004 -47.152814)
		(end 67.130676 -47.152814)
		(width 0.1016)
		(layer "F.Cu")
		(net "M_H_DQ<25>")
	)
	(segment
		(start 62.418468 -43.118278)
		(end 66.151252 -46.851062)
		(width 0.1651)
		(layer "F.Cu")
		(net "M_H_DQ<25>")
	)
	(segment
		(start 78.051406 -50.63744)
		(end 78.051406 -50.316384)
		(width 0.0889)
		(layer "F.Cu")
		(net "M_H_DQ<25>")
	)
	(segment
		(start 61.149484 -5.822442)
		(end 61.149484 -7.086346)
		(width 0.1651)
		(layer "F.Cu")
		(net "M_H_DQ<25>")
	)
	(segment
		(start 78.020418 -49.838356)
		(end 76.781152 -48.59909)
		(width 0.1016)
		(layer "F.Cu")
		(net "M_H_DQ<25>")
	)
	(segment
		(start 72.526652 -48.33239)
		(end 68.310252 -48.33239)
		(width 0.1016)
		(layer "F.Cu")
		(net "M_H_DQ<25>")
	)
	(segment
		(start 61.618368 -37.617654)
		(end 62.418468 -38.417754)
		(width 0.1651)
		(layer "F.Cu")
		(net "M_H_DQ<25>")
	)
	(segment
		(start 62.418468 -40.126412)
		(end 62.253368 -40.291512)
		(width 0.1651)
		(layer "F.Cu")
		(net "M_H_DQ<25>")
	)
	(segment
		(start 62.253368 -39.618412)
		(end 62.418468 -39.783512)
		(width 0.1651)
		(layer "F.Cu")
		(net "M_H_DQ<25>")
	)
	(segment
		(start 60.900564 -27.326336)
		(end 60.900564 -27.603196)
		(width 0.1651)
		(layer "F.Cu")
		(net "M_H_DQ<25>")
	)
	(segment
		(start 61.631068 -40.291512)
		(end 61.465968 -40.456612)
		(width 0.1651)
		(layer "F.Cu")
		(net "M_H_DQ<25>")
	)
	(segment
		(start 68.310252 -48.33239)
		(end 67.130676 -47.152814)
		(width 0.1016)
		(layer "F.Cu")
		(net "M_H_DQ<25>")
	)
	(segment
		(start 62.418468 -38.417754)
		(end 62.418468 -38.780212)
		(width 0.1651)
		(layer "F.Cu")
		(net "M_H_DQ<25>")
	)
	(segment
		(start 78.020418 -50.285396)
		(end 78.020418 -49.838356)
		(width 0.0889)
		(layer "F.Cu")
		(net "M_H_DQ<25>")
	)
	(segment
		(start 62.418468 -39.783512)
		(end 62.418468 -40.126412)
		(width 0.1651)
		(layer "F.Cu")
		(net "M_H_DQ<25>")
	)
	(segment
		(start 61.821568 -27.161236)
		(end 61.065664 -27.161236)
		(width 0.1651)
		(layer "F.Cu")
		(net "M_H_DQ<25>")
	)
	(segment
		(start 76.781152 -48.59909)
		(end 72.793352 -48.59909)
		(width 0.1016)
		(layer "F.Cu")
		(net "M_H_DQ<25>")
	)
	(segment
		(start 62.253368 -40.291512)
		(end 61.631068 -40.291512)
		(width 0.1651)
		(layer "F.Cu")
		(net "M_H_DQ<25>")
	)
	(segment
		(start 66.151252 -46.851062)
		(end 66.453004 -47.152814)
		(width 0.1016)
		(layer "F.Cu")
		(net "M_H_DQ<25>")
	)
	(segment
		(start 62.253368 -40.964612)
		(end 62.418468 -41.129712)
		(width 0.1651)
		(layer "F.Cu")
		(net "M_H_DQ<25>")
	)
	(segment
		(start 72.793352 -48.59909)
		(end 72.526652 -48.33239)
		(width 0.1016)
		(layer "F.Cu")
		(net "M_H_DQ<25>")
	)
	(segment
		(start 78.051406 -50.316384)
		(end 78.020418 -50.285396)
		(width 0.0889)
		(layer "F.Cu")
		(net "M_H_DQ<25>")
	)
	(segment
		(start 61.465968 -40.456612)
		(end 61.465968 -40.799512)
		(width 0.1651)
		(layer "F.Cu")
		(net "M_H_DQ<25>")
	)
	(segment
		(start 62.037468 -38.945312)
		(end 61.872368 -39.110412)
		(width 0.1651)
		(layer "F.Cu")
		(net "M_H_DQ<25>")
	)
	(segment
		(start 62.253368 -38.945312)
		(end 62.037468 -38.945312)
		(width 0.1651)
		(layer "F.Cu")
		(net "M_H_DQ<25>")
	)
	(segment
		(start 62.418468 -41.129712)
		(end 62.418468 -43.118278)
		(width 0.1651)
		(layer "F.Cu")
		(net "M_H_DQ<25>")
	)
	(segment
		(start 62.418468 -38.780212)
		(end 62.253368 -38.945312)
		(width 0.1651)
		(layer "F.Cu")
		(net "M_H_DQ<25>")
	)
	(segment
		(start 61.872368 -39.453312)
		(end 62.037468 -39.618412)
		(width 0.1651)
		(layer "F.Cu")
		(net "M_H_DQ<25>")
	)
	(segment
		(start 61.631068 -40.964612)
		(end 62.253368 -40.964612)
		(width 0.1651)
		(layer "F.Cu")
		(net "M_H_DQ<25>")
	)
	(segment
		(start 62.037468 -39.618412)
		(end 62.253368 -39.618412)
		(width 0.1651)
		(layer "F.Cu")
		(net "M_H_DQ<25>")
	)
	(via
		(at 61.618368 -36.068)
		(size 0.508)
		(drill 0.254)
		(layers "F.Cu" "B.Cu")
		(net "M_H_DQ<25>")
	)
	(via
		(at 61.821568 -12.678156)
		(size 0.508)
		(drill 0.254)
		(layers "F.Cu" "B.Cu")
		(net "M_H_DQ<25>")
	)
	(via
		(at 61.149484 -7.086346)
		(size 0.508)
		(drill 0.254)
		(layers "F.Cu" "B.Cu")
		(net "M_H_DQ<25>")
	)
	(via
		(at 61.821568 -27.161236)
		(size 0.508)
		(drill 0.254)
		(layers "F.Cu" "B.Cu")
		(net "M_H_DQ<25>")
	)
	(segment
		(start 61.999368 -10.623042)
		(end 61.999368 -11.997182)
		(width 0.1651)
		(layer "B.Cu")
		(net "M_H_DQ<25>")
	)
	(segment
		(start 61.821568 -12.174982)
		(end 61.821568 -12.678156)
		(width 0.1651)
		(layer "B.Cu")
		(net "M_H_DQ<25>")
	)
	(segment
		(start 61.999368 -11.997182)
		(end 61.821568 -12.174982)
		(width 0.1651)
		(layer "B.Cu")
		(net "M_H_DQ<25>")
	)
	(segment
		(start 61.662564 -15.690596)
		(end 61.662564 -13.836396)
		(width 0.14224)
		(layer "In4.Cu")
		(net "M_H_DQ<25>")
	)
	(segment
		(start 61.821568 -12.678156)
		(end 62.19571 -12.304014)
		(width 0.14224)
		(layer "In4.Cu")
		(net "M_H_DQ<25>")
	)
	(segment
		(start 62.352174 -8.472424)
		(end 61.98235 -8.1026)
		(width 0.14224)
		(layer "In4.Cu")
		(net "M_H_DQ<25>")
	)
	(segment
		(start 62.19571 -12.304014)
		(end 62.19571 -8.970264)
		(width 0.14224)
		(layer "In4.Cu")
		(net "M_H_DQ<25>")
	)
	(segment
		(start 62.19571 -8.970264)
		(end 62.352174 -8.8138)
		(width 0.14224)
		(layer "In4.Cu")
		(net "M_H_DQ<25>")
	)
	(segment
		(start 62.352174 -8.8138)
		(end 62.352174 -8.472424)
		(width 0.14224)
		(layer "In4.Cu")
		(net "M_H_DQ<25>")
	)
	(segment
		(start 61.306964 -13.480796)
		(end 61.306964 -13.19276)
		(width 0.14224)
		(layer "In4.Cu")
		(net "M_H_DQ<25>")
	)
	(segment
		(start 61.662564 -13.836396)
		(end 61.306964 -13.480796)
		(width 0.14224)
		(layer "In4.Cu")
		(net "M_H_DQ<25>")
	)
	(segment
		(start 61.306964 -13.19276)
		(end 61.821568 -12.678156)
		(width 0.14224)
		(layer "In4.Cu")
		(net "M_H_DQ<25>")
	)
	(segment
		(start 61.821568 -27.161236)
		(end 62.30747 -26.675334)
		(width 0.14224)
		(layer "In4.Cu")
		(net "M_H_DQ<25>")
	)
	(segment
		(start 61.98235 -8.1026)
		(end 61.62675 -8.1026)
		(width 0.14224)
		(layer "In4.Cu")
		(net "M_H_DQ<25>")
	)
	(segment
		(start 61.149484 -7.625334)
		(end 61.149484 -7.086346)
		(width 0.14224)
		(layer "In4.Cu")
		(net "M_H_DQ<25>")
	)
	(segment
		(start 61.62675 -8.1026)
		(end 61.149484 -7.625334)
		(width 0.14224)
		(layer "In4.Cu")
		(net "M_H_DQ<25>")
	)
	(segment
		(start 62.30747 -16.335502)
		(end 61.662564 -15.690596)
		(width 0.14224)
		(layer "In4.Cu")
		(net "M_H_DQ<25>")
	)
	(segment
		(start 62.30747 -26.675334)
		(end 62.30747 -16.335502)
		(width 0.14224)
		(layer "In4.Cu")
		(net "M_H_DQ<25>")
	)
	(segment
		(start 61.999368 -10.422382)
		(end 61.840872 -8.763)
		(width 0.1651)
		(layer "F.Cu")
		(net "M_H_DQ<24>")
	)
	(segment
		(start 60.246768 -30.680914)
		(end 60.246768 -30.338014)
		(width 0.1651)
		(layer "F.Cu")
		(net "M_H_DQ<24>")
	)
	(segment
		(start 60.932568 -32.357314)
		(end 60.767468 -32.192214)
		(width 0.1651)
		(layer "F.Cu")
		(net "M_H_DQ<24>")
	)
	(segment
		(start 76.65466 -48.90389)
		(end 72.66686 -48.90389)
		(width 0.1016)
		(layer "F.Cu")
		(net "M_H_DQ<24>")
	)
	(segment
		(start 65.69202 -47.310294)
		(end 65.691766 -47.310294)
		(width 0.1651)
		(layer "F.Cu")
		(net "M_H_DQ<24>")
	)
	(segment
		(start 60.767468 -32.865314)
		(end 60.932568 -32.700214)
		(width 0.1651)
		(layer "F.Cu")
		(net "M_H_DQ<24>")
	)
	(segment
		(start 60.246768 -31.684214)
		(end 60.411868 -31.519114)
		(width 0.1651)
		(layer "F.Cu")
		(net "M_H_DQ<24>")
	)
	(segment
		(start 65.691766 -47.310294)
		(end 60.757308 -42.375836)
		(width 0.1651)
		(layer "F.Cu")
		(net "M_H_DQ<24>")
	)
	(segment
		(start 60.246768 -32.027114)
		(end 60.246768 -31.684214)
		(width 0.1651)
		(layer "F.Cu")
		(net "M_H_DQ<24>")
	)
	(segment
		(start 61.840872 -8.763)
		(end 61.821568 -8.5598)
		(width 0.1651)
		(layer "F.Cu")
		(net "M_H_DQ<24>")
	)
	(segment
		(start 77.583792 -50.74158)
		(end 77.583792 -49.946814)
		(width 0.0889)
		(layer "F.Cu")
		(net "M_H_DQ<24>")
	)
	(segment
		(start 60.932568 -32.700214)
		(end 60.932568 -32.357314)
		(width 0.1651)
		(layer "F.Cu")
		(net "M_H_DQ<24>")
	)
	(segment
		(start 60.757308 -38.262814)
		(end 60.932568 -38.087554)
		(width 0.1651)
		(layer "F.Cu")
		(net "M_H_DQ<24>")
	)
	(segment
		(start 65.92824 -47.546514)
		(end 65.69202 -47.310294)
		(width 0.1016)
		(layer "F.Cu")
		(net "M_H_DQ<24>")
	)
	(segment
		(start 72.66686 -48.90389)
		(end 72.48906 -48.72609)
		(width 0.1016)
		(layer "F.Cu")
		(net "M_H_DQ<24>")
	)
	(segment
		(start 60.767468 -30.846014)
		(end 60.411868 -30.846014)
		(width 0.1651)
		(layer "F.Cu")
		(net "M_H_DQ<24>")
	)
	(segment
		(start 60.767468 -31.519114)
		(end 60.932568 -31.354014)
		(width 0.1651)
		(layer "F.Cu")
		(net "M_H_DQ<24>")
	)
	(segment
		(start 60.932568 -30.007814)
		(end 60.932568 -28.747974)
		(width 0.1651)
		(layer "F.Cu")
		(net "M_H_DQ<24>")
	)
	(segment
		(start 66.967354 -47.546514)
		(end 65.92824 -47.546514)
		(width 0.1016)
		(layer "F.Cu")
		(net "M_H_DQ<24>")
	)
	(segment
		(start 60.932568 -38.087554)
		(end 60.932568 -34.29)
		(width 0.1651)
		(layer "F.Cu")
		(net "M_H_DQ<24>")
	)
	(segment
		(start 60.932568 -33.703514)
		(end 60.767468 -33.538414)
		(width 0.1651)
		(layer "F.Cu")
		(net "M_H_DQ<24>")
	)
	(segment
		(start 60.246768 -33.373314)
		(end 60.246768 -33.030414)
		(width 0.1651)
		(layer "F.Cu")
		(net "M_H_DQ<24>")
	)
	(segment
		(start 60.411868 -30.172914)
		(end 60.767468 -30.172914)
		(width 0.1651)
		(layer "F.Cu")
		(net "M_H_DQ<24>")
	)
	(segment
		(start 72.48906 -48.72609)
		(end 68.14693 -48.72609)
		(width 0.1016)
		(layer "F.Cu")
		(net "M_H_DQ<24>")
	)
	(segment
		(start 60.411868 -31.519114)
		(end 60.767468 -31.519114)
		(width 0.1651)
		(layer "F.Cu")
		(net "M_H_DQ<24>")
	)
	(segment
		(start 60.411868 -30.846014)
		(end 60.246768 -30.680914)
		(width 0.1651)
		(layer "F.Cu")
		(net "M_H_DQ<24>")
	)
	(segment
		(start 77.583792 -49.833022)
		(end 76.65466 -48.90389)
		(width 0.1016)
		(layer "F.Cu")
		(net "M_H_DQ<24>")
	)
	(segment
		(start 60.411868 -33.538414)
		(end 60.246768 -33.373314)
		(width 0.1651)
		(layer "F.Cu")
		(net "M_H_DQ<24>")
	)
	(segment
		(start 60.932568 -31.011114)
		(end 60.767468 -30.846014)
		(width 0.1651)
		(layer "F.Cu")
		(net "M_H_DQ<24>")
	)
	(segment
		(start 60.932568 -28.747974)
		(end 61.149484 -28.531058)
		(width 0.1651)
		(layer "F.Cu")
		(net "M_H_DQ<24>")
	)
	(segment
		(start 60.246768 -30.338014)
		(end 60.411868 -30.172914)
		(width 0.1651)
		(layer "F.Cu")
		(net "M_H_DQ<24>")
	)
	(segment
		(start 60.767468 -32.192214)
		(end 60.411868 -32.192214)
		(width 0.1651)
		(layer "F.Cu")
		(net "M_H_DQ<24>")
	)
	(segment
		(start 60.411868 -32.865314)
		(end 60.767468 -32.865314)
		(width 0.1651)
		(layer "F.Cu")
		(net "M_H_DQ<24>")
	)
	(segment
		(start 60.246768 -33.030414)
		(end 60.411868 -32.865314)
		(width 0.1651)
		(layer "F.Cu")
		(net "M_H_DQ<24>")
	)
	(segment
		(start 60.767468 -30.172914)
		(end 60.932568 -30.007814)
		(width 0.1651)
		(layer "F.Cu")
		(net "M_H_DQ<24>")
	)
	(segment
		(start 60.932568 -34.29)
		(end 60.932568 -33.703514)
		(width 0.1651)
		(layer "F.Cu")
		(net "M_H_DQ<24>")
	)
	(segment
		(start 77.192886 -51.132486)
		(end 77.583792 -50.74158)
		(width 0.0889)
		(layer "F.Cu")
		(net "M_H_DQ<24>")
	)
	(segment
		(start 60.757308 -42.375836)
		(end 60.757308 -38.262814)
		(width 0.1651)
		(layer "F.Cu")
		(net "M_H_DQ<24>")
	)
	(segment
		(start 60.767468 -33.538414)
		(end 60.411868 -33.538414)
		(width 0.1651)
		(layer "F.Cu")
		(net "M_H_DQ<24>")
	)
	(segment
		(start 60.932568 -31.354014)
		(end 60.932568 -31.011114)
		(width 0.1651)
		(layer "F.Cu")
		(net "M_H_DQ<24>")
	)
	(segment
		(start 68.14693 -48.72609)
		(end 66.967354 -47.546514)
		(width 0.1016)
		(layer "F.Cu")
		(net "M_H_DQ<24>")
	)
	(segment
		(start 77.583792 -49.946814)
		(end 77.583792 -49.833022)
		(width 0.1016)
		(layer "F.Cu")
		(net "M_H_DQ<24>")
	)
	(segment
		(start 60.411868 -32.192214)
		(end 60.246768 -32.027114)
		(width 0.1651)
		(layer "F.Cu")
		(net "M_H_DQ<24>")
	)
	(via
		(at 61.821568 -8.5598)
		(size 0.508)
		(drill 0.254)
		(layers "F.Cu" "B.Cu")
		(net "M_H_DQ<24>")
	)
	(via
		(at 61.149484 -13.959078)
		(size 0.508)
		(drill 0.254)
		(layers "F.Cu" "B.Cu")
		(net "M_H_DQ<24>")
	)
	(via
		(at 61.149484 -28.531058)
		(size 0.508)
		(drill 0.254)
		(layers "F.Cu" "B.Cu")
		(net "M_H_DQ<24>")
	)
	(via
		(at 60.932568 -34.29)
		(size 0.508)
		(drill 0.254)
		(layers "F.Cu" "B.Cu")
		(net "M_H_DQ<24>")
	)
	(segment
		(start 61.149484 -15.222982)
		(end 61.149484 -13.959078)
		(width 0.1651)
		(layer "B.Cu")
		(net "M_H_DQ<24>")
	)
	(segment
		(start 61.637164 -21.682202)
		(end 61.637164 -18.632678)
		(width 0.14224)
		(layer "In4.Cu")
		(net "M_H_DQ<24>")
	)
	(segment
		(start 61.637164 -18.632678)
		(end 61.332364 -18.327878)
		(width 0.14224)
		(layer "In4.Cu")
		(net "M_H_DQ<24>")
	)
	(segment
		(start 61.529468 -10.4521)
		(end 61.186568 -10.1092)
		(width 0.14224)
		(layer "In4.Cu")
		(net "M_H_DQ<24>")
	)
	(segment
		(start 61.32957 -26.955496)
		(end 61.60897 -26.676096)
		(width 0.14224)
		(layer "In4.Cu")
		(net "M_H_DQ<24>")
	)
	(segment
		(start 61.332364 -18.327878)
		(end 61.332364 -17.123156)
		(width 0.14224)
		(layer "In4.Cu")
		(net "M_H_DQ<24>")
	)
	(segment
		(start 61.211968 -10.9982)
		(end 61.529468 -10.6807)
		(width 0.14224)
		(layer "In4.Cu")
		(net "M_H_DQ<24>")
	)
	(segment
		(start 61.63437 -16.475202)
		(end 61.149484 -15.990316)
		(width 0.14224)
		(layer "In4.Cu")
		(net "M_H_DQ<24>")
	)
	(segment
		(start 61.60897 -26.676096)
		(end 61.60897 -23.383748)
		(width 0.14224)
		(layer "In4.Cu")
		(net "M_H_DQ<24>")
	)
	(segment
		(start 61.63437 -16.82115)
		(end 61.63437 -16.475202)
		(width 0.14224)
		(layer "In4.Cu")
		(net "M_H_DQ<24>")
	)
	(segment
		(start 61.211968 -11.302746)
		(end 61.211968 -10.9982)
		(width 0.14224)
		(layer "In4.Cu")
		(net "M_H_DQ<24>")
	)
	(segment
		(start 61.529468 -10.6807)
		(end 61.529468 -10.4521)
		(width 0.14224)
		(layer "In4.Cu")
		(net "M_H_DQ<24>")
	)
	(segment
		(start 61.60897 -23.383748)
		(end 61.25337 -23.028148)
		(width 0.14224)
		(layer "In4.Cu")
		(net "M_H_DQ<24>")
	)
	(segment
		(start 61.332364 -17.123156)
		(end 61.63437 -16.82115)
		(width 0.14224)
		(layer "In4.Cu")
		(net "M_H_DQ<24>")
	)
	(segment
		(start 61.186568 -10.1092)
		(end 61.186568 -9.779254)
		(width 0.14224)
		(layer "In4.Cu")
		(net "M_H_DQ<24>")
	)
	(segment
		(start 61.149484 -28.531058)
		(end 61.32957 -28.350972)
		(width 0.14224)
		(layer "In4.Cu")
		(net "M_H_DQ<24>")
	)
	(segment
		(start 61.25337 -22.065996)
		(end 61.637164 -21.682202)
		(width 0.14224)
		(layer "In4.Cu")
		(net "M_H_DQ<24>")
	)
	(segment
		(start 61.32957 -28.350972)
		(end 61.32957 -26.955496)
		(width 0.14224)
		(layer "In4.Cu")
		(net "M_H_DQ<24>")
	)
	(segment
		(start 61.25337 -23.028148)
		(end 61.25337 -22.065996)
		(width 0.14224)
		(layer "In4.Cu")
		(net "M_H_DQ<24>")
	)
	(segment
		(start 61.60135 -8.780018)
		(end 61.821568 -8.5598)
		(width 0.14224)
		(layer "In4.Cu")
		(net "M_H_DQ<24>")
	)
	(segment
		(start 60.86475 -13.674344)
		(end 60.86475 -12.9286)
		(width 0.14224)
		(layer "In4.Cu")
		(net "M_H_DQ<24>")
	)
	(segment
		(start 61.149484 -15.990316)
		(end 61.149484 -13.959078)
		(width 0.14224)
		(layer "In4.Cu")
		(net "M_H_DQ<24>")
	)
	(segment
		(start 60.86475 -12.9286)
		(end 61.60135 -12.192)
		(width 0.14224)
		(layer "In4.Cu")
		(net "M_H_DQ<24>")
	)
	(segment
		(start 61.149484 -13.959078)
		(end 60.86475 -13.674344)
		(width 0.14224)
		(layer "In4.Cu")
		(net "M_H_DQ<24>")
	)
	(segment
		(start 61.60135 -12.192)
		(end 61.60135 -11.692128)
		(width 0.14224)
		(layer "In4.Cu")
		(net "M_H_DQ<24>")
	)
	(segment
		(start 61.186568 -9.779254)
		(end 61.60135 -9.364472)
		(width 0.14224)
		(layer "In4.Cu")
		(net "M_H_DQ<24>")
	)
	(segment
		(start 61.60135 -11.692128)
		(end 61.211968 -11.302746)
		(width 0.14224)
		(layer "In4.Cu")
		(net "M_H_DQ<24>")
	)
	(segment
		(start 61.60135 -9.364472)
		(end 61.60135 -8.780018)
		(width 0.14224)
		(layer "In4.Cu")
		(net "M_H_DQ<24>")
	)
	(segment
		(start 74.617326 -53.60924)
		(end 74.045826 -53.60924)
		(width 0.1016)
		(layer "F.Cu")
		(net "M_H_DQ<23>")
	)
	(segment
		(start 56.049418 -5.822442)
		(end 56.049418 -7.086346)
		(width 0.1651)
		(layer "F.Cu")
		(net "M_H_DQ<23>")
	)
	(via
		(at 56.049418 -7.086346)
		(size 0.508)
		(drill 0.254)
		(layers "F.Cu" "B.Cu")
		(net "M_H_DQ<23>")
	)
	(via
		(at 56.899302 -12.678156)
		(size 0.508)
		(drill 0.254)
		(layers "F.Cu" "B.Cu")
		(net "M_H_DQ<23>")
	)
	(via
		(at 74.045826 -53.60924)
		(size 0.508)
		(drill 0.254)
		(layers "F.Cu" "B.Cu")
		(net "M_H_DQ<23>")
	)
	(segment
		(start 56.899302 -11.110976)
		(end 56.899302 -12.678156)
		(width 0.1651)
		(layer "B.Cu")
		(net "M_H_DQ<23>")
	)
	(segment
		(start 56.899556 -11.110722)
		(end 56.899302 -11.110976)
		(width 0.1651)
		(layer "B.Cu")
		(net "M_H_DQ<23>")
	)
	(segment
		(start 56.899556 -10.623042)
		(end 56.899556 -11.110722)
		(width 0.1651)
		(layer "B.Cu")
		(net "M_H_DQ<23>")
	)
	(segment
		(start 66.302382 -36.954714)
		(end 66.52133 -36.954714)
		(width 0.14224)
		(layer "In4.Cu")
		(net "M_H_DQ<23>")
	)
	(segment
		(start 57.480708 -18.361914)
		(end 57.252108 -18.590514)
		(width 0.14224)
		(layer "In4.Cu")
		(net "M_H_DQ<23>")
	)
	(segment
		(start 74.484992 -50.216816)
		(end 74.557636 -50.342038)
		(width 0.0889)
		(layer "In4.Cu")
		(net "M_H_DQ<23>")
	)
	(segment
		(start 66.867532 -36.608512)
		(end 67.08648 -36.608512)
		(width 0.14224)
		(layer "In4.Cu")
		(net "M_H_DQ<23>")
	)
	(segment
		(start 67.08648 -36.608512)
		(end 67.336416 -36.858448)
		(width 0.14224)
		(layer "In4.Cu")
		(net "M_H_DQ<23>")
	)
	(segment
		(start 57.630568 -20.955)
		(end 57.252108 -21.33346)
		(width 0.14224)
		(layer "In4.Cu")
		(net "M_H_DQ<23>")
	)
	(segment
		(start 70.978268 -46.267624)
		(end 70.978268 -46.724062)
		(width 0.14224)
		(layer "In4.Cu")
		(net "M_H_DQ<23>")
	)
	(segment
		(start 57.579768 -15.0368)
		(end 57.579768 -16.129)
		(width 0.14224)
		(layer "In4.Cu")
		(net "M_H_DQ<23>")
	)
	(segment
		(start 67.600068 -42.889424)
		(end 70.978268 -46.267624)
		(width 0.14224)
		(layer "In4.Cu")
		(net "M_H_DQ<23>")
	)
	(segment
		(start 56.950356 -8.0518)
		(end 57.407556 -8.509)
		(width 0.14224)
		(layer "In4.Cu")
		(net "M_H_DQ<23>")
	)
	(segment
		(start 74.563986 -50.92192)
		(end 74.557636 -50.932588)
		(width 0.0889)
		(layer "In4.Cu")
		(net "M_H_DQ<23>")
	)
	(segment
		(start 57.681368 -24.1808)
		(end 57.681368 -29.568902)
		(width 0.14224)
		(layer "In4.Cu")
		(net "M_H_DQ<23>")
	)
	(segment
		(start 60.332366 -32.2199)
		(end 61.567568 -32.2199)
		(width 0.14224)
		(layer "In4.Cu")
		(net "M_H_DQ<23>")
	)
	(segment
		(start 56.366156 -7.403084)
		(end 56.366156 -7.7216)
		(width 0.14224)
		(layer "In4.Cu")
		(net "M_H_DQ<23>")
	)
	(segment
		(start 74.557636 -51.923442)
		(end 74.557636 -51.923696)
		(width 0.0889)
		(layer "In4.Cu")
		(net "M_H_DQ<23>")
	)
	(segment
		(start 70.978268 -46.724062)
		(end 71.535036 -47.28083)
		(width 0.14224)
		(layer "In4.Cu")
		(net "M_H_DQ<23>")
	)
	(segment
		(start 67.600068 -38.2524)
		(end 67.600068 -42.889424)
		(width 0.14224)
		(layer "In4.Cu")
		(net "M_H_DQ<23>")
	)
	(segment
		(start 56.439308 -13.13815)
		(end 56.439308 -13.60932)
		(width 0.14224)
		(layer "In4.Cu")
		(net "M_H_DQ<23>")
	)
	(segment
		(start 56.439308 -13.60932)
		(end 56.807608 -13.97762)
		(width 0.14224)
		(layer "In4.Cu")
		(net "M_H_DQ<23>")
	)
	(segment
		(start 57.407556 -8.8646)
		(end 57.252108 -9.020048)
		(width 0.14224)
		(layer "In4.Cu")
		(net "M_H_DQ<23>")
	)
	(segment
		(start 57.455308 -23.118572)
		(end 57.277508 -23.296372)
		(width 0.14224)
		(layer "In4.Cu")
		(net "M_H_DQ<23>")
	)
	(segment
		(start 57.252108 -12.32535)
		(end 56.899302 -12.678156)
		(width 0.14224)
		(layer "In4.Cu")
		(net "M_H_DQ<23>")
	)
	(segment
		(start 74.392536 -52.818792)
		(end 74.045826 -53.60924)
		(width 0.0889)
		(layer "In4.Cu")
		(net "M_H_DQ<23>")
	)
	(segment
		(start 57.579768 -16.129)
		(end 57.274968 -16.4338)
		(width 0.14224)
		(layer "In4.Cu")
		(net "M_H_DQ<23>")
	)
	(segment
		(start 57.455308 -21.975572)
		(end 57.455308 -23.118572)
		(width 0.14224)
		(layer "In4.Cu")
		(net "M_H_DQ<23>")
	)
	(segment
		(start 66.990214 -37.642546)
		(end 67.600068 -38.2524)
		(width 0.14224)
		(layer "In4.Cu")
		(net "M_H_DQ<23>")
	)
	(segment
		(start 57.252108 -9.020048)
		(end 57.252108 -12.32535)
		(width 0.14224)
		(layer "In4.Cu")
		(net "M_H_DQ<23>")
	)
	(segment
		(start 74.557636 -50.932588)
		(end 74.55281 -50.941224)
		(width 0.0889)
		(layer "In4.Cu")
		(net "M_H_DQ<23>")
	)
	(segment
		(start 57.407556 -8.509)
		(end 57.407556 -8.8646)
		(width 0.14224)
		(layer "In4.Cu")
		(net "M_H_DQ<23>")
	)
	(segment
		(start 66.990214 -37.423598)
		(end 66.990214 -37.642546)
		(width 0.14224)
		(layer "In4.Cu")
		(net "M_H_DQ<23>")
	)
	(segment
		(start 56.807608 -13.97762)
		(end 56.807608 -14.26464)
		(width 0.14224)
		(layer "In4.Cu")
		(net "M_H_DQ<23>")
	)
	(segment
		(start 66.52133 -36.954714)
		(end 66.867532 -36.608512)
		(width 0.14224)
		(layer "In4.Cu")
		(net "M_H_DQ<23>")
	)
	(segment
		(start 61.567568 -32.2199)
		(end 66.302382 -36.954714)
		(width 0.14224)
		(layer "In4.Cu")
		(net "M_H_DQ<23>")
	)
	(segment
		(start 71.535036 -47.499524)
		(end 72.013826 -47.978314)
		(width 0.0889)
		(layer "In4.Cu")
		(net "M_H_DQ<23>")
	)
	(segment
		(start 71.535036 -47.28083)
		(end 71.535036 -47.499524)
		(width 0.0889)
		(layer "In4.Cu")
		(net "M_H_DQ<23>")
	)
	(segment
		(start 56.366156 -7.7216)
		(end 56.696356 -8.0518)
		(width 0.14224)
		(layer "In4.Cu")
		(net "M_H_DQ<23>")
	)
	(segment
		(start 57.480708 -17.082262)
		(end 57.480708 -18.361914)
		(width 0.14224)
		(layer "In4.Cu")
		(net "M_H_DQ<23>")
	)
	(segment
		(start 57.277508 -23.296372)
		(end 57.277508 -23.77694)
		(width 0.14224)
		(layer "In4.Cu")
		(net "M_H_DQ<23>")
	)
	(segment
		(start 57.681368 -29.568902)
		(end 60.332366 -32.2199)
		(width 0.14224)
		(layer "In4.Cu")
		(net "M_H_DQ<23>")
	)
	(segment
		(start 56.899302 -12.678156)
		(end 56.439308 -13.13815)
		(width 0.14224)
		(layer "In4.Cu")
		(net "M_H_DQ<23>")
	)
	(segment
		(start 57.274968 -16.4338)
		(end 57.274968 -16.876522)
		(width 0.14224)
		(layer "In4.Cu")
		(net "M_H_DQ<23>")
	)
	(segment
		(start 56.807608 -14.26464)
		(end 57.579768 -15.0368)
		(width 0.14224)
		(layer "In4.Cu")
		(net "M_H_DQ<23>")
	)
	(segment
		(start 74.484992 -49.710086)
		(end 74.484992 -50.216816)
		(width 0.0889)
		(layer "In4.Cu")
		(net "M_H_DQ<23>")
	)
	(segment
		(start 57.630568 -19.35226)
		(end 57.630568 -20.955)
		(width 0.14224)
		(layer "In4.Cu")
		(net "M_H_DQ<23>")
	)
	(segment
		(start 57.252108 -18.590514)
		(end 57.252108 -18.9738)
		(width 0.14224)
		(layer "In4.Cu")
		(net "M_H_DQ<23>")
	)
	(segment
		(start 57.252108 -21.772372)
		(end 57.455308 -21.975572)
		(width 0.14224)
		(layer "In4.Cu")
		(net "M_H_DQ<23>")
	)
	(segment
		(start 72.013826 -47.978314)
		(end 72.75322 -47.978314)
		(width 0.0889)
		(layer "In4.Cu")
		(net "M_H_DQ<23>")
	)
	(segment
		(start 57.274968 -16.876522)
		(end 57.480708 -17.082262)
		(width 0.14224)
		(layer "In4.Cu")
		(net "M_H_DQ<23>")
	)
	(segment
		(start 57.252108 -21.33346)
		(end 57.252108 -21.772372)
		(width 0.14224)
		(layer "In4.Cu")
		(net "M_H_DQ<23>")
	)
	(segment
		(start 57.277508 -23.77694)
		(end 57.681368 -24.1808)
		(width 0.14224)
		(layer "In4.Cu")
		(net "M_H_DQ<23>")
	)
	(segment
		(start 56.049418 -7.086346)
		(end 56.366156 -7.403084)
		(width 0.14224)
		(layer "In4.Cu")
		(net "M_H_DQ<23>")
	)
	(segment
		(start 67.336416 -36.858448)
		(end 67.336416 -37.077396)
		(width 0.14224)
		(layer "In4.Cu")
		(net "M_H_DQ<23>")
	)
	(segment
		(start 67.336416 -37.077396)
		(end 66.990214 -37.423598)
		(width 0.14224)
		(layer "In4.Cu")
		(net "M_H_DQ<23>")
	)
	(segment
		(start 72.75322 -47.978314)
		(end 74.484992 -49.710086)
		(width 0.0889)
		(layer "In4.Cu")
		(net "M_H_DQ<23>")
	)
	(segment
		(start 57.252108 -18.9738)
		(end 57.630568 -19.35226)
		(width 0.14224)
		(layer "In4.Cu")
		(net "M_H_DQ<23>")
	)
	(segment
		(start 56.696356 -8.0518)
		(end 56.950356 -8.0518)
		(width 0.14224)
		(layer "In4.Cu")
		(net "M_H_DQ<23>")
	)
	(arc
		(start 74.557636 -51.332638)
		(mid 74.636767 -51.62804)
		(end 74.557636 -51.923442)
		(width 0.0889)
		(layer "In4.Cu")
		(net "M_H_DQ<23>")
	)
	(arc
		(start 74.557636 -50.342038)
		(mid 74.636858 -50.631156)
		(end 74.563986 -50.92192)
		(width 0.0889)
		(layer "In4.Cu")
		(net "M_H_DQ<23>")
	)
	(arc
		(start 74.557636 -51.923696)
		(mid 74.44539 -52.226972)
		(end 74.440034 -52.550314)
		(width 0.0889)
		(layer "In4.Cu")
		(net "M_H_DQ<23>")
	)
	(arc
		(start 74.440034 -52.550314)
		(mid 74.439817 -52.688709)
		(end 74.392536 -52.818792)
		(width 0.0889)
		(layer "In4.Cu")
		(net "M_H_DQ<23>")
	)
	(arc
		(start 74.55281 -50.941224)
		(mid 74.504055 -51.137576)
		(end 74.557636 -51.332638)
		(width 0.0889)
		(layer "In4.Cu")
		(net "M_H_DQ<23>")
	)
	(segment
		(start 56.899556 -8.661654)
		(end 56.899302 -8.6614)
		(width 0.1651)
		(layer "F.Cu")
		(net "M_H_DQ<22>")
	)
	(segment
		(start 56.899556 -10.422382)
		(end 56.899556 -9.4488)
		(width 0.1651)
		(layer "F.Cu")
		(net "M_H_DQ<22>")
	)
	(segment
		(start 56.899556 -8.9662)
		(end 56.899556 -8.661654)
		(width 0.1651)
		(layer "F.Cu")
		(net "M_H_DQ<22>")
	)
	(segment
		(start 74.617326 -51.62804)
		(end 74.045826 -51.62804)
		(width 0.1016)
		(layer "F.Cu")
		(net "M_H_DQ<22>")
	)
	(segment
		(start 56.899556 -9.4488)
		(end 57.031636 -9.31672)
		(width 0.1651)
		(layer "F.Cu")
		(net "M_H_DQ<22>")
	)
	(segment
		(start 57.031636 -9.09828)
		(end 56.899556 -8.9662)
		(width 0.1651)
		(layer "F.Cu")
		(net "M_H_DQ<22>")
	)
	(segment
		(start 57.031636 -9.31672)
		(end 57.031636 -9.09828)
		(width 0.1651)
		(layer "F.Cu")
		(net "M_H_DQ<22>")
	)
	(via
		(at 74.045826 -51.62804)
		(size 0.508)
		(drill 0.254)
		(layers "F.Cu" "B.Cu")
		(net "M_H_DQ<22>")
	)
	(via
		(at 56.049418 -13.959078)
		(size 0.508)
		(drill 0.254)
		(layers "F.Cu" "B.Cu")
		(net "M_H_DQ<22>")
	)
	(via
		(at 56.899302 -8.6614)
		(size 0.508)
		(drill 0.254)
		(layers "F.Cu" "B.Cu")
		(net "M_H_DQ<22>")
	)
	(segment
		(start 56.049418 -15.222982)
		(end 56.049418 -13.959078)
		(width 0.1651)
		(layer "B.Cu")
		(net "M_H_DQ<22>")
	)
	(segment
		(start 57.020968 -25.092406)
		(end 57.020968 -24.686006)
		(width 0.14224)
		(layer "In4.Cu")
		(net "M_H_DQ<22>")
	)
	(segment
		(start 56.843168 -20.397216)
		(end 57.046368 -20.194016)
		(width 0.14224)
		(layer "In4.Cu")
		(net "M_H_DQ<22>")
	)
	(segment
		(start 56.524906 -9.313672)
		(end 56.524906 -9.035796)
		(width 0.14224)
		(layer "In4.Cu")
		(net "M_H_DQ<22>")
	)
	(segment
		(start 56.512968 -19.381216)
		(end 56.512968 -18.542254)
		(width 0.14224)
		(layer "In4.Cu")
		(net "M_H_DQ<22>")
	)
	(segment
		(start 74.294492 -49.78908)
		(end 72.674226 -48.168814)
		(width 0.0889)
		(layer "In4.Cu")
		(net "M_H_DQ<22>")
	)
	(segment
		(start 74.045826 -51.62804)
		(end 74.3839 -51.62804)
		(width 0.0889)
		(layer "In4.Cu")
		(net "M_H_DQ<22>")
	)
	(segment
		(start 56.436768 -26.921206)
		(end 56.817768 -26.921206)
		(width 0.14224)
		(layer "In4.Cu")
		(net "M_H_DQ<22>")
	)
	(segment
		(start 56.817768 -27.734006)
		(end 56.436768 -27.734006)
		(width 0.14224)
		(layer "In4.Cu")
		(net "M_H_DQ<22>")
	)
	(segment
		(start 57.046368 -19.787616)
		(end 56.843168 -19.584416)
		(width 0.14224)
		(layer "In4.Cu")
		(net "M_H_DQ<22>")
	)
	(segment
		(start 57.020968 -26.311606)
		(end 56.817768 -26.108406)
		(width 0.14224)
		(layer "In4.Cu")
		(net "M_H_DQ<22>")
	)
	(segment
		(start 74.392536 -50.837338)
		(end 74.397362 -50.828702)
		(width 0.0889)
		(layer "In4.Cu")
		(net "M_H_DQ<22>")
	)
	(segment
		(start 61.364876 -33.350708)
		(end 61.145928 -33.350708)
		(width 0.14224)
		(layer "In4.Cu")
		(net "M_H_DQ<22>")
	)
	(segment
		(start 56.413908 -16.993362)
		(end 56.566308 -16.840962)
		(width 0.14224)
		(layer "In4.Cu")
		(net "M_H_DQ<22>")
	)
	(segment
		(start 56.160924 -9.988296)
		(end 56.160924 -9.677654)
		(width 0.14224)
		(layer "In4.Cu")
		(net "M_H_DQ<22>")
	)
	(segment
		(start 74.392536 -50.437288)
		(end 74.294492 -50.267616)
		(width 0.0889)
		(layer "In4.Cu")
		(net "M_H_DQ<22>")
	)
	(segment
		(start 56.436768 -25.295606)
		(end 56.817768 -25.295606)
		(width 0.14224)
		(layer "In4.Cu")
		(net "M_H_DQ<22>")
	)
	(segment
		(start 61.433964 -34.219388)
		(end 61.433964 -34.00044)
		(width 0.14224)
		(layer "In4.Cu")
		(net "M_H_DQ<22>")
	)
	(segment
		(start 56.413908 -23.169372)
		(end 56.413908 -21.975572)
		(width 0.14224)
		(layer "In4.Cu")
		(net "M_H_DQ<22>")
	)
	(segment
		(start 55.771796 -14.524228)
		(end 55.771796 -14.2367)
		(width 0.14224)
		(layer "In4.Cu")
		(net "M_H_DQ<22>")
	)
	(segment
		(start 56.817768 -28.546806)
		(end 57.020968 -28.343606)
		(width 0.14224)
		(layer "In4.Cu")
		(net "M_H_DQ<22>")
	)
	(segment
		(start 56.512968 -20.600416)
		(end 56.716168 -20.397216)
		(width 0.14224)
		(layer "In4.Cu")
		(net "M_H_DQ<22>")
	)
	(segment
		(start 61.433964 -34.00044)
		(end 61.614812 -33.819592)
		(width 0.14224)
		(layer "In4.Cu")
		(net "M_H_DQ<22>")
	)
	(segment
		(start 56.566308 -16.840962)
		(end 56.566308 -15.92326)
		(width 0.14224)
		(layer "In4.Cu")
		(net "M_H_DQ<22>")
	)
	(segment
		(start 60.746132 -33.531556)
		(end 56.411368 -29.196792)
		(width 0.14224)
		(layer "In4.Cu")
		(net "M_H_DQ<22>")
	)
	(segment
		(start 74.294492 -50.267616)
		(end 74.294492 -49.78908)
		(width 0.0889)
		(layer "In4.Cu")
		(net "M_H_DQ<22>")
	)
	(segment
		(start 56.160924 -9.677654)
		(end 56.524906 -9.313672)
		(width 0.14224)
		(layer "In4.Cu")
		(net "M_H_DQ<22>")
	)
	(segment
		(start 56.769762 -24.4348)
		(end 56.622696 -24.4348)
		(width 0.14224)
		(layer "In4.Cu")
		(net "M_H_DQ<22>")
	)
	(segment
		(start 70.267068 -46.454568)
		(end 66.977768 -43.165268)
		(width 0.14224)
		(layer "In4.Cu")
		(net "M_H_DQ<22>")
	)
	(segment
		(start 56.817768 -26.921206)
		(end 57.020968 -26.718006)
		(width 0.14224)
		(layer "In4.Cu")
		(net "M_H_DQ<22>")
	)
	(segment
		(start 56.515508 -23.84806)
		(end 56.515508 -23.270972)
		(width 0.14224)
		(layer "In4.Cu")
		(net "M_H_DQ<22>")
	)
	(segment
		(start 74.3839 -51.62804)
		(end 74.441812 -51.570128)
		(width 0.0889)
		(layer "In4.Cu")
		(net "M_H_DQ<22>")
	)
	(segment
		(start 60.96508 -33.531556)
		(end 60.746132 -33.531556)
		(width 0.14224)
		(layer "In4.Cu")
		(net "M_H_DQ<22>")
	)
	(segment
		(start 56.716168 -20.397216)
		(end 56.843168 -20.397216)
		(width 0.14224)
		(layer "In4.Cu")
		(net "M_H_DQ<22>")
	)
	(segment
		(start 66.977768 -43.165268)
		(end 66.977768 -39.763192)
		(width 0.14224)
		(layer "In4.Cu")
		(net "M_H_DQ<22>")
	)
	(segment
		(start 57.020968 -26.718006)
		(end 57.020968 -26.311606)
		(width 0.14224)
		(layer "In4.Cu")
		(net "M_H_DQ<22>")
	)
	(segment
		(start 56.233568 -27.530806)
		(end 56.233568 -27.124406)
		(width 0.14224)
		(layer "In4.Cu")
		(net "M_H_DQ<22>")
	)
	(segment
		(start 56.566308 -15.92326)
		(end 56.843168 -15.6464)
		(width 0.14224)
		(layer "In4.Cu")
		(net "M_H_DQ<22>")
	)
	(segment
		(start 55.771796 -14.2367)
		(end 56.049418 -13.959078)
		(width 0.14224)
		(layer "In4.Cu")
		(net "M_H_DQ<22>")
	)
	(segment
		(start 56.160924 -11.093704)
		(end 56.541924 -10.712704)
		(width 0.14224)
		(layer "In4.Cu")
		(net "M_H_DQ<22>")
	)
	(segment
		(start 56.524906 -9.035796)
		(end 56.899302 -8.6614)
		(width 0.14224)
		(layer "In4.Cu")
		(net "M_H_DQ<22>")
	)
	(segment
		(start 56.586374 -11.804396)
		(end 56.160924 -11.378946)
		(width 0.14224)
		(layer "In4.Cu")
		(net "M_H_DQ<22>")
	)
	(segment
		(start 72.674226 -48.168814)
		(end 71.934832 -48.168814)
		(width 0.0889)
		(layer "In4.Cu")
		(net "M_H_DQ<22>")
	)
	(segment
		(start 55.813706 -12.928854)
		(end 56.586374 -12.156186)
		(width 0.14224)
		(layer "In4.Cu")
		(net "M_H_DQ<22>")
	)
	(segment
		(start 57.020968 -28.343606)
		(end 57.020968 -27.937206)
		(width 0.14224)
		(layer "In4.Cu")
		(net "M_H_DQ<22>")
	)
	(segment
		(start 56.843168 -19.584416)
		(end 56.716168 -19.584416)
		(width 0.14224)
		(layer "In4.Cu")
		(net "M_H_DQ<22>")
	)
	(segment
		(start 56.233568 -25.905206)
		(end 56.233568 -25.498806)
		(width 0.14224)
		(layer "In4.Cu")
		(net "M_H_DQ<22>")
	)
	(segment
		(start 56.622696 -24.4348)
		(end 56.419496 -24.2316)
		(width 0.14224)
		(layer "In4.Cu")
		(net "M_H_DQ<22>")
	)
	(segment
		(start 57.046368 -20.194016)
		(end 57.046368 -19.787616)
		(width 0.14224)
		(layer "In4.Cu")
		(net "M_H_DQ<22>")
	)
	(segment
		(start 56.160924 -11.378946)
		(end 56.160924 -11.093704)
		(width 0.14224)
		(layer "In4.Cu")
		(net "M_H_DQ<22>")
	)
	(segment
		(start 56.541924 -10.712704)
		(end 56.541924 -10.369296)
		(width 0.14224)
		(layer "In4.Cu")
		(net "M_H_DQ<22>")
	)
	(segment
		(start 55.813706 -13.723366)
		(end 55.813706 -12.928854)
		(width 0.14224)
		(layer "In4.Cu")
		(net "M_H_DQ<22>")
	)
	(segment
		(start 56.817768 -25.295606)
		(end 57.020968 -25.092406)
		(width 0.14224)
		(layer "In4.Cu")
		(net "M_H_DQ<22>")
	)
	(segment
		(start 56.411368 -28.689046)
		(end 56.553608 -28.546806)
		(width 0.14224)
		(layer "In4.Cu")
		(net "M_H_DQ<22>")
	)
	(segment
		(start 61.145928 -33.350708)
		(end 60.96508 -33.531556)
		(width 0.14224)
		(layer "In4.Cu")
		(net "M_H_DQ<22>")
	)
	(segment
		(start 56.419496 -23.944072)
		(end 56.515508 -23.84806)
		(width 0.14224)
		(layer "In4.Cu")
		(net "M_H_DQ<22>")
	)
	(segment
		(start 61.614812 -33.819592)
		(end 61.614812 -33.600644)
		(width 0.14224)
		(layer "In4.Cu")
		(net "M_H_DQ<22>")
	)
	(segment
		(start 56.843168 -15.6464)
		(end 56.843168 -15.2146)
		(width 0.14224)
		(layer "In4.Cu")
		(net "M_H_DQ<22>")
	)
	(segment
		(start 57.020968 -24.686006)
		(end 56.769762 -24.4348)
		(width 0.14224)
		(layer "In4.Cu")
		(net "M_H_DQ<22>")
	)
	(segment
		(start 55.966868 -14.7193)
		(end 55.771796 -14.524228)
		(width 0.14224)
		(layer "In4.Cu")
		(net "M_H_DQ<22>")
	)
	(segment
		(start 56.419496 -24.2316)
		(end 56.419496 -23.944072)
		(width 0.14224)
		(layer "In4.Cu")
		(net "M_H_DQ<22>")
	)
	(segment
		(start 56.817768 -26.108406)
		(end 56.436768 -26.108406)
		(width 0.14224)
		(layer "In4.Cu")
		(net "M_H_DQ<22>")
	)
	(segment
		(start 56.553608 -28.546806)
		(end 56.817768 -28.546806)
		(width 0.14224)
		(layer "In4.Cu")
		(net "M_H_DQ<22>")
	)
	(segment
		(start 66.977768 -39.763192)
		(end 61.433964 -34.219388)
		(width 0.14224)
		(layer "In4.Cu")
		(net "M_H_DQ<22>")
	)
	(segment
		(start 56.049418 -13.959078)
		(end 55.813706 -13.723366)
		(width 0.14224)
		(layer "In4.Cu")
		(net "M_H_DQ<22>")
	)
	(segment
		(start 57.020968 -27.937206)
		(end 56.817768 -27.734006)
		(width 0.14224)
		(layer "In4.Cu")
		(net "M_H_DQ<22>")
	)
	(segment
		(start 61.614812 -33.600644)
		(end 61.364876 -33.350708)
		(width 0.14224)
		(layer "In4.Cu")
		(net "M_H_DQ<22>")
	)
	(segment
		(start 71.934832 -48.168814)
		(end 71.50735 -47.741332)
		(width 0.0889)
		(layer "In4.Cu")
		(net "M_H_DQ<22>")
	)
	(segment
		(start 56.515508 -23.270972)
		(end 56.413908 -23.169372)
		(width 0.14224)
		(layer "In4.Cu")
		(net "M_H_DQ<22>")
	)
	(segment
		(start 56.436768 -26.108406)
		(end 56.233568 -25.905206)
		(width 0.14224)
		(layer "In4.Cu")
		(net "M_H_DQ<22>")
	)
	(segment
		(start 56.436768 -27.734006)
		(end 56.233568 -27.530806)
		(width 0.14224)
		(layer "In4.Cu")
		(net "M_H_DQ<22>")
	)
	(segment
		(start 56.541924 -10.369296)
		(end 56.160924 -9.988296)
		(width 0.14224)
		(layer "In4.Cu")
		(net "M_H_DQ<22>")
	)
	(segment
		(start 56.512968 -18.542254)
		(end 56.413908 -18.443194)
		(width 0.14224)
		(layer "In4.Cu")
		(net "M_H_DQ<22>")
	)
	(segment
		(start 71.50735 -47.741332)
		(end 71.097394 -47.741332)
		(width 0.0889)
		(layer "In4.Cu")
		(net "M_H_DQ<22>")
	)
	(segment
		(start 56.413908 -18.443194)
		(end 56.413908 -16.993362)
		(width 0.14224)
		(layer "In4.Cu")
		(net "M_H_DQ<22>")
	)
	(segment
		(start 56.413908 -21.975572)
		(end 56.512968 -21.876512)
		(width 0.14224)
		(layer "In4.Cu")
		(net "M_H_DQ<22>")
	)
	(segment
		(start 71.097394 -47.741332)
		(end 70.267068 -46.911006)
		(width 0.14224)
		(layer "In4.Cu")
		(net "M_H_DQ<22>")
	)
	(segment
		(start 74.386186 -50.848006)
		(end 74.392536 -50.837338)
		(width 0.0889)
		(layer "In4.Cu")
		(net "M_H_DQ<22>")
	)
	(segment
		(start 56.512968 -21.876512)
		(end 56.512968 -20.600416)
		(width 0.14224)
		(layer "In4.Cu")
		(net "M_H_DQ<22>")
	)
	(segment
		(start 56.347868 -14.7193)
		(end 55.966868 -14.7193)
		(width 0.14224)
		(layer "In4.Cu")
		(net "M_H_DQ<22>")
	)
	(segment
		(start 56.233568 -27.124406)
		(end 56.436768 -26.921206)
		(width 0.14224)
		(layer "In4.Cu")
		(net "M_H_DQ<22>")
	)
	(segment
		(start 56.586374 -12.156186)
		(end 56.586374 -11.804396)
		(width 0.14224)
		(layer "In4.Cu")
		(net "M_H_DQ<22>")
	)
	(segment
		(start 70.267068 -46.911006)
		(end 70.267068 -46.454568)
		(width 0.14224)
		(layer "In4.Cu")
		(net "M_H_DQ<22>")
	)
	(segment
		(start 56.843168 -15.2146)
		(end 56.347868 -14.7193)
		(width 0.14224)
		(layer "In4.Cu")
		(net "M_H_DQ<22>")
	)
	(segment
		(start 56.411368 -29.196792)
		(end 56.411368 -28.689046)
		(width 0.14224)
		(layer "In4.Cu")
		(net "M_H_DQ<22>")
	)
	(segment
		(start 56.233568 -25.498806)
		(end 56.436768 -25.295606)
		(width 0.14224)
		(layer "In4.Cu")
		(net "M_H_DQ<22>")
	)
	(segment
		(start 56.716168 -19.584416)
		(end 56.512968 -19.381216)
		(width 0.14224)
		(layer "In4.Cu")
		(net "M_H_DQ<22>")
	)
	(arc
		(start 74.392536 -51.427888)
		(mid 74.313314 -51.13877)
		(end 74.386186 -50.848006)
		(width 0.0889)
		(layer "In4.Cu")
		(net "M_H_DQ<22>")
	)
	(arc
		(start 74.41946 -51.484276)
		(mid 74.407115 -51.455549)
		(end 74.392536 -51.427888)
		(width 0.0889)
		(layer "In4.Cu")
		(net "M_H_DQ<22>")
	)
	(arc
		(start 74.397362 -50.828702)
		(mid 74.446117 -50.63235)
		(end 74.392536 -50.437288)
		(width 0.0889)
		(layer "In4.Cu")
		(net "M_H_DQ<22>")
	)
	(arc
		(start 74.441812 -51.570128)
		(mid 74.433013 -51.526584)
		(end 74.41946 -51.484276)
		(width 0.0889)
		(layer "In4.Cu")
		(net "M_H_DQ<22>")
	)
	(segment
		(start 50.099468 -5.822442)
		(end 50.099468 -7.086346)
		(width 0.1651)
		(layer "F.Cu")
		(net "M_H_DQ<21>")
	)
	(segment
		(start 72.041766 -53.113686)
		(end 71.470266 -53.113686)
		(width 0.1016)
		(layer "F.Cu")
		(net "M_H_DQ<21>")
	)
	(via
		(at 50.099468 -7.086346)
		(size 0.508)
		(drill 0.254)
		(layers "F.Cu" "B.Cu")
		(net "M_H_DQ<21>")
	)
	(via
		(at 50.873152 -12.678156)
		(size 0.508)
		(drill 0.254)
		(layers "F.Cu" "B.Cu")
		(net "M_H_DQ<21>")
	)
	(via
		(at 71.470266 -53.113686)
		(size 0.508)
		(drill 0.254)
		(layers "F.Cu" "B.Cu")
		(net "M_H_DQ<21>")
	)
	(segment
		(start 50.949352 -12.601956)
		(end 50.873152 -12.678156)
		(width 0.1651)
		(layer "B.Cu")
		(net "M_H_DQ<21>")
	)
	(segment
		(start 50.949352 -10.623042)
		(end 50.949352 -12.601956)
		(width 0.1651)
		(layer "B.Cu")
		(net "M_H_DQ<21>")
	)
	(segment
		(start 51.257708 -18.976086)
		(end 51.610768 -19.329146)
		(width 0.14224)
		(layer "In4.Cu")
		(net "M_H_DQ<21>")
	)
	(segment
		(start 50.797968 -15.584424)
		(end 51.283108 -16.069564)
		(width 0.14224)
		(layer "In4.Cu")
		(net "M_H_DQ<21>")
	)
	(segment
		(start 65.815464 -48.775366)
		(end 66.915538 -49.87544)
		(width 0.0889)
		(layer "In4.Cu")
		(net "M_H_DQ<21>")
	)
	(segment
		(start 50.981102 -8.0518)
		(end 51.381406 -8.452104)
		(width 0.14224)
		(layer "In4.Cu")
		(net "M_H_DQ<21>")
	)
	(segment
		(start 51.184556 -12.366752)
		(end 50.873152 -12.678156)
		(width 0.14224)
		(layer "In4.Cu")
		(net "M_H_DQ<21>")
	)
	(segment
		(start 53.680868 -31.4833)
		(end 53.680868 -32.695642)
		(width 0.14224)
		(layer "In4.Cu")
		(net "M_H_DQ<21>")
	)
	(segment
		(start 51.610768 -19.329146)
		(end 51.610768 -20.904454)
		(width 0.14224)
		(layer "In4.Cu")
		(net "M_H_DQ<21>")
	)
	(segment
		(start 65.585086 -47.845218)
		(end 65.585086 -48.544988)
		(width 0.0889)
		(layer "In4.Cu")
		(net "M_H_DQ<21>")
	)
	(segment
		(start 62.227968 -41.242742)
		(end 62.227968 -43.877738)
		(width 0.14224)
		(layer "In4.Cu")
		(net "M_H_DQ<21>")
	)
	(segment
		(start 50.797968 -15.2654)
		(end 50.797968 -15.584424)
		(width 0.14224)
		(layer "In4.Cu")
		(net "M_H_DQ<21>")
	)
	(segment
		(start 65.364868 -47.014638)
		(end 65.364868 -47.625)
		(width 0.14224)
		(layer "In4.Cu")
		(net "M_H_DQ<21>")
	)
	(segment
		(start 53.680868 -32.695642)
		(end 62.227968 -41.242742)
		(width 0.14224)
		(layer "In4.Cu")
		(net "M_H_DQ<21>")
	)
	(segment
		(start 50.873152 -12.678156)
		(end 50.368708 -13.1826)
		(width 0.14224)
		(layer "In4.Cu")
		(net "M_H_DQ<21>")
	)
	(segment
		(start 70.778116 -52.015136)
		(end 70.914514 -51.965352)
		(width 0.0889)
		(layer "In4.Cu")
		(net "M_H_DQ<21>")
	)
	(segment
		(start 50.670206 -8.0518)
		(end 50.981102 -8.0518)
		(width 0.14224)
		(layer "In4.Cu")
		(net "M_H_DQ<21>")
	)
	(segment
		(start 70.593712 -52.027836)
		(end 70.674992 -52.027836)
		(width 0.0889)
		(layer "In4.Cu")
		(net "M_H_DQ<21>")
	)
	(segment
		(start 50.099468 -7.086346)
		(end 50.099468 -7.481062)
		(width 0.14224)
		(layer "In4.Cu")
		(net "M_H_DQ<21>")
	)
	(segment
		(start 51.346608 -23.220172)
		(end 51.283108 -23.283672)
		(width 0.14224)
		(layer "In4.Cu")
		(net "M_H_DQ<21>")
	)
	(segment
		(start 51.184556 -9.06145)
		(end 51.184556 -12.366752)
		(width 0.14224)
		(layer "In4.Cu")
		(net "M_H_DQ<21>")
	)
	(segment
		(start 70.674992 -52.027836)
		(end 70.778116 -52.015136)
		(width 0.0889)
		(layer "In4.Cu")
		(net "M_H_DQ<21>")
	)
	(segment
		(start 51.178968 -24.13)
		(end 51.178968 -26.5303)
		(width 0.14224)
		(layer "In4.Cu")
		(net "M_H_DQ<21>")
	)
	(segment
		(start 71.787258 -52.855368)
		(end 71.763382 -52.944776)
		(width 0.0889)
		(layer "In4.Cu")
		(net "M_H_DQ<21>")
	)
	(segment
		(start 51.257708 -21.873972)
		(end 51.346608 -21.962872)
		(width 0.14224)
		(layer "In4.Cu")
		(net "M_H_DQ<21>")
	)
	(segment
		(start 51.381406 -8.8646)
		(end 51.184556 -9.06145)
		(width 0.14224)
		(layer "In4.Cu")
		(net "M_H_DQ<21>")
	)
	(segment
		(start 51.610768 -20.904454)
		(end 51.257708 -21.257514)
		(width 0.14224)
		(layer "In4.Cu")
		(net "M_H_DQ<21>")
	)
	(segment
		(start 65.585086 -48.544988)
		(end 65.815464 -48.775366)
		(width 0.0889)
		(layer "In4.Cu")
		(net "M_H_DQ<21>")
	)
	(segment
		(start 51.257708 -18.593562)
		(end 51.257708 -18.976086)
		(width 0.14224)
		(layer "In4.Cu")
		(net "M_H_DQ<21>")
	)
	(segment
		(start 70.914514 -51.965352)
		(end 71.228458 -51.80457)
		(width 0.0889)
		(layer "In4.Cu")
		(net "M_H_DQ<21>")
	)
	(segment
		(start 50.368708 -13.1826)
		(end 50.368708 -13.542772)
		(width 0.14224)
		(layer "In4.Cu")
		(net "M_H_DQ<21>")
	)
	(segment
		(start 51.257708 -21.257514)
		(end 51.257708 -21.873972)
		(width 0.14224)
		(layer "In4.Cu")
		(net "M_H_DQ<21>")
	)
	(segment
		(start 51.346608 -18.504662)
		(end 51.257708 -18.593562)
		(width 0.14224)
		(layer "In4.Cu")
		(net "M_H_DQ<21>")
	)
	(segment
		(start 51.283108 -16.069564)
		(end 51.283108 -16.866362)
		(width 0.14224)
		(layer "In4.Cu")
		(net "M_H_DQ<21>")
	)
	(segment
		(start 65.364868 -47.625)
		(end 65.585086 -47.845218)
		(width 0.14224)
		(layer "In4.Cu")
		(net "M_H_DQ<21>")
	)
	(segment
		(start 51.034188 -15.02918)
		(end 50.797968 -15.2654)
		(width 0.14224)
		(layer "In4.Cu")
		(net "M_H_DQ<21>")
	)
	(segment
		(start 51.283108 -24.02586)
		(end 51.178968 -24.13)
		(width 0.14224)
		(layer "In4.Cu")
		(net "M_H_DQ<21>")
	)
	(segment
		(start 66.915538 -49.87544)
		(end 68.098924 -49.87544)
		(width 0.0889)
		(layer "In4.Cu")
		(net "M_H_DQ<21>")
	)
	(segment
		(start 50.368708 -13.542772)
		(end 51.034188 -14.208252)
		(width 0.14224)
		(layer "In4.Cu")
		(net "M_H_DQ<21>")
	)
	(segment
		(start 51.381406 -8.452104)
		(end 51.381406 -8.8646)
		(width 0.14224)
		(layer "In4.Cu")
		(net "M_H_DQ<21>")
	)
	(segment
		(start 51.283108 -16.866362)
		(end 51.346608 -16.929862)
		(width 0.14224)
		(layer "In4.Cu")
		(net "M_H_DQ<21>")
	)
	(segment
		(start 62.227968 -43.877738)
		(end 65.364868 -47.014638)
		(width 0.14224)
		(layer "In4.Cu")
		(net "M_H_DQ<21>")
	)
	(segment
		(start 51.178968 -26.5303)
		(end 52.080668 -27.432)
		(width 0.14224)
		(layer "In4.Cu")
		(net "M_H_DQ<21>")
	)
	(segment
		(start 68.098924 -49.87544)
		(end 69.202554 -50.97907)
		(width 0.0889)
		(layer "In4.Cu")
		(net "M_H_DQ<21>")
	)
	(segment
		(start 69.202554 -50.97907)
		(end 69.406516 -51.332638)
		(width 0.0889)
		(layer "In4.Cu")
		(net "M_H_DQ<21>")
	)
	(segment
		(start 51.034188 -14.208252)
		(end 51.034188 -15.02918)
		(width 0.14224)
		(layer "In4.Cu")
		(net "M_H_DQ<21>")
	)
	(segment
		(start 51.346608 -21.962872)
		(end 51.346608 -23.220172)
		(width 0.14224)
		(layer "In4.Cu")
		(net "M_H_DQ<21>")
	)
	(segment
		(start 69.73824 -51.532536)
		(end 69.76618 -51.532536)
		(width 0.0889)
		(layer "In4.Cu")
		(net "M_H_DQ<21>")
	)
	(segment
		(start 50.099468 -7.481062)
		(end 50.670206 -8.0518)
		(width 0.14224)
		(layer "In4.Cu")
		(net "M_H_DQ<21>")
	)
	(segment
		(start 51.283108 -23.283672)
		(end 51.283108 -24.02586)
		(width 0.14224)
		(layer "In4.Cu")
		(net "M_H_DQ<21>")
	)
	(segment
		(start 51.346608 -16.929862)
		(end 51.346608 -18.504662)
		(width 0.14224)
		(layer "In4.Cu")
		(net "M_H_DQ<21>")
	)
	(segment
		(start 52.080668 -27.432)
		(end 52.080668 -29.8831)
		(width 0.14224)
		(layer "In4.Cu")
		(net "M_H_DQ<21>")
	)
	(segment
		(start 71.763382 -52.944776)
		(end 71.470266 -53.113686)
		(width 0.0889)
		(layer "In4.Cu")
		(net "M_H_DQ<21>")
	)
	(segment
		(start 52.080668 -29.8831)
		(end 53.680868 -31.4833)
		(width 0.14224)
		(layer "In4.Cu")
		(net "M_H_DQ<21>")
	)
	(arc
		(start 69.406516 -51.332638)
		(mid 69.546595 -51.475374)
		(end 69.73824 -51.532536)
		(width 0.0889)
		(layer "In4.Cu")
		(net "M_H_DQ<21>")
	)
	(arc
		(start 71.816976 -52.323238)
		(mid 71.813709 -52.328517)
		(end 71.810626 -52.333906)
		(width 0.0889)
		(layer "In4.Cu")
		(net "M_H_DQ<21>")
	)
	(arc
		(start 71.228458 -51.80457)
		(mid 71.734817 -51.823177)
		(end 71.816976 -52.323238)
		(width 0.0889)
		(layer "In4.Cu")
		(net "M_H_DQ<21>")
	)
	(arc
		(start 71.810626 -52.333906)
		(mid 71.738231 -52.591918)
		(end 71.787258 -52.855368)
		(width 0.0889)
		(layer "In4.Cu")
		(net "M_H_DQ<21>")
	)
	(arc
		(start 70.265036 -51.827938)
		(mid 70.40378 -51.969971)
		(end 70.593712 -52.027836)
		(width 0.0889)
		(layer "In4.Cu")
		(net "M_H_DQ<21>")
	)
	(arc
		(start 69.76618 -51.532536)
		(mid 70.054325 -51.614855)
		(end 70.265036 -51.827938)
		(width 0.0889)
		(layer "In4.Cu")
		(net "M_H_DQ<21>")
	)
	(segment
		(start 50.8889 -8.763)
		(end 50.851308 -8.5598)
		(width 0.1651)
		(layer "F.Cu")
		(net "M_H_DQ<20>")
	)
	(segment
		(start 50.949352 -10.422382)
		(end 50.949352 -9.091168)
		(width 0.1651)
		(layer "F.Cu")
		(net "M_H_DQ<20>")
	)
	(segment
		(start 50.949352 -9.091168)
		(end 50.8889 -8.763)
		(width 0.1651)
		(layer "F.Cu")
		(net "M_H_DQ<20>")
	)
	(segment
		(start 72.041766 -52.12334)
		(end 71.470266 -52.12334)
		(width 0.1016)
		(layer "F.Cu")
		(net "M_H_DQ<20>")
	)
	(via
		(at 71.470266 -52.12334)
		(size 0.508)
		(drill 0.254)
		(layers "F.Cu" "B.Cu")
		(net "M_H_DQ<20>")
	)
	(via
		(at 50.851308 -8.5598)
		(size 0.508)
		(drill 0.254)
		(layers "F.Cu" "B.Cu")
		(net "M_H_DQ<20>")
	)
	(via
		(at 50.099468 -13.959078)
		(size 0.508)
		(drill 0.254)
		(layers "F.Cu" "B.Cu")
		(net "M_H_DQ<20>")
	)
	(segment
		(start 50.099468 -15.222982)
		(end 50.099468 -13.959078)
		(width 0.1651)
		(layer "B.Cu")
		(net "M_H_DQ<20>")
	)
	(segment
		(start 51.407568 -29.32049)
		(end 51.407568 -28.96743)
		(width 0.14224)
		(layer "In4.Cu")
		(net "M_H_DQ<20>")
	)
	(segment
		(start 50.574956 -11.742928)
		(end 50.223674 -11.391646)
		(width 0.14224)
		(layer "In4.Cu")
		(net "M_H_DQ<20>")
	)
	(segment
		(start 50.368708 -23.169372)
		(end 50.368708 -21.950172)
		(width 0.14224)
		(layer "In4.Cu")
		(net "M_H_DQ<20>")
	)
	(segment
		(start 50.368708 -17.066514)
		(end 50.597308 -16.837914)
		(width 0.14224)
		(layer "In4.Cu")
		(net "M_H_DQ<20>")
	)
	(segment
		(start 51.407568 -27.626056)
		(end 50.518568 -26.737056)
		(width 0.14224)
		(layer "In4.Cu")
		(net "M_H_DQ<20>")
	)
	(segment
		(start 50.099468 -13.959078)
		(end 49.863756 -13.723366)
		(width 0.14224)
		(layer "In4.Cu")
		(net "M_H_DQ<20>")
	)
	(segment
		(start 50.362104 -14.549882)
		(end 50.099468 -14.287246)
		(width 0.14224)
		(layer "In4.Cu")
		(net "M_H_DQ<20>")
	)
	(segment
		(start 50.864008 -30.13837)
		(end 50.709068 -29.98343)
		(width 0.14224)
		(layer "In4.Cu")
		(net "M_H_DQ<20>")
	)
	(segment
		(start 50.709068 -29.63037)
		(end 50.864008 -29.47543)
		(width 0.14224)
		(layer "In4.Cu")
		(net "M_H_DQ<20>")
	)
	(segment
		(start 50.574956 -12.217654)
		(end 50.574956 -11.742928)
		(width 0.14224)
		(layer "In4.Cu")
		(net "M_H_DQ<20>")
	)
	(segment
		(start 50.368708 -21.950172)
		(end 50.622708 -21.696172)
		(width 0.14224)
		(layer "In4.Cu")
		(net "M_H_DQ<20>")
	)
	(segment
		(start 50.518568 -26.737056)
		(end 50.518568 -23.8506)
		(width 0.14224)
		(layer "In4.Cu")
		(net "M_H_DQ<20>")
	)
	(segment
		(start 51.252628 -29.47543)
		(end 51.407568 -29.32049)
		(width 0.14224)
		(layer "In4.Cu")
		(net "M_H_DQ<20>")
	)
	(segment
		(start 50.622708 -21.696172)
		(end 50.622708 -20.95246)
		(width 0.14224)
		(layer "In4.Cu")
		(net "M_H_DQ<20>")
	)
	(segment
		(start 50.952908 -28.14955)
		(end 51.252628 -28.14955)
		(width 0.14224)
		(layer "In4.Cu")
		(net "M_H_DQ<20>")
	)
	(segment
		(start 50.952908 -28.81249)
		(end 50.810668 -28.67025)
		(width 0.14224)
		(layer "In4.Cu")
		(net "M_H_DQ<20>")
	)
	(segment
		(start 50.864008 -29.47543)
		(end 51.252628 -29.47543)
		(width 0.14224)
		(layer "In4.Cu")
		(net "M_H_DQ<20>")
	)
	(segment
		(start 71.470266 -52.12334)
		(end 71.102728 -52.180998)
		(width 0.0889)
		(layer "In4.Cu")
		(net "M_H_DQ<20>")
	)
	(segment
		(start 50.223674 -11.391646)
		(end 50.223674 -11.0363)
		(width 0.14224)
		(layer "In4.Cu")
		(net "M_H_DQ<20>")
	)
	(segment
		(start 50.597308 -16.837914)
		(end 50.597308 -16.18234)
		(width 0.14224)
		(layer "In4.Cu")
		(net "M_H_DQ<20>")
	)
	(segment
		(start 50.368708 -18.314162)
		(end 50.368708 -17.066514)
		(width 0.14224)
		(layer "In4.Cu")
		(net "M_H_DQ<20>")
	)
	(segment
		(start 50.709068 -29.98343)
		(end 50.709068 -29.63037)
		(width 0.14224)
		(layer "In4.Cu")
		(net "M_H_DQ<20>")
	)
	(segment
		(start 61.592968 -44.140882)
		(end 61.592968 -41.505886)
		(width 0.14224)
		(layer "In4.Cu")
		(net "M_H_DQ<20>")
	)
	(segment
		(start 50.597308 -23.77186)
		(end 50.597308 -23.397972)
		(width 0.14224)
		(layer "In4.Cu")
		(net "M_H_DQ<20>")
	)
	(segment
		(start 50.810668 -28.29179)
		(end 50.952908 -28.14955)
		(width 0.14224)
		(layer "In4.Cu")
		(net "M_H_DQ<20>")
	)
	(segment
		(start 50.099468 -14.287246)
		(end 50.099468 -13.959078)
		(width 0.14224)
		(layer "In4.Cu")
		(net "M_H_DQ<20>")
	)
	(segment
		(start 51.252628 -28.81249)
		(end 50.952908 -28.81249)
		(width 0.14224)
		(layer "In4.Cu")
		(net "M_H_DQ<20>")
	)
	(segment
		(start 50.591974 -10.668)
		(end 50.591974 -10.3632)
		(width 0.14224)
		(layer "In4.Cu")
		(net "M_H_DQ<20>")
	)
	(segment
		(start 65.137538 -48.680624)
		(end 64.844168 -48.387254)
		(width 0.0889)
		(layer "In4.Cu")
		(net "M_H_DQ<20>")
	)
	(segment
		(start 65.451482 -48.680624)
		(end 65.137538 -48.680624)
		(width 0.0889)
		(layer "In4.Cu")
		(net "M_H_DQ<20>")
	)
	(segment
		(start 69.241416 -51.427888)
		(end 69.241924 -51.427634)
		(width 0.0889)
		(layer "In4.Cu")
		(net "M_H_DQ<20>")
	)
	(segment
		(start 51.252628 -28.14955)
		(end 51.407568 -27.99461)
		(width 0.14224)
		(layer "In4.Cu")
		(net "M_H_DQ<20>")
	)
	(segment
		(start 69.050408 -51.095656)
		(end 68.020438 -50.065686)
		(width 0.0889)
		(layer "In4.Cu")
		(net "M_H_DQ<20>")
	)
	(segment
		(start 49.863756 -13.723366)
		(end 49.863756 -12.928854)
		(width 0.14224)
		(layer "In4.Cu")
		(net "M_H_DQ<20>")
	)
	(segment
		(start 50.622708 -19.2786)
		(end 50.622708 -18.568162)
		(width 0.14224)
		(layer "In4.Cu")
		(net "M_H_DQ<20>")
	)
	(segment
		(start 50.223674 -11.0363)
		(end 50.591974 -10.668)
		(width 0.14224)
		(layer "In4.Cu")
		(net "M_H_DQ<20>")
	)
	(segment
		(start 50.099468 -15.1003)
		(end 50.362104 -14.837664)
		(width 0.14224)
		(layer "In4.Cu")
		(net "M_H_DQ<20>")
	)
	(segment
		(start 50.210974 -9.9822)
		(end 50.210974 -9.677654)
		(width 0.14224)
		(layer "In4.Cu")
		(net "M_H_DQ<20>")
	)
	(segment
		(start 50.099468 -15.6845)
		(end 50.099468 -15.1003)
		(width 0.14224)
		(layer "In4.Cu")
		(net "M_H_DQ<20>")
	)
	(segment
		(start 52.880768 -32.793686)
		(end 52.880768 -31.76651)
		(width 0.14224)
		(layer "In4.Cu")
		(net "M_H_DQ<20>")
	)
	(segment
		(start 50.518568 -23.8506)
		(end 50.597308 -23.77186)
		(width 0.14224)
		(layer "In4.Cu")
		(net "M_H_DQ<20>")
	)
	(segment
		(start 49.863756 -12.928854)
		(end 50.574956 -12.217654)
		(width 0.14224)
		(layer "In4.Cu")
		(net "M_H_DQ<20>")
	)
	(segment
		(start 50.622708 -18.568162)
		(end 50.368708 -18.314162)
		(width 0.14224)
		(layer "In4.Cu")
		(net "M_H_DQ<20>")
	)
	(segment
		(start 64.844168 -48.387254)
		(end 64.844168 -47.392082)
		(width 0.14224)
		(layer "In4.Cu")
		(net "M_H_DQ<20>")
	)
	(segment
		(start 68.020438 -50.065686)
		(end 66.836544 -50.065686)
		(width 0.0889)
		(layer "In4.Cu")
		(net "M_H_DQ<20>")
	)
	(segment
		(start 50.574956 -8.836152)
		(end 50.851308 -8.5598)
		(width 0.14224)
		(layer "In4.Cu")
		(net "M_H_DQ<20>")
	)
	(segment
		(start 70.777354 -52.21859)
		(end 70.590156 -52.21859)
		(width 0.0889)
		(layer "In4.Cu")
		(net "M_H_DQ<20>")
	)
	(segment
		(start 50.810668 -28.67025)
		(end 50.810668 -28.29179)
		(width 0.14224)
		(layer "In4.Cu")
		(net "M_H_DQ<20>")
	)
	(segment
		(start 50.591974 -10.3632)
		(end 50.210974 -9.9822)
		(width 0.14224)
		(layer "In4.Cu")
		(net "M_H_DQ<20>")
	)
	(segment
		(start 71.102728 -52.180998)
		(end 70.777354 -52.21859)
		(width 0.0889)
		(layer "In4.Cu")
		(net "M_H_DQ<20>")
	)
	(segment
		(start 50.950368 -20.6248)
		(end 50.950368 -19.60626)
		(width 0.14224)
		(layer "In4.Cu")
		(net "M_H_DQ<20>")
	)
	(segment
		(start 50.362104 -14.837664)
		(end 50.362104 -14.549882)
		(width 0.14224)
		(layer "In4.Cu")
		(net "M_H_DQ<20>")
	)
	(segment
		(start 69.241924 -51.427634)
		(end 69.050408 -51.095656)
		(width 0.0889)
		(layer "In4.Cu")
		(net "M_H_DQ<20>")
	)
	(segment
		(start 50.574956 -9.313672)
		(end 50.574956 -8.836152)
		(width 0.14224)
		(layer "In4.Cu")
		(net "M_H_DQ<20>")
	)
	(segment
		(start 64.844168 -47.392082)
		(end 61.592968 -44.140882)
		(width 0.14224)
		(layer "In4.Cu")
		(net "M_H_DQ<20>")
	)
	(segment
		(start 50.210974 -9.677654)
		(end 50.574956 -9.313672)
		(width 0.14224)
		(layer "In4.Cu")
		(net "M_H_DQ<20>")
	)
	(segment
		(start 51.407568 -28.96743)
		(end 51.252628 -28.81249)
		(width 0.14224)
		(layer "In4.Cu")
		(net "M_H_DQ<20>")
	)
	(segment
		(start 51.252628 -30.13837)
		(end 50.864008 -30.13837)
		(width 0.14224)
		(layer "In4.Cu")
		(net "M_H_DQ<20>")
	)
	(segment
		(start 69.764402 -51.72329)
		(end 69.740272 -51.72329)
		(width 0.0889)
		(layer "In4.Cu")
		(net "M_H_DQ<20>")
	)
	(segment
		(start 50.950368 -19.60626)
		(end 50.622708 -19.2786)
		(width 0.14224)
		(layer "In4.Cu")
		(net "M_H_DQ<20>")
	)
	(segment
		(start 52.880768 -31.76651)
		(end 51.252628 -30.13837)
		(width 0.14224)
		(layer "In4.Cu")
		(net "M_H_DQ<20>")
	)
	(segment
		(start 66.836544 -50.065686)
		(end 65.451482 -48.680624)
		(width 0.0889)
		(layer "In4.Cu")
		(net "M_H_DQ<20>")
	)
	(segment
		(start 50.622708 -20.95246)
		(end 50.950368 -20.6248)
		(width 0.14224)
		(layer "In4.Cu")
		(net "M_H_DQ<20>")
	)
	(segment
		(start 50.597308 -23.397972)
		(end 50.368708 -23.169372)
		(width 0.14224)
		(layer "In4.Cu")
		(net "M_H_DQ<20>")
	)
	(segment
		(start 61.592968 -41.505886)
		(end 52.880768 -32.793686)
		(width 0.14224)
		(layer "In4.Cu")
		(net "M_H_DQ<20>")
	)
	(segment
		(start 50.597308 -16.18234)
		(end 50.099468 -15.6845)
		(width 0.14224)
		(layer "In4.Cu")
		(net "M_H_DQ<20>")
	)
	(segment
		(start 51.407568 -27.99461)
		(end 51.407568 -27.626056)
		(width 0.14224)
		(layer "In4.Cu")
		(net "M_H_DQ<20>")
	)
	(arc
		(start 70.099936 -51.923442)
		(mid 69.958253 -51.779638)
		(end 69.764402 -51.72329)
		(width 0.0889)
		(layer "In4.Cu")
		(net "M_H_DQ<20>")
	)
	(arc
		(start 70.590156 -52.21859)
		(mid 70.306939 -52.134309)
		(end 70.099936 -51.923442)
		(width 0.0889)
		(layer "In4.Cu")
		(net "M_H_DQ<20>")
	)
	(arc
		(start 69.740272 -51.72329)
		(mid 69.452127 -51.640971)
		(end 69.241416 -51.427888)
		(width 0.0889)
		(layer "In4.Cu")
		(net "M_H_DQ<20>")
	)
	(segment
		(start 73.758806 -66.982086)
		(end 73.187306 -66.982086)
		(width 0.0889)
		(layer "F.Cu")
		(net "M_H_DQ<1>")
	)
	(segment
		(start 33.099502 -5.822442)
		(end 33.099502 -7.086346)
		(width 0.1651)
		(layer "F.Cu")
		(net "M_H_DQ<1>")
	)
	(via
		(at 33.771586 -12.678156)
		(size 0.508)
		(drill 0.254)
		(layers "F.Cu" "B.Cu")
		(net "M_H_DQ<1>")
	)
	(via
		(at 33.099502 -7.086346)
		(size 0.508)
		(drill 0.254)
		(layers "F.Cu" "B.Cu")
		(net "M_H_DQ<1>")
	)
	(via
		(at 73.187306 -66.982086)
		(size 0.508)
		(drill 0.254)
		(layers "F.Cu" "B.Cu")
		(net "M_H_DQ<1>")
	)
	(segment
		(start 33.949386 -11.997182)
		(end 33.771586 -12.174982)
		(width 0.1651)
		(layer "B.Cu")
		(net "M_H_DQ<1>")
	)
	(segment
		(start 33.949386 -10.623042)
		(end 33.949386 -11.997182)
		(width 0.1651)
		(layer "B.Cu")
		(net "M_H_DQ<1>")
	)
	(segment
		(start 33.771586 -12.174982)
		(end 33.771586 -12.678156)
		(width 0.1651)
		(layer "B.Cu")
		(net "M_H_DQ<1>")
	)
	(segment
		(start 33.245044 -13.485876)
		(end 33.62452 -13.865352)
		(width 0.14224)
		(layer "In4.Cu")
		(net "M_H_DQ<1>")
	)
	(segment
		(start 34.541968 -24.0792)
		(end 34.541968 -27.3304)
		(width 0.14224)
		(layer "In4.Cu")
		(net "M_H_DQ<1>")
	)
	(segment
		(start 33.62452 -13.865352)
		(end 33.62452 -15.617952)
		(width 0.14224)
		(layer "In4.Cu")
		(net "M_H_DQ<1>")
	)
	(segment
		(start 38.879018 -41.21785)
		(end 38.879018 -42.03065)
		(width 0.14224)
		(layer "In4.Cu")
		(net "M_H_DQ<1>")
	)
	(segment
		(start 33.771586 -12.678156)
		(end 34.145728 -12.304014)
		(width 0.14224)
		(layer "In4.Cu")
		(net "M_H_DQ<1>")
	)
	(segment
		(start 69.73824 -69.363336)
		(end 69.768212 -69.363336)
		(width 0.0889)
		(layer "In4.Cu")
		(net "M_H_DQ<1>")
	)
	(segment
		(start 70.590156 -68.86829)
		(end 70.622922 -68.86829)
		(width 0.0889)
		(layer "In4.Cu")
		(net "M_H_DQ<1>")
	)
	(segment
		(start 71.45909 -67.572636)
		(end 71.563992 -67.572636)
		(width 0.0889)
		(layer "In4.Cu")
		(net "M_H_DQ<1>")
	)
	(segment
		(start 34.021268 -37.1729)
		(end 36.847018 -39.99865)
		(width 0.14224)
		(layer "In4.Cu")
		(net "M_H_DQ<1>")
	)
	(segment
		(start 72.69226 -67.648074)
		(end 73.187306 -66.982086)
		(width 0.0889)
		(layer "In4.Cu")
		(net "M_H_DQ<1>")
	)
	(segment
		(start 67.869308 -68.372736)
		(end 68.053966 -68.372736)
		(width 0.0889)
		(layer "In4.Cu")
		(net "M_H_DQ<1>")
	)
	(segment
		(start 66.522092 -67.772534)
		(end 66.627248 -67.87769)
		(width 0.0889)
		(layer "In4.Cu")
		(net "M_H_DQ<1>")
	)
	(segment
		(start 33.62452 -15.617952)
		(end 34.25952 -16.252952)
		(width 0.14224)
		(layer "In4.Cu")
		(net "M_H_DQ<1>")
	)
	(segment
		(start 54.112668 -57.2643)
		(end 54.455568 -57.2643)
		(width 0.14224)
		(layer "In4.Cu")
		(net "M_H_DQ<1>")
	)
	(segment
		(start 34.25952 -23.796752)
		(end 34.541968 -24.0792)
		(width 0.14224)
		(layer "In4.Cu")
		(net "M_H_DQ<1>")
	)
	(segment
		(start 33.771586 -12.678156)
		(end 33.245044 -13.204698)
		(width 0.14224)
		(layer "In4.Cu")
		(net "M_H_DQ<1>")
	)
	(segment
		(start 34.302192 -8.8138)
		(end 34.302192 -8.472424)
		(width 0.14224)
		(layer "In4.Cu")
		(net "M_H_DQ<1>")
	)
	(segment
		(start 38.879018 -42.03065)
		(end 54.112668 -57.2643)
		(width 0.14224)
		(layer "In4.Cu")
		(net "M_H_DQ<1>")
	)
	(segment
		(start 36.847018 -39.99865)
		(end 37.659818 -39.99865)
		(width 0.14224)
		(layer "In4.Cu")
		(net "M_H_DQ<1>")
	)
	(segment
		(start 37.659818 -39.99865)
		(end 38.879018 -41.21785)
		(width 0.14224)
		(layer "In4.Cu")
		(net "M_H_DQ<1>")
	)
	(segment
		(start 34.25952 -16.252952)
		(end 34.25952 -23.796752)
		(width 0.14224)
		(layer "In4.Cu")
		(net "M_H_DQ<1>")
	)
	(segment
		(start 54.455568 -57.2643)
		(end 64.963802 -67.772534)
		(width 0.14224)
		(layer "In4.Cu")
		(net "M_H_DQ<1>")
	)
	(segment
		(start 64.963802 -67.772534)
		(end 66.522092 -67.772534)
		(width 0.14224)
		(layer "In4.Cu")
		(net "M_H_DQ<1>")
	)
	(segment
		(start 68.88353 -68.86829)
		(end 68.916296 -68.86829)
		(width 0.0889)
		(layer "In4.Cu")
		(net "M_H_DQ<1>")
	)
	(segment
		(start 33.245044 -13.204698)
		(end 33.245044 -13.485876)
		(width 0.14224)
		(layer "In4.Cu")
		(net "M_H_DQ<1>")
	)
	(segment
		(start 34.145728 -12.304014)
		(end 34.145728 -8.970264)
		(width 0.14224)
		(layer "In4.Cu")
		(net "M_H_DQ<1>")
	)
	(segment
		(start 33.099502 -7.625334)
		(end 33.099502 -7.086346)
		(width 0.14224)
		(layer "In4.Cu")
		(net "M_H_DQ<1>")
	)
	(segment
		(start 34.541968 -27.3304)
		(end 34.021268 -27.8511)
		(width 0.14224)
		(layer "In4.Cu")
		(net "M_H_DQ<1>")
	)
	(segment
		(start 34.145728 -8.970264)
		(end 34.302192 -8.8138)
		(width 0.14224)
		(layer "In4.Cu")
		(net "M_H_DQ<1>")
	)
	(segment
		(start 71.012812 -68.573904)
		(end 71.07047 -67.992244)
		(width 0.0889)
		(layer "In4.Cu")
		(net "M_H_DQ<1>")
	)
	(segment
		(start 33.932368 -8.1026)
		(end 33.576768 -8.1026)
		(width 0.14224)
		(layer "In4.Cu")
		(net "M_H_DQ<1>")
	)
	(segment
		(start 33.576768 -8.1026)
		(end 33.099502 -7.625334)
		(width 0.14224)
		(layer "In4.Cu")
		(net "M_H_DQ<1>")
	)
	(segment
		(start 34.302192 -8.472424)
		(end 33.932368 -8.1026)
		(width 0.14224)
		(layer "In4.Cu")
		(net "M_H_DQ<1>")
	)
	(segment
		(start 72.675496 -67.677538)
		(end 72.69226 -67.648074)
		(width 0.0889)
		(layer "In4.Cu")
		(net "M_H_DQ<1>")
	)
	(segment
		(start 34.021268 -27.8511)
		(end 34.021268 -37.1729)
		(width 0.14224)
		(layer "In4.Cu")
		(net "M_H_DQ<1>")
	)
	(segment
		(start 71.563992 -67.572636)
		(end 72.111362 -67.813682)
		(width 0.0889)
		(layer "In4.Cu")
		(net "M_H_DQ<1>")
	)
	(segment
		(start 66.627248 -67.87769)
		(end 67.304666 -67.87769)
		(width 0.0889)
		(layer "In4.Cu")
		(net "M_H_DQ<1>")
	)
	(segment
		(start 70.958456 -68.668138)
		(end 71.012812 -68.573904)
		(width 0.0889)
		(layer "In4.Cu")
		(net "M_H_DQ<1>")
	)
	(arc
		(start 68.547996 -68.668138)
		(mid 68.689679 -68.811942)
		(end 68.88353 -68.86829)
		(width 0.0889)
		(layer "In4.Cu")
		(net "M_H_DQ<1>")
	)
	(arc
		(start 70.099936 -69.163438)
		(mid 70.30694 -68.952574)
		(end 70.590156 -68.86829)
		(width 0.0889)
		(layer "In4.Cu")
		(net "M_H_DQ<1>")
	)
	(arc
		(start 68.916296 -68.86829)
		(mid 69.199513 -68.952571)
		(end 69.406516 -69.163438)
		(width 0.0889)
		(layer "In4.Cu")
		(net "M_H_DQ<1>")
	)
	(arc
		(start 67.304666 -67.87769)
		(mid 67.50726 -67.993508)
		(end 67.653154 -68.175632)
		(width 0.0889)
		(layer "In4.Cu")
		(net "M_H_DQ<1>")
	)
	(arc
		(start 70.622922 -68.86829)
		(mid 70.816772 -68.81194)
		(end 70.958456 -68.668138)
		(width 0.0889)
		(layer "In4.Cu")
		(net "M_H_DQ<1>")
	)
	(arc
		(start 69.768212 -69.363336)
		(mid 69.959854 -69.30617)
		(end 70.099936 -69.163438)
		(width 0.0889)
		(layer "In4.Cu")
		(net "M_H_DQ<1>")
	)
	(arc
		(start 68.053966 -68.372736)
		(mid 68.33939 -68.456203)
		(end 68.547996 -68.668138)
		(width 0.0889)
		(layer "In4.Cu")
		(net "M_H_DQ<1>")
	)
	(arc
		(start 67.653154 -68.175632)
		(mid 67.744098 -68.292975)
		(end 67.869308 -68.372736)
		(width 0.0889)
		(layer "In4.Cu")
		(net "M_H_DQ<1>")
	)
	(arc
		(start 71.07047 -67.992244)
		(mid 71.176571 -67.700726)
		(end 71.45909 -67.572636)
		(width 0.0889)
		(layer "In4.Cu")
		(net "M_H_DQ<1>")
	)
	(arc
		(start 69.406516 -69.163438)
		(mid 69.546595 -69.306174)
		(end 69.73824 -69.363336)
		(width 0.0889)
		(layer "In4.Cu")
		(net "M_H_DQ<1>")
	)
	(arc
		(start 72.111362 -67.813682)
		(mid 72.422665 -67.866721)
		(end 72.675496 -67.677538)
		(width 0.0889)
		(layer "In4.Cu")
		(net "M_H_DQ<1>")
	)
	(segment
		(start 75.475846 -53.113686)
		(end 74.904346 -53.113686)
		(width 0.1016)
		(layer "F.Cu")
		(net "M_H_DQ<19>")
	)
	(segment
		(start 57.74944 -5.822442)
		(end 57.74944 -7.086346)
		(width 0.1651)
		(layer "F.Cu")
		(net "M_H_DQ<19>")
	)
	(via
		(at 57.74944 -7.086346)
		(size 0.508)
		(drill 0.254)
		(layers "F.Cu" "B.Cu")
		(net "M_H_DQ<19>")
	)
	(via
		(at 58.599324 -12.678156)
		(size 0.508)
		(drill 0.254)
		(layers "F.Cu" "B.Cu")
		(net "M_H_DQ<19>")
	)
	(via
		(at 74.904346 -53.113686)
		(size 0.508)
		(drill 0.254)
		(layers "F.Cu" "B.Cu")
		(net "M_H_DQ<19>")
	)
	(segment
		(start 58.599578 -10.882122)
		(end 58.599324 -10.882376)
		(width 0.1651)
		(layer "B.Cu")
		(net "M_H_DQ<19>")
	)
	(segment
		(start 58.599578 -10.623042)
		(end 58.599578 -10.882122)
		(width 0.1651)
		(layer "B.Cu")
		(net "M_H_DQ<19>")
	)
	(segment
		(start 58.599324 -10.882376)
		(end 58.599324 -12.678156)
		(width 0.1651)
		(layer "B.Cu")
		(net "M_H_DQ<19>")
	)
	(segment
		(start 58.95213 -12.32535)
		(end 58.599324 -12.678156)
		(width 0.14224)
		(layer "In4.Cu")
		(net "M_H_DQ<19>")
	)
	(segment
		(start 58.396378 -8.0518)
		(end 58.650378 -8.0518)
		(width 0.14224)
		(layer "In4.Cu")
		(net "M_H_DQ<19>")
	)
	(segment
		(start 58.966608 -16.891762)
		(end 59.106308 -17.031462)
		(width 0.14224)
		(layer "In4.Cu")
		(net "M_H_DQ<19>")
	)
	(segment
		(start 58.95213 -9.020048)
		(end 58.95213 -12.32535)
		(width 0.14224)
		(layer "In4.Cu")
		(net "M_H_DQ<19>")
	)
	(segment
		(start 75.503532 -50.3047)
		(end 75.42911 -50.416968)
		(width 0.0889)
		(layer "In4.Cu")
		(net "M_H_DQ<19>")
	)
	(segment
		(start 58.115708 -13.161772)
		(end 58.115708 -13.568172)
		(width 0.14224)
		(layer "In4.Cu")
		(net "M_H_DQ<19>")
	)
	(segment
		(start 75.41133 -51.819302)
		(end 75.416156 -51.827938)
		(width 0.0889)
		(layer "In4.Cu")
		(net "M_H_DQ<19>")
	)
	(segment
		(start 72.420226 -46.367954)
		(end 72.420226 -46.556168)
		(width 0.0889)
		(layer "In4.Cu")
		(net "M_H_DQ<19>")
	)
	(segment
		(start 61.692282 -30.65526)
		(end 61.847222 -30.8102)
		(width 0.14224)
		(layer "In4.Cu")
		(net "M_H_DQ<19>")
	)
	(segment
		(start 59.131708 -22.000972)
		(end 59.131708 -23.118572)
		(width 0.14224)
		(layer "In4.Cu")
		(net "M_H_DQ<19>")
	)
	(segment
		(start 61.692282 -30.070806)
		(end 61.692282 -30.65526)
		(width 0.14224)
		(layer "In4.Cu")
		(net "M_H_DQ<19>")
	)
	(segment
		(start 58.599324 -12.678156)
		(end 58.115708 -13.161772)
		(width 0.14224)
		(layer "In4.Cu")
		(net "M_H_DQ<19>")
	)
	(segment
		(start 74.96937 -52.710588)
		(end 74.904346 -52.775612)
		(width 0.0889)
		(layer "In4.Cu")
		(net "M_H_DQ<19>")
	)
	(segment
		(start 75.503532 -49.639474)
		(end 75.503532 -50.3047)
		(width 0.0889)
		(layer "In4.Cu")
		(net "M_H_DQ<19>")
	)
	(segment
		(start 58.115708 -13.568172)
		(end 58.966608 -14.419072)
		(width 0.14224)
		(layer "In4.Cu")
		(net "M_H_DQ<19>")
	)
	(segment
		(start 59.824874 -29.915866)
		(end 61.537342 -29.915866)
		(width 0.14224)
		(layer "In4.Cu")
		(net "M_H_DQ<19>")
	)
	(segment
		(start 58.953908 -18.565114)
		(end 58.953908 -21.823172)
		(width 0.14224)
		(layer "In4.Cu")
		(net "M_H_DQ<19>")
	)
	(segment
		(start 58.650378 -8.0518)
		(end 59.107578 -8.509)
		(width 0.14224)
		(layer "In4.Cu")
		(net "M_H_DQ<19>")
	)
	(segment
		(start 58.953908 -21.823172)
		(end 59.131708 -22.000972)
		(width 0.14224)
		(layer "In4.Cu")
		(net "M_H_DQ<19>")
	)
	(segment
		(start 59.107578 -8.8646)
		(end 58.95213 -9.020048)
		(width 0.14224)
		(layer "In4.Cu")
		(net "M_H_DQ<19>")
	)
	(segment
		(start 61.847222 -30.8102)
		(end 62.200282 -30.8102)
		(width 0.14224)
		(layer "In4.Cu")
		(net "M_H_DQ<19>")
	)
	(segment
		(start 72.420226 -46.556168)
		(end 75.503532 -49.639474)
		(width 0.0889)
		(layer "In4.Cu")
		(net "M_H_DQ<19>")
	)
	(segment
		(start 75.416156 -50.837338)
		(end 75.422506 -50.848006)
		(width 0.0889)
		(layer "In4.Cu")
		(net "M_H_DQ<19>")
	)
	(segment
		(start 62.510162 -29.915866)
		(end 62.933834 -29.915866)
		(width 0.14224)
		(layer "In4.Cu")
		(net "M_H_DQ<19>")
	)
	(segment
		(start 75.41133 -50.828702)
		(end 75.416156 -50.837338)
		(width 0.0889)
		(layer "In4.Cu")
		(net "M_H_DQ<19>")
	)
	(segment
		(start 62.933834 -29.915866)
		(end 69.289168 -36.2712)
		(width 0.14224)
		(layer "In4.Cu")
		(net "M_H_DQ<19>")
	)
	(segment
		(start 74.904346 -52.775612)
		(end 74.904346 -53.113686)
		(width 0.0889)
		(layer "In4.Cu")
		(net "M_H_DQ<19>")
	)
	(segment
		(start 72.420226 -45.913294)
		(end 72.420226 -46.367954)
		(width 0.14224)
		(layer "In4.Cu")
		(net "M_H_DQ<19>")
	)
	(segment
		(start 62.200282 -30.8102)
		(end 62.355222 -30.65526)
		(width 0.14224)
		(layer "In4.Cu")
		(net "M_H_DQ<19>")
	)
	(segment
		(start 69.289168 -42.782236)
		(end 72.420226 -45.913294)
		(width 0.14224)
		(layer "In4.Cu")
		(net "M_H_DQ<19>")
	)
	(segment
		(start 58.966608 -29.0576)
		(end 59.824874 -29.915866)
		(width 0.14224)
		(layer "In4.Cu")
		(net "M_H_DQ<19>")
	)
	(segment
		(start 59.106308 -17.031462)
		(end 59.106308 -18.412714)
		(width 0.14224)
		(layer "In4.Cu")
		(net "M_H_DQ<19>")
	)
	(segment
		(start 62.355222 -30.65526)
		(end 62.355222 -30.070806)
		(width 0.14224)
		(layer "In4.Cu")
		(net "M_H_DQ<19>")
	)
	(segment
		(start 69.289168 -36.2712)
		(end 69.289168 -42.782236)
		(width 0.14224)
		(layer "In4.Cu")
		(net "M_H_DQ<19>")
	)
	(segment
		(start 58.966608 -14.419072)
		(end 58.966608 -16.891762)
		(width 0.14224)
		(layer "In4.Cu")
		(net "M_H_DQ<19>")
	)
	(segment
		(start 59.107578 -8.509)
		(end 59.107578 -8.8646)
		(width 0.14224)
		(layer "In4.Cu")
		(net "M_H_DQ<19>")
	)
	(segment
		(start 58.066178 -7.403084)
		(end 58.066178 -7.7216)
		(width 0.14224)
		(layer "In4.Cu")
		(net "M_H_DQ<19>")
	)
	(segment
		(start 61.537342 -29.915866)
		(end 61.692282 -30.070806)
		(width 0.14224)
		(layer "In4.Cu")
		(net "M_H_DQ<19>")
	)
	(segment
		(start 59.131708 -23.118572)
		(end 58.966608 -23.283672)
		(width 0.14224)
		(layer "In4.Cu")
		(net "M_H_DQ<19>")
	)
	(segment
		(start 58.966608 -23.283672)
		(end 58.966608 -29.0576)
		(width 0.14224)
		(layer "In4.Cu")
		(net "M_H_DQ<19>")
	)
	(segment
		(start 57.74944 -7.086346)
		(end 58.066178 -7.403084)
		(width 0.14224)
		(layer "In4.Cu")
		(net "M_H_DQ<19>")
	)
	(segment
		(start 58.066178 -7.7216)
		(end 58.396378 -8.0518)
		(width 0.14224)
		(layer "In4.Cu")
		(net "M_H_DQ<19>")
	)
	(segment
		(start 59.106308 -18.412714)
		(end 58.953908 -18.565114)
		(width 0.14224)
		(layer "In4.Cu")
		(net "M_H_DQ<19>")
	)
	(segment
		(start 62.355222 -30.070806)
		(end 62.510162 -29.915866)
		(width 0.14224)
		(layer "In4.Cu")
		(net "M_H_DQ<19>")
	)
	(arc
		(start 75.416156 -51.427888)
		(mid 75.362686 -51.622951)
		(end 75.41133 -51.819302)
		(width 0.0889)
		(layer "In4.Cu")
		(net "M_H_DQ<19>")
	)
	(arc
		(start 75.422506 -50.848006)
		(mid 75.495304 -51.138769)
		(end 75.416156 -51.427888)
		(width 0.0889)
		(layer "In4.Cu")
		(net "M_H_DQ<19>")
	)
	(arc
		(start 75.416156 -51.827938)
		(mid 75.431604 -52.390193)
		(end 74.96937 -52.710588)
		(width 0.0889)
		(layer "In4.Cu")
		(net "M_H_DQ<19>")
	)
	(arc
		(start 75.42911 -50.416968)
		(mid 75.362974 -50.620377)
		(end 75.41133 -50.828702)
		(width 0.0889)
		(layer "In4.Cu")
		(net "M_H_DQ<19>")
	)
	(segment
		(start 58.730896 -9.07034)
		(end 58.599324 -8.938768)
		(width 0.1651)
		(layer "F.Cu")
		(net "M_H_DQ<18>")
	)
	(segment
		(start 58.599324 -9.425432)
		(end 58.730896 -9.29386)
		(width 0.1651)
		(layer "F.Cu")
		(net "M_H_DQ<18>")
	)
	(segment
		(start 75.475846 -52.12334)
		(end 74.904346 -52.12334)
		(width 0.1016)
		(layer "F.Cu")
		(net "M_H_DQ<18>")
	)
	(segment
		(start 58.599578 -10.422382)
		(end 58.599324 -10.422128)
		(width 0.1651)
		(layer "F.Cu")
		(net "M_H_DQ<18>")
	)
	(segment
		(start 58.730896 -9.29386)
		(end 58.730896 -9.07034)
		(width 0.1651)
		(layer "F.Cu")
		(net "M_H_DQ<18>")
	)
	(segment
		(start 58.599324 -10.422128)
		(end 58.599324 -9.425432)
		(width 0.1651)
		(layer "F.Cu")
		(net "M_H_DQ<18>")
	)
	(segment
		(start 58.599324 -8.938768)
		(end 58.599324 -8.6614)
		(width 0.1651)
		(layer "F.Cu")
		(net "M_H_DQ<18>")
	)
	(via
		(at 58.599324 -8.6614)
		(size 0.508)
		(drill 0.254)
		(layers "F.Cu" "B.Cu")
		(net "M_H_DQ<18>")
	)
	(via
		(at 74.904346 -52.12334)
		(size 0.508)
		(drill 0.254)
		(layers "F.Cu" "B.Cu")
		(net "M_H_DQ<18>")
	)
	(via
		(at 57.74944 -13.959078)
		(size 0.508)
		(drill 0.254)
		(layers "F.Cu" "B.Cu")
		(net "M_H_DQ<18>")
	)
	(segment
		(start 57.74944 -15.222982)
		(end 57.74944 -13.959078)
		(width 0.1651)
		(layer "B.Cu")
		(net "M_H_DQ<18>")
	)
	(segment
		(start 74.904346 -52.461414)
		(end 74.962258 -52.519326)
		(width 0.0889)
		(layer "In4.Cu")
		(net "M_H_DQ<18>")
	)
	(segment
		(start 65.768982 -34.529014)
		(end 65.768982 -34.310066)
		(width 0.14224)
		(layer "In4.Cu")
		(net "M_H_DQ<18>")
	)
	(segment
		(start 58.318908 -14.836394)
		(end 57.74944 -14.266926)
		(width 0.14224)
		(layer "In4.Cu")
		(net "M_H_DQ<18>")
	)
	(segment
		(start 65.08115 -33.841182)
		(end 64.831214 -33.591246)
		(width 0.14224)
		(layer "In4.Cu")
		(net "M_H_DQ<18>")
	)
	(segment
		(start 65.300098 -33.841182)
		(end 65.08115 -33.841182)
		(width 0.14224)
		(layer "In4.Cu")
		(net "M_H_DQ<18>")
	)
	(segment
		(start 64.613282 -32.652462)
		(end 64.44234 -32.823404)
		(width 0.14224)
		(layer "In4.Cu")
		(net "M_H_DQ<18>")
	)
	(segment
		(start 75.313032 -50.225198)
		(end 75.313032 -49.718214)
		(width 0.0889)
		(layer "In4.Cu")
		(net "M_H_DQ<18>")
	)
	(segment
		(start 63.973456 -32.555688)
		(end 63.973456 -32.35452)
		(width 0.14224)
		(layer "In4.Cu")
		(net "M_H_DQ<18>")
	)
	(segment
		(start 60.405264 -31.3944)
		(end 58.331608 -29.320744)
		(width 0.14224)
		(layer "In4.Cu")
		(net "M_H_DQ<18>")
	)
	(segment
		(start 57.856374 -10.058146)
		(end 57.856374 -9.709404)
		(width 0.14224)
		(layer "In4.Cu")
		(net "M_H_DQ<18>")
	)
	(segment
		(start 58.313574 -12.079732)
		(end 58.313574 -11.811)
		(width 0.14224)
		(layer "In4.Cu")
		(net "M_H_DQ<18>")
	)
	(segment
		(start 57.464706 -13.674344)
		(end 57.464706 -12.9286)
		(width 0.14224)
		(layer "In4.Cu")
		(net "M_H_DQ<18>")
	)
	(segment
		(start 65.55105 -33.59023)
		(end 65.300098 -33.841182)
		(width 0.14224)
		(layer "In4.Cu")
		(net "M_H_DQ<18>")
	)
	(segment
		(start 58.201306 -9.059418)
		(end 58.599324 -8.6614)
		(width 0.14224)
		(layer "In4.Cu")
		(net "M_H_DQ<18>")
	)
	(segment
		(start 75.251056 -50.932588)
		(end 75.244706 -50.92192)
		(width 0.0889)
		(layer "In4.Cu")
		(net "M_H_DQ<18>")
	)
	(segment
		(start 68.425568 -42.81678)
		(end 68.425568 -36.2458)
		(width 0.14224)
		(layer "In4.Cu")
		(net "M_H_DQ<18>")
	)
	(segment
		(start 65.082166 -32.902398)
		(end 64.83223 -32.652462)
		(width 0.14224)
		(layer "In4.Cu")
		(net "M_H_DQ<18>")
	)
	(segment
		(start 66.237866 -34.77895)
		(end 66.018918 -34.77895)
		(width 0.14224)
		(layer "In4.Cu")
		(net "M_H_DQ<18>")
	)
	(segment
		(start 71.613268 -46.460918)
		(end 71.613268 -46.00448)
		(width 0.14224)
		(layer "In4.Cu")
		(net "M_H_DQ<18>")
	)
	(segment
		(start 58.090308 -23.143972)
		(end 58.090308 -21.950172)
		(width 0.14224)
		(layer "In4.Cu")
		(net "M_H_DQ<18>")
	)
	(segment
		(start 64.831214 -33.591246)
		(end 64.831214 -33.372298)
		(width 0.14224)
		(layer "In4.Cu")
		(net "M_H_DQ<18>")
	)
	(segment
		(start 66.018918 -34.77895)
		(end 65.768982 -34.529014)
		(width 0.14224)
		(layer "In4.Cu")
		(net "M_H_DQ<18>")
	)
	(segment
		(start 68.425568 -36.2458)
		(end 66.707766 -34.527998)
		(width 0.14224)
		(layer "In4.Cu")
		(net "M_H_DQ<18>")
	)
	(segment
		(start 58.161174 -10.362946)
		(end 57.856374 -10.058146)
		(width 0.14224)
		(layer "In4.Cu")
		(net "M_H_DQ<18>")
	)
	(segment
		(start 64.831214 -33.372298)
		(end 65.082166 -33.121346)
		(width 0.14224)
		(layer "In4.Cu")
		(net "M_H_DQ<18>")
	)
	(segment
		(start 66.707766 -34.527998)
		(end 66.488818 -34.527998)
		(width 0.14224)
		(layer "In4.Cu")
		(net "M_H_DQ<18>")
	)
	(segment
		(start 58.090308 -21.950172)
		(end 58.242708 -21.797772)
		(width 0.14224)
		(layer "In4.Cu")
		(net "M_H_DQ<18>")
	)
	(segment
		(start 57.464706 -12.9286)
		(end 58.313574 -12.079732)
		(width 0.14224)
		(layer "In4.Cu")
		(net "M_H_DQ<18>")
	)
	(segment
		(start 71.987918 -46.835568)
		(end 71.613268 -46.460918)
		(width 0.14224)
		(layer "In4.Cu")
		(net "M_H_DQ<18>")
	)
	(segment
		(start 58.242708 -18.570194)
		(end 58.115708 -18.443194)
		(width 0.14224)
		(layer "In4.Cu")
		(net "M_H_DQ<18>")
	)
	(segment
		(start 58.242708 -21.797772)
		(end 58.242708 -18.570194)
		(width 0.14224)
		(layer "In4.Cu")
		(net "M_H_DQ<18>")
	)
	(segment
		(start 58.331608 -29.320744)
		(end 58.331608 -23.385272)
		(width 0.14224)
		(layer "In4.Cu")
		(net "M_H_DQ<18>")
	)
	(segment
		(start 64.44234 -32.823404)
		(end 64.241172 -32.823404)
		(width 0.14224)
		(layer "In4.Cu")
		(net "M_H_DQ<18>")
	)
	(segment
		(start 64.144398 -32.183578)
		(end 64.144398 -31.96463)
		(width 0.14224)
		(layer "In4.Cu")
		(net "M_H_DQ<18>")
	)
	(segment
		(start 66.019934 -33.840166)
		(end 65.769998 -33.59023)
		(width 0.14224)
		(layer "In4.Cu")
		(net "M_H_DQ<18>")
	)
	(segment
		(start 58.161174 -10.64895)
		(end 58.161174 -10.362946)
		(width 0.14224)
		(layer "In4.Cu")
		(net "M_H_DQ<18>")
	)
	(segment
		(start 63.973456 -32.35452)
		(end 64.144398 -32.183578)
		(width 0.14224)
		(layer "In4.Cu")
		(net "M_H_DQ<18>")
	)
	(segment
		(start 57.856374 -9.709404)
		(end 58.201306 -9.364472)
		(width 0.14224)
		(layer "In4.Cu")
		(net "M_H_DQ<18>")
	)
	(segment
		(start 72.430386 -46.835568)
		(end 71.987918 -46.835568)
		(width 0.0889)
		(layer "In4.Cu")
		(net "M_H_DQ<18>")
	)
	(segment
		(start 57.74944 -14.266926)
		(end 57.74944 -13.959078)
		(width 0.14224)
		(layer "In4.Cu")
		(net "M_H_DQ<18>")
	)
	(segment
		(start 64.83223 -32.652462)
		(end 64.613282 -32.652462)
		(width 0.14224)
		(layer "In4.Cu")
		(net "M_H_DQ<18>")
	)
	(segment
		(start 65.769998 -33.59023)
		(end 65.55105 -33.59023)
		(width 0.14224)
		(layer "In4.Cu")
		(net "M_H_DQ<18>")
	)
	(segment
		(start 58.313574 -11.811)
		(end 57.856374 -11.3538)
		(width 0.14224)
		(layer "In4.Cu")
		(net "M_H_DQ<18>")
	)
	(segment
		(start 74.904346 -52.12334)
		(end 74.904346 -52.461414)
		(width 0.0889)
		(layer "In4.Cu")
		(net "M_H_DQ<18>")
	)
	(segment
		(start 58.115708 -18.443194)
		(end 58.115708 -16.967962)
		(width 0.14224)
		(layer "In4.Cu")
		(net "M_H_DQ<18>")
	)
	(segment
		(start 58.318908 -16.764762)
		(end 58.318908 -14.836394)
		(width 0.14224)
		(layer "In4.Cu")
		(net "M_H_DQ<18>")
	)
	(segment
		(start 66.019934 -34.059114)
		(end 66.019934 -33.840166)
		(width 0.14224)
		(layer "In4.Cu")
		(net "M_H_DQ<18>")
	)
	(segment
		(start 58.115708 -16.967962)
		(end 58.318908 -16.764762)
		(width 0.14224)
		(layer "In4.Cu")
		(net "M_H_DQ<18>")
	)
	(segment
		(start 71.613268 -46.00448)
		(end 68.425568 -42.81678)
		(width 0.14224)
		(layer "In4.Cu")
		(net "M_H_DQ<18>")
	)
	(segment
		(start 65.082166 -33.121346)
		(end 65.082166 -32.902398)
		(width 0.14224)
		(layer "In4.Cu")
		(net "M_H_DQ<18>")
	)
	(segment
		(start 57.856374 -10.95375)
		(end 58.161174 -10.64895)
		(width 0.14224)
		(layer "In4.Cu")
		(net "M_H_DQ<18>")
	)
	(segment
		(start 75.255882 -50.941224)
		(end 75.251056 -50.932588)
		(width 0.0889)
		(layer "In4.Cu")
		(net "M_H_DQ<18>")
	)
	(segment
		(start 57.74944 -13.959078)
		(end 57.464706 -13.674344)
		(width 0.14224)
		(layer "In4.Cu")
		(net "M_H_DQ<18>")
	)
	(segment
		(start 64.144398 -31.96463)
		(end 63.574168 -31.3944)
		(width 0.14224)
		(layer "In4.Cu")
		(net "M_H_DQ<18>")
	)
	(segment
		(start 58.331608 -23.385272)
		(end 58.090308 -23.143972)
		(width 0.14224)
		(layer "In4.Cu")
		(net "M_H_DQ<18>")
	)
	(segment
		(start 65.768982 -34.310066)
		(end 66.019934 -34.059114)
		(width 0.14224)
		(layer "In4.Cu")
		(net "M_H_DQ<18>")
	)
	(segment
		(start 75.251056 -50.342038)
		(end 75.313032 -50.225198)
		(width 0.0889)
		(layer "In4.Cu")
		(net "M_H_DQ<18>")
	)
	(segment
		(start 63.574168 -31.3944)
		(end 60.405264 -31.3944)
		(width 0.14224)
		(layer "In4.Cu")
		(net "M_H_DQ<18>")
	)
	(segment
		(start 58.201306 -9.364472)
		(end 58.201306 -9.059418)
		(width 0.14224)
		(layer "In4.Cu")
		(net "M_H_DQ<18>")
	)
	(segment
		(start 64.241172 -32.823404)
		(end 63.973456 -32.555688)
		(width 0.14224)
		(layer "In4.Cu")
		(net "M_H_DQ<18>")
	)
	(segment
		(start 75.313032 -49.718214)
		(end 72.430386 -46.835568)
		(width 0.0889)
		(layer "In4.Cu")
		(net "M_H_DQ<18>")
	)
	(segment
		(start 66.488818 -34.527998)
		(end 66.237866 -34.77895)
		(width 0.14224)
		(layer "In4.Cu")
		(net "M_H_DQ<18>")
	)
	(segment
		(start 57.856374 -11.3538)
		(end 57.856374 -10.95375)
		(width 0.14224)
		(layer "In4.Cu")
		(net "M_H_DQ<18>")
	)
	(arc
		(start 74.962258 -52.519326)
		(mid 75.264479 -52.297876)
		(end 75.251056 -51.923442)
		(width 0.0889)
		(layer "In4.Cu")
		(net "M_H_DQ<18>")
	)
	(arc
		(start 75.251056 -51.332638)
		(mid 75.304526 -51.137575)
		(end 75.255882 -50.941224)
		(width 0.0889)
		(layer "In4.Cu")
		(net "M_H_DQ<18>")
	)
	(arc
		(start 75.251056 -51.923442)
		(mid 75.171925 -51.62804)
		(end 75.251056 -51.332638)
		(width 0.0889)
		(layer "In4.Cu")
		(net "M_H_DQ<18>")
	)
	(arc
		(start 75.244706 -50.92192)
		(mid 75.171908 -50.631157)
		(end 75.251056 -50.342038)
		(width 0.0889)
		(layer "In4.Cu")
		(net "M_H_DQ<18>")
	)
	(segment
		(start 72.900286 -53.60924)
		(end 72.328786 -53.60924)
		(width 0.1016)
		(layer "F.Cu")
		(net "M_H_DQ<17>")
	)
	(segment
		(start 51.79949 -5.822442)
		(end 51.79949 -7.086346)
		(width 0.1651)
		(layer "F.Cu")
		(net "M_H_DQ<17>")
	)
	(via
		(at 72.328786 -53.60924)
		(size 0.508)
		(drill 0.254)
		(layers "F.Cu" "B.Cu")
		(net "M_H_DQ<17>")
	)
	(via
		(at 51.79949 -7.086346)
		(size 0.508)
		(drill 0.254)
		(layers "F.Cu" "B.Cu")
		(net "M_H_DQ<17>")
	)
	(via
		(at 52.471574 -12.678156)
		(size 0.508)
		(drill 0.254)
		(layers "F.Cu" "B.Cu")
		(net "M_H_DQ<17>")
	)
	(segment
		(start 52.471574 -12.174982)
		(end 52.471574 -12.678156)
		(width 0.1651)
		(layer "B.Cu")
		(net "M_H_DQ<17>")
	)
	(segment
		(start 52.649374 -11.997182)
		(end 52.471574 -12.174982)
		(width 0.1651)
		(layer "B.Cu")
		(net "M_H_DQ<17>")
	)
	(segment
		(start 52.649374 -10.623042)
		(end 52.649374 -11.997182)
		(width 0.1651)
		(layer "B.Cu")
		(net "M_H_DQ<17>")
	)
	(segment
		(start 72.311006 -51.228244)
		(end 72.34936 -51.228244)
		(width 0.0889)
		(layer "In4.Cu")
		(net "M_H_DQ<17>")
	)
	(segment
		(start 58.703464 -34.918142)
		(end 58.703464 -35.92195)
		(width 0.14224)
		(layer "In4.Cu")
		(net "M_H_DQ<17>")
	)
	(segment
		(start 52.487068 -25.350216)
		(end 53.236368 -26.099516)
		(width 0.14224)
		(layer "In4.Cu")
		(net "M_H_DQ<17>")
	)
	(segment
		(start 51.79949 -7.086346)
		(end 51.79949 -7.625334)
		(width 0.14224)
		(layer "In4.Cu")
		(net "M_H_DQ<17>")
	)
	(segment
		(start 52.324508 -13.87094)
		(end 52.324508 -15.64894)
		(width 0.14224)
		(layer "In4.Cu")
		(net "M_H_DQ<17>")
	)
	(segment
		(start 53.236368 -26.099516)
		(end 53.236368 -29.451046)
		(width 0.14224)
		(layer "In4.Cu")
		(net "M_H_DQ<17>")
	)
	(segment
		(start 52.487068 -24.791416)
		(end 52.487068 -25.350216)
		(width 0.14224)
		(layer "In4.Cu")
		(net "M_H_DQ<17>")
	)
	(segment
		(start 66.686176 -46.539658)
		(end 66.686176 -47.269146)
		(width 0.14224)
		(layer "In4.Cu")
		(net "M_H_DQ<17>")
	)
	(segment
		(start 72.680322 -51.819302)
		(end 72.675496 -51.827938)
		(width 0.0889)
		(layer "In4.Cu")
		(net "M_H_DQ<17>")
	)
	(segment
		(start 53.236368 -29.451046)
		(end 58.703464 -34.918142)
		(width 0.14224)
		(layer "In4.Cu")
		(net "M_H_DQ<17>")
	)
	(segment
		(start 72.570594 -51.951382)
		(end 72.0852 -52.300886)
		(width 0.0889)
		(layer "In4.Cu")
		(net "M_H_DQ<17>")
	)
	(segment
		(start 70.112128 -50.57394)
		(end 70.265036 -50.837338)
		(width 0.0889)
		(layer "In4.Cu")
		(net "M_H_DQ<17>")
	)
	(segment
		(start 51.945032 -13.204698)
		(end 51.945032 -13.491464)
		(width 0.14224)
		(layer "In4.Cu")
		(net "M_H_DQ<17>")
	)
	(segment
		(start 51.945032 -13.491464)
		(end 52.324508 -13.87094)
		(width 0.14224)
		(layer "In4.Cu")
		(net "M_H_DQ<17>")
	)
	(segment
		(start 63.497968 -40.716454)
		(end 63.497968 -43.35145)
		(width 0.14224)
		(layer "In4.Cu")
		(net "M_H_DQ<17>")
	)
	(segment
		(start 52.471574 -12.678156)
		(end 51.945032 -13.204698)
		(width 0.14224)
		(layer "In4.Cu")
		(net "M_H_DQ<17>")
	)
	(segment
		(start 71.45528 -50.73269)
		(end 71.485252 -50.73269)
		(width 0.0889)
		(layer "In4.Cu")
		(net "M_H_DQ<17>")
	)
	(segment
		(start 68.560696 -49.022762)
		(end 70.112128 -50.57394)
		(width 0.0889)
		(layer "In4.Cu")
		(net "M_H_DQ<17>")
	)
	(segment
		(start 66.686176 -47.553118)
		(end 68.15582 -49.022762)
		(width 0.0889)
		(layer "In4.Cu")
		(net "M_H_DQ<17>")
	)
	(segment
		(start 71.99884 -52.84724)
		(end 72.328786 -53.60924)
		(width 0.0889)
		(layer "In4.Cu")
		(net "M_H_DQ<17>")
	)
	(segment
		(start 53.00218 -8.472424)
		(end 53.00218 -8.8138)
		(width 0.14224)
		(layer "In4.Cu")
		(net "M_H_DQ<17>")
	)
	(segment
		(start 52.324508 -15.64894)
		(end 52.959508 -16.28394)
		(width 0.14224)
		(layer "In4.Cu")
		(net "M_H_DQ<17>")
	)
	(segment
		(start 68.15582 -49.022762)
		(end 68.560696 -49.022762)
		(width 0.0889)
		(layer "In4.Cu")
		(net "M_H_DQ<17>")
	)
	(segment
		(start 52.959508 -16.28394)
		(end 52.959508 -24.318976)
		(width 0.14224)
		(layer "In4.Cu")
		(net "M_H_DQ<17>")
	)
	(segment
		(start 71.982076 -52.818284)
		(end 71.99884 -52.84724)
		(width 0.0889)
		(layer "In4.Cu")
		(net "M_H_DQ<17>")
	)
	(segment
		(start 72.675496 -51.827938)
		(end 72.632062 -51.903376)
		(width 0.0889)
		(layer "In4.Cu")
		(net "M_H_DQ<17>")
	)
	(segment
		(start 66.686176 -47.269146)
		(end 66.686176 -47.553118)
		(width 0.0889)
		(layer "In4.Cu")
		(net "M_H_DQ<17>")
	)
	(segment
		(start 53.00218 -8.8138)
		(end 52.845716 -8.970264)
		(width 0.14224)
		(layer "In4.Cu")
		(net "M_H_DQ<17>")
	)
	(segment
		(start 52.959508 -24.318976)
		(end 52.487068 -24.791416)
		(width 0.14224)
		(layer "In4.Cu")
		(net "M_H_DQ<17>")
	)
	(segment
		(start 72.632062 -51.903376)
		(end 72.570594 -51.951382)
		(width 0.0889)
		(layer "In4.Cu")
		(net "M_H_DQ<17>")
	)
	(segment
		(start 52.632356 -8.1026)
		(end 53.00218 -8.472424)
		(width 0.14224)
		(layer "In4.Cu")
		(net "M_H_DQ<17>")
	)
	(segment
		(start 70.59676 -51.03749)
		(end 70.700392 -51.03749)
		(width 0.0889)
		(layer "In4.Cu")
		(net "M_H_DQ<17>")
	)
	(segment
		(start 52.276756 -8.1026)
		(end 52.632356 -8.1026)
		(width 0.14224)
		(layer "In4.Cu")
		(net "M_H_DQ<17>")
	)
	(segment
		(start 63.497968 -43.35145)
		(end 66.686176 -46.539658)
		(width 0.14224)
		(layer "In4.Cu")
		(net "M_H_DQ<17>")
	)
	(segment
		(start 51.79949 -7.625334)
		(end 52.276756 -8.1026)
		(width 0.14224)
		(layer "In4.Cu")
		(net "M_H_DQ<17>")
	)
	(segment
		(start 58.703464 -35.92195)
		(end 63.497968 -40.716454)
		(width 0.14224)
		(layer "In4.Cu")
		(net "M_H_DQ<17>")
	)
	(segment
		(start 52.845716 -12.304014)
		(end 52.471574 -12.678156)
		(width 0.14224)
		(layer "In4.Cu")
		(net "M_H_DQ<17>")
	)
	(segment
		(start 70.700392 -51.03749)
		(end 71.231506 -50.81143)
		(width 0.0889)
		(layer "In4.Cu")
		(net "M_H_DQ<17>")
	)
	(segment
		(start 52.845716 -8.970264)
		(end 52.845716 -12.304014)
		(width 0.14224)
		(layer "In4.Cu")
		(net "M_H_DQ<17>")
	)
	(arc
		(start 71.816976 -50.932842)
		(mid 72.025584 -51.144774)
		(end 72.311006 -51.228244)
		(width 0.0889)
		(layer "In4.Cu")
		(net "M_H_DQ<17>")
	)
	(arc
		(start 72.675496 -51.427888)
		(mid 72.728966 -51.622951)
		(end 72.680322 -51.819302)
		(width 0.0889)
		(layer "In4.Cu")
		(net "M_H_DQ<17>")
	)
	(arc
		(start 70.265036 -50.837338)
		(mid 70.405054 -50.980249)
		(end 70.59676 -51.03749)
		(width 0.0889)
		(layer "In4.Cu")
		(net "M_H_DQ<17>")
	)
	(arc
		(start 71.231506 -50.81143)
		(mid 71.33742 -50.75508)
		(end 71.45528 -50.73269)
		(width 0.0889)
		(layer "In4.Cu")
		(net "M_H_DQ<17>")
	)
	(arc
		(start 72.0852 -52.300886)
		(mid 72.02785 -52.35461)
		(end 71.982076 -52.418488)
		(width 0.0889)
		(layer "In4.Cu")
		(net "M_H_DQ<17>")
	)
	(arc
		(start 71.485252 -50.73269)
		(mid 71.676956 -50.789936)
		(end 71.816976 -50.932842)
		(width 0.0889)
		(layer "In4.Cu")
		(net "M_H_DQ<17>")
	)
	(arc
		(start 72.34936 -51.228244)
		(mid 72.537802 -51.286613)
		(end 72.675496 -51.427888)
		(width 0.0889)
		(layer "In4.Cu")
		(net "M_H_DQ<17>")
	)
	(arc
		(start 71.982076 -52.418488)
		(mid 71.928577 -52.618386)
		(end 71.982076 -52.818284)
		(width 0.0889)
		(layer "In4.Cu")
		(net "M_H_DQ<17>")
	)
	(segment
		(start 52.649374 -10.422382)
		(end 52.490878 -8.763)
		(width 0.1651)
		(layer "F.Cu")
		(net "M_H_DQ<16>")
	)
	(segment
		(start 72.900286 -51.62804)
		(end 72.328786 -51.62804)
		(width 0.1016)
		(layer "F.Cu")
		(net "M_H_DQ<16>")
	)
	(segment
		(start 52.490878 -8.763)
		(end 52.471574 -8.5598)
		(width 0.1651)
		(layer "F.Cu")
		(net "M_H_DQ<16>")
	)
	(via
		(at 52.471574 -8.5598)
		(size 0.508)
		(drill 0.254)
		(layers "F.Cu" "B.Cu")
		(net "M_H_DQ<16>")
	)
	(via
		(at 72.328786 -51.62804)
		(size 0.508)
		(drill 0.254)
		(layers "F.Cu" "B.Cu")
		(net "M_H_DQ<16>")
	)
	(via
		(at 51.79949 -13.959078)
		(size 0.508)
		(drill 0.254)
		(layers "F.Cu" "B.Cu")
		(net "M_H_DQ<16>")
	)
	(segment
		(start 51.79949 -15.222982)
		(end 51.79949 -13.959078)
		(width 0.1651)
		(layer "B.Cu")
		(net "M_H_DQ<16>")
	)
	(segment
		(start 68.076826 -49.213008)
		(end 66.579242 -47.715424)
		(width 0.0889)
		(layer "In4.Cu")
		(net "M_H_DQ<16>")
	)
	(segment
		(start 52.251356 -8.780018)
		(end 52.471574 -8.5598)
		(width 0.14224)
		(layer "In4.Cu")
		(net "M_H_DQ<16>")
	)
	(segment
		(start 51.740308 -24.40686)
		(end 52.296568 -23.8506)
		(width 0.14224)
		(layer "In4.Cu")
		(net "M_H_DQ<16>")
	)
	(segment
		(start 56.523636 -34.29)
		(end 56.764428 -34.049208)
		(width 0.14224)
		(layer "In4.Cu")
		(net "M_H_DQ<16>")
	)
	(segment
		(start 54.888892 -32.173672)
		(end 54.888892 -31.954978)
		(width 0.14224)
		(layer "In4.Cu")
		(net "M_H_DQ<16>")
	)
	(segment
		(start 55.468012 -33.470088)
		(end 55.82666 -33.111694)
		(width 0.14224)
		(layer "In4.Cu")
		(net "M_H_DQ<16>")
	)
	(segment
		(start 55.576724 -32.64281)
		(end 55.357522 -32.64281)
		(width 0.14224)
		(layer "In4.Cu")
		(net "M_H_DQ<16>")
	)
	(segment
		(start 52.677568 -29.743654)
		(end 52.677568 -26.679144)
		(width 0.14224)
		(layer "In4.Cu")
		(net "M_H_DQ<16>")
	)
	(segment
		(start 71.50481 -51.532536)
		(end 71.45528 -51.532536)
		(width 0.0889)
		(layer "In4.Cu")
		(net "M_H_DQ<16>")
	)
	(segment
		(start 52.273708 -16.43634)
		(end 51.79949 -15.962122)
		(width 0.14224)
		(layer "In4.Cu")
		(net "M_H_DQ<16>")
	)
	(segment
		(start 56.764428 -33.830514)
		(end 56.514492 -33.580578)
		(width 0.14224)
		(layer "In4.Cu")
		(net "M_H_DQ<16>")
	)
	(segment
		(start 62.862968 -40.979598)
		(end 57.924192 -36.040822)
		(width 0.14224)
		(layer "In4.Cu")
		(net "M_H_DQ<16>")
	)
	(segment
		(start 52.296568 -23.4188)
		(end 51.981608 -23.10384)
		(width 0.14224)
		(layer "In4.Cu")
		(net "M_H_DQ<16>")
	)
	(segment
		(start 52.273708 -16.831818)
		(end 52.273708 -16.43634)
		(width 0.14224)
		(layer "In4.Cu")
		(net "M_H_DQ<16>")
	)
	(segment
		(start 70.099936 -50.932842)
		(end 69.959982 -50.69078)
		(width 0.0889)
		(layer "In4.Cu")
		(net "M_H_DQ<16>")
	)
	(segment
		(start 54.643782 -32.598614)
		(end 54.643782 -32.418782)
		(width 0.14224)
		(layer "In4.Cu")
		(net "M_H_DQ<16>")
	)
	(segment
		(start 51.861974 -11.302746)
		(end 51.861974 -10.9982)
		(width 0.14224)
		(layer "In4.Cu")
		(net "M_H_DQ<16>")
	)
	(segment
		(start 55.112666 -32.887666)
		(end 54.932834 -32.887666)
		(width 0.14224)
		(layer "In4.Cu")
		(net "M_H_DQ<16>")
	)
	(segment
		(start 52.179474 -10.6807)
		(end 52.179474 -10.4521)
		(width 0.14224)
		(layer "In4.Cu")
		(net "M_H_DQ<16>")
	)
	(segment
		(start 52.179474 -10.4521)
		(end 51.836574 -10.1092)
		(width 0.14224)
		(layer "In4.Cu")
		(net "M_H_DQ<16>")
	)
	(segment
		(start 66.579242 -47.715424)
		(end 66.239644 -47.715424)
		(width 0.0889)
		(layer "In4.Cu")
		(net "M_H_DQ<16>")
	)
	(segment
		(start 54.888892 -31.954978)
		(end 52.677568 -29.743654)
		(width 0.14224)
		(layer "In4.Cu")
		(net "M_H_DQ<16>")
	)
	(segment
		(start 55.82666 -32.892746)
		(end 55.576724 -32.64281)
		(width 0.14224)
		(layer "In4.Cu")
		(net "M_H_DQ<16>")
	)
	(segment
		(start 57.45226 -34.518346)
		(end 57.233058 -34.518346)
		(width 0.14224)
		(layer "In4.Cu")
		(net "M_H_DQ<16>")
	)
	(segment
		(start 51.836574 -10.1092)
		(end 51.836574 -9.779254)
		(width 0.14224)
		(layer "In4.Cu")
		(net "M_H_DQ<16>")
	)
	(segment
		(start 52.251356 -11.692128)
		(end 51.861974 -11.302746)
		(width 0.14224)
		(layer "In4.Cu")
		(net "M_H_DQ<16>")
	)
	(segment
		(start 55.468012 -33.689036)
		(end 55.468012 -33.470088)
		(width 0.14224)
		(layer "In4.Cu")
		(net "M_H_DQ<16>")
	)
	(segment
		(start 56.514492 -33.580578)
		(end 56.295544 -33.580578)
		(width 0.14224)
		(layer "In4.Cu")
		(net "M_H_DQ<16>")
	)
	(segment
		(start 52.251356 -9.364472)
		(end 52.251356 -8.780018)
		(width 0.14224)
		(layer "In4.Cu")
		(net "M_H_DQ<16>")
	)
	(segment
		(start 57.233058 -34.518346)
		(end 56.99252 -34.758884)
		(width 0.14224)
		(layer "In4.Cu")
		(net "M_H_DQ<16>")
	)
	(segment
		(start 51.514756 -13.674344)
		(end 51.514756 -12.9286)
		(width 0.14224)
		(layer "In4.Cu")
		(net "M_H_DQ<16>")
	)
	(segment
		(start 69.959982 -50.69078)
		(end 68.481956 -49.212754)
		(width 0.0889)
		(layer "In4.Cu")
		(net "M_H_DQ<16>")
	)
	(segment
		(start 65.974468 -47.450248)
		(end 65.974468 -46.726094)
		(width 0.14224)
		(layer "In4.Cu")
		(net "M_H_DQ<16>")
	)
	(segment
		(start 68.481956 -49.212754)
		(end 68.481702 -49.212754)
		(width 0.0889)
		(layer "In4.Cu")
		(net "M_H_DQ<16>")
	)
	(segment
		(start 51.981608 -18.302986)
		(end 51.981608 -17.123918)
		(width 0.14224)
		(layer "In4.Cu")
		(net "M_H_DQ<16>")
	)
	(segment
		(start 56.791352 -34.758884)
		(end 56.523636 -34.491168)
		(width 0.14224)
		(layer "In4.Cu")
		(net "M_H_DQ<16>")
	)
	(segment
		(start 62.862968 -43.614594)
		(end 62.862968 -40.979598)
		(width 0.14224)
		(layer "In4.Cu")
		(net "M_H_DQ<16>")
	)
	(segment
		(start 55.82666 -33.111694)
		(end 55.82666 -32.892746)
		(width 0.14224)
		(layer "In4.Cu")
		(net "M_H_DQ<16>")
	)
	(segment
		(start 68.481702 -49.212754)
		(end 68.481448 -49.213008)
		(width 0.0889)
		(layer "In4.Cu")
		(net "M_H_DQ<16>")
	)
	(segment
		(start 52.677568 -26.679144)
		(end 51.740308 -25.741884)
		(width 0.14224)
		(layer "In4.Cu")
		(net "M_H_DQ<16>")
	)
	(segment
		(start 56.295544 -33.580578)
		(end 55.936896 -33.938972)
		(width 0.14224)
		(layer "In4.Cu")
		(net "M_H_DQ<16>")
	)
	(segment
		(start 56.99252 -34.758884)
		(end 56.791352 -34.758884)
		(width 0.14224)
		(layer "In4.Cu")
		(net "M_H_DQ<16>")
	)
	(segment
		(start 52.324508 -21.683472)
		(end 52.324508 -18.645886)
		(width 0.14224)
		(layer "In4.Cu")
		(net "M_H_DQ<16>")
	)
	(segment
		(start 55.357522 -32.64281)
		(end 55.112666 -32.887666)
		(width 0.14224)
		(layer "In4.Cu")
		(net "M_H_DQ<16>")
	)
	(segment
		(start 66.239644 -47.715424)
		(end 65.974468 -47.450248)
		(width 0.14224)
		(layer "In4.Cu")
		(net "M_H_DQ<16>")
	)
	(segment
		(start 52.251356 -12.192)
		(end 52.251356 -11.692128)
		(width 0.14224)
		(layer "In4.Cu")
		(net "M_H_DQ<16>")
	)
	(segment
		(start 56.764428 -34.049208)
		(end 56.764428 -33.830514)
		(width 0.14224)
		(layer "In4.Cu")
		(net "M_H_DQ<16>")
	)
	(segment
		(start 51.514756 -12.9286)
		(end 52.251356 -12.192)
		(width 0.14224)
		(layer "In4.Cu")
		(net "M_H_DQ<16>")
	)
	(segment
		(start 51.981608 -23.10384)
		(end 51.981608 -22.026372)
		(width 0.14224)
		(layer "In4.Cu")
		(net "M_H_DQ<16>")
	)
	(segment
		(start 72.328786 -51.62804)
		(end 71.50481 -51.532536)
		(width 0.0889)
		(layer "In4.Cu")
		(net "M_H_DQ<16>")
	)
	(segment
		(start 54.643782 -32.418782)
		(end 54.888892 -32.173672)
		(width 0.14224)
		(layer "In4.Cu")
		(net "M_H_DQ<16>")
	)
	(segment
		(start 68.481448 -49.213008)
		(end 68.076826 -49.213008)
		(width 0.0889)
		(layer "In4.Cu")
		(net "M_H_DQ<16>")
	)
	(segment
		(start 65.974468 -46.726094)
		(end 62.862968 -43.614594)
		(width 0.14224)
		(layer "In4.Cu")
		(net "M_H_DQ<16>")
	)
	(segment
		(start 55.717948 -33.938972)
		(end 55.468012 -33.689036)
		(width 0.14224)
		(layer "In4.Cu")
		(net "M_H_DQ<16>")
	)
	(segment
		(start 52.296568 -23.8506)
		(end 52.296568 -23.4188)
		(width 0.14224)
		(layer "In4.Cu")
		(net "M_H_DQ<16>")
	)
	(segment
		(start 57.924192 -36.040822)
		(end 57.924192 -34.990278)
		(width 0.14224)
		(layer "In4.Cu")
		(net "M_H_DQ<16>")
	)
	(segment
		(start 51.861974 -10.9982)
		(end 52.179474 -10.6807)
		(width 0.14224)
		(layer "In4.Cu")
		(net "M_H_DQ<16>")
	)
	(segment
		(start 56.523636 -34.491168)
		(end 56.523636 -34.29)
		(width 0.14224)
		(layer "In4.Cu")
		(net "M_H_DQ<16>")
	)
	(segment
		(start 55.936896 -33.938972)
		(end 55.717948 -33.938972)
		(width 0.14224)
		(layer "In4.Cu")
		(net "M_H_DQ<16>")
	)
	(segment
		(start 51.981608 -22.026372)
		(end 52.324508 -21.683472)
		(width 0.14224)
		(layer "In4.Cu")
		(net "M_H_DQ<16>")
	)
	(segment
		(start 57.924192 -34.990278)
		(end 57.45226 -34.518346)
		(width 0.14224)
		(layer "In4.Cu")
		(net "M_H_DQ<16>")
	)
	(segment
		(start 51.836574 -9.779254)
		(end 52.251356 -9.364472)
		(width 0.14224)
		(layer "In4.Cu")
		(net "M_H_DQ<16>")
	)
	(segment
		(start 70.751192 -51.228244)
		(end 70.593966 -51.228244)
		(width 0.0889)
		(layer "In4.Cu")
		(net "M_H_DQ<16>")
	)
	(segment
		(start 51.79949 -13.959078)
		(end 51.514756 -13.674344)
		(width 0.14224)
		(layer "In4.Cu")
		(net "M_H_DQ<16>")
	)
	(segment
		(start 51.79949 -15.962122)
		(end 51.79949 -13.959078)
		(width 0.14224)
		(layer "In4.Cu")
		(net "M_H_DQ<16>")
	)
	(segment
		(start 52.324508 -18.645886)
		(end 51.981608 -18.302986)
		(width 0.14224)
		(layer "In4.Cu")
		(net "M_H_DQ<16>")
	)
	(segment
		(start 54.932834 -32.887666)
		(end 54.643782 -32.598614)
		(width 0.14224)
		(layer "In4.Cu")
		(net "M_H_DQ<16>")
	)
	(segment
		(start 51.740308 -25.741884)
		(end 51.740308 -24.40686)
		(width 0.14224)
		(layer "In4.Cu")
		(net "M_H_DQ<16>")
	)
	(segment
		(start 51.981608 -17.123918)
		(end 52.273708 -16.831818)
		(width 0.14224)
		(layer "In4.Cu")
		(net "M_H_DQ<16>")
	)
	(arc
		(start 71.45528 -51.532536)
		(mid 71.335924 -51.509522)
		(end 71.228966 -51.451764)
		(width 0.0889)
		(layer "In4.Cu")
		(net "M_H_DQ<16>")
	)
	(arc
		(start 71.228966 -51.451764)
		(mid 71.001869 -51.314799)
		(end 70.751192 -51.228244)
		(width 0.0889)
		(layer "In4.Cu")
		(net "M_H_DQ<16>")
	)
	(arc
		(start 70.593966 -51.228244)
		(mid 70.308542 -51.144777)
		(end 70.099936 -50.932842)
		(width 0.0889)
		(layer "In4.Cu")
		(net "M_H_DQ<16>")
	)
	(segment
		(start 46.699424 -5.822442)
		(end 46.699424 -7.086346)
		(width 0.1651)
		(layer "F.Cu")
		(net "M_H_DQ<15>")
	)
	(segment
		(start 72.900286 -60.54344)
		(end 72.328786 -60.54344)
		(width 0.1016)
		(layer "F.Cu")
		(net "M_H_DQ<15>")
	)
	(via
		(at 72.328786 -60.54344)
		(size 0.508)
		(drill 0.254)
		(layers "F.Cu" "B.Cu")
		(net "M_H_DQ<15>")
	)
	(via
		(at 47.549308 -12.678156)
		(size 0.508)
		(drill 0.254)
		(layers "F.Cu" "B.Cu")
		(net "M_H_DQ<15>")
	)
	(via
		(at 46.699424 -7.086346)
		(size 0.508)
		(drill 0.254)
		(layers "F.Cu" "B.Cu")
		(net "M_H_DQ<15>")
	)
	(segment
		(start 47.549308 -10.780776)
		(end 47.549308 -12.678156)
		(width 0.1651)
		(layer "B.Cu")
		(net "M_H_DQ<15>")
	)
	(segment
		(start 47.549562 -10.780522)
		(end 47.549308 -10.780776)
		(width 0.1651)
		(layer "B.Cu")
		(net "M_H_DQ<15>")
	)
	(segment
		(start 47.549562 -10.623042)
		(end 47.549562 -10.780522)
		(width 0.1651)
		(layer "B.Cu")
		(net "M_H_DQ<15>")
	)
	(segment
		(start 57.457594 -43.753532)
		(end 57.238646 -43.753532)
		(width 0.14224)
		(layer "In4.Cu")
		(net "M_H_DQ<15>")
	)
	(segment
		(start 48.130714 -17.082262)
		(end 47.851314 -16.802862)
		(width 0.14224)
		(layer "In4.Cu")
		(net "M_H_DQ<15>")
	)
	(segment
		(start 47.016162 -7.7216)
		(end 47.016162 -7.403084)
		(width 0.14224)
		(layer "In4.Cu")
		(net "M_H_DQ<15>")
	)
	(segment
		(start 56.64581 -41.307258)
		(end 56.64581 -41.01973)
		(width 0.14224)
		(layer "In4.Cu")
		(net "M_H_DQ<15>")
	)
	(segment
		(start 47.749968 -23.748746)
		(end 47.927514 -23.5712)
		(width 0.14224)
		(layer "In4.Cu")
		(net "M_H_DQ<15>")
	)
	(segment
		(start 57.512712 -42.7609)
		(end 57.512712 -42.541952)
		(width 0.14224)
		(layer "In4.Cu")
		(net "M_H_DQ<15>")
	)
	(segment
		(start 69.464174 -55.494936)
		(end 69.242432 -55.273194)
		(width 0.0889)
		(layer "In4.Cu")
		(net "M_H_DQ<15>")
	)
	(segment
		(start 58.919364 -44.167552)
		(end 58.509662 -44.577)
		(width 0.14224)
		(layer "In4.Cu")
		(net "M_H_DQ<15>")
	)
	(segment
		(start 47.851314 -16.802862)
		(end 47.851314 -14.778228)
		(width 0.14224)
		(layer "In4.Cu")
		(net "M_H_DQ<15>")
	)
	(segment
		(start 58.864246 -45.160184)
		(end 59.388248 -44.636436)
		(width 0.14224)
		(layer "In4.Cu")
		(net "M_H_DQ<15>")
	)
	(segment
		(start 57.238646 -43.753532)
		(end 56.98871 -43.503596)
		(width 0.14224)
		(layer "In4.Cu")
		(net "M_H_DQ<15>")
	)
	(segment
		(start 47.549308 -12.678156)
		(end 47.902114 -12.32535)
		(width 0.14224)
		(layer "In4.Cu")
		(net "M_H_DQ<15>")
	)
	(segment
		(start 48.057562 -8.8646)
		(end 48.057562 -8.509)
		(width 0.14224)
		(layer "In4.Cu")
		(net "M_H_DQ<15>")
	)
	(segment
		(start 58.509662 -44.577)
		(end 58.395362 -44.6913)
		(width 0.14224)
		(layer "In4.Cu")
		(net "M_H_DQ<15>")
	)
	(segment
		(start 47.902114 -9.020048)
		(end 48.057562 -8.8646)
		(width 0.14224)
		(layer "In4.Cu")
		(net "M_H_DQ<15>")
	)
	(segment
		(start 58.395362 -44.6913)
		(end 58.176414 -44.6913)
		(width 0.14224)
		(layer "In4.Cu")
		(net "M_H_DQ<15>")
	)
	(segment
		(start 56.519826 -42.815764)
		(end 56.300878 -42.815764)
		(width 0.14224)
		(layer "In4.Cu")
		(net "M_H_DQ<15>")
	)
	(segment
		(start 47.600362 -8.0518)
		(end 47.346362 -8.0518)
		(width 0.14224)
		(layer "In4.Cu")
		(net "M_H_DQ<15>")
	)
	(segment
		(start 57.512712 -42.541952)
		(end 57.262776 -42.292016)
		(width 0.14224)
		(layer "In4.Cu")
		(net "M_H_DQ<15>")
	)
	(segment
		(start 57.043828 -42.292016)
		(end 56.519826 -42.815764)
		(width 0.14224)
		(layer "In4.Cu")
		(net "M_H_DQ<15>")
	)
	(segment
		(start 47.902114 -18.567654)
		(end 48.130714 -18.339054)
		(width 0.14224)
		(layer "In4.Cu")
		(net "M_H_DQ<15>")
	)
	(segment
		(start 71.342504 -60.543186)
		(end 70.942454 -60.943236)
		(width 0.0889)
		(layer "In4.Cu")
		(net "M_H_DQ<15>")
	)
	(segment
		(start 59.388248 -44.417488)
		(end 59.138312 -44.167552)
		(width 0.14224)
		(layer "In4.Cu")
		(net "M_H_DQ<15>")
	)
	(segment
		(start 47.209964 -14.136878)
		(end 47.209964 -13.75283)
		(width 0.14224)
		(layer "In4.Cu")
		(net "M_H_DQ<15>")
	)
	(segment
		(start 48.105314 -23.118572)
		(end 48.105314 -21.975572)
		(width 0.14224)
		(layer "In4.Cu")
		(net "M_H_DQ<15>")
	)
	(segment
		(start 58.45048 -43.47972)
		(end 58.200544 -43.229784)
		(width 0.14224)
		(layer "In4.Cu")
		(net "M_H_DQ<15>")
	)
	(segment
		(start 47.016162 -7.403084)
		(end 46.699424 -7.086346)
		(width 0.14224)
		(layer "In4.Cu")
		(net "M_H_DQ<15>")
	)
	(segment
		(start 47.346362 -8.0518)
		(end 47.016162 -7.7216)
		(width 0.14224)
		(layer "In4.Cu")
		(net "M_H_DQ<15>")
	)
	(segment
		(start 47.089314 -13.63218)
		(end 47.089314 -13.13815)
		(width 0.14224)
		(layer "In4.Cu")
		(net "M_H_DQ<15>")
	)
	(segment
		(start 47.927514 -23.296372)
		(end 48.105314 -23.118572)
		(width 0.14224)
		(layer "In4.Cu")
		(net "M_H_DQ<15>")
	)
	(segment
		(start 47.749968 -30.8229)
		(end 47.749968 -23.748746)
		(width 0.14224)
		(layer "In4.Cu")
		(net "M_H_DQ<15>")
	)
	(segment
		(start 57.926478 -44.441364)
		(end 57.926478 -44.222416)
		(width 0.14224)
		(layer "In4.Cu")
		(net "M_H_DQ<15>")
	)
	(segment
		(start 56.64581 -41.01973)
		(end 53.786024 -38.159944)
		(width 0.14224)
		(layer "In4.Cu")
		(net "M_H_DQ<15>")
	)
	(segment
		(start 68.758308 -55.273194)
		(end 58.864246 -45.379132)
		(width 0.14224)
		(layer "In4.Cu")
		(net "M_H_DQ<15>")
	)
	(segment
		(start 55.875682 -42.077386)
		(end 56.64581 -41.307258)
		(width 0.14224)
		(layer "In4.Cu")
		(net "M_H_DQ<15>")
	)
	(segment
		(start 47.089314 -13.13815)
		(end 47.549308 -12.678156)
		(width 0.14224)
		(layer "In4.Cu")
		(net "M_H_DQ<15>")
	)
	(segment
		(start 48.130714 -18.339054)
		(end 48.130714 -17.082262)
		(width 0.14224)
		(layer "In4.Cu")
		(net "M_H_DQ<15>")
	)
	(segment
		(start 55.875682 -42.390568)
		(end 55.875682 -42.077386)
		(width 0.14224)
		(layer "In4.Cu")
		(net "M_H_DQ<15>")
	)
	(segment
		(start 58.45048 -43.698668)
		(end 58.45048 -43.47972)
		(width 0.14224)
		(layer "In4.Cu")
		(net "M_H_DQ<15>")
	)
	(segment
		(start 56.98871 -43.503596)
		(end 56.98871 -43.284648)
		(width 0.14224)
		(layer "In4.Cu")
		(net "M_H_DQ<15>")
	)
	(segment
		(start 57.262776 -42.292016)
		(end 57.043828 -42.292016)
		(width 0.14224)
		(layer "In4.Cu")
		(net "M_H_DQ<15>")
	)
	(segment
		(start 59.388248 -44.636436)
		(end 59.388248 -44.417488)
		(width 0.14224)
		(layer "In4.Cu")
		(net "M_H_DQ<15>")
	)
	(segment
		(start 48.105314 -21.975572)
		(end 47.902114 -21.772372)
		(width 0.14224)
		(layer "In4.Cu")
		(net "M_H_DQ<15>")
	)
	(segment
		(start 48.057562 -8.509)
		(end 47.600362 -8.0518)
		(width 0.14224)
		(layer "In4.Cu")
		(net "M_H_DQ<15>")
	)
	(segment
		(start 58.864246 -45.379132)
		(end 58.864246 -45.160184)
		(width 0.14224)
		(layer "In4.Cu")
		(net "M_H_DQ<15>")
	)
	(segment
		(start 47.851314 -14.778228)
		(end 47.209964 -14.136878)
		(width 0.14224)
		(layer "In4.Cu")
		(net "M_H_DQ<15>")
	)
	(segment
		(start 72.328786 -60.54344)
		(end 72.328786 -60.543186)
		(width 0.0889)
		(layer "In4.Cu")
		(net "M_H_DQ<15>")
	)
	(segment
		(start 47.927514 -23.5712)
		(end 47.927514 -23.296372)
		(width 0.14224)
		(layer "In4.Cu")
		(net "M_H_DQ<15>")
	)
	(segment
		(start 47.902114 -21.772372)
		(end 47.902114 -18.567654)
		(width 0.14224)
		(layer "In4.Cu")
		(net "M_H_DQ<15>")
	)
	(segment
		(start 69.242432 -55.273194)
		(end 68.758308 -55.273194)
		(width 0.14224)
		(layer "In4.Cu")
		(net "M_H_DQ<15>")
	)
	(segment
		(start 57.981596 -43.229784)
		(end 57.457594 -43.753532)
		(width 0.14224)
		(layer "In4.Cu")
		(net "M_H_DQ<15>")
	)
	(segment
		(start 69.771006 -55.494936)
		(end 69.464174 -55.494936)
		(width 0.0889)
		(layer "In4.Cu")
		(net "M_H_DQ<15>")
	)
	(segment
		(start 58.200544 -43.229784)
		(end 57.981596 -43.229784)
		(width 0.14224)
		(layer "In4.Cu")
		(net "M_H_DQ<15>")
	)
	(segment
		(start 70.942454 -60.943236)
		(end 70.60057 -60.943236)
		(width 0.0889)
		(layer "In4.Cu")
		(net "M_H_DQ<15>")
	)
	(segment
		(start 56.300878 -42.815764)
		(end 55.875682 -42.390568)
		(width 0.14224)
		(layer "In4.Cu")
		(net "M_H_DQ<15>")
	)
	(segment
		(start 70.271386 -55.801006)
		(end 70.265036 -55.790338)
		(width 0.0889)
		(layer "In4.Cu")
		(net "M_H_DQ<15>")
	)
	(segment
		(start 72.328786 -60.543186)
		(end 71.342504 -60.543186)
		(width 0.0889)
		(layer "In4.Cu")
		(net "M_H_DQ<15>")
	)
	(segment
		(start 56.98871 -43.284648)
		(end 57.512712 -42.7609)
		(width 0.14224)
		(layer "In4.Cu")
		(net "M_H_DQ<15>")
	)
	(segment
		(start 47.902114 -12.32535)
		(end 47.902114 -9.020048)
		(width 0.14224)
		(layer "In4.Cu")
		(net "M_H_DQ<15>")
	)
	(segment
		(start 58.176414 -44.6913)
		(end 57.926478 -44.441364)
		(width 0.14224)
		(layer "In4.Cu")
		(net "M_H_DQ<15>")
	)
	(segment
		(start 53.786024 -38.159944)
		(end 53.786024 -36.858956)
		(width 0.14224)
		(layer "In4.Cu")
		(net "M_H_DQ<15>")
	)
	(segment
		(start 59.138312 -44.167552)
		(end 58.919364 -44.167552)
		(width 0.14224)
		(layer "In4.Cu")
		(net "M_H_DQ<15>")
	)
	(segment
		(start 57.926478 -44.222416)
		(end 58.45048 -43.698668)
		(width 0.14224)
		(layer "In4.Cu")
		(net "M_H_DQ<15>")
	)
	(segment
		(start 47.209964 -13.75283)
		(end 47.089314 -13.63218)
		(width 0.14224)
		(layer "In4.Cu")
		(net "M_H_DQ<15>")
	)
	(segment
		(start 53.786024 -36.858956)
		(end 47.749968 -30.8229)
		(width 0.14224)
		(layer "In4.Cu")
		(net "M_H_DQ<15>")
	)
	(arc
		(start 70.265036 -60.343288)
		(mid 70.344167 -60.047886)
		(end 70.265036 -59.752484)
		(width 0.0889)
		(layer "In4.Cu")
		(net "M_H_DQ<15>")
	)
	(arc
		(start 70.265036 -58.761884)
		(mid 70.211537 -58.561986)
		(end 70.265036 -58.362088)
		(width 0.0889)
		(layer "In4.Cu")
		(net "M_H_DQ<15>")
	)
	(arc
		(start 70.265036 -57.771284)
		(mid 70.211537 -57.571386)
		(end 70.265036 -57.371488)
		(width 0.0889)
		(layer "In4.Cu")
		(net "M_H_DQ<15>")
	)
	(arc
		(start 70.265036 -55.790338)
		(mid 70.247674 -55.762425)
		(end 70.229222 -55.73522)
		(width 0.0889)
		(layer "In4.Cu")
		(net "M_H_DQ<15>")
	)
	(arc
		(start 70.265036 -56.380888)
		(mid 70.344258 -56.09177)
		(end 70.271386 -55.801006)
		(width 0.0889)
		(layer "In4.Cu")
		(net "M_H_DQ<15>")
	)
	(arc
		(start 70.265036 -56.780684)
		(mid 70.211537 -56.580786)
		(end 70.265036 -56.380888)
		(width 0.0889)
		(layer "In4.Cu")
		(net "M_H_DQ<15>")
	)
	(arc
		(start 70.60057 -60.943236)
		(mid 70.262455 -60.738534)
		(end 70.265036 -60.343288)
		(width 0.0889)
		(layer "In4.Cu")
		(net "M_H_DQ<15>")
	)
	(arc
		(start 70.265036 -59.352688)
		(mid 70.344167 -59.057286)
		(end 70.265036 -58.761884)
		(width 0.0889)
		(layer "In4.Cu")
		(net "M_H_DQ<15>")
	)
	(arc
		(start 70.265036 -59.752484)
		(mid 70.211537 -59.552586)
		(end 70.265036 -59.352688)
		(width 0.0889)
		(layer "In4.Cu")
		(net "M_H_DQ<15>")
	)
	(arc
		(start 70.265036 -58.362088)
		(mid 70.344167 -58.066686)
		(end 70.265036 -57.771284)
		(width 0.0889)
		(layer "In4.Cu")
		(net "M_H_DQ<15>")
	)
	(arc
		(start 70.265036 -57.371488)
		(mid 70.344167 -57.076086)
		(end 70.265036 -56.780684)
		(width 0.0889)
		(layer "In4.Cu")
		(net "M_H_DQ<15>")
	)
	(arc
		(start 70.229222 -55.73522)
		(mid 70.027812 -55.562267)
		(end 69.771006 -55.494936)
		(width 0.0889)
		(layer "In4.Cu")
		(net "M_H_DQ<15>")
	)
	(segment
		(start 47.549562 -8.661654)
		(end 47.549308 -8.6614)
		(width 0.1651)
		(layer "F.Cu")
		(net "M_H_DQ<14>")
	)
	(segment
		(start 71.183246 -61.53404)
		(end 70.611746 -61.53404)
		(width 0.1016)
		(layer "F.Cu")
		(net "M_H_DQ<14>")
	)
	(segment
		(start 47.681642 -9.09828)
		(end 47.549562 -8.9662)
		(width 0.1651)
		(layer "F.Cu")
		(net "M_H_DQ<14>")
	)
	(segment
		(start 47.549562 -10.422382)
		(end 47.549562 -9.4488)
		(width 0.1651)
		(layer "F.Cu")
		(net "M_H_DQ<14>")
	)
	(segment
		(start 47.681642 -9.31672)
		(end 47.681642 -9.09828)
		(width 0.1651)
		(layer "F.Cu")
		(net "M_H_DQ<14>")
	)
	(segment
		(start 47.549562 -8.9662)
		(end 47.549562 -8.661654)
		(width 0.1651)
		(layer "F.Cu")
		(net "M_H_DQ<14>")
	)
	(segment
		(start 47.549562 -9.4488)
		(end 47.681642 -9.31672)
		(width 0.1651)
		(layer "F.Cu")
		(net "M_H_DQ<14>")
	)
	(via
		(at 47.549308 -8.6614)
		(size 0.508)
		(drill 0.254)
		(layers "F.Cu" "B.Cu")
		(net "M_H_DQ<14>")
	)
	(via
		(at 46.699424 -13.959078)
		(size 0.508)
		(drill 0.254)
		(layers "F.Cu" "B.Cu")
		(net "M_H_DQ<14>")
	)
	(via
		(at 70.611746 -61.53404)
		(size 0.508)
		(drill 0.254)
		(layers "F.Cu" "B.Cu")
		(net "M_H_DQ<14>")
	)
	(segment
		(start 46.699424 -15.222982)
		(end 46.699424 -13.959078)
		(width 0.1651)
		(layer "B.Cu")
		(net "M_H_DQ<14>")
	)
	(segment
		(start 53.517546 -40.75049)
		(end 53.298598 -40.75049)
		(width 0.14224)
		(layer "In4.Cu")
		(net "M_H_DQ<14>")
	)
	(segment
		(start 52.628546 -38.212522)
		(end 52.628546 -36.768278)
		(width 0.14224)
		(layer "In4.Cu")
		(net "M_H_DQ<14>")
	)
	(segment
		(start 53.895244 -39.216076)
		(end 53.645308 -38.96614)
		(width 0.14224)
		(layer "In4.Cu")
		(net "M_H_DQ<14>")
	)
	(segment
		(start 47.216314 -16.840962)
		(end 47.216314 -15.041372)
		(width 0.14224)
		(layer "In4.Cu")
		(net "M_H_DQ<14>")
	)
	(segment
		(start 52.579778 -39.812722)
		(end 52.36083 -39.812722)
		(width 0.14224)
		(layer "In4.Cu")
		(net "M_H_DQ<14>")
	)
	(segment
		(start 53.98643 -41.438322)
		(end 53.98643 -41.219374)
		(width 0.14224)
		(layer "In4.Cu")
		(net "M_H_DQ<14>")
	)
	(segment
		(start 54.364128 -39.903908)
		(end 53.517546 -40.75049)
		(width 0.14224)
		(layer "In4.Cu")
		(net "M_H_DQ<14>")
	)
	(segment
		(start 53.298598 -40.75049)
		(end 53.048662 -40.500554)
		(width 0.14224)
		(layer "In4.Cu")
		(net "M_H_DQ<14>")
	)
	(segment
		(start 69.764402 -55.685436)
		(end 69.46519 -55.685436)
		(width 0.0889)
		(layer "In4.Cu")
		(net "M_H_DQ<14>")
	)
	(segment
		(start 46.699424 -13.959078)
		(end 46.463712 -13.723366)
		(width 0.14224)
		(layer "In4.Cu")
		(net "M_H_DQ<14>")
	)
	(segment
		(start 55.301896 -40.841676)
		(end 54.455314 -41.688258)
		(width 0.14224)
		(layer "In4.Cu")
		(net "M_H_DQ<14>")
	)
	(segment
		(start 54.455314 -41.688258)
		(end 54.236366 -41.688258)
		(width 0.14224)
		(layer "In4.Cu")
		(net "M_H_DQ<14>")
	)
	(segment
		(start 53.895244 -39.435024)
		(end 53.895244 -39.216076)
		(width 0.14224)
		(layer "In4.Cu")
		(net "M_H_DQ<14>")
	)
	(segment
		(start 52.628546 -36.768278)
		(end 47.114968 -31.2547)
		(width 0.14224)
		(layer "In4.Cu")
		(net "M_H_DQ<14>")
	)
	(segment
		(start 47.23638 -11.804396)
		(end 46.81093 -11.378946)
		(width 0.14224)
		(layer "In4.Cu")
		(net "M_H_DQ<14>")
	)
	(segment
		(start 47.114968 -23.875746)
		(end 47.165514 -23.8252)
		(width 0.14224)
		(layer "In4.Cu")
		(net "M_H_DQ<14>")
	)
	(segment
		(start 46.699424 -14.524482)
		(end 46.699424 -13.959078)
		(width 0.14224)
		(layer "In4.Cu")
		(net "M_H_DQ<14>")
	)
	(segment
		(start 70.104762 -55.894224)
		(end 70.099936 -55.885588)
		(width 0.0889)
		(layer "In4.Cu")
		(net "M_H_DQ<14>")
	)
	(segment
		(start 47.23638 -12.156186)
		(end 47.23638 -11.804396)
		(width 0.14224)
		(layer "In4.Cu")
		(net "M_H_DQ<14>")
	)
	(segment
		(start 53.98643 -41.219374)
		(end 54.833012 -40.372792)
		(width 0.14224)
		(layer "In4.Cu")
		(net "M_H_DQ<14>")
	)
	(segment
		(start 68.456302 -55.908194)
		(end 54.924198 -42.37609)
		(width 0.14224)
		(layer "In4.Cu")
		(net "M_H_DQ<14>")
	)
	(segment
		(start 47.174912 -9.035796)
		(end 47.549308 -8.6614)
		(width 0.14224)
		(layer "In4.Cu")
		(net "M_H_DQ<14>")
	)
	(segment
		(start 47.19193 -10.712704)
		(end 47.19193 -10.369296)
		(width 0.14224)
		(layer "In4.Cu")
		(net "M_H_DQ<14>")
	)
	(segment
		(start 55.520844 -40.841676)
		(end 55.301896 -40.841676)
		(width 0.14224)
		(layer "In4.Cu")
		(net "M_H_DQ<14>")
	)
	(segment
		(start 51.940968 -38.9001)
		(end 52.628546 -38.212522)
		(width 0.14224)
		(layer "In4.Cu")
		(net "M_H_DQ<14>")
	)
	(segment
		(start 47.174912 -9.313672)
		(end 47.174912 -9.035796)
		(width 0.14224)
		(layer "In4.Cu")
		(net "M_H_DQ<14>")
	)
	(segment
		(start 47.165514 -23.270972)
		(end 47.063914 -23.169372)
		(width 0.14224)
		(layer "In4.Cu")
		(net "M_H_DQ<14>")
	)
	(segment
		(start 46.463712 -12.928854)
		(end 47.23638 -12.156186)
		(width 0.14224)
		(layer "In4.Cu")
		(net "M_H_DQ<14>")
	)
	(segment
		(start 46.463712 -13.723366)
		(end 46.463712 -12.928854)
		(width 0.14224)
		(layer "In4.Cu")
		(net "M_H_DQ<14>")
	)
	(segment
		(start 46.81093 -9.677654)
		(end 47.174912 -9.313672)
		(width 0.14224)
		(layer "In4.Cu")
		(net "M_H_DQ<14>")
	)
	(segment
		(start 46.81093 -9.988296)
		(end 46.81093 -9.677654)
		(width 0.14224)
		(layer "In4.Cu")
		(net "M_H_DQ<14>")
	)
	(segment
		(start 54.833012 -40.153844)
		(end 54.583076 -39.903908)
		(width 0.14224)
		(layer "In4.Cu")
		(net "M_H_DQ<14>")
	)
	(segment
		(start 47.063914 -23.169372)
		(end 47.063914 -21.975572)
		(width 0.14224)
		(layer "In4.Cu")
		(net "M_H_DQ<14>")
	)
	(segment
		(start 54.236366 -41.688258)
		(end 53.98643 -41.438322)
		(width 0.14224)
		(layer "In4.Cu")
		(net "M_H_DQ<14>")
	)
	(segment
		(start 47.267114 -18.668746)
		(end 47.063914 -18.465546)
		(width 0.14224)
		(layer "In4.Cu")
		(net "M_H_DQ<14>")
	)
	(segment
		(start 53.645308 -38.96614)
		(end 53.42636 -38.96614)
		(width 0.14224)
		(layer "In4.Cu")
		(net "M_H_DQ<14>")
	)
	(segment
		(start 53.048662 -40.281606)
		(end 53.895244 -39.435024)
		(width 0.14224)
		(layer "In4.Cu")
		(net "M_H_DQ<14>")
	)
	(segment
		(start 47.063914 -18.465546)
		(end 47.063914 -16.993362)
		(width 0.14224)
		(layer "In4.Cu")
		(net "M_H_DQ<14>")
	)
	(segment
		(start 55.77078 -41.31056)
		(end 55.77078 -41.091612)
		(width 0.14224)
		(layer "In4.Cu")
		(net "M_H_DQ<14>")
	)
	(segment
		(start 47.114968 -31.2547)
		(end 47.114968 -23.875746)
		(width 0.14224)
		(layer "In4.Cu")
		(net "M_H_DQ<14>")
	)
	(segment
		(start 47.216314 -15.041372)
		(end 46.699424 -14.524482)
		(width 0.14224)
		(layer "In4.Cu")
		(net "M_H_DQ<14>")
	)
	(segment
		(start 51.940968 -39.39286)
		(end 51.940968 -38.9001)
		(width 0.14224)
		(layer "In4.Cu")
		(net "M_H_DQ<14>")
	)
	(segment
		(start 54.833012 -40.372792)
		(end 54.833012 -40.153844)
		(width 0.14224)
		(layer "In4.Cu")
		(net "M_H_DQ<14>")
	)
	(segment
		(start 47.267114 -21.772372)
		(end 47.267114 -18.668746)
		(width 0.14224)
		(layer "In4.Cu")
		(net "M_H_DQ<14>")
	)
	(segment
		(start 46.81093 -11.378946)
		(end 46.81093 -11.093704)
		(width 0.14224)
		(layer "In4.Cu")
		(net "M_H_DQ<14>")
	)
	(segment
		(start 53.048662 -40.500554)
		(end 53.048662 -40.281606)
		(width 0.14224)
		(layer "In4.Cu")
		(net "M_H_DQ<14>")
	)
	(segment
		(start 47.063914 -16.993362)
		(end 47.216314 -16.840962)
		(width 0.14224)
		(layer "In4.Cu")
		(net "M_H_DQ<14>")
	)
	(segment
		(start 54.924198 -42.37609)
		(end 54.924198 -42.157142)
		(width 0.14224)
		(layer "In4.Cu")
		(net "M_H_DQ<14>")
	)
	(segment
		(start 55.77078 -41.091612)
		(end 55.520844 -40.841676)
		(width 0.14224)
		(layer "In4.Cu")
		(net "M_H_DQ<14>")
	)
	(segment
		(start 47.165514 -23.8252)
		(end 47.165514 -23.270972)
		(width 0.14224)
		(layer "In4.Cu")
		(net "M_H_DQ<14>")
	)
	(segment
		(start 47.19193 -10.369296)
		(end 46.81093 -9.988296)
		(width 0.14224)
		(layer "In4.Cu")
		(net "M_H_DQ<14>")
	)
	(segment
		(start 52.36083 -39.812722)
		(end 51.940968 -39.39286)
		(width 0.14224)
		(layer "In4.Cu")
		(net "M_H_DQ<14>")
	)
	(segment
		(start 46.81093 -11.093704)
		(end 47.19193 -10.712704)
		(width 0.14224)
		(layer "In4.Cu")
		(net "M_H_DQ<14>")
	)
	(segment
		(start 69.46519 -55.685436)
		(end 69.242432 -55.908194)
		(width 0.0889)
		(layer "In4.Cu")
		(net "M_H_DQ<14>")
	)
	(segment
		(start 54.583076 -39.903908)
		(end 54.364128 -39.903908)
		(width 0.14224)
		(layer "In4.Cu")
		(net "M_H_DQ<14>")
	)
	(segment
		(start 53.42636 -38.96614)
		(end 52.579778 -39.812722)
		(width 0.14224)
		(layer "In4.Cu")
		(net "M_H_DQ<14>")
	)
	(segment
		(start 47.063914 -21.975572)
		(end 47.267114 -21.772372)
		(width 0.14224)
		(layer "In4.Cu")
		(net "M_H_DQ<14>")
	)
	(segment
		(start 54.924198 -42.157142)
		(end 55.77078 -41.31056)
		(width 0.14224)
		(layer "In4.Cu")
		(net "M_H_DQ<14>")
	)
	(segment
		(start 70.611746 -61.53404)
		(end 70.611746 -61.533786)
		(width 0.0889)
		(layer "In4.Cu")
		(net "M_H_DQ<14>")
	)
	(segment
		(start 69.242432 -55.908194)
		(end 68.456302 -55.908194)
		(width 0.14224)
		(layer "In4.Cu")
		(net "M_H_DQ<14>")
	)
	(arc
		(start 70.099936 -55.885588)
		(mid 70.08473 -55.860998)
		(end 70.067424 -55.837836)
		(width 0.0889)
		(layer "In4.Cu")
		(net "M_H_DQ<14>")
	)
	(arc
		(start 70.099936 -58.857388)
		(mid 70.020805 -58.561986)
		(end 70.099936 -58.266584)
		(width 0.0889)
		(layer "In4.Cu")
		(net "M_H_DQ<14>")
	)
	(arc
		(start 70.099936 -60.838588)
		(mid 70.020805 -60.543186)
		(end 70.099936 -60.247784)
		(width 0.0889)
		(layer "In4.Cu")
		(net "M_H_DQ<14>")
	)
	(arc
		(start 70.099936 -57.275984)
		(mid 70.153435 -57.076086)
		(end 70.099936 -56.876188)
		(width 0.0889)
		(layer "In4.Cu")
		(net "M_H_DQ<14>")
	)
	(arc
		(start 70.099936 -56.876188)
		(mid 70.020805 -56.580786)
		(end 70.099936 -56.285384)
		(width 0.0889)
		(layer "In4.Cu")
		(net "M_H_DQ<14>")
	)
	(arc
		(start 70.132194 -56.21401)
		(mid 70.151928 -56.051251)
		(end 70.104762 -55.894224)
		(width 0.0889)
		(layer "In4.Cu")
		(net "M_H_DQ<14>")
	)
	(arc
		(start 70.067424 -55.837836)
		(mid 69.932862 -55.727924)
		(end 69.764402 -55.685436)
		(width 0.0889)
		(layer "In4.Cu")
		(net "M_H_DQ<14>")
	)
	(arc
		(start 70.099936 -60.247784)
		(mid 70.153435 -60.047886)
		(end 70.099936 -59.847988)
		(width 0.0889)
		(layer "In4.Cu")
		(net "M_H_DQ<14>")
	)
	(arc
		(start 70.611746 -61.533786)
		(mid 70.336513 -61.200417)
		(end 70.099936 -60.838588)
		(width 0.0889)
		(layer "In4.Cu")
		(net "M_H_DQ<14>")
	)
	(arc
		(start 70.099936 -59.847988)
		(mid 70.020805 -59.552586)
		(end 70.099936 -59.257184)
		(width 0.0889)
		(layer "In4.Cu")
		(net "M_H_DQ<14>")
	)
	(arc
		(start 70.099936 -58.266584)
		(mid 70.153435 -58.066686)
		(end 70.099936 -57.866788)
		(width 0.0889)
		(layer "In4.Cu")
		(net "M_H_DQ<14>")
	)
	(arc
		(start 70.099936 -57.866788)
		(mid 70.020805 -57.571386)
		(end 70.099936 -57.275984)
		(width 0.0889)
		(layer "In4.Cu")
		(net "M_H_DQ<14>")
	)
	(arc
		(start 70.099936 -59.257184)
		(mid 70.153435 -59.057286)
		(end 70.099936 -58.857388)
		(width 0.0889)
		(layer "In4.Cu")
		(net "M_H_DQ<14>")
	)
	(arc
		(start 70.099936 -56.285384)
		(mid 70.117811 -56.250486)
		(end 70.132194 -56.21401)
		(width 0.0889)
		(layer "In4.Cu")
		(net "M_H_DQ<14>")
	)
	(segment
		(start 40.749474 -5.822442)
		(end 40.749474 -7.086346)
		(width 0.1651)
		(layer "F.Cu")
		(net "M_H_DQ<13>")
	)
	(segment
		(start 73.758806 -63.019686)
		(end 73.187306 -63.019686)
		(width 0.1016)
		(layer "F.Cu")
		(net "M_H_DQ<13>")
	)
	(via
		(at 40.749474 -7.086346)
		(size 0.508)
		(drill 0.254)
		(layers "F.Cu" "B.Cu")
		(net "M_H_DQ<13>")
	)
	(via
		(at 41.523158 -12.678156)
		(size 0.508)
		(drill 0.254)
		(layers "F.Cu" "B.Cu")
		(net "M_H_DQ<13>")
	)
	(via
		(at 73.187306 -63.019686)
		(size 0.508)
		(drill 0.254)
		(layers "F.Cu" "B.Cu")
		(net "M_H_DQ<13>")
	)
	(segment
		(start 41.599358 -10.623042)
		(end 41.599358 -12.601956)
		(width 0.1651)
		(layer "B.Cu")
		(net "M_H_DQ<13>")
	)
	(segment
		(start 41.599358 -12.601956)
		(end 41.523158 -12.678156)
		(width 0.1651)
		(layer "B.Cu")
		(net "M_H_DQ<13>")
	)
	(segment
		(start 71.45909 -63.610236)
		(end 71.491856 -63.610236)
		(width 0.0889)
		(layer "In4.Cu")
		(net "M_H_DQ<13>")
	)
	(segment
		(start 66.164206 -60.071)
		(end 66.414142 -60.320936)
		(width 0.14224)
		(layer "In4.Cu")
		(net "M_H_DQ<13>")
	)
	(segment
		(start 42.582592 -27.281124)
		(end 43.279568 -27.9781)
		(width 0.14224)
		(layer "In4.Cu")
		(net "M_H_DQ<13>")
	)
	(segment
		(start 41.954196 -21.920454)
		(end 41.980358 -21.946616)
		(width 0.14224)
		(layer "In4.Cu")
		(net "M_H_DQ<13>")
	)
	(segment
		(start 66.679572 -62.740794)
		(end 66.863468 -62.92469)
		(width 0.0889)
		(layer "In4.Cu")
		(net "M_H_DQ<13>")
	)
	(segment
		(start 69.73824 -64.410336)
		(end 69.849492 -64.410336)
		(width 0.0889)
		(layer "In4.Cu")
		(net "M_H_DQ<13>")
	)
	(segment
		(start 42.031412 -8.8646)
		(end 41.834562 -9.06145)
		(width 0.14224)
		(layer "In4.Cu")
		(net "M_H_DQ<13>")
	)
	(segment
		(start 41.958514 -18.542762)
		(end 41.954196 -18.54708)
		(width 0.14224)
		(layer "In4.Cu")
		(net "M_H_DQ<13>")
	)
	(segment
		(start 41.511728 -14.035786)
		(end 41.958514 -16.306546)
		(width 0.14224)
		(layer "In4.Cu")
		(net "M_H_DQ<13>")
	)
	(segment
		(start 41.980358 -23.691088)
		(end 42.582592 -24.761952)
		(width 0.14224)
		(layer "In4.Cu")
		(net "M_H_DQ<13>")
	)
	(segment
		(start 43.279568 -27.9781)
		(end 43.279568 -36.213288)
		(width 0.14224)
		(layer "In4.Cu")
		(net "M_H_DQ<13>")
	)
	(segment
		(start 70.071742 -64.337438)
		(end 70.363842 -64.191642)
		(width 0.0889)
		(layer "In4.Cu")
		(net "M_H_DQ<13>")
	)
	(segment
		(start 66.863468 -62.92469)
		(end 67.199256 -62.92469)
		(width 0.0889)
		(layer "In4.Cu")
		(net "M_H_DQ<13>")
	)
	(segment
		(start 41.958514 -16.306546)
		(end 41.958514 -18.542762)
		(width 0.14224)
		(layer "In4.Cu")
		(net "M_H_DQ<13>")
	)
	(segment
		(start 70.59676 -64.10579)
		(end 70.629526 -64.10579)
		(width 0.0889)
		(layer "In4.Cu")
		(net "M_H_DQ<13>")
	)
	(segment
		(start 41.834562 -12.366752)
		(end 41.523158 -12.678156)
		(width 0.14224)
		(layer "In4.Cu")
		(net "M_H_DQ<13>")
	)
	(segment
		(start 72.3138 -63.11519)
		(end 72.364854 -63.11519)
		(width 0.0889)
		(layer "In4.Cu")
		(net "M_H_DQ<13>")
	)
	(segment
		(start 66.414142 -60.320936)
		(end 66.414142 -60.659264)
		(width 0.0889)
		(layer "In4.Cu")
		(net "M_H_DQ<13>")
	)
	(segment
		(start 41.523158 -12.678156)
		(end 41.053258 -13.148056)
		(width 0.14224)
		(layer "In4.Cu")
		(net "M_H_DQ<13>")
	)
	(segment
		(start 42.582592 -24.761952)
		(end 42.582592 -27.281124)
		(width 0.14224)
		(layer "In4.Cu")
		(net "M_H_DQ<13>")
	)
	(segment
		(start 72.364854 -63.11519)
		(end 73.187306 -63.019686)
		(width 0.0889)
		(layer "In4.Cu")
		(net "M_H_DQ<13>")
	)
	(segment
		(start 62.951868 -57.053988)
		(end 65.96888 -60.071)
		(width 0.14224)
		(layer "In4.Cu")
		(net "M_H_DQ<13>")
	)
	(segment
		(start 68.88353 -63.91529)
		(end 68.916296 -63.91529)
		(width 0.0889)
		(layer "In4.Cu")
		(net "M_H_DQ<13>")
	)
	(segment
		(start 41.834562 -9.06145)
		(end 41.834562 -12.366752)
		(width 0.14224)
		(layer "In4.Cu")
		(net "M_H_DQ<13>")
	)
	(segment
		(start 41.053258 -13.148056)
		(end 41.053258 -13.577316)
		(width 0.14224)
		(layer "In4.Cu")
		(net "M_H_DQ<13>")
	)
	(segment
		(start 41.954196 -18.54708)
		(end 41.954196 -21.920454)
		(width 0.14224)
		(layer "In4.Cu")
		(net "M_H_DQ<13>")
	)
	(segment
		(start 40.749474 -7.086346)
		(end 40.749474 -7.481062)
		(width 0.14224)
		(layer "In4.Cu")
		(net "M_H_DQ<13>")
	)
	(segment
		(start 41.980358 -21.946616)
		(end 41.980358 -23.691088)
		(width 0.14224)
		(layer "In4.Cu")
		(net "M_H_DQ<13>")
	)
	(segment
		(start 41.631108 -8.0518)
		(end 42.031412 -8.452104)
		(width 0.14224)
		(layer "In4.Cu")
		(net "M_H_DQ<13>")
	)
	(segment
		(start 41.053258 -13.577316)
		(end 41.511728 -14.035786)
		(width 0.14224)
		(layer "In4.Cu")
		(net "M_H_DQ<13>")
	)
	(segment
		(start 69.849492 -64.410336)
		(end 70.071742 -64.337438)
		(width 0.0889)
		(layer "In4.Cu")
		(net "M_H_DQ<13>")
	)
	(segment
		(start 40.749474 -7.481062)
		(end 41.320212 -8.0518)
		(width 0.14224)
		(layer "In4.Cu")
		(net "M_H_DQ<13>")
	)
	(segment
		(start 66.679572 -60.924694)
		(end 66.679572 -62.740794)
		(width 0.0889)
		(layer "In4.Cu")
		(net "M_H_DQ<13>")
	)
	(segment
		(start 66.414142 -60.659264)
		(end 66.679572 -60.924694)
		(width 0.0889)
		(layer "In4.Cu")
		(net "M_H_DQ<13>")
	)
	(segment
		(start 41.320212 -8.0518)
		(end 41.631108 -8.0518)
		(width 0.14224)
		(layer "In4.Cu")
		(net "M_H_DQ<13>")
	)
	(segment
		(start 42.031412 -8.452104)
		(end 42.031412 -8.8646)
		(width 0.14224)
		(layer "In4.Cu")
		(net "M_H_DQ<13>")
	)
	(segment
		(start 43.279568 -36.213288)
		(end 62.951868 -55.885588)
		(width 0.14224)
		(layer "In4.Cu")
		(net "M_H_DQ<13>")
	)
	(segment
		(start 65.96888 -60.071)
		(end 66.164206 -60.071)
		(width 0.14224)
		(layer "In4.Cu")
		(net "M_H_DQ<13>")
	)
	(segment
		(start 68.0212 -63.419736)
		(end 68.053966 -63.419736)
		(width 0.0889)
		(layer "In4.Cu")
		(net "M_H_DQ<13>")
	)
	(segment
		(start 62.951868 -55.885588)
		(end 62.951868 -57.053988)
		(width 0.14224)
		(layer "In4.Cu")
		(net "M_H_DQ<13>")
	)
	(arc
		(start 69.406516 -64.210438)
		(mid 69.546595 -64.353174)
		(end 69.73824 -64.410336)
		(width 0.0889)
		(layer "In4.Cu")
		(net "M_H_DQ<13>")
	)
	(arc
		(start 68.547996 -63.715138)
		(mid 68.689679 -63.858942)
		(end 68.88353 -63.91529)
		(width 0.0889)
		(layer "In4.Cu")
		(net "M_H_DQ<13>")
	)
	(arc
		(start 67.199256 -62.92469)
		(mid 67.482473 -63.008971)
		(end 67.689476 -63.219838)
		(width 0.0889)
		(layer "In4.Cu")
		(net "M_H_DQ<13>")
	)
	(arc
		(start 70.629526 -64.10579)
		(mid 70.91495 -64.022323)
		(end 71.123556 -63.810388)
		(width 0.0889)
		(layer "In4.Cu")
		(net "M_H_DQ<13>")
	)
	(arc
		(start 68.053966 -63.419736)
		(mid 68.33939 -63.503203)
		(end 68.547996 -63.715138)
		(width 0.0889)
		(layer "In4.Cu")
		(net "M_H_DQ<13>")
	)
	(arc
		(start 71.123556 -63.810388)
		(mid 71.265239 -63.666584)
		(end 71.45909 -63.610236)
		(width 0.0889)
		(layer "In4.Cu")
		(net "M_H_DQ<13>")
	)
	(arc
		(start 71.982076 -63.315088)
		(mid 72.122155 -63.172352)
		(end 72.3138 -63.11519)
		(width 0.0889)
		(layer "In4.Cu")
		(net "M_H_DQ<13>")
	)
	(arc
		(start 68.916296 -63.91529)
		(mid 69.199513 -63.999571)
		(end 69.406516 -64.210438)
		(width 0.0889)
		(layer "In4.Cu")
		(net "M_H_DQ<13>")
	)
	(arc
		(start 71.491856 -63.610236)
		(mid 71.775073 -63.525955)
		(end 71.982076 -63.315088)
		(width 0.0889)
		(layer "In4.Cu")
		(net "M_H_DQ<13>")
	)
	(arc
		(start 70.363842 -64.191642)
		(mid 70.473475 -64.130189)
		(end 70.59676 -64.10579)
		(width 0.0889)
		(layer "In4.Cu")
		(net "M_H_DQ<13>")
	)
	(arc
		(start 67.689476 -63.219838)
		(mid 67.829555 -63.362574)
		(end 68.0212 -63.419736)
		(width 0.0889)
		(layer "In4.Cu")
		(net "M_H_DQ<13>")
	)
	(segment
		(start 41.538906 -8.763)
		(end 41.501314 -8.5598)
		(width 0.1651)
		(layer "F.Cu")
		(net "M_H_DQ<12>")
	)
	(segment
		(start 41.599358 -10.422382)
		(end 41.599358 -9.091168)
		(width 0.1651)
		(layer "F.Cu")
		(net "M_H_DQ<12>")
	)
	(segment
		(start 41.599358 -9.091168)
		(end 41.538906 -8.763)
		(width 0.1651)
		(layer "F.Cu")
		(net "M_H_DQ<12>")
	)
	(segment
		(start 72.900286 -63.51524)
		(end 72.328786 -63.51524)
		(width 0.1016)
		(layer "F.Cu")
		(net "M_H_DQ<12>")
	)
	(via
		(at 40.749474 -13.959078)
		(size 0.508)
		(drill 0.254)
		(layers "F.Cu" "B.Cu")
		(net "M_H_DQ<12>")
	)
	(via
		(at 41.501314 -8.5598)
		(size 0.508)
		(drill 0.254)
		(layers "F.Cu" "B.Cu")
		(net "M_H_DQ<12>")
	)
	(via
		(at 72.328786 -63.51524)
		(size 0.508)
		(drill 0.254)
		(layers "F.Cu" "B.Cu")
		(net "M_H_DQ<12>")
	)
	(segment
		(start 40.749474 -15.222982)
		(end 40.749474 -13.959078)
		(width 0.1651)
		(layer "B.Cu")
		(net "M_H_DQ<12>")
	)
	(segment
		(start 66.489072 -62.819788)
		(end 66.784474 -63.11519)
		(width 0.0889)
		(layer "In4.Cu")
		(net "M_H_DQ<12>")
	)
	(segment
		(start 41.018968 -16.281146)
		(end 41.247314 -16.509492)
		(width 0.14224)
		(layer "In4.Cu")
		(net "M_H_DQ<12>")
	)
	(segment
		(start 66.489072 -61.016388)
		(end 66.489072 -62.819788)
		(width 0.0889)
		(layer "In4.Cu")
		(net "M_H_DQ<12>")
	)
	(segment
		(start 41.224962 -11.742928)
		(end 41.224962 -12.217654)
		(width 0.14224)
		(layer "In4.Cu")
		(net "M_H_DQ<12>")
	)
	(segment
		(start 41.018968 -14.559026)
		(end 41.018968 -16.281146)
		(width 0.14224)
		(layer "In4.Cu")
		(net "M_H_DQ<12>")
	)
	(segment
		(start 41.247314 -16.840454)
		(end 41.018714 -17.069054)
		(width 0.14224)
		(layer "In4.Cu")
		(net "M_H_DQ<12>")
	)
	(segment
		(start 41.501314 -8.5598)
		(end 41.224962 -8.836152)
		(width 0.14224)
		(layer "In4.Cu")
		(net "M_H_DQ<12>")
	)
	(segment
		(start 41.224962 -9.313672)
		(end 40.86098 -9.677654)
		(width 0.14224)
		(layer "In4.Cu")
		(net "M_H_DQ<12>")
	)
	(segment
		(start 42.644568 -28.1813)
		(end 42.644568 -36.476432)
		(width 0.14224)
		(layer "In4.Cu")
		(net "M_H_DQ<12>")
	)
	(segment
		(start 69.731636 -64.600836)
		(end 69.764402 -64.600836)
		(width 0.0889)
		(layer "In4.Cu")
		(net "M_H_DQ<12>")
	)
	(segment
		(start 41.018714 -17.069054)
		(end 41.018714 -18.314162)
		(width 0.14224)
		(layer "In4.Cu")
		(net "M_H_DQ<12>")
	)
	(segment
		(start 41.018714 -18.314162)
		(end 41.272714 -18.568162)
		(width 0.14224)
		(layer "In4.Cu")
		(net "M_H_DQ<12>")
	)
	(segment
		(start 40.749474 -13.959078)
		(end 40.749474 -14.289532)
		(width 0.14224)
		(layer "In4.Cu")
		(net "M_H_DQ<12>")
	)
	(segment
		(start 41.24198 -10.668)
		(end 40.87368 -11.0363)
		(width 0.14224)
		(layer "In4.Cu")
		(net "M_H_DQ<12>")
	)
	(segment
		(start 40.87368 -11.0363)
		(end 40.87368 -11.391646)
		(width 0.14224)
		(layer "In4.Cu")
		(net "M_H_DQ<12>")
	)
	(segment
		(start 41.894506 -27.431238)
		(end 42.644568 -28.1813)
		(width 0.14224)
		(layer "In4.Cu")
		(net "M_H_DQ<12>")
	)
	(segment
		(start 66.392298 -60.919614)
		(end 66.489072 -61.016388)
		(width 0.0889)
		(layer "In4.Cu")
		(net "M_H_DQ<12>")
	)
	(segment
		(start 71.790052 -64.251078)
		(end 72.042274 -63.9064)
		(width 0.0889)
		(layer "In4.Cu")
		(net "M_H_DQ<12>")
	)
	(segment
		(start 62.316868 -56.148732)
		(end 62.316868 -57.317132)
		(width 0.14224)
		(layer "In4.Cu")
		(net "M_H_DQ<12>")
	)
	(segment
		(start 41.272714 -18.568162)
		(end 41.272714 -21.696172)
		(width 0.14224)
		(layer "In4.Cu")
		(net "M_H_DQ<12>")
	)
	(segment
		(start 40.87368 -11.391646)
		(end 41.224962 -11.742928)
		(width 0.14224)
		(layer "In4.Cu")
		(net "M_H_DQ<12>")
	)
	(segment
		(start 71.18731 -64.593978)
		(end 71.645018 -64.370458)
		(width 0.0889)
		(layer "In4.Cu")
		(net "M_H_DQ<12>")
	)
	(segment
		(start 41.247314 -16.509492)
		(end 41.247314 -16.840454)
		(width 0.14224)
		(layer "In4.Cu")
		(net "M_H_DQ<12>")
	)
	(segment
		(start 40.749474 -14.289532)
		(end 41.018968 -14.559026)
		(width 0.14224)
		(layer "In4.Cu")
		(net "M_H_DQ<12>")
	)
	(segment
		(start 41.224962 -12.217654)
		(end 40.513762 -12.928854)
		(width 0.14224)
		(layer "In4.Cu")
		(net "M_H_DQ<12>")
	)
	(segment
		(start 40.513762 -13.723366)
		(end 40.749474 -13.959078)
		(width 0.14224)
		(layer "In4.Cu")
		(net "M_H_DQ<12>")
	)
	(segment
		(start 41.272714 -21.696172)
		(end 41.018714 -21.950172)
		(width 0.14224)
		(layer "In4.Cu")
		(net "M_H_DQ<12>")
	)
	(segment
		(start 68.876926 -64.10579)
		(end 68.909692 -64.10579)
		(width 0.0889)
		(layer "In4.Cu")
		(net "M_H_DQ<12>")
	)
	(segment
		(start 41.247314 -23.397972)
		(end 41.247314 -24.148796)
		(width 0.14224)
		(layer "In4.Cu")
		(net "M_H_DQ<12>")
	)
	(segment
		(start 40.513762 -12.928854)
		(end 40.513762 -13.723366)
		(width 0.14224)
		(layer "In4.Cu")
		(net "M_H_DQ<12>")
	)
	(segment
		(start 41.018714 -23.169372)
		(end 41.247314 -23.397972)
		(width 0.14224)
		(layer "In4.Cu")
		(net "M_H_DQ<12>")
	)
	(segment
		(start 70.535292 -64.90589)
		(end 70.622922 -64.90589)
		(width 0.0889)
		(layer "In4.Cu")
		(net "M_H_DQ<12>")
	)
	(segment
		(start 66.784474 -63.11519)
		(end 67.192652 -63.11519)
		(width 0.0889)
		(layer "In4.Cu")
		(net "M_H_DQ<12>")
	)
	(segment
		(start 41.894506 -24.795988)
		(end 41.894506 -27.431238)
		(width 0.14224)
		(layer "In4.Cu")
		(net "M_H_DQ<12>")
	)
	(segment
		(start 40.86098 -9.9822)
		(end 41.24198 -10.3632)
		(width 0.14224)
		(layer "In4.Cu")
		(net "M_H_DQ<12>")
	)
	(segment
		(start 40.86098 -9.677654)
		(end 40.86098 -9.9822)
		(width 0.14224)
		(layer "In4.Cu")
		(net "M_H_DQ<12>")
	)
	(segment
		(start 70.19163 -64.769746)
		(end 70.535292 -64.90589)
		(width 0.0889)
		(layer "In4.Cu")
		(net "M_H_DQ<12>")
	)
	(segment
		(start 72.042274 -63.9064)
		(end 72.328786 -63.51524)
		(width 0.0889)
		(layer "In4.Cu")
		(net "M_H_DQ<12>")
	)
	(segment
		(start 68.014596 -63.610236)
		(end 68.047362 -63.610236)
		(width 0.0889)
		(layer "In4.Cu")
		(net "M_H_DQ<12>")
	)
	(segment
		(start 66.110612 -60.919614)
		(end 66.392298 -60.919614)
		(width 0.0889)
		(layer "In4.Cu")
		(net "M_H_DQ<12>")
	)
	(segment
		(start 41.224962 -8.836152)
		(end 41.224962 -9.313672)
		(width 0.14224)
		(layer "In4.Cu")
		(net "M_H_DQ<12>")
	)
	(segment
		(start 41.018714 -21.950172)
		(end 41.018714 -23.169372)
		(width 0.14224)
		(layer "In4.Cu")
		(net "M_H_DQ<12>")
	)
	(segment
		(start 41.247314 -24.148796)
		(end 41.894506 -24.795988)
		(width 0.14224)
		(layer "In4.Cu")
		(net "M_H_DQ<12>")
	)
	(segment
		(start 62.316868 -57.317132)
		(end 65.91935 -60.919614)
		(width 0.14224)
		(layer "In4.Cu")
		(net "M_H_DQ<12>")
	)
	(segment
		(start 70.901052 -64.782446)
		(end 71.18731 -64.593978)
		(width 0.0889)
		(layer "In4.Cu")
		(net "M_H_DQ<12>")
	)
	(segment
		(start 69.926454 -64.640206)
		(end 70.19163 -64.769746)
		(width 0.0889)
		(layer "In4.Cu")
		(net "M_H_DQ<12>")
	)
	(segment
		(start 41.24198 -10.3632)
		(end 41.24198 -10.668)
		(width 0.14224)
		(layer "In4.Cu")
		(net "M_H_DQ<12>")
	)
	(segment
		(start 42.644568 -36.476432)
		(end 62.316868 -56.148732)
		(width 0.14224)
		(layer "In4.Cu")
		(net "M_H_DQ<12>")
	)
	(segment
		(start 65.91935 -60.919614)
		(end 66.110612 -60.919614)
		(width 0.14224)
		(layer "In4.Cu")
		(net "M_H_DQ<12>")
	)
	(arc
		(start 71.645018 -64.370458)
		(mid 71.724645 -64.319403)
		(end 71.790052 -64.251078)
		(width 0.0889)
		(layer "In4.Cu")
		(net "M_H_DQ<12>")
	)
	(arc
		(start 70.622922 -64.90589)
		(mid 70.77416 -64.871608)
		(end 70.901052 -64.782446)
		(width 0.0889)
		(layer "In4.Cu")
		(net "M_H_DQ<12>")
	)
	(arc
		(start 68.047362 -63.610236)
		(mid 68.241212 -63.666586)
		(end 68.382896 -63.810388)
		(width 0.0889)
		(layer "In4.Cu")
		(net "M_H_DQ<12>")
	)
	(arc
		(start 67.192652 -63.11519)
		(mid 67.384294 -63.172356)
		(end 67.524376 -63.315088)
		(width 0.0889)
		(layer "In4.Cu")
		(net "M_H_DQ<12>")
	)
	(arc
		(start 68.382896 -63.810388)
		(mid 68.591504 -64.02232)
		(end 68.876926 -64.10579)
		(width 0.0889)
		(layer "In4.Cu")
		(net "M_H_DQ<12>")
	)
	(arc
		(start 69.241416 -64.305688)
		(mid 69.44842 -64.516552)
		(end 69.731636 -64.600836)
		(width 0.0889)
		(layer "In4.Cu")
		(net "M_H_DQ<12>")
	)
	(arc
		(start 69.764402 -64.600836)
		(mid 69.847498 -64.611996)
		(end 69.926454 -64.640206)
		(width 0.0889)
		(layer "In4.Cu")
		(net "M_H_DQ<12>")
	)
	(arc
		(start 68.909692 -64.10579)
		(mid 69.101334 -64.162956)
		(end 69.241416 -64.305688)
		(width 0.0889)
		(layer "In4.Cu")
		(net "M_H_DQ<12>")
	)
	(arc
		(start 67.524376 -63.315088)
		(mid 67.73138 -63.525952)
		(end 68.014596 -63.610236)
		(width 0.0889)
		(layer "In4.Cu")
		(net "M_H_DQ<12>")
	)
	(segment
		(start 48.399446 -5.822442)
		(end 48.399446 -7.086346)
		(width 0.1651)
		(layer "F.Cu")
		(net "M_H_DQ<11>")
	)
	(segment
		(start 72.041766 -60.047886)
		(end 71.470266 -60.047886)
		(width 0.1016)
		(layer "F.Cu")
		(net "M_H_DQ<11>")
	)
	(via
		(at 71.470266 -60.047886)
		(size 0.508)
		(drill 0.254)
		(layers "F.Cu" "B.Cu")
		(net "M_H_DQ<11>")
	)
	(via
		(at 48.399446 -7.086346)
		(size 0.508)
		(drill 0.254)
		(layers "F.Cu" "B.Cu")
		(net "M_H_DQ<11>")
	)
	(via
		(at 49.24933 -12.678156)
		(size 0.508)
		(drill 0.254)
		(layers "F.Cu" "B.Cu")
		(net "M_H_DQ<11>")
	)
	(segment
		(start 49.249584 -10.623042)
		(end 49.249584 -10.805922)
		(width 0.1651)
		(layer "B.Cu")
		(net "M_H_DQ<11>")
	)
	(segment
		(start 49.249584 -10.805922)
		(end 49.24933 -10.806176)
		(width 0.1651)
		(layer "B.Cu")
		(net "M_H_DQ<11>")
	)
	(segment
		(start 49.24933 -10.806176)
		(end 49.24933 -12.678156)
		(width 0.1651)
		(layer "B.Cu")
		(net "M_H_DQ<11>")
	)
	(segment
		(start 69.924168 -53.594)
		(end 70.381368 -54.0512)
		(width 0.14224)
		(layer "In4.Cu")
		(net "M_H_DQ<11>")
	)
	(segment
		(start 49.757584 -8.509)
		(end 49.757584 -8.8646)
		(width 0.14224)
		(layer "In4.Cu")
		(net "M_H_DQ<11>")
	)
	(segment
		(start 49.616614 -23.283672)
		(end 49.616614 -25.37968)
		(width 0.14224)
		(layer "In4.Cu")
		(net "M_H_DQ<11>")
	)
	(segment
		(start 49.24933 -12.678156)
		(end 48.765714 -13.161772)
		(width 0.14224)
		(layer "In4.Cu")
		(net "M_H_DQ<11>")
	)
	(segment
		(start 49.144428 -13.946886)
		(end 49.144428 -15.809214)
		(width 0.14224)
		(layer "In4.Cu")
		(net "M_H_DQ<11>")
	)
	(segment
		(start 71.123556 -59.847988)
		(end 71.11873 -59.856624)
		(width 0.0889)
		(layer "In4.Cu")
		(net "M_H_DQ<11>")
	)
	(segment
		(start 71.129906 -59.83732)
		(end 71.123556 -59.847988)
		(width 0.0889)
		(layer "In4.Cu")
		(net "M_H_DQ<11>")
	)
	(segment
		(start 71.129906 -55.87492)
		(end 71.123556 -55.885588)
		(width 0.0889)
		(layer "In4.Cu")
		(net "M_H_DQ<11>")
	)
	(segment
		(start 70.381368 -54.0512)
		(end 70.711568 -54.0512)
		(width 0.14224)
		(layer "In4.Cu")
		(net "M_H_DQ<11>")
	)
	(segment
		(start 49.756314 -18.389854)
		(end 49.603914 -18.542254)
		(width 0.14224)
		(layer "In4.Cu")
		(net "M_H_DQ<11>")
	)
	(segment
		(start 71.17715 -60.21705)
		(end 71.470266 -60.047886)
		(width 0.0889)
		(layer "In4.Cu")
		(net "M_H_DQ<11>")
	)
	(segment
		(start 49.781714 -22.000972)
		(end 49.781714 -23.118572)
		(width 0.14224)
		(layer "In4.Cu")
		(net "M_H_DQ<11>")
	)
	(segment
		(start 49.174908 -29.48432)
		(end 49.019968 -29.63926)
		(width 0.14224)
		(layer "In4.Cu")
		(net "M_H_DQ<11>")
	)
	(segment
		(start 49.731168 -29.48432)
		(end 49.174908 -29.48432)
		(width 0.14224)
		(layer "In4.Cu")
		(net "M_H_DQ<11>")
	)
	(segment
		(start 62.246764 -45.904404)
		(end 62.246764 -46.123352)
		(width 0.14224)
		(layer "In4.Cu")
		(net "M_H_DQ<11>")
	)
	(segment
		(start 49.300384 -8.0518)
		(end 49.757584 -8.509)
		(width 0.14224)
		(layer "In4.Cu")
		(net "M_H_DQ<11>")
	)
	(segment
		(start 49.174908 -25.50668)
		(end 49.019968 -25.66162)
		(width 0.14224)
		(layer "In4.Cu")
		(net "M_H_DQ<11>")
	)
	(segment
		(start 49.743868 -26.67762)
		(end 49.588928 -26.83256)
		(width 0.14224)
		(layer "In4.Cu")
		(net "M_H_DQ<11>")
	)
	(segment
		(start 71.123556 -58.266838)
		(end 71.129906 -58.277506)
		(width 0.0889)
		(layer "In4.Cu")
		(net "M_H_DQ<11>")
	)
	(segment
		(start 49.602136 -12.32535)
		(end 49.24933 -12.678156)
		(width 0.14224)
		(layer "In4.Cu")
		(net "M_H_DQ<11>")
	)
	(segment
		(start 48.716184 -7.403084)
		(end 48.716184 -7.7216)
		(width 0.14224)
		(layer "In4.Cu")
		(net "M_H_DQ<11>")
	)
	(segment
		(start 63.929768 -48.641254)
		(end 63.929768 -48.66386)
		(width 0.14224)
		(layer "In4.Cu")
		(net "M_H_DQ<11>")
	)
	(segment
		(start 71.068946 -54.704488)
		(end 71.068946 -55.0926)
		(width 0.0889)
		(layer "In4.Cu")
		(net "M_H_DQ<11>")
	)
	(segment
		(start 49.804828 -28.15844)
		(end 49.174908 -28.15844)
		(width 0.14224)
		(layer "In4.Cu")
		(net "M_H_DQ<11>")
	)
	(segment
		(start 61.470032 -45.96257)
		(end 61.77788 -45.654468)
		(width 0.14224)
		(layer "In4.Cu")
		(net "M_H_DQ<11>")
	)
	(segment
		(start 49.588928 -26.83256)
		(end 49.174908 -26.83256)
		(width 0.14224)
		(layer "In4.Cu")
		(net "M_H_DQ<11>")
	)
	(segment
		(start 48.765714 -13.161772)
		(end 48.765714 -13.568172)
		(width 0.14224)
		(layer "In4.Cu")
		(net "M_H_DQ<11>")
	)
	(segment
		(start 49.046384 -8.0518)
		(end 49.300384 -8.0518)
		(width 0.14224)
		(layer "In4.Cu")
		(net "M_H_DQ<11>")
	)
	(segment
		(start 49.616614 -25.37968)
		(end 49.489614 -25.50668)
		(width 0.14224)
		(layer "In4.Cu")
		(net "M_H_DQ<11>")
	)
	(segment
		(start 49.804828 -27.4955)
		(end 49.959768 -27.65044)
		(width 0.14224)
		(layer "In4.Cu")
		(net "M_H_DQ<11>")
	)
	(segment
		(start 69.517768 -53.594)
		(end 69.924168 -53.594)
		(width 0.14224)
		(layer "In4.Cu")
		(net "M_H_DQ<11>")
	)
	(segment
		(start 49.019968 -27.34056)
		(end 49.174908 -27.4955)
		(width 0.14224)
		(layer "In4.Cu")
		(net "M_H_DQ<11>")
	)
	(segment
		(start 49.019968 -26.9875)
		(end 49.019968 -27.34056)
		(width 0.14224)
		(layer "In4.Cu")
		(net "M_H_DQ<11>")
	)
	(segment
		(start 49.588928 -26.16962)
		(end 49.743868 -26.32456)
		(width 0.14224)
		(layer "In4.Cu")
		(net "M_H_DQ<11>")
	)
	(segment
		(start 64.084708 -48.8188)
		(end 64.361568 -48.8188)
		(width 0.14224)
		(layer "In4.Cu")
		(net "M_H_DQ<11>")
	)
	(segment
		(start 71.129906 -56.86552)
		(end 71.123556 -56.876188)
		(width 0.0889)
		(layer "In4.Cu")
		(net "M_H_DQ<11>")
	)
	(segment
		(start 71.0692 -55.153052)
		(end 71.080376 -55.230776)
		(width 0.0889)
		(layer "In4.Cu")
		(net "M_H_DQ<11>")
	)
	(segment
		(start 60.589668 -45.301154)
		(end 61.251084 -45.96257)
		(width 0.14224)
		(layer "In4.Cu")
		(net "M_H_DQ<11>")
	)
	(segment
		(start 61.938916 -46.431454)
		(end 61.938916 -46.650402)
		(width 0.14224)
		(layer "In4.Cu")
		(net "M_H_DQ<11>")
	)
	(segment
		(start 49.144428 -15.809214)
		(end 49.616614 -16.2814)
		(width 0.14224)
		(layer "In4.Cu")
		(net "M_H_DQ<11>")
	)
	(segment
		(start 49.603914 -21.823172)
		(end 49.781714 -22.000972)
		(width 0.14224)
		(layer "In4.Cu")
		(net "M_H_DQ<11>")
	)
	(segment
		(start 71.123556 -55.885588)
		(end 71.11873 -55.894224)
		(width 0.0889)
		(layer "In4.Cu")
		(net "M_H_DQ<11>")
	)
	(segment
		(start 50.822352 -30.910784)
		(end 51.072288 -31.16072)
		(width 0.14224)
		(layer "In4.Cu")
		(net "M_H_DQ<11>")
	)
	(segment
		(start 63.184532 -46.842172)
		(end 63.184532 -47.06112)
		(width 0.14224)
		(layer "In4.Cu")
		(net "M_H_DQ<11>")
	)
	(segment
		(start 48.399446 -7.086346)
		(end 48.716184 -7.403084)
		(width 0.14224)
		(layer "In4.Cu")
		(net "M_H_DQ<11>")
	)
	(segment
		(start 49.174908 -26.16962)
		(end 49.588928 -26.16962)
		(width 0.14224)
		(layer "In4.Cu")
		(net "M_H_DQ<11>")
	)
	(segment
		(start 49.781714 -23.118572)
		(end 49.616614 -23.283672)
		(width 0.14224)
		(layer "In4.Cu")
		(net "M_H_DQ<11>")
	)
	(segment
		(start 71.067168 -54.70271)
		(end 71.068946 -54.704488)
		(width 0.14224)
		(layer "In4.Cu")
		(net "M_H_DQ<11>")
	)
	(segment
		(start 49.858168 -29.35732)
		(end 49.731168 -29.48432)
		(width 0.14224)
		(layer "In4.Cu")
		(net "M_H_DQ<11>")
	)
	(segment
		(start 71.09841 -60.195714)
		(end 71.17715 -60.21705)
		(width 0.0889)
		(layer "In4.Cu")
		(net "M_H_DQ<11>")
	)
	(segment
		(start 61.77788 -45.654468)
		(end 61.996828 -45.654468)
		(width 0.14224)
		(layer "In4.Cu")
		(net "M_H_DQ<11>")
	)
	(segment
		(start 50.603404 -30.910784)
		(end 50.822352 -30.910784)
		(width 0.14224)
		(layer "In4.Cu")
		(net "M_H_DQ<11>")
	)
	(segment
		(start 50.751486 -31.919418)
		(end 51.001422 -32.169354)
		(width 0.14224)
		(layer "In4.Cu")
		(net "M_H_DQ<11>")
	)
	(segment
		(start 51.001422 -32.169354)
		(end 51.22037 -32.169354)
		(width 0.14224)
		(layer "In4.Cu")
		(net "M_H_DQ<11>")
	)
	(segment
		(start 69.009768 -53.086)
		(end 69.517768 -53.594)
		(width 0.14224)
		(layer "In4.Cu")
		(net "M_H_DQ<11>")
	)
	(segment
		(start 52.010056 -32.098488)
		(end 52.010056 -32.317436)
		(width 0.14224)
		(layer "In4.Cu")
		(net "M_H_DQ<11>")
	)
	(segment
		(start 61.938916 -46.650402)
		(end 62.188852 -46.900338)
		(width 0.14224)
		(layer "In4.Cu")
		(net "M_H_DQ<11>")
	)
	(segment
		(start 49.959768 -27.65044)
		(end 49.959768 -28.0035)
		(width 0.14224)
		(layer "In4.Cu")
		(net "M_H_DQ<11>")
	)
	(segment
		(start 49.602136 -9.020048)
		(end 49.602136 -12.32535)
		(width 0.14224)
		(layer "In4.Cu")
		(net "M_H_DQ<11>")
	)
	(segment
		(start 49.616614 -16.891762)
		(end 49.756314 -17.031462)
		(width 0.14224)
		(layer "In4.Cu")
		(net "M_H_DQ<11>")
	)
	(segment
		(start 49.019968 -25.66162)
		(end 49.019968 -26.01468)
		(width 0.14224)
		(layer "In4.Cu")
		(net "M_H_DQ<11>")
	)
	(segment
		(start 49.756314 -17.031462)
		(end 49.756314 -18.389854)
		(width 0.14224)
		(layer "In4.Cu")
		(net "M_H_DQ<11>")
	)
	(segment
		(start 49.743868 -26.32456)
		(end 49.743868 -26.67762)
		(width 0.14224)
		(layer "In4.Cu")
		(net "M_H_DQ<11>")
	)
	(segment
		(start 62.4078 -46.900338)
		(end 62.715648 -46.592236)
		(width 0.14224)
		(layer "In4.Cu")
		(net "M_H_DQ<11>")
	)
	(segment
		(start 71.123556 -56.876188)
		(end 71.11873 -56.884824)
		(width 0.0889)
		(layer "In4.Cu")
		(net "M_H_DQ<11>")
	)
	(segment
		(start 71.123556 -58.857388)
		(end 71.11873 -58.866024)
		(width 0.0889)
		(layer "In4.Cu")
		(net "M_H_DQ<11>")
	)
	(segment
		(start 51.072288 -31.16072)
		(end 51.072288 -31.379668)
		(width 0.14224)
		(layer "In4.Cu")
		(net "M_H_DQ<11>")
	)
	(segment
		(start 49.019968 -28.66644)
		(end 49.174908 -28.82138)
		(width 0.14224)
		(layer "In4.Cu")
		(net "M_H_DQ<11>")
	)
	(segment
		(start 70.711568 -54.0512)
		(end 71.067168 -54.4068)
		(width 0.14224)
		(layer "In4.Cu")
		(net "M_H_DQ<11>")
	)
	(segment
		(start 49.858168 -28.94838)
		(end 49.858168 -29.35732)
		(width 0.14224)
		(layer "In4.Cu")
		(net "M_H_DQ<11>")
	)
	(segment
		(start 62.876684 -47.369222)
		(end 62.876684 -47.58817)
		(width 0.14224)
		(layer "In4.Cu")
		(net "M_H_DQ<11>")
	)
	(segment
		(start 71.068946 -55.0926)
		(end 71.0692 -55.153052)
		(width 0.0889)
		(layer "In4.Cu")
		(net "M_H_DQ<11>")
	)
	(segment
		(start 61.996828 -45.654468)
		(end 62.246764 -45.904404)
		(width 0.14224)
		(layer "In4.Cu")
		(net "M_H_DQ<11>")
	)
	(segment
		(start 49.174908 -28.15844)
		(end 49.019968 -28.31338)
		(width 0.14224)
		(layer "In4.Cu")
		(net "M_H_DQ<11>")
	)
	(segment
		(start 52.010056 -32.317436)
		(end 51.689254 -32.638238)
		(width 0.14224)
		(layer "In4.Cu")
		(net "M_H_DQ<11>")
	)
	(segment
		(start 49.174908 -26.83256)
		(end 49.019968 -26.9875)
		(width 0.14224)
		(layer "In4.Cu")
		(net "M_H_DQ<11>")
	)
	(segment
		(start 49.019968 -26.01468)
		(end 49.174908 -26.16962)
		(width 0.14224)
		(layer "In4.Cu")
		(net "M_H_DQ<11>")
	)
	(segment
		(start 49.603914 -18.542254)
		(end 49.603914 -21.823172)
		(width 0.14224)
		(layer "In4.Cu")
		(net "M_H_DQ<11>")
	)
	(segment
		(start 63.184532 -47.06112)
		(end 62.876684 -47.369222)
		(width 0.14224)
		(layer "In4.Cu")
		(net "M_H_DQ<11>")
	)
	(segment
		(start 62.188852 -46.900338)
		(end 62.4078 -46.900338)
		(width 0.14224)
		(layer "In4.Cu")
		(net "M_H_DQ<11>")
	)
	(segment
		(start 51.541172 -31.848552)
		(end 51.76012 -31.848552)
		(width 0.14224)
		(layer "In4.Cu")
		(net "M_H_DQ<11>")
	)
	(segment
		(start 49.489614 -25.50668)
		(end 49.174908 -25.50668)
		(width 0.14224)
		(layer "In4.Cu")
		(net "M_H_DQ<11>")
	)
	(segment
		(start 50.063654 -31.231586)
		(end 50.282602 -31.231586)
		(width 0.14224)
		(layer "In4.Cu")
		(net "M_H_DQ<11>")
	)
	(segment
		(start 64.361568 -48.8188)
		(end 68.628768 -53.086)
		(width 0.14224)
		(layer "In4.Cu")
		(net "M_H_DQ<11>")
	)
	(segment
		(start 51.22037 -32.169354)
		(end 51.541172 -31.848552)
		(width 0.14224)
		(layer "In4.Cu")
		(net "M_H_DQ<11>")
	)
	(segment
		(start 48.716184 -7.7216)
		(end 49.046384 -8.0518)
		(width 0.14224)
		(layer "In4.Cu")
		(net "M_H_DQ<11>")
	)
	(segment
		(start 50.282602 -31.231586)
		(end 50.603404 -30.910784)
		(width 0.14224)
		(layer "In4.Cu")
		(net "M_H_DQ<11>")
	)
	(segment
		(start 61.251084 -45.96257)
		(end 61.470032 -45.96257)
		(width 0.14224)
		(layer "In4.Cu")
		(net "M_H_DQ<11>")
	)
	(segment
		(start 49.174908 -27.4955)
		(end 49.804828 -27.4955)
		(width 0.14224)
		(layer "In4.Cu")
		(net "M_H_DQ<11>")
	)
	(segment
		(start 51.76012 -31.848552)
		(end 52.010056 -32.098488)
		(width 0.14224)
		(layer "In4.Cu")
		(net "M_H_DQ<11>")
	)
	(segment
		(start 49.616614 -16.2814)
		(end 49.616614 -16.891762)
		(width 0.14224)
		(layer "In4.Cu")
		(net "M_H_DQ<11>")
	)
	(segment
		(start 49.174908 -28.82138)
		(end 49.731168 -28.82138)
		(width 0.14224)
		(layer "In4.Cu")
		(net "M_H_DQ<11>")
	)
	(segment
		(start 62.246764 -46.123352)
		(end 61.938916 -46.431454)
		(width 0.14224)
		(layer "In4.Cu")
		(net "M_H_DQ<11>")
	)
	(segment
		(start 60.589668 -41.7576)
		(end 60.589668 -45.301154)
		(width 0.14224)
		(layer "In4.Cu")
		(net "M_H_DQ<11>")
	)
	(segment
		(start 63.929768 -48.66386)
		(end 64.084708 -48.8188)
		(width 0.14224)
		(layer "In4.Cu")
		(net "M_H_DQ<11>")
	)
	(segment
		(start 51.689254 -32.857186)
		(end 60.589668 -41.7576)
		(width 0.14224)
		(layer "In4.Cu")
		(net "M_H_DQ<11>")
	)
	(segment
		(start 62.934596 -46.592236)
		(end 63.184532 -46.842172)
		(width 0.14224)
		(layer "In4.Cu")
		(net "M_H_DQ<11>")
	)
	(segment
		(start 51.072288 -31.379668)
		(end 50.751486 -31.70047)
		(width 0.14224)
		(layer "In4.Cu")
		(net "M_H_DQ<11>")
	)
	(segment
		(start 50.751486 -31.70047)
		(end 50.751486 -31.919418)
		(width 0.14224)
		(layer "In4.Cu")
		(net "M_H_DQ<11>")
	)
	(segment
		(start 71.067168 -54.4068)
		(end 71.067168 -54.70271)
		(width 0.14224)
		(layer "In4.Cu")
		(net "M_H_DQ<11>")
	)
	(segment
		(start 48.765714 -13.568172)
		(end 49.144428 -13.946886)
		(width 0.14224)
		(layer "In4.Cu")
		(net "M_H_DQ<11>")
	)
	(segment
		(start 51.689254 -32.638238)
		(end 51.689254 -32.857186)
		(width 0.14224)
		(layer "In4.Cu")
		(net "M_H_DQ<11>")
	)
	(segment
		(start 49.959768 -28.0035)
		(end 49.804828 -28.15844)
		(width 0.14224)
		(layer "In4.Cu")
		(net "M_H_DQ<11>")
	)
	(segment
		(start 62.876684 -47.58817)
		(end 63.929768 -48.641254)
		(width 0.14224)
		(layer "In4.Cu")
		(net "M_H_DQ<11>")
	)
	(segment
		(start 49.019968 -28.31338)
		(end 49.019968 -28.66644)
		(width 0.14224)
		(layer "In4.Cu")
		(net "M_H_DQ<11>")
	)
	(segment
		(start 49.757584 -8.8646)
		(end 49.602136 -9.020048)
		(width 0.14224)
		(layer "In4.Cu")
		(net "M_H_DQ<11>")
	)
	(segment
		(start 49.731168 -28.82138)
		(end 49.858168 -28.94838)
		(width 0.14224)
		(layer "In4.Cu")
		(net "M_H_DQ<11>")
	)
	(segment
		(start 62.715648 -46.592236)
		(end 62.934596 -46.592236)
		(width 0.14224)
		(layer "In4.Cu")
		(net "M_H_DQ<11>")
	)
	(segment
		(start 49.019968 -30.1879)
		(end 50.063654 -31.231586)
		(width 0.14224)
		(layer "In4.Cu")
		(net "M_H_DQ<11>")
	)
	(segment
		(start 49.019968 -29.63926)
		(end 49.019968 -30.1879)
		(width 0.14224)
		(layer "In4.Cu")
		(net "M_H_DQ<11>")
	)
	(segment
		(start 68.628768 -53.086)
		(end 69.009768 -53.086)
		(width 0.14224)
		(layer "In4.Cu")
		(net "M_H_DQ<11>")
	)
	(arc
		(start 71.11873 -56.884824)
		(mid 71.069975 -57.081176)
		(end 71.123556 -57.276238)
		(width 0.0889)
		(layer "In4.Cu")
		(net "M_H_DQ<11>")
	)
	(arc
		(start 71.123556 -57.276238)
		(mid 71.202687 -57.57164)
		(end 71.123556 -57.867042)
		(width 0.0889)
		(layer "In4.Cu")
		(net "M_H_DQ<11>")
	)
	(arc
		(start 71.080376 -55.230776)
		(mid 71.200906 -55.545469)
		(end 71.129906 -55.87492)
		(width 0.0889)
		(layer "In4.Cu")
		(net "M_H_DQ<11>")
	)
	(arc
		(start 71.123556 -59.257438)
		(mid 71.202778 -59.546556)
		(end 71.129906 -59.83732)
		(width 0.0889)
		(layer "In4.Cu")
		(net "M_H_DQ<11>")
	)
	(arc
		(start 71.129906 -58.277506)
		(mid 71.202704 -58.568269)
		(end 71.123556 -58.857388)
		(width 0.0889)
		(layer "In4.Cu")
		(net "M_H_DQ<11>")
	)
	(arc
		(start 71.11873 -59.856624)
		(mid 71.070817 -60.023909)
		(end 71.09841 -60.195714)
		(width 0.0889)
		(layer "In4.Cu")
		(net "M_H_DQ<11>")
	)
	(arc
		(start 71.123556 -57.867042)
		(mid 71.070057 -58.06694)
		(end 71.123556 -58.266838)
		(width 0.0889)
		(layer "In4.Cu")
		(net "M_H_DQ<11>")
	)
	(arc
		(start 71.11873 -55.894224)
		(mid 71.069975 -56.090576)
		(end 71.123556 -56.285638)
		(width 0.0889)
		(layer "In4.Cu")
		(net "M_H_DQ<11>")
	)
	(arc
		(start 71.11873 -58.866024)
		(mid 71.069975 -59.062376)
		(end 71.123556 -59.257438)
		(width 0.0889)
		(layer "In4.Cu")
		(net "M_H_DQ<11>")
	)
	(arc
		(start 71.123556 -56.285638)
		(mid 71.202778 -56.574756)
		(end 71.129906 -56.86552)
		(width 0.0889)
		(layer "In4.Cu")
		(net "M_H_DQ<11>")
	)
	(segment
		(start 49.249584 -10.422382)
		(end 49.249584 -9.425686)
		(width 0.1651)
		(layer "F.Cu")
		(net "M_H_DQ<10>")
	)
	(segment
		(start 49.24933 -9.425432)
		(end 49.380902 -9.29386)
		(width 0.1651)
		(layer "F.Cu")
		(net "M_H_DQ<10>")
	)
	(segment
		(start 49.24933 -8.938768)
		(end 49.24933 -8.6614)
		(width 0.1651)
		(layer "F.Cu")
		(net "M_H_DQ<10>")
	)
	(segment
		(start 71.183246 -60.54344)
		(end 70.611746 -60.54344)
		(width 0.1016)
		(layer "F.Cu")
		(net "M_H_DQ<10>")
	)
	(segment
		(start 49.380902 -9.29386)
		(end 49.380902 -9.07034)
		(width 0.1651)
		(layer "F.Cu")
		(net "M_H_DQ<10>")
	)
	(segment
		(start 49.249584 -9.425686)
		(end 49.24933 -9.425432)
		(width 0.1651)
		(layer "F.Cu")
		(net "M_H_DQ<10>")
	)
	(segment
		(start 49.380902 -9.07034)
		(end 49.24933 -8.938768)
		(width 0.1651)
		(layer "F.Cu")
		(net "M_H_DQ<10>")
	)
	(via
		(at 48.399446 -13.959078)
		(size 0.508)
		(drill 0.254)
		(layers "F.Cu" "B.Cu")
		(net "M_H_DQ<10>")
	)
	(via
		(at 49.24933 -8.6614)
		(size 0.508)
		(drill 0.254)
		(layers "F.Cu" "B.Cu")
		(net "M_H_DQ<10>")
	)
	(via
		(at 70.611746 -60.54344)
		(size 0.508)
		(drill 0.254)
		(layers "F.Cu" "B.Cu")
		(net "M_H_DQ<10>")
	)
	(segment
		(start 48.399446 -15.222982)
		(end 48.399446 -13.959078)
		(width 0.1651)
		(layer "B.Cu")
		(net "M_H_DQ<10>")
	)
	(segment
		(start 58.611008 -40.772588)
		(end 58.611008 -40.55364)
		(width 0.14224)
		(layer "In4.Cu")
		(net "M_H_DQ<10>")
	)
	(segment
		(start 58.361072 -40.303704)
		(end 58.142124 -40.303704)
		(width 0.14224)
		(layer "In4.Cu")
		(net "M_H_DQ<10>")
	)
	(segment
		(start 48.384968 -24.269192)
		(end 48.860964 -23.793196)
		(width 0.14224)
		(layer "In4.Cu")
		(net "M_H_DQ<10>")
	)
	(segment
		(start 48.399446 -15.991078)
		(end 48.399446 -13.959078)
		(width 0.14224)
		(layer "In4.Cu")
		(net "M_H_DQ<10>")
	)
	(segment
		(start 56.735472 -38.897052)
		(end 56.735472 -38.678104)
		(width 0.14224)
		(layer "In4.Cu")
		(net "M_H_DQ<10>")
	)
	(segment
		(start 70.952106 -59.763406)
		(end 70.958456 -59.752738)
		(width 0.0889)
		(layer "In4.Cu")
		(net "M_H_DQ<10>")
	)
	(segment
		(start 69.950838 -54.61)
		(end 68.857368 -54.61)
		(width 0.14224)
		(layer "In4.Cu")
		(net "M_H_DQ<10>")
	)
	(segment
		(start 58.142124 -40.303704)
		(end 57.586626 -40.859202)
		(width 0.14224)
		(layer "In4.Cu")
		(net "M_H_DQ<10>")
	)
	(segment
		(start 70.958456 -59.752738)
		(end 70.963282 -59.744102)
		(width 0.0889)
		(layer "In4.Cu")
		(net "M_H_DQ<10>")
	)
	(segment
		(start 57.67324 -39.83482)
		(end 57.67324 -39.615872)
		(width 0.14224)
		(layer "In4.Cu")
		(net "M_H_DQ<10>")
	)
	(segment
		(start 48.740314 -23.143972)
		(end 48.740314 -21.950172)
		(width 0.14224)
		(layer "In4.Cu")
		(net "M_H_DQ<10>")
	)
	(segment
		(start 57.788556 -41.813988)
		(end 57.788556 -41.59504)
		(width 0.14224)
		(layer "In4.Cu")
		(net "M_H_DQ<10>")
	)
	(segment
		(start 48.50638 -9.709404)
		(end 48.851312 -9.364472)
		(width 0.14224)
		(layer "In4.Cu")
		(net "M_H_DQ<10>")
	)
	(segment
		(start 48.50638 -10.95375)
		(end 48.81118 -10.64895)
		(width 0.14224)
		(layer "In4.Cu")
		(net "M_H_DQ<10>")
	)
	(segment
		(start 48.867568 -16.866108)
		(end 48.867568 -16.4592)
		(width 0.14224)
		(layer "In4.Cu")
		(net "M_H_DQ<10>")
	)
	(segment
		(start 54.304438 -37.577014)
		(end 54.859936 -37.021516)
		(width 0.14224)
		(layer "In4.Cu")
		(net "M_H_DQ<10>")
	)
	(segment
		(start 58.25744 -42.063924)
		(end 58.038492 -42.063924)
		(width 0.14224)
		(layer "In4.Cu")
		(net "M_H_DQ<10>")
	)
	(segment
		(start 56.266588 -38.428168)
		(end 55.71109 -38.983666)
		(width 0.14224)
		(layer "In4.Cu")
		(net "M_H_DQ<10>")
	)
	(segment
		(start 70.958456 -55.790338)
		(end 70.963282 -55.781702)
		(width 0.0889)
		(layer "In4.Cu")
		(net "M_H_DQ<10>")
	)
	(segment
		(start 59.941968 -41.8846)
		(end 59.29884 -41.241472)
		(width 0.14224)
		(layer "In4.Cu")
		(net "M_H_DQ<10>")
	)
	(segment
		(start 55.547768 -37.4904)
		(end 55.32882 -37.4904)
		(width 0.14224)
		(layer "In4.Cu")
		(net "M_H_DQ<10>")
	)
	(segment
		(start 58.038492 -42.063924)
		(end 57.788556 -41.813988)
		(width 0.14224)
		(layer "In4.Cu")
		(net "M_H_DQ<10>")
	)
	(segment
		(start 67.485768 -53.095398)
		(end 59.941968 -45.551598)
		(width 0.14224)
		(layer "In4.Cu")
		(net "M_H_DQ<10>")
	)
	(segment
		(start 54.304438 -37.795962)
		(end 54.304438 -37.577014)
		(width 0.14224)
		(layer "In4.Cu")
		(net "M_H_DQ<10>")
	)
	(segment
		(start 56.485536 -38.428168)
		(end 56.266588 -38.428168)
		(width 0.14224)
		(layer "In4.Cu")
		(net "M_H_DQ<10>")
	)
	(segment
		(start 57.788556 -41.59504)
		(end 58.611008 -40.772588)
		(width 0.14224)
		(layer "In4.Cu")
		(net "M_H_DQ<10>")
	)
	(segment
		(start 57.117742 -40.609266)
		(end 57.117742 -40.390318)
		(width 0.14224)
		(layer "In4.Cu")
		(net "M_H_DQ<10>")
	)
	(segment
		(start 55.797704 -37.740336)
		(end 55.547768 -37.4904)
		(width 0.14224)
		(layer "In4.Cu")
		(net "M_H_DQ<10>")
	)
	(segment
		(start 57.67324 -39.615872)
		(end 57.423304 -39.365936)
		(width 0.14224)
		(layer "In4.Cu")
		(net "M_H_DQ<10>")
	)
	(segment
		(start 54.554374 -38.045898)
		(end 54.304438 -37.795962)
		(width 0.14224)
		(layer "In4.Cu")
		(net "M_H_DQ<10>")
	)
	(segment
		(start 70.958456 -57.771538)
		(end 70.963282 -57.762902)
		(width 0.0889)
		(layer "In4.Cu")
		(net "M_H_DQ<10>")
	)
	(segment
		(start 70.904862 -60.374276)
		(end 70.928738 -60.284868)
		(width 0.0889)
		(layer "In4.Cu")
		(net "M_H_DQ<10>")
	)
	(segment
		(start 48.81118 -10.362946)
		(end 48.50638 -10.058146)
		(width 0.14224)
		(layer "In4.Cu")
		(net "M_H_DQ<10>")
	)
	(segment
		(start 54.859936 -37.021516)
		(end 54.859936 -36.802568)
		(width 0.14224)
		(layer "In4.Cu")
		(net "M_H_DQ<10>")
	)
	(segment
		(start 54.773322 -38.045898)
		(end 54.554374 -38.045898)
		(width 0.14224)
		(layer "In4.Cu")
		(net "M_H_DQ<10>")
	)
	(segment
		(start 70.611746 -60.54344)
		(end 70.904862 -60.374276)
		(width 0.0889)
		(layer "In4.Cu")
		(net "M_H_DQ<10>")
	)
	(segment
		(start 56.735472 -38.678104)
		(end 56.485536 -38.428168)
		(width 0.14224)
		(layer "In4.Cu")
		(net "M_H_DQ<10>")
	)
	(segment
		(start 57.586626 -40.859202)
		(end 57.367678 -40.859202)
		(width 0.14224)
		(layer "In4.Cu")
		(net "M_H_DQ<10>")
	)
	(segment
		(start 56.42991 -39.921434)
		(end 56.179974 -39.671498)
		(width 0.14224)
		(layer "In4.Cu")
		(net "M_H_DQ<10>")
	)
	(segment
		(start 48.765714 -18.440146)
		(end 48.765714 -16.967962)
		(width 0.14224)
		(layer "In4.Cu")
		(net "M_H_DQ<10>")
	)
	(segment
		(start 59.079892 -41.241472)
		(end 58.25744 -42.063924)
		(width 0.14224)
		(layer "In4.Cu")
		(net "M_H_DQ<10>")
	)
	(segment
		(start 67.485768 -53.2384)
		(end 67.485768 -53.095398)
		(width 0.14224)
		(layer "In4.Cu")
		(net "M_H_DQ<10>")
	)
	(segment
		(start 55.797704 -37.959284)
		(end 55.797704 -37.740336)
		(width 0.14224)
		(layer "In4.Cu")
		(net "M_H_DQ<10>")
	)
	(segment
		(start 48.860964 -23.264622)
		(end 48.740314 -23.143972)
		(width 0.14224)
		(layer "In4.Cu")
		(net "M_H_DQ<10>")
	)
	(segment
		(start 59.941968 -45.551598)
		(end 59.941968 -41.8846)
		(width 0.14224)
		(layer "In4.Cu")
		(net "M_H_DQ<10>")
	)
	(segment
		(start 48.765714 -16.967962)
		(end 48.867568 -16.866108)
		(width 0.14224)
		(layer "In4.Cu")
		(net "M_H_DQ<10>")
	)
	(segment
		(start 56.179974 -39.671498)
		(end 56.179974 -39.45255)
		(width 0.14224)
		(layer "In4.Cu")
		(net "M_H_DQ<10>")
	)
	(segment
		(start 58.611008 -40.55364)
		(end 58.361072 -40.303704)
		(width 0.14224)
		(layer "In4.Cu")
		(net "M_H_DQ<10>")
	)
	(segment
		(start 48.96358 -11.811)
		(end 48.50638 -11.3538)
		(width 0.14224)
		(layer "In4.Cu")
		(net "M_H_DQ<10>")
	)
	(segment
		(start 48.96358 -12.079732)
		(end 48.96358 -11.811)
		(width 0.14224)
		(layer "In4.Cu")
		(net "M_H_DQ<10>")
	)
	(segment
		(start 48.867568 -16.4592)
		(end 48.399446 -15.991078)
		(width 0.14224)
		(layer "In4.Cu")
		(net "M_H_DQ<10>")
	)
	(segment
		(start 48.892714 -18.567146)
		(end 48.765714 -18.440146)
		(width 0.14224)
		(layer "In4.Cu")
		(net "M_H_DQ<10>")
	)
	(segment
		(start 48.114712 -13.674344)
		(end 48.114712 -12.9286)
		(width 0.14224)
		(layer "In4.Cu")
		(net "M_H_DQ<10>")
	)
	(segment
		(start 57.117742 -40.390318)
		(end 57.67324 -39.83482)
		(width 0.14224)
		(layer "In4.Cu")
		(net "M_H_DQ<10>")
	)
	(segment
		(start 48.114712 -12.9286)
		(end 48.96358 -12.079732)
		(width 0.14224)
		(layer "In4.Cu")
		(net "M_H_DQ<10>")
	)
	(segment
		(start 59.29884 -41.241472)
		(end 59.079892 -41.241472)
		(width 0.14224)
		(layer "In4.Cu")
		(net "M_H_DQ<10>")
	)
	(segment
		(start 55.242206 -38.514782)
		(end 55.797704 -37.959284)
		(width 0.14224)
		(layer "In4.Cu")
		(net "M_H_DQ<10>")
	)
	(segment
		(start 55.32882 -37.4904)
		(end 54.773322 -38.045898)
		(width 0.14224)
		(layer "In4.Cu")
		(net "M_H_DQ<10>")
	)
	(segment
		(start 68.857368 -54.61)
		(end 67.485768 -53.2384)
		(width 0.14224)
		(layer "In4.Cu")
		(net "M_H_DQ<10>")
	)
	(segment
		(start 48.81118 -10.64895)
		(end 48.81118 -10.362946)
		(width 0.14224)
		(layer "In4.Cu")
		(net "M_H_DQ<10>")
	)
	(segment
		(start 48.860964 -23.793196)
		(end 48.860964 -23.264622)
		(width 0.14224)
		(layer "In4.Cu")
		(net "M_H_DQ<10>")
	)
	(segment
		(start 57.367678 -40.859202)
		(end 57.117742 -40.609266)
		(width 0.14224)
		(layer "In4.Cu")
		(net "M_H_DQ<10>")
	)
	(segment
		(start 70.123812 -54.86527)
		(end 70.123812 -54.851554)
		(width 0.0889)
		(layer "In4.Cu")
		(net "M_H_DQ<10>")
	)
	(segment
		(start 57.204356 -39.365936)
		(end 56.648858 -39.921434)
		(width 0.14224)
		(layer "In4.Cu")
		(net "M_H_DQ<10>")
	)
	(segment
		(start 48.740314 -21.950172)
		(end 48.892714 -21.797772)
		(width 0.14224)
		(layer "In4.Cu")
		(net "M_H_DQ<10>")
	)
	(segment
		(start 56.179974 -39.45255)
		(end 56.735472 -38.897052)
		(width 0.14224)
		(layer "In4.Cu")
		(net "M_H_DQ<10>")
	)
	(segment
		(start 70.075298 -54.73446)
		(end 69.950838 -54.61)
		(width 0.0889)
		(layer "In4.Cu")
		(net "M_H_DQ<10>")
	)
	(segment
		(start 70.952106 -55.801006)
		(end 70.958456 -55.790338)
		(width 0.0889)
		(layer "In4.Cu")
		(net "M_H_DQ<10>")
	)
	(segment
		(start 48.851312 -9.364472)
		(end 48.851312 -9.059418)
		(width 0.14224)
		(layer "In4.Cu")
		(net "M_H_DQ<10>")
	)
	(segment
		(start 48.399446 -13.959078)
		(end 48.114712 -13.674344)
		(width 0.14224)
		(layer "In4.Cu")
		(net "M_H_DQ<10>")
	)
	(segment
		(start 70.626732 -55.19039)
		(end 70.593966 -55.19039)
		(width 0.0889)
		(layer "In4.Cu")
		(net "M_H_DQ<10>")
	)
	(segment
		(start 48.851312 -9.059418)
		(end 49.24933 -8.6614)
		(width 0.14224)
		(layer "In4.Cu")
		(net "M_H_DQ<10>")
	)
	(segment
		(start 70.952106 -56.791606)
		(end 70.958456 -56.780938)
		(width 0.0889)
		(layer "In4.Cu")
		(net "M_H_DQ<10>")
	)
	(segment
		(start 55.71109 -38.983666)
		(end 55.492142 -38.983666)
		(width 0.14224)
		(layer "In4.Cu")
		(net "M_H_DQ<10>")
	)
	(segment
		(start 70.958456 -58.362088)
		(end 70.952106 -58.35142)
		(width 0.0889)
		(layer "In4.Cu")
		(net "M_H_DQ<10>")
	)
	(segment
		(start 55.492142 -38.983666)
		(end 55.242206 -38.73373)
		(width 0.14224)
		(layer "In4.Cu")
		(net "M_H_DQ<10>")
	)
	(segment
		(start 48.50638 -11.3538)
		(end 48.50638 -10.95375)
		(width 0.14224)
		(layer "In4.Cu")
		(net "M_H_DQ<10>")
	)
	(segment
		(start 55.242206 -38.73373)
		(end 55.242206 -38.514782)
		(width 0.14224)
		(layer "In4.Cu")
		(net "M_H_DQ<10>")
	)
	(segment
		(start 57.423304 -39.365936)
		(end 57.204356 -39.365936)
		(width 0.14224)
		(layer "In4.Cu")
		(net "M_H_DQ<10>")
	)
	(segment
		(start 48.892714 -21.797772)
		(end 48.892714 -18.567146)
		(width 0.14224)
		(layer "In4.Cu")
		(net "M_H_DQ<10>")
	)
	(segment
		(start 48.50638 -10.058146)
		(end 48.50638 -9.709404)
		(width 0.14224)
		(layer "In4.Cu")
		(net "M_H_DQ<10>")
	)
	(segment
		(start 70.958456 -56.780938)
		(end 70.963282 -56.772302)
		(width 0.0889)
		(layer "In4.Cu")
		(net "M_H_DQ<10>")
	)
	(segment
		(start 54.859936 -36.802568)
		(end 48.384968 -30.3276)
		(width 0.14224)
		(layer "In4.Cu")
		(net "M_H_DQ<10>")
	)
	(segment
		(start 48.384968 -30.3276)
		(end 48.384968 -24.269192)
		(width 0.14224)
		(layer "In4.Cu")
		(net "M_H_DQ<10>")
	)
	(segment
		(start 56.648858 -39.921434)
		(end 56.42991 -39.921434)
		(width 0.14224)
		(layer "In4.Cu")
		(net "M_H_DQ<10>")
	)
	(arc
		(start 70.174866 -54.99735)
		(mid 70.137013 -54.936074)
		(end 70.123812 -54.86527)
		(width 0.0889)
		(layer "In4.Cu")
		(net "M_H_DQ<10>")
	)
	(arc
		(start 70.958456 -58.761884)
		(mid 71.011955 -58.561986)
		(end 70.958456 -58.362088)
		(width 0.0889)
		(layer "In4.Cu")
		(net "M_H_DQ<10>")
	)
	(arc
		(start 70.593966 -55.19039)
		(mid 70.364799 -55.136465)
		(end 70.174866 -54.99735)
		(width 0.0889)
		(layer "In4.Cu")
		(net "M_H_DQ<10>")
	)
	(arc
		(start 70.963282 -59.744102)
		(mid 71.012037 -59.54775)
		(end 70.958456 -59.352688)
		(width 0.0889)
		(layer "In4.Cu")
		(net "M_H_DQ<10>")
	)
	(arc
		(start 70.928738 -60.284868)
		(mid 70.879726 -60.021419)
		(end 70.952106 -59.763406)
		(width 0.0889)
		(layer "In4.Cu")
		(net "M_H_DQ<10>")
	)
	(arc
		(start 70.958456 -56.380888)
		(mid 70.879234 -56.09177)
		(end 70.952106 -55.801006)
		(width 0.0889)
		(layer "In4.Cu")
		(net "M_H_DQ<10>")
	)
	(arc
		(start 70.123812 -54.851554)
		(mid 70.111206 -54.788179)
		(end 70.075298 -54.73446)
		(width 0.0889)
		(layer "In4.Cu")
		(net "M_H_DQ<10>")
	)
	(arc
		(start 70.963282 -57.762902)
		(mid 71.012037 -57.56655)
		(end 70.958456 -57.371488)
		(width 0.0889)
		(layer "In4.Cu")
		(net "M_H_DQ<10>")
	)
	(arc
		(start 70.958456 -57.371488)
		(mid 70.879234 -57.08237)
		(end 70.952106 -56.791606)
		(width 0.0889)
		(layer "In4.Cu")
		(net "M_H_DQ<10>")
	)
	(arc
		(start 70.963282 -55.781702)
		(mid 70.959535 -55.392446)
		(end 70.626732 -55.19039)
		(width 0.0889)
		(layer "In4.Cu")
		(net "M_H_DQ<10>")
	)
	(arc
		(start 70.952106 -58.35142)
		(mid 70.879308 -58.060657)
		(end 70.958456 -57.771538)
		(width 0.0889)
		(layer "In4.Cu")
		(net "M_H_DQ<10>")
	)
	(arc
		(start 70.963282 -56.772302)
		(mid 71.012037 -56.57595)
		(end 70.958456 -56.380888)
		(width 0.0889)
		(layer "In4.Cu")
		(net "M_H_DQ<10>")
	)
	(arc
		(start 70.958456 -59.352688)
		(mid 70.879325 -59.057286)
		(end 70.958456 -58.761884)
		(width 0.0889)
		(layer "In4.Cu")
		(net "M_H_DQ<10>")
	)
	(segment
		(start 33.949386 -10.422382)
		(end 33.79089 -8.763)
		(width 0.1651)
		(layer "F.Cu")
		(net "M_H_DQ<0>")
	)
	(segment
		(start 33.79089 -8.763)
		(end 33.771586 -8.5598)
		(width 0.1651)
		(layer "F.Cu")
		(net "M_H_DQ<0>")
	)
	(segment
		(start 72.041766 -67.972686)
		(end 71.470266 -67.972686)
		(width 0.0889)
		(layer "F.Cu")
		(net "M_H_DQ<0>")
	)
	(via
		(at 71.470266 -67.972686)
		(size 0.508)
		(drill 0.254)
		(layers "F.Cu" "B.Cu")
		(net "M_H_DQ<0>")
	)
	(via
		(at 33.099502 -13.959078)
		(size 0.508)
		(drill 0.254)
		(layers "F.Cu" "B.Cu")
		(net "M_H_DQ<0>")
	)
	(via
		(at 33.771586 -8.5598)
		(size 0.508)
		(drill 0.254)
		(layers "F.Cu" "B.Cu")
		(net "M_H_DQ<0>")
	)
	(segment
		(start 33.099502 -13.959078)
		(end 33.099502 -15.222982)
		(width 0.1651)
		(layer "B.Cu")
		(net "M_H_DQ<0>")
	)
	(segment
		(start 71.123556 -68.763388)
		(end 71.140828 -68.73367)
		(width 0.0889)
		(layer "In4.Cu")
		(net "M_H_DQ<0>")
	)
	(segment
		(start 33.828228 -27.272996)
		(end 33.627568 -27.272996)
		(width 0.14224)
		(layer "In4.Cu")
		(net "M_H_DQ<0>")
	)
	(segment
		(start 33.208468 -36.492688)
		(end 33.500568 -36.784788)
		(width 0.14224)
		(layer "In4.Cu")
		(net "M_H_DQ<0>")
	)
	(segment
		(start 33.271968 -26.102056)
		(end 33.271968 -26.455116)
		(width 0.14224)
		(layer "In4.Cu")
		(net "M_H_DQ<0>")
	)
	(segment
		(start 33.551368 -12.192)
		(end 33.551368 -11.692128)
		(width 0.14224)
		(layer "In4.Cu")
		(net "M_H_DQ<0>")
	)
	(segment
		(start 33.983168 -25.439116)
		(end 33.983168 -25.792176)
		(width 0.14224)
		(layer "In4.Cu")
		(net "M_H_DQ<0>")
	)
	(segment
		(start 33.136586 -9.779254)
		(end 33.551368 -9.364472)
		(width 0.14224)
		(layer "In4.Cu")
		(net "M_H_DQ<0>")
	)
	(segment
		(start 33.208468 -32.144208)
		(end 33.208468 -32.515048)
		(width 0.14224)
		(layer "In4.Cu")
		(net "M_H_DQ<0>")
	)
	(segment
		(start 54.214268 -57.7596)
		(end 64.862202 -68.407534)
		(width 0.14224)
		(layer "In4.Cu")
		(net "M_H_DQ<0>")
	)
	(segment
		(start 33.551368 -11.692128)
		(end 33.161986 -11.302746)
		(width 0.14224)
		(layer "In4.Cu")
		(net "M_H_DQ<0>")
	)
	(segment
		(start 33.297368 -23.114)
		(end 33.62452 -23.441152)
		(width 0.14224)
		(layer "In4.Cu")
		(net "M_H_DQ<0>")
	)
	(segment
		(start 69.731636 -69.553836)
		(end 69.774816 -69.553836)
		(width 0.0889)
		(layer "In4.Cu")
		(net "M_H_DQ<0>")
	)
	(segment
		(start 71.252842 -68.552314)
		(end 71.470266 -67.972686)
		(width 0.0889)
		(layer "In4.Cu")
		(net "M_H_DQ<0>")
	)
	(segment
		(start 33.208468 -35.166808)
		(end 33.500568 -35.458908)
		(width 0.14224)
		(layer "In4.Cu")
		(net "M_H_DQ<0>")
	)
	(segment
		(start 33.500568 -34.133028)
		(end 33.500568 -34.503868)
		(width 0.14224)
		(layer "In4.Cu")
		(net "M_H_DQ<0>")
	)
	(segment
		(start 33.828228 -25.284176)
		(end 33.983168 -25.439116)
		(width 0.14224)
		(layer "In4.Cu")
		(net "M_H_DQ<0>")
	)
	(segment
		(start 33.136586 -10.1092)
		(end 33.136586 -9.779254)
		(width 0.14224)
		(layer "In4.Cu")
		(net "M_H_DQ<0>")
	)
	(segment
		(start 32.814768 -13.674344)
		(end 32.814768 -12.9286)
		(width 0.14224)
		(layer "In4.Cu")
		(net "M_H_DQ<0>")
	)
	(segment
		(start 33.271968 -18.288)
		(end 33.576768 -18.5928)
		(width 0.14224)
		(layer "In4.Cu")
		(net "M_H_DQ<0>")
	)
	(segment
		(start 33.983168 -26.764996)
		(end 33.983168 -27.118056)
		(width 0.14224)
		(layer "In4.Cu")
		(net "M_H_DQ<0>")
	)
	(segment
		(start 36.751768 -40.6273)
		(end 37.577268 -40.6273)
		(width 0.14224)
		(layer "In4.Cu")
		(net "M_H_DQ<0>")
	)
	(segment
		(start 33.271968 -24.2824)
		(end 33.271968 -25.129236)
		(width 0.14224)
		(layer "In4.Cu")
		(net "M_H_DQ<0>")
	)
	(segment
		(start 38.371018 -42.24655)
		(end 53.884068 -57.7596)
		(width 0.14224)
		(layer "In4.Cu")
		(net "M_H_DQ<0>")
	)
	(segment
		(start 33.426908 -25.284176)
		(end 33.828228 -25.284176)
		(width 0.14224)
		(layer "In4.Cu")
		(net "M_H_DQ<0>")
	)
	(segment
		(start 33.479486 -10.6807)
		(end 33.479486 -10.4521)
		(width 0.14224)
		(layer "In4.Cu")
		(net "M_H_DQ<0>")
	)
	(segment
		(start 33.271968 -17.1323)
		(end 33.271968 -18.288)
		(width 0.14224)
		(layer "In4.Cu")
		(net "M_H_DQ<0>")
	)
	(segment
		(start 33.500568 -31.852108)
		(end 33.208468 -32.144208)
		(width 0.14224)
		(layer "In4.Cu")
		(net "M_H_DQ<0>")
	)
	(segment
		(start 33.426908 -26.610056)
		(end 33.828228 -26.610056)
		(width 0.14224)
		(layer "In4.Cu")
		(net "M_H_DQ<0>")
	)
	(segment
		(start 33.500568 -32.807148)
		(end 33.500568 -33.177988)
		(width 0.14224)
		(layer "In4.Cu")
		(net "M_H_DQ<0>")
	)
	(segment
		(start 33.099502 -15.956534)
		(end 33.602168 -16.4592)
		(width 0.14224)
		(layer "In4.Cu")
		(net "M_H_DQ<0>")
	)
	(segment
		(start 66.861436 -68.06819)
		(end 67.268344 -68.06819)
		(width 0.0889)
		(layer "In4.Cu")
		(net "M_H_DQ<0>")
	)
	(segment
		(start 33.208468 -34.795968)
		(end 33.208468 -35.166808)
		(width 0.14224)
		(layer "In4.Cu")
		(net "M_H_DQ<0>")
	)
	(segment
		(start 66.522092 -68.407534)
		(end 66.861436 -68.06819)
		(width 0.0889)
		(layer "In4.Cu")
		(net "M_H_DQ<0>")
	)
	(segment
		(start 68.876926 -69.05879)
		(end 68.909692 -69.05879)
		(width 0.0889)
		(layer "In4.Cu")
		(net "M_H_DQ<0>")
	)
	(segment
		(start 33.161986 -10.9982)
		(end 33.479486 -10.6807)
		(width 0.14224)
		(layer "In4.Cu")
		(net "M_H_DQ<0>")
	)
	(segment
		(start 33.500568 -34.503868)
		(end 33.208468 -34.795968)
		(width 0.14224)
		(layer "In4.Cu")
		(net "M_H_DQ<0>")
	)
	(segment
		(start 33.551368 -9.364472)
		(end 33.551368 -8.780018)
		(width 0.14224)
		(layer "In4.Cu")
		(net "M_H_DQ<0>")
	)
	(segment
		(start 33.161986 -11.302746)
		(end 33.161986 -10.9982)
		(width 0.14224)
		(layer "In4.Cu")
		(net "M_H_DQ<0>")
	)
	(segment
		(start 33.500568 -36.784788)
		(end 33.500568 -37.3761)
		(width 0.14224)
		(layer "In4.Cu")
		(net "M_H_DQ<0>")
	)
	(segment
		(start 33.099502 -13.959078)
		(end 33.099502 -15.956534)
		(width 0.14224)
		(layer "In4.Cu")
		(net "M_H_DQ<0>")
	)
	(segment
		(start 33.576768 -21.6662)
		(end 33.297368 -21.9456)
		(width 0.14224)
		(layer "In4.Cu")
		(net "M_H_DQ<0>")
	)
	(segment
		(start 33.627568 -27.272996)
		(end 33.500568 -27.399996)
		(width 0.14224)
		(layer "In4.Cu")
		(net "M_H_DQ<0>")
	)
	(segment
		(start 33.551368 -8.780018)
		(end 33.771586 -8.5598)
		(width 0.14224)
		(layer "In4.Cu")
		(net "M_H_DQ<0>")
	)
	(segment
		(start 67.832986 -68.563236)
		(end 68.047362 -68.563236)
		(width 0.0889)
		(layer "In4.Cu")
		(net "M_H_DQ<0>")
	)
	(segment
		(start 32.814768 -12.9286)
		(end 33.551368 -12.192)
		(width 0.14224)
		(layer "In4.Cu")
		(net "M_H_DQ<0>")
	)
	(segment
		(start 33.576768 -18.5928)
		(end 33.576768 -21.6662)
		(width 0.14224)
		(layer "In4.Cu")
		(net "M_H_DQ<0>")
	)
	(segment
		(start 33.500568 -35.829748)
		(end 33.208468 -36.121848)
		(width 0.14224)
		(layer "In4.Cu")
		(net "M_H_DQ<0>")
	)
	(segment
		(start 33.828228 -25.947116)
		(end 33.426908 -25.947116)
		(width 0.14224)
		(layer "In4.Cu")
		(net "M_H_DQ<0>")
	)
	(segment
		(start 33.297368 -21.9456)
		(end 33.297368 -23.114)
		(width 0.14224)
		(layer "In4.Cu")
		(net "M_H_DQ<0>")
	)
	(segment
		(start 33.099502 -13.959078)
		(end 32.814768 -13.674344)
		(width 0.14224)
		(layer "In4.Cu")
		(net "M_H_DQ<0>")
	)
	(segment
		(start 33.500568 -37.3761)
		(end 36.751768 -40.6273)
		(width 0.14224)
		(layer "In4.Cu")
		(net "M_H_DQ<0>")
	)
	(segment
		(start 33.479486 -10.4521)
		(end 33.136586 -10.1092)
		(width 0.14224)
		(layer "In4.Cu")
		(net "M_H_DQ<0>")
	)
	(segment
		(start 70.59676 -69.05879)
		(end 70.629526 -69.05879)
		(width 0.0889)
		(layer "In4.Cu")
		(net "M_H_DQ<0>")
	)
	(segment
		(start 33.208468 -33.470088)
		(end 33.208468 -33.840928)
		(width 0.14224)
		(layer "In4.Cu")
		(net "M_H_DQ<0>")
	)
	(segment
		(start 33.208468 -36.121848)
		(end 33.208468 -36.492688)
		(width 0.14224)
		(layer "In4.Cu")
		(net "M_H_DQ<0>")
	)
	(segment
		(start 37.577268 -40.6273)
		(end 38.371018 -41.42105)
		(width 0.14224)
		(layer "In4.Cu")
		(net "M_H_DQ<0>")
	)
	(segment
		(start 33.500568 -35.458908)
		(end 33.500568 -35.829748)
		(width 0.14224)
		(layer "In4.Cu")
		(net "M_H_DQ<0>")
	)
	(segment
		(start 33.208468 -33.840928)
		(end 33.500568 -34.133028)
		(width 0.14224)
		(layer "In4.Cu")
		(net "M_H_DQ<0>")
	)
	(segment
		(start 53.884068 -57.7596)
		(end 54.214268 -57.7596)
		(width 0.14224)
		(layer "In4.Cu")
		(net "M_H_DQ<0>")
	)
	(segment
		(start 33.426908 -25.947116)
		(end 33.271968 -26.102056)
		(width 0.14224)
		(layer "In4.Cu")
		(net "M_H_DQ<0>")
	)
	(segment
		(start 33.62452 -23.929848)
		(end 33.271968 -24.2824)
		(width 0.14224)
		(layer "In4.Cu")
		(net "M_H_DQ<0>")
	)
	(segment
		(start 38.371018 -41.42105)
		(end 38.371018 -42.24655)
		(width 0.14224)
		(layer "In4.Cu")
		(net "M_H_DQ<0>")
	)
	(segment
		(start 64.862202 -68.407534)
		(end 66.522092 -68.407534)
		(width 0.14224)
		(layer "In4.Cu")
		(net "M_H_DQ<0>")
	)
	(segment
		(start 33.271968 -26.455116)
		(end 33.426908 -26.610056)
		(width 0.14224)
		(layer "In4.Cu")
		(net "M_H_DQ<0>")
	)
	(segment
		(start 33.208468 -32.515048)
		(end 33.500568 -32.807148)
		(width 0.14224)
		(layer "In4.Cu")
		(net "M_H_DQ<0>")
	)
	(segment
		(start 33.271968 -25.129236)
		(end 33.426908 -25.284176)
		(width 0.14224)
		(layer "In4.Cu")
		(net "M_H_DQ<0>")
	)
	(segment
		(start 33.983168 -25.792176)
		(end 33.828228 -25.947116)
		(width 0.14224)
		(layer "In4.Cu")
		(net "M_H_DQ<0>")
	)
	(segment
		(start 33.602168 -16.8021)
		(end 33.271968 -17.1323)
		(width 0.14224)
		(layer "In4.Cu")
		(net "M_H_DQ<0>")
	)
	(segment
		(start 33.983168 -27.118056)
		(end 33.828228 -27.272996)
		(width 0.14224)
		(layer "In4.Cu")
		(net "M_H_DQ<0>")
	)
	(segment
		(start 33.828228 -26.610056)
		(end 33.983168 -26.764996)
		(width 0.14224)
		(layer "In4.Cu")
		(net "M_H_DQ<0>")
	)
	(segment
		(start 33.62452 -23.441152)
		(end 33.62452 -23.929848)
		(width 0.14224)
		(layer "In4.Cu")
		(net "M_H_DQ<0>")
	)
	(segment
		(start 71.140828 -68.73367)
		(end 71.252842 -68.552314)
		(width 0.0889)
		(layer "In4.Cu")
		(net "M_H_DQ<0>")
	)
	(segment
		(start 33.602168 -16.4592)
		(end 33.602168 -16.8021)
		(width 0.14224)
		(layer "In4.Cu")
		(net "M_H_DQ<0>")
	)
	(segment
		(start 33.500568 -33.177988)
		(end 33.208468 -33.470088)
		(width 0.14224)
		(layer "In4.Cu")
		(net "M_H_DQ<0>")
	)
	(segment
		(start 33.500568 -27.399996)
		(end 33.500568 -31.852108)
		(width 0.14224)
		(layer "In4.Cu")
		(net "M_H_DQ<0>")
	)
	(arc
		(start 67.484498 -68.265294)
		(mid 67.630423 -68.447381)
		(end 67.832986 -68.563236)
		(width 0.0889)
		(layer "In4.Cu")
		(net "M_H_DQ<0>")
	)
	(arc
		(start 67.268344 -68.06819)
		(mid 67.393545 -68.147961)
		(end 67.484498 -68.265294)
		(width 0.0889)
		(layer "In4.Cu")
		(net "M_H_DQ<0>")
	)
	(arc
		(start 68.047362 -68.563236)
		(mid 68.241212 -68.619586)
		(end 68.382896 -68.763388)
		(width 0.0889)
		(layer "In4.Cu")
		(net "M_H_DQ<0>")
	)
	(arc
		(start 69.774816 -69.553836)
		(mid 70.058033 -69.469555)
		(end 70.265036 -69.258688)
		(width 0.0889)
		(layer "In4.Cu")
		(net "M_H_DQ<0>")
	)
	(arc
		(start 69.241416 -69.258688)
		(mid 69.44842 -69.469552)
		(end 69.731636 -69.553836)
		(width 0.0889)
		(layer "In4.Cu")
		(net "M_H_DQ<0>")
	)
	(arc
		(start 68.909692 -69.05879)
		(mid 69.101334 -69.115956)
		(end 69.241416 -69.258688)
		(width 0.0889)
		(layer "In4.Cu")
		(net "M_H_DQ<0>")
	)
	(arc
		(start 70.629526 -69.05879)
		(mid 70.91495 -68.975323)
		(end 71.123556 -68.763388)
		(width 0.0889)
		(layer "In4.Cu")
		(net "M_H_DQ<0>")
	)
	(arc
		(start 70.265036 -69.258688)
		(mid 70.405115 -69.115952)
		(end 70.59676 -69.05879)
		(width 0.0889)
		(layer "In4.Cu")
		(net "M_H_DQ<0>")
	)
	(arc
		(start 68.382896 -68.763388)
		(mid 68.591504 -68.97532)
		(end 68.876926 -69.05879)
		(width 0.0889)
		(layer "In4.Cu")
		(net "M_H_DQ<0>")
	)
	(segment
		(start 102.089204 -56.58104)
		(end 101.517704 -56.58104)
		(width 0.1016)
		(layer "F.Cu")
		(net "M_H_CS_N<7>")
	)
	(via
		(at 101.517704 -56.58104)
		(size 0.508)
		(drill 0.254)
		(layers "F.Cu" "B.Cu")
		(net "M_H_CS_N<7>")
	)
	(via
		(at 112.99952 -11.918188)
		(size 0.4572)
		(drill 0.2032)
		(layers "F.Cu" "B.Cu")
		(net "M_H_CS_N<7>")
	)
	(segment
		(start 112.99952 -11.918188)
		(end 112.99952 -10.623042)
		(width 0.1651)
		(layer "B.Cu")
		(net "M_H_CS_N<7>")
	)
	(segment
		(start 103.604568 -50.038)
		(end 103.92537 -49.717198)
		(width 0.0889)
		(layer "In4.Cu")
		(net "M_H_CS_N<7>")
	)
	(segment
		(start 103.096568 -51.816)
		(end 103.604568 -51.308)
		(width 0.0889)
		(layer "In4.Cu")
		(net "M_H_CS_N<7>")
	)
	(segment
		(start 103.738172 -55.499)
		(end 103.985568 -55.251604)
		(width 0.0889)
		(layer "In4.Cu")
		(net "M_H_CS_N<7>")
	)
	(segment
		(start 113.075212 -13.194284)
		(end 113.075212 -11.99388)
		(width 0.14224)
		(layer "In4.Cu")
		(net "M_H_CS_N<7>")
	)
	(segment
		(start 103.985568 -54.991)
		(end 103.096568 -53.213)
		(width 0.0889)
		(layer "In4.Cu")
		(net "M_H_CS_N<7>")
	)
	(segment
		(start 103.92537 -49.2887)
		(end 103.92537 -34.603944)
		(width 0.14224)
		(layer "In4.Cu")
		(net "M_H_CS_N<7>")
	)
	(segment
		(start 103.92537 -34.603944)
		(end 113.495328 -25.033986)
		(width 0.14224)
		(layer "In4.Cu")
		(net "M_H_CS_N<7>")
	)
	(segment
		(start 103.92537 -49.717198)
		(end 103.92537 -49.2887)
		(width 0.0889)
		(layer "In4.Cu")
		(net "M_H_CS_N<7>")
	)
	(segment
		(start 113.535968 -17.079214)
		(end 113.535968 -13.65504)
		(width 0.14224)
		(layer "In4.Cu")
		(net "M_H_CS_N<7>")
	)
	(segment
		(start 113.075212 -11.99388)
		(end 112.99952 -11.918188)
		(width 0.14224)
		(layer "In4.Cu")
		(net "M_H_CS_N<7>")
	)
	(segment
		(start 103.985568 -55.251604)
		(end 103.985568 -54.991)
		(width 0.0889)
		(layer "In4.Cu")
		(net "M_H_CS_N<7>")
	)
	(segment
		(start 101.517704 -56.58104)
		(end 103.738172 -55.499)
		(width 0.0889)
		(layer "In4.Cu")
		(net "M_H_CS_N<7>")
	)
	(segment
		(start 113.495328 -25.033986)
		(end 113.495328 -17.119854)
		(width 0.14224)
		(layer "In4.Cu")
		(net "M_H_CS_N<7>")
	)
	(segment
		(start 103.096568 -53.213)
		(end 103.096568 -51.816)
		(width 0.0889)
		(layer "In4.Cu")
		(net "M_H_CS_N<7>")
	)
	(segment
		(start 113.495328 -17.119854)
		(end 113.535968 -17.079214)
		(width 0.14224)
		(layer "In4.Cu")
		(net "M_H_CS_N<7>")
	)
	(segment
		(start 103.604568 -51.308)
		(end 103.604568 -50.038)
		(width 0.0889)
		(layer "In4.Cu")
		(net "M_H_CS_N<7>")
	)
	(segment
		(start 113.535968 -13.65504)
		(end 113.075212 -13.194284)
		(width 0.14224)
		(layer "In4.Cu")
		(net "M_H_CS_N<7>")
	)
	(segment
		(start 102.947724 -55.094886)
		(end 103.557324 -55.094886)
		(width 0.1016)
		(layer "F.Cu")
		(net "M_H_CS_N<6>")
	)
	(via
		(at 103.557324 -55.094886)
		(size 0.508)
		(drill 0.254)
		(layers "F.Cu" "B.Cu")
		(net "M_H_CS_N<6>")
	)
	(via
		(at 112.99952 -13.934186)
		(size 0.4572)
		(drill 0.2032)
		(layers "F.Cu" "B.Cu")
		(net "M_H_CS_N<6>")
	)
	(segment
		(start 112.99952 -15.222982)
		(end 112.99952 -13.934186)
		(width 0.1651)
		(layer "B.Cu")
		(net "M_H_CS_N<6>")
	)
	(segment
		(start 112.443006 -23.017226)
		(end 112.443006 -22.6949)
		(width 0.14224)
		(layer "In4.Cu")
		(net "M_H_CS_N<6>")
	)
	(segment
		(start 112.740948 -21.99005)
		(end 112.411764 -21.660866)
		(width 0.14224)
		(layer "In4.Cu")
		(net "M_H_CS_N<6>")
	)
	(segment
		(start 112.746536 -15.62227)
		(end 112.591596 -15.46733)
		(width 0.14224)
		(layer "In4.Cu")
		(net "M_H_CS_N<6>")
	)
	(segment
		(start 102.842568 -54.990746)
		(end 102.842568 -51.689)
		(width 0.0889)
		(layer "In4.Cu")
		(net "M_H_CS_N<6>")
	)
	(segment
		(start 103.534718 -34.27603)
		(end 110.782862 -27.027886)
		(width 0.14224)
		(layer "In4.Cu")
		(net "M_H_CS_N<6>")
	)
	(segment
		(start 112.726724 -24.758904)
		(end 112.993424 -24.492204)
		(width 0.14224)
		(layer "In4.Cu")
		(net "M_H_CS_N<6>")
	)
	(segment
		(start 112.993424 -23.567644)
		(end 112.443006 -23.017226)
		(width 0.14224)
		(layer "In4.Cu")
		(net "M_H_CS_N<6>")
	)
	(segment
		(start 113.057686 -20.576032)
		(end 113.057686 -20.222972)
		(width 0.14224)
		(layer "In4.Cu")
		(net "M_H_CS_N<6>")
	)
	(segment
		(start 110.49 -26.447496)
		(end 110.49 -26.159968)
		(width 0.14224)
		(layer "In4.Cu")
		(net "M_H_CS_N<6>")
	)
	(segment
		(start 112.411764 -21.660866)
		(end 112.411764 -20.895056)
		(width 0.14224)
		(layer "In4.Cu")
		(net "M_H_CS_N<6>")
	)
	(segment
		(start 112.591596 -16.44015)
		(end 112.746536 -16.28521)
		(width 0.14224)
		(layer "In4.Cu")
		(net "M_H_CS_N<6>")
	)
	(segment
		(start 103.350568 -49.784)
		(end 103.534718 -49.59985)
		(width 0.0889)
		(layer "In4.Cu")
		(net "M_H_CS_N<6>")
	)
	(segment
		(start 112.99952 -14.684248)
		(end 112.99952 -13.934186)
		(width 0.14224)
		(layer "In4.Cu")
		(net "M_H_CS_N<6>")
	)
	(segment
		(start 113.089436 -15.77721)
		(end 112.934496 -15.62227)
		(width 0.14224)
		(layer "In4.Cu")
		(net "M_H_CS_N<6>")
	)
	(segment
		(start 112.443006 -22.6949)
		(end 112.740948 -22.396958)
		(width 0.14224)
		(layer "In4.Cu")
		(net "M_H_CS_N<6>")
	)
	(segment
		(start 112.902746 -20.068032)
		(end 112.526572 -20.068032)
		(width 0.14224)
		(layer "In4.Cu")
		(net "M_H_CS_N<6>")
	)
	(segment
		(start 112.740948 -22.396958)
		(end 112.740948 -21.99005)
		(width 0.14224)
		(layer "In4.Cu")
		(net "M_H_CS_N<6>")
	)
	(segment
		(start 113.057686 -20.222972)
		(end 112.902746 -20.068032)
		(width 0.14224)
		(layer "In4.Cu")
		(net "M_H_CS_N<6>")
	)
	(segment
		(start 112.526572 -20.068032)
		(end 112.371378 -19.912838)
		(width 0.14224)
		(layer "In4.Cu")
		(net "M_H_CS_N<6>")
	)
	(segment
		(start 113.078768 -17.48536)
		(end 112.923828 -17.33042)
		(width 0.14224)
		(layer "In4.Cu")
		(net "M_H_CS_N<6>")
	)
	(segment
		(start 112.591596 -15.092172)
		(end 112.99952 -14.684248)
		(width 0.14224)
		(layer "In4.Cu")
		(net "M_H_CS_N<6>")
	)
	(segment
		(start 111.357664 -26.165556)
		(end 111.645192 -26.165556)
		(width 0.14224)
		(layer "In4.Cu")
		(net "M_H_CS_N<6>")
	)
	(segment
		(start 110.782862 -27.027886)
		(end 110.782862 -26.740358)
		(width 0.14224)
		(layer "In4.Cu")
		(net "M_H_CS_N<6>")
	)
	(segment
		(start 103.534718 -49.319688)
		(end 103.534718 -34.27603)
		(width 0.14224)
		(layer "In4.Cu")
		(net "M_H_CS_N<6>")
	)
	(segment
		(start 112.902746 -20.730972)
		(end 113.057686 -20.576032)
		(width 0.14224)
		(layer "In4.Cu")
		(net "M_H_CS_N<6>")
	)
	(segment
		(start 110.782862 -26.740358)
		(end 110.49 -26.447496)
		(width 0.14224)
		(layer "In4.Cu")
		(net "M_H_CS_N<6>")
	)
	(segment
		(start 112.934496 -15.62227)
		(end 112.746536 -15.62227)
		(width 0.14224)
		(layer "In4.Cu")
		(net "M_H_CS_N<6>")
	)
	(segment
		(start 112.411764 -20.895056)
		(end 112.575848 -20.730972)
		(width 0.14224)
		(layer "In4.Cu")
		(net "M_H_CS_N<6>")
	)
	(segment
		(start 112.371378 -19.912838)
		(end 112.371378 -19.312382)
		(width 0.14224)
		(layer "In4.Cu")
		(net "M_H_CS_N<6>")
	)
	(segment
		(start 112.591596 -18.1483)
		(end 112.746536 -17.99336)
		(width 0.14224)
		(layer "In4.Cu")
		(net "M_H_CS_N<6>")
	)
	(segment
		(start 103.557324 -55.094886)
		(end 102.946708 -55.094886)
		(width 0.0889)
		(layer "In4.Cu")
		(net "M_H_CS_N<6>")
	)
	(segment
		(start 111.639604 -25.297892)
		(end 111.639604 -25.010364)
		(width 0.14224)
		(layer "In4.Cu")
		(net "M_H_CS_N<6>")
	)
	(segment
		(start 112.591596 -19.092164)
		(end 112.591596 -18.1483)
		(width 0.14224)
		(layer "In4.Cu")
		(net "M_H_CS_N<6>")
	)
	(segment
		(start 112.923828 -17.33042)
		(end 112.746536 -17.33042)
		(width 0.14224)
		(layer "In4.Cu")
		(net "M_H_CS_N<6>")
	)
	(segment
		(start 112.371378 -19.312382)
		(end 112.591596 -19.092164)
		(width 0.14224)
		(layer "In4.Cu")
		(net "M_H_CS_N<6>")
	)
	(segment
		(start 111.645192 -26.165556)
		(end 111.932466 -25.878282)
		(width 0.14224)
		(layer "In4.Cu")
		(net "M_H_CS_N<6>")
	)
	(segment
		(start 113.078768 -17.83842)
		(end 113.078768 -17.48536)
		(width 0.14224)
		(layer "In4.Cu")
		(net "M_H_CS_N<6>")
	)
	(segment
		(start 112.993424 -24.492204)
		(end 112.993424 -23.567644)
		(width 0.14224)
		(layer "In4.Cu")
		(net "M_H_CS_N<6>")
	)
	(segment
		(start 112.746536 -17.33042)
		(end 112.591596 -17.17548)
		(width 0.14224)
		(layer "In4.Cu")
		(net "M_H_CS_N<6>")
	)
	(segment
		(start 112.591596 -15.46733)
		(end 112.591596 -15.092172)
		(width 0.14224)
		(layer "In4.Cu")
		(net "M_H_CS_N<6>")
	)
	(segment
		(start 112.934496 -16.28521)
		(end 113.089436 -16.13027)
		(width 0.14224)
		(layer "In4.Cu")
		(net "M_H_CS_N<6>")
	)
	(segment
		(start 103.350568 -51.181)
		(end 103.350568 -49.784)
		(width 0.0889)
		(layer "In4.Cu")
		(net "M_H_CS_N<6>")
	)
	(segment
		(start 113.089436 -16.13027)
		(end 113.089436 -15.77721)
		(width 0.14224)
		(layer "In4.Cu")
		(net "M_H_CS_N<6>")
	)
	(segment
		(start 110.49 -26.159968)
		(end 110.777274 -25.872694)
		(width 0.14224)
		(layer "In4.Cu")
		(net "M_H_CS_N<6>")
	)
	(segment
		(start 102.842568 -51.689)
		(end 103.350568 -51.181)
		(width 0.0889)
		(layer "In4.Cu")
		(net "M_H_CS_N<6>")
	)
	(segment
		(start 103.534718 -49.59985)
		(end 103.534718 -49.319688)
		(width 0.0889)
		(layer "In4.Cu")
		(net "M_H_CS_N<6>")
	)
	(segment
		(start 102.946708 -55.094886)
		(end 102.842568 -54.990746)
		(width 0.0889)
		(layer "In4.Cu")
		(net "M_H_CS_N<6>")
	)
	(segment
		(start 110.777274 -25.872694)
		(end 111.064802 -25.872694)
		(width 0.14224)
		(layer "In4.Cu")
		(net "M_H_CS_N<6>")
	)
	(segment
		(start 111.932466 -25.590754)
		(end 111.639604 -25.297892)
		(width 0.14224)
		(layer "In4.Cu")
		(net "M_H_CS_N<6>")
	)
	(segment
		(start 111.891064 -24.758904)
		(end 112.726724 -24.758904)
		(width 0.14224)
		(layer "In4.Cu")
		(net "M_H_CS_N<6>")
	)
	(segment
		(start 112.746536 -17.99336)
		(end 112.923828 -17.99336)
		(width 0.14224)
		(layer "In4.Cu")
		(net "M_H_CS_N<6>")
	)
	(segment
		(start 112.923828 -17.99336)
		(end 113.078768 -17.83842)
		(width 0.14224)
		(layer "In4.Cu")
		(net "M_H_CS_N<6>")
	)
	(segment
		(start 111.932466 -25.878282)
		(end 111.932466 -25.590754)
		(width 0.14224)
		(layer "In4.Cu")
		(net "M_H_CS_N<6>")
	)
	(segment
		(start 111.639604 -25.010364)
		(end 111.891064 -24.758904)
		(width 0.14224)
		(layer "In4.Cu")
		(net "M_H_CS_N<6>")
	)
	(segment
		(start 112.746536 -16.28521)
		(end 112.934496 -16.28521)
		(width 0.14224)
		(layer "In4.Cu")
		(net "M_H_CS_N<6>")
	)
	(segment
		(start 111.064802 -25.872694)
		(end 111.357664 -26.165556)
		(width 0.14224)
		(layer "In4.Cu")
		(net "M_H_CS_N<6>")
	)
	(segment
		(start 112.575848 -20.730972)
		(end 112.902746 -20.730972)
		(width 0.14224)
		(layer "In4.Cu")
		(net "M_H_CS_N<6>")
	)
	(segment
		(start 112.591596 -17.17548)
		(end 112.591596 -16.44015)
		(width 0.14224)
		(layer "In4.Cu")
		(net "M_H_CS_N<6>")
	)
	(segment
		(start 99.513898 -57.076086)
		(end 98.942398 -57.076086)
		(width 0.1016)
		(layer "F.Cu")
		(net "M_H_CS_N<5>")
	)
	(via
		(at 98.942398 -57.076086)
		(size 0.508)
		(drill 0.254)
		(layers "F.Cu" "B.Cu")
		(net "M_H_CS_N<5>")
	)
	(via
		(at 109.599476 -13.929868)
		(size 0.4572)
		(drill 0.2032)
		(layers "F.Cu" "B.Cu")
		(net "M_H_CS_N<5>")
	)
	(segment
		(start 109.599476 -15.222982)
		(end 109.599476 -13.929868)
		(width 0.1651)
		(layer "B.Cu")
		(net "M_H_CS_N<5>")
	)
	(segment
		(start 108.165646 -22.408896)
		(end 108.165646 -21.964396)
		(width 0.14224)
		(layer "In4.Cu")
		(net "M_H_CS_N<5>")
	)
	(segment
		(start 99.438714 -56.408574)
		(end 99.454208 -56.381142)
		(width 0.0889)
		(layer "In4.Cu")
		(net "M_H_CS_N<5>")
	)
	(segment
		(start 100.312474 -53.904388)
		(end 100.318824 -53.89372)
		(width 0.0889)
		(layer "In4.Cu")
		(net "M_H_CS_N<5>")
	)
	(segment
		(start 108.419646 -22.662896)
		(end 108.165646 -22.408896)
		(width 0.14224)
		(layer "In4.Cu")
		(net "M_H_CS_N<5>")
	)
	(segment
		(start 108.125768 -24.2824)
		(end 108.125768 -23.418546)
		(width 0.14224)
		(layer "In4.Cu")
		(net "M_H_CS_N<5>")
	)
	(segment
		(start 100.307648 -53.913024)
		(end 100.312474 -53.904388)
		(width 0.0889)
		(layer "In4.Cu")
		(net "M_H_CS_N<5>")
	)
	(segment
		(start 106.398568 -26.0096)
		(end 108.125768 -24.2824)
		(width 0.14224)
		(layer "In4.Cu")
		(net "M_H_CS_N<5>")
	)
	(segment
		(start 101.482398 -50.683414)
		(end 101.482398 -49.658778)
		(width 0.0889)
		(layer "In4.Cu")
		(net "M_H_CS_N<5>")
	)
	(segment
		(start 100.988368 -51.177444)
		(end 101.482398 -50.683414)
		(width 0.0889)
		(layer "In4.Cu")
		(net "M_H_CS_N<5>")
	)
	(segment
		(start 99.800664 -55.19039)
		(end 99.818444 -55.19039)
		(width 0.0889)
		(layer "In4.Cu")
		(net "M_H_CS_N<5>")
	)
	(segment
		(start 108.33608 -21.003768)
		(end 108.33608 -15.193264)
		(width 0.14224)
		(layer "In4.Cu")
		(net "M_H_CS_N<5>")
	)
	(segment
		(start 100.301806 -52.807108)
		(end 100.988368 -52.1208)
		(width 0.0889)
		(layer "In4.Cu")
		(net "M_H_CS_N<5>")
	)
	(segment
		(start 108.448602 -21.68144)
		(end 108.448602 -21.11629)
		(width 0.14224)
		(layer "In4.Cu")
		(net "M_H_CS_N<5>")
	)
	(segment
		(start 100.988368 -52.1208)
		(end 100.988368 -51.177444)
		(width 0.0889)
		(layer "In4.Cu")
		(net "M_H_CS_N<5>")
	)
	(segment
		(start 99.463098 -55.805578)
		(end 99.454208 -55.790338)
		(width 0.0889)
		(layer "In4.Cu")
		(net "M_H_CS_N<5>")
	)
	(segment
		(start 101.482398 -49.658778)
		(end 101.482398 -32.73425)
		(width 0.14224)
		(layer "In4.Cu")
		(net "M_H_CS_N<5>")
	)
	(segment
		(start 108.165646 -21.964396)
		(end 108.448602 -21.68144)
		(width 0.14224)
		(layer "In4.Cu")
		(net "M_H_CS_N<5>")
	)
	(segment
		(start 108.448602 -21.11629)
		(end 108.33608 -21.003768)
		(width 0.14224)
		(layer "In4.Cu")
		(net "M_H_CS_N<5>")
	)
	(segment
		(start 101.482398 -32.73425)
		(end 106.398568 -27.81808)
		(width 0.14224)
		(layer "In4.Cu")
		(net "M_H_CS_N<5>")
	)
	(segment
		(start 100.239068 -53.039772)
		(end 100.239068 -52.959)
		(width 0.0889)
		(layer "In4.Cu")
		(net "M_H_CS_N<5>")
	)
	(segment
		(start 98.942398 -57.076086)
		(end 99.438714 -56.408574)
		(width 0.0889)
		(layer "In4.Cu")
		(net "M_H_CS_N<5>")
	)
	(segment
		(start 108.125768 -23.418546)
		(end 108.419646 -23.124668)
		(width 0.14224)
		(layer "In4.Cu")
		(net "M_H_CS_N<5>")
	)
	(segment
		(start 106.398568 -27.81808)
		(end 106.398568 -26.0096)
		(width 0.14224)
		(layer "In4.Cu")
		(net "M_H_CS_N<5>")
	)
	(segment
		(start 108.33608 -15.193264)
		(end 109.599476 -13.929868)
		(width 0.14224)
		(layer "In4.Cu")
		(net "M_H_CS_N<5>")
	)
	(segment
		(start 108.419646 -23.124668)
		(end 108.419646 -22.662896)
		(width 0.14224)
		(layer "In4.Cu")
		(net "M_H_CS_N<5>")
	)
	(arc
		(start 99.454208 -55.790338)
		(mid 99.454291 -55.390397)
		(end 99.800664 -55.19039)
		(width 0.0889)
		(layer "In4.Cu")
		(net "M_H_CS_N<5>")
	)
	(arc
		(start 99.818444 -55.19039)
		(mid 100.316695 -54.88755)
		(end 100.312474 -54.304438)
		(width 0.0889)
		(layer "In4.Cu")
		(net "M_H_CS_N<5>")
	)
	(arc
		(start 100.239068 -52.959)
		(mid 100.255323 -52.876811)
		(end 100.301806 -52.807108)
		(width 0.0889)
		(layer "In4.Cu")
		(net "M_H_CS_N<5>")
	)
	(arc
		(start 100.312474 -54.304438)
		(mid 100.259004 -54.109375)
		(end 100.307648 -53.913024)
		(width 0.0889)
		(layer "In4.Cu")
		(net "M_H_CS_N<5>")
	)
	(arc
		(start 99.454208 -56.381142)
		(mid 99.533397 -56.094527)
		(end 99.463098 -55.805578)
		(width 0.0889)
		(layer "In4.Cu")
		(net "M_H_CS_N<5>")
	)
	(arc
		(start 100.312474 -53.313838)
		(mid 100.257768 -53.18163)
		(end 100.239068 -53.039772)
		(width 0.0889)
		(layer "In4.Cu")
		(net "M_H_CS_N<5>")
	)
	(arc
		(start 100.318824 -53.89372)
		(mid 100.391622 -53.602957)
		(end 100.312474 -53.313838)
		(width 0.0889)
		(layer "In4.Cu")
		(net "M_H_CS_N<5>")
	)
	(segment
		(start 98.655378 -53.60924)
		(end 98.083878 -53.60924)
		(width 0.1016)
		(layer "F.Cu")
		(net "M_H_CS_N<4>")
	)
	(via
		(at 98.083878 -53.60924)
		(size 0.508)
		(drill 0.254)
		(layers "F.Cu" "B.Cu")
		(net "M_H_CS_N<4>")
	)
	(via
		(at 105.349802 -13.933678)
		(size 0.4572)
		(drill 0.2032)
		(layers "F.Cu" "B.Cu")
		(net "M_H_CS_N<4>")
	)
	(segment
		(start 105.349548 -13.933932)
		(end 105.349802 -13.933678)
		(width 0.1651)
		(layer "B.Cu")
		(net "M_H_CS_N<4>")
	)
	(segment
		(start 105.349548 -15.222982)
		(end 105.349548 -13.933932)
		(width 0.1651)
		(layer "B.Cu")
		(net "M_H_CS_N<4>")
	)
	(segment
		(start 104.264968 -17.26819)
		(end 104.089962 -17.093184)
		(width 0.14224)
		(layer "In4.Cu")
		(net "M_H_CS_N<4>")
	)
	(segment
		(start 98.485452 -52.723542)
		(end 98.485452 -51.93157)
		(width 0.0889)
		(layer "In4.Cu")
		(net "M_H_CS_N<4>")
	)
	(segment
		(start 104.024176 -23.203408)
		(end 104.024176 -22.554184)
		(width 0.14224)
		(layer "In4.Cu")
		(net "M_H_CS_N<4>")
	)
	(segment
		(start 102.613968 -27.95905)
		(end 102.613968 -25.8572)
		(width 0.14224)
		(layer "In4.Cu")
		(net "M_H_CS_N<4>")
	)
	(segment
		(start 104.087422 -20.919694)
		(end 104.087422 -18.391632)
		(width 0.14224)
		(layer "In4.Cu")
		(net "M_H_CS_N<4>")
	)
	(segment
		(start 100.42144 -29.914342)
		(end 100.16617 -29.659326)
		(width 0.14224)
		(layer "In4.Cu")
		(net "M_H_CS_N<4>")
	)
	(segment
		(start 100.16617 -29.659326)
		(end 100.16617 -29.372306)
		(width 0.14224)
		(layer "In4.Cu")
		(net "M_H_CS_N<4>")
	)
	(segment
		(start 101.603556 -27.93492)
		(end 101.890576 -27.93492)
		(width 0.14224)
		(layer "In4.Cu")
		(net "M_H_CS_N<4>")
	)
	(segment
		(start 102.116128 -28.160472)
		(end 102.412546 -28.160472)
		(width 0.14224)
		(layer "In4.Cu")
		(net "M_H_CS_N<4>")
	)
	(segment
		(start 101.315774 -28.509722)
		(end 101.315774 -28.222702)
		(width 0.14224)
		(layer "In4.Cu")
		(net "M_H_CS_N<4>")
	)
	(segment
		(start 98.485452 -51.93157)
		(end 99.108768 -51.308254)
		(width 0.0889)
		(layer "In4.Cu")
		(net "M_H_CS_N<4>")
	)
	(segment
		(start 104.024176 -22.554184)
		(end 104.11968 -22.45868)
		(width 0.14224)
		(layer "In4.Cu")
		(net "M_H_CS_N<4>")
	)
	(segment
		(start 102.412546 -28.160472)
		(end 102.613968 -27.95905)
		(width 0.14224)
		(layer "In4.Cu")
		(net "M_H_CS_N<4>")
	)
	(segment
		(start 101.571044 -28.764738)
		(end 101.315774 -28.509722)
		(width 0.14224)
		(layer "In4.Cu")
		(net "M_H_CS_N<4>")
	)
	(segment
		(start 104.128062 -24.343106)
		(end 104.128062 -23.307294)
		(width 0.14224)
		(layer "In4.Cu")
		(net "M_H_CS_N<4>")
	)
	(segment
		(start 101.283262 -29.33954)
		(end 101.571044 -29.051758)
		(width 0.14224)
		(layer "In4.Cu")
		(net "M_H_CS_N<4>")
	)
	(segment
		(start 103.946706 -21.779738)
		(end 103.946706 -21.06041)
		(width 0.14224)
		(layer "In4.Cu")
		(net "M_H_CS_N<4>")
	)
	(segment
		(start 103.946706 -21.06041)
		(end 104.087422 -20.919694)
		(width 0.14224)
		(layer "In4.Cu")
		(net "M_H_CS_N<4>")
	)
	(segment
		(start 104.089962 -17.093184)
		(end 104.089962 -15.193518)
		(width 0.14224)
		(layer "In4.Cu")
		(net "M_H_CS_N<4>")
	)
	(segment
		(start 104.11968 -21.952712)
		(end 103.946706 -21.779738)
		(width 0.14224)
		(layer "In4.Cu")
		(net "M_H_CS_N<4>")
	)
	(segment
		(start 99.191064 -48.848264)
		(end 99.191064 -30.727396)
		(width 0.14224)
		(layer "In4.Cu")
		(net "M_H_CS_N<4>")
	)
	(segment
		(start 102.613968 -25.8572)
		(end 104.128062 -24.343106)
		(width 0.14224)
		(layer "In4.Cu")
		(net "M_H_CS_N<4>")
	)
	(segment
		(start 100.42144 -30.201362)
		(end 100.42144 -29.914342)
		(width 0.14224)
		(layer "In4.Cu")
		(net "M_H_CS_N<4>")
	)
	(segment
		(start 101.315774 -28.222702)
		(end 101.603556 -27.93492)
		(width 0.14224)
		(layer "In4.Cu")
		(net "M_H_CS_N<4>")
	)
	(segment
		(start 100.453952 -29.084524)
		(end 100.740972 -29.084524)
		(width 0.14224)
		(layer "In4.Cu")
		(net "M_H_CS_N<4>")
	)
	(segment
		(start 100.740972 -29.084524)
		(end 100.996242 -29.33954)
		(width 0.14224)
		(layer "In4.Cu")
		(net "M_H_CS_N<4>")
	)
	(segment
		(start 99.191064 -30.727396)
		(end 99.490784 -30.427676)
		(width 0.14224)
		(layer "In4.Cu")
		(net "M_H_CS_N<4>")
	)
	(segment
		(start 99.108768 -51.308254)
		(end 99.108768 -49.149254)
		(width 0.0889)
		(layer "In4.Cu")
		(net "M_H_CS_N<4>")
	)
	(segment
		(start 104.11968 -22.45868)
		(end 104.11968 -21.952712)
		(width 0.14224)
		(layer "In4.Cu")
		(net "M_H_CS_N<4>")
	)
	(segment
		(start 101.571044 -29.051758)
		(end 101.571044 -28.764738)
		(width 0.14224)
		(layer "In4.Cu")
		(net "M_H_CS_N<4>")
	)
	(segment
		(start 98.413824 -52.84724)
		(end 98.485452 -52.723542)
		(width 0.0889)
		(layer "In4.Cu")
		(net "M_H_CS_N<4>")
	)
	(segment
		(start 100.16617 -29.372306)
		(end 100.453952 -29.084524)
		(width 0.14224)
		(layer "In4.Cu")
		(net "M_H_CS_N<4>")
	)
	(segment
		(start 104.128062 -23.307294)
		(end 104.024176 -23.203408)
		(width 0.14224)
		(layer "In4.Cu")
		(net "M_H_CS_N<4>")
	)
	(segment
		(start 99.191064 -49.066958)
		(end 99.191064 -48.848264)
		(width 0.0889)
		(layer "In4.Cu")
		(net "M_H_CS_N<4>")
	)
	(segment
		(start 100.195126 -30.427676)
		(end 100.42144 -30.201362)
		(width 0.14224)
		(layer "In4.Cu")
		(net "M_H_CS_N<4>")
	)
	(segment
		(start 99.108768 -49.149254)
		(end 99.191064 -49.066958)
		(width 0.0889)
		(layer "In4.Cu")
		(net "M_H_CS_N<4>")
	)
	(segment
		(start 100.996242 -29.33954)
		(end 101.283262 -29.33954)
		(width 0.14224)
		(layer "In4.Cu")
		(net "M_H_CS_N<4>")
	)
	(segment
		(start 99.490784 -30.427676)
		(end 100.195126 -30.427676)
		(width 0.14224)
		(layer "In4.Cu")
		(net "M_H_CS_N<4>")
	)
	(segment
		(start 104.087422 -18.391632)
		(end 104.264968 -18.214086)
		(width 0.14224)
		(layer "In4.Cu")
		(net "M_H_CS_N<4>")
	)
	(segment
		(start 101.890576 -27.93492)
		(end 102.116128 -28.160472)
		(width 0.14224)
		(layer "In4.Cu")
		(net "M_H_CS_N<4>")
	)
	(segment
		(start 104.264968 -18.214086)
		(end 104.264968 -17.26819)
		(width 0.14224)
		(layer "In4.Cu")
		(net "M_H_CS_N<4>")
	)
	(segment
		(start 104.089962 -15.193518)
		(end 105.349802 -13.933678)
		(width 0.14224)
		(layer "In4.Cu")
		(net "M_H_CS_N<4>")
	)
	(segment
		(start 98.083878 -53.60924)
		(end 98.413824 -52.84724)
		(width 0.0889)
		(layer "In4.Cu")
		(net "M_H_CS_N<4>")
	)
	(segment
		(start 112.99952 -9.133586)
		(end 113.000028 -9.133078)
		(width 0.1651)
		(layer "F.Cu")
		(net "M_H_CS_N<3>")
	)
	(segment
		(start 101.230684 -58.06694)
		(end 100.659184 -58.06694)
		(width 0.1016)
		(layer "F.Cu")
		(net "M_H_CS_N<3>")
	)
	(segment
		(start 112.99952 -10.422382)
		(end 112.99952 -9.133586)
		(width 0.1651)
		(layer "F.Cu")
		(net "M_H_CS_N<3>")
	)
	(via
		(at 100.659184 -58.06694)
		(size 0.508)
		(drill 0.254)
		(layers "F.Cu" "B.Cu")
		(net "M_H_CS_N<3>")
	)
	(via
		(at 113.000028 -9.133078)
		(size 0.4572)
		(drill 0.2032)
		(layers "F.Cu" "B.Cu")
		(net "M_H_CS_N<3>")
	)
	(segment
		(start 102.489 -55.242968)
		(end 102.489 -51.534822)
		(width 0.0889)
		(layer "In4.Cu")
		(net "M_H_CS_N<3>")
	)
	(segment
		(start 111.834168 -19.0754)
		(end 111.716312 -18.957544)
		(width 0.14224)
		(layer "In4.Cu")
		(net "M_H_CS_N<3>")
	)
	(segment
		(start 111.620808 -24.218646)
		(end 111.620808 -23.30196)
		(width 0.14224)
		(layer "In4.Cu")
		(net "M_H_CS_N<3>")
	)
	(segment
		(start 111.711994 -15.209774)
		(end 112.587024 -14.334744)
		(width 0.14224)
		(layer "In4.Cu")
		(net "M_H_CS_N<3>")
	)
	(segment
		(start 111.834168 -21.7678)
		(end 111.834168 -19.0754)
		(width 0.14224)
		(layer "In4.Cu")
		(net "M_H_CS_N<3>")
	)
	(segment
		(start 111.620808 -23.30196)
		(end 111.884968 -23.0378)
		(width 0.14224)
		(layer "In4.Cu")
		(net "M_H_CS_N<3>")
	)
	(segment
		(start 111.580168 -17.5768)
		(end 111.580168 -17.145)
		(width 0.14224)
		(layer "In4.Cu")
		(net "M_H_CS_N<3>")
	)
	(segment
		(start 111.808768 -18.2626)
		(end 111.808768 -17.8054)
		(width 0.14224)
		(layer "In4.Cu")
		(net "M_H_CS_N<3>")
	)
	(segment
		(start 109.700568 -27.39136)
		(end 109.700568 -26.138886)
		(width 0.14224)
		(layer "In4.Cu")
		(net "M_H_CS_N<3>")
	)
	(segment
		(start 101.177344 -56.791606)
		(end 101.170994 -56.780938)
		(width 0.0889)
		(layer "In4.Cu")
		(net "M_H_CS_N<3>")
	)
	(segment
		(start 111.571532 -22.030436)
		(end 111.834168 -21.7678)
		(width 0.14224)
		(layer "In4.Cu")
		(net "M_H_CS_N<3>")
	)
	(segment
		(start 100.659184 -58.06694)
		(end 101.15423 -57.400698)
		(width 0.0889)
		(layer "In4.Cu")
		(net "M_H_CS_N<3>")
	)
	(segment
		(start 111.884968 -23.0378)
		(end 111.884968 -22.6314)
		(width 0.14224)
		(layer "In4.Cu")
		(net "M_H_CS_N<3>")
	)
	(segment
		(start 112.587024 -14.334744)
		(end 112.587024 -13.503656)
		(width 0.14224)
		(layer "In4.Cu")
		(net "M_H_CS_N<3>")
	)
	(segment
		(start 111.716312 -18.355056)
		(end 111.808768 -18.2626)
		(width 0.14224)
		(layer "In4.Cu")
		(net "M_H_CS_N<3>")
	)
	(segment
		(start 112.587024 -13.503656)
		(end 112.443768 -13.3604)
		(width 0.14224)
		(layer "In4.Cu")
		(net "M_H_CS_N<3>")
	)
	(segment
		(start 111.716312 -18.957544)
		(end 111.716312 -18.355056)
		(width 0.14224)
		(layer "In4.Cu")
		(net "M_H_CS_N<3>")
	)
	(segment
		(start 111.884968 -22.6314)
		(end 111.571532 -22.317964)
		(width 0.14224)
		(layer "In4.Cu")
		(net "M_H_CS_N<3>")
	)
	(segment
		(start 102.489 -51.534822)
		(end 103.121968 -50.901854)
		(width 0.0889)
		(layer "In4.Cu")
		(net "M_H_CS_N<3>")
	)
	(segment
		(start 111.711994 -17.013174)
		(end 111.711994 -15.209774)
		(width 0.14224)
		(layer "In4.Cu")
		(net "M_H_CS_N<3>")
	)
	(segment
		(start 109.700568 -26.138886)
		(end 111.620808 -24.218646)
		(width 0.14224)
		(layer "In4.Cu")
		(net "M_H_CS_N<3>")
	)
	(segment
		(start 101.550978 -56.18099)
		(end 102.489 -55.242968)
		(width 0.0889)
		(layer "In4.Cu")
		(net "M_H_CS_N<3>")
	)
	(segment
		(start 111.580168 -17.145)
		(end 111.711994 -17.013174)
		(width 0.14224)
		(layer "In4.Cu")
		(net "M_H_CS_N<3>")
	)
	(segment
		(start 101.170994 -56.780938)
		(end 101.166168 -56.772302)
		(width 0.0889)
		(layer "In4.Cu")
		(net "M_H_CS_N<3>")
	)
	(segment
		(start 103.121968 -33.96996)
		(end 109.700568 -27.39136)
		(width 0.14224)
		(layer "In4.Cu")
		(net "M_H_CS_N<3>")
	)
	(segment
		(start 111.808768 -17.8054)
		(end 111.580168 -17.5768)
		(width 0.14224)
		(layer "In4.Cu")
		(net "M_H_CS_N<3>")
	)
	(segment
		(start 103.121968 -50.901854)
		(end 103.121968 -49.368964)
		(width 0.0889)
		(layer "In4.Cu")
		(net "M_H_CS_N<3>")
	)
	(segment
		(start 112.443768 -12.43838)
		(end 112.587024 -12.092178)
		(width 0.14224)
		(layer "In4.Cu")
		(net "M_H_CS_N<3>")
	)
	(segment
		(start 111.571532 -22.317964)
		(end 111.571532 -22.030436)
		(width 0.14224)
		(layer "In4.Cu")
		(net "M_H_CS_N<3>")
	)
	(segment
		(start 112.443768 -13.3604)
		(end 112.443768 -12.43838)
		(width 0.14224)
		(layer "In4.Cu")
		(net "M_H_CS_N<3>")
	)
	(segment
		(start 103.121968 -49.368964)
		(end 103.121968 -33.96996)
		(width 0.14224)
		(layer "In4.Cu")
		(net "M_H_CS_N<3>")
	)
	(segment
		(start 112.587024 -9.546082)
		(end 113.000028 -9.133078)
		(width 0.14224)
		(layer "In4.Cu")
		(net "M_H_CS_N<3>")
	)
	(segment
		(start 101.502718 -56.18099)
		(end 101.550978 -56.18099)
		(width 0.0889)
		(layer "In4.Cu")
		(net "M_H_CS_N<3>")
	)
	(segment
		(start 101.15423 -57.400698)
		(end 101.170994 -57.371488)
		(width 0.0889)
		(layer "In4.Cu")
		(net "M_H_CS_N<3>")
	)
	(segment
		(start 112.587024 -12.092178)
		(end 112.587024 -9.546082)
		(width 0.14224)
		(layer "In4.Cu")
		(net "M_H_CS_N<3>")
	)
	(arc
		(start 101.166168 -56.772302)
		(mid 101.169915 -56.383046)
		(end 101.502718 -56.18099)
		(width 0.0889)
		(layer "In4.Cu")
		(net "M_H_CS_N<3>")
	)
	(arc
		(start 101.170994 -57.371488)
		(mid 101.250216 -57.08237)
		(end 101.177344 -56.791606)
		(width 0.0889)
		(layer "In4.Cu")
		(net "M_H_CS_N<3>")
	)
	(segment
		(start 112.99952 -7.117588)
		(end 112.99952 -5.822442)
		(width 0.1651)
		(layer "F.Cu")
		(net "M_H_CS_N<2>")
	)
	(segment
		(start 102.089204 -55.59044)
		(end 101.517704 -55.59044)
		(width 0.1016)
		(layer "F.Cu")
		(net "M_H_CS_N<2>")
	)
	(via
		(at 101.517704 -55.59044)
		(size 0.508)
		(drill 0.254)
		(layers "F.Cu" "B.Cu")
		(net "M_H_CS_N<2>")
	)
	(via
		(at 112.99952 -7.117588)
		(size 0.4572)
		(drill 0.2032)
		(layers "F.Cu" "B.Cu")
		(net "M_H_CS_N<2>")
	)
	(segment
		(start 110.919768 -23.2156)
		(end 110.767368 -23.0632)
		(width 0.14224)
		(layer "In4.Cu")
		(net "M_H_CS_N<2>")
	)
	(segment
		(start 111.712502 -12.5984)
		(end 111.712502 -8.910066)
		(width 0.14224)
		(layer "In4.Cu")
		(net "M_H_CS_N<2>")
	)
	(segment
		(start 110.970568 -21.9456)
		(end 110.741968 -21.717)
		(width 0.14224)
		(layer "In4.Cu")
		(net "M_H_CS_N<2>")
	)
	(segment
		(start 110.945168 -17.145)
		(end 110.885732 -17.085564)
		(width 0.14224)
		(layer "In4.Cu")
		(net "M_H_CS_N<2>")
	)
	(segment
		(start 112.99952 -7.623048)
		(end 112.99952 -7.117588)
		(width 0.14224)
		(layer "In4.Cu")
		(net "M_H_CS_N<2>")
	)
	(segment
		(start 110.885732 -15.22222)
		(end 111.71047 -14.397482)
		(width 0.14224)
		(layer "In4.Cu")
		(net "M_H_CS_N<2>")
	)
	(segment
		(start 101.517704 -55.59044)
		(end 102.2985 -54.809644)
		(width 0.0889)
		(layer "In4.Cu")
		(net "M_H_CS_N<2>")
	)
	(segment
		(start 111.71047 -14.397482)
		(end 111.71047 -12.600432)
		(width 0.14224)
		(layer "In4.Cu")
		(net "M_H_CS_N<2>")
	)
	(segment
		(start 110.945168 -17.653)
		(end 110.945168 -17.145)
		(width 0.14224)
		(layer "In4.Cu")
		(net "M_H_CS_N<2>")
	)
	(segment
		(start 110.767368 -23.0632)
		(end 110.767368 -22.6822)
		(width 0.14224)
		(layer "In4.Cu")
		(net "M_H_CS_N<2>")
	)
	(segment
		(start 110.868968 -21.082)
		(end 110.868968 -18.415)
		(width 0.14224)
		(layer "In4.Cu")
		(net "M_H_CS_N<2>")
	)
	(segment
		(start 102.705662 -49.664874)
		(end 102.705662 -33.667446)
		(width 0.14224)
		(layer "In4.Cu")
		(net "M_H_CS_N<2>")
	)
	(segment
		(start 102.705662 -33.667446)
		(end 109.167168 -27.20594)
		(width 0.14224)
		(layer "In4.Cu")
		(net "M_H_CS_N<2>")
	)
	(segment
		(start 110.970568 -22.479)
		(end 110.970568 -21.9456)
		(width 0.14224)
		(layer "In4.Cu")
		(net "M_H_CS_N<2>")
	)
	(segment
		(start 102.705662 -49.97577)
		(end 102.705662 -49.664874)
		(width 0.0889)
		(layer "In4.Cu")
		(net "M_H_CS_N<2>")
	)
	(segment
		(start 110.885732 -17.085564)
		(end 110.885732 -15.22222)
		(width 0.14224)
		(layer "In4.Cu")
		(net "M_H_CS_N<2>")
	)
	(segment
		(start 102.2985 -54.809644)
		(end 102.2985 -50.382932)
		(width 0.0889)
		(layer "In4.Cu")
		(net "M_H_CS_N<2>")
	)
	(segment
		(start 110.741968 -17.8562)
		(end 110.945168 -17.653)
		(width 0.14224)
		(layer "In4.Cu")
		(net "M_H_CS_N<2>")
	)
	(segment
		(start 109.167168 -27.20594)
		(end 109.167168 -25.95372)
		(width 0.14224)
		(layer "In4.Cu")
		(net "M_H_CS_N<2>")
	)
	(segment
		(start 109.167168 -25.95372)
		(end 110.919768 -24.20112)
		(width 0.14224)
		(layer "In4.Cu")
		(net "M_H_CS_N<2>")
	)
	(segment
		(start 111.71047 -12.600432)
		(end 111.712502 -12.5984)
		(width 0.14224)
		(layer "In4.Cu")
		(net "M_H_CS_N<2>")
	)
	(segment
		(start 110.741968 -18.288)
		(end 110.741968 -17.8562)
		(width 0.14224)
		(layer "In4.Cu")
		(net "M_H_CS_N<2>")
	)
	(segment
		(start 110.741968 -21.209)
		(end 110.868968 -21.082)
		(width 0.14224)
		(layer "In4.Cu")
		(net "M_H_CS_N<2>")
	)
	(segment
		(start 110.868968 -18.415)
		(end 110.741968 -18.288)
		(width 0.14224)
		(layer "In4.Cu")
		(net "M_H_CS_N<2>")
	)
	(segment
		(start 111.712502 -8.910066)
		(end 112.99952 -7.623048)
		(width 0.14224)
		(layer "In4.Cu")
		(net "M_H_CS_N<2>")
	)
	(segment
		(start 102.2985 -50.382932)
		(end 102.705662 -49.97577)
		(width 0.0889)
		(layer "In4.Cu")
		(net "M_H_CS_N<2>")
	)
	(segment
		(start 110.919768 -24.20112)
		(end 110.919768 -23.2156)
		(width 0.14224)
		(layer "In4.Cu")
		(net "M_H_CS_N<2>")
	)
	(segment
		(start 110.767368 -22.6822)
		(end 110.970568 -22.479)
		(width 0.14224)
		(layer "In4.Cu")
		(net "M_H_CS_N<2>")
	)
	(segment
		(start 110.741968 -21.717)
		(end 110.741968 -21.209)
		(width 0.14224)
		(layer "In4.Cu")
		(net "M_H_CS_N<2>")
	)
	(segment
		(start 98.655378 -56.58104)
		(end 98.083878 -56.58104)
		(width 0.1016)
		(layer "F.Cu")
		(net "M_H_CS_N<1>")
	)
	(segment
		(start 109.599476 -7.113778)
		(end 109.599476 -5.822442)
		(width 0.1651)
		(layer "F.Cu")
		(net "M_H_CS_N<1>")
	)
	(via
		(at 98.083878 -56.58104)
		(size 0.508)
		(drill 0.254)
		(layers "F.Cu" "B.Cu")
		(net "M_H_CS_N<1>")
	)
	(via
		(at 109.599476 -7.113778)
		(size 0.508)
		(drill 0.254)
		(layers "F.Cu" "B.Cu")
		(net "M_H_CS_N<1>")
	)
	(segment
		(start 107.604306 -17.132046)
		(end 107.465368 -16.993108)
		(width 0.14224)
		(layer "In4.Cu")
		(net "M_H_CS_N<1>")
	)
	(segment
		(start 108.310172 -14.115796)
		(end 108.310172 -13.633196)
		(width 0.14224)
		(layer "In4.Cu")
		(net "M_H_CS_N<1>")
	)
	(segment
		(start 107.617768 -23.372318)
		(end 107.362752 -23.117302)
		(width 0.14224)
		(layer "In4.Cu")
		(net "M_H_CS_N<1>")
	)
	(segment
		(start 100.759768 -51.968146)
		(end 100.759768 -51.136296)
		(width 0.0889)
		(layer "In4.Cu")
		(net "M_H_CS_N<1>")
	)
	(segment
		(start 101.070156 -49.63414)
		(end 101.070156 -32.427672)
		(width 0.14224)
		(layer "In4.Cu")
		(net "M_H_CS_N<1>")
	)
	(segment
		(start 101.070156 -50.825908)
		(end 101.070156 -49.63414)
		(width 0.0889)
		(layer "In4.Cu")
		(net "M_H_CS_N<1>")
	)
	(segment
		(start 107.465368 -14.9606)
		(end 108.310172 -14.115796)
		(width 0.14224)
		(layer "In4.Cu")
		(net "M_H_CS_N<1>")
	)
	(segment
		(start 98.413316 -55.820056)
		(end 98.430588 -55.790338)
		(width 0.0889)
		(layer "In4.Cu")
		(net "M_H_CS_N<1>")
	)
	(segment
		(start 100.138484 -52.589176)
		(end 100.759768 -51.968146)
		(width 0.0889)
		(layer "In4.Cu")
		(net "M_H_CS_N<1>")
	)
	(segment
		(start 107.604306 -18.026126)
		(end 107.604306 -17.132046)
		(width 0.14224)
		(layer "In4.Cu")
		(net "M_H_CS_N<1>")
	)
	(segment
		(start 107.362752 -22.61489)
		(end 107.520994 -22.456648)
		(width 0.14224)
		(layer "In4.Cu")
		(net "M_H_CS_N<1>")
	)
	(segment
		(start 100.141024 -53.819806)
		(end 100.147374 -53.809138)
		(width 0.0889)
		(layer "In4.Cu")
		(net "M_H_CS_N<1>")
	)
	(segment
		(start 107.357164 -21.740114)
		(end 107.357164 -19.412204)
		(width 0.14224)
		(layer "In4.Cu")
		(net "M_H_CS_N<1>")
	)
	(segment
		(start 99.775772 -54.99989)
		(end 99.81184 -54.99989)
		(width 0.0889)
		(layer "In4.Cu")
		(net "M_H_CS_N<1>")
	)
	(segment
		(start 105.872534 -27.625294)
		(end 105.872534 -25.773634)
		(width 0.14224)
		(layer "In4.Cu")
		(net "M_H_CS_N<1>")
	)
	(segment
		(start 109.599476 -7.619492)
		(end 109.599476 -7.113778)
		(width 0.14224)
		(layer "In4.Cu")
		(net "M_H_CS_N<1>")
	)
	(segment
		(start 105.872534 -25.773634)
		(end 107.617768 -24.0284)
		(width 0.14224)
		(layer "In4.Cu")
		(net "M_H_CS_N<1>")
	)
	(segment
		(start 107.617768 -24.0284)
		(end 107.617768 -23.372318)
		(width 0.14224)
		(layer "In4.Cu")
		(net "M_H_CS_N<1>")
	)
	(segment
		(start 100.147374 -53.809138)
		(end 100.1522 -53.800502)
		(width 0.0889)
		(layer "In4.Cu")
		(net "M_H_CS_N<1>")
	)
	(segment
		(start 107.357164 -19.412204)
		(end 107.461304 -19.308064)
		(width 0.14224)
		(layer "In4.Cu")
		(net "M_H_CS_N<1>")
	)
	(segment
		(start 108.310172 -13.633196)
		(end 108.339382 -13.603986)
		(width 0.14224)
		(layer "In4.Cu")
		(net "M_H_CS_N<1>")
	)
	(segment
		(start 107.465368 -16.993108)
		(end 107.465368 -14.9606)
		(width 0.14224)
		(layer "In4.Cu")
		(net "M_H_CS_N<1>")
	)
	(segment
		(start 107.461304 -19.308064)
		(end 107.461304 -18.169128)
		(width 0.14224)
		(layer "In4.Cu")
		(net "M_H_CS_N<1>")
	)
	(segment
		(start 107.520994 -22.456648)
		(end 107.520994 -21.903944)
		(width 0.14224)
		(layer "In4.Cu")
		(net "M_H_CS_N<1>")
	)
	(segment
		(start 108.339382 -13.603986)
		(end 108.339382 -8.879586)
		(width 0.14224)
		(layer "In4.Cu")
		(net "M_H_CS_N<1>")
	)
	(segment
		(start 107.461304 -18.169128)
		(end 107.604306 -18.026126)
		(width 0.14224)
		(layer "In4.Cu")
		(net "M_H_CS_N<1>")
	)
	(segment
		(start 98.924618 -55.494936)
		(end 98.942398 -55.494936)
		(width 0.0889)
		(layer "In4.Cu")
		(net "M_H_CS_N<1>")
	)
	(segment
		(start 107.520994 -21.903944)
		(end 107.357164 -21.740114)
		(width 0.14224)
		(layer "In4.Cu")
		(net "M_H_CS_N<1>")
	)
	(segment
		(start 100.759768 -51.136296)
		(end 101.070156 -50.825908)
		(width 0.0889)
		(layer "In4.Cu")
		(net "M_H_CS_N<1>")
	)
	(segment
		(start 107.362752 -23.117302)
		(end 107.362752 -22.61489)
		(width 0.14224)
		(layer "In4.Cu")
		(net "M_H_CS_N<1>")
	)
	(segment
		(start 101.070156 -32.427672)
		(end 105.872534 -27.625294)
		(width 0.14224)
		(layer "In4.Cu")
		(net "M_H_CS_N<1>")
	)
	(segment
		(start 108.339382 -8.879586)
		(end 109.599476 -7.619492)
		(width 0.14224)
		(layer "In4.Cu")
		(net "M_H_CS_N<1>")
	)
	(segment
		(start 98.083878 -56.58104)
		(end 98.413316 -55.820056)
		(width 0.0889)
		(layer "In4.Cu")
		(net "M_H_CS_N<1>")
	)
	(segment
		(start 99.285552 -55.300626)
		(end 99.288854 -55.294784)
		(width 0.0889)
		(layer "In4.Cu")
		(net "M_H_CS_N<1>")
	)
	(segment
		(start 100.048568 -53.040026)
		(end 100.048568 -52.8066)
		(width 0.0889)
		(layer "In4.Cu")
		(net "M_H_CS_N<1>")
	)
	(arc
		(start 100.1522 -53.800502)
		(mid 100.200955 -53.60415)
		(end 100.147374 -53.409088)
		(width 0.0889)
		(layer "In4.Cu")
		(net "M_H_CS_N<1>")
	)
	(arc
		(start 99.288854 -55.294784)
		(mid 99.494475 -55.084861)
		(end 99.775772 -54.99989)
		(width 0.0889)
		(layer "In4.Cu")
		(net "M_H_CS_N<1>")
	)
	(arc
		(start 98.430588 -55.790338)
		(mid 98.639196 -55.578406)
		(end 98.924618 -55.494936)
		(width 0.0889)
		(layer "In4.Cu")
		(net "M_H_CS_N<1>")
	)
	(arc
		(start 98.942398 -55.494936)
		(mid 99.139559 -55.442977)
		(end 99.285552 -55.300626)
		(width 0.0889)
		(layer "In4.Cu")
		(net "M_H_CS_N<1>")
	)
	(arc
		(start 100.147374 -54.399688)
		(mid 100.068152 -54.11057)
		(end 100.141024 -53.819806)
		(width 0.0889)
		(layer "In4.Cu")
		(net "M_H_CS_N<1>")
	)
	(arc
		(start 100.048568 -52.8066)
		(mid 100.07188 -52.688932)
		(end 100.138484 -52.589176)
		(width 0.0889)
		(layer "In4.Cu")
		(net "M_H_CS_N<1>")
	)
	(arc
		(start 100.147374 -53.409088)
		(mid 100.073744 -53.231048)
		(end 100.048568 -53.040026)
		(width 0.0889)
		(layer "In4.Cu")
		(net "M_H_CS_N<1>")
	)
	(arc
		(start 99.81184 -54.99989)
		(mid 100.150009 -54.795092)
		(end 100.147374 -54.399688)
		(width 0.0889)
		(layer "In4.Cu")
		(net "M_H_CS_N<1>")
	)
	(segment
		(start 97.796858 -54.104286)
		(end 97.225358 -54.104286)
		(width 0.1016)
		(layer "F.Cu")
		(net "M_H_CS_N<0>")
	)
	(segment
		(start 105.349548 -5.822442)
		(end 105.349548 -7.117334)
		(width 0.1651)
		(layer "F.Cu")
		(net "M_H_CS_N<0>")
	)
	(via
		(at 105.349548 -7.117334)
		(size 0.4572)
		(drill 0.2032)
		(layers "F.Cu" "B.Cu")
		(net "M_H_CS_N<0>")
	)
	(via
		(at 97.225358 -54.104286)
		(size 0.508)
		(drill 0.254)
		(layers "F.Cu" "B.Cu")
		(net "M_H_CS_N<0>")
	)
	(segment
		(start 105.564686 -8.400796)
		(end 105.349548 -8.185658)
		(width 0.14224)
		(layer "In4.Cu")
		(net "M_H_CS_N<0>")
	)
	(segment
		(start 99.614228 -50.293524)
		(end 99.386136 -50.065432)
		(width 0.0889)
		(layer "In4.Cu")
		(net "M_H_CS_N<0>")
	)
	(segment
		(start 97.227644 -54.102)
		(end 98.14052 -54.102)
		(width 0.0889)
		(layer "In4.Cu")
		(net "M_H_CS_N<0>")
	)
	(segment
		(start 104.874568 -23.2156)
		(end 104.95661 -23.133558)
		(width 0.14224)
		(layer "In4.Cu")
		(net "M_H_CS_N<0>")
	)
	(segment
		(start 98.595688 -52.913788)
		(end 98.727768 -52.705508)
		(width 0.0889)
		(layer "In4.Cu")
		(net "M_H_CS_N<0>")
	)
	(segment
		(start 105.349548 -8.185658)
		(end 105.349548 -7.117334)
		(width 0.14224)
		(layer "In4.Cu")
		(net "M_H_CS_N<0>")
	)
	(segment
		(start 105.761028 -13.041376)
		(end 106.641646 -12.160758)
		(width 0.14224)
		(layer "In4.Cu")
		(net "M_H_CS_N<0>")
	)
	(segment
		(start 106.641646 -9.39673)
		(end 106.641646 -8.383524)
		(width 0.14224)
		(layer "In4.Cu")
		(net "M_H_CS_N<0>")
	)
	(segment
		(start 104.941624 -18.356326)
		(end 104.941624 -16.450056)
		(width 0.14224)
		(layer "In4.Cu")
		(net "M_H_CS_N<0>")
	)
	(segment
		(start 99.574604 -49.150016)
		(end 99.574604 -48.906938)
		(width 0.0889)
		(layer "In4.Cu")
		(net "M_H_CS_N<0>")
	)
	(segment
		(start 98.727768 -52.07)
		(end 99.614228 -51.18354)
		(width 0.0889)
		(layer "In4.Cu")
		(net "M_H_CS_N<0>")
	)
	(segment
		(start 99.574604 -48.906938)
		(end 99.574604 -31.767018)
		(width 0.14224)
		(layer "In4.Cu")
		(net "M_H_CS_N<0>")
	)
	(segment
		(start 104.892094 -21.864066)
		(end 104.95661 -21.79955)
		(width 0.14224)
		(layer "In4.Cu")
		(net "M_H_CS_N<0>")
	)
	(segment
		(start 106.641646 -8.383524)
		(end 106.372152 -8.11403)
		(width 0.14224)
		(layer "In4.Cu")
		(net "M_H_CS_N<0>")
	)
	(segment
		(start 105.761028 -14.30274)
		(end 105.761028 -13.041376)
		(width 0.14224)
		(layer "In4.Cu")
		(net "M_H_CS_N<0>")
	)
	(segment
		(start 104.95661 -21.79955)
		(end 104.95661 -21.291296)
		(width 0.14224)
		(layer "In4.Cu")
		(net "M_H_CS_N<0>")
	)
	(segment
		(start 99.574604 -31.767018)
		(end 103.172768 -28.168854)
		(width 0.14224)
		(layer "In4.Cu")
		(net "M_H_CS_N<0>")
	)
	(segment
		(start 104.95661 -23.133558)
		(end 104.95661 -22.561042)
		(width 0.14224)
		(layer "In4.Cu")
		(net "M_H_CS_N<0>")
	)
	(segment
		(start 104.908604 -21.24329)
		(end 104.908604 -18.389346)
		(width 0.14224)
		(layer "In4.Cu")
		(net "M_H_CS_N<0>")
	)
	(segment
		(start 104.8766 -15.187168)
		(end 105.761028 -14.30274)
		(width 0.14224)
		(layer "In4.Cu")
		(net "M_H_CS_N<0>")
	)
	(segment
		(start 104.908604 -18.389346)
		(end 104.941624 -18.356326)
		(width 0.14224)
		(layer "In4.Cu")
		(net "M_H_CS_N<0>")
	)
	(segment
		(start 98.590862 -52.922424)
		(end 98.595688 -52.913788)
		(width 0.0889)
		(layer "In4.Cu")
		(net "M_H_CS_N<0>")
	)
	(segment
		(start 99.386136 -49.338484)
		(end 99.574604 -49.150016)
		(width 0.0889)
		(layer "In4.Cu")
		(net "M_H_CS_N<0>")
	)
	(segment
		(start 99.614228 -51.18354)
		(end 99.614228 -50.293524)
		(width 0.0889)
		(layer "In4.Cu")
		(net "M_H_CS_N<0>")
	)
	(segment
		(start 106.372152 -8.11403)
		(end 106.121708 -8.11403)
		(width 0.14224)
		(layer "In4.Cu")
		(net "M_H_CS_N<0>")
	)
	(segment
		(start 97.225358 -54.104286)
		(end 97.227644 -54.102)
		(width 0.0889)
		(layer "In4.Cu")
		(net "M_H_CS_N<0>")
	)
	(segment
		(start 104.892094 -22.496526)
		(end 104.892094 -21.864066)
		(width 0.14224)
		(layer "In4.Cu")
		(net "M_H_CS_N<0>")
	)
	(segment
		(start 106.641646 -11.442954)
		(end 106.80065 -11.28395)
		(width 0.14224)
		(layer "In4.Cu")
		(net "M_H_CS_N<0>")
	)
	(segment
		(start 106.641646 -12.160758)
		(end 106.641646 -11.442954)
		(width 0.14224)
		(layer "In4.Cu")
		(net "M_H_CS_N<0>")
	)
	(segment
		(start 98.727768 -52.705508)
		(end 98.727768 -52.07)
		(width 0.0889)
		(layer "In4.Cu")
		(net "M_H_CS_N<0>")
	)
	(segment
		(start 104.874568 -24.3332)
		(end 104.874568 -23.2156)
		(width 0.14224)
		(layer "In4.Cu")
		(net "M_H_CS_N<0>")
	)
	(segment
		(start 104.95661 -22.561042)
		(end 104.892094 -22.496526)
		(width 0.14224)
		(layer "In4.Cu")
		(net "M_H_CS_N<0>")
	)
	(segment
		(start 106.80065 -9.555734)
		(end 106.641646 -9.39673)
		(width 0.14224)
		(layer "In4.Cu")
		(net "M_H_CS_N<0>")
	)
	(segment
		(start 103.172768 -28.168854)
		(end 103.172768 -26.035)
		(width 0.14224)
		(layer "In4.Cu")
		(net "M_H_CS_N<0>")
	)
	(segment
		(start 106.80065 -11.28395)
		(end 106.80065 -9.555734)
		(width 0.14224)
		(layer "In4.Cu")
		(net "M_H_CS_N<0>")
	)
	(segment
		(start 105.834942 -8.400796)
		(end 105.564686 -8.400796)
		(width 0.14224)
		(layer "In4.Cu")
		(net "M_H_CS_N<0>")
	)
	(segment
		(start 99.386136 -50.065432)
		(end 99.386136 -49.338484)
		(width 0.0889)
		(layer "In4.Cu")
		(net "M_H_CS_N<0>")
	)
	(segment
		(start 106.121708 -8.11403)
		(end 105.834942 -8.400796)
		(width 0.14224)
		(layer "In4.Cu")
		(net "M_H_CS_N<0>")
	)
	(segment
		(start 104.941624 -16.450056)
		(end 104.8766 -16.385032)
		(width 0.14224)
		(layer "In4.Cu")
		(net "M_H_CS_N<0>")
	)
	(segment
		(start 104.95661 -21.291296)
		(end 104.908604 -21.24329)
		(width 0.14224)
		(layer "In4.Cu")
		(net "M_H_CS_N<0>")
	)
	(segment
		(start 104.8766 -16.385032)
		(end 104.8766 -15.187168)
		(width 0.14224)
		(layer "In4.Cu")
		(net "M_H_CS_N<0>")
	)
	(segment
		(start 103.172768 -26.035)
		(end 104.874568 -24.3332)
		(width 0.14224)
		(layer "In4.Cu")
		(net "M_H_CS_N<0>")
	)
	(arc
		(start 98.595688 -53.313838)
		(mid 98.542218 -53.118775)
		(end 98.590862 -52.922424)
		(width 0.0889)
		(layer "In4.Cu")
		(net "M_H_CS_N<0>")
	)
	(arc
		(start 98.14052 -54.102)
		(mid 98.595605 -53.839295)
		(end 98.595688 -53.313838)
		(width 0.0889)
		(layer "In4.Cu")
		(net "M_H_CS_N<0>")
	)
	(segment
		(start 92.645738 -57.076086)
		(end 92.074238 -57.076086)
		(width 0.1016)
		(layer "F.Cu")
		(net "M_H_CLK_DP<3>")
	)
	(via
		(at 92.074238 -57.076086)
		(size 0.508)
		(drill 0.254)
		(layers "F.Cu" "B.Cu")
		(net "M_H_CLK_DP<3>")
	)
	(via
		(at 91.825572 -11.916156)
		(size 0.4572)
		(drill 0.2032)
		(layers "F.Cu" "B.Cu")
		(net "M_H_CLK_DP<3>")
	)
	(segment
		(start 91.749372 -10.623042)
		(end 91.749372 -11.839956)
		(width 0.1651)
		(layer "B.Cu")
		(net "M_H_CLK_DP<3>")
	)
	(segment
		(start 91.749372 -11.839956)
		(end 91.825572 -11.916156)
		(width 0.1651)
		(layer "B.Cu")
		(net "M_H_CLK_DP<3>")
	)
	(segment
		(start 93.457014 -13.32484)
		(end 92.951554 -13.32484)
		(width 0.14224)
		(layer "In4.Cu")
		(net "M_H_CLK_DP<3>")
	)
	(segment
		(start 94.846648 -17.69872)
		(end 94.846648 -14.714474)
		(width 0.14224)
		(layer "In4.Cu")
		(net "M_H_CLK_DP<3>")
	)
	(segment
		(start 94.890844 -47.936404)
		(end 94.890844 -26.737564)
		(width 0.14224)
		(layer "In4.Cu")
		(net "M_H_CLK_DP<3>")
	)
	(segment
		(start 93.355668 -52.496212)
		(end 93.355668 -51.101752)
		(width 0.0889)
		(layer "In4.Cu")
		(net "M_H_CLK_DP<3>")
	)
	(segment
		(start 94.828868 -49.628552)
		(end 94.828868 -48.68926)
		(width 0.0889)
		(layer "In4.Cu")
		(net "M_H_CLK_DP<3>")
	)
	(segment
		(start 94.926912 -48.591216)
		(end 94.926912 -47.99457)
		(width 0.0889)
		(layer "In4.Cu")
		(net "M_H_CLK_DP<3>")
	)
	(segment
		(start 93.194632 -54.164484)
		(end 93.194632 -52.657248)
		(width 0.0889)
		(layer "In4.Cu")
		(net "M_H_CLK_DP<3>")
	)
	(segment
		(start 94.828868 -48.68926)
		(end 94.926912 -48.591216)
		(width 0.0889)
		(layer "In4.Cu")
		(net "M_H_CLK_DP<3>")
	)
	(segment
		(start 94.846648 -14.714474)
		(end 93.457014 -13.32484)
		(width 0.14224)
		(layer "In4.Cu")
		(net "M_H_CLK_DP<3>")
	)
	(segment
		(start 92.074238 -57.076086)
		(end 92.187522 -56.963056)
		(width 0.0889)
		(layer "In4.Cu")
		(net "M_H_CLK_DP<3>")
	)
	(segment
		(start 92.020644 -12.39393)
		(end 92.020644 -12.111228)
		(width 0.14224)
		(layer "In4.Cu")
		(net "M_H_CLK_DP<3>")
	)
	(segment
		(start 93.355668 -51.101752)
		(end 94.828868 -49.628552)
		(width 0.0889)
		(layer "In4.Cu")
		(net "M_H_CLK_DP<3>")
	)
	(segment
		(start 94.890844 -26.737564)
		(end 94.287848 -26.134568)
		(width 0.14224)
		(layer "In4.Cu")
		(net "M_H_CLK_DP<3>")
	)
	(segment
		(start 94.890844 -47.958502)
		(end 94.890844 -47.936404)
		(width 0.0889)
		(layer "In4.Cu")
		(net "M_H_CLK_DP<3>")
	)
	(segment
		(start 92.951554 -13.32484)
		(end 92.020644 -12.39393)
		(width 0.14224)
		(layer "In4.Cu")
		(net "M_H_CLK_DP<3>")
	)
	(segment
		(start 92.020644 -12.111228)
		(end 91.825572 -11.916156)
		(width 0.14224)
		(layer "In4.Cu")
		(net "M_H_CLK_DP<3>")
	)
	(segment
		(start 93.194632 -52.657248)
		(end 93.355668 -52.496212)
		(width 0.0889)
		(layer "In4.Cu")
		(net "M_H_CLK_DP<3>")
	)
	(segment
		(start 94.926912 -47.99457)
		(end 94.890844 -47.958502)
		(width 0.0889)
		(layer "In4.Cu")
		(net "M_H_CLK_DP<3>")
	)
	(segment
		(start 92.911168 -55.99049)
		(end 92.943934 -55.99049)
		(width 0.0889)
		(layer "In4.Cu")
		(net "M_H_CLK_DP<3>")
	)
	(segment
		(start 93.194886 -54.25313)
		(end 93.194632 -54.164484)
		(width 0.0889)
		(layer "In4.Cu")
		(net "M_H_CLK_DP<3>")
	)
	(segment
		(start 93.273118 -54.810406)
		(end 93.279468 -54.799738)
		(width 0.0889)
		(layer "In4.Cu")
		(net "M_H_CLK_DP<3>")
	)
	(segment
		(start 94.287848 -18.25752)
		(end 94.846648 -17.69872)
		(width 0.14224)
		(layer "In4.Cu")
		(net "M_H_CLK_DP<3>")
	)
	(segment
		(start 93.279468 -54.399942)
		(end 93.194886 -54.25313)
		(width 0.0889)
		(layer "In4.Cu")
		(net "M_H_CLK_DP<3>")
	)
	(segment
		(start 94.287848 -26.134568)
		(end 94.287848 -18.25752)
		(width 0.14224)
		(layer "In4.Cu")
		(net "M_H_CLK_DP<3>")
	)
	(segment
		(start 93.279468 -54.799738)
		(end 93.284294 -54.791102)
		(width 0.0889)
		(layer "In4.Cu")
		(net "M_H_CLK_DP<3>")
	)
	(arc
		(start 92.187522 -56.963056)
		(mid 92.30167 -56.792082)
		(end 92.3417 -56.590438)
		(width 0.0889)
		(layer "In4.Cu")
		(net "M_H_CLK_DP<3>")
	)
	(arc
		(start 92.3417 -56.590438)
		(mid 92.503949 -56.174149)
		(end 92.911168 -55.99049)
		(width 0.0889)
		(layer "In4.Cu")
		(net "M_H_CLK_DP<3>")
	)
	(arc
		(start 92.943934 -55.99049)
		(mid 93.282103 -55.785692)
		(end 93.279468 -55.390288)
		(width 0.0889)
		(layer "In4.Cu")
		(net "M_H_CLK_DP<3>")
	)
	(arc
		(start 93.284294 -54.791102)
		(mid 93.332926 -54.594894)
		(end 93.279468 -54.399942)
		(width 0.0889)
		(layer "In4.Cu")
		(net "M_H_CLK_DP<3>")
	)
	(arc
		(start 93.279468 -55.390288)
		(mid 93.200246 -55.10117)
		(end 93.273118 -54.810406)
		(width 0.0889)
		(layer "In4.Cu")
		(net "M_H_CLK_DP<3>")
	)
	(segment
		(start 94.362778 -57.076086)
		(end 93.791278 -57.076086)
		(width 0.1016)
		(layer "F.Cu")
		(net "M_H_CLK_DP<1>")
	)
	(segment
		(start 91.749372 -10.422382)
		(end 91.749372 -9.129268)
		(width 0.1651)
		(layer "F.Cu")
		(net "M_H_CLK_DP<1>")
	)
	(via
		(at 91.749372 -9.129268)
		(size 0.508)
		(drill 0.254)
		(layers "F.Cu" "B.Cu")
		(net "M_H_CLK_DP<1>")
	)
	(via
		(at 93.791278 -57.076086)
		(size 0.508)
		(drill 0.254)
		(layers "F.Cu" "B.Cu")
		(net "M_H_CLK_DP<1>")
	)
	(segment
		(start 95.837248 -12.748768)
		(end 94.687136 -11.598656)
		(width 0.14224)
		(layer "In4.Cu")
		(net "M_H_CLK_DP<1>")
	)
	(segment
		(start 93.680534 -10.93089)
		(end 93.33611 -11.275314)
		(width 0.14224)
		(layer "In4.Cu")
		(net "M_H_CLK_DP<1>")
	)
	(segment
		(start 93.807534 -10.55878)
		(end 93.680534 -10.68578)
		(width 0.14224)
		(layer "In4.Cu")
		(net "M_H_CLK_DP<1>")
	)
	(segment
		(start 94.058994 -53.595524)
		(end 94.058994 -51.257962)
		(width 0.0889)
		(layer "In4.Cu")
		(net "M_H_CLK_DP<1>")
	)
	(segment
		(start 94.137988 -54.304692)
		(end 94.138242 -54.304692)
		(width 0.0889)
		(layer "In4.Cu")
		(net "M_H_CLK_DP<1>")
	)
	(segment
		(start 94.687136 -10.931906)
		(end 94.31401 -10.55878)
		(width 0.14224)
		(layer "In4.Cu")
		(net "M_H_CLK_DP<1>")
	)
	(segment
		(start 95.837248 -25.758902)
		(end 95.837248 -12.748768)
		(width 0.14224)
		(layer "In4.Cu")
		(net "M_H_CLK_DP<1>")
	)
	(segment
		(start 95.476568 -49.840388)
		(end 95.476568 -48.904906)
		(width 0.0889)
		(layer "In4.Cu")
		(net "M_H_CLK_DP<1>")
	)
	(segment
		(start 92.481654 -11.275314)
		(end 92.020644 -10.814304)
		(width 0.14224)
		(layer "In4.Cu")
		(net "M_H_CLK_DP<1>")
	)
	(segment
		(start 94.687136 -11.598656)
		(end 94.687136 -10.931906)
		(width 0.14224)
		(layer "In4.Cu")
		(net "M_H_CLK_DP<1>")
	)
	(segment
		(start 95.729044 -47.987204)
		(end 95.729044 -25.867106)
		(width 0.14224)
		(layer "In4.Cu")
		(net "M_H_CLK_DP<1>")
	)
	(segment
		(start 93.33611 -11.275314)
		(end 92.481654 -11.275314)
		(width 0.14224)
		(layer "In4.Cu")
		(net "M_H_CLK_DP<1>")
	)
	(segment
		(start 92.020644 -9.40054)
		(end 91.749372 -9.129268)
		(width 0.14224)
		(layer "In4.Cu")
		(net "M_H_CLK_DP<1>")
	)
	(segment
		(start 92.020644 -10.814304)
		(end 92.020644 -9.40054)
		(width 0.14224)
		(layer "In4.Cu")
		(net "M_H_CLK_DP<1>")
	)
	(segment
		(start 95.755968 -48.625506)
		(end 95.755968 -48.036226)
		(width 0.0889)
		(layer "In4.Cu")
		(net "M_H_CLK_DP<1>")
	)
	(segment
		(start 93.680534 -10.68578)
		(end 93.680534 -10.93089)
		(width 0.14224)
		(layer "In4.Cu")
		(net "M_H_CLK_DP<1>")
	)
	(segment
		(start 93.791278 -57.076086)
		(end 93.905578 -56.961786)
		(width 0.0889)
		(layer "In4.Cu")
		(net "M_H_CLK_DP<1>")
	)
	(segment
		(start 94.31401 -10.55878)
		(end 93.807534 -10.55878)
		(width 0.14224)
		(layer "In4.Cu")
		(net "M_H_CLK_DP<1>")
	)
	(segment
		(start 95.729044 -48.009302)
		(end 95.729044 -47.987204)
		(width 0.0889)
		(layer "In4.Cu")
		(net "M_H_CLK_DP<1>")
	)
	(segment
		(start 94.058994 -51.257962)
		(end 95.476568 -49.840388)
		(width 0.0889)
		(layer "In4.Cu")
		(net "M_H_CLK_DP<1>")
	)
	(segment
		(start 95.476568 -48.904906)
		(end 95.755968 -48.625506)
		(width 0.0889)
		(layer "In4.Cu")
		(net "M_H_CLK_DP<1>")
	)
	(segment
		(start 95.755968 -48.036226)
		(end 95.729044 -48.009302)
		(width 0.0889)
		(layer "In4.Cu")
		(net "M_H_CLK_DP<1>")
	)
	(segment
		(start 95.729044 -25.867106)
		(end 95.837248 -25.758902)
		(width 0.14224)
		(layer "In4.Cu")
		(net "M_H_CLK_DP<1>")
	)
	(arc
		(start 94.137988 -56.285892)
		(mid 94.191487 -56.085994)
		(end 94.137988 -55.886096)
		(width 0.0889)
		(layer "In4.Cu")
		(net "M_H_CLK_DP<1>")
	)
	(arc
		(start 94.05874 -56.591962)
		(mid 94.07749 -56.433519)
		(end 94.137988 -56.285892)
		(width 0.0889)
		(layer "In4.Cu")
		(net "M_H_CLK_DP<1>")
	)
	(arc
		(start 94.143068 -53.913532)
		(mid 94.078472 -53.760494)
		(end 94.058994 -53.595524)
		(width 0.0889)
		(layer "In4.Cu")
		(net "M_H_CLK_DP<1>")
	)
	(arc
		(start 94.137988 -55.886096)
		(mid 94.058857 -55.590694)
		(end 94.137988 -55.295292)
		(width 0.0889)
		(layer "In4.Cu")
		(net "M_H_CLK_DP<1>")
	)
	(arc
		(start 93.905578 -56.961786)
		(mid 94.018952 -56.792109)
		(end 94.05874 -56.591962)
		(width 0.0889)
		(layer "In4.Cu")
		(net "M_H_CLK_DP<1>")
	)
	(arc
		(start 94.137988 -55.295292)
		(mid 94.191487 -55.095394)
		(end 94.137988 -54.895496)
		(width 0.0889)
		(layer "In4.Cu")
		(net "M_H_CLK_DP<1>")
	)
	(arc
		(start 94.137988 -54.895496)
		(mid 94.058857 -54.600094)
		(end 94.137988 -54.304692)
		(width 0.0889)
		(layer "In4.Cu")
		(net "M_H_CLK_DP<1>")
	)
	(arc
		(start 94.138242 -54.304692)
		(mid 94.191676 -54.109741)
		(end 94.143068 -53.913532)
		(width 0.0889)
		(layer "In4.Cu")
		(net "M_H_CLK_DP<1>")
	)
	(segment
		(start 92.645738 -55.094886)
		(end 92.074238 -55.094886)
		(width 0.1016)
		(layer "F.Cu")
		(net "M_H_CLK_DP<2>")
	)
	(via
		(at 92.074238 -55.094886)
		(size 0.508)
		(drill 0.254)
		(layers "F.Cu" "B.Cu")
		(net "M_H_CLK_DP<2>")
	)
	(via
		(at 91.749372 -13.929868)
		(size 0.508)
		(drill 0.254)
		(layers "F.Cu" "B.Cu")
		(net "M_H_CLK_DP<2>")
	)
	(segment
		(start 91.749372 -15.222982)
		(end 91.749372 -13.929868)
		(width 0.1651)
		(layer "B.Cu")
		(net "M_H_CLK_DP<2>")
	)
	(segment
		(start 93.128592 -19.890994)
		(end 92.232988 -19.890994)
		(width 0.14224)
		(layer "In4.Cu")
		(net "M_H_CLK_DP<2>")
	)
	(segment
		(start 94.089474 -48.512476)
		(end 94.089474 -48.046132)
		(width 0.0889)
		(layer "In4.Cu")
		(net "M_H_CLK_DP<2>")
	)
	(segment
		(start 92.425774 -54.903624)
		(end 92.420948 -54.894988)
		(width 0.0889)
		(layer "In4.Cu")
		(net "M_H_CLK_DP<2>")
	)
	(segment
		(start 93.373194 -26.057098)
		(end 91.35618 -24.040084)
		(width 0.14224)
		(layer "In4.Cu")
		(net "M_H_CLK_DP<2>")
	)
	(segment
		(start 92.557092 -54.068726)
		(end 92.557092 -52.1589)
		(width 0.0889)
		(layer "In4.Cu")
		(net "M_H_CLK_DP<2>")
	)
	(segment
		(start 94.052644 -48.009302)
		(end 94.052644 -47.987204)
		(width 0.0889)
		(layer "In4.Cu")
		(net "M_H_CLK_DP<2>")
	)
	(segment
		(start 91.920568 -19.578574)
		(end 91.920568 -18.220944)
		(width 0.14224)
		(layer "In4.Cu")
		(net "M_H_CLK_DP<2>")
	)
	(segment
		(start 91.35618 -24.040084)
		(end 91.35618 -23.211536)
		(width 0.14224)
		(layer "In4.Cu")
		(net "M_H_CLK_DP<2>")
	)
	(segment
		(start 91.920568 -20.866354)
		(end 92.232988 -20.553934)
		(width 0.14224)
		(layer "In4.Cu")
		(net "M_H_CLK_DP<2>")
	)
	(segment
		(start 91.336368 -21.801074)
		(end 91.920568 -21.216874)
		(width 0.14224)
		(layer "In4.Cu")
		(net "M_H_CLK_DP<2>")
	)
	(segment
		(start 92.557092 -52.1589)
		(end 92.331032 -51.76774)
		(width 0.0889)
		(layer "In4.Cu")
		(net "M_H_CLK_DP<2>")
	)
	(segment
		(start 91.920568 -18.220944)
		(end 92.539312 -17.6022)
		(width 0.14224)
		(layer "In4.Cu")
		(net "M_H_CLK_DP<2>")
	)
	(segment
		(start 92.420948 -54.894988)
		(end 92.414598 -54.88432)
		(width 0.0889)
		(layer "In4.Cu")
		(net "M_H_CLK_DP<2>")
	)
	(segment
		(start 94.052644 -47.987204)
		(end 94.052644 -27.143964)
		(width 0.14224)
		(layer "In4.Cu")
		(net "M_H_CLK_DP<2>")
	)
	(segment
		(start 92.672154 -15.574264)
		(end 92.046044 -14.948154)
		(width 0.14224)
		(layer "In4.Cu")
		(net "M_H_CLK_DP<2>")
	)
	(segment
		(start 92.331032 -51.194716)
		(end 94.23273 -49.293018)
		(width 0.0889)
		(layer "In4.Cu")
		(net "M_H_CLK_DP<2>")
	)
	(segment
		(start 91.336368 -23.191724)
		(end 91.336368 -21.801074)
		(width 0.14224)
		(layer "In4.Cu")
		(net "M_H_CLK_DP<2>")
	)
	(segment
		(start 93.171772 -15.574264)
		(end 92.672154 -15.574264)
		(width 0.14224)
		(layer "In4.Cu")
		(net "M_H_CLK_DP<2>")
	)
	(segment
		(start 92.074238 -55.094886)
		(end 92.367354 -55.26405)
		(width 0.0889)
		(layer "In4.Cu")
		(net "M_H_CLK_DP<2>")
	)
	(segment
		(start 91.920568 -21.216874)
		(end 91.920568 -20.866354)
		(width 0.14224)
		(layer "In4.Cu")
		(net "M_H_CLK_DP<2>")
	)
	(segment
		(start 93.373194 -26.464514)
		(end 93.373194 -26.057098)
		(width 0.14224)
		(layer "In4.Cu")
		(net "M_H_CLK_DP<2>")
	)
	(segment
		(start 93.672152 -16.074644)
		(end 93.171772 -15.574264)
		(width 0.14224)
		(layer "In4.Cu")
		(net "M_H_CLK_DP<2>")
	)
	(segment
		(start 92.232988 -19.890994)
		(end 91.920568 -19.578574)
		(width 0.14224)
		(layer "In4.Cu")
		(net "M_H_CLK_DP<2>")
	)
	(segment
		(start 93.11386 -20.553934)
		(end 93.276166 -20.391628)
		(width 0.14224)
		(layer "In4.Cu")
		(net "M_H_CLK_DP<2>")
	)
	(segment
		(start 94.23273 -49.293018)
		(end 94.23273 -48.655732)
		(width 0.0889)
		(layer "In4.Cu")
		(net "M_H_CLK_DP<2>")
	)
	(segment
		(start 92.331032 -51.76774)
		(end 92.331032 -51.194716)
		(width 0.0889)
		(layer "In4.Cu")
		(net "M_H_CLK_DP<2>")
	)
	(segment
		(start 93.276166 -20.391628)
		(end 93.276166 -20.038568)
		(width 0.14224)
		(layer "In4.Cu")
		(net "M_H_CLK_DP<2>")
	)
	(segment
		(start 94.089474 -48.046132)
		(end 94.052644 -48.009302)
		(width 0.0889)
		(layer "In4.Cu")
		(net "M_H_CLK_DP<2>")
	)
	(segment
		(start 93.672152 -17.156176)
		(end 93.672152 -16.074644)
		(width 0.14224)
		(layer "In4.Cu")
		(net "M_H_CLK_DP<2>")
	)
	(segment
		(start 92.420948 -54.304438)
		(end 92.557092 -54.068726)
		(width 0.0889)
		(layer "In4.Cu")
		(net "M_H_CLK_DP<2>")
	)
	(segment
		(start 92.367354 -55.26405)
		(end 92.446094 -55.242714)
		(width 0.0889)
		(layer "In4.Cu")
		(net "M_H_CLK_DP<2>")
	)
	(segment
		(start 91.35618 -23.211536)
		(end 91.336368 -23.191724)
		(width 0.14224)
		(layer "In4.Cu")
		(net "M_H_CLK_DP<2>")
	)
	(segment
		(start 92.046044 -14.22654)
		(end 91.749372 -13.929868)
		(width 0.14224)
		(layer "In4.Cu")
		(net "M_H_CLK_DP<2>")
	)
	(segment
		(start 93.276166 -20.038568)
		(end 93.128592 -19.890994)
		(width 0.14224)
		(layer "In4.Cu")
		(net "M_H_CLK_DP<2>")
	)
	(segment
		(start 94.23273 -48.655732)
		(end 94.089474 -48.512476)
		(width 0.0889)
		(layer "In4.Cu")
		(net "M_H_CLK_DP<2>")
	)
	(segment
		(start 93.226128 -17.6022)
		(end 93.672152 -17.156176)
		(width 0.14224)
		(layer "In4.Cu")
		(net "M_H_CLK_DP<2>")
	)
	(segment
		(start 92.539312 -17.6022)
		(end 93.226128 -17.6022)
		(width 0.14224)
		(layer "In4.Cu")
		(net "M_H_CLK_DP<2>")
	)
	(segment
		(start 94.052644 -27.143964)
		(end 93.373194 -26.464514)
		(width 0.14224)
		(layer "In4.Cu")
		(net "M_H_CLK_DP<2>")
	)
	(segment
		(start 92.046044 -14.948154)
		(end 92.046044 -14.22654)
		(width 0.14224)
		(layer "In4.Cu")
		(net "M_H_CLK_DP<2>")
	)
	(segment
		(start 92.232988 -20.553934)
		(end 93.11386 -20.553934)
		(width 0.14224)
		(layer "In4.Cu")
		(net "M_H_CLK_DP<2>")
	)
	(arc
		(start 92.414598 -54.88432)
		(mid 92.3418 -54.593557)
		(end 92.420948 -54.304438)
		(width 0.0889)
		(layer "In4.Cu")
		(net "M_H_CLK_DP<2>")
	)
	(arc
		(start 92.446094 -55.242714)
		(mid 92.467319 -55.169513)
		(end 92.474288 -55.093616)
		(width 0.0889)
		(layer "In4.Cu")
		(net "M_H_CLK_DP<2>")
	)
	(arc
		(start 92.474288 -55.093616)
		(mid 92.461847 -54.995603)
		(end 92.425774 -54.903624)
		(width 0.0889)
		(layer "In4.Cu")
		(net "M_H_CLK_DP<2>")
	)
	(segment
		(start 95.221298 -55.59044)
		(end 94.649798 -55.59044)
		(width 0.1016)
		(layer "F.Cu")
		(net "M_H_CLK_DP<0>")
	)
	(segment
		(start 91.749372 -5.822442)
		(end 91.749372 -7.115556)
		(width 0.1651)
		(layer "F.Cu")
		(net "M_H_CLK_DP<0>")
	)
	(via
		(at 94.649798 -55.59044)
		(size 0.508)
		(drill 0.254)
		(layers "F.Cu" "B.Cu")
		(net "M_H_CLK_DP<0>")
	)
	(via
		(at 91.749372 -7.115556)
		(size 0.4572)
		(drill 0.2032)
		(layers "F.Cu" "B.Cu")
		(net "M_H_CLK_DP<0>")
	)
	(segment
		(start 96.515682 -48.598074)
		(end 96.474788 -48.55718)
		(width 0.0889)
		(layer "In4.Cu")
		(net "M_H_CLK_DP<0>")
	)
	(segment
		(start 96.675448 -26.234644)
		(end 96.675448 -20.41652)
		(width 0.14224)
		(layer "In4.Cu")
		(net "M_H_CLK_DP<0>")
	)
	(segment
		(start 96.675448 -20.41652)
		(end 97.213928 -19.87804)
		(width 0.14224)
		(layer "In4.Cu")
		(net "M_H_CLK_DP<0>")
	)
	(segment
		(start 97.213928 -19.87804)
		(end 97.213928 -13.80236)
		(width 0.14224)
		(layer "In4.Cu")
		(net "M_H_CLK_DP<0>")
	)
	(segment
		(start 96.515682 -49.75098)
		(end 96.515682 -48.598074)
		(width 0.0889)
		(layer "In4.Cu")
		(net "M_H_CLK_DP<0>")
	)
	(segment
		(start 93.976444 -8.325866)
		(end 92.492068 -8.325866)
		(width 0.14224)
		(layer "In4.Cu")
		(net "M_H_CLK_DP<0>")
	)
	(segment
		(start 94.906592 -51.36007)
		(end 96.515682 -49.75098)
		(width 0.0889)
		(layer "In4.Cu")
		(net "M_H_CLK_DP<0>")
	)
	(segment
		(start 94.649798 -55.59044)
		(end 94.761812 -55.47868)
		(width 0.0889)
		(layer "In4.Cu")
		(net "M_H_CLK_DP<0>")
	)
	(segment
		(start 94.996508 -54.799738)
		(end 95.001334 -54.791102)
		(width 0.0889)
		(layer "In4.Cu")
		(net "M_H_CLK_DP<0>")
	)
	(segment
		(start 96.474788 -26.435304)
		(end 96.675448 -26.234644)
		(width 0.14224)
		(layer "In4.Cu")
		(net "M_H_CLK_DP<0>")
	)
	(segment
		(start 97.213928 -13.80236)
		(end 96.675448 -13.26388)
		(width 0.14224)
		(layer "In4.Cu")
		(net "M_H_CLK_DP<0>")
	)
	(segment
		(start 92.020644 -7.386828)
		(end 91.749372 -7.115556)
		(width 0.14224)
		(layer "In4.Cu")
		(net "M_H_CLK_DP<0>")
	)
	(segment
		(start 94.996508 -52.418488)
		(end 94.906592 -52.262278)
		(width 0.0889)
		(layer "In4.Cu")
		(net "M_H_CLK_DP<0>")
	)
	(segment
		(start 96.675448 -11.793728)
		(end 95.893128 -11.011408)
		(width 0.14224)
		(layer "In4.Cu")
		(net "M_H_CLK_DP<0>")
	)
	(segment
		(start 94.989904 -52.830222)
		(end 94.994984 -52.821332)
		(width 0.0889)
		(layer "In4.Cu")
		(net "M_H_CLK_DP<0>")
	)
	(segment
		(start 94.990158 -53.819806)
		(end 94.996508 -53.809138)
		(width 0.0889)
		(layer "In4.Cu")
		(net "M_H_CLK_DP<0>")
	)
	(segment
		(start 94.906592 -52.262278)
		(end 94.906592 -51.36007)
		(width 0.0889)
		(layer "In4.Cu")
		(net "M_H_CLK_DP<0>")
	)
	(segment
		(start 96.474788 -48.55718)
		(end 96.474788 -26.435304)
		(width 0.14224)
		(layer "In4.Cu")
		(net "M_H_CLK_DP<0>")
	)
	(segment
		(start 96.675448 -13.26388)
		(end 96.675448 -11.793728)
		(width 0.14224)
		(layer "In4.Cu")
		(net "M_H_CLK_DP<0>")
	)
	(segment
		(start 94.996508 -53.809138)
		(end 95.001334 -53.800502)
		(width 0.0889)
		(layer "In4.Cu")
		(net "M_H_CLK_DP<0>")
	)
	(segment
		(start 92.020644 -7.854442)
		(end 92.020644 -7.386828)
		(width 0.14224)
		(layer "In4.Cu")
		(net "M_H_CLK_DP<0>")
	)
	(segment
		(start 94.990158 -54.810406)
		(end 94.996508 -54.799738)
		(width 0.0889)
		(layer "In4.Cu")
		(net "M_H_CLK_DP<0>")
	)
	(segment
		(start 94.994984 -52.821332)
		(end 94.996508 -52.818538)
		(width 0.0889)
		(layer "In4.Cu")
		(net "M_H_CLK_DP<0>")
	)
	(segment
		(start 92.492068 -8.325866)
		(end 92.020644 -7.854442)
		(width 0.14224)
		(layer "In4.Cu")
		(net "M_H_CLK_DP<0>")
	)
	(segment
		(start 95.893128 -10.24255)
		(end 93.976444 -8.325866)
		(width 0.14224)
		(layer "In4.Cu")
		(net "M_H_CLK_DP<0>")
	)
	(segment
		(start 95.893128 -11.011408)
		(end 95.893128 -10.24255)
		(width 0.14224)
		(layer "In4.Cu")
		(net "M_H_CLK_DP<0>")
	)
	(arc
		(start 94.91726 -55.103014)
		(mid 94.934744 -54.951988)
		(end 94.990158 -54.810406)
		(width 0.0889)
		(layer "In4.Cu")
		(net "M_H_CLK_DP<0>")
	)
	(arc
		(start 94.996508 -53.409088)
		(mid 94.917416 -53.120508)
		(end 94.989904 -52.830222)
		(width 0.0889)
		(layer "In4.Cu")
		(net "M_H_CLK_DP<0>")
	)
	(arc
		(start 94.996508 -52.818538)
		(mid 95.050007 -52.61853)
		(end 94.996508 -52.418488)
		(width 0.0889)
		(layer "In4.Cu")
		(net "M_H_CLK_DP<0>")
	)
	(arc
		(start 95.001334 -54.791102)
		(mid 95.050089 -54.59475)
		(end 94.996508 -54.399688)
		(width 0.0889)
		(layer "In4.Cu")
		(net "M_H_CLK_DP<0>")
	)
	(arc
		(start 94.996508 -54.399688)
		(mid 94.917286 -54.11057)
		(end 94.990158 -53.819806)
		(width 0.0889)
		(layer "In4.Cu")
		(net "M_H_CLK_DP<0>")
	)
	(arc
		(start 94.761812 -55.47868)
		(mid 94.876894 -55.306308)
		(end 94.91726 -55.103014)
		(width 0.0889)
		(layer "In4.Cu")
		(net "M_H_CLK_DP<0>")
	)
	(arc
		(start 95.001334 -53.800502)
		(mid 95.050089 -53.60415)
		(end 94.996508 -53.409088)
		(width 0.0889)
		(layer "In4.Cu")
		(net "M_H_CLK_DP<0>")
	)
	(segment
		(start 93.504258 -56.58104)
		(end 92.932758 -56.58104)
		(width 0.1016)
		(layer "F.Cu")
		(net "M_H_CLK_DN<3>")
	)
	(via
		(at 92.932758 -56.58104)
		(size 0.508)
		(drill 0.254)
		(layers "F.Cu" "B.Cu")
		(net "M_H_CLK_DN<3>")
	)
	(via
		(at 92.52331 -11.916156)
		(size 0.4572)
		(drill 0.2032)
		(layers "F.Cu" "B.Cu")
		(net "M_H_CLK_DN<3>")
	)
	(segment
		(start 92.59951 -10.623042)
		(end 92.59951 -11.839956)
		(width 0.1651)
		(layer "B.Cu")
		(net "M_H_CLK_DN<3>")
	)
	(segment
		(start 92.59951 -11.839956)
		(end 92.52331 -11.916156)
		(width 0.1651)
		(layer "B.Cu")
		(net "M_H_CLK_DN<3>")
	)
	(segment
		(start 93.546168 -52.575206)
		(end 93.546168 -51.180746)
		(width 0.0889)
		(layer "In4.Cu")
		(net "M_H_CLK_DN<3>")
	)
	(segment
		(start 95.117412 -48.67021)
		(end 95.117412 -48.009556)
		(width 0.0889)
		(layer "In4.Cu")
		(net "M_H_CLK_DN<3>")
	)
	(segment
		(start 95.115888 -14.602714)
		(end 93.568774 -13.0556)
		(width 0.14224)
		(layer "In4.Cu")
		(net "M_H_CLK_DN<3>")
	)
	(segment
		(start 95.160084 -47.966884)
		(end 95.160084 -26.625804)
		(width 0.14224)
		(layer "In4.Cu")
		(net "M_H_CLK_DN<3>")
	)
	(segment
		(start 95.019368 -48.768254)
		(end 95.117412 -48.67021)
		(width 0.0889)
		(layer "In4.Cu")
		(net "M_H_CLK_DN<3>")
	)
	(segment
		(start 93.385132 -53.949346)
		(end 93.385132 -52.736242)
		(width 0.0889)
		(layer "In4.Cu")
		(net "M_H_CLK_DN<3>")
	)
	(segment
		(start 95.160084 -26.625804)
		(end 94.557088 -26.022808)
		(width 0.14224)
		(layer "In4.Cu")
		(net "M_H_CLK_DN<3>")
	)
	(segment
		(start 93.444822 -54.304692)
		(end 93.385386 -54.202076)
		(width 0.0889)
		(layer "In4.Cu")
		(net "M_H_CLK_DN<3>")
	)
	(segment
		(start 95.117412 -48.009556)
		(end 95.160084 -47.966884)
		(width 0.0889)
		(layer "In4.Cu")
		(net "M_H_CLK_DN<3>")
	)
	(segment
		(start 92.289884 -12.28217)
		(end 92.289884 -12.149582)
		(width 0.14224)
		(layer "In4.Cu")
		(net "M_H_CLK_DN<3>")
	)
	(segment
		(start 93.45168 -54.882288)
		(end 93.450918 -54.88432)
		(width 0.0889)
		(layer "In4.Cu")
		(net "M_H_CLK_DN<3>")
	)
	(segment
		(start 93.385386 -54.202076)
		(end 93.385132 -53.949346)
		(width 0.0889)
		(layer "In4.Cu")
		(net "M_H_CLK_DN<3>")
	)
	(segment
		(start 92.639642 -56.74995)
		(end 92.560902 -56.728614)
		(width 0.0889)
		(layer "In4.Cu")
		(net "M_H_CLK_DN<3>")
	)
	(segment
		(start 93.439742 -54.903624)
		(end 93.45168 -54.882288)
		(width 0.0889)
		(layer "In4.Cu")
		(net "M_H_CLK_DN<3>")
	)
	(segment
		(start 93.385132 -52.736242)
		(end 93.546168 -52.575206)
		(width 0.0889)
		(layer "In4.Cu")
		(net "M_H_CLK_DN<3>")
	)
	(segment
		(start 94.557088 -18.36928)
		(end 95.115888 -17.81048)
		(width 0.14224)
		(layer "In4.Cu")
		(net "M_H_CLK_DN<3>")
	)
	(segment
		(start 93.546168 -51.180746)
		(end 95.019368 -49.707546)
		(width 0.0889)
		(layer "In4.Cu")
		(net "M_H_CLK_DN<3>")
	)
	(segment
		(start 93.063314 -13.0556)
		(end 92.289884 -12.28217)
		(width 0.14224)
		(layer "In4.Cu")
		(net "M_H_CLK_DN<3>")
	)
	(segment
		(start 94.557088 -26.022808)
		(end 94.557088 -18.36928)
		(width 0.14224)
		(layer "In4.Cu")
		(net "M_H_CLK_DN<3>")
	)
	(segment
		(start 95.115888 -17.81048)
		(end 95.115888 -14.602714)
		(width 0.14224)
		(layer "In4.Cu")
		(net "M_H_CLK_DN<3>")
	)
	(segment
		(start 92.917772 -56.18099)
		(end 92.950538 -56.18099)
		(width 0.0889)
		(layer "In4.Cu")
		(net "M_H_CLK_DN<3>")
	)
	(segment
		(start 93.568774 -13.0556)
		(end 93.063314 -13.0556)
		(width 0.14224)
		(layer "In4.Cu")
		(net "M_H_CLK_DN<3>")
	)
	(segment
		(start 95.019368 -49.707546)
		(end 95.019368 -48.768254)
		(width 0.0889)
		(layer "In4.Cu")
		(net "M_H_CLK_DN<3>")
	)
	(segment
		(start 92.932758 -56.58104)
		(end 92.639642 -56.74995)
		(width 0.0889)
		(layer "In4.Cu")
		(net "M_H_CLK_DN<3>")
	)
	(segment
		(start 92.289884 -12.149582)
		(end 92.52331 -11.916156)
		(width 0.14224)
		(layer "In4.Cu")
		(net "M_H_CLK_DN<3>")
	)
	(arc
		(start 92.950538 -56.18099)
		(mid 93.448789 -55.87815)
		(end 93.444568 -55.295038)
		(width 0.0889)
		(layer "In4.Cu")
		(net "M_H_CLK_DN<3>")
	)
	(arc
		(start 92.560902 -56.728614)
		(mid 92.540427 -56.659278)
		(end 92.532708 -56.58739)
		(width 0.0889)
		(layer "In4.Cu")
		(net "M_H_CLK_DN<3>")
	)
	(arc
		(start 93.450918 -54.88432)
		(mid 93.523843 -54.593696)
		(end 93.444822 -54.304692)
		(width 0.0889)
		(layer "In4.Cu")
		(net "M_H_CLK_DN<3>")
	)
	(arc
		(start 92.532708 -56.58739)
		(mid 92.642388 -56.305684)
		(end 92.917772 -56.18099)
		(width 0.0889)
		(layer "In4.Cu")
		(net "M_H_CLK_DN<3>")
	)
	(arc
		(start 93.444568 -55.295038)
		(mid 93.391098 -55.099975)
		(end 93.439742 -54.903624)
		(width 0.0889)
		(layer "In4.Cu")
		(net "M_H_CLK_DN<3>")
	)
	(segment
		(start 95.221298 -56.58104)
		(end 94.649798 -56.58104)
		(width 0.1016)
		(layer "F.Cu")
		(net "M_H_CLK_DN<1>")
	)
	(segment
		(start 92.59951 -10.422382)
		(end 92.59951 -9.129268)
		(width 0.1651)
		(layer "F.Cu")
		(net "M_H_CLK_DN<1>")
	)
	(via
		(at 94.649798 -56.58104)
		(size 0.508)
		(drill 0.254)
		(layers "F.Cu" "B.Cu")
		(net "M_H_CLK_DN<1>")
	)
	(via
		(at 92.59951 -9.129268)
		(size 0.508)
		(drill 0.254)
		(layers "F.Cu" "B.Cu")
		(net "M_H_CLK_DN<1>")
	)
	(segment
		(start 94.956376 -11.486896)
		(end 94.956376 -10.820146)
		(width 0.14224)
		(layer "In4.Cu")
		(net "M_H_CLK_DN<1>")
	)
	(segment
		(start 95.667068 -48.9839)
		(end 95.946468 -48.7045)
		(width 0.0889)
		(layer "In4.Cu")
		(net "M_H_CLK_DN<1>")
	)
	(segment
		(start 93.411294 -10.81913)
		(end 93.22435 -11.006074)
		(width 0.14224)
		(layer "In4.Cu")
		(net "M_H_CLK_DN<1>")
	)
	(segment
		(start 95.667068 -49.919382)
		(end 95.667068 -48.9839)
		(width 0.0889)
		(layer "In4.Cu")
		(net "M_H_CLK_DN<1>")
	)
	(segment
		(start 94.303342 -53.809646)
		(end 94.303088 -53.809646)
		(width 0.0889)
		(layer "In4.Cu")
		(net "M_H_CLK_DN<1>")
	)
	(segment
		(start 96.106488 -25.870662)
		(end 96.106488 -12.637008)
		(width 0.14224)
		(layer "In4.Cu")
		(net "M_H_CLK_DN<1>")
	)
	(segment
		(start 92.289884 -9.438894)
		(end 92.59951 -9.129268)
		(width 0.14224)
		(layer "In4.Cu")
		(net "M_H_CLK_DN<1>")
	)
	(segment
		(start 94.42577 -10.28954)
		(end 93.695774 -10.28954)
		(width 0.14224)
		(layer "In4.Cu")
		(net "M_H_CLK_DN<1>")
	)
	(segment
		(start 95.998284 -48.017684)
		(end 95.998284 -25.978866)
		(width 0.14224)
		(layer "In4.Cu")
		(net "M_H_CLK_DN<1>")
	)
	(segment
		(start 94.249494 -51.336956)
		(end 95.667068 -49.919382)
		(width 0.0889)
		(layer "In4.Cu")
		(net "M_H_CLK_DN<1>")
	)
	(segment
		(start 94.956376 -10.820146)
		(end 94.42577 -10.28954)
		(width 0.14224)
		(layer "In4.Cu")
		(net "M_H_CLK_DN<1>")
	)
	(segment
		(start 92.593414 -11.006074)
		(end 92.289884 -10.702544)
		(width 0.14224)
		(layer "In4.Cu")
		(net "M_H_CLK_DN<1>")
	)
	(segment
		(start 94.649798 -56.58104)
		(end 94.356682 -56.750204)
		(width 0.0889)
		(layer "In4.Cu")
		(net "M_H_CLK_DN<1>")
	)
	(segment
		(start 95.998284 -25.978866)
		(end 96.106488 -25.870662)
		(width 0.14224)
		(layer "In4.Cu")
		(net "M_H_CLK_DN<1>")
	)
	(segment
		(start 94.249494 -53.598064)
		(end 94.249494 -51.336956)
		(width 0.0889)
		(layer "In4.Cu")
		(net "M_H_CLK_DN<1>")
	)
	(segment
		(start 96.106488 -12.637008)
		(end 94.956376 -11.486896)
		(width 0.14224)
		(layer "In4.Cu")
		(net "M_H_CLK_DN<1>")
	)
	(segment
		(start 92.289884 -10.702544)
		(end 92.289884 -9.438894)
		(width 0.14224)
		(layer "In4.Cu")
		(net "M_H_CLK_DN<1>")
	)
	(segment
		(start 93.411294 -10.57402)
		(end 93.411294 -10.81913)
		(width 0.14224)
		(layer "In4.Cu")
		(net "M_H_CLK_DN<1>")
	)
	(segment
		(start 95.946468 -48.7045)
		(end 95.946468 -48.0695)
		(width 0.0889)
		(layer "In4.Cu")
		(net "M_H_CLK_DN<1>")
	)
	(segment
		(start 95.946468 -48.0695)
		(end 95.998284 -48.017684)
		(width 0.0889)
		(layer "In4.Cu")
		(net "M_H_CLK_DN<1>")
	)
	(segment
		(start 93.695774 -10.28954)
		(end 93.411294 -10.57402)
		(width 0.14224)
		(layer "In4.Cu")
		(net "M_H_CLK_DN<1>")
	)
	(segment
		(start 94.356682 -56.750204)
		(end 94.277942 -56.728868)
		(width 0.0889)
		(layer "In4.Cu")
		(net "M_H_CLK_DN<1>")
	)
	(segment
		(start 93.22435 -11.006074)
		(end 92.593414 -11.006074)
		(width 0.14224)
		(layer "In4.Cu")
		(net "M_H_CLK_DN<1>")
	)
	(arc
		(start 94.277942 -56.728868)
		(mid 94.250673 -56.552239)
		(end 94.303088 -56.381396)
		(width 0.0889)
		(layer "In4.Cu")
		(net "M_H_CLK_DN<1>")
	)
	(arc
		(start 94.303088 -53.809646)
		(mid 94.261597 -53.707577)
		(end 94.249494 -53.598064)
		(width 0.0889)
		(layer "In4.Cu")
		(net "M_H_CLK_DN<1>")
	)
	(arc
		(start 94.303088 -55.390796)
		(mid 94.382219 -55.095394)
		(end 94.303088 -54.799992)
		(width 0.0889)
		(layer "In4.Cu")
		(net "M_H_CLK_DN<1>")
	)
	(arc
		(start 94.303088 -54.400196)
		(mid 94.382219 -54.104967)
		(end 94.303342 -53.809646)
		(width 0.0889)
		(layer "In4.Cu")
		(net "M_H_CLK_DN<1>")
	)
	(arc
		(start 94.303088 -54.799992)
		(mid 94.249589 -54.600094)
		(end 94.303088 -54.400196)
		(width 0.0889)
		(layer "In4.Cu")
		(net "M_H_CLK_DN<1>")
	)
	(arc
		(start 94.303088 -55.790592)
		(mid 94.249589 -55.590694)
		(end 94.303088 -55.390796)
		(width 0.0889)
		(layer "In4.Cu")
		(net "M_H_CLK_DN<1>")
	)
	(arc
		(start 94.303088 -56.381396)
		(mid 94.382219 -56.085994)
		(end 94.303088 -55.790592)
		(width 0.0889)
		(layer "In4.Cu")
		(net "M_H_CLK_DN<1>")
	)
	(segment
		(start 93.504258 -55.59044)
		(end 92.932758 -55.59044)
		(width 0.1016)
		(layer "F.Cu")
		(net "M_H_CLK_DN<2>")
	)
	(via
		(at 92.59951 -13.929868)
		(size 0.508)
		(drill 0.254)
		(layers "F.Cu" "B.Cu")
		(net "M_H_CLK_DN<2>")
	)
	(via
		(at 92.932758 -55.59044)
		(size 0.508)
		(drill 0.254)
		(layers "F.Cu" "B.Cu")
		(net "M_H_CLK_DN<2>")
	)
	(segment
		(start 92.59951 -15.222982)
		(end 92.59951 -13.929868)
		(width 0.1651)
		(layer "B.Cu")
		(net "M_H_CLK_DN<2>")
	)
	(segment
		(start 91.62542 -23.928324)
		(end 91.62542 -23.099776)
		(width 0.14224)
		(layer "In4.Cu")
		(net "M_H_CLK_DN<2>")
	)
	(segment
		(start 93.22562 -20.823174)
		(end 93.545406 -20.503388)
		(width 0.14224)
		(layer "In4.Cu")
		(net "M_H_CLK_DN<2>")
	)
	(segment
		(start 93.240352 -19.621754)
		(end 92.344748 -19.621754)
		(width 0.14224)
		(layer "In4.Cu")
		(net "M_H_CLK_DN<2>")
	)
	(segment
		(start 92.586048 -54.399688)
		(end 92.747592 -54.120034)
		(width 0.0889)
		(layer "In4.Cu")
		(net "M_H_CLK_DN<2>")
	)
	(segment
		(start 92.344748 -20.823174)
		(end 93.22562 -20.823174)
		(width 0.14224)
		(layer "In4.Cu")
		(net "M_H_CLK_DN<2>")
	)
	(segment
		(start 92.521532 -51.27371)
		(end 94.42323 -49.372012)
		(width 0.0889)
		(layer "In4.Cu")
		(net "M_H_CLK_DN<2>")
	)
	(segment
		(start 92.521532 -51.716432)
		(end 92.521532 -51.27371)
		(width 0.0889)
		(layer "In4.Cu")
		(net "M_H_CLK_DN<2>")
	)
	(segment
		(start 92.344748 -19.621754)
		(end 92.189808 -19.466814)
		(width 0.14224)
		(layer "In4.Cu")
		(net "M_H_CLK_DN<2>")
	)
	(segment
		(start 93.642434 -25.945338)
		(end 91.62542 -23.928324)
		(width 0.14224)
		(layer "In4.Cu")
		(net "M_H_CLK_DN<2>")
	)
	(segment
		(start 91.605608 -21.912834)
		(end 92.189808 -21.328634)
		(width 0.14224)
		(layer "In4.Cu")
		(net "M_H_CLK_DN<2>")
	)
	(segment
		(start 92.586048 -54.799738)
		(end 92.581222 -54.791102)
		(width 0.0889)
		(layer "In4.Cu")
		(net "M_H_CLK_DN<2>")
	)
	(segment
		(start 93.642434 -26.352754)
		(end 93.642434 -25.945338)
		(width 0.14224)
		(layer "In4.Cu")
		(net "M_H_CLK_DN<2>")
	)
	(segment
		(start 92.315284 -14.214094)
		(end 92.59951 -13.929868)
		(width 0.14224)
		(layer "In4.Cu")
		(net "M_H_CLK_DN<2>")
	)
	(segment
		(start 92.189808 -18.332704)
		(end 92.651072 -17.87144)
		(width 0.14224)
		(layer "In4.Cu")
		(net "M_H_CLK_DN<2>")
	)
	(segment
		(start 92.315284 -14.836394)
		(end 92.315284 -14.214094)
		(width 0.14224)
		(layer "In4.Cu")
		(net "M_H_CLK_DN<2>")
	)
	(segment
		(start 94.321884 -27.031442)
		(end 93.904308 -26.613866)
		(width 0.14224)
		(layer "In4.Cu")
		(net "M_H_CLK_DN<2>")
	)
	(segment
		(start 94.42323 -48.576738)
		(end 94.279974 -48.433482)
		(width 0.0889)
		(layer "In4.Cu")
		(net "M_H_CLK_DN<2>")
	)
	(segment
		(start 92.592398 -54.810406)
		(end 92.586048 -54.799738)
		(width 0.0889)
		(layer "In4.Cu")
		(net "M_H_CLK_DN<2>")
	)
	(segment
		(start 92.651072 -17.87144)
		(end 93.337888 -17.87144)
		(width 0.14224)
		(layer "In4.Cu")
		(net "M_H_CLK_DN<2>")
	)
	(segment
		(start 92.783914 -15.305024)
		(end 92.315284 -14.836394)
		(width 0.14224)
		(layer "In4.Cu")
		(net "M_H_CLK_DN<2>")
	)
	(segment
		(start 94.321884 -48.017684)
		(end 94.321884 -27.031442)
		(width 0.14224)
		(layer "In4.Cu")
		(net "M_H_CLK_DN<2>")
	)
	(segment
		(start 94.42323 -49.372012)
		(end 94.42323 -48.576738)
		(width 0.0889)
		(layer "In4.Cu")
		(net "M_H_CLK_DN<2>")
	)
	(segment
		(start 93.941392 -15.962884)
		(end 93.283532 -15.305024)
		(width 0.14224)
		(layer "In4.Cu")
		(net "M_H_CLK_DN<2>")
	)
	(segment
		(start 92.747592 -52.107592)
		(end 92.521532 -51.716432)
		(width 0.0889)
		(layer "In4.Cu")
		(net "M_H_CLK_DN<2>")
	)
	(segment
		(start 92.189808 -21.328634)
		(end 92.189808 -20.978114)
		(width 0.14224)
		(layer "In4.Cu")
		(net "M_H_CLK_DN<2>")
	)
	(segment
		(start 94.279974 -48.059594)
		(end 94.321884 -48.017684)
		(width 0.0889)
		(layer "In4.Cu")
		(net "M_H_CLK_DN<2>")
	)
	(segment
		(start 93.283532 -15.305024)
		(end 92.783914 -15.305024)
		(width 0.14224)
		(layer "In4.Cu")
		(net "M_H_CLK_DN<2>")
	)
	(segment
		(start 92.932758 -55.59044)
		(end 92.82811 -55.485538)
		(width 0.0889)
		(layer "In4.Cu")
		(net "M_H_CLK_DN<2>")
	)
	(segment
		(start 91.605608 -23.079964)
		(end 91.605608 -21.912834)
		(width 0.14224)
		(layer "In4.Cu")
		(net "M_H_CLK_DN<2>")
	)
	(segment
		(start 94.279974 -48.433482)
		(end 94.279974 -48.059594)
		(width 0.0889)
		(layer "In4.Cu")
		(net "M_H_CLK_DN<2>")
	)
	(segment
		(start 93.903546 -26.613866)
		(end 93.642434 -26.352754)
		(width 0.14224)
		(layer "In4.Cu")
		(net "M_H_CLK_DN<2>")
	)
	(segment
		(start 92.189808 -19.466814)
		(end 92.189808 -18.332704)
		(width 0.14224)
		(layer "In4.Cu")
		(net "M_H_CLK_DN<2>")
	)
	(segment
		(start 93.337888 -17.87144)
		(end 93.941392 -17.267936)
		(width 0.14224)
		(layer "In4.Cu")
		(net "M_H_CLK_DN<2>")
	)
	(segment
		(start 93.545406 -20.503388)
		(end 93.545406 -19.926808)
		(width 0.14224)
		(layer "In4.Cu")
		(net "M_H_CLK_DN<2>")
	)
	(segment
		(start 91.62542 -23.099776)
		(end 91.605608 -23.079964)
		(width 0.14224)
		(layer "In4.Cu")
		(net "M_H_CLK_DN<2>")
	)
	(segment
		(start 93.904308 -26.613866)
		(end 93.903546 -26.613866)
		(width 0.14224)
		(layer "In4.Cu")
		(net "M_H_CLK_DN<2>")
	)
	(segment
		(start 93.941392 -17.267936)
		(end 93.941392 -15.962884)
		(width 0.14224)
		(layer "In4.Cu")
		(net "M_H_CLK_DN<2>")
	)
	(segment
		(start 93.545406 -19.926808)
		(end 93.240352 -19.621754)
		(width 0.14224)
		(layer "In4.Cu")
		(net "M_H_CLK_DN<2>")
	)
	(segment
		(start 92.189808 -20.978114)
		(end 92.344748 -20.823174)
		(width 0.14224)
		(layer "In4.Cu")
		(net "M_H_CLK_DN<2>")
	)
	(segment
		(start 92.747592 -54.120034)
		(end 92.747592 -52.107592)
		(width 0.0889)
		(layer "In4.Cu")
		(net "M_H_CLK_DN<2>")
	)
	(arc
		(start 92.581222 -54.791102)
		(mid 92.532467 -54.59475)
		(end 92.586048 -54.399688)
		(width 0.0889)
		(layer "In4.Cu")
		(net "M_H_CLK_DN<2>")
	)
	(arc
		(start 92.82811 -55.485538)
		(mid 92.707645 -55.305388)
		(end 92.665296 -55.092854)
		(width 0.0889)
		(layer "In4.Cu")
		(net "M_H_CLK_DN<2>")
	)
	(arc
		(start 92.665296 -55.092854)
		(mid 92.64657 -54.947054)
		(end 92.592398 -54.810406)
		(width 0.0889)
		(layer "In4.Cu")
		(net "M_H_CLK_DN<2>")
	)
	(segment
		(start 96.079818 -55.094886)
		(end 95.508318 -55.094886)
		(width 0.1016)
		(layer "F.Cu")
		(net "M_H_CLK_DN<0>")
	)
	(segment
		(start 92.59951 -5.822442)
		(end 92.59951 -7.115556)
		(width 0.1651)
		(layer "F.Cu")
		(net "M_H_CLK_DN<0>")
	)
	(via
		(at 92.59951 -7.115556)
		(size 0.4572)
		(drill 0.2032)
		(layers "F.Cu" "B.Cu")
		(net "M_H_CLK_DN<0>")
	)
	(via
		(at 95.508318 -55.094886)
		(size 0.508)
		(drill 0.254)
		(layers "F.Cu" "B.Cu")
		(net "M_H_CLK_DN<0>")
	)
	(segment
		(start 92.289884 -7.742682)
		(end 92.289884 -7.425182)
		(width 0.14224)
		(layer "In4.Cu")
		(net "M_H_CLK_DN<0>")
	)
	(segment
		(start 96.706182 -49.829974)
		(end 96.706182 -48.586644)
		(width 0.0889)
		(layer "In4.Cu")
		(net "M_H_CLK_DN<0>")
	)
	(segment
		(start 95.508318 -55.094886)
		(end 95.215202 -55.26405)
		(width 0.0889)
		(layer "In4.Cu")
		(net "M_H_CLK_DN<0>")
	)
	(segment
		(start 96.162368 -10.13079)
		(end 94.088204 -8.056626)
		(width 0.14224)
		(layer "In4.Cu")
		(net "M_H_CLK_DN<0>")
	)
	(segment
		(start 96.944688 -26.346404)
		(end 96.944688 -20.52828)
		(width 0.14224)
		(layer "In4.Cu")
		(net "M_H_CLK_DN<0>")
	)
	(segment
		(start 95.215202 -55.26405)
		(end 95.136462 -55.242714)
		(width 0.0889)
		(layer "In4.Cu")
		(net "M_H_CLK_DN<0>")
	)
	(segment
		(start 96.706182 -48.586644)
		(end 96.744028 -48.548798)
		(width 0.0889)
		(layer "In4.Cu")
		(net "M_H_CLK_DN<0>")
	)
	(segment
		(start 96.944688 -11.681968)
		(end 96.162368 -10.899648)
		(width 0.14224)
		(layer "In4.Cu")
		(net "M_H_CLK_DN<0>")
	)
	(segment
		(start 97.483168 -13.6906)
		(end 96.944688 -13.15212)
		(width 0.14224)
		(layer "In4.Cu")
		(net "M_H_CLK_DN<0>")
	)
	(segment
		(start 92.289884 -7.425182)
		(end 92.59951 -7.115556)
		(width 0.14224)
		(layer "In4.Cu")
		(net "M_H_CLK_DN<0>")
	)
	(segment
		(start 95.160846 -52.915058)
		(end 95.161608 -52.913788)
		(width 0.0889)
		(layer "In4.Cu")
		(net "M_H_CLK_DN<0>")
	)
	(segment
		(start 96.944688 -13.15212)
		(end 96.944688 -11.681968)
		(width 0.14224)
		(layer "In4.Cu")
		(net "M_H_CLK_DN<0>")
	)
	(segment
		(start 95.156782 -52.922424)
		(end 95.160846 -52.915058)
		(width 0.0889)
		(layer "In4.Cu")
		(net "M_H_CLK_DN<0>")
	)
	(segment
		(start 95.097092 -52.211224)
		(end 95.097092 -51.439064)
		(width 0.0889)
		(layer "In4.Cu")
		(net "M_H_CLK_DN<0>")
	)
	(segment
		(start 96.744028 -48.548798)
		(end 96.744028 -48.5267)
		(width 0.0889)
		(layer "In4.Cu")
		(net "M_H_CLK_DN<0>")
	)
	(segment
		(start 95.161608 -52.322984)
		(end 95.097092 -52.211224)
		(width 0.0889)
		(layer "In4.Cu")
		(net "M_H_CLK_DN<0>")
	)
	(segment
		(start 94.088204 -8.056626)
		(end 92.603828 -8.056626)
		(width 0.14224)
		(layer "In4.Cu")
		(net "M_H_CLK_DN<0>")
	)
	(segment
		(start 95.097092 -51.439064)
		(end 96.706182 -49.829974)
		(width 0.0889)
		(layer "In4.Cu")
		(net "M_H_CLK_DN<0>")
	)
	(segment
		(start 95.161608 -54.894988)
		(end 95.167958 -54.88432)
		(width 0.0889)
		(layer "In4.Cu")
		(net "M_H_CLK_DN<0>")
	)
	(segment
		(start 97.483168 -19.9898)
		(end 97.483168 -13.6906)
		(width 0.14224)
		(layer "In4.Cu")
		(net "M_H_CLK_DN<0>")
	)
	(segment
		(start 96.744028 -26.547064)
		(end 96.944688 -26.346404)
		(width 0.14224)
		(layer "In4.Cu")
		(net "M_H_CLK_DN<0>")
	)
	(segment
		(start 96.162368 -10.899648)
		(end 96.162368 -10.13079)
		(width 0.14224)
		(layer "In4.Cu")
		(net "M_H_CLK_DN<0>")
	)
	(segment
		(start 96.944688 -20.52828)
		(end 97.483168 -19.9898)
		(width 0.14224)
		(layer "In4.Cu")
		(net "M_H_CLK_DN<0>")
	)
	(segment
		(start 92.603828 -8.056626)
		(end 92.289884 -7.742682)
		(width 0.14224)
		(layer "In4.Cu")
		(net "M_H_CLK_DN<0>")
	)
	(segment
		(start 95.156782 -53.913024)
		(end 95.161608 -53.904388)
		(width 0.0889)
		(layer "In4.Cu")
		(net "M_H_CLK_DN<0>")
	)
	(segment
		(start 96.744028 -48.5267)
		(end 96.744028 -26.547064)
		(width 0.14224)
		(layer "In4.Cu")
		(net "M_H_CLK_DN<0>")
	)
	(segment
		(start 95.161608 -53.904388)
		(end 95.167958 -53.89372)
		(width 0.0889)
		(layer "In4.Cu")
		(net "M_H_CLK_DN<0>")
	)
	(segment
		(start 95.156782 -54.903624)
		(end 95.161608 -54.894988)
		(width 0.0889)
		(layer "In4.Cu")
		(net "M_H_CLK_DN<0>")
	)
	(arc
		(start 95.136462 -55.242714)
		(mid 95.115888 -55.172879)
		(end 95.108268 -55.100474)
		(width 0.0889)
		(layer "In4.Cu")
		(net "M_H_CLK_DN<0>")
	)
	(arc
		(start 95.167958 -54.88432)
		(mid 95.240756 -54.593557)
		(end 95.161608 -54.304438)
		(width 0.0889)
		(layer "In4.Cu")
		(net "M_H_CLK_DN<0>")
	)
	(arc
		(start 95.161608 -53.313838)
		(mid 95.108138 -53.118775)
		(end 95.156782 -52.922424)
		(width 0.0889)
		(layer "In4.Cu")
		(net "M_H_CLK_DN<0>")
	)
	(arc
		(start 95.167958 -53.89372)
		(mid 95.240756 -53.602957)
		(end 95.161608 -53.313838)
		(width 0.0889)
		(layer "In4.Cu")
		(net "M_H_CLK_DN<0>")
	)
	(arc
		(start 95.161608 -52.913788)
		(mid 95.240739 -52.618386)
		(end 95.161608 -52.322984)
		(width 0.0889)
		(layer "In4.Cu")
		(net "M_H_CLK_DN<0>")
	)
	(arc
		(start 95.108268 -55.100474)
		(mid 95.119835 -54.998918)
		(end 95.156782 -54.903624)
		(width 0.0889)
		(layer "In4.Cu")
		(net "M_H_CLK_DN<0>")
	)
	(arc
		(start 95.161608 -54.304438)
		(mid 95.108138 -54.109375)
		(end 95.156782 -53.913024)
		(width 0.0889)
		(layer "In4.Cu")
		(net "M_H_CLK_DN<0>")
	)
	(segment
		(start 86.636352 -54.59984)
		(end 86.064852 -54.59984)
		(width 0.1016)
		(layer "F.Cu")
		(net "M_H_CKE<3>")
	)
	(via
		(at 86.064852 -54.59984)
		(size 0.508)
		(drill 0.254)
		(layers "F.Cu" "B.Cu")
		(net "M_H_CKE<3>")
	)
	(via
		(at 78.999334 -11.916156)
		(size 0.4572)
		(drill 0.2032)
		(layers "F.Cu" "B.Cu")
		(net "M_H_CKE<3>")
	)
	(segment
		(start 78.999334 -11.916156)
		(end 78.999334 -10.623042)
		(width 0.1651)
		(layer "B.Cu")
		(net "M_H_CKE<3>")
	)
	(segment
		(start 86.78164 -33.585912)
		(end 80.77454 -27.578812)
		(width 0.14224)
		(layer "In4.Cu")
		(net "M_H_CKE<3>")
	)
	(segment
		(start 79.493364 -21.811996)
		(end 79.493364 -19.068796)
		(width 0.14224)
		(layer "In4.Cu")
		(net "M_H_CKE<3>")
	)
	(segment
		(start 79.41183 -18.987262)
		(end 79.41183 -18.48612)
		(width 0.14224)
		(layer "In4.Cu")
		(net "M_H_CKE<3>")
	)
	(segment
		(start 86.487254 -51.562508)
		(end 86.487254 -51.157886)
		(width 0.0889)
		(layer "In4.Cu")
		(net "M_H_CKE<3>")
	)
	(segment
		(start 79.437992 -14.12621)
		(end 79.437992 -12.354814)
		(width 0.14224)
		(layer "In4.Cu")
		(net "M_H_CKE<3>")
	)
	(segment
		(start 79.41183 -18.48612)
		(end 79.493364 -18.404586)
		(width 0.14224)
		(layer "In4.Cu")
		(net "M_H_CKE<3>")
	)
	(segment
		(start 79.544164 -22.599396)
		(end 79.366364 -22.421596)
		(width 0.14224)
		(layer "In4.Cu")
		(net "M_H_CKE<3>")
	)
	(segment
		(start 86.411562 -51.827684)
		(end 86.416388 -51.819048)
		(width 0.0889)
		(layer "In4.Cu")
		(net "M_H_CKE<3>")
	)
	(segment
		(start 86.487254 -51.157886)
		(end 86.78164 -50.8635)
		(width 0.0889)
		(layer "In4.Cu")
		(net "M_H_CKE<3>")
	)
	(segment
		(start 86.41842 -52.43068)
		(end 86.402672 -52.403248)
		(width 0.0889)
		(layer "In4.Cu")
		(net "M_H_CKE<3>")
	)
	(segment
		(start 79.437992 -15.731744)
		(end 79.205328 -15.49908)
		(width 0.14224)
		(layer "In4.Cu")
		(net "M_H_CKE<3>")
	)
	(segment
		(start 79.544164 -23.132796)
		(end 79.544164 -22.599396)
		(width 0.14224)
		(layer "In4.Cu")
		(net "M_H_CKE<3>")
	)
	(segment
		(start 79.437992 -17.012158)
		(end 79.437992 -15.731744)
		(width 0.14224)
		(layer "In4.Cu")
		(net "M_H_CKE<3>")
	)
	(segment
		(start 79.35849 -23.734776)
		(end 79.35849 -23.31847)
		(width 0.14224)
		(layer "In4.Cu")
		(net "M_H_CKE<3>")
	)
	(segment
		(start 80.77454 -27.578812)
		(end 80.77454 -25.150826)
		(width 0.14224)
		(layer "In4.Cu")
		(net "M_H_CKE<3>")
	)
	(segment
		(start 79.340964 -17.617186)
		(end 79.340964 -17.109186)
		(width 0.14224)
		(layer "In4.Cu")
		(net "M_H_CKE<3>")
	)
	(segment
		(start 79.437992 -12.354814)
		(end 78.999334 -11.916156)
		(width 0.14224)
		(layer "In4.Cu")
		(net "M_H_CKE<3>")
	)
	(segment
		(start 86.78164 -50.268886)
		(end 86.78164 -33.585912)
		(width 0.14224)
		(layer "In4.Cu")
		(net "M_H_CKE<3>")
	)
	(segment
		(start 79.366364 -21.938996)
		(end 79.493364 -21.811996)
		(width 0.14224)
		(layer "In4.Cu")
		(net "M_H_CKE<3>")
	)
	(segment
		(start 86.411562 -53.408834)
		(end 86.405212 -53.398166)
		(width 0.0889)
		(layer "In4.Cu")
		(net "M_H_CKE<3>")
	)
	(segment
		(start 79.493364 -17.769586)
		(end 79.340964 -17.617186)
		(width 0.14224)
		(layer "In4.Cu")
		(net "M_H_CKE<3>")
	)
	(segment
		(start 86.78164 -50.8635)
		(end 86.78164 -50.268886)
		(width 0.0889)
		(layer "In4.Cu")
		(net "M_H_CKE<3>")
	)
	(segment
		(start 86.416388 -53.41747)
		(end 86.411562 -53.408834)
		(width 0.0889)
		(layer "In4.Cu")
		(net "M_H_CKE<3>")
	)
	(segment
		(start 79.493364 -18.404586)
		(end 79.493364 -17.769586)
		(width 0.14224)
		(layer "In4.Cu")
		(net "M_H_CKE<3>")
	)
	(segment
		(start 79.35849 -23.31847)
		(end 79.544164 -23.132796)
		(width 0.14224)
		(layer "In4.Cu")
		(net "M_H_CKE<3>")
	)
	(segment
		(start 79.340964 -17.109186)
		(end 79.437992 -17.012158)
		(width 0.14224)
		(layer "In4.Cu")
		(net "M_H_CKE<3>")
	)
	(segment
		(start 79.366364 -22.421596)
		(end 79.366364 -21.938996)
		(width 0.14224)
		(layer "In4.Cu")
		(net "M_H_CKE<3>")
	)
	(segment
		(start 86.064852 -54.59984)
		(end 86.411562 -53.808884)
		(width 0.0889)
		(layer "In4.Cu")
		(net "M_H_CKE<3>")
	)
	(segment
		(start 79.205328 -15.49908)
		(end 79.205328 -14.358874)
		(width 0.14224)
		(layer "In4.Cu")
		(net "M_H_CKE<3>")
	)
	(segment
		(start 80.77454 -25.150826)
		(end 79.35849 -23.734776)
		(width 0.14224)
		(layer "In4.Cu")
		(net "M_H_CKE<3>")
	)
	(segment
		(start 79.205328 -14.358874)
		(end 79.437992 -14.12621)
		(width 0.14224)
		(layer "In4.Cu")
		(net "M_H_CKE<3>")
	)
	(segment
		(start 79.493364 -19.068796)
		(end 79.41183 -18.987262)
		(width 0.14224)
		(layer "In4.Cu")
		(net "M_H_CKE<3>")
	)
	(arc
		(start 86.405212 -53.398166)
		(mid 86.332414 -53.107403)
		(end 86.411562 -52.818284)
		(width 0.0889)
		(layer "In4.Cu")
		(net "M_H_CKE<3>")
	)
	(arc
		(start 86.411562 -53.808884)
		(mid 86.465032 -53.613821)
		(end 86.416388 -53.41747)
		(width 0.0889)
		(layer "In4.Cu")
		(net "M_H_CKE<3>")
	)
	(arc
		(start 86.416388 -51.819048)
		(mid 86.468211 -51.695308)
		(end 86.487254 -51.562508)
		(width 0.0889)
		(layer "In4.Cu")
		(net "M_H_CKE<3>")
	)
	(arc
		(start 86.402672 -52.403248)
		(mid 86.332275 -52.114297)
		(end 86.411562 -51.827684)
		(width 0.0889)
		(layer "In4.Cu")
		(net "M_H_CKE<3>")
	)
	(arc
		(start 86.411562 -52.818284)
		(mid 86.465 -52.625379)
		(end 86.41842 -52.43068)
		(width 0.0889)
		(layer "In4.Cu")
		(net "M_H_CKE<3>")
	)
	(segment
		(start 87.494872 -54.104286)
		(end 86.923372 -54.104286)
		(width 0.1016)
		(layer "F.Cu")
		(net "M_H_CKE<2>")
	)
	(via
		(at 86.923372 -54.104286)
		(size 0.508)
		(drill 0.254)
		(layers "F.Cu" "B.Cu")
		(net "M_H_CKE<2>")
	)
	(via
		(at 79.849472 -13.933678)
		(size 0.4572)
		(drill 0.2032)
		(layers "F.Cu" "B.Cu")
		(net "M_H_CKE<2>")
	)
	(segment
		(start 79.849472 -15.222982)
		(end 79.849472 -13.933678)
		(width 0.1651)
		(layer "B.Cu")
		(net "M_H_CKE<2>")
	)
	(segment
		(start 81.304638 -24.962358)
		(end 80.356964 -24.014684)
		(width 0.14224)
		(layer "In4.Cu")
		(net "M_H_CKE<2>")
	)
	(segment
		(start 80.356964 -21.913596)
		(end 80.204564 -21.761196)
		(width 0.14224)
		(layer "In4.Cu")
		(net "M_H_CKE<2>")
	)
	(segment
		(start 79.849472 -14.32179)
		(end 79.849472 -13.933678)
		(width 0.14224)
		(layer "In4.Cu")
		(net "M_H_CKE<2>")
	)
	(segment
		(start 80.287114 -18.461736)
		(end 80.204564 -18.379186)
		(width 0.14224)
		(layer "In4.Cu")
		(net "M_H_CKE<2>")
	)
	(segment
		(start 80.356964 -16.389858)
		(end 80.356964 -14.829282)
		(width 0.14224)
		(layer "In4.Cu")
		(net "M_H_CKE<2>")
	)
	(segment
		(start 80.264254 -17.041876)
		(end 80.264254 -16.482568)
		(width 0.14224)
		(layer "In4.Cu")
		(net "M_H_CKE<2>")
	)
	(segment
		(start 87.245444 -50.787554)
		(end 87.245444 -50.470562)
		(width 0.0889)
		(layer "In4.Cu")
		(net "M_H_CKE<2>")
	)
	(segment
		(start 81.304638 -27.254708)
		(end 81.304638 -24.962358)
		(width 0.14224)
		(layer "In4.Cu")
		(net "M_H_CKE<2>")
	)
	(segment
		(start 80.204564 -17.794986)
		(end 80.356964 -17.642586)
		(width 0.14224)
		(layer "In4.Cu")
		(net "M_H_CKE<2>")
	)
	(segment
		(start 86.70417 -51.44643)
		(end 86.70417 -51.328828)
		(width 0.0889)
		(layer "In4.Cu")
		(net "M_H_CKE<2>")
	)
	(segment
		(start 80.356964 -24.014684)
		(end 80.356964 -23.285196)
		(width 0.14224)
		(layer "In4.Cu")
		(net "M_H_CKE<2>")
	)
	(segment
		(start 86.583012 -52.333652)
		(end 86.576662 -52.322984)
		(width 0.0889)
		(layer "In4.Cu")
		(net "M_H_CKE<2>")
	)
	(segment
		(start 80.356964 -17.642586)
		(end 80.356964 -17.134586)
		(width 0.14224)
		(layer "In4.Cu")
		(net "M_H_CKE<2>")
	)
	(segment
		(start 86.576662 -52.322984)
		(end 86.569804 -52.310792)
		(width 0.0889)
		(layer "In4.Cu")
		(net "M_H_CKE<2>")
	)
	(segment
		(start 86.593934 -53.343302)
		(end 86.571836 -53.304948)
		(width 0.0889)
		(layer "In4.Cu")
		(net "M_H_CKE<2>")
	)
	(segment
		(start 80.287114 -19.058636)
		(end 80.287114 -18.461736)
		(width 0.14224)
		(layer "In4.Cu")
		(net "M_H_CKE<2>")
	)
	(segment
		(start 80.356964 -22.396196)
		(end 80.356964 -21.913596)
		(width 0.14224)
		(layer "In4.Cu")
		(net "M_H_CKE<2>")
	)
	(segment
		(start 87.245444 -50.470562)
		(end 87.245444 -33.195514)
		(width 0.14224)
		(layer "In4.Cu")
		(net "M_H_CKE<2>")
	)
	(segment
		(start 80.204564 -21.761196)
		(end 80.204564 -19.141186)
		(width 0.14224)
		(layer "In4.Cu")
		(net "M_H_CKE<2>")
	)
	(segment
		(start 80.356964 -14.829282)
		(end 79.849472 -14.32179)
		(width 0.14224)
		(layer "In4.Cu")
		(net "M_H_CKE<2>")
	)
	(segment
		(start 80.204564 -19.141186)
		(end 80.287114 -19.058636)
		(width 0.14224)
		(layer "In4.Cu")
		(net "M_H_CKE<2>")
	)
	(segment
		(start 80.179164 -22.573996)
		(end 80.356964 -22.396196)
		(width 0.14224)
		(layer "In4.Cu")
		(net "M_H_CKE<2>")
	)
	(segment
		(start 87.245444 -33.195514)
		(end 81.304638 -27.254708)
		(width 0.14224)
		(layer "In4.Cu")
		(net "M_H_CKE<2>")
	)
	(segment
		(start 80.204564 -18.379186)
		(end 80.204564 -17.794986)
		(width 0.14224)
		(layer "In4.Cu")
		(net "M_H_CKE<2>")
	)
	(segment
		(start 80.356964 -23.285196)
		(end 80.179164 -23.107396)
		(width 0.14224)
		(layer "In4.Cu")
		(net "M_H_CKE<2>")
	)
	(segment
		(start 80.264254 -16.482568)
		(end 80.356964 -16.389858)
		(width 0.14224)
		(layer "In4.Cu")
		(net "M_H_CKE<2>")
	)
	(segment
		(start 80.179164 -23.107396)
		(end 80.179164 -22.573996)
		(width 0.14224)
		(layer "In4.Cu")
		(net "M_H_CKE<2>")
	)
	(segment
		(start 80.356964 -17.134586)
		(end 80.264254 -17.041876)
		(width 0.14224)
		(layer "In4.Cu")
		(net "M_H_CKE<2>")
	)
	(segment
		(start 86.70417 -51.328828)
		(end 87.245444 -50.787554)
		(width 0.0889)
		(layer "In4.Cu")
		(net "M_H_CKE<2>")
	)
	(segment
		(start 86.923372 -54.104286)
		(end 86.593934 -53.343302)
		(width 0.0889)
		(layer "In4.Cu")
		(net "M_H_CKE<2>")
	)
	(arc
		(start 86.576662 -52.913534)
		(mid 86.655884 -52.624416)
		(end 86.583012 -52.333652)
		(width 0.0889)
		(layer "In4.Cu")
		(net "M_H_CKE<2>")
	)
	(arc
		(start 86.569804 -52.310792)
		(mid 86.523128 -52.116091)
		(end 86.576662 -51.923188)
		(width 0.0889)
		(layer "In4.Cu")
		(net "M_H_CKE<2>")
	)
	(arc
		(start 86.576662 -51.923188)
		(mid 86.67177 -51.693192)
		(end 86.70417 -51.44643)
		(width 0.0889)
		(layer "In4.Cu")
		(net "M_H_CKE<2>")
	)
	(arc
		(start 86.571836 -53.304948)
		(mid 86.523081 -53.108596)
		(end 86.576662 -52.913534)
		(width 0.0889)
		(layer "In4.Cu")
		(net "M_H_CKE<2>")
	)
	(segment
		(start 78.999334 -10.422382)
		(end 78.999334 -9.133078)
		(width 0.1651)
		(layer "F.Cu")
		(net "M_H_CKE<1>")
	)
	(segment
		(start 86.636352 -56.58104)
		(end 86.064852 -56.58104)
		(width 0.1016)
		(layer "F.Cu")
		(net "M_H_CKE<1>")
	)
	(via
		(at 78.999334 -9.133078)
		(size 0.4572)
		(drill 0.2032)
		(layers "F.Cu" "B.Cu")
		(net "M_H_CKE<1>")
	)
	(via
		(at 86.064852 -56.58104)
		(size 0.508)
		(drill 0.254)
		(layers "F.Cu" "B.Cu")
		(net "M_H_CKE<1>")
	)
	(segment
		(start 86.385654 -50.645314)
		(end 86.385654 -50.26279)
		(width 0.0889)
		(layer "In4.Cu")
		(net "M_H_CKE<1>")
	)
	(segment
		(start 78.737968 -12.5984)
		(end 78.585568 -12.446)
		(width 0.14224)
		(layer "In4.Cu")
		(net "M_H_CKE<1>")
	)
	(segment
		(start 78.756764 -23.851616)
		(end 78.756764 -23.437596)
		(width 0.14224)
		(layer "In4.Cu")
		(net "M_H_CKE<1>")
	)
	(segment
		(start 86.064852 -56.58104)
		(end 85.735414 -55.820056)
		(width 0.0889)
		(layer "In4.Cu")
		(net "M_H_CKE<1>")
	)
	(segment
		(start 78.502764 -23.183596)
		(end 78.502764 -22.662896)
		(width 0.14224)
		(layer "In4.Cu")
		(net "M_H_CKE<1>")
	)
	(segment
		(start 85.724492 -54.810406)
		(end 85.718142 -54.799738)
		(width 0.0889)
		(layer "In4.Cu")
		(net "M_H_CKE<1>")
	)
	(segment
		(start 80.269334 -25.364186)
		(end 78.756764 -23.851616)
		(width 0.14224)
		(layer "In4.Cu")
		(net "M_H_CKE<1>")
	)
	(segment
		(start 78.756764 -21.964396)
		(end 78.502764 -21.710396)
		(width 0.14224)
		(layer "In4.Cu")
		(net "M_H_CKE<1>")
	)
	(segment
		(start 78.502764 -21.710396)
		(end 78.502764 -19.082258)
		(width 0.14224)
		(layer "In4.Cu")
		(net "M_H_CKE<1>")
	)
	(segment
		(start 78.737968 -13.10894)
		(end 78.737968 -12.5984)
		(width 0.14224)
		(layer "In4.Cu")
		(net "M_H_CKE<1>")
	)
	(segment
		(start 78.590648 -18.46707)
		(end 78.756764 -18.300954)
		(width 0.14224)
		(layer "In4.Cu")
		(net "M_H_CKE<1>")
	)
	(segment
		(start 78.756764 -17.159986)
		(end 78.566264 -16.969486)
		(width 0.14224)
		(layer "In4.Cu")
		(net "M_H_CKE<1>")
	)
	(segment
		(start 85.664802 -54.610254)
		(end 85.662008 -54.50332)
		(width 0.0889)
		(layer "In4.Cu")
		(net "M_H_CKE<1>")
	)
	(segment
		(start 86.385654 -50.26279)
		(end 86.385654 -33.963864)
		(width 0.14224)
		(layer "In4.Cu")
		(net "M_H_CKE<1>")
	)
	(segment
		(start 78.585568 -9.546844)
		(end 78.999334 -9.133078)
		(width 0.14224)
		(layer "In4.Cu")
		(net "M_H_CKE<1>")
	)
	(segment
		(start 78.502764 -22.662896)
		(end 78.756764 -22.408896)
		(width 0.14224)
		(layer "In4.Cu")
		(net "M_H_CKE<1>")
	)
	(segment
		(start 78.566264 -16.969486)
		(end 78.566264 -13.280644)
		(width 0.14224)
		(layer "In4.Cu")
		(net "M_H_CKE<1>")
	)
	(segment
		(start 86.385654 -33.963864)
		(end 80.269334 -27.847544)
		(width 0.14224)
		(layer "In4.Cu")
		(net "M_H_CKE<1>")
	)
	(segment
		(start 78.756764 -22.408896)
		(end 78.756764 -21.964396)
		(width 0.14224)
		(layer "In4.Cu")
		(net "M_H_CKE<1>")
	)
	(segment
		(start 78.585568 -12.446)
		(end 78.585568 -9.546844)
		(width 0.14224)
		(layer "In4.Cu")
		(net "M_H_CKE<1>")
	)
	(segment
		(start 85.662008 -54.50332)
		(end 85.662008 -51.36896)
		(width 0.0889)
		(layer "In4.Cu")
		(net "M_H_CKE<1>")
	)
	(segment
		(start 85.662008 -51.36896)
		(end 86.385654 -50.645314)
		(width 0.0889)
		(layer "In4.Cu")
		(net "M_H_CKE<1>")
	)
	(segment
		(start 78.756764 -18.300954)
		(end 78.756764 -17.159986)
		(width 0.14224)
		(layer "In4.Cu")
		(net "M_H_CKE<1>")
	)
	(segment
		(start 78.566264 -13.280644)
		(end 78.737968 -13.10894)
		(width 0.14224)
		(layer "In4.Cu")
		(net "M_H_CKE<1>")
	)
	(segment
		(start 78.502764 -19.082258)
		(end 78.590648 -18.994374)
		(width 0.14224)
		(layer "In4.Cu")
		(net "M_H_CKE<1>")
	)
	(segment
		(start 78.756764 -23.437596)
		(end 78.502764 -23.183596)
		(width 0.14224)
		(layer "In4.Cu")
		(net "M_H_CKE<1>")
	)
	(segment
		(start 78.590648 -18.994374)
		(end 78.590648 -18.46707)
		(width 0.14224)
		(layer "In4.Cu")
		(net "M_H_CKE<1>")
	)
	(segment
		(start 80.269334 -27.847544)
		(end 80.269334 -25.364186)
		(width 0.14224)
		(layer "In4.Cu")
		(net "M_H_CKE<1>")
	)
	(segment
		(start 85.735414 -55.820056)
		(end 85.713316 -55.781702)
		(width 0.0889)
		(layer "In4.Cu")
		(net "M_H_CKE<1>")
	)
	(arc
		(start 85.718142 -55.390288)
		(mid 85.797364 -55.10117)
		(end 85.724492 -54.810406)
		(width 0.0889)
		(layer "In4.Cu")
		(net "M_H_CKE<1>")
	)
	(arc
		(start 85.718142 -54.799738)
		(mid 85.679628 -54.708329)
		(end 85.664802 -54.610254)
		(width 0.0889)
		(layer "In4.Cu")
		(net "M_H_CKE<1>")
	)
	(arc
		(start 85.713316 -55.781702)
		(mid 85.664561 -55.58535)
		(end 85.718142 -55.390288)
		(width 0.0889)
		(layer "In4.Cu")
		(net "M_H_CKE<1>")
	)
	(segment
		(start 88.353392 -55.59044)
		(end 87.781892 -55.59044)
		(width 0.1016)
		(layer "F.Cu")
		(net "M_H_CKE<0>")
	)
	(segment
		(start 79.849472 -5.822442)
		(end 79.849472 -7.115556)
		(width 0.1651)
		(layer "F.Cu")
		(net "M_H_CKE<0>")
	)
	(via
		(at 87.781892 -55.59044)
		(size 0.508)
		(drill 0.254)
		(layers "F.Cu" "B.Cu")
		(net "M_H_CKE<0>")
	)
	(via
		(at 79.849472 -7.115556)
		(size 0.4572)
		(drill 0.2032)
		(layers "F.Cu" "B.Cu")
		(net "M_H_CKE<0>")
	)
	(segment
		(start 81.042764 -21.888196)
		(end 81.195164 -21.735796)
		(width 0.14224)
		(layer "In4.Cu")
		(net "M_H_CKE<0>")
	)
	(segment
		(start 81.139792 -16.499078)
		(end 80.871568 -16.230854)
		(width 0.14224)
		(layer "In4.Cu")
		(net "M_H_CKE<0>")
	)
	(segment
		(start 87.184992 -51.775614)
		(end 87.184992 -51.328828)
		(width 0.0889)
		(layer "In4.Cu")
		(net "M_H_CKE<0>")
	)
	(segment
		(start 79.849472 -8.268716)
		(end 79.849472 -7.115556)
		(width 0.14224)
		(layer "In4.Cu")
		(net "M_H_CKE<0>")
	)
	(segment
		(start 80.287368 -12.63396)
		(end 80.287368 -8.706612)
		(width 0.14224)
		(layer "In4.Cu")
		(net "M_H_CKE<0>")
	)
	(segment
		(start 81.195164 -21.278596)
		(end 81.112868 -21.1963)
		(width 0.14224)
		(layer "In4.Cu")
		(net "M_H_CKE<0>")
	)
	(segment
		(start 80.991964 -17.236186)
		(end 81.139792 -17.088358)
		(width 0.14224)
		(layer "In4.Cu")
		(net "M_H_CKE<0>")
	)
	(segment
		(start 80.871568 -14.74724)
		(end 80.261968 -14.13764)
		(width 0.14224)
		(layer "In4.Cu")
		(net "M_H_CKE<0>")
	)
	(segment
		(start 80.871568 -16.230854)
		(end 80.871568 -14.74724)
		(width 0.14224)
		(layer "In4.Cu")
		(net "M_H_CKE<0>")
	)
	(segment
		(start 87.781892 -55.59044)
		(end 87.744554 -55.553102)
		(width 0.0889)
		(layer "In4.Cu")
		(net "M_H_CKE<0>")
	)
	(segment
		(start 80.261968 -14.13764)
		(end 80.261968 -12.65936)
		(width 0.14224)
		(layer "In4.Cu")
		(net "M_H_CKE<0>")
	)
	(segment
		(start 87.351108 -55.037228)
		(end 87.270082 -54.894988)
		(width 0.0889)
		(layer "In4.Cu")
		(net "M_H_CKE<0>")
	)
	(segment
		(start 81.139792 -17.088358)
		(end 81.139792 -16.499078)
		(width 0.14224)
		(layer "In4.Cu")
		(net "M_H_CKE<0>")
	)
	(segment
		(start 87.639398 -32.77743)
		(end 81.87182 -27.009852)
		(width 0.14224)
		(layer "In4.Cu")
		(net "M_H_CKE<0>")
	)
	(segment
		(start 81.195164 -23.107396)
		(end 81.195164 -22.599396)
		(width 0.14224)
		(layer "In4.Cu")
		(net "M_H_CKE<0>")
	)
	(segment
		(start 87.270082 -53.904388)
		(end 87.263732 -53.89372)
		(width 0.0889)
		(layer "In4.Cu")
		(net "M_H_CKE<0>")
	)
	(segment
		(start 81.112868 -21.1963)
		(end 81.112868 -17.68729)
		(width 0.14224)
		(layer "In4.Cu")
		(net "M_H_CKE<0>")
	)
	(segment
		(start 81.87182 -24.810974)
		(end 81.042764 -23.981918)
		(width 0.14224)
		(layer "In4.Cu")
		(net "M_H_CKE<0>")
	)
	(segment
		(start 81.87182 -27.009852)
		(end 81.87182 -24.810974)
		(width 0.14224)
		(layer "In4.Cu")
		(net "M_H_CKE<0>")
	)
	(segment
		(start 87.263732 -52.333906)
		(end 87.270082 -52.323238)
		(width 0.0889)
		(layer "In4.Cu")
		(net "M_H_CKE<0>")
	)
	(segment
		(start 87.639398 -50.379884)
		(end 87.639398 -32.77743)
		(width 0.14224)
		(layer "In4.Cu")
		(net "M_H_CKE<0>")
	)
	(segment
		(start 81.195164 -22.599396)
		(end 81.042764 -22.446996)
		(width 0.14224)
		(layer "In4.Cu")
		(net "M_H_CKE<0>")
	)
	(segment
		(start 81.042764 -22.446996)
		(end 81.042764 -21.888196)
		(width 0.14224)
		(layer "In4.Cu")
		(net "M_H_CKE<0>")
	)
	(segment
		(start 81.195164 -21.735796)
		(end 81.195164 -21.278596)
		(width 0.14224)
		(layer "In4.Cu")
		(net "M_H_CKE<0>")
	)
	(segment
		(start 87.270082 -54.894988)
		(end 87.263732 -54.88432)
		(width 0.0889)
		(layer "In4.Cu")
		(net "M_H_CKE<0>")
	)
	(segment
		(start 87.270082 -51.923442)
		(end 87.184992 -51.775614)
		(width 0.0889)
		(layer "In4.Cu")
		(net "M_H_CKE<0>")
	)
	(segment
		(start 81.042764 -23.259796)
		(end 81.195164 -23.107396)
		(width 0.14224)
		(layer "In4.Cu")
		(net "M_H_CKE<0>")
	)
	(segment
		(start 81.112868 -17.68729)
		(end 80.991964 -17.566386)
		(width 0.14224)
		(layer "In4.Cu")
		(net "M_H_CKE<0>")
	)
	(segment
		(start 80.287368 -8.706612)
		(end 79.849472 -8.268716)
		(width 0.14224)
		(layer "In4.Cu")
		(net "M_H_CKE<0>")
	)
	(segment
		(start 80.261968 -12.65936)
		(end 80.287368 -12.63396)
		(width 0.14224)
		(layer "In4.Cu")
		(net "M_H_CKE<0>")
	)
	(segment
		(start 87.184992 -51.328828)
		(end 87.639398 -50.874422)
		(width 0.0889)
		(layer "In4.Cu")
		(net "M_H_CKE<0>")
	)
	(segment
		(start 87.639398 -50.874422)
		(end 87.639398 -50.379884)
		(width 0.0889)
		(layer "In4.Cu")
		(net "M_H_CKE<0>")
	)
	(segment
		(start 81.042764 -23.981918)
		(end 81.042764 -23.259796)
		(width 0.14224)
		(layer "In4.Cu")
		(net "M_H_CKE<0>")
	)
	(segment
		(start 87.274908 -52.922424)
		(end 87.270082 -52.913788)
		(width 0.0889)
		(layer "In4.Cu")
		(net "M_H_CKE<0>")
	)
	(segment
		(start 87.274908 -53.913024)
		(end 87.270082 -53.904388)
		(width 0.0889)
		(layer "In4.Cu")
		(net "M_H_CKE<0>")
	)
	(segment
		(start 80.991964 -17.566386)
		(end 80.991964 -17.236186)
		(width 0.14224)
		(layer "In4.Cu")
		(net "M_H_CKE<0>")
	)
	(arc
		(start 87.270082 -53.313838)
		(mid 87.323552 -53.118775)
		(end 87.274908 -52.922424)
		(width 0.0889)
		(layer "In4.Cu")
		(net "M_H_CKE<0>")
	)
	(arc
		(start 87.263732 -53.89372)
		(mid 87.190934 -53.602957)
		(end 87.270082 -53.313838)
		(width 0.0889)
		(layer "In4.Cu")
		(net "M_H_CKE<0>")
	)
	(arc
		(start 87.270082 -52.323238)
		(mid 87.323581 -52.12334)
		(end 87.270082 -51.923442)
		(width 0.0889)
		(layer "In4.Cu")
		(net "M_H_CKE<0>")
	)
	(arc
		(start 87.263732 -54.88432)
		(mid 87.190934 -54.593557)
		(end 87.270082 -54.304438)
		(width 0.0889)
		(layer "In4.Cu")
		(net "M_H_CKE<0>")
	)
	(arc
		(start 87.270082 -54.304438)
		(mid 87.323552 -54.109375)
		(end 87.274908 -53.913024)
		(width 0.0889)
		(layer "In4.Cu")
		(net "M_H_CKE<0>")
	)
	(arc
		(start 87.270082 -52.913788)
		(mid 87.19086 -52.62467)
		(end 87.263732 -52.333906)
		(width 0.0889)
		(layer "In4.Cu")
		(net "M_H_CKE<0>")
	)
	(arc
		(start 87.744554 -55.553102)
		(mid 87.530555 -55.308341)
		(end 87.351108 -55.037228)
		(width 0.0889)
		(layer "In4.Cu")
		(net "M_H_CKE<0>")
	)
	(segment
		(start 111.299498 -9.133586)
		(end 111.300006 -9.133078)
		(width 0.10795)
		(layer "F.Cu")
		(net "M_H_C<2>")
	)
	(segment
		(start 111.299498 -10.422382)
		(end 111.299498 -9.133586)
		(width 0.10795)
		(layer "F.Cu")
		(net "M_H_C<2>")
	)
	(segment
		(start 101.230684 -55.094886)
		(end 100.659184 -55.094886)
		(width 0.1016)
		(layer "F.Cu")
		(net "M_H_C<2>")
	)
	(via
		(at 100.659184 -55.094886)
		(size 0.508)
		(drill 0.254)
		(layers "F.Cu" "B.Cu")
		(net "M_H_C<2>")
	)
	(via
		(at 111.300006 -11.918188)
		(size 0.4572)
		(drill 0.2032)
		(layers "F.Cu" "B.Cu")
		(net "M_H_C<2>")
	)
	(via
		(at 111.300006 -9.133078)
		(size 0.4572)
		(drill 0.2032)
		(layers "F.Cu" "B.Cu")
		(net "M_H_C<2>")
	)
	(segment
		(start 111.299498 -11.91768)
		(end 111.300006 -11.918188)
		(width 0.10795)
		(layer "B.Cu")
		(net "M_H_C<2>")
	)
	(segment
		(start 111.299498 -10.623042)
		(end 111.299498 -11.91768)
		(width 0.10795)
		(layer "B.Cu")
		(net "M_H_C<2>")
	)
	(segment
		(start 109.878368 -22.479)
		(end 109.878368 -21.8948)
		(width 0.14224)
		(layer "In11.Cu")
		(net "M_H_C<2>")
	)
	(segment
		(start 102.336092 -35.273742)
		(end 109.649768 -27.960066)
		(width 0.14224)
		(layer "In11.Cu")
		(net "M_H_C<2>")
	)
	(segment
		(start 100.328984 -54.33314)
		(end 100.312474 -54.304692)
		(width 0.0889)
		(layer "In11.Cu")
		(net "M_H_C<2>")
	)
	(segment
		(start 109.929168 -19.4691)
		(end 110.036864 -19.361404)
		(width 0.14224)
		(layer "In11.Cu")
		(net "M_H_C<2>")
	)
	(segment
		(start 100.312474 -52.914296)
		(end 101.107494 -51.555142)
		(width 0.0889)
		(layer "In11.Cu")
		(net "M_H_C<2>")
	)
	(segment
		(start 110.776512 -13.097256)
		(end 111.299498 -12.57427)
		(width 0.14224)
		(layer "In11.Cu")
		(net "M_H_C<2>")
	)
	(segment
		(start 110.081568 -21.6916)
		(end 110.081568 -21.2598)
		(width 0.14224)
		(layer "In11.Cu")
		(net "M_H_C<2>")
	)
	(segment
		(start 109.667294 -18.02638)
		(end 109.667294 -17.330166)
		(width 0.14224)
		(layer "In11.Cu")
		(net "M_H_C<2>")
	)
	(segment
		(start 111.300006 -11.918188)
		(end 110.868968 -11.48715)
		(width 0.14224)
		(layer "In11.Cu")
		(net "M_H_C<2>")
	)
	(segment
		(start 101.107494 -51.555142)
		(end 101.581712 -49.787048)
		(width 0.0889)
		(layer "In11.Cu")
		(net "M_H_C<2>")
	)
	(segment
		(start 110.868968 -11.48715)
		(end 110.868968 -9.564116)
		(width 0.14224)
		(layer "In11.Cu")
		(net "M_H_C<2>")
	)
	(segment
		(start 109.649768 -27.960066)
		(end 109.649768 -26.1112)
		(width 0.14224)
		(layer "In11.Cu")
		(net "M_H_C<2>")
	)
	(segment
		(start 110.885478 -13.68171)
		(end 110.776512 -13.572744)
		(width 0.14224)
		(layer "In11.Cu")
		(net "M_H_C<2>")
	)
	(segment
		(start 109.929168 -23.7744)
		(end 109.929168 -23.2918)
		(width 0.14224)
		(layer "In11.Cu")
		(net "M_H_C<2>")
	)
	(segment
		(start 101.581712 -49.787048)
		(end 102.336092 -49.032668)
		(width 0.0889)
		(layer "In11.Cu")
		(net "M_H_C<2>")
	)
	(segment
		(start 110.868968 -9.564116)
		(end 111.300006 -9.133078)
		(width 0.14224)
		(layer "In11.Cu")
		(net "M_H_C<2>")
	)
	(segment
		(start 111.299498 -12.57427)
		(end 111.299498 -11.918696)
		(width 0.14224)
		(layer "In11.Cu")
		(net "M_H_C<2>")
	)
	(segment
		(start 110.036864 -19.361404)
		(end 110.036864 -18.39595)
		(width 0.14224)
		(layer "In11.Cu")
		(net "M_H_C<2>")
	)
	(segment
		(start 109.649768 -26.1112)
		(end 110.056168 -25.7048)
		(width 0.14224)
		(layer "In11.Cu")
		(net "M_H_C<2>")
	)
	(segment
		(start 110.036864 -16.960596)
		(end 110.036864 -16.38173)
		(width 0.14224)
		(layer "In11.Cu")
		(net "M_H_C<2>")
	)
	(segment
		(start 102.336092 -48.641)
		(end 102.336092 -35.273742)
		(width 0.14224)
		(layer "In11.Cu")
		(net "M_H_C<2>")
	)
	(segment
		(start 110.056168 -25.7048)
		(end 110.056168 -23.9014)
		(width 0.14224)
		(layer "In11.Cu")
		(net "M_H_C<2>")
	)
	(segment
		(start 111.299498 -11.918696)
		(end 111.300006 -11.918188)
		(width 0.14224)
		(layer "In11.Cu")
		(net "M_H_C<2>")
	)
	(segment
		(start 109.929168 -23.2918)
		(end 110.081568 -23.1394)
		(width 0.14224)
		(layer "In11.Cu")
		(net "M_H_C<2>")
	)
	(segment
		(start 110.081568 -23.1394)
		(end 110.081568 -22.6822)
		(width 0.14224)
		(layer "In11.Cu")
		(net "M_H_C<2>")
	)
	(segment
		(start 102.336092 -49.032668)
		(end 102.336092 -48.641)
		(width 0.0889)
		(layer "In11.Cu")
		(net "M_H_C<2>")
	)
	(segment
		(start 110.885478 -15.533116)
		(end 110.885478 -13.68171)
		(width 0.14224)
		(layer "In11.Cu")
		(net "M_H_C<2>")
	)
	(segment
		(start 110.776512 -13.572744)
		(end 110.776512 -13.097256)
		(width 0.14224)
		(layer "In11.Cu")
		(net "M_H_C<2>")
	)
	(segment
		(start 110.081568 -21.2598)
		(end 109.929168 -21.1074)
		(width 0.14224)
		(layer "In11.Cu")
		(net "M_H_C<2>")
	)
	(segment
		(start 110.056168 -23.9014)
		(end 109.929168 -23.7744)
		(width 0.14224)
		(layer "In11.Cu")
		(net "M_H_C<2>")
	)
	(segment
		(start 110.081568 -22.6822)
		(end 109.878368 -22.479)
		(width 0.14224)
		(layer "In11.Cu")
		(net "M_H_C<2>")
	)
	(segment
		(start 110.036864 -18.39595)
		(end 109.667294 -18.02638)
		(width 0.14224)
		(layer "In11.Cu")
		(net "M_H_C<2>")
	)
	(segment
		(start 100.659184 -55.094886)
		(end 100.328984 -54.33314)
		(width 0.0889)
		(layer "In11.Cu")
		(net "M_H_C<2>")
	)
	(segment
		(start 109.878368 -21.8948)
		(end 110.081568 -21.6916)
		(width 0.14224)
		(layer "In11.Cu")
		(net "M_H_C<2>")
	)
	(segment
		(start 109.667294 -17.330166)
		(end 110.036864 -16.960596)
		(width 0.14224)
		(layer "In11.Cu")
		(net "M_H_C<2>")
	)
	(segment
		(start 110.036864 -16.38173)
		(end 110.885478 -15.533116)
		(width 0.14224)
		(layer "In11.Cu")
		(net "M_H_C<2>")
	)
	(segment
		(start 109.929168 -21.1074)
		(end 109.929168 -19.4691)
		(width 0.14224)
		(layer "In11.Cu")
		(net "M_H_C<2>")
	)
	(arc
		(start 100.312474 -54.304692)
		(mid 100.258975 -54.104794)
		(end 100.312474 -53.904896)
		(width 0.0889)
		(layer "In11.Cu")
		(net "M_H_C<2>")
	)
	(arc
		(start 100.312474 -53.314092)
		(mid 100.258975 -53.114194)
		(end 100.312474 -52.914296)
		(width 0.0889)
		(layer "In11.Cu")
		(net "M_H_C<2>")
	)
	(arc
		(start 100.312474 -53.904896)
		(mid 100.391605 -53.609494)
		(end 100.312474 -53.314092)
		(width 0.0889)
		(layer "In11.Cu")
		(net "M_H_C<2>")
	)
	(segment
		(start 82.399378 -10.422382)
		(end 82.399378 -9.133078)
		(width 0.1651)
		(layer "F.Cu")
		(net "M_H_BG<1>")
	)
	(segment
		(start 90.070178 -55.59044)
		(end 89.498678 -55.59044)
		(width 0.1016)
		(layer "F.Cu")
		(net "M_H_BG<1>")
	)
	(via
		(at 89.498678 -55.59044)
		(size 0.508)
		(drill 0.254)
		(layers "F.Cu" "B.Cu")
		(net "M_H_BG<1>")
	)
	(via
		(at 82.399378 -11.916156)
		(size 0.4572)
		(drill 0.2032)
		(layers "F.Cu" "B.Cu")
		(net "M_H_BG<1>")
	)
	(via
		(at 82.399378 -9.133078)
		(size 0.4572)
		(drill 0.2032)
		(layers "F.Cu" "B.Cu")
		(net "M_H_BG<1>")
	)
	(segment
		(start 82.399378 -10.623042)
		(end 82.399378 -11.916156)
		(width 0.1651)
		(layer "B.Cu")
		(net "M_H_BG<1>")
	)
	(segment
		(start 86.332568 -18.288)
		(end 86.332568 -17.098264)
		(width 0.14224)
		(layer "In11.Cu")
		(net "M_H_BG<1>")
	)
	(segment
		(start 82.941922 -14.414754)
		(end 82.814668 -14.2875)
		(width 0.14224)
		(layer "In11.Cu")
		(net "M_H_BG<1>")
	)
	(segment
		(start 86.662768 -28.016454)
		(end 86.459568 -27.813254)
		(width 0.14224)
		(layer "In11.Cu")
		(net "M_H_BG<1>")
	)
	(segment
		(start 86.209378 -18.41119)
		(end 86.332568 -18.288)
		(width 0.14224)
		(layer "In11.Cu")
		(net "M_H_BG<1>")
	)
	(segment
		(start 88.947752 -50.62347)
		(end 88.947752 -32.663384)
		(width 0.14224)
		(layer "In11.Cu")
		(net "M_H_BG<1>")
	)
	(segment
		(start 86.992968 -27.000454)
		(end 86.992968 -26.6446)
		(width 0.14224)
		(layer "In11.Cu")
		(net "M_H_BG<1>")
	)
	(segment
		(start 86.992968 -28.219654)
		(end 86.789768 -28.016454)
		(width 0.14224)
		(layer "In11.Cu")
		(net "M_H_BG<1>")
	)
	(segment
		(start 85.955886 -16.129254)
		(end 83.62696 -16.129254)
		(width 0.14224)
		(layer "In11.Cu")
		(net "M_H_BG<1>")
	)
	(segment
		(start 89.498678 -55.59044)
		(end 89.003124 -54.92369)
		(width 0.0889)
		(layer "In11.Cu")
		(net "M_H_BG<1>")
	)
	(segment
		(start 86.103968 -23.6474)
		(end 86.103968 -23.3172)
		(width 0.14224)
		(layer "In11.Cu")
		(net "M_H_BG<1>")
	)
	(segment
		(start 88.986868 -53.904388)
		(end 88.977978 -53.889148)
		(width 0.0889)
		(layer "In11.Cu")
		(net "M_H_BG<1>")
	)
	(segment
		(start 89.050368 -53.076856)
		(end 89.050368 -50.927)
		(width 0.0889)
		(layer "In11.Cu")
		(net "M_H_BG<1>")
	)
	(segment
		(start 88.947752 -32.663384)
		(end 86.992968 -30.7086)
		(width 0.14224)
		(layer "In11.Cu")
		(net "M_H_BG<1>")
	)
	(segment
		(start 86.789768 -28.016454)
		(end 86.662768 -28.016454)
		(width 0.14224)
		(layer "In11.Cu")
		(net "M_H_BG<1>")
	)
	(segment
		(start 89.050368 -50.927)
		(end 88.947752 -50.824384)
		(width 0.0889)
		(layer "In11.Cu")
		(net "M_H_BG<1>")
	)
	(segment
		(start 86.332568 -23.0886)
		(end 86.332568 -22.5806)
		(width 0.14224)
		(layer "In11.Cu")
		(net "M_H_BG<1>")
	)
	(segment
		(start 86.662768 -27.203654)
		(end 86.789768 -27.203654)
		(width 0.14224)
		(layer "In11.Cu")
		(net "M_H_BG<1>")
	)
	(segment
		(start 86.789768 -27.203654)
		(end 86.992968 -27.000454)
		(width 0.14224)
		(layer "In11.Cu")
		(net "M_H_BG<1>")
	)
	(segment
		(start 82.814668 -12.9159)
		(end 82.399378 -12.50061)
		(width 0.14224)
		(layer "In11.Cu")
		(net "M_H_BG<1>")
	)
	(segment
		(start 86.230968 -25.8826)
		(end 86.230968 -23.7744)
		(width 0.14224)
		(layer "In11.Cu")
		(net "M_H_BG<1>")
	)
	(segment
		(start 82.941922 -15.444216)
		(end 82.941922 -14.414754)
		(width 0.14224)
		(layer "In11.Cu")
		(net "M_H_BG<1>")
	)
	(segment
		(start 86.332568 -19.2278)
		(end 86.209378 -19.10461)
		(width 0.14224)
		(layer "In11.Cu")
		(net "M_H_BG<1>")
	)
	(segment
		(start 86.236302 -16.40967)
		(end 85.955886 -16.129254)
		(width 0.14224)
		(layer "In11.Cu")
		(net "M_H_BG<1>")
	)
	(segment
		(start 86.459568 -27.406854)
		(end 86.662768 -27.203654)
		(width 0.14224)
		(layer "In11.Cu")
		(net "M_H_BG<1>")
	)
	(segment
		(start 82.399378 -11.916156)
		(end 82.399378 -9.133078)
		(width 0.14224)
		(layer "In11.Cu")
		(net "M_H_BG<1>")
	)
	(segment
		(start 86.332568 -17.098264)
		(end 86.236302 -17.001998)
		(width 0.14224)
		(layer "In11.Cu")
		(net "M_H_BG<1>")
	)
	(segment
		(start 88.947752 -50.824384)
		(end 88.947752 -50.62347)
		(width 0.0889)
		(layer "In11.Cu")
		(net "M_H_BG<1>")
	)
	(segment
		(start 89.003124 -54.92369)
		(end 88.977978 -54.879748)
		(width 0.0889)
		(layer "In11.Cu")
		(net "M_H_BG<1>")
	)
	(segment
		(start 82.399378 -12.50061)
		(end 82.399378 -11.916156)
		(width 0.14224)
		(layer "In11.Cu")
		(net "M_H_BG<1>")
	)
	(segment
		(start 86.236302 -17.001998)
		(end 86.236302 -16.40967)
		(width 0.14224)
		(layer "In11.Cu")
		(net "M_H_BG<1>")
	)
	(segment
		(start 86.209378 -19.10461)
		(end 86.209378 -18.41119)
		(width 0.14224)
		(layer "In11.Cu")
		(net "M_H_BG<1>")
	)
	(segment
		(start 86.332568 -22.5806)
		(end 86.180168 -22.4282)
		(width 0.14224)
		(layer "In11.Cu")
		(net "M_H_BG<1>")
	)
	(segment
		(start 86.992968 -30.7086)
		(end 86.992968 -28.219654)
		(width 0.14224)
		(layer "In11.Cu")
		(net "M_H_BG<1>")
	)
	(segment
		(start 83.62696 -16.129254)
		(end 82.941922 -15.444216)
		(width 0.14224)
		(layer "In11.Cu")
		(net "M_H_BG<1>")
	)
	(segment
		(start 86.230968 -23.7744)
		(end 86.103968 -23.6474)
		(width 0.14224)
		(layer "In11.Cu")
		(net "M_H_BG<1>")
	)
	(segment
		(start 82.814668 -14.2875)
		(end 82.814668 -12.9159)
		(width 0.14224)
		(layer "In11.Cu")
		(net "M_H_BG<1>")
	)
	(segment
		(start 86.180168 -21.9456)
		(end 86.332568 -21.7932)
		(width 0.14224)
		(layer "In11.Cu")
		(net "M_H_BG<1>")
	)
	(segment
		(start 86.103968 -23.3172)
		(end 86.332568 -23.0886)
		(width 0.14224)
		(layer "In11.Cu")
		(net "M_H_BG<1>")
	)
	(segment
		(start 86.180168 -22.4282)
		(end 86.180168 -21.9456)
		(width 0.14224)
		(layer "In11.Cu")
		(net "M_H_BG<1>")
	)
	(segment
		(start 86.459568 -27.813254)
		(end 86.459568 -27.406854)
		(width 0.14224)
		(layer "In11.Cu")
		(net "M_H_BG<1>")
	)
	(segment
		(start 86.332568 -21.7932)
		(end 86.332568 -19.2278)
		(width 0.14224)
		(layer "In11.Cu")
		(net "M_H_BG<1>")
	)
	(segment
		(start 86.992968 -26.6446)
		(end 86.230968 -25.8826)
		(width 0.14224)
		(layer "In11.Cu")
		(net "M_H_BG<1>")
	)
	(arc
		(start 88.986868 -53.313584)
		(mid 89.034173 -53.199397)
		(end 89.050368 -53.076856)
		(width 0.0889)
		(layer "In11.Cu")
		(net "M_H_BG<1>")
	)
	(arc
		(start 88.977978 -54.879748)
		(mid 88.907581 -54.590797)
		(end 88.986868 -54.304184)
		(width 0.0889)
		(layer "In11.Cu")
		(net "M_H_BG<1>")
	)
	(arc
		(start 88.977978 -53.889148)
		(mid 88.907581 -53.600197)
		(end 88.986868 -53.313584)
		(width 0.0889)
		(layer "In11.Cu")
		(net "M_H_BG<1>")
	)
	(arc
		(start 88.986868 -54.304184)
		(mid 89.040401 -54.104286)
		(end 88.986868 -53.904388)
		(width 0.0889)
		(layer "In11.Cu")
		(net "M_H_BG<1>")
	)
	(segment
		(start 89.211912 -55.094886)
		(end 88.640412 -55.094886)
		(width 0.1016)
		(layer "F.Cu")
		(net "M_H_BG<0>")
	)
	(segment
		(start 82.399378 -5.822442)
		(end 82.399378 -7.115556)
		(width 0.1651)
		(layer "F.Cu")
		(net "M_H_BG<0>")
	)
	(via
		(at 88.640412 -55.094886)
		(size 0.508)
		(drill 0.254)
		(layers "F.Cu" "B.Cu")
		(net "M_H_BG<0>")
	)
	(via
		(at 82.399378 -7.115556)
		(size 0.4572)
		(drill 0.2032)
		(layers "F.Cu" "B.Cu")
		(net "M_H_BG<0>")
	)
	(via
		(at 82.399378 -13.933678)
		(size 0.4572)
		(drill 0.2032)
		(layers "F.Cu" "B.Cu")
		(net "M_H_BG<0>")
	)
	(segment
		(start 82.399378 -15.222982)
		(end 82.399378 -13.933678)
		(width 0.1651)
		(layer "B.Cu")
		(net "M_H_BG<0>")
	)
	(segment
		(start 83.657948 -12.326874)
		(end 83.657948 -8.374126)
		(width 0.14224)
		(layer "In4.Cu")
		(net "M_H_BG<0>")
	)
	(segment
		(start 83.689698 -15.48257)
		(end 82.399378 -14.19225)
		(width 0.14224)
		(layer "In4.Cu")
		(net "M_H_BG<0>")
	)
	(segment
		(start 83.604608 -17.794986)
		(end 83.757008 -17.642586)
		(width 0.14224)
		(layer "In4.Cu")
		(net "M_H_BG<0>")
	)
	(segment
		(start 88.947752 -50.527712)
		(end 88.947752 -29.9085)
		(width 0.14224)
		(layer "In4.Cu")
		(net "M_H_BG<0>")
	)
	(segment
		(start 85.452966 -26.93543)
		(end 85.273134 -26.93543)
		(width 0.14224)
		(layer "In4.Cu")
		(net "M_H_BG<0>")
	)
	(segment
		(start 83.689698 -17.067276)
		(end 83.689698 -15.48257)
		(width 0.14224)
		(layer "In4.Cu")
		(net "M_H_BG<0>")
	)
	(segment
		(start 87.036402 -27.813254)
		(end 86.817454 -27.813254)
		(width 0.14224)
		(layer "In4.Cu")
		(net "M_H_BG<0>")
	)
	(segment
		(start 83.604608 -21.761196)
		(end 83.604608 -21.345906)
		(width 0.14224)
		(layer "In4.Cu")
		(net "M_H_BG<0>")
	)
	(segment
		(start 85.083904 -26.183336)
		(end 85.083904 -25.860756)
		(width 0.14224)
		(layer "In4.Cu")
		(net "M_H_BG<0>")
	)
	(segment
		(start 83.757008 -17.134586)
		(end 83.689698 -17.067276)
		(width 0.14224)
		(layer "In4.Cu")
		(net "M_H_BG<0>")
	)
	(segment
		(start 83.665822 -21.284692)
		(end 83.665822 -18.4404)
		(width 0.14224)
		(layer "In4.Cu")
		(net "M_H_BG<0>")
	)
	(segment
		(start 82.399378 -13.585444)
		(end 83.657948 -12.326874)
		(width 0.14224)
		(layer "In4.Cu")
		(net "M_H_BG<0>")
	)
	(segment
		(start 83.579208 -23.107396)
		(end 83.579208 -22.573996)
		(width 0.14224)
		(layer "In4.Cu")
		(net "M_H_BG<0>")
	)
	(segment
		(start 82.399378 -14.19225)
		(end 82.399378 -13.933678)
		(width 0.14224)
		(layer "In4.Cu")
		(net "M_H_BG<0>")
	)
	(segment
		(start 86.538816 -28.091892)
		(end 86.319868 -28.091892)
		(width 0.14224)
		(layer "In4.Cu")
		(net "M_H_BG<0>")
	)
	(segment
		(start 84.892388 -26.374852)
		(end 85.083904 -26.183336)
		(width 0.14224)
		(layer "In4.Cu")
		(net "M_H_BG<0>")
	)
	(segment
		(start 85.083904 -25.860756)
		(end 83.934808 -24.71166)
		(width 0.14224)
		(layer "In4.Cu")
		(net "M_H_BG<0>")
	)
	(segment
		(start 87.378032 -28.373832)
		(end 87.378032 -28.154884)
		(width 0.14224)
		(layer "In4.Cu")
		(net "M_H_BG<0>")
	)
	(segment
		(start 83.657948 -8.374126)
		(end 82.399378 -7.115556)
		(width 0.14224)
		(layer "In4.Cu")
		(net "M_H_BG<0>")
	)
	(segment
		(start 83.604608 -21.345906)
		(end 83.665822 -21.284692)
		(width 0.14224)
		(layer "In4.Cu")
		(net "M_H_BG<0>")
	)
	(segment
		(start 86.256876 -27.252676)
		(end 86.256876 -27.033728)
		(width 0.14224)
		(layer "In4.Cu")
		(net "M_H_BG<0>")
	)
	(segment
		(start 85.915246 -26.692098)
		(end 85.696298 -26.692098)
		(width 0.14224)
		(layer "In4.Cu")
		(net "M_H_BG<0>")
	)
	(segment
		(start 88.046052 -29.0068)
		(end 87.86622 -29.0068)
		(width 0.14224)
		(layer "In4.Cu")
		(net "M_H_BG<0>")
	)
	(segment
		(start 85.696298 -26.692098)
		(end 85.452966 -26.93543)
		(width 0.14224)
		(layer "In4.Cu")
		(net "M_H_BG<0>")
	)
	(segment
		(start 87.099394 -28.871418)
		(end 87.099394 -28.65247)
		(width 0.14224)
		(layer "In4.Cu")
		(net "M_H_BG<0>")
	)
	(segment
		(start 83.757008 -22.396196)
		(end 83.757008 -21.913596)
		(width 0.14224)
		(layer "In4.Cu")
		(net "M_H_BG<0>")
	)
	(segment
		(start 87.378032 -28.154884)
		(end 87.036402 -27.813254)
		(width 0.14224)
		(layer "In4.Cu")
		(net "M_H_BG<0>")
	)
	(segment
		(start 85.978238 -27.750262)
		(end 85.978238 -27.531314)
		(width 0.14224)
		(layer "In4.Cu")
		(net "M_H_BG<0>")
	)
	(segment
		(start 83.579208 -22.573996)
		(end 83.757008 -22.396196)
		(width 0.14224)
		(layer "In4.Cu")
		(net "M_H_BG<0>")
	)
	(segment
		(start 88.640412 -55.094886)
		(end 88.352884 -54.447694)
		(width 0.0889)
		(layer "In4.Cu")
		(net "M_H_BG<0>")
	)
	(segment
		(start 83.757008 -21.913596)
		(end 83.604608 -21.761196)
		(width 0.14224)
		(layer "In4.Cu")
		(net "M_H_BG<0>")
	)
	(segment
		(start 85.273134 -26.93543)
		(end 84.892388 -26.554684)
		(width 0.14224)
		(layer "In4.Cu")
		(net "M_H_BG<0>")
	)
	(segment
		(start 83.934808 -24.71166)
		(end 83.934808 -23.462996)
		(width 0.14224)
		(layer "In4.Cu")
		(net "M_H_BG<0>")
	)
	(segment
		(start 87.441024 -29.213048)
		(end 87.099394 -28.871418)
		(width 0.14224)
		(layer "In4.Cu")
		(net "M_H_BG<0>")
	)
	(segment
		(start 86.319868 -28.091892)
		(end 85.978238 -27.750262)
		(width 0.14224)
		(layer "In4.Cu")
		(net "M_H_BG<0>")
	)
	(segment
		(start 88.947752 -29.9085)
		(end 88.046052 -29.0068)
		(width 0.14224)
		(layer "In4.Cu")
		(net "M_H_BG<0>")
	)
	(segment
		(start 88.293702 -51.923696)
		(end 88.32723 -51.86553)
		(width 0.0889)
		(layer "In4.Cu")
		(net "M_H_BG<0>")
	)
	(segment
		(start 86.256876 -27.033728)
		(end 85.915246 -26.692098)
		(width 0.14224)
		(layer "In4.Cu")
		(net "M_H_BG<0>")
	)
	(segment
		(start 88.389968 -51.4096)
		(end 88.947752 -50.851816)
		(width 0.0889)
		(layer "In4.Cu")
		(net "M_H_BG<0>")
	)
	(segment
		(start 82.399378 -13.933678)
		(end 82.399378 -13.585444)
		(width 0.14224)
		(layer "In4.Cu")
		(net "M_H_BG<0>")
	)
	(segment
		(start 88.947752 -50.851816)
		(end 88.947752 -50.527712)
		(width 0.0889)
		(layer "In4.Cu")
		(net "M_H_BG<0>")
	)
	(segment
		(start 88.389968 -51.802792)
		(end 88.389968 -51.4096)
		(width 0.0889)
		(layer "In4.Cu")
		(net "M_H_BG<0>")
	)
	(segment
		(start 83.757008 -17.642586)
		(end 83.757008 -17.134586)
		(width 0.14224)
		(layer "In4.Cu")
		(net "M_H_BG<0>")
	)
	(segment
		(start 87.099394 -28.65247)
		(end 87.378032 -28.373832)
		(width 0.14224)
		(layer "In4.Cu")
		(net "M_H_BG<0>")
	)
	(segment
		(start 83.665822 -18.4404)
		(end 83.604608 -18.379186)
		(width 0.14224)
		(layer "In4.Cu")
		(net "M_H_BG<0>")
	)
	(segment
		(start 84.892388 -26.554684)
		(end 84.892388 -26.374852)
		(width 0.14224)
		(layer "In4.Cu")
		(net "M_H_BG<0>")
	)
	(segment
		(start 88.32723 -51.86553)
		(end 88.389968 -51.802792)
		(width 0.0889)
		(layer "In4.Cu")
		(net "M_H_BG<0>")
	)
	(segment
		(start 87.659972 -29.213048)
		(end 87.441024 -29.213048)
		(width 0.14224)
		(layer "In4.Cu")
		(net "M_H_BG<0>")
	)
	(segment
		(start 83.934808 -23.462996)
		(end 83.579208 -23.107396)
		(width 0.14224)
		(layer "In4.Cu")
		(net "M_H_BG<0>")
	)
	(segment
		(start 83.604608 -18.379186)
		(end 83.604608 -17.794986)
		(width 0.14224)
		(layer "In4.Cu")
		(net "M_H_BG<0>")
	)
	(segment
		(start 87.86622 -29.0068)
		(end 87.659972 -29.213048)
		(width 0.14224)
		(layer "In4.Cu")
		(net "M_H_BG<0>")
	)
	(segment
		(start 85.978238 -27.531314)
		(end 86.256876 -27.252676)
		(width 0.14224)
		(layer "In4.Cu")
		(net "M_H_BG<0>")
	)
	(segment
		(start 86.817454 -27.813254)
		(end 86.538816 -28.091892)
		(width 0.14224)
		(layer "In4.Cu")
		(net "M_H_BG<0>")
	)
	(arc
		(start 88.352884 -54.447694)
		(mid 88.327984 -54.374253)
		(end 88.293702 -54.304692)
		(width 0.0889)
		(layer "In4.Cu")
		(net "M_H_BG<0>")
	)
	(arc
		(start 88.293702 -52.914296)
		(mid 88.372833 -52.618894)
		(end 88.293702 -52.323492)
		(width 0.0889)
		(layer "In4.Cu")
		(net "M_H_BG<0>")
	)
	(arc
		(start 88.293702 -54.304692)
		(mid 88.240203 -54.104794)
		(end 88.293702 -53.904896)
		(width 0.0889)
		(layer "In4.Cu")
		(net "M_H_BG<0>")
	)
	(arc
		(start 88.293702 -53.314092)
		(mid 88.240203 -53.114194)
		(end 88.293702 -52.914296)
		(width 0.0889)
		(layer "In4.Cu")
		(net "M_H_BG<0>")
	)
	(arc
		(start 88.293702 -53.904896)
		(mid 88.372833 -53.609494)
		(end 88.293702 -53.314092)
		(width 0.0889)
		(layer "In4.Cu")
		(net "M_H_BG<0>")
	)
	(arc
		(start 88.293702 -52.323492)
		(mid 88.240203 -52.123594)
		(end 88.293702 -51.923696)
		(width 0.0889)
		(layer "In4.Cu")
		(net "M_H_BG<0>")
	)
	(segment
		(start 101.949504 -10.422382)
		(end 101.949504 -9.133332)
		(width 0.1651)
		(layer "F.Cu")
		(net "M_H_BA<1>")
	)
	(segment
		(start 94.362778 -54.104286)
		(end 93.791278 -54.104286)
		(width 0.1016)
		(layer "F.Cu")
		(net "M_H_BA<1>")
	)
	(segment
		(start 101.949504 -9.133332)
		(end 101.949758 -9.133078)
		(width 0.1651)
		(layer "F.Cu")
		(net "M_H_BA<1>")
	)
	(via
		(at 101.949758 -11.918188)
		(size 0.4572)
		(drill 0.2032)
		(layers "F.Cu" "B.Cu")
		(net "M_H_BA<1>")
	)
	(via
		(at 101.949758 -9.133078)
		(size 0.4572)
		(drill 0.2032)
		(layers "F.Cu" "B.Cu")
		(net "M_H_BA<1>")
	)
	(via
		(at 93.791278 -54.104286)
		(size 0.508)
		(drill 0.254)
		(layers "F.Cu" "B.Cu")
		(net "M_H_BA<1>")
	)
	(segment
		(start 101.949504 -10.623042)
		(end 101.949504 -11.917934)
		(width 0.1651)
		(layer "B.Cu")
		(net "M_H_BA<1>")
	)
	(segment
		(start 101.949504 -11.917934)
		(end 101.949758 -11.918188)
		(width 0.1651)
		(layer "B.Cu")
		(net "M_H_BA<1>")
	)
	(segment
		(start 98.981768 -15.4432)
		(end 99.743768 -14.6812)
		(width 0.14224)
		(layer "In11.Cu")
		(net "M_H_BA<1>")
	)
	(segment
		(start 95.025972 -30.509972)
		(end 95.585026 -29.950918)
		(width 0.14224)
		(layer "In11.Cu")
		(net "M_H_BA<1>")
	)
	(segment
		(start 95.58274 -28.799028)
		(end 95.870268 -28.799028)
		(width 0.14224)
		(layer "In11.Cu")
		(net "M_H_BA<1>")
	)
	(segment
		(start 98.140012 -15.4432)
		(end 98.981768 -15.4432)
		(width 0.14224)
		(layer "In11.Cu")
		(net "M_H_BA<1>")
	)
	(segment
		(start 96.670368 -19.9644)
		(end 97.432368 -19.2024)
		(width 0.14224)
		(layer "In11.Cu")
		(net "M_H_BA<1>")
	)
	(segment
		(start 95.295466 -29.086302)
		(end 95.58274 -28.799028)
		(width 0.14224)
		(layer "In11.Cu")
		(net "M_H_BA<1>")
	)
	(segment
		(start 101.769418 -12.7762)
		(end 101.94925 -12.596368)
		(width 0.14224)
		(layer "In11.Cu")
		(net "M_H_BA<1>")
	)
	(segment
		(start 101.94925 -11.918696)
		(end 101.949758 -11.918188)
		(width 0.14224)
		(layer "In11.Cu")
		(net "M_H_BA<1>")
	)
	(segment
		(start 101.263704 -9.819132)
		(end 101.949758 -9.133078)
		(width 0.14224)
		(layer "In11.Cu")
		(net "M_H_BA<1>")
	)
	(segment
		(start 100.683568 -12.7762)
		(end 101.769418 -12.7762)
		(width 0.14224)
		(layer "In11.Cu")
		(net "M_H_BA<1>")
	)
	(segment
		(start 99.743768 -13.716)
		(end 100.683568 -12.7762)
		(width 0.14224)
		(layer "In11.Cu")
		(net "M_H_BA<1>")
	)
	(segment
		(start 96.670368 -28.865576)
		(end 96.670368 -19.9644)
		(width 0.14224)
		(layer "In11.Cu")
		(net "M_H_BA<1>")
	)
	(segment
		(start 93.980508 -53.667914)
		(end 93.980508 -51.358038)
		(width 0.0889)
		(layer "In11.Cu")
		(net "M_H_BA<1>")
	)
	(segment
		(start 95.025972 -50.134774)
		(end 95.025972 -30.509972)
		(width 0.14224)
		(layer "In11.Cu")
		(net "M_H_BA<1>")
	)
	(segment
		(start 96.159828 -29.088588)
		(end 96.447356 -29.088588)
		(width 0.14224)
		(layer "In11.Cu")
		(net "M_H_BA<1>")
	)
	(segment
		(start 97.432368 -18.8722)
		(end 97.102168 -18.542)
		(width 0.14224)
		(layer "In11.Cu")
		(net "M_H_BA<1>")
	)
	(segment
		(start 95.295466 -29.37383)
		(end 95.295466 -29.086302)
		(width 0.14224)
		(layer "In11.Cu")
		(net "M_H_BA<1>")
	)
	(segment
		(start 95.870268 -28.799028)
		(end 96.159828 -29.088588)
		(width 0.14224)
		(layer "In11.Cu")
		(net "M_H_BA<1>")
	)
	(segment
		(start 97.102168 -18.542)
		(end 97.102168 -16.481044)
		(width 0.14224)
		(layer "In11.Cu")
		(net "M_H_BA<1>")
	)
	(segment
		(start 96.447356 -29.088588)
		(end 96.670368 -28.865576)
		(width 0.14224)
		(layer "In11.Cu")
		(net "M_H_BA<1>")
	)
	(segment
		(start 101.94925 -12.596368)
		(end 101.94925 -11.918696)
		(width 0.14224)
		(layer "In11.Cu")
		(net "M_H_BA<1>")
	)
	(segment
		(start 93.791278 -54.104286)
		(end 93.980508 -53.667914)
		(width 0.0889)
		(layer "In11.Cu")
		(net "M_H_BA<1>")
	)
	(segment
		(start 94.613984 -50.724816)
		(end 95.025972 -50.312574)
		(width 0.0889)
		(layer "In11.Cu")
		(net "M_H_BA<1>")
	)
	(segment
		(start 99.743768 -14.6812)
		(end 99.743768 -13.716)
		(width 0.14224)
		(layer "In11.Cu")
		(net "M_H_BA<1>")
	)
	(segment
		(start 101.949758 -11.918188)
		(end 101.263704 -11.232134)
		(width 0.14224)
		(layer "In11.Cu")
		(net "M_H_BA<1>")
	)
	(segment
		(start 95.585026 -29.950918)
		(end 95.585026 -29.66339)
		(width 0.14224)
		(layer "In11.Cu")
		(net "M_H_BA<1>")
	)
	(segment
		(start 97.102168 -16.481044)
		(end 98.140012 -15.4432)
		(width 0.14224)
		(layer "In11.Cu")
		(net "M_H_BA<1>")
	)
	(segment
		(start 95.585026 -29.66339)
		(end 95.295466 -29.37383)
		(width 0.14224)
		(layer "In11.Cu")
		(net "M_H_BA<1>")
	)
	(segment
		(start 101.263704 -11.232134)
		(end 101.263704 -9.819132)
		(width 0.14224)
		(layer "In11.Cu")
		(net "M_H_BA<1>")
	)
	(segment
		(start 93.980508 -51.358038)
		(end 94.613984 -50.724816)
		(width 0.0889)
		(layer "In11.Cu")
		(net "M_H_BA<1>")
	)
	(segment
		(start 97.432368 -19.2024)
		(end 97.432368 -18.8722)
		(width 0.14224)
		(layer "In11.Cu")
		(net "M_H_BA<1>")
	)
	(segment
		(start 95.025972 -50.312574)
		(end 95.025972 -50.134774)
		(width 0.0889)
		(layer "In11.Cu")
		(net "M_H_BA<1>")
	)
	(segment
		(start 102.799388 -7.117334)
		(end 102.799642 -7.117588)
		(width 0.1651)
		(layer "F.Cu")
		(net "M_H_BA<0>")
	)
	(segment
		(start 102.799388 -5.822442)
		(end 102.799388 -7.117334)
		(width 0.1651)
		(layer "F.Cu")
		(net "M_H_BA<0>")
	)
	(segment
		(start 96.079818 -57.076086)
		(end 95.508318 -57.076086)
		(width 0.1016)
		(layer "F.Cu")
		(net "M_H_BA<0>")
	)
	(via
		(at 102.799642 -13.933678)
		(size 0.4572)
		(drill 0.2032)
		(layers "F.Cu" "B.Cu")
		(net "M_H_BA<0>")
	)
	(via
		(at 95.508318 -57.076086)
		(size 0.508)
		(drill 0.254)
		(layers "F.Cu" "B.Cu")
		(net "M_H_BA<0>")
	)
	(via
		(at 102.799642 -7.117588)
		(size 0.4572)
		(drill 0.2032)
		(layers "F.Cu" "B.Cu")
		(net "M_H_BA<0>")
	)
	(segment
		(start 102.799388 -15.222982)
		(end 102.799388 -13.933932)
		(width 0.1651)
		(layer "B.Cu")
		(net "M_H_BA<0>")
	)
	(segment
		(start 102.799388 -13.933932)
		(end 102.799642 -13.933678)
		(width 0.1651)
		(layer "B.Cu")
		(net "M_H_BA<0>")
	)
	(segment
		(start 102.37724 -8.724392)
		(end 102.799388 -8.302244)
		(width 0.14224)
		(layer "In4.Cu")
		(net "M_H_BA<0>")
	)
	(segment
		(start 96.38792 -53.328316)
		(end 96.631506 -52.91836)
		(width 0.0889)
		(layer "In4.Cu")
		(net "M_H_BA<0>")
	)
	(segment
		(start 101.445568 -19.002502)
		(end 101.53904 -18.90903)
		(width 0.14224)
		(layer "In4.Cu")
		(net "M_H_BA<0>")
	)
	(segment
		(start 97.972626 -27.954986)
		(end 100.988368 -24.939244)
		(width 0.14224)
		(layer "In4.Cu")
		(net "M_H_BA<0>")
	)
	(segment
		(start 102.65029 -13.933678)
		(end 102.799642 -13.933678)
		(width 0.14224)
		(layer "In4.Cu")
		(net "M_H_BA<0>")
	)
	(segment
		(start 101.54031 -15.993364)
		(end 101.839268 -14.7447)
		(width 0.14224)
		(layer "In4.Cu")
		(net "M_H_BA<0>")
	)
	(segment
		(start 102.799388 -7.117842)
		(end 102.799642 -7.117588)
		(width 0.14224)
		(layer "In4.Cu")
		(net "M_H_BA<0>")
	)
	(segment
		(start 96.713548 -52.818284)
		(end 96.89719 -52.500784)
		(width 0.0889)
		(layer "In4.Cu")
		(net "M_H_BA<0>")
	)
	(segment
		(start 97.972626 -50.842164)
		(end 97.972626 -27.954986)
		(width 0.14224)
		(layer "In4.Cu")
		(net "M_H_BA<0>")
	)
	(segment
		(start 100.988368 -24.939244)
		(end 100.988368 -23.820374)
		(width 0.14224)
		(layer "In4.Cu")
		(net "M_H_BA<0>")
	)
	(segment
		(start 101.445568 -22.360382)
		(end 101.445568 -21.92782)
		(width 0.14224)
		(layer "In4.Cu")
		(net "M_H_BA<0>")
	)
	(segment
		(start 102.799642 -13.77823)
		(end 102.37724 -13.355828)
		(width 0.14224)
		(layer "In4.Cu")
		(net "M_H_BA<0>")
	)
	(segment
		(start 101.839268 -14.7447)
		(end 102.65029 -13.933678)
		(width 0.14224)
		(layer "In4.Cu")
		(net "M_H_BA<0>")
	)
	(segment
		(start 100.988368 -23.820374)
		(end 101.777546 -23.031196)
		(width 0.14224)
		(layer "In4.Cu")
		(net "M_H_BA<0>")
	)
	(segment
		(start 102.37724 -13.355828)
		(end 102.37724 -8.724392)
		(width 0.14224)
		(layer "In4.Cu")
		(net "M_H_BA<0>")
	)
	(segment
		(start 95.855028 -54.304438)
		(end 96.238568 -53.638958)
		(width 0.0889)
		(layer "In4.Cu")
		(net "M_H_BA<0>")
	)
	(segment
		(start 101.697282 -21.194522)
		(end 101.445568 -20.942808)
		(width 0.14224)
		(layer "In4.Cu")
		(net "M_H_BA<0>")
	)
	(segment
		(start 101.777546 -22.69236)
		(end 101.445568 -22.360382)
		(width 0.14224)
		(layer "In4.Cu")
		(net "M_H_BA<0>")
	)
	(segment
		(start 95.859854 -54.903624)
		(end 95.855028 -54.894988)
		(width 0.0889)
		(layer "In4.Cu")
		(net "M_H_BA<0>")
	)
	(segment
		(start 101.53904 -17.016476)
		(end 101.54031 -17.010634)
		(width 0.14224)
		(layer "In4.Cu")
		(net "M_H_BA<0>")
	)
	(segment
		(start 101.697282 -21.676106)
		(end 101.697282 -21.194522)
		(width 0.14224)
		(layer "In4.Cu")
		(net "M_H_BA<0>")
	)
	(segment
		(start 101.445568 -21.92782)
		(end 101.697282 -21.676106)
		(width 0.14224)
		(layer "In4.Cu")
		(net "M_H_BA<0>")
	)
	(segment
		(start 101.777546 -23.031196)
		(end 101.777546 -22.69236)
		(width 0.14224)
		(layer "In4.Cu")
		(net "M_H_BA<0>")
	)
	(segment
		(start 95.855028 -54.894988)
		(end 95.848678 -54.88432)
		(width 0.0889)
		(layer "In4.Cu")
		(net "M_H_BA<0>")
	)
	(segment
		(start 102.799642 -13.933678)
		(end 102.799642 -13.77823)
		(width 0.14224)
		(layer "In4.Cu")
		(net "M_H_BA<0>")
	)
	(segment
		(start 97.972626 -51.351942)
		(end 97.972626 -50.842164)
		(width 0.0889)
		(layer "In4.Cu")
		(net "M_H_BA<0>")
	)
	(segment
		(start 97.140268 -52.1843)
		(end 97.972626 -51.351942)
		(width 0.0889)
		(layer "In4.Cu")
		(net "M_H_BA<0>")
	)
	(segment
		(start 95.838264 -56.31434)
		(end 95.855028 -56.285638)
		(width 0.0889)
		(layer "In4.Cu")
		(net "M_H_BA<0>")
	)
	(segment
		(start 96.238568 -53.638958)
		(end 96.38792 -53.328316)
		(width 0.0889)
		(layer "In4.Cu")
		(net "M_H_BA<0>")
	)
	(segment
		(start 95.855028 -55.885588)
		(end 95.848678 -55.87492)
		(width 0.0889)
		(layer "In4.Cu")
		(net "M_H_BA<0>")
	)
	(segment
		(start 101.53904 -18.90903)
		(end 101.53904 -17.016476)
		(width 0.14224)
		(layer "In4.Cu")
		(net "M_H_BA<0>")
	)
	(segment
		(start 101.54031 -17.010634)
		(end 101.54031 -15.993364)
		(width 0.14224)
		(layer "In4.Cu")
		(net "M_H_BA<0>")
	)
	(segment
		(start 102.799388 -8.302244)
		(end 102.799388 -7.117842)
		(width 0.14224)
		(layer "In4.Cu")
		(net "M_H_BA<0>")
	)
	(segment
		(start 95.859854 -55.894224)
		(end 95.855028 -55.885588)
		(width 0.0889)
		(layer "In4.Cu")
		(net "M_H_BA<0>")
	)
	(segment
		(start 101.445568 -20.942808)
		(end 101.445568 -19.002502)
		(width 0.14224)
		(layer "In4.Cu")
		(net "M_H_BA<0>")
	)
	(segment
		(start 95.508318 -57.076086)
		(end 95.838264 -56.31434)
		(width 0.0889)
		(layer "In4.Cu")
		(net "M_H_BA<0>")
	)
	(arc
		(start 96.631506 -52.91836)
		(mid 96.676603 -52.871663)
		(end 96.713548 -52.818284)
		(width 0.0889)
		(layer "In4.Cu")
		(net "M_H_BA<0>")
	)
	(arc
		(start 95.848678 -54.88432)
		(mid 95.77588 -54.593557)
		(end 95.855028 -54.304438)
		(width 0.0889)
		(layer "In4.Cu")
		(net "M_H_BA<0>")
	)
	(arc
		(start 96.89719 -52.500784)
		(mid 97.008404 -52.334613)
		(end 97.140268 -52.1843)
		(width 0.0889)
		(layer "In4.Cu")
		(net "M_H_BA<0>")
	)
	(arc
		(start 95.855028 -55.295038)
		(mid 95.908498 -55.099975)
		(end 95.859854 -54.903624)
		(width 0.0889)
		(layer "In4.Cu")
		(net "M_H_BA<0>")
	)
	(arc
		(start 95.848678 -55.87492)
		(mid 95.77588 -55.584157)
		(end 95.855028 -55.295038)
		(width 0.0889)
		(layer "In4.Cu")
		(net "M_H_BA<0>")
	)
	(arc
		(start 95.855028 -56.285638)
		(mid 95.908498 -56.090575)
		(end 95.859854 -55.894224)
		(width 0.0889)
		(layer "In4.Cu")
		(net "M_H_BA<0>")
	)
	(segment
		(start 83.249516 -10.422382)
		(end 83.249516 -9.133078)
		(width 0.1651)
		(layer "F.Cu")
		(net "M_H_ALERT_N")
	)
	(segment
		(start 88.353392 -58.561986)
		(end 87.781892 -58.561986)
		(width 0.1651)
		(layer "F.Cu")
		(net "M_H_ALERT_N")
	)
	(via
		(at 83.249516 -11.916156)
		(size 0.4572)
		(drill 0.2032)
		(layers "F.Cu" "B.Cu")
		(net "M_H_ALERT_N")
	)
	(via
		(at 83.249516 -9.133078)
		(size 0.4572)
		(drill 0.2032)
		(layers "F.Cu" "B.Cu")
		(net "M_H_ALERT_N")
	)
	(via
		(at 87.781892 -58.561986)
		(size 0.508)
		(drill 0.254)
		(layers "F.Cu" "B.Cu")
		(net "M_H_ALERT_N")
	)
	(segment
		(start 83.249516 -10.623042)
		(end 83.249516 -11.916156)
		(width 0.1651)
		(layer "B.Cu")
		(net "M_H_ALERT_N")
	)
	(segment
		(start 82.893408 -21.3106)
		(end 82.893408 -21.811996)
		(width 0.14224)
		(layer "In4.Cu")
		(net "M_H_ALERT_N")
	)
	(segment
		(start 84.2264 -25.721818)
		(end 84.2264 -26.628598)
		(width 0.14224)
		(layer "In4.Cu")
		(net "M_H_ALERT_N")
	)
	(segment
		(start 88.293702 -57.867296)
		(end 88.277192 -57.895998)
		(width 0.0889)
		(layer "In4.Cu")
		(net "M_H_ALERT_N")
	)
	(segment
		(start 81.989168 -13.176504)
		(end 81.989168 -14.666214)
		(width 0.14224)
		(layer "In4.Cu")
		(net "M_H_ALERT_N")
	)
	(segment
		(start 83.249516 -9.133078)
		(end 83.055968 -9.133078)
		(width 0.14224)
		(layer "In4.Cu")
		(net "M_H_ALERT_N")
	)
	(segment
		(start 81.989168 -14.666214)
		(end 82.808826 -15.485872)
		(width 0.14224)
		(layer "In4.Cu")
		(net "M_H_ALERT_N")
	)
	(segment
		(start 82.839052 -21.256244)
		(end 82.893408 -21.3106)
		(width 0.14224)
		(layer "In4.Cu")
		(net "M_H_ALERT_N")
	)
	(segment
		(start 88.439752 -30.84195)
		(end 88.439752 -50.348896)
		(width 0.14224)
		(layer "In4.Cu")
		(net "M_H_ALERT_N")
	)
	(segment
		(start 88.277192 -57.895998)
		(end 87.781892 -58.561986)
		(width 0.0889)
		(layer "In4.Cu")
		(net "M_H_ALERT_N")
	)
	(segment
		(start 82.827368 -11.494008)
		(end 83.249516 -11.916156)
		(width 0.14224)
		(layer "In4.Cu")
		(net "M_H_ALERT_N")
	)
	(segment
		(start 82.827368 -9.361678)
		(end 82.827368 -11.494008)
		(width 0.14224)
		(layer "In4.Cu")
		(net "M_H_ALERT_N")
	)
	(segment
		(start 82.893408 -18.404586)
		(end 82.839052 -18.458942)
		(width 0.14224)
		(layer "In4.Cu")
		(net "M_H_ALERT_N")
	)
	(segment
		(start 83.249516 -11.916156)
		(end 81.989168 -13.176504)
		(width 0.14224)
		(layer "In4.Cu")
		(net "M_H_ALERT_N")
	)
	(segment
		(start 82.741008 -17.617186)
		(end 82.893408 -17.769586)
		(width 0.14224)
		(layer "In4.Cu")
		(net "M_H_ALERT_N")
	)
	(segment
		(start 82.758534 -23.31847)
		(end 82.758534 -24.253952)
		(width 0.14224)
		(layer "In4.Cu")
		(net "M_H_ALERT_N")
	)
	(segment
		(start 82.766408 -21.938996)
		(end 82.766408 -22.421596)
		(width 0.14224)
		(layer "In4.Cu")
		(net "M_H_ALERT_N")
	)
	(segment
		(start 82.893408 -17.769586)
		(end 82.893408 -18.404586)
		(width 0.14224)
		(layer "In4.Cu")
		(net "M_H_ALERT_N")
	)
	(segment
		(start 82.944208 -22.599396)
		(end 82.944208 -23.132796)
		(width 0.14224)
		(layer "In4.Cu")
		(net "M_H_ALERT_N")
	)
	(segment
		(start 82.808826 -17.041368)
		(end 82.741008 -17.109186)
		(width 0.14224)
		(layer "In4.Cu")
		(net "M_H_ALERT_N")
	)
	(segment
		(start 82.808826 -15.485872)
		(end 82.808826 -17.041368)
		(width 0.14224)
		(layer "In4.Cu")
		(net "M_H_ALERT_N")
	)
	(segment
		(start 82.766408 -22.421596)
		(end 82.944208 -22.599396)
		(width 0.14224)
		(layer "In4.Cu")
		(net "M_H_ALERT_N")
	)
	(segment
		(start 88.188292 -51.724814)
		(end 88.128602 -51.828192)
		(width 0.0889)
		(layer "In4.Cu")
		(net "M_H_ALERT_N")
	)
	(segment
		(start 82.839052 -18.458942)
		(end 82.839052 -21.256244)
		(width 0.14224)
		(layer "In4.Cu")
		(net "M_H_ALERT_N")
	)
	(segment
		(start 82.758534 -24.253952)
		(end 84.2264 -25.721818)
		(width 0.14224)
		(layer "In4.Cu")
		(net "M_H_ALERT_N")
	)
	(segment
		(start 82.893408 -21.811996)
		(end 82.766408 -21.938996)
		(width 0.14224)
		(layer "In4.Cu")
		(net "M_H_ALERT_N")
	)
	(segment
		(start 88.439752 -50.851562)
		(end 88.188292 -51.103022)
		(width 0.0889)
		(layer "In4.Cu")
		(net "M_H_ALERT_N")
	)
	(segment
		(start 88.188292 -51.103022)
		(end 88.188292 -51.724814)
		(width 0.0889)
		(layer "In4.Cu")
		(net "M_H_ALERT_N")
	)
	(segment
		(start 83.055968 -9.133078)
		(end 82.827368 -9.361678)
		(width 0.14224)
		(layer "In4.Cu")
		(net "M_H_ALERT_N")
	)
	(segment
		(start 84.2264 -26.628598)
		(end 88.439752 -30.84195)
		(width 0.14224)
		(layer "In4.Cu")
		(net "M_H_ALERT_N")
	)
	(segment
		(start 82.944208 -23.132796)
		(end 82.758534 -23.31847)
		(width 0.14224)
		(layer "In4.Cu")
		(net "M_H_ALERT_N")
	)
	(segment
		(start 82.741008 -17.109186)
		(end 82.741008 -17.617186)
		(width 0.14224)
		(layer "In4.Cu")
		(net "M_H_ALERT_N")
	)
	(segment
		(start 88.439752 -50.348896)
		(end 88.439752 -50.851562)
		(width 0.0889)
		(layer "In4.Cu")
		(net "M_H_ALERT_N")
	)
	(arc
		(start 88.293702 -56.876696)
		(mid 88.240203 -57.076594)
		(end 88.293702 -57.276492)
		(width 0.0889)
		(layer "In4.Cu")
		(net "M_H_ALERT_N")
	)
	(arc
		(start 88.293702 -57.276492)
		(mid 88.372833 -57.571894)
		(end 88.293702 -57.867296)
		(width 0.0889)
		(layer "In4.Cu")
		(net "M_H_ALERT_N")
	)
	(arc
		(start 88.293702 -56.285892)
		(mid 88.372833 -56.581294)
		(end 88.293702 -56.876696)
		(width 0.0889)
		(layer "In4.Cu")
		(net "M_H_ALERT_N")
	)
	(arc
		(start 88.128602 -51.828192)
		(mid 88.049471 -52.123594)
		(end 88.128602 -52.418996)
		(width 0.0889)
		(layer "In4.Cu")
		(net "M_H_ALERT_N")
	)
	(arc
		(start 88.128602 -54.400196)
		(mid 88.163214 -54.478438)
		(end 88.180418 -54.562248)
		(width 0.0889)
		(layer "In4.Cu")
		(net "M_H_ALERT_N")
	)
	(arc
		(start 88.180418 -54.562248)
		(mid 88.188586 -54.74544)
		(end 88.178132 -54.928516)
		(width 0.0889)
		(layer "In4.Cu")
		(net "M_H_ALERT_N")
	)
	(arc
		(start 88.293702 -55.295292)
		(mid 88.372833 -55.590694)
		(end 88.293702 -55.886096)
		(width 0.0889)
		(layer "In4.Cu")
		(net "M_H_ALERT_N")
	)
	(arc
		(start 88.128602 -52.418996)
		(mid 88.182135 -52.618894)
		(end 88.128602 -52.818792)
		(width 0.0889)
		(layer "In4.Cu")
		(net "M_H_ALERT_N")
	)
	(arc
		(start 88.128602 -53.409596)
		(mid 88.182135 -53.609494)
		(end 88.128602 -53.809392)
		(width 0.0889)
		(layer "In4.Cu")
		(net "M_H_ALERT_N")
	)
	(arc
		(start 88.128602 -53.809392)
		(mid 88.049471 -54.104794)
		(end 88.128602 -54.400196)
		(width 0.0889)
		(layer "In4.Cu")
		(net "M_H_ALERT_N")
	)
	(arc
		(start 88.128602 -52.818792)
		(mid 88.049471 -53.114194)
		(end 88.128602 -53.409596)
		(width 0.0889)
		(layer "In4.Cu")
		(net "M_H_ALERT_N")
	)
	(arc
		(start 88.178132 -54.928516)
		(mid 88.215835 -55.11823)
		(end 88.293702 -55.295292)
		(width 0.0889)
		(layer "In4.Cu")
		(net "M_H_ALERT_N")
	)
	(arc
		(start 88.293702 -55.886096)
		(mid 88.240203 -56.085994)
		(end 88.293702 -56.285892)
		(width 0.0889)
		(layer "In4.Cu")
		(net "M_H_ALERT_N")
	)
	(segment
		(start 87.494872 -57.076086)
		(end 86.923372 -57.076086)
		(width 0.1651)
		(layer "F.Cu")
		(net "M_H_ACT_N")
	)
	(segment
		(start 81.549494 -5.822442)
		(end 81.549494 -7.115556)
		(width 0.1651)
		(layer "F.Cu")
		(net "M_H_ACT_N")
	)
	(via
		(at 81.549494 -7.115556)
		(size 0.4572)
		(drill 0.2032)
		(layers "F.Cu" "B.Cu")
		(net "M_H_ACT_N")
	)
	(via
		(at 81.549494 -13.933678)
		(size 0.4572)
		(drill 0.2032)
		(layers "F.Cu" "B.Cu")
		(net "M_H_ACT_N")
	)
	(via
		(at 86.923372 -57.076086)
		(size 0.508)
		(drill 0.254)
		(layers "F.Cu" "B.Cu")
		(net "M_H_ACT_N")
	)
	(segment
		(start 81.549494 -15.222982)
		(end 81.549494 -13.933678)
		(width 0.1651)
		(layer "B.Cu")
		(net "M_H_ACT_N")
	)
	(segment
		(start 87.467694 -56.19877)
		(end 87.943436 -55.956962)
		(width 0.0889)
		(layer "In4.Cu")
		(net "M_H_ACT_N")
	)
	(segment
		(start 87.805514 -55.106824)
		(end 87.793576 -55.094886)
		(width 0.0889)
		(layer "In4.Cu")
		(net "M_H_ACT_N")
	)
	(segment
		(start 81.50225 -10.216642)
		(end 81.267808 -10.216642)
		(width 0.14224)
		(layer "In4.Cu")
		(net "M_H_ACT_N")
	)
	(segment
		(start 82.156808 -24.370792)
		(end 82.156808 -23.437596)
		(width 0.14224)
		(layer "In4.Cu")
		(net "M_H_ACT_N")
	)
	(segment
		(start 81.989168 -15.37462)
		(end 81.549494 -14.934946)
		(width 0.14224)
		(layer "In4.Cu")
		(net "M_H_ACT_N")
	)
	(segment
		(start 82.156808 -18.301462)
		(end 82.156808 -17.159986)
		(width 0.14224)
		(layer "In4.Cu")
		(net "M_H_ACT_N")
	)
	(segment
		(start 81.902808 -19.110706)
		(end 81.990946 -19.022568)
		(width 0.14224)
		(layer "In4.Cu")
		(net "M_H_ACT_N")
	)
	(segment
		(start 83.690968 -26.811732)
		(end 83.690968 -25.904952)
		(width 0.14224)
		(layer "In4.Cu")
		(net "M_H_ACT_N")
	)
	(segment
		(start 81.112868 -8.16991)
		(end 81.235296 -7.874)
		(width 0.14224)
		(layer "In4.Cu")
		(net "M_H_ACT_N")
	)
	(segment
		(start 88.030304 -50.753264)
		(end 88.030304 -50.305716)
		(width 0.0889)
		(layer "In4.Cu")
		(net "M_H_ACT_N")
	)
	(segment
		(start 88.030304 -31.151068)
		(end 83.690968 -26.811732)
		(width 0.14224)
		(layer "In4.Cu")
		(net "M_H_ACT_N")
	)
	(segment
		(start 81.50225 -11.009122)
		(end 81.65719 -10.854182)
		(width 0.14224)
		(layer "In4.Cu")
		(net "M_H_ACT_N")
	)
	(segment
		(start 81.524094 -13.933678)
		(end 81.112868 -13.522452)
		(width 0.14224)
		(layer "In4.Cu")
		(net "M_H_ACT_N")
	)
	(segment
		(start 87.435182 -53.809138)
		(end 87.430356 -53.800502)
		(width 0.0889)
		(layer "In4.Cu")
		(net "M_H_ACT_N")
	)
	(segment
		(start 81.112868 -11.164062)
		(end 81.267808 -11.009122)
		(width 0.14224)
		(layer "In4.Cu")
		(net "M_H_ACT_N")
	)
	(segment
		(start 81.990946 -18.467324)
		(end 82.156808 -18.301462)
		(width 0.14224)
		(layer "In4.Cu")
		(net "M_H_ACT_N")
	)
	(segment
		(start 82.156808 -22.408896)
		(end 82.156808 -21.964396)
		(width 0.14224)
		(layer "In4.Cu")
		(net "M_H_ACT_N")
	)
	(segment
		(start 81.112868 -13.522452)
		(end 81.112868 -11.164062)
		(width 0.14224)
		(layer "In4.Cu")
		(net "M_H_ACT_N")
	)
	(segment
		(start 83.690968 -25.904952)
		(end 82.156808 -24.370792)
		(width 0.14224)
		(layer "In4.Cu")
		(net "M_H_ACT_N")
	)
	(segment
		(start 86.923372 -57.076086)
		(end 87.467694 -56.19877)
		(width 0.0889)
		(layer "In4.Cu")
		(net "M_H_ACT_N")
	)
	(segment
		(start 81.549494 -14.934946)
		(end 81.549494 -13.933678)
		(width 0.14224)
		(layer "In4.Cu")
		(net "M_H_ACT_N")
	)
	(segment
		(start 81.902808 -22.662896)
		(end 82.156808 -22.408896)
		(width 0.14224)
		(layer "In4.Cu")
		(net "M_H_ACT_N")
	)
	(segment
		(start 81.549494 -13.933678)
		(end 81.524094 -13.933678)
		(width 0.14224)
		(layer "In4.Cu")
		(net "M_H_ACT_N")
	)
	(segment
		(start 81.235296 -7.874)
		(end 81.549494 -7.115556)
		(width 0.14224)
		(layer "In4.Cu")
		(net "M_H_ACT_N")
	)
	(segment
		(start 81.902808 -21.710396)
		(end 81.902808 -19.110706)
		(width 0.14224)
		(layer "In4.Cu")
		(net "M_H_ACT_N")
	)
	(segment
		(start 82.156808 -23.437596)
		(end 81.902808 -23.183596)
		(width 0.14224)
		(layer "In4.Cu")
		(net "M_H_ACT_N")
	)
	(segment
		(start 87.441532 -53.819806)
		(end 87.435182 -53.809138)
		(width 0.0889)
		(layer "In4.Cu")
		(net "M_H_ACT_N")
	)
	(segment
		(start 81.112868 -10.061702)
		(end 81.112868 -8.16991)
		(width 0.14224)
		(layer "In4.Cu")
		(net "M_H_ACT_N")
	)
	(segment
		(start 81.267808 -10.216642)
		(end 81.112868 -10.061702)
		(width 0.14224)
		(layer "In4.Cu")
		(net "M_H_ACT_N")
	)
	(segment
		(start 81.902808 -23.183596)
		(end 81.902808 -22.662896)
		(width 0.14224)
		(layer "In4.Cu")
		(net "M_H_ACT_N")
	)
	(segment
		(start 81.989168 -16.992346)
		(end 81.989168 -15.37462)
		(width 0.14224)
		(layer "In4.Cu")
		(net "M_H_ACT_N")
	)
	(segment
		(start 87.375492 -51.408076)
		(end 88.030304 -50.753264)
		(width 0.0889)
		(layer "In4.Cu")
		(net "M_H_ACT_N")
	)
	(segment
		(start 88.030304 -50.305716)
		(end 88.030304 -31.151068)
		(width 0.14224)
		(layer "In4.Cu")
		(net "M_H_ACT_N")
	)
	(segment
		(start 81.65719 -10.854182)
		(end 81.65719 -10.371582)
		(width 0.14224)
		(layer "In4.Cu")
		(net "M_H_ACT_N")
	)
	(segment
		(start 87.375492 -51.60391)
		(end 87.375492 -51.408076)
		(width 0.0889)
		(layer "In4.Cu")
		(net "M_H_ACT_N")
	)
	(segment
		(start 87.435182 -52.418488)
		(end 87.441532 -52.40782)
		(width 0.0889)
		(layer "In4.Cu")
		(net "M_H_ACT_N")
	)
	(segment
		(start 81.65719 -10.371582)
		(end 81.50225 -10.216642)
		(width 0.14224)
		(layer "In4.Cu")
		(net "M_H_ACT_N")
	)
	(segment
		(start 81.990946 -19.022568)
		(end 81.990946 -18.467324)
		(width 0.14224)
		(layer "In4.Cu")
		(net "M_H_ACT_N")
	)
	(segment
		(start 81.267808 -11.009122)
		(end 81.50225 -11.009122)
		(width 0.14224)
		(layer "In4.Cu")
		(net "M_H_ACT_N")
	)
	(segment
		(start 82.156808 -21.964396)
		(end 81.902808 -21.710396)
		(width 0.14224)
		(layer "In4.Cu")
		(net "M_H_ACT_N")
	)
	(segment
		(start 82.156808 -17.159986)
		(end 81.989168 -16.992346)
		(width 0.14224)
		(layer "In4.Cu")
		(net "M_H_ACT_N")
	)
	(arc
		(start 87.430356 -53.800502)
		(mid 87.381601 -53.60415)
		(end 87.435182 -53.409088)
		(width 0.0889)
		(layer "In4.Cu")
		(net "M_H_ACT_N")
	)
	(arc
		(start 87.622888 -54.973982)
		(mid 87.512221 -54.897702)
		(end 87.430356 -54.791102)
		(width 0.0889)
		(layer "In4.Cu")
		(net "M_H_ACT_N")
	)
	(arc
		(start 87.955374 -55.230014)
		(mid 87.873031 -55.177439)
		(end 87.805514 -55.106824)
		(width 0.0889)
		(layer "In4.Cu")
		(net "M_H_ACT_N")
	)
	(arc
		(start 87.943436 -55.956962)
		(mid 88.182149 -55.597285)
		(end 87.955374 -55.230014)
		(width 0.0889)
		(layer "In4.Cu")
		(net "M_H_ACT_N")
	)
	(arc
		(start 87.435436 -51.828192)
		(mid 87.390764 -51.719982)
		(end 87.375492 -51.60391)
		(width 0.0889)
		(layer "In4.Cu")
		(net "M_H_ACT_N")
	)
	(arc
		(start 87.435182 -52.818284)
		(mid 87.381683 -52.618386)
		(end 87.435182 -52.418488)
		(width 0.0889)
		(layer "In4.Cu")
		(net "M_H_ACT_N")
	)
	(arc
		(start 87.435182 -53.409088)
		(mid 87.514313 -53.113686)
		(end 87.435182 -52.818284)
		(width 0.0889)
		(layer "In4.Cu")
		(net "M_H_ACT_N")
	)
	(arc
		(start 87.49411 -51.970178)
		(mid 87.469417 -51.897265)
		(end 87.435436 -51.828192)
		(width 0.0889)
		(layer "In4.Cu")
		(net "M_H_ACT_N")
	)
	(arc
		(start 87.430356 -54.791102)
		(mid 87.381601 -54.59475)
		(end 87.435182 -54.399688)
		(width 0.0889)
		(layer "In4.Cu")
		(net "M_H_ACT_N")
	)
	(arc
		(start 87.441532 -52.40782)
		(mid 87.510147 -52.194084)
		(end 87.49411 -51.970178)
		(width 0.0889)
		(layer "In4.Cu")
		(net "M_H_ACT_N")
	)
	(arc
		(start 87.793576 -55.094886)
		(mid 87.713343 -55.02722)
		(end 87.622888 -54.973982)
		(width 0.0889)
		(layer "In4.Cu")
		(net "M_H_ACT_N")
	)
	(arc
		(start 87.435182 -54.399688)
		(mid 87.514404 -54.11057)
		(end 87.441532 -53.819806)
		(width 0.0889)
		(layer "In4.Cu")
		(net "M_H_ACT_N")
	)
	(segment
		(start 100.249228 -23.62454)
		(end 100.249228 -22.197568)
		(width 0.1651)
		(layer "F.Cu")
		(net "M_G_PAR")
	)
	(segment
		(start 97.083372 -46.78553)
		(end 96.623378 -46.325536)
		(width 0.0889)
		(layer "F.Cu")
		(net "M_G_PAR")
	)
	(segment
		(start 96.623378 -46.009814)
		(end 96.623378 -27.25039)
		(width 0.1651)
		(layer "F.Cu")
		(net "M_G_PAR")
	)
	(segment
		(start 96.079818 -51.132486)
		(end 96.492568 -50.179478)
		(width 0.0889)
		(layer "F.Cu")
		(net "M_G_PAR")
	)
	(segment
		(start 96.492568 -48.8442)
		(end 97.083372 -48.253396)
		(width 0.0889)
		(layer "F.Cu")
		(net "M_G_PAR")
	)
	(segment
		(start 97.520252 -26.353516)
		(end 100.249228 -23.62454)
		(width 0.1651)
		(layer "F.Cu")
		(net "M_G_PAR")
	)
	(segment
		(start 96.492568 -50.179478)
		(end 96.492568 -48.8442)
		(width 0.0889)
		(layer "F.Cu")
		(net "M_G_PAR")
	)
	(segment
		(start 100.249228 -22.197568)
		(end 100.249482 -22.197314)
		(width 0.1651)
		(layer "F.Cu")
		(net "M_G_PAR")
	)
	(segment
		(start 100.249482 -22.197314)
		(end 100.249482 -20.023582)
		(width 0.1651)
		(layer "F.Cu")
		(net "M_G_PAR")
	)
	(segment
		(start 97.083372 -48.253396)
		(end 97.083372 -46.78553)
		(width 0.0889)
		(layer "F.Cu")
		(net "M_G_PAR")
	)
	(segment
		(start 96.623378 -27.25039)
		(end 97.520252 -26.353516)
		(width 0.1651)
		(layer "F.Cu")
		(net "M_G_PAR")
	)
	(segment
		(start 96.623378 -46.325536)
		(end 96.623378 -46.009814)
		(width 0.0889)
		(layer "F.Cu")
		(net "M_G_PAR")
	)
	(via
		(at 100.249228 -22.197568)
		(size 0.508)
		(drill 0.254)
		(layers "F.Cu" "B.Cu")
		(net "M_G_PAR")
	)
	(via
		(at 97.520252 -26.353516)
		(size 0.508)
		(drill 0.254)
		(layers "F.Cu" "B.Cu")
		(net "M_G_PAR")
	)
	(segment
		(start 100.249482 -22.197314)
		(end 100.249228 -22.197568)
		(width 0.1651)
		(layer "B.Cu")
		(net "M_G_PAR")
	)
	(segment
		(start 100.249482 -20.224242)
		(end 100.249482 -22.197314)
		(width 0.1651)
		(layer "B.Cu")
		(net "M_G_PAR")
	)
	(segment
		(start 109.294168 -25.4762)
		(end 110.919768 -23.8506)
		(width 0.1651)
		(layer "F.Cu")
		(net "M_G_ODT<3>")
	)
	(segment
		(start 102.673658 -48.632364)
		(end 102.673658 -48.136302)
		(width 0.0889)
		(layer "F.Cu")
		(net "M_G_ODT<3>")
	)
	(segment
		(start 101.57841 -50.32756)
		(end 101.721158 -50.084736)
		(width 0.0889)
		(layer "F.Cu")
		(net "M_G_ODT<3>")
	)
	(segment
		(start 101.721158 -50.084736)
		(end 101.721158 -49.584864)
		(width 0.0889)
		(layer "F.Cu")
		(net "M_G_ODT<3>")
	)
	(segment
		(start 102.673658 -48.136302)
		(end 102.673658 -32.658812)
		(width 0.1651)
		(layer "F.Cu")
		(net "M_G_ODT<3>")
	)
	(segment
		(start 110.919768 -23.8506)
		(end 110.919768 -23.230586)
		(width 0.1651)
		(layer "F.Cu")
		(net "M_G_ODT<3>")
	)
	(segment
		(start 101.721158 -49.584864)
		(end 102.673658 -48.632364)
		(width 0.0889)
		(layer "F.Cu")
		(net "M_G_ODT<3>")
	)
	(segment
		(start 102.673658 -32.658812)
		(end 108.074968 -27.257502)
		(width 0.1651)
		(layer "F.Cu")
		(net "M_G_ODT<3>")
	)
	(segment
		(start 108.633768 -25.4762)
		(end 109.294168 -25.4762)
		(width 0.1651)
		(layer "F.Cu")
		(net "M_G_ODT<3>")
	)
	(segment
		(start 100.772214 -51.015392)
		(end 101.24567 -50.541936)
		(width 0.0889)
		(layer "F.Cu")
		(net "M_G_ODT<3>")
	)
	(segment
		(start 108.074968 -26.035)
		(end 108.633768 -25.4762)
		(width 0.1651)
		(layer "F.Cu")
		(net "M_G_ODT<3>")
	)
	(segment
		(start 100.772214 -51.637184)
		(end 100.772214 -51.015392)
		(width 0.0889)
		(layer "F.Cu")
		(net "M_G_ODT<3>")
	)
	(segment
		(start 108.074968 -26.607008)
		(end 108.074968 -26.035)
		(width 0.1651)
		(layer "F.Cu")
		(net "M_G_ODT<3>")
	)
	(segment
		(start 100.372164 -52.618386)
		(end 100.702364 -51.856386)
		(width 0.0889)
		(layer "F.Cu")
		(net "M_G_ODT<3>")
	)
	(segment
		(start 100.702364 -51.856386)
		(end 100.7237 -51.819302)
		(width 0.0889)
		(layer "F.Cu")
		(net "M_G_ODT<3>")
	)
	(segment
		(start 108.074968 -27.257502)
		(end 108.074968 -26.607008)
		(width 0.1651)
		(layer "F.Cu")
		(net "M_G_ODT<3>")
	)
	(segment
		(start 110.919768 -23.230586)
		(end 111.299498 -22.850856)
		(width 0.1651)
		(layer "F.Cu")
		(net "M_G_ODT<3>")
	)
	(via
		(at 108.074968 -26.607008)
		(size 0.508)
		(drill 0.254)
		(layers "F.Cu" "B.Cu")
		(net "M_G_ODT<3>")
	)
	(via
		(at 111.299498 -22.850856)
		(size 0.508)
		(drill 0.254)
		(layers "F.Cu" "B.Cu")
		(net "M_G_ODT<3>")
	)
	(arc
		(start 100.7237 -51.819302)
		(mid 100.758853 -51.731143)
		(end 100.772214 -51.637184)
		(width 0.0889)
		(layer "F.Cu")
		(net "M_G_ODT<3>")
	)
	(arc
		(start 101.24567 -50.541936)
		(mid 101.441414 -50.480345)
		(end 101.57841 -50.32756)
		(width 0.0889)
		(layer "F.Cu")
		(net "M_G_ODT<3>")
	)
	(segment
		(start 111.299498 -22.850856)
		(end 111.299498 -24.824182)
		(width 0.1651)
		(layer "B.Cu")
		(net "M_G_ODT<3>")
	)
	(segment
		(start 106.372914 -24.79167)
		(end 106.872278 -24.292306)
		(width 0.1651)
		(layer "F.Cu")
		(net "M_G_ODT<2>")
	)
	(segment
		(start 106.872278 -24.292306)
		(end 107.155742 -24.292306)
		(width 0.1651)
		(layer "F.Cu")
		(net "M_G_ODT<2>")
	)
	(segment
		(start 105.913428 -25.5778)
		(end 106.372914 -25.118314)
		(width 0.1651)
		(layer "F.Cu")
		(net "M_G_ODT<2>")
	)
	(segment
		(start 100.656898 -47.43958)
		(end 100.656898 -31.411672)
		(width 0.1651)
		(layer "F.Cu")
		(net "M_G_ODT<2>")
	)
	(segment
		(start 98.995738 -50.848006)
		(end 99.002088 -50.837338)
		(width 0.0889)
		(layer "F.Cu")
		(net "M_G_ODT<2>")
	)
	(segment
		(start 105.280968 -25.5778)
		(end 105.913428 -25.5778)
		(width 0.1651)
		(layer "F.Cu")
		(net "M_G_ODT<2>")
	)
	(segment
		(start 98.886772 -49.497742)
		(end 100.656898 -47.727616)
		(width 0.0889)
		(layer "F.Cu")
		(net "M_G_ODT<2>")
	)
	(segment
		(start 98.985578 -51.856386)
		(end 99.006914 -51.819302)
		(width 0.0889)
		(layer "F.Cu")
		(net "M_G_ODT<2>")
	)
	(segment
		(start 100.656898 -47.727616)
		(end 100.656898 -47.43958)
		(width 0.0889)
		(layer "F.Cu")
		(net "M_G_ODT<2>")
	)
	(segment
		(start 104.849168 -26.55316)
		(end 104.849168 -26.0096)
		(width 0.1651)
		(layer "F.Cu")
		(net "M_G_ODT<2>")
	)
	(segment
		(start 98.886772 -50.006758)
		(end 98.886772 -49.497742)
		(width 0.0889)
		(layer "F.Cu")
		(net "M_G_ODT<2>")
	)
	(segment
		(start 106.372914 -25.118314)
		(end 106.372914 -24.79167)
		(width 0.1651)
		(layer "F.Cu")
		(net "M_G_ODT<2>")
	)
	(segment
		(start 107.899454 -23.548594)
		(end 107.899454 -22.850856)
		(width 0.1651)
		(layer "F.Cu")
		(net "M_G_ODT<2>")
	)
	(segment
		(start 107.155742 -24.292306)
		(end 107.899454 -23.548594)
		(width 0.1651)
		(layer "F.Cu")
		(net "M_G_ODT<2>")
	)
	(segment
		(start 104.849168 -26.0096)
		(end 105.280968 -25.5778)
		(width 0.1651)
		(layer "F.Cu")
		(net "M_G_ODT<2>")
	)
	(segment
		(start 104.849168 -27.219402)
		(end 104.849168 -26.55316)
		(width 0.1651)
		(layer "F.Cu")
		(net "M_G_ODT<2>")
	)
	(segment
		(start 98.655378 -52.618386)
		(end 98.985578 -51.856386)
		(width 0.0889)
		(layer "F.Cu")
		(net "M_G_ODT<2>")
	)
	(segment
		(start 99.002088 -50.837338)
		(end 99.006914 -50.828702)
		(width 0.0889)
		(layer "F.Cu")
		(net "M_G_ODT<2>")
	)
	(segment
		(start 100.656898 -31.411672)
		(end 104.849168 -27.219402)
		(width 0.1651)
		(layer "F.Cu")
		(net "M_G_ODT<2>")
	)
	(via
		(at 104.849168 -26.55316)
		(size 0.508)
		(drill 0.254)
		(layers "F.Cu" "B.Cu")
		(net "M_G_ODT<2>")
	)
	(via
		(at 107.899454 -22.850856)
		(size 0.508)
		(drill 0.254)
		(layers "F.Cu" "B.Cu")
		(net "M_G_ODT<2>")
	)
	(arc
		(start 99.006914 -51.819302)
		(mid 99.055669 -51.62295)
		(end 99.002088 -51.427888)
		(width 0.0889)
		(layer "F.Cu")
		(net "M_G_ODT<2>")
	)
	(arc
		(start 99.006914 -50.828702)
		(mid 99.055669 -50.63235)
		(end 99.002088 -50.437288)
		(width 0.0889)
		(layer "F.Cu")
		(net "M_G_ODT<2>")
	)
	(arc
		(start 99.002088 -51.427888)
		(mid 98.922866 -51.13877)
		(end 98.995738 -50.848006)
		(width 0.0889)
		(layer "F.Cu")
		(net "M_G_ODT<2>")
	)
	(arc
		(start 99.002088 -50.437288)
		(mid 98.916072 -50.229616)
		(end 98.886772 -50.006758)
		(width 0.0889)
		(layer "F.Cu")
		(net "M_G_ODT<2>")
	)
	(segment
		(start 107.899454 -22.850856)
		(end 107.899454 -24.824182)
		(width 0.1651)
		(layer "B.Cu")
		(net "M_G_ODT<2>")
	)
	(segment
		(start 100.266246 -50.216308)
		(end 100.372164 -50.63744)
		(width 0.0889)
		(layer "F.Cu")
		(net "M_G_ODT<1>")
	)
	(segment
		(start 111.299498 -16.71828)
		(end 111.300006 -16.718788)
		(width 0.1651)
		(layer "F.Cu")
		(net "M_G_ODT<1>")
	)
	(segment
		(start 100.737416 -49.425352)
		(end 100.420678 -49.74209)
		(width 0.0889)
		(layer "F.Cu")
		(net "M_G_ODT<1>")
	)
	(segment
		(start 111.299498 -15.423642)
		(end 111.299498 -16.71828)
		(width 0.1651)
		(layer "F.Cu")
		(net "M_G_ODT<1>")
	)
	(segment
		(start 102.169468 -47.815754)
		(end 102.169468 -48.3743)
		(width 0.0889)
		(layer "F.Cu")
		(net "M_G_ODT<1>")
	)
	(segment
		(start 102.169468 -48.3743)
		(end 101.118416 -49.425352)
		(width 0.0889)
		(layer "F.Cu")
		(net "M_G_ODT<1>")
	)
	(segment
		(start 107.541568 -27.0383)
		(end 105.96626 -28.613608)
		(width 0.1651)
		(layer "F.Cu")
		(net "M_G_ODT<1>")
	)
	(segment
		(start 107.541568 -26.668984)
		(end 107.541568 -27.0383)
		(width 0.1651)
		(layer "F.Cu")
		(net "M_G_ODT<1>")
	)
	(segment
		(start 105.96626 -28.613608)
		(end 102.169468 -32.4104)
		(width 0.1651)
		(layer "F.Cu")
		(net "M_G_ODT<1>")
	)
	(segment
		(start 100.420678 -49.74209)
		(end 100.3046 -49.942496)
		(width 0.0889)
		(layer "F.Cu")
		(net "M_G_ODT<1>")
	)
	(segment
		(start 102.169468 -32.4104)
		(end 102.169468 -47.815754)
		(width 0.1651)
		(layer "F.Cu")
		(net "M_G_ODT<1>")
	)
	(segment
		(start 107.064048 -26.191464)
		(end 107.541568 -26.668984)
		(width 0.1651)
		(layer "F.Cu")
		(net "M_G_ODT<1>")
	)
	(segment
		(start 101.118416 -49.425352)
		(end 100.737416 -49.425352)
		(width 0.0889)
		(layer "F.Cu")
		(net "M_G_ODT<1>")
	)
	(via
		(at 111.300006 -16.718788)
		(size 0.4572)
		(drill 0.2032)
		(layers "F.Cu" "B.Cu")
		(net "M_G_ODT<1>")
	)
	(via
		(at 107.064048 -26.191464)
		(size 0.508)
		(drill 0.254)
		(layers "F.Cu" "B.Cu")
		(net "M_G_ODT<1>")
	)
	(via
		(at 105.96626 -28.613608)
		(size 0.508)
		(drill 0.254)
		(layers "F.Cu" "B.Cu")
		(net "M_G_ODT<1>")
	)
	(arc
		(start 100.3046 -49.942496)
		(mid 100.258652 -50.075656)
		(end 100.266246 -50.216308)
		(width 0.0889)
		(layer "F.Cu")
		(net "M_G_ODT<1>")
	)
	(segment
		(start 111.543846 -20.579588)
		(end 111.738664 -20.38477)
		(width 0.14224)
		(layer "In9.Cu")
		(net "M_G_ODT<1>")
	)
	(segment
		(start 110.792768 -20.782788)
		(end 110.995968 -20.579588)
		(width 0.14224)
		(layer "In9.Cu")
		(net "M_G_ODT<1>")
	)
	(segment
		(start 110.871 -19.098768)
		(end 110.871 -18.442432)
		(width 0.14224)
		(layer "In9.Cu")
		(net "M_G_ODT<1>")
	)
	(segment
		(start 110.995968 -19.741388)
		(end 110.792768 -19.538188)
		(width 0.14224)
		(layer "In9.Cu")
		(net "M_G_ODT<1>")
	)
	(segment
		(start 111.738664 -20.38477)
		(end 111.738664 -19.95297)
		(width 0.14224)
		(layer "In9.Cu")
		(net "M_G_ODT<1>")
	)
	(segment
		(start 111.299498 -16.719296)
		(end 111.300006 -16.718788)
		(width 0.14224)
		(layer "In9.Cu")
		(net "M_G_ODT<1>")
	)
	(segment
		(start 110.792768 -19.538188)
		(end 110.792768 -19.177)
		(width 0.14224)
		(layer "In9.Cu")
		(net "M_G_ODT<1>")
	)
	(segment
		(start 110.73257 -18.304002)
		(end 110.73257 -17.865598)
		(width 0.14224)
		(layer "In9.Cu")
		(net "M_G_ODT<1>")
	)
	(segment
		(start 107.576112 -25.6794)
		(end 107.617768 -25.6794)
		(width 0.14224)
		(layer "In9.Cu")
		(net "M_G_ODT<1>")
	)
	(segment
		(start 111.738664 -19.95297)
		(end 111.527082 -19.741388)
		(width 0.14224)
		(layer "In9.Cu")
		(net "M_G_ODT<1>")
	)
	(segment
		(start 110.871 -18.442432)
		(end 110.73257 -18.304002)
		(width 0.14224)
		(layer "In9.Cu")
		(net "M_G_ODT<1>")
	)
	(segment
		(start 110.73257 -17.865598)
		(end 111.299498 -17.29867)
		(width 0.14224)
		(layer "In9.Cu")
		(net "M_G_ODT<1>")
	)
	(segment
		(start 111.527082 -19.741388)
		(end 110.995968 -19.741388)
		(width 0.14224)
		(layer "In9.Cu")
		(net "M_G_ODT<1>")
	)
	(segment
		(start 110.792768 -21.717)
		(end 110.792768 -20.782788)
		(width 0.14224)
		(layer "In9.Cu")
		(net "M_G_ODT<1>")
	)
	(segment
		(start 107.617768 -25.6794)
		(end 110.995968 -22.3012)
		(width 0.14224)
		(layer "In9.Cu")
		(net "M_G_ODT<1>")
	)
	(segment
		(start 110.792768 -19.177)
		(end 110.871 -19.098768)
		(width 0.14224)
		(layer "In9.Cu")
		(net "M_G_ODT<1>")
	)
	(segment
		(start 107.064048 -26.191464)
		(end 107.576112 -25.6794)
		(width 0.14224)
		(layer "In9.Cu")
		(net "M_G_ODT<1>")
	)
	(segment
		(start 110.995968 -22.3012)
		(end 110.995968 -21.9202)
		(width 0.14224)
		(layer "In9.Cu")
		(net "M_G_ODT<1>")
	)
	(segment
		(start 111.299498 -17.29867)
		(end 111.299498 -16.719296)
		(width 0.14224)
		(layer "In9.Cu")
		(net "M_G_ODT<1>")
	)
	(segment
		(start 110.995968 -21.9202)
		(end 110.792768 -21.717)
		(width 0.14224)
		(layer "In9.Cu")
		(net "M_G_ODT<1>")
	)
	(segment
		(start 110.995968 -20.579588)
		(end 111.543846 -20.579588)
		(width 0.14224)
		(layer "In9.Cu")
		(net "M_G_ODT<1>")
	)
	(segment
		(start 100.152708 -47.501302)
		(end 100.152708 -31.16326)
		(width 0.1651)
		(layer "F.Cu")
		(net "M_G_ODT<0>")
	)
	(segment
		(start 104.150668 -26.191464)
		(end 103.664004 -26.191464)
		(width 0.1651)
		(layer "F.Cu")
		(net "M_G_ODT<0>")
	)
	(segment
		(start 107.899454 -15.423642)
		(end 107.899454 -16.714978)
		(width 0.1651)
		(layer "F.Cu")
		(net "M_G_ODT<0>")
	)
	(segment
		(start 104.315768 -27.0002)
		(end 104.315768 -26.356564)
		(width 0.1651)
		(layer "F.Cu")
		(net "M_G_ODT<0>")
	)
	(segment
		(start 100.152708 -31.16326)
		(end 102.621588 -28.69438)
		(width 0.1651)
		(layer "F.Cu")
		(net "M_G_ODT<0>")
	)
	(segment
		(start 100.152708 -47.851314)
		(end 100.152708 -47.501302)
		(width 0.0889)
		(layer "F.Cu")
		(net "M_G_ODT<0>")
	)
	(segment
		(start 98.655378 -50.63744)
		(end 98.655378 -49.348644)
		(width 0.0889)
		(layer "F.Cu")
		(net "M_G_ODT<0>")
	)
	(segment
		(start 104.315768 -26.356564)
		(end 104.150668 -26.191464)
		(width 0.1651)
		(layer "F.Cu")
		(net "M_G_ODT<0>")
	)
	(segment
		(start 102.621588 -28.69438)
		(end 104.315768 -27.0002)
		(width 0.1651)
		(layer "F.Cu")
		(net "M_G_ODT<0>")
	)
	(segment
		(start 98.655378 -49.348644)
		(end 100.152708 -47.851314)
		(width 0.0889)
		(layer "F.Cu")
		(net "M_G_ODT<0>")
	)
	(via
		(at 103.664004 -26.191464)
		(size 0.508)
		(drill 0.254)
		(layers "F.Cu" "B.Cu")
		(net "M_G_ODT<0>")
	)
	(via
		(at 107.899454 -16.714978)
		(size 0.508)
		(drill 0.254)
		(layers "F.Cu" "B.Cu")
		(net "M_G_ODT<0>")
	)
	(via
		(at 102.621588 -28.69438)
		(size 0.508)
		(drill 0.254)
		(layers "F.Cu" "B.Cu")
		(net "M_G_ODT<0>")
	)
	(segment
		(start 107.899454 -17.71777)
		(end 107.899454 -16.714978)
		(width 0.14224)
		(layer "In9.Cu")
		(net "M_G_ODT<0>")
	)
	(segment
		(start 108.582968 -20.6121)
		(end 108.582968 -20.2057)
		(width 0.14224)
		(layer "In9.Cu")
		(net "M_G_ODT<0>")
	)
	(segment
		(start 107.439968 -21.0185)
		(end 107.643168 -20.8153)
		(width 0.14224)
		(layer "In9.Cu")
		(net "M_G_ODT<0>")
	)
	(segment
		(start 104.328468 -25.5651)
		(end 107.516168 -22.3774)
		(width 0.14224)
		(layer "In9.Cu")
		(net "M_G_ODT<0>")
	)
	(segment
		(start 108.582968 -20.2057)
		(end 108.379768 -20.0025)
		(width 0.14224)
		(layer "In9.Cu")
		(net "M_G_ODT<0>")
	)
	(segment
		(start 107.643168 -20.0025)
		(end 107.461812 -19.821144)
		(width 0.14224)
		(layer "In9.Cu")
		(net "M_G_ODT<0>")
	)
	(segment
		(start 107.461812 -19.821144)
		(end 107.461812 -18.155412)
		(width 0.14224)
		(layer "In9.Cu")
		(net "M_G_ODT<0>")
	)
	(segment
		(start 107.461812 -18.155412)
		(end 107.899454 -17.71777)
		(width 0.14224)
		(layer "In9.Cu")
		(net "M_G_ODT<0>")
	)
	(segment
		(start 108.379768 -20.0025)
		(end 107.643168 -20.0025)
		(width 0.14224)
		(layer "In9.Cu")
		(net "M_G_ODT<0>")
	)
	(segment
		(start 108.379768 -20.8153)
		(end 108.582968 -20.6121)
		(width 0.14224)
		(layer "In9.Cu")
		(net "M_G_ODT<0>")
	)
	(segment
		(start 103.664004 -26.191464)
		(end 104.290368 -25.5651)
		(width 0.14224)
		(layer "In9.Cu")
		(net "M_G_ODT<0>")
	)
	(segment
		(start 107.643168 -20.8153)
		(end 108.379768 -20.8153)
		(width 0.14224)
		(layer "In9.Cu")
		(net "M_G_ODT<0>")
	)
	(segment
		(start 104.290368 -25.5651)
		(end 104.328468 -25.5651)
		(width 0.14224)
		(layer "In9.Cu")
		(net "M_G_ODT<0>")
	)
	(segment
		(start 107.516168 -22.3774)
		(end 107.516168 -21.9202)
		(width 0.14224)
		(layer "In9.Cu")
		(net "M_G_ODT<0>")
	)
	(segment
		(start 107.439968 -21.844)
		(end 107.439968 -21.0185)
		(width 0.14224)
		(layer "In9.Cu")
		(net "M_G_ODT<0>")
	)
	(segment
		(start 107.516168 -21.9202)
		(end 107.439968 -21.844)
		(width 0.14224)
		(layer "In9.Cu")
		(net "M_G_ODT<0>")
	)
	(segment
		(start 84.949538 -16.716502)
		(end 84.949284 -16.716756)
		(width 0.1651)
		(layer "F.Cu")
		(net "M_G_MA<9>")
	)
	(segment
		(start 89.211912 -52.12334)
		(end 88.640412 -52.12334)
		(width 0.1016)
		(layer "F.Cu")
		(net "M_G_MA<9>")
	)
	(segment
		(start 84.949538 -15.423642)
		(end 84.949538 -16.716502)
		(width 0.1651)
		(layer "F.Cu")
		(net "M_G_MA<9>")
	)
	(via
		(at 88.640412 -52.12334)
		(size 0.508)
		(drill 0.254)
		(layers "F.Cu" "B.Cu")
		(net "M_G_MA<9>")
	)
	(via
		(at 84.949538 -23.560278)
		(size 0.508)
		(drill 0.254)
		(layers "F.Cu" "B.Cu")
		(net "M_G_MA<9>")
	)
	(via
		(at 84.949284 -16.716756)
		(size 0.4572)
		(drill 0.2032)
		(layers "F.Cu" "B.Cu")
		(net "M_G_MA<9>")
	)
	(segment
		(start 84.949538 -23.560278)
		(end 84.949538 -24.824182)
		(width 0.1651)
		(layer "B.Cu")
		(net "M_G_MA<9>")
	)
	(segment
		(start 84.884768 -29.557726)
		(end 84.884768 -29.889196)
		(width 0.14224)
		(layer "In11.Cu")
		(net "M_G_MA<9>")
	)
	(segment
		(start 85.367368 -24.387556)
		(end 85.367368 -26.4668)
		(width 0.14224)
		(layer "In11.Cu")
		(net "M_G_MA<9>")
	)
	(segment
		(start 85.341968 -21.8694)
		(end 85.434932 -21.962364)
		(width 0.14224)
		(layer "In11.Cu")
		(net "M_G_MA<9>")
	)
	(segment
		(start 85.434932 -22.462236)
		(end 85.291168 -22.606)
		(width 0.14224)
		(layer "In11.Cu")
		(net "M_G_MA<9>")
	)
	(segment
		(start 84.949538 -23.969726)
		(end 85.367368 -24.387556)
		(width 0.14224)
		(layer "In11.Cu")
		(net "M_G_MA<9>")
	)
	(segment
		(start 84.884768 -28.190698)
		(end 85.087968 -28.393898)
		(width 0.14224)
		(layer "In11.Cu")
		(net "M_G_MA<9>")
	)
	(segment
		(start 86.122764 -28.393898)
		(end 86.326472 -28.597606)
		(width 0.14224)
		(layer "In11.Cu")
		(net "M_G_MA<9>")
	)
	(segment
		(start 85.388196 -21.238972)
		(end 85.341968 -21.2852)
		(width 0.14224)
		(layer "In11.Cu")
		(net "M_G_MA<9>")
	)
	(segment
		(start 85.388196 -17.155668)
		(end 85.388196 -21.238972)
		(width 0.14224)
		(layer "In11.Cu")
		(net "M_G_MA<9>")
	)
	(segment
		(start 85.291168 -22.606)
		(end 85.291168 -23.218648)
		(width 0.14224)
		(layer "In11.Cu")
		(net "M_G_MA<9>")
	)
	(segment
		(start 85.434932 -21.962364)
		(end 85.434932 -22.462236)
		(width 0.14224)
		(layer "In11.Cu")
		(net "M_G_MA<9>")
	)
	(segment
		(start 85.341968 -21.2852)
		(end 85.341968 -21.8694)
		(width 0.14224)
		(layer "In11.Cu")
		(net "M_G_MA<9>")
	)
	(segment
		(start 88.134952 -50.561748)
		(end 88.134952 -50.852324)
		(width 0.0889)
		(layer "In11.Cu")
		(net "M_G_MA<9>")
	)
	(segment
		(start 88.640412 -51.357784)
		(end 88.640412 -52.12334)
		(width 0.0889)
		(layer "In11.Cu")
		(net "M_G_MA<9>")
	)
	(segment
		(start 84.884768 -29.889196)
		(end 88.134952 -33.13938)
		(width 0.14224)
		(layer "In11.Cu")
		(net "M_G_MA<9>")
	)
	(segment
		(start 88.134952 -50.852324)
		(end 88.640412 -51.357784)
		(width 0.0889)
		(layer "In11.Cu")
		(net "M_G_MA<9>")
	)
	(segment
		(start 85.367368 -26.4668)
		(end 85.545168 -26.6446)
		(width 0.14224)
		(layer "In11.Cu")
		(net "M_G_MA<9>")
	)
	(segment
		(start 84.949538 -23.560278)
		(end 84.949538 -23.969726)
		(width 0.14224)
		(layer "In11.Cu")
		(net "M_G_MA<9>")
	)
	(segment
		(start 88.134952 -33.13938)
		(end 88.134952 -50.561748)
		(width 0.14224)
		(layer "In11.Cu")
		(net "M_G_MA<9>")
	)
	(segment
		(start 86.326472 -29.151834)
		(end 86.12378 -29.354526)
		(width 0.14224)
		(layer "In11.Cu")
		(net "M_G_MA<9>")
	)
	(segment
		(start 86.12378 -29.354526)
		(end 85.087968 -29.354526)
		(width 0.14224)
		(layer "In11.Cu")
		(net "M_G_MA<9>")
	)
	(segment
		(start 85.291168 -23.218648)
		(end 84.949538 -23.560278)
		(width 0.14224)
		(layer "In11.Cu")
		(net "M_G_MA<9>")
	)
	(segment
		(start 84.884768 -27.80792)
		(end 84.884768 -28.190698)
		(width 0.14224)
		(layer "In11.Cu")
		(net "M_G_MA<9>")
	)
	(segment
		(start 86.326472 -28.597606)
		(end 86.326472 -29.151834)
		(width 0.14224)
		(layer "In11.Cu")
		(net "M_G_MA<9>")
	)
	(segment
		(start 85.545168 -26.6446)
		(end 85.545168 -27.14752)
		(width 0.14224)
		(layer "In11.Cu")
		(net "M_G_MA<9>")
	)
	(segment
		(start 85.087968 -29.354526)
		(end 84.884768 -29.557726)
		(width 0.14224)
		(layer "In11.Cu")
		(net "M_G_MA<9>")
	)
	(segment
		(start 85.087968 -28.393898)
		(end 86.122764 -28.393898)
		(width 0.14224)
		(layer "In11.Cu")
		(net "M_G_MA<9>")
	)
	(segment
		(start 84.949284 -16.716756)
		(end 85.388196 -17.155668)
		(width 0.14224)
		(layer "In11.Cu")
		(net "M_G_MA<9>")
	)
	(segment
		(start 85.545168 -27.14752)
		(end 84.884768 -27.80792)
		(width 0.14224)
		(layer "In11.Cu")
		(net "M_G_MA<9>")
	)
	(segment
		(start 86.328758 -27.636216)
		(end 86.455758 -27.509216)
		(width 0.1651)
		(layer "F.Cu")
		(net "M_G_MA<8>")
	)
	(segment
		(start 89.908888 -47.710344)
		(end 89.908888 -47.360078)
		(width 0.0889)
		(layer "F.Cu")
		(net "M_G_MA<8>")
	)
	(segment
		(start 86.335362 -25.350978)
		(end 86.335362 -25.000966)
		(width 0.1651)
		(layer "F.Cu")
		(net "M_G_MA<8>")
	)
	(segment
		(start 86.830662 -28.843732)
		(end 86.999572 -28.674822)
		(width 0.1651)
		(layer "F.Cu")
		(net "M_G_MA<8>")
	)
	(segment
		(start 89.908888 -47.360078)
		(end 89.908888 -32.934148)
		(width 0.1651)
		(layer "F.Cu")
		(net "M_G_MA<8>")
	)
	(segment
		(start 87.21725 -27.013916)
		(end 87.05215 -26.848816)
		(width 0.1651)
		(layer "F.Cu")
		(net "M_G_MA<8>")
	)
	(segment
		(start 86.335362 -25.000966)
		(end 86.462362 -24.873966)
		(width 0.1651)
		(layer "F.Cu")
		(net "M_G_MA<8>")
	)
	(segment
		(start 86.455758 -27.509216)
		(end 87.04199 -27.509216)
		(width 0.1651)
		(layer "F.Cu")
		(net "M_G_MA<8>")
	)
	(segment
		(start 86.595204 -26.848816)
		(end 86.411054 -26.664666)
		(width 0.1651)
		(layer "F.Cu")
		(net "M_G_MA<8>")
	)
	(segment
		(start 86.838282 -28.170632)
		(end 86.493858 -28.170632)
		(width 0.1651)
		(layer "F.Cu")
		(net "M_G_MA<8>")
	)
	(segment
		(start 90.070178 -50.63744)
		(end 90.207846 -50.499772)
		(width 0.0889)
		(layer "F.Cu")
		(net "M_G_MA<8>")
	)
	(segment
		(start 87.067644 -25.528016)
		(end 86.5124 -25.528016)
		(width 0.1651)
		(layer "F.Cu")
		(net "M_G_MA<8>")
	)
	(segment
		(start 90.207846 -50.499772)
		(end 90.207846 -48.009302)
		(width 0.0889)
		(layer "F.Cu")
		(net "M_G_MA<8>")
	)
	(segment
		(start 86.328758 -28.005532)
		(end 86.328758 -27.636216)
		(width 0.1651)
		(layer "F.Cu")
		(net "M_G_MA<8>")
	)
	(segment
		(start 86.411054 -26.664666)
		(end 86.411054 -26.334466)
		(width 0.1651)
		(layer "F.Cu")
		(net "M_G_MA<8>")
	)
	(segment
		(start 86.493858 -28.170632)
		(end 86.328758 -28.005532)
		(width 0.1651)
		(layer "F.Cu")
		(net "M_G_MA<8>")
	)
	(segment
		(start 90.207846 -48.009302)
		(end 89.908888 -47.710344)
		(width 0.0889)
		(layer "F.Cu")
		(net "M_G_MA<8>")
	)
	(segment
		(start 87.04199 -27.509216)
		(end 87.21725 -27.333956)
		(width 0.1651)
		(layer "F.Cu")
		(net "M_G_MA<8>")
	)
	(segment
		(start 86.41842 -28.997656)
		(end 86.572344 -28.843732)
		(width 0.1651)
		(layer "F.Cu")
		(net "M_G_MA<8>")
	)
	(segment
		(start 86.999572 -28.331922)
		(end 86.838282 -28.170632)
		(width 0.1651)
		(layer "F.Cu")
		(net "M_G_MA<8>")
	)
	(segment
		(start 86.979252 -24.873966)
		(end 87.166704 -24.686514)
		(width 0.1651)
		(layer "F.Cu")
		(net "M_G_MA<8>")
	)
	(segment
		(start 87.166704 -24.3967)
		(end 86.95309 -24.183086)
		(width 0.1651)
		(layer "F.Cu")
		(net "M_G_MA<8>")
	)
	(segment
		(start 86.462362 -24.873966)
		(end 86.979252 -24.873966)
		(width 0.1651)
		(layer "F.Cu")
		(net "M_G_MA<8>")
	)
	(segment
		(start 87.166704 -24.686514)
		(end 87.166704 -24.3967)
		(width 0.1651)
		(layer "F.Cu")
		(net "M_G_MA<8>")
	)
	(segment
		(start 86.81466 -24.183086)
		(end 86.64956 -24.017986)
		(width 0.1651)
		(layer "F.Cu")
		(net "M_G_MA<8>")
	)
	(segment
		(start 87.067644 -26.188416)
		(end 87.232744 -26.023316)
		(width 0.1651)
		(layer "F.Cu")
		(net "M_G_MA<8>")
	)
	(segment
		(start 89.908888 -32.934148)
		(end 86.41842 -29.44368)
		(width 0.1651)
		(layer "F.Cu")
		(net "M_G_MA<8>")
	)
	(segment
		(start 86.999572 -28.674822)
		(end 86.999572 -28.331922)
		(width 0.1651)
		(layer "F.Cu")
		(net "M_G_MA<8>")
	)
	(segment
		(start 86.5124 -25.528016)
		(end 86.335362 -25.350978)
		(width 0.1651)
		(layer "F.Cu")
		(net "M_G_MA<8>")
	)
	(segment
		(start 86.64956 -24.017986)
		(end 86.64956 -23.560278)
		(width 0.1651)
		(layer "F.Cu")
		(net "M_G_MA<8>")
	)
	(segment
		(start 86.572344 -28.843732)
		(end 86.830662 -28.843732)
		(width 0.1651)
		(layer "F.Cu")
		(net "M_G_MA<8>")
	)
	(segment
		(start 87.21725 -27.333956)
		(end 87.21725 -27.013916)
		(width 0.1651)
		(layer "F.Cu")
		(net "M_G_MA<8>")
	)
	(segment
		(start 86.41842 -29.44368)
		(end 86.41842 -28.997656)
		(width 0.1651)
		(layer "F.Cu")
		(net "M_G_MA<8>")
	)
	(segment
		(start 86.95309 -24.183086)
		(end 86.81466 -24.183086)
		(width 0.1651)
		(layer "F.Cu")
		(net "M_G_MA<8>")
	)
	(segment
		(start 87.05215 -26.848816)
		(end 86.595204 -26.848816)
		(width 0.1651)
		(layer "F.Cu")
		(net "M_G_MA<8>")
	)
	(segment
		(start 87.232744 -25.693116)
		(end 87.067644 -25.528016)
		(width 0.1651)
		(layer "F.Cu")
		(net "M_G_MA<8>")
	)
	(segment
		(start 86.557104 -26.188416)
		(end 87.067644 -26.188416)
		(width 0.1651)
		(layer "F.Cu")
		(net "M_G_MA<8>")
	)
	(segment
		(start 87.232744 -26.023316)
		(end 87.232744 -25.693116)
		(width 0.1651)
		(layer "F.Cu")
		(net "M_G_MA<8>")
	)
	(segment
		(start 86.411054 -26.334466)
		(end 86.557104 -26.188416)
		(width 0.1651)
		(layer "F.Cu")
		(net "M_G_MA<8>")
	)
	(segment
		(start 86.64956 -16.718788)
		(end 86.64956 -15.423642)
		(width 0.1651)
		(layer "F.Cu")
		(net "M_G_MA<8>")
	)
	(via
		(at 86.64956 -16.718788)
		(size 0.4572)
		(drill 0.2032)
		(layers "F.Cu" "B.Cu")
		(net "M_G_MA<8>")
	)
	(via
		(at 86.64956 -23.560278)
		(size 0.508)
		(drill 0.254)
		(layers "F.Cu" "B.Cu")
		(net "M_G_MA<8>")
	)
	(segment
		(start 86.64956 -23.560278)
		(end 86.64956 -24.824182)
		(width 0.1651)
		(layer "B.Cu")
		(net "M_G_MA<8>")
	)
	(segment
		(start 86.208616 -19.365214)
		(end 86.208616 -17.783556)
		(width 0.14224)
		(layer "In9.Cu")
		(net "M_G_MA<8>")
	)
	(segment
		(start 86.208616 -17.783556)
		(end 86.64956 -16.718788)
		(width 0.14224)
		(layer "In9.Cu")
		(net "M_G_MA<8>")
	)
	(segment
		(start 86.307168 -19.6977)
		(end 86.208616 -19.365214)
		(width 0.14224)
		(layer "In9.Cu")
		(net "M_G_MA<8>")
	)
	(segment
		(start 86.174072 -21.900896)
		(end 86.307168 -21.7678)
		(width 0.14224)
		(layer "In9.Cu")
		(net "M_G_MA<8>")
	)
	(segment
		(start 86.174072 -22.388576)
		(end 86.174072 -21.900896)
		(width 0.14224)
		(layer "In9.Cu")
		(net "M_G_MA<8>")
	)
	(segment
		(start 86.42858 -22.836632)
		(end 86.174072 -22.388576)
		(width 0.14224)
		(layer "In9.Cu")
		(net "M_G_MA<8>")
	)
	(segment
		(start 86.307168 -21.7678)
		(end 86.307168 -19.6977)
		(width 0.14224)
		(layer "In9.Cu")
		(net "M_G_MA<8>")
	)
	(segment
		(start 86.64956 -23.560278)
		(end 86.42858 -22.836632)
		(width 0.14224)
		(layer "In9.Cu")
		(net "M_G_MA<8>")
	)
	(segment
		(start 85.799422 -22.173946)
		(end 85.291168 -22.6822)
		(width 0.1651)
		(layer "F.Cu")
		(net "M_G_MA<7>")
	)
	(segment
		(start 89.404698 -47.323248)
		(end 89.404698 -47.597822)
		(width 0.0889)
		(layer "F.Cu")
		(net "M_G_MA<7>")
	)
	(segment
		(start 89.404698 -33.14319)
		(end 89.404698 -47.323248)
		(width 0.1651)
		(layer "F.Cu")
		(net "M_G_MA<7>")
	)
	(segment
		(start 85.291168 -22.6822)
		(end 85.291168 -23.114)
		(width 0.1651)
		(layer "F.Cu")
		(net "M_G_MA<7>")
	)
	(segment
		(start 85.824568 -29.56306)
		(end 89.404698 -33.14319)
		(width 0.1651)
		(layer "F.Cu")
		(net "M_G_MA<7>")
	)
	(segment
		(start 85.824568 -28.944824)
		(end 85.824568 -29.56306)
		(width 0.1651)
		(layer "F.Cu")
		(net "M_G_MA<7>")
	)
	(segment
		(start 85.799422 -20.023582)
		(end 85.799422 -18.734278)
		(width 0.1651)
		(layer "F.Cu")
		(net "M_G_MA<7>")
	)
	(segment
		(start 85.824568 -23.6474)
		(end 85.824568 -28.944824)
		(width 0.1651)
		(layer "F.Cu")
		(net "M_G_MA<7>")
	)
	(segment
		(start 89.723722 -50.837338)
		(end 89.732612 -50.852578)
		(width 0.0889)
		(layer "F.Cu")
		(net "M_G_MA<7>")
	)
	(segment
		(start 85.799422 -21.488146)
		(end 85.799422 -22.173946)
		(width 0.1651)
		(layer "F.Cu")
		(net "M_G_MA<7>")
	)
	(segment
		(start 89.67978 -47.872904)
		(end 89.67978 -50.72507)
		(width 0.0889)
		(layer "F.Cu")
		(net "M_G_MA<7>")
	)
	(segment
		(start 85.291168 -23.114)
		(end 85.824568 -23.6474)
		(width 0.1651)
		(layer "F.Cu")
		(net "M_G_MA<7>")
	)
	(segment
		(start 89.739724 -51.85537)
		(end 90.070178 -52.618386)
		(width 0.0889)
		(layer "F.Cu")
		(net "M_G_MA<7>")
	)
	(segment
		(start 89.404698 -47.597822)
		(end 89.67978 -47.872904)
		(width 0.0889)
		(layer "F.Cu")
		(net "M_G_MA<7>")
	)
	(segment
		(start 89.723722 -51.827938)
		(end 89.739724 -51.85537)
		(width 0.0889)
		(layer "F.Cu")
		(net "M_G_MA<7>")
	)
	(via
		(at 85.824568 -28.944824)
		(size 0.508)
		(drill 0.254)
		(layers "F.Cu" "B.Cu")
		(net "M_G_MA<7>")
	)
	(via
		(at 85.799422 -18.734278)
		(size 0.4572)
		(drill 0.2032)
		(layers "F.Cu" "B.Cu")
		(net "M_G_MA<7>")
	)
	(via
		(at 85.799422 -21.488146)
		(size 0.508)
		(drill 0.254)
		(layers "F.Cu" "B.Cu")
		(net "M_G_MA<7>")
	)
	(arc
		(start 89.67978 -50.72507)
		(mid 89.697485 -50.782875)
		(end 89.723722 -50.837338)
		(width 0.0889)
		(layer "F.Cu")
		(net "M_G_MA<7>")
	)
	(arc
		(start 89.732612 -50.852578)
		(mid 89.803009 -51.141529)
		(end 89.723722 -51.428142)
		(width 0.0889)
		(layer "F.Cu")
		(net "M_G_MA<7>")
	)
	(arc
		(start 89.723722 -51.428142)
		(mid 89.670189 -51.62804)
		(end 89.723722 -51.827938)
		(width 0.0889)
		(layer "F.Cu")
		(net "M_G_MA<7>")
	)
	(segment
		(start 85.799422 -20.224242)
		(end 85.799422 -21.488146)
		(width 0.1651)
		(layer "B.Cu")
		(net "M_G_MA<7>")
	)
	(segment
		(start 84.598256 -20.870926)
		(end 84.598256 -21.285454)
		(width 0.14224)
		(layer "In9.Cu")
		(net "M_G_MA<7>")
	)
	(segment
		(start 85.579458 -20.528026)
		(end 85.406484 -20.701)
		(width 0.14224)
		(layer "In9.Cu")
		(net "M_G_MA<7>")
	)
	(segment
		(start 84.800948 -21.488146)
		(end 85.799422 -21.488146)
		(width 0.14224)
		(layer "In9.Cu")
		(net "M_G_MA<7>")
	)
	(segment
		(start 85.799422 -18.734278)
		(end 85.3059 -19.2278)
		(width 0.14224)
		(layer "In9.Cu")
		(net "M_G_MA<7>")
	)
	(segment
		(start 85.3059 -19.2278)
		(end 84.316062 -19.2278)
		(width 0.14224)
		(layer "In9.Cu")
		(net "M_G_MA<7>")
	)
	(segment
		(start 85.406484 -20.701)
		(end 84.768182 -20.701)
		(width 0.14224)
		(layer "In9.Cu")
		(net "M_G_MA<7>")
	)
	(segment
		(start 84.768182 -20.701)
		(end 84.598256 -20.870926)
		(width 0.14224)
		(layer "In9.Cu")
		(net "M_G_MA<7>")
	)
	(segment
		(start 85.579458 -20.147026)
		(end 85.579458 -20.528026)
		(width 0.14224)
		(layer "In9.Cu")
		(net "M_G_MA<7>")
	)
	(segment
		(start 84.176108 -19.813778)
		(end 84.32673 -19.9644)
		(width 0.14224)
		(layer "In9.Cu")
		(net "M_G_MA<7>")
	)
	(segment
		(start 85.396832 -19.9644)
		(end 85.579458 -20.147026)
		(width 0.14224)
		(layer "In9.Cu")
		(net "M_G_MA<7>")
	)
	(segment
		(start 84.32673 -19.9644)
		(end 85.396832 -19.9644)
		(width 0.14224)
		(layer "In9.Cu")
		(net "M_G_MA<7>")
	)
	(segment
		(start 84.598256 -21.285454)
		(end 84.800948 -21.488146)
		(width 0.14224)
		(layer "In9.Cu")
		(net "M_G_MA<7>")
	)
	(segment
		(start 84.176108 -19.367754)
		(end 84.176108 -19.813778)
		(width 0.14224)
		(layer "In9.Cu")
		(net "M_G_MA<7>")
	)
	(segment
		(start 84.316062 -19.2278)
		(end 84.176108 -19.367754)
		(width 0.14224)
		(layer "In9.Cu")
		(net "M_G_MA<7>")
	)
	(segment
		(start 89.160604 -31.19755)
		(end 89.160604 -31.472378)
		(width 0.1651)
		(layer "F.Cu")
		(net "M_G_MA<6>")
	)
	(segment
		(start 87.295228 -22.64664)
		(end 87.061294 -22.64664)
		(width 0.1651)
		(layer "F.Cu")
		(net "M_G_MA<6>")
	)
	(segment
		(start 87.754968 -24.340058)
		(end 87.754968 -28.464002)
		(width 0.1651)
		(layer "F.Cu")
		(net "M_G_MA<6>")
	)
	(segment
		(start 87.754968 -28.464002)
		(end 87.754968 -29.080968)
		(width 0.1651)
		(layer "F.Cu")
		(net "M_G_MA<6>")
	)
	(segment
		(start 90.479372 -47.719996)
		(end 90.479372 -50.18532)
		(width 0.0889)
		(layer "F.Cu")
		(net "M_G_MA<6>")
	)
	(segment
		(start 88.239854 -30.249622)
		(end 88.239854 -30.483048)
		(width 0.1651)
		(layer "F.Cu")
		(net "M_G_MA<6>")
	)
	(segment
		(start 90.108278 -32.351472)
		(end 90.413078 -32.656272)
		(width 0.1651)
		(layer "F.Cu")
		(net "M_G_MA<6>")
	)
	(segment
		(start 90.333576 -31.892748)
		(end 90.108278 -32.118046)
		(width 0.1651)
		(layer "F.Cu")
		(net "M_G_MA<6>")
	)
	(segment
		(start 89.160604 -31.472378)
		(end 89.373456 -31.68523)
		(width 0.1651)
		(layer "F.Cu")
		(net "M_G_MA<6>")
	)
	(segment
		(start 88.70696 -30.716982)
		(end 88.932512 -30.49143)
		(width 0.1651)
		(layer "F.Cu")
		(net "M_G_MA<6>")
	)
	(segment
		(start 89.16543 -30.49143)
		(end 89.399364 -30.725364)
		(width 0.1651)
		(layer "F.Cu")
		(net "M_G_MA<6>")
	)
	(segment
		(start 87.754968 -29.080968)
		(end 88.465152 -29.791152)
		(width 0.1651)
		(layer "F.Cu")
		(net "M_G_MA<6>")
	)
	(segment
		(start 89.607136 -31.68523)
		(end 89.866724 -31.425642)
		(width 0.1651)
		(layer "F.Cu")
		(net "M_G_MA<6>")
	)
	(segment
		(start 90.108278 -32.118046)
		(end 90.108278 -32.351472)
		(width 0.1651)
		(layer "F.Cu")
		(net "M_G_MA<6>")
	)
	(segment
		(start 87.499444 -22.850856)
		(end 87.295228 -22.64664)
		(width 0.1651)
		(layer "F.Cu")
		(net "M_G_MA<6>")
	)
	(segment
		(start 90.413078 -32.656272)
		(end 90.413078 -47.233332)
		(width 0.1651)
		(layer "F.Cu")
		(net "M_G_MA<6>")
	)
	(segment
		(start 86.85911 -22.848824)
		(end 86.85911 -23.12797)
		(width 0.1651)
		(layer "F.Cu")
		(net "M_G_MA<6>")
	)
	(segment
		(start 89.399364 -30.95879)
		(end 89.160604 -31.19755)
		(width 0.1651)
		(layer "F.Cu")
		(net "M_G_MA<6>")
	)
	(segment
		(start 87.061294 -22.64664)
		(end 86.85911 -22.848824)
		(width 0.1651)
		(layer "F.Cu")
		(net "M_G_MA<6>")
	)
	(segment
		(start 89.373456 -31.68523)
		(end 89.607136 -31.68523)
		(width 0.1651)
		(layer "F.Cu")
		(net "M_G_MA<6>")
	)
	(segment
		(start 88.473788 -30.716982)
		(end 88.70696 -30.716982)
		(width 0.1651)
		(layer "F.Cu")
		(net "M_G_MA<6>")
	)
	(segment
		(start 86.85911 -23.12797)
		(end 87.196168 -23.465028)
		(width 0.1651)
		(layer "F.Cu")
		(net "M_G_MA<6>")
	)
	(segment
		(start 87.196168 -23.465028)
		(end 87.196168 -23.781258)
		(width 0.1651)
		(layer "F.Cu")
		(net "M_G_MA<6>")
	)
	(segment
		(start 90.099642 -31.425642)
		(end 90.333576 -31.659576)
		(width 0.1651)
		(layer "F.Cu")
		(net "M_G_MA<6>")
	)
	(segment
		(start 88.465152 -29.791152)
		(end 88.465152 -30.024324)
		(width 0.1651)
		(layer "F.Cu")
		(net "M_G_MA<6>")
	)
	(segment
		(start 90.413078 -47.233332)
		(end 90.413078 -47.653702)
		(width 0.0889)
		(layer "F.Cu")
		(net "M_G_MA<6>")
	)
	(segment
		(start 88.932512 -30.49143)
		(end 89.16543 -30.49143)
		(width 0.1651)
		(layer "F.Cu")
		(net "M_G_MA<6>")
	)
	(segment
		(start 89.399364 -30.725364)
		(end 89.399364 -30.95879)
		(width 0.1651)
		(layer "F.Cu")
		(net "M_G_MA<6>")
	)
	(segment
		(start 89.866724 -31.425642)
		(end 90.099642 -31.425642)
		(width 0.1651)
		(layer "F.Cu")
		(net "M_G_MA<6>")
	)
	(segment
		(start 87.196168 -23.781258)
		(end 87.754968 -24.340058)
		(width 0.1651)
		(layer "F.Cu")
		(net "M_G_MA<6>")
	)
	(segment
		(start 88.465152 -30.024324)
		(end 88.239854 -30.249622)
		(width 0.1651)
		(layer "F.Cu")
		(net "M_G_MA<6>")
	)
	(segment
		(start 90.413078 -47.653702)
		(end 90.479372 -47.719996)
		(width 0.0889)
		(layer "F.Cu")
		(net "M_G_MA<6>")
	)
	(segment
		(start 90.479372 -50.18532)
		(end 90.928698 -51.132486)
		(width 0.0889)
		(layer "F.Cu")
		(net "M_G_MA<6>")
	)
	(segment
		(start 87.499444 -15.423642)
		(end 87.499444 -16.718788)
		(width 0.1651)
		(layer "F.Cu")
		(net "M_G_MA<6>")
	)
	(segment
		(start 88.239854 -30.483048)
		(end 88.473788 -30.716982)
		(width 0.1651)
		(layer "F.Cu")
		(net "M_G_MA<6>")
	)
	(segment
		(start 90.333576 -31.659576)
		(end 90.333576 -31.892748)
		(width 0.1651)
		(layer "F.Cu")
		(net "M_G_MA<6>")
	)
	(via
		(at 87.754968 -28.464002)
		(size 0.508)
		(drill 0.254)
		(layers "F.Cu" "B.Cu")
		(net "M_G_MA<6>")
	)
	(via
		(at 87.499444 -16.718788)
		(size 0.4572)
		(drill 0.2032)
		(layers "F.Cu" "B.Cu")
		(net "M_G_MA<6>")
	)
	(via
		(at 87.499444 -22.850856)
		(size 0.508)
		(drill 0.254)
		(layers "F.Cu" "B.Cu")
		(net "M_G_MA<6>")
	)
	(segment
		(start 87.499444 -22.850856)
		(end 87.499444 -24.824182)
		(width 0.1651)
		(layer "B.Cu")
		(net "M_G_MA<6>")
	)
	(segment
		(start 87.499444 -22.850856)
		(end 86.858602 -21.30425)
		(width 0.14224)
		(layer "In9.Cu")
		(net "M_G_MA<6>")
	)
	(segment
		(start 86.858602 -21.30425)
		(end 86.858602 -19.376136)
		(width 0.14224)
		(layer "In9.Cu")
		(net "M_G_MA<6>")
	)
	(segment
		(start 87.398098 -16.96339)
		(end 87.499444 -16.718788)
		(width 0.14224)
		(layer "In9.Cu")
		(net "M_G_MA<6>")
	)
	(segment
		(start 87.084154 -18.832068)
		(end 87.084154 -18.542508)
		(width 0.14224)
		(layer "In9.Cu")
		(net "M_G_MA<6>")
	)
	(segment
		(start 87.084154 -18.542508)
		(end 87.398098 -16.96339)
		(width 0.14224)
		(layer "In9.Cu")
		(net "M_G_MA<6>")
	)
	(segment
		(start 86.858602 -19.376136)
		(end 87.084154 -18.832068)
		(width 0.14224)
		(layer "In9.Cu")
		(net "M_G_MA<6>")
	)
	(segment
		(start 87.499444 -20.023582)
		(end 87.499444 -18.734278)
		(width 0.1651)
		(layer "F.Cu")
		(net "M_G_MA<5>")
	)
	(segment
		(start 90.917268 -31.530036)
		(end 88.288368 -28.901136)
		(width 0.1651)
		(layer "F.Cu")
		(net "M_G_MA<5>")
	)
	(segment
		(start 91.025472 -52.63642)
		(end 91.050618 -52.661566)
		(width 0.0889)
		(layer "F.Cu")
		(net "M_G_MA<5>")
	)
	(segment
		(start 91.275408 -50.932588)
		(end 91.269058 -50.92192)
		(width 0.0889)
		(layer "F.Cu")
		(net "M_G_MA<5>")
	)
	(segment
		(start 88.288368 -28.901136)
		(end 88.288368 -26.414222)
		(width 0.1651)
		(layer "F.Cu")
		(net "M_G_MA<5>")
	)
	(segment
		(start 91.336368 -50.114454)
		(end 91.336368 -48.919384)
		(width 0.0889)
		(layer "F.Cu")
		(net "M_G_MA<5>")
	)
	(segment
		(start 88.288368 -26.414222)
		(end 88.288368 -24.154892)
		(width 0.1651)
		(layer "F.Cu")
		(net "M_G_MA<5>")
	)
	(segment
		(start 91.401138 -52.141628)
		(end 91.275408 -51.923442)
		(width 0.0889)
		(layer "F.Cu")
		(net "M_G_MA<5>")
	)
	(segment
		(start 91.186254 -52.7177)
		(end 91.195398 -52.7177)
		(width 0.0889)
		(layer "F.Cu")
		(net "M_G_MA<5>")
	)
	(segment
		(start 87.886032 -23.381208)
		(end 87.962994 -23.304246)
		(width 0.1651)
		(layer "F.Cu")
		(net "M_G_MA<5>")
	)
	(segment
		(start 87.962994 -22.534626)
		(end 87.499444 -22.071076)
		(width 0.1651)
		(layer "F.Cu")
		(net "M_G_MA<5>")
	)
	(segment
		(start 87.886032 -23.752556)
		(end 87.886032 -23.381208)
		(width 0.1651)
		(layer "F.Cu")
		(net "M_G_MA<5>")
	)
	(segment
		(start 91.401646 -52.142136)
		(end 91.401138 -52.141628)
		(width 0.0889)
		(layer "F.Cu")
		(net "M_G_MA<5>")
	)
	(segment
		(start 88.288368 -24.154892)
		(end 87.886032 -23.752556)
		(width 0.1651)
		(layer "F.Cu")
		(net "M_G_MA<5>")
	)
	(segment
		(start 87.962994 -23.304246)
		(end 87.962994 -22.534626)
		(width 0.1651)
		(layer "F.Cu")
		(net "M_G_MA<5>")
	)
	(segment
		(start 91.280234 -50.941224)
		(end 91.275408 -50.932588)
		(width 0.0889)
		(layer "F.Cu")
		(net "M_G_MA<5>")
	)
	(segment
		(start 90.928698 -52.12334)
		(end 90.928698 -52.40274)
		(width 0.0889)
		(layer "F.Cu")
		(net "M_G_MA<5>")
	)
	(segment
		(start 90.917268 -48.167036)
		(end 90.917268 -31.530036)
		(width 0.1651)
		(layer "F.Cu")
		(net "M_G_MA<5>")
	)
	(segment
		(start 91.336368 -48.919384)
		(end 90.917268 -48.500284)
		(width 0.0889)
		(layer "F.Cu")
		(net "M_G_MA<5>")
	)
	(segment
		(start 90.917268 -48.500284)
		(end 90.917268 -48.167036)
		(width 0.0889)
		(layer "F.Cu")
		(net "M_G_MA<5>")
	)
	(segment
		(start 87.499444 -22.071076)
		(end 87.499444 -21.517356)
		(width 0.1651)
		(layer "F.Cu")
		(net "M_G_MA<5>")
	)
	(segment
		(start 91.401646 -52.511452)
		(end 91.401646 -52.142136)
		(width 0.0889)
		(layer "F.Cu")
		(net "M_G_MA<5>")
	)
	(via
		(at 88.288368 -26.414222)
		(size 0.508)
		(drill 0.254)
		(layers "F.Cu" "B.Cu")
		(net "M_G_MA<5>")
	)
	(via
		(at 87.499444 -18.734278)
		(size 0.4572)
		(drill 0.2032)
		(layers "F.Cu" "B.Cu")
		(net "M_G_MA<5>")
	)
	(via
		(at 87.499444 -21.517356)
		(size 0.508)
		(drill 0.254)
		(layers "F.Cu" "B.Cu")
		(net "M_G_MA<5>")
	)
	(arc
		(start 91.195398 -52.7177)
		(mid 91.341237 -52.657291)
		(end 91.401646 -52.511452)
		(width 0.0889)
		(layer "F.Cu")
		(net "M_G_MA<5>")
	)
	(arc
		(start 91.275408 -51.332638)
		(mid 91.328878 -51.137575)
		(end 91.280234 -50.941224)
		(width 0.0889)
		(layer "F.Cu")
		(net "M_G_MA<5>")
	)
	(arc
		(start 91.275408 -50.342038)
		(mid 91.320852 -50.232255)
		(end 91.336368 -50.114454)
		(width 0.0889)
		(layer "F.Cu")
		(net "M_G_MA<5>")
	)
	(arc
		(start 90.928698 -52.40274)
		(mid 90.953852 -52.529199)
		(end 91.025472 -52.63642)
		(width 0.0889)
		(layer "F.Cu")
		(net "M_G_MA<5>")
	)
	(arc
		(start 91.275408 -51.923442)
		(mid 91.196277 -51.62804)
		(end 91.275408 -51.332638)
		(width 0.0889)
		(layer "F.Cu")
		(net "M_G_MA<5>")
	)
	(arc
		(start 91.050618 -52.661566)
		(mid 91.112863 -52.703093)
		(end 91.186254 -52.7177)
		(width 0.0889)
		(layer "F.Cu")
		(net "M_G_MA<5>")
	)
	(arc
		(start 91.269058 -50.92192)
		(mid 91.19626 -50.631157)
		(end 91.275408 -50.342038)
		(width 0.0889)
		(layer "F.Cu")
		(net "M_G_MA<5>")
	)
	(segment
		(start 87.499444 -20.224242)
		(end 87.499444 -21.517356)
		(width 0.1651)
		(layer "B.Cu")
		(net "M_G_MA<5>")
	)
	(segment
		(start 87.499444 -18.734278)
		(end 87.801704 -18.734278)
		(width 0.14224)
		(layer "In9.Cu")
		(net "M_G_MA<5>")
	)
	(segment
		(start 87.433404 -19.844258)
		(end 87.786718 -19.844258)
		(width 0.14224)
		(layer "In9.Cu")
		(net "M_G_MA<5>")
	)
	(segment
		(start 87.758016 -21.517356)
		(end 87.499444 -21.517356)
		(width 0.14224)
		(layer "In9.Cu")
		(net "M_G_MA<5>")
	)
	(segment
		(start 87.278464 -19.689318)
		(end 87.433404 -19.844258)
		(width 0.14224)
		(layer "In9.Cu")
		(net "M_G_MA<5>")
	)
	(segment
		(start 87.928958 -20.2819)
		(end 87.776304 -20.434554)
		(width 0.14224)
		(layer "In9.Cu")
		(net "M_G_MA<5>")
	)
	(segment
		(start 87.786718 -19.844258)
		(end 87.928958 -19.986498)
		(width 0.14224)
		(layer "In9.Cu")
		(net "M_G_MA<5>")
	)
	(segment
		(start 87.433404 -19.282918)
		(end 87.278464 -19.437858)
		(width 0.14224)
		(layer "In9.Cu")
		(net "M_G_MA<5>")
	)
	(segment
		(start 87.891366 -21.384006)
		(end 87.758016 -21.517356)
		(width 0.14224)
		(layer "In9.Cu")
		(net "M_G_MA<5>")
	)
	(segment
		(start 87.933022 -19.151854)
		(end 87.801958 -19.282918)
		(width 0.14224)
		(layer "In9.Cu")
		(net "M_G_MA<5>")
	)
	(segment
		(start 87.43315 -20.434554)
		(end 87.282274 -20.58543)
		(width 0.14224)
		(layer "In9.Cu")
		(net "M_G_MA<5>")
	)
	(segment
		(start 87.764366 -20.975574)
		(end 87.891366 -21.102574)
		(width 0.14224)
		(layer "In9.Cu")
		(net "M_G_MA<5>")
	)
	(segment
		(start 87.801958 -19.282918)
		(end 87.433404 -19.282918)
		(width 0.14224)
		(layer "In9.Cu")
		(net "M_G_MA<5>")
	)
	(segment
		(start 87.282274 -20.81657)
		(end 87.441278 -20.975574)
		(width 0.14224)
		(layer "In9.Cu")
		(net "M_G_MA<5>")
	)
	(segment
		(start 87.278464 -19.437858)
		(end 87.278464 -19.689318)
		(width 0.14224)
		(layer "In9.Cu")
		(net "M_G_MA<5>")
	)
	(segment
		(start 87.801704 -18.734278)
		(end 87.933022 -18.865596)
		(width 0.14224)
		(layer "In9.Cu")
		(net "M_G_MA<5>")
	)
	(segment
		(start 87.282274 -20.58543)
		(end 87.282274 -20.81657)
		(width 0.14224)
		(layer "In9.Cu")
		(net "M_G_MA<5>")
	)
	(segment
		(start 87.933022 -18.865596)
		(end 87.933022 -19.151854)
		(width 0.14224)
		(layer "In9.Cu")
		(net "M_G_MA<5>")
	)
	(segment
		(start 87.441278 -20.975574)
		(end 87.764366 -20.975574)
		(width 0.14224)
		(layer "In9.Cu")
		(net "M_G_MA<5>")
	)
	(segment
		(start 87.891366 -21.102574)
		(end 87.891366 -21.384006)
		(width 0.14224)
		(layer "In9.Cu")
		(net "M_G_MA<5>")
	)
	(segment
		(start 87.776304 -20.434554)
		(end 87.43315 -20.434554)
		(width 0.14224)
		(layer "In9.Cu")
		(net "M_G_MA<5>")
	)
	(segment
		(start 87.928958 -19.986498)
		(end 87.928958 -20.2819)
		(width 0.14224)
		(layer "In9.Cu")
		(net "M_G_MA<5>")
	)
	(segment
		(start 91.546172 -48.654716)
		(end 91.421458 -48.530002)
		(width 0.0889)
		(layer "F.Cu")
		(net "M_G_MA<4>")
	)
	(segment
		(start 91.619832 -52.139342)
		(end 91.435682 -51.819302)
		(width 0.0889)
		(layer "F.Cu")
		(net "M_G_MA<4>")
	)
	(segment
		(start 88.821768 -27.595322)
		(end 88.821768 -23.2664)
		(width 0.1651)
		(layer "F.Cu")
		(net "M_G_MA<4>")
	)
	(segment
		(start 91.421458 -48.237902)
		(end 91.421458 -31.32074)
		(width 0.1651)
		(layer "F.Cu")
		(net "M_G_MA<4>")
	)
	(segment
		(start 88.821768 -28.72105)
		(end 88.821768 -27.595322)
		(width 0.1651)
		(layer "F.Cu")
		(net "M_G_MA<4>")
	)
	(segment
		(start 91.440508 -50.837338)
		(end 91.435682 -50.828702)
		(width 0.0889)
		(layer "F.Cu")
		(net "M_G_MA<4>")
	)
	(segment
		(start 91.70162 -52.328064)
		(end 91.619832 -52.139342)
		(width 0.0889)
		(layer "F.Cu")
		(net "M_G_MA<4>")
	)
	(segment
		(start 88.821768 -23.2664)
		(end 88.586564 -23.031196)
		(width 0.1651)
		(layer "F.Cu")
		(net "M_G_MA<4>")
	)
	(segment
		(start 91.421458 -31.32074)
		(end 88.821768 -28.72105)
		(width 0.1651)
		(layer "F.Cu")
		(net "M_G_MA<4>")
	)
	(segment
		(start 88.586564 -23.031196)
		(end 88.586564 -22.43455)
		(width 0.1651)
		(layer "F.Cu")
		(net "M_G_MA<4>")
	)
	(segment
		(start 88.586564 -22.43455)
		(end 88.349582 -22.197568)
		(width 0.1651)
		(layer "F.Cu")
		(net "M_G_MA<4>")
	)
	(segment
		(start 91.421458 -48.530002)
		(end 91.421458 -48.237902)
		(width 0.0889)
		(layer "F.Cu")
		(net "M_G_MA<4>")
	)
	(segment
		(start 88.349582 -20.023582)
		(end 88.349582 -18.734278)
		(width 0.1651)
		(layer "F.Cu")
		(net "M_G_MA<4>")
	)
	(segment
		(start 91.446858 -50.848006)
		(end 91.440508 -50.837338)
		(width 0.0889)
		(layer "F.Cu")
		(net "M_G_MA<4>")
	)
	(segment
		(start 91.787218 -52.618386)
		(end 91.70162 -52.328064)
		(width 0.0889)
		(layer "F.Cu")
		(net "M_G_MA<4>")
	)
	(segment
		(start 91.546172 -50.04308)
		(end 91.546172 -48.654716)
		(width 0.0889)
		(layer "F.Cu")
		(net "M_G_MA<4>")
	)
	(via
		(at 88.349582 -22.197568)
		(size 0.508)
		(drill 0.254)
		(layers "F.Cu" "B.Cu")
		(net "M_G_MA<4>")
	)
	(via
		(at 88.349582 -18.734278)
		(size 0.4572)
		(drill 0.2032)
		(layers "F.Cu" "B.Cu")
		(net "M_G_MA<4>")
	)
	(via
		(at 88.821768 -27.595322)
		(size 0.508)
		(drill 0.254)
		(layers "F.Cu" "B.Cu")
		(net "M_G_MA<4>")
	)
	(arc
		(start 91.440508 -50.437288)
		(mid 91.519325 -50.247147)
		(end 91.546172 -50.04308)
		(width 0.0889)
		(layer "F.Cu")
		(net "M_G_MA<4>")
	)
	(arc
		(start 91.435682 -51.819302)
		(mid 91.386927 -51.62295)
		(end 91.440508 -51.427888)
		(width 0.0889)
		(layer "F.Cu")
		(net "M_G_MA<4>")
	)
	(arc
		(start 91.435682 -50.828702)
		(mid 91.386927 -50.63235)
		(end 91.440508 -50.437288)
		(width 0.0889)
		(layer "F.Cu")
		(net "M_G_MA<4>")
	)
	(arc
		(start 91.440508 -51.427888)
		(mid 91.51973 -51.13877)
		(end 91.446858 -50.848006)
		(width 0.0889)
		(layer "F.Cu")
		(net "M_G_MA<4>")
	)
	(segment
		(start 88.349582 -22.197568)
		(end 88.349582 -20.224242)
		(width 0.1651)
		(layer "B.Cu")
		(net "M_G_MA<4>")
	)
	(segment
		(start 88.349582 -22.197568)
		(end 88.310974 -22.15896)
		(width 0.14224)
		(layer "In9.Cu")
		(net "M_G_MA<4>")
	)
	(segment
		(start 88.463374 -20.390358)
		(end 88.606376 -20.390358)
		(width 0.14224)
		(layer "In9.Cu")
		(net "M_G_MA<4>")
	)
	(segment
		(start 88.634316 -19.829018)
		(end 88.504522 -19.829018)
		(width 0.14224)
		(layer "In9.Cu")
		(net "M_G_MA<4>")
	)
	(segment
		(start 88.349582 -19.674078)
		(end 88.349582 -18.734278)
		(width 0.14224)
		(layer "In9.Cu")
		(net "M_G_MA<4>")
	)
	(segment
		(start 88.310974 -22.15896)
		(end 88.310974 -20.542758)
		(width 0.14224)
		(layer "In9.Cu")
		(net "M_G_MA<4>")
	)
	(segment
		(start 88.504522 -19.829018)
		(end 88.349582 -19.674078)
		(width 0.14224)
		(layer "In9.Cu")
		(net "M_G_MA<4>")
	)
	(segment
		(start 88.761316 -20.235418)
		(end 88.761316 -19.956018)
		(width 0.14224)
		(layer "In9.Cu")
		(net "M_G_MA<4>")
	)
	(segment
		(start 88.606376 -20.390358)
		(end 88.761316 -20.235418)
		(width 0.14224)
		(layer "In9.Cu")
		(net "M_G_MA<4>")
	)
	(segment
		(start 88.310974 -20.542758)
		(end 88.463374 -20.390358)
		(width 0.14224)
		(layer "In9.Cu")
		(net "M_G_MA<4>")
	)
	(segment
		(start 88.761316 -19.956018)
		(end 88.634316 -19.829018)
		(width 0.14224)
		(layer "In9.Cu")
		(net "M_G_MA<4>")
	)
	(segment
		(start 89.57056 -23.84806)
		(end 89.57056 -22.992334)
		(width 0.1651)
		(layer "F.Cu")
		(net "M_G_MA<3>")
	)
	(segment
		(start 89.875868 -29.061664)
		(end 89.325958 -28.511754)
		(width 0.1651)
		(layer "F.Cu")
		(net "M_G_MA<3>")
	)
	(segment
		(start 91.925648 -31.111444)
		(end 89.875868 -29.061664)
		(width 0.1651)
		(layer "F.Cu")
		(net "M_G_MA<3>")
	)
	(segment
		(start 91.862402 -48.300386)
		(end 91.925648 -48.23714)
		(width 0.0889)
		(layer "F.Cu")
		(net "M_G_MA<3>")
	)
	(segment
		(start 89.325958 -24.092662)
		(end 89.57056 -23.84806)
		(width 0.1651)
		(layer "F.Cu")
		(net "M_G_MA<3>")
	)
	(segment
		(start 91.787218 -50.63744)
		(end 91.862402 -50.562256)
		(width 0.0889)
		(layer "F.Cu")
		(net "M_G_MA<3>")
	)
	(segment
		(start 89.429082 -22.850856)
		(end 89.199466 -22.850856)
		(width 0.1651)
		(layer "F.Cu")
		(net "M_G_MA<3>")
	)
	(segment
		(start 89.57056 -22.992334)
		(end 89.429082 -22.850856)
		(width 0.1651)
		(layer "F.Cu")
		(net "M_G_MA<3>")
	)
	(segment
		(start 89.199466 -16.718788)
		(end 89.199466 -15.423642)
		(width 0.1651)
		(layer "F.Cu")
		(net "M_G_MA<3>")
	)
	(segment
		(start 91.862402 -50.562256)
		(end 91.862402 -48.300386)
		(width 0.0889)
		(layer "F.Cu")
		(net "M_G_MA<3>")
	)
	(segment
		(start 89.325958 -28.511754)
		(end 89.325958 -24.092662)
		(width 0.1651)
		(layer "F.Cu")
		(net "M_G_MA<3>")
	)
	(segment
		(start 91.925648 -48.23714)
		(end 91.925648 -47.914306)
		(width 0.0889)
		(layer "F.Cu")
		(net "M_G_MA<3>")
	)
	(segment
		(start 91.925648 -47.914306)
		(end 91.925648 -31.111444)
		(width 0.1651)
		(layer "F.Cu")
		(net "M_G_MA<3>")
	)
	(via
		(at 89.199466 -22.850856)
		(size 0.508)
		(drill 0.254)
		(layers "F.Cu" "B.Cu")
		(net "M_G_MA<3>")
	)
	(via
		(at 89.199466 -16.718788)
		(size 0.4572)
		(drill 0.2032)
		(layers "F.Cu" "B.Cu")
		(net "M_G_MA<3>")
	)
	(via
		(at 89.875868 -29.061664)
		(size 0.508)
		(drill 0.254)
		(layers "F.Cu" "B.Cu")
		(net "M_G_MA<3>")
	)
	(segment
		(start 89.199466 -22.850856)
		(end 89.199466 -24.824182)
		(width 0.1651)
		(layer "B.Cu")
		(net "M_G_MA<3>")
	)
	(segment
		(start 89.177368 -19.43862)
		(end 88.761062 -19.022314)
		(width 0.14224)
		(layer "In9.Cu")
		(net "M_G_MA<3>")
	)
	(segment
		(start 89.199466 -18.099532)
		(end 89.199466 -17.895062)
		(width 0.14224)
		(layer "In9.Cu")
		(net "M_G_MA<3>")
	)
	(segment
		(start 89.199466 -22.850856)
		(end 88.847168 -22.498558)
		(width 0.14224)
		(layer "In9.Cu")
		(net "M_G_MA<3>")
	)
	(segment
		(start 88.507824 -17.232122)
		(end 88.662764 -17.077182)
		(width 0.14224)
		(layer "In9.Cu")
		(net "M_G_MA<3>")
	)
	(segment
		(start 88.847168 -21.844)
		(end 88.730836 -21.727668)
		(width 0.14224)
		(layer "In9.Cu")
		(net "M_G_MA<3>")
	)
	(segment
		(start 88.507824 -17.585182)
		(end 88.507824 -17.232122)
		(width 0.14224)
		(layer "In9.Cu")
		(net "M_G_MA<3>")
	)
	(segment
		(start 89.044526 -17.740122)
		(end 88.662764 -17.740122)
		(width 0.14224)
		(layer "In9.Cu")
		(net "M_G_MA<3>")
	)
	(segment
		(start 88.761062 -19.022314)
		(end 88.761062 -18.537936)
		(width 0.14224)
		(layer "In9.Cu")
		(net "M_G_MA<3>")
	)
	(segment
		(start 88.730836 -21.341842)
		(end 89.177368 -20.89531)
		(width 0.14224)
		(layer "In9.Cu")
		(net "M_G_MA<3>")
	)
	(segment
		(start 88.761062 -18.537936)
		(end 89.199466 -18.099532)
		(width 0.14224)
		(layer "In9.Cu")
		(net "M_G_MA<3>")
	)
	(segment
		(start 89.044526 -17.077182)
		(end 89.199466 -16.922242)
		(width 0.14224)
		(layer "In9.Cu")
		(net "M_G_MA<3>")
	)
	(segment
		(start 89.199466 -17.895062)
		(end 89.044526 -17.740122)
		(width 0.14224)
		(layer "In9.Cu")
		(net "M_G_MA<3>")
	)
	(segment
		(start 88.847168 -22.498558)
		(end 88.847168 -21.844)
		(width 0.14224)
		(layer "In9.Cu")
		(net "M_G_MA<3>")
	)
	(segment
		(start 88.662764 -17.740122)
		(end 88.507824 -17.585182)
		(width 0.14224)
		(layer "In9.Cu")
		(net "M_G_MA<3>")
	)
	(segment
		(start 88.730836 -21.727668)
		(end 88.730836 -21.341842)
		(width 0.14224)
		(layer "In9.Cu")
		(net "M_G_MA<3>")
	)
	(segment
		(start 89.177368 -20.89531)
		(end 89.177368 -19.43862)
		(width 0.14224)
		(layer "In9.Cu")
		(net "M_G_MA<3>")
	)
	(segment
		(start 89.199466 -16.922242)
		(end 89.199466 -16.718788)
		(width 0.14224)
		(layer "In9.Cu")
		(net "M_G_MA<3>")
	)
	(segment
		(start 88.662764 -17.077182)
		(end 89.044526 -17.077182)
		(width 0.14224)
		(layer "In9.Cu")
		(net "M_G_MA<3>")
	)
	(segment
		(start 90.781378 -25.762966)
		(end 90.616278 -25.597866)
		(width 0.1651)
		(layer "F.Cu")
		(net "M_G_MA<2>")
	)
	(segment
		(start 90.616278 -25.597866)
		(end 90.512646 -25.597866)
		(width 0.1651)
		(layer "F.Cu")
		(net "M_G_MA<2>")
	)
	(segment
		(start 90.347546 -28.106624)
		(end 90.347546 -27.782266)
		(width 0.1651)
		(layer "F.Cu")
		(net "M_G_MA<2>")
	)
	(segment
		(start 90.347546 -26.778966)
		(end 90.347546 -26.436066)
		(width 0.1651)
		(layer "F.Cu")
		(net "M_G_MA<2>")
	)
	(segment
		(start 90.765122 -24.151844)
		(end 90.47226 -23.858982)
		(width 0.1651)
		(layer "F.Cu")
		(net "M_G_MA<2>")
	)
	(segment
		(start 90.347546 -27.782266)
		(end 90.512646 -27.617166)
		(width 0.1651)
		(layer "F.Cu")
		(net "M_G_MA<2>")
	)
	(segment
		(start 90.781378 -26.105866)
		(end 90.781378 -25.762966)
		(width 0.1651)
		(layer "F.Cu")
		(net "M_G_MA<2>")
	)
	(segment
		(start 92.645738 -51.132486)
		(end 92.267024 -50.25771)
		(width 0.0889)
		(layer "F.Cu")
		(net "M_G_MA<2>")
	)
	(segment
		(start 90.294968 -22.7584)
		(end 90.45702 -22.596348)
		(width 0.1651)
		(layer "F.Cu")
		(net "M_G_MA<2>")
	)
	(segment
		(start 90.049604 -18.759678)
		(end 90.049604 -18.734278)
		(width 0.1651)
		(layer "F.Cu")
		(net "M_G_MA<2>")
	)
	(segment
		(start 90.800428 -27.071066)
		(end 90.673428 -26.944066)
		(width 0.1651)
		(layer "F.Cu")
		(net "M_G_MA<2>")
	)
	(segment
		(start 90.45702 -22.362668)
		(end 90.29192 -22.197568)
		(width 0.1651)
		(layer "F.Cu")
		(net "M_G_MA<2>")
	)
	(segment
		(start 90.512646 -25.597866)
		(end 90.347546 -25.432766)
		(width 0.1651)
		(layer "F.Cu")
		(net "M_G_MA<2>")
	)
	(segment
		(start 90.29192 -22.197568)
		(end 90.02141 -22.197568)
		(width 0.1651)
		(layer "F.Cu")
		(net "M_G_MA<2>")
	)
	(segment
		(start 92.249752 -48.768762)
		(end 92.934028 -48.08474)
		(width 0.0889)
		(layer "F.Cu")
		(net "M_G_MA<2>")
	)
	(segment
		(start 92.934028 -30.693106)
		(end 90.347546 -28.106624)
		(width 0.1651)
		(layer "F.Cu")
		(net "M_G_MA<2>")
	)
	(segment
		(start 90.04935 -20.023582)
		(end 90.04935 -18.759932)
		(width 0.1651)
		(layer "F.Cu")
		(net "M_G_MA<2>")
	)
	(segment
		(start 90.04935 -18.759932)
		(end 90.049604 -18.759678)
		(width 0.1651)
		(layer "F.Cu")
		(net "M_G_MA<2>")
	)
	(segment
		(start 90.512646 -27.617166)
		(end 90.673428 -27.617166)
		(width 0.1651)
		(layer "F.Cu")
		(net "M_G_MA<2>")
	)
	(segment
		(start 90.512646 -26.270966)
		(end 90.616278 -26.270966)
		(width 0.1651)
		(layer "F.Cu")
		(net "M_G_MA<2>")
	)
	(segment
		(start 90.800428 -27.490166)
		(end 90.800428 -27.071066)
		(width 0.1651)
		(layer "F.Cu")
		(net "M_G_MA<2>")
	)
	(segment
		(start 90.616278 -26.270966)
		(end 90.781378 -26.105866)
		(width 0.1651)
		(layer "F.Cu")
		(net "M_G_MA<2>")
	)
	(segment
		(start 90.765122 -24.641556)
		(end 90.765122 -24.151844)
		(width 0.1651)
		(layer "F.Cu")
		(net "M_G_MA<2>")
	)
	(segment
		(start 90.47226 -23.18131)
		(end 90.294968 -23.004018)
		(width 0.1651)
		(layer "F.Cu")
		(net "M_G_MA<2>")
	)
	(segment
		(start 90.294968 -23.004018)
		(end 90.294968 -22.7584)
		(width 0.1651)
		(layer "F.Cu")
		(net "M_G_MA<2>")
	)
	(segment
		(start 90.347546 -25.059132)
		(end 90.765122 -24.641556)
		(width 0.1651)
		(layer "F.Cu")
		(net "M_G_MA<2>")
	)
	(segment
		(start 90.512646 -26.944066)
		(end 90.347546 -26.778966)
		(width 0.1651)
		(layer "F.Cu")
		(net "M_G_MA<2>")
	)
	(segment
		(start 90.673428 -26.944066)
		(end 90.512646 -26.944066)
		(width 0.1651)
		(layer "F.Cu")
		(net "M_G_MA<2>")
	)
	(segment
		(start 92.934028 -47.80661)
		(end 92.934028 -30.693106)
		(width 0.1651)
		(layer "F.Cu")
		(net "M_G_MA<2>")
	)
	(segment
		(start 92.249752 -50.174652)
		(end 92.249752 -48.768762)
		(width 0.0889)
		(layer "F.Cu")
		(net "M_G_MA<2>")
	)
	(segment
		(start 90.673428 -27.617166)
		(end 90.800428 -27.490166)
		(width 0.1651)
		(layer "F.Cu")
		(net "M_G_MA<2>")
	)
	(segment
		(start 90.47226 -23.858982)
		(end 90.47226 -23.18131)
		(width 0.1651)
		(layer "F.Cu")
		(net "M_G_MA<2>")
	)
	(segment
		(start 92.934028 -48.08474)
		(end 92.934028 -47.80661)
		(width 0.0889)
		(layer "F.Cu")
		(net "M_G_MA<2>")
	)
	(segment
		(start 90.347546 -26.436066)
		(end 90.512646 -26.270966)
		(width 0.1651)
		(layer "F.Cu")
		(net "M_G_MA<2>")
	)
	(segment
		(start 90.347546 -25.432766)
		(end 90.347546 -25.059132)
		(width 0.1651)
		(layer "F.Cu")
		(net "M_G_MA<2>")
	)
	(segment
		(start 90.45702 -22.596348)
		(end 90.45702 -22.362668)
		(width 0.1651)
		(layer "F.Cu")
		(net "M_G_MA<2>")
	)
	(via
		(at 90.02141 -22.197568)
		(size 0.508)
		(drill 0.254)
		(layers "F.Cu" "B.Cu")
		(net "M_G_MA<2>")
	)
	(via
		(at 90.049604 -18.734278)
		(size 0.4572)
		(drill 0.2032)
		(layers "F.Cu" "B.Cu")
		(net "M_G_MA<2>")
	)
	(arc
		(start 92.267024 -50.25771)
		(mid 92.254109 -50.217069)
		(end 92.249752 -50.174652)
		(width 0.0889)
		(layer "F.Cu")
		(net "M_G_MA<2>")
	)
	(segment
		(start 90.04935 -22.169628)
		(end 90.02141 -22.197568)
		(width 0.1651)
		(layer "B.Cu")
		(net "M_G_MA<2>")
	)
	(segment
		(start 90.04935 -20.224242)
		(end 90.04935 -22.169628)
		(width 0.1651)
		(layer "B.Cu")
		(net "M_G_MA<2>")
	)
	(segment
		(start 90.024458 -22.197568)
		(end 90.151458 -22.070568)
		(width 0.14224)
		(layer "In9.Cu")
		(net "M_G_MA<2>")
	)
	(segment
		(start 90.151458 -22.070568)
		(end 90.151458 -18.836132)
		(width 0.14224)
		(layer "In9.Cu")
		(net "M_G_MA<2>")
	)
	(segment
		(start 90.151458 -18.836132)
		(end 90.049604 -18.734278)
		(width 0.14224)
		(layer "In9.Cu")
		(net "M_G_MA<2>")
	)
	(segment
		(start 90.02141 -22.197568)
		(end 90.024458 -22.197568)
		(width 0.14224)
		(layer "In9.Cu")
		(net "M_G_MA<2>")
	)
	(segment
		(start 92.193872 -51.34102)
		(end 92.645738 -52.12334)
		(width 0.0889)
		(layer "F.Cu")
		(net "M_G_MA<1>")
	)
	(segment
		(start 90.02141 -23.560278)
		(end 90.02141 -24.07539)
		(width 0.1651)
		(layer "F.Cu")
		(net "M_G_MA<1>")
	)
	(segment
		(start 92.059252 -50.35042)
		(end 92.130372 -50.45202)
		(width 0.0889)
		(layer "F.Cu")
		(net "M_G_MA<1>")
	)
	(segment
		(start 89.843356 -26.399744)
		(end 89.843356 -28.315666)
		(width 0.1651)
		(layer "F.Cu")
		(net "M_G_MA<1>")
	)
	(segment
		(start 90.02141 -24.07539)
		(end 89.843356 -24.505412)
		(width 0.1651)
		(layer "F.Cu")
		(net "M_G_MA<1>")
	)
	(segment
		(start 92.168472 -50.51552)
		(end 92.181172 -50.65522)
		(width 0.0889)
		(layer "F.Cu")
		(net "M_G_MA<1>")
	)
	(segment
		(start 89.843356 -24.505412)
		(end 89.843356 -26.399744)
		(width 0.1651)
		(layer "F.Cu")
		(net "M_G_MA<1>")
	)
	(segment
		(start 92.059252 -48.534828)
		(end 92.059252 -50.35042)
		(width 0.0889)
		(layer "F.Cu")
		(net "M_G_MA<1>")
	)
	(segment
		(start 92.429838 -48.164242)
		(end 92.059252 -48.534828)
		(width 0.0889)
		(layer "F.Cu")
		(net "M_G_MA<1>")
	)
	(segment
		(start 92.181172 -50.65522)
		(end 92.193872 -51.34102)
		(width 0.0889)
		(layer "F.Cu")
		(net "M_G_MA<1>")
	)
	(segment
		(start 90.04935 -16.718788)
		(end 90.04935 -15.423642)
		(width 0.1651)
		(layer "F.Cu")
		(net "M_G_MA<1>")
	)
	(segment
		(start 92.429838 -47.788068)
		(end 92.429838 -48.164242)
		(width 0.0889)
		(layer "F.Cu")
		(net "M_G_MA<1>")
	)
	(segment
		(start 89.843356 -28.315666)
		(end 92.429838 -30.902148)
		(width 0.1651)
		(layer "F.Cu")
		(net "M_G_MA<1>")
	)
	(segment
		(start 92.429838 -30.902148)
		(end 92.429838 -47.788068)
		(width 0.1651)
		(layer "F.Cu")
		(net "M_G_MA<1>")
	)
	(segment
		(start 92.130372 -50.45202)
		(end 92.168472 -50.51552)
		(width 0.0889)
		(layer "F.Cu")
		(net "M_G_MA<1>")
	)
	(via
		(at 89.843356 -26.399744)
		(size 0.508)
		(drill 0.254)
		(layers "F.Cu" "B.Cu")
		(net "M_G_MA<1>")
	)
	(via
		(at 90.04935 -16.718788)
		(size 0.4572)
		(drill 0.2032)
		(layers "F.Cu" "B.Cu")
		(net "M_G_MA<1>")
	)
	(via
		(at 90.02141 -23.560278)
		(size 0.508)
		(drill 0.254)
		(layers "F.Cu" "B.Cu")
		(net "M_G_MA<1>")
	)
	(segment
		(start 90.04935 -24.824182)
		(end 90.04935 -23.588218)
		(width 0.1651)
		(layer "B.Cu")
		(net "M_G_MA<1>")
	)
	(segment
		(start 90.04935 -23.588218)
		(end 90.02141 -23.560278)
		(width 0.1651)
		(layer "B.Cu")
		(net "M_G_MA<1>")
	)
	(segment
		(start 89.685368 -21.717)
		(end 89.685368 -19.228054)
		(width 0.14224)
		(layer "In9.Cu")
		(net "M_G_MA<1>")
	)
	(segment
		(start 90.049604 -17.396968)
		(end 90.04935 -17.396714)
		(width 0.14224)
		(layer "In9.Cu")
		(net "M_G_MA<1>")
	)
	(segment
		(start 90.049604 -17.949418)
		(end 90.049604 -17.396968)
		(width 0.14224)
		(layer "In9.Cu")
		(net "M_G_MA<1>")
	)
	(segment
		(start 90.04935 -17.396714)
		(end 90.04935 -16.718788)
		(width 0.14224)
		(layer "In9.Cu")
		(net "M_G_MA<1>")
	)
	(segment
		(start 89.549478 -22.47011)
		(end 89.549478 -21.85289)
		(width 0.14224)
		(layer "In9.Cu")
		(net "M_G_MA<1>")
	)
	(segment
		(start 89.685368 -19.228054)
		(end 89.641934 -19.18462)
		(width 0.14224)
		(layer "In9.Cu")
		(net "M_G_MA<1>")
	)
	(segment
		(start 90.02141 -23.560278)
		(end 90.02141 -22.942042)
		(width 0.14224)
		(layer "In9.Cu")
		(net "M_G_MA<1>")
	)
	(segment
		(start 89.641934 -18.357088)
		(end 90.049604 -17.949418)
		(width 0.14224)
		(layer "In9.Cu")
		(net "M_G_MA<1>")
	)
	(segment
		(start 90.02141 -22.942042)
		(end 89.549478 -22.47011)
		(width 0.14224)
		(layer "In9.Cu")
		(net "M_G_MA<1>")
	)
	(segment
		(start 89.549478 -21.85289)
		(end 89.685368 -21.717)
		(width 0.14224)
		(layer "In9.Cu")
		(net "M_G_MA<1>")
	)
	(segment
		(start 89.641934 -19.18462)
		(end 89.641934 -18.357088)
		(width 0.14224)
		(layer "In9.Cu")
		(net "M_G_MA<1>")
	)
	(segment
		(start 110.44936 -18.734786)
		(end 110.449868 -18.734278)
		(width 0.1651)
		(layer "F.Cu")
		(net "M_G_MA<17>")
	)
	(segment
		(start 101.230684 -54.104286)
		(end 100.659184 -54.104286)
		(width 0.1016)
		(layer "F.Cu")
		(net "M_G_MA<17>")
	)
	(segment
		(start 110.44936 -20.023582)
		(end 110.44936 -18.734786)
		(width 0.1651)
		(layer "F.Cu")
		(net "M_G_MA<17>")
	)
	(via
		(at 110.449868 -18.734278)
		(size 0.4572)
		(drill 0.2032)
		(layers "F.Cu" "B.Cu")
		(net "M_G_MA<17>")
	)
	(via
		(at 100.659184 -54.104286)
		(size 0.508)
		(drill 0.254)
		(layers "F.Cu" "B.Cu")
		(net "M_G_MA<17>")
	)
	(via
		(at 110.44936 -22.197568)
		(size 0.508)
		(drill 0.254)
		(layers "F.Cu" "B.Cu")
		(net "M_G_MA<17>")
	)
	(segment
		(start 110.44936 -22.197568)
		(end 110.44936 -20.224242)
		(width 0.1651)
		(layer "B.Cu")
		(net "M_G_MA<17>")
	)
	(segment
		(start 110.868968 -23.8506)
		(end 110.919768 -23.7998)
		(width 0.14224)
		(layer "In11.Cu")
		(net "M_G_MA<17>")
	)
	(segment
		(start 101.083872 -52.585874)
		(end 101.227636 -52.270406)
		(width 0.0889)
		(layer "In11.Cu")
		(net "M_G_MA<17>")
	)
	(segment
		(start 110.784132 -21.675344)
		(end 110.784132 -19.068542)
		(width 0.14224)
		(layer "In11.Cu")
		(net "M_G_MA<17>")
	)
	(segment
		(start 110.919768 -23.7998)
		(end 110.919768 -23.1902)
		(width 0.14224)
		(layer "In11.Cu")
		(net "M_G_MA<17>")
	)
	(segment
		(start 103.174292 -48.509174)
		(end 103.174292 -35.585146)
		(width 0.14224)
		(layer "In11.Cu")
		(net "M_G_MA<17>")
	)
	(segment
		(start 110.818168 -22.733)
		(end 110.44936 -22.364192)
		(width 0.14224)
		(layer "In11.Cu")
		(net "M_G_MA<17>")
	)
	(segment
		(start 103.174292 -35.585146)
		(end 110.462568 -28.29687)
		(width 0.14224)
		(layer "In11.Cu")
		(net "M_G_MA<17>")
	)
	(segment
		(start 101.083872 -53.15712)
		(end 101.083872 -52.585874)
		(width 0.0889)
		(layer "In11.Cu")
		(net "M_G_MA<17>")
	)
	(segment
		(start 110.919768 -21.994368)
		(end 110.919768 -21.81098)
		(width 0.14224)
		(layer "In11.Cu")
		(net "M_G_MA<17>")
	)
	(segment
		(start 101.953568 -50.1142)
		(end 103.174292 -48.893476)
		(width 0.0889)
		(layer "In11.Cu")
		(net "M_G_MA<17>")
	)
	(segment
		(start 110.919768 -23.1902)
		(end 110.818168 -23.0886)
		(width 0.14224)
		(layer "In11.Cu")
		(net "M_G_MA<17>")
	)
	(segment
		(start 110.462568 -28.29687)
		(end 110.462568 -26.289)
		(width 0.14224)
		(layer "In11.Cu")
		(net "M_G_MA<17>")
	)
	(segment
		(start 110.44936 -22.364192)
		(end 110.44936 -22.197568)
		(width 0.14224)
		(layer "In11.Cu")
		(net "M_G_MA<17>")
	)
	(segment
		(start 110.784132 -19.068542)
		(end 110.449868 -18.734278)
		(width 0.14224)
		(layer "In11.Cu")
		(net "M_G_MA<17>")
	)
	(segment
		(start 110.44936 -22.197568)
		(end 110.716568 -22.197568)
		(width 0.14224)
		(layer "In11.Cu")
		(net "M_G_MA<17>")
	)
	(segment
		(start 110.919768 -21.81098)
		(end 110.784132 -21.675344)
		(width 0.14224)
		(layer "In11.Cu")
		(net "M_G_MA<17>")
	)
	(segment
		(start 101.227636 -52.270406)
		(end 101.768402 -51.991768)
		(width 0.0889)
		(layer "In11.Cu")
		(net "M_G_MA<17>")
	)
	(segment
		(start 101.953568 -51.73599)
		(end 101.953568 -50.1142)
		(width 0.0889)
		(layer "In11.Cu")
		(net "M_G_MA<17>")
	)
	(segment
		(start 101.768402 -51.991768)
		(end 101.953568 -51.73599)
		(width 0.0889)
		(layer "In11.Cu")
		(net "M_G_MA<17>")
	)
	(segment
		(start 100.659184 -54.104286)
		(end 101.083872 -53.15712)
		(width 0.0889)
		(layer "In11.Cu")
		(net "M_G_MA<17>")
	)
	(segment
		(start 103.174292 -48.893476)
		(end 103.174292 -48.509174)
		(width 0.0889)
		(layer "In11.Cu")
		(net "M_G_MA<17>")
	)
	(segment
		(start 110.716568 -22.197568)
		(end 110.919768 -21.994368)
		(width 0.14224)
		(layer "In11.Cu")
		(net "M_G_MA<17>")
	)
	(segment
		(start 110.462568 -26.289)
		(end 110.868968 -25.8826)
		(width 0.14224)
		(layer "In11.Cu")
		(net "M_G_MA<17>")
	)
	(segment
		(start 110.868968 -25.8826)
		(end 110.868968 -23.8506)
		(width 0.14224)
		(layer "In11.Cu")
		(net "M_G_MA<17>")
	)
	(segment
		(start 110.818168 -23.0886)
		(end 110.818168 -22.733)
		(width 0.14224)
		(layer "In11.Cu")
		(net "M_G_MA<17>")
	)
	(segment
		(start 100.691442 -26.586688)
		(end 100.691442 -26.284936)
		(width 0.1651)
		(layer "F.Cu")
		(net "M_G_MA<16>")
	)
	(segment
		(start 100.224336 -26.752042)
		(end 100.526088 -26.752042)
		(width 0.1651)
		(layer "F.Cu")
		(net "M_G_MA<16>")
	)
	(segment
		(start 100.854256 -25.513538)
		(end 101.216714 -25.875996)
		(width 0.1651)
		(layer "F.Cu")
		(net "M_G_MA<16>")
	)
	(segment
		(start 99.839526 -26.60015)
		(end 100.072444 -26.60015)
		(width 0.1651)
		(layer "F.Cu")
		(net "M_G_MA<16>")
	)
	(segment
		(start 100.072444 -26.60015)
		(end 100.224336 -26.752042)
		(width 0.1651)
		(layer "F.Cu")
		(net "M_G_MA<16>")
	)
	(segment
		(start 101.321616 -25.046686)
		(end 101.321616 -24.812752)
		(width 0.1651)
		(layer "F.Cu")
		(net "M_G_MA<16>")
	)
	(segment
		(start 102.640638 -24.33574)
		(end 102.361746 -24.056848)
		(width 0.1651)
		(layer "F.Cu")
		(net "M_G_MA<16>")
	)
	(segment
		(start 98.302572 -46.245526)
		(end 98.135948 -46.078902)
		(width 0.0889)
		(layer "F.Cu")
		(net "M_G_MA<16>")
	)
	(segment
		(start 102.093014 -24.883618)
		(end 102.475538 -24.883618)
		(width 0.1651)
		(layer "F.Cu")
		(net "M_G_MA<16>")
	)
	(segment
		(start 101.68382 -25.64257)
		(end 101.68382 -25.40889)
		(width 0.1651)
		(layer "F.Cu")
		(net "M_G_MA<16>")
	)
	(segment
		(start 102.475538 -24.883618)
		(end 102.640638 -24.718518)
		(width 0.1651)
		(layer "F.Cu")
		(net "M_G_MA<16>")
	)
	(segment
		(start 103.649526 -16.714978)
		(end 103.649526 -15.423642)
		(width 0.1651)
		(layer "F.Cu")
		(net "M_G_MA<16>")
	)
	(segment
		(start 101.450394 -25.875996)
		(end 101.68382 -25.64257)
		(width 0.1651)
		(layer "F.Cu")
		(net "M_G_MA<16>")
	)
	(segment
		(start 98.135948 -45.72)
		(end 98.135948 -29.243274)
		(width 0.1651)
		(layer "F.Cu")
		(net "M_G_MA<16>")
	)
	(segment
		(start 102.361746 -24.056848)
		(end 102.361746 -23.798022)
		(width 0.1651)
		(layer "F.Cu")
		(net "M_G_MA<16>")
	)
	(segment
		(start 99.75723 -27.621992)
		(end 99.75723 -27.218894)
		(width 0.1651)
		(layer "F.Cu")
		(net "M_G_MA<16>")
	)
	(segment
		(start 102.79126 -23.368508)
		(end 103.457502 -23.368508)
		(width 0.1651)
		(layer "F.Cu")
		(net "M_G_MA<16>")
	)
	(segment
		(start 100.387404 -25.747472)
		(end 100.621338 -25.513538)
		(width 0.1651)
		(layer "F.Cu")
		(net "M_G_MA<16>")
	)
	(segment
		(start 98.135948 -46.078902)
		(end 98.135948 -45.72)
		(width 0.0889)
		(layer "F.Cu")
		(net "M_G_MA<16>")
	)
	(segment
		(start 103.457502 -23.368508)
		(end 103.649272 -23.560278)
		(width 0.1651)
		(layer "F.Cu")
		(net "M_G_MA<16>")
	)
	(segment
		(start 100.691442 -26.284936)
		(end 100.387404 -25.980644)
		(width 0.1651)
		(layer "F.Cu")
		(net "M_G_MA<16>")
	)
	(segment
		(start 100.621338 -25.513538)
		(end 100.854256 -25.513538)
		(width 0.1651)
		(layer "F.Cu")
		(net "M_G_MA<16>")
	)
	(segment
		(start 101.788722 -24.579326)
		(end 102.093014 -24.883618)
		(width 0.1651)
		(layer "F.Cu")
		(net "M_G_MA<16>")
	)
	(segment
		(start 97.169732 -49.28489)
		(end 98.302572 -48.15205)
		(width 0.0889)
		(layer "F.Cu")
		(net "M_G_MA<16>")
	)
	(segment
		(start 98.135948 -29.243274)
		(end 98.843592 -28.53563)
		(width 0.1651)
		(layer "F.Cu")
		(net "M_G_MA<16>")
	)
	(segment
		(start 100.526088 -26.752042)
		(end 100.691442 -26.586688)
		(width 0.1651)
		(layer "F.Cu")
		(net "M_G_MA<16>")
	)
	(segment
		(start 102.361746 -23.798022)
		(end 102.79126 -23.368508)
		(width 0.1651)
		(layer "F.Cu")
		(net "M_G_MA<16>")
	)
	(segment
		(start 102.640638 -24.718518)
		(end 102.640638 -24.33574)
		(width 0.1651)
		(layer "F.Cu")
		(net "M_G_MA<16>")
	)
	(segment
		(start 101.216714 -25.875996)
		(end 101.450394 -25.875996)
		(width 0.1651)
		(layer "F.Cu")
		(net "M_G_MA<16>")
	)
	(segment
		(start 97.169732 -50.303684)
		(end 97.169732 -49.28489)
		(width 0.0889)
		(layer "F.Cu")
		(net "M_G_MA<16>")
	)
	(segment
		(start 101.321616 -24.812752)
		(end 101.555042 -24.579326)
		(width 0.1651)
		(layer "F.Cu")
		(net "M_G_MA<16>")
	)
	(segment
		(start 98.302572 -48.15205)
		(end 98.302572 -46.245526)
		(width 0.0889)
		(layer "F.Cu")
		(net "M_G_MA<16>")
	)
	(segment
		(start 97.796858 -51.132486)
		(end 97.169732 -50.303684)
		(width 0.0889)
		(layer "F.Cu")
		(net "M_G_MA<16>")
	)
	(segment
		(start 99.75723 -27.218894)
		(end 99.605592 -27.067256)
		(width 0.1651)
		(layer "F.Cu")
		(net "M_G_MA<16>")
	)
	(segment
		(start 101.555042 -24.579326)
		(end 101.788722 -24.579326)
		(width 0.1651)
		(layer "F.Cu")
		(net "M_G_MA<16>")
	)
	(segment
		(start 99.605592 -27.067256)
		(end 99.605592 -26.834084)
		(width 0.1651)
		(layer "F.Cu")
		(net "M_G_MA<16>")
	)
	(segment
		(start 100.387404 -25.980644)
		(end 100.387404 -25.747472)
		(width 0.1651)
		(layer "F.Cu")
		(net "M_G_MA<16>")
	)
	(segment
		(start 99.605592 -26.834084)
		(end 99.839526 -26.60015)
		(width 0.1651)
		(layer "F.Cu")
		(net "M_G_MA<16>")
	)
	(segment
		(start 101.68382 -25.40889)
		(end 101.321616 -25.046686)
		(width 0.1651)
		(layer "F.Cu")
		(net "M_G_MA<16>")
	)
	(segment
		(start 98.843592 -28.53563)
		(end 99.75723 -27.621992)
		(width 0.1651)
		(layer "F.Cu")
		(net "M_G_MA<16>")
	)
	(via
		(at 98.843592 -28.53563)
		(size 0.508)
		(drill 0.254)
		(layers "F.Cu" "B.Cu")
		(net "M_G_MA<16>")
	)
	(via
		(at 103.649526 -16.714978)
		(size 0.508)
		(drill 0.254)
		(layers "F.Cu" "B.Cu")
		(net "M_G_MA<16>")
	)
	(via
		(at 103.649272 -23.560278)
		(size 0.508)
		(drill 0.254)
		(layers "F.Cu" "B.Cu")
		(net "M_G_MA<16>")
	)
	(segment
		(start 103.649526 -23.560532)
		(end 103.649272 -23.560278)
		(width 0.1651)
		(layer "B.Cu")
		(net "M_G_MA<16>")
	)
	(segment
		(start 103.649526 -24.824182)
		(end 103.649526 -23.560532)
		(width 0.1651)
		(layer "B.Cu")
		(net "M_G_MA<16>")
	)
	(segment
		(start 103.649272 -23.560278)
		(end 103.20274 -22.482302)
		(width 0.14224)
		(layer "In9.Cu")
		(net "M_G_MA<16>")
	)
	(segment
		(start 103.20274 -22.482302)
		(end 103.20274 -21.915628)
		(width 0.14224)
		(layer "In9.Cu")
		(net "M_G_MA<16>")
	)
	(segment
		(start 103.262684 -21.770848)
		(end 103.262684 -19.253962)
		(width 0.14224)
		(layer "In9.Cu")
		(net "M_G_MA<16>")
	)
	(segment
		(start 103.20274 -21.915628)
		(end 103.262684 -21.770848)
		(width 0.14224)
		(layer "In9.Cu")
		(net "M_G_MA<16>")
	)
	(segment
		(start 103.262684 -19.253962)
		(end 103.210614 -19.135852)
		(width 0.14224)
		(layer "In9.Cu")
		(net "M_G_MA<16>")
	)
	(segment
		(start 103.55326 -16.811244)
		(end 103.649526 -16.714978)
		(width 0.14224)
		(layer "In9.Cu")
		(net "M_G_MA<16>")
	)
	(segment
		(start 103.210614 -17.638522)
		(end 103.55326 -16.811244)
		(width 0.14224)
		(layer "In9.Cu")
		(net "M_G_MA<16>")
	)
	(segment
		(start 103.210614 -19.135852)
		(end 103.210614 -17.638522)
		(width 0.14224)
		(layer "In9.Cu")
		(net "M_G_MA<16>")
	)
	(segment
		(start 107.04957 -16.718534)
		(end 107.049824 -16.718788)
		(width 0.1651)
		(layer "F.Cu")
		(net "M_G_MA<15>")
	)
	(segment
		(start 99.513898 -54.104286)
		(end 98.942398 -54.104286)
		(width 0.1016)
		(layer "F.Cu")
		(net "M_G_MA<15>")
	)
	(segment
		(start 107.04957 -15.423642)
		(end 107.04957 -16.718534)
		(width 0.1651)
		(layer "F.Cu")
		(net "M_G_MA<15>")
	)
	(via
		(at 107.049824 -16.718788)
		(size 0.4572)
		(drill 0.2032)
		(layers "F.Cu" "B.Cu")
		(net "M_G_MA<15>")
	)
	(via
		(at 98.942398 -54.104286)
		(size 0.508)
		(drill 0.254)
		(layers "F.Cu" "B.Cu")
		(net "M_G_MA<15>")
	)
	(via
		(at 107.049316 -23.560278)
		(size 0.508)
		(drill 0.254)
		(layers "F.Cu" "B.Cu")
		(net "M_G_MA<15>")
	)
	(segment
		(start 107.04957 -23.560532)
		(end 107.049316 -23.560278)
		(width 0.1651)
		(layer "B.Cu")
		(net "M_G_MA<15>")
	)
	(segment
		(start 107.04957 -24.824182)
		(end 107.04957 -23.560532)
		(width 0.1651)
		(layer "B.Cu")
		(net "M_G_MA<15>")
	)
	(segment
		(start 100.494592 -48.610774)
		(end 100.494592 -34.086292)
		(width 0.14224)
		(layer "In11.Cu")
		(net "M_G_MA<15>")
	)
	(segment
		(start 100.494592 -34.086292)
		(end 100.697792 -33.883092)
		(width 0.14224)
		(layer "In11.Cu")
		(net "M_G_MA<15>")
	)
	(segment
		(start 99.343972 -52.914804)
		(end 99.184968 -52.7558)
		(width 0.0889)
		(layer "In11.Cu")
		(net "M_G_MA<15>")
	)
	(segment
		(start 107.17911 -23.430484)
		(end 107.17911 -20.295108)
		(width 0.14224)
		(layer "In11.Cu")
		(net "M_G_MA<15>")
	)
	(segment
		(start 99.81184 -50.325528)
		(end 100.494592 -49.14392)
		(width 0.0889)
		(layer "In11.Cu")
		(net "M_G_MA<15>")
	)
	(segment
		(start 107.100116 -25.390094)
		(end 107.100116 -24.95423)
		(width 0.14224)
		(layer "In11.Cu")
		(net "M_G_MA<15>")
	)
	(segment
		(start 107.633516 -25.923494)
		(end 107.100116 -25.390094)
		(width 0.14224)
		(layer "In11.Cu")
		(net "M_G_MA<15>")
	)
	(segment
		(start 100.494592 -49.14392)
		(end 100.494592 -48.610774)
		(width 0.0889)
		(layer "In11.Cu")
		(net "M_G_MA<15>")
	)
	(segment
		(start 103.351838 -31.67126)
		(end 103.622348 -31.40075)
		(width 0.14224)
		(layer "In11.Cu")
		(net "M_G_MA<15>")
	)
	(segment
		(start 107.603036 -24.388318)
		(end 107.452668 -24.23795)
		(width 0.14224)
		(layer "In11.Cu")
		(net "M_G_MA<15>")
	)
	(segment
		(start 102.727506 -31.67126)
		(end 103.351838 -31.67126)
		(width 0.14224)
		(layer "In11.Cu")
		(net "M_G_MA<15>")
	)
	(segment
		(start 102.45598 -31.942786)
		(end 102.727506 -31.67126)
		(width 0.14224)
		(layer "In11.Cu")
		(net "M_G_MA<15>")
	)
	(segment
		(start 99.343972 -53.24602)
		(end 99.343972 -52.914804)
		(width 0.0889)
		(layer "In11.Cu")
		(net "M_G_MA<15>")
	)
	(segment
		(start 107.452668 -24.23795)
		(end 107.204256 -24.23795)
		(width 0.14224)
		(layer "In11.Cu")
		(net "M_G_MA<15>")
	)
	(segment
		(start 106.538522 -17.614646)
		(end 107.049824 -17.103344)
		(width 0.14224)
		(layer "In11.Cu")
		(net "M_G_MA<15>")
	)
	(segment
		(start 107.100116 -24.95423)
		(end 107.255056 -24.79929)
		(width 0.14224)
		(layer "In11.Cu")
		(net "M_G_MA<15>")
	)
	(segment
		(start 106.639614 -18.344388)
		(end 106.538522 -18.243296)
		(width 0.14224)
		(layer "In11.Cu")
		(net "M_G_MA<15>")
	)
	(segment
		(start 103.622348 -30.776418)
		(end 103.87711 -30.521656)
		(width 0.14224)
		(layer "In11.Cu")
		(net "M_G_MA<15>")
	)
	(segment
		(start 107.443524 -24.79929)
		(end 107.603036 -24.639778)
		(width 0.14224)
		(layer "In11.Cu")
		(net "M_G_MA<15>")
	)
	(segment
		(start 107.049824 -17.103344)
		(end 107.049824 -16.718788)
		(width 0.14224)
		(layer "In11.Cu")
		(net "M_G_MA<15>")
	)
	(segment
		(start 107.049316 -23.560278)
		(end 107.17911 -23.430484)
		(width 0.14224)
		(layer "In11.Cu")
		(net "M_G_MA<15>")
	)
	(segment
		(start 101.140006 -33.883092)
		(end 101.306376 -33.716722)
		(width 0.14224)
		(layer "In11.Cu")
		(net "M_G_MA<15>")
	)
	(segment
		(start 102.202234 -32.820864)
		(end 102.45598 -32.567118)
		(width 0.14224)
		(layer "In11.Cu")
		(net "M_G_MA<15>")
	)
	(segment
		(start 103.622348 -31.40075)
		(end 103.622348 -30.776418)
		(width 0.14224)
		(layer "In11.Cu")
		(net "M_G_MA<15>")
	)
	(segment
		(start 106.538522 -18.243296)
		(end 106.538522 -17.614646)
		(width 0.14224)
		(layer "In11.Cu")
		(net "M_G_MA<15>")
	)
	(segment
		(start 107.255056 -24.79929)
		(end 107.443524 -24.79929)
		(width 0.14224)
		(layer "In11.Cu")
		(net "M_G_MA<15>")
	)
	(segment
		(start 101.577902 -32.820864)
		(end 102.202234 -32.820864)
		(width 0.14224)
		(layer "In11.Cu")
		(net "M_G_MA<15>")
	)
	(segment
		(start 101.306376 -33.09239)
		(end 101.577902 -32.820864)
		(width 0.14224)
		(layer "In11.Cu")
		(net "M_G_MA<15>")
	)
	(segment
		(start 107.204256 -24.23795)
		(end 107.049316 -24.08301)
		(width 0.14224)
		(layer "In11.Cu")
		(net "M_G_MA<15>")
	)
	(segment
		(start 99.184968 -50.9524)
		(end 99.81184 -50.325528)
		(width 0.0889)
		(layer "In11.Cu")
		(net "M_G_MA<15>")
	)
	(segment
		(start 101.306376 -33.716722)
		(end 101.306376 -33.09239)
		(width 0.14224)
		(layer "In11.Cu")
		(net "M_G_MA<15>")
	)
	(segment
		(start 107.049316 -24.08301)
		(end 107.049316 -23.560278)
		(width 0.14224)
		(layer "In11.Cu")
		(net "M_G_MA<15>")
	)
	(segment
		(start 100.697792 -33.883092)
		(end 101.140006 -33.883092)
		(width 0.14224)
		(layer "In11.Cu")
		(net "M_G_MA<15>")
	)
	(segment
		(start 107.603036 -24.639778)
		(end 107.603036 -24.388318)
		(width 0.14224)
		(layer "In11.Cu")
		(net "M_G_MA<15>")
	)
	(segment
		(start 99.184968 -52.7558)
		(end 99.184968 -50.9524)
		(width 0.0889)
		(layer "In11.Cu")
		(net "M_G_MA<15>")
	)
	(segment
		(start 107.633516 -27.389582)
		(end 107.633516 -25.923494)
		(width 0.14224)
		(layer "In11.Cu")
		(net "M_G_MA<15>")
	)
	(segment
		(start 107.17911 -20.295108)
		(end 106.639614 -19.755612)
		(width 0.14224)
		(layer "In11.Cu")
		(net "M_G_MA<15>")
	)
	(segment
		(start 104.501442 -30.521656)
		(end 107.633516 -27.389582)
		(width 0.14224)
		(layer "In11.Cu")
		(net "M_G_MA<15>")
	)
	(segment
		(start 102.45598 -32.567118)
		(end 102.45598 -31.942786)
		(width 0.14224)
		(layer "In11.Cu")
		(net "M_G_MA<15>")
	)
	(segment
		(start 103.87711 -30.521656)
		(end 104.501442 -30.521656)
		(width 0.14224)
		(layer "In11.Cu")
		(net "M_G_MA<15>")
	)
	(segment
		(start 98.942398 -54.104286)
		(end 99.343972 -53.24602)
		(width 0.0889)
		(layer "In11.Cu")
		(net "M_G_MA<15>")
	)
	(segment
		(start 106.639614 -19.755612)
		(end 106.639614 -18.344388)
		(width 0.14224)
		(layer "In11.Cu")
		(net "M_G_MA<15>")
	)
	(segment
		(start 98.308668 -50.837338)
		(end 98.303842 -50.828702)
		(width 0.0889)
		(layer "F.Cu")
		(net "M_G_MA<14>")
	)
	(segment
		(start 105.738168 -23.1394)
		(end 105.738168 -22.586442)
		(width 0.1651)
		(layer "F.Cu")
		(net "M_G_MA<14>")
	)
	(segment
		(start 105.349548 -18.734532)
		(end 105.349802 -18.734278)
		(width 0.1651)
		(layer "F.Cu")
		(net "M_G_MA<14>")
	)
	(segment
		(start 105.921302 -23.322534)
		(end 105.738168 -23.1394)
		(width 0.1651)
		(layer "F.Cu")
		(net "M_G_MA<14>")
	)
	(segment
		(start 105.738168 -22.586442)
		(end 105.349294 -22.197568)
		(width 0.1651)
		(layer "F.Cu")
		(net "M_G_MA<14>")
	)
	(segment
		(start 105.349548 -20.023582)
		(end 105.349548 -18.734532)
		(width 0.1651)
		(layer "F.Cu")
		(net "M_G_MA<14>")
	)
	(segment
		(start 105.921302 -23.95601)
		(end 105.921302 -23.322534)
		(width 0.1651)
		(layer "F.Cu")
		(net "M_G_MA<14>")
	)
	(segment
		(start 103.056182 -27.497786)
		(end 103.056182 -26.535888)
		(width 0.1651)
		(layer "F.Cu")
		(net "M_G_MA<14>")
	)
	(segment
		(start 103.532686 -25.319482)
		(end 104.55783 -25.319482)
		(width 0.1651)
		(layer "F.Cu")
		(net "M_G_MA<14>")
	)
	(segment
		(start 99.648518 -47.501302)
		(end 99.648518 -30.90545)
		(width 0.1651)
		(layer "F.Cu")
		(net "M_G_MA<14>")
	)
	(segment
		(start 104.55783 -25.319482)
		(end 105.921302 -23.95601)
		(width 0.1651)
		(layer "F.Cu")
		(net "M_G_MA<14>")
	)
	(segment
		(start 98.239072 -50.574194)
		(end 98.239072 -49.38395)
		(width 0.0889)
		(layer "F.Cu")
		(net "M_G_MA<14>")
	)
	(segment
		(start 98.239072 -49.38395)
		(end 99.648518 -47.974504)
		(width 0.0889)
		(layer "F.Cu")
		(net "M_G_MA<14>")
	)
	(segment
		(start 99.648518 -47.974504)
		(end 99.648518 -47.501302)
		(width 0.0889)
		(layer "F.Cu")
		(net "M_G_MA<14>")
	)
	(segment
		(start 98.254058 -51.66614)
		(end 98.254058 -51.573684)
		(width 0.0889)
		(layer "F.Cu")
		(net "M_G_MA<14>")
	)
	(segment
		(start 103.056182 -25.795986)
		(end 103.532686 -25.319482)
		(width 0.1651)
		(layer "F.Cu")
		(net "M_G_MA<14>")
	)
	(segment
		(start 98.315018 -50.848006)
		(end 98.308668 -50.837338)
		(width 0.0889)
		(layer "F.Cu")
		(net "M_G_MA<14>")
	)
	(segment
		(start 103.056182 -26.535888)
		(end 103.056182 -25.795986)
		(width 0.1651)
		(layer "F.Cu")
		(net "M_G_MA<14>")
	)
	(segment
		(start 97.796858 -52.12334)
		(end 98.254058 -51.66614)
		(width 0.0889)
		(layer "F.Cu")
		(net "M_G_MA<14>")
	)
	(segment
		(start 99.648518 -30.90545)
		(end 103.056182 -27.497786)
		(width 0.1651)
		(layer "F.Cu")
		(net "M_G_MA<14>")
	)
	(via
		(at 105.349294 -22.197568)
		(size 0.508)
		(drill 0.254)
		(layers "F.Cu" "B.Cu")
		(net "M_G_MA<14>")
	)
	(via
		(at 103.056182 -26.535888)
		(size 0.508)
		(drill 0.254)
		(layers "F.Cu" "B.Cu")
		(net "M_G_MA<14>")
	)
	(via
		(at 105.349802 -18.734278)
		(size 0.4572)
		(drill 0.2032)
		(layers "F.Cu" "B.Cu")
		(net "M_G_MA<14>")
	)
	(arc
		(start 98.308668 -51.427888)
		(mid 98.38789 -51.13877)
		(end 98.315018 -50.848006)
		(width 0.0889)
		(layer "F.Cu")
		(net "M_G_MA<14>")
	)
	(arc
		(start 98.254058 -51.573684)
		(mid 98.275335 -51.498529)
		(end 98.308668 -51.427888)
		(width 0.0889)
		(layer "F.Cu")
		(net "M_G_MA<14>")
	)
	(arc
		(start 98.303842 -50.828702)
		(mid 98.255493 -50.705509)
		(end 98.239072 -50.574194)
		(width 0.0889)
		(layer "F.Cu")
		(net "M_G_MA<14>")
	)
	(segment
		(start 105.349548 -20.224242)
		(end 105.349294 -20.224496)
		(width 0.1651)
		(layer "B.Cu")
		(net "M_G_MA<14>")
	)
	(segment
		(start 105.349294 -20.224496)
		(end 105.349294 -22.197568)
		(width 0.1651)
		(layer "B.Cu")
		(net "M_G_MA<14>")
	)
	(segment
		(start 104.178608 -21.01215)
		(end 104.00538 -20.838922)
		(width 0.14224)
		(layer "In9.Cu")
		(net "M_G_MA<14>")
	)
	(segment
		(start 103.983536 -19.73453)
		(end 103.983536 -19.48307)
		(width 0.14224)
		(layer "In9.Cu")
		(net "M_G_MA<14>")
	)
	(segment
		(start 105.160064 -22.008338)
		(end 105.160064 -21.203158)
		(width 0.14224)
		(layer "In9.Cu")
		(net "M_G_MA<14>")
	)
	(segment
		(start 105.173272 -19.32813)
		(end 105.349802 -19.1516)
		(width 0.14224)
		(layer "In9.Cu")
		(net "M_G_MA<14>")
	)
	(segment
		(start 104.969056 -21.01215)
		(end 104.178608 -21.01215)
		(width 0.14224)
		(layer "In9.Cu")
		(net "M_G_MA<14>")
	)
	(segment
		(start 103.983536 -19.48307)
		(end 104.138476 -19.32813)
		(width 0.14224)
		(layer "In9.Cu")
		(net "M_G_MA<14>")
	)
	(segment
		(start 104.138476 -19.32813)
		(end 105.173272 -19.32813)
		(width 0.14224)
		(layer "In9.Cu")
		(net "M_G_MA<14>")
	)
	(segment
		(start 105.221532 -20.29587)
		(end 105.221532 -20.04441)
		(width 0.14224)
		(layer "In9.Cu")
		(net "M_G_MA<14>")
	)
	(segment
		(start 105.066592 -20.45081)
		(end 105.221532 -20.29587)
		(width 0.14224)
		(layer "In9.Cu")
		(net "M_G_MA<14>")
	)
	(segment
		(start 104.138476 -19.88947)
		(end 103.983536 -19.73453)
		(width 0.14224)
		(layer "In9.Cu")
		(net "M_G_MA<14>")
	)
	(segment
		(start 105.066592 -19.88947)
		(end 104.138476 -19.88947)
		(width 0.14224)
		(layer "In9.Cu")
		(net "M_G_MA<14>")
	)
	(segment
		(start 105.349294 -22.197568)
		(end 105.160064 -22.008338)
		(width 0.14224)
		(layer "In9.Cu")
		(net "M_G_MA<14>")
	)
	(segment
		(start 104.00538 -20.587462)
		(end 104.142032 -20.45081)
		(width 0.14224)
		(layer "In9.Cu")
		(net "M_G_MA<14>")
	)
	(segment
		(start 105.221532 -20.04441)
		(end 105.066592 -19.88947)
		(width 0.14224)
		(layer "In9.Cu")
		(net "M_G_MA<14>")
	)
	(segment
		(start 105.349802 -19.1516)
		(end 105.349802 -18.734278)
		(width 0.14224)
		(layer "In9.Cu")
		(net "M_G_MA<14>")
	)
	(segment
		(start 104.142032 -20.45081)
		(end 105.066592 -20.45081)
		(width 0.14224)
		(layer "In9.Cu")
		(net "M_G_MA<14>")
	)
	(segment
		(start 104.00538 -20.838922)
		(end 104.00538 -20.587462)
		(width 0.14224)
		(layer "In9.Cu")
		(net "M_G_MA<14>")
	)
	(segment
		(start 105.160064 -21.203158)
		(end 104.969056 -21.01215)
		(width 0.14224)
		(layer "In9.Cu")
		(net "M_G_MA<14>")
	)
	(segment
		(start 108.749338 -18.734786)
		(end 108.749846 -18.734278)
		(width 0.1651)
		(layer "F.Cu")
		(net "M_G_MA<13>")
	)
	(segment
		(start 100.372164 -53.60924)
		(end 99.800664 -53.60924)
		(width 0.1016)
		(layer "F.Cu")
		(net "M_G_MA<13>")
	)
	(segment
		(start 108.749338 -20.023582)
		(end 108.749338 -18.734786)
		(width 0.1651)
		(layer "F.Cu")
		(net "M_G_MA<13>")
	)
	(via
		(at 108.749846 -18.734278)
		(size 0.4572)
		(drill 0.2032)
		(layers "F.Cu" "B.Cu")
		(net "M_G_MA<13>")
	)
	(via
		(at 99.800664 -53.60924)
		(size 0.508)
		(drill 0.254)
		(layers "F.Cu" "B.Cu")
		(net "M_G_MA<13>")
	)
	(via
		(at 108.749338 -22.197568)
		(size 0.508)
		(drill 0.254)
		(layers "F.Cu" "B.Cu")
		(net "M_G_MA<13>")
	)
	(segment
		(start 108.749338 -22.197568)
		(end 108.749338 -20.224242)
		(width 0.1651)
		(layer "B.Cu")
		(net "M_G_MA<13>")
	)
	(segment
		(start 108.809536 -19.926554)
		(end 108.645706 -19.762724)
		(width 0.14224)
		(layer "In11.Cu")
		(net "M_G_MA<13>")
	)
	(segment
		(start 99.400868 -52.6923)
		(end 99.400868 -51.045364)
		(width 0.0889)
		(layer "In11.Cu")
		(net "M_G_MA<13>")
	)
	(segment
		(start 108.517436 -20.885404)
		(end 107.793536 -20.885404)
		(width 0.14224)
		(layer "In11.Cu")
		(net "M_G_MA<13>")
	)
	(segment
		(start 108.672376 -22.120606)
		(end 108.672376 -21.040344)
		(width 0.14224)
		(layer "In11.Cu")
		(net "M_G_MA<13>")
	)
	(segment
		(start 108.328968 -25.8318)
		(end 108.328968 -23.7998)
		(width 0.14224)
		(layer "In11.Cu")
		(net "M_G_MA<13>")
	)
	(segment
		(start 108.221526 -23.323042)
		(end 108.659168 -22.8854)
		(width 0.14224)
		(layer "In11.Cu")
		(net "M_G_MA<13>")
	)
	(segment
		(start 108.659168 -22.8854)
		(end 108.659168 -22.4536)
		(width 0.14224)
		(layer "In11.Cu")
		(net "M_G_MA<13>")
	)
	(segment
		(start 108.663486 -20.324064)
		(end 108.809536 -20.178014)
		(width 0.14224)
		(layer "In11.Cu")
		(net "M_G_MA<13>")
	)
	(segment
		(start 107.249976 -19.762724)
		(end 107.081574 -19.594322)
		(width 0.14224)
		(layer "In11.Cu")
		(net "M_G_MA<13>")
	)
	(segment
		(start 99.591368 -52.8828)
		(end 99.400868 -52.6923)
		(width 0.0889)
		(layer "In11.Cu")
		(net "M_G_MA<13>")
	)
	(segment
		(start 107.793536 -20.324064)
		(end 108.663486 -20.324064)
		(width 0.14224)
		(layer "In11.Cu")
		(net "M_G_MA<13>")
	)
	(segment
		(start 108.645706 -19.762724)
		(end 107.249976 -19.762724)
		(width 0.14224)
		(layer "In11.Cu")
		(net "M_G_MA<13>")
	)
	(segment
		(start 99.800664 -53.60924)
		(end 99.591368 -53.399944)
		(width 0.0889)
		(layer "In11.Cu")
		(net "M_G_MA<13>")
	)
	(segment
		(start 108.141516 -26.019252)
		(end 108.328968 -25.8318)
		(width 0.14224)
		(layer "In11.Cu")
		(net "M_G_MA<13>")
	)
	(segment
		(start 108.659168 -22.4536)
		(end 108.749338 -22.36343)
		(width 0.14224)
		(layer "In11.Cu")
		(net "M_G_MA<13>")
	)
	(segment
		(start 108.749338 -22.36343)
		(end 108.749338 -22.197568)
		(width 0.14224)
		(layer "In11.Cu")
		(net "M_G_MA<13>")
	)
	(segment
		(start 99.591368 -53.399944)
		(end 99.591368 -52.8828)
		(width 0.0889)
		(layer "In11.Cu")
		(net "M_G_MA<13>")
	)
	(segment
		(start 107.638596 -20.479004)
		(end 107.793536 -20.324064)
		(width 0.14224)
		(layer "In11.Cu")
		(net "M_G_MA<13>")
	)
	(segment
		(start 108.141516 -27.600148)
		(end 108.141516 -26.019252)
		(width 0.14224)
		(layer "In11.Cu")
		(net "M_G_MA<13>")
	)
	(segment
		(start 108.809536 -20.178014)
		(end 108.809536 -19.926554)
		(width 0.14224)
		(layer "In11.Cu")
		(net "M_G_MA<13>")
	)
	(segment
		(start 99.400868 -51.045364)
		(end 100.032566 -50.413666)
		(width 0.0889)
		(layer "In11.Cu")
		(net "M_G_MA<13>")
	)
	(segment
		(start 108.221526 -23.692358)
		(end 108.221526 -23.323042)
		(width 0.14224)
		(layer "In11.Cu")
		(net "M_G_MA<13>")
	)
	(segment
		(start 108.749338 -22.197568)
		(end 108.672376 -22.120606)
		(width 0.14224)
		(layer "In11.Cu")
		(net "M_G_MA<13>")
	)
	(segment
		(start 107.793536 -20.885404)
		(end 107.638596 -20.730464)
		(width 0.14224)
		(layer "In11.Cu")
		(net "M_G_MA<13>")
	)
	(segment
		(start 108.328968 -23.7998)
		(end 108.221526 -23.692358)
		(width 0.14224)
		(layer "In11.Cu")
		(net "M_G_MA<13>")
	)
	(segment
		(start 101.002592 -48.506126)
		(end 101.002592 -34.739072)
		(width 0.14224)
		(layer "In11.Cu")
		(net "M_G_MA<13>")
	)
	(segment
		(start 107.081574 -19.342862)
		(end 107.223052 -19.201384)
		(width 0.14224)
		(layer "In11.Cu")
		(net "M_G_MA<13>")
	)
	(segment
		(start 101.002592 -48.73371)
		(end 101.002592 -48.506126)
		(width 0.0889)
		(layer "In11.Cu")
		(net "M_G_MA<13>")
	)
	(segment
		(start 108.598716 -19.201384)
		(end 108.749846 -19.050254)
		(width 0.14224)
		(layer "In11.Cu")
		(net "M_G_MA<13>")
	)
	(segment
		(start 100.032566 -50.413666)
		(end 101.002592 -48.73371)
		(width 0.0889)
		(layer "In11.Cu")
		(net "M_G_MA<13>")
	)
	(segment
		(start 107.223052 -19.201384)
		(end 108.598716 -19.201384)
		(width 0.14224)
		(layer "In11.Cu")
		(net "M_G_MA<13>")
	)
	(segment
		(start 107.081574 -19.594322)
		(end 107.081574 -19.342862)
		(width 0.14224)
		(layer "In11.Cu")
		(net "M_G_MA<13>")
	)
	(segment
		(start 108.749846 -19.050254)
		(end 108.749846 -18.734278)
		(width 0.14224)
		(layer "In11.Cu")
		(net "M_G_MA<13>")
	)
	(segment
		(start 108.672376 -21.040344)
		(end 108.517436 -20.885404)
		(width 0.14224)
		(layer "In11.Cu")
		(net "M_G_MA<13>")
	)
	(segment
		(start 107.638596 -20.730464)
		(end 107.638596 -20.479004)
		(width 0.14224)
		(layer "In11.Cu")
		(net "M_G_MA<13>")
	)
	(segment
		(start 101.002592 -34.739072)
		(end 108.141516 -27.600148)
		(width 0.14224)
		(layer "In11.Cu")
		(net "M_G_MA<13>")
	)
	(segment
		(start 86.636352 -53.60924)
		(end 86.636352 -53.400706)
		(width 0.1651)
		(layer "F.Cu")
		(net "M_G_MA<12>")
	)
	(segment
		(start 86.636352 -53.400706)
		(end 86.923372 -53.113686)
		(width 0.1651)
		(layer "F.Cu")
		(net "M_G_MA<12>")
	)
	(segment
		(start 84.0994 -16.716756)
		(end 84.0994 -15.423642)
		(width 0.1651)
		(layer "F.Cu")
		(net "M_G_MA<12>")
	)
	(via
		(at 84.0994 -16.716756)
		(size 0.4572)
		(drill 0.2032)
		(layers "F.Cu" "B.Cu")
		(net "M_G_MA<12>")
	)
	(via
		(at 84.0994 -22.850856)
		(size 0.508)
		(drill 0.254)
		(layers "F.Cu" "B.Cu")
		(net "M_G_MA<12>")
	)
	(via
		(at 86.923372 -53.113686)
		(size 0.508)
		(drill 0.254)
		(layers "F.Cu" "B.Cu")
		(net "M_G_MA<12>")
	)
	(segment
		(start 84.0994 -22.850856)
		(end 84.0994 -24.824182)
		(width 0.1651)
		(layer "B.Cu")
		(net "M_G_MA<12>")
	)
	(segment
		(start 87.118952 -50.700432)
		(end 87.118952 -51.002184)
		(width 0.0889)
		(layer "In11.Cu")
		(net "M_G_MA<12>")
	)
	(segment
		(start 83.114896 -17.474438)
		(end 82.959956 -17.629378)
		(width 0.14224)
		(layer "In11.Cu")
		(net "M_G_MA<12>")
	)
	(segment
		(start 87.118952 -33.560512)
		(end 87.118952 -50.700432)
		(width 0.14224)
		(layer "In11.Cu")
		(net "M_G_MA<12>")
	)
	(segment
		(start 83.520788 -20.705318)
		(end 83.520788 -21.678392)
		(width 0.14224)
		(layer "In11.Cu")
		(net "M_G_MA<12>")
	)
	(segment
		(start 83.509612 -18.137378)
		(end 83.664552 -18.292318)
		(width 0.14224)
		(layer "In11.Cu")
		(net "M_G_MA<12>")
	)
	(segment
		(start 84.0994 -16.716756)
		(end 84.0994 -17.276572)
		(width 0.14224)
		(layer "In11.Cu")
		(net "M_G_MA<12>")
	)
	(segment
		(start 82.959956 -17.629378)
		(end 82.959956 -17.982438)
		(width 0.14224)
		(layer "In11.Cu")
		(net "M_G_MA<12>")
	)
	(segment
		(start 84.0994 -22.257004)
		(end 84.0994 -22.850856)
		(width 0.14224)
		(layer "In11.Cu")
		(net "M_G_MA<12>")
	)
	(segment
		(start 84.186268 -25.0825)
		(end 84.186268 -27.0764)
		(width 0.14224)
		(layer "In11.Cu")
		(net "M_G_MA<12>")
	)
	(segment
		(start 87.37092 -51.254152)
		(end 87.37092 -52.666138)
		(width 0.0889)
		(layer "In11.Cu")
		(net "M_G_MA<12>")
	)
	(segment
		(start 87.37092 -52.666138)
		(end 86.923372 -53.113686)
		(width 0.0889)
		(layer "In11.Cu")
		(net "M_G_MA<12>")
	)
	(segment
		(start 83.817968 -23.132288)
		(end 83.817968 -24.7142)
		(width 0.14224)
		(layer "In11.Cu")
		(net "M_G_MA<12>")
	)
	(segment
		(start 83.901534 -17.474438)
		(end 83.114896 -17.474438)
		(width 0.14224)
		(layer "In11.Cu")
		(net "M_G_MA<12>")
	)
	(segment
		(start 84.0994 -17.276572)
		(end 83.901534 -17.474438)
		(width 0.14224)
		(layer "In11.Cu")
		(net "M_G_MA<12>")
	)
	(segment
		(start 83.767168 -27.4955)
		(end 83.767168 -30.208728)
		(width 0.14224)
		(layer "In11.Cu")
		(net "M_G_MA<12>")
	)
	(segment
		(start 83.664552 -18.292318)
		(end 83.664552 -20.561554)
		(width 0.14224)
		(layer "In11.Cu")
		(net "M_G_MA<12>")
	)
	(segment
		(start 83.664552 -20.561554)
		(end 83.520788 -20.705318)
		(width 0.14224)
		(layer "In11.Cu")
		(net "M_G_MA<12>")
	)
	(segment
		(start 83.817968 -24.7142)
		(end 84.186268 -25.0825)
		(width 0.14224)
		(layer "In11.Cu")
		(net "M_G_MA<12>")
	)
	(segment
		(start 83.767168 -30.208728)
		(end 87.118952 -33.560512)
		(width 0.14224)
		(layer "In11.Cu")
		(net "M_G_MA<12>")
	)
	(segment
		(start 83.520788 -21.678392)
		(end 84.0994 -22.257004)
		(width 0.14224)
		(layer "In11.Cu")
		(net "M_G_MA<12>")
	)
	(segment
		(start 84.0994 -22.850856)
		(end 83.817968 -23.132288)
		(width 0.14224)
		(layer "In11.Cu")
		(net "M_G_MA<12>")
	)
	(segment
		(start 82.959956 -17.982438)
		(end 83.114896 -18.137378)
		(width 0.14224)
		(layer "In11.Cu")
		(net "M_G_MA<12>")
	)
	(segment
		(start 84.186268 -27.0764)
		(end 83.767168 -27.4955)
		(width 0.14224)
		(layer "In11.Cu")
		(net "M_G_MA<12>")
	)
	(segment
		(start 83.114896 -18.137378)
		(end 83.509612 -18.137378)
		(width 0.14224)
		(layer "In11.Cu")
		(net "M_G_MA<12>")
	)
	(segment
		(start 87.118952 -51.002184)
		(end 87.37092 -51.254152)
		(width 0.0889)
		(layer "In11.Cu")
		(net "M_G_MA<12>")
	)
	(segment
		(start 84.949538 -20.023582)
		(end 84.949538 -18.734278)
		(width 0.1651)
		(layer "F.Cu")
		(net "M_G_MA<11>")
	)
	(segment
		(start 88.353392 -52.618386)
		(end 87.781892 -52.618386)
		(width 0.1016)
		(layer "F.Cu")
		(net "M_G_MA<11>")
	)
	(via
		(at 87.781892 -52.618386)
		(size 0.508)
		(drill 0.254)
		(layers "F.Cu" "B.Cu")
		(net "M_G_MA<11>")
	)
	(via
		(at 84.949538 -18.734278)
		(size 0.4572)
		(drill 0.2032)
		(layers "F.Cu" "B.Cu")
		(net "M_G_MA<11>")
	)
	(via
		(at 84.949538 -22.197568)
		(size 0.508)
		(drill 0.254)
		(layers "F.Cu" "B.Cu")
		(net "M_G_MA<11>")
	)
	(segment
		(start 84.949538 -22.197568)
		(end 84.949538 -20.224242)
		(width 0.1651)
		(layer "B.Cu")
		(net "M_G_MA<11>")
	)
	(segment
		(start 84.651342 -21.899372)
		(end 84.651342 -19.032474)
		(width 0.14224)
		(layer "In11.Cu")
		(net "M_G_MA<11>")
	)
	(segment
		(start 88.193372 -52.206906)
		(end 88.193372 -51.467258)
		(width 0.0889)
		(layer "In11.Cu")
		(net "M_G_MA<11>")
	)
	(segment
		(start 84.630768 -23.114)
		(end 84.630768 -22.516338)
		(width 0.14224)
		(layer "In11.Cu")
		(net "M_G_MA<11>")
	)
	(segment
		(start 84.351368 -27.660346)
		(end 84.859368 -27.152346)
		(width 0.14224)
		(layer "In11.Cu")
		(net "M_G_MA<11>")
	)
	(segment
		(start 84.351368 -30.074362)
		(end 84.351368 -27.660346)
		(width 0.14224)
		(layer "In11.Cu")
		(net "M_G_MA<11>")
	)
	(segment
		(start 87.626952 -50.900838)
		(end 87.626952 -50.672492)
		(width 0.0889)
		(layer "In11.Cu")
		(net "M_G_MA<11>")
	)
	(segment
		(start 88.193372 -51.467258)
		(end 87.626952 -50.900838)
		(width 0.0889)
		(layer "In11.Cu")
		(net "M_G_MA<11>")
	)
	(segment
		(start 87.626952 -50.672492)
		(end 87.626952 -33.349946)
		(width 0.14224)
		(layer "In11.Cu")
		(net "M_G_MA<11>")
	)
	(segment
		(start 84.949538 -22.197568)
		(end 84.651342 -21.899372)
		(width 0.14224)
		(layer "In11.Cu")
		(net "M_G_MA<11>")
	)
	(segment
		(start 84.859368 -27.152346)
		(end 84.859368 -24.748744)
		(width 0.14224)
		(layer "In11.Cu")
		(net "M_G_MA<11>")
	)
	(segment
		(start 84.630768 -22.516338)
		(end 84.949538 -22.197568)
		(width 0.14224)
		(layer "In11.Cu")
		(net "M_G_MA<11>")
	)
	(segment
		(start 84.651342 -19.032474)
		(end 84.949538 -18.734278)
		(width 0.14224)
		(layer "In11.Cu")
		(net "M_G_MA<11>")
	)
	(segment
		(start 87.626952 -33.349946)
		(end 84.351368 -30.074362)
		(width 0.14224)
		(layer "In11.Cu")
		(net "M_G_MA<11>")
	)
	(segment
		(start 84.859368 -24.748744)
		(end 84.427568 -24.316944)
		(width 0.14224)
		(layer "In11.Cu")
		(net "M_G_MA<11>")
	)
	(segment
		(start 87.781892 -52.618386)
		(end 88.193372 -52.206906)
		(width 0.0889)
		(layer "In11.Cu")
		(net "M_G_MA<11>")
	)
	(segment
		(start 84.427568 -24.316944)
		(end 84.427568 -23.3172)
		(width 0.14224)
		(layer "In11.Cu")
		(net "M_G_MA<11>")
	)
	(segment
		(start 84.427568 -23.3172)
		(end 84.630768 -23.114)
		(width 0.14224)
		(layer "In11.Cu")
		(net "M_G_MA<11>")
	)
	(segment
		(start 102.799388 -18.734532)
		(end 102.799642 -18.734278)
		(width 0.1651)
		(layer "F.Cu")
		(net "M_G_MA<10>")
	)
	(segment
		(start 102.799388 -20.023582)
		(end 102.799388 -18.734532)
		(width 0.1651)
		(layer "F.Cu")
		(net "M_G_MA<10>")
	)
	(segment
		(start 95.221298 -53.60924)
		(end 94.649798 -53.60924)
		(width 0.1016)
		(layer "F.Cu")
		(net "M_G_MA<10>")
	)
	(via
		(at 102.799388 -21.488146)
		(size 0.508)
		(drill 0.254)
		(layers "F.Cu" "B.Cu")
		(net "M_G_MA<10>")
	)
	(via
		(at 94.649798 -53.60924)
		(size 0.508)
		(drill 0.254)
		(layers "F.Cu" "B.Cu")
		(net "M_G_MA<10>")
	)
	(via
		(at 102.799642 -18.734278)
		(size 0.4572)
		(drill 0.2032)
		(layers "F.Cu" "B.Cu")
		(net "M_G_MA<10>")
	)
	(segment
		(start 102.799388 -20.224242)
		(end 102.799388 -21.488146)
		(width 0.1651)
		(layer "B.Cu")
		(net "M_G_MA<10>")
	)
	(segment
		(start 94.649798 -53.60924)
		(end 94.649798 -53.609494)
		(width 0.0889)
		(layer "In11.Cu")
		(net "M_G_MA<10>")
	)
	(segment
		(start 102.653338 -20.243546)
		(end 102.715314 -20.18157)
		(width 0.14224)
		(layer "In11.Cu")
		(net "M_G_MA<10>")
	)
	(segment
		(start 102.207568 -25.007824)
		(end 102.207568 -23.9522)
		(width 0.14224)
		(layer "In11.Cu")
		(net "M_G_MA<10>")
	)
	(segment
		(start 96.854772 -48.42002)
		(end 96.854772 -31.387796)
		(width 0.14224)
		(layer "In11.Cu")
		(net "M_G_MA<10>")
	)
	(segment
		(start 102.653338 -21.12137)
		(end 102.653338 -20.243546)
		(width 0.14224)
		(layer "In11.Cu")
		(net "M_G_MA<10>")
	)
	(segment
		(start 102.410768 -22.5552)
		(end 102.410768 -21.876766)
		(width 0.14224)
		(layer "In11.Cu")
		(net "M_G_MA<10>")
	)
	(segment
		(start 102.334568 -23.1902)
		(end 102.334568 -22.6314)
		(width 0.14224)
		(layer "In11.Cu")
		(net "M_G_MA<10>")
	)
	(segment
		(start 96.854772 -31.387796)
		(end 101.420168 -26.8224)
		(width 0.14224)
		(layer "In11.Cu")
		(net "M_G_MA<10>")
	)
	(segment
		(start 102.715314 -18.818606)
		(end 102.799642 -18.734278)
		(width 0.14224)
		(layer "In11.Cu")
		(net "M_G_MA<10>")
	)
	(segment
		(start 102.207568 -23.9522)
		(end 102.410768 -23.749)
		(width 0.14224)
		(layer "In11.Cu")
		(net "M_G_MA<10>")
	)
	(segment
		(start 102.410768 -23.749)
		(end 102.410768 -23.2664)
		(width 0.14224)
		(layer "In11.Cu")
		(net "M_G_MA<10>")
	)
	(segment
		(start 102.715314 -20.18157)
		(end 102.715314 -18.818606)
		(width 0.14224)
		(layer "In11.Cu")
		(net "M_G_MA<10>")
	)
	(segment
		(start 102.799388 -21.488146)
		(end 102.799642 -21.487892)
		(width 0.14224)
		(layer "In11.Cu")
		(net "M_G_MA<10>")
	)
	(segment
		(start 102.799642 -21.267674)
		(end 102.653338 -21.12137)
		(width 0.14224)
		(layer "In11.Cu")
		(net "M_G_MA<10>")
	)
	(segment
		(start 94.979998 -52.84724)
		(end 94.996508 -52.818792)
		(width 0.0889)
		(layer "In11.Cu")
		(net "M_G_MA<10>")
	)
	(segment
		(start 102.799642 -21.487892)
		(end 102.799642 -21.267674)
		(width 0.14224)
		(layer "In11.Cu")
		(net "M_G_MA<10>")
	)
	(segment
		(start 96.854772 -49.978056)
		(end 96.854772 -48.42002)
		(width 0.0889)
		(layer "In11.Cu")
		(net "M_G_MA<10>")
	)
	(segment
		(start 101.420168 -25.795224)
		(end 102.207568 -25.007824)
		(width 0.14224)
		(layer "In11.Cu")
		(net "M_G_MA<10>")
	)
	(segment
		(start 102.334568 -22.6314)
		(end 102.410768 -22.5552)
		(width 0.14224)
		(layer "In11.Cu")
		(net "M_G_MA<10>")
	)
	(segment
		(start 101.420168 -26.8224)
		(end 101.420168 -25.795224)
		(width 0.14224)
		(layer "In11.Cu")
		(net "M_G_MA<10>")
	)
	(segment
		(start 94.649798 -53.609494)
		(end 94.979998 -52.84724)
		(width 0.0889)
		(layer "In11.Cu")
		(net "M_G_MA<10>")
	)
	(segment
		(start 102.410768 -21.876766)
		(end 102.799388 -21.488146)
		(width 0.14224)
		(layer "In11.Cu")
		(net "M_G_MA<10>")
	)
	(segment
		(start 102.410768 -23.2664)
		(end 102.334568 -23.1902)
		(width 0.14224)
		(layer "In11.Cu")
		(net "M_G_MA<10>")
	)
	(segment
		(start 95.063056 -51.769772)
		(end 96.854772 -49.978056)
		(width 0.0889)
		(layer "In11.Cu")
		(net "M_G_MA<10>")
	)
	(segment
		(start 95.063056 -52.570126)
		(end 95.063056 -51.769772)
		(width 0.0889)
		(layer "In11.Cu")
		(net "M_G_MA<10>")
	)
	(arc
		(start 94.996508 -52.818792)
		(mid 95.046133 -52.698835)
		(end 95.063056 -52.570126)
		(width 0.0889)
		(layer "In11.Cu")
		(net "M_G_MA<10>")
	)
	(segment
		(start 97.489772 -46.52645)
		(end 97.127568 -46.164246)
		(width 0.0889)
		(layer "F.Cu")
		(net "M_G_MA<0>")
	)
	(segment
		(start 100.632006 -23.978616)
		(end 101.099366 -22.850856)
		(width 0.1651)
		(layer "F.Cu")
		(net "M_G_MA<0>")
	)
	(segment
		(start 96.699832 -48.992536)
		(end 97.489772 -48.202596)
		(width 0.0889)
		(layer "F.Cu")
		(net "M_G_MA<0>")
	)
	(segment
		(start 96.079818 -52.12334)
		(end 96.538288 -51.66487)
		(width 0.0889)
		(layer "F.Cu")
		(net "M_G_MA<0>")
	)
	(segment
		(start 101.099366 -16.714978)
		(end 101.099366 -15.423642)
		(width 0.1651)
		(layer "F.Cu")
		(net "M_G_MA<0>")
	)
	(segment
		(start 97.127568 -45.923454)
		(end 97.127568 -27.920188)
		(width 0.1651)
		(layer "F.Cu")
		(net "M_G_MA<0>")
	)
	(segment
		(start 96.538288 -51.66487)
		(end 96.538288 -50.648362)
		(width 0.0889)
		(layer "F.Cu")
		(net "M_G_MA<0>")
	)
	(segment
		(start 97.127568 -27.920188)
		(end 97.127568 -27.483054)
		(width 0.1651)
		(layer "F.Cu")
		(net "M_G_MA<0>")
	)
	(segment
		(start 97.127568 -46.164246)
		(end 97.127568 -45.923454)
		(width 0.0889)
		(layer "F.Cu")
		(net "M_G_MA<0>")
	)
	(segment
		(start 97.489772 -48.202596)
		(end 97.489772 -46.52645)
		(width 0.0889)
		(layer "F.Cu")
		(net "M_G_MA<0>")
	)
	(segment
		(start 97.127568 -27.483054)
		(end 100.632006 -23.978616)
		(width 0.1651)
		(layer "F.Cu")
		(net "M_G_MA<0>")
	)
	(segment
		(start 96.699832 -50.308764)
		(end 96.699832 -48.992536)
		(width 0.0889)
		(layer "F.Cu")
		(net "M_G_MA<0>")
	)
	(segment
		(start 96.65589 -50.352706)
		(end 96.699832 -50.308764)
		(width 0.0889)
		(layer "F.Cu")
		(net "M_G_MA<0>")
	)
	(via
		(at 101.099366 -22.850856)
		(size 0.508)
		(drill 0.254)
		(layers "F.Cu" "B.Cu")
		(net "M_G_MA<0>")
	)
	(via
		(at 97.127568 -27.920188)
		(size 0.508)
		(drill 0.254)
		(layers "F.Cu" "B.Cu")
		(net "M_G_MA<0>")
	)
	(via
		(at 101.099366 -16.714978)
		(size 0.508)
		(drill 0.254)
		(layers "F.Cu" "B.Cu")
		(net "M_G_MA<0>")
	)
	(arc
		(start 96.538288 -50.648362)
		(mid 96.566635 -50.488421)
		(end 96.65589 -50.352706)
		(width 0.0889)
		(layer "F.Cu")
		(net "M_G_MA<0>")
	)
	(segment
		(start 101.099366 -22.850856)
		(end 101.099366 -24.824182)
		(width 0.1651)
		(layer "B.Cu")
		(net "M_G_MA<0>")
	)
	(segment
		(start 101.099366 -22.850856)
		(end 101.099366 -22.220428)
		(width 0.14224)
		(layer "In9.Cu")
		(net "M_G_MA<0>")
	)
	(segment
		(start 101.54031 -21.779484)
		(end 101.54031 -17.155922)
		(width 0.14224)
		(layer "In9.Cu")
		(net "M_G_MA<0>")
	)
	(segment
		(start 101.54031 -17.155922)
		(end 101.099366 -16.714978)
		(width 0.14224)
		(layer "In9.Cu")
		(net "M_G_MA<0>")
	)
	(segment
		(start 101.099366 -22.220428)
		(end 101.54031 -21.779484)
		(width 0.14224)
		(layer "In9.Cu")
		(net "M_G_MA<0>")
	)
	(segment
		(start 84.919312 -62.52464)
		(end 84.347812 -62.52464)
		(width 0.1016)
		(layer "F.Cu")
		(net "M_G_ECC<7>")
	)
	(segment
		(start 74.749406 -15.423642)
		(end 74.749406 -16.687546)
		(width 0.1651)
		(layer "F.Cu")
		(net "M_G_ECC<7>")
	)
	(via
		(at 75.59929 -22.279356)
		(size 0.508)
		(drill 0.254)
		(layers "F.Cu" "B.Cu")
		(net "M_G_ECC<7>")
	)
	(via
		(at 84.347812 -62.52464)
		(size 0.508)
		(drill 0.254)
		(layers "F.Cu" "B.Cu")
		(net "M_G_ECC<7>")
	)
	(via
		(at 74.749406 -16.687546)
		(size 0.508)
		(drill 0.254)
		(layers "F.Cu" "B.Cu")
		(net "M_G_ECC<7>")
	)
	(segment
		(start 75.59929 -20.224496)
		(end 75.59929 -22.279356)
		(width 0.1651)
		(layer "B.Cu")
		(net "M_G_ECC<7>")
	)
	(segment
		(start 75.599544 -20.224242)
		(end 75.59929 -20.224496)
		(width 0.1651)
		(layer "B.Cu")
		(net "M_G_ECC<7>")
	)
	(segment
		(start 77.171296 -31.5468)
		(end 77.313536 -31.68904)
		(width 0.14224)
		(layer "In2.Cu")
		(net "M_G_ECC<7>")
	)
	(segment
		(start 75.840336 -26.210768)
		(end 76.089764 -26.460196)
		(width 0.14224)
		(layer "In2.Cu")
		(net "M_G_ECC<7>")
	)
	(segment
		(start 83.656424 -54.143656)
		(end 83.362292 -54.437788)
		(width 0.0889)
		(layer "In2.Cu")
		(net "M_G_ECC<7>")
	)
	(segment
		(start 76.107544 -18.1102)
		(end 76.107544 -18.4658)
		(width 0.14224)
		(layer "In2.Cu")
		(net "M_G_ECC<7>")
	)
	(segment
		(start 77.313536 -41.433496)
		(end 80.98282 -45.10278)
		(width 0.14224)
		(layer "In2.Cu")
		(net "M_G_ECC<7>")
	)
	(segment
		(start 83.142582 -56.876188)
		(end 83.137756 -56.884824)
		(width 0.0889)
		(layer "In2.Cu")
		(net "M_G_ECC<7>")
	)
	(segment
		(start 75.952096 -21.92655)
		(end 75.59929 -22.279356)
		(width 0.14224)
		(layer "In2.Cu")
		(net "M_G_ECC<7>")
	)
	(segment
		(start 84.859622 -59.847988)
		(end 84.854796 -59.856624)
		(width 0.0889)
		(layer "In2.Cu")
		(net "M_G_ECC<7>")
	)
	(segment
		(start 75.967336 -27.662632)
		(end 75.967336 -28.970224)
		(width 0.14224)
		(layer "In2.Cu")
		(net "M_G_ECC<7>")
	)
	(segment
		(start 75.967336 -28.970224)
		(end 75.611736 -29.325824)
		(width 0.14224)
		(layer "In2.Cu")
		(net "M_G_ECC<7>")
	)
	(segment
		(start 76.107544 -18.4658)
		(end 75.952096 -18.621248)
		(width 0.14224)
		(layer "In2.Cu")
		(net "M_G_ECC<7>")
	)
	(segment
		(start 84.859622 -60.838588)
		(end 84.854796 -60.847224)
		(width 0.0889)
		(layer "In2.Cu")
		(net "M_G_ECC<7>")
	)
	(segment
		(start 83.362292 -54.437788)
		(end 83.362292 -55.504588)
		(width 0.0889)
		(layer "In2.Cu")
		(net "M_G_ECC<7>")
	)
	(segment
		(start 82.950812 -48.803814)
		(end 82.750152 -49.004474)
		(width 0.0889)
		(layer "In2.Cu")
		(net "M_G_ECC<7>")
	)
	(segment
		(start 84.329778 -57.971436)
		(end 84.365592 -57.971436)
		(width 0.0889)
		(layer "In2.Cu")
		(net "M_G_ECC<7>")
	)
	(segment
		(start 84.850478 -61.506862)
		(end 84.347812 -62.52464)
		(width 0.0889)
		(layer "In2.Cu")
		(net "M_G_ECC<7>")
	)
	(segment
		(start 75.753976 -31.5468)
		(end 77.171296 -31.5468)
		(width 0.14224)
		(layer "In2.Cu")
		(net "M_G_ECC<7>")
	)
	(segment
		(start 84.859622 -58.857388)
		(end 84.854796 -58.866024)
		(width 0.0889)
		(layer "In2.Cu")
		(net "M_G_ECC<7>")
	)
	(segment
		(start 83.4517 -50.117248)
		(end 83.4517 -50.81905)
		(width 0.0889)
		(layer "In2.Cu")
		(net "M_G_ECC<7>")
	)
	(segment
		(start 75.59929 -22.279356)
		(end 75.131168 -22.747478)
		(width 0.14224)
		(layer "In2.Cu")
		(net "M_G_ECC<7>")
	)
	(segment
		(start 76.089764 -26.460196)
		(end 76.089764 -27.540204)
		(width 0.14224)
		(layer "In2.Cu")
		(net "M_G_ECC<7>")
	)
	(segment
		(start 82.750152 -49.4157)
		(end 83.4517 -50.117248)
		(width 0.0889)
		(layer "In2.Cu")
		(net "M_G_ECC<7>")
	)
	(segment
		(start 84.865972 -59.83732)
		(end 84.859622 -59.847988)
		(width 0.0889)
		(layer "In2.Cu")
		(net "M_G_ECC<7>")
	)
	(segment
		(start 77.313536 -31.68904)
		(end 77.313536 -41.433496)
		(width 0.14224)
		(layer "In2.Cu")
		(net "M_G_ECC<7>")
	)
	(segment
		(start 75.396344 -17.653)
		(end 75.650344 -17.653)
		(width 0.14224)
		(layer "In2.Cu")
		(net "M_G_ECC<7>")
	)
	(segment
		(start 75.611736 -29.325824)
		(end 75.611736 -31.40456)
		(width 0.14224)
		(layer "In2.Cu")
		(net "M_G_ECC<7>")
	)
	(segment
		(start 75.066144 -17.3228)
		(end 75.396344 -17.653)
		(width 0.14224)
		(layer "In2.Cu")
		(net "M_G_ECC<7>")
	)
	(segment
		(start 81.778348 -45.10278)
		(end 82.950812 -46.275244)
		(width 0.14224)
		(layer "In2.Cu")
		(net "M_G_ECC<7>")
	)
	(segment
		(start 75.066144 -17.004284)
		(end 75.066144 -17.3228)
		(width 0.14224)
		(layer "In2.Cu")
		(net "M_G_ECC<7>")
	)
	(segment
		(start 75.131168 -22.747478)
		(end 75.131168 -23.1902)
		(width 0.14224)
		(layer "In2.Cu")
		(net "M_G_ECC<7>")
	)
	(segment
		(start 84.865972 -60.82792)
		(end 84.859622 -60.838588)
		(width 0.0889)
		(layer "In2.Cu")
		(net "M_G_ECC<7>")
	)
	(segment
		(start 75.650344 -17.653)
		(end 76.107544 -18.1102)
		(width 0.14224)
		(layer "In2.Cu")
		(net "M_G_ECC<7>")
	)
	(segment
		(start 76.089764 -27.540204)
		(end 75.967336 -27.662632)
		(width 0.14224)
		(layer "In2.Cu")
		(net "M_G_ECC<7>")
	)
	(segment
		(start 83.148932 -56.86552)
		(end 83.142582 -56.876188)
		(width 0.0889)
		(layer "In2.Cu")
		(net "M_G_ECC<7>")
	)
	(segment
		(start 82.750152 -49.004474)
		(end 82.750152 -49.4157)
		(width 0.0889)
		(layer "In2.Cu")
		(net "M_G_ECC<7>")
	)
	(segment
		(start 84.859622 -61.238638)
		(end 84.850478 -61.506862)
		(width 0.0889)
		(layer "In2.Cu")
		(net "M_G_ECC<7>")
	)
	(segment
		(start 83.656424 -51.023774)
		(end 83.656424 -54.143656)
		(width 0.0889)
		(layer "In2.Cu")
		(net "M_G_ECC<7>")
	)
	(segment
		(start 75.840336 -23.899368)
		(end 75.840336 -26.210768)
		(width 0.14224)
		(layer "In2.Cu")
		(net "M_G_ECC<7>")
	)
	(segment
		(start 75.131168 -23.1902)
		(end 75.840336 -23.899368)
		(width 0.14224)
		(layer "In2.Cu")
		(net "M_G_ECC<7>")
	)
	(segment
		(start 82.950812 -46.275244)
		(end 82.950812 -48.803814)
		(width 0.14224)
		(layer "In2.Cu")
		(net "M_G_ECC<7>")
	)
	(segment
		(start 83.362292 -55.504588)
		(end 83.137756 -55.894224)
		(width 0.0889)
		(layer "In2.Cu")
		(net "M_G_ECC<7>")
	)
	(segment
		(start 74.749406 -16.687546)
		(end 75.066144 -17.004284)
		(width 0.14224)
		(layer "In2.Cu")
		(net "M_G_ECC<7>")
	)
	(segment
		(start 83.4517 -50.81905)
		(end 83.656424 -51.023774)
		(width 0.0889)
		(layer "In2.Cu")
		(net "M_G_ECC<7>")
	)
	(segment
		(start 75.952096 -18.621248)
		(end 75.952096 -21.92655)
		(width 0.14224)
		(layer "In2.Cu")
		(net "M_G_ECC<7>")
	)
	(segment
		(start 83.474306 -57.476136)
		(end 83.502246 -57.476136)
		(width 0.0889)
		(layer "In2.Cu")
		(net "M_G_ECC<7>")
	)
	(segment
		(start 80.98282 -45.10278)
		(end 81.778348 -45.10278)
		(width 0.14224)
		(layer "In2.Cu")
		(net "M_G_ECC<7>")
	)
	(segment
		(start 75.611736 -31.40456)
		(end 75.753976 -31.5468)
		(width 0.14224)
		(layer "In2.Cu")
		(net "M_G_ECC<7>")
	)
	(arc
		(start 83.137756 -56.884824)
		(mid 83.141503 -57.27408)
		(end 83.474306 -57.476136)
		(width 0.0889)
		(layer "In2.Cu")
		(net "M_G_ECC<7>")
	)
	(arc
		(start 84.365592 -57.971436)
		(mid 84.863843 -58.274276)
		(end 84.859622 -58.857388)
		(width 0.0889)
		(layer "In2.Cu")
		(net "M_G_ECC<7>")
	)
	(arc
		(start 83.142582 -56.285638)
		(mid 83.221804 -56.574756)
		(end 83.148932 -56.86552)
		(width 0.0889)
		(layer "In2.Cu")
		(net "M_G_ECC<7>")
	)
	(arc
		(start 84.001102 -57.771538)
		(mid 84.139846 -57.913571)
		(end 84.329778 -57.971436)
		(width 0.0889)
		(layer "In2.Cu")
		(net "M_G_ECC<7>")
	)
	(arc
		(start 83.502246 -57.476136)
		(mid 83.790391 -57.558455)
		(end 84.001102 -57.771538)
		(width 0.0889)
		(layer "In2.Cu")
		(net "M_G_ECC<7>")
	)
	(arc
		(start 84.859622 -60.248038)
		(mid 84.938844 -60.537156)
		(end 84.865972 -60.82792)
		(width 0.0889)
		(layer "In2.Cu")
		(net "M_G_ECC<7>")
	)
	(arc
		(start 84.859622 -59.257438)
		(mid 84.938844 -59.546556)
		(end 84.865972 -59.83732)
		(width 0.0889)
		(layer "In2.Cu")
		(net "M_G_ECC<7>")
	)
	(arc
		(start 83.137756 -55.894224)
		(mid 83.089001 -56.090576)
		(end 83.142582 -56.285638)
		(width 0.0889)
		(layer "In2.Cu")
		(net "M_G_ECC<7>")
	)
	(arc
		(start 84.854796 -60.847224)
		(mid 84.806041 -61.043576)
		(end 84.859622 -61.238638)
		(width 0.0889)
		(layer "In2.Cu")
		(net "M_G_ECC<7>")
	)
	(arc
		(start 84.854796 -58.866024)
		(mid 84.806041 -59.062376)
		(end 84.859622 -59.257438)
		(width 0.0889)
		(layer "In2.Cu")
		(net "M_G_ECC<7>")
	)
	(arc
		(start 84.854796 -59.856624)
		(mid 84.806041 -60.052976)
		(end 84.859622 -60.248038)
		(width 0.0889)
		(layer "In2.Cu")
		(net "M_G_ECC<7>")
	)
	(segment
		(start 75.731624 -18.69948)
		(end 75.599544 -18.5674)
		(width 0.1651)
		(layer "F.Cu")
		(net "M_G_ECC<6>")
	)
	(segment
		(start 75.599544 -18.5674)
		(end 75.599544 -18.262854)
		(width 0.1651)
		(layer "F.Cu")
		(net "M_G_ECC<6>")
	)
	(segment
		(start 84.919312 -60.54344)
		(end 84.347812 -60.54344)
		(width 0.1016)
		(layer "F.Cu")
		(net "M_G_ECC<6>")
	)
	(segment
		(start 75.731624 -18.91792)
		(end 75.731624 -18.69948)
		(width 0.1651)
		(layer "F.Cu")
		(net "M_G_ECC<6>")
	)
	(segment
		(start 75.599544 -18.262854)
		(end 75.59929 -18.2626)
		(width 0.1651)
		(layer "F.Cu")
		(net "M_G_ECC<6>")
	)
	(segment
		(start 75.599544 -20.023582)
		(end 75.599544 -19.05)
		(width 0.1651)
		(layer "F.Cu")
		(net "M_G_ECC<6>")
	)
	(segment
		(start 75.599544 -19.05)
		(end 75.731624 -18.91792)
		(width 0.1651)
		(layer "F.Cu")
		(net "M_G_ECC<6>")
	)
	(via
		(at 84.347812 -60.54344)
		(size 0.508)
		(drill 0.254)
		(layers "F.Cu" "B.Cu")
		(net "M_G_ECC<6>")
	)
	(via
		(at 75.59929 -18.2626)
		(size 0.508)
		(drill 0.254)
		(layers "F.Cu" "B.Cu")
		(net "M_G_ECC<6>")
	)
	(via
		(at 74.749406 -23.560278)
		(size 0.508)
		(drill 0.254)
		(layers "F.Cu" "B.Cu")
		(net "M_G_ECC<6>")
	)
	(segment
		(start 74.749406 -23.560278)
		(end 74.749406 -24.824182)
		(width 0.1651)
		(layer "B.Cu")
		(net "M_G_ECC<6>")
	)
	(segment
		(start 76.782168 -37.006022)
		(end 76.782168 -37.412422)
		(width 0.14224)
		(layer "In2.Cu")
		(net "M_G_ECC<6>")
	)
	(segment
		(start 83.2612 -50.196242)
		(end 83.2612 -50.897282)
		(width 0.0889)
		(layer "In2.Cu")
		(net "M_G_ECC<6>")
	)
	(segment
		(start 83.2612 -50.897282)
		(end 83.466432 -51.102514)
		(width 0.0889)
		(layer "In2.Cu")
		(net "M_G_ECC<6>")
	)
	(segment
		(start 80.784192 -45.58157)
		(end 81.469738 -45.58157)
		(width 0.14224)
		(layer "In2.Cu")
		(net "M_G_ECC<6>")
	)
	(segment
		(start 82.977482 -56.780938)
		(end 82.971132 -56.791606)
		(width 0.0889)
		(layer "In2.Cu")
		(net "M_G_ECC<6>")
	)
	(segment
		(start 74.431144 -23.242016)
		(end 74.749406 -23.560278)
		(width 0.14224)
		(layer "In2.Cu")
		(net "M_G_ECC<6>")
	)
	(segment
		(start 76.440792 -40.32123)
		(end 76.678536 -40.558974)
		(width 0.14224)
		(layer "In2.Cu")
		(net "M_G_ECC<6>")
	)
	(segment
		(start 76.005944 -40.32123)
		(end 76.440792 -40.32123)
		(width 0.14224)
		(layer "In2.Cu")
		(net "M_G_ECC<6>")
	)
	(segment
		(start 75.840336 -38.225222)
		(end 76.043536 -38.428422)
		(width 0.14224)
		(layer "In2.Cu")
		(net "M_G_ECC<6>")
	)
	(segment
		(start 74.749406 -23.561294)
		(end 75.230736 -24.042624)
		(width 0.14224)
		(layer "In2.Cu")
		(net "M_G_ECC<6>")
	)
	(segment
		(start 84.67725 -59.782456)
		(end 84.347812 -60.54344)
		(width 0.0889)
		(layer "In2.Cu")
		(net "M_G_ECC<6>")
	)
	(segment
		(start 75.840336 -36.599622)
		(end 76.043536 -36.802822)
		(width 0.14224)
		(layer "In2.Cu")
		(net "M_G_ECC<6>")
	)
	(segment
		(start 76.807568 -39.038022)
		(end 76.604368 -39.241222)
		(width 0.14224)
		(layer "In2.Cu")
		(net "M_G_ECC<6>")
	)
	(segment
		(start 75.378564 -28.619196)
		(end 74.976736 -29.021024)
		(width 0.14224)
		(layer "In2.Cu")
		(net "M_G_ECC<6>")
	)
	(segment
		(start 76.043536 -39.241222)
		(end 75.840336 -39.444422)
		(width 0.14224)
		(layer "In2.Cu")
		(net "M_G_ECC<6>")
	)
	(segment
		(start 76.782168 -37.412422)
		(end 76.578968 -37.615622)
		(width 0.14224)
		(layer "In2.Cu")
		(net "M_G_ECC<6>")
	)
	(segment
		(start 76.578968 -36.802822)
		(end 76.782168 -37.006022)
		(width 0.14224)
		(layer "In2.Cu")
		(net "M_G_ECC<6>")
	)
	(segment
		(start 83.171792 -55.454042)
		(end 82.971132 -55.801006)
		(width 0.0889)
		(layer "In2.Cu")
		(net "M_G_ECC<6>")
	)
	(segment
		(start 75.840336 -37.818822)
		(end 75.840336 -38.225222)
		(width 0.14224)
		(layer "In2.Cu")
		(net "M_G_ECC<6>")
	)
	(segment
		(start 75.840336 -40.155622)
		(end 76.005944 -40.32123)
		(width 0.14224)
		(layer "In2.Cu")
		(net "M_G_ECC<6>")
	)
	(segment
		(start 75.378564 -27.857196)
		(end 75.378564 -28.619196)
		(width 0.14224)
		(layer "In2.Cu")
		(net "M_G_ECC<6>")
	)
	(segment
		(start 74.431144 -22.7965)
		(end 74.431144 -23.242016)
		(width 0.14224)
		(layer "In2.Cu")
		(net "M_G_ECC<6>")
	)
	(segment
		(start 76.680568 -35.786822)
		(end 76.477368 -35.990022)
		(width 0.14224)
		(layer "In2.Cu")
		(net "M_G_ECC<6>")
	)
	(segment
		(start 76.678536 -40.558974)
		(end 76.678536 -41.475914)
		(width 0.14224)
		(layer "In2.Cu")
		(net "M_G_ECC<6>")
	)
	(segment
		(start 84.326222 -58.16219)
		(end 84.365846 -58.16219)
		(width 0.0889)
		(layer "In2.Cu")
		(net "M_G_ECC<6>")
	)
	(segment
		(start 75.193144 -22.0345)
		(end 74.431144 -22.7965)
		(width 0.14224)
		(layer "In2.Cu")
		(net "M_G_ECC<6>")
	)
	(segment
		(start 75.840336 -34.974022)
		(end 76.043536 -35.177222)
		(width 0.14224)
		(layer "In2.Cu")
		(net "M_G_ECC<6>")
	)
	(segment
		(start 75.193144 -18.668746)
		(end 75.193144 -22.0345)
		(width 0.14224)
		(layer "In2.Cu")
		(net "M_G_ECC<6>")
	)
	(segment
		(start 76.043536 -38.428422)
		(end 76.604368 -38.428422)
		(width 0.14224)
		(layer "In2.Cu")
		(net "M_G_ECC<6>")
	)
	(segment
		(start 75.840336 -39.444422)
		(end 75.840336 -40.155622)
		(width 0.14224)
		(layer "In2.Cu")
		(net "M_G_ECC<6>")
	)
	(segment
		(start 74.976736 -32.729678)
		(end 75.918568 -33.67151)
		(width 0.14224)
		(layer "In2.Cu")
		(net "M_G_ECC<6>")
	)
	(segment
		(start 75.230736 -26.291032)
		(end 75.099164 -26.422604)
		(width 0.14224)
		(layer "In2.Cu")
		(net "M_G_ECC<6>")
	)
	(segment
		(start 82.303112 -46.414944)
		(end 82.303112 -48.801274)
		(width 0.14224)
		(layer "In2.Cu")
		(net "M_G_ECC<6>")
	)
	(segment
		(start 75.59929 -18.2626)
		(end 75.193144 -18.668746)
		(width 0.14224)
		(layer "In2.Cu")
		(net "M_G_ECC<6>")
	)
	(segment
		(start 81.469738 -45.58157)
		(end 82.303112 -46.414944)
		(width 0.14224)
		(layer "In2.Cu")
		(net "M_G_ECC<6>")
	)
	(segment
		(start 84.699348 -59.744102)
		(end 84.67725 -59.782456)
		(width 0.0889)
		(layer "In2.Cu")
		(net "M_G_ECC<6>")
	)
	(segment
		(start 75.840336 -34.567622)
		(end 75.840336 -34.974022)
		(width 0.14224)
		(layer "In2.Cu")
		(net "M_G_ECC<6>")
	)
	(segment
		(start 76.578968 -37.615622)
		(end 76.043536 -37.615622)
		(width 0.14224)
		(layer "In2.Cu")
		(net "M_G_ECC<6>")
	)
	(segment
		(start 75.840336 -36.193222)
		(end 75.840336 -36.599622)
		(width 0.14224)
		(layer "In2.Cu")
		(net "M_G_ECC<6>")
	)
	(segment
		(start 76.680568 -35.380422)
		(end 76.680568 -35.786822)
		(width 0.14224)
		(layer "In2.Cu")
		(net "M_G_ECC<6>")
	)
	(segment
		(start 83.171792 -54.358794)
		(end 83.171792 -55.454042)
		(width 0.0889)
		(layer "In2.Cu")
		(net "M_G_ECC<6>")
	)
	(segment
		(start 76.604368 -39.241222)
		(end 76.043536 -39.241222)
		(width 0.14224)
		(layer "In2.Cu")
		(net "M_G_ECC<6>")
	)
	(segment
		(start 76.807568 -38.631622)
		(end 76.807568 -39.038022)
		(width 0.14224)
		(layer "In2.Cu")
		(net "M_G_ECC<6>")
	)
	(segment
		(start 76.043536 -37.615622)
		(end 75.840336 -37.818822)
		(width 0.14224)
		(layer "In2.Cu")
		(net "M_G_ECC<6>")
	)
	(segment
		(start 75.230736 -24.042624)
		(end 75.230736 -26.291032)
		(width 0.14224)
		(layer "In2.Cu")
		(net "M_G_ECC<6>")
	)
	(segment
		(start 82.559652 -49.494694)
		(end 83.2612 -50.196242)
		(width 0.0889)
		(layer "In2.Cu")
		(net "M_G_ECC<6>")
	)
	(segment
		(start 74.976736 -29.021024)
		(end 74.976736 -32.729678)
		(width 0.14224)
		(layer "In2.Cu")
		(net "M_G_ECC<6>")
	)
	(segment
		(start 75.918568 -34.48939)
		(end 75.840336 -34.567622)
		(width 0.14224)
		(layer "In2.Cu")
		(net "M_G_ECC<6>")
	)
	(segment
		(start 82.559652 -49.057814)
		(end 82.559652 -49.494694)
		(width 0.0889)
		(layer "In2.Cu")
		(net "M_G_ECC<6>")
	)
	(segment
		(start 83.476338 -57.66689)
		(end 83.500468 -57.66689)
		(width 0.0889)
		(layer "In2.Cu")
		(net "M_G_ECC<6>")
	)
	(segment
		(start 76.604368 -38.428422)
		(end 76.807568 -38.631622)
		(width 0.14224)
		(layer "In2.Cu")
		(net "M_G_ECC<6>")
	)
	(segment
		(start 75.918568 -33.67151)
		(end 75.918568 -34.48939)
		(width 0.14224)
		(layer "In2.Cu")
		(net "M_G_ECC<6>")
	)
	(segment
		(start 76.043536 -35.177222)
		(end 76.477368 -35.177222)
		(width 0.14224)
		(layer "In2.Cu")
		(net "M_G_ECC<6>")
	)
	(segment
		(start 76.043536 -35.990022)
		(end 75.840336 -36.193222)
		(width 0.14224)
		(layer "In2.Cu")
		(net "M_G_ECC<6>")
	)
	(segment
		(start 76.477368 -35.990022)
		(end 76.043536 -35.990022)
		(width 0.14224)
		(layer "In2.Cu")
		(net "M_G_ECC<6>")
	)
	(segment
		(start 74.749406 -23.560278)
		(end 74.749406 -23.561294)
		(width 0.14224)
		(layer "In2.Cu")
		(net "M_G_ECC<6>")
	)
	(segment
		(start 82.303112 -48.801274)
		(end 82.559652 -49.057814)
		(width 0.0889)
		(layer "In2.Cu")
		(net "M_G_ECC<6>")
	)
	(segment
		(start 83.466432 -54.064154)
		(end 83.171792 -54.358794)
		(width 0.0889)
		(layer "In2.Cu")
		(net "M_G_ECC<6>")
	)
	(segment
		(start 75.099164 -26.422604)
		(end 75.099164 -27.577796)
		(width 0.14224)
		(layer "In2.Cu")
		(net "M_G_ECC<6>")
	)
	(segment
		(start 75.099164 -27.577796)
		(end 75.378564 -27.857196)
		(width 0.14224)
		(layer "In2.Cu")
		(net "M_G_ECC<6>")
	)
	(segment
		(start 76.678536 -41.475914)
		(end 80.784192 -45.58157)
		(width 0.14224)
		(layer "In2.Cu")
		(net "M_G_ECC<6>")
	)
	(segment
		(start 76.043536 -36.802822)
		(end 76.578968 -36.802822)
		(width 0.14224)
		(layer "In2.Cu")
		(net "M_G_ECC<6>")
	)
	(segment
		(start 83.466432 -51.102514)
		(end 83.466432 -54.064154)
		(width 0.0889)
		(layer "In2.Cu")
		(net "M_G_ECC<6>")
	)
	(segment
		(start 76.477368 -35.177222)
		(end 76.680568 -35.380422)
		(width 0.14224)
		(layer "In2.Cu")
		(net "M_G_ECC<6>")
	)
	(segment
		(start 82.982308 -56.772302)
		(end 82.977482 -56.780938)
		(width 0.0889)
		(layer "In2.Cu")
		(net "M_G_ECC<6>")
	)
	(arc
		(start 82.977482 -56.380888)
		(mid 83.030952 -56.575951)
		(end 82.982308 -56.772302)
		(width 0.0889)
		(layer "In2.Cu")
		(net "M_G_ECC<6>")
	)
	(arc
		(start 84.694522 -59.352688)
		(mid 84.747992 -59.547751)
		(end 84.699348 -59.744102)
		(width 0.0889)
		(layer "In2.Cu")
		(net "M_G_ECC<6>")
	)
	(arc
		(start 84.694522 -58.761884)
		(mid 84.615391 -59.057286)
		(end 84.694522 -59.352688)
		(width 0.0889)
		(layer "In2.Cu")
		(net "M_G_ECC<6>")
	)
	(arc
		(start 83.500468 -57.66689)
		(mid 83.694318 -57.72324)
		(end 83.836002 -57.867042)
		(width 0.0889)
		(layer "In2.Cu")
		(net "M_G_ECC<6>")
	)
	(arc
		(start 84.365846 -58.16219)
		(mid 84.698762 -58.369642)
		(end 84.694522 -58.761884)
		(width 0.0889)
		(layer "In2.Cu")
		(net "M_G_ECC<6>")
	)
	(arc
		(start 82.971132 -56.791606)
		(mid 82.977309 -57.371538)
		(end 83.476338 -57.66689)
		(width 0.0889)
		(layer "In2.Cu")
		(net "M_G_ECC<6>")
	)
	(arc
		(start 82.971132 -55.801006)
		(mid 82.898334 -56.091769)
		(end 82.977482 -56.380888)
		(width 0.0889)
		(layer "In2.Cu")
		(net "M_G_ECC<6>")
	)
	(arc
		(start 83.836002 -57.867042)
		(mid 84.043006 -58.077906)
		(end 84.326222 -58.16219)
		(width 0.0889)
		(layer "In2.Cu")
		(net "M_G_ECC<6>")
	)
	(segment
		(start 68.799456 -15.423642)
		(end 68.799456 -16.687546)
		(width 0.1651)
		(layer "F.Cu")
		(net "M_G_ECC<5>")
	)
	(segment
		(start 82.343752 -62.029086)
		(end 81.772252 -62.029086)
		(width 0.1016)
		(layer "F.Cu")
		(net "M_G_ECC<5>")
	)
	(via
		(at 69.57314 -22.279356)
		(size 0.508)
		(drill 0.254)
		(layers "F.Cu" "B.Cu")
		(net "M_G_ECC<5>")
	)
	(via
		(at 68.799456 -16.687546)
		(size 0.508)
		(drill 0.254)
		(layers "F.Cu" "B.Cu")
		(net "M_G_ECC<5>")
	)
	(via
		(at 81.772252 -62.029086)
		(size 0.508)
		(drill 0.254)
		(layers "F.Cu" "B.Cu")
		(net "M_G_ECC<5>")
	)
	(segment
		(start 69.64934 -20.224242)
		(end 69.64934 -22.203156)
		(width 0.1651)
		(layer "B.Cu")
		(net "M_G_ECC<5>")
	)
	(segment
		(start 69.64934 -22.203156)
		(end 69.57314 -22.279356)
		(width 0.1651)
		(layer "B.Cu")
		(net "M_G_ECC<5>")
	)
	(segment
		(start 81.85531 -60.58154)
		(end 82.07375 -60.754006)
		(width 0.0889)
		(layer "In2.Cu")
		(net "M_G_ECC<5>")
	)
	(segment
		(start 70.081394 -18.4658)
		(end 69.884544 -18.66265)
		(width 0.14224)
		(layer "In2.Cu")
		(net "M_G_ECC<5>")
	)
	(segment
		(start 79.708502 -58.857388)
		(end 79.703676 -58.866024)
		(width 0.0889)
		(layer "In2.Cu")
		(net "M_G_ECC<5>")
	)
	(segment
		(start 82.06486 -61.355732)
		(end 81.772252 -61.64834)
		(width 0.0889)
		(layer "In2.Cu")
		(net "M_G_ECC<5>")
	)
	(segment
		(start 79.585566 -52.6669)
		(end 79.585566 -53.100732)
		(width 0.0889)
		(layer "In2.Cu")
		(net "M_G_ECC<5>")
	)
	(segment
		(start 82.102198 -61.26734)
		(end 82.06486 -61.3537)
		(width 0.0889)
		(layer "In2.Cu")
		(net "M_G_ECC<5>")
	)
	(segment
		(start 77.679296 -49.628552)
		(end 79.882492 -51.831748)
		(width 0.0889)
		(layer "In2.Cu")
		(net "M_G_ECC<5>")
	)
	(segment
		(start 82.06486 -61.3537)
		(end 82.06486 -61.355732)
		(width 0.0889)
		(layer "In2.Cu")
		(net "M_G_ECC<5>")
	)
	(segment
		(start 79.714852 -56.86552)
		(end 79.708502 -56.876188)
		(width 0.0889)
		(layer "In2.Cu")
		(net "M_G_ECC<5>")
	)
	(segment
		(start 69.968364 -26.917396)
		(end 70.044564 -26.993596)
		(width 0.14224)
		(layer "In2.Cu")
		(net "M_G_ECC<5>")
	)
	(segment
		(start 79.708502 -56.876188)
		(end 79.703676 -56.884824)
		(width 0.0889)
		(layer "In2.Cu")
		(net "M_G_ECC<5>")
	)
	(segment
		(start 69.884544 -21.967952)
		(end 69.57314 -22.279356)
		(width 0.14224)
		(layer "In2.Cu")
		(net "M_G_ECC<5>")
	)
	(segment
		(start 79.882492 -51.831748)
		(end 79.882492 -52.369974)
		(width 0.0889)
		(layer "In2.Cu")
		(net "M_G_ECC<5>")
	)
	(segment
		(start 70.081394 -18.053304)
		(end 70.081394 -18.4658)
		(width 0.14224)
		(layer "In2.Cu")
		(net "M_G_ECC<5>")
	)
	(segment
		(start 69.968364 -24.034496)
		(end 69.968364 -26.917396)
		(width 0.14224)
		(layer "In2.Cu")
		(net "M_G_ECC<5>")
	)
	(segment
		(start 82.118962 -61.238638)
		(end 82.102198 -61.26734)
		(width 0.0889)
		(layer "In2.Cu")
		(net "M_G_ECC<5>")
	)
	(segment
		(start 79.708502 -55.885588)
		(end 79.703676 -55.894224)
		(width 0.0889)
		(layer "In2.Cu")
		(net "M_G_ECC<5>")
	)
	(segment
		(start 70.044564 -26.993596)
		(end 70.044564 -28.187396)
		(width 0.14224)
		(layer "In2.Cu")
		(net "M_G_ECC<5>")
	)
	(segment
		(start 79.708502 -58.266838)
		(end 79.714852 -58.277506)
		(width 0.0889)
		(layer "In2.Cu")
		(net "M_G_ECC<5>")
	)
	(segment
		(start 69.526404 -22.279356)
		(end 69.055996 -22.749764)
		(width 0.14224)
		(layer "In2.Cu")
		(net "M_G_ECC<5>")
	)
	(segment
		(start 68.799456 -17.082262)
		(end 69.370194 -17.653)
		(width 0.14224)
		(layer "In2.Cu")
		(net "M_G_ECC<5>")
	)
	(segment
		(start 69.884544 -18.66265)
		(end 69.884544 -21.967952)
		(width 0.14224)
		(layer "In2.Cu")
		(net "M_G_ECC<5>")
	)
	(segment
		(start 70.660768 -29.7688)
		(end 70.660768 -41.084754)
		(width 0.14224)
		(layer "In2.Cu")
		(net "M_G_ECC<5>")
	)
	(segment
		(start 70.044564 -28.187396)
		(end 69.993764 -28.238196)
		(width 0.14224)
		(layer "In2.Cu")
		(net "M_G_ECC<5>")
	)
	(segment
		(start 77.679296 -49.39157)
		(end 77.679296 -49.628552)
		(width 0.0889)
		(layer "In2.Cu")
		(net "M_G_ECC<5>")
	)
	(segment
		(start 79.708502 -53.904388)
		(end 79.703676 -53.913024)
		(width 0.0889)
		(layer "In2.Cu")
		(net "M_G_ECC<5>")
	)
	(segment
		(start 69.055996 -23.122128)
		(end 69.968364 -24.034496)
		(width 0.14224)
		(layer "In2.Cu")
		(net "M_G_ECC<5>")
	)
	(segment
		(start 80.040226 -59.457336)
		(end 80.072992 -59.457336)
		(width 0.0889)
		(layer "In2.Cu")
		(net "M_G_ECC<5>")
	)
	(segment
		(start 69.57314 -22.279356)
		(end 69.526404 -22.279356)
		(width 0.14224)
		(layer "In2.Cu")
		(net "M_G_ECC<5>")
	)
	(segment
		(start 69.993764 -29.101796)
		(end 70.660768 -29.7688)
		(width 0.14224)
		(layer "In2.Cu")
		(net "M_G_ECC<5>")
	)
	(segment
		(start 80.902556 -59.95289)
		(end 80.935322 -59.95289)
		(width 0.0889)
		(layer "In2.Cu")
		(net "M_G_ECC<5>")
	)
	(segment
		(start 69.055996 -22.749764)
		(end 69.055996 -23.122128)
		(width 0.14224)
		(layer "In2.Cu")
		(net "M_G_ECC<5>")
	)
	(segment
		(start 70.660768 -41.084754)
		(end 77.919072 -48.343058)
		(width 0.14224)
		(layer "In2.Cu")
		(net "M_G_ECC<5>")
	)
	(segment
		(start 69.993764 -28.238196)
		(end 69.993764 -29.101796)
		(width 0.14224)
		(layer "In2.Cu")
		(net "M_G_ECC<5>")
	)
	(segment
		(start 79.714852 -54.88432)
		(end 79.708502 -54.894988)
		(width 0.0889)
		(layer "In2.Cu")
		(net "M_G_ECC<5>")
	)
	(segment
		(start 81.772252 -61.64834)
		(end 81.772252 -62.029086)
		(width 0.0889)
		(layer "In2.Cu")
		(net "M_G_ECC<5>")
	)
	(segment
		(start 69.68109 -17.653)
		(end 70.081394 -18.053304)
		(width 0.14224)
		(layer "In2.Cu")
		(net "M_G_ECC<5>")
	)
	(segment
		(start 77.919072 -49.151794)
		(end 77.679296 -49.39157)
		(width 0.0889)
		(layer "In2.Cu")
		(net "M_G_ECC<5>")
	)
	(segment
		(start 79.585566 -53.100732)
		(end 79.708502 -53.313838)
		(width 0.0889)
		(layer "In2.Cu")
		(net "M_G_ECC<5>")
	)
	(segment
		(start 69.370194 -17.653)
		(end 69.68109 -17.653)
		(width 0.14224)
		(layer "In2.Cu")
		(net "M_G_ECC<5>")
	)
	(segment
		(start 79.882492 -52.369974)
		(end 79.585566 -52.6669)
		(width 0.0889)
		(layer "In2.Cu")
		(net "M_G_ECC<5>")
	)
	(segment
		(start 79.714852 -53.89372)
		(end 79.708502 -53.904388)
		(width 0.0889)
		(layer "In2.Cu")
		(net "M_G_ECC<5>")
	)
	(segment
		(start 81.558638 -60.386468)
		(end 81.85531 -60.58154)
		(width 0.0889)
		(layer "In2.Cu")
		(net "M_G_ECC<5>")
	)
	(segment
		(start 77.919072 -48.343058)
		(end 77.919072 -49.151794)
		(width 0.14224)
		(layer "In2.Cu")
		(net "M_G_ECC<5>")
	)
	(segment
		(start 79.714852 -55.87492)
		(end 79.708502 -55.885588)
		(width 0.0889)
		(layer "In2.Cu")
		(net "M_G_ECC<5>")
	)
	(segment
		(start 82.07375 -60.754006)
		(end 82.121756 -60.837318)
		(width 0.0889)
		(layer "In2.Cu")
		(net "M_G_ECC<5>")
	)
	(segment
		(start 68.799456 -16.687546)
		(end 68.799456 -17.082262)
		(width 0.14224)
		(layer "In2.Cu")
		(net "M_G_ECC<5>")
	)
	(segment
		(start 79.708502 -54.894988)
		(end 79.703676 -54.903624)
		(width 0.0889)
		(layer "In2.Cu")
		(net "M_G_ECC<5>")
	)
	(arc
		(start 79.708502 -53.313838)
		(mid 79.787724 -53.602956)
		(end 79.714852 -53.89372)
		(width 0.0889)
		(layer "In2.Cu")
		(net "M_G_ECC<5>")
	)
	(arc
		(start 79.703676 -53.913024)
		(mid 79.654921 -54.109376)
		(end 79.708502 -54.304438)
		(width 0.0889)
		(layer "In2.Cu")
		(net "M_G_ECC<5>")
	)
	(arc
		(start 80.935322 -59.95289)
		(mid 81.218539 -60.037171)
		(end 81.425542 -60.248038)
		(width 0.0889)
		(layer "In2.Cu")
		(net "M_G_ECC<5>")
	)
	(arc
		(start 79.708502 -55.295038)
		(mid 79.787724 -55.584156)
		(end 79.714852 -55.87492)
		(width 0.0889)
		(layer "In2.Cu")
		(net "M_G_ECC<5>")
	)
	(arc
		(start 79.708502 -57.276238)
		(mid 79.787633 -57.57164)
		(end 79.708502 -57.867042)
		(width 0.0889)
		(layer "In2.Cu")
		(net "M_G_ECC<5>")
	)
	(arc
		(start 79.703676 -58.866024)
		(mid 79.707423 -59.25528)
		(end 80.040226 -59.457336)
		(width 0.0889)
		(layer "In2.Cu")
		(net "M_G_ECC<5>")
	)
	(arc
		(start 79.703676 -55.894224)
		(mid 79.654921 -56.090576)
		(end 79.708502 -56.285638)
		(width 0.0889)
		(layer "In2.Cu")
		(net "M_G_ECC<5>")
	)
	(arc
		(start 79.708502 -54.304438)
		(mid 79.787724 -54.593556)
		(end 79.714852 -54.88432)
		(width 0.0889)
		(layer "In2.Cu")
		(net "M_G_ECC<5>")
	)
	(arc
		(start 79.708502 -57.867042)
		(mid 79.655003 -58.06694)
		(end 79.708502 -58.266838)
		(width 0.0889)
		(layer "In2.Cu")
		(net "M_G_ECC<5>")
	)
	(arc
		(start 80.072992 -59.457336)
		(mid 80.358416 -59.540803)
		(end 80.567022 -59.752738)
		(width 0.0889)
		(layer "In2.Cu")
		(net "M_G_ECC<5>")
	)
	(arc
		(start 79.714852 -58.277506)
		(mid 79.78765 -58.568269)
		(end 79.708502 -58.857388)
		(width 0.0889)
		(layer "In2.Cu")
		(net "M_G_ECC<5>")
	)
	(arc
		(start 79.708502 -56.285638)
		(mid 79.787724 -56.574756)
		(end 79.714852 -56.86552)
		(width 0.0889)
		(layer "In2.Cu")
		(net "M_G_ECC<5>")
	)
	(arc
		(start 82.121756 -60.837318)
		(mid 82.173308 -61.038336)
		(end 82.118962 -61.238638)
		(width 0.0889)
		(layer "In2.Cu")
		(net "M_G_ECC<5>")
	)
	(arc
		(start 80.567022 -59.752738)
		(mid 80.708705 -59.896542)
		(end 80.902556 -59.95289)
		(width 0.0889)
		(layer "In2.Cu")
		(net "M_G_ECC<5>")
	)
	(arc
		(start 79.703676 -54.903624)
		(mid 79.654921 -55.099976)
		(end 79.708502 -55.295038)
		(width 0.0889)
		(layer "In2.Cu")
		(net "M_G_ECC<5>")
	)
	(arc
		(start 81.425542 -60.248038)
		(mid 81.483667 -60.325352)
		(end 81.558638 -60.386468)
		(width 0.0889)
		(layer "In2.Cu")
		(net "M_G_ECC<5>")
	)
	(arc
		(start 79.703676 -56.884824)
		(mid 79.654921 -57.081176)
		(end 79.708502 -57.276238)
		(width 0.0889)
		(layer "In2.Cu")
		(net "M_G_ECC<5>")
	)
	(segment
		(start 69.64934 -20.023582)
		(end 69.64934 -18.692368)
		(width 0.1651)
		(layer "F.Cu")
		(net "M_G_ECC<4>")
	)
	(segment
		(start 82.343752 -61.038486)
		(end 81.772252 -61.038486)
		(width 0.1016)
		(layer "F.Cu")
		(net "M_G_ECC<4>")
	)
	(segment
		(start 69.64934 -18.692368)
		(end 69.551296 -18.161)
		(width 0.1651)
		(layer "F.Cu")
		(net "M_G_ECC<4>")
	)
	(via
		(at 69.551296 -18.161)
		(size 0.508)
		(drill 0.254)
		(layers "F.Cu" "B.Cu")
		(net "M_G_ECC<4>")
	)
	(via
		(at 68.799456 -23.560278)
		(size 0.508)
		(drill 0.254)
		(layers "F.Cu" "B.Cu")
		(net "M_G_ECC<4>")
	)
	(via
		(at 81.772252 -61.038486)
		(size 0.508)
		(drill 0.254)
		(layers "F.Cu" "B.Cu")
		(net "M_G_ECC<4>")
	)
	(segment
		(start 68.799456 -23.560278)
		(end 68.799456 -24.824182)
		(width 0.1651)
		(layer "B.Cu")
		(net "M_G_ECC<4>")
	)
	(segment
		(start 77.271372 -48.372776)
		(end 77.271372 -49.177194)
		(width 0.14224)
		(layer "In2.Cu")
		(net "M_G_ECC<4>")
	)
	(segment
		(start 77.271372 -49.177194)
		(end 77.487272 -49.393094)
		(width 0.0889)
		(layer "In2.Cu")
		(net "M_G_ECC<4>")
	)
	(segment
		(start 68.563744 -23.324566)
		(end 68.799456 -23.560278)
		(width 0.14224)
		(layer "In2.Cu")
		(net "M_G_ECC<4>")
	)
	(segment
		(start 70.019672 -30.177994)
		(end 69.871844 -30.325822)
		(width 0.14224)
		(layer "In2.Cu")
		(net "M_G_ECC<4>")
	)
	(segment
		(start 68.799456 -23.560278)
		(end 69.490336 -24.251158)
		(width 0.14224)
		(layer "In2.Cu")
		(net "M_G_ECC<4>")
	)
	(segment
		(start 81.323942 -60.43295)
		(end 81.772252 -61.038486)
		(width 0.0889)
		(layer "In2.Cu")
		(net "M_G_ECC<4>")
	)
	(segment
		(start 69.287136 -25.594056)
		(end 69.490336 -25.797256)
		(width 0.14224)
		(layer "In2.Cu")
		(net "M_G_ECC<4>")
	)
	(segment
		(start 70.095364 -31.280862)
		(end 70.095364 -41.196768)
		(width 0.14224)
		(layer "In2.Cu")
		(net "M_G_ECC<4>")
	)
	(segment
		(start 68.847208 -30.325822)
		(end 68.704968 -30.468062)
		(width 0.14224)
		(layer "In2.Cu")
		(net "M_G_ECC<4>")
	)
	(segment
		(start 79.395066 -52.621688)
		(end 79.395066 -53.151786)
		(width 0.0889)
		(layer "In2.Cu")
		(net "M_G_ECC<4>")
	)
	(segment
		(start 79.548228 -57.762902)
		(end 79.543402 -57.771538)
		(width 0.0889)
		(layer "In2.Cu")
		(net "M_G_ECC<4>")
	)
	(segment
		(start 79.548228 -55.781702)
		(end 79.543402 -55.790338)
		(width 0.0889)
		(layer "In2.Cu")
		(net "M_G_ECC<4>")
	)
	(segment
		(start 69.337936 -28.420568)
		(end 69.337936 -29.360622)
		(width 0.14224)
		(layer "In2.Cu")
		(net "M_G_ECC<4>")
	)
	(segment
		(start 79.183992 -51.405028)
		(end 79.183992 -51.663854)
		(width 0.0889)
		(layer "In2.Cu")
		(net "M_G_ECC<4>")
	)
	(segment
		(start 79.543402 -54.799738)
		(end 79.537052 -54.810406)
		(width 0.0889)
		(layer "In2.Cu")
		(net "M_G_ECC<4>")
	)
	(segment
		(start 70.095364 -41.196768)
		(end 77.271372 -48.372776)
		(width 0.14224)
		(layer "In2.Cu")
		(net "M_G_ECC<4>")
	)
	(segment
		(start 69.274944 -18.437352)
		(end 69.274944 -21.818854)
		(width 0.14224)
		(layer "In2.Cu")
		(net "M_G_ECC<4>")
	)
	(segment
		(start 77.487272 -49.393094)
		(end 77.487272 -49.708308)
		(width 0.0889)
		(layer "In2.Cu")
		(net "M_G_ECC<4>")
	)
	(segment
		(start 79.543402 -53.809138)
		(end 79.537052 -53.819806)
		(width 0.0889)
		(layer "In2.Cu")
		(net "M_G_ECC<4>")
	)
	(segment
		(start 80.895952 -60.14339)
		(end 80.928718 -60.14339)
		(width 0.0889)
		(layer "In2.Cu")
		(net "M_G_ECC<4>")
	)
	(segment
		(start 79.548228 -54.791102)
		(end 79.543402 -54.799738)
		(width 0.0889)
		(layer "In2.Cu")
		(net "M_G_ECC<4>")
	)
	(segment
		(start 79.072232 -51.775614)
		(end 79.072232 -52.298854)
		(width 0.0889)
		(layer "In2.Cu")
		(net "M_G_ECC<4>")
	)
	(segment
		(start 80.033622 -59.647836)
		(end 80.066388 -59.647836)
		(width 0.0889)
		(layer "In2.Cu")
		(net "M_G_ECC<4>")
	)
	(segment
		(start 68.704968 -30.468062)
		(end 68.704968 -30.996382)
		(width 0.14224)
		(layer "In2.Cu")
		(net "M_G_ECC<4>")
	)
	(segment
		(start 77.487272 -49.708308)
		(end 79.183992 -51.405028)
		(width 0.0889)
		(layer "In2.Cu")
		(net "M_G_ECC<4>")
	)
	(segment
		(start 79.183992 -51.663854)
		(end 79.072232 -51.775614)
		(width 0.0889)
		(layer "In2.Cu")
		(net "M_G_ECC<4>")
	)
	(segment
		(start 69.871844 -30.325822)
		(end 68.847208 -30.325822)
		(width 0.14224)
		(layer "In2.Cu")
		(net "M_G_ECC<4>")
	)
	(segment
		(start 70.019672 -30.042358)
		(end 70.019672 -30.177994)
		(width 0.14224)
		(layer "In2.Cu")
		(net "M_G_ECC<4>")
	)
	(segment
		(start 68.677536 -24.984456)
		(end 68.677536 -25.390856)
		(width 0.14224)
		(layer "In2.Cu")
		(net "M_G_ECC<4>")
	)
	(segment
		(start 69.551296 -18.161)
		(end 69.274944 -18.437352)
		(width 0.14224)
		(layer "In2.Cu")
		(net "M_G_ECC<4>")
	)
	(segment
		(start 79.072232 -52.298854)
		(end 79.395066 -52.621688)
		(width 0.0889)
		(layer "In2.Cu")
		(net "M_G_ECC<4>")
	)
	(segment
		(start 68.855336 -24.806656)
		(end 68.677536 -24.984456)
		(width 0.14224)
		(layer "In2.Cu")
		(net "M_G_ECC<4>")
	)
	(segment
		(start 68.847208 -31.138622)
		(end 69.953124 -31.138622)
		(width 0.14224)
		(layer "In2.Cu")
		(net "M_G_ECC<4>")
	)
	(segment
		(start 69.490336 -25.797256)
		(end 69.490336 -26.633424)
		(width 0.14224)
		(layer "In2.Cu")
		(net "M_G_ECC<4>")
	)
	(segment
		(start 68.677536 -25.390856)
		(end 68.880736 -25.594056)
		(width 0.14224)
		(layer "In2.Cu")
		(net "M_G_ECC<4>")
	)
	(segment
		(start 69.953124 -31.138622)
		(end 70.095364 -31.280862)
		(width 0.14224)
		(layer "In2.Cu")
		(net "M_G_ECC<4>")
	)
	(segment
		(start 69.490336 -24.578056)
		(end 69.261736 -24.806656)
		(width 0.14224)
		(layer "In2.Cu")
		(net "M_G_ECC<4>")
	)
	(segment
		(start 68.880736 -25.594056)
		(end 69.287136 -25.594056)
		(width 0.14224)
		(layer "In2.Cu")
		(net "M_G_ECC<4>")
	)
	(segment
		(start 68.563744 -22.530054)
		(end 68.563744 -23.324566)
		(width 0.14224)
		(layer "In2.Cu")
		(net "M_G_ECC<4>")
	)
	(segment
		(start 69.490336 -26.633424)
		(end 69.053964 -27.069796)
		(width 0.14224)
		(layer "In2.Cu")
		(net "M_G_ECC<4>")
	)
	(segment
		(start 79.543402 -56.780938)
		(end 79.537052 -56.791606)
		(width 0.0889)
		(layer "In2.Cu")
		(net "M_G_ECC<4>")
	)
	(segment
		(start 79.543402 -55.790338)
		(end 79.537052 -55.801006)
		(width 0.0889)
		(layer "In2.Cu")
		(net "M_G_ECC<4>")
	)
	(segment
		(start 68.704968 -30.996382)
		(end 68.847208 -31.138622)
		(width 0.14224)
		(layer "In2.Cu")
		(net "M_G_ECC<4>")
	)
	(segment
		(start 79.537052 -58.35142)
		(end 79.543402 -58.362088)
		(width 0.0889)
		(layer "In2.Cu")
		(net "M_G_ECC<4>")
	)
	(segment
		(start 69.490336 -24.251158)
		(end 69.490336 -24.578056)
		(width 0.14224)
		(layer "In2.Cu")
		(net "M_G_ECC<4>")
	)
	(segment
		(start 79.548228 -53.800502)
		(end 79.543402 -53.809138)
		(width 0.0889)
		(layer "In2.Cu")
		(net "M_G_ECC<4>")
	)
	(segment
		(start 69.053964 -27.069796)
		(end 69.053964 -28.136596)
		(width 0.14224)
		(layer "In2.Cu")
		(net "M_G_ECC<4>")
	)
	(segment
		(start 69.274944 -21.818854)
		(end 68.563744 -22.530054)
		(width 0.14224)
		(layer "In2.Cu")
		(net "M_G_ECC<4>")
	)
	(segment
		(start 69.053964 -28.136596)
		(end 69.337936 -28.420568)
		(width 0.14224)
		(layer "In2.Cu")
		(net "M_G_ECC<4>")
	)
	(segment
		(start 79.548228 -56.772302)
		(end 79.543402 -56.780938)
		(width 0.0889)
		(layer "In2.Cu")
		(net "M_G_ECC<4>")
	)
	(segment
		(start 79.395066 -53.151786)
		(end 79.543402 -53.409088)
		(width 0.0889)
		(layer "In2.Cu")
		(net "M_G_ECC<4>")
	)
	(segment
		(start 69.337936 -29.360622)
		(end 70.019672 -30.042358)
		(width 0.14224)
		(layer "In2.Cu")
		(net "M_G_ECC<4>")
	)
	(segment
		(start 69.261736 -24.806656)
		(end 68.855336 -24.806656)
		(width 0.14224)
		(layer "In2.Cu")
		(net "M_G_ECC<4>")
	)
	(arc
		(start 79.543402 -58.362088)
		(mid 79.596901 -58.561986)
		(end 79.543402 -58.761884)
		(width 0.0889)
		(layer "In2.Cu")
		(net "M_G_ECC<4>")
	)
	(arc
		(start 79.543402 -57.371488)
		(mid 79.596872 -57.566551)
		(end 79.548228 -57.762902)
		(width 0.0889)
		(layer "In2.Cu")
		(net "M_G_ECC<4>")
	)
	(arc
		(start 80.066388 -59.647836)
		(mid 80.260238 -59.704186)
		(end 80.401922 -59.847988)
		(width 0.0889)
		(layer "In2.Cu")
		(net "M_G_ECC<4>")
	)
	(arc
		(start 80.928718 -60.14339)
		(mid 81.12036 -60.200556)
		(end 81.260442 -60.343288)
		(width 0.0889)
		(layer "In2.Cu")
		(net "M_G_ECC<4>")
	)
	(arc
		(start 79.543402 -58.761884)
		(mid 79.538148 -59.343392)
		(end 80.033622 -59.647836)
		(width 0.0889)
		(layer "In2.Cu")
		(net "M_G_ECC<4>")
	)
	(arc
		(start 79.543402 -55.390288)
		(mid 79.596872 -55.585351)
		(end 79.548228 -55.781702)
		(width 0.0889)
		(layer "In2.Cu")
		(net "M_G_ECC<4>")
	)
	(arc
		(start 79.543402 -56.380888)
		(mid 79.596872 -56.575951)
		(end 79.548228 -56.772302)
		(width 0.0889)
		(layer "In2.Cu")
		(net "M_G_ECC<4>")
	)
	(arc
		(start 80.401922 -59.847988)
		(mid 80.61053 -60.05992)
		(end 80.895952 -60.14339)
		(width 0.0889)
		(layer "In2.Cu")
		(net "M_G_ECC<4>")
	)
	(arc
		(start 81.260442 -60.343288)
		(mid 81.290103 -60.389599)
		(end 81.323942 -60.43295)
		(width 0.0889)
		(layer "In2.Cu")
		(net "M_G_ECC<4>")
	)
	(arc
		(start 79.543402 -53.409088)
		(mid 79.596872 -53.604151)
		(end 79.548228 -53.800502)
		(width 0.0889)
		(layer "In2.Cu")
		(net "M_G_ECC<4>")
	)
	(arc
		(start 79.537052 -53.819806)
		(mid 79.464254 -54.110569)
		(end 79.543402 -54.399688)
		(width 0.0889)
		(layer "In2.Cu")
		(net "M_G_ECC<4>")
	)
	(arc
		(start 79.543402 -57.771538)
		(mid 79.46418 -58.060656)
		(end 79.537052 -58.35142)
		(width 0.0889)
		(layer "In2.Cu")
		(net "M_G_ECC<4>")
	)
	(arc
		(start 79.537052 -56.791606)
		(mid 79.464254 -57.082369)
		(end 79.543402 -57.371488)
		(width 0.0889)
		(layer "In2.Cu")
		(net "M_G_ECC<4>")
	)
	(arc
		(start 79.537052 -54.810406)
		(mid 79.464254 -55.101169)
		(end 79.543402 -55.390288)
		(width 0.0889)
		(layer "In2.Cu")
		(net "M_G_ECC<4>")
	)
	(arc
		(start 79.543402 -54.399688)
		(mid 79.596872 -54.594751)
		(end 79.548228 -54.791102)
		(width 0.0889)
		(layer "In2.Cu")
		(net "M_G_ECC<4>")
	)
	(arc
		(start 79.537052 -55.801006)
		(mid 79.464254 -56.091769)
		(end 79.543402 -56.380888)
		(width 0.0889)
		(layer "In2.Cu")
		(net "M_G_ECC<4>")
	)
	(segment
		(start 76.449428 -15.423642)
		(end 76.449428 -16.687546)
		(width 0.1651)
		(layer "F.Cu")
		(net "M_G_ECC<3>")
	)
	(segment
		(start 85.777832 -62.029086)
		(end 85.206332 -62.029086)
		(width 0.1016)
		(layer "F.Cu")
		(net "M_G_ECC<3>")
	)
	(via
		(at 85.206332 -62.029086)
		(size 0.508)
		(drill 0.254)
		(layers "F.Cu" "B.Cu")
		(net "M_G_ECC<3>")
	)
	(via
		(at 76.449428 -16.687546)
		(size 0.508)
		(drill 0.254)
		(layers "F.Cu" "B.Cu")
		(net "M_G_ECC<3>")
	)
	(via
		(at 77.299312 -22.279356)
		(size 0.508)
		(drill 0.254)
		(layers "F.Cu" "B.Cu")
		(net "M_G_ECC<3>")
	)
	(segment
		(start 77.299566 -20.224242)
		(end 77.299566 -20.973542)
		(width 0.1651)
		(layer "B.Cu")
		(net "M_G_ECC<3>")
	)
	(segment
		(start 77.299566 -20.973542)
		(end 77.299312 -20.973796)
		(width 0.1651)
		(layer "B.Cu")
		(net "M_G_ECC<3>")
	)
	(segment
		(start 77.299312 -20.973796)
		(end 77.299312 -22.279356)
		(width 0.1651)
		(layer "B.Cu")
		(net "M_G_ECC<3>")
	)
	(segment
		(start 77.872336 -27.57678)
		(end 78.075536 -27.77998)
		(width 0.14224)
		(layer "In2.Cu")
		(net "M_G_ECC<3>")
	)
	(segment
		(start 76.766166 -17.3228)
		(end 77.096366 -17.653)
		(width 0.14224)
		(layer "In2.Cu")
		(net "M_G_ECC<3>")
	)
	(segment
		(start 79.957168 -40.961056)
		(end 79.957168 -42.722546)
		(width 0.14224)
		(layer "In2.Cu")
		(net "M_G_ECC<3>")
	)
	(segment
		(start 84.001102 -55.790338)
		(end 84.007452 -55.801006)
		(width 0.0889)
		(layer "In2.Cu")
		(net "M_G_ECC<3>")
	)
	(segment
		(start 77.872336 -27.17038)
		(end 77.872336 -27.57678)
		(width 0.14224)
		(layer "In2.Cu")
		(net "M_G_ECC<3>")
	)
	(segment
		(start 77.096366 -17.653)
		(end 77.350366 -17.653)
		(width 0.14224)
		(layer "In2.Cu")
		(net "M_G_ECC<3>")
	)
	(segment
		(start 84.274406 -45.871638)
		(end 84.274406 -49.323244)
		(width 0.14224)
		(layer "In2.Cu")
		(net "M_G_ECC<3>")
	)
	(segment
		(start 84.336636 -56.98109)
		(end 84.369402 -56.98109)
		(width 0.0889)
		(layer "In2.Cu")
		(net "M_G_ECC<3>")
	)
	(segment
		(start 85.206332 -62.43828)
		(end 85.206332 -62.029086)
		(width 0.0889)
		(layer "In2.Cu")
		(net "M_G_ECC<3>")
	)
	(segment
		(start 85.713316 -60.734702)
		(end 85.718142 -60.743338)
		(width 0.0889)
		(layer "In2.Cu")
		(net "M_G_ECC<3>")
	)
	(segment
		(start 76.766166 -17.004284)
		(end 76.766166 -17.3228)
		(width 0.14224)
		(layer "In2.Cu")
		(net "M_G_ECC<3>")
	)
	(segment
		(start 84.146644 -50.366422)
		(end 84.654644 -50.874422)
		(width 0.0889)
		(layer "In2.Cu")
		(net "M_G_ECC<3>")
	)
	(segment
		(start 77.791564 -22.771608)
		(end 77.791564 -23.183596)
		(width 0.14224)
		(layer "In2.Cu")
		(net "M_G_ECC<3>")
	)
	(segment
		(start 82.547968 -44.1452)
		(end 84.274406 -45.871638)
		(width 0.14224)
		(layer "In2.Cu")
		(net "M_G_ECC<3>")
	)
	(segment
		(start 78.583536 -28.025344)
		(end 78.583536 -39.587424)
		(width 0.14224)
		(layer "In2.Cu")
		(net "M_G_ECC<3>")
	)
	(segment
		(start 84.654644 -51.395376)
		(end 84.423504 -51.626516)
		(width 0.0889)
		(layer "In2.Cu")
		(net "M_G_ECC<3>")
	)
	(segment
		(start 77.807566 -18.1102)
		(end 77.807566 -18.380456)
		(width 0.14224)
		(layer "In2.Cu")
		(net "M_G_ECC<3>")
	)
	(segment
		(start 77.161136 -24.661368)
		(end 78.179168 -25.6794)
		(width 0.14224)
		(layer "In2.Cu")
		(net "M_G_ECC<3>")
	)
	(segment
		(start 84.654644 -50.874422)
		(end 84.654644 -51.395376)
		(width 0.0889)
		(layer "In2.Cu")
		(net "M_G_ECC<3>")
	)
	(segment
		(start 78.583536 -39.587424)
		(end 79.957168 -40.961056)
		(width 0.14224)
		(layer "In2.Cu")
		(net "M_G_ECC<3>")
	)
	(segment
		(start 77.652118 -21.92655)
		(end 77.299312 -22.279356)
		(width 0.14224)
		(layer "In2.Cu")
		(net "M_G_ECC<3>")
	)
	(segment
		(start 78.338172 -27.77998)
		(end 78.583536 -28.025344)
		(width 0.14224)
		(layer "In2.Cu")
		(net "M_G_ECC<3>")
	)
	(segment
		(start 78.075536 -27.77998)
		(end 78.338172 -27.77998)
		(width 0.14224)
		(layer "In2.Cu")
		(net "M_G_ECC<3>")
	)
	(segment
		(start 77.161136 -23.814024)
		(end 77.161136 -24.661368)
		(width 0.14224)
		(layer "In2.Cu")
		(net "M_G_ECC<3>")
	)
	(segment
		(start 81.379822 -44.1452)
		(end 82.547968 -44.1452)
		(width 0.14224)
		(layer "In2.Cu")
		(net "M_G_ECC<3>")
	)
	(segment
		(start 85.718142 -60.743338)
		(end 85.724492 -60.754006)
		(width 0.0889)
		(layer "In2.Cu")
		(net "M_G_ECC<3>")
	)
	(segment
		(start 78.179168 -26.863548)
		(end 77.872336 -27.17038)
		(width 0.14224)
		(layer "In2.Cu")
		(net "M_G_ECC<3>")
	)
	(segment
		(start 84.423504 -51.626516)
		(end 84.423504 -54.657244)
		(width 0.0889)
		(layer "In2.Cu")
		(net "M_G_ECC<3>")
	)
	(segment
		(start 77.299312 -22.279356)
		(end 77.791564 -22.771608)
		(width 0.14224)
		(layer "In2.Cu")
		(net "M_G_ECC<3>")
	)
	(segment
		(start 84.146644 -49.451006)
		(end 84.146644 -50.366422)
		(width 0.0889)
		(layer "In2.Cu")
		(net "M_G_ECC<3>")
	)
	(segment
		(start 77.807566 -18.380456)
		(end 77.652118 -18.535904)
		(width 0.14224)
		(layer "In2.Cu")
		(net "M_G_ECC<3>")
	)
	(segment
		(start 85.191346 -57.476136)
		(end 85.219286 -57.476136)
		(width 0.0889)
		(layer "In2.Cu")
		(net "M_G_ECC<3>")
	)
	(segment
		(start 85.590888 -61.487304)
		(end 85.590888 -61.670692)
		(width 0.0889)
		(layer "In2.Cu")
		(net "M_G_ECC<3>")
	)
	(segment
		(start 84.423504 -54.657244)
		(end 84.001102 -55.390542)
		(width 0.0889)
		(layer "In2.Cu")
		(net "M_G_ECC<3>")
	)
	(segment
		(start 84.274406 -49.323244)
		(end 84.146644 -49.451006)
		(width 0.0889)
		(layer "In2.Cu")
		(net "M_G_ECC<3>")
	)
	(segment
		(start 79.957168 -42.722546)
		(end 81.379822 -44.1452)
		(width 0.14224)
		(layer "In2.Cu")
		(net "M_G_ECC<3>")
	)
	(segment
		(start 85.831172 -62.159896)
		(end 85.453728 -62.53734)
		(width 0.0889)
		(layer "In2.Cu")
		(net "M_G_ECC<3>")
	)
	(segment
		(start 85.453728 -62.53734)
		(end 85.305392 -62.53734)
		(width 0.0889)
		(layer "In2.Cu")
		(net "M_G_ECC<3>")
	)
	(segment
		(start 85.713316 -59.744102)
		(end 85.718142 -59.752738)
		(width 0.0889)
		(layer "In2.Cu")
		(net "M_G_ECC<3>")
	)
	(segment
		(start 76.449428 -16.687546)
		(end 76.766166 -17.004284)
		(width 0.14224)
		(layer "In2.Cu")
		(net "M_G_ECC<3>")
	)
	(segment
		(start 77.652118 -18.535904)
		(end 77.652118 -21.92655)
		(width 0.14224)
		(layer "In2.Cu")
		(net "M_G_ECC<3>")
	)
	(segment
		(start 77.350366 -17.653)
		(end 77.807566 -18.1102)
		(width 0.14224)
		(layer "In2.Cu")
		(net "M_G_ECC<3>")
	)
	(segment
		(start 85.590888 -61.670692)
		(end 85.831172 -61.910976)
		(width 0.0889)
		(layer "In2.Cu")
		(net "M_G_ECC<3>")
	)
	(segment
		(start 85.718142 -59.752738)
		(end 85.724492 -59.763406)
		(width 0.0889)
		(layer "In2.Cu")
		(net "M_G_ECC<3>")
	)
	(segment
		(start 78.179168 -25.6794)
		(end 78.179168 -26.863548)
		(width 0.14224)
		(layer "In2.Cu")
		(net "M_G_ECC<3>")
	)
	(segment
		(start 85.305392 -62.53734)
		(end 85.206332 -62.43828)
		(width 0.0889)
		(layer "In2.Cu")
		(net "M_G_ECC<3>")
	)
	(segment
		(start 85.831172 -61.910976)
		(end 85.831172 -62.159896)
		(width 0.0889)
		(layer "In2.Cu")
		(net "M_G_ECC<3>")
	)
	(segment
		(start 85.724492 -58.35142)
		(end 85.718142 -58.362088)
		(width 0.0889)
		(layer "In2.Cu")
		(net "M_G_ECC<3>")
	)
	(segment
		(start 77.791564 -23.183596)
		(end 77.161136 -23.814024)
		(width 0.14224)
		(layer "In2.Cu")
		(net "M_G_ECC<3>")
	)
	(arc
		(start 84.001102 -56.380888)
		(mid 83.998354 -56.776355)
		(end 84.336636 -56.98109)
		(width 0.0889)
		(layer "In2.Cu")
		(net "M_G_ECC<3>")
	)
	(arc
		(start 85.718142 -60.343288)
		(mid 85.664672 -60.538351)
		(end 85.713316 -60.734702)
		(width 0.0889)
		(layer "In2.Cu")
		(net "M_G_ECC<3>")
	)
	(arc
		(start 85.718142 -58.362088)
		(mid 85.664643 -58.561986)
		(end 85.718142 -58.761884)
		(width 0.0889)
		(layer "In2.Cu")
		(net "M_G_ECC<3>")
	)
	(arc
		(start 85.219286 -57.476136)
		(mid 85.718167 -57.771573)
		(end 85.724492 -58.35142)
		(width 0.0889)
		(layer "In2.Cu")
		(net "M_G_ECC<3>")
	)
	(arc
		(start 84.859622 -57.276238)
		(mid 84.999701 -57.418974)
		(end 85.191346 -57.476136)
		(width 0.0889)
		(layer "In2.Cu")
		(net "M_G_ECC<3>")
	)
	(arc
		(start 85.724492 -59.763406)
		(mid 85.79729 -60.054169)
		(end 85.718142 -60.343288)
		(width 0.0889)
		(layer "In2.Cu")
		(net "M_G_ECC<3>")
	)
	(arc
		(start 85.718142 -58.761884)
		(mid 85.797273 -59.057286)
		(end 85.718142 -59.352688)
		(width 0.0889)
		(layer "In2.Cu")
		(net "M_G_ECC<3>")
	)
	(arc
		(start 85.724492 -60.754006)
		(mid 85.787884 -61.144391)
		(end 85.590888 -61.487304)
		(width 0.0889)
		(layer "In2.Cu")
		(net "M_G_ECC<3>")
	)
	(arc
		(start 85.718142 -59.352688)
		(mid 85.664672 -59.547751)
		(end 85.713316 -59.744102)
		(width 0.0889)
		(layer "In2.Cu")
		(net "M_G_ECC<3>")
	)
	(arc
		(start 84.001102 -55.390542)
		(mid 83.947603 -55.59044)
		(end 84.001102 -55.790338)
		(width 0.0889)
		(layer "In2.Cu")
		(net "M_G_ECC<3>")
	)
	(arc
		(start 84.007452 -55.801006)
		(mid 84.08025 -56.091769)
		(end 84.001102 -56.380888)
		(width 0.0889)
		(layer "In2.Cu")
		(net "M_G_ECC<3>")
	)
	(arc
		(start 84.369402 -56.98109)
		(mid 84.652619 -57.065371)
		(end 84.859622 -57.276238)
		(width 0.0889)
		(layer "In2.Cu")
		(net "M_G_ECC<3>")
	)
	(segment
		(start 77.299312 -19.026632)
		(end 77.430884 -18.89506)
		(width 0.1651)
		(layer "F.Cu")
		(net "M_G_ECC<2>")
	)
	(segment
		(start 77.299566 -20.023582)
		(end 77.299312 -20.023328)
		(width 0.1651)
		(layer "F.Cu")
		(net "M_G_ECC<2>")
	)
	(segment
		(start 77.299312 -20.023328)
		(end 77.299312 -19.026632)
		(width 0.1651)
		(layer "F.Cu")
		(net "M_G_ECC<2>")
	)
	(segment
		(start 77.299312 -18.539968)
		(end 77.299312 -18.2626)
		(width 0.1651)
		(layer "F.Cu")
		(net "M_G_ECC<2>")
	)
	(segment
		(start 85.777832 -61.038486)
		(end 85.206332 -61.038486)
		(width 0.1016)
		(layer "F.Cu")
		(net "M_G_ECC<2>")
	)
	(segment
		(start 77.430884 -18.89506)
		(end 77.430884 -18.67154)
		(width 0.1651)
		(layer "F.Cu")
		(net "M_G_ECC<2>")
	)
	(segment
		(start 77.430884 -18.67154)
		(end 77.299312 -18.539968)
		(width 0.1651)
		(layer "F.Cu")
		(net "M_G_ECC<2>")
	)
	(via
		(at 77.299312 -18.2626)
		(size 0.508)
		(drill 0.254)
		(layers "F.Cu" "B.Cu")
		(net "M_G_ECC<2>")
	)
	(via
		(at 76.449428 -23.560278)
		(size 0.508)
		(drill 0.254)
		(layers "F.Cu" "B.Cu")
		(net "M_G_ECC<2>")
	)
	(via
		(at 85.206332 -61.038486)
		(size 0.508)
		(drill 0.254)
		(layers "F.Cu" "B.Cu")
		(net "M_G_ECC<2>")
	)
	(segment
		(start 76.449428 -23.560278)
		(end 76.449428 -24.824182)
		(width 0.1651)
		(layer "B.Cu")
		(net "M_G_ECC<2>")
	)
	(segment
		(start 76.629768 -25.654)
		(end 77.036422 -25.654)
		(width 0.14224)
		(layer "In2.Cu")
		(net "M_G_ECC<2>")
	)
	(segment
		(start 77.036422 -25.654)
		(end 77.213968 -25.831546)
		(width 0.14224)
		(layer "In2.Cu")
		(net "M_G_ECC<2>")
	)
	(segment
		(start 84.233004 -54.606698)
		(end 83.836002 -55.295292)
		(width 0.0889)
		(layer "In2.Cu")
		(net "M_G_ECC<2>")
	)
	(segment
		(start 76.578968 -29.710888)
		(end 76.578968 -30.28696)
		(width 0.14224)
		(layer "In2.Cu")
		(net "M_G_ECC<2>")
	)
	(segment
		(start 76.893166 -18.668746)
		(end 76.893166 -21.921724)
		(width 0.14224)
		(layer "In2.Cu")
		(net "M_G_ECC<2>")
	)
	(segment
		(start 78.951582 -42.394378)
		(end 81.181194 -44.62399)
		(width 0.14224)
		(layer "In2.Cu")
		(net "M_G_ECC<2>")
	)
	(segment
		(start 78.951582 -42.19321)
		(end 78.951582 -42.394378)
		(width 0.14224)
		(layer "In2.Cu")
		(net "M_G_ECC<2>")
	)
	(segment
		(start 79.368396 -41.776396)
		(end 78.951582 -42.19321)
		(width 0.14224)
		(layer "In2.Cu")
		(net "M_G_ECC<2>")
	)
	(segment
		(start 77.948536 -30.6324)
		(end 77.948536 -41.391332)
		(width 0.14224)
		(layer "In2.Cu")
		(net "M_G_ECC<2>")
	)
	(segment
		(start 78.908402 -41.316402)
		(end 79.10957 -41.316402)
		(width 0.14224)
		(layer "In2.Cu")
		(net "M_G_ECC<2>")
	)
	(segment
		(start 85.496908 -60.380372)
		(end 85.206332 -61.038486)
		(width 0.0889)
		(layer "In2.Cu")
		(net "M_G_ECC<2>")
	)
	(segment
		(start 85.553042 -58.857388)
		(end 85.557868 -58.866024)
		(width 0.0889)
		(layer "In2.Cu")
		(net "M_G_ECC<2>")
	)
	(segment
		(start 77.745336 -30.4292)
		(end 77.948536 -30.6324)
		(width 0.14224)
		(layer "In2.Cu")
		(net "M_G_ECC<2>")
	)
	(segment
		(start 76.578968 -30.28696)
		(end 76.721208 -30.4292)
		(width 0.14224)
		(layer "In2.Cu")
		(net "M_G_ECC<2>")
	)
	(segment
		(start 76.132944 -22.681946)
		(end 76.132944 -23.243794)
		(width 0.14224)
		(layer "In2.Cu")
		(net "M_G_ECC<2>")
	)
	(segment
		(start 76.449428 -25.47366)
		(end 76.629768 -25.654)
		(width 0.14224)
		(layer "In2.Cu")
		(net "M_G_ECC<2>")
	)
	(segment
		(start 77.213968 -25.831546)
		(end 77.213968 -26.035)
		(width 0.14224)
		(layer "In2.Cu")
		(net "M_G_ECC<2>")
	)
	(segment
		(start 84.464652 -50.95621)
		(end 84.464652 -51.315874)
		(width 0.0889)
		(layer "In2.Cu")
		(net "M_G_ECC<2>")
	)
	(segment
		(start 78.29042 -41.733216)
		(end 78.491588 -41.733216)
		(width 0.14224)
		(layer "In2.Cu")
		(net "M_G_ECC<2>")
	)
	(segment
		(start 85.193378 -57.66689)
		(end 85.217508 -57.66689)
		(width 0.0889)
		(layer "In2.Cu")
		(net "M_G_ECC<2>")
	)
	(segment
		(start 83.836002 -55.885588)
		(end 83.840828 -55.894224)
		(width 0.0889)
		(layer "In2.Cu")
		(net "M_G_ECC<2>")
	)
	(segment
		(start 76.721208 -30.4292)
		(end 77.745336 -30.4292)
		(width 0.14224)
		(layer "In2.Cu")
		(net "M_G_ECC<2>")
	)
	(segment
		(start 77.299312 -18.2626)
		(end 76.893166 -18.668746)
		(width 0.14224)
		(layer "In2.Cu")
		(net "M_G_ECC<2>")
	)
	(segment
		(start 76.721208 -29.568648)
		(end 76.578968 -29.710888)
		(width 0.14224)
		(layer "In2.Cu")
		(net "M_G_ECC<2>")
	)
	(segment
		(start 79.10957 -41.316402)
		(end 79.368396 -41.575228)
		(width 0.14224)
		(layer "In2.Cu")
		(net "M_G_ECC<2>")
	)
	(segment
		(start 76.934568 -28.321)
		(end 77.253592 -28.640024)
		(width 0.14224)
		(layer "In2.Cu")
		(net "M_G_ECC<2>")
	)
	(segment
		(start 76.449428 -23.560278)
		(end 76.449428 -25.47366)
		(width 0.14224)
		(layer "In2.Cu")
		(net "M_G_ECC<2>")
	)
	(segment
		(start 84.233004 -51.547522)
		(end 84.233004 -54.606698)
		(width 0.0889)
		(layer "In2.Cu")
		(net "M_G_ECC<2>")
	)
	(segment
		(start 83.956652 -49.658016)
		(end 83.956652 -50.44821)
		(width 0.0889)
		(layer "In2.Cu")
		(net "M_G_ECC<2>")
	)
	(segment
		(start 85.546692 -59.83732)
		(end 85.553042 -59.847988)
		(width 0.0889)
		(layer "In2.Cu")
		(net "M_G_ECC<2>")
	)
	(segment
		(start 84.330032 -57.17159)
		(end 84.362798 -57.17159)
		(width 0.0889)
		(layer "In2.Cu")
		(net "M_G_ECC<2>")
	)
	(segment
		(start 77.745336 -29.568648)
		(end 76.721208 -29.568648)
		(width 0.14224)
		(layer "In2.Cu")
		(net "M_G_ECC<2>")
	)
	(segment
		(start 76.132944 -23.243794)
		(end 76.449428 -23.560278)
		(width 0.14224)
		(layer "In2.Cu")
		(net "M_G_ECC<2>")
	)
	(segment
		(start 84.464652 -51.315874)
		(end 84.233004 -51.547522)
		(width 0.0889)
		(layer "In2.Cu")
		(net "M_G_ECC<2>")
	)
	(segment
		(start 76.934568 -27.686)
		(end 76.934568 -28.321)
		(width 0.14224)
		(layer "In2.Cu")
		(net "M_G_ECC<2>")
	)
	(segment
		(start 82.163158 -44.62399)
		(end 83.62188 -46.082712)
		(width 0.14224)
		(layer "In2.Cu")
		(net "M_G_ECC<2>")
	)
	(segment
		(start 81.181194 -44.62399)
		(end 82.163158 -44.62399)
		(width 0.14224)
		(layer "In2.Cu")
		(net "M_G_ECC<2>")
	)
	(segment
		(start 85.553042 -58.266838)
		(end 85.546692 -58.277506)
		(width 0.0889)
		(layer "In2.Cu")
		(net "M_G_ECC<2>")
	)
	(segment
		(start 79.368396 -41.575228)
		(end 79.368396 -41.776396)
		(width 0.14224)
		(layer "In2.Cu")
		(net "M_G_ECC<2>")
	)
	(segment
		(start 77.719936 -28.640024)
		(end 77.948536 -28.868624)
		(width 0.14224)
		(layer "In2.Cu")
		(net "M_G_ECC<2>")
	)
	(segment
		(start 76.893166 -21.921724)
		(end 76.132944 -22.681946)
		(width 0.14224)
		(layer "In2.Cu")
		(net "M_G_ECC<2>")
	)
	(segment
		(start 77.213968 -26.035)
		(end 76.775564 -26.473404)
		(width 0.14224)
		(layer "In2.Cu")
		(net "M_G_ECC<2>")
	)
	(segment
		(start 77.948536 -41.391332)
		(end 78.29042 -41.733216)
		(width 0.14224)
		(layer "In2.Cu")
		(net "M_G_ECC<2>")
	)
	(segment
		(start 77.253592 -28.640024)
		(end 77.719936 -28.640024)
		(width 0.14224)
		(layer "In2.Cu")
		(net "M_G_ECC<2>")
	)
	(segment
		(start 76.775564 -26.473404)
		(end 76.775564 -27.526996)
		(width 0.14224)
		(layer "In2.Cu")
		(net "M_G_ECC<2>")
	)
	(segment
		(start 78.491588 -41.733216)
		(end 78.908402 -41.316402)
		(width 0.14224)
		(layer "In2.Cu")
		(net "M_G_ECC<2>")
	)
	(segment
		(start 83.62188 -46.082712)
		(end 83.62188 -49.323244)
		(width 0.14224)
		(layer "In2.Cu")
		(net "M_G_ECC<2>")
	)
	(segment
		(start 83.62188 -49.323244)
		(end 83.956652 -49.658016)
		(width 0.0889)
		(layer "In2.Cu")
		(net "M_G_ECC<2>")
	)
	(segment
		(start 85.553042 -59.847988)
		(end 85.557868 -59.856624)
		(width 0.0889)
		(layer "In2.Cu")
		(net "M_G_ECC<2>")
	)
	(segment
		(start 76.775564 -27.526996)
		(end 76.934568 -27.686)
		(width 0.14224)
		(layer "In2.Cu")
		(net "M_G_ECC<2>")
	)
	(segment
		(start 83.956652 -50.44821)
		(end 84.464652 -50.95621)
		(width 0.0889)
		(layer "In2.Cu")
		(net "M_G_ECC<2>")
	)
	(segment
		(start 77.948536 -28.868624)
		(end 77.948536 -29.365448)
		(width 0.14224)
		(layer "In2.Cu")
		(net "M_G_ECC<2>")
	)
	(segment
		(start 77.948536 -29.365448)
		(end 77.745336 -29.568648)
		(width 0.14224)
		(layer "In2.Cu")
		(net "M_G_ECC<2>")
	)
	(arc
		(start 85.553042 -60.248038)
		(mid 85.520951 -60.312497)
		(end 85.496908 -60.380372)
		(width 0.0889)
		(layer "In2.Cu")
		(net "M_G_ECC<2>")
	)
	(arc
		(start 84.694522 -57.371488)
		(mid 84.905235 -57.584567)
		(end 85.193378 -57.66689)
		(width 0.0889)
		(layer "In2.Cu")
		(net "M_G_ECC<2>")
	)
	(arc
		(start 85.557868 -58.866024)
		(mid 85.606623 -59.062376)
		(end 85.553042 -59.257438)
		(width 0.0889)
		(layer "In2.Cu")
		(net "M_G_ECC<2>")
	)
	(arc
		(start 85.217508 -57.66689)
		(mid 85.555623 -57.871592)
		(end 85.553042 -58.266838)
		(width 0.0889)
		(layer "In2.Cu")
		(net "M_G_ECC<2>")
	)
	(arc
		(start 85.557868 -59.856624)
		(mid 85.606623 -60.052976)
		(end 85.553042 -60.248038)
		(width 0.0889)
		(layer "In2.Cu")
		(net "M_G_ECC<2>")
	)
	(arc
		(start 83.840828 -55.894224)
		(mid 83.889583 -56.090576)
		(end 83.836002 -56.285638)
		(width 0.0889)
		(layer "In2.Cu")
		(net "M_G_ECC<2>")
	)
	(arc
		(start 83.836002 -55.295292)
		(mid 83.756997 -55.59044)
		(end 83.836002 -55.885588)
		(width 0.0889)
		(layer "In2.Cu")
		(net "M_G_ECC<2>")
	)
	(arc
		(start 83.836002 -56.285638)
		(mid 83.831673 -56.86881)
		(end 84.330032 -57.17159)
		(width 0.0889)
		(layer "In2.Cu")
		(net "M_G_ECC<2>")
	)
	(arc
		(start 84.362798 -57.17159)
		(mid 84.55444 -57.228756)
		(end 84.694522 -57.371488)
		(width 0.0889)
		(layer "In2.Cu")
		(net "M_G_ECC<2>")
	)
	(arc
		(start 85.553042 -59.257438)
		(mid 85.47382 -59.546556)
		(end 85.546692 -59.83732)
		(width 0.0889)
		(layer "In2.Cu")
		(net "M_G_ECC<2>")
	)
	(arc
		(start 85.546692 -58.277506)
		(mid 85.473894 -58.568269)
		(end 85.553042 -58.857388)
		(width 0.0889)
		(layer "In2.Cu")
		(net "M_G_ECC<2>")
	)
	(segment
		(start 70.499478 -15.423642)
		(end 70.499478 -16.687546)
		(width 0.1651)
		(layer "F.Cu")
		(net "M_G_ECC<1>")
	)
	(segment
		(start 83.202272 -62.52464)
		(end 82.630772 -62.52464)
		(width 0.1016)
		(layer "F.Cu")
		(net "M_G_ECC<1>")
	)
	(via
		(at 82.630772 -62.52464)
		(size 0.508)
		(drill 0.254)
		(layers "F.Cu" "B.Cu")
		(net "M_G_ECC<1>")
	)
	(via
		(at 70.499478 -16.687546)
		(size 0.508)
		(drill 0.254)
		(layers "F.Cu" "B.Cu")
		(net "M_G_ECC<1>")
	)
	(via
		(at 71.171562 -22.279356)
		(size 0.508)
		(drill 0.254)
		(layers "F.Cu" "B.Cu")
		(net "M_G_ECC<1>")
	)
	(segment
		(start 71.171562 -21.776182)
		(end 71.171562 -22.279356)
		(width 0.1651)
		(layer "B.Cu")
		(net "M_G_ECC<1>")
	)
	(segment
		(start 71.349362 -21.598382)
		(end 71.171562 -21.776182)
		(width 0.1651)
		(layer "B.Cu")
		(net "M_G_ECC<1>")
	)
	(segment
		(start 71.349362 -20.224242)
		(end 71.349362 -21.598382)
		(width 0.1651)
		(layer "B.Cu")
		(net "M_G_ECC<1>")
	)
	(segment
		(start 80.793844 -51.648614)
		(end 80.793844 -52.698396)
		(width 0.0889)
		(layer "In2.Cu")
		(net "M_G_ECC<1>")
	)
	(segment
		(start 81.757266 -59.457336)
		(end 81.790032 -59.457336)
		(width 0.0889)
		(layer "In2.Cu")
		(net "M_G_ECC<1>")
	)
	(segment
		(start 80.793844 -52.698396)
		(end 80.676242 -52.815998)
		(width 0.0889)
		(layer "In2.Cu")
		(net "M_G_ECC<1>")
	)
	(segment
		(start 70.499478 -17.226534)
		(end 70.976744 -17.7038)
		(width 0.14224)
		(layer "In2.Cu")
		(net "M_G_ECC<1>")
	)
	(segment
		(start 78.975204 -49.512982)
		(end 78.975204 -49.829974)
		(width 0.0889)
		(layer "In2.Cu")
		(net "M_G_ECC<1>")
	)
	(segment
		(start 70.654164 -22.796754)
		(end 70.654164 -23.081996)
		(width 0.14224)
		(layer "In2.Cu")
		(net "M_G_ECC<1>")
	)
	(segment
		(start 80.676242 -55.215282)
		(end 80.567022 -55.390542)
		(width 0.0889)
		(layer "In2.Cu")
		(net "M_G_ECC<1>")
	)
	(segment
		(start 72.208136 -40.31234)
		(end 79.214472 -47.318676)
		(width 0.14224)
		(layer "In2.Cu")
		(net "M_G_ECC<1>")
	)
	(segment
		(start 70.976744 -17.7038)
		(end 71.332344 -17.7038)
		(width 0.14224)
		(layer "In2.Cu")
		(net "M_G_ECC<1>")
	)
	(segment
		(start 80.902556 -58.962036)
		(end 80.926686 -58.962036)
		(width 0.0889)
		(layer "In2.Cu")
		(net "M_G_ECC<1>")
	)
	(segment
		(start 82.630772 -62.982094)
		(end 82.630772 -62.52464)
		(width 0.0889)
		(layer "In2.Cu")
		(net "M_G_ECC<1>")
	)
	(segment
		(start 82.381852 -61.891164)
		(end 82.381852 -62.103254)
		(width 0.0889)
		(layer "In2.Cu")
		(net "M_G_ECC<1>")
	)
	(segment
		(start 80.676242 -52.815998)
		(end 80.676242 -55.215282)
		(width 0.0889)
		(layer "In2.Cu")
		(net "M_G_ECC<1>")
	)
	(segment
		(start 71.545704 -21.905214)
		(end 71.171562 -22.279356)
		(width 0.14224)
		(layer "In2.Cu")
		(net "M_G_ECC<1>")
	)
	(segment
		(start 82.230722 -62.254384)
		(end 82.230722 -63.057024)
		(width 0.0889)
		(layer "In2.Cu")
		(net "M_G_ECC<1>")
	)
	(segment
		(start 80.567022 -56.780938)
		(end 80.573372 -56.791606)
		(width 0.0889)
		(layer "In2.Cu")
		(net "M_G_ECC<1>")
	)
	(segment
		(start 80.562196 -57.762902)
		(end 80.567022 -57.771538)
		(width 0.0889)
		(layer "In2.Cu")
		(net "M_G_ECC<1>")
	)
	(segment
		(start 80.573372 -58.35142)
		(end 80.567022 -58.362088)
		(width 0.0889)
		(layer "In2.Cu")
		(net "M_G_ECC<1>")
	)
	(segment
		(start 79.214472 -47.318676)
		(end 79.214472 -49.273714)
		(width 0.14224)
		(layer "In2.Cu")
		(net "M_G_ECC<1>")
	)
	(segment
		(start 71.702168 -18.415)
		(end 71.545704 -18.571464)
		(width 0.14224)
		(layer "In2.Cu")
		(net "M_G_ECC<1>")
	)
	(segment
		(start 82.503772 -63.109094)
		(end 82.630772 -62.982094)
		(width 0.0889)
		(layer "In2.Cu")
		(net "M_G_ECC<1>")
	)
	(segment
		(start 78.975204 -49.829974)
		(end 80.793844 -51.648614)
		(width 0.0889)
		(layer "In2.Cu")
		(net "M_G_ECC<1>")
	)
	(segment
		(start 71.111364 -25.739852)
		(end 71.657464 -26.285952)
		(width 0.14224)
		(layer "In2.Cu")
		(net "M_G_ECC<1>")
	)
	(segment
		(start 82.282792 -63.109094)
		(end 82.503772 -63.109094)
		(width 0.0889)
		(layer "In2.Cu")
		(net "M_G_ECC<1>")
	)
	(segment
		(start 72.208136 -29.461714)
		(end 72.208136 -40.31234)
		(width 0.14224)
		(layer "In2.Cu")
		(net "M_G_ECC<1>")
	)
	(segment
		(start 71.702168 -18.073624)
		(end 71.702168 -18.415)
		(width 0.14224)
		(layer "In2.Cu")
		(net "M_G_ECC<1>")
	)
	(segment
		(start 70.499478 -16.687546)
		(end 70.499478 -17.226534)
		(width 0.14224)
		(layer "In2.Cu")
		(net "M_G_ECC<1>")
	)
	(segment
		(start 71.657464 -26.285952)
		(end 71.657464 -28.911042)
		(width 0.14224)
		(layer "In2.Cu")
		(net "M_G_ECC<1>")
	)
	(segment
		(start 80.562196 -56.772302)
		(end 80.567022 -56.780938)
		(width 0.0889)
		(layer "In2.Cu")
		(net "M_G_ECC<1>")
	)
	(segment
		(start 71.545704 -18.571464)
		(end 71.545704 -21.905214)
		(width 0.14224)
		(layer "In2.Cu")
		(net "M_G_ECC<1>")
	)
	(segment
		(start 70.654164 -23.081996)
		(end 71.111364 -23.539196)
		(width 0.14224)
		(layer "In2.Cu")
		(net "M_G_ECC<1>")
	)
	(segment
		(start 71.332344 -17.7038)
		(end 71.702168 -18.073624)
		(width 0.14224)
		(layer "In2.Cu")
		(net "M_G_ECC<1>")
	)
	(segment
		(start 71.171562 -22.279356)
		(end 70.654164 -22.796754)
		(width 0.14224)
		(layer "In2.Cu")
		(net "M_G_ECC<1>")
	)
	(segment
		(start 82.230722 -63.057024)
		(end 82.282792 -63.109094)
		(width 0.0889)
		(layer "In2.Cu")
		(net "M_G_ECC<1>")
	)
	(segment
		(start 82.230722 -61.740034)
		(end 82.381852 -61.891164)
		(width 0.0889)
		(layer "In2.Cu")
		(net "M_G_ECC<1>")
	)
	(segment
		(start 71.111364 -23.539196)
		(end 71.111364 -25.739852)
		(width 0.14224)
		(layer "In2.Cu")
		(net "M_G_ECC<1>")
	)
	(segment
		(start 80.567022 -55.790338)
		(end 80.573372 -55.801006)
		(width 0.0889)
		(layer "In2.Cu")
		(net "M_G_ECC<1>")
	)
	(segment
		(start 71.657464 -28.911042)
		(end 72.208136 -29.461714)
		(width 0.14224)
		(layer "In2.Cu")
		(net "M_G_ECC<1>")
	)
	(segment
		(start 79.214472 -49.273714)
		(end 78.975204 -49.512982)
		(width 0.0889)
		(layer "In2.Cu")
		(net "M_G_ECC<1>")
	)
	(segment
		(start 82.381852 -62.103254)
		(end 82.230722 -62.254384)
		(width 0.0889)
		(layer "In2.Cu")
		(net "M_G_ECC<1>")
	)
	(segment
		(start 82.230722 -61.538866)
		(end 82.230722 -61.740034)
		(width 0.0889)
		(layer "In2.Cu")
		(net "M_G_ECC<1>")
	)
	(arc
		(start 80.567022 -56.380888)
		(mid 80.513552 -56.575951)
		(end 80.562196 -56.772302)
		(width 0.0889)
		(layer "In2.Cu")
		(net "M_G_ECC<1>")
	)
	(arc
		(start 80.567022 -58.362088)
		(mid 80.564439 -58.757335)
		(end 80.902556 -58.962036)
		(width 0.0889)
		(layer "In2.Cu")
		(net "M_G_ECC<1>")
	)
	(arc
		(start 80.567022 -55.390542)
		(mid 80.513523 -55.59044)
		(end 80.567022 -55.790338)
		(width 0.0889)
		(layer "In2.Cu")
		(net "M_G_ECC<1>")
	)
	(arc
		(start 82.948272 -60.786772)
		(mid 82.739637 -61.008966)
		(end 82.477356 -61.164216)
		(width 0.0889)
		(layer "In2.Cu")
		(net "M_G_ECC<1>")
	)
	(arc
		(start 82.284062 -59.752484)
		(mid 82.494023 -60.004271)
		(end 82.776568 -60.170568)
		(width 0.0889)
		(layer "In2.Cu")
		(net "M_G_ECC<1>")
	)
	(arc
		(start 82.477356 -61.164216)
		(mid 82.296571 -61.313722)
		(end 82.230722 -61.538866)
		(width 0.0889)
		(layer "In2.Cu")
		(net "M_G_ECC<1>")
	)
	(arc
		(start 82.776568 -60.170568)
		(mid 83.016219 -60.435801)
		(end 82.948272 -60.786772)
		(width 0.0889)
		(layer "In2.Cu")
		(net "M_G_ECC<1>")
	)
	(arc
		(start 81.790032 -59.457336)
		(mid 82.075469 -59.540609)
		(end 82.284062 -59.752484)
		(width 0.0889)
		(layer "In2.Cu")
		(net "M_G_ECC<1>")
	)
	(arc
		(start 80.567022 -57.771538)
		(mid 80.646244 -58.060656)
		(end 80.573372 -58.35142)
		(width 0.0889)
		(layer "In2.Cu")
		(net "M_G_ECC<1>")
	)
	(arc
		(start 80.926686 -58.962036)
		(mid 81.214831 -59.044355)
		(end 81.425542 -59.257438)
		(width 0.0889)
		(layer "In2.Cu")
		(net "M_G_ECC<1>")
	)
	(arc
		(start 80.573372 -56.791606)
		(mid 80.64617 -57.082369)
		(end 80.567022 -57.371488)
		(width 0.0889)
		(layer "In2.Cu")
		(net "M_G_ECC<1>")
	)
	(arc
		(start 80.567022 -57.371488)
		(mid 80.513552 -57.566551)
		(end 80.562196 -57.762902)
		(width 0.0889)
		(layer "In2.Cu")
		(net "M_G_ECC<1>")
	)
	(arc
		(start 81.425542 -59.257438)
		(mid 81.565621 -59.400174)
		(end 81.757266 -59.457336)
		(width 0.0889)
		(layer "In2.Cu")
		(net "M_G_ECC<1>")
	)
	(arc
		(start 80.573372 -55.801006)
		(mid 80.64617 -56.091769)
		(end 80.567022 -56.380888)
		(width 0.0889)
		(layer "In2.Cu")
		(net "M_G_ECC<1>")
	)
	(segment
		(start 71.349362 -20.023582)
		(end 71.26859 -19.177)
		(width 0.1651)
		(layer "F.Cu")
		(net "M_G_ECC<0>")
	)
	(segment
		(start 83.202272 -60.54344)
		(end 82.630772 -60.54344)
		(width 0.1016)
		(layer "F.Cu")
		(net "M_G_ECC<0>")
	)
	(segment
		(start 71.26859 -19.177)
		(end 71.171562 -18.161)
		(width 0.1651)
		(layer "F.Cu")
		(net "M_G_ECC<0>")
	)
	(via
		(at 82.630772 -60.54344)
		(size 0.508)
		(drill 0.254)
		(layers "F.Cu" "B.Cu")
		(net "M_G_ECC<0>")
	)
	(via
		(at 71.171562 -18.161)
		(size 0.508)
		(drill 0.254)
		(layers "F.Cu" "B.Cu")
		(net "M_G_ECC<0>")
	)
	(via
		(at 70.499478 -23.560278)
		(size 0.508)
		(drill 0.254)
		(layers "F.Cu" "B.Cu")
		(net "M_G_ECC<0>")
	)
	(segment
		(start 70.499478 -23.560278)
		(end 70.499478 -24.824182)
		(width 0.1651)
		(layer "B.Cu")
		(net "M_G_ECC<0>")
	)
	(segment
		(start 80.603852 -51.727354)
		(end 78.785212 -49.908714)
		(width 0.0889)
		(layer "In2.Cu")
		(net "M_G_ECC<0>")
	)
	(segment
		(start 74.1934 -43.648884)
		(end 74.420984 -43.4213)
		(width 0.14224)
		(layer "In2.Cu")
		(net "M_G_ECC<0>")
	)
	(segment
		(start 78.636368 -49.34331)
		(end 78.636368 -47.417736)
		(width 0.14224)
		(layer "In2.Cu")
		(net "M_G_ECC<0>")
	)
	(segment
		(start 82.22361 -60.343796)
		(end 82.279998 -60.287408)
		(width 0.0889)
		(layer "In2.Cu")
		(net "M_G_ECC<0>")
	)
	(segment
		(start 74.768202 -44.223686)
		(end 74.549254 -44.223686)
		(width 0.14224)
		(layer "In2.Cu")
		(net "M_G_ECC<0>")
	)
	(segment
		(start 73.846182 -42.846498)
		(end 73.618598 -43.074082)
		(width 0.14224)
		(layer "In2.Cu")
		(net "M_G_ECC<0>")
	)
	(segment
		(start 73.27138 -42.271696)
		(end 73.27138 -42.052748)
		(width 0.14224)
		(layer "In2.Cu")
		(net "M_G_ECC<0>")
	)
	(segment
		(start 77.06741 -46.522894)
		(end 76.848462 -46.522894)
		(width 0.14224)
		(layer "In2.Cu")
		(net "M_G_ECC<0>")
	)
	(segment
		(start 73.27138 -42.052748)
		(end 72.915526 -41.696894)
		(width 0.14224)
		(layer "In2.Cu")
		(net "M_G_ECC<0>")
	)
	(segment
		(start 78.785212 -49.492154)
		(end 78.636368 -49.34331)
		(width 0.0889)
		(layer "In2.Cu")
		(net "M_G_ECC<0>")
	)
	(segment
		(start 80.406748 -55.894224)
		(end 80.401922 -55.885588)
		(width 0.0889)
		(layer "In2.Cu")
		(net "M_G_ECC<0>")
	)
	(segment
		(start 75.570588 -44.351956)
		(end 75.214734 -43.996102)
		(width 0.14224)
		(layer "In2.Cu")
		(net "M_G_ECC<0>")
	)
	(segment
		(start 76.720192 -45.50156)
		(end 76.364338 -45.145706)
		(width 0.14224)
		(layer "In2.Cu")
		(net "M_G_ECC<0>")
	)
	(segment
		(start 74.06513 -42.846498)
		(end 73.846182 -42.846498)
		(width 0.14224)
		(layer "In2.Cu")
		(net "M_G_ECC<0>")
	)
	(segment
		(start 74.995786 -43.996102)
		(end 74.768202 -44.223686)
		(width 0.14224)
		(layer "In2.Cu")
		(net "M_G_ECC<0>")
	)
	(segment
		(start 75.343004 -45.017436)
		(end 75.343004 -44.798488)
		(width 0.14224)
		(layer "In2.Cu")
		(net "M_G_ECC<0>")
	)
	(segment
		(start 80.401922 -56.876188)
		(end 80.395572 -56.86552)
		(width 0.0889)
		(layer "In2.Cu")
		(net "M_G_ECC<0>")
	)
	(segment
		(start 73.043796 -42.49928)
		(end 73.27138 -42.271696)
		(width 0.14224)
		(layer "In2.Cu")
		(net "M_G_ECC<0>")
	)
	(segment
		(start 71.894192 -41.568624)
		(end 71.894192 -41.349676)
		(width 0.14224)
		(layer "In2.Cu")
		(net "M_G_ECC<0>")
	)
	(segment
		(start 70.951344 -21.7932)
		(end 70.951344 -18.381218)
		(width 0.14224)
		(layer "In2.Cu")
		(net "M_G_ECC<0>")
	)
	(segment
		(start 72.121776 -41.122092)
		(end 72.121776 -40.903144)
		(width 0.14224)
		(layer "In2.Cu")
		(net "M_G_ECC<0>")
	)
	(segment
		(start 75.917806 -45.37329)
		(end 75.698858 -45.37329)
		(width 0.14224)
		(layer "In2.Cu")
		(net "M_G_ECC<0>")
	)
	(segment
		(start 80.928718 -59.15279)
		(end 80.900778 -59.15279)
		(width 0.0889)
		(layer "In2.Cu")
		(net "M_G_ECC<0>")
	)
	(segment
		(start 82.22361 -60.469272)
		(end 82.22361 -60.343796)
		(width 0.0889)
		(layer "In2.Cu")
		(net "M_G_ECC<0>")
	)
	(segment
		(start 71.039736 -26.633424)
		(end 71.039736 -26.419556)
		(width 0.14224)
		(layer "In2.Cu")
		(net "M_G_ECC<0>")
	)
	(segment
		(start 75.570588 -44.570904)
		(end 75.570588 -44.351956)
		(width 0.14224)
		(layer "In2.Cu")
		(net "M_G_ECC<0>")
	)
	(segment
		(start 70.499478 -23.560278)
		(end 70.214744 -23.275544)
		(width 0.14224)
		(layer "In2.Cu")
		(net "M_G_ECC<0>")
	)
	(segment
		(start 76.492608 -45.948092)
		(end 76.720192 -45.720508)
		(width 0.14224)
		(layer "In2.Cu")
		(net "M_G_ECC<0>")
	)
	(segment
		(start 70.679564 -28.034996)
		(end 70.679564 -26.993596)
		(width 0.14224)
		(layer "In2.Cu")
		(net "M_G_ECC<0>")
	)
	(segment
		(start 73.39965 -43.074082)
		(end 73.043796 -42.718228)
		(width 0.14224)
		(layer "In2.Cu")
		(net "M_G_ECC<0>")
	)
	(segment
		(start 74.420984 -43.202352)
		(end 74.06513 -42.846498)
		(width 0.14224)
		(layer "In2.Cu")
		(net "M_G_ECC<0>")
	)
	(segment
		(start 73.618598 -43.074082)
		(end 73.39965 -43.074082)
		(width 0.14224)
		(layer "In2.Cu")
		(net "M_G_ECC<0>")
	)
	(segment
		(start 80.401922 -55.295292)
		(end 80.485742 -55.136542)
		(width 0.0889)
		(layer "In2.Cu")
		(net "M_G_ECC<0>")
	)
	(segment
		(start 74.549254 -44.223686)
		(end 74.1934 -43.867832)
		(width 0.14224)
		(layer "In2.Cu")
		(net "M_G_ECC<0>")
	)
	(segment
		(start 80.406748 -56.884824)
		(end 80.401922 -56.876188)
		(width 0.0889)
		(layer "In2.Cu")
		(net "M_G_ECC<0>")
	)
	(segment
		(start 80.395572 -58.277506)
		(end 80.401922 -58.266838)
		(width 0.0889)
		(layer "In2.Cu")
		(net "M_G_ECC<0>")
	)
	(segment
		(start 72.121776 -40.903144)
		(end 71.168768 -39.950136)
		(width 0.14224)
		(layer "In2.Cu")
		(net "M_G_ECC<0>")
	)
	(segment
		(start 71.894192 -41.349676)
		(end 72.121776 -41.122092)
		(width 0.14224)
		(layer "In2.Cu")
		(net "M_G_ECC<0>")
	)
	(segment
		(start 72.250046 -41.924478)
		(end 71.894192 -41.568624)
		(width 0.14224)
		(layer "In2.Cu")
		(net "M_G_ECC<0>")
	)
	(segment
		(start 75.214734 -43.996102)
		(end 74.995786 -43.996102)
		(width 0.14224)
		(layer "In2.Cu")
		(net "M_G_ECC<0>")
	)
	(segment
		(start 81.783428 -59.647836)
		(end 81.750662 -59.647836)
		(width 0.0889)
		(layer "In2.Cu")
		(net "M_G_ECC<0>")
	)
	(segment
		(start 78.785212 -49.908714)
		(end 78.785212 -49.492154)
		(width 0.0889)
		(layer "In2.Cu")
		(net "M_G_ECC<0>")
	)
	(segment
		(start 70.679564 -26.993596)
		(end 71.039736 -26.633424)
		(width 0.14224)
		(layer "In2.Cu")
		(net "M_G_ECC<0>")
	)
	(segment
		(start 76.720192 -45.720508)
		(end 76.720192 -45.50156)
		(width 0.14224)
		(layer "In2.Cu")
		(net "M_G_ECC<0>")
	)
	(segment
		(start 71.039736 -26.419556)
		(end 70.577964 -25.957784)
		(width 0.14224)
		(layer "In2.Cu")
		(net "M_G_ECC<0>")
	)
	(segment
		(start 70.214744 -23.275544)
		(end 70.214744 -22.5298)
		(width 0.14224)
		(layer "In2.Cu")
		(net "M_G_ECC<0>")
	)
	(segment
		(start 75.343004 -44.798488)
		(end 75.570588 -44.570904)
		(width 0.14224)
		(layer "In2.Cu")
		(net "M_G_ECC<0>")
	)
	(segment
		(start 70.951344 -18.381218)
		(end 71.171562 -18.161)
		(width 0.14224)
		(layer "In2.Cu")
		(net "M_G_ECC<0>")
	)
	(segment
		(start 82.123026 -59.8551)
		(end 82.118962 -59.847988)
		(width 0.0889)
		(layer "In2.Cu")
		(net "M_G_ECC<0>")
	)
	(segment
		(start 80.603852 -52.618894)
		(end 80.603852 -51.727354)
		(width 0.0889)
		(layer "In2.Cu")
		(net "M_G_ECC<0>")
	)
	(segment
		(start 74.1934 -43.867832)
		(end 74.1934 -43.648884)
		(width 0.14224)
		(layer "In2.Cu")
		(net "M_G_ECC<0>")
	)
	(segment
		(start 82.297778 -60.54344)
		(end 82.22361 -60.469272)
		(width 0.0889)
		(layer "In2.Cu")
		(net "M_G_ECC<0>")
	)
	(segment
		(start 77.294994 -46.29531)
		(end 77.06741 -46.522894)
		(width 0.14224)
		(layer "In2.Cu")
		(net "M_G_ECC<0>")
	)
	(segment
		(start 82.279998 -60.287408)
		(end 82.279998 -60.150248)
		(width 0.0889)
		(layer "In2.Cu")
		(net "M_G_ECC<0>")
	)
	(segment
		(start 74.420984 -43.4213)
		(end 74.420984 -43.202352)
		(width 0.14224)
		(layer "In2.Cu")
		(net "M_G_ECC<0>")
	)
	(segment
		(start 76.492608 -46.16704)
		(end 76.492608 -45.948092)
		(width 0.14224)
		(layer "In2.Cu")
		(net "M_G_ECC<0>")
	)
	(segment
		(start 82.630772 -60.54344)
		(end 82.297778 -60.54344)
		(width 0.0889)
		(layer "In2.Cu")
		(net "M_G_ECC<0>")
	)
	(segment
		(start 76.14539 -45.145706)
		(end 75.917806 -45.37329)
		(width 0.14224)
		(layer "In2.Cu")
		(net "M_G_ECC<0>")
	)
	(segment
		(start 77.513942 -46.29531)
		(end 77.294994 -46.29531)
		(width 0.14224)
		(layer "In2.Cu")
		(net "M_G_ECC<0>")
	)
	(segment
		(start 75.698858 -45.37329)
		(end 75.343004 -45.017436)
		(width 0.14224)
		(layer "In2.Cu")
		(net "M_G_ECC<0>")
	)
	(segment
		(start 72.468994 -41.924478)
		(end 72.250046 -41.924478)
		(width 0.14224)
		(layer "In2.Cu")
		(net "M_G_ECC<0>")
	)
	(segment
		(start 76.848462 -46.522894)
		(end 76.492608 -46.16704)
		(width 0.14224)
		(layer "In2.Cu")
		(net "M_G_ECC<0>")
	)
	(segment
		(start 70.214744 -22.5298)
		(end 70.951344 -21.7932)
		(width 0.14224)
		(layer "In2.Cu")
		(net "M_G_ECC<0>")
	)
	(segment
		(start 80.485742 -52.737004)
		(end 80.603852 -52.618894)
		(width 0.0889)
		(layer "In2.Cu")
		(net "M_G_ECC<0>")
	)
	(segment
		(start 71.168768 -39.950136)
		(end 71.168768 -29.362146)
		(width 0.14224)
		(layer "In2.Cu")
		(net "M_G_ECC<0>")
	)
	(segment
		(start 80.485742 -55.136542)
		(end 80.485742 -52.737004)
		(width 0.0889)
		(layer "In2.Cu")
		(net "M_G_ECC<0>")
	)
	(segment
		(start 71.168768 -29.362146)
		(end 70.984364 -29.177742)
		(width 0.14224)
		(layer "In2.Cu")
		(net "M_G_ECC<0>")
	)
	(segment
		(start 76.364338 -45.145706)
		(end 76.14539 -45.145706)
		(width 0.14224)
		(layer "In2.Cu")
		(net "M_G_ECC<0>")
	)
	(segment
		(start 72.915526 -41.696894)
		(end 72.696578 -41.696894)
		(width 0.14224)
		(layer "In2.Cu")
		(net "M_G_ECC<0>")
	)
	(segment
		(start 70.577964 -23.638764)
		(end 70.499478 -23.560278)
		(width 0.14224)
		(layer "In2.Cu")
		(net "M_G_ECC<0>")
	)
	(segment
		(start 70.984364 -28.339796)
		(end 70.679564 -28.034996)
		(width 0.14224)
		(layer "In2.Cu")
		(net "M_G_ECC<0>")
	)
	(segment
		(start 73.043796 -42.718228)
		(end 73.043796 -42.49928)
		(width 0.14224)
		(layer "In2.Cu")
		(net "M_G_ECC<0>")
	)
	(segment
		(start 70.577964 -25.957784)
		(end 70.577964 -23.638764)
		(width 0.14224)
		(layer "In2.Cu")
		(net "M_G_ECC<0>")
	)
	(segment
		(start 78.636368 -47.417736)
		(end 77.513942 -46.29531)
		(width 0.14224)
		(layer "In2.Cu")
		(net "M_G_ECC<0>")
	)
	(segment
		(start 70.984364 -29.177742)
		(end 70.984364 -28.339796)
		(width 0.14224)
		(layer "In2.Cu")
		(net "M_G_ECC<0>")
	)
	(segment
		(start 72.696578 -41.696894)
		(end 72.468994 -41.924478)
		(width 0.14224)
		(layer "In2.Cu")
		(net "M_G_ECC<0>")
	)
	(arc
		(start 80.401922 -55.885588)
		(mid 80.322917 -55.59044)
		(end 80.401922 -55.295292)
		(width 0.0889)
		(layer "In2.Cu")
		(net "M_G_ECC<0>")
	)
	(arc
		(start 80.900778 -59.15279)
		(mid 80.401897 -58.857353)
		(end 80.395572 -58.277506)
		(width 0.0889)
		(layer "In2.Cu")
		(net "M_G_ECC<0>")
	)
	(arc
		(start 81.750662 -59.647836)
		(mid 81.467445 -59.563555)
		(end 81.260442 -59.352688)
		(width 0.0889)
		(layer "In2.Cu")
		(net "M_G_ECC<0>")
	)
	(arc
		(start 82.254344 -60.066428)
		(mid 82.186983 -59.961822)
		(end 82.123026 -59.8551)
		(width 0.0889)
		(layer "In2.Cu")
		(net "M_G_ECC<0>")
	)
	(arc
		(start 80.401922 -56.285638)
		(mid 80.455392 -56.090575)
		(end 80.406748 -55.894224)
		(width 0.0889)
		(layer "In2.Cu")
		(net "M_G_ECC<0>")
	)
	(arc
		(start 82.118962 -59.847988)
		(mid 81.977505 -59.703774)
		(end 81.783428 -59.647836)
		(width 0.0889)
		(layer "In2.Cu")
		(net "M_G_ECC<0>")
	)
	(arc
		(start 82.279998 -60.150248)
		(mid 82.27333 -60.106454)
		(end 82.254344 -60.066428)
		(width 0.0889)
		(layer "In2.Cu")
		(net "M_G_ECC<0>")
	)
	(arc
		(start 81.260442 -59.352688)
		(mid 81.120363 -59.209952)
		(end 80.928718 -59.15279)
		(width 0.0889)
		(layer "In2.Cu")
		(net "M_G_ECC<0>")
	)
	(arc
		(start 80.401922 -58.266838)
		(mid 80.455421 -58.06694)
		(end 80.401922 -57.867042)
		(width 0.0889)
		(layer "In2.Cu")
		(net "M_G_ECC<0>")
	)
	(arc
		(start 80.395572 -56.86552)
		(mid 80.322774 -56.574757)
		(end 80.401922 -56.285638)
		(width 0.0889)
		(layer "In2.Cu")
		(net "M_G_ECC<0>")
	)
	(arc
		(start 80.401922 -57.276238)
		(mid 80.455392 -57.081175)
		(end 80.406748 -56.884824)
		(width 0.0889)
		(layer "In2.Cu")
		(net "M_G_ECC<0>")
	)
	(arc
		(start 80.401922 -57.867042)
		(mid 80.322791 -57.57164)
		(end 80.401922 -57.276238)
		(width 0.0889)
		(layer "In2.Cu")
		(net "M_G_ECC<0>")
	)
	(segment
		(start 34.363406 -16.476472)
		(end 34.278824 -16.660368)
		(width 0.1651)
		(layer "F.Cu")
		(net "M_G_DQS_DP<9>")
	)
	(segment
		(start 34.799524 -15.423642)
		(end 34.799524 -16.040354)
		(width 0.1651)
		(layer "F.Cu")
		(net "M_G_DQS_DP<9>")
	)
	(segment
		(start 34.799524 -16.040354)
		(end 34.363406 -16.476472)
		(width 0.1651)
		(layer "F.Cu")
		(net "M_G_DQS_DP<9>")
	)
	(segment
		(start 34.360358 -17.702784)
		(end 34.74212 -18.084546)
		(width 0.1651)
		(layer "F.Cu")
		(net "M_G_DQS_DP<9>")
	)
	(segment
		(start 34.278824 -16.660368)
		(end 34.278824 -17.478502)
		(width 0.1651)
		(layer "F.Cu")
		(net "M_G_DQS_DP<9>")
	)
	(segment
		(start 34.278824 -17.478502)
		(end 34.360358 -17.702784)
		(width 0.1651)
		(layer "F.Cu")
		(net "M_G_DQS_DP<9>")
	)
	(segment
		(start 68.607686 -65.000886)
		(end 68.036186 -65.000886)
		(width 0.1016)
		(layer "F.Cu")
		(net "M_G_DQS_DP<9>")
	)
	(via
		(at 34.74212 -22.1742)
		(size 0.508)
		(drill 0.254)
		(layers "F.Cu" "B.Cu")
		(net "M_G_DQS_DP<9>")
	)
	(via
		(at 68.036186 -65.000886)
		(size 0.508)
		(drill 0.254)
		(layers "F.Cu" "B.Cu")
		(net "M_G_DQS_DP<9>")
	)
	(via
		(at 34.74212 -18.084546)
		(size 0.508)
		(drill 0.254)
		(layers "F.Cu" "B.Cu")
		(net "M_G_DQS_DP<9>")
	)
	(segment
		(start 34.266124 -22.722332)
		(end 34.3535 -22.56282)
		(width 0.1651)
		(layer "B.Cu")
		(net "M_G_DQS_DP<9>")
	)
	(segment
		(start 34.266124 -23.617936)
		(end 34.266124 -22.722332)
		(width 0.1651)
		(layer "B.Cu")
		(net "M_G_DQS_DP<9>")
	)
	(segment
		(start 34.3535 -22.56282)
		(end 34.74212 -22.1742)
		(width 0.1651)
		(layer "B.Cu")
		(net "M_G_DQS_DP<9>")
	)
	(segment
		(start 34.799524 -24.824182)
		(end 34.799524 -24.206454)
		(width 0.1651)
		(layer "B.Cu")
		(net "M_G_DQS_DP<9>")
	)
	(segment
		(start 34.799524 -24.206454)
		(end 34.34334 -23.75027)
		(width 0.1651)
		(layer "B.Cu")
		(net "M_G_DQS_DP<9>")
	)
	(segment
		(start 34.34334 -23.75027)
		(end 34.266124 -23.617936)
		(width 0.1651)
		(layer "B.Cu")
		(net "M_G_DQS_DP<9>")
	)
	(segment
		(start 34.927032 -21.0439)
		(end 34.770568 -20.887436)
		(width 0.14224)
		(layer "In2.Cu")
		(net "M_G_DQS_DP<9>")
	)
	(segment
		(start 34.74212 -22.1742)
		(end 34.271204 -22.645116)
		(width 0.14224)
		(layer "In2.Cu")
		(net "M_G_DQS_DP<9>")
	)
	(segment
		(start 35.261804 -21.29028)
		(end 35.015424 -21.0439)
		(width 0.14224)
		(layer "In2.Cu")
		(net "M_G_DQS_DP<9>")
	)
	(segment
		(start 34.271204 -22.645116)
		(end 34.271204 -24.895302)
		(width 0.14224)
		(layer "In2.Cu")
		(net "M_G_DQS_DP<9>")
	)
	(segment
		(start 68.222622 -65.000886)
		(end 68.036186 -65.000886)
		(width 0.0889)
		(layer "In2.Cu")
		(net "M_G_DQS_DP<9>")
	)
	(segment
		(start 65.911984 -64.831722)
		(end 65.972182 -64.771524)
		(width 0.0889)
		(layer "In2.Cu")
		(net "M_G_DQS_DP<9>")
	)
	(segment
		(start 34.950146 -17.87652)
		(end 34.74212 -18.084546)
		(width 0.14224)
		(layer "In2.Cu")
		(net "M_G_DQS_DP<9>")
	)
	(segment
		(start 35.261804 -21.933662)
		(end 35.261804 -21.29028)
		(width 0.14224)
		(layer "In2.Cu")
		(net "M_G_DQS_DP<9>")
	)
	(segment
		(start 68.311522 -64.689736)
		(end 68.311522 -64.911986)
		(width 0.0889)
		(layer "In2.Cu")
		(net "M_G_DQS_DP<9>")
	)
	(segment
		(start 34.898076 -20.4216)
		(end 35.078924 -20.4216)
		(width 0.14224)
		(layer "In2.Cu")
		(net "M_G_DQS_DP<9>")
	)
	(segment
		(start 35.08121 -17.87652)
		(end 34.950146 -17.87652)
		(width 0.14224)
		(layer "In2.Cu")
		(net "M_G_DQS_DP<9>")
	)
	(segment
		(start 35.015424 -21.0439)
		(end 34.927032 -21.0439)
		(width 0.14224)
		(layer "In2.Cu")
		(net "M_G_DQS_DP<9>")
	)
	(segment
		(start 34.926524 -19.7866)
		(end 34.774124 -19.6342)
		(width 0.14224)
		(layer "In2.Cu")
		(net "M_G_DQS_DP<9>")
	)
	(segment
		(start 66.933064 -64.10579)
		(end 67.287902 -64.10579)
		(width 0.0889)
		(layer "In2.Cu")
		(net "M_G_DQS_DP<9>")
	)
	(segment
		(start 35.399218 -36.652962)
		(end 35.677348 -36.652962)
		(width 0.14224)
		(layer "In2.Cu")
		(net "M_G_DQS_DP<9>")
	)
	(segment
		(start 36.299648 -37.553392)
		(end 63.577978 -64.831722)
		(width 0.14224)
		(layer "In2.Cu")
		(net "M_G_DQS_DP<9>")
	)
	(segment
		(start 34.74212 -22.1742)
		(end 35.021266 -22.1742)
		(width 0.14224)
		(layer "In2.Cu")
		(net "M_G_DQS_DP<9>")
	)
	(segment
		(start 66.26733 -64.771524)
		(end 66.933064 -64.10579)
		(width 0.0889)
		(layer "In2.Cu")
		(net "M_G_DQS_DP<9>")
	)
	(segment
		(start 35.261804 -19.99488)
		(end 35.053524 -19.7866)
		(width 0.14224)
		(layer "In2.Cu")
		(net "M_G_DQS_DP<9>")
	)
	(segment
		(start 36.299648 -37.275262)
		(end 36.299648 -37.553392)
		(width 0.14224)
		(layer "In2.Cu")
		(net "M_G_DQS_DP<9>")
	)
	(segment
		(start 35.261804 -20.23872)
		(end 35.261804 -19.99488)
		(width 0.14224)
		(layer "In2.Cu")
		(net "M_G_DQS_DP<9>")
	)
	(segment
		(start 65.972182 -64.771524)
		(end 66.26733 -64.771524)
		(width 0.0889)
		(layer "In2.Cu")
		(net "M_G_DQS_DP<9>")
	)
	(segment
		(start 34.799016 -36.05276)
		(end 35.399218 -36.652962)
		(width 0.14224)
		(layer "In2.Cu")
		(net "M_G_DQS_DP<9>")
	)
	(segment
		(start 67.287902 -64.10579)
		(end 67.782948 -64.600836)
		(width 0.0889)
		(layer "In2.Cu")
		(net "M_G_DQS_DP<9>")
	)
	(segment
		(start 35.078924 -20.4216)
		(end 35.261804 -20.23872)
		(width 0.14224)
		(layer "In2.Cu")
		(net "M_G_DQS_DP<9>")
	)
	(segment
		(start 34.770568 -20.887436)
		(end 34.770568 -20.549108)
		(width 0.14224)
		(layer "In2.Cu")
		(net "M_G_DQS_DP<9>")
	)
	(segment
		(start 35.261804 -18.057114)
		(end 35.08121 -17.87652)
		(width 0.14224)
		(layer "In2.Cu")
		(net "M_G_DQS_DP<9>")
	)
	(segment
		(start 35.053524 -19.7866)
		(end 34.926524 -19.7866)
		(width 0.14224)
		(layer "In2.Cu")
		(net "M_G_DQS_DP<9>")
	)
	(segment
		(start 35.261804 -18.89252)
		(end 35.261804 -18.057114)
		(width 0.14224)
		(layer "In2.Cu")
		(net "M_G_DQS_DP<9>")
	)
	(segment
		(start 34.799016 -25.423114)
		(end 34.799016 -36.05276)
		(width 0.14224)
		(layer "In2.Cu")
		(net "M_G_DQS_DP<9>")
	)
	(segment
		(start 34.271204 -24.895302)
		(end 34.799016 -25.423114)
		(width 0.14224)
		(layer "In2.Cu")
		(net "M_G_DQS_DP<9>")
	)
	(segment
		(start 67.782948 -64.600836)
		(end 68.222622 -64.600836)
		(width 0.0889)
		(layer "In2.Cu")
		(net "M_G_DQS_DP<9>")
	)
	(segment
		(start 34.774124 -19.3802)
		(end 35.261804 -18.89252)
		(width 0.14224)
		(layer "In2.Cu")
		(net "M_G_DQS_DP<9>")
	)
	(segment
		(start 35.021266 -22.1742)
		(end 35.261804 -21.933662)
		(width 0.14224)
		(layer "In2.Cu")
		(net "M_G_DQS_DP<9>")
	)
	(segment
		(start 34.770568 -20.549108)
		(end 34.898076 -20.4216)
		(width 0.14224)
		(layer "In2.Cu")
		(net "M_G_DQS_DP<9>")
	)
	(segment
		(start 63.577978 -64.831722)
		(end 65.911984 -64.831722)
		(width 0.14224)
		(layer "In2.Cu")
		(net "M_G_DQS_DP<9>")
	)
	(segment
		(start 34.774124 -19.6342)
		(end 34.774124 -19.3802)
		(width 0.14224)
		(layer "In2.Cu")
		(net "M_G_DQS_DP<9>")
	)
	(segment
		(start 35.677348 -36.652962)
		(end 36.299648 -37.275262)
		(width 0.14224)
		(layer "In2.Cu")
		(net "M_G_DQS_DP<9>")
	)
	(arc
		(start 68.311522 -64.911986)
		(mid 68.285484 -64.974848)
		(end 68.222622 -65.000886)
		(width 0.0889)
		(layer "In2.Cu")
		(net "M_G_DQS_DP<9>")
	)
	(arc
		(start 68.222622 -64.600836)
		(mid 68.254136 -64.606609)
		(end 68.28155 -64.623188)
		(width 0.0889)
		(layer "In2.Cu")
		(net "M_G_DQS_DP<9>")
	)
	(arc
		(start 68.28155 -64.623188)
		(mid 68.303675 -64.653245)
		(end 68.311522 -64.689736)
		(width 0.0889)
		(layer "In2.Cu")
		(net "M_G_DQS_DP<9>")
	)
	(segment
		(start 73.937368 -18.9738)
		(end 73.937368 -17.6022)
		(width 0.1651)
		(layer "F.Cu")
		(net "M_G_DQS_DP<8>")
	)
	(segment
		(start 73.693528 -17.35836)
		(end 73.437496 -17.35836)
		(width 0.1651)
		(layer "F.Cu")
		(net "M_G_DQS_DP<8>")
	)
	(segment
		(start 84.060792 -62.029086)
		(end 83.489292 -62.029086)
		(width 0.1016)
		(layer "F.Cu")
		(net "M_G_DQS_DP<8>")
	)
	(segment
		(start 73.899522 -20.023582)
		(end 73.899522 -19.011646)
		(width 0.1651)
		(layer "F.Cu")
		(net "M_G_DQS_DP<8>")
	)
	(segment
		(start 73.937368 -17.6022)
		(end 73.693528 -17.35836)
		(width 0.1651)
		(layer "F.Cu")
		(net "M_G_DQS_DP<8>")
	)
	(segment
		(start 73.899522 -19.011646)
		(end 73.937368 -18.9738)
		(width 0.1651)
		(layer "F.Cu")
		(net "M_G_DQS_DP<8>")
	)
	(via
		(at 73.437496 -17.35836)
		(size 0.508)
		(drill 0.254)
		(layers "F.Cu" "B.Cu")
		(net "M_G_DQS_DP<8>")
	)
	(via
		(at 73.437496 -22.888956)
		(size 0.508)
		(drill 0.254)
		(layers "F.Cu" "B.Cu")
		(net "M_G_DQS_DP<8>")
	)
	(via
		(at 83.489292 -62.029086)
		(size 0.508)
		(drill 0.254)
		(layers "F.Cu" "B.Cu")
		(net "M_G_DQS_DP<8>")
	)
	(segment
		(start 73.679812 -22.888956)
		(end 73.437496 -22.888956)
		(width 0.1651)
		(layer "B.Cu")
		(net "M_G_DQS_DP<8>")
	)
	(segment
		(start 73.937368 -21.4122)
		(end 73.937368 -22.6314)
		(width 0.1651)
		(layer "B.Cu")
		(net "M_G_DQS_DP<8>")
	)
	(segment
		(start 73.899522 -21.374354)
		(end 73.937368 -21.4122)
		(width 0.1651)
		(layer "B.Cu")
		(net "M_G_DQS_DP<8>")
	)
	(segment
		(start 73.899522 -20.224242)
		(end 73.899522 -21.374354)
		(width 0.1651)
		(layer "B.Cu")
		(net "M_G_DQS_DP<8>")
	)
	(segment
		(start 73.937368 -22.6314)
		(end 73.679812 -22.888956)
		(width 0.1651)
		(layer "B.Cu")
		(net "M_G_DQS_DP<8>")
	)
	(segment
		(start 83.43138 -62.425072)
		(end 83.489292 -62.36716)
		(width 0.0889)
		(layer "In2.Cu")
		(net "M_G_DQS_DP<8>")
	)
	(segment
		(start 83.489292 -62.36716)
		(end 83.489292 -62.029086)
		(width 0.0889)
		(layer "In2.Cu")
		(net "M_G_DQS_DP<8>")
	)
	(segment
		(start 77.573124 -43.243246)
		(end 77.573124 -43.386756)
		(width 0.14224)
		(layer "In2.Cu")
		(net "M_G_DQS_DP<8>")
	)
	(segment
		(start 73.9013 -23.35276)
		(end 73.9013 -23.861268)
		(width 0.14224)
		(layer "In2.Cu")
		(net "M_G_DQS_DP<8>")
	)
	(segment
		(start 81.582768 -48.403002)
		(end 81.582768 -49.01311)
		(width 0.14224)
		(layer "In2.Cu")
		(net "M_G_DQS_DP<8>")
	)
	(segment
		(start 74.311256 -28.779216)
		(end 74.311256 -33.03651)
		(width 0.14224)
		(layer "In2.Cu")
		(net "M_G_DQS_DP<8>")
	)
	(segment
		(start 82.22996 -53.19522)
		(end 82.22996 -55.707026)
		(width 0.0889)
		(layer "In2.Cu")
		(net "M_G_DQS_DP<8>")
	)
	(segment
		(start 73.437496 -17.35836)
		(end 74.248264 -18.169128)
		(width 0.14224)
		(layer "In2.Cu")
		(net "M_G_DQS_DP<8>")
	)
	(segment
		(start 74.219816 -28.687776)
		(end 74.311256 -28.779216)
		(width 0.14224)
		(layer "In2.Cu")
		(net "M_G_DQS_DP<8>")
	)
	(segment
		(start 79.175356 -44.845478)
		(end 79.175356 -44.988988)
		(width 0.14224)
		(layer "In2.Cu")
		(net "M_G_DQS_DP<8>")
	)
	(segment
		(start 74.219816 -26.28392)
		(end 74.377296 -26.4414)
		(width 0.14224)
		(layer "In2.Cu")
		(net "M_G_DQS_DP<8>")
	)
	(segment
		(start 78.37424 -44.187872)
		(end 78.702916 -44.516548)
		(width 0.14224)
		(layer "In2.Cu")
		(net "M_G_DQS_DP<8>")
	)
	(segment
		(start 77.100684 -42.914316)
		(end 77.244194 -42.914316)
		(width 0.14224)
		(layer "In2.Cu")
		(net "M_G_DQS_DP<8>")
	)
	(segment
		(start 73.855326 -24.976074)
		(end 73.855326 -25.198578)
		(width 0.14224)
		(layer "In2.Cu")
		(net "M_G_DQS_DP<8>")
	)
	(segment
		(start 82.940652 -50.88636)
		(end 82.940652 -52.484528)
		(width 0.0889)
		(layer "In2.Cu")
		(net "M_G_DQS_DP<8>")
	)
	(segment
		(start 83.510882 -61.629036)
		(end 83.478116 -61.629036)
		(width 0.0889)
		(layer "In2.Cu")
		(net "M_G_DQS_DP<8>")
	)
	(segment
		(start 74.219816 -25.563068)
		(end 74.219816 -26.28392)
		(width 0.14224)
		(layer "In2.Cu")
		(net "M_G_DQS_DP<8>")
	)
	(segment
		(start 83.471258 -58.466736)
		(end 83.510882 -58.466736)
		(width 0.0889)
		(layer "In2.Cu")
		(net "M_G_DQS_DP<8>")
	)
	(segment
		(start 75.174856 -33.90011)
		(end 75.174856 -40.988488)
		(width 0.14224)
		(layer "In2.Cu")
		(net "M_G_DQS_DP<8>")
	)
	(segment
		(start 78.702916 -44.516548)
		(end 78.846426 -44.516548)
		(width 0.14224)
		(layer "In2.Cu")
		(net "M_G_DQS_DP<8>")
	)
	(segment
		(start 73.675494 -24.796242)
		(end 73.855326 -24.976074)
		(width 0.14224)
		(layer "In2.Cu")
		(net "M_G_DQS_DP<8>")
	)
	(segment
		(start 84.001102 -59.752738)
		(end 84.007452 -59.763406)
		(width 0.0889)
		(layer "In2.Cu")
		(net "M_G_DQS_DP<8>")
	)
	(segment
		(start 73.855326 -25.198578)
		(end 74.219816 -25.563068)
		(width 0.14224)
		(layer "In2.Cu")
		(net "M_G_DQS_DP<8>")
	)
	(segment
		(start 81.538572 -49.48428)
		(end 82.940652 -50.88636)
		(width 0.0889)
		(layer "In2.Cu")
		(net "M_G_DQS_DP<8>")
	)
	(segment
		(start 73.437496 -22.888956)
		(end 73.9013 -23.35276)
		(width 0.14224)
		(layer "In2.Cu")
		(net "M_G_DQS_DP<8>")
	)
	(segment
		(start 73.26122 -24.604472)
		(end 73.45299 -24.796242)
		(width 0.14224)
		(layer "In2.Cu")
		(net "M_G_DQS_DP<8>")
	)
	(segment
		(start 77.9018 -43.715432)
		(end 78.04531 -43.715432)
		(width 0.14224)
		(layer "In2.Cu")
		(net "M_G_DQS_DP<8>")
	)
	(segment
		(start 82.279236 -56.772302)
		(end 82.278982 -56.772556)
		(width 0.0889)
		(layer "In2.Cu")
		(net "M_G_DQS_DP<8>")
	)
	(segment
		(start 84.001102 -60.743338)
		(end 84.007452 -60.754006)
		(width 0.0889)
		(layer "In2.Cu")
		(net "M_G_DQS_DP<8>")
	)
	(segment
		(start 82.27949 -56.773318)
		(end 82.290412 -56.791606)
		(width 0.0889)
		(layer "In2.Cu")
		(net "M_G_DQS_DP<8>")
	)
	(segment
		(start 73.9013 -23.861268)
		(end 73.734168 -24.0284)
		(width 0.14224)
		(layer "In2.Cu")
		(net "M_G_DQS_DP<8>")
	)
	(segment
		(start 73.26122 -24.221948)
		(end 73.26122 -24.604472)
		(width 0.14224)
		(layer "In2.Cu")
		(net "M_G_DQS_DP<8>")
	)
	(segment
		(start 74.248264 -18.169128)
		(end 74.248264 -22.078188)
		(width 0.14224)
		(layer "In2.Cu")
		(net "M_G_DQS_DP<8>")
	)
	(segment
		(start 83.996276 -59.744102)
		(end 84.001102 -59.752738)
		(width 0.0889)
		(layer "In2.Cu")
		(net "M_G_DQS_DP<8>")
	)
	(segment
		(start 81.582768 -49.01311)
		(end 81.538572 -49.057306)
		(width 0.0889)
		(layer "In2.Cu")
		(net "M_G_DQS_DP<8>")
	)
	(segment
		(start 74.377296 -26.4414)
		(end 74.377296 -26.6954)
		(width 0.14224)
		(layer "In2.Cu")
		(net "M_G_DQS_DP<8>")
	)
	(segment
		(start 73.734168 -24.0284)
		(end 73.454768 -24.0284)
		(width 0.14224)
		(layer "In2.Cu")
		(net "M_G_DQS_DP<8>")
	)
	(segment
		(start 73.45299 -24.796242)
		(end 73.675494 -24.796242)
		(width 0.14224)
		(layer "In2.Cu")
		(net "M_G_DQS_DP<8>")
	)
	(segment
		(start 79.175356 -44.988988)
		(end 80.87106 -46.684692)
		(width 0.14224)
		(layer "In2.Cu")
		(net "M_G_DQS_DP<8>")
	)
	(segment
		(start 82.22996 -55.707026)
		(end 82.253328 -55.730394)
		(width 0.0889)
		(layer "In2.Cu")
		(net "M_G_DQS_DP<8>")
	)
	(segment
		(start 75.174856 -40.988488)
		(end 77.100684 -42.914316)
		(width 0.14224)
		(layer "In2.Cu")
		(net "M_G_DQS_DP<8>")
	)
	(segment
		(start 82.278982 -56.772556)
		(end 82.27949 -56.773318)
		(width 0.0889)
		(layer "In2.Cu")
		(net "M_G_DQS_DP<8>")
	)
	(segment
		(start 78.04531 -43.715432)
		(end 78.37424 -44.044362)
		(width 0.14224)
		(layer "In2.Cu")
		(net "M_G_DQS_DP<8>")
	)
	(segment
		(start 78.846426 -44.516548)
		(end 79.175356 -44.845478)
		(width 0.14224)
		(layer "In2.Cu")
		(net "M_G_DQS_DP<8>")
	)
	(segment
		(start 74.219816 -26.85288)
		(end 74.219816 -28.687776)
		(width 0.14224)
		(layer "In2.Cu")
		(net "M_G_DQS_DP<8>")
	)
	(segment
		(start 82.940652 -52.484528)
		(end 82.22996 -53.19522)
		(width 0.0889)
		(layer "In2.Cu")
		(net "M_G_DQS_DP<8>")
	)
	(segment
		(start 83.996276 -60.734702)
		(end 84.001102 -60.743338)
		(width 0.0889)
		(layer "In2.Cu")
		(net "M_G_DQS_DP<8>")
	)
	(segment
		(start 80.87106 -46.684692)
		(end 81.582768 -48.403002)
		(width 0.14224)
		(layer "In2.Cu")
		(net "M_G_DQS_DP<8>")
	)
	(segment
		(start 73.454768 -24.0284)
		(end 73.26122 -24.221948)
		(width 0.14224)
		(layer "In2.Cu")
		(net "M_G_DQS_DP<8>")
	)
	(segment
		(start 74.248264 -22.078188)
		(end 73.437496 -22.888956)
		(width 0.14224)
		(layer "In2.Cu")
		(net "M_G_DQS_DP<8>")
	)
	(segment
		(start 74.377296 -26.6954)
		(end 74.219816 -26.85288)
		(width 0.14224)
		(layer "In2.Cu")
		(net "M_G_DQS_DP<8>")
	)
	(segment
		(start 77.573124 -43.386756)
		(end 77.9018 -43.715432)
		(width 0.14224)
		(layer "In2.Cu")
		(net "M_G_DQS_DP<8>")
	)
	(segment
		(start 78.37424 -44.044362)
		(end 78.37424 -44.187872)
		(width 0.14224)
		(layer "In2.Cu")
		(net "M_G_DQS_DP<8>")
	)
	(segment
		(start 74.311256 -33.03651)
		(end 75.174856 -33.90011)
		(width 0.14224)
		(layer "In2.Cu")
		(net "M_G_DQS_DP<8>")
	)
	(segment
		(start 82.612738 -57.971436)
		(end 82.648552 -57.971436)
		(width 0.0889)
		(layer "In2.Cu")
		(net "M_G_DQS_DP<8>")
	)
	(segment
		(start 77.244194 -42.914316)
		(end 77.573124 -43.243246)
		(width 0.14224)
		(layer "In2.Cu")
		(net "M_G_DQS_DP<8>")
	)
	(segment
		(start 81.538572 -49.057306)
		(end 81.538572 -49.48428)
		(width 0.0889)
		(layer "In2.Cu")
		(net "M_G_DQS_DP<8>")
	)
	(arc
		(start 84.007452 -59.763406)
		(mid 84.08025 -60.054169)
		(end 84.001102 -60.343288)
		(width 0.0889)
		(layer "In2.Cu")
		(net "M_G_DQS_DP<8>")
	)
	(arc
		(start 83.478116 -61.629036)
		(mid 83.089774 -62.00563)
		(end 83.43138 -62.425072)
		(width 0.0889)
		(layer "In2.Cu")
		(net "M_G_DQS_DP<8>")
	)
	(arc
		(start 84.001102 -59.352688)
		(mid 83.947632 -59.547751)
		(end 83.996276 -59.744102)
		(width 0.0889)
		(layer "In2.Cu")
		(net "M_G_DQS_DP<8>")
	)
	(arc
		(start 82.253328 -55.730394)
		(mid 82.364199 -56.051141)
		(end 82.284062 -56.380888)
		(width 0.0889)
		(layer "In2.Cu")
		(net "M_G_DQS_DP<8>")
	)
	(arc
		(start 82.648552 -57.971436)
		(mid 82.933976 -58.054903)
		(end 83.142582 -58.266838)
		(width 0.0889)
		(layer "In2.Cu")
		(net "M_G_DQS_DP<8>")
	)
	(arc
		(start 82.290412 -56.791606)
		(mid 82.36321 -57.082369)
		(end 82.284062 -57.371488)
		(width 0.0889)
		(layer "In2.Cu")
		(net "M_G_DQS_DP<8>")
	)
	(arc
		(start 84.001102 -60.343288)
		(mid 83.947632 -60.538351)
		(end 83.996276 -60.734702)
		(width 0.0889)
		(layer "In2.Cu")
		(net "M_G_DQS_DP<8>")
	)
	(arc
		(start 84.007452 -60.754006)
		(mid 84.003421 -61.330188)
		(end 83.510882 -61.629036)
		(width 0.0889)
		(layer "In2.Cu")
		(net "M_G_DQS_DP<8>")
	)
	(arc
		(start 83.510882 -58.466736)
		(mid 84.006359 -58.771179)
		(end 84.001102 -59.352688)
		(width 0.0889)
		(layer "In2.Cu")
		(net "M_G_DQS_DP<8>")
	)
	(arc
		(start 82.284062 -57.371488)
		(mid 82.279652 -57.763951)
		(end 82.612738 -57.971436)
		(width 0.0889)
		(layer "In2.Cu")
		(net "M_G_DQS_DP<8>")
	)
	(arc
		(start 83.142582 -58.266838)
		(mid 83.281326 -58.408871)
		(end 83.471258 -58.466736)
		(width 0.0889)
		(layer "In2.Cu")
		(net "M_G_DQS_DP<8>")
	)
	(arc
		(start 82.284062 -56.380888)
		(mid 82.230592 -56.575951)
		(end 82.279236 -56.772302)
		(width 0.0889)
		(layer "In2.Cu")
		(net "M_G_DQS_DP<8>")
	)
	(segment
		(start 147.84959 -20.023328)
		(end 147.84959 -19.011646)
		(width 0.1651)
		(layer "F.Cu")
		(net "M_G_DQS_DP<7>")
	)
	(segment
		(start 122.504708 -58.381138)
		(end 121.933208 -58.381138)
		(width 0.1016)
		(layer "F.Cu")
		(net "M_G_DQS_DP<7>")
	)
	(segment
		(start 147.84959 -19.011646)
		(end 147.887436 -18.9738)
		(width 0.1651)
		(layer "F.Cu")
		(net "M_G_DQS_DP<7>")
	)
	(segment
		(start 147.849336 -20.023582)
		(end 147.84959 -20.023328)
		(width 0.1651)
		(layer "F.Cu")
		(net "M_G_DQS_DP<7>")
	)
	(segment
		(start 147.643596 -17.35836)
		(end 147.387564 -17.35836)
		(width 0.1651)
		(layer "F.Cu")
		(net "M_G_DQS_DP<7>")
	)
	(segment
		(start 147.887436 -17.6022)
		(end 147.643596 -17.35836)
		(width 0.1651)
		(layer "F.Cu")
		(net "M_G_DQS_DP<7>")
	)
	(segment
		(start 147.887436 -18.9738)
		(end 147.887436 -17.6022)
		(width 0.1651)
		(layer "F.Cu")
		(net "M_G_DQS_DP<7>")
	)
	(via
		(at 121.933208 -58.381138)
		(size 0.508)
		(drill 0.254)
		(layers "F.Cu" "B.Cu")
		(net "M_G_DQS_DP<7>")
	)
	(via
		(at 147.387564 -22.888956)
		(size 0.508)
		(drill 0.254)
		(layers "F.Cu" "B.Cu")
		(net "M_G_DQS_DP<7>")
	)
	(via
		(at 147.387564 -17.35836)
		(size 0.508)
		(drill 0.254)
		(layers "F.Cu" "B.Cu")
		(net "M_G_DQS_DP<7>")
	)
	(segment
		(start 147.887436 -22.6314)
		(end 147.62988 -22.888956)
		(width 0.1651)
		(layer "B.Cu")
		(net "M_G_DQS_DP<7>")
	)
	(segment
		(start 147.887436 -21.4122)
		(end 147.887436 -22.6314)
		(width 0.1651)
		(layer "B.Cu")
		(net "M_G_DQS_DP<7>")
	)
	(segment
		(start 147.84959 -20.224496)
		(end 147.84959 -21.374354)
		(width 0.1651)
		(layer "B.Cu")
		(net "M_G_DQS_DP<7>")
	)
	(segment
		(start 147.84959 -21.374354)
		(end 147.887436 -21.4122)
		(width 0.1651)
		(layer "B.Cu")
		(net "M_G_DQS_DP<7>")
	)
	(segment
		(start 147.62988 -22.888956)
		(end 147.387564 -22.888956)
		(width 0.1651)
		(layer "B.Cu")
		(net "M_G_DQS_DP<7>")
	)
	(segment
		(start 147.849336 -20.224242)
		(end 147.84959 -20.224496)
		(width 0.1651)
		(layer "B.Cu")
		(net "M_G_DQS_DP<7>")
	)
	(segment
		(start 147.688808 -24.83104)
		(end 147.218908 -24.36114)
		(width 0.14224)
		(layer "In2.Cu")
		(net "M_G_DQS_DP<7>")
	)
	(segment
		(start 122.445018 -57.685686)
		(end 122.451368 -57.675018)
		(width 0.0889)
		(layer "In2.Cu")
		(net "M_G_DQS_DP<7>")
	)
	(segment
		(start 147.688808 -37.42436)
		(end 147.688808 -24.83104)
		(width 0.14224)
		(layer "In2.Cu")
		(net "M_G_DQS_DP<7>")
	)
	(segment
		(start 121.933208 -58.043064)
		(end 121.998486 -57.977786)
		(width 0.0889)
		(layer "In2.Cu")
		(net "M_G_DQS_DP<7>")
	)
	(segment
		(start 124.695966 -51.9049)
		(end 124.711714 -51.889152)
		(width 0.0889)
		(layer "In2.Cu")
		(net "M_G_DQS_DP<7>")
	)
	(segment
		(start 147.825968 -23.7236)
		(end 147.825968 -23.32736)
		(width 0.14224)
		(layer "In2.Cu")
		(net "M_G_DQS_DP<7>")
	)
	(segment
		(start 147.419568 -24.003)
		(end 147.546568 -24.003)
		(width 0.14224)
		(layer "In2.Cu")
		(net "M_G_DQS_DP<7>")
	)
	(segment
		(start 122.445018 -56.695086)
		(end 122.451368 -56.684418)
		(width 0.0889)
		(layer "In2.Cu")
		(net "M_G_DQS_DP<7>")
	)
	(segment
		(start 124.640594 -51.9049)
		(end 124.695966 -51.9049)
		(width 0.0889)
		(layer "In2.Cu")
		(net "M_G_DQS_DP<7>")
	)
	(segment
		(start 124.711714 -51.889152)
		(end 129.19583 -47.405036)
		(width 0.14224)
		(layer "In2.Cu")
		(net "M_G_DQS_DP<7>")
	)
	(segment
		(start 147.546568 -24.003)
		(end 147.825968 -23.7236)
		(width 0.14224)
		(layer "In2.Cu")
		(net "M_G_DQS_DP<7>")
	)
	(segment
		(start 131.834128 -46.01464)
		(end 136.482582 -46.01464)
		(width 0.14224)
		(layer "In2.Cu")
		(net "M_G_DQS_DP<7>")
	)
	(segment
		(start 143.727932 -38.76929)
		(end 146.343878 -38.76929)
		(width 0.14224)
		(layer "In2.Cu")
		(net "M_G_DQS_DP<7>")
	)
	(segment
		(start 129.19583 -47.405036)
		(end 130.443732 -47.405036)
		(width 0.14224)
		(layer "In2.Cu")
		(net "M_G_DQS_DP<7>")
	)
	(segment
		(start 122.440192 -56.703722)
		(end 122.445018 -56.695086)
		(width 0.0889)
		(layer "In2.Cu")
		(net "M_G_DQS_DP<7>")
	)
	(segment
		(start 122.780552 -54.513734)
		(end 122.813318 -54.513734)
		(width 0.0889)
		(layer "In2.Cu")
		(net "M_G_DQS_DP<7>")
	)
	(segment
		(start 130.443732 -47.405036)
		(end 131.834128 -46.01464)
		(width 0.14224)
		(layer "In2.Cu")
		(net "M_G_DQS_DP<7>")
	)
	(segment
		(start 123.455938 -53.07838)
		(end 123.480068 -53.065172)
		(width 0.0889)
		(layer "In2.Cu")
		(net "M_G_DQS_DP<7>")
	)
	(segment
		(start 147.218908 -24.20366)
		(end 147.419568 -24.003)
		(width 0.14224)
		(layer "In2.Cu")
		(net "M_G_DQS_DP<7>")
	)
	(segment
		(start 123.480068 -53.065426)
		(end 124.640594 -51.9049)
		(width 0.0889)
		(layer "In2.Cu")
		(net "M_G_DQS_DP<7>")
	)
	(segment
		(start 146.343878 -38.76929)
		(end 147.688808 -37.42436)
		(width 0.14224)
		(layer "In2.Cu")
		(net "M_G_DQS_DP<7>")
	)
	(segment
		(start 123.480068 -53.065172)
		(end 123.480068 -53.065426)
		(width 0.0889)
		(layer "In2.Cu")
		(net "M_G_DQS_DP<7>")
	)
	(segment
		(start 147.387564 -22.888956)
		(end 148.198332 -22.078188)
		(width 0.14224)
		(layer "In2.Cu")
		(net "M_G_DQS_DP<7>")
	)
	(segment
		(start 147.218908 -24.36114)
		(end 147.218908 -24.20366)
		(width 0.14224)
		(layer "In2.Cu")
		(net "M_G_DQS_DP<7>")
	)
	(segment
		(start 121.933208 -58.381138)
		(end 121.933208 -58.043064)
		(width 0.0889)
		(layer "In2.Cu")
		(net "M_G_DQS_DP<7>")
	)
	(segment
		(start 147.825968 -23.32736)
		(end 147.387564 -22.888956)
		(width 0.14224)
		(layer "In2.Cu")
		(net "M_G_DQS_DP<7>")
	)
	(segment
		(start 148.198332 -22.078188)
		(end 148.198332 -18.169128)
		(width 0.14224)
		(layer "In2.Cu")
		(net "M_G_DQS_DP<7>")
	)
	(segment
		(start 136.482582 -46.01464)
		(end 143.727932 -38.76929)
		(width 0.14224)
		(layer "In2.Cu")
		(net "M_G_DQS_DP<7>")
	)
	(segment
		(start 122.445018 -55.704486)
		(end 122.451368 -55.693818)
		(width 0.0889)
		(layer "In2.Cu")
		(net "M_G_DQS_DP<7>")
	)
	(segment
		(start 122.440192 -55.713122)
		(end 122.445018 -55.704486)
		(width 0.0889)
		(layer "In2.Cu")
		(net "M_G_DQS_DP<7>")
	)
	(segment
		(start 148.198332 -18.169128)
		(end 147.387564 -17.35836)
		(width 0.14224)
		(layer "In2.Cu")
		(net "M_G_DQS_DP<7>")
	)
	(arc
		(start 122.445018 -55.113936)
		(mid 122.391548 -54.918873)
		(end 122.440192 -54.722522)
		(width 0.0889)
		(layer "In2.Cu")
		(net "M_G_DQS_DP<7>")
	)
	(arc
		(start 122.813318 -54.513734)
		(mid 123.308795 -54.209291)
		(end 123.303538 -53.627782)
		(width 0.0889)
		(layer "In2.Cu")
		(net "M_G_DQS_DP<7>")
	)
	(arc
		(start 122.451368 -55.693818)
		(mid 122.524166 -55.403055)
		(end 122.445018 -55.113936)
		(width 0.0889)
		(layer "In2.Cu")
		(net "M_G_DQS_DP<7>")
	)
	(arc
		(start 122.451368 -56.684418)
		(mid 122.524166 -56.393655)
		(end 122.445018 -56.104536)
		(width 0.0889)
		(layer "In2.Cu")
		(net "M_G_DQS_DP<7>")
	)
	(arc
		(start 122.440192 -54.722522)
		(mid 122.455404 -54.696912)
		(end 122.47245 -54.672484)
		(width 0.0889)
		(layer "In2.Cu")
		(net "M_G_DQS_DP<7>")
	)
	(arc
		(start 122.445018 -57.095136)
		(mid 122.391548 -56.900073)
		(end 122.440192 -56.703722)
		(width 0.0889)
		(layer "In2.Cu")
		(net "M_G_DQS_DP<7>")
	)
	(arc
		(start 122.445018 -56.104536)
		(mid 122.391548 -55.909473)
		(end 122.440192 -55.713122)
		(width 0.0889)
		(layer "In2.Cu")
		(net "M_G_DQS_DP<7>")
	)
	(arc
		(start 122.451368 -57.675018)
		(mid 122.524166 -57.384255)
		(end 122.445018 -57.095136)
		(width 0.0889)
		(layer "In2.Cu")
		(net "M_G_DQS_DP<7>")
	)
	(arc
		(start 123.303538 -53.627782)
		(mid 123.250005 -53.427774)
		(end 123.303538 -53.227732)
		(width 0.0889)
		(layer "In2.Cu")
		(net "M_G_DQS_DP<7>")
	)
	(arc
		(start 121.998486 -57.977786)
		(mid 122.256623 -57.885032)
		(end 122.445018 -57.685686)
		(width 0.0889)
		(layer "In2.Cu")
		(net "M_G_DQS_DP<7>")
	)
	(arc
		(start 122.47245 -54.672484)
		(mid 122.608424 -54.558026)
		(end 122.780552 -54.513734)
		(width 0.0889)
		(layer "In2.Cu")
		(net "M_G_DQS_DP<7>")
	)
	(arc
		(start 123.303538 -53.227732)
		(mid 123.369526 -53.14264)
		(end 123.455938 -53.07838)
		(width 0.0889)
		(layer "In2.Cu")
		(net "M_G_DQS_DP<7>")
	)
	(segment
		(start 138.499342 -20.023582)
		(end 138.499596 -20.023328)
		(width 0.1651)
		(layer "F.Cu")
		(net "M_G_DQS_DP<6>")
	)
	(segment
		(start 138.537442 -17.6022)
		(end 138.293602 -17.35836)
		(width 0.1651)
		(layer "F.Cu")
		(net "M_G_DQS_DP<6>")
	)
	(segment
		(start 138.537442 -18.9738)
		(end 138.537442 -17.6022)
		(width 0.1651)
		(layer "F.Cu")
		(net "M_G_DQS_DP<6>")
	)
	(segment
		(start 138.499596 -19.011646)
		(end 138.537442 -18.9738)
		(width 0.1651)
		(layer "F.Cu")
		(net "M_G_DQS_DP<6>")
	)
	(segment
		(start 138.293602 -17.35836)
		(end 138.03757 -17.35836)
		(width 0.1651)
		(layer "F.Cu")
		(net "M_G_DQS_DP<6>")
	)
	(segment
		(start 117.353842 -57.390538)
		(end 116.782342 -57.390538)
		(width 0.1016)
		(layer "F.Cu")
		(net "M_G_DQS_DP<6>")
	)
	(segment
		(start 138.499596 -20.023328)
		(end 138.499596 -19.011646)
		(width 0.1651)
		(layer "F.Cu")
		(net "M_G_DQS_DP<6>")
	)
	(via
		(at 116.782342 -57.390538)
		(size 0.508)
		(drill 0.254)
		(layers "F.Cu" "B.Cu")
		(net "M_G_DQS_DP<6>")
	)
	(via
		(at 138.03757 -22.888956)
		(size 0.508)
		(drill 0.254)
		(layers "F.Cu" "B.Cu")
		(net "M_G_DQS_DP<6>")
	)
	(via
		(at 138.03757 -17.35836)
		(size 0.508)
		(drill 0.254)
		(layers "F.Cu" "B.Cu")
		(net "M_G_DQS_DP<6>")
	)
	(segment
		(start 138.432032 -22.737064)
		(end 138.279886 -22.888956)
		(width 0.1651)
		(layer "B.Cu")
		(net "M_G_DQS_DP<6>")
	)
	(segment
		(start 138.537442 -21.4122)
		(end 138.537442 -22.6314)
		(width 0.1651)
		(layer "B.Cu")
		(net "M_G_DQS_DP<6>")
	)
	(segment
		(start 138.499342 -20.224242)
		(end 138.499596 -20.224496)
		(width 0.1651)
		(layer "B.Cu")
		(net "M_G_DQS_DP<6>")
	)
	(segment
		(start 138.499596 -21.374354)
		(end 138.537442 -21.4122)
		(width 0.1651)
		(layer "B.Cu")
		(net "M_G_DQS_DP<6>")
	)
	(segment
		(start 138.499596 -20.224496)
		(end 138.499596 -21.374354)
		(width 0.1651)
		(layer "B.Cu")
		(net "M_G_DQS_DP<6>")
	)
	(segment
		(start 138.537442 -22.6314)
		(end 138.432032 -22.737064)
		(width 0.1651)
		(layer "B.Cu")
		(net "M_G_DQS_DP<6>")
	)
	(segment
		(start 138.279886 -22.888956)
		(end 138.03757 -22.888956)
		(width 0.1651)
		(layer "B.Cu")
		(net "M_G_DQS_DP<6>")
	)
	(segment
		(start 117.711982 -48.4378)
		(end 117.711982 -48.415702)
		(width 0.0889)
		(layer "In2.Cu")
		(net "M_G_DQS_DP<6>")
	)
	(segment
		(start 117.826282 -47.7774)
		(end 117.711982 -47.6631)
		(width 0.14224)
		(layer "In2.Cu")
		(net "M_G_DQS_DP<6>")
	)
	(segment
		(start 117.826282 -45.3644)
		(end 117.711982 -45.2501)
		(width 0.14224)
		(layer "In2.Cu")
		(net "M_G_DQS_DP<6>")
	)
	(segment
		(start 117.711982 -48.415702)
		(end 117.711982 -48.1457)
		(width 0.14224)
		(layer "In2.Cu")
		(net "M_G_DQS_DP<6>")
	)
	(segment
		(start 137.861294 -24.201374)
		(end 138.034268 -24.0284)
		(width 0.14224)
		(layer "In2.Cu")
		(net "M_G_DQS_DP<6>")
	)
	(segment
		(start 117.826282 -44.7802)
		(end 117.826282 -44.5262)
		(width 0.14224)
		(layer "In2.Cu")
		(net "M_G_DQS_DP<6>")
	)
	(segment
		(start 138.221974 -24.0284)
		(end 138.362944 -23.887176)
		(width 0.14224)
		(layer "In2.Cu")
		(net "M_G_DQS_DP<6>")
	)
	(segment
		(start 132.621528 -36.99764)
		(end 138.822684 -30.796484)
		(width 0.14224)
		(layer "In2.Cu")
		(net "M_G_DQS_DP<6>")
	)
	(segment
		(start 117.711982 -45.9867)
		(end 117.711982 -45.7327)
		(width 0.14224)
		(layer "In2.Cu")
		(net "M_G_DQS_DP<6>")
	)
	(segment
		(start 117.711982 -47.2821)
		(end 117.826282 -47.1678)
		(width 0.14224)
		(layer "In2.Cu")
		(net "M_G_DQS_DP<6>")
	)
	(segment
		(start 117.711982 -45.2501)
		(end 117.711982 -44.8945)
		(width 0.14224)
		(layer "In2.Cu")
		(net "M_G_DQS_DP<6>")
	)
	(segment
		(start 117.168168 -51.182016)
		(end 117.168168 -50.7746)
		(width 0.0889)
		(layer "In2.Cu")
		(net "M_G_DQS_DP<6>")
	)
	(segment
		(start 117.826282 -46.355)
		(end 117.826282 -46.101)
		(width 0.14224)
		(layer "In2.Cu")
		(net "M_G_DQS_DP<6>")
	)
	(segment
		(start 117.331998 -54.03088)
		(end 117.331998 -51.345846)
		(width 0.0889)
		(layer "In2.Cu")
		(net "M_G_DQS_DP<6>")
	)
	(segment
		(start 117.711982 -46.4693)
		(end 117.826282 -46.355)
		(width 0.14224)
		(layer "In2.Cu")
		(net "M_G_DQS_DP<6>")
	)
	(segment
		(start 138.822684 -30.796484)
		(end 138.822684 -25.481534)
		(width 0.14224)
		(layer "In2.Cu")
		(net "M_G_DQS_DP<6>")
	)
	(segment
		(start 116.939568 -50.2158)
		(end 117.672612 -49.482756)
		(width 0.0889)
		(layer "In2.Cu")
		(net "M_G_DQS_DP<6>")
	)
	(segment
		(start 117.826282 -45.6184)
		(end 117.826282 -45.3644)
		(width 0.14224)
		(layer "In2.Cu")
		(net "M_G_DQS_DP<6>")
	)
	(segment
		(start 117.826282 -44.5262)
		(end 117.711982 -44.4119)
		(width 0.14224)
		(layer "In2.Cu")
		(net "M_G_DQS_DP<6>")
	)
	(segment
		(start 117.89156 -43.574462)
		(end 118.053104 -43.574462)
		(width 0.14224)
		(layer "In2.Cu")
		(net "M_G_DQS_DP<6>")
	)
	(segment
		(start 138.848338 -22.078188)
		(end 138.848338 -18.169128)
		(width 0.14224)
		(layer "In2.Cu")
		(net "M_G_DQS_DP<6>")
	)
	(segment
		(start 138.822684 -25.481534)
		(end 137.861294 -24.520144)
		(width 0.14224)
		(layer "In2.Cu")
		(net "M_G_DQS_DP<6>")
	)
	(segment
		(start 138.501374 -23.35276)
		(end 138.03757 -22.888956)
		(width 0.14224)
		(layer "In2.Cu")
		(net "M_G_DQS_DP<6>")
	)
	(segment
		(start 117.294152 -54.713886)
		(end 117.450362 -54.444646)
		(width 0.0889)
		(layer "In2.Cu")
		(net "M_G_DQS_DP<6>")
	)
	(segment
		(start 138.31062 -22.615652)
		(end 138.760962 -22.165564)
		(width 0.14224)
		(layer "In2.Cu")
		(net "M_G_DQS_DP<6>")
	)
	(segment
		(start 117.711982 -43.75404)
		(end 117.89156 -43.574462)
		(width 0.14224)
		(layer "In2.Cu")
		(net "M_G_DQS_DP<6>")
	)
	(segment
		(start 116.767356 -56.990488)
		(end 116.803932 -56.990488)
		(width 0.0889)
		(layer "In2.Cu")
		(net "M_G_DQS_DP<6>")
	)
	(segment
		(start 117.711982 -44.4119)
		(end 117.711982 -43.75404)
		(width 0.14224)
		(layer "In2.Cu")
		(net "M_G_DQS_DP<6>")
	)
	(segment
		(start 116.435632 -57.590436)
		(end 116.430806 -57.5818)
		(width 0.0889)
		(layer "In2.Cu")
		(net "M_G_DQS_DP<6>")
	)
	(segment
		(start 117.711982 -45.7327)
		(end 117.826282 -45.6184)
		(width 0.14224)
		(layer "In2.Cu")
		(net "M_G_DQS_DP<6>")
	)
	(segment
		(start 117.711982 -47.6631)
		(end 117.711982 -47.2821)
		(width 0.14224)
		(layer "In2.Cu")
		(net "M_G_DQS_DP<6>")
	)
	(segment
		(start 138.501374 -23.749)
		(end 138.501374 -23.35276)
		(width 0.14224)
		(layer "In2.Cu")
		(net "M_G_DQS_DP<6>")
	)
	(segment
		(start 138.03757 -22.888956)
		(end 138.31062 -22.615652)
		(width 0.14224)
		(layer "In2.Cu")
		(net "M_G_DQS_DP<6>")
	)
	(segment
		(start 118.053104 -43.574462)
		(end 118.232936 -43.39463)
		(width 0.14224)
		(layer "In2.Cu")
		(net "M_G_DQS_DP<6>")
	)
	(segment
		(start 117.826282 -47.1678)
		(end 117.826282 -46.9138)
		(width 0.14224)
		(layer "In2.Cu")
		(net "M_G_DQS_DP<6>")
	)
	(segment
		(start 117.168168 -50.7746)
		(end 116.939568 -50.546)
		(width 0.0889)
		(layer "In2.Cu")
		(net "M_G_DQS_DP<6>")
	)
	(segment
		(start 118.232936 -43.39463)
		(end 118.232936 -43.233086)
		(width 0.14224)
		(layer "In2.Cu")
		(net "M_G_DQS_DP<6>")
	)
	(segment
		(start 118.232936 -43.233086)
		(end 124.468382 -36.99764)
		(width 0.14224)
		(layer "In2.Cu")
		(net "M_G_DQS_DP<6>")
	)
	(segment
		(start 117.826282 -46.9138)
		(end 117.711982 -46.7995)
		(width 0.14224)
		(layer "In2.Cu")
		(net "M_G_DQS_DP<6>")
	)
	(segment
		(start 117.672612 -49.482756)
		(end 117.672612 -48.47717)
		(width 0.0889)
		(layer "In2.Cu")
		(net "M_G_DQS_DP<6>")
	)
	(segment
		(start 124.468382 -36.99764)
		(end 132.621528 -36.99764)
		(width 0.14224)
		(layer "In2.Cu")
		(net "M_G_DQS_DP<6>")
	)
	(segment
		(start 116.782342 -57.728612)
		(end 116.72443 -57.786524)
		(width 0.0889)
		(layer "In2.Cu")
		(net "M_G_DQS_DP<6>")
	)
	(segment
		(start 117.331998 -51.345846)
		(end 117.168168 -51.182016)
		(width 0.0889)
		(layer "In2.Cu")
		(net "M_G_DQS_DP<6>")
	)
	(segment
		(start 137.861294 -24.520144)
		(end 137.861294 -24.201374)
		(width 0.14224)
		(layer "In2.Cu")
		(net "M_G_DQS_DP<6>")
	)
	(segment
		(start 116.939568 -50.546)
		(end 116.939568 -50.2158)
		(width 0.0889)
		(layer "In2.Cu")
		(net "M_G_DQS_DP<6>")
	)
	(segment
		(start 117.672612 -48.47717)
		(end 117.711982 -48.4378)
		(width 0.0889)
		(layer "In2.Cu")
		(net "M_G_DQS_DP<6>")
	)
	(segment
		(start 117.711982 -48.1457)
		(end 117.826282 -48.0314)
		(width 0.14224)
		(layer "In2.Cu")
		(net "M_G_DQS_DP<6>")
	)
	(segment
		(start 117.450362 -54.149244)
		(end 117.331998 -54.03088)
		(width 0.0889)
		(layer "In2.Cu")
		(net "M_G_DQS_DP<6>")
	)
	(segment
		(start 117.826282 -46.101)
		(end 117.711982 -45.9867)
		(width 0.14224)
		(layer "In2.Cu")
		(net "M_G_DQS_DP<6>")
	)
	(segment
		(start 117.450362 -54.444646)
		(end 117.450362 -54.149244)
		(width 0.0889)
		(layer "In2.Cu")
		(net "M_G_DQS_DP<6>")
	)
	(segment
		(start 138.848338 -18.169128)
		(end 138.03757 -17.35836)
		(width 0.14224)
		(layer "In2.Cu")
		(net "M_G_DQS_DP<6>")
	)
	(segment
		(start 117.711982 -46.7995)
		(end 117.711982 -46.4693)
		(width 0.14224)
		(layer "In2.Cu")
		(net "M_G_DQS_DP<6>")
	)
	(segment
		(start 138.362944 -23.887176)
		(end 138.501374 -23.749)
		(width 0.14224)
		(layer "In2.Cu")
		(net "M_G_DQS_DP<6>")
	)
	(segment
		(start 117.826282 -48.0314)
		(end 117.826282 -47.7774)
		(width 0.14224)
		(layer "In2.Cu")
		(net "M_G_DQS_DP<6>")
	)
	(segment
		(start 117.711982 -44.8945)
		(end 117.826282 -44.7802)
		(width 0.14224)
		(layer "In2.Cu")
		(net "M_G_DQS_DP<6>")
	)
	(segment
		(start 116.782342 -57.390538)
		(end 116.782342 -57.728612)
		(width 0.0889)
		(layer "In2.Cu")
		(net "M_G_DQS_DP<6>")
	)
	(segment
		(start 138.760962 -22.165564)
		(end 138.848338 -22.078188)
		(width 0.14224)
		(layer "In2.Cu")
		(net "M_G_DQS_DP<6>")
	)
	(segment
		(start 138.034268 -24.0284)
		(end 138.221974 -24.0284)
		(width 0.14224)
		(layer "In2.Cu")
		(net "M_G_DQS_DP<6>")
	)
	(arc
		(start 116.72443 -57.786524)
		(mid 116.557529 -57.721624)
		(end 116.435632 -57.590436)
		(width 0.0889)
		(layer "In2.Cu")
		(net "M_G_DQS_DP<6>")
	)
	(arc
		(start 117.294152 -56.104536)
		(mid 117.240653 -55.904638)
		(end 117.294152 -55.70474)
		(width 0.0889)
		(layer "In2.Cu")
		(net "M_G_DQS_DP<6>")
	)
	(arc
		(start 116.430806 -57.5818)
		(mid 116.382051 -57.385448)
		(end 116.435632 -57.190386)
		(width 0.0889)
		(layer "In2.Cu")
		(net "M_G_DQS_DP<6>")
	)
	(arc
		(start 116.435632 -57.190386)
		(mid 116.575711 -57.04765)
		(end 116.767356 -56.990488)
		(width 0.0889)
		(layer "In2.Cu")
		(net "M_G_DQS_DP<6>")
	)
	(arc
		(start 117.294152 -55.11419)
		(mid 117.240526 -54.914038)
		(end 117.294152 -54.713886)
		(width 0.0889)
		(layer "In2.Cu")
		(net "M_G_DQS_DP<6>")
	)
	(arc
		(start 117.294152 -55.70474)
		(mid 117.373123 -55.409482)
		(end 117.294152 -55.11419)
		(width 0.0889)
		(layer "In2.Cu")
		(net "M_G_DQS_DP<6>")
	)
	(arc
		(start 116.803932 -56.990488)
		(mid 117.299409 -56.686045)
		(end 117.294152 -56.104536)
		(width 0.0889)
		(layer "In2.Cu")
		(net "M_G_DQS_DP<6>")
	)
	(segment
		(start 129.187448 -17.6022)
		(end 128.943608 -17.35836)
		(width 0.1651)
		(layer "F.Cu")
		(net "M_G_DQS_DP<5>")
	)
	(segment
		(start 129.187448 -18.9738)
		(end 129.187448 -17.6022)
		(width 0.1651)
		(layer "F.Cu")
		(net "M_G_DQS_DP<5>")
	)
	(segment
		(start 129.149602 -19.011646)
		(end 129.187448 -18.9738)
		(width 0.1651)
		(layer "F.Cu")
		(net "M_G_DQS_DP<5>")
	)
	(segment
		(start 112.202722 -57.390538)
		(end 111.631222 -57.390538)
		(width 0.1016)
		(layer "F.Cu")
		(net "M_G_DQS_DP<5>")
	)
	(segment
		(start 128.943608 -17.35836)
		(end 128.687576 -17.35836)
		(width 0.1651)
		(layer "F.Cu")
		(net "M_G_DQS_DP<5>")
	)
	(segment
		(start 129.149348 -20.023582)
		(end 129.149602 -20.023328)
		(width 0.1651)
		(layer "F.Cu")
		(net "M_G_DQS_DP<5>")
	)
	(segment
		(start 129.149602 -20.023328)
		(end 129.149602 -19.011646)
		(width 0.1651)
		(layer "F.Cu")
		(net "M_G_DQS_DP<5>")
	)
	(via
		(at 128.687576 -22.888956)
		(size 0.508)
		(drill 0.254)
		(layers "F.Cu" "B.Cu")
		(net "M_G_DQS_DP<5>")
	)
	(via
		(at 111.631222 -57.390538)
		(size 0.508)
		(drill 0.254)
		(layers "F.Cu" "B.Cu")
		(net "M_G_DQS_DP<5>")
	)
	(via
		(at 128.687576 -17.35836)
		(size 0.508)
		(drill 0.254)
		(layers "F.Cu" "B.Cu")
		(net "M_G_DQS_DP<5>")
	)
	(segment
		(start 129.149602 -20.224496)
		(end 129.149602 -21.374354)
		(width 0.1651)
		(layer "B.Cu")
		(net "M_G_DQS_DP<5>")
	)
	(segment
		(start 128.929892 -22.888956)
		(end 128.687576 -22.888956)
		(width 0.1651)
		(layer "B.Cu")
		(net "M_G_DQS_DP<5>")
	)
	(segment
		(start 129.149602 -21.374354)
		(end 129.187448 -21.4122)
		(width 0.1651)
		(layer "B.Cu")
		(net "M_G_DQS_DP<5>")
	)
	(segment
		(start 129.187448 -21.4122)
		(end 129.187448 -22.6314)
		(width 0.1651)
		(layer "B.Cu")
		(net "M_G_DQS_DP<5>")
	)
	(segment
		(start 129.187448 -22.6314)
		(end 128.929892 -22.888956)
		(width 0.1651)
		(layer "B.Cu")
		(net "M_G_DQS_DP<5>")
	)
	(segment
		(start 129.149348 -20.224242)
		(end 129.149602 -20.224496)
		(width 0.1651)
		(layer "B.Cu")
		(net "M_G_DQS_DP<5>")
	)
	(segment
		(start 128.161288 -25.39492)
		(end 128.161288 -25.159208)
		(width 0.14224)
		(layer "In2.Cu")
		(net "M_G_DQS_DP<5>")
	)
	(segment
		(start 110.09884 -49.240186)
		(end 110.09884 -47.102268)
		(width 0.0889)
		(layer "In2.Cu")
		(net "M_G_DQS_DP<5>")
	)
	(segment
		(start 118.295674 -29.53004)
		(end 127.675894 -29.53004)
		(width 0.14224)
		(layer "In2.Cu")
		(net "M_G_DQS_DP<5>")
	)
	(segment
		(start 128.318768 -25.8064)
		(end 128.318768 -25.5524)
		(width 0.14224)
		(layer "In2.Cu")
		(net "M_G_DQS_DP<5>")
	)
	(segment
		(start 112.229392 -54.564788)
		(end 112.229392 -53.08092)
		(width 0.0889)
		(layer "In2.Cu")
		(net "M_G_DQS_DP<5>")
	)
	(segment
		(start 112.143032 -54.714394)
		(end 112.229392 -54.564788)
		(width 0.0889)
		(layer "In2.Cu")
		(net "M_G_DQS_DP<5>")
	)
	(segment
		(start 129.207768 -23.409148)
		(end 128.687576 -22.888956)
		(width 0.14224)
		(layer "In2.Cu")
		(net "M_G_DQS_DP<5>")
	)
	(segment
		(start 128.161288 -25.96388)
		(end 128.318768 -25.8064)
		(width 0.14224)
		(layer "In2.Cu")
		(net "M_G_DQS_DP<5>")
	)
	(segment
		(start 111.079026 -50.220372)
		(end 110.09884 -49.240186)
		(width 0.0889)
		(layer "In2.Cu")
		(net "M_G_DQS_DP<5>")
	)
	(segment
		(start 111.620046 -56.990488)
		(end 111.652812 -56.990488)
		(width 0.0889)
		(layer "In2.Cu")
		(net "M_G_DQS_DP<5>")
	)
	(segment
		(start 128.5113 -24.267668)
		(end 128.725168 -24.0538)
		(width 0.14224)
		(layer "In2.Cu")
		(net "M_G_DQS_DP<5>")
	)
	(segment
		(start 129.498344 -18.169128)
		(end 128.687576 -17.35836)
		(width 0.14224)
		(layer "In2.Cu")
		(net "M_G_DQS_DP<5>")
	)
	(segment
		(start 128.161288 -29.044646)
		(end 128.161288 -25.96388)
		(width 0.14224)
		(layer "In2.Cu")
		(net "M_G_DQS_DP<5>")
	)
	(segment
		(start 111.079026 -51.930554)
		(end 111.079026 -50.220372)
		(width 0.0889)
		(layer "In2.Cu")
		(net "M_G_DQS_DP<5>")
	)
	(segment
		(start 129.207768 -23.876254)
		(end 129.207768 -23.409148)
		(width 0.14224)
		(layer "In2.Cu")
		(net "M_G_DQS_DP<5>")
	)
	(segment
		(start 129.030222 -24.0538)
		(end 129.207768 -23.876254)
		(width 0.14224)
		(layer "In2.Cu")
		(net "M_G_DQS_DP<5>")
	)
	(segment
		(start 128.725168 -24.0538)
		(end 129.030222 -24.0538)
		(width 0.14224)
		(layer "In2.Cu")
		(net "M_G_DQS_DP<5>")
	)
	(segment
		(start 111.834168 -57.593484)
		(end 111.834168 -57.682384)
		(width 0.0889)
		(layer "In2.Cu")
		(net "M_G_DQS_DP<5>")
	)
	(segment
		(start 110.09884 -47.102268)
		(end 110.13821 -47.062898)
		(width 0.0889)
		(layer "In2.Cu")
		(net "M_G_DQS_DP<5>")
	)
	(segment
		(start 128.687576 -22.888956)
		(end 129.498344 -22.078188)
		(width 0.14224)
		(layer "In2.Cu")
		(net "M_G_DQS_DP<5>")
	)
	(segment
		(start 110.13821 -37.687504)
		(end 118.295674 -29.53004)
		(width 0.14224)
		(layer "In2.Cu")
		(net "M_G_DQS_DP<5>")
	)
	(segment
		(start 127.675894 -29.53004)
		(end 128.161288 -29.044646)
		(width 0.14224)
		(layer "In2.Cu")
		(net "M_G_DQS_DP<5>")
	)
	(segment
		(start 112.229392 -53.08092)
		(end 111.079026 -51.930554)
		(width 0.0889)
		(layer "In2.Cu")
		(net "M_G_DQS_DP<5>")
	)
	(segment
		(start 110.13821 -47.062898)
		(end 110.13821 -37.687504)
		(width 0.14224)
		(layer "In2.Cu")
		(net "M_G_DQS_DP<5>")
	)
	(segment
		(start 128.5113 -24.809196)
		(end 128.5113 -24.267668)
		(width 0.14224)
		(layer "In2.Cu")
		(net "M_G_DQS_DP<5>")
	)
	(segment
		(start 111.631222 -57.390538)
		(end 111.834168 -57.593484)
		(width 0.0889)
		(layer "In2.Cu")
		(net "M_G_DQS_DP<5>")
	)
	(segment
		(start 129.498344 -22.078188)
		(end 129.498344 -18.169128)
		(width 0.14224)
		(layer "In2.Cu")
		(net "M_G_DQS_DP<5>")
	)
	(segment
		(start 128.318768 -25.5524)
		(end 128.161288 -25.39492)
		(width 0.14224)
		(layer "In2.Cu")
		(net "M_G_DQS_DP<5>")
	)
	(segment
		(start 128.161288 -25.159208)
		(end 128.5113 -24.809196)
		(width 0.14224)
		(layer "In2.Cu")
		(net "M_G_DQS_DP<5>")
	)
	(arc
		(start 112.143032 -55.70474)
		(mid 112.222163 -55.409338)
		(end 112.143032 -55.113936)
		(width 0.0889)
		(layer "In2.Cu")
		(net "M_G_DQS_DP<5>")
	)
	(arc
		(start 112.089438 -54.914038)
		(mid 112.103149 -54.810708)
		(end 112.143032 -54.714394)
		(width 0.0889)
		(layer "In2.Cu")
		(net "M_G_DQS_DP<5>")
	)
	(arc
		(start 111.652812 -56.990488)
		(mid 112.148289 -56.686045)
		(end 112.143032 -56.104536)
		(width 0.0889)
		(layer "In2.Cu")
		(net "M_G_DQS_DP<5>")
	)
	(arc
		(start 112.143032 -55.113936)
		(mid 112.103078 -55.017512)
		(end 112.089438 -54.914038)
		(width 0.0889)
		(layer "In2.Cu")
		(net "M_G_DQS_DP<5>")
	)
	(arc
		(start 111.337344 -57.662318)
		(mid 111.262263 -57.235302)
		(end 111.620046 -56.990488)
		(width 0.0889)
		(layer "In2.Cu")
		(net "M_G_DQS_DP<5>")
	)
	(arc
		(start 111.749078 -57.767728)
		(mid 111.662383 -57.78826)
		(end 111.57331 -57.786524)
		(width 0.0889)
		(layer "In2.Cu")
		(net "M_G_DQS_DP<5>")
	)
	(arc
		(start 111.834168 -57.682384)
		(mid 111.800883 -57.734275)
		(end 111.749078 -57.767728)
		(width 0.0889)
		(layer "In2.Cu")
		(net "M_G_DQS_DP<5>")
	)
	(arc
		(start 112.143032 -56.104536)
		(mid 112.089533 -55.904638)
		(end 112.143032 -55.70474)
		(width 0.0889)
		(layer "In2.Cu")
		(net "M_G_DQS_DP<5>")
	)
	(arc
		(start 111.57331 -57.786524)
		(mid 111.444706 -57.744615)
		(end 111.337344 -57.662318)
		(width 0.0889)
		(layer "In2.Cu")
		(net "M_G_DQS_DP<5>")
	)
	(segment
		(start 109.175042 -50.292)
		(end 109.175042 -50.0888)
		(width 0.0889)
		(layer "F.Cu")
		(net "M_G_DQS_DP<4>")
	)
	(segment
		(start 119.936768 -23.054056)
		(end 119.771668 -22.888956)
		(width 0.1651)
		(layer "F.Cu")
		(net "M_G_DQS_DP<4>")
	)
	(segment
		(start 108.768896 -53.636672)
		(end 108.663486 -53.742082)
		(width 0.0889)
		(layer "F.Cu")
		(net "M_G_DQS_DP<4>")
	)
	(segment
		(start 109.378242 -49.8856)
		(end 109.378242 -40.479218)
		(width 0.1016)
		(layer "F.Cu")
		(net "M_G_DQS_DP<4>")
	)
	(segment
		(start 119.8372 -17.6022)
		(end 119.59336 -17.35836)
		(width 0.1651)
		(layer "F.Cu")
		(net "M_G_DQS_DP<4>")
	)
	(segment
		(start 119.799354 -20.023582)
		(end 119.799354 -19.011646)
		(width 0.1651)
		(layer "F.Cu")
		(net "M_G_DQS_DP<4>")
	)
	(segment
		(start 119.8372 -18.9738)
		(end 119.8372 -17.6022)
		(width 0.1651)
		(layer "F.Cu")
		(net "M_G_DQS_DP<4>")
	)
	(segment
		(start 119.600726 -24.0284)
		(end 119.936768 -23.692358)
		(width 0.1651)
		(layer "F.Cu")
		(net "M_G_DQS_DP<4>")
	)
	(segment
		(start 109.378242 -40.479218)
		(end 109.451648 -40.405812)
		(width 0.1016)
		(layer "F.Cu")
		(net "M_G_DQS_DP<4>")
	)
	(segment
		(start 119.799354 -19.011646)
		(end 119.8372 -18.9738)
		(width 0.1651)
		(layer "F.Cu")
		(net "M_G_DQS_DP<4>")
	)
	(segment
		(start 118.684548 -24.550878)
		(end 119.207026 -24.0284)
		(width 0.1651)
		(layer "F.Cu")
		(net "M_G_DQS_DP<4>")
	)
	(segment
		(start 109.280706 -52.141882)
		(end 109.280452 -52.142136)
		(width 0.0889)
		(layer "F.Cu")
		(net "M_G_DQS_DP<4>")
	)
	(segment
		(start 119.936768 -23.692358)
		(end 119.936768 -23.054056)
		(width 0.1651)
		(layer "F.Cu")
		(net "M_G_DQS_DP<4>")
	)
	(segment
		(start 109.231684 -50.957226)
		(end 109.175042 -50.86096)
		(width 0.0889)
		(layer "F.Cu")
		(net "M_G_DQS_DP<4>")
	)
	(segment
		(start 109.175042 -50.86096)
		(end 109.175042 -50.6476)
		(width 0.0889)
		(layer "F.Cu")
		(net "M_G_DQS_DP<4>")
	)
	(segment
		(start 109.451648 -40.316404)
		(end 109.451648 -39.15029)
		(width 0.1651)
		(layer "F.Cu")
		(net "M_G_DQS_DP<4>")
	)
	(segment
		(start 109.451648 -39.15029)
		(end 118.684548 -29.91739)
		(width 0.1651)
		(layer "F.Cu")
		(net "M_G_DQS_DP<4>")
	)
	(segment
		(start 108.527596 -53.742082)
		(end 108.485686 -53.700172)
		(width 0.0889)
		(layer "F.Cu")
		(net "M_G_DQS_DP<4>")
	)
	(segment
		(start 109.175042 -50.0888)
		(end 109.378242 -49.8856)
		(width 0.0889)
		(layer "F.Cu")
		(net "M_G_DQS_DP<4>")
	)
	(segment
		(start 119.59336 -17.35836)
		(end 119.337328 -17.35836)
		(width 0.1651)
		(layer "F.Cu")
		(net "M_G_DQS_DP<4>")
	)
	(segment
		(start 119.771668 -22.888956)
		(end 119.337328 -22.888956)
		(width 0.1651)
		(layer "F.Cu")
		(net "M_G_DQS_DP<4>")
	)
	(segment
		(start 109.276642 -50.3936)
		(end 109.175042 -50.292)
		(width 0.0889)
		(layer "F.Cu")
		(net "M_G_DQS_DP<4>")
	)
	(segment
		(start 109.175042 -50.6476)
		(end 109.276642 -50.546)
		(width 0.0889)
		(layer "F.Cu")
		(net "M_G_DQS_DP<4>")
	)
	(segment
		(start 109.451648 -40.405812)
		(end 109.451648 -40.316404)
		(width 0.1016)
		(layer "F.Cu")
		(net "M_G_DQS_DP<4>")
	)
	(segment
		(start 108.768896 -53.427884)
		(end 108.768896 -53.636672)
		(width 0.0889)
		(layer "F.Cu")
		(net "M_G_DQS_DP<4>")
	)
	(segment
		(start 118.684548 -29.91739)
		(end 118.684548 -27.686)
		(width 0.1651)
		(layer "F.Cu")
		(net "M_G_DQS_DP<4>")
	)
	(segment
		(start 109.276642 -50.546)
		(end 109.276642 -50.3936)
		(width 0.0889)
		(layer "F.Cu")
		(net "M_G_DQS_DP<4>")
	)
	(segment
		(start 109.358938 -51.474878)
		(end 109.358938 -51.47437)
		(width 0.0889)
		(layer "F.Cu")
		(net "M_G_DQS_DP<4>")
	)
	(segment
		(start 108.663486 -53.742082)
		(end 108.527596 -53.742082)
		(width 0.0889)
		(layer "F.Cu")
		(net "M_G_DQS_DP<4>")
	)
	(segment
		(start 108.75772 -53.027834)
		(end 108.790486 -53.027834)
		(width 0.0889)
		(layer "F.Cu")
		(net "M_G_DQS_DP<4>")
	)
	(segment
		(start 119.207026 -24.0284)
		(end 119.600726 -24.0284)
		(width 0.1651)
		(layer "F.Cu")
		(net "M_G_DQS_DP<4>")
	)
	(segment
		(start 118.684548 -27.686)
		(end 118.684548 -24.550878)
		(width 0.1651)
		(layer "F.Cu")
		(net "M_G_DQS_DP<4>")
	)
	(via
		(at 119.337328 -22.888956)
		(size 0.508)
		(drill 0.254)
		(layers "F.Cu" "B.Cu")
		(net "M_G_DQS_DP<4>")
	)
	(via
		(at 118.684548 -27.686)
		(size 0.508)
		(drill 0.254)
		(layers "F.Cu" "B.Cu")
		(net "M_G_DQS_DP<4>")
	)
	(via
		(at 119.337328 -17.35836)
		(size 0.508)
		(drill 0.254)
		(layers "F.Cu" "B.Cu")
		(net "M_G_DQS_DP<4>")
	)
	(arc
		(start 109.280452 -52.142136)
		(mid 109.226826 -51.941984)
		(end 109.280452 -51.741832)
		(width 0.0889)
		(layer "F.Cu")
		(net "M_G_DQS_DP<4>")
	)
	(arc
		(start 108.466382 -53.16601)
		(mid 108.597528 -53.066324)
		(end 108.75772 -53.027834)
		(width 0.0889)
		(layer "F.Cu")
		(net "M_G_DQS_DP<4>")
	)
	(arc
		(start 109.358938 -51.47437)
		(mid 109.333056 -51.206505)
		(end 109.231684 -50.957226)
		(width 0.0889)
		(layer "F.Cu")
		(net "M_G_DQS_DP<4>")
	)
	(arc
		(start 109.280452 -51.741832)
		(mid 109.335634 -51.613042)
		(end 109.358938 -51.474878)
		(width 0.0889)
		(layer "F.Cu")
		(net "M_G_DQS_DP<4>")
	)
	(arc
		(start 108.790486 -53.027834)
		(mid 109.285963 -52.723391)
		(end 109.280706 -52.141882)
		(width 0.0889)
		(layer "F.Cu")
		(net "M_G_DQS_DP<4>")
	)
	(arc
		(start 108.485686 -53.700172)
		(mid 108.37105 -53.436908)
		(end 108.466382 -53.16601)
		(width 0.0889)
		(layer "F.Cu")
		(net "M_G_DQS_DP<4>")
	)
	(segment
		(start 119.799354 -20.224242)
		(end 119.799354 -21.374354)
		(width 0.1651)
		(layer "B.Cu")
		(net "M_G_DQS_DP<4>")
	)
	(segment
		(start 119.8372 -22.6314)
		(end 119.579644 -22.888956)
		(width 0.1651)
		(layer "B.Cu")
		(net "M_G_DQS_DP<4>")
	)
	(segment
		(start 119.579644 -22.888956)
		(end 119.337328 -22.888956)
		(width 0.1651)
		(layer "B.Cu")
		(net "M_G_DQS_DP<4>")
	)
	(segment
		(start 119.799354 -21.374354)
		(end 119.8372 -21.4122)
		(width 0.1651)
		(layer "B.Cu")
		(net "M_G_DQS_DP<4>")
	)
	(segment
		(start 119.8372 -21.4122)
		(end 119.8372 -22.6314)
		(width 0.1651)
		(layer "B.Cu")
		(net "M_G_DQS_DP<4>")
	)
	(segment
		(start 120.148096 -22.078188)
		(end 120.148096 -18.169128)
		(width 0.14224)
		(layer "In2.Cu")
		(net "M_G_DQS_DP<4>")
	)
	(segment
		(start 120.148096 -18.169128)
		(end 119.337328 -17.35836)
		(width 0.14224)
		(layer "In2.Cu")
		(net "M_G_DQS_DP<4>")
	)
	(segment
		(start 119.337328 -22.888956)
		(end 120.148096 -22.078188)
		(width 0.14224)
		(layer "In2.Cu")
		(net "M_G_DQS_DP<4>")
	)
	(segment
		(start 64.549528 -20.023582)
		(end 64.549528 -19.011646)
		(width 0.1651)
		(layer "F.Cu")
		(net "M_G_DQS_DP<3>")
	)
	(segment
		(start 64.343534 -17.35836)
		(end 64.087502 -17.35836)
		(width 0.1651)
		(layer "F.Cu")
		(net "M_G_DQS_DP<3>")
	)
	(segment
		(start 64.587374 -18.9738)
		(end 64.587374 -17.6022)
		(width 0.1651)
		(layer "F.Cu")
		(net "M_G_DQS_DP<3>")
	)
	(segment
		(start 64.587374 -17.6022)
		(end 64.343534 -17.35836)
		(width 0.1651)
		(layer "F.Cu")
		(net "M_G_DQS_DP<3>")
	)
	(segment
		(start 64.549528 -19.011646)
		(end 64.587374 -18.9738)
		(width 0.1651)
		(layer "F.Cu")
		(net "M_G_DQS_DP<3>")
	)
	(segment
		(start 77.192886 -56.085486)
		(end 76.621386 -56.085486)
		(width 0.1016)
		(layer "F.Cu")
		(net "M_G_DQS_DP<3>")
	)
	(via
		(at 76.621386 -56.085486)
		(size 0.508)
		(drill 0.254)
		(layers "F.Cu" "B.Cu")
		(net "M_G_DQS_DP<3>")
	)
	(via
		(at 64.087502 -17.35836)
		(size 0.508)
		(drill 0.254)
		(layers "F.Cu" "B.Cu")
		(net "M_G_DQS_DP<3>")
	)
	(via
		(at 64.087502 -22.888956)
		(size 0.508)
		(drill 0.254)
		(layers "F.Cu" "B.Cu")
		(net "M_G_DQS_DP<3>")
	)
	(segment
		(start 64.549528 -21.374354)
		(end 64.587374 -21.4122)
		(width 0.1651)
		(layer "B.Cu")
		(net "M_G_DQS_DP<3>")
	)
	(segment
		(start 64.329818 -22.888956)
		(end 64.087502 -22.888956)
		(width 0.1651)
		(layer "B.Cu")
		(net "M_G_DQS_DP<3>")
	)
	(segment
		(start 64.587374 -21.4122)
		(end 64.587374 -22.6314)
		(width 0.1651)
		(layer "B.Cu")
		(net "M_G_DQS_DP<3>")
	)
	(segment
		(start 64.587374 -22.6314)
		(end 64.329818 -22.888956)
		(width 0.1651)
		(layer "B.Cu")
		(net "M_G_DQS_DP<3>")
	)
	(segment
		(start 64.549528 -20.224242)
		(end 64.549528 -21.374354)
		(width 0.1651)
		(layer "B.Cu")
		(net "M_G_DQS_DP<3>")
	)
	(segment
		(start 64.883284 -30.29712)
		(end 65.040764 -30.4546)
		(width 0.14224)
		(layer "In2.Cu")
		(net "M_G_DQS_DP<3>")
	)
	(segment
		(start 65.040764 -29.1846)
		(end 64.883284 -29.34208)
		(width 0.14224)
		(layer "In2.Cu")
		(net "M_G_DQS_DP<3>")
	)
	(segment
		(start 65.040764 -30.4546)
		(end 65.040764 -30.7086)
		(width 0.14224)
		(layer "In2.Cu")
		(net "M_G_DQS_DP<3>")
	)
	(segment
		(start 64.883284 -28.77312)
		(end 65.040764 -28.9306)
		(width 0.14224)
		(layer "In2.Cu")
		(net "M_G_DQS_DP<3>")
	)
	(segment
		(start 65.040764 -28.9306)
		(end 65.040764 -29.1846)
		(width 0.14224)
		(layer "In2.Cu")
		(net "M_G_DQS_DP<3>")
	)
	(segment
		(start 77.12837 -53.800502)
		(end 77.133196 -53.809138)
		(width 0.0889)
		(layer "In2.Cu")
		(net "M_G_DQS_DP<3>")
	)
	(segment
		(start 65.040764 -32.2326)
		(end 64.883284 -32.39008)
		(width 0.14224)
		(layer "In2.Cu")
		(net "M_G_DQS_DP<3>")
	)
	(segment
		(start 76.6064 -52.523136)
		(end 76.639166 -52.523136)
		(width 0.0889)
		(layer "In2.Cu")
		(net "M_G_DQS_DP<3>")
	)
	(segment
		(start 65.040764 -31.2166)
		(end 65.040764 -31.4706)
		(width 0.14224)
		(layer "In2.Cu")
		(net "M_G_DQS_DP<3>")
	)
	(segment
		(start 75.75169 -52.02809)
		(end 75.784456 -52.02809)
		(width 0.0889)
		(layer "In2.Cu")
		(net "M_G_DQS_DP<3>")
	)
	(segment
		(start 64.883284 -29.34208)
		(end 64.883284 -29.53512)
		(width 0.14224)
		(layer "In2.Cu")
		(net "M_G_DQS_DP<3>")
	)
	(segment
		(start 64.883284 -41.002712)
		(end 72.86625 -48.985678)
		(width 0.14224)
		(layer "In2.Cu")
		(net "M_G_DQS_DP<3>")
	)
	(segment
		(start 64.687958 -24.90978)
		(end 64.687958 -25.132284)
		(width 0.14224)
		(layer "In2.Cu")
		(net "M_G_DQS_DP<3>")
	)
	(segment
		(start 73.17232 -50.541936)
		(end 73.205086 -50.541936)
		(width 0.0889)
		(layer "In2.Cu")
		(net "M_G_DQS_DP<3>")
	)
	(segment
		(start 77.133196 -54.799738)
		(end 77.139546 -54.810406)
		(width 0.0889)
		(layer "In2.Cu")
		(net "M_G_DQS_DP<3>")
	)
	(segment
		(start 72.82688 -49.488852)
		(end 72.82688 -50.290984)
		(width 0.0889)
		(layer "In2.Cu")
		(net "M_G_DQS_DP<3>")
	)
	(segment
		(start 76.621386 -56.42356)
		(end 76.621386 -56.085486)
		(width 0.0889)
		(layer "In2.Cu")
		(net "M_G_DQS_DP<3>")
	)
	(segment
		(start 64.89827 -22.078188)
		(end 64.087502 -22.888956)
		(width 0.14224)
		(layer "In2.Cu")
		(net "M_G_DQS_DP<3>")
	)
	(segment
		(start 64.883284 -30.10408)
		(end 64.883284 -30.29712)
		(width 0.14224)
		(layer "In2.Cu")
		(net "M_G_DQS_DP<3>")
	)
	(segment
		(start 64.89827 -18.169128)
		(end 64.89827 -22.078188)
		(width 0.14224)
		(layer "In2.Cu")
		(net "M_G_DQS_DP<3>")
	)
	(segment
		(start 64.883284 -29.53512)
		(end 65.040764 -29.6926)
		(width 0.14224)
		(layer "In2.Cu")
		(net "M_G_DQS_DP<3>")
	)
	(segment
		(start 64.038226 -24.26208)
		(end 64.038226 -24.482552)
		(width 0.14224)
		(layer "In2.Cu")
		(net "M_G_DQS_DP<3>")
	)
	(segment
		(start 72.86625 -49.449482)
		(end 72.82688 -49.488852)
		(width 0.0889)
		(layer "In2.Cu")
		(net "M_G_DQS_DP<3>")
	)
	(segment
		(start 74.88936 -51.532536)
		(end 74.922126 -51.532536)
		(width 0.0889)
		(layer "In2.Cu")
		(net "M_G_DQS_DP<3>")
	)
	(segment
		(start 65.040764 -31.4706)
		(end 64.883284 -31.62808)
		(width 0.14224)
		(layer "In2.Cu")
		(net "M_G_DQS_DP<3>")
	)
	(segment
		(start 64.087502 -22.888956)
		(end 64.551306 -23.35276)
		(width 0.14224)
		(layer "In2.Cu")
		(net "M_G_DQS_DP<3>")
	)
	(segment
		(start 64.508126 -24.729948)
		(end 64.687958 -24.90978)
		(width 0.14224)
		(layer "In2.Cu")
		(net "M_G_DQS_DP<3>")
	)
	(segment
		(start 77.133196 -53.809138)
		(end 77.139546 -53.819806)
		(width 0.0889)
		(layer "In2.Cu")
		(net "M_G_DQS_DP<3>")
	)
	(segment
		(start 76.642976 -55.685436)
		(end 76.61021 -55.685436)
		(width 0.0889)
		(layer "In2.Cu")
		(net "M_G_DQS_DP<3>")
	)
	(segment
		(start 65.040764 -31.9786)
		(end 65.040764 -32.2326)
		(width 0.14224)
		(layer "In2.Cu")
		(net "M_G_DQS_DP<3>")
	)
	(segment
		(start 65.040764 -29.9466)
		(end 64.883284 -30.10408)
		(width 0.14224)
		(layer "In2.Cu")
		(net "M_G_DQS_DP<3>")
	)
	(segment
		(start 74.03465 -51.03749)
		(end 74.067416 -51.03749)
		(width 0.0889)
		(layer "In2.Cu")
		(net "M_G_DQS_DP<3>")
	)
	(segment
		(start 65.040764 -29.6926)
		(end 65.040764 -29.9466)
		(width 0.14224)
		(layer "In2.Cu")
		(net "M_G_DQS_DP<3>")
	)
	(segment
		(start 72.86625 -48.985678)
		(end 72.86625 -49.449482)
		(width 0.14224)
		(layer "In2.Cu")
		(net "M_G_DQS_DP<3>")
	)
	(segment
		(start 64.087502 -17.35836)
		(end 64.89827 -18.169128)
		(width 0.14224)
		(layer "In2.Cu")
		(net "M_G_DQS_DP<3>")
	)
	(segment
		(start 76.563474 -56.481472)
		(end 76.621386 -56.42356)
		(width 0.0889)
		(layer "In2.Cu")
		(net "M_G_DQS_DP<3>")
	)
	(segment
		(start 64.038226 -24.482552)
		(end 64.285622 -24.729948)
		(width 0.14224)
		(layer "In2.Cu")
		(net "M_G_DQS_DP<3>")
	)
	(segment
		(start 64.883284 -32.39008)
		(end 64.883284 -41.002712)
		(width 0.14224)
		(layer "In2.Cu")
		(net "M_G_DQS_DP<3>")
	)
	(segment
		(start 64.285622 -24.729948)
		(end 64.508126 -24.729948)
		(width 0.14224)
		(layer "In2.Cu")
		(net "M_G_DQS_DP<3>")
	)
	(segment
		(start 64.883284 -30.86608)
		(end 64.883284 -31.05912)
		(width 0.14224)
		(layer "In2.Cu")
		(net "M_G_DQS_DP<3>")
	)
	(segment
		(start 64.551306 -23.749)
		(end 64.038226 -24.26208)
		(width 0.14224)
		(layer "In2.Cu")
		(net "M_G_DQS_DP<3>")
	)
	(segment
		(start 64.883284 -31.62808)
		(end 64.883284 -31.82112)
		(width 0.14224)
		(layer "In2.Cu")
		(net "M_G_DQS_DP<3>")
	)
	(segment
		(start 77.12837 -54.791102)
		(end 77.133196 -54.799738)
		(width 0.0889)
		(layer "In2.Cu")
		(net "M_G_DQS_DP<3>")
	)
	(segment
		(start 64.883284 -31.05912)
		(end 65.040764 -31.2166)
		(width 0.14224)
		(layer "In2.Cu")
		(net "M_G_DQS_DP<3>")
	)
	(segment
		(start 64.687958 -25.132284)
		(end 64.883284 -25.32761)
		(width 0.14224)
		(layer "In2.Cu")
		(net "M_G_DQS_DP<3>")
	)
	(segment
		(start 64.883284 -25.32761)
		(end 64.883284 -28.77312)
		(width 0.14224)
		(layer "In2.Cu")
		(net "M_G_DQS_DP<3>")
	)
	(segment
		(start 65.040764 -30.7086)
		(end 64.883284 -30.86608)
		(width 0.14224)
		(layer "In2.Cu")
		(net "M_G_DQS_DP<3>")
	)
	(segment
		(start 64.551306 -23.35276)
		(end 64.551306 -23.749)
		(width 0.14224)
		(layer "In2.Cu")
		(net "M_G_DQS_DP<3>")
	)
	(segment
		(start 64.883284 -31.82112)
		(end 65.040764 -31.9786)
		(width 0.14224)
		(layer "In2.Cu")
		(net "M_G_DQS_DP<3>")
	)
	(arc
		(start 76.61021 -55.685436)
		(mid 76.221868 -56.06203)
		(end 76.563474 -56.481472)
		(width 0.0889)
		(layer "In2.Cu")
		(net "M_G_DQS_DP<3>")
	)
	(arc
		(start 74.557636 -51.332638)
		(mid 74.697715 -51.475374)
		(end 74.88936 -51.532536)
		(width 0.0889)
		(layer "In2.Cu")
		(net "M_G_DQS_DP<3>")
	)
	(arc
		(start 72.82688 -50.290984)
		(mid 72.830369 -50.317416)
		(end 72.840596 -50.342038)
		(width 0.0889)
		(layer "In2.Cu")
		(net "M_G_DQS_DP<3>")
	)
	(arc
		(start 74.922126 -51.532536)
		(mid 75.20755 -51.616003)
		(end 75.416156 -51.827938)
		(width 0.0889)
		(layer "In2.Cu")
		(net "M_G_DQS_DP<3>")
	)
	(arc
		(start 77.133196 -54.399688)
		(mid 77.079726 -54.594751)
		(end 77.12837 -54.791102)
		(width 0.0889)
		(layer "In2.Cu")
		(net "M_G_DQS_DP<3>")
	)
	(arc
		(start 73.699116 -50.837338)
		(mid 73.840799 -50.981142)
		(end 74.03465 -51.03749)
		(width 0.0889)
		(layer "In2.Cu")
		(net "M_G_DQS_DP<3>")
	)
	(arc
		(start 77.133196 -53.409088)
		(mid 77.079726 -53.604151)
		(end 77.12837 -53.800502)
		(width 0.0889)
		(layer "In2.Cu")
		(net "M_G_DQS_DP<3>")
	)
	(arc
		(start 77.139546 -53.819806)
		(mid 77.212344 -54.110569)
		(end 77.133196 -54.399688)
		(width 0.0889)
		(layer "In2.Cu")
		(net "M_G_DQS_DP<3>")
	)
	(arc
		(start 72.840596 -50.342038)
		(mid 72.980675 -50.484774)
		(end 73.17232 -50.541936)
		(width 0.0889)
		(layer "In2.Cu")
		(net "M_G_DQS_DP<3>")
	)
	(arc
		(start 74.067416 -51.03749)
		(mid 74.350633 -51.121771)
		(end 74.557636 -51.332638)
		(width 0.0889)
		(layer "In2.Cu")
		(net "M_G_DQS_DP<3>")
	)
	(arc
		(start 76.274676 -52.323238)
		(mid 76.414755 -52.465974)
		(end 76.6064 -52.523136)
		(width 0.0889)
		(layer "In2.Cu")
		(net "M_G_DQS_DP<3>")
	)
	(arc
		(start 76.639166 -52.523136)
		(mid 77.137417 -52.825976)
		(end 77.133196 -53.409088)
		(width 0.0889)
		(layer "In2.Cu")
		(net "M_G_DQS_DP<3>")
	)
	(arc
		(start 73.205086 -50.541936)
		(mid 73.49051 -50.625403)
		(end 73.699116 -50.837338)
		(width 0.0889)
		(layer "In2.Cu")
		(net "M_G_DQS_DP<3>")
	)
	(arc
		(start 75.416156 -51.827938)
		(mid 75.557839 -51.971742)
		(end 75.75169 -52.02809)
		(width 0.0889)
		(layer "In2.Cu")
		(net "M_G_DQS_DP<3>")
	)
	(arc
		(start 75.784456 -52.02809)
		(mid 76.067673 -52.112371)
		(end 76.274676 -52.323238)
		(width 0.0889)
		(layer "In2.Cu")
		(net "M_G_DQS_DP<3>")
	)
	(arc
		(start 77.139546 -54.810406)
		(mid 77.135515 -55.386588)
		(end 76.642976 -55.685436)
		(width 0.0889)
		(layer "In2.Cu")
		(net "M_G_DQS_DP<3>")
	)
	(segment
		(start 55.199534 -20.023582)
		(end 55.199534 -19.011646)
		(width 0.1651)
		(layer "F.Cu")
		(net "M_G_DQS_DP<2>")
	)
	(segment
		(start 55.199534 -19.011646)
		(end 55.23738 -18.9738)
		(width 0.1651)
		(layer "F.Cu")
		(net "M_G_DQS_DP<2>")
	)
	(segment
		(start 54.99354 -17.35836)
		(end 54.737508 -17.35836)
		(width 0.1651)
		(layer "F.Cu")
		(net "M_G_DQS_DP<2>")
	)
	(segment
		(start 72.900286 -56.58104)
		(end 72.328786 -56.58104)
		(width 0.1016)
		(layer "F.Cu")
		(net "M_G_DQS_DP<2>")
	)
	(segment
		(start 55.23738 -17.6022)
		(end 54.99354 -17.35836)
		(width 0.1651)
		(layer "F.Cu")
		(net "M_G_DQS_DP<2>")
	)
	(segment
		(start 55.23738 -18.9738)
		(end 55.23738 -17.6022)
		(width 0.1651)
		(layer "F.Cu")
		(net "M_G_DQS_DP<2>")
	)
	(via
		(at 54.737508 -22.888956)
		(size 0.508)
		(drill 0.254)
		(layers "F.Cu" "B.Cu")
		(net "M_G_DQS_DP<2>")
	)
	(via
		(at 72.328786 -56.58104)
		(size 0.508)
		(drill 0.254)
		(layers "F.Cu" "B.Cu")
		(net "M_G_DQS_DP<2>")
	)
	(via
		(at 54.737508 -17.35836)
		(size 0.508)
		(drill 0.254)
		(layers "F.Cu" "B.Cu")
		(net "M_G_DQS_DP<2>")
	)
	(segment
		(start 55.23738 -22.6314)
		(end 54.979824 -22.888956)
		(width 0.1651)
		(layer "B.Cu")
		(net "M_G_DQS_DP<2>")
	)
	(segment
		(start 54.979824 -22.888956)
		(end 54.737508 -22.888956)
		(width 0.1651)
		(layer "B.Cu")
		(net "M_G_DQS_DP<2>")
	)
	(segment
		(start 55.199534 -20.224242)
		(end 55.199534 -21.374354)
		(width 0.1651)
		(layer "B.Cu")
		(net "M_G_DQS_DP<2>")
	)
	(segment
		(start 55.199534 -21.374354)
		(end 55.23738 -21.4122)
		(width 0.1651)
		(layer "B.Cu")
		(net "M_G_DQS_DP<2>")
	)
	(segment
		(start 55.23738 -21.4122)
		(end 55.23738 -22.6314)
		(width 0.1651)
		(layer "B.Cu")
		(net "M_G_DQS_DP<2>")
	)
	(segment
		(start 67.449192 -55.203344)
		(end 67.488562 -55.242714)
		(width 0.0889)
		(layer "In2.Cu")
		(net "M_G_DQS_DP<2>")
	)
	(segment
		(start 53.906928 -34.348928)
		(end 54.04485 -34.348928)
		(width 0.14224)
		(layer "In2.Cu")
		(net "M_G_DQS_DP<2>")
	)
	(segment
		(start 54.423056 -31.99384)
		(end 54.423056 -32.960056)
		(width 0.14224)
		(layer "In2.Cu")
		(net "M_G_DQS_DP<2>")
	)
	(segment
		(start 65.565274 -53.84927)
		(end 65.863978 -54.147974)
		(width 0.14224)
		(layer "In2.Cu")
		(net "M_G_DQS_DP<2>")
	)
	(segment
		(start 54.737508 -22.888956)
		(end 55.201312 -23.35276)
		(width 0.14224)
		(layer "In2.Cu")
		(net "M_G_DQS_DP<2>")
	)
	(segment
		(start 54.385464 -27.358848)
		(end 54.385464 -27.612848)
		(width 0.14224)
		(layer "In2.Cu")
		(net "M_G_DQS_DP<2>")
	)
	(segment
		(start 54.423056 -37.419534)
		(end 54.423056 -42.707052)
		(width 0.14224)
		(layer "In2.Cu")
		(net "M_G_DQS_DP<2>")
	)
	(segment
		(start 72.700642 -56.433212)
		(end 72.621902 -56.411876)
		(width 0.0889)
		(layer "In2.Cu")
		(net "M_G_DQS_DP<2>")
	)
	(segment
		(start 54.227984 -24.915368)
		(end 54.385464 -25.072848)
		(width 0.14224)
		(layer "In2.Cu")
		(net "M_G_DQS_DP<2>")
	)
	(segment
		(start 53.882544 -37.041328)
		(end 54.04485 -37.041328)
		(width 0.14224)
		(layer "In2.Cu")
		(net "M_G_DQS_DP<2>")
	)
	(segment
		(start 64.39789 -52.502054)
		(end 64.559434 -52.663598)
		(width 0.14224)
		(layer "In2.Cu")
		(net "M_G_DQS_DP<2>")
	)
	(segment
		(start 65.863978 -54.147974)
		(end 66.04381 -54.147974)
		(width 0.14224)
		(layer "In2.Cu")
		(net "M_G_DQS_DP<2>")
	)
	(segment
		(start 54.227984 -28.906216)
		(end 54.423056 -29.101288)
		(width 0.14224)
		(layer "In2.Cu")
		(net "M_G_DQS_DP<2>")
	)
	(segment
		(start 64.056514 -52.160678)
		(end 64.056514 -52.34051)
		(width 0.14224)
		(layer "In2.Cu")
		(net "M_G_DQS_DP<2>")
	)
	(segment
		(start 55.201312 -23.706328)
		(end 54.227984 -24.679656)
		(width 0.14224)
		(layer "In2.Cu")
		(net "M_G_DQS_DP<2>")
	)
	(segment
		(start 65.062354 -53.166518)
		(end 65.062354 -53.34635)
		(width 0.14224)
		(layer "In2.Cu")
		(net "M_G_DQS_DP<2>")
	)
	(segment
		(start 54.423056 -34.727134)
		(end 54.423056 -35.586162)
		(width 0.14224)
		(layer "In2.Cu")
		(net "M_G_DQS_DP<2>")
	)
	(segment
		(start 54.227984 -27.201368)
		(end 54.385464 -27.358848)
		(width 0.14224)
		(layer "In2.Cu")
		(net "M_G_DQS_DP<2>")
	)
	(segment
		(start 66.708274 -54.812438)
		(end 66.708274 -54.99227)
		(width 0.14224)
		(layer "In2.Cu")
		(net "M_G_DQS_DP<2>")
	)
	(segment
		(start 66.04381 -54.147974)
		(end 66.205354 -54.309518)
		(width 0.14224)
		(layer "In2.Cu")
		(net "M_G_DQS_DP<2>")
	)
	(segment
		(start 64.056514 -52.34051)
		(end 64.218058 -52.502054)
		(width 0.14224)
		(layer "In2.Cu")
		(net "M_G_DQS_DP<2>")
	)
	(segment
		(start 64.218058 -52.502054)
		(end 64.39789 -52.502054)
		(width 0.14224)
		(layer "In2.Cu")
		(net "M_G_DQS_DP<2>")
	)
	(segment
		(start 53.661056 -34.103056)
		(end 53.906928 -34.348928)
		(width 0.14224)
		(layer "In2.Cu")
		(net "M_G_DQS_DP<2>")
	)
	(segment
		(start 54.423056 -30.31236)
		(end 53.861208 -30.874208)
		(width 0.14224)
		(layer "In2.Cu")
		(net "M_G_DQS_DP<2>")
	)
	(segment
		(start 66.54673 -54.650894)
		(end 66.708274 -54.812438)
		(width 0.14224)
		(layer "In2.Cu")
		(net "M_G_DQS_DP<2>")
	)
	(segment
		(start 54.227984 -26.439368)
		(end 54.385464 -26.596848)
		(width 0.14224)
		(layer "In2.Cu")
		(net "M_G_DQS_DP<2>")
	)
	(segment
		(start 54.04485 -35.964368)
		(end 53.806344 -35.964368)
		(width 0.14224)
		(layer "In2.Cu")
		(net "M_G_DQS_DP<2>")
	)
	(segment
		(start 63.89497 -51.999134)
		(end 64.056514 -52.160678)
		(width 0.14224)
		(layer "In2.Cu")
		(net "M_G_DQS_DP<2>")
	)
	(segment
		(start 65.40373 -53.507894)
		(end 65.565274 -53.669438)
		(width 0.14224)
		(layer "In2.Cu")
		(net "M_G_DQS_DP<2>")
	)
	(segment
		(start 72.621902 -56.411876)
		(end 72.328786 -56.58104)
		(width 0.0889)
		(layer "In2.Cu")
		(net "M_G_DQS_DP<2>")
	)
	(segment
		(start 63.715138 -51.999134)
		(end 63.89497 -51.999134)
		(width 0.14224)
		(layer "In2.Cu")
		(net "M_G_DQS_DP<2>")
	)
	(segment
		(start 70.611492 -56.98109)
		(end 70.612254 -56.98109)
		(width 0.0889)
		(layer "In2.Cu")
		(net "M_G_DQS_DP<2>")
	)
	(segment
		(start 54.423056 -32.960056)
		(end 53.661056 -33.722056)
		(width 0.14224)
		(layer "In2.Cu")
		(net "M_G_DQS_DP<2>")
	)
	(segment
		(start 54.227984 -28.55468)
		(end 54.227984 -28.906216)
		(width 0.14224)
		(layer "In2.Cu")
		(net "M_G_DQS_DP<2>")
	)
	(segment
		(start 71.469758 -56.485536)
		(end 71.470266 -56.485536)
		(width 0.0889)
		(layer "In2.Cu")
		(net "M_G_DQS_DP<2>")
	)
	(segment
		(start 68.071492 -55.242714)
		(end 69.314314 -56.485536)
		(width 0.0889)
		(layer "In2.Cu")
		(net "M_G_DQS_DP<2>")
	)
	(segment
		(start 53.806344 -35.964368)
		(end 53.584856 -36.185856)
		(width 0.14224)
		(layer "In2.Cu")
		(net "M_G_DQS_DP<2>")
	)
	(segment
		(start 66.205354 -54.48935)
		(end 66.366898 -54.650894)
		(width 0.14224)
		(layer "In2.Cu")
		(net "M_G_DQS_DP<2>")
	)
	(segment
		(start 66.366898 -54.650894)
		(end 66.54673 -54.650894)
		(width 0.14224)
		(layer "In2.Cu")
		(net "M_G_DQS_DP<2>")
	)
	(segment
		(start 54.227984 -24.679656)
		(end 54.227984 -24.915368)
		(width 0.14224)
		(layer "In2.Cu")
		(net "M_G_DQS_DP<2>")
	)
	(segment
		(start 53.584856 -36.185856)
		(end 53.584856 -36.74364)
		(width 0.14224)
		(layer "In2.Cu")
		(net "M_G_DQS_DP<2>")
	)
	(segment
		(start 54.423056 -35.586162)
		(end 54.04485 -35.964368)
		(width 0.14224)
		(layer "In2.Cu")
		(net "M_G_DQS_DP<2>")
	)
	(segment
		(start 53.661056 -33.722056)
		(end 53.661056 -34.103056)
		(width 0.14224)
		(layer "In2.Cu")
		(net "M_G_DQS_DP<2>")
	)
	(segment
		(start 54.227984 -27.98572)
		(end 54.385464 -28.1432)
		(width 0.14224)
		(layer "In2.Cu")
		(net "M_G_DQS_DP<2>")
	)
	(segment
		(start 54.227984 -27.770328)
		(end 54.227984 -27.98572)
		(width 0.14224)
		(layer "In2.Cu")
		(net "M_G_DQS_DP<2>")
	)
	(segment
		(start 55.548276 -18.169128)
		(end 55.548276 -22.078188)
		(width 0.14224)
		(layer "In2.Cu")
		(net "M_G_DQS_DP<2>")
	)
	(segment
		(start 54.423056 -29.101288)
		(end 54.423056 -30.31236)
		(width 0.14224)
		(layer "In2.Cu")
		(net "M_G_DQS_DP<2>")
	)
	(segment
		(start 66.919348 -55.203344)
		(end 67.427094 -55.203344)
		(width 0.14224)
		(layer "In2.Cu")
		(net "M_G_DQS_DP<2>")
	)
	(segment
		(start 54.385464 -28.1432)
		(end 54.385464 -28.3972)
		(width 0.14224)
		(layer "In2.Cu")
		(net "M_G_DQS_DP<2>")
	)
	(segment
		(start 54.737508 -17.35836)
		(end 55.548276 -18.169128)
		(width 0.14224)
		(layer "In2.Cu")
		(net "M_G_DQS_DP<2>")
	)
	(segment
		(start 54.227984 -26.246328)
		(end 54.227984 -26.439368)
		(width 0.14224)
		(layer "In2.Cu")
		(net "M_G_DQS_DP<2>")
	)
	(segment
		(start 64.720978 -53.004974)
		(end 64.90081 -53.004974)
		(width 0.14224)
		(layer "In2.Cu")
		(net "M_G_DQS_DP<2>")
	)
	(segment
		(start 65.565274 -53.669438)
		(end 65.565274 -53.84927)
		(width 0.14224)
		(layer "In2.Cu")
		(net "M_G_DQS_DP<2>")
	)
	(segment
		(start 69.314314 -56.485536)
		(end 69.766942 -56.485536)
		(width 0.0889)
		(layer "In2.Cu")
		(net "M_G_DQS_DP<2>")
	)
	(segment
		(start 53.861208 -31.431992)
		(end 54.423056 -31.99384)
		(width 0.14224)
		(layer "In2.Cu")
		(net "M_G_DQS_DP<2>")
	)
	(segment
		(start 66.708274 -54.99227)
		(end 66.919348 -55.203344)
		(width 0.14224)
		(layer "In2.Cu")
		(net "M_G_DQS_DP<2>")
	)
	(segment
		(start 53.584856 -36.74364)
		(end 53.882544 -37.041328)
		(width 0.14224)
		(layer "In2.Cu")
		(net "M_G_DQS_DP<2>")
	)
	(segment
		(start 54.385464 -26.850848)
		(end 54.227984 -27.008328)
		(width 0.14224)
		(layer "In2.Cu")
		(net "M_G_DQS_DP<2>")
	)
	(segment
		(start 54.385464 -25.834848)
		(end 54.385464 -26.088848)
		(width 0.14224)
		(layer "In2.Cu")
		(net "M_G_DQS_DP<2>")
	)
	(segment
		(start 65.062354 -53.34635)
		(end 65.223898 -53.507894)
		(width 0.14224)
		(layer "In2.Cu")
		(net "M_G_DQS_DP<2>")
	)
	(segment
		(start 67.427094 -55.203344)
		(end 67.449192 -55.203344)
		(width 0.0889)
		(layer "In2.Cu")
		(net "M_G_DQS_DP<2>")
	)
	(segment
		(start 64.559434 -52.663598)
		(end 64.559434 -52.84343)
		(width 0.14224)
		(layer "In2.Cu")
		(net "M_G_DQS_DP<2>")
	)
	(segment
		(start 66.205354 -54.309518)
		(end 66.205354 -54.48935)
		(width 0.14224)
		(layer "In2.Cu")
		(net "M_G_DQS_DP<2>")
	)
	(segment
		(start 55.201312 -23.35276)
		(end 55.201312 -23.706328)
		(width 0.14224)
		(layer "In2.Cu")
		(net "M_G_DQS_DP<2>")
	)
	(segment
		(start 54.423056 -42.707052)
		(end 63.715138 -51.999134)
		(width 0.14224)
		(layer "In2.Cu")
		(net "M_G_DQS_DP<2>")
	)
	(segment
		(start 54.385464 -26.088848)
		(end 54.227984 -26.246328)
		(width 0.14224)
		(layer "In2.Cu")
		(net "M_G_DQS_DP<2>")
	)
	(segment
		(start 54.385464 -27.612848)
		(end 54.227984 -27.770328)
		(width 0.14224)
		(layer "In2.Cu")
		(net "M_G_DQS_DP<2>")
	)
	(segment
		(start 54.04485 -34.348928)
		(end 54.423056 -34.727134)
		(width 0.14224)
		(layer "In2.Cu")
		(net "M_G_DQS_DP<2>")
	)
	(segment
		(start 55.548276 -22.078188)
		(end 54.737508 -22.888956)
		(width 0.14224)
		(layer "In2.Cu")
		(net "M_G_DQS_DP<2>")
	)
	(segment
		(start 54.227984 -25.677368)
		(end 54.385464 -25.834848)
		(width 0.14224)
		(layer "In2.Cu")
		(net "M_G_DQS_DP<2>")
	)
	(segment
		(start 54.385464 -25.072848)
		(end 54.385464 -25.326848)
		(width 0.14224)
		(layer "In2.Cu")
		(net "M_G_DQS_DP<2>")
	)
	(segment
		(start 54.04485 -37.041328)
		(end 54.423056 -37.419534)
		(width 0.14224)
		(layer "In2.Cu")
		(net "M_G_DQS_DP<2>")
	)
	(segment
		(start 64.559434 -52.84343)
		(end 64.720978 -53.004974)
		(width 0.14224)
		(layer "In2.Cu")
		(net "M_G_DQS_DP<2>")
	)
	(segment
		(start 54.385464 -28.3972)
		(end 54.227984 -28.55468)
		(width 0.14224)
		(layer "In2.Cu")
		(net "M_G_DQS_DP<2>")
	)
	(segment
		(start 67.488562 -55.242714)
		(end 68.071492 -55.242714)
		(width 0.0889)
		(layer "In2.Cu")
		(net "M_G_DQS_DP<2>")
	)
	(segment
		(start 64.90081 -53.004974)
		(end 65.062354 -53.166518)
		(width 0.14224)
		(layer "In2.Cu")
		(net "M_G_DQS_DP<2>")
	)
	(segment
		(start 54.385464 -25.326848)
		(end 54.227984 -25.484328)
		(width 0.14224)
		(layer "In2.Cu")
		(net "M_G_DQS_DP<2>")
	)
	(segment
		(start 54.227984 -25.484328)
		(end 54.227984 -25.677368)
		(width 0.14224)
		(layer "In2.Cu")
		(net "M_G_DQS_DP<2>")
	)
	(segment
		(start 54.227984 -27.008328)
		(end 54.227984 -27.201368)
		(width 0.14224)
		(layer "In2.Cu")
		(net "M_G_DQS_DP<2>")
	)
	(segment
		(start 65.223898 -53.507894)
		(end 65.40373 -53.507894)
		(width 0.14224)
		(layer "In2.Cu")
		(net "M_G_DQS_DP<2>")
	)
	(segment
		(start 53.861208 -30.874208)
		(end 53.861208 -31.431992)
		(width 0.14224)
		(layer "In2.Cu")
		(net "M_G_DQS_DP<2>")
	)
	(segment
		(start 54.385464 -26.596848)
		(end 54.385464 -26.850848)
		(width 0.14224)
		(layer "In2.Cu")
		(net "M_G_DQS_DP<2>")
	)
	(arc
		(start 71.982076 -56.780938)
		(mid 72.123375 -56.924302)
		(end 72.316594 -56.980836)
		(width 0.0889)
		(layer "In2.Cu")
		(net "M_G_DQS_DP<2>")
	)
	(arc
		(start 70.612254 -56.98109)
		(mid 70.812151 -56.927381)
		(end 70.958456 -56.780938)
		(width 0.0889)
		(layer "In2.Cu")
		(net "M_G_DQS_DP<2>")
	)
	(arc
		(start 71.470266 -56.485536)
		(mid 71.765817 -56.56456)
		(end 71.982076 -56.780938)
		(width 0.0889)
		(layer "In2.Cu")
		(net "M_G_DQS_DP<2>")
	)
	(arc
		(start 70.958456 -56.780938)
		(mid 71.174519 -56.564729)
		(end 71.469758 -56.485536)
		(width 0.0889)
		(layer "In2.Cu")
		(net "M_G_DQS_DP<2>")
	)
	(arc
		(start 70.265036 -56.780938)
		(mid 70.411418 -56.927502)
		(end 70.611492 -56.98109)
		(width 0.0889)
		(layer "In2.Cu")
		(net "M_G_DQS_DP<2>")
	)
	(arc
		(start 69.766942 -56.485536)
		(mid 70.054629 -56.568057)
		(end 70.265036 -56.780938)
		(width 0.0889)
		(layer "In2.Cu")
		(net "M_G_DQS_DP<2>")
	)
	(arc
		(start 72.340724 -56.980836)
		(mid 72.663214 -56.800651)
		(end 72.700642 -56.433212)
		(width 0.0889)
		(layer "In2.Cu")
		(net "M_G_DQS_DP<2>")
	)
	(arc
		(start 72.316594 -56.980836)
		(mid 72.328659 -56.981022)
		(end 72.340724 -56.980836)
		(width 0.0889)
		(layer "In2.Cu")
		(net "M_G_DQS_DP<2>")
	)
	(segment
		(start 52.747164 -36.142676)
		(end 52.747164 -36.396676)
		(width 0.1651)
		(layer "F.Cu")
		(net "M_G_DQS_DP<1>")
	)
	(segment
		(start 68.598288 -56.488838)
		(end 68.779136 -56.488838)
		(width 0.0889)
		(layer "F.Cu")
		(net "M_G_DQS_DP<1>")
	)
	(segment
		(start 54.286658 -43.0784)
		(end 54.5846 -43.376342)
		(width 0.1651)
		(layer "F.Cu")
		(net "M_G_DQS_DP<1>")
	)
	(segment
		(start 46.5836 -25.1968)
		(end 45.350684 -25.1968)
		(width 0.1651)
		(layer "F.Cu")
		(net "M_G_DQS_DP<1>")
	)
	(segment
		(start 52.874164 -34.999676)
		(end 52.874164 -35.253676)
		(width 0.1651)
		(layer "F.Cu")
		(net "M_G_DQS_DP<1>")
	)
	(segment
		(start 52.747164 -35.634676)
		(end 52.874164 -35.761676)
		(width 0.1651)
		(layer "F.Cu")
		(net "M_G_DQS_DP<1>")
	)
	(segment
		(start 52.747164 -36.904676)
		(end 52.747164 -37.100764)
		(width 0.1651)
		(layer "F.Cu")
		(net "M_G_DQS_DP<1>")
	)
	(segment
		(start 45.743368 -24.003)
		(end 45.870368 -23.876)
		(width 0.1651)
		(layer "F.Cu")
		(net "M_G_DQS_DP<1>")
	)
	(segment
		(start 45.643546 -17.35836)
		(end 45.387514 -17.35836)
		(width 0.1651)
		(layer "F.Cu")
		(net "M_G_DQS_DP<1>")
	)
	(segment
		(start 53.7337 -42.3291)
		(end 53.6067 -42.4561)
		(width 0.1651)
		(layer "F.Cu")
		(net "M_G_DQS_DP<1>")
	)
	(segment
		(start 45.84954 -20.023582)
		(end 45.84954 -19.011646)
		(width 0.1651)
		(layer "F.Cu")
		(net "M_G_DQS_DP<1>")
	)
	(segment
		(start 52.747164 -33.356042)
		(end 52.747164 -34.110676)
		(width 0.1651)
		(layer "F.Cu")
		(net "M_G_DQS_DP<1>")
	)
	(segment
		(start 67.498468 -55.99049)
		(end 67.770756 -55.99049)
		(width 0.0889)
		(layer "F.Cu")
		(net "M_G_DQS_DP<1>")
	)
	(segment
		(start 53.7337 -43.0784)
		(end 54.286658 -43.0784)
		(width 0.1651)
		(layer "F.Cu")
		(net "M_G_DQS_DP<1>")
	)
	(segment
		(start 52.874164 -35.761676)
		(end 52.874164 -36.015676)
		(width 0.1651)
		(layer "F.Cu")
		(net "M_G_DQS_DP<1>")
	)
	(segment
		(start 52.874164 -34.237676)
		(end 52.874164 -34.491676)
		(width 0.1651)
		(layer "F.Cu")
		(net "M_G_DQS_DP<1>")
	)
	(segment
		(start 53.6067 -42.4561)
		(end 53.6067 -42.9514)
		(width 0.1651)
		(layer "F.Cu")
		(net "M_G_DQS_DP<1>")
	)
	(segment
		(start 52.874164 -36.777676)
		(end 52.747164 -36.904676)
		(width 0.1651)
		(layer "F.Cu")
		(net "M_G_DQS_DP<1>")
	)
	(segment
		(start 52.747164 -34.872676)
		(end 52.874164 -34.999676)
		(width 0.1651)
		(layer "F.Cu")
		(net "M_G_DQS_DP<1>")
	)
	(segment
		(start 55.043832 -41.0464)
		(end 55.341774 -41.344342)
		(width 0.1651)
		(layer "F.Cu")
		(net "M_G_DQS_DP<1>")
	)
	(segment
		(start 45.887386 -18.9738)
		(end 45.887386 -17.6022)
		(width 0.1651)
		(layer "F.Cu")
		(net "M_G_DQS_DP<1>")
	)
	(segment
		(start 45.887386 -17.6022)
		(end 45.643546 -17.35836)
		(width 0.1651)
		(layer "F.Cu")
		(net "M_G_DQS_DP<1>")
	)
	(segment
		(start 52.874164 -35.253676)
		(end 52.747164 -35.380676)
		(width 0.1651)
		(layer "F.Cu")
		(net "M_G_DQS_DP<1>")
	)
	(segment
		(start 45.223684 -25.0698)
		(end 45.223684 -24.141684)
		(width 0.1651)
		(layer "F.Cu")
		(net "M_G_DQS_DP<1>")
	)
	(segment
		(start 55.043832 -42.3291)
		(end 53.7337 -42.3291)
		(width 0.1651)
		(layer "F.Cu")
		(net "M_G_DQS_DP<1>")
	)
	(segment
		(start 55.341774 -42.031158)
		(end 55.043832 -42.3291)
		(width 0.1651)
		(layer "F.Cu")
		(net "M_G_DQS_DP<1>")
	)
	(segment
		(start 45.747178 -22.888956)
		(end 45.387514 -22.888956)
		(width 0.1651)
		(layer "F.Cu")
		(net "M_G_DQS_DP<1>")
	)
	(segment
		(start 45.350684 -25.1968)
		(end 45.223684 -25.0698)
		(width 0.1651)
		(layer "F.Cu")
		(net "M_G_DQS_DP<1>")
	)
	(segment
		(start 52.874164 -36.523676)
		(end 52.874164 -36.777676)
		(width 0.1651)
		(layer "F.Cu")
		(net "M_G_DQS_DP<1>")
	)
	(segment
		(start 52.747164 -35.380676)
		(end 52.747164 -35.634676)
		(width 0.1651)
		(layer "F.Cu")
		(net "M_G_DQS_DP<1>")
	)
	(segment
		(start 52.747164 -34.618676)
		(end 52.747164 -34.872676)
		(width 0.1651)
		(layer "F.Cu")
		(net "M_G_DQS_DP<1>")
	)
	(segment
		(start 51.0286 -29.6418)
		(end 46.5836 -25.1968)
		(width 0.1651)
		(layer "F.Cu")
		(net "M_G_DQS_DP<1>")
	)
	(segment
		(start 45.84954 -19.011646)
		(end 45.887386 -18.9738)
		(width 0.1651)
		(layer "F.Cu")
		(net "M_G_DQS_DP<1>")
	)
	(segment
		(start 66.838576 -55.858664)
		(end 66.895726 -55.915814)
		(width 0.0889)
		(layer "F.Cu")
		(net "M_G_DQS_DP<1>")
	)
	(segment
		(start 51.0286 -30.658816)
		(end 51.0286 -29.6418)
		(width 0.1651)
		(layer "F.Cu")
		(net "M_G_DQS_DP<1>")
	)
	(segment
		(start 51.0286 -31.637478)
		(end 52.747164 -33.356042)
		(width 0.1651)
		(layer "F.Cu")
		(net "M_G_DQS_DP<1>")
	)
	(segment
		(start 45.870368 -23.876)
		(end 45.870368 -23.012146)
		(width 0.1651)
		(layer "F.Cu")
		(net "M_G_DQS_DP<1>")
	)
	(segment
		(start 45.870368 -23.012146)
		(end 45.747178 -22.888956)
		(width 0.1651)
		(layer "F.Cu")
		(net "M_G_DQS_DP<1>")
	)
	(segment
		(start 54.5846 -43.376342)
		(end 54.5846 -45.100494)
		(width 0.1651)
		(layer "F.Cu")
		(net "M_G_DQS_DP<1>")
	)
	(segment
		(start 51.0286 -30.658816)
		(end 51.0286 -31.637478)
		(width 0.1651)
		(layer "F.Cu")
		(net "M_G_DQS_DP<1>")
	)
	(segment
		(start 68.779136 -56.085486)
		(end 68.607686 -56.085486)
		(width 0.0889)
		(layer "F.Cu")
		(net "M_G_DQS_DP<1>")
	)
	(segment
		(start 67.423792 -55.915814)
		(end 67.498468 -55.99049)
		(width 0.0889)
		(layer "F.Cu")
		(net "M_G_DQS_DP<1>")
	)
	(segment
		(start 52.747164 -36.396676)
		(end 52.874164 -36.523676)
		(width 0.1651)
		(layer "F.Cu")
		(net "M_G_DQS_DP<1>")
	)
	(segment
		(start 52.747164 -37.100764)
		(end 53.665374 -38.018974)
		(width 0.1651)
		(layer "F.Cu")
		(net "M_G_DQS_DP<1>")
	)
	(segment
		(start 52.874164 -36.015676)
		(end 52.747164 -36.142676)
		(width 0.1651)
		(layer "F.Cu")
		(net "M_G_DQS_DP<1>")
	)
	(segment
		(start 53.792374 -41.0464)
		(end 55.043832 -41.0464)
		(width 0.1651)
		(layer "F.Cu")
		(net "M_G_DQS_DP<1>")
	)
	(segment
		(start 53.665374 -40.9194)
		(end 53.792374 -41.0464)
		(width 0.1651)
		(layer "F.Cu")
		(net "M_G_DQS_DP<1>")
	)
	(segment
		(start 52.874164 -34.491676)
		(end 52.747164 -34.618676)
		(width 0.1651)
		(layer "F.Cu")
		(net "M_G_DQS_DP<1>")
	)
	(segment
		(start 53.665374 -38.018974)
		(end 53.665374 -40.9194)
		(width 0.1651)
		(layer "F.Cu")
		(net "M_G_DQS_DP<1>")
	)
	(segment
		(start 66.895726 -55.915814)
		(end 67.423792 -55.915814)
		(width 0.0889)
		(layer "F.Cu")
		(net "M_G_DQS_DP<1>")
	)
	(segment
		(start 54.5846 -45.100494)
		(end 65.34277 -55.858664)
		(width 0.1651)
		(layer "F.Cu")
		(net "M_G_DQS_DP<1>")
	)
	(segment
		(start 52.747164 -34.110676)
		(end 52.874164 -34.237676)
		(width 0.1651)
		(layer "F.Cu")
		(net "M_G_DQS_DP<1>")
	)
	(segment
		(start 45.223684 -24.141684)
		(end 45.362368 -24.003)
		(width 0.1651)
		(layer "F.Cu")
		(net "M_G_DQS_DP<1>")
	)
	(segment
		(start 65.34277 -55.858664)
		(end 66.838576 -55.858664)
		(width 0.1651)
		(layer "F.Cu")
		(net "M_G_DQS_DP<1>")
	)
	(segment
		(start 45.362368 -24.003)
		(end 45.743368 -24.003)
		(width 0.1651)
		(layer "F.Cu")
		(net "M_G_DQS_DP<1>")
	)
	(segment
		(start 55.341774 -41.344342)
		(end 55.341774 -42.031158)
		(width 0.1651)
		(layer "F.Cu")
		(net "M_G_DQS_DP<1>")
	)
	(segment
		(start 68.906136 -56.361838)
		(end 68.906136 -56.212486)
		(width 0.0889)
		(layer "F.Cu")
		(net "M_G_DQS_DP<1>")
	)
	(segment
		(start 53.6067 -42.9514)
		(end 53.7337 -43.0784)
		(width 0.1651)
		(layer "F.Cu")
		(net "M_G_DQS_DP<1>")
	)
	(via
		(at 45.387514 -22.888956)
		(size 0.508)
		(drill 0.254)
		(layers "F.Cu" "B.Cu")
		(net "M_G_DQS_DP<1>")
	)
	(via
		(at 45.387514 -17.35836)
		(size 0.508)
		(drill 0.254)
		(layers "F.Cu" "B.Cu")
		(net "M_G_DQS_DP<1>")
	)
	(via
		(at 51.0286 -30.658816)
		(size 0.508)
		(drill 0.254)
		(layers "F.Cu" "B.Cu")
		(net "M_G_DQS_DP<1>")
	)
	(arc
		(start 67.770756 -55.99049)
		(mid 68.053973 -56.074771)
		(end 68.260976 -56.285638)
		(width 0.0889)
		(layer "F.Cu")
		(net "M_G_DQS_DP<1>")
	)
	(arc
		(start 68.260976 -56.285638)
		(mid 68.403427 -56.430712)
		(end 68.598288 -56.488838)
		(width 0.0889)
		(layer "F.Cu")
		(net "M_G_DQS_DP<1>")
	)
	(arc
		(start 68.906136 -56.212486)
		(mid 68.868939 -56.122683)
		(end 68.779136 -56.085486)
		(width 0.0889)
		(layer "F.Cu")
		(net "M_G_DQS_DP<1>")
	)
	(arc
		(start 68.779136 -56.488838)
		(mid 68.868939 -56.451641)
		(end 68.906136 -56.361838)
		(width 0.0889)
		(layer "F.Cu")
		(net "M_G_DQS_DP<1>")
	)
	(segment
		(start 45.887386 -21.4122)
		(end 45.887386 -22.6314)
		(width 0.1651)
		(layer "B.Cu")
		(net "M_G_DQS_DP<1>")
	)
	(segment
		(start 45.887386 -22.6314)
		(end 45.62983 -22.888956)
		(width 0.1651)
		(layer "B.Cu")
		(net "M_G_DQS_DP<1>")
	)
	(segment
		(start 45.84954 -21.374354)
		(end 45.887386 -21.4122)
		(width 0.1651)
		(layer "B.Cu")
		(net "M_G_DQS_DP<1>")
	)
	(segment
		(start 45.84954 -20.224242)
		(end 45.84954 -21.374354)
		(width 0.1651)
		(layer "B.Cu")
		(net "M_G_DQS_DP<1>")
	)
	(segment
		(start 45.62983 -22.888956)
		(end 45.387514 -22.888956)
		(width 0.1651)
		(layer "B.Cu")
		(net "M_G_DQS_DP<1>")
	)
	(segment
		(start 46.198282 -18.169128)
		(end 45.387514 -17.35836)
		(width 0.14224)
		(layer "In2.Cu")
		(net "M_G_DQS_DP<1>")
	)
	(segment
		(start 46.198282 -22.078188)
		(end 46.198282 -18.169128)
		(width 0.14224)
		(layer "In2.Cu")
		(net "M_G_DQS_DP<1>")
	)
	(segment
		(start 45.387514 -22.888956)
		(end 46.198282 -22.078188)
		(width 0.14224)
		(layer "In2.Cu")
		(net "M_G_DQS_DP<1>")
	)
	(segment
		(start 71.763382 -16.476472)
		(end 71.6788 -16.660368)
		(width 0.1651)
		(layer "F.Cu")
		(net "M_G_DQS_DP<17>")
	)
	(segment
		(start 72.1995 -15.423642)
		(end 72.1995 -16.040354)
		(width 0.1651)
		(layer "F.Cu")
		(net "M_G_DQS_DP<17>")
	)
	(segment
		(start 71.760334 -17.702784)
		(end 72.142096 -18.084546)
		(width 0.1651)
		(layer "F.Cu")
		(net "M_G_DQS_DP<17>")
	)
	(segment
		(start 71.6788 -17.478502)
		(end 71.760334 -17.702784)
		(width 0.1651)
		(layer "F.Cu")
		(net "M_G_DQS_DP<17>")
	)
	(segment
		(start 72.1995 -16.040354)
		(end 71.763382 -16.476472)
		(width 0.1651)
		(layer "F.Cu")
		(net "M_G_DQS_DP<17>")
	)
	(segment
		(start 71.6788 -16.660368)
		(end 71.6788 -17.478502)
		(width 0.1651)
		(layer "F.Cu")
		(net "M_G_DQS_DP<17>")
	)
	(segment
		(start 84.060792 -61.038486)
		(end 83.489292 -61.038486)
		(width 0.1016)
		(layer "F.Cu")
		(net "M_G_DQS_DP<17>")
	)
	(via
		(at 72.142096 -18.084546)
		(size 0.508)
		(drill 0.254)
		(layers "F.Cu" "B.Cu")
		(net "M_G_DQS_DP<17>")
	)
	(via
		(at 72.142096 -22.1742)
		(size 0.508)
		(drill 0.254)
		(layers "F.Cu" "B.Cu")
		(net "M_G_DQS_DP<17>")
	)
	(via
		(at 83.489292 -61.038486)
		(size 0.508)
		(drill 0.254)
		(layers "F.Cu" "B.Cu")
		(net "M_G_DQS_DP<17>")
	)
	(segment
		(start 72.1995 -24.206454)
		(end 71.743316 -23.75027)
		(width 0.1651)
		(layer "B.Cu")
		(net "M_G_DQS_DP<17>")
	)
	(segment
		(start 72.1995 -24.824182)
		(end 72.1995 -24.206454)
		(width 0.1651)
		(layer "B.Cu")
		(net "M_G_DQS_DP<17>")
	)
	(segment
		(start 71.6661 -22.722332)
		(end 71.753476 -22.56282)
		(width 0.1651)
		(layer "B.Cu")
		(net "M_G_DQS_DP<17>")
	)
	(segment
		(start 71.6661 -23.617936)
		(end 71.6661 -22.722332)
		(width 0.1651)
		(layer "B.Cu")
		(net "M_G_DQS_DP<17>")
	)
	(segment
		(start 71.753476 -22.56282)
		(end 72.142096 -22.1742)
		(width 0.1651)
		(layer "B.Cu")
		(net "M_G_DQS_DP<17>")
	)
	(segment
		(start 71.743316 -23.75027)
		(end 71.6661 -23.617936)
		(width 0.1651)
		(layer "B.Cu")
		(net "M_G_DQS_DP<17>")
	)
	(segment
		(start 72.170544 -20.549108)
		(end 72.298052 -20.4216)
		(width 0.14224)
		(layer "In2.Cu")
		(net "M_G_DQS_DP<17>")
	)
	(segment
		(start 72.4535 -19.7866)
		(end 72.3265 -19.7866)
		(width 0.14224)
		(layer "In2.Cu")
		(net "M_G_DQS_DP<17>")
	)
	(segment
		(start 72.4154 -21.0439)
		(end 72.327008 -21.0439)
		(width 0.14224)
		(layer "In2.Cu")
		(net "M_G_DQS_DP<17>")
	)
	(segment
		(start 82.645758 -59.15279)
		(end 82.617818 -59.15279)
		(width 0.0889)
		(layer "In2.Cu")
		(net "M_G_DQS_DP<17>")
	)
	(segment
		(start 72.421242 -22.1742)
		(end 72.66178 -21.933662)
		(width 0.14224)
		(layer "In2.Cu")
		(net "M_G_DQS_DP<17>")
	)
	(segment
		(start 83.489292 -61.038486)
		(end 83.487514 -61.034676)
		(width 0.0889)
		(layer "In2.Cu")
		(net "M_G_DQS_DP<17>")
	)
	(segment
		(start 72.350122 -17.87652)
		(end 72.142096 -18.084546)
		(width 0.14224)
		(layer "In2.Cu")
		(net "M_G_DQS_DP<17>")
	)
	(segment
		(start 81.318354 -55.324756)
		(end 81.266792 -55.273194)
		(width 0.0889)
		(layer "In2.Cu")
		(net "M_G_DQS_DP<17>")
	)
	(segment
		(start 81.266792 -55.273194)
		(end 81.266792 -52.806854)
		(width 0.0889)
		(layer "In2.Cu")
		(net "M_G_DQS_DP<17>")
	)
	(segment
		(start 72.804528 -36.437316)
		(end 72.804528 -35.717988)
		(width 0.14224)
		(layer "In2.Cu")
		(net "M_G_DQS_DP<17>")
	)
	(segment
		(start 72.66178 -18.057114)
		(end 72.481186 -17.87652)
		(width 0.14224)
		(layer "In2.Cu")
		(net "M_G_DQS_DP<17>")
	)
	(segment
		(start 73.71969 -36.885372)
		(end 73.252584 -36.885372)
		(width 0.14224)
		(layer "In2.Cu")
		(net "M_G_DQS_DP<17>")
	)
	(segment
		(start 81.318354 -55.687976)
		(end 81.318354 -55.324756)
		(width 0.0889)
		(layer "In2.Cu")
		(net "M_G_DQS_DP<17>")
	)
	(segment
		(start 72.873616 -33.859978)
		(end 72.873616 -29.170376)
		(width 0.14224)
		(layer "In2.Cu")
		(net "M_G_DQS_DP<17>")
	)
	(segment
		(start 73.940416 -35.048444)
		(end 73.940416 -34.454338)
		(width 0.14224)
		(layer "In2.Cu")
		(net "M_G_DQS_DP<17>")
	)
	(segment
		(start 72.804528 -35.717988)
		(end 73.252584 -35.269932)
		(width 0.14224)
		(layer "In2.Cu")
		(net "M_G_DQS_DP<17>")
	)
	(segment
		(start 81.266792 -52.806854)
		(end 81.88198 -52.191666)
		(width 0.0889)
		(layer "In2.Cu")
		(net "M_G_DQS_DP<17>")
	)
	(segment
		(start 81.253076 -55.802784)
		(end 81.318354 -55.687976)
		(width 0.0889)
		(layer "In2.Cu")
		(net "M_G_DQS_DP<17>")
	)
	(segment
		(start 73.226168 -40.623236)
		(end 73.226168 -38.285928)
		(width 0.14224)
		(layer "In2.Cu")
		(net "M_G_DQS_DP<17>")
	)
	(segment
		(start 73.940416 -37.740844)
		(end 73.940416 -37.106098)
		(width 0.14224)
		(layer "In2.Cu")
		(net "M_G_DQS_DP<17>")
	)
	(segment
		(start 73.252584 -36.885372)
		(end 72.804528 -36.437316)
		(width 0.14224)
		(layer "In2.Cu")
		(net "M_G_DQS_DP<17>")
	)
	(segment
		(start 72.640444 -25.869138)
		(end 71.67118 -24.899874)
		(width 0.14224)
		(layer "In2.Cu")
		(net "M_G_DQS_DP<17>")
	)
	(segment
		(start 79.891128 -47.9806)
		(end 79.891128 -47.288196)
		(width 0.14224)
		(layer "In2.Cu")
		(net "M_G_DQS_DP<17>")
	)
	(segment
		(start 73.252584 -35.269932)
		(end 73.718928 -35.269932)
		(width 0.14224)
		(layer "In2.Cu")
		(net "M_G_DQS_DP<17>")
	)
	(segment
		(start 72.1741 -19.6342)
		(end 72.1741 -19.3802)
		(width 0.14224)
		(layer "In2.Cu")
		(net "M_G_DQS_DP<17>")
	)
	(segment
		(start 81.88198 -51.51374)
		(end 81.753964 -51.293014)
		(width 0.0889)
		(layer "In2.Cu")
		(net "M_G_DQS_DP<17>")
	)
	(segment
		(start 72.142096 -22.1742)
		(end 72.421242 -22.1742)
		(width 0.14224)
		(layer "In2.Cu")
		(net "M_G_DQS_DP<17>")
	)
	(segment
		(start 72.66178 -21.933662)
		(end 72.66178 -21.29028)
		(width 0.14224)
		(layer "In2.Cu")
		(net "M_G_DQS_DP<17>")
	)
	(segment
		(start 72.66178 -20.23872)
		(end 72.66178 -19.99488)
		(width 0.14224)
		(layer "In2.Cu")
		(net "M_G_DQS_DP<17>")
	)
	(segment
		(start 81.260442 -56.780938)
		(end 81.265268 -56.772302)
		(width 0.0889)
		(layer "In2.Cu")
		(net "M_G_DQS_DP<17>")
	)
	(segment
		(start 71.67118 -22.645116)
		(end 72.142096 -22.1742)
		(width 0.14224)
		(layer "In2.Cu")
		(net "M_G_DQS_DP<17>")
	)
	(segment
		(start 73.940416 -37.106098)
		(end 73.71969 -36.885372)
		(width 0.14224)
		(layer "In2.Cu")
		(net "M_G_DQS_DP<17>")
	)
	(segment
		(start 73.261982 -34.248344)
		(end 72.873616 -33.859978)
		(width 0.14224)
		(layer "In2.Cu")
		(net "M_G_DQS_DP<17>")
	)
	(segment
		(start 73.718928 -37.962332)
		(end 73.940416 -37.740844)
		(width 0.14224)
		(layer "In2.Cu")
		(net "M_G_DQS_DP<17>")
	)
	(segment
		(start 81.88198 -52.191666)
		(end 81.88198 -51.51374)
		(width 0.0889)
		(layer "In2.Cu")
		(net "M_G_DQS_DP<17>")
	)
	(segment
		(start 72.481186 -17.87652)
		(end 72.350122 -17.87652)
		(width 0.14224)
		(layer "In2.Cu")
		(net "M_G_DQS_DP<17>")
	)
	(segment
		(start 72.3265 -19.7866)
		(end 72.1741 -19.6342)
		(width 0.14224)
		(layer "In2.Cu")
		(net "M_G_DQS_DP<17>")
	)
	(segment
		(start 81.790286 -58.65749)
		(end 81.754472 -58.65749)
		(width 0.0889)
		(layer "In2.Cu")
		(net "M_G_DQS_DP<17>")
	)
	(segment
		(start 73.734422 -34.248344)
		(end 73.261982 -34.248344)
		(width 0.14224)
		(layer "In2.Cu")
		(net "M_G_DQS_DP<17>")
	)
	(segment
		(start 81.753964 -51.293014)
		(end 79.930498 -49.469548)
		(width 0.0889)
		(layer "In2.Cu")
		(net "M_G_DQS_DP<17>")
	)
	(segment
		(start 81.254092 -56.791606)
		(end 81.260442 -56.780938)
		(width 0.0889)
		(layer "In2.Cu")
		(net "M_G_DQS_DP<17>")
	)
	(segment
		(start 73.940416 -34.454338)
		(end 73.734422 -34.248344)
		(width 0.14224)
		(layer "In2.Cu")
		(net "M_G_DQS_DP<17>")
	)
	(segment
		(start 79.930498 -48.042068)
		(end 79.891128 -48.002698)
		(width 0.0889)
		(layer "In2.Cu")
		(net "M_G_DQS_DP<17>")
	)
	(segment
		(start 79.891128 -47.288196)
		(end 73.226168 -40.623236)
		(width 0.14224)
		(layer "In2.Cu")
		(net "M_G_DQS_DP<17>")
	)
	(segment
		(start 72.66178 -21.29028)
		(end 72.4154 -21.0439)
		(width 0.14224)
		(layer "In2.Cu")
		(net "M_G_DQS_DP<17>")
	)
	(segment
		(start 81.260442 -57.771538)
		(end 81.265268 -57.762902)
		(width 0.0889)
		(layer "In2.Cu")
		(net "M_G_DQS_DP<17>")
	)
	(segment
		(start 79.891128 -48.002698)
		(end 79.891128 -47.9806)
		(width 0.0889)
		(layer "In2.Cu")
		(net "M_G_DQS_DP<17>")
	)
	(segment
		(start 71.67118 -24.899874)
		(end 71.67118 -22.645116)
		(width 0.14224)
		(layer "In2.Cu")
		(net "M_G_DQS_DP<17>")
	)
	(segment
		(start 72.1741 -19.3802)
		(end 72.66178 -18.89252)
		(width 0.14224)
		(layer "In2.Cu")
		(net "M_G_DQS_DP<17>")
	)
	(segment
		(start 73.549764 -37.962332)
		(end 73.718928 -37.962332)
		(width 0.14224)
		(layer "In2.Cu")
		(net "M_G_DQS_DP<17>")
	)
	(segment
		(start 72.327008 -21.0439)
		(end 72.170544 -20.887436)
		(width 0.14224)
		(layer "In2.Cu")
		(net "M_G_DQS_DP<17>")
	)
	(segment
		(start 72.170544 -20.887436)
		(end 72.170544 -20.549108)
		(width 0.14224)
		(layer "In2.Cu")
		(net "M_G_DQS_DP<17>")
	)
	(segment
		(start 72.298052 -20.4216)
		(end 72.4789 -20.4216)
		(width 0.14224)
		(layer "In2.Cu")
		(net "M_G_DQS_DP<17>")
	)
	(segment
		(start 73.718928 -35.269932)
		(end 73.940416 -35.048444)
		(width 0.14224)
		(layer "In2.Cu")
		(net "M_G_DQS_DP<17>")
	)
	(segment
		(start 72.873616 -29.170376)
		(end 72.640444 -28.937204)
		(width 0.14224)
		(layer "In2.Cu")
		(net "M_G_DQS_DP<17>")
	)
	(segment
		(start 72.4789 -20.4216)
		(end 72.66178 -20.23872)
		(width 0.14224)
		(layer "In2.Cu")
		(net "M_G_DQS_DP<17>")
	)
	(segment
		(start 73.226168 -38.285928)
		(end 73.549764 -37.962332)
		(width 0.14224)
		(layer "In2.Cu")
		(net "M_G_DQS_DP<17>")
	)
	(segment
		(start 72.640444 -28.937204)
		(end 72.640444 -25.869138)
		(width 0.14224)
		(layer "In2.Cu")
		(net "M_G_DQS_DP<17>")
	)
	(segment
		(start 72.66178 -18.89252)
		(end 72.66178 -18.057114)
		(width 0.14224)
		(layer "In2.Cu")
		(net "M_G_DQS_DP<17>")
	)
	(segment
		(start 79.930498 -49.469548)
		(end 79.930498 -48.042068)
		(width 0.0889)
		(layer "In2.Cu")
		(net "M_G_DQS_DP<17>")
	)
	(segment
		(start 72.66178 -19.99488)
		(end 72.4535 -19.7866)
		(width 0.14224)
		(layer "In2.Cu")
		(net "M_G_DQS_DP<17>")
	)
	(arc
		(start 81.754472 -58.65749)
		(mid 81.256221 -58.35465)
		(end 81.260442 -57.771538)
		(width 0.0889)
		(layer "In2.Cu")
		(net "M_G_DQS_DP<17>")
	)
	(arc
		(start 83.037172 -59.475116)
		(mid 83.009471 -59.412857)
		(end 82.977482 -59.352688)
		(width 0.0889)
		(layer "In2.Cu")
		(net "M_G_DQS_DP<17>")
	)
	(arc
		(start 81.265268 -56.772302)
		(mid 81.314023 -56.57595)
		(end 81.260442 -56.380888)
		(width 0.0889)
		(layer "In2.Cu")
		(net "M_G_DQS_DP<17>")
	)
	(arc
		(start 81.260442 -56.380888)
		(mid 81.181232 -56.092794)
		(end 81.253076 -55.802784)
		(width 0.0889)
		(layer "In2.Cu")
		(net "M_G_DQS_DP<17>")
	)
	(arc
		(start 82.977482 -59.352688)
		(mid 82.837403 -59.209952)
		(end 82.645758 -59.15279)
		(width 0.0889)
		(layer "In2.Cu")
		(net "M_G_DQS_DP<17>")
	)
	(arc
		(start 83.101688 -59.948318)
		(mid 83.098924 -59.707693)
		(end 83.037172 -59.475116)
		(width 0.0889)
		(layer "In2.Cu")
		(net "M_G_DQS_DP<17>")
	)
	(arc
		(start 81.265268 -57.762902)
		(mid 81.314023 -57.56655)
		(end 81.260442 -57.371488)
		(width 0.0889)
		(layer "In2.Cu")
		(net "M_G_DQS_DP<17>")
	)
	(arc
		(start 81.260442 -57.371488)
		(mid 81.18122 -57.08237)
		(end 81.254092 -56.791606)
		(width 0.0889)
		(layer "In2.Cu")
		(net "M_G_DQS_DP<17>")
	)
	(arc
		(start 82.617818 -59.15279)
		(mid 82.329673 -59.070471)
		(end 82.118962 -58.857388)
		(width 0.0889)
		(layer "In2.Cu")
		(net "M_G_DQS_DP<17>")
	)
	(arc
		(start 83.487514 -61.034676)
		(mid 83.336696 -60.63174)
		(end 83.142582 -60.247784)
		(width 0.0889)
		(layer "In2.Cu")
		(net "M_G_DQS_DP<17>")
	)
	(arc
		(start 82.118962 -58.857388)
		(mid 81.980218 -58.715355)
		(end 81.790286 -58.65749)
		(width 0.0889)
		(layer "In2.Cu")
		(net "M_G_DQS_DP<17>")
	)
	(arc
		(start 83.142582 -60.247784)
		(mid 83.092767 -60.102059)
		(end 83.101688 -59.948318)
		(width 0.0889)
		(layer "In2.Cu")
		(net "M_G_DQS_DP<17>")
	)
	(segment
		(start 145.628868 -17.478502)
		(end 145.710402 -17.702784)
		(width 0.1651)
		(layer "F.Cu")
		(net "M_G_DQS_DP<16>")
	)
	(segment
		(start 145.628868 -16.660368)
		(end 145.628868 -17.478502)
		(width 0.1651)
		(layer "F.Cu")
		(net "M_G_DQS_DP<16>")
	)
	(segment
		(start 122.504708 -56.399938)
		(end 121.933208 -56.399938)
		(width 0.1016)
		(layer "F.Cu")
		(net "M_G_DQS_DP<16>")
	)
	(segment
		(start 146.149568 -15.423642)
		(end 146.149568 -16.040354)
		(width 0.1651)
		(layer "F.Cu")
		(net "M_G_DQS_DP<16>")
	)
	(segment
		(start 146.149568 -16.040354)
		(end 145.71345 -16.476472)
		(width 0.1651)
		(layer "F.Cu")
		(net "M_G_DQS_DP<16>")
	)
	(segment
		(start 145.71345 -16.476472)
		(end 145.628868 -16.660368)
		(width 0.1651)
		(layer "F.Cu")
		(net "M_G_DQS_DP<16>")
	)
	(segment
		(start 145.710402 -17.702784)
		(end 146.092164 -18.084546)
		(width 0.1651)
		(layer "F.Cu")
		(net "M_G_DQS_DP<16>")
	)
	(via
		(at 146.092164 -22.1742)
		(size 0.508)
		(drill 0.254)
		(layers "F.Cu" "B.Cu")
		(net "M_G_DQS_DP<16>")
	)
	(via
		(at 146.092164 -18.084546)
		(size 0.508)
		(drill 0.254)
		(layers "F.Cu" "B.Cu")
		(net "M_G_DQS_DP<16>")
	)
	(via
		(at 121.933208 -56.399938)
		(size 0.508)
		(drill 0.254)
		(layers "F.Cu" "B.Cu")
		(net "M_G_DQS_DP<16>")
	)
	(segment
		(start 146.149568 -24.824182)
		(end 146.149568 -24.206454)
		(width 0.1651)
		(layer "B.Cu")
		(net "M_G_DQS_DP<16>")
	)
	(segment
		(start 146.149568 -24.206454)
		(end 145.693384 -23.75027)
		(width 0.1651)
		(layer "B.Cu")
		(net "M_G_DQS_DP<16>")
	)
	(segment
		(start 145.693384 -23.75027)
		(end 145.616168 -23.617936)
		(width 0.1651)
		(layer "B.Cu")
		(net "M_G_DQS_DP<16>")
	)
	(segment
		(start 145.616168 -22.722332)
		(end 145.703544 -22.56282)
		(width 0.1651)
		(layer "B.Cu")
		(net "M_G_DQS_DP<16>")
	)
	(segment
		(start 145.616168 -23.617936)
		(end 145.616168 -22.722332)
		(width 0.1651)
		(layer "B.Cu")
		(net "M_G_DQS_DP<16>")
	)
	(segment
		(start 145.703544 -22.56282)
		(end 146.092164 -22.1742)
		(width 0.1651)
		(layer "B.Cu")
		(net "M_G_DQS_DP<16>")
	)
	(segment
		(start 133.952742 -43.7642)
		(end 136.751568 -43.7642)
		(width 0.14224)
		(layer "In2.Cu")
		(net "M_G_DQS_DP<16>")
	)
	(segment
		(start 146.428968 -20.4216)
		(end 146.611848 -20.23872)
		(width 0.14224)
		(layer "In2.Cu")
		(net "M_G_DQS_DP<16>")
	)
	(segment
		(start 121.398792 -55.255414)
		(end 121.421398 -55.113936)
		(width 0.0889)
		(layer "In2.Cu")
		(net "M_G_DQS_DP<16>")
	)
	(segment
		(start 146.120612 -20.549108)
		(end 146.24812 -20.4216)
		(width 0.14224)
		(layer "In2.Cu")
		(net "M_G_DQS_DP<16>")
	)
	(segment
		(start 145.590768 -22.675596)
		(end 146.092164 -22.1742)
		(width 0.14224)
		(layer "In2.Cu")
		(net "M_G_DQS_DP<16>")
	)
	(segment
		(start 146.611848 -18.89252)
		(end 146.611848 -18.057114)
		(width 0.14224)
		(layer "In2.Cu")
		(net "M_G_DQS_DP<16>")
	)
	(segment
		(start 146.124168 -19.6342)
		(end 146.124168 -19.3802)
		(width 0.14224)
		(layer "In2.Cu")
		(net "M_G_DQS_DP<16>")
	)
	(segment
		(start 132.977382 -44.83862)
		(end 133.132322 -44.99356)
		(width 0.14224)
		(layer "In2.Cu")
		(net "M_G_DQS_DP<16>")
	)
	(segment
		(start 133.640322 -44.83862)
		(end 133.640322 -44.07662)
		(width 0.14224)
		(layer "In2.Cu")
		(net "M_G_DQS_DP<16>")
	)
	(segment
		(start 123.798584 -51.007264)
		(end 123.798584 -50.953416)
		(width 0.0889)
		(layer "In2.Cu")
		(net "M_G_DQS_DP<16>")
	)
	(segment
		(start 121.586498 -55.609236)
		(end 121.398792 -55.255414)
		(width 0.0889)
		(layer "In2.Cu")
		(net "M_G_DQS_DP<16>")
	)
	(segment
		(start 146.365468 -21.0439)
		(end 146.277076 -21.0439)
		(width 0.14224)
		(layer "In2.Cu")
		(net "M_G_DQS_DP<16>")
	)
	(segment
		(start 146.403568 -36.8554)
		(end 146.403568 -25.3238)
		(width 0.14224)
		(layer "In2.Cu")
		(net "M_G_DQS_DP<16>")
	)
	(segment
		(start 143.116554 -37.399214)
		(end 145.859754 -37.399214)
		(width 0.14224)
		(layer "In2.Cu")
		(net "M_G_DQS_DP<16>")
	)
	(segment
		(start 145.692368 -24.6126)
		(end 145.692368 -23.789894)
		(width 0.14224)
		(layer "In2.Cu")
		(net "M_G_DQS_DP<16>")
	)
	(segment
		(start 146.124168 -19.3802)
		(end 146.611848 -18.89252)
		(width 0.14224)
		(layer "In2.Cu")
		(net "M_G_DQS_DP<16>")
	)
	(segment
		(start 146.611848 -18.057114)
		(end 146.431254 -17.87652)
		(width 0.14224)
		(layer "In2.Cu")
		(net "M_G_DQS_DP<16>")
	)
	(segment
		(start 146.092164 -22.1742)
		(end 146.37131 -22.1742)
		(width 0.14224)
		(layer "In2.Cu")
		(net "M_G_DQS_DP<16>")
	)
	(segment
		(start 133.132322 -44.99356)
		(end 133.485382 -44.99356)
		(width 0.14224)
		(layer "In2.Cu")
		(net "M_G_DQS_DP<16>")
	)
	(segment
		(start 128.364234 -46.387766)
		(end 129.149856 -46.387766)
		(width 0.14224)
		(layer "In2.Cu")
		(net "M_G_DQS_DP<16>")
	)
	(segment
		(start 146.611848 -21.933662)
		(end 146.611848 -21.29028)
		(width 0.14224)
		(layer "In2.Cu")
		(net "M_G_DQS_DP<16>")
	)
	(segment
		(start 133.640322 -44.07662)
		(end 133.952742 -43.7642)
		(width 0.14224)
		(layer "In2.Cu")
		(net "M_G_DQS_DP<16>")
	)
	(segment
		(start 146.120612 -20.887436)
		(end 146.120612 -20.549108)
		(width 0.14224)
		(layer "In2.Cu")
		(net "M_G_DQS_DP<16>")
	)
	(segment
		(start 121.933208 -56.399938)
		(end 121.716292 -56.012588)
		(width 0.0889)
		(layer "In2.Cu")
		(net "M_G_DQS_DP<16>")
	)
	(segment
		(start 146.276568 -19.7866)
		(end 146.124168 -19.6342)
		(width 0.14224)
		(layer "In2.Cu")
		(net "M_G_DQS_DP<16>")
	)
	(segment
		(start 123.798584 -50.953416)
		(end 123.814332 -50.937668)
		(width 0.0889)
		(layer "In2.Cu")
		(net "M_G_DQS_DP<16>")
	)
	(segment
		(start 132.977382 -44.07662)
		(end 132.977382 -44.83862)
		(width 0.14224)
		(layer "In2.Cu")
		(net "M_G_DQS_DP<16>")
	)
	(segment
		(start 122.432318 -52.37353)
		(end 123.798584 -51.007264)
		(width 0.0889)
		(layer "In2.Cu")
		(net "M_G_DQS_DP<16>")
	)
	(segment
		(start 146.30019 -17.87652)
		(end 146.092164 -18.084546)
		(width 0.14224)
		(layer "In2.Cu")
		(net "M_G_DQS_DP<16>")
	)
	(segment
		(start 145.859754 -37.399214)
		(end 146.403568 -36.8554)
		(width 0.14224)
		(layer "In2.Cu")
		(net "M_G_DQS_DP<16>")
	)
	(segment
		(start 132.664962 -43.7642)
		(end 132.977382 -44.07662)
		(width 0.14224)
		(layer "In2.Cu")
		(net "M_G_DQS_DP<16>")
	)
	(segment
		(start 146.403568 -19.7866)
		(end 146.276568 -19.7866)
		(width 0.14224)
		(layer "In2.Cu")
		(net "M_G_DQS_DP<16>")
	)
	(segment
		(start 129.149856 -46.387766)
		(end 131.773422 -43.7642)
		(width 0.14224)
		(layer "In2.Cu")
		(net "M_G_DQS_DP<16>")
	)
	(segment
		(start 133.485382 -44.99356)
		(end 133.640322 -44.83862)
		(width 0.14224)
		(layer "In2.Cu")
		(net "M_G_DQS_DP<16>")
	)
	(segment
		(start 146.431254 -17.87652)
		(end 146.30019 -17.87652)
		(width 0.14224)
		(layer "In2.Cu")
		(net "M_G_DQS_DP<16>")
	)
	(segment
		(start 121.592848 -55.619904)
		(end 121.586498 -55.609236)
		(width 0.0889)
		(layer "In2.Cu")
		(net "M_G_DQS_DP<16>")
	)
	(segment
		(start 146.611848 -19.99488)
		(end 146.403568 -19.7866)
		(width 0.14224)
		(layer "In2.Cu")
		(net "M_G_DQS_DP<16>")
	)
	(segment
		(start 145.692368 -23.789894)
		(end 145.590768 -23.688294)
		(width 0.14224)
		(layer "In2.Cu")
		(net "M_G_DQS_DP<16>")
	)
	(segment
		(start 136.751568 -43.7642)
		(end 143.116554 -37.399214)
		(width 0.14224)
		(layer "In2.Cu")
		(net "M_G_DQS_DP<16>")
	)
	(segment
		(start 146.277076 -21.0439)
		(end 146.120612 -20.887436)
		(width 0.14224)
		(layer "In2.Cu")
		(net "M_G_DQS_DP<16>")
	)
	(segment
		(start 146.24812 -20.4216)
		(end 146.428968 -20.4216)
		(width 0.14224)
		(layer "In2.Cu")
		(net "M_G_DQS_DP<16>")
	)
	(segment
		(start 121.920254 -53.827934)
		(end 121.944384 -53.827934)
		(width 0.0889)
		(layer "In2.Cu")
		(net "M_G_DQS_DP<16>")
	)
	(segment
		(start 131.773422 -43.7642)
		(end 132.664962 -43.7642)
		(width 0.14224)
		(layer "In2.Cu")
		(net "M_G_DQS_DP<16>")
	)
	(segment
		(start 145.590768 -23.688294)
		(end 145.590768 -22.675596)
		(width 0.14224)
		(layer "In2.Cu")
		(net "M_G_DQS_DP<16>")
	)
	(segment
		(start 146.403568 -25.3238)
		(end 145.692368 -24.6126)
		(width 0.14224)
		(layer "In2.Cu")
		(net "M_G_DQS_DP<16>")
	)
	(segment
		(start 123.814332 -50.937668)
		(end 128.364234 -46.387766)
		(width 0.14224)
		(layer "In2.Cu")
		(net "M_G_DQS_DP<16>")
	)
	(segment
		(start 146.611848 -20.23872)
		(end 146.611848 -19.99488)
		(width 0.14224)
		(layer "In2.Cu")
		(net "M_G_DQS_DP<16>")
	)
	(segment
		(start 146.611848 -21.29028)
		(end 146.365468 -21.0439)
		(width 0.14224)
		(layer "In2.Cu")
		(net "M_G_DQS_DP<16>")
	)
	(segment
		(start 146.37131 -22.1742)
		(end 146.611848 -21.933662)
		(width 0.14224)
		(layer "In2.Cu")
		(net "M_G_DQS_DP<16>")
	)
	(segment
		(start 122.279918 -52.637182)
		(end 122.432318 -52.37353)
		(width 0.0889)
		(layer "In2.Cu")
		(net "M_G_DQS_DP<16>")
	)
	(arc
		(start 121.415048 -54.703218)
		(mid 121.421225 -54.123286)
		(end 121.920254 -53.827934)
		(width 0.0889)
		(layer "In2.Cu")
		(net "M_G_DQS_DP<16>")
	)
	(arc
		(start 121.944384 -53.827934)
		(mid 122.282499 -53.623232)
		(end 122.279918 -53.227986)
		(width 0.0889)
		(layer "In2.Cu")
		(net "M_G_DQS_DP<16>")
	)
	(arc
		(start 122.279918 -53.227986)
		(mid 122.200787 -52.932584)
		(end 122.279918 -52.637182)
		(width 0.0889)
		(layer "In2.Cu")
		(net "M_G_DQS_DP<16>")
	)
	(arc
		(start 121.445528 -55.06466)
		(mid 121.474329 -54.891429)
		(end 121.426224 -54.722522)
		(width 0.0889)
		(layer "In2.Cu")
		(net "M_G_DQS_DP<16>")
	)
	(arc
		(start 121.426224 -54.722522)
		(mid 121.420764 -54.712796)
		(end 121.415048 -54.703218)
		(width 0.0889)
		(layer "In2.Cu")
		(net "M_G_DQS_DP<16>")
	)
	(arc
		(start 121.421398 -55.113936)
		(mid 121.434306 -55.089711)
		(end 121.445528 -55.06466)
		(width 0.0889)
		(layer "In2.Cu")
		(net "M_G_DQS_DP<16>")
	)
	(arc
		(start 121.716292 -56.012588)
		(mid 121.673968 -55.81015)
		(end 121.592848 -55.619904)
		(width 0.0889)
		(layer "In2.Cu")
		(net "M_G_DQS_DP<16>")
	)
	(segment
		(start 136.360408 -17.702784)
		(end 136.74217 -18.084546)
		(width 0.1651)
		(layer "F.Cu")
		(net "M_G_DQS_DP<15>")
	)
	(segment
		(start 136.363456 -16.476472)
		(end 136.278874 -16.660368)
		(width 0.1651)
		(layer "F.Cu")
		(net "M_G_DQS_DP<15>")
	)
	(segment
		(start 136.799574 -16.040354)
		(end 136.363456 -16.476472)
		(width 0.1651)
		(layer "F.Cu")
		(net "M_G_DQS_DP<15>")
	)
	(segment
		(start 136.278874 -16.660368)
		(end 136.278874 -17.478502)
		(width 0.1651)
		(layer "F.Cu")
		(net "M_G_DQS_DP<15>")
	)
	(segment
		(start 136.278874 -17.478502)
		(end 136.360408 -17.702784)
		(width 0.1651)
		(layer "F.Cu")
		(net "M_G_DQS_DP<15>")
	)
	(segment
		(start 117.353842 -56.399938)
		(end 116.782342 -56.399938)
		(width 0.1016)
		(layer "F.Cu")
		(net "M_G_DQS_DP<15>")
	)
	(segment
		(start 136.799574 -15.423642)
		(end 136.799574 -16.040354)
		(width 0.1651)
		(layer "F.Cu")
		(net "M_G_DQS_DP<15>")
	)
	(via
		(at 136.74217 -18.084546)
		(size 0.508)
		(drill 0.254)
		(layers "F.Cu" "B.Cu")
		(net "M_G_DQS_DP<15>")
	)
	(via
		(at 136.74217 -22.1742)
		(size 0.508)
		(drill 0.254)
		(layers "F.Cu" "B.Cu")
		(net "M_G_DQS_DP<15>")
	)
	(via
		(at 116.782342 -56.399938)
		(size 0.508)
		(drill 0.254)
		(layers "F.Cu" "B.Cu")
		(net "M_G_DQS_DP<15>")
	)
	(segment
		(start 136.799574 -24.206454)
		(end 136.34339 -23.75027)
		(width 0.1651)
		(layer "B.Cu")
		(net "M_G_DQS_DP<15>")
	)
	(segment
		(start 136.696196 -22.220428)
		(end 136.74217 -22.1742)
		(width 0.1651)
		(layer "B.Cu")
		(net "M_G_DQS_DP<15>")
	)
	(segment
		(start 136.34339 -23.75027)
		(end 136.266174 -23.617936)
		(width 0.1651)
		(layer "B.Cu")
		(net "M_G_DQS_DP<15>")
	)
	(segment
		(start 136.266174 -22.722332)
		(end 136.35355 -22.56282)
		(width 0.1651)
		(layer "B.Cu")
		(net "M_G_DQS_DP<15>")
	)
	(segment
		(start 136.35355 -22.56282)
		(end 136.696196 -22.220428)
		(width 0.1651)
		(layer "B.Cu")
		(net "M_G_DQS_DP<15>")
	)
	(segment
		(start 136.266174 -23.617936)
		(end 136.266174 -22.722332)
		(width 0.1651)
		(layer "B.Cu")
		(net "M_G_DQS_DP<15>")
	)
	(segment
		(start 136.799574 -24.824182)
		(end 136.799574 -24.206454)
		(width 0.1651)
		(layer "B.Cu")
		(net "M_G_DQS_DP<15>")
	)
	(segment
		(start 116.229638 -48.251872)
		(end 116.190268 -48.212502)
		(width 0.0889)
		(layer "In2.Cu")
		(net "M_G_DQS_DP<15>")
	)
	(segment
		(start 136.74217 -22.1742)
		(end 137.021824 -22.1742)
		(width 0.14224)
		(layer "In2.Cu")
		(net "M_G_DQS_DP<15>")
	)
	(segment
		(start 137.261854 -18.057114)
		(end 137.08126 -17.87652)
		(width 0.14224)
		(layer "In2.Cu")
		(net "M_G_DQS_DP<15>")
	)
	(segment
		(start 137.261854 -18.89252)
		(end 137.261854 -18.057114)
		(width 0.14224)
		(layer "In2.Cu")
		(net "M_G_DQS_DP<15>")
	)
	(segment
		(start 116.269262 -54.711854)
		(end 116.263166 -54.70144)
		(width 0.0889)
		(layer "In2.Cu")
		(net "M_G_DQS_DP<15>")
	)
	(segment
		(start 136.271254 -22.645116)
		(end 136.696196 -22.220428)
		(width 0.14224)
		(layer "In2.Cu")
		(net "M_G_DQS_DP<15>")
	)
	(segment
		(start 137.258044 -25.771856)
		(end 136.271254 -24.785066)
		(width 0.14224)
		(layer "In2.Cu")
		(net "M_G_DQS_DP<15>")
	)
	(segment
		(start 132.751322 -34.972752)
		(end 132.553964 -34.775394)
		(width 0.14224)
		(layer "In2.Cu")
		(net "M_G_DQS_DP<15>")
	)
	(segment
		(start 116.190268 -43.4213)
		(end 123.848368 -35.7632)
		(width 0.14224)
		(layer "In2.Cu")
		(net "M_G_DQS_DP<15>")
	)
	(segment
		(start 137.015474 -21.0439)
		(end 136.927082 -21.0439)
		(width 0.14224)
		(layer "In2.Cu")
		(net "M_G_DQS_DP<15>")
	)
	(segment
		(start 134.070598 -33.653476)
		(end 133.86054 -33.443418)
		(width 0.14224)
		(layer "In2.Cu")
		(net "M_G_DQS_DP<15>")
	)
	(segment
		(start 116.328952 -54.02199)
		(end 116.328952 -51.823366)
		(width 0.0889)
		(layer "In2.Cu")
		(net "M_G_DQS_DP<15>")
	)
	(segment
		(start 133.86054 -33.041082)
		(end 134.308596 -32.593026)
		(width 0.14224)
		(layer "In2.Cu")
		(net "M_G_DQS_DP<15>")
	)
	(segment
		(start 136.926574 -19.7866)
		(end 136.774174 -19.6342)
		(width 0.14224)
		(layer "In2.Cu")
		(net "M_G_DQS_DP<15>")
	)
	(segment
		(start 116.782342 -56.399938)
		(end 116.780564 -56.396128)
		(width 0.0889)
		(layer "In2.Cu")
		(net "M_G_DQS_DP<15>")
	)
	(segment
		(start 115.885976 -50.644298)
		(end 116.229638 -50.300636)
		(width 0.0889)
		(layer "In2.Cu")
		(net "M_G_DQS_DP<15>")
	)
	(segment
		(start 133.86054 -33.443418)
		(end 133.86054 -33.041082)
		(width 0.14224)
		(layer "In2.Cu")
		(net "M_G_DQS_DP<15>")
	)
	(segment
		(start 116.328952 -51.823366)
		(end 115.885976 -51.38039)
		(width 0.0889)
		(layer "In2.Cu")
		(net "M_G_DQS_DP<15>")
	)
	(segment
		(start 137.021824 -22.1742)
		(end 137.261854 -21.93417)
		(width 0.14224)
		(layer "In2.Cu")
		(net "M_G_DQS_DP<15>")
	)
	(segment
		(start 136.774174 -19.6342)
		(end 136.774174 -19.3802)
		(width 0.14224)
		(layer "In2.Cu")
		(net "M_G_DQS_DP<15>")
	)
	(segment
		(start 137.053574 -19.7866)
		(end 136.926574 -19.7866)
		(width 0.14224)
		(layer "In2.Cu")
		(net "M_G_DQS_DP<15>")
	)
	(segment
		(start 116.190268 -48.190404)
		(end 116.190268 -43.4213)
		(width 0.14224)
		(layer "In2.Cu")
		(net "M_G_DQS_DP<15>")
	)
	(segment
		(start 116.190268 -48.212502)
		(end 116.190268 -48.190404)
		(width 0.0889)
		(layer "In2.Cu")
		(net "M_G_DQS_DP<15>")
	)
	(segment
		(start 135.389874 -32.553148)
		(end 135.389874 -32.3342)
		(width 0.14224)
		(layer "In2.Cu")
		(net "M_G_DQS_DP<15>")
	)
	(segment
		(start 137.258044 -30.684978)
		(end 137.258044 -25.771856)
		(width 0.14224)
		(layer "In2.Cu")
		(net "M_G_DQS_DP<15>")
	)
	(segment
		(start 137.08126 -17.87652)
		(end 136.950196 -17.87652)
		(width 0.14224)
		(layer "In2.Cu")
		(net "M_G_DQS_DP<15>")
	)
	(segment
		(start 133.404356 -33.925002)
		(end 133.601714 -34.12236)
		(width 0.14224)
		(layer "In2.Cu")
		(net "M_G_DQS_DP<15>")
	)
	(segment
		(start 137.261854 -20.23872)
		(end 137.261854 -19.99488)
		(width 0.14224)
		(layer "In2.Cu")
		(net "M_G_DQS_DP<15>")
	)
	(segment
		(start 116.270278 -54.124098)
		(end 116.328952 -54.02199)
		(width 0.0889)
		(layer "In2.Cu")
		(net "M_G_DQS_DP<15>")
	)
	(segment
		(start 132.553964 -34.373058)
		(end 133.00202 -33.925002)
		(width 0.14224)
		(layer "In2.Cu")
		(net "M_G_DQS_DP<15>")
	)
	(segment
		(start 136.707372 -31.23565)
		(end 137.258044 -30.684978)
		(width 0.14224)
		(layer "In2.Cu")
		(net "M_G_DQS_DP<15>")
	)
	(segment
		(start 115.885976 -51.38039)
		(end 115.885976 -50.644298)
		(width 0.0889)
		(layer "In2.Cu")
		(net "M_G_DQS_DP<15>")
	)
	(segment
		(start 135.141716 -31.683706)
		(end 135.589772 -31.23565)
		(width 0.14224)
		(layer "In2.Cu")
		(net "M_G_DQS_DP<15>")
	)
	(segment
		(start 134.070598 -33.872424)
		(end 134.070598 -33.653476)
		(width 0.14224)
		(layer "In2.Cu")
		(net "M_G_DQS_DP<15>")
	)
	(segment
		(start 136.774174 -19.3802)
		(end 137.261854 -18.89252)
		(width 0.14224)
		(layer "In2.Cu")
		(net "M_G_DQS_DP<15>")
	)
	(segment
		(start 136.271254 -24.785066)
		(end 136.271254 -22.645116)
		(width 0.14224)
		(layer "In2.Cu")
		(net "M_G_DQS_DP<15>")
	)
	(segment
		(start 136.927082 -21.0439)
		(end 136.770618 -20.887436)
		(width 0.14224)
		(layer "In2.Cu")
		(net "M_G_DQS_DP<15>")
	)
	(segment
		(start 137.261854 -19.99488)
		(end 137.053574 -19.7866)
		(width 0.14224)
		(layer "In2.Cu")
		(net "M_G_DQS_DP<15>")
	)
	(segment
		(start 116.229638 -50.300636)
		(end 116.229638 -48.251872)
		(width 0.0889)
		(layer "In2.Cu")
		(net "M_G_DQS_DP<15>")
	)
	(segment
		(start 135.141716 -32.086042)
		(end 135.141716 -31.683706)
		(width 0.14224)
		(layer "In2.Cu")
		(net "M_G_DQS_DP<15>")
	)
	(segment
		(start 132.553964 -34.775394)
		(end 132.553964 -34.373058)
		(width 0.14224)
		(layer "In2.Cu")
		(net "M_G_DQS_DP<15>")
	)
	(segment
		(start 134.308596 -32.593026)
		(end 134.710932 -32.593026)
		(width 0.14224)
		(layer "In2.Cu")
		(net "M_G_DQS_DP<15>")
	)
	(segment
		(start 136.770618 -20.887436)
		(end 136.770618 -20.549108)
		(width 0.14224)
		(layer "In2.Cu")
		(net "M_G_DQS_DP<15>")
	)
	(segment
		(start 134.92099 -32.803084)
		(end 135.139938 -32.803084)
		(width 0.14224)
		(layer "In2.Cu")
		(net "M_G_DQS_DP<15>")
	)
	(segment
		(start 133.820662 -34.12236)
		(end 134.070598 -33.872424)
		(width 0.14224)
		(layer "In2.Cu")
		(net "M_G_DQS_DP<15>")
	)
	(segment
		(start 136.770618 -20.549108)
		(end 136.898126 -20.4216)
		(width 0.14224)
		(layer "In2.Cu")
		(net "M_G_DQS_DP<15>")
	)
	(segment
		(start 135.589772 -31.23565)
		(end 136.707372 -31.23565)
		(width 0.14224)
		(layer "In2.Cu")
		(net "M_G_DQS_DP<15>")
	)
	(segment
		(start 133.601714 -34.12236)
		(end 133.820662 -34.12236)
		(width 0.14224)
		(layer "In2.Cu")
		(net "M_G_DQS_DP<15>")
	)
	(segment
		(start 136.950196 -17.87652)
		(end 136.74217 -18.084546)
		(width 0.14224)
		(layer "In2.Cu")
		(net "M_G_DQS_DP<15>")
	)
	(segment
		(start 116.270532 -54.71414)
		(end 116.269262 -54.711854)
		(width 0.0889)
		(layer "In2.Cu")
		(net "M_G_DQS_DP<15>")
	)
	(segment
		(start 123.848368 -35.7632)
		(end 132.179822 -35.7632)
		(width 0.14224)
		(layer "In2.Cu")
		(net "M_G_DQS_DP<15>")
	)
	(segment
		(start 137.078974 -20.4216)
		(end 137.261854 -20.23872)
		(width 0.14224)
		(layer "In2.Cu")
		(net "M_G_DQS_DP<15>")
	)
	(segment
		(start 135.389874 -32.3342)
		(end 135.141716 -32.086042)
		(width 0.14224)
		(layer "In2.Cu")
		(net "M_G_DQS_DP<15>")
	)
	(segment
		(start 136.898126 -20.4216)
		(end 137.078974 -20.4216)
		(width 0.14224)
		(layer "In2.Cu")
		(net "M_G_DQS_DP<15>")
	)
	(segment
		(start 132.179822 -35.7632)
		(end 132.751322 -35.1917)
		(width 0.14224)
		(layer "In2.Cu")
		(net "M_G_DQS_DP<15>")
	)
	(segment
		(start 137.261854 -21.29028)
		(end 137.015474 -21.0439)
		(width 0.14224)
		(layer "In2.Cu")
		(net "M_G_DQS_DP<15>")
	)
	(segment
		(start 135.139938 -32.803084)
		(end 135.389874 -32.553148)
		(width 0.14224)
		(layer "In2.Cu")
		(net "M_G_DQS_DP<15>")
	)
	(segment
		(start 136.696196 -22.220428)
		(end 136.74217 -22.1742)
		(width 0.14224)
		(layer "In2.Cu")
		(net "M_G_DQS_DP<15>")
	)
	(segment
		(start 133.00202 -33.925002)
		(end 133.404356 -33.925002)
		(width 0.14224)
		(layer "In2.Cu")
		(net "M_G_DQS_DP<15>")
	)
	(segment
		(start 137.261854 -21.93417)
		(end 137.261854 -21.29028)
		(width 0.14224)
		(layer "In2.Cu")
		(net "M_G_DQS_DP<15>")
	)
	(segment
		(start 134.710932 -32.593026)
		(end 134.92099 -32.803084)
		(width 0.14224)
		(layer "In2.Cu")
		(net "M_G_DQS_DP<15>")
	)
	(segment
		(start 132.751322 -35.1917)
		(end 132.751322 -34.972752)
		(width 0.14224)
		(layer "In2.Cu")
		(net "M_G_DQS_DP<15>")
	)
	(arc
		(start 116.780564 -56.396128)
		(mid 116.629746 -55.993192)
		(end 116.435632 -55.609236)
		(width 0.0889)
		(layer "In2.Cu")
		(net "M_G_DQS_DP<15>")
	)
	(arc
		(start 116.435632 -55.609236)
		(mid 116.385817 -55.463511)
		(end 116.394738 -55.30977)
		(width 0.0889)
		(layer "In2.Cu")
		(net "M_G_DQS_DP<15>")
	)
	(arc
		(start 116.394738 -55.30977)
		(mid 116.38034 -55.002012)
		(end 116.270532 -54.71414)
		(width 0.0889)
		(layer "In2.Cu")
		(net "M_G_DQS_DP<15>")
	)
	(arc
		(start 116.263166 -54.70144)
		(mid 116.191476 -54.411858)
		(end 116.270278 -54.124098)
		(width 0.0889)
		(layer "In2.Cu")
		(net "M_G_DQS_DP<15>")
	)
	(segment
		(start 127.44958 -15.423642)
		(end 127.44958 -16.040354)
		(width 0.1651)
		(layer "F.Cu")
		(net "M_G_DQS_DP<14>")
	)
	(segment
		(start 126.92888 -17.478502)
		(end 127.010414 -17.702784)
		(width 0.1651)
		(layer "F.Cu")
		(net "M_G_DQS_DP<14>")
	)
	(segment
		(start 127.44958 -16.040354)
		(end 127.013462 -16.476472)
		(width 0.1651)
		(layer "F.Cu")
		(net "M_G_DQS_DP<14>")
	)
	(segment
		(start 127.013462 -16.476472)
		(end 126.92888 -16.660368)
		(width 0.1651)
		(layer "F.Cu")
		(net "M_G_DQS_DP<14>")
	)
	(segment
		(start 127.010414 -17.702784)
		(end 127.392176 -18.084546)
		(width 0.1651)
		(layer "F.Cu")
		(net "M_G_DQS_DP<14>")
	)
	(segment
		(start 112.202722 -56.399938)
		(end 111.631222 -56.399938)
		(width 0.1016)
		(layer "F.Cu")
		(net "M_G_DQS_DP<14>")
	)
	(segment
		(start 126.92888 -16.660368)
		(end 126.92888 -17.478502)
		(width 0.1651)
		(layer "F.Cu")
		(net "M_G_DQS_DP<14>")
	)
	(via
		(at 127.392176 -18.084546)
		(size 0.508)
		(drill 0.254)
		(layers "F.Cu" "B.Cu")
		(net "M_G_DQS_DP<14>")
	)
	(via
		(at 127.392176 -22.1742)
		(size 0.508)
		(drill 0.254)
		(layers "F.Cu" "B.Cu")
		(net "M_G_DQS_DP<14>")
	)
	(via
		(at 111.631222 -56.399938)
		(size 0.508)
		(drill 0.254)
		(layers "F.Cu" "B.Cu")
		(net "M_G_DQS_DP<14>")
	)
	(segment
		(start 127.003556 -22.56282)
		(end 127.392176 -22.1742)
		(width 0.1651)
		(layer "B.Cu")
		(net "M_G_DQS_DP<14>")
	)
	(segment
		(start 126.91618 -22.722332)
		(end 127.003556 -22.56282)
		(width 0.1651)
		(layer "B.Cu")
		(net "M_G_DQS_DP<14>")
	)
	(segment
		(start 127.44958 -24.824182)
		(end 127.44958 -24.206454)
		(width 0.1651)
		(layer "B.Cu")
		(net "M_G_DQS_DP<14>")
	)
	(segment
		(start 126.993396 -23.75027)
		(end 126.91618 -23.617936)
		(width 0.1651)
		(layer "B.Cu")
		(net "M_G_DQS_DP<14>")
	)
	(segment
		(start 127.44958 -24.206454)
		(end 126.993396 -23.75027)
		(width 0.1651)
		(layer "B.Cu")
		(net "M_G_DQS_DP<14>")
	)
	(segment
		(start 126.91618 -23.617936)
		(end 126.91618 -22.722332)
		(width 0.1651)
		(layer "B.Cu")
		(net "M_G_DQS_DP<14>")
	)
	(segment
		(start 121.842022 -27.5844)
		(end 123.696222 -25.7302)
		(width 0.14224)
		(layer "In2.Cu")
		(net "M_G_DQS_DP<14>")
	)
	(segment
		(start 127.731266 -17.87652)
		(end 127.600202 -17.87652)
		(width 0.14224)
		(layer "In2.Cu")
		(net "M_G_DQS_DP<14>")
	)
	(segment
		(start 108.872528 -46.62805)
		(end 108.872528 -36.05784)
		(width 0.14224)
		(layer "In2.Cu")
		(net "M_G_DQS_DP<14>")
	)
	(segment
		(start 127.420624 -20.887436)
		(end 127.420624 -20.549108)
		(width 0.14224)
		(layer "In2.Cu")
		(net "M_G_DQS_DP<14>")
	)
	(segment
		(start 111.989362 -33.865566)
		(end 111.748316 -33.62452)
		(width 0.14224)
		(layer "In2.Cu")
		(net "M_G_DQS_DP<14>")
	)
	(segment
		(start 127.66548 -21.0439)
		(end 127.577088 -21.0439)
		(width 0.14224)
		(layer "In2.Cu")
		(net "M_G_DQS_DP<14>")
	)
	(segment
		(start 127.91186 -20.23872)
		(end 127.91186 -19.99488)
		(width 0.14224)
		(layer "In2.Cu")
		(net "M_G_DQS_DP<14>")
	)
	(segment
		(start 114.659918 -31.28645)
		(end 114.91087 -31.035498)
		(width 0.14224)
		(layer "In2.Cu")
		(net "M_G_DQS_DP<14>")
	)
	(segment
		(start 127.91186 -18.89252)
		(end 127.91186 -18.057114)
		(width 0.14224)
		(layer "In2.Cu")
		(net "M_G_DQS_DP<14>")
	)
	(segment
		(start 114.441478 -31.28645)
		(end 114.659918 -31.28645)
		(width 0.14224)
		(layer "In2.Cu")
		(net "M_G_DQS_DP<14>")
	)
	(segment
		(start 127.577088 -21.0439)
		(end 127.420624 -20.887436)
		(width 0.14224)
		(layer "In2.Cu")
		(net "M_G_DQS_DP<14>")
	)
	(segment
		(start 111.51997 -34.334958)
		(end 111.73841 -34.334958)
		(width 0.14224)
		(layer "In2.Cu")
		(net "M_G_DQS_DP<14>")
	)
	(segment
		(start 111.119412 -54.71414)
		(end 111.117888 -54.7116)
		(width 0.0889)
		(layer "In2.Cu")
		(net "M_G_DQS_DP<14>")
	)
	(segment
		(start 127.91186 -18.057114)
		(end 127.731266 -17.87652)
		(width 0.14224)
		(layer "In2.Cu")
		(net "M_G_DQS_DP<14>")
	)
	(segment
		(start 114.263932 -31.108904)
		(end 114.441478 -31.28645)
		(width 0.14224)
		(layer "In2.Cu")
		(net "M_G_DQS_DP<14>")
	)
	(segment
		(start 110.904274 -53.35016)
		(end 110.904274 -53.056536)
		(width 0.0889)
		(layer "In2.Cu")
		(net "M_G_DQS_DP<14>")
	)
	(segment
		(start 111.73841 -34.334958)
		(end 111.989362 -34.084006)
		(width 0.14224)
		(layer "In2.Cu")
		(net "M_G_DQS_DP<14>")
	)
	(segment
		(start 109.066838 -47.062898)
		(end 109.066838 -46.82236)
		(width 0.14224)
		(layer "In2.Cu")
		(net "M_G_DQS_DP<14>")
	)
	(segment
		(start 113.122202 -32.605726)
		(end 113.340642 -32.605726)
		(width 0.14224)
		(layer "In2.Cu")
		(net "M_G_DQS_DP<14>")
	)
	(segment
		(start 111.989362 -34.084006)
		(end 111.989362 -33.865566)
		(width 0.14224)
		(layer "In2.Cu")
		(net "M_G_DQS_DP<14>")
	)
	(segment
		(start 110.904274 -53.056536)
		(end 110.164626 -52.316888)
		(width 0.0889)
		(layer "In2.Cu")
		(net "M_G_DQS_DP<14>")
	)
	(segment
		(start 109.08919 -47.08525)
		(end 109.078014 -47.08525)
		(width 0.0889)
		(layer "In2.Cu")
		(net "M_G_DQS_DP<14>")
	)
	(segment
		(start 111.748316 -33.182052)
		(end 112.502188 -32.42818)
		(width 0.14224)
		(layer "In2.Cu")
		(net "M_G_DQS_DP<14>")
	)
	(segment
		(start 127.70358 -19.7866)
		(end 127.57658 -19.7866)
		(width 0.14224)
		(layer "In2.Cu")
		(net "M_G_DQS_DP<14>")
	)
	(segment
		(start 109.959648 -35.413188)
		(end 110.200694 -35.654234)
		(width 0.14224)
		(layer "In2.Cu")
		(net "M_G_DQS_DP<14>")
	)
	(segment
		(start 114.91087 -31.035498)
		(end 114.91087 -30.817058)
		(width 0.14224)
		(layer "In2.Cu")
		(net "M_G_DQS_DP<14>")
	)
	(segment
		(start 113.591594 -32.136334)
		(end 113.414048 -31.958788)
		(width 0.14224)
		(layer "In2.Cu")
		(net "M_G_DQS_DP<14>")
	)
	(segment
		(start 111.748316 -33.62452)
		(end 111.748316 -33.182052)
		(width 0.14224)
		(layer "In2.Cu")
		(net "M_G_DQS_DP<14>")
	)
	(segment
		(start 127.91186 -21.29028)
		(end 127.66548 -21.0439)
		(width 0.14224)
		(layer "In2.Cu")
		(net "M_G_DQS_DP<14>")
	)
	(segment
		(start 110.42904 -34.943796)
		(end 110.42904 -34.501328)
		(width 0.14224)
		(layer "In2.Cu")
		(net "M_G_DQS_DP<14>")
	)
	(segment
		(start 126.35484 -25.7302)
		(end 126.89078 -25.19426)
		(width 0.14224)
		(layer "In2.Cu")
		(net "M_G_DQS_DP<14>")
	)
	(segment
		(start 127.57658 -19.7866)
		(end 127.42418 -19.6342)
		(width 0.14224)
		(layer "In2.Cu")
		(net "M_G_DQS_DP<14>")
	)
	(segment
		(start 127.91186 -21.933154)
		(end 127.91186 -21.29028)
		(width 0.14224)
		(layer "In2.Cu")
		(net "M_G_DQS_DP<14>")
	)
	(segment
		(start 110.419134 -35.654234)
		(end 110.670086 -35.403282)
		(width 0.14224)
		(layer "In2.Cu")
		(net "M_G_DQS_DP<14>")
	)
	(segment
		(start 110.836456 -34.093912)
		(end 111.278924 -34.093912)
		(width 0.14224)
		(layer "In2.Cu")
		(net "M_G_DQS_DP<14>")
	)
	(segment
		(start 110.670086 -35.184842)
		(end 110.42904 -34.943796)
		(width 0.14224)
		(layer "In2.Cu")
		(net "M_G_DQS_DP<14>")
	)
	(segment
		(start 118.763288 -27.84856)
		(end 120.322848 -27.84856)
		(width 0.14224)
		(layer "In2.Cu")
		(net "M_G_DQS_DP<14>")
	)
	(segment
		(start 113.340642 -32.605726)
		(end 113.591594 -32.354774)
		(width 0.14224)
		(layer "In2.Cu")
		(net "M_G_DQS_DP<14>")
	)
	(segment
		(start 114.733324 -30.639512)
		(end 114.733324 -30.197044)
		(width 0.14224)
		(layer "In2.Cu")
		(net "M_G_DQS_DP<14>")
	)
	(segment
		(start 113.414048 -31.51632)
		(end 113.821464 -31.108904)
		(width 0.14224)
		(layer "In2.Cu")
		(net "M_G_DQS_DP<14>")
	)
	(segment
		(start 111.117888 -54.7116)
		(end 111.115602 -54.707536)
		(width 0.0889)
		(layer "In2.Cu")
		(net "M_G_DQS_DP<14>")
	)
	(segment
		(start 111.278924 -34.093912)
		(end 111.51997 -34.334958)
		(width 0.14224)
		(layer "In2.Cu")
		(net "M_G_DQS_DP<14>")
	)
	(segment
		(start 112.502188 -32.42818)
		(end 112.944656 -32.42818)
		(width 0.14224)
		(layer "In2.Cu")
		(net "M_G_DQS_DP<14>")
	)
	(segment
		(start 110.200694 -35.654234)
		(end 110.419134 -35.654234)
		(width 0.14224)
		(layer "In2.Cu")
		(net "M_G_DQS_DP<14>")
	)
	(segment
		(start 109.066838 -46.82236)
		(end 108.872528 -46.62805)
		(width 0.14224)
		(layer "In2.Cu")
		(net "M_G_DQS_DP<14>")
	)
	(segment
		(start 127.420624 -20.549108)
		(end 127.548132 -20.4216)
		(width 0.14224)
		(layer "In2.Cu")
		(net "M_G_DQS_DP<14>")
	)
	(segment
		(start 114.91087 -30.817058)
		(end 114.733324 -30.639512)
		(width 0.14224)
		(layer "In2.Cu")
		(net "M_G_DQS_DP<14>")
	)
	(segment
		(start 127.600202 -17.87652)
		(end 127.392176 -18.084546)
		(width 0.14224)
		(layer "In2.Cu")
		(net "M_G_DQS_DP<14>")
	)
	(segment
		(start 120.322848 -27.84856)
		(end 120.587008 -27.5844)
		(width 0.14224)
		(layer "In2.Cu")
		(net "M_G_DQS_DP<14>")
	)
	(segment
		(start 120.587008 -27.5844)
		(end 121.842022 -27.5844)
		(width 0.14224)
		(layer "In2.Cu")
		(net "M_G_DQS_DP<14>")
	)
	(segment
		(start 127.42418 -19.6342)
		(end 127.42418 -19.3802)
		(width 0.14224)
		(layer "In2.Cu")
		(net "M_G_DQS_DP<14>")
	)
	(segment
		(start 110.42904 -34.501328)
		(end 110.836456 -34.093912)
		(width 0.14224)
		(layer "In2.Cu")
		(net "M_G_DQS_DP<14>")
	)
	(segment
		(start 117.345968 -27.5844)
		(end 118.499128 -27.5844)
		(width 0.14224)
		(layer "In2.Cu")
		(net "M_G_DQS_DP<14>")
	)
	(segment
		(start 111.115602 -54.707536)
		(end 111.114586 -54.706012)
		(width 0.0889)
		(layer "In2.Cu")
		(net "M_G_DQS_DP<14>")
	)
	(segment
		(start 109.106208 -47.102268)
		(end 109.08919 -47.08525)
		(width 0.0889)
		(layer "In2.Cu")
		(net "M_G_DQS_DP<14>")
	)
	(segment
		(start 127.91186 -19.99488)
		(end 127.70358 -19.7866)
		(width 0.14224)
		(layer "In2.Cu")
		(net "M_G_DQS_DP<14>")
	)
	(segment
		(start 111.119412 -53.723286)
		(end 110.904274 -53.35016)
		(width 0.0889)
		(layer "In2.Cu")
		(net "M_G_DQS_DP<14>")
	)
	(segment
		(start 127.42418 -19.3802)
		(end 127.91186 -18.89252)
		(width 0.14224)
		(layer "In2.Cu")
		(net "M_G_DQS_DP<14>")
	)
	(segment
		(start 112.944656 -32.42818)
		(end 113.122202 -32.605726)
		(width 0.14224)
		(layer "In2.Cu")
		(net "M_G_DQS_DP<14>")
	)
	(segment
		(start 127.548132 -20.4216)
		(end 127.72898 -20.4216)
		(width 0.14224)
		(layer "In2.Cu")
		(net "M_G_DQS_DP<14>")
	)
	(segment
		(start 113.591594 -32.354774)
		(end 113.591594 -32.136334)
		(width 0.14224)
		(layer "In2.Cu")
		(net "M_G_DQS_DP<14>")
	)
	(segment
		(start 111.631222 -56.399938)
		(end 111.629444 -56.396128)
		(width 0.0889)
		(layer "In2.Cu")
		(net "M_G_DQS_DP<14>")
	)
	(segment
		(start 126.89078 -22.675596)
		(end 127.392176 -22.1742)
		(width 0.14224)
		(layer "In2.Cu")
		(net "M_G_DQS_DP<14>")
	)
	(segment
		(start 113.414048 -31.958788)
		(end 113.414048 -31.51632)
		(width 0.14224)
		(layer "In2.Cu")
		(net "M_G_DQS_DP<14>")
	)
	(segment
		(start 110.164626 -52.316888)
		(end 110.164626 -51.21402)
		(width 0.0889)
		(layer "In2.Cu")
		(net "M_G_DQS_DP<14>")
	)
	(segment
		(start 127.72898 -20.4216)
		(end 127.91186 -20.23872)
		(width 0.14224)
		(layer "In2.Cu")
		(net "M_G_DQS_DP<14>")
	)
	(segment
		(start 123.696222 -25.7302)
		(end 126.35484 -25.7302)
		(width 0.14224)
		(layer "In2.Cu")
		(net "M_G_DQS_DP<14>")
	)
	(segment
		(start 114.733324 -30.197044)
		(end 117.345968 -27.5844)
		(width 0.14224)
		(layer "In2.Cu")
		(net "M_G_DQS_DP<14>")
	)
	(segment
		(start 109.106208 -50.155602)
		(end 109.106208 -47.102268)
		(width 0.0889)
		(layer "In2.Cu")
		(net "M_G_DQS_DP<14>")
	)
	(segment
		(start 110.164626 -51.21402)
		(end 109.106208 -50.155602)
		(width 0.0889)
		(layer "In2.Cu")
		(net "M_G_DQS_DP<14>")
	)
	(segment
		(start 127.392176 -22.1742)
		(end 127.670814 -22.1742)
		(width 0.14224)
		(layer "In2.Cu")
		(net "M_G_DQS_DP<14>")
	)
	(segment
		(start 111.114586 -54.706012)
		(end 111.113062 -54.703218)
		(width 0.0889)
		(layer "In2.Cu")
		(net "M_G_DQS_DP<14>")
	)
	(segment
		(start 109.066838 -47.074074)
		(end 109.066838 -47.062898)
		(width 0.0889)
		(layer "In2.Cu")
		(net "M_G_DQS_DP<14>")
	)
	(segment
		(start 110.670086 -35.403282)
		(end 110.670086 -35.184842)
		(width 0.14224)
		(layer "In2.Cu")
		(net "M_G_DQS_DP<14>")
	)
	(segment
		(start 108.872528 -36.05784)
		(end 109.51718 -35.413188)
		(width 0.14224)
		(layer "In2.Cu")
		(net "M_G_DQS_DP<14>")
	)
	(segment
		(start 113.821464 -31.108904)
		(end 114.263932 -31.108904)
		(width 0.14224)
		(layer "In2.Cu")
		(net "M_G_DQS_DP<14>")
	)
	(segment
		(start 126.89078 -25.19426)
		(end 126.89078 -22.675596)
		(width 0.14224)
		(layer "In2.Cu")
		(net "M_G_DQS_DP<14>")
	)
	(segment
		(start 109.51718 -35.413188)
		(end 109.959648 -35.413188)
		(width 0.14224)
		(layer "In2.Cu")
		(net "M_G_DQS_DP<14>")
	)
	(segment
		(start 109.078014 -47.08525)
		(end 109.066838 -47.074074)
		(width 0.0889)
		(layer "In2.Cu")
		(net "M_G_DQS_DP<14>")
	)
	(segment
		(start 118.499128 -27.5844)
		(end 118.763288 -27.84856)
		(width 0.14224)
		(layer "In2.Cu")
		(net "M_G_DQS_DP<14>")
	)
	(segment
		(start 127.670814 -22.1742)
		(end 127.91186 -21.933154)
		(width 0.14224)
		(layer "In2.Cu")
		(net "M_G_DQS_DP<14>")
	)
	(arc
		(start 111.284512 -55.609236)
		(mid 111.234697 -55.463511)
		(end 111.243618 -55.30977)
		(width 0.0889)
		(layer "In2.Cu")
		(net "M_G_DQS_DP<14>")
	)
	(arc
		(start 111.243618 -55.30977)
		(mid 111.22922 -55.002012)
		(end 111.119412 -54.71414)
		(width 0.0889)
		(layer "In2.Cu")
		(net "M_G_DQS_DP<14>")
	)
	(arc
		(start 111.629444 -56.396128)
		(mid 111.478626 -55.993192)
		(end 111.284512 -55.609236)
		(width 0.0889)
		(layer "In2.Cu")
		(net "M_G_DQS_DP<14>")
	)
	(arc
		(start 111.119412 -54.123336)
		(mid 111.172945 -53.923328)
		(end 111.119412 -53.723286)
		(width 0.0889)
		(layer "In2.Cu")
		(net "M_G_DQS_DP<14>")
	)
	(arc
		(start 111.113062 -54.703218)
		(mid 111.040264 -54.412455)
		(end 111.119412 -54.123336)
		(width 0.0889)
		(layer "In2.Cu")
		(net "M_G_DQS_DP<14>")
	)
	(segment
		(start 115.640612 -30.236668)
		(end 116.134896 -30.236668)
		(width 0.1651)
		(layer "F.Cu")
		(net "M_G_DQS_DP<13>")
	)
	(segment
		(start 116.914168 -29.21)
		(end 116.914168 -28.403804)
		(width 0.1651)
		(layer "F.Cu")
		(net "M_G_DQS_DP<13>")
	)
	(segment
		(start 112.305592 -33.571688)
		(end 112.799876 -33.571688)
		(width 0.1651)
		(layer "F.Cu")
		(net "M_G_DQS_DP<13>")
	)
	(segment
		(start 113.973102 -31.904178)
		(end 114.467386 -31.904178)
		(width 0.1651)
		(layer "F.Cu")
		(net "M_G_DQS_DP<13>")
	)
	(segment
		(start 111.759746 -34.611818)
		(end 111.759746 -34.117534)
		(width 0.1651)
		(layer "F.Cu")
		(net "M_G_DQS_DP<13>")
	)
	(segment
		(start 115.181126 -31.615126)
		(end 115.181126 -31.363158)
		(width 0.1651)
		(layer "F.Cu")
		(net "M_G_DQS_DP<13>")
	)
	(segment
		(start 117.384068 -26.7589)
		(end 117.384068 -24.168354)
		(width 0.1651)
		(layer "F.Cu")
		(net "M_G_DQS_DP<13>")
	)
	(segment
		(start 116.473224 -30.323028)
		(end 116.914168 -29.882084)
		(width 0.1651)
		(layer "F.Cu")
		(net "M_G_DQS_DP<13>")
	)
	(segment
		(start 108.201206 -51.097942)
		(end 108.310172 -50.90795)
		(width 0.0889)
		(layer "F.Cu")
		(net "M_G_DQS_DP<13>")
	)
	(segment
		(start 114.805714 -31.990538)
		(end 115.181126 -31.615126)
		(width 0.1651)
		(layer "F.Cu")
		(net "M_G_DQS_DP<13>")
	)
	(segment
		(start 115.181126 -31.363158)
		(end 115.094766 -31.276798)
		(width 0.1651)
		(layer "F.Cu")
		(net "M_G_DQS_DP<13>")
	)
	(segment
		(start 117.561868 -23.990554)
		(end 117.561868 -22.65426)
		(width 0.1651)
		(layer "F.Cu")
		(net "M_G_DQS_DP<13>")
	)
	(segment
		(start 112.886236 -33.658048)
		(end 113.138204 -33.658048)
		(width 0.1651)
		(layer "F.Cu")
		(net "M_G_DQS_DP<13>")
	)
	(segment
		(start 116.134896 -30.236668)
		(end 116.221256 -30.323028)
		(width 0.1651)
		(layer "F.Cu")
		(net "M_G_DQS_DP<13>")
	)
	(segment
		(start 111.759746 -34.117534)
		(end 112.305592 -33.571688)
		(width 0.1651)
		(layer "F.Cu")
		(net "M_G_DQS_DP<13>")
	)
	(segment
		(start 108.265468 -51.755802)
		(end 108.265722 -51.755802)
		(width 0.0889)
		(layer "F.Cu")
		(net "M_G_DQS_DP<13>")
	)
	(segment
		(start 117.578632 -16.660368)
		(end 117.578632 -17.478502)
		(width 0.1651)
		(layer "F.Cu")
		(net "M_G_DQS_DP<13>")
	)
	(segment
		(start 108.227622 -37.721032)
		(end 110.623096 -35.325558)
		(width 0.1651)
		(layer "F.Cu")
		(net "M_G_DQS_DP<13>")
	)
	(segment
		(start 108.197142 -49.812448)
		(end 108.197142 -40.381174)
		(width 0.1016)
		(layer "F.Cu")
		(net "M_G_DQS_DP<13>")
	)
	(segment
		(start 117.561868 -22.65426)
		(end 118.041928 -22.1742)
		(width 0.1651)
		(layer "F.Cu")
		(net "M_G_DQS_DP<13>")
	)
	(segment
		(start 117.660166 -17.702784)
		(end 118.041928 -18.084546)
		(width 0.1651)
		(layer "F.Cu")
		(net "M_G_DQS_DP<13>")
	)
	(segment
		(start 114.467386 -31.904178)
		(end 114.553746 -31.990538)
		(width 0.1651)
		(layer "F.Cu")
		(net "M_G_DQS_DP<13>")
	)
	(segment
		(start 115.094766 -31.276798)
		(end 115.094766 -30.782514)
		(width 0.1651)
		(layer "F.Cu")
		(net "M_G_DQS_DP<13>")
	)
	(segment
		(start 111.846106 -34.698178)
		(end 111.759746 -34.611818)
		(width 0.1651)
		(layer "F.Cu")
		(net "M_G_DQS_DP<13>")
	)
	(segment
		(start 113.513616 -33.282636)
		(end 113.513616 -33.030668)
		(width 0.1651)
		(layer "F.Cu")
		(net "M_G_DQS_DP<13>")
	)
	(segment
		(start 108.227622 -40.350694)
		(end 108.227622 -37.721032)
		(width 0.1651)
		(layer "F.Cu")
		(net "M_G_DQS_DP<13>")
	)
	(segment
		(start 116.710968 -27.432)
		(end 117.384068 -26.7589)
		(width 0.1651)
		(layer "F.Cu")
		(net "M_G_DQS_DP<13>")
	)
	(segment
		(start 108.310172 -49.925478)
		(end 108.197142 -49.812448)
		(width 0.0889)
		(layer "F.Cu")
		(net "M_G_DQS_DP<13>")
	)
	(segment
		(start 108.310172 -50.90795)
		(end 108.310172 -49.925478)
		(width 0.0889)
		(layer "F.Cu")
		(net "M_G_DQS_DP<13>")
	)
	(segment
		(start 118.099332 -15.423642)
		(end 118.099332 -16.040608)
		(width 0.1651)
		(layer "F.Cu")
		(net "M_G_DQS_DP<13>")
	)
	(segment
		(start 116.914168 -29.882084)
		(end 116.914168 -29.21)
		(width 0.1651)
		(layer "F.Cu")
		(net "M_G_DQS_DP<13>")
	)
	(segment
		(start 116.710968 -28.200604)
		(end 116.710968 -27.432)
		(width 0.1651)
		(layer "F.Cu")
		(net "M_G_DQS_DP<13>")
	)
	(segment
		(start 117.578632 -17.478502)
		(end 117.660166 -17.702784)
		(width 0.1651)
		(layer "F.Cu")
		(net "M_G_DQS_DP<13>")
	)
	(segment
		(start 118.099332 -16.040608)
		(end 117.663214 -16.476726)
		(width 0.1651)
		(layer "F.Cu")
		(net "M_G_DQS_DP<13>")
	)
	(segment
		(start 111.470694 -35.325558)
		(end 111.846106 -34.950146)
		(width 0.1651)
		(layer "F.Cu")
		(net "M_G_DQS_DP<13>")
	)
	(segment
		(start 113.427256 -32.944308)
		(end 113.427256 -32.450024)
		(width 0.1651)
		(layer "F.Cu")
		(net "M_G_DQS_DP<13>")
	)
	(segment
		(start 113.427256 -32.450024)
		(end 113.973102 -31.904178)
		(width 0.1651)
		(layer "F.Cu")
		(net "M_G_DQS_DP<13>")
	)
	(segment
		(start 113.513616 -33.030668)
		(end 113.427256 -32.944308)
		(width 0.1651)
		(layer "F.Cu")
		(net "M_G_DQS_DP<13>")
	)
	(segment
		(start 117.663214 -16.476726)
		(end 117.578632 -16.660368)
		(width 0.1651)
		(layer "F.Cu")
		(net "M_G_DQS_DP<13>")
	)
	(segment
		(start 115.094766 -30.782514)
		(end 115.640612 -30.236668)
		(width 0.1651)
		(layer "F.Cu")
		(net "M_G_DQS_DP<13>")
	)
	(segment
		(start 108.197142 -40.381174)
		(end 108.227622 -40.350694)
		(width 0.1016)
		(layer "F.Cu")
		(net "M_G_DQS_DP<13>")
	)
	(segment
		(start 108.768896 -52.437538)
		(end 108.508546 -52.115212)
		(width 0.0889)
		(layer "F.Cu")
		(net "M_G_DQS_DP<13>")
	)
	(segment
		(start 112.799876 -33.571688)
		(end 112.886236 -33.658048)
		(width 0.1651)
		(layer "F.Cu")
		(net "M_G_DQS_DP<13>")
	)
	(segment
		(start 116.221256 -30.323028)
		(end 116.473224 -30.323028)
		(width 0.1651)
		(layer "F.Cu")
		(net "M_G_DQS_DP<13>")
	)
	(segment
		(start 111.846106 -34.950146)
		(end 111.846106 -34.698178)
		(width 0.1651)
		(layer "F.Cu")
		(net "M_G_DQS_DP<13>")
	)
	(segment
		(start 110.623096 -35.325558)
		(end 111.470694 -35.325558)
		(width 0.1651)
		(layer "F.Cu")
		(net "M_G_DQS_DP<13>")
	)
	(segment
		(start 117.384068 -24.168354)
		(end 117.561868 -23.990554)
		(width 0.1651)
		(layer "F.Cu")
		(net "M_G_DQS_DP<13>")
	)
	(segment
		(start 113.138204 -33.658048)
		(end 113.513616 -33.282636)
		(width 0.1651)
		(layer "F.Cu")
		(net "M_G_DQS_DP<13>")
	)
	(segment
		(start 114.553746 -31.990538)
		(end 114.805714 -31.990538)
		(width 0.1651)
		(layer "F.Cu")
		(net "M_G_DQS_DP<13>")
	)
	(segment
		(start 108.201206 -51.527456)
		(end 108.201206 -51.097942)
		(width 0.0889)
		(layer "F.Cu")
		(net "M_G_DQS_DP<13>")
	)
	(segment
		(start 116.914168 -28.403804)
		(end 116.710968 -28.200604)
		(width 0.1651)
		(layer "F.Cu")
		(net "M_G_DQS_DP<13>")
	)
	(via
		(at 116.914168 -29.21)
		(size 0.508)
		(drill 0.254)
		(layers "F.Cu" "B.Cu")
		(net "M_G_DQS_DP<13>")
	)
	(via
		(at 118.041928 -22.1742)
		(size 0.508)
		(drill 0.254)
		(layers "F.Cu" "B.Cu")
		(net "M_G_DQS_DP<13>")
	)
	(via
		(at 118.041928 -18.084546)
		(size 0.508)
		(drill 0.254)
		(layers "F.Cu" "B.Cu")
		(net "M_G_DQS_DP<13>")
	)
	(arc
		(start 108.265722 -51.755802)
		(mid 108.217591 -51.646108)
		(end 108.201206 -51.527456)
		(width 0.0889)
		(layer "F.Cu")
		(net "M_G_DQS_DP<13>")
	)
	(arc
		(start 108.508546 -52.115212)
		(mid 108.383076 -51.938165)
		(end 108.265468 -51.755802)
		(width 0.0889)
		(layer "F.Cu")
		(net "M_G_DQS_DP<13>")
	)
	(segment
		(start 117.653308 -22.56282)
		(end 118.041928 -22.1742)
		(width 0.1651)
		(layer "B.Cu")
		(net "M_G_DQS_DP<13>")
	)
	(segment
		(start 118.099332 -24.824182)
		(end 118.099332 -24.206454)
		(width 0.1651)
		(layer "B.Cu")
		(net "M_G_DQS_DP<13>")
	)
	(segment
		(start 117.643148 -23.75027)
		(end 117.565932 -23.617936)
		(width 0.1651)
		(layer "B.Cu")
		(net "M_G_DQS_DP<13>")
	)
	(segment
		(start 118.099332 -24.206454)
		(end 117.643148 -23.75027)
		(width 0.1651)
		(layer "B.Cu")
		(net "M_G_DQS_DP<13>")
	)
	(segment
		(start 117.565932 -22.722332)
		(end 117.653308 -22.56282)
		(width 0.1651)
		(layer "B.Cu")
		(net "M_G_DQS_DP<13>")
	)
	(segment
		(start 117.565932 -23.617936)
		(end 117.565932 -22.722332)
		(width 0.1651)
		(layer "B.Cu")
		(net "M_G_DQS_DP<13>")
	)
	(segment
		(start 118.378732 -20.4216)
		(end 118.561612 -20.23872)
		(width 0.14224)
		(layer "In2.Cu")
		(net "M_G_DQS_DP<13>")
	)
	(segment
		(start 118.561612 -21.933662)
		(end 118.561612 -21.29028)
		(width 0.14224)
		(layer "In2.Cu")
		(net "M_G_DQS_DP<13>")
	)
	(segment
		(start 118.561612 -18.89252)
		(end 118.561612 -18.057114)
		(width 0.14224)
		(layer "In2.Cu")
		(net "M_G_DQS_DP<13>")
	)
	(segment
		(start 118.561612 -18.057114)
		(end 118.381018 -17.87652)
		(width 0.14224)
		(layer "In2.Cu")
		(net "M_G_DQS_DP<13>")
	)
	(segment
		(start 118.197884 -20.4216)
		(end 118.378732 -20.4216)
		(width 0.14224)
		(layer "In2.Cu")
		(net "M_G_DQS_DP<13>")
	)
	(segment
		(start 118.353332 -19.7866)
		(end 118.226332 -19.7866)
		(width 0.14224)
		(layer "In2.Cu")
		(net "M_G_DQS_DP<13>")
	)
	(segment
		(start 118.249954 -17.87652)
		(end 118.041928 -18.084546)
		(width 0.14224)
		(layer "In2.Cu")
		(net "M_G_DQS_DP<13>")
	)
	(segment
		(start 118.073932 -19.6342)
		(end 118.073932 -19.3802)
		(width 0.14224)
		(layer "In2.Cu")
		(net "M_G_DQS_DP<13>")
	)
	(segment
		(start 118.070376 -20.549108)
		(end 118.197884 -20.4216)
		(width 0.14224)
		(layer "In2.Cu")
		(net "M_G_DQS_DP<13>")
	)
	(segment
		(start 118.22684 -21.0439)
		(end 118.070376 -20.887436)
		(width 0.14224)
		(layer "In2.Cu")
		(net "M_G_DQS_DP<13>")
	)
	(segment
		(start 118.561612 -20.23872)
		(end 118.561612 -19.99488)
		(width 0.14224)
		(layer "In2.Cu")
		(net "M_G_DQS_DP<13>")
	)
	(segment
		(start 118.315232 -21.0439)
		(end 118.22684 -21.0439)
		(width 0.14224)
		(layer "In2.Cu")
		(net "M_G_DQS_DP<13>")
	)
	(segment
		(start 118.226332 -19.7866)
		(end 118.073932 -19.6342)
		(width 0.14224)
		(layer "In2.Cu")
		(net "M_G_DQS_DP<13>")
	)
	(segment
		(start 118.321074 -22.1742)
		(end 118.561612 -21.933662)
		(width 0.14224)
		(layer "In2.Cu")
		(net "M_G_DQS_DP<13>")
	)
	(segment
		(start 118.381018 -17.87652)
		(end 118.249954 -17.87652)
		(width 0.14224)
		(layer "In2.Cu")
		(net "M_G_DQS_DP<13>")
	)
	(segment
		(start 118.041928 -22.1742)
		(end 118.321074 -22.1742)
		(width 0.14224)
		(layer "In2.Cu")
		(net "M_G_DQS_DP<13>")
	)
	(segment
		(start 118.561612 -21.29028)
		(end 118.315232 -21.0439)
		(width 0.14224)
		(layer "In2.Cu")
		(net "M_G_DQS_DP<13>")
	)
	(segment
		(start 118.561612 -19.99488)
		(end 118.353332 -19.7866)
		(width 0.14224)
		(layer "In2.Cu")
		(net "M_G_DQS_DP<13>")
	)
	(segment
		(start 118.070376 -20.887436)
		(end 118.070376 -20.549108)
		(width 0.14224)
		(layer "In2.Cu")
		(net "M_G_DQS_DP<13>")
	)
	(segment
		(start 118.073932 -19.3802)
		(end 118.561612 -18.89252)
		(width 0.14224)
		(layer "In2.Cu")
		(net "M_G_DQS_DP<13>")
	)
	(segment
		(start 62.41034 -17.702784)
		(end 62.792102 -18.084546)
		(width 0.1651)
		(layer "F.Cu")
		(net "M_G_DQS_DP<12>")
	)
	(segment
		(start 62.328806 -17.478502)
		(end 62.41034 -17.702784)
		(width 0.1651)
		(layer "F.Cu")
		(net "M_G_DQS_DP<12>")
	)
	(segment
		(start 62.849506 -15.423642)
		(end 62.849506 -16.040354)
		(width 0.1651)
		(layer "F.Cu")
		(net "M_G_DQS_DP<12>")
	)
	(segment
		(start 62.413388 -16.476472)
		(end 62.328806 -16.660368)
		(width 0.1651)
		(layer "F.Cu")
		(net "M_G_DQS_DP<12>")
	)
	(segment
		(start 77.192886 -55.094886)
		(end 76.621386 -55.094886)
		(width 0.1016)
		(layer "F.Cu")
		(net "M_G_DQS_DP<12>")
	)
	(segment
		(start 62.849506 -16.040354)
		(end 62.413388 -16.476472)
		(width 0.1651)
		(layer "F.Cu")
		(net "M_G_DQS_DP<12>")
	)
	(segment
		(start 62.328806 -16.660368)
		(end 62.328806 -17.478502)
		(width 0.1651)
		(layer "F.Cu")
		(net "M_G_DQS_DP<12>")
	)
	(via
		(at 62.792102 -22.1742)
		(size 0.508)
		(drill 0.254)
		(layers "F.Cu" "B.Cu")
		(net "M_G_DQS_DP<12>")
	)
	(via
		(at 76.621386 -55.094886)
		(size 0.508)
		(drill 0.254)
		(layers "F.Cu" "B.Cu")
		(net "M_G_DQS_DP<12>")
	)
	(via
		(at 62.792102 -18.084546)
		(size 0.508)
		(drill 0.254)
		(layers "F.Cu" "B.Cu")
		(net "M_G_DQS_DP<12>")
	)
	(segment
		(start 62.316106 -22.722332)
		(end 62.403482 -22.56282)
		(width 0.1651)
		(layer "B.Cu")
		(net "M_G_DQS_DP<12>")
	)
	(segment
		(start 62.316106 -23.617936)
		(end 62.316106 -22.722332)
		(width 0.1651)
		(layer "B.Cu")
		(net "M_G_DQS_DP<12>")
	)
	(segment
		(start 62.393322 -23.75027)
		(end 62.316106 -23.617936)
		(width 0.1651)
		(layer "B.Cu")
		(net "M_G_DQS_DP<12>")
	)
	(segment
		(start 62.849506 -24.824182)
		(end 62.849506 -24.206454)
		(width 0.1651)
		(layer "B.Cu")
		(net "M_G_DQS_DP<12>")
	)
	(segment
		(start 62.403482 -22.56282)
		(end 62.792102 -22.1742)
		(width 0.1651)
		(layer "B.Cu")
		(net "M_G_DQS_DP<12>")
	)
	(segment
		(start 62.849506 -24.206454)
		(end 62.393322 -23.75027)
		(width 0.1651)
		(layer "B.Cu")
		(net "M_G_DQS_DP<12>")
	)
	(segment
		(start 62.977014 -21.0439)
		(end 62.82055 -20.887436)
		(width 0.14224)
		(layer "In2.Cu")
		(net "M_G_DQS_DP<12>")
	)
	(segment
		(start 71.171562 -49.481994)
		(end 71.117968 -49.4284)
		(width 0.1016)
		(layer "In2.Cu")
		(net "M_G_DQS_DP<12>")
	)
	(segment
		(start 62.976506 -19.7866)
		(end 62.824106 -19.6342)
		(width 0.14224)
		(layer "In2.Cu")
		(net "M_G_DQS_DP<12>")
	)
	(segment
		(start 62.561216 -37.118798)
		(end 62.939422 -36.740592)
		(width 0.14224)
		(layer "In2.Cu")
		(net "M_G_DQS_DP<12>")
	)
	(segment
		(start 74.06386 -52.21859)
		(end 74.024236 -52.21859)
		(width 0.0889)
		(layer "In2.Cu")
		(net "M_G_DQS_DP<12>")
	)
	(segment
		(start 62.824106 -19.6342)
		(end 62.824106 -19.3802)
		(width 0.14224)
		(layer "In2.Cu")
		(net "M_G_DQS_DP<12>")
	)
	(segment
		(start 63.374016 -33.879282)
		(end 63.293244 -33.79851)
		(width 0.14224)
		(layer "In2.Cu")
		(net "M_G_DQS_DP<12>")
	)
	(segment
		(start 74.92238 -52.71389)
		(end 74.886566 -52.71389)
		(width 0.0889)
		(layer "In2.Cu")
		(net "M_G_DQS_DP<12>")
	)
	(segment
		(start 63.374016 -36.544504)
		(end 63.374016 -33.879282)
		(width 0.14224)
		(layer "In2.Cu")
		(net "M_G_DQS_DP<12>")
	)
	(segment
		(start 62.82055 -20.887436)
		(end 62.82055 -20.549108)
		(width 0.14224)
		(layer "In2.Cu")
		(net "M_G_DQS_DP<12>")
	)
	(segment
		(start 63.177928 -36.740592)
		(end 63.374016 -36.544504)
		(width 0.14224)
		(layer "In2.Cu")
		(net "M_G_DQS_DP<12>")
	)
	(segment
		(start 62.321186 -22.645116)
		(end 62.792102 -22.1742)
		(width 0.14224)
		(layer "In2.Cu")
		(net "M_G_DQS_DP<12>")
	)
	(segment
		(start 63.406528 -39.432992)
		(end 63.628016 -39.211504)
		(width 0.14224)
		(layer "In2.Cu")
		(net "M_G_DQS_DP<12>")
	)
	(segment
		(start 63.628016 -38.57752)
		(end 63.406528 -38.356032)
		(width 0.14224)
		(layer "In2.Cu")
		(net "M_G_DQS_DP<12>")
	)
	(segment
		(start 62.939422 -38.356032)
		(end 62.561216 -37.977826)
		(width 0.14224)
		(layer "In2.Cu")
		(net "M_G_DQS_DP<12>")
	)
	(segment
		(start 62.321186 -24.722074)
		(end 62.321186 -22.645116)
		(width 0.14224)
		(layer "In2.Cu")
		(net "M_G_DQS_DP<12>")
	)
	(segment
		(start 62.948058 -20.4216)
		(end 63.128906 -20.4216)
		(width 0.14224)
		(layer "In2.Cu")
		(net "M_G_DQS_DP<12>")
	)
	(segment
		(start 62.561216 -40.670226)
		(end 62.561216 -39.811198)
		(width 0.14224)
		(layer "In2.Cu")
		(net "M_G_DQS_DP<12>")
	)
	(segment
		(start 75.777852 -53.20919)
		(end 75.749912 -53.20919)
		(width 0.0889)
		(layer "In2.Cu")
		(net "M_G_DQS_DP<12>")
	)
	(segment
		(start 62.939422 -39.432992)
		(end 63.406528 -39.432992)
		(width 0.14224)
		(layer "In2.Cu")
		(net "M_G_DQS_DP<12>")
	)
	(segment
		(start 71.736712 -50.793142)
		(end 71.736712 -50.019712)
		(width 0.0889)
		(layer "In2.Cu")
		(net "M_G_DQS_DP<12>")
	)
	(segment
		(start 63.311786 -18.89252)
		(end 63.311786 -18.057114)
		(width 0.14224)
		(layer "In2.Cu")
		(net "M_G_DQS_DP<12>")
	)
	(segment
		(start 71.736712 -50.019712)
		(end 71.198994 -49.481994)
		(width 0.0889)
		(layer "In2.Cu")
		(net "M_G_DQS_DP<12>")
	)
	(segment
		(start 63.131192 -17.87652)
		(end 63.000128 -17.87652)
		(width 0.14224)
		(layer "In2.Cu")
		(net "M_G_DQS_DP<12>")
	)
	(segment
		(start 63.293244 -33.79851)
		(end 63.293244 -25.694132)
		(width 0.14224)
		(layer "In2.Cu")
		(net "M_G_DQS_DP<12>")
	)
	(segment
		(start 63.628016 -41.269158)
		(end 63.40729 -41.048432)
		(width 0.14224)
		(layer "In2.Cu")
		(net "M_G_DQS_DP<12>")
	)
	(segment
		(start 73.198482 -51.72329)
		(end 73.174352 -51.72329)
		(width 0.0889)
		(layer "In2.Cu")
		(net "M_G_DQS_DP<12>")
	)
	(segment
		(start 76.621386 -55.094886)
		(end 76.291694 -54.333648)
		(width 0.0889)
		(layer "In2.Cu")
		(net "M_G_DQS_DP<12>")
	)
	(segment
		(start 72.343772 -51.22799)
		(end 72.31507 -51.22799)
		(width 0.0889)
		(layer "In2.Cu")
		(net "M_G_DQS_DP<12>")
	)
	(segment
		(start 76.291694 -54.333648)
		(end 76.274676 -54.304438)
		(width 0.0889)
		(layer "In2.Cu")
		(net "M_G_DQS_DP<12>")
	)
	(segment
		(start 71.198994 -49.481994)
		(end 71.171562 -49.481994)
		(width 0.0889)
		(layer "In2.Cu")
		(net "M_G_DQS_DP<12>")
	)
	(segment
		(start 62.824106 -19.3802)
		(end 63.311786 -18.89252)
		(width 0.14224)
		(layer "In2.Cu")
		(net "M_G_DQS_DP<12>")
	)
	(segment
		(start 63.628016 -39.211504)
		(end 63.628016 -38.57752)
		(width 0.14224)
		(layer "In2.Cu")
		(net "M_G_DQS_DP<12>")
	)
	(segment
		(start 63.293244 -25.694132)
		(end 62.321186 -24.722074)
		(width 0.14224)
		(layer "In2.Cu")
		(net "M_G_DQS_DP<12>")
	)
	(segment
		(start 63.311786 -21.29028)
		(end 63.065406 -21.0439)
		(width 0.14224)
		(layer "In2.Cu")
		(net "M_G_DQS_DP<12>")
	)
	(segment
		(start 71.816722 -50.932588)
		(end 71.736712 -50.793142)
		(width 0.0889)
		(layer "In2.Cu")
		(net "M_G_DQS_DP<12>")
	)
	(segment
		(start 63.071248 -22.1742)
		(end 63.311786 -21.933662)
		(width 0.14224)
		(layer "In2.Cu")
		(net "M_G_DQS_DP<12>")
	)
	(segment
		(start 76.259944 -53.669438)
		(end 76.109576 -53.409088)
		(width 0.0889)
		(layer "In2.Cu")
		(net "M_G_DQS_DP<12>")
	)
	(segment
		(start 71.117968 -49.4284)
		(end 63.628016 -41.938448)
		(width 0.14224)
		(layer "In2.Cu")
		(net "M_G_DQS_DP<12>")
	)
	(segment
		(start 63.128906 -20.4216)
		(end 63.311786 -20.23872)
		(width 0.14224)
		(layer "In2.Cu")
		(net "M_G_DQS_DP<12>")
	)
	(segment
		(start 63.311786 -21.933662)
		(end 63.311786 -21.29028)
		(width 0.14224)
		(layer "In2.Cu")
		(net "M_G_DQS_DP<12>")
	)
	(segment
		(start 63.000128 -17.87652)
		(end 62.792102 -18.084546)
		(width 0.14224)
		(layer "In2.Cu")
		(net "M_G_DQS_DP<12>")
	)
	(segment
		(start 62.561216 -39.811198)
		(end 62.939422 -39.432992)
		(width 0.14224)
		(layer "In2.Cu")
		(net "M_G_DQS_DP<12>")
	)
	(segment
		(start 63.406528 -38.356032)
		(end 62.939422 -38.356032)
		(width 0.14224)
		(layer "In2.Cu")
		(net "M_G_DQS_DP<12>")
	)
	(segment
		(start 62.939422 -41.048432)
		(end 62.561216 -40.670226)
		(width 0.14224)
		(layer "In2.Cu")
		(net "M_G_DQS_DP<12>")
	)
	(segment
		(start 63.311786 -19.99488)
		(end 63.103506 -19.7866)
		(width 0.14224)
		(layer "In2.Cu")
		(net "M_G_DQS_DP<12>")
	)
	(segment
		(start 63.40729 -41.048432)
		(end 62.939422 -41.048432)
		(width 0.14224)
		(layer "In2.Cu")
		(net "M_G_DQS_DP<12>")
	)
	(segment
		(start 63.103506 -19.7866)
		(end 62.976506 -19.7866)
		(width 0.14224)
		(layer "In2.Cu")
		(net "M_G_DQS_DP<12>")
	)
	(segment
		(start 62.82055 -20.549108)
		(end 62.948058 -20.4216)
		(width 0.14224)
		(layer "In2.Cu")
		(net "M_G_DQS_DP<12>")
	)
	(segment
		(start 63.628016 -41.938448)
		(end 63.628016 -41.269158)
		(width 0.14224)
		(layer "In2.Cu")
		(net "M_G_DQS_DP<12>")
	)
	(segment
		(start 63.311786 -20.23872)
		(end 63.311786 -19.99488)
		(width 0.14224)
		(layer "In2.Cu")
		(net "M_G_DQS_DP<12>")
	)
	(segment
		(start 62.561216 -37.977826)
		(end 62.561216 -37.118798)
		(width 0.14224)
		(layer "In2.Cu")
		(net "M_G_DQS_DP<12>")
	)
	(segment
		(start 62.939422 -36.740592)
		(end 63.177928 -36.740592)
		(width 0.14224)
		(layer "In2.Cu")
		(net "M_G_DQS_DP<12>")
	)
	(segment
		(start 63.065406 -21.0439)
		(end 62.977014 -21.0439)
		(width 0.14224)
		(layer "In2.Cu")
		(net "M_G_DQS_DP<12>")
	)
	(segment
		(start 62.792102 -22.1742)
		(end 63.071248 -22.1742)
		(width 0.14224)
		(layer "In2.Cu")
		(net "M_G_DQS_DP<12>")
	)
	(segment
		(start 63.311786 -18.057114)
		(end 63.131192 -17.87652)
		(width 0.14224)
		(layer "In2.Cu")
		(net "M_G_DQS_DP<12>")
	)
	(arc
		(start 74.024236 -52.21859)
		(mid 73.741019 -52.134309)
		(end 73.534016 -51.923442)
		(width 0.0889)
		(layer "In2.Cu")
		(net "M_G_DQS_DP<12>")
	)
	(arc
		(start 74.886566 -52.71389)
		(mid 74.601142 -52.630423)
		(end 74.392536 -52.418488)
		(width 0.0889)
		(layer "In2.Cu")
		(net "M_G_DQS_DP<12>")
	)
	(arc
		(start 76.274676 -53.904642)
		(mid 76.293258 -53.794387)
		(end 76.268072 -53.68544)
		(width 0.0889)
		(layer "In2.Cu")
		(net "M_G_DQS_DP<12>")
	)
	(arc
		(start 72.675496 -51.427888)
		(mid 72.535417 -51.285152)
		(end 72.343772 -51.22799)
		(width 0.0889)
		(layer "In2.Cu")
		(net "M_G_DQS_DP<12>")
	)
	(arc
		(start 76.274676 -54.304438)
		(mid 76.221177 -54.10454)
		(end 76.274676 -53.904642)
		(width 0.0889)
		(layer "In2.Cu")
		(net "M_G_DQS_DP<12>")
	)
	(arc
		(start 73.534016 -51.923442)
		(mid 73.392333 -51.779638)
		(end 73.198482 -51.72329)
		(width 0.0889)
		(layer "In2.Cu")
		(net "M_G_DQS_DP<12>")
	)
	(arc
		(start 76.109576 -53.409088)
		(mid 75.969497 -53.266352)
		(end 75.777852 -53.20919)
		(width 0.0889)
		(layer "In2.Cu")
		(net "M_G_DQS_DP<12>")
	)
	(arc
		(start 73.174352 -51.72329)
		(mid 72.886207 -51.640971)
		(end 72.675496 -51.427888)
		(width 0.0889)
		(layer "In2.Cu")
		(net "M_G_DQS_DP<12>")
	)
	(arc
		(start 72.31507 -51.22799)
		(mid 72.027241 -51.145529)
		(end 71.816722 -50.932588)
		(width 0.0889)
		(layer "In2.Cu")
		(net "M_G_DQS_DP<12>")
	)
	(arc
		(start 76.268072 -53.68544)
		(mid 76.264188 -53.677347)
		(end 76.259944 -53.669438)
		(width 0.0889)
		(layer "In2.Cu")
		(net "M_G_DQS_DP<12>")
	)
	(arc
		(start 75.749912 -53.20919)
		(mid 75.461767 -53.126871)
		(end 75.251056 -52.913788)
		(width 0.0889)
		(layer "In2.Cu")
		(net "M_G_DQS_DP<12>")
	)
	(arc
		(start 75.251056 -52.913788)
		(mid 75.112312 -52.771755)
		(end 74.92238 -52.71389)
		(width 0.0889)
		(layer "In2.Cu")
		(net "M_G_DQS_DP<12>")
	)
	(arc
		(start 74.392536 -52.418488)
		(mid 74.253792 -52.276455)
		(end 74.06386 -52.21859)
		(width 0.0889)
		(layer "In2.Cu")
		(net "M_G_DQS_DP<12>")
	)
	(segment
		(start 53.060346 -17.702784)
		(end 53.442108 -18.084546)
		(width 0.1651)
		(layer "F.Cu")
		(net "M_G_DQS_DP<11>")
	)
	(segment
		(start 72.041766 -57.076086)
		(end 71.470266 -57.076086)
		(width 0.1016)
		(layer "F.Cu")
		(net "M_G_DQS_DP<11>")
	)
	(segment
		(start 52.978812 -16.660368)
		(end 52.978812 -17.478502)
		(width 0.1651)
		(layer "F.Cu")
		(net "M_G_DQS_DP<11>")
	)
	(segment
		(start 53.063394 -16.476472)
		(end 52.978812 -16.660368)
		(width 0.1651)
		(layer "F.Cu")
		(net "M_G_DQS_DP<11>")
	)
	(segment
		(start 52.978812 -17.478502)
		(end 53.060346 -17.702784)
		(width 0.1651)
		(layer "F.Cu")
		(net "M_G_DQS_DP<11>")
	)
	(segment
		(start 53.499512 -15.423642)
		(end 53.499512 -16.040354)
		(width 0.1651)
		(layer "F.Cu")
		(net "M_G_DQS_DP<11>")
	)
	(segment
		(start 53.499512 -16.040354)
		(end 53.063394 -16.476472)
		(width 0.1651)
		(layer "F.Cu")
		(net "M_G_DQS_DP<11>")
	)
	(via
		(at 71.470266 -57.076086)
		(size 0.508)
		(drill 0.254)
		(layers "F.Cu" "B.Cu")
		(net "M_G_DQS_DP<11>")
	)
	(via
		(at 53.442108 -18.084546)
		(size 0.508)
		(drill 0.254)
		(layers "F.Cu" "B.Cu")
		(net "M_G_DQS_DP<11>")
	)
	(via
		(at 53.442108 -22.1742)
		(size 0.508)
		(drill 0.254)
		(layers "F.Cu" "B.Cu")
		(net "M_G_DQS_DP<11>")
	)
	(segment
		(start 53.043328 -23.75027)
		(end 52.966112 -23.617936)
		(width 0.1651)
		(layer "B.Cu")
		(net "M_G_DQS_DP<11>")
	)
	(segment
		(start 53.499512 -24.824182)
		(end 53.499512 -24.206454)
		(width 0.1651)
		(layer "B.Cu")
		(net "M_G_DQS_DP<11>")
	)
	(segment
		(start 53.053488 -22.56282)
		(end 53.442108 -22.1742)
		(width 0.1651)
		(layer "B.Cu")
		(net "M_G_DQS_DP<11>")
	)
	(segment
		(start 52.966112 -23.617936)
		(end 52.966112 -22.722332)
		(width 0.1651)
		(layer "B.Cu")
		(net "M_G_DQS_DP<11>")
	)
	(segment
		(start 52.966112 -22.722332)
		(end 53.053488 -22.56282)
		(width 0.1651)
		(layer "B.Cu")
		(net "M_G_DQS_DP<11>")
	)
	(segment
		(start 53.499512 -24.206454)
		(end 53.043328 -23.75027)
		(width 0.1651)
		(layer "B.Cu")
		(net "M_G_DQS_DP<11>")
	)
	(segment
		(start 53.781198 -17.87652)
		(end 53.650134 -17.87652)
		(width 0.14224)
		(layer "In2.Cu")
		(net "M_G_DQS_DP<11>")
	)
	(segment
		(start 53.188616 -41.126918)
		(end 52.967128 -40.90543)
		(width 0.14224)
		(layer "In2.Cu")
		(net "M_G_DQS_DP<11>")
	)
	(segment
		(start 71.511668 -57.420764)
		(end 71.457312 -57.476136)
		(width 0.0889)
		(layer "In2.Cu")
		(net "M_G_DQS_DP<11>")
	)
	(segment
		(start 53.721254 -22.1742)
		(end 53.961792 -21.933662)
		(width 0.14224)
		(layer "In2.Cu")
		(net "M_G_DQS_DP<11>")
	)
	(segment
		(start 52.581048 -42.57548)
		(end 52.581048 -42.13352)
		(width 0.14224)
		(layer "In2.Cu")
		(net "M_G_DQS_DP<11>")
	)
	(segment
		(start 53.188616 -43.576494)
		(end 53.188616 -43.183048)
		(width 0.14224)
		(layer "In2.Cu")
		(net "M_G_DQS_DP<11>")
	)
	(segment
		(start 53.188616 -41.525952)
		(end 53.188616 -41.126918)
		(width 0.14224)
		(layer "In2.Cu")
		(net "M_G_DQS_DP<11>")
	)
	(segment
		(start 52.706016 -32.856678)
		(end 52.706016 -24.295862)
		(width 0.14224)
		(layer "In2.Cu")
		(net "M_G_DQS_DP<11>")
	)
	(segment
		(start 52.540916 -39.28999)
		(end 53.140102 -39.28999)
		(width 0.14224)
		(layer "In2.Cu")
		(net "M_G_DQS_DP<11>")
	)
	(segment
		(start 53.442108 -22.1742)
		(end 53.721254 -22.1742)
		(width 0.14224)
		(layer "In2.Cu")
		(net "M_G_DQS_DP<11>")
	)
	(segment
		(start 52.940712 -22.675596)
		(end 53.442108 -22.1742)
		(width 0.14224)
		(layer "In2.Cu")
		(net "M_G_DQS_DP<11>")
	)
	(segment
		(start 53.470556 -20.887436)
		(end 53.470556 -20.549108)
		(width 0.14224)
		(layer "In2.Cu")
		(net "M_G_DQS_DP<11>")
	)
	(segment
		(start 69.76364 -57.666636)
		(end 68.70192 -57.666636)
		(width 0.0889)
		(layer "In2.Cu")
		(net "M_G_DQS_DP<11>")
	)
	(segment
		(start 53.598064 -20.4216)
		(end 53.778912 -20.4216)
		(width 0.14224)
		(layer "In2.Cu")
		(net "M_G_DQS_DP<11>")
	)
	(segment
		(start 53.474112 -19.3802)
		(end 53.961792 -18.89252)
		(width 0.14224)
		(layer "In2.Cu")
		(net "M_G_DQS_DP<11>")
	)
	(segment
		(start 52.350416 -37.858192)
		(end 52.350416 -33.212278)
		(width 0.14224)
		(layer "In2.Cu")
		(net "M_G_DQS_DP<11>")
	)
	(segment
		(start 52.205128 -40.526462)
		(end 52.205128 -39.625778)
		(width 0.14224)
		(layer "In2.Cu")
		(net "M_G_DQS_DP<11>")
	)
	(segment
		(start 71.511668 -57.117488)
		(end 71.511668 -57.420764)
		(width 0.0889)
		(layer "In2.Cu")
		(net "M_G_DQS_DP<11>")
	)
	(segment
		(start 53.753512 -19.7866)
		(end 53.626512 -19.7866)
		(width 0.14224)
		(layer "In2.Cu")
		(net "M_G_DQS_DP<11>")
	)
	(segment
		(start 53.62702 -21.0439)
		(end 53.470556 -20.887436)
		(width 0.14224)
		(layer "In2.Cu")
		(net "M_G_DQS_DP<11>")
	)
	(segment
		(start 53.961792 -18.057114)
		(end 53.781198 -17.87652)
		(width 0.14224)
		(layer "In2.Cu")
		(net "M_G_DQS_DP<11>")
	)
	(segment
		(start 53.961792 -19.99488)
		(end 53.753512 -19.7866)
		(width 0.14224)
		(layer "In2.Cu")
		(net "M_G_DQS_DP<11>")
	)
	(segment
		(start 71.470266 -57.076086)
		(end 71.511668 -57.117488)
		(width 0.0889)
		(layer "In2.Cu")
		(net "M_G_DQS_DP<11>")
	)
	(segment
		(start 52.705254 -38.21303)
		(end 52.350416 -37.858192)
		(width 0.14224)
		(layer "In2.Cu")
		(net "M_G_DQS_DP<11>")
	)
	(segment
		(start 53.140102 -39.28999)
		(end 53.360828 -39.069264)
		(width 0.14224)
		(layer "In2.Cu")
		(net "M_G_DQS_DP<11>")
	)
	(segment
		(start 53.470556 -20.549108)
		(end 53.598064 -20.4216)
		(width 0.14224)
		(layer "In2.Cu")
		(net "M_G_DQS_DP<11>")
	)
	(segment
		(start 52.350416 -33.212278)
		(end 52.706016 -32.856678)
		(width 0.14224)
		(layer "In2.Cu")
		(net "M_G_DQS_DP<11>")
	)
	(segment
		(start 52.205128 -39.625778)
		(end 52.540916 -39.28999)
		(width 0.14224)
		(layer "In2.Cu")
		(net "M_G_DQS_DP<11>")
	)
	(segment
		(start 68.70192 -57.666636)
		(end 68.206874 -57.17159)
		(width 0.0889)
		(layer "In2.Cu")
		(net "M_G_DQS_DP<11>")
	)
	(segment
		(start 65.45072 -55.838598)
		(end 65.434972 -55.82285)
		(width 0.0889)
		(layer "In2.Cu")
		(net "M_G_DQS_DP<11>")
	)
	(segment
		(start 53.650134 -17.87652)
		(end 53.442108 -18.084546)
		(width 0.14224)
		(layer "In2.Cu")
		(net "M_G_DQS_DP<11>")
	)
	(segment
		(start 52.706016 -24.295862)
		(end 52.940712 -24.061166)
		(width 0.14224)
		(layer "In2.Cu")
		(net "M_G_DQS_DP<11>")
	)
	(segment
		(start 53.360828 -38.415976)
		(end 53.157882 -38.21303)
		(width 0.14224)
		(layer "In2.Cu")
		(net "M_G_DQS_DP<11>")
	)
	(segment
		(start 53.188616 -43.183048)
		(end 52.581048 -42.57548)
		(width 0.14224)
		(layer "In2.Cu")
		(net "M_G_DQS_DP<11>")
	)
	(segment
		(start 65.434972 -55.82285)
		(end 53.188616 -43.576494)
		(width 0.14224)
		(layer "In2.Cu")
		(net "M_G_DQS_DP<11>")
	)
	(segment
		(start 52.584096 -40.90543)
		(end 52.205128 -40.526462)
		(width 0.14224)
		(layer "In2.Cu")
		(net "M_G_DQS_DP<11>")
	)
	(segment
		(start 53.961792 -21.933662)
		(end 53.961792 -21.29028)
		(width 0.14224)
		(layer "In2.Cu")
		(net "M_G_DQS_DP<11>")
	)
	(segment
		(start 52.581048 -42.13352)
		(end 53.188616 -41.525952)
		(width 0.14224)
		(layer "In2.Cu")
		(net "M_G_DQS_DP<11>")
	)
	(segment
		(start 53.626512 -19.7866)
		(end 53.474112 -19.6342)
		(width 0.14224)
		(layer "In2.Cu")
		(net "M_G_DQS_DP<11>")
	)
	(segment
		(start 52.967128 -40.90543)
		(end 52.584096 -40.90543)
		(width 0.14224)
		(layer "In2.Cu")
		(net "M_G_DQS_DP<11>")
	)
	(segment
		(start 53.715412 -21.0439)
		(end 53.62702 -21.0439)
		(width 0.14224)
		(layer "In2.Cu")
		(net "M_G_DQS_DP<11>")
	)
	(segment
		(start 53.961792 -18.89252)
		(end 53.961792 -18.057114)
		(width 0.14224)
		(layer "In2.Cu")
		(net "M_G_DQS_DP<11>")
	)
	(segment
		(start 52.940712 -24.061166)
		(end 52.940712 -22.675596)
		(width 0.14224)
		(layer "In2.Cu")
		(net "M_G_DQS_DP<11>")
	)
	(segment
		(start 53.360828 -39.069264)
		(end 53.360828 -38.415976)
		(width 0.14224)
		(layer "In2.Cu")
		(net "M_G_DQS_DP<11>")
	)
	(segment
		(start 53.778912 -20.4216)
		(end 53.961792 -20.23872)
		(width 0.14224)
		(layer "In2.Cu")
		(net "M_G_DQS_DP<11>")
	)
	(segment
		(start 65.506092 -55.838598)
		(end 65.45072 -55.838598)
		(width 0.0889)
		(layer "In2.Cu")
		(net "M_G_DQS_DP<11>")
	)
	(segment
		(start 70.62978 -57.971436)
		(end 70.593712 -57.971436)
		(width 0.0889)
		(layer "In2.Cu")
		(net "M_G_DQS_DP<11>")
	)
	(segment
		(start 66.838322 -57.17159)
		(end 65.506092 -55.838598)
		(width 0.0889)
		(layer "In2.Cu")
		(net "M_G_DQS_DP<11>")
	)
	(segment
		(start 53.474112 -19.6342)
		(end 53.474112 -19.3802)
		(width 0.14224)
		(layer "In2.Cu")
		(net "M_G_DQS_DP<11>")
	)
	(segment
		(start 53.157882 -38.21303)
		(end 52.705254 -38.21303)
		(width 0.14224)
		(layer "In2.Cu")
		(net "M_G_DQS_DP<11>")
	)
	(segment
		(start 53.961792 -20.23872)
		(end 53.961792 -19.99488)
		(width 0.14224)
		(layer "In2.Cu")
		(net "M_G_DQS_DP<11>")
	)
	(segment
		(start 68.206874 -57.17159)
		(end 66.838322 -57.17159)
		(width 0.0889)
		(layer "In2.Cu")
		(net "M_G_DQS_DP<11>")
	)
	(segment
		(start 53.961792 -21.29028)
		(end 53.715412 -21.0439)
		(width 0.14224)
		(layer "In2.Cu")
		(net "M_G_DQS_DP<11>")
	)
	(arc
		(start 70.958456 -57.771538)
		(mid 70.819712 -57.913571)
		(end 70.62978 -57.971436)
		(width 0.0889)
		(layer "In2.Cu")
		(net "M_G_DQS_DP<11>")
	)
	(arc
		(start 70.593712 -57.971436)
		(mid 70.276135 -57.89914)
		(end 69.9897 -57.744106)
		(width 0.0889)
		(layer "In2.Cu")
		(net "M_G_DQS_DP<11>")
	)
	(arc
		(start 69.957696 -57.72277)
		(mid 69.864618 -57.682485)
		(end 69.764402 -57.66689)
		(width 0.0889)
		(layer "In2.Cu")
		(net "M_G_DQS_DP<11>")
	)
	(arc
		(start 69.764402 -57.66689)
		(mid 69.764021 -57.666763)
		(end 69.76364 -57.666636)
		(width 0.0889)
		(layer "In2.Cu")
		(net "M_G_DQS_DP<11>")
	)
	(arc
		(start 71.457312 -57.476136)
		(mid 71.169167 -57.558455)
		(end 70.958456 -57.771538)
		(width 0.0889)
		(layer "In2.Cu")
		(net "M_G_DQS_DP<11>")
	)
	(arc
		(start 69.9897 -57.744106)
		(mid 69.973953 -57.733056)
		(end 69.957696 -57.72277)
		(width 0.0889)
		(layer "In2.Cu")
		(net "M_G_DQS_DP<11>")
	)
	(segment
		(start 53.200046 -44.3611)
		(end 53.3273 -44.488354)
		(width 0.1651)
		(layer "F.Cu")
		(net "M_G_DQS_DP<10>")
	)
	(segment
		(start 51.4985 -36.496244)
		(end 51.4985 -37.583618)
		(width 0.1651)
		(layer "F.Cu")
		(net "M_G_DQS_DP<10>")
	)
	(segment
		(start 48.088042 -28.8671)
		(end 47.884842 -28.6639)
		(width 0.1651)
		(layer "F.Cu")
		(net "M_G_DQS_DP<10>")
	)
	(segment
		(start 49.7332 -32.290258)
		(end 51.494436 -34.051494)
		(width 0.1651)
		(layer "F.Cu")
		(net "M_G_DQS_DP<10>")
	)
	(segment
		(start 51.494436 -34.051494)
		(end 51.494436 -34.230564)
		(width 0.1651)
		(layer "F.Cu")
		(net "M_G_DQS_DP<10>")
	)
	(segment
		(start 47.884842 -28.6639)
		(end 47.644558 -28.6639)
		(width 0.1651)
		(layer "F.Cu")
		(net "M_G_DQS_DP<10>")
	)
	(segment
		(start 52.680616 -44.3611)
		(end 53.200046 -44.3611)
		(width 0.1651)
		(layer "F.Cu")
		(net "M_G_DQS_DP<10>")
	)
	(segment
		(start 68.594732 -57.66689)
		(end 68.716144 -57.66689)
		(width 0.0889)
		(layer "F.Cu")
		(net "M_G_DQS_DP<10>")
	)
	(segment
		(start 43.628818 -16.660368)
		(end 43.628818 -17.478502)
		(width 0.1651)
		(layer "F.Cu")
		(net "M_G_DQS_DP<10>")
	)
	(segment
		(start 52.382674 -44.063158)
		(end 52.680616 -44.3611)
		(width 0.1651)
		(layer "F.Cu")
		(net "M_G_DQS_DP<10>")
	)
	(segment
		(start 49.7332 -31.6484)
		(end 49.7332 -32.290258)
		(width 0.1651)
		(layer "F.Cu")
		(net "M_G_DQS_DP<10>")
	)
	(segment
		(start 47.441358 -28.8671)
		(end 46.901354 -28.8671)
		(width 0.1651)
		(layer "F.Cu")
		(net "M_G_DQS_DP<10>")
	)
	(segment
		(start 66.678048 -57.223914)
		(end 66.730372 -57.17159)
		(width 0.0889)
		(layer "F.Cu")
		(net "M_G_DQS_DP<10>")
	)
	(segment
		(start 53.3273 -45.662342)
		(end 64.888872 -57.223914)
		(width 0.1651)
		(layer "F.Cu")
		(net "M_G_DQS_DP<10>")
	)
	(segment
		(start 43.7134 -16.476472)
		(end 43.628818 -16.660368)
		(width 0.1651)
		(layer "F.Cu")
		(net "M_G_DQS_DP<10>")
	)
	(segment
		(start 50.638964 -35.636708)
		(end 51.4985 -36.496244)
		(width 0.1651)
		(layer "F.Cu")
		(net "M_G_DQS_DP<10>")
	)
	(segment
		(start 47.644558 -28.6639)
		(end 47.441358 -28.8671)
		(width 0.1651)
		(layer "F.Cu")
		(net "M_G_DQS_DP<10>")
	)
	(segment
		(start 68.715636 -58.06694)
		(end 68.607686 -58.06694)
		(width 0.0889)
		(layer "F.Cu")
		(net "M_G_DQS_DP<10>")
	)
	(segment
		(start 51.494436 -34.230564)
		(end 50.638964 -35.086036)
		(width 0.1651)
		(layer "F.Cu")
		(net "M_G_DQS_DP<10>")
	)
	(segment
		(start 52.382674 -38.467792)
		(end 52.382674 -44.063158)
		(width 0.1651)
		(layer "F.Cu")
		(net "M_G_DQS_DP<10>")
	)
	(segment
		(start 51.4985 -37.583618)
		(end 52.382674 -38.467792)
		(width 0.1651)
		(layer "F.Cu")
		(net "M_G_DQS_DP<10>")
	)
	(segment
		(start 53.3273 -44.488354)
		(end 53.3273 -45.662342)
		(width 0.1651)
		(layer "F.Cu")
		(net "M_G_DQS_DP<10>")
	)
	(segment
		(start 46.901354 -28.8671)
		(end 43.429936 -25.395682)
		(width 0.1651)
		(layer "F.Cu")
		(net "M_G_DQS_DP<10>")
	)
	(segment
		(start 49.7332 -30.207458)
		(end 48.392842 -28.8671)
		(width 0.1651)
		(layer "F.Cu")
		(net "M_G_DQS_DP<10>")
	)
	(segment
		(start 44.149518 -16.040354)
		(end 43.7134 -16.476472)
		(width 0.1651)
		(layer "F.Cu")
		(net "M_G_DQS_DP<10>")
	)
	(segment
		(start 64.888872 -57.223914)
		(end 66.678048 -57.223914)
		(width 0.1651)
		(layer "F.Cu")
		(net "M_G_DQS_DP<10>")
	)
	(segment
		(start 50.638964 -35.086036)
		(end 50.638964 -35.636708)
		(width 0.1651)
		(layer "F.Cu")
		(net "M_G_DQS_DP<10>")
	)
	(segment
		(start 48.392842 -28.8671)
		(end 48.088042 -28.8671)
		(width 0.1651)
		(layer "F.Cu")
		(net "M_G_DQS_DP<10>")
	)
	(segment
		(start 43.429936 -24.048974)
		(end 43.622468 -23.856442)
		(width 0.1651)
		(layer "F.Cu")
		(net "M_G_DQS_DP<10>")
	)
	(segment
		(start 44.149518 -15.423642)
		(end 44.149518 -16.040354)
		(width 0.1651)
		(layer "F.Cu")
		(net "M_G_DQS_DP<10>")
	)
	(segment
		(start 43.622468 -22.643846)
		(end 44.092114 -22.1742)
		(width 0.1651)
		(layer "F.Cu")
		(net "M_G_DQS_DP<10>")
	)
	(segment
		(start 49.7332 -31.6484)
		(end 49.7332 -30.207458)
		(width 0.1651)
		(layer "F.Cu")
		(net "M_G_DQS_DP<10>")
	)
	(segment
		(start 43.710352 -17.702784)
		(end 44.092114 -18.084546)
		(width 0.1651)
		(layer "F.Cu")
		(net "M_G_DQS_DP<10>")
	)
	(segment
		(start 66.730372 -57.17159)
		(end 67.764152 -57.17159)
		(width 0.0889)
		(layer "F.Cu")
		(net "M_G_DQS_DP<10>")
	)
	(segment
		(start 43.622468 -23.856442)
		(end 43.622468 -22.643846)
		(width 0.1651)
		(layer "F.Cu")
		(net "M_G_DQS_DP<10>")
	)
	(segment
		(start 43.628818 -17.478502)
		(end 43.710352 -17.702784)
		(width 0.1651)
		(layer "F.Cu")
		(net "M_G_DQS_DP<10>")
	)
	(segment
		(start 43.429936 -25.395682)
		(end 43.429936 -24.048974)
		(width 0.1651)
		(layer "F.Cu")
		(net "M_G_DQS_DP<10>")
	)
	(via
		(at 44.092114 -22.1742)
		(size 0.508)
		(drill 0.254)
		(layers "F.Cu" "B.Cu")
		(net "M_G_DQS_DP<10>")
	)
	(via
		(at 49.7332 -31.6484)
		(size 0.508)
		(drill 0.254)
		(layers "F.Cu" "B.Cu")
		(net "M_G_DQS_DP<10>")
	)
	(via
		(at 44.092114 -18.084546)
		(size 0.508)
		(drill 0.254)
		(layers "F.Cu" "B.Cu")
		(net "M_G_DQS_DP<10>")
	)
	(arc
		(start 68.801996 -57.686194)
		(mid 68.911148 -57.91104)
		(end 68.715636 -58.06694)
		(width 0.0889)
		(layer "F.Cu")
		(net "M_G_DQS_DP<10>")
	)
	(arc
		(start 67.764152 -57.17159)
		(mid 67.955794 -57.228756)
		(end 68.095876 -57.371488)
		(width 0.0889)
		(layer "F.Cu")
		(net "M_G_DQS_DP<10>")
	)
	(arc
		(start 68.716144 -57.66689)
		(mid 68.760137 -57.671785)
		(end 68.801996 -57.686194)
		(width 0.0889)
		(layer "F.Cu")
		(net "M_G_DQS_DP<10>")
	)
	(arc
		(start 68.095876 -57.371488)
		(mid 68.306589 -57.584567)
		(end 68.594732 -57.66689)
		(width 0.0889)
		(layer "F.Cu")
		(net "M_G_DQS_DP<10>")
	)
	(segment
		(start 44.149518 -24.206454)
		(end 43.693334 -23.75027)
		(width 0.1651)
		(layer "B.Cu")
		(net "M_G_DQS_DP<10>")
	)
	(segment
		(start 43.616118 -22.722332)
		(end 43.703494 -22.56282)
		(width 0.1651)
		(layer "B.Cu")
		(net "M_G_DQS_DP<10>")
	)
	(segment
		(start 43.616118 -23.617936)
		(end 43.616118 -22.722332)
		(width 0.1651)
		(layer "B.Cu")
		(net "M_G_DQS_DP<10>")
	)
	(segment
		(start 44.149518 -24.824182)
		(end 44.149518 -24.206454)
		(width 0.1651)
		(layer "B.Cu")
		(net "M_G_DQS_DP<10>")
	)
	(segment
		(start 43.693334 -23.75027)
		(end 43.616118 -23.617936)
		(width 0.1651)
		(layer "B.Cu")
		(net "M_G_DQS_DP<10>")
	)
	(segment
		(start 43.703494 -22.56282)
		(end 44.092114 -22.1742)
		(width 0.1651)
		(layer "B.Cu")
		(net "M_G_DQS_DP<10>")
	)
	(segment
		(start 44.37126 -22.1742)
		(end 44.611798 -21.933662)
		(width 0.14224)
		(layer "In2.Cu")
		(net "M_G_DQS_DP<10>")
	)
	(segment
		(start 44.120562 -20.549108)
		(end 44.24807 -20.4216)
		(width 0.14224)
		(layer "In2.Cu")
		(net "M_G_DQS_DP<10>")
	)
	(segment
		(start 44.120562 -20.887436)
		(end 44.120562 -20.549108)
		(width 0.14224)
		(layer "In2.Cu")
		(net "M_G_DQS_DP<10>")
	)
	(segment
		(start 44.403518 -19.7866)
		(end 44.276518 -19.7866)
		(width 0.14224)
		(layer "In2.Cu")
		(net "M_G_DQS_DP<10>")
	)
	(segment
		(start 44.365418 -21.0439)
		(end 44.277026 -21.0439)
		(width 0.14224)
		(layer "In2.Cu")
		(net "M_G_DQS_DP<10>")
	)
	(segment
		(start 44.092114 -22.1742)
		(end 44.37126 -22.1742)
		(width 0.14224)
		(layer "In2.Cu")
		(net "M_G_DQS_DP<10>")
	)
	(segment
		(start 44.30014 -17.87652)
		(end 44.092114 -18.084546)
		(width 0.14224)
		(layer "In2.Cu")
		(net "M_G_DQS_DP<10>")
	)
	(segment
		(start 44.431204 -17.87652)
		(end 44.30014 -17.87652)
		(width 0.14224)
		(layer "In2.Cu")
		(net "M_G_DQS_DP<10>")
	)
	(segment
		(start 44.428918 -20.4216)
		(end 44.611798 -20.23872)
		(width 0.14224)
		(layer "In2.Cu")
		(net "M_G_DQS_DP<10>")
	)
	(segment
		(start 44.276518 -19.7866)
		(end 44.124118 -19.6342)
		(width 0.14224)
		(layer "In2.Cu")
		(net "M_G_DQS_DP<10>")
	)
	(segment
		(start 44.611798 -18.057114)
		(end 44.431204 -17.87652)
		(width 0.14224)
		(layer "In2.Cu")
		(net "M_G_DQS_DP<10>")
	)
	(segment
		(start 44.124118 -19.3802)
		(end 44.611798 -18.89252)
		(width 0.14224)
		(layer "In2.Cu")
		(net "M_G_DQS_DP<10>")
	)
	(segment
		(start 44.611798 -20.23872)
		(end 44.611798 -19.99488)
		(width 0.14224)
		(layer "In2.Cu")
		(net "M_G_DQS_DP<10>")
	)
	(segment
		(start 44.24807 -20.4216)
		(end 44.428918 -20.4216)
		(width 0.14224)
		(layer "In2.Cu")
		(net "M_G_DQS_DP<10>")
	)
	(segment
		(start 44.124118 -19.6342)
		(end 44.124118 -19.3802)
		(width 0.14224)
		(layer "In2.Cu")
		(net "M_G_DQS_DP<10>")
	)
	(segment
		(start 44.611798 -18.89252)
		(end 44.611798 -18.057114)
		(width 0.14224)
		(layer "In2.Cu")
		(net "M_G_DQS_DP<10>")
	)
	(segment
		(start 44.277026 -21.0439)
		(end 44.120562 -20.887436)
		(width 0.14224)
		(layer "In2.Cu")
		(net "M_G_DQS_DP<10>")
	)
	(segment
		(start 44.611798 -21.933662)
		(end 44.611798 -21.29028)
		(width 0.14224)
		(layer "In2.Cu")
		(net "M_G_DQS_DP<10>")
	)
	(segment
		(start 44.611798 -19.99488)
		(end 44.403518 -19.7866)
		(width 0.14224)
		(layer "In2.Cu")
		(net "M_G_DQS_DP<10>")
	)
	(segment
		(start 44.611798 -21.29028)
		(end 44.365418 -21.0439)
		(width 0.14224)
		(layer "In2.Cu")
		(net "M_G_DQS_DP<10>")
	)
	(segment
		(start 36.537392 -17.6022)
		(end 36.293552 -17.35836)
		(width 0.1651)
		(layer "F.Cu")
		(net "M_G_DQS_DP<0>")
	)
	(segment
		(start 36.499546 -20.023582)
		(end 36.499546 -19.011646)
		(width 0.1651)
		(layer "F.Cu")
		(net "M_G_DQS_DP<0>")
	)
	(segment
		(start 36.537392 -18.9738)
		(end 36.537392 -17.6022)
		(width 0.1651)
		(layer "F.Cu")
		(net "M_G_DQS_DP<0>")
	)
	(segment
		(start 36.499546 -19.011646)
		(end 36.537392 -18.9738)
		(width 0.1651)
		(layer "F.Cu")
		(net "M_G_DQS_DP<0>")
	)
	(segment
		(start 36.293552 -17.35836)
		(end 36.03752 -17.35836)
		(width 0.1651)
		(layer "F.Cu")
		(net "M_G_DQS_DP<0>")
	)
	(segment
		(start 68.607686 -63.019686)
		(end 68.036186 -63.019686)
		(width 0.1016)
		(layer "F.Cu")
		(net "M_G_DQS_DP<0>")
	)
	(via
		(at 68.036186 -63.019686)
		(size 0.508)
		(drill 0.254)
		(layers "F.Cu" "B.Cu")
		(net "M_G_DQS_DP<0>")
	)
	(via
		(at 36.03752 -22.888956)
		(size 0.508)
		(drill 0.254)
		(layers "F.Cu" "B.Cu")
		(net "M_G_DQS_DP<0>")
	)
	(via
		(at 36.03752 -17.35836)
		(size 0.508)
		(drill 0.254)
		(layers "F.Cu" "B.Cu")
		(net "M_G_DQS_DP<0>")
	)
	(segment
		(start 36.499546 -20.224242)
		(end 36.499546 -21.374354)
		(width 0.1651)
		(layer "B.Cu")
		(net "M_G_DQS_DP<0>")
	)
	(segment
		(start 36.537392 -21.4122)
		(end 36.537392 -22.6314)
		(width 0.1651)
		(layer "B.Cu")
		(net "M_G_DQS_DP<0>")
	)
	(segment
		(start 36.499546 -21.374354)
		(end 36.537392 -21.4122)
		(width 0.1651)
		(layer "B.Cu")
		(net "M_G_DQS_DP<0>")
	)
	(segment
		(start 36.537392 -22.6314)
		(end 36.279836 -22.888956)
		(width 0.1651)
		(layer "B.Cu")
		(net "M_G_DQS_DP<0>")
	)
	(segment
		(start 36.279836 -22.888956)
		(end 36.03752 -22.888956)
		(width 0.1651)
		(layer "B.Cu")
		(net "M_G_DQS_DP<0>")
	)
	(segment
		(start 36.236656 -25.02916)
		(end 36.236656 -25.240488)
		(width 0.14224)
		(layer "In2.Cu")
		(net "M_G_DQS_DP<0>")
	)
	(segment
		(start 36.236656 -34.16427)
		(end 36.48329 -34.410904)
		(width 0.14224)
		(layer "In2.Cu")
		(net "M_G_DQS_DP<0>")
	)
	(segment
		(start 38.217856 -37.202872)
		(end 38.490144 -37.47516)
		(width 0.14224)
		(layer "In2.Cu")
		(net "M_G_DQS_DP<0>")
	)
	(segment
		(start 35.861244 -24.653748)
		(end 36.236656 -25.02916)
		(width 0.14224)
		(layer "In2.Cu")
		(net "M_G_DQS_DP<0>")
	)
	(segment
		(start 36.394136 -27.175968)
		(end 36.236656 -27.333448)
		(width 0.14224)
		(layer "In2.Cu")
		(net "M_G_DQS_DP<0>")
	)
	(segment
		(start 38.80485 -37.47516)
		(end 39.183056 -37.853366)
		(width 0.14224)
		(layer "In2.Cu")
		(net "M_G_DQS_DP<0>")
	)
	(segment
		(start 36.394136 -28.445968)
		(end 36.394136 -28.699968)
		(width 0.14224)
		(layer "In2.Cu")
		(net "M_G_DQS_DP<0>")
	)
	(segment
		(start 38.9128 -35.0012)
		(end 39.056056 -35.14471)
		(width 0.14224)
		(layer "In2.Cu")
		(net "M_G_DQS_DP<0>")
	)
	(segment
		(start 36.48329 -34.410904)
		(end 38.32225 -34.410904)
		(width 0.14224)
		(layer "In2.Cu")
		(net "M_G_DQS_DP<0>")
	)
	(segment
		(start 38.32225 -34.410904)
		(end 38.9128 -35.0012)
		(width 0.14224)
		(layer "In2.Cu")
		(net "M_G_DQS_DP<0>")
	)
	(segment
		(start 36.848288 -22.078188)
		(end 36.03752 -22.888956)
		(width 0.14224)
		(layer "In2.Cu")
		(net "M_G_DQS_DP<0>")
	)
	(segment
		(start 36.394136 -28.699968)
		(end 36.236656 -28.857448)
		(width 0.14224)
		(layer "In2.Cu")
		(net "M_G_DQS_DP<0>")
	)
	(segment
		(start 66.000884 -63.584836)
		(end 66.031872 -63.615824)
		(width 0.0889)
		(layer "In2.Cu")
		(net "M_G_DQS_DP<0>")
	)
	(segment
		(start 36.236656 -26.002488)
		(end 36.394136 -26.159968)
		(width 0.14224)
		(layer "In2.Cu")
		(net "M_G_DQS_DP<0>")
	)
	(segment
		(start 36.394136 -26.413968)
		(end 36.236656 -26.571448)
		(width 0.14224)
		(layer "In2.Cu")
		(net "M_G_DQS_DP<0>")
	)
	(segment
		(start 66.834258 -62.92469)
		(end 67.366642 -62.92469)
		(width 0.0889)
		(layer "In2.Cu")
		(net "M_G_DQS_DP<0>")
	)
	(segment
		(start 36.394136 -26.921968)
		(end 36.394136 -27.175968)
		(width 0.14224)
		(layer "In2.Cu")
		(net "M_G_DQS_DP<0>")
	)
	(segment
		(start 36.03752 -17.35836)
		(end 36.848288 -18.169128)
		(width 0.14224)
		(layer "In2.Cu")
		(net "M_G_DQS_DP<0>")
	)
	(segment
		(start 39.183056 -37.853366)
		(end 39.183056 -38.685216)
		(width 0.14224)
		(layer "In2.Cu")
		(net "M_G_DQS_DP<0>")
	)
	(segment
		(start 38.490144 -37.47516)
		(end 38.80485 -37.47516)
		(width 0.14224)
		(layer "In2.Cu")
		(net "M_G_DQS_DP<0>")
	)
	(segment
		(start 36.394136 -25.651968)
		(end 36.236656 -25.809448)
		(width 0.14224)
		(layer "In2.Cu")
		(net "M_G_DQS_DP<0>")
	)
	(segment
		(start 36.236656 -25.809448)
		(end 36.236656 -26.002488)
		(width 0.14224)
		(layer "In2.Cu")
		(net "M_G_DQS_DP<0>")
	)
	(segment
		(start 36.548568 -23.400004)
		(end 36.548568 -23.7998)
		(width 0.14224)
		(layer "In2.Cu")
		(net "M_G_DQS_DP<0>")
	)
	(segment
		(start 36.236656 -28.857448)
		(end 36.236656 -34.16427)
		(width 0.14224)
		(layer "In2.Cu")
		(net "M_G_DQS_DP<0>")
	)
	(segment
		(start 36.065968 -24.0538)
		(end 35.861244 -24.258524)
		(width 0.14224)
		(layer "In2.Cu")
		(net "M_G_DQS_DP<0>")
	)
	(segment
		(start 39.183056 -38.685216)
		(end 64.082676 -63.584836)
		(width 0.14224)
		(layer "In2.Cu")
		(net "M_G_DQS_DP<0>")
	)
	(segment
		(start 36.236656 -28.288488)
		(end 36.394136 -28.445968)
		(width 0.14224)
		(layer "In2.Cu")
		(net "M_G_DQS_DP<0>")
	)
	(segment
		(start 38.217856 -36.664138)
		(end 38.217856 -37.202872)
		(width 0.14224)
		(layer "In2.Cu")
		(net "M_G_DQS_DP<0>")
	)
	(segment
		(start 36.236656 -28.095448)
		(end 36.236656 -28.288488)
		(width 0.14224)
		(layer "In2.Cu")
		(net "M_G_DQS_DP<0>")
	)
	(segment
		(start 39.056056 -35.825938)
		(end 38.217856 -36.664138)
		(width 0.14224)
		(layer "In2.Cu")
		(net "M_G_DQS_DP<0>")
	)
	(segment
		(start 67.366642 -62.92469)
		(end 67.861688 -63.419736)
		(width 0.0889)
		(layer "In2.Cu")
		(net "M_G_DQS_DP<0>")
	)
	(segment
		(start 36.236656 -25.240488)
		(end 36.394136 -25.397968)
		(width 0.14224)
		(layer "In2.Cu")
		(net "M_G_DQS_DP<0>")
	)
	(segment
		(start 66.143124 -63.615824)
		(end 66.834258 -62.92469)
		(width 0.0889)
		(layer "In2.Cu")
		(net "M_G_DQS_DP<0>")
	)
	(segment
		(start 64.082676 -63.584836)
		(end 66.000884 -63.584836)
		(width 0.14224)
		(layer "In2.Cu")
		(net "M_G_DQS_DP<0>")
	)
	(segment
		(start 36.236656 -26.764488)
		(end 36.394136 -26.921968)
		(width 0.14224)
		(layer "In2.Cu")
		(net "M_G_DQS_DP<0>")
	)
	(segment
		(start 36.394136 -25.397968)
		(end 36.394136 -25.651968)
		(width 0.14224)
		(layer "In2.Cu")
		(net "M_G_DQS_DP<0>")
	)
	(segment
		(start 39.056056 -35.14471)
		(end 39.056056 -35.825938)
		(width 0.14224)
		(layer "In2.Cu")
		(net "M_G_DQS_DP<0>")
	)
	(segment
		(start 36.236656 -27.526488)
		(end 36.394136 -27.683968)
		(width 0.14224)
		(layer "In2.Cu")
		(net "M_G_DQS_DP<0>")
	)
	(segment
		(start 35.861244 -24.258524)
		(end 35.861244 -24.653748)
		(width 0.14224)
		(layer "In2.Cu")
		(net "M_G_DQS_DP<0>")
	)
	(segment
		(start 67.861688 -63.419736)
		(end 68.172076 -63.419736)
		(width 0.0889)
		(layer "In2.Cu")
		(net "M_G_DQS_DP<0>")
	)
	(segment
		(start 36.394136 -27.683968)
		(end 36.394136 -27.937968)
		(width 0.14224)
		(layer "In2.Cu")
		(net "M_G_DQS_DP<0>")
	)
	(segment
		(start 36.394136 -27.937968)
		(end 36.236656 -28.095448)
		(width 0.14224)
		(layer "In2.Cu")
		(net "M_G_DQS_DP<0>")
	)
	(segment
		(start 36.03752 -22.888956)
		(end 36.548568 -23.400004)
		(width 0.14224)
		(layer "In2.Cu")
		(net "M_G_DQS_DP<0>")
	)
	(segment
		(start 36.236656 -26.571448)
		(end 36.236656 -26.764488)
		(width 0.14224)
		(layer "In2.Cu")
		(net "M_G_DQS_DP<0>")
	)
	(segment
		(start 36.548568 -23.7998)
		(end 36.294568 -24.0538)
		(width 0.14224)
		(layer "In2.Cu")
		(net "M_G_DQS_DP<0>")
	)
	(segment
		(start 36.236656 -27.333448)
		(end 36.236656 -27.526488)
		(width 0.14224)
		(layer "In2.Cu")
		(net "M_G_DQS_DP<0>")
	)
	(segment
		(start 36.848288 -18.169128)
		(end 36.848288 -22.078188)
		(width 0.14224)
		(layer "In2.Cu")
		(net "M_G_DQS_DP<0>")
	)
	(segment
		(start 66.031872 -63.615824)
		(end 66.143124 -63.615824)
		(width 0.0889)
		(layer "In2.Cu")
		(net "M_G_DQS_DP<0>")
	)
	(segment
		(start 68.172076 -63.019686)
		(end 68.036186 -63.019686)
		(width 0.0889)
		(layer "In2.Cu")
		(net "M_G_DQS_DP<0>")
	)
	(segment
		(start 36.394136 -26.159968)
		(end 36.394136 -26.413968)
		(width 0.14224)
		(layer "In2.Cu")
		(net "M_G_DQS_DP<0>")
	)
	(segment
		(start 36.294568 -24.0538)
		(end 36.065968 -24.0538)
		(width 0.14224)
		(layer "In2.Cu")
		(net "M_G_DQS_DP<0>")
	)
	(arc
		(start 68.172076 -63.419736)
		(mid 68.208372 -63.416413)
		(end 68.24345 -63.406528)
		(width 0.0889)
		(layer "In2.Cu")
		(net "M_G_DQS_DP<0>")
	)
	(arc
		(start 68.24345 -63.406528)
		(mid 68.368864 -63.183295)
		(end 68.172076 -63.019686)
		(width 0.0889)
		(layer "In2.Cu")
		(net "M_G_DQS_DP<0>")
	)
	(segment
		(start 34.767774 -17.4117)
		(end 34.748724 -17.4117)
		(width 0.1651)
		(layer "F.Cu")
		(net "M_G_DQS_DN<9>")
	)
	(segment
		(start 35.649408 -16.077184)
		(end 35.231324 -16.495268)
		(width 0.1651)
		(layer "F.Cu")
		(net "M_G_DQS_DN<9>")
	)
	(segment
		(start 35.417252 -17.102328)
		(end 35.417252 -17.348962)
		(width 0.1651)
		(layer "F.Cu")
		(net "M_G_DQS_DN<9>")
	)
	(segment
		(start 35.231324 -16.495268)
		(end 35.231324 -16.9164)
		(width 0.1651)
		(layer "F.Cu")
		(net "M_G_DQS_DN<9>")
	)
	(segment
		(start 35.231324 -16.9164)
		(end 35.417252 -17.102328)
		(width 0.1651)
		(layer "F.Cu")
		(net "M_G_DQS_DN<9>")
	)
	(segment
		(start 69.466206 -64.50584)
		(end 68.894706 -64.50584)
		(width 0.1016)
		(layer "F.Cu")
		(net "M_G_DQS_DN<9>")
	)
	(segment
		(start 34.957004 -17.60093)
		(end 34.767774 -17.4117)
		(width 0.1651)
		(layer "F.Cu")
		(net "M_G_DQS_DN<9>")
	)
	(segment
		(start 35.649408 -15.423642)
		(end 35.649408 -16.077184)
		(width 0.1651)
		(layer "F.Cu")
		(net "M_G_DQS_DN<9>")
	)
	(segment
		(start 35.417252 -17.348962)
		(end 35.165284 -17.60093)
		(width 0.1651)
		(layer "F.Cu")
		(net "M_G_DQS_DN<9>")
	)
	(segment
		(start 35.165284 -17.60093)
		(end 34.957004 -17.60093)
		(width 0.1651)
		(layer "F.Cu")
		(net "M_G_DQS_DN<9>")
	)
	(via
		(at 68.894706 -64.50584)
		(size 0.508)
		(drill 0.254)
		(layers "F.Cu" "B.Cu")
		(net "M_G_DQS_DN<9>")
	)
	(via
		(at 34.74212 -22.8346)
		(size 0.508)
		(drill 0.254)
		(layers "F.Cu" "B.Cu")
		(net "M_G_DQS_DN<9>")
	)
	(via
		(at 34.748724 -17.4117)
		(size 0.508)
		(drill 0.254)
		(layers "F.Cu" "B.Cu")
		(net "M_G_DQS_DN<9>")
	)
	(segment
		(start 35.383724 -22.86)
		(end 35.16376 -22.640036)
		(width 0.1651)
		(layer "B.Cu")
		(net "M_G_DQS_DN<9>")
	)
	(segment
		(start 35.649662 -24.167592)
		(end 35.205924 -23.723854)
		(width 0.1651)
		(layer "B.Cu")
		(net "M_G_DQS_DN<9>")
	)
	(segment
		(start 34.936684 -22.640036)
		(end 34.74212 -22.8346)
		(width 0.1651)
		(layer "B.Cu")
		(net "M_G_DQS_DN<9>")
	)
	(segment
		(start 35.205924 -23.368)
		(end 35.383724 -23.1902)
		(width 0.1651)
		(layer "B.Cu")
		(net "M_G_DQS_DN<9>")
	)
	(segment
		(start 35.649662 -24.823928)
		(end 35.649662 -24.167592)
		(width 0.1651)
		(layer "B.Cu")
		(net "M_G_DQS_DN<9>")
	)
	(segment
		(start 35.205924 -23.723854)
		(end 35.205924 -23.368)
		(width 0.1651)
		(layer "B.Cu")
		(net "M_G_DQS_DN<9>")
	)
	(segment
		(start 35.383724 -23.1902)
		(end 35.383724 -22.86)
		(width 0.1651)
		(layer "B.Cu")
		(net "M_G_DQS_DN<9>")
	)
	(segment
		(start 35.16376 -22.640036)
		(end 34.936684 -22.640036)
		(width 0.1651)
		(layer "B.Cu")
		(net "M_G_DQS_DN<9>")
	)
	(segment
		(start 35.649408 -24.824182)
		(end 35.649662 -24.823928)
		(width 0.1651)
		(layer "B.Cu")
		(net "M_G_DQS_DN<9>")
	)
	(segment
		(start 35.78987 -36.383722)
		(end 36.568888 -37.16274)
		(width 0.14224)
		(layer "In2.Cu")
		(net "M_G_DQS_DN<9>")
	)
	(segment
		(start 35.225736 -28.0162)
		(end 35.068256 -28.17368)
		(width 0.14224)
		(layer "In2.Cu")
		(net "M_G_DQS_DN<9>")
	)
	(segment
		(start 35.068256 -26.08072)
		(end 35.225736 -26.2382)
		(width 0.14224)
		(layer "In2.Cu")
		(net "M_G_DQS_DN<9>")
	)
	(segment
		(start 35.225736 -25.6794)
		(end 35.068256 -25.83688)
		(width 0.14224)
		(layer "In2.Cu")
		(net "M_G_DQS_DN<9>")
	)
	(segment
		(start 36.568888 -37.16274)
		(end 36.568888 -37.44087)
		(width 0.14224)
		(layer "In2.Cu")
		(net "M_G_DQS_DN<9>")
	)
	(segment
		(start 35.531044 -17.944592)
		(end 35.531044 -22.045676)
		(width 0.14224)
		(layer "In2.Cu")
		(net "M_G_DQS_DN<9>")
	)
	(segment
		(start 35.180524 -23.720044)
		(end 34.897568 -24.003)
		(width 0.14224)
		(layer "In2.Cu")
		(net "M_G_DQS_DN<9>")
	)
	(segment
		(start 35.531044 -22.045676)
		(end 34.74212 -22.8346)
		(width 0.14224)
		(layer "In2.Cu")
		(net "M_G_DQS_DN<9>")
	)
	(segment
		(start 35.068256 -28.36672)
		(end 35.225736 -28.5242)
		(width 0.14224)
		(layer "In2.Cu")
		(net "M_G_DQS_DN<9>")
	)
	(segment
		(start 65.881504 -64.562482)
		(end 65.903602 -64.562482)
		(width 0.0889)
		(layer "In2.Cu")
		(net "M_G_DQS_DN<9>")
	)
	(segment
		(start 34.723324 -24.003)
		(end 34.540444 -24.18588)
		(width 0.14224)
		(layer "In2.Cu")
		(net "M_G_DQS_DN<9>")
	)
	(segment
		(start 35.225736 -27.0002)
		(end 35.225736 -27.2542)
		(width 0.14224)
		(layer "In2.Cu")
		(net "M_G_DQS_DN<9>")
	)
	(segment
		(start 35.225736 -28.7782)
		(end 35.068256 -28.93568)
		(width 0.14224)
		(layer "In2.Cu")
		(net "M_G_DQS_DN<9>")
	)
	(segment
		(start 66.85407 -63.91529)
		(end 67.366896 -63.91529)
		(width 0.0889)
		(layer "In2.Cu")
		(net "M_G_DQS_DN<9>")
	)
	(segment
		(start 35.225736 -27.7622)
		(end 35.225736 -28.0162)
		(width 0.14224)
		(layer "In2.Cu")
		(net "M_G_DQS_DN<9>")
	)
	(segment
		(start 35.225736 -26.4922)
		(end 35.068256 -26.64968)
		(width 0.14224)
		(layer "In2.Cu")
		(net "M_G_DQS_DN<9>")
	)
	(segment
		(start 34.897568 -24.003)
		(end 34.723324 -24.003)
		(width 0.14224)
		(layer "In2.Cu")
		(net "M_G_DQS_DN<9>")
	)
	(segment
		(start 35.225736 -27.2542)
		(end 35.068256 -27.41168)
		(width 0.14224)
		(layer "In2.Cu")
		(net "M_G_DQS_DN<9>")
	)
	(segment
		(start 63.6905 -64.562482)
		(end 65.881504 -64.562482)
		(width 0.14224)
		(layer "In2.Cu")
		(net "M_G_DQS_DN<9>")
	)
	(segment
		(start 35.193732 -17.60728)
		(end 35.531044 -17.944592)
		(width 0.14224)
		(layer "In2.Cu")
		(net "M_G_DQS_DN<9>")
	)
	(segment
		(start 67.861942 -64.410336)
		(end 68.222622 -64.410336)
		(width 0.0889)
		(layer "In2.Cu")
		(net "M_G_DQS_DN<9>")
	)
	(segment
		(start 35.068256 -27.41168)
		(end 35.068256 -27.60472)
		(width 0.14224)
		(layer "In2.Cu")
		(net "M_G_DQS_DN<9>")
	)
	(segment
		(start 35.51174 -36.383722)
		(end 35.78987 -36.383722)
		(width 0.14224)
		(layer "In2.Cu")
		(net "M_G_DQS_DN<9>")
	)
	(segment
		(start 35.225736 -26.2382)
		(end 35.225736 -26.4922)
		(width 0.14224)
		(layer "In2.Cu")
		(net "M_G_DQS_DN<9>")
	)
	(segment
		(start 35.068256 -29.12872)
		(end 35.225736 -29.2862)
		(width 0.14224)
		(layer "In2.Cu")
		(net "M_G_DQS_DN<9>")
	)
	(segment
		(start 35.068256 -28.17368)
		(end 35.068256 -28.36672)
		(width 0.14224)
		(layer "In2.Cu")
		(net "M_G_DQS_DN<9>")
	)
	(segment
		(start 67.366896 -63.91529)
		(end 67.861942 -64.410336)
		(width 0.0889)
		(layer "In2.Cu")
		(net "M_G_DQS_DN<9>")
	)
	(segment
		(start 66.188336 -64.581024)
		(end 66.85407 -63.91529)
		(width 0.0889)
		(layer "In2.Cu")
		(net "M_G_DQS_DN<9>")
	)
	(segment
		(start 65.903602 -64.562482)
		(end 65.922144 -64.581024)
		(width 0.0889)
		(layer "In2.Cu")
		(net "M_G_DQS_DN<9>")
	)
	(segment
		(start 35.068256 -25.83688)
		(end 35.068256 -26.08072)
		(width 0.14224)
		(layer "In2.Cu")
		(net "M_G_DQS_DN<9>")
	)
	(segment
		(start 34.944304 -17.60728)
		(end 35.193732 -17.60728)
		(width 0.14224)
		(layer "In2.Cu")
		(net "M_G_DQS_DN<9>")
	)
	(segment
		(start 35.225736 -25.468072)
		(end 35.225736 -25.6794)
		(width 0.14224)
		(layer "In2.Cu")
		(net "M_G_DQS_DN<9>")
	)
	(segment
		(start 36.568888 -37.44087)
		(end 63.6905 -64.562482)
		(width 0.14224)
		(layer "In2.Cu")
		(net "M_G_DQS_DN<9>")
	)
	(segment
		(start 34.540444 -24.78278)
		(end 35.225736 -25.468072)
		(width 0.14224)
		(layer "In2.Cu")
		(net "M_G_DQS_DN<9>")
	)
	(segment
		(start 35.180524 -23.273004)
		(end 35.180524 -23.720044)
		(width 0.14224)
		(layer "In2.Cu")
		(net "M_G_DQS_DN<9>")
	)
	(segment
		(start 35.068256 -28.93568)
		(end 35.068256 -29.12872)
		(width 0.14224)
		(layer "In2.Cu")
		(net "M_G_DQS_DN<9>")
	)
	(segment
		(start 35.068256 -27.60472)
		(end 35.225736 -27.7622)
		(width 0.14224)
		(layer "In2.Cu")
		(net "M_G_DQS_DN<9>")
	)
	(segment
		(start 35.225736 -28.5242)
		(end 35.225736 -28.7782)
		(width 0.14224)
		(layer "In2.Cu")
		(net "M_G_DQS_DN<9>")
	)
	(segment
		(start 34.540444 -24.18588)
		(end 34.540444 -24.78278)
		(width 0.14224)
		(layer "In2.Cu")
		(net "M_G_DQS_DN<9>")
	)
	(segment
		(start 35.225736 -29.2862)
		(end 35.225736 -29.5402)
		(width 0.14224)
		(layer "In2.Cu")
		(net "M_G_DQS_DN<9>")
	)
	(segment
		(start 35.068256 -35.940238)
		(end 35.51174 -36.383722)
		(width 0.14224)
		(layer "In2.Cu")
		(net "M_G_DQS_DN<9>")
	)
	(segment
		(start 35.068256 -26.84272)
		(end 35.225736 -27.0002)
		(width 0.14224)
		(layer "In2.Cu")
		(net "M_G_DQS_DN<9>")
	)
	(segment
		(start 68.474844 -64.50584)
		(end 68.894706 -64.50584)
		(width 0.0889)
		(layer "In2.Cu")
		(net "M_G_DQS_DN<9>")
	)
	(segment
		(start 65.922144 -64.581024)
		(end 66.188336 -64.581024)
		(width 0.0889)
		(layer "In2.Cu")
		(net "M_G_DQS_DN<9>")
	)
	(segment
		(start 34.748724 -17.4117)
		(end 34.944304 -17.60728)
		(width 0.14224)
		(layer "In2.Cu")
		(net "M_G_DQS_DN<9>")
	)
	(segment
		(start 35.068256 -26.64968)
		(end 35.068256 -26.84272)
		(width 0.14224)
		(layer "In2.Cu")
		(net "M_G_DQS_DN<9>")
	)
	(segment
		(start 35.068256 -29.69768)
		(end 35.068256 -35.940238)
		(width 0.14224)
		(layer "In2.Cu")
		(net "M_G_DQS_DN<9>")
	)
	(segment
		(start 35.225736 -29.5402)
		(end 35.068256 -29.69768)
		(width 0.14224)
		(layer "In2.Cu")
		(net "M_G_DQS_DN<9>")
	)
	(segment
		(start 34.74212 -22.8346)
		(end 35.180524 -23.273004)
		(width 0.14224)
		(layer "In2.Cu")
		(net "M_G_DQS_DN<9>")
	)
	(arc
		(start 68.407788 -64.48044)
		(mid 68.438997 -64.499253)
		(end 68.474844 -64.50584)
		(width 0.0889)
		(layer "In2.Cu")
		(net "M_G_DQS_DN<9>")
	)
	(arc
		(start 68.222622 -64.410336)
		(mid 68.321621 -64.428445)
		(end 68.407788 -64.48044)
		(width 0.0889)
		(layer "In2.Cu")
		(net "M_G_DQS_DN<9>")
	)
	(segment
		(start 73.22185 -17.8054)
		(end 73.437496 -18.021046)
		(width 0.1651)
		(layer "F.Cu")
		(net "M_G_DQS_DN<8>")
	)
	(segment
		(start 73.049384 -18.94967)
		(end 72.667368 -18.567654)
		(width 0.1651)
		(layer "F.Cu")
		(net "M_G_DQS_DN<8>")
	)
	(segment
		(start 73.049384 -20.023582)
		(end 73.049384 -18.94967)
		(width 0.1651)
		(layer "F.Cu")
		(net "M_G_DQS_DN<8>")
	)
	(segment
		(start 72.667368 -18.567654)
		(end 72.667368 -18.135854)
		(width 0.1651)
		(layer "F.Cu")
		(net "M_G_DQS_DN<8>")
	)
	(segment
		(start 72.997822 -17.8054)
		(end 73.22185 -17.8054)
		(width 0.1651)
		(layer "F.Cu")
		(net "M_G_DQS_DN<8>")
	)
	(segment
		(start 72.667368 -18.135854)
		(end 72.997822 -17.8054)
		(width 0.1651)
		(layer "F.Cu")
		(net "M_G_DQS_DN<8>")
	)
	(segment
		(start 84.060792 -63.019686)
		(end 83.489292 -63.019686)
		(width 0.1016)
		(layer "F.Cu")
		(net "M_G_DQS_DN<8>")
	)
	(via
		(at 83.489292 -63.019686)
		(size 0.508)
		(drill 0.254)
		(layers "F.Cu" "B.Cu")
		(net "M_G_DQS_DN<8>")
	)
	(via
		(at 73.437496 -22.228556)
		(size 0.508)
		(drill 0.254)
		(layers "F.Cu" "B.Cu")
		(net "M_G_DQS_DN<8>")
	)
	(via
		(at 73.437496 -18.021046)
		(size 0.508)
		(drill 0.254)
		(layers "F.Cu" "B.Cu")
		(net "M_G_DQS_DN<8>")
	)
	(segment
		(start 73.049384 -20.224242)
		(end 73.049384 -21.13153)
		(width 0.1651)
		(layer "B.Cu")
		(net "M_G_DQS_DN<8>")
	)
	(segment
		(start 72.667368 -21.767546)
		(end 72.667368 -22.098)
		(width 0.1651)
		(layer "B.Cu")
		(net "M_G_DQS_DN<8>")
	)
	(segment
		(start 73.212452 -22.4536)
		(end 73.437496 -22.228556)
		(width 0.1651)
		(layer "B.Cu")
		(net "M_G_DQS_DN<8>")
	)
	(segment
		(start 72.667368 -22.098)
		(end 73.022968 -22.4536)
		(width 0.1651)
		(layer "B.Cu")
		(net "M_G_DQS_DN<8>")
	)
	(segment
		(start 72.921368 -21.259546)
		(end 72.921368 -21.513546)
		(width 0.1651)
		(layer "B.Cu")
		(net "M_G_DQS_DN<8>")
	)
	(segment
		(start 73.022968 -22.4536)
		(end 73.212452 -22.4536)
		(width 0.1651)
		(layer "B.Cu")
		(net "M_G_DQS_DN<8>")
	)
	(segment
		(start 72.921368 -21.513546)
		(end 72.667368 -21.767546)
		(width 0.1651)
		(layer "B.Cu")
		(net "M_G_DQS_DN<8>")
	)
	(segment
		(start 73.049384 -21.13153)
		(end 72.921368 -21.259546)
		(width 0.1651)
		(layer "B.Cu")
		(net "M_G_DQS_DN<8>")
	)
	(segment
		(start 73.4441 -19.278854)
		(end 73.596754 -19.1262)
		(width 0.14224)
		(layer "In2.Cu")
		(net "M_G_DQS_DN<8>")
	)
	(segment
		(start 73.950576 -28.800298)
		(end 73.950576 -25.67559)
		(width 0.14224)
		(layer "In2.Cu")
		(net "M_G_DQS_DN<8>")
	)
	(segment
		(start 73.596754 -19.7358)
		(end 73.4441 -19.583146)
		(width 0.14224)
		(layer "In2.Cu")
		(net "M_G_DQS_DN<8>")
	)
	(segment
		(start 82.106262 -55.852822)
		(end 82.03946 -55.78602)
		(width 0.0889)
		(layer "In2.Cu")
		(net "M_G_DQS_DN<8>")
	)
	(segment
		(start 82.115406 -56.870092)
		(end 82.112612 -56.86552)
		(width 0.0889)
		(layer "In2.Cu")
		(net "M_G_DQS_DN<8>")
	)
	(segment
		(start 72.99198 -24.716232)
		(end 72.99198 -22.674072)
		(width 0.14224)
		(layer "In2.Cu")
		(net "M_G_DQS_DN<8>")
	)
	(segment
		(start 73.437496 -22.228556)
		(end 73.437496 -22.22881)
		(width 0.14224)
		(layer "In2.Cu")
		(net "M_G_DQS_DN<8>")
	)
	(segment
		(start 73.437496 -22.22881)
		(end 73.716388 -22.22881)
		(width 0.14224)
		(layer "In2.Cu")
		(net "M_G_DQS_DN<8>")
	)
	(segment
		(start 73.979024 -18.280888)
		(end 73.719182 -18.021046)
		(width 0.14224)
		(layer "In2.Cu")
		(net "M_G_DQS_DN<8>")
	)
	(segment
		(start 73.4441 -19.583146)
		(end 73.4441 -19.278854)
		(width 0.14224)
		(layer "In2.Cu")
		(net "M_G_DQS_DN<8>")
	)
	(segment
		(start 73.979024 -21.966174)
		(end 73.979024 -21.261324)
		(width 0.14224)
		(layer "In2.Cu")
		(net "M_G_DQS_DN<8>")
	)
	(segment
		(start 83.836002 -60.838588)
		(end 83.829652 -60.82792)
		(width 0.0889)
		(layer "In2.Cu")
		(net "M_G_DQS_DN<8>")
	)
	(segment
		(start 73.7997 -21.082)
		(end 73.669144 -21.082)
		(width 0.14224)
		(layer "In2.Cu")
		(net "M_G_DQS_DN<8>")
	)
	(segment
		(start 81.348072 -49.042066)
		(end 81.313528 -49.007522)
		(width 0.0889)
		(layer "In2.Cu")
		(net "M_G_DQS_DN<8>")
	)
	(segment
		(start 72.99198 -22.674072)
		(end 73.437496 -22.228556)
		(width 0.14224)
		(layer "In2.Cu")
		(net "M_G_DQS_DN<8>")
	)
	(segment
		(start 82.750152 -52.405534)
		(end 82.750152 -50.965354)
		(width 0.0889)
		(layer "In2.Cu")
		(net "M_G_DQS_DN<8>")
	)
	(segment
		(start 73.979024 -18.946622)
		(end 73.979024 -18.280888)
		(width 0.14224)
		(layer "In2.Cu")
		(net "M_G_DQS_DN<8>")
	)
	(segment
		(start 83.840828 -60.847224)
		(end 83.836002 -60.838588)
		(width 0.0889)
		(layer "In2.Cu")
		(net "M_G_DQS_DN<8>")
	)
	(segment
		(start 83.471512 -61.438536)
		(end 83.504278 -61.438536)
		(width 0.0889)
		(layer "In2.Cu")
		(net "M_G_DQS_DN<8>")
	)
	(segment
		(start 73.796144 -20.4724)
		(end 73.979024 -20.28952)
		(width 0.14224)
		(layer "In2.Cu")
		(net "M_G_DQS_DN<8>")
	)
	(segment
		(start 73.979024 -21.261324)
		(end 73.7997 -21.082)
		(width 0.14224)
		(layer "In2.Cu")
		(net "M_G_DQS_DN<8>")
	)
	(segment
		(start 82.116676 -56.872632)
		(end 82.115406 -56.870092)
		(width 0.0889)
		(layer "In2.Cu")
		(net "M_G_DQS_DN<8>")
	)
	(segment
		(start 83.489292 -63.019686)
		(end 83.489292 -62.681612)
		(width 0.0889)
		(layer "In2.Cu")
		(net "M_G_DQS_DN<8>")
	)
	(segment
		(start 82.750152 -50.965354)
		(end 81.348072 -49.563274)
		(width 0.0889)
		(layer "In2.Cu")
		(net "M_G_DQS_DN<8>")
	)
	(segment
		(start 73.26249 -24.986742)
		(end 72.99198 -24.716232)
		(width 0.14224)
		(layer "In2.Cu")
		(net "M_G_DQS_DN<8>")
	)
	(segment
		(start 73.491344 -20.9042)
		(end 73.491344 -20.6502)
		(width 0.14224)
		(layer "In2.Cu")
		(net "M_G_DQS_DN<8>")
	)
	(segment
		(start 80.642714 -46.837346)
		(end 74.905616 -41.100248)
		(width 0.14224)
		(layer "In2.Cu")
		(net "M_G_DQS_DN<8>")
	)
	(segment
		(start 73.950576 -25.67559)
		(end 73.26249 -24.987504)
		(width 0.14224)
		(layer "In2.Cu")
		(net "M_G_DQS_DN<8>")
	)
	(segment
		(start 74.905616 -41.100248)
		(end 74.905616 -34.012632)
		(width 0.14224)
		(layer "In2.Cu")
		(net "M_G_DQS_DN<8>")
	)
	(segment
		(start 73.596754 -19.1262)
		(end 73.799446 -19.1262)
		(width 0.14224)
		(layer "In2.Cu")
		(net "M_G_DQS_DN<8>")
	)
	(segment
		(start 82.03946 -53.116226)
		(end 82.750152 -52.405534)
		(width 0.0889)
		(layer "In2.Cu")
		(net "M_G_DQS_DN<8>")
	)
	(segment
		(start 73.719182 -18.021046)
		(end 73.437496 -18.021046)
		(width 0.14224)
		(layer "In2.Cu")
		(net "M_G_DQS_DN<8>")
	)
	(segment
		(start 81.348072 -49.563274)
		(end 81.348072 -49.042066)
		(width 0.0889)
		(layer "In2.Cu")
		(net "M_G_DQS_DN<8>")
	)
	(segment
		(start 73.26249 -24.987504)
		(end 73.26249 -24.986742)
		(width 0.14224)
		(layer "In2.Cu")
		(net "M_G_DQS_DN<8>")
	)
	(segment
		(start 73.979024 -19.940778)
		(end 73.774046 -19.7358)
		(width 0.14224)
		(layer "In2.Cu")
		(net "M_G_DQS_DN<8>")
	)
	(segment
		(start 73.799446 -19.1262)
		(end 73.979024 -18.946622)
		(width 0.14224)
		(layer "In2.Cu")
		(net "M_G_DQS_DN<8>")
	)
	(segment
		(start 74.042016 -33.149032)
		(end 74.042016 -28.891738)
		(width 0.14224)
		(layer "In2.Cu")
		(net "M_G_DQS_DN<8>")
	)
	(segment
		(start 73.774046 -19.7358)
		(end 73.596754 -19.7358)
		(width 0.14224)
		(layer "In2.Cu")
		(net "M_G_DQS_DN<8>")
	)
	(segment
		(start 73.491344 -20.6502)
		(end 73.669144 -20.4724)
		(width 0.14224)
		(layer "In2.Cu")
		(net "M_G_DQS_DN<8>")
	)
	(segment
		(start 82.118962 -56.876188)
		(end 82.117692 -56.874156)
		(width 0.0889)
		(layer "In2.Cu")
		(net "M_G_DQS_DN<8>")
	)
	(segment
		(start 73.979024 -20.28952)
		(end 73.979024 -19.940778)
		(width 0.14224)
		(layer "In2.Cu")
		(net "M_G_DQS_DN<8>")
	)
	(segment
		(start 74.905616 -34.012632)
		(end 74.042016 -33.149032)
		(width 0.14224)
		(layer "In2.Cu")
		(net "M_G_DQS_DN<8>")
	)
	(segment
		(start 83.840828 -59.856624)
		(end 83.836002 -59.847988)
		(width 0.0889)
		(layer "In2.Cu")
		(net "M_G_DQS_DN<8>")
	)
	(segment
		(start 73.716388 -22.22881)
		(end 73.979024 -21.966174)
		(width 0.14224)
		(layer "In2.Cu")
		(net "M_G_DQS_DN<8>")
	)
	(segment
		(start 81.313528 -49.007522)
		(end 81.313528 -48.456596)
		(width 0.14224)
		(layer "In2.Cu")
		(net "M_G_DQS_DN<8>")
	)
	(segment
		(start 82.648806 -58.16219)
		(end 82.609182 -58.16219)
		(width 0.0889)
		(layer "In2.Cu")
		(net "M_G_DQS_DN<8>")
	)
	(segment
		(start 83.507326 -58.65749)
		(end 83.471512 -58.65749)
		(width 0.0889)
		(layer "In2.Cu")
		(net "M_G_DQS_DN<8>")
	)
	(segment
		(start 73.669144 -20.4724)
		(end 73.796144 -20.4724)
		(width 0.14224)
		(layer "In2.Cu")
		(net "M_G_DQS_DN<8>")
	)
	(segment
		(start 82.03946 -55.78602)
		(end 82.03946 -53.116226)
		(width 0.0889)
		(layer "In2.Cu")
		(net "M_G_DQS_DN<8>")
	)
	(segment
		(start 82.123788 -56.884824)
		(end 82.118962 -56.876188)
		(width 0.0889)
		(layer "In2.Cu")
		(net "M_G_DQS_DN<8>")
	)
	(segment
		(start 83.489292 -62.681612)
		(end 83.424268 -62.616588)
		(width 0.0889)
		(layer "In2.Cu")
		(net "M_G_DQS_DN<8>")
	)
	(segment
		(start 73.669144 -21.082)
		(end 73.491344 -20.9042)
		(width 0.14224)
		(layer "In2.Cu")
		(net "M_G_DQS_DN<8>")
	)
	(segment
		(start 83.836002 -59.847988)
		(end 83.829652 -59.83732)
		(width 0.0889)
		(layer "In2.Cu")
		(net "M_G_DQS_DN<8>")
	)
	(segment
		(start 74.042016 -28.891738)
		(end 73.950576 -28.800298)
		(width 0.14224)
		(layer "In2.Cu")
		(net "M_G_DQS_DN<8>")
	)
	(segment
		(start 82.117692 -56.874156)
		(end 82.116676 -56.872632)
		(width 0.0889)
		(layer "In2.Cu")
		(net "M_G_DQS_DN<8>")
	)
	(segment
		(start 81.313528 -48.456596)
		(end 80.642714 -46.837346)
		(width 0.14224)
		(layer "In2.Cu")
		(net "M_G_DQS_DN<8>")
	)
	(arc
		(start 83.829652 -59.83732)
		(mid 83.756854 -59.546557)
		(end 83.836002 -59.257438)
		(width 0.0889)
		(layer "In2.Cu")
		(net "M_G_DQS_DN<8>")
	)
	(arc
		(start 82.118962 -57.276238)
		(mid 82.172432 -57.081175)
		(end 82.123788 -56.884824)
		(width 0.0889)
		(layer "In2.Cu")
		(net "M_G_DQS_DN<8>")
	)
	(arc
		(start 82.118962 -56.285638)
		(mid 82.1741 -56.067407)
		(end 82.106262 -55.852822)
		(width 0.0889)
		(layer "In2.Cu")
		(net "M_G_DQS_DN<8>")
	)
	(arc
		(start 82.609182 -58.16219)
		(mid 82.113705 -57.857747)
		(end 82.118962 -57.276238)
		(width 0.0889)
		(layer "In2.Cu")
		(net "M_G_DQS_DN<8>")
	)
	(arc
		(start 82.112612 -56.86552)
		(mid 82.039814 -56.574757)
		(end 82.118962 -56.285638)
		(width 0.0889)
		(layer "In2.Cu")
		(net "M_G_DQS_DN<8>")
	)
	(arc
		(start 83.836002 -60.248038)
		(mid 83.889472 -60.052975)
		(end 83.840828 -59.856624)
		(width 0.0889)
		(layer "In2.Cu")
		(net "M_G_DQS_DN<8>")
	)
	(arc
		(start 83.424268 -62.616588)
		(mid 82.89893 -62.005656)
		(end 83.471512 -61.438536)
		(width 0.0889)
		(layer "In2.Cu")
		(net "M_G_DQS_DN<8>")
	)
	(arc
		(start 82.977482 -58.362088)
		(mid 82.838738 -58.220055)
		(end 82.648806 -58.16219)
		(width 0.0889)
		(layer "In2.Cu")
		(net "M_G_DQS_DN<8>")
	)
	(arc
		(start 83.836002 -59.257438)
		(mid 83.840412 -58.864975)
		(end 83.507326 -58.65749)
		(width 0.0889)
		(layer "In2.Cu")
		(net "M_G_DQS_DN<8>")
	)
	(arc
		(start 83.504278 -61.438536)
		(mid 83.837196 -61.236545)
		(end 83.840828 -60.847224)
		(width 0.0889)
		(layer "In2.Cu")
		(net "M_G_DQS_DN<8>")
	)
	(arc
		(start 83.829652 -60.82792)
		(mid 83.756854 -60.537157)
		(end 83.836002 -60.248038)
		(width 0.0889)
		(layer "In2.Cu")
		(net "M_G_DQS_DN<8>")
	)
	(arc
		(start 83.471512 -58.65749)
		(mid 83.186088 -58.574023)
		(end 82.977482 -58.362088)
		(width 0.0889)
		(layer "In2.Cu")
		(net "M_G_DQS_DN<8>")
	)
	(segment
		(start 147.171918 -17.8054)
		(end 147.387564 -18.021046)
		(width 0.1651)
		(layer "F.Cu")
		(net "M_G_DQS_DN<7>")
	)
	(segment
		(start 146.999452 -18.94967)
		(end 146.617436 -18.567654)
		(width 0.1651)
		(layer "F.Cu")
		(net "M_G_DQS_DN<7>")
	)
	(segment
		(start 146.94789 -17.8054)
		(end 147.171918 -17.8054)
		(width 0.1651)
		(layer "F.Cu")
		(net "M_G_DQS_DN<7>")
	)
	(segment
		(start 122.504708 -57.390538)
		(end 121.933208 -57.390538)
		(width 0.1016)
		(layer "F.Cu")
		(net "M_G_DQS_DN<7>")
	)
	(segment
		(start 146.617436 -18.567654)
		(end 146.617436 -18.135854)
		(width 0.1651)
		(layer "F.Cu")
		(net "M_G_DQS_DN<7>")
	)
	(segment
		(start 146.999452 -20.023582)
		(end 146.999452 -18.94967)
		(width 0.1651)
		(layer "F.Cu")
		(net "M_G_DQS_DN<7>")
	)
	(segment
		(start 146.617436 -18.135854)
		(end 146.94789 -17.8054)
		(width 0.1651)
		(layer "F.Cu")
		(net "M_G_DQS_DN<7>")
	)
	(via
		(at 147.387564 -22.228556)
		(size 0.508)
		(drill 0.254)
		(layers "F.Cu" "B.Cu")
		(net "M_G_DQS_DN<7>")
	)
	(via
		(at 121.933208 -57.390538)
		(size 0.4826)
		(drill 0.254)
		(layers "F.Cu" "B.Cu")
		(net "M_G_DQS_DN<7>")
	)
	(via
		(at 147.387564 -18.021046)
		(size 0.508)
		(drill 0.254)
		(layers "F.Cu" "B.Cu")
		(net "M_G_DQS_DN<7>")
	)
	(segment
		(start 146.617436 -22.098)
		(end 146.973036 -22.4536)
		(width 0.1651)
		(layer "B.Cu")
		(net "M_G_DQS_DN<7>")
	)
	(segment
		(start 146.871436 -21.259546)
		(end 146.871436 -21.513546)
		(width 0.1651)
		(layer "B.Cu")
		(net "M_G_DQS_DN<7>")
	)
	(segment
		(start 146.871436 -21.513546)
		(end 146.617436 -21.767546)
		(width 0.1651)
		(layer "B.Cu")
		(net "M_G_DQS_DN<7>")
	)
	(segment
		(start 146.973036 -22.4536)
		(end 147.16252 -22.4536)
		(width 0.1651)
		(layer "B.Cu")
		(net "M_G_DQS_DN<7>")
	)
	(segment
		(start 146.999452 -20.224242)
		(end 146.999452 -21.13153)
		(width 0.1651)
		(layer "B.Cu")
		(net "M_G_DQS_DN<7>")
	)
	(segment
		(start 147.16252 -22.4536)
		(end 147.387564 -22.228556)
		(width 0.1651)
		(layer "B.Cu")
		(net "M_G_DQS_DN<7>")
	)
	(segment
		(start 146.617436 -21.767546)
		(end 146.617436 -22.098)
		(width 0.1651)
		(layer "B.Cu")
		(net "M_G_DQS_DN<7>")
	)
	(segment
		(start 146.999452 -21.13153)
		(end 146.871436 -21.259546)
		(width 0.1651)
		(layer "B.Cu")
		(net "M_G_DQS_DN<7>")
	)
	(segment
		(start 147.441412 -20.6502)
		(end 147.619212 -20.4724)
		(width 0.14224)
		(layer "In2.Cu")
		(net "M_G_DQS_DN<7>")
	)
	(segment
		(start 147.394168 -19.583146)
		(end 147.394168 -19.278854)
		(width 0.14224)
		(layer "In2.Cu")
		(net "M_G_DQS_DN<7>")
	)
	(segment
		(start 123.36399 -52.911502)
		(end 123.364498 -52.911248)
		(width 0.0889)
		(layer "In2.Cu")
		(net "M_G_DQS_DN<7>")
	)
	(segment
		(start 121.933208 -57.728612)
		(end 121.99112 -57.786524)
		(width 0.0889)
		(layer "In2.Cu")
		(net "M_G_DQS_DN<7>")
	)
	(segment
		(start 122.279918 -55.609236)
		(end 122.284744 -55.6006)
		(width 0.0889)
		(layer "In2.Cu")
		(net "M_G_DQS_DN<7>")
	)
	(segment
		(start 147.749514 -19.1262)
		(end 147.929092 -18.946622)
		(width 0.14224)
		(layer "In2.Cu")
		(net "M_G_DQS_DN<7>")
	)
	(segment
		(start 147.929092 -18.280888)
		(end 147.66925 -18.021046)
		(width 0.14224)
		(layer "In2.Cu")
		(net "M_G_DQS_DN<7>")
	)
	(segment
		(start 147.546822 -19.7358)
		(end 147.394168 -19.583146)
		(width 0.14224)
		(layer "In2.Cu")
		(net "M_G_DQS_DN<7>")
	)
	(segment
		(start 123.364498 -52.911248)
		(end 124.505466 -51.77028)
		(width 0.0889)
		(layer "In2.Cu")
		(net "M_G_DQS_DN<7>")
	)
	(segment
		(start 131.722368 -45.7454)
		(end 136.370822 -45.7454)
		(width 0.14224)
		(layer "In2.Cu")
		(net "M_G_DQS_DN<7>")
	)
	(segment
		(start 121.933208 -57.390538)
		(end 121.933208 -57.728612)
		(width 0.0889)
		(layer "In2.Cu")
		(net "M_G_DQS_DN<7>")
	)
	(segment
		(start 146.949668 -24.4729)
		(end 146.949668 -22.666452)
		(width 0.14224)
		(layer "In2.Cu")
		(net "M_G_DQS_DN<7>")
	)
	(segment
		(start 147.929092 -21.966174)
		(end 147.929092 -21.261324)
		(width 0.14224)
		(layer "In2.Cu")
		(net "M_G_DQS_DN<7>")
	)
	(segment
		(start 122.279918 -56.599836)
		(end 122.284744 -56.5912)
		(width 0.0889)
		(layer "In2.Cu")
		(net "M_G_DQS_DN<7>")
	)
	(segment
		(start 147.746212 -20.4724)
		(end 147.929092 -20.28952)
		(width 0.14224)
		(layer "In2.Cu")
		(net "M_G_DQS_DN<7>")
	)
	(segment
		(start 147.929092 -21.261324)
		(end 147.749768 -21.082)
		(width 0.14224)
		(layer "In2.Cu")
		(net "M_G_DQS_DN<7>")
	)
	(segment
		(start 124.505466 -51.77028)
		(end 124.505466 -51.7144)
		(width 0.0889)
		(layer "In2.Cu")
		(net "M_G_DQS_DN<7>")
	)
	(segment
		(start 147.929092 -19.940778)
		(end 147.724114 -19.7358)
		(width 0.14224)
		(layer "In2.Cu")
		(net "M_G_DQS_DN<7>")
	)
	(segment
		(start 147.619212 -20.4724)
		(end 147.746212 -20.4724)
		(width 0.14224)
		(layer "In2.Cu")
		(net "M_G_DQS_DN<7>")
	)
	(segment
		(start 147.749768 -21.082)
		(end 147.619212 -21.082)
		(width 0.14224)
		(layer "In2.Cu")
		(net "M_G_DQS_DN<7>")
	)
	(segment
		(start 129.08407 -47.135796)
		(end 130.331972 -47.135796)
		(width 0.14224)
		(layer "In2.Cu")
		(net "M_G_DQS_DN<7>")
	)
	(segment
		(start 122.279918 -57.590436)
		(end 122.284744 -57.5818)
		(width 0.0889)
		(layer "In2.Cu")
		(net "M_G_DQS_DN<7>")
	)
	(segment
		(start 147.929092 -20.28952)
		(end 147.929092 -19.940778)
		(width 0.14224)
		(layer "In2.Cu")
		(net "M_G_DQS_DN<7>")
	)
	(segment
		(start 147.387564 -22.228556)
		(end 147.387564 -22.22881)
		(width 0.14224)
		(layer "In2.Cu")
		(net "M_G_DQS_DN<7>")
	)
	(segment
		(start 147.666456 -22.22881)
		(end 147.929092 -21.966174)
		(width 0.14224)
		(layer "In2.Cu")
		(net "M_G_DQS_DN<7>")
	)
	(segment
		(start 147.724114 -19.7358)
		(end 147.546822 -19.7358)
		(width 0.14224)
		(layer "In2.Cu")
		(net "M_G_DQS_DN<7>")
	)
	(segment
		(start 146.232118 -38.50005)
		(end 147.419568 -37.3126)
		(width 0.14224)
		(layer "In2.Cu")
		(net "M_G_DQS_DN<7>")
	)
	(segment
		(start 124.505466 -51.7144)
		(end 124.521214 -51.698652)
		(width 0.0889)
		(layer "In2.Cu")
		(net "M_G_DQS_DN<7>")
	)
	(segment
		(start 147.387564 -22.22881)
		(end 147.666456 -22.22881)
		(width 0.14224)
		(layer "In2.Cu")
		(net "M_G_DQS_DN<7>")
	)
	(segment
		(start 122.273568 -55.619904)
		(end 122.279918 -55.609236)
		(width 0.0889)
		(layer "In2.Cu")
		(net "M_G_DQS_DN<7>")
	)
	(segment
		(start 147.419568 -37.3126)
		(end 147.419568 -24.9428)
		(width 0.14224)
		(layer "In2.Cu")
		(net "M_G_DQS_DN<7>")
	)
	(segment
		(start 147.929092 -18.946622)
		(end 147.929092 -18.280888)
		(width 0.14224)
		(layer "In2.Cu")
		(net "M_G_DQS_DN<7>")
	)
	(segment
		(start 147.66925 -18.021046)
		(end 147.387564 -18.021046)
		(width 0.14224)
		(layer "In2.Cu")
		(net "M_G_DQS_DN<7>")
	)
	(segment
		(start 122.273568 -56.610504)
		(end 122.279918 -56.599836)
		(width 0.0889)
		(layer "In2.Cu")
		(net "M_G_DQS_DN<7>")
	)
	(segment
		(start 147.619212 -21.082)
		(end 147.441412 -20.9042)
		(width 0.14224)
		(layer "In2.Cu")
		(net "M_G_DQS_DN<7>")
	)
	(segment
		(start 136.370822 -45.7454)
		(end 143.616172 -38.50005)
		(width 0.14224)
		(layer "In2.Cu")
		(net "M_G_DQS_DN<7>")
	)
	(segment
		(start 122.773948 -54.323234)
		(end 122.806714 -54.323234)
		(width 0.0889)
		(layer "In2.Cu")
		(net "M_G_DQS_DN<7>")
	)
	(segment
		(start 130.331972 -47.135796)
		(end 131.722368 -45.7454)
		(width 0.14224)
		(layer "In2.Cu")
		(net "M_G_DQS_DN<7>")
	)
	(segment
		(start 147.394168 -19.278854)
		(end 147.546822 -19.1262)
		(width 0.14224)
		(layer "In2.Cu")
		(net "M_G_DQS_DN<7>")
	)
	(segment
		(start 124.521214 -51.698652)
		(end 129.08407 -47.135796)
		(width 0.14224)
		(layer "In2.Cu")
		(net "M_G_DQS_DN<7>")
	)
	(segment
		(start 146.949668 -22.666452)
		(end 147.387564 -22.228556)
		(width 0.14224)
		(layer "In2.Cu")
		(net "M_G_DQS_DN<7>")
	)
	(segment
		(start 147.441412 -20.9042)
		(end 147.441412 -20.6502)
		(width 0.14224)
		(layer "In2.Cu")
		(net "M_G_DQS_DN<7>")
	)
	(segment
		(start 147.546822 -19.1262)
		(end 147.749514 -19.1262)
		(width 0.14224)
		(layer "In2.Cu")
		(net "M_G_DQS_DN<7>")
	)
	(segment
		(start 147.419568 -24.9428)
		(end 146.949668 -24.4729)
		(width 0.14224)
		(layer "In2.Cu")
		(net "M_G_DQS_DN<7>")
	)
	(segment
		(start 143.616172 -38.50005)
		(end 146.232118 -38.50005)
		(width 0.14224)
		(layer "In2.Cu")
		(net "M_G_DQS_DN<7>")
	)
	(arc
		(start 122.320304 -54.557676)
		(mid 122.520491 -54.388918)
		(end 122.773948 -54.323234)
		(width 0.0889)
		(layer "In2.Cu")
		(net "M_G_DQS_DN<7>")
	)
	(arc
		(start 123.138438 -53.132482)
		(mid 123.23608 -53.006542)
		(end 123.36399 -52.911502)
		(width 0.0889)
		(layer "In2.Cu")
		(net "M_G_DQS_DN<7>")
	)
	(arc
		(start 122.284744 -55.6006)
		(mid 122.333499 -55.404248)
		(end 122.279918 -55.209186)
		(width 0.0889)
		(layer "In2.Cu")
		(net "M_G_DQS_DN<7>")
	)
	(arc
		(start 122.284744 -57.5818)
		(mid 122.333499 -57.385448)
		(end 122.279918 -57.190386)
		(width 0.0889)
		(layer "In2.Cu")
		(net "M_G_DQS_DN<7>")
	)
	(arc
		(start 122.272806 -54.631336)
		(mid 122.295186 -54.593623)
		(end 122.320304 -54.557676)
		(width 0.0889)
		(layer "In2.Cu")
		(net "M_G_DQS_DN<7>")
	)
	(arc
		(start 122.279918 -57.190386)
		(mid 122.200696 -56.901268)
		(end 122.273568 -56.610504)
		(width 0.0889)
		(layer "In2.Cu")
		(net "M_G_DQS_DN<7>")
	)
	(arc
		(start 122.284744 -56.5912)
		(mid 122.333499 -56.394848)
		(end 122.279918 -56.199786)
		(width 0.0889)
		(layer "In2.Cu")
		(net "M_G_DQS_DN<7>")
	)
	(arc
		(start 121.99112 -57.786524)
		(mid 122.158021 -57.721624)
		(end 122.279918 -57.590436)
		(width 0.0889)
		(layer "In2.Cu")
		(net "M_G_DQS_DN<7>")
	)
	(arc
		(start 122.279918 -55.209186)
		(mid 122.200957 -54.921204)
		(end 122.272806 -54.631336)
		(width 0.0889)
		(layer "In2.Cu")
		(net "M_G_DQS_DN<7>")
	)
	(arc
		(start 122.279918 -56.199786)
		(mid 122.200696 -55.910668)
		(end 122.273568 -55.619904)
		(width 0.0889)
		(layer "In2.Cu")
		(net "M_G_DQS_DN<7>")
	)
	(arc
		(start 123.143264 -53.731922)
		(mid 123.059308 -53.432864)
		(end 123.138438 -53.132482)
		(width 0.0889)
		(layer "In2.Cu")
		(net "M_G_DQS_DN<7>")
	)
	(arc
		(start 122.806714 -54.323234)
		(mid 123.139632 -54.121243)
		(end 123.143264 -53.731922)
		(width 0.0889)
		(layer "In2.Cu")
		(net "M_G_DQS_DN<7>")
	)
	(segment
		(start 137.649458 -20.023582)
		(end 137.649458 -18.94967)
		(width 0.1651)
		(layer "F.Cu")
		(net "M_G_DQS_DN<6>")
	)
	(segment
		(start 137.597896 -17.8054)
		(end 137.821924 -17.8054)
		(width 0.1651)
		(layer "F.Cu")
		(net "M_G_DQS_DN<6>")
	)
	(segment
		(start 137.267442 -18.135854)
		(end 137.597896 -17.8054)
		(width 0.1651)
		(layer "F.Cu")
		(net "M_G_DQS_DN<6>")
	)
	(segment
		(start 137.267442 -18.567654)
		(end 137.267442 -18.135854)
		(width 0.1651)
		(layer "F.Cu")
		(net "M_G_DQS_DN<6>")
	)
	(segment
		(start 137.649458 -18.94967)
		(end 137.267442 -18.567654)
		(width 0.1651)
		(layer "F.Cu")
		(net "M_G_DQS_DN<6>")
	)
	(segment
		(start 117.353842 -58.381138)
		(end 116.782342 -58.381138)
		(width 0.1016)
		(layer "F.Cu")
		(net "M_G_DQS_DN<6>")
	)
	(segment
		(start 137.821924 -17.8054)
		(end 138.03757 -18.021046)
		(width 0.1651)
		(layer "F.Cu")
		(net "M_G_DQS_DN<6>")
	)
	(via
		(at 138.03757 -18.021046)
		(size 0.508)
		(drill 0.254)
		(layers "F.Cu" "B.Cu")
		(net "M_G_DQS_DN<6>")
	)
	(via
		(at 138.03757 -22.228556)
		(size 0.508)
		(drill 0.254)
		(layers "F.Cu" "B.Cu")
		(net "M_G_DQS_DN<6>")
	)
	(via
		(at 116.782342 -58.381138)
		(size 0.508)
		(drill 0.254)
		(layers "F.Cu" "B.Cu")
		(net "M_G_DQS_DN<6>")
	)
	(segment
		(start 137.812526 -22.4536)
		(end 137.98042 -22.285452)
		(width 0.1651)
		(layer "B.Cu")
		(net "M_G_DQS_DN<6>")
	)
	(segment
		(start 137.267442 -21.767546)
		(end 137.267442 -22.098)
		(width 0.1651)
		(layer "B.Cu")
		(net "M_G_DQS_DN<6>")
	)
	(segment
		(start 137.267442 -22.098)
		(end 137.623042 -22.4536)
		(width 0.1651)
		(layer "B.Cu")
		(net "M_G_DQS_DN<6>")
	)
	(segment
		(start 137.521442 -21.513546)
		(end 137.267442 -21.767546)
		(width 0.1651)
		(layer "B.Cu")
		(net "M_G_DQS_DN<6>")
	)
	(segment
		(start 137.521442 -21.259546)
		(end 137.521442 -21.513546)
		(width 0.1651)
		(layer "B.Cu")
		(net "M_G_DQS_DN<6>")
	)
	(segment
		(start 137.649458 -20.224242)
		(end 137.649458 -21.13153)
		(width 0.1651)
		(layer "B.Cu")
		(net "M_G_DQS_DN<6>")
	)
	(segment
		(start 137.623042 -22.4536)
		(end 137.812526 -22.4536)
		(width 0.1651)
		(layer "B.Cu")
		(net "M_G_DQS_DN<6>")
	)
	(segment
		(start 137.98042 -22.285452)
		(end 138.03757 -22.228556)
		(width 0.1651)
		(layer "B.Cu")
		(net "M_G_DQS_DN<6>")
	)
	(segment
		(start 137.649458 -21.13153)
		(end 137.521442 -21.259546)
		(width 0.1651)
		(layer "B.Cu")
		(net "M_G_DQS_DN<6>")
	)
	(segment
		(start 138.579098 -21.261324)
		(end 138.399774 -21.082)
		(width 0.14224)
		(layer "In2.Cu")
		(net "M_G_DQS_DN<6>")
	)
	(segment
		(start 117.259862 -54.228238)
		(end 117.141498 -54.109874)
		(width 0.0889)
		(layer "In2.Cu")
		(net "M_G_DQS_DN<6>")
	)
	(segment
		(start 138.03757 -22.22881)
		(end 138.316462 -22.22881)
		(width 0.14224)
		(layer "In2.Cu")
		(net "M_G_DQS_DN<6>")
	)
	(segment
		(start 138.37412 -19.7358)
		(end 138.196828 -19.7358)
		(width 0.14224)
		(layer "In2.Cu")
		(net "M_G_DQS_DN<6>")
	)
	(segment
		(start 138.091418 -20.9042)
		(end 138.091418 -20.6502)
		(width 0.14224)
		(layer "In2.Cu")
		(net "M_G_DQS_DN<6>")
	)
	(segment
		(start 117.442742 -48.415702)
		(end 117.442742 -43.64228)
		(width 0.14224)
		(layer "In2.Cu")
		(net "M_G_DQS_DN<6>")
	)
	(segment
		(start 117.482112 -49.403762)
		(end 117.482112 -48.47717)
		(width 0.0889)
		(layer "In2.Cu")
		(net "M_G_DQS_DN<6>")
	)
	(segment
		(start 116.782342 -58.043064)
		(end 116.717064 -57.977786)
		(width 0.0889)
		(layer "In2.Cu")
		(net "M_G_DQS_DN<6>")
	)
	(segment
		(start 138.39952 -19.1262)
		(end 138.579098 -18.946622)
		(width 0.14224)
		(layer "In2.Cu")
		(net "M_G_DQS_DN<6>")
	)
	(segment
		(start 138.196828 -19.1262)
		(end 138.39952 -19.1262)
		(width 0.14224)
		(layer "In2.Cu")
		(net "M_G_DQS_DN<6>")
	)
	(segment
		(start 116.749068 -50.624994)
		(end 116.749068 -50.136806)
		(width 0.0889)
		(layer "In2.Cu")
		(net "M_G_DQS_DN<6>")
	)
	(segment
		(start 117.482112 -48.47717)
		(end 117.442742 -48.4378)
		(width 0.0889)
		(layer "In2.Cu")
		(net "M_G_DQS_DN<6>")
	)
	(segment
		(start 116.977668 -51.26101)
		(end 116.977668 -50.853594)
		(width 0.0889)
		(layer "In2.Cu")
		(net "M_G_DQS_DN<6>")
	)
	(segment
		(start 137.592054 -22.674072)
		(end 137.98042 -22.285452)
		(width 0.14224)
		(layer "In2.Cu")
		(net "M_G_DQS_DN<6>")
	)
	(segment
		(start 138.044174 -19.583146)
		(end 138.044174 -19.278854)
		(width 0.14224)
		(layer "In2.Cu")
		(net "M_G_DQS_DN<6>")
	)
	(segment
		(start 137.592054 -24.631904)
		(end 137.592054 -22.674072)
		(width 0.14224)
		(layer "In2.Cu")
		(net "M_G_DQS_DN<6>")
	)
	(segment
		(start 117.129052 -54.618636)
		(end 117.259862 -54.393338)
		(width 0.0889)
		(layer "In2.Cu")
		(net "M_G_DQS_DN<6>")
	)
	(segment
		(start 138.579098 -18.946622)
		(end 138.579098 -18.280888)
		(width 0.14224)
		(layer "In2.Cu")
		(net "M_G_DQS_DN<6>")
	)
	(segment
		(start 117.259862 -54.393338)
		(end 117.259862 -54.228238)
		(width 0.0889)
		(layer "In2.Cu")
		(net "M_G_DQS_DN<6>")
	)
	(segment
		(start 138.091418 -20.6502)
		(end 138.269218 -20.4724)
		(width 0.14224)
		(layer "In2.Cu")
		(net "M_G_DQS_DN<6>")
	)
	(segment
		(start 138.269218 -21.082)
		(end 138.091418 -20.9042)
		(width 0.14224)
		(layer "In2.Cu")
		(net "M_G_DQS_DN<6>")
	)
	(segment
		(start 138.396218 -20.4724)
		(end 138.579098 -20.28952)
		(width 0.14224)
		(layer "In2.Cu")
		(net "M_G_DQS_DN<6>")
	)
	(segment
		(start 138.579098 -18.280888)
		(end 138.319256 -18.021046)
		(width 0.14224)
		(layer "In2.Cu")
		(net "M_G_DQS_DN<6>")
	)
	(segment
		(start 138.579098 -20.28952)
		(end 138.579098 -19.940778)
		(width 0.14224)
		(layer "In2.Cu")
		(net "M_G_DQS_DN<6>")
	)
	(segment
		(start 116.782342 -58.381138)
		(end 116.782342 -58.043064)
		(width 0.0889)
		(layer "In2.Cu")
		(net "M_G_DQS_DN<6>")
	)
	(segment
		(start 138.196828 -19.7358)
		(end 138.044174 -19.583146)
		(width 0.14224)
		(layer "In2.Cu")
		(net "M_G_DQS_DN<6>")
	)
	(segment
		(start 116.749068 -50.136806)
		(end 117.482112 -49.403762)
		(width 0.0889)
		(layer "In2.Cu")
		(net "M_G_DQS_DN<6>")
	)
	(segment
		(start 117.141498 -51.42484)
		(end 116.977668 -51.26101)
		(width 0.0889)
		(layer "In2.Cu")
		(net "M_G_DQS_DN<6>")
	)
	(segment
		(start 137.98042 -22.285452)
		(end 138.03757 -22.228556)
		(width 0.14224)
		(layer "In2.Cu")
		(net "M_G_DQS_DN<6>")
	)
	(segment
		(start 138.316462 -22.22881)
		(end 138.579098 -21.966174)
		(width 0.14224)
		(layer "In2.Cu")
		(net "M_G_DQS_DN<6>")
	)
	(segment
		(start 116.760752 -56.799988)
		(end 116.793518 -56.799988)
		(width 0.0889)
		(layer "In2.Cu")
		(net "M_G_DQS_DN<6>")
	)
	(segment
		(start 138.553444 -30.684724)
		(end 138.553444 -25.593294)
		(width 0.14224)
		(layer "In2.Cu")
		(net "M_G_DQS_DN<6>")
	)
	(segment
		(start 138.399774 -21.082)
		(end 138.269218 -21.082)
		(width 0.14224)
		(layer "In2.Cu")
		(net "M_G_DQS_DN<6>")
	)
	(segment
		(start 138.269218 -20.4724)
		(end 138.396218 -20.4724)
		(width 0.14224)
		(layer "In2.Cu")
		(net "M_G_DQS_DN<6>")
	)
	(segment
		(start 138.553444 -25.593294)
		(end 137.592054 -24.631904)
		(width 0.14224)
		(layer "In2.Cu")
		(net "M_G_DQS_DN<6>")
	)
	(segment
		(start 117.442742 -43.64228)
		(end 124.356622 -36.7284)
		(width 0.14224)
		(layer "In2.Cu")
		(net "M_G_DQS_DN<6>")
	)
	(segment
		(start 138.579098 -21.966174)
		(end 138.579098 -21.261324)
		(width 0.14224)
		(layer "In2.Cu")
		(net "M_G_DQS_DN<6>")
	)
	(segment
		(start 138.579098 -19.940778)
		(end 138.37412 -19.7358)
		(width 0.14224)
		(layer "In2.Cu")
		(net "M_G_DQS_DN<6>")
	)
	(segment
		(start 138.319256 -18.021046)
		(end 138.03757 -18.021046)
		(width 0.14224)
		(layer "In2.Cu")
		(net "M_G_DQS_DN<6>")
	)
	(segment
		(start 138.03757 -22.228556)
		(end 138.03757 -22.22881)
		(width 0.14224)
		(layer "In2.Cu")
		(net "M_G_DQS_DN<6>")
	)
	(segment
		(start 116.977668 -50.853594)
		(end 116.749068 -50.624994)
		(width 0.0889)
		(layer "In2.Cu")
		(net "M_G_DQS_DN<6>")
	)
	(segment
		(start 117.442742 -48.4378)
		(end 117.442742 -48.415702)
		(width 0.0889)
		(layer "In2.Cu")
		(net "M_G_DQS_DN<6>")
	)
	(segment
		(start 116.270532 -57.685686)
		(end 116.264182 -57.675018)
		(width 0.0889)
		(layer "In2.Cu")
		(net "M_G_DQS_DN<6>")
	)
	(segment
		(start 132.509768 -36.7284)
		(end 138.553444 -30.684724)
		(width 0.14224)
		(layer "In2.Cu")
		(net "M_G_DQS_DN<6>")
	)
	(segment
		(start 117.141498 -54.109874)
		(end 117.141498 -51.42484)
		(width 0.0889)
		(layer "In2.Cu")
		(net "M_G_DQS_DN<6>")
	)
	(segment
		(start 124.356622 -36.7284)
		(end 132.509768 -36.7284)
		(width 0.14224)
		(layer "In2.Cu")
		(net "M_G_DQS_DN<6>")
	)
	(segment
		(start 138.044174 -19.278854)
		(end 138.196828 -19.1262)
		(width 0.14224)
		(layer "In2.Cu")
		(net "M_G_DQS_DN<6>")
	)
	(arc
		(start 117.129052 -55.20944)
		(mid 117.049921 -54.914038)
		(end 117.129052 -54.618636)
		(width 0.0889)
		(layer "In2.Cu")
		(net "M_G_DQS_DN<6>")
	)
	(arc
		(start 116.264182 -57.675018)
		(mid 116.191384 -57.384255)
		(end 116.270532 -57.095136)
		(width 0.0889)
		(layer "In2.Cu")
		(net "M_G_DQS_DN<6>")
	)
	(arc
		(start 117.129052 -56.20004)
		(mid 117.049921 -55.904638)
		(end 117.129052 -55.609236)
		(width 0.0889)
		(layer "In2.Cu")
		(net "M_G_DQS_DN<6>")
	)
	(arc
		(start 117.129052 -55.609236)
		(mid 117.182551 -55.409338)
		(end 117.129052 -55.20944)
		(width 0.0889)
		(layer "In2.Cu")
		(net "M_G_DQS_DN<6>")
	)
	(arc
		(start 116.717064 -57.977786)
		(mid 116.458927 -57.885032)
		(end 116.270532 -57.685686)
		(width 0.0889)
		(layer "In2.Cu")
		(net "M_G_DQS_DN<6>")
	)
	(arc
		(start 116.270532 -57.095136)
		(mid 116.477536 -56.884272)
		(end 116.760752 -56.799988)
		(width 0.0889)
		(layer "In2.Cu")
		(net "M_G_DQS_DN<6>")
	)
	(arc
		(start 116.793518 -56.799988)
		(mid 117.131633 -56.595286)
		(end 117.129052 -56.20004)
		(width 0.0889)
		(layer "In2.Cu")
		(net "M_G_DQS_DN<6>")
	)
	(segment
		(start 112.202722 -58.381138)
		(end 111.631222 -58.381138)
		(width 0.1016)
		(layer "F.Cu")
		(net "M_G_DQS_DN<5>")
	)
	(segment
		(start 128.299464 -20.023582)
		(end 128.299464 -18.94967)
		(width 0.1651)
		(layer "F.Cu")
		(net "M_G_DQS_DN<5>")
	)
	(segment
		(start 128.299464 -18.94967)
		(end 127.917448 -18.567654)
		(width 0.1651)
		(layer "F.Cu")
		(net "M_G_DQS_DN<5>")
	)
	(segment
		(start 128.47193 -17.8054)
		(end 128.687576 -18.021046)
		(width 0.1651)
		(layer "F.Cu")
		(net "M_G_DQS_DN<5>")
	)
	(segment
		(start 127.917448 -18.135854)
		(end 128.247902 -17.8054)
		(width 0.1651)
		(layer "F.Cu")
		(net "M_G_DQS_DN<5>")
	)
	(segment
		(start 127.917448 -18.567654)
		(end 127.917448 -18.135854)
		(width 0.1651)
		(layer "F.Cu")
		(net "M_G_DQS_DN<5>")
	)
	(segment
		(start 128.247902 -17.8054)
		(end 128.47193 -17.8054)
		(width 0.1651)
		(layer "F.Cu")
		(net "M_G_DQS_DN<5>")
	)
	(via
		(at 111.631222 -58.381138)
		(size 0.508)
		(drill 0.254)
		(layers "F.Cu" "B.Cu")
		(net "M_G_DQS_DN<5>")
	)
	(via
		(at 128.687576 -22.228556)
		(size 0.508)
		(drill 0.254)
		(layers "F.Cu" "B.Cu")
		(net "M_G_DQS_DN<5>")
	)
	(via
		(at 128.687576 -18.021046)
		(size 0.508)
		(drill 0.254)
		(layers "F.Cu" "B.Cu")
		(net "M_G_DQS_DN<5>")
	)
	(segment
		(start 128.273048 -22.4536)
		(end 128.462532 -22.4536)
		(width 0.1651)
		(layer "B.Cu")
		(net "M_G_DQS_DN<5>")
	)
	(segment
		(start 127.917448 -21.767546)
		(end 127.917448 -22.098)
		(width 0.1651)
		(layer "B.Cu")
		(net "M_G_DQS_DN<5>")
	)
	(segment
		(start 128.299464 -21.13153)
		(end 128.171448 -21.259546)
		(width 0.1651)
		(layer "B.Cu")
		(net "M_G_DQS_DN<5>")
	)
	(segment
		(start 128.299464 -20.224242)
		(end 128.299464 -21.13153)
		(width 0.1651)
		(layer "B.Cu")
		(net "M_G_DQS_DN<5>")
	)
	(segment
		(start 127.917448 -22.098)
		(end 128.273048 -22.4536)
		(width 0.1651)
		(layer "B.Cu")
		(net "M_G_DQS_DN<5>")
	)
	(segment
		(start 128.462532 -22.4536)
		(end 128.687576 -22.228556)
		(width 0.1651)
		(layer "B.Cu")
		(net "M_G_DQS_DN<5>")
	)
	(segment
		(start 128.171448 -21.259546)
		(end 128.171448 -21.513546)
		(width 0.1651)
		(layer "B.Cu")
		(net "M_G_DQS_DN<5>")
	)
	(segment
		(start 128.171448 -21.513546)
		(end 127.917448 -21.767546)
		(width 0.1651)
		(layer "B.Cu")
		(net "M_G_DQS_DN<5>")
	)
	(segment
		(start 111.977932 -54.61889)
		(end 112.038892 -54.51348)
		(width 0.0889)
		(layer "In2.Cu")
		(net "M_G_DQS_DN<5>")
	)
	(segment
		(start 111.977932 -55.20944)
		(end 111.977678 -55.208932)
		(width 0.0889)
		(layer "In2.Cu")
		(net "M_G_DQS_DN<5>")
	)
	(segment
		(start 109.880146 -47.08525)
		(end 109.86897 -47.074074)
		(width 0.0889)
		(layer "In2.Cu")
		(net "M_G_DQS_DN<5>")
	)
	(segment
		(start 127.892048 -28.932886)
		(end 127.892048 -25.047448)
		(width 0.14224)
		(layer "In2.Cu")
		(net "M_G_DQS_DN<5>")
	)
	(segment
		(start 118.183914 -29.2608)
		(end 127.564134 -29.2608)
		(width 0.14224)
		(layer "In2.Cu")
		(net "M_G_DQS_DN<5>")
	)
	(segment
		(start 128.741424 -20.9042)
		(end 128.741424 -20.6502)
		(width 0.14224)
		(layer "In2.Cu")
		(net "M_G_DQS_DN<5>")
	)
	(segment
		(start 129.046224 -20.4724)
		(end 129.229104 -20.28952)
		(width 0.14224)
		(layer "In2.Cu")
		(net "M_G_DQS_DN<5>")
	)
	(segment
		(start 129.229104 -21.261324)
		(end 129.04978 -21.082)
		(width 0.14224)
		(layer "In2.Cu")
		(net "M_G_DQS_DN<5>")
	)
	(segment
		(start 109.90834 -47.102268)
		(end 109.891322 -47.08525)
		(width 0.0889)
		(layer "In2.Cu")
		(net "M_G_DQS_DN<5>")
	)
	(segment
		(start 128.919224 -21.082)
		(end 128.741424 -20.9042)
		(width 0.14224)
		(layer "In2.Cu")
		(net "M_G_DQS_DN<5>")
	)
	(segment
		(start 128.846834 -19.1262)
		(end 129.049526 -19.1262)
		(width 0.14224)
		(layer "In2.Cu")
		(net "M_G_DQS_DN<5>")
	)
	(segment
		(start 129.229104 -21.966174)
		(end 129.229104 -21.261324)
		(width 0.14224)
		(layer "In2.Cu")
		(net "M_G_DQS_DN<5>")
	)
	(segment
		(start 128.24206 -22.674072)
		(end 128.687576 -22.228556)
		(width 0.14224)
		(layer "In2.Cu")
		(net "M_G_DQS_DN<5>")
	)
	(segment
		(start 112.038892 -53.159914)
		(end 110.888526 -52.009548)
		(width 0.0889)
		(layer "In2.Cu")
		(net "M_G_DQS_DN<5>")
	)
	(segment
		(start 128.687576 -22.228556)
		(end 128.687576 -22.22881)
		(width 0.14224)
		(layer "In2.Cu")
		(net "M_G_DQS_DN<5>")
	)
	(segment
		(start 111.609632 -56.799988)
		(end 111.642398 -56.799988)
		(width 0.0889)
		(layer "In2.Cu")
		(net "M_G_DQS_DN<5>")
	)
	(segment
		(start 109.86897 -47.062898)
		(end 109.86897 -37.575744)
		(width 0.14224)
		(layer "In2.Cu")
		(net "M_G_DQS_DN<5>")
	)
	(segment
		(start 110.888526 -52.009548)
		(end 110.888526 -50.299366)
		(width 0.0889)
		(layer "In2.Cu")
		(net "M_G_DQS_DN<5>")
	)
	(segment
		(start 128.24206 -24.697436)
		(end 128.24206 -22.674072)
		(width 0.14224)
		(layer "In2.Cu")
		(net "M_G_DQS_DN<5>")
	)
	(segment
		(start 128.846834 -19.7358)
		(end 128.69418 -19.583146)
		(width 0.14224)
		(layer "In2.Cu")
		(net "M_G_DQS_DN<5>")
	)
	(segment
		(start 128.919224 -20.4724)
		(end 129.046224 -20.4724)
		(width 0.14224)
		(layer "In2.Cu")
		(net "M_G_DQS_DN<5>")
	)
	(segment
		(start 129.229104 -20.28952)
		(end 129.229104 -19.940778)
		(width 0.14224)
		(layer "In2.Cu")
		(net "M_G_DQS_DN<5>")
	)
	(segment
		(start 109.891322 -47.08525)
		(end 109.880146 -47.08525)
		(width 0.0889)
		(layer "In2.Cu")
		(net "M_G_DQS_DN<5>")
	)
	(segment
		(start 128.687576 -22.22881)
		(end 128.966468 -22.22881)
		(width 0.14224)
		(layer "In2.Cu")
		(net "M_G_DQS_DN<5>")
	)
	(segment
		(start 128.69418 -19.583146)
		(end 128.69418 -19.278854)
		(width 0.14224)
		(layer "In2.Cu")
		(net "M_G_DQS_DN<5>")
	)
	(segment
		(start 129.024126 -19.7358)
		(end 128.846834 -19.7358)
		(width 0.14224)
		(layer "In2.Cu")
		(net "M_G_DQS_DN<5>")
	)
	(segment
		(start 128.969262 -18.021046)
		(end 128.687576 -18.021046)
		(width 0.14224)
		(layer "In2.Cu")
		(net "M_G_DQS_DN<5>")
	)
	(segment
		(start 129.049526 -19.1262)
		(end 129.229104 -18.946622)
		(width 0.14224)
		(layer "In2.Cu")
		(net "M_G_DQS_DN<5>")
	)
	(segment
		(start 129.229104 -19.940778)
		(end 129.024126 -19.7358)
		(width 0.14224)
		(layer "In2.Cu")
		(net "M_G_DQS_DN<5>")
	)
	(segment
		(start 109.90834 -49.31918)
		(end 109.90834 -47.102268)
		(width 0.0889)
		(layer "In2.Cu")
		(net "M_G_DQS_DN<5>")
	)
	(segment
		(start 127.892048 -25.047448)
		(end 128.24206 -24.697436)
		(width 0.14224)
		(layer "In2.Cu")
		(net "M_G_DQS_DN<5>")
	)
	(segment
		(start 109.86897 -37.575744)
		(end 118.183914 -29.2608)
		(width 0.14224)
		(layer "In2.Cu")
		(net "M_G_DQS_DN<5>")
	)
	(segment
		(start 129.229104 -18.946622)
		(end 129.229104 -18.280888)
		(width 0.14224)
		(layer "In2.Cu")
		(net "M_G_DQS_DN<5>")
	)
	(segment
		(start 110.888526 -50.299366)
		(end 109.90834 -49.31918)
		(width 0.0889)
		(layer "In2.Cu")
		(net "M_G_DQS_DN<5>")
	)
	(segment
		(start 109.86897 -47.074074)
		(end 109.86897 -47.062898)
		(width 0.0889)
		(layer "In2.Cu")
		(net "M_G_DQS_DN<5>")
	)
	(segment
		(start 112.038892 -54.51348)
		(end 112.038892 -53.159914)
		(width 0.0889)
		(layer "In2.Cu")
		(net "M_G_DQS_DN<5>")
	)
	(segment
		(start 128.966468 -22.22881)
		(end 129.229104 -21.966174)
		(width 0.14224)
		(layer "In2.Cu")
		(net "M_G_DQS_DN<5>")
	)
	(segment
		(start 127.564134 -29.2608)
		(end 127.892048 -28.932886)
		(width 0.14224)
		(layer "In2.Cu")
		(net "M_G_DQS_DN<5>")
	)
	(segment
		(start 129.04978 -21.082)
		(end 128.919224 -21.082)
		(width 0.14224)
		(layer "In2.Cu")
		(net "M_G_DQS_DN<5>")
	)
	(segment
		(start 128.741424 -20.6502)
		(end 128.919224 -20.4724)
		(width 0.14224)
		(layer "In2.Cu")
		(net "M_G_DQS_DN<5>")
	)
	(segment
		(start 128.69418 -19.278854)
		(end 128.846834 -19.1262)
		(width 0.14224)
		(layer "In2.Cu")
		(net "M_G_DQS_DN<5>")
	)
	(segment
		(start 129.229104 -18.280888)
		(end 128.969262 -18.021046)
		(width 0.14224)
		(layer "In2.Cu")
		(net "M_G_DQS_DN<5>")
	)
	(arc
		(start 111.898684 -54.914038)
		(mid 111.918915 -54.76126)
		(end 111.977932 -54.61889)
		(width 0.0889)
		(layer "In2.Cu")
		(net "M_G_DQS_DN<5>")
	)
	(arc
		(start 111.631222 -58.381138)
		(mid 111.430788 -58.074242)
		(end 111.19739 -57.791604)
		(width 0.0889)
		(layer "In2.Cu")
		(net "M_G_DQS_DN<5>")
	)
	(arc
		(start 111.642398 -56.799988)
		(mid 111.980513 -56.595286)
		(end 111.977932 -56.20004)
		(width 0.0889)
		(layer "In2.Cu")
		(net "M_G_DQS_DN<5>")
	)
	(arc
		(start 111.977932 -56.20004)
		(mid 111.898801 -55.904638)
		(end 111.977932 -55.609236)
		(width 0.0889)
		(layer "In2.Cu")
		(net "M_G_DQS_DN<5>")
	)
	(arc
		(start 111.19739 -57.791604)
		(mid 111.085682 -57.16371)
		(end 111.609632 -56.799988)
		(width 0.0889)
		(layer "In2.Cu")
		(net "M_G_DQS_DN<5>")
	)
	(arc
		(start 111.977932 -55.609236)
		(mid 112.031431 -55.409338)
		(end 111.977932 -55.20944)
		(width 0.0889)
		(layer "In2.Cu")
		(net "M_G_DQS_DN<5>")
	)
	(arc
		(start 111.977678 -55.208932)
		(mid 111.91881 -55.066677)
		(end 111.898684 -54.914038)
		(width 0.0889)
		(layer "In2.Cu")
		(net "M_G_DQS_DN<5>")
	)
	(segment
		(start 108.984542 -40.500046)
		(end 109.159548 -40.32504)
		(width 0.1016)
		(layer "F.Cu")
		(net "M_G_DQS_DN<4>")
	)
	(segment
		(start 108.984542 -50.91303)
		(end 108.984542 -49.8856)
		(width 0.0889)
		(layer "F.Cu")
		(net "M_G_DQS_DN<4>")
	)
	(segment
		(start 118.5672 -18.135854)
		(end 118.897654 -17.8054)
		(width 0.1651)
		(layer "F.Cu")
		(net "M_G_DQS_DN<4>")
	)
	(segment
		(start 108.747306 -52.837334)
		(end 108.768896 -52.837334)
		(width 0.0889)
		(layer "F.Cu")
		(net "M_G_DQS_DN<4>")
	)
	(segment
		(start 118.897654 -17.8054)
		(end 119.121682 -17.8054)
		(width 0.1651)
		(layer "F.Cu")
		(net "M_G_DQS_DN<4>")
	)
	(segment
		(start 108.984542 -49.8856)
		(end 108.984542 -40.500046)
		(width 0.1016)
		(layer "F.Cu")
		(net "M_G_DQS_DN<4>")
	)
	(segment
		(start 109.159548 -39.029132)
		(end 118.392448 -29.796232)
		(width 0.1651)
		(layer "F.Cu")
		(net "M_G_DQS_DN<4>")
	)
	(segment
		(start 118.5672 -18.567654)
		(end 118.5672 -18.135854)
		(width 0.1651)
		(layer "F.Cu")
		(net "M_G_DQS_DN<4>")
	)
	(segment
		(start 118.949216 -20.023328)
		(end 118.949216 -18.94967)
		(width 0.1651)
		(layer "F.Cu")
		(net "M_G_DQS_DN<4>")
	)
	(segment
		(start 109.159548 -40.32504)
		(end 109.159548 -39.029132)
		(width 0.1651)
		(layer "F.Cu")
		(net "M_G_DQS_DN<4>")
	)
	(segment
		(start 118.94947 -20.023582)
		(end 118.949216 -20.023328)
		(width 0.1651)
		(layer "F.Cu")
		(net "M_G_DQS_DN<4>")
	)
	(segment
		(start 118.392448 -24.42972)
		(end 118.881398 -23.94077)
		(width 0.1651)
		(layer "F.Cu")
		(net "M_G_DQS_DN<4>")
	)
	(segment
		(start 109.067346 -51.053746)
		(end 108.984542 -50.91303)
		(width 0.0889)
		(layer "F.Cu")
		(net "M_G_DQS_DN<4>")
	)
	(segment
		(start 119.121682 -17.8054)
		(end 119.337328 -18.021046)
		(width 0.1651)
		(layer "F.Cu")
		(net "M_G_DQS_DN<4>")
	)
	(segment
		(start 118.881398 -22.684486)
		(end 119.337328 -22.228556)
		(width 0.1651)
		(layer "F.Cu")
		(net "M_G_DQS_DN<4>")
	)
	(segment
		(start 118.881398 -23.94077)
		(end 118.881398 -22.684486)
		(width 0.1651)
		(layer "F.Cu")
		(net "M_G_DQS_DN<4>")
	)
	(segment
		(start 118.392448 -28.956)
		(end 118.392448 -24.42972)
		(width 0.1651)
		(layer "F.Cu")
		(net "M_G_DQS_DN<4>")
	)
	(segment
		(start 118.949216 -18.94967)
		(end 118.5672 -18.567654)
		(width 0.1651)
		(layer "F.Cu")
		(net "M_G_DQS_DN<4>")
	)
	(segment
		(start 109.168438 -51.469798)
		(end 109.168438 -51.465226)
		(width 0.0889)
		(layer "F.Cu")
		(net "M_G_DQS_DN<4>")
	)
	(segment
		(start 118.392448 -29.796232)
		(end 118.392448 -28.956)
		(width 0.1651)
		(layer "F.Cu")
		(net "M_G_DQS_DN<4>")
	)
	(via
		(at 118.392448 -28.956)
		(size 0.508)
		(drill 0.254)
		(layers "F.Cu" "B.Cu")
		(net "M_G_DQS_DN<4>")
	)
	(via
		(at 119.337328 -22.228556)
		(size 0.508)
		(drill 0.254)
		(layers "F.Cu" "B.Cu")
		(net "M_G_DQS_DN<4>")
	)
	(via
		(at 119.337328 -18.021046)
		(size 0.508)
		(drill 0.254)
		(layers "F.Cu" "B.Cu")
		(net "M_G_DQS_DN<4>")
	)
	(arc
		(start 108.768896 -54.418738)
		(mid 108.546708 -54.104616)
		(end 108.31068 -53.800756)
		(width 0.0889)
		(layer "F.Cu")
		(net "M_G_DQS_DN<4>")
	)
	(arc
		(start 108.31068 -53.800756)
		(mid 108.178262 -53.418957)
		(end 108.32211 -53.041296)
		(width 0.0889)
		(layer "F.Cu")
		(net "M_G_DQS_DN<4>")
	)
	(arc
		(start 109.115352 -52.237386)
		(mid 109.036221 -51.941984)
		(end 109.115352 -51.646582)
		(width 0.0889)
		(layer "F.Cu")
		(net "M_G_DQS_DN<4>")
	)
	(arc
		(start 109.115352 -51.646582)
		(mid 109.15225 -51.561297)
		(end 109.168438 -51.469798)
		(width 0.0889)
		(layer "F.Cu")
		(net "M_G_DQS_DN<4>")
	)
	(arc
		(start 108.32211 -53.041296)
		(mid 108.513475 -52.895037)
		(end 108.747306 -52.837334)
		(width 0.0889)
		(layer "F.Cu")
		(net "M_G_DQS_DN<4>")
	)
	(arc
		(start 109.168438 -51.465226)
		(mid 109.147874 -51.252125)
		(end 109.067346 -51.053746)
		(width 0.0889)
		(layer "F.Cu")
		(net "M_G_DQS_DN<4>")
	)
	(arc
		(start 108.768896 -52.837334)
		(mid 109.115322 -52.637357)
		(end 109.115352 -52.237386)
		(width 0.0889)
		(layer "F.Cu")
		(net "M_G_DQS_DN<4>")
	)
	(segment
		(start 118.8212 -21.513546)
		(end 118.5672 -21.767546)
		(width 0.1651)
		(layer "B.Cu")
		(net "M_G_DQS_DN<4>")
	)
	(segment
		(start 118.5672 -21.767546)
		(end 118.5672 -22.098)
		(width 0.1651)
		(layer "B.Cu")
		(net "M_G_DQS_DN<4>")
	)
	(segment
		(start 118.5672 -22.098)
		(end 118.9228 -22.4536)
		(width 0.1651)
		(layer "B.Cu")
		(net "M_G_DQS_DN<4>")
	)
	(segment
		(start 119.112284 -22.4536)
		(end 119.337328 -22.228556)
		(width 0.1651)
		(layer "B.Cu")
		(net "M_G_DQS_DN<4>")
	)
	(segment
		(start 118.9228 -22.4536)
		(end 119.112284 -22.4536)
		(width 0.1651)
		(layer "B.Cu")
		(net "M_G_DQS_DN<4>")
	)
	(segment
		(start 118.8212 -21.259546)
		(end 118.8212 -21.513546)
		(width 0.1651)
		(layer "B.Cu")
		(net "M_G_DQS_DN<4>")
	)
	(segment
		(start 118.94947 -21.131276)
		(end 118.8212 -21.259546)
		(width 0.1651)
		(layer "B.Cu")
		(net "M_G_DQS_DN<4>")
	)
	(segment
		(start 118.94947 -20.224242)
		(end 118.94947 -21.131276)
		(width 0.1651)
		(layer "B.Cu")
		(net "M_G_DQS_DN<4>")
	)
	(segment
		(start 119.878856 -18.280888)
		(end 119.619014 -18.021046)
		(width 0.14224)
		(layer "In2.Cu")
		(net "M_G_DQS_DN<4>")
	)
	(segment
		(start 119.878856 -21.966174)
		(end 119.878856 -21.261324)
		(width 0.14224)
		(layer "In2.Cu")
		(net "M_G_DQS_DN<4>")
	)
	(segment
		(start 119.568976 -21.082)
		(end 119.391176 -20.9042)
		(width 0.14224)
		(layer "In2.Cu")
		(net "M_G_DQS_DN<4>")
	)
	(segment
		(start 119.699532 -21.082)
		(end 119.568976 -21.082)
		(width 0.14224)
		(layer "In2.Cu")
		(net "M_G_DQS_DN<4>")
	)
	(segment
		(start 119.391176 -20.6502)
		(end 119.568976 -20.4724)
		(width 0.14224)
		(layer "In2.Cu")
		(net "M_G_DQS_DN<4>")
	)
	(segment
		(start 119.343932 -19.583146)
		(end 119.343932 -19.278854)
		(width 0.14224)
		(layer "In2.Cu")
		(net "M_G_DQS_DN<4>")
	)
	(segment
		(start 119.699278 -19.1262)
		(end 119.878856 -18.946622)
		(width 0.14224)
		(layer "In2.Cu")
		(net "M_G_DQS_DN<4>")
	)
	(segment
		(start 119.496586 -19.7358)
		(end 119.343932 -19.583146)
		(width 0.14224)
		(layer "In2.Cu")
		(net "M_G_DQS_DN<4>")
	)
	(segment
		(start 119.343932 -19.278854)
		(end 119.496586 -19.1262)
		(width 0.14224)
		(layer "In2.Cu")
		(net "M_G_DQS_DN<4>")
	)
	(segment
		(start 119.337328 -22.22881)
		(end 119.61622 -22.22881)
		(width 0.14224)
		(layer "In2.Cu")
		(net "M_G_DQS_DN<4>")
	)
	(segment
		(start 119.337328 -22.228556)
		(end 119.337328 -22.22881)
		(width 0.14224)
		(layer "In2.Cu")
		(net "M_G_DQS_DN<4>")
	)
	(segment
		(start 119.568976 -20.4724)
		(end 119.695976 -20.4724)
		(width 0.14224)
		(layer "In2.Cu")
		(net "M_G_DQS_DN<4>")
	)
	(segment
		(start 119.496586 -19.1262)
		(end 119.699278 -19.1262)
		(width 0.14224)
		(layer "In2.Cu")
		(net "M_G_DQS_DN<4>")
	)
	(segment
		(start 119.878856 -20.28952)
		(end 119.878856 -19.940778)
		(width 0.14224)
		(layer "In2.Cu")
		(net "M_G_DQS_DN<4>")
	)
	(segment
		(start 119.673878 -19.7358)
		(end 119.496586 -19.7358)
		(width 0.14224)
		(layer "In2.Cu")
		(net "M_G_DQS_DN<4>")
	)
	(segment
		(start 119.619014 -18.021046)
		(end 119.337328 -18.021046)
		(width 0.14224)
		(layer "In2.Cu")
		(net "M_G_DQS_DN<4>")
	)
	(segment
		(start 119.61622 -22.22881)
		(end 119.878856 -21.966174)
		(width 0.14224)
		(layer "In2.Cu")
		(net "M_G_DQS_DN<4>")
	)
	(segment
		(start 119.391176 -20.9042)
		(end 119.391176 -20.6502)
		(width 0.14224)
		(layer "In2.Cu")
		(net "M_G_DQS_DN<4>")
	)
	(segment
		(start 119.878856 -18.946622)
		(end 119.878856 -18.280888)
		(width 0.14224)
		(layer "In2.Cu")
		(net "M_G_DQS_DN<4>")
	)
	(segment
		(start 119.878856 -21.261324)
		(end 119.699532 -21.082)
		(width 0.14224)
		(layer "In2.Cu")
		(net "M_G_DQS_DN<4>")
	)
	(segment
		(start 119.695976 -20.4724)
		(end 119.878856 -20.28952)
		(width 0.14224)
		(layer "In2.Cu")
		(net "M_G_DQS_DN<4>")
	)
	(segment
		(start 119.878856 -19.940778)
		(end 119.673878 -19.7358)
		(width 0.14224)
		(layer "In2.Cu")
		(net "M_G_DQS_DN<4>")
	)
	(segment
		(start 63.647828 -17.8054)
		(end 63.871856 -17.8054)
		(width 0.1651)
		(layer "F.Cu")
		(net "M_G_DQS_DN<3>")
	)
	(segment
		(start 63.69939 -20.023582)
		(end 63.69939 -18.94967)
		(width 0.1651)
		(layer "F.Cu")
		(net "M_G_DQS_DN<3>")
	)
	(segment
		(start 77.192886 -57.076086)
		(end 76.621386 -57.076086)
		(width 0.1016)
		(layer "F.Cu")
		(net "M_G_DQS_DN<3>")
	)
	(segment
		(start 63.317374 -18.135854)
		(end 63.647828 -17.8054)
		(width 0.1651)
		(layer "F.Cu")
		(net "M_G_DQS_DN<3>")
	)
	(segment
		(start 63.69939 -18.94967)
		(end 63.317374 -18.567654)
		(width 0.1651)
		(layer "F.Cu")
		(net "M_G_DQS_DN<3>")
	)
	(segment
		(start 63.317374 -18.567654)
		(end 63.317374 -18.135854)
		(width 0.1651)
		(layer "F.Cu")
		(net "M_G_DQS_DN<3>")
	)
	(segment
		(start 63.871856 -17.8054)
		(end 64.087502 -18.021046)
		(width 0.1651)
		(layer "F.Cu")
		(net "M_G_DQS_DN<3>")
	)
	(via
		(at 64.087502 -18.021046)
		(size 0.508)
		(drill 0.254)
		(layers "F.Cu" "B.Cu")
		(net "M_G_DQS_DN<3>")
	)
	(via
		(at 64.087502 -22.228556)
		(size 0.508)
		(drill 0.254)
		(layers "F.Cu" "B.Cu")
		(net "M_G_DQS_DN<3>")
	)
	(via
		(at 76.621386 -57.076086)
		(size 0.508)
		(drill 0.254)
		(layers "F.Cu" "B.Cu")
		(net "M_G_DQS_DN<3>")
	)
	(segment
		(start 63.862458 -22.4536)
		(end 64.087502 -22.228556)
		(width 0.1651)
		(layer "B.Cu")
		(net "M_G_DQS_DN<3>")
	)
	(segment
		(start 63.69939 -20.224242)
		(end 63.69939 -21.13153)
		(width 0.1651)
		(layer "B.Cu")
		(net "M_G_DQS_DN<3>")
	)
	(segment
		(start 63.571374 -21.259546)
		(end 63.571374 -21.513546)
		(width 0.1651)
		(layer "B.Cu")
		(net "M_G_DQS_DN<3>")
	)
	(segment
		(start 63.317374 -22.098)
		(end 63.672974 -22.4536)
		(width 0.1651)
		(layer "B.Cu")
		(net "M_G_DQS_DN<3>")
	)
	(segment
		(start 63.672974 -22.4536)
		(end 63.862458 -22.4536)
		(width 0.1651)
		(layer "B.Cu")
		(net "M_G_DQS_DN<3>")
	)
	(segment
		(start 63.571374 -21.513546)
		(end 63.317374 -21.767546)
		(width 0.1651)
		(layer "B.Cu")
		(net "M_G_DQS_DN<3>")
	)
	(segment
		(start 63.69939 -21.13153)
		(end 63.571374 -21.259546)
		(width 0.1651)
		(layer "B.Cu")
		(net "M_G_DQS_DN<3>")
	)
	(segment
		(start 63.317374 -21.767546)
		(end 63.317374 -22.098)
		(width 0.1651)
		(layer "B.Cu")
		(net "M_G_DQS_DN<3>")
	)
	(segment
		(start 76.972922 -54.903624)
		(end 76.968096 -54.894988)
		(width 0.0889)
		(layer "In2.Cu")
		(net "M_G_DQS_DN<3>")
	)
	(segment
		(start 76.968096 -54.894988)
		(end 76.961746 -54.88432)
		(width 0.0889)
		(layer "In2.Cu")
		(net "M_G_DQS_DN<3>")
	)
	(segment
		(start 72.59701 -49.097438)
		(end 64.614044 -41.114472)
		(width 0.14224)
		(layer "In2.Cu")
		(net "M_G_DQS_DN<3>")
	)
	(segment
		(start 76.968096 -53.904388)
		(end 76.961746 -53.89372)
		(width 0.0889)
		(layer "In2.Cu")
		(net "M_G_DQS_DN<3>")
	)
	(segment
		(start 64.449706 -21.082)
		(end 64.31915 -21.082)
		(width 0.14224)
		(layer "In2.Cu")
		(net "M_G_DQS_DN<3>")
	)
	(segment
		(start 64.62903 -19.940778)
		(end 64.424052 -19.7358)
		(width 0.14224)
		(layer "In2.Cu")
		(net "M_G_DQS_DN<3>")
	)
	(segment
		(start 72.63638 -49.488852)
		(end 72.59701 -49.449482)
		(width 0.0889)
		(layer "In2.Cu")
		(net "M_G_DQS_DN<3>")
	)
	(segment
		(start 63.768986 -24.020018)
		(end 63.649606 -23.900638)
		(width 0.14224)
		(layer "In2.Cu")
		(net "M_G_DQS_DN<3>")
	)
	(segment
		(start 63.649606 -22.666452)
		(end 64.087502 -22.228556)
		(width 0.14224)
		(layer "In2.Cu")
		(net "M_G_DQS_DN<3>")
	)
	(segment
		(start 63.649606 -23.900638)
		(end 63.649606 -22.666452)
		(width 0.14224)
		(layer "In2.Cu")
		(net "M_G_DQS_DN<3>")
	)
	(segment
		(start 72.59701 -49.449482)
		(end 72.59701 -49.097438)
		(width 0.14224)
		(layer "In2.Cu")
		(net "M_G_DQS_DN<3>")
	)
	(segment
		(start 64.614044 -25.440132)
		(end 63.768986 -24.595074)
		(width 0.14224)
		(layer "In2.Cu")
		(net "M_G_DQS_DN<3>")
	)
	(segment
		(start 64.614044 -41.114472)
		(end 64.614044 -25.440132)
		(width 0.14224)
		(layer "In2.Cu")
		(net "M_G_DQS_DN<3>")
	)
	(segment
		(start 64.094106 -19.278854)
		(end 64.24676 -19.1262)
		(width 0.14224)
		(layer "In2.Cu")
		(net "M_G_DQS_DN<3>")
	)
	(segment
		(start 74.915522 -51.723036)
		(end 74.882756 -51.723036)
		(width 0.0889)
		(layer "In2.Cu")
		(net "M_G_DQS_DN<3>")
	)
	(segment
		(start 76.603606 -55.494936)
		(end 76.636372 -55.494936)
		(width 0.0889)
		(layer "In2.Cu")
		(net "M_G_DQS_DN<3>")
	)
	(segment
		(start 75.777852 -52.21859)
		(end 75.745086 -52.21859)
		(width 0.0889)
		(layer "In2.Cu")
		(net "M_G_DQS_DN<3>")
	)
	(segment
		(start 64.31915 -21.082)
		(end 64.14135 -20.9042)
		(width 0.14224)
		(layer "In2.Cu")
		(net "M_G_DQS_DN<3>")
	)
	(segment
		(start 64.449452 -19.1262)
		(end 64.62903 -18.946622)
		(width 0.14224)
		(layer "In2.Cu")
		(net "M_G_DQS_DN<3>")
	)
	(segment
		(start 76.632562 -52.713636)
		(end 76.599796 -52.713636)
		(width 0.0889)
		(layer "In2.Cu")
		(net "M_G_DQS_DN<3>")
	)
	(segment
		(start 64.14135 -20.9042)
		(end 64.14135 -20.6502)
		(width 0.14224)
		(layer "In2.Cu")
		(net "M_G_DQS_DN<3>")
	)
	(segment
		(start 64.24676 -19.7358)
		(end 64.094106 -19.583146)
		(width 0.14224)
		(layer "In2.Cu")
		(net "M_G_DQS_DN<3>")
	)
	(segment
		(start 64.369188 -18.021046)
		(end 64.087502 -18.021046)
		(width 0.14224)
		(layer "In2.Cu")
		(net "M_G_DQS_DN<3>")
	)
	(segment
		(start 64.62903 -21.261324)
		(end 64.449706 -21.082)
		(width 0.14224)
		(layer "In2.Cu")
		(net "M_G_DQS_DN<3>")
	)
	(segment
		(start 64.62903 -21.966174)
		(end 64.62903 -21.261324)
		(width 0.14224)
		(layer "In2.Cu")
		(net "M_G_DQS_DN<3>")
	)
	(segment
		(start 64.31915 -20.4724)
		(end 64.44615 -20.4724)
		(width 0.14224)
		(layer "In2.Cu")
		(net "M_G_DQS_DN<3>")
	)
	(segment
		(start 76.621386 -56.738012)
		(end 76.556362 -56.672988)
		(width 0.0889)
		(layer "In2.Cu")
		(net "M_G_DQS_DN<3>")
	)
	(segment
		(start 64.24676 -19.1262)
		(end 64.449452 -19.1262)
		(width 0.14224)
		(layer "In2.Cu")
		(net "M_G_DQS_DN<3>")
	)
	(segment
		(start 64.087502 -22.22881)
		(end 64.366394 -22.22881)
		(width 0.14224)
		(layer "In2.Cu")
		(net "M_G_DQS_DN<3>")
	)
	(segment
		(start 64.094106 -19.583146)
		(end 64.094106 -19.278854)
		(width 0.14224)
		(layer "In2.Cu")
		(net "M_G_DQS_DN<3>")
	)
	(segment
		(start 74.060812 -51.22799)
		(end 74.028046 -51.22799)
		(width 0.0889)
		(layer "In2.Cu")
		(net "M_G_DQS_DN<3>")
	)
	(segment
		(start 64.087502 -22.228556)
		(end 64.087502 -22.22881)
		(width 0.14224)
		(layer "In2.Cu")
		(net "M_G_DQS_DN<3>")
	)
	(segment
		(start 64.62903 -20.28952)
		(end 64.62903 -19.940778)
		(width 0.14224)
		(layer "In2.Cu")
		(net "M_G_DQS_DN<3>")
	)
	(segment
		(start 63.768986 -24.595074)
		(end 63.768986 -24.020018)
		(width 0.14224)
		(layer "In2.Cu")
		(net "M_G_DQS_DN<3>")
	)
	(segment
		(start 76.621386 -57.076086)
		(end 76.621386 -56.738012)
		(width 0.0889)
		(layer "In2.Cu")
		(net "M_G_DQS_DN<3>")
	)
	(segment
		(start 64.366394 -22.22881)
		(end 64.62903 -21.966174)
		(width 0.14224)
		(layer "In2.Cu")
		(net "M_G_DQS_DN<3>")
	)
	(segment
		(start 64.62903 -18.280888)
		(end 64.369188 -18.021046)
		(width 0.14224)
		(layer "In2.Cu")
		(net "M_G_DQS_DN<3>")
	)
	(segment
		(start 64.44615 -20.4724)
		(end 64.62903 -20.28952)
		(width 0.14224)
		(layer "In2.Cu")
		(net "M_G_DQS_DN<3>")
	)
	(segment
		(start 64.14135 -20.6502)
		(end 64.31915 -20.4724)
		(width 0.14224)
		(layer "In2.Cu")
		(net "M_G_DQS_DN<3>")
	)
	(segment
		(start 72.63638 -50.291238)
		(end 72.63638 -49.488852)
		(width 0.0889)
		(layer "In2.Cu")
		(net "M_G_DQS_DN<3>")
	)
	(segment
		(start 73.198482 -50.732436)
		(end 73.165716 -50.732436)
		(width 0.0889)
		(layer "In2.Cu")
		(net "M_G_DQS_DN<3>")
	)
	(segment
		(start 64.424052 -19.7358)
		(end 64.24676 -19.7358)
		(width 0.14224)
		(layer "In2.Cu")
		(net "M_G_DQS_DN<3>")
	)
	(segment
		(start 76.972922 -53.913024)
		(end 76.968096 -53.904388)
		(width 0.0889)
		(layer "In2.Cu")
		(net "M_G_DQS_DN<3>")
	)
	(segment
		(start 64.62903 -18.946622)
		(end 64.62903 -18.280888)
		(width 0.14224)
		(layer "In2.Cu")
		(net "M_G_DQS_DN<3>")
	)
	(arc
		(start 76.968096 -54.304438)
		(mid 77.021566 -54.109375)
		(end 76.972922 -53.913024)
		(width 0.0889)
		(layer "In2.Cu")
		(net "M_G_DQS_DN<3>")
	)
	(arc
		(start 74.882756 -51.723036)
		(mid 74.599539 -51.638755)
		(end 74.392536 -51.427888)
		(width 0.0889)
		(layer "In2.Cu")
		(net "M_G_DQS_DN<3>")
	)
	(arc
		(start 76.636372 -55.494936)
		(mid 76.96929 -55.292945)
		(end 76.972922 -54.903624)
		(width 0.0889)
		(layer "In2.Cu")
		(net "M_G_DQS_DN<3>")
	)
	(arc
		(start 76.599796 -52.713636)
		(mid 76.316579 -52.629355)
		(end 76.109576 -52.418488)
		(width 0.0889)
		(layer "In2.Cu")
		(net "M_G_DQS_DN<3>")
	)
	(arc
		(start 74.028046 -51.22799)
		(mid 73.742622 -51.144523)
		(end 73.534016 -50.932588)
		(width 0.0889)
		(layer "In2.Cu")
		(net "M_G_DQS_DN<3>")
	)
	(arc
		(start 74.392536 -51.427888)
		(mid 74.252457 -51.285152)
		(end 74.060812 -51.22799)
		(width 0.0889)
		(layer "In2.Cu")
		(net "M_G_DQS_DN<3>")
	)
	(arc
		(start 76.961746 -53.89372)
		(mid 76.888948 -53.602957)
		(end 76.968096 -53.313838)
		(width 0.0889)
		(layer "In2.Cu")
		(net "M_G_DQS_DN<3>")
	)
	(arc
		(start 73.534016 -50.932588)
		(mid 73.392333 -50.788784)
		(end 73.198482 -50.732436)
		(width 0.0889)
		(layer "In2.Cu")
		(net "M_G_DQS_DN<3>")
	)
	(arc
		(start 76.556362 -56.672988)
		(mid 76.031024 -56.062056)
		(end 76.603606 -55.494936)
		(width 0.0889)
		(layer "In2.Cu")
		(net "M_G_DQS_DN<3>")
	)
	(arc
		(start 75.251056 -51.923188)
		(mid 75.109373 -51.779384)
		(end 74.915522 -51.723036)
		(width 0.0889)
		(layer "In2.Cu")
		(net "M_G_DQS_DN<3>")
	)
	(arc
		(start 76.109576 -52.418488)
		(mid 75.969497 -52.275752)
		(end 75.777852 -52.21859)
		(width 0.0889)
		(layer "In2.Cu")
		(net "M_G_DQS_DN<3>")
	)
	(arc
		(start 76.961746 -54.88432)
		(mid 76.888948 -54.593557)
		(end 76.968096 -54.304438)
		(width 0.0889)
		(layer "In2.Cu")
		(net "M_G_DQS_DN<3>")
	)
	(arc
		(start 73.165716 -50.732436)
		(mid 72.882499 -50.648155)
		(end 72.675496 -50.437288)
		(width 0.0889)
		(layer "In2.Cu")
		(net "M_G_DQS_DN<3>")
	)
	(arc
		(start 75.745086 -52.21859)
		(mid 75.459662 -52.135123)
		(end 75.251056 -51.923188)
		(width 0.0889)
		(layer "In2.Cu")
		(net "M_G_DQS_DN<3>")
	)
	(arc
		(start 76.968096 -53.313838)
		(mid 76.970844 -52.918371)
		(end 76.632562 -52.713636)
		(width 0.0889)
		(layer "In2.Cu")
		(net "M_G_DQS_DN<3>")
	)
	(arc
		(start 72.675496 -50.437288)
		(mid 72.646342 -50.366834)
		(end 72.63638 -50.291238)
		(width 0.0889)
		(layer "In2.Cu")
		(net "M_G_DQS_DN<3>")
	)
	(segment
		(start 54.349396 -18.94967)
		(end 53.96738 -18.567654)
		(width 0.1651)
		(layer "F.Cu")
		(net "M_G_DQS_DN<2>")
	)
	(segment
		(start 53.96738 -18.567654)
		(end 53.96738 -18.135854)
		(width 0.1651)
		(layer "F.Cu")
		(net "M_G_DQS_DN<2>")
	)
	(segment
		(start 54.349396 -20.023582)
		(end 54.349396 -18.94967)
		(width 0.1651)
		(layer "F.Cu")
		(net "M_G_DQS_DN<2>")
	)
	(segment
		(start 54.521862 -17.8054)
		(end 54.737508 -18.021046)
		(width 0.1651)
		(layer "F.Cu")
		(net "M_G_DQS_DN<2>")
	)
	(segment
		(start 53.96738 -18.135854)
		(end 54.297834 -17.8054)
		(width 0.1651)
		(layer "F.Cu")
		(net "M_G_DQS_DN<2>")
	)
	(segment
		(start 73.758806 -56.085486)
		(end 73.187306 -56.085486)
		(width 0.1016)
		(layer "F.Cu")
		(net "M_G_DQS_DN<2>")
	)
	(segment
		(start 54.297834 -17.8054)
		(end 54.521862 -17.8054)
		(width 0.1651)
		(layer "F.Cu")
		(net "M_G_DQS_DN<2>")
	)
	(via
		(at 54.737508 -18.021046)
		(size 0.508)
		(drill 0.254)
		(layers "F.Cu" "B.Cu")
		(net "M_G_DQS_DN<2>")
	)
	(via
		(at 54.737508 -22.228556)
		(size 0.508)
		(drill 0.254)
		(layers "F.Cu" "B.Cu")
		(net "M_G_DQS_DN<2>")
	)
	(via
		(at 73.187306 -56.085486)
		(size 0.508)
		(drill 0.254)
		(layers "F.Cu" "B.Cu")
		(net "M_G_DQS_DN<2>")
	)
	(segment
		(start 53.96738 -21.767546)
		(end 53.96738 -22.098)
		(width 0.1651)
		(layer "B.Cu")
		(net "M_G_DQS_DN<2>")
	)
	(segment
		(start 54.349396 -21.13153)
		(end 54.22138 -21.259546)
		(width 0.1651)
		(layer "B.Cu")
		(net "M_G_DQS_DN<2>")
	)
	(segment
		(start 54.349396 -20.224242)
		(end 54.349396 -21.13153)
		(width 0.1651)
		(layer "B.Cu")
		(net "M_G_DQS_DN<2>")
	)
	(segment
		(start 54.512464 -22.4536)
		(end 54.737508 -22.228556)
		(width 0.1651)
		(layer "B.Cu")
		(net "M_G_DQS_DN<2>")
	)
	(segment
		(start 54.32298 -22.4536)
		(end 54.512464 -22.4536)
		(width 0.1651)
		(layer "B.Cu")
		(net "M_G_DQS_DN<2>")
	)
	(segment
		(start 54.22138 -21.259546)
		(end 54.22138 -21.513546)
		(width 0.1651)
		(layer "B.Cu")
		(net "M_G_DQS_DN<2>")
	)
	(segment
		(start 54.22138 -21.513546)
		(end 53.96738 -21.767546)
		(width 0.1651)
		(layer "B.Cu")
		(net "M_G_DQS_DN<2>")
	)
	(segment
		(start 53.96738 -22.098)
		(end 54.32298 -22.4536)
		(width 0.1651)
		(layer "B.Cu")
		(net "M_G_DQS_DN<2>")
	)
	(segment
		(start 54.969156 -20.4724)
		(end 55.096156 -20.4724)
		(width 0.14224)
		(layer "In2.Cu")
		(net "M_G_DQS_DN<2>")
	)
	(segment
		(start 53.770022 -37.310568)
		(end 53.315616 -36.856162)
		(width 0.14224)
		(layer "In2.Cu")
		(net "M_G_DQS_DN<2>")
	)
	(segment
		(start 71.816976 -56.876188)
		(end 71.816722 -56.876188)
		(width 0.0889)
		(layer "In2.Cu")
		(net "M_G_DQS_DN<2>")
	)
	(segment
		(start 54.791356 -20.9042)
		(end 54.791356 -20.6502)
		(width 0.14224)
		(layer "In2.Cu")
		(net "M_G_DQS_DN<2>")
	)
	(segment
		(start 54.153816 -35.47364)
		(end 54.153816 -34.839656)
		(width 0.14224)
		(layer "In2.Cu")
		(net "M_G_DQS_DN<2>")
	)
	(segment
		(start 54.744112 -19.278854)
		(end 54.896766 -19.1262)
		(width 0.14224)
		(layer "In2.Cu")
		(net "M_G_DQS_DN<2>")
	)
	(segment
		(start 53.932328 -37.310568)
		(end 53.770022 -37.310568)
		(width 0.14224)
		(layer "In2.Cu")
		(net "M_G_DQS_DN<2>")
	)
	(segment
		(start 71.47052 -56.676036)
		(end 71.470012 -56.676036)
		(width 0.0889)
		(layer "In2.Cu")
		(net "M_G_DQS_DN<2>")
	)
	(segment
		(start 55.0164 -22.22881)
		(end 55.279036 -21.966174)
		(width 0.14224)
		(layer "In2.Cu")
		(net "M_G_DQS_DN<2>")
	)
	(segment
		(start 53.693822 -35.695128)
		(end 53.932328 -35.695128)
		(width 0.14224)
		(layer "In2.Cu")
		(net "M_G_DQS_DN<2>")
	)
	(segment
		(start 54.153816 -32.1056)
		(end 53.591968 -31.543752)
		(width 0.14224)
		(layer "In2.Cu")
		(net "M_G_DQS_DN<2>")
	)
	(segment
		(start 55.099712 -21.082)
		(end 54.969156 -21.082)
		(width 0.14224)
		(layer "In2.Cu")
		(net "M_G_DQS_DN<2>")
	)
	(segment
		(start 53.391816 -34.215578)
		(end 53.391816 -33.610296)
		(width 0.14224)
		(layer "In2.Cu")
		(net "M_G_DQS_DN<2>")
	)
	(segment
		(start 53.932328 -34.618168)
		(end 53.794406 -34.618168)
		(width 0.14224)
		(layer "In2.Cu")
		(net "M_G_DQS_DN<2>")
	)
	(segment
		(start 55.279036 -20.28952)
		(end 55.279036 -19.940778)
		(width 0.14224)
		(layer "In2.Cu")
		(net "M_G_DQS_DN<2>")
	)
	(segment
		(start 54.737508 -22.228556)
		(end 54.737508 -22.22881)
		(width 0.14224)
		(layer "In2.Cu")
		(net "M_G_DQS_DN<2>")
	)
	(segment
		(start 54.744112 -19.583146)
		(end 54.744112 -19.278854)
		(width 0.14224)
		(layer "In2.Cu")
		(net "M_G_DQS_DN<2>")
	)
	(segment
		(start 72.89419 -56.25465)
		(end 72.870314 -56.344058)
		(width 0.0889)
		(layer "In2.Cu")
		(net "M_G_DQS_DN<2>")
	)
	(segment
		(start 53.315616 -36.073334)
		(end 53.693822 -35.695128)
		(width 0.14224)
		(layer "In2.Cu")
		(net "M_G_DQS_DN<2>")
	)
	(segment
		(start 55.279036 -18.946622)
		(end 55.279036 -18.280888)
		(width 0.14224)
		(layer "In2.Cu")
		(net "M_G_DQS_DN<2>")
	)
	(segment
		(start 53.591968 -30.762448)
		(end 54.153816 -30.2006)
		(width 0.14224)
		(layer "In2.Cu")
		(net "M_G_DQS_DN<2>")
	)
	(segment
		(start 53.315616 -36.856162)
		(end 53.315616 -36.073334)
		(width 0.14224)
		(layer "In2.Cu")
		(net "M_G_DQS_DN<2>")
	)
	(segment
		(start 54.153816 -32.848296)
		(end 54.153816 -32.1056)
		(width 0.14224)
		(layer "In2.Cu")
		(net "M_G_DQS_DN<2>")
	)
	(segment
		(start 55.096156 -20.4724)
		(end 55.279036 -20.28952)
		(width 0.14224)
		(layer "In2.Cu")
		(net "M_G_DQS_DN<2>")
	)
	(segment
		(start 53.591968 -31.543752)
		(end 53.591968 -30.762448)
		(width 0.14224)
		(layer "In2.Cu")
		(net "M_G_DQS_DN<2>")
	)
	(segment
		(start 54.737508 -22.22881)
		(end 55.0164 -22.22881)
		(width 0.14224)
		(layer "In2.Cu")
		(net "M_G_DQS_DN<2>")
	)
	(segment
		(start 67.488562 -55.433214)
		(end 67.449192 -55.472584)
		(width 0.0889)
		(layer "In2.Cu")
		(net "M_G_DQS_DN<2>")
	)
	(segment
		(start 55.279036 -21.261324)
		(end 55.099712 -21.082)
		(width 0.14224)
		(layer "In2.Cu")
		(net "M_G_DQS_DN<2>")
	)
	(segment
		(start 53.794406 -34.618168)
		(end 53.391816 -34.215578)
		(width 0.14224)
		(layer "In2.Cu")
		(net "M_G_DQS_DN<2>")
	)
	(segment
		(start 54.299612 -24.226266)
		(end 54.299612 -22.666452)
		(width 0.14224)
		(layer "In2.Cu")
		(net "M_G_DQS_DN<2>")
	)
	(segment
		(start 67.449192 -55.472584)
		(end 67.427094 -55.472584)
		(width 0.0889)
		(layer "In2.Cu")
		(net "M_G_DQS_DN<2>")
	)
	(segment
		(start 55.099458 -19.1262)
		(end 55.279036 -18.946622)
		(width 0.14224)
		(layer "In2.Cu")
		(net "M_G_DQS_DN<2>")
	)
	(segment
		(start 53.958744 -29.017976)
		(end 53.958744 -24.567134)
		(width 0.14224)
		(layer "In2.Cu")
		(net "M_G_DQS_DN<2>")
	)
	(segment
		(start 53.958744 -24.567134)
		(end 54.299612 -24.226266)
		(width 0.14224)
		(layer "In2.Cu")
		(net "M_G_DQS_DN<2>")
	)
	(segment
		(start 54.153816 -37.532056)
		(end 53.932328 -37.310568)
		(width 0.14224)
		(layer "In2.Cu")
		(net "M_G_DQS_DN<2>")
	)
	(segment
		(start 53.932328 -35.695128)
		(end 54.153816 -35.47364)
		(width 0.14224)
		(layer "In2.Cu")
		(net "M_G_DQS_DN<2>")
	)
	(segment
		(start 55.279036 -19.940778)
		(end 55.074058 -19.7358)
		(width 0.14224)
		(layer "In2.Cu")
		(net "M_G_DQS_DN<2>")
	)
	(segment
		(start 55.279036 -21.966174)
		(end 55.279036 -21.261324)
		(width 0.14224)
		(layer "In2.Cu")
		(net "M_G_DQS_DN<2>")
	)
	(segment
		(start 55.279036 -18.280888)
		(end 55.019194 -18.021046)
		(width 0.14224)
		(layer "In2.Cu")
		(net "M_G_DQS_DN<2>")
	)
	(segment
		(start 67.427094 -55.472584)
		(end 66.807588 -55.472584)
		(width 0.14224)
		(layer "In2.Cu")
		(net "M_G_DQS_DN<2>")
	)
	(segment
		(start 54.153816 -42.818812)
		(end 54.153816 -37.532056)
		(width 0.14224)
		(layer "In2.Cu")
		(net "M_G_DQS_DN<2>")
	)
	(segment
		(start 54.153816 -34.839656)
		(end 53.932328 -34.618168)
		(width 0.14224)
		(layer "In2.Cu")
		(net "M_G_DQS_DN<2>")
	)
	(segment
		(start 70.612 -57.17159)
		(end 70.611238 -57.17159)
		(width 0.0889)
		(layer "In2.Cu")
		(net "M_G_DQS_DN<2>")
	)
	(segment
		(start 72.346566 -57.17159)
		(end 72.311006 -57.17159)
		(width 0.0889)
		(layer "In2.Cu")
		(net "M_G_DQS_DN<2>")
	)
	(segment
		(start 54.299612 -22.666452)
		(end 54.737508 -22.228556)
		(width 0.14224)
		(layer "In2.Cu")
		(net "M_G_DQS_DN<2>")
	)
	(segment
		(start 69.764402 -56.676036)
		(end 69.23532 -56.676036)
		(width 0.0889)
		(layer "In2.Cu")
		(net "M_G_DQS_DN<2>")
	)
	(segment
		(start 54.969156 -21.082)
		(end 54.791356 -20.9042)
		(width 0.14224)
		(layer "In2.Cu")
		(net "M_G_DQS_DN<2>")
	)
	(segment
		(start 54.153816 -29.213048)
		(end 53.958744 -29.017976)
		(width 0.14224)
		(layer "In2.Cu")
		(net "M_G_DQS_DN<2>")
	)
	(segment
		(start 73.187306 -56.085486)
		(end 72.89419 -56.25465)
		(width 0.0889)
		(layer "In2.Cu")
		(net "M_G_DQS_DN<2>")
	)
	(segment
		(start 54.791356 -20.6502)
		(end 54.969156 -20.4724)
		(width 0.14224)
		(layer "In2.Cu")
		(net "M_G_DQS_DN<2>")
	)
	(segment
		(start 66.807588 -55.472584)
		(end 54.153816 -42.818812)
		(width 0.14224)
		(layer "In2.Cu")
		(net "M_G_DQS_DN<2>")
	)
	(segment
		(start 54.896766 -19.7358)
		(end 54.744112 -19.583146)
		(width 0.14224)
		(layer "In2.Cu")
		(net "M_G_DQS_DN<2>")
	)
	(segment
		(start 69.23532 -56.676036)
		(end 67.992498 -55.433214)
		(width 0.0889)
		(layer "In2.Cu")
		(net "M_G_DQS_DN<2>")
	)
	(segment
		(start 67.992498 -55.433214)
		(end 67.488562 -55.433214)
		(width 0.0889)
		(layer "In2.Cu")
		(net "M_G_DQS_DN<2>")
	)
	(segment
		(start 55.074058 -19.7358)
		(end 54.896766 -19.7358)
		(width 0.14224)
		(layer "In2.Cu")
		(net "M_G_DQS_DN<2>")
	)
	(segment
		(start 54.153816 -30.2006)
		(end 54.153816 -29.213048)
		(width 0.14224)
		(layer "In2.Cu")
		(net "M_G_DQS_DN<2>")
	)
	(segment
		(start 53.391816 -33.610296)
		(end 54.153816 -32.848296)
		(width 0.14224)
		(layer "In2.Cu")
		(net "M_G_DQS_DN<2>")
	)
	(segment
		(start 54.896766 -19.1262)
		(end 55.099458 -19.1262)
		(width 0.14224)
		(layer "In2.Cu")
		(net "M_G_DQS_DN<2>")
	)
	(segment
		(start 55.019194 -18.021046)
		(end 54.737508 -18.021046)
		(width 0.14224)
		(layer "In2.Cu")
		(net "M_G_DQS_DN<2>")
	)
	(arc
		(start 71.816722 -56.876188)
		(mid 71.670429 -56.729783)
		(end 71.47052 -56.676036)
		(width 0.0889)
		(layer "In2.Cu")
		(net "M_G_DQS_DN<2>")
	)
	(arc
		(start 70.611238 -57.17159)
		(mid 70.315975 -57.092439)
		(end 70.099936 -56.876188)
		(width 0.0889)
		(layer "In2.Cu")
		(net "M_G_DQS_DN<2>")
	)
	(arc
		(start 72.311006 -57.17159)
		(mid 72.025582 -57.088123)
		(end 71.816976 -56.876188)
		(width 0.0889)
		(layer "In2.Cu")
		(net "M_G_DQS_DN<2>")
	)
	(arc
		(start 71.470012 -56.676036)
		(mid 71.269971 -56.729681)
		(end 71.123556 -56.876188)
		(width 0.0889)
		(layer "In2.Cu")
		(net "M_G_DQS_DN<2>")
	)
	(arc
		(start 72.870314 -56.344058)
		(mid 72.828335 -56.897018)
		(end 72.346566 -57.17159)
		(width 0.0889)
		(layer "In2.Cu")
		(net "M_G_DQS_DN<2>")
	)
	(arc
		(start 71.123556 -56.876188)
		(mid 70.907372 -57.092467)
		(end 70.612 -57.17159)
		(width 0.0889)
		(layer "In2.Cu")
		(net "M_G_DQS_DN<2>")
	)
	(arc
		(start 70.099936 -56.876188)
		(mid 69.958253 -56.732384)
		(end 69.764402 -56.676036)
		(width 0.0889)
		(layer "In2.Cu")
		(net "M_G_DQS_DN<2>")
	)
	(segment
		(start 52.455064 -33.4772)
		(end 52.455064 -37.221922)
		(width 0.1651)
		(layer "F.Cu")
		(net "M_G_DQS_DN<1>")
	)
	(segment
		(start 53.612542 -43.3705)
		(end 54.1655 -43.3705)
		(width 0.1651)
		(layer "F.Cu")
		(net "M_G_DQS_DN<1>")
	)
	(segment
		(start 44.999402 -20.023582)
		(end 44.999402 -18.94967)
		(width 0.1651)
		(layer "F.Cu")
		(net "M_G_DQS_DN<1>")
	)
	(segment
		(start 68.594986 -56.679338)
		(end 69.22897 -56.679338)
		(width 0.0889)
		(layer "F.Cu")
		(net "M_G_DQS_DN<1>")
	)
	(segment
		(start 44.999402 -18.94967)
		(end 44.600368 -18.550636)
		(width 0.1651)
		(layer "F.Cu")
		(net "M_G_DQS_DN<1>")
	)
	(segment
		(start 53.612542 -42.037)
		(end 53.3146 -42.334942)
		(width 0.1651)
		(layer "F.Cu")
		(net "M_G_DQS_DN<1>")
	)
	(segment
		(start 55.049674 -41.91)
		(end 54.922674 -42.037)
		(width 0.1651)
		(layer "F.Cu")
		(net "M_G_DQS_DN<1>")
	)
	(segment
		(start 53.671216 -41.3385)
		(end 54.922674 -41.3385)
		(width 0.1651)
		(layer "F.Cu")
		(net "M_G_DQS_DN<1>")
	)
	(segment
		(start 44.931584 -22.684486)
		(end 44.931584 -25.190958)
		(width 0.1651)
		(layer "F.Cu")
		(net "M_G_DQS_DN<1>")
	)
	(segment
		(start 54.922674 -42.037)
		(end 53.612542 -42.037)
		(width 0.1651)
		(layer "F.Cu")
		(net "M_G_DQS_DN<1>")
	)
	(segment
		(start 44.600368 -18.152872)
		(end 44.94784 -17.8054)
		(width 0.1651)
		(layer "F.Cu")
		(net "M_G_DQS_DN<1>")
	)
	(segment
		(start 65.221612 -56.150764)
		(end 66.838576 -56.150764)
		(width 0.1651)
		(layer "F.Cu")
		(net "M_G_DQS_DN<1>")
	)
	(segment
		(start 53.373274 -38.140132)
		(end 53.373274 -41.040558)
		(width 0.1651)
		(layer "F.Cu")
		(net "M_G_DQS_DN<1>")
	)
	(segment
		(start 66.883026 -56.106314)
		(end 67.344798 -56.106314)
		(width 0.0889)
		(layer "F.Cu")
		(net "M_G_DQS_DN<1>")
	)
	(segment
		(start 50.7365 -31.758636)
		(end 52.455064 -33.4772)
		(width 0.1651)
		(layer "F.Cu")
		(net "M_G_DQS_DN<1>")
	)
	(segment
		(start 54.2925 -45.221652)
		(end 65.221612 -56.150764)
		(width 0.1651)
		(layer "F.Cu")
		(net "M_G_DQS_DN<1>")
	)
	(segment
		(start 45.387514 -22.228556)
		(end 44.931584 -22.684486)
		(width 0.1651)
		(layer "F.Cu")
		(net "M_G_DQS_DN<1>")
	)
	(segment
		(start 50.7365 -29.762958)
		(end 50.7365 -31.758636)
		(width 0.1651)
		(layer "F.Cu")
		(net "M_G_DQS_DN<1>")
	)
	(segment
		(start 53.3146 -43.072558)
		(end 53.612542 -43.3705)
		(width 0.1651)
		(layer "F.Cu")
		(net "M_G_DQS_DN<1>")
	)
	(segment
		(start 45.171868 -17.8054)
		(end 45.387514 -18.021046)
		(width 0.1651)
		(layer "F.Cu")
		(net "M_G_DQS_DN<1>")
	)
	(segment
		(start 44.931584 -25.190958)
		(end 45.229526 -25.4889)
		(width 0.1651)
		(layer "F.Cu")
		(net "M_G_DQS_DN<1>")
	)
	(segment
		(start 67.344798 -56.106314)
		(end 67.419474 -56.18099)
		(width 0.0889)
		(layer "F.Cu")
		(net "M_G_DQS_DN<1>")
	)
	(segment
		(start 44.600368 -18.550636)
		(end 44.600368 -18.152872)
		(width 0.1651)
		(layer "F.Cu")
		(net "M_G_DQS_DN<1>")
	)
	(segment
		(start 55.049674 -41.4655)
		(end 55.049674 -41.91)
		(width 0.1651)
		(layer "F.Cu")
		(net "M_G_DQS_DN<1>")
	)
	(segment
		(start 66.838576 -56.150764)
		(end 66.883026 -56.106314)
		(width 0.0889)
		(layer "F.Cu")
		(net "M_G_DQS_DN<1>")
	)
	(segment
		(start 52.455064 -37.221922)
		(end 53.373274 -38.140132)
		(width 0.1651)
		(layer "F.Cu")
		(net "M_G_DQS_DN<1>")
	)
	(segment
		(start 45.229526 -25.4889)
		(end 46.462442 -25.4889)
		(width 0.1651)
		(layer "F.Cu")
		(net "M_G_DQS_DN<1>")
	)
	(segment
		(start 44.94784 -17.8054)
		(end 45.171868 -17.8054)
		(width 0.1651)
		(layer "F.Cu")
		(net "M_G_DQS_DN<1>")
	)
	(segment
		(start 54.1655 -43.3705)
		(end 54.2925 -43.4975)
		(width 0.1651)
		(layer "F.Cu")
		(net "M_G_DQS_DN<1>")
	)
	(segment
		(start 54.922674 -41.3385)
		(end 55.049674 -41.4655)
		(width 0.1651)
		(layer "F.Cu")
		(net "M_G_DQS_DN<1>")
	)
	(segment
		(start 46.462442 -25.4889)
		(end 50.7365 -29.762958)
		(width 0.1651)
		(layer "F.Cu")
		(net "M_G_DQS_DN<1>")
	)
	(segment
		(start 53.3146 -42.334942)
		(end 53.3146 -43.072558)
		(width 0.1651)
		(layer "F.Cu")
		(net "M_G_DQS_DN<1>")
	)
	(segment
		(start 53.373274 -41.040558)
		(end 53.671216 -41.3385)
		(width 0.1651)
		(layer "F.Cu")
		(net "M_G_DQS_DN<1>")
	)
	(segment
		(start 54.2925 -43.4975)
		(end 54.2925 -45.221652)
		(width 0.1651)
		(layer "F.Cu")
		(net "M_G_DQS_DN<1>")
	)
	(segment
		(start 67.419474 -56.18099)
		(end 67.766692 -56.18099)
		(width 0.0889)
		(layer "F.Cu")
		(net "M_G_DQS_DN<1>")
	)
	(via
		(at 45.387514 -18.021046)
		(size 0.508)
		(drill 0.254)
		(layers "F.Cu" "B.Cu")
		(net "M_G_DQS_DN<1>")
	)
	(via
		(at 45.387514 -22.228556)
		(size 0.508)
		(drill 0.254)
		(layers "F.Cu" "B.Cu")
		(net "M_G_DQS_DN<1>")
	)
	(arc
		(start 68.095876 -56.380888)
		(mid 68.306667 -56.594938)
		(end 68.594986 -56.679338)
		(width 0.0889)
		(layer "F.Cu")
		(net "M_G_DQS_DN<1>")
	)
	(arc
		(start 69.22897 -56.679338)
		(mid 69.357373 -56.653797)
		(end 69.466206 -56.58104)
		(width 0.0889)
		(layer "F.Cu")
		(net "M_G_DQS_DN<1>")
	)
	(arc
		(start 67.766692 -56.18099)
		(mid 67.956934 -56.238725)
		(end 68.095876 -56.380888)
		(width 0.0889)
		(layer "F.Cu")
		(net "M_G_DQS_DN<1>")
	)
	(segment
		(start 44.999402 -20.224242)
		(end 44.999402 -21.13153)
		(width 0.1651)
		(layer "B.Cu")
		(net "M_G_DQS_DN<1>")
	)
	(segment
		(start 44.972986 -22.4536)
		(end 45.16247 -22.4536)
		(width 0.1651)
		(layer "B.Cu")
		(net "M_G_DQS_DN<1>")
	)
	(segment
		(start 45.16247 -22.4536)
		(end 45.387514 -22.228556)
		(width 0.1651)
		(layer "B.Cu")
		(net "M_G_DQS_DN<1>")
	)
	(segment
		(start 44.617386 -22.098)
		(end 44.972986 -22.4536)
		(width 0.1651)
		(layer "B.Cu")
		(net "M_G_DQS_DN<1>")
	)
	(segment
		(start 44.617386 -21.767546)
		(end 44.617386 -22.098)
		(width 0.1651)
		(layer "B.Cu")
		(net "M_G_DQS_DN<1>")
	)
	(segment
		(start 44.871386 -21.259546)
		(end 44.871386 -21.513546)
		(width 0.1651)
		(layer "B.Cu")
		(net "M_G_DQS_DN<1>")
	)
	(segment
		(start 44.871386 -21.513546)
		(end 44.617386 -21.767546)
		(width 0.1651)
		(layer "B.Cu")
		(net "M_G_DQS_DN<1>")
	)
	(segment
		(start 44.999402 -21.13153)
		(end 44.871386 -21.259546)
		(width 0.1651)
		(layer "B.Cu")
		(net "M_G_DQS_DN<1>")
	)
	(segment
		(start 45.746162 -20.4724)
		(end 45.929042 -20.28952)
		(width 0.14224)
		(layer "In2.Cu")
		(net "M_G_DQS_DN<1>")
	)
	(segment
		(start 45.929042 -21.261324)
		(end 45.749718 -21.082)
		(width 0.14224)
		(layer "In2.Cu")
		(net "M_G_DQS_DN<1>")
	)
	(segment
		(start 45.546772 -19.1262)
		(end 45.749464 -19.1262)
		(width 0.14224)
		(layer "In2.Cu")
		(net "M_G_DQS_DN<1>")
	)
	(segment
		(start 45.749464 -19.1262)
		(end 45.929042 -18.946622)
		(width 0.14224)
		(layer "In2.Cu")
		(net "M_G_DQS_DN<1>")
	)
	(segment
		(start 45.619162 -21.082)
		(end 45.441362 -20.9042)
		(width 0.14224)
		(layer "In2.Cu")
		(net "M_G_DQS_DN<1>")
	)
	(segment
		(start 45.929042 -18.946622)
		(end 45.929042 -18.280888)
		(width 0.14224)
		(layer "In2.Cu")
		(net "M_G_DQS_DN<1>")
	)
	(segment
		(start 45.666406 -22.22881)
		(end 45.929042 -21.966174)
		(width 0.14224)
		(layer "In2.Cu")
		(net "M_G_DQS_DN<1>")
	)
	(segment
		(start 45.441362 -20.6502)
		(end 45.619162 -20.4724)
		(width 0.14224)
		(layer "In2.Cu")
		(net "M_G_DQS_DN<1>")
	)
	(segment
		(start 45.441362 -20.9042)
		(end 45.441362 -20.6502)
		(width 0.14224)
		(layer "In2.Cu")
		(net "M_G_DQS_DN<1>")
	)
	(segment
		(start 45.546772 -19.7358)
		(end 45.394118 -19.583146)
		(width 0.14224)
		(layer "In2.Cu")
		(net "M_G_DQS_DN<1>")
	)
	(segment
		(start 45.394118 -19.583146)
		(end 45.394118 -19.278854)
		(width 0.14224)
		(layer "In2.Cu")
		(net "M_G_DQS_DN<1>")
	)
	(segment
		(start 45.6692 -18.021046)
		(end 45.387514 -18.021046)
		(width 0.14224)
		(layer "In2.Cu")
		(net "M_G_DQS_DN<1>")
	)
	(segment
		(start 45.929042 -19.940778)
		(end 45.724064 -19.7358)
		(width 0.14224)
		(layer "In2.Cu")
		(net "M_G_DQS_DN<1>")
	)
	(segment
		(start 45.387514 -22.228556)
		(end 45.387514 -22.22881)
		(width 0.14224)
		(layer "In2.Cu")
		(net "M_G_DQS_DN<1>")
	)
	(segment
		(start 45.724064 -19.7358)
		(end 45.546772 -19.7358)
		(width 0.14224)
		(layer "In2.Cu")
		(net "M_G_DQS_DN<1>")
	)
	(segment
		(start 45.929042 -20.28952)
		(end 45.929042 -19.940778)
		(width 0.14224)
		(layer "In2.Cu")
		(net "M_G_DQS_DN<1>")
	)
	(segment
		(start 45.619162 -20.4724)
		(end 45.746162 -20.4724)
		(width 0.14224)
		(layer "In2.Cu")
		(net "M_G_DQS_DN<1>")
	)
	(segment
		(start 45.929042 -18.280888)
		(end 45.6692 -18.021046)
		(width 0.14224)
		(layer "In2.Cu")
		(net "M_G_DQS_DN<1>")
	)
	(segment
		(start 45.929042 -21.966174)
		(end 45.929042 -21.261324)
		(width 0.14224)
		(layer "In2.Cu")
		(net "M_G_DQS_DN<1>")
	)
	(segment
		(start 45.394118 -19.278854)
		(end 45.546772 -19.1262)
		(width 0.14224)
		(layer "In2.Cu")
		(net "M_G_DQS_DN<1>")
	)
	(segment
		(start 45.749718 -21.082)
		(end 45.619162 -21.082)
		(width 0.14224)
		(layer "In2.Cu")
		(net "M_G_DQS_DN<1>")
	)
	(segment
		(start 45.387514 -22.22881)
		(end 45.666406 -22.22881)
		(width 0.14224)
		(layer "In2.Cu")
		(net "M_G_DQS_DN<1>")
	)
	(segment
		(start 72.6313 -16.9164)
		(end 72.817228 -17.102328)
		(width 0.1651)
		(layer "F.Cu")
		(net "M_G_DQS_DN<17>")
	)
	(segment
		(start 72.56526 -17.60093)
		(end 72.35698 -17.60093)
		(width 0.1651)
		(layer "F.Cu")
		(net "M_G_DQS_DN<17>")
	)
	(segment
		(start 84.060792 -60.047886)
		(end 83.489292 -60.047886)
		(width 0.1016)
		(layer "F.Cu")
		(net "M_G_DQS_DN<17>")
	)
	(segment
		(start 72.16775 -17.4117)
		(end 72.1487 -17.4117)
		(width 0.1651)
		(layer "F.Cu")
		(net "M_G_DQS_DN<17>")
	)
	(segment
		(start 72.817228 -17.348962)
		(end 72.56526 -17.60093)
		(width 0.1651)
		(layer "F.Cu")
		(net "M_G_DQS_DN<17>")
	)
	(segment
		(start 72.817228 -17.102328)
		(end 72.817228 -17.348962)
		(width 0.1651)
		(layer "F.Cu")
		(net "M_G_DQS_DN<17>")
	)
	(segment
		(start 72.35698 -17.60093)
		(end 72.16775 -17.4117)
		(width 0.1651)
		(layer "F.Cu")
		(net "M_G_DQS_DN<17>")
	)
	(segment
		(start 72.6313 -16.495268)
		(end 72.6313 -16.9164)
		(width 0.1651)
		(layer "F.Cu")
		(net "M_G_DQS_DN<17>")
	)
	(segment
		(start 73.049384 -15.423642)
		(end 73.049384 -16.077184)
		(width 0.1651)
		(layer "F.Cu")
		(net "M_G_DQS_DN<17>")
	)
	(segment
		(start 73.049384 -16.077184)
		(end 72.6313 -16.495268)
		(width 0.1651)
		(layer "F.Cu")
		(net "M_G_DQS_DN<17>")
	)
	(via
		(at 72.142096 -22.8346)
		(size 0.508)
		(drill 0.254)
		(layers "F.Cu" "B.Cu")
		(net "M_G_DQS_DN<17>")
	)
	(via
		(at 83.489292 -60.047886)
		(size 0.508)
		(drill 0.254)
		(layers "F.Cu" "B.Cu")
		(net "M_G_DQS_DN<17>")
	)
	(via
		(at 72.1487 -17.4117)
		(size 0.508)
		(drill 0.254)
		(layers "F.Cu" "B.Cu")
		(net "M_G_DQS_DN<17>")
	)
	(segment
		(start 72.33666 -22.640036)
		(end 72.142096 -22.8346)
		(width 0.1651)
		(layer "B.Cu")
		(net "M_G_DQS_DN<17>")
	)
	(segment
		(start 73.049384 -24.824182)
		(end 73.049638 -24.823928)
		(width 0.1651)
		(layer "B.Cu")
		(net "M_G_DQS_DN<17>")
	)
	(segment
		(start 73.049638 -24.167592)
		(end 72.6059 -23.723854)
		(width 0.1651)
		(layer "B.Cu")
		(net "M_G_DQS_DN<17>")
	)
	(segment
		(start 72.7837 -22.86)
		(end 72.563736 -22.640036)
		(width 0.1651)
		(layer "B.Cu")
		(net "M_G_DQS_DN<17>")
	)
	(segment
		(start 72.7837 -23.1902)
		(end 72.7837 -22.86)
		(width 0.1651)
		(layer "B.Cu")
		(net "M_G_DQS_DN<17>")
	)
	(segment
		(start 73.049638 -24.823928)
		(end 73.049638 -24.167592)
		(width 0.1651)
		(layer "B.Cu")
		(net "M_G_DQS_DN<17>")
	)
	(segment
		(start 72.563736 -22.640036)
		(end 72.33666 -22.640036)
		(width 0.1651)
		(layer "B.Cu")
		(net "M_G_DQS_DN<17>")
	)
	(segment
		(start 72.6059 -23.368)
		(end 72.7837 -23.1902)
		(width 0.1651)
		(layer "B.Cu")
		(net "M_G_DQS_DN<17>")
	)
	(segment
		(start 72.6059 -23.723854)
		(end 72.6059 -23.368)
		(width 0.1651)
		(layer "B.Cu")
		(net "M_G_DQS_DN<17>")
	)
	(segment
		(start 73.269856 -30.200854)
		(end 73.269856 -30.454854)
		(width 0.14224)
		(layer "In2.Cu")
		(net "M_G_DQS_DN<17>")
	)
	(segment
		(start 73.142856 -32.614616)
		(end 73.244456 -32.716216)
		(width 0.14224)
		(layer "In2.Cu")
		(net "M_G_DQS_DN<17>")
	)
	(segment
		(start 74.696066 -41.568624)
		(end 75.024996 -41.897554)
		(width 0.14224)
		(layer "In2.Cu")
		(net "M_G_DQS_DN<17>")
	)
	(segment
		(start 81.432146 -57.855104)
		(end 81.425542 -57.866788)
		(width 0.0889)
		(layer "In2.Cu")
		(net "M_G_DQS_DN<17>")
	)
	(segment
		(start 78.22946 -45.245528)
		(end 78.558136 -45.574204)
		(width 0.14224)
		(layer "In2.Cu")
		(net "M_G_DQS_DN<17>")
	)
	(segment
		(start 73.269856 -29.692854)
		(end 73.142856 -29.819854)
		(width 0.14224)
		(layer "In2.Cu")
		(net "M_G_DQS_DN<17>")
	)
	(segment
		(start 79.831692 -46.84776)
		(end 80.160368 -47.176436)
		(width 0.14224)
		(layer "In2.Cu")
		(net "M_G_DQS_DN<17>")
	)
	(segment
		(start 79.502762 -46.37532)
		(end 79.831692 -46.70425)
		(width 0.14224)
		(layer "In2.Cu")
		(net "M_G_DQS_DN<17>")
	)
	(segment
		(start 77.428344 -44.300902)
		(end 77.428344 -44.444412)
		(width 0.14224)
		(layer "In2.Cu")
		(net "M_G_DQS_DN<17>")
	)
	(segment
		(start 74.209656 -35.160966)
		(end 73.83145 -35.539172)
		(width 0.14224)
		(layer "In2.Cu")
		(net "M_G_DQS_DN<17>")
	)
	(segment
		(start 72.909684 -28.824682)
		(end 73.142856 -29.057854)
		(width 0.14224)
		(layer "In2.Cu")
		(net "M_G_DQS_DN<17>")
	)
	(segment
		(start 72.593708 -17.60728)
		(end 72.93102 -17.944592)
		(width 0.14224)
		(layer "In2.Cu")
		(net "M_G_DQS_DN<17>")
	)
	(segment
		(start 80.160368 -47.9806)
		(end 80.160368 -48.002698)
		(width 0.0889)
		(layer "In2.Cu")
		(net "M_G_DQS_DN<17>")
	)
	(segment
		(start 73.142856 -30.073854)
		(end 73.269856 -30.200854)
		(width 0.14224)
		(layer "In2.Cu")
		(net "M_G_DQS_DN<17>")
	)
	(segment
		(start 79.359252 -46.37532)
		(end 79.502762 -46.37532)
		(width 0.14224)
		(layer "In2.Cu")
		(net "M_G_DQS_DN<17>")
	)
	(segment
		(start 73.142856 -29.819854)
		(end 73.142856 -30.073854)
		(width 0.14224)
		(layer "In2.Cu")
		(net "M_G_DQS_DN<17>")
	)
	(segment
		(start 73.495408 -40.511476)
		(end 74.552556 -41.568624)
		(width 0.14224)
		(layer "In2.Cu")
		(net "M_G_DQS_DN<17>")
	)
	(segment
		(start 75.024996 -42.041064)
		(end 75.353672 -42.36974)
		(width 0.14224)
		(layer "In2.Cu")
		(net "M_G_DQS_DN<17>")
	)
	(segment
		(start 73.597008 -39.175436)
		(end 73.597008 -39.640256)
		(width 0.14224)
		(layer "In2.Cu")
		(net "M_G_DQS_DN<17>")
	)
	(segment
		(start 74.209656 -34.341816)
		(end 74.209656 -35.160966)
		(width 0.14224)
		(layer "In2.Cu")
		(net "M_G_DQS_DN<17>")
	)
	(segment
		(start 73.83145 -35.539172)
		(end 73.364344 -35.539172)
		(width 0.14224)
		(layer "In2.Cu")
		(net "M_G_DQS_DN<17>")
	)
	(segment
		(start 73.597008 -39.640256)
		(end 73.495408 -39.741856)
		(width 0.14224)
		(layer "In2.Cu")
		(net "M_G_DQS_DN<17>")
	)
	(segment
		(start 72.93102 -17.944592)
		(end 72.93102 -22.045676)
		(width 0.14224)
		(layer "In2.Cu")
		(net "M_G_DQS_DN<17>")
	)
	(segment
		(start 73.244456 -33.181036)
		(end 73.142856 -33.282636)
		(width 0.14224)
		(layer "In2.Cu")
		(net "M_G_DQS_DN<17>")
	)
	(segment
		(start 73.073768 -36.325556)
		(end 73.364344 -36.616132)
		(width 0.14224)
		(layer "In2.Cu")
		(net "M_G_DQS_DN<17>")
	)
	(segment
		(start 73.067164 -26.379424)
		(end 72.909684 -26.536904)
		(width 0.14224)
		(layer "In2.Cu")
		(net "M_G_DQS_DN<17>")
	)
	(segment
		(start 73.142856 -30.581854)
		(end 73.142856 -30.835854)
		(width 0.14224)
		(layer "In2.Cu")
		(net "M_G_DQS_DN<17>")
	)
	(segment
		(start 73.846944 -33.979104)
		(end 74.209656 -34.341816)
		(width 0.14224)
		(layer "In2.Cu")
		(net "M_G_DQS_DN<17>")
	)
	(segment
		(start 73.83145 -38.231572)
		(end 73.661524 -38.231572)
		(width 0.14224)
		(layer "In2.Cu")
		(net "M_G_DQS_DN<17>")
	)
	(segment
		(start 72.1487 -17.4117)
		(end 72.34428 -17.60728)
		(width 0.14224)
		(layer "In2.Cu")
		(net "M_G_DQS_DN<17>")
	)
	(segment
		(start 74.209656 -36.994338)
		(end 74.209656 -37.853366)
		(width 0.14224)
		(layer "In2.Cu")
		(net "M_G_DQS_DN<17>")
	)
	(segment
		(start 73.269856 -30.454854)
		(end 73.142856 -30.581854)
		(width 0.14224)
		(layer "In2.Cu")
		(net "M_G_DQS_DN<17>")
	)
	(segment
		(start 82.07248 -51.462432)
		(end 82.07248 -52.27066)
		(width 0.0889)
		(layer "In2.Cu")
		(net "M_G_DQS_DN<17>")
	)
	(segment
		(start 73.374504 -33.979104)
		(end 73.846944 -33.979104)
		(width 0.14224)
		(layer "In2.Cu")
		(net "M_G_DQS_DN<17>")
	)
	(segment
		(start 80.160368 -47.176436)
		(end 80.160368 -47.9806)
		(width 0.14224)
		(layer "In2.Cu")
		(net "M_G_DQS_DN<17>")
	)
	(segment
		(start 71.94042 -24.13)
		(end 71.94042 -24.787352)
		(width 0.14224)
		(layer "In2.Cu")
		(net "M_G_DQS_DN<17>")
	)
	(segment
		(start 72.5805 -23.876)
		(end 72.4535 -24.003)
		(width 0.14224)
		(layer "In2.Cu")
		(net "M_G_DQS_DN<17>")
	)
	(segment
		(start 75.826112 -42.69867)
		(end 75.826112 -42.84218)
		(width 0.14224)
		(layer "In2.Cu")
		(net "M_G_DQS_DN<17>")
	)
	(segment
		(start 76.154788 -43.170856)
		(end 76.298298 -43.170856)
		(width 0.14224)
		(layer "In2.Cu")
		(net "M_G_DQS_DN<17>")
	)
	(segment
		(start 79.831692 -46.70425)
		(end 79.831692 -46.84776)
		(width 0.14224)
		(layer "In2.Cu")
		(net "M_G_DQS_DN<17>")
	)
	(segment
		(start 82.07248 -52.27066)
		(end 81.457292 -52.885848)
		(width 0.0889)
		(layer "In2.Cu")
		(net "M_G_DQS_DN<17>")
	)
	(segment
		(start 72.5805 -23.273004)
		(end 72.5805 -23.876)
		(width 0.14224)
		(layer "In2.Cu")
		(net "M_G_DQS_DN<17>")
	)
	(segment
		(start 79.030576 -45.903134)
		(end 79.030576 -46.046644)
		(width 0.14224)
		(layer "In2.Cu")
		(net "M_G_DQS_DN<17>")
	)
	(segment
		(start 72.4535 -24.003)
		(end 72.06742 -24.003)
		(width 0.14224)
		(layer "In2.Cu")
		(net "M_G_DQS_DN<17>")
	)
	(segment
		(start 72.909684 -25.756616)
		(end 72.909684 -25.967944)
		(width 0.14224)
		(layer "In2.Cu")
		(net "M_G_DQS_DN<17>")
	)
	(segment
		(start 73.269856 -29.438854)
		(end 73.269856 -29.692854)
		(width 0.14224)
		(layer "In2.Cu")
		(net "M_G_DQS_DN<17>")
	)
	(segment
		(start 81.457292 -55.1942)
		(end 81.508854 -55.245762)
		(width 0.0889)
		(layer "In2.Cu")
		(net "M_G_DQS_DN<17>")
	)
	(segment
		(start 71.94042 -24.787352)
		(end 72.909684 -25.756616)
		(width 0.14224)
		(layer "In2.Cu")
		(net "M_G_DQS_DN<17>")
	)
	(segment
		(start 81.508854 -55.738522)
		(end 81.4197 -55.89524)
		(width 0.0889)
		(layer "In2.Cu")
		(net "M_G_DQS_DN<17>")
	)
	(segment
		(start 72.93102 -22.045676)
		(end 72.142096 -22.8346)
		(width 0.14224)
		(layer "In2.Cu")
		(net "M_G_DQS_DN<17>")
	)
	(segment
		(start 78.558136 -45.574204)
		(end 78.701646 -45.574204)
		(width 0.14224)
		(layer "In2.Cu")
		(net "M_G_DQS_DN<17>")
	)
	(segment
		(start 81.425542 -56.876188)
		(end 81.4197 -56.88584)
		(width 0.0889)
		(layer "In2.Cu")
		(net "M_G_DQS_DN<17>")
	)
	(segment
		(start 75.024996 -41.897554)
		(end 75.024996 -42.041064)
		(width 0.14224)
		(layer "In2.Cu")
		(net "M_G_DQS_DN<17>")
	)
	(segment
		(start 73.364344 -35.539172)
		(end 73.073768 -35.829748)
		(width 0.14224)
		(layer "In2.Cu")
		(net "M_G_DQS_DN<17>")
	)
	(segment
		(start 73.067164 -26.125424)
		(end 73.067164 -26.379424)
		(width 0.14224)
		(layer "In2.Cu")
		(net "M_G_DQS_DN<17>")
	)
	(segment
		(start 72.909684 -26.536904)
		(end 72.909684 -28.824682)
		(width 0.14224)
		(layer "In2.Cu")
		(net "M_G_DQS_DN<17>")
	)
	(segment
		(start 73.142856 -33.282636)
		(end 73.142856 -33.747456)
		(width 0.14224)
		(layer "In2.Cu")
		(net "M_G_DQS_DN<17>")
	)
	(segment
		(start 72.142096 -22.8346)
		(end 72.5805 -23.273004)
		(width 0.14224)
		(layer "In2.Cu")
		(net "M_G_DQS_DN<17>")
	)
	(segment
		(start 73.073768 -35.829748)
		(end 73.073768 -36.325556)
		(width 0.14224)
		(layer "In2.Cu")
		(net "M_G_DQS_DN<17>")
	)
	(segment
		(start 80.160368 -48.002698)
		(end 80.120998 -48.042068)
		(width 0.0889)
		(layer "In2.Cu")
		(net "M_G_DQS_DN<17>")
	)
	(segment
		(start 78.701646 -45.574204)
		(end 79.030576 -45.903134)
		(width 0.14224)
		(layer "In2.Cu")
		(net "M_G_DQS_DN<17>")
	)
	(segment
		(start 83.213956 -59.403742)
		(end 83.489292 -60.047886)
		(width 0.0889)
		(layer "In2.Cu")
		(net "M_G_DQS_DN<17>")
	)
	(segment
		(start 73.495408 -39.073836)
		(end 73.597008 -39.175436)
		(width 0.14224)
		(layer "In2.Cu")
		(net "M_G_DQS_DN<17>")
	)
	(segment
		(start 73.495408 -39.741856)
		(end 73.495408 -40.511476)
		(width 0.14224)
		(layer "In2.Cu")
		(net "M_G_DQS_DN<17>")
	)
	(segment
		(start 73.244456 -32.716216)
		(end 73.244456 -33.181036)
		(width 0.14224)
		(layer "In2.Cu")
		(net "M_G_DQS_DN<17>")
	)
	(segment
		(start 72.909684 -25.967944)
		(end 73.067164 -26.125424)
		(width 0.14224)
		(layer "In2.Cu")
		(net "M_G_DQS_DN<17>")
	)
	(segment
		(start 77.099414 -43.971972)
		(end 77.428344 -44.300902)
		(width 0.14224)
		(layer "In2.Cu")
		(net "M_G_DQS_DN<17>")
	)
	(segment
		(start 76.298298 -43.170856)
		(end 76.627228 -43.499786)
		(width 0.14224)
		(layer "In2.Cu")
		(net "M_G_DQS_DN<17>")
	)
	(segment
		(start 81.757774 -58.46699)
		(end 81.79435 -58.46699)
		(width 0.0889)
		(layer "In2.Cu")
		(net "M_G_DQS_DN<17>")
	)
	(segment
		(start 73.495408 -38.397688)
		(end 73.495408 -39.073836)
		(width 0.14224)
		(layer "In2.Cu")
		(net "M_G_DQS_DN<17>")
	)
	(segment
		(start 72.06742 -24.003)
		(end 71.94042 -24.13)
		(width 0.14224)
		(layer "In2.Cu")
		(net "M_G_DQS_DN<17>")
	)
	(segment
		(start 77.90053 -44.773088)
		(end 78.22946 -45.102018)
		(width 0.14224)
		(layer "In2.Cu")
		(net "M_G_DQS_DN<17>")
	)
	(segment
		(start 74.552556 -41.568624)
		(end 74.696066 -41.568624)
		(width 0.14224)
		(layer "In2.Cu")
		(net "M_G_DQS_DN<17>")
	)
	(segment
		(start 80.120998 -48.042068)
		(end 80.120998 -49.390554)
		(width 0.0889)
		(layer "In2.Cu")
		(net "M_G_DQS_DN<17>")
	)
	(segment
		(start 73.364344 -36.616132)
		(end 73.83145 -36.616132)
		(width 0.14224)
		(layer "In2.Cu")
		(net "M_G_DQS_DN<17>")
	)
	(segment
		(start 75.826112 -42.84218)
		(end 76.154788 -43.170856)
		(width 0.14224)
		(layer "In2.Cu")
		(net "M_G_DQS_DN<17>")
	)
	(segment
		(start 81.508854 -55.245762)
		(end 81.508854 -55.738522)
		(width 0.0889)
		(layer "In2.Cu")
		(net "M_G_DQS_DN<17>")
	)
	(segment
		(start 73.142856 -29.311854)
		(end 73.269856 -29.438854)
		(width 0.14224)
		(layer "In2.Cu")
		(net "M_G_DQS_DN<17>")
	)
	(segment
		(start 73.142856 -31.343854)
		(end 73.142856 -32.614616)
		(width 0.14224)
		(layer "In2.Cu")
		(net "M_G_DQS_DN<17>")
	)
	(segment
		(start 76.627228 -43.643296)
		(end 76.955904 -43.971972)
		(width 0.14224)
		(layer "In2.Cu")
		(net "M_G_DQS_DN<17>")
	)
	(segment
		(start 81.906364 -51.17592)
		(end 82.07248 -51.462432)
		(width 0.0889)
		(layer "In2.Cu")
		(net "M_G_DQS_DN<17>")
	)
	(segment
		(start 72.34428 -17.60728)
		(end 72.593708 -17.60728)
		(width 0.14224)
		(layer "In2.Cu")
		(net "M_G_DQS_DN<17>")
	)
	(segment
		(start 82.620358 -58.96229)
		(end 82.64906 -58.96229)
		(width 0.0889)
		(layer "In2.Cu")
		(net "M_G_DQS_DN<17>")
	)
	(segment
		(start 73.269856 -30.962854)
		(end 73.269856 -31.216854)
		(width 0.14224)
		(layer "In2.Cu")
		(net "M_G_DQS_DN<17>")
	)
	(segment
		(start 75.497182 -42.36974)
		(end 75.826112 -42.69867)
		(width 0.14224)
		(layer "In2.Cu")
		(net "M_G_DQS_DN<17>")
	)
	(segment
		(start 77.428344 -44.444412)
		(end 77.75702 -44.773088)
		(width 0.14224)
		(layer "In2.Cu")
		(net "M_G_DQS_DN<17>")
	)
	(segment
		(start 81.432146 -56.864504)
		(end 81.425542 -56.876188)
		(width 0.0889)
		(layer "In2.Cu")
		(net "M_G_DQS_DN<17>")
	)
	(segment
		(start 73.142856 -33.747456)
		(end 73.374504 -33.979104)
		(width 0.14224)
		(layer "In2.Cu")
		(net "M_G_DQS_DN<17>")
	)
	(segment
		(start 81.457292 -52.885848)
		(end 81.457292 -55.1942)
		(width 0.0889)
		(layer "In2.Cu")
		(net "M_G_DQS_DN<17>")
	)
	(segment
		(start 79.030576 -46.046644)
		(end 79.359252 -46.37532)
		(width 0.14224)
		(layer "In2.Cu")
		(net "M_G_DQS_DN<17>")
	)
	(segment
		(start 76.627228 -43.499786)
		(end 76.627228 -43.643296)
		(width 0.14224)
		(layer "In2.Cu")
		(net "M_G_DQS_DN<17>")
	)
	(segment
		(start 77.75702 -44.773088)
		(end 77.90053 -44.773088)
		(width 0.14224)
		(layer "In2.Cu")
		(net "M_G_DQS_DN<17>")
	)
	(segment
		(start 75.353672 -42.36974)
		(end 75.497182 -42.36974)
		(width 0.14224)
		(layer "In2.Cu")
		(net "M_G_DQS_DN<17>")
	)
	(segment
		(start 73.83145 -36.616132)
		(end 74.209656 -36.994338)
		(width 0.14224)
		(layer "In2.Cu")
		(net "M_G_DQS_DN<17>")
	)
	(segment
		(start 78.22946 -45.102018)
		(end 78.22946 -45.245528)
		(width 0.14224)
		(layer "In2.Cu")
		(net "M_G_DQS_DN<17>")
	)
	(segment
		(start 73.661524 -38.231572)
		(end 73.495408 -38.397688)
		(width 0.14224)
		(layer "In2.Cu")
		(net "M_G_DQS_DN<17>")
	)
	(segment
		(start 73.142856 -29.057854)
		(end 73.142856 -29.311854)
		(width 0.14224)
		(layer "In2.Cu")
		(net "M_G_DQS_DN<17>")
	)
	(segment
		(start 74.209656 -37.853366)
		(end 73.83145 -38.231572)
		(width 0.14224)
		(layer "In2.Cu")
		(net "M_G_DQS_DN<17>")
	)
	(segment
		(start 73.142856 -30.835854)
		(end 73.269856 -30.962854)
		(width 0.14224)
		(layer "In2.Cu")
		(net "M_G_DQS_DN<17>")
	)
	(segment
		(start 76.955904 -43.971972)
		(end 77.099414 -43.971972)
		(width 0.14224)
		(layer "In2.Cu")
		(net "M_G_DQS_DN<17>")
	)
	(segment
		(start 73.269856 -31.216854)
		(end 73.142856 -31.343854)
		(width 0.14224)
		(layer "In2.Cu")
		(net "M_G_DQS_DN<17>")
	)
	(segment
		(start 80.120998 -49.390554)
		(end 81.906364 -51.17592)
		(width 0.0889)
		(layer "In2.Cu")
		(net "M_G_DQS_DN<17>")
	)
	(arc
		(start 81.425542 -56.285638)
		(mid 81.504634 -56.574218)
		(end 81.432146 -56.864504)
		(width 0.0889)
		(layer "In2.Cu")
		(net "M_G_DQS_DN<17>")
	)
	(arc
		(start 81.4197 -55.89524)
		(mid 81.371809 -56.091203)
		(end 81.425542 -56.285638)
		(width 0.0889)
		(layer "In2.Cu")
		(net "M_G_DQS_DN<17>")
	)
	(arc
		(start 81.79435 -58.46699)
		(mid 82.077254 -58.551409)
		(end 82.284062 -58.762138)
		(width 0.0889)
		(layer "In2.Cu")
		(net "M_G_DQS_DN<17>")
	)
	(arc
		(start 81.425542 -57.276238)
		(mid 81.504634 -57.564818)
		(end 81.432146 -57.855104)
		(width 0.0889)
		(layer "In2.Cu")
		(net "M_G_DQS_DN<17>")
	)
	(arc
		(start 82.64906 -58.96229)
		(mid 82.934107 -59.045818)
		(end 83.142582 -59.257438)
		(width 0.0889)
		(layer "In2.Cu")
		(net "M_G_DQS_DN<17>")
	)
	(arc
		(start 81.4197 -56.88584)
		(mid 81.371809 -57.081803)
		(end 81.425542 -57.276238)
		(width 0.0889)
		(layer "In2.Cu")
		(net "M_G_DQS_DN<17>")
	)
	(arc
		(start 81.425542 -57.866788)
		(mid 81.421992 -58.260813)
		(end 81.757774 -58.46699)
		(width 0.0889)
		(layer "In2.Cu")
		(net "M_G_DQS_DN<17>")
	)
	(arc
		(start 83.142582 -59.257438)
		(mid 83.180825 -59.329343)
		(end 83.213956 -59.403742)
		(width 0.0889)
		(layer "In2.Cu")
		(net "M_G_DQS_DN<17>")
	)
	(arc
		(start 82.284062 -58.762138)
		(mid 82.426105 -58.90605)
		(end 82.620358 -58.96229)
		(width 0.0889)
		(layer "In2.Cu")
		(net "M_G_DQS_DN<17>")
	)
	(segment
		(start 146.307048 -17.60093)
		(end 146.117818 -17.4117)
		(width 0.1651)
		(layer "F.Cu")
		(net "M_G_DQS_DN<16>")
	)
	(segment
		(start 146.117818 -17.4117)
		(end 146.098768 -17.4117)
		(width 0.1651)
		(layer "F.Cu")
		(net "M_G_DQS_DN<16>")
	)
	(segment
		(start 146.999452 -15.423642)
		(end 146.999452 -16.077184)
		(width 0.1651)
		(layer "F.Cu")
		(net "M_G_DQS_DN<16>")
	)
	(segment
		(start 146.581368 -16.9164)
		(end 146.767296 -17.102328)
		(width 0.1651)
		(layer "F.Cu")
		(net "M_G_DQS_DN<16>")
	)
	(segment
		(start 122.504708 -55.409338)
		(end 121.933208 -55.409338)
		(width 0.1016)
		(layer "F.Cu")
		(net "M_G_DQS_DN<16>")
	)
	(segment
		(start 146.767296 -17.102328)
		(end 146.767296 -17.348962)
		(width 0.1651)
		(layer "F.Cu")
		(net "M_G_DQS_DN<16>")
	)
	(segment
		(start 146.515328 -17.60093)
		(end 146.307048 -17.60093)
		(width 0.1651)
		(layer "F.Cu")
		(net "M_G_DQS_DN<16>")
	)
	(segment
		(start 146.767296 -17.348962)
		(end 146.515328 -17.60093)
		(width 0.1651)
		(layer "F.Cu")
		(net "M_G_DQS_DN<16>")
	)
	(segment
		(start 146.999452 -16.077184)
		(end 146.581368 -16.495268)
		(width 0.1651)
		(layer "F.Cu")
		(net "M_G_DQS_DN<16>")
	)
	(segment
		(start 146.581368 -16.495268)
		(end 146.581368 -16.9164)
		(width 0.1651)
		(layer "F.Cu")
		(net "M_G_DQS_DN<16>")
	)
	(via
		(at 146.092164 -22.8346)
		(size 0.508)
		(drill 0.254)
		(layers "F.Cu" "B.Cu")
		(net "M_G_DQS_DN<16>")
	)
	(via
		(at 121.933208 -55.409338)
		(size 0.508)
		(drill 0.254)
		(layers "F.Cu" "B.Cu")
		(net "M_G_DQS_DN<16>")
	)
	(via
		(at 146.098768 -17.4117)
		(size 0.508)
		(drill 0.254)
		(layers "F.Cu" "B.Cu")
		(net "M_G_DQS_DN<16>")
	)
	(segment
		(start 146.513804 -22.640036)
		(end 146.286728 -22.640036)
		(width 0.1651)
		(layer "B.Cu")
		(net "M_G_DQS_DN<16>")
	)
	(segment
		(start 146.999706 -24.823928)
		(end 146.999706 -24.167592)
		(width 0.1651)
		(layer "B.Cu")
		(net "M_G_DQS_DN<16>")
	)
	(segment
		(start 146.733768 -22.86)
		(end 146.513804 -22.640036)
		(width 0.1651)
		(layer "B.Cu")
		(net "M_G_DQS_DN<16>")
	)
	(segment
		(start 146.286728 -22.640036)
		(end 146.092164 -22.8346)
		(width 0.1651)
		(layer "B.Cu")
		(net "M_G_DQS_DN<16>")
	)
	(segment
		(start 146.999706 -24.167592)
		(end 146.555968 -23.723854)
		(width 0.1651)
		(layer "B.Cu")
		(net "M_G_DQS_DN<16>")
	)
	(segment
		(start 146.555968 -23.723854)
		(end 146.555968 -23.368)
		(width 0.1651)
		(layer "B.Cu")
		(net "M_G_DQS_DN<16>")
	)
	(segment
		(start 146.999452 -24.824182)
		(end 146.999706 -24.823928)
		(width 0.1651)
		(layer "B.Cu")
		(net "M_G_DQS_DN<16>")
	)
	(segment
		(start 146.733768 -23.1902)
		(end 146.733768 -22.86)
		(width 0.1651)
		(layer "B.Cu")
		(net "M_G_DQS_DN<16>")
	)
	(segment
		(start 146.555968 -23.368)
		(end 146.733768 -23.1902)
		(width 0.1651)
		(layer "B.Cu")
		(net "M_G_DQS_DN<16>")
	)
	(segment
		(start 122.584718 -52.490624)
		(end 123.932188 -51.143154)
		(width 0.0889)
		(layer "In2.Cu")
		(net "M_G_DQS_DN<16>")
	)
	(segment
		(start 145.971514 -37.668454)
		(end 146.672808 -36.96716)
		(width 0.14224)
		(layer "In2.Cu")
		(net "M_G_DQS_DN<16>")
	)
	(segment
		(start 128.018286 -47.27448)
		(end 128.198118 -47.094648)
		(width 0.14224)
		(layer "In2.Cu")
		(net "M_G_DQS_DN<16>")
	)
	(segment
		(start 125.566678 -49.726088)
		(end 125.566678 -49.564544)
		(width 0.14224)
		(layer "In2.Cu")
		(net "M_G_DQS_DN<16>")
	)
	(segment
		(start 121.60504 -55.177944)
		(end 121.622058 -55.136542)
		(width 0.0889)
		(layer "In2.Cu")
		(net "M_G_DQS_DN<16>")
	)
	(segment
		(start 125.922278 -49.370742)
		(end 126.10211 -49.19091)
		(width 0.14224)
		(layer "In2.Cu")
		(net "M_G_DQS_DN<16>")
	)
	(segment
		(start 145.961608 -24.11476)
		(end 146.098768 -23.9776)
		(width 0.14224)
		(layer "In2.Cu")
		(net "M_G_DQS_DN<16>")
	)
	(segment
		(start 124.865892 -50.426874)
		(end 125.045724 -50.247042)
		(width 0.14224)
		(layer "In2.Cu")
		(net "M_G_DQS_DN<16>")
	)
	(segment
		(start 126.443232 -48.849534)
		(end 126.623064 -48.669702)
		(width 0.14224)
		(layer "In2.Cu")
		(net "M_G_DQS_DN<16>")
	)
	(segment
		(start 125.045724 -50.247042)
		(end 125.045724 -50.085498)
		(width 0.14224)
		(layer "In2.Cu")
		(net "M_G_DQS_DN<16>")
	)
	(segment
		(start 126.976378 -48.316642)
		(end 127.15621 -48.13681)
		(width 0.14224)
		(layer "In2.Cu")
		(net "M_G_DQS_DN<16>")
	)
	(segment
		(start 133.597142 -45.2628)
		(end 133.909562 -44.95038)
		(width 0.14224)
		(layer "In2.Cu")
		(net "M_G_DQS_DN<16>")
	)
	(segment
		(start 129.78257 -46.136052)
		(end 129.962148 -45.956474)
		(width 0.14224)
		(layer "In2.Cu")
		(net "M_G_DQS_DN<16>")
	)
	(segment
		(start 126.10211 -49.029112)
		(end 126.281688 -48.849534)
		(width 0.14224)
		(layer "In2.Cu")
		(net "M_G_DQS_DN<16>")
	)
	(segment
		(start 127.677164 -47.615602)
		(end 127.677164 -47.454058)
		(width 0.14224)
		(layer "In2.Cu")
		(net "M_G_DQS_DN<16>")
	)
	(segment
		(start 145.961608 -24.50084)
		(end 145.961608 -24.11476)
		(width 0.14224)
		(layer "In2.Cu")
		(net "M_G_DQS_DN<16>")
	)
	(segment
		(start 124.52477 -50.606452)
		(end 124.704348 -50.426874)
		(width 0.14224)
		(layer "In2.Cu")
		(net "M_G_DQS_DN<16>")
	)
	(segment
		(start 132.708142 -44.95038)
		(end 133.020562 -45.2628)
		(width 0.14224)
		(layer "In2.Cu")
		(net "M_G_DQS_DN<16>")
	)
	(segment
		(start 122.445018 -53.132482)
		(end 122.440192 -53.123846)
		(width 0.0889)
		(layer "In2.Cu")
		(net "M_G_DQS_DN<16>")
	)
	(segment
		(start 132.553202 -44.03344)
		(end 132.708142 -44.18838)
		(width 0.14224)
		(layer "In2.Cu")
		(net "M_G_DQS_DN<16>")
	)
	(segment
		(start 124.344938 -50.947828)
		(end 124.52477 -50.767996)
		(width 0.14224)
		(layer "In2.Cu")
		(net "M_G_DQS_DN<16>")
	)
	(segment
		(start 130.483102 -45.43552)
		(end 130.644646 -45.43552)
		(width 0.14224)
		(layer "In2.Cu")
		(net "M_G_DQS_DN<16>")
	)
	(segment
		(start 125.045724 -50.085498)
		(end 125.225302 -49.90592)
		(width 0.14224)
		(layer "In2.Cu")
		(net "M_G_DQS_DN<16>")
	)
	(segment
		(start 136.863328 -44.03344)
		(end 143.228314 -37.668454)
		(width 0.14224)
		(layer "In2.Cu")
		(net "M_G_DQS_DN<16>")
	)
	(segment
		(start 127.335788 -47.795434)
		(end 127.497332 -47.795434)
		(width 0.14224)
		(layer "In2.Cu")
		(net "M_G_DQS_DN<16>")
	)
	(segment
		(start 121.933208 -55.409338)
		(end 121.627392 -55.230014)
		(width 0.0889)
		(layer "In2.Cu")
		(net "M_G_DQS_DN<16>")
	)
	(segment
		(start 146.294348 -17.60728)
		(end 146.098768 -17.4117)
		(width 0.14224)
		(layer "In2.Cu")
		(net "M_G_DQS_DN<16>")
	)
	(segment
		(start 126.623064 -48.669702)
		(end 126.623064 -48.508158)
		(width 0.14224)
		(layer "In2.Cu")
		(net "M_G_DQS_DN<16>")
	)
	(segment
		(start 121.627392 -55.230014)
		(end 121.60504 -55.177944)
		(width 0.0889)
		(layer "In2.Cu")
		(net "M_G_DQS_DN<16>")
	)
	(segment
		(start 134.064502 -44.03344)
		(end 136.863328 -44.03344)
		(width 0.14224)
		(layer "In2.Cu")
		(net "M_G_DQS_DN<16>")
	)
	(segment
		(start 130.824478 -45.255688)
		(end 130.824478 -45.094144)
		(width 0.14224)
		(layer "In2.Cu")
		(net "M_G_DQS_DN<16>")
	)
	(segment
		(start 133.909562 -44.95038)
		(end 133.909562 -44.18838)
		(width 0.14224)
		(layer "In2.Cu")
		(net "M_G_DQS_DN<16>")
	)
	(segment
		(start 146.092164 -22.8346)
		(end 146.881088 -22.045676)
		(width 0.14224)
		(layer "In2.Cu")
		(net "M_G_DQS_DN<16>")
	)
	(segment
		(start 129.602738 -46.477428)
		(end 129.78257 -46.297596)
		(width 0.14224)
		(layer "In2.Cu")
		(net "M_G_DQS_DN<16>")
	)
	(segment
		(start 123.932188 -51.143154)
		(end 123.988068 -51.143154)
		(width 0.0889)
		(layer "In2.Cu")
		(net "M_G_DQS_DN<16>")
	)
	(segment
		(start 131.004056 -44.914566)
		(end 131.1656 -44.914566)
		(width 0.14224)
		(layer "In2.Cu")
		(net "M_G_DQS_DN<16>")
	)
	(segment
		(start 127.15621 -48.13681)
		(end 127.15621 -47.975012)
		(width 0.14224)
		(layer "In2.Cu")
		(net "M_G_DQS_DN<16>")
	)
	(segment
		(start 146.543776 -17.60728)
		(end 146.294348 -17.60728)
		(width 0.14224)
		(layer "In2.Cu")
		(net "M_G_DQS_DN<16>")
	)
	(segment
		(start 143.228314 -37.668454)
		(end 145.971514 -37.668454)
		(width 0.14224)
		(layer "In2.Cu")
		(net "M_G_DQS_DN<16>")
	)
	(segment
		(start 121.592848 -54.629304)
		(end 121.586498 -54.618636)
		(width 0.0889)
		(layer "In2.Cu")
		(net "M_G_DQS_DN<16>")
	)
	(segment
		(start 127.856488 -47.27448)
		(end 128.018286 -47.27448)
		(width 0.14224)
		(layer "In2.Cu")
		(net "M_G_DQS_DN<16>")
	)
	(segment
		(start 130.303524 -45.776642)
		(end 130.303524 -45.615098)
		(width 0.14224)
		(layer "In2.Cu")
		(net "M_G_DQS_DN<16>")
	)
	(segment
		(start 130.123692 -45.956474)
		(end 130.303524 -45.776642)
		(width 0.14224)
		(layer "In2.Cu")
		(net "M_G_DQS_DN<16>")
	)
	(segment
		(start 133.020562 -45.2628)
		(end 133.597142 -45.2628)
		(width 0.14224)
		(layer "In2.Cu")
		(net "M_G_DQS_DN<16>")
	)
	(segment
		(start 130.824478 -45.094144)
		(end 131.004056 -44.914566)
		(width 0.14224)
		(layer "In2.Cu")
		(net "M_G_DQS_DN<16>")
	)
	(segment
		(start 129.78257 -46.297596)
		(end 129.78257 -46.136052)
		(width 0.14224)
		(layer "In2.Cu")
		(net "M_G_DQS_DN<16>")
	)
	(segment
		(start 128.198118 -47.094648)
		(end 128.198118 -46.933104)
		(width 0.14224)
		(layer "In2.Cu")
		(net "M_G_DQS_DN<16>")
	)
	(segment
		(start 130.303524 -45.615098)
		(end 130.483102 -45.43552)
		(width 0.14224)
		(layer "In2.Cu")
		(net "M_G_DQS_DN<16>")
	)
	(segment
		(start 129.261616 -46.657006)
		(end 129.441194 -46.477428)
		(width 0.14224)
		(layer "In2.Cu")
		(net "M_G_DQS_DN<16>")
	)
	(segment
		(start 146.881088 -17.944592)
		(end 146.543776 -17.60728)
		(width 0.14224)
		(layer "In2.Cu")
		(net "M_G_DQS_DN<16>")
	)
	(segment
		(start 123.988068 -51.143154)
		(end 124.003816 -51.127406)
		(width 0.0889)
		(layer "In2.Cu")
		(net "M_G_DQS_DN<16>")
	)
	(segment
		(start 146.098768 -23.9776)
		(end 146.276568 -23.9776)
		(width 0.14224)
		(layer "In2.Cu")
		(net "M_G_DQS_DN<16>")
	)
	(segment
		(start 125.225302 -49.90592)
		(end 125.386846 -49.90592)
		(width 0.14224)
		(layer "In2.Cu")
		(net "M_G_DQS_DN<16>")
	)
	(segment
		(start 146.672808 -36.96716)
		(end 146.672808 -26.4541)
		(width 0.14224)
		(layer "In2.Cu")
		(net "M_G_DQS_DN<16>")
	)
	(segment
		(start 127.15621 -47.975012)
		(end 127.335788 -47.795434)
		(width 0.14224)
		(layer "In2.Cu")
		(net "M_G_DQS_DN<16>")
	)
	(segment
		(start 129.441194 -46.477428)
		(end 129.602738 -46.477428)
		(width 0.14224)
		(layer "In2.Cu")
		(net "M_G_DQS_DN<16>")
	)
	(segment
		(start 126.623064 -48.508158)
		(end 126.81458 -48.316642)
		(width 0.14224)
		(layer "In2.Cu")
		(net "M_G_DQS_DN<16>")
	)
	(segment
		(start 124.704348 -50.426874)
		(end 124.865892 -50.426874)
		(width 0.14224)
		(layer "In2.Cu")
		(net "M_G_DQS_DN<16>")
	)
	(segment
		(start 146.530568 -23.7236)
		(end 146.530568 -23.273004)
		(width 0.14224)
		(layer "In2.Cu")
		(net "M_G_DQS_DN<16>")
	)
	(segment
		(start 146.276568 -23.9776)
		(end 146.530568 -23.7236)
		(width 0.14224)
		(layer "In2.Cu")
		(net "M_G_DQS_DN<16>")
	)
	(segment
		(start 130.644646 -45.43552)
		(end 130.824478 -45.255688)
		(width 0.14224)
		(layer "In2.Cu")
		(net "M_G_DQS_DN<16>")
	)
	(segment
		(start 127.677164 -47.454058)
		(end 127.856488 -47.27448)
		(width 0.14224)
		(layer "In2.Cu")
		(net "M_G_DQS_DN<16>")
	)
	(segment
		(start 126.281688 -48.849534)
		(end 126.443232 -48.849534)
		(width 0.14224)
		(layer "In2.Cu")
		(net "M_G_DQS_DN<16>")
	)
	(segment
		(start 125.386846 -49.90592)
		(end 125.566678 -49.726088)
		(width 0.14224)
		(layer "In2.Cu")
		(net "M_G_DQS_DN<16>")
	)
	(segment
		(start 127.497332 -47.795434)
		(end 127.677164 -47.615602)
		(width 0.14224)
		(layer "In2.Cu")
		(net "M_G_DQS_DN<16>")
	)
	(segment
		(start 125.76048 -49.370742)
		(end 125.922278 -49.370742)
		(width 0.14224)
		(layer "In2.Cu")
		(net "M_G_DQS_DN<16>")
	)
	(segment
		(start 128.473962 -46.657006)
		(end 129.261616 -46.657006)
		(width 0.14224)
		(layer "In2.Cu")
		(net "M_G_DQS_DN<16>")
	)
	(segment
		(start 126.81458 -48.316642)
		(end 126.976378 -48.316642)
		(width 0.14224)
		(layer "In2.Cu")
		(net "M_G_DQS_DN<16>")
	)
	(segment
		(start 128.198118 -46.933104)
		(end 128.473962 -46.657006)
		(width 0.14224)
		(layer "In2.Cu")
		(net "M_G_DQS_DN<16>")
	)
	(segment
		(start 146.787108 -25.32634)
		(end 145.961608 -24.50084)
		(width 0.14224)
		(layer "In2.Cu")
		(net "M_G_DQS_DN<16>")
	)
	(segment
		(start 132.708142 -44.18838)
		(end 132.708142 -44.95038)
		(width 0.14224)
		(layer "In2.Cu")
		(net "M_G_DQS_DN<16>")
	)
	(segment
		(start 126.10211 -49.19091)
		(end 126.10211 -49.029112)
		(width 0.14224)
		(layer "In2.Cu")
		(net "M_G_DQS_DN<16>")
	)
	(segment
		(start 122.445018 -52.732432)
		(end 122.584718 -52.490624)
		(width 0.0889)
		(layer "In2.Cu")
		(net "M_G_DQS_DN<16>")
	)
	(segment
		(start 131.885182 -44.03344)
		(end 132.553202 -44.03344)
		(width 0.14224)
		(layer "In2.Cu")
		(net "M_G_DQS_DN<16>")
	)
	(segment
		(start 124.183394 -50.947828)
		(end 124.344938 -50.947828)
		(width 0.14224)
		(layer "In2.Cu")
		(net "M_G_DQS_DN<16>")
	)
	(segment
		(start 133.909562 -44.18838)
		(end 134.064502 -44.03344)
		(width 0.14224)
		(layer "In2.Cu")
		(net "M_G_DQS_DN<16>")
	)
	(segment
		(start 146.787108 -26.3398)
		(end 146.787108 -25.32634)
		(width 0.14224)
		(layer "In2.Cu")
		(net "M_G_DQS_DN<16>")
	)
	(segment
		(start 131.1656 -44.914566)
		(end 131.345432 -44.734734)
		(width 0.14224)
		(layer "In2.Cu")
		(net "M_G_DQS_DN<16>")
	)
	(segment
		(start 124.003816 -51.127406)
		(end 124.183394 -50.947828)
		(width 0.14224)
		(layer "In2.Cu")
		(net "M_G_DQS_DN<16>")
	)
	(segment
		(start 146.881088 -22.045676)
		(end 146.881088 -17.944592)
		(width 0.14224)
		(layer "In2.Cu")
		(net "M_G_DQS_DN<16>")
	)
	(segment
		(start 125.566678 -49.564544)
		(end 125.76048 -49.370742)
		(width 0.14224)
		(layer "In2.Cu")
		(net "M_G_DQS_DN<16>")
	)
	(segment
		(start 121.918222 -54.018688)
		(end 121.946162 -54.018688)
		(width 0.0889)
		(layer "In2.Cu")
		(net "M_G_DQS_DN<16>")
	)
	(segment
		(start 121.586498 -54.618636)
		(end 121.581672 -54.61)
		(width 0.0889)
		(layer "In2.Cu")
		(net "M_G_DQS_DN<16>")
	)
	(segment
		(start 124.52477 -50.767996)
		(end 124.52477 -50.606452)
		(width 0.14224)
		(layer "In2.Cu")
		(net "M_G_DQS_DN<16>")
	)
	(segment
		(start 129.962148 -45.956474)
		(end 130.123692 -45.956474)
		(width 0.14224)
		(layer "In2.Cu")
		(net "M_G_DQS_DN<16>")
	)
	(segment
		(start 146.672808 -26.4541)
		(end 146.787108 -26.3398)
		(width 0.14224)
		(layer "In2.Cu")
		(net "M_G_DQS_DN<16>")
	)
	(segment
		(start 131.345432 -44.57319)
		(end 131.885182 -44.03344)
		(width 0.14224)
		(layer "In2.Cu")
		(net "M_G_DQS_DN<16>")
	)
	(segment
		(start 131.345432 -44.734734)
		(end 131.345432 -44.57319)
		(width 0.14224)
		(layer "In2.Cu")
		(net "M_G_DQS_DN<16>")
	)
	(segment
		(start 146.530568 -23.273004)
		(end 146.092164 -22.8346)
		(width 0.14224)
		(layer "In2.Cu")
		(net "M_G_DQS_DN<16>")
	)
	(arc
		(start 121.581672 -54.61)
		(mid 121.585419 -54.220744)
		(end 121.918222 -54.018688)
		(width 0.0889)
		(layer "In2.Cu")
		(net "M_G_DQS_DN<16>")
	)
	(arc
		(start 122.440192 -53.123846)
		(mid 122.391437 -52.927494)
		(end 122.445018 -52.732432)
		(width 0.0889)
		(layer "In2.Cu")
		(net "M_G_DQS_DN<16>")
	)
	(arc
		(start 121.622058 -55.136542)
		(mid 121.664771 -54.879615)
		(end 121.592848 -54.629304)
		(width 0.0889)
		(layer "In2.Cu")
		(net "M_G_DQS_DN<16>")
	)
	(arc
		(start 121.946162 -54.018688)
		(mid 122.448171 -53.717764)
		(end 122.445018 -53.132482)
		(width 0.0889)
		(layer "In2.Cu")
		(net "M_G_DQS_DN<16>")
	)
	(segment
		(start 136.957054 -17.60093)
		(end 136.767824 -17.4117)
		(width 0.1651)
		(layer "F.Cu")
		(net "M_G_DQS_DN<15>")
	)
	(segment
		(start 137.649458 -15.423642)
		(end 137.649458 -16.077184)
		(width 0.1651)
		(layer "F.Cu")
		(net "M_G_DQS_DN<15>")
	)
	(segment
		(start 137.231374 -16.495268)
		(end 137.231374 -16.9164)
		(width 0.1651)
		(layer "F.Cu")
		(net "M_G_DQS_DN<15>")
	)
	(segment
		(start 137.231374 -16.9164)
		(end 137.417302 -17.102328)
		(width 0.1651)
		(layer "F.Cu")
		(net "M_G_DQS_DN<15>")
	)
	(segment
		(start 137.165334 -17.60093)
		(end 136.957054 -17.60093)
		(width 0.1651)
		(layer "F.Cu")
		(net "M_G_DQS_DN<15>")
	)
	(segment
		(start 137.417302 -17.102328)
		(end 137.417302 -17.348962)
		(width 0.1651)
		(layer "F.Cu")
		(net "M_G_DQS_DN<15>")
	)
	(segment
		(start 136.767824 -17.4117)
		(end 136.748774 -17.4117)
		(width 0.1651)
		(layer "F.Cu")
		(net "M_G_DQS_DN<15>")
	)
	(segment
		(start 117.353842 -55.409338)
		(end 116.782342 -55.409338)
		(width 0.1016)
		(layer "F.Cu")
		(net "M_G_DQS_DN<15>")
	)
	(segment
		(start 137.417302 -17.348962)
		(end 137.165334 -17.60093)
		(width 0.1651)
		(layer "F.Cu")
		(net "M_G_DQS_DN<15>")
	)
	(segment
		(start 137.649458 -16.077184)
		(end 137.231374 -16.495268)
		(width 0.1651)
		(layer "F.Cu")
		(net "M_G_DQS_DN<15>")
	)
	(via
		(at 116.782342 -55.409338)
		(size 0.508)
		(drill 0.254)
		(layers "F.Cu" "B.Cu")
		(net "M_G_DQS_DN<15>")
	)
	(via
		(at 136.74217 -22.8346)
		(size 0.508)
		(drill 0.254)
		(layers "F.Cu" "B.Cu")
		(net "M_G_DQS_DN<15>")
	)
	(via
		(at 136.748774 -17.4117)
		(size 0.508)
		(drill 0.254)
		(layers "F.Cu" "B.Cu")
		(net "M_G_DQS_DN<15>")
	)
	(segment
		(start 137.205974 -23.368)
		(end 137.383774 -23.1902)
		(width 0.1651)
		(layer "B.Cu")
		(net "M_G_DQS_DN<15>")
	)
	(segment
		(start 137.383774 -22.86)
		(end 137.16381 -22.640036)
		(width 0.1651)
		(layer "B.Cu")
		(net "M_G_DQS_DN<15>")
	)
	(segment
		(start 136.936734 -22.640036)
		(end 136.74217 -22.8346)
		(width 0.1651)
		(layer "B.Cu")
		(net "M_G_DQS_DN<15>")
	)
	(segment
		(start 137.649712 -24.167592)
		(end 137.205974 -23.723854)
		(width 0.1651)
		(layer "B.Cu")
		(net "M_G_DQS_DN<15>")
	)
	(segment
		(start 137.383774 -23.1902)
		(end 137.383774 -22.86)
		(width 0.1651)
		(layer "B.Cu")
		(net "M_G_DQS_DN<15>")
	)
	(segment
		(start 137.205974 -23.723854)
		(end 137.205974 -23.368)
		(width 0.1651)
		(layer "B.Cu")
		(net "M_G_DQS_DN<15>")
	)
	(segment
		(start 137.649458 -24.824182)
		(end 137.649712 -24.823928)
		(width 0.1651)
		(layer "B.Cu")
		(net "M_G_DQS_DN<15>")
	)
	(segment
		(start 137.649712 -24.823928)
		(end 137.649712 -24.167592)
		(width 0.1651)
		(layer "B.Cu")
		(net "M_G_DQS_DN<15>")
	)
	(segment
		(start 137.16381 -22.640036)
		(end 136.936734 -22.640036)
		(width 0.1651)
		(layer "B.Cu")
		(net "M_G_DQS_DN<15>")
	)
	(segment
		(start 118.075456 -41.917112)
		(end 118.255034 -41.737534)
		(width 0.14224)
		(layer "In2.Cu")
		(net "M_G_DQS_DN<15>")
	)
	(segment
		(start 137.193782 -17.60728)
		(end 136.944354 -17.60728)
		(width 0.14224)
		(layer "In2.Cu")
		(net "M_G_DQS_DN<15>")
	)
	(segment
		(start 137.411206 -22.165564)
		(end 137.531094 -22.045676)
		(width 0.14224)
		(layer "In2.Cu")
		(net "M_G_DQS_DN<15>")
	)
	(segment
		(start 136.74217 -22.8346)
		(end 137.026396 -22.550628)
		(width 0.14224)
		(layer "In2.Cu")
		(net "M_G_DQS_DN<15>")
	)
	(segment
		(start 116.980462 -43.17365)
		(end 116.980462 -43.012106)
		(width 0.14224)
		(layer "In2.Cu")
		(net "M_G_DQS_DN<15>")
	)
	(segment
		(start 136.540494 -24.672544)
		(end 136.540494 -24.18588)
		(width 0.14224)
		(layer "In2.Cu")
		(net "M_G_DQS_DN<15>")
	)
	(segment
		(start 116.573808 -46.3042)
		(end 116.573808 -46.0502)
		(width 0.14224)
		(layer "In2.Cu")
		(net "M_G_DQS_DN<15>")
	)
	(segment
		(start 135.410956 -31.974282)
		(end 135.410956 -31.795466)
		(width 0.14224)
		(layer "In2.Cu")
		(net "M_G_DQS_DN<15>")
	)
	(segment
		(start 116.459508 -48.212502)
		(end 116.459508 -48.190404)
		(width 0.0889)
		(layer "In2.Cu")
		(net "M_G_DQS_DN<15>")
	)
	(segment
		(start 134.339838 -33.541716)
		(end 134.12978 -33.331658)
		(width 0.14224)
		(layer "In2.Cu")
		(net "M_G_DQS_DN<15>")
	)
	(segment
		(start 118.85168 -41.140888)
		(end 119.013224 -41.140888)
		(width 0.14224)
		(layer "In2.Cu")
		(net "M_G_DQS_DN<15>")
	)
	(segment
		(start 136.723374 -24.003)
		(end 136.977374 -24.003)
		(width 0.14224)
		(layer "In2.Cu")
		(net "M_G_DQS_DN<15>")
	)
	(segment
		(start 116.435632 -54.21884)
		(end 116.519452 -54.073044)
		(width 0.0889)
		(layer "In2.Cu")
		(net "M_G_DQS_DN<15>")
	)
	(segment
		(start 116.459508 -44.8691)
		(end 116.573808 -44.7548)
		(width 0.14224)
		(layer "In2.Cu")
		(net "M_G_DQS_DN<15>")
	)
	(segment
		(start 137.527284 -30.796738)
		(end 137.527284 -30.07868)
		(width 0.14224)
		(layer "In2.Cu")
		(net "M_G_DQS_DN<15>")
	)
	(segment
		(start 119.802656 -40.351456)
		(end 119.802656 -40.189912)
		(width 0.14224)
		(layer "In2.Cu")
		(net "M_G_DQS_DN<15>")
	)
	(segment
		(start 116.573808 -44.7548)
		(end 116.573808 -44.5008)
		(width 0.14224)
		(layer "In2.Cu")
		(net "M_G_DQS_DN<15>")
	)
	(segment
		(start 117.349524 -42.804588)
		(end 117.529356 -42.624756)
		(width 0.14224)
		(layer "In2.Cu")
		(net "M_G_DQS_DN<15>")
	)
	(segment
		(start 116.519452 -54.073044)
		(end 116.519452 -51.744372)
		(width 0.0889)
		(layer "In2.Cu")
		(net "M_G_DQS_DN<15>")
	)
	(segment
		(start 116.573808 -47.0408)
		(end 116.573808 -46.7868)
		(width 0.14224)
		(layer "In2.Cu")
		(net "M_G_DQS_DN<15>")
	)
	(segment
		(start 135.251698 -33.072324)
		(end 135.659114 -32.664908)
		(width 0.14224)
		(layer "In2.Cu")
		(net "M_G_DQS_DN<15>")
	)
	(segment
		(start 136.977374 -24.003)
		(end 137.180574 -23.7998)
		(width 0.14224)
		(layer "In2.Cu")
		(net "M_G_DQS_DN<15>")
	)
	(segment
		(start 119.46128 -40.531288)
		(end 119.622824 -40.531288)
		(width 0.14224)
		(layer "In2.Cu")
		(net "M_G_DQS_DN<15>")
	)
	(segment
		(start 133.020562 -34.860992)
		(end 132.823204 -34.663634)
		(width 0.14224)
		(layer "In2.Cu")
		(net "M_G_DQS_DN<15>")
	)
	(segment
		(start 117.895624 -42.258488)
		(end 118.075456 -42.078656)
		(width 0.14224)
		(layer "In2.Cu")
		(net "M_G_DQS_DN<15>")
	)
	(segment
		(start 116.519452 -51.744372)
		(end 116.076476 -51.301396)
		(width 0.0889)
		(layer "In2.Cu")
		(net "M_G_DQS_DN<15>")
	)
	(segment
		(start 136.540494 -24.18588)
		(end 136.723374 -24.003)
		(width 0.14224)
		(layer "In2.Cu")
		(net "M_G_DQS_DN<15>")
	)
	(segment
		(start 116.420138 -50.37963)
		(end 116.420138 -48.251872)
		(width 0.0889)
		(layer "In2.Cu")
		(net "M_G_DQS_DN<15>")
	)
	(segment
		(start 136.819132 -31.50489)
		(end 137.527284 -30.796738)
		(width 0.14224)
		(layer "In2.Cu")
		(net "M_G_DQS_DN<15>")
	)
	(segment
		(start 134.12978 -33.152842)
		(end 134.420356 -32.862266)
		(width 0.14224)
		(layer "In2.Cu")
		(net "M_G_DQS_DN<15>")
	)
	(segment
		(start 116.573808 -46.0502)
		(end 116.459508 -45.9359)
		(width 0.14224)
		(layer "In2.Cu")
		(net "M_G_DQS_DN<15>")
	)
	(segment
		(start 119.802656 -40.189912)
		(end 123.960128 -36.03244)
		(width 0.14224)
		(layer "In2.Cu")
		(net "M_G_DQS_DN<15>")
	)
	(segment
		(start 135.410956 -31.795466)
		(end 135.701532 -31.50489)
		(width 0.14224)
		(layer "In2.Cu")
		(net "M_G_DQS_DN<15>")
	)
	(segment
		(start 137.527284 -25.659334)
		(end 136.540494 -24.672544)
		(width 0.14224)
		(layer "In2.Cu")
		(net "M_G_DQS_DN<15>")
	)
	(segment
		(start 133.932422 -34.3916)
		(end 134.339838 -33.984184)
		(width 0.14224)
		(layer "In2.Cu")
		(net "M_G_DQS_DN<15>")
	)
	(segment
		(start 116.459508 -46.4185)
		(end 116.573808 -46.3042)
		(width 0.14224)
		(layer "In2.Cu")
		(net "M_G_DQS_DN<15>")
	)
	(segment
		(start 116.459508 -47.453804)
		(end 116.459508 -47.1551)
		(width 0.14224)
		(layer "In2.Cu")
		(net "M_G_DQS_DN<15>")
	)
	(segment
		(start 116.573808 -45.3136)
		(end 116.459508 -45.1993)
		(width 0.14224)
		(layer "In2.Cu")
		(net "M_G_DQS_DN<15>")
	)
	(segment
		(start 118.075456 -42.078656)
		(end 118.075456 -41.917112)
		(width 0.14224)
		(layer "In2.Cu")
		(net "M_G_DQS_DN<15>")
	)
	(segment
		(start 137.527284 -25.870662)
		(end 137.527284 -25.659334)
		(width 0.14224)
		(layer "In2.Cu")
		(net "M_G_DQS_DN<15>")
	)
	(segment
		(start 116.573808 -44.5008)
		(end 116.459508 -44.3865)
		(width 0.14224)
		(layer "In2.Cu")
		(net "M_G_DQS_DN<15>")
	)
	(segment
		(start 137.026396 -22.550628)
		(end 137.411206 -22.165564)
		(width 0.14224)
		(layer "In2.Cu")
		(net "M_G_DQS_DN<15>")
	)
	(segment
		(start 117.18798 -42.804588)
		(end 117.349524 -42.804588)
		(width 0.14224)
		(layer "In2.Cu")
		(net "M_G_DQS_DN<15>")
	)
	(segment
		(start 116.80063 -43.353482)
		(end 116.980462 -43.17365)
		(width 0.14224)
		(layer "In2.Cu")
		(net "M_G_DQS_DN<15>")
	)
	(segment
		(start 118.416578 -41.737534)
		(end 118.59641 -41.557702)
		(width 0.14224)
		(layer "In2.Cu")
		(net "M_G_DQS_DN<15>")
	)
	(segment
		(start 134.420356 -32.862266)
		(end 134.599172 -32.862266)
		(width 0.14224)
		(layer "In2.Cu")
		(net "M_G_DQS_DN<15>")
	)
	(segment
		(start 123.960128 -36.03244)
		(end 132.291582 -36.03244)
		(width 0.14224)
		(layer "In2.Cu")
		(net "M_G_DQS_DN<15>")
	)
	(segment
		(start 132.291582 -36.03244)
		(end 133.020562 -35.30346)
		(width 0.14224)
		(layer "In2.Cu")
		(net "M_G_DQS_DN<15>")
	)
	(segment
		(start 135.659114 -32.22244)
		(end 135.410956 -31.974282)
		(width 0.14224)
		(layer "In2.Cu")
		(net "M_G_DQS_DN<15>")
	)
	(segment
		(start 116.459508 -44.3865)
		(end 116.459508 -43.53306)
		(width 0.14224)
		(layer "In2.Cu")
		(net "M_G_DQS_DN<15>")
	)
	(segment
		(start 135.701532 -31.50489)
		(end 136.819132 -31.50489)
		(width 0.14224)
		(layer "In2.Cu")
		(net "M_G_DQS_DN<15>")
	)
	(segment
		(start 116.459508 -46.6725)
		(end 116.459508 -46.4185)
		(width 0.14224)
		(layer "In2.Cu")
		(net "M_G_DQS_DN<15>")
	)
	(segment
		(start 116.459508 -48.190404)
		(end 116.459508 -47.936404)
		(width 0.14224)
		(layer "In2.Cu")
		(net "M_G_DQS_DN<15>")
	)
	(segment
		(start 133.020562 -35.30346)
		(end 133.020562 -34.860992)
		(width 0.14224)
		(layer "In2.Cu")
		(net "M_G_DQS_DN<15>")
	)
	(segment
		(start 119.193056 -40.961056)
		(end 119.193056 -40.799512)
		(width 0.14224)
		(layer "In2.Cu")
		(net "M_G_DQS_DN<15>")
	)
	(segment
		(start 133.489954 -34.3916)
		(end 133.932422 -34.3916)
		(width 0.14224)
		(layer "In2.Cu")
		(net "M_G_DQS_DN<15>")
	)
	(segment
		(start 137.527284 -29.50972)
		(end 137.527284 -26.439622)
		(width 0.14224)
		(layer "In2.Cu")
		(net "M_G_DQS_DN<15>")
	)
	(segment
		(start 116.459508 -45.6819)
		(end 116.573808 -45.5676)
		(width 0.14224)
		(layer "In2.Cu")
		(net "M_G_DQS_DN<15>")
	)
	(segment
		(start 116.420138 -48.251872)
		(end 116.459508 -48.212502)
		(width 0.0889)
		(layer "In2.Cu")
		(net "M_G_DQS_DN<15>")
	)
	(segment
		(start 117.73408 -42.258488)
		(end 117.895624 -42.258488)
		(width 0.14224)
		(layer "In2.Cu")
		(net "M_G_DQS_DN<15>")
	)
	(segment
		(start 134.12978 -33.331658)
		(end 134.12978 -33.152842)
		(width 0.14224)
		(layer "In2.Cu")
		(net "M_G_DQS_DN<15>")
	)
	(segment
		(start 137.684764 -26.282142)
		(end 137.684764 -26.028142)
		(width 0.14224)
		(layer "In2.Cu")
		(net "M_G_DQS_DN<15>")
	)
	(segment
		(start 117.529356 -42.624756)
		(end 117.529356 -42.463212)
		(width 0.14224)
		(layer "In2.Cu")
		(net "M_G_DQS_DN<15>")
	)
	(segment
		(start 137.180574 -23.7998)
		(end 137.180574 -23.273004)
		(width 0.14224)
		(layer "In2.Cu")
		(net "M_G_DQS_DN<15>")
	)
	(segment
		(start 137.531094 -22.045676)
		(end 137.531094 -17.944592)
		(width 0.14224)
		(layer "In2.Cu")
		(net "M_G_DQS_DN<15>")
	)
	(segment
		(start 135.659114 -32.664908)
		(end 135.659114 -32.22244)
		(width 0.14224)
		(layer "In2.Cu")
		(net "M_G_DQS_DN<15>")
	)
	(segment
		(start 117.529356 -42.463212)
		(end 117.73408 -42.258488)
		(width 0.14224)
		(layer "In2.Cu")
		(net "M_G_DQS_DN<15>")
	)
	(segment
		(start 137.684764 -29.6672)
		(end 137.527284 -29.50972)
		(width 0.14224)
		(layer "In2.Cu")
		(net "M_G_DQS_DN<15>")
	)
	(segment
		(start 116.980462 -43.012106)
		(end 117.18798 -42.804588)
		(width 0.14224)
		(layer "In2.Cu")
		(net "M_G_DQS_DN<15>")
	)
	(segment
		(start 116.459508 -43.53306)
		(end 116.639086 -43.353482)
		(width 0.14224)
		(layer "In2.Cu")
		(net "M_G_DQS_DN<15>")
	)
	(segment
		(start 137.180574 -23.273004)
		(end 136.74217 -22.8346)
		(width 0.14224)
		(layer "In2.Cu")
		(net "M_G_DQS_DN<15>")
	)
	(segment
		(start 116.459508 -47.936404)
		(end 116.573808 -47.822104)
		(width 0.14224)
		(layer "In2.Cu")
		(net "M_G_DQS_DN<15>")
	)
	(segment
		(start 118.59641 -41.396158)
		(end 118.85168 -41.140888)
		(width 0.14224)
		(layer "In2.Cu")
		(net "M_G_DQS_DN<15>")
	)
	(segment
		(start 134.599172 -32.862266)
		(end 134.80923 -33.072324)
		(width 0.14224)
		(layer "In2.Cu")
		(net "M_G_DQS_DN<15>")
	)
	(segment
		(start 132.823204 -34.663634)
		(end 132.823204 -34.484818)
		(width 0.14224)
		(layer "In2.Cu")
		(net "M_G_DQS_DN<15>")
	)
	(segment
		(start 116.62664 -55.085996)
		(end 116.51361 -54.749446)
		(width 0.0889)
		(layer "In2.Cu")
		(net "M_G_DQS_DN<15>")
	)
	(segment
		(start 134.339838 -33.984184)
		(end 134.339838 -33.541716)
		(width 0.14224)
		(layer "In2.Cu")
		(net "M_G_DQS_DN<15>")
	)
	(segment
		(start 116.51361 -54.749446)
		(end 116.432584 -54.61381)
		(width 0.0889)
		(layer "In2.Cu")
		(net "M_G_DQS_DN<15>")
	)
	(segment
		(start 137.531094 -17.944592)
		(end 137.193782 -17.60728)
		(width 0.14224)
		(layer "In2.Cu")
		(net "M_G_DQS_DN<15>")
	)
	(segment
		(start 119.013224 -41.140888)
		(end 119.193056 -40.961056)
		(width 0.14224)
		(layer "In2.Cu")
		(net "M_G_DQS_DN<15>")
	)
	(segment
		(start 137.684764 -26.028142)
		(end 137.527284 -25.870662)
		(width 0.14224)
		(layer "In2.Cu")
		(net "M_G_DQS_DN<15>")
	)
	(segment
		(start 136.944354 -17.60728)
		(end 136.748774 -17.4117)
		(width 0.14224)
		(layer "In2.Cu")
		(net "M_G_DQS_DN<15>")
	)
	(segment
		(start 116.639086 -43.353482)
		(end 116.80063 -43.353482)
		(width 0.14224)
		(layer "In2.Cu")
		(net "M_G_DQS_DN<15>")
	)
	(segment
		(start 137.527284 -26.439622)
		(end 137.684764 -26.282142)
		(width 0.14224)
		(layer "In2.Cu")
		(net "M_G_DQS_DN<15>")
	)
	(segment
		(start 116.459508 -45.9359)
		(end 116.459508 -45.6819)
		(width 0.14224)
		(layer "In2.Cu")
		(net "M_G_DQS_DN<15>")
	)
	(segment
		(start 116.076476 -51.301396)
		(end 116.076476 -50.723292)
		(width 0.0889)
		(layer "In2.Cu")
		(net "M_G_DQS_DN<15>")
	)
	(segment
		(start 118.255034 -41.737534)
		(end 118.416578 -41.737534)
		(width 0.14224)
		(layer "In2.Cu")
		(net "M_G_DQS_DN<15>")
	)
	(segment
		(start 133.292596 -34.194242)
		(end 133.489954 -34.3916)
		(width 0.14224)
		(layer "In2.Cu")
		(net "M_G_DQS_DN<15>")
	)
	(segment
		(start 116.573808 -46.7868)
		(end 116.459508 -46.6725)
		(width 0.14224)
		(layer "In2.Cu")
		(net "M_G_DQS_DN<15>")
	)
	(segment
		(start 116.782342 -55.409338)
		(end 116.62664 -55.085996)
		(width 0.0889)
		(layer "In2.Cu")
		(net "M_G_DQS_DN<15>")
	)
	(segment
		(start 116.432584 -54.61381)
		(end 116.430552 -54.610254)
		(width 0.0889)
		(layer "In2.Cu")
		(net "M_G_DQS_DN<15>")
	)
	(segment
		(start 119.193056 -40.799512)
		(end 119.46128 -40.531288)
		(width 0.14224)
		(layer "In2.Cu")
		(net "M_G_DQS_DN<15>")
	)
	(segment
		(start 116.459508 -47.1551)
		(end 116.573808 -47.0408)
		(width 0.14224)
		(layer "In2.Cu")
		(net "M_G_DQS_DN<15>")
	)
	(segment
		(start 116.459508 -45.1993)
		(end 116.459508 -44.8691)
		(width 0.14224)
		(layer "In2.Cu")
		(net "M_G_DQS_DN<15>")
	)
	(segment
		(start 137.527284 -30.07868)
		(end 137.684764 -29.9212)
		(width 0.14224)
		(layer "In2.Cu")
		(net "M_G_DQS_DN<15>")
	)
	(segment
		(start 132.823204 -34.484818)
		(end 133.11378 -34.194242)
		(width 0.14224)
		(layer "In2.Cu")
		(net "M_G_DQS_DN<15>")
	)
	(segment
		(start 134.80923 -33.072324)
		(end 135.251698 -33.072324)
		(width 0.14224)
		(layer "In2.Cu")
		(net "M_G_DQS_DN<15>")
	)
	(segment
		(start 116.573808 -47.568104)
		(end 116.459508 -47.453804)
		(width 0.14224)
		(layer "In2.Cu")
		(net "M_G_DQS_DN<15>")
	)
	(segment
		(start 137.684764 -29.9212)
		(end 137.684764 -29.6672)
		(width 0.14224)
		(layer "In2.Cu")
		(net "M_G_DQS_DN<15>")
	)
	(segment
		(start 118.59641 -41.557702)
		(end 118.59641 -41.396158)
		(width 0.14224)
		(layer "In2.Cu")
		(net "M_G_DQS_DN<15>")
	)
	(segment
		(start 116.573808 -45.5676)
		(end 116.573808 -45.3136)
		(width 0.14224)
		(layer "In2.Cu")
		(net "M_G_DQS_DN<15>")
	)
	(segment
		(start 116.573808 -47.822104)
		(end 116.573808 -47.568104)
		(width 0.14224)
		(layer "In2.Cu")
		(net "M_G_DQS_DN<15>")
	)
	(segment
		(start 116.076476 -50.723292)
		(end 116.420138 -50.37963)
		(width 0.0889)
		(layer "In2.Cu")
		(net "M_G_DQS_DN<15>")
	)
	(segment
		(start 133.11378 -34.194242)
		(end 133.292596 -34.194242)
		(width 0.14224)
		(layer "In2.Cu")
		(net "M_G_DQS_DN<15>")
	)
	(segment
		(start 119.622824 -40.531288)
		(end 119.802656 -40.351456)
		(width 0.14224)
		(layer "In2.Cu")
		(net "M_G_DQS_DN<15>")
	)
	(arc
		(start 116.430552 -54.610254)
		(mid 116.381953 -54.413872)
		(end 116.435632 -54.21884)
		(width 0.0889)
		(layer "In2.Cu")
		(net "M_G_DQS_DN<15>")
	)
	(segment
		(start 127.88138 -16.9164)
		(end 128.067308 -17.102328)
		(width 0.1651)
		(layer "F.Cu")
		(net "M_G_DQS_DN<14>")
	)
	(segment
		(start 112.202722 -55.409338)
		(end 111.631222 -55.409338)
		(width 0.1016)
		(layer "F.Cu")
		(net "M_G_DQS_DN<14>")
	)
	(segment
		(start 128.067308 -17.348962)
		(end 127.81534 -17.60093)
		(width 0.1651)
		(layer "F.Cu")
		(net "M_G_DQS_DN<14>")
	)
	(segment
		(start 127.88138 -16.495268)
		(end 127.88138 -16.9164)
		(width 0.1651)
		(layer "F.Cu")
		(net "M_G_DQS_DN<14>")
	)
	(segment
		(start 128.299464 -15.423642)
		(end 128.299464 -16.077184)
		(width 0.1651)
		(layer "F.Cu")
		(net "M_G_DQS_DN<14>")
	)
	(segment
		(start 128.067308 -17.102328)
		(end 128.067308 -17.348962)
		(width 0.1651)
		(layer "F.Cu")
		(net "M_G_DQS_DN<14>")
	)
	(segment
		(start 128.299464 -16.077184)
		(end 127.88138 -16.495268)
		(width 0.1651)
		(layer "F.Cu")
		(net "M_G_DQS_DN<14>")
	)
	(segment
		(start 127.60706 -17.60093)
		(end 127.41783 -17.4117)
		(width 0.1651)
		(layer "F.Cu")
		(net "M_G_DQS_DN<14>")
	)
	(segment
		(start 127.41783 -17.4117)
		(end 127.39878 -17.4117)
		(width 0.1651)
		(layer "F.Cu")
		(net "M_G_DQS_DN<14>")
	)
	(segment
		(start 127.81534 -17.60093)
		(end 127.60706 -17.60093)
		(width 0.1651)
		(layer "F.Cu")
		(net "M_G_DQS_DN<14>")
	)
	(via
		(at 111.631222 -55.409338)
		(size 0.508)
		(drill 0.254)
		(layers "F.Cu" "B.Cu")
		(net "M_G_DQS_DN<14>")
	)
	(via
		(at 127.39878 -17.4117)
		(size 0.508)
		(drill 0.254)
		(layers "F.Cu" "B.Cu")
		(net "M_G_DQS_DN<14>")
	)
	(via
		(at 127.392176 -22.8346)
		(size 0.508)
		(drill 0.254)
		(layers "F.Cu" "B.Cu")
		(net "M_G_DQS_DN<14>")
	)
	(segment
		(start 128.299718 -24.823928)
		(end 128.299718 -24.167592)
		(width 0.1651)
		(layer "B.Cu")
		(net "M_G_DQS_DN<14>")
	)
	(segment
		(start 127.813816 -22.640036)
		(end 127.58674 -22.640036)
		(width 0.1651)
		(layer "B.Cu")
		(net "M_G_DQS_DN<14>")
	)
	(segment
		(start 128.299464 -24.824182)
		(end 128.299718 -24.823928)
		(width 0.1651)
		(layer "B.Cu")
		(net "M_G_DQS_DN<14>")
	)
	(segment
		(start 127.85598 -23.368)
		(end 128.03378 -23.1902)
		(width 0.1651)
		(layer "B.Cu")
		(net "M_G_DQS_DN<14>")
	)
	(segment
		(start 128.299718 -24.167592)
		(end 127.85598 -23.723854)
		(width 0.1651)
		(layer "B.Cu")
		(net "M_G_DQS_DN<14>")
	)
	(segment
		(start 128.03378 -22.86)
		(end 127.813816 -22.640036)
		(width 0.1651)
		(layer "B.Cu")
		(net "M_G_DQS_DN<14>")
	)
	(segment
		(start 127.58674 -22.640036)
		(end 127.392176 -22.8346)
		(width 0.1651)
		(layer "B.Cu")
		(net "M_G_DQS_DN<14>")
	)
	(segment
		(start 128.03378 -23.1902)
		(end 128.03378 -22.86)
		(width 0.1651)
		(layer "B.Cu")
		(net "M_G_DQS_DN<14>")
	)
	(segment
		(start 127.85598 -23.723854)
		(end 127.85598 -23.368)
		(width 0.1651)
		(layer "B.Cu")
		(net "M_G_DQS_DN<14>")
	)
	(segment
		(start 111.631222 -55.409338)
		(end 111.47552 -55.085996)
		(width 0.0889)
		(layer "In2.Cu")
		(net "M_G_DQS_DN<14>")
	)
	(segment
		(start 120.698768 -27.85364)
		(end 121.953782 -27.85364)
		(width 0.14224)
		(layer "In2.Cu")
		(net "M_G_DQS_DN<14>")
	)
	(segment
		(start 118.651528 -28.1178)
		(end 120.434608 -28.1178)
		(width 0.14224)
		(layer "In2.Cu")
		(net "M_G_DQS_DN<14>")
	)
	(segment
		(start 127.16002 -24.8412)
		(end 127.27432 -24.7269)
		(width 0.14224)
		(layer "In2.Cu")
		(net "M_G_DQS_DN<14>")
	)
	(segment
		(start 109.141768 -45.0215)
		(end 109.141768 -44.7675)
		(width 0.14224)
		(layer "In2.Cu")
		(net "M_G_DQS_DN<14>")
	)
	(segment
		(start 110.69828 -34.613088)
		(end 110.948216 -34.363152)
		(width 0.14224)
		(layer "In2.Cu")
		(net "M_G_DQS_DN<14>")
	)
	(segment
		(start 109.141768 -39.8653)
		(end 109.141768 -39.5097)
		(width 0.14224)
		(layer "In2.Cu")
		(net "M_G_DQS_DN<14>")
	)
	(segment
		(start 109.141768 -39.0271)
		(end 109.141768 -38.7477)
		(width 0.14224)
		(layer "In2.Cu")
		(net "M_G_DQS_DN<14>")
	)
	(segment
		(start 127.16002 -24.3586)
		(end 127.16002 -24.1046)
		(width 0.14224)
		(layer "In2.Cu")
		(net "M_G_DQS_DN<14>")
	)
	(segment
		(start 109.256068 -43.9166)
		(end 109.256068 -43.6626)
		(width 0.14224)
		(layer "In2.Cu")
		(net "M_G_DQS_DN<14>")
	)
	(segment
		(start 109.141768 -42.5577)
		(end 109.256068 -42.4434)
		(width 0.14224)
		(layer "In2.Cu")
		(net "M_G_DQS_DN<14>")
	)
	(segment
		(start 124.927868 -25.99944)
		(end 126.4666 -25.99944)
		(width 0.14224)
		(layer "In2.Cu")
		(net "M_G_DQS_DN<14>")
	)
	(segment
		(start 109.256068 -46.1264)
		(end 109.256068 -45.8724)
		(width 0.14224)
		(layer "In2.Cu")
		(net "M_G_DQS_DN<14>")
	)
	(segment
		(start 109.141768 -42.8117)
		(end 109.141768 -42.5577)
		(width 0.14224)
		(layer "In2.Cu")
		(net "M_G_DQS_DN<14>")
	)
	(segment
		(start 109.256068 -44.3992)
		(end 109.141768 -44.2849)
		(width 0.14224)
		(layer "In2.Cu")
		(net "M_G_DQS_DN<14>")
	)
	(segment
		(start 109.336078 -46.7106)
		(end 109.141768 -46.51629)
		(width 0.14224)
		(layer "In2.Cu")
		(net "M_G_DQS_DN<14>")
	)
	(segment
		(start 109.336078 -47.062898)
		(end 109.336078 -46.7106)
		(width 0.14224)
		(layer "In2.Cu")
		(net "M_G_DQS_DN<14>")
	)
	(segment
		(start 122.71121 -27.25801)
		(end 122.71121 -27.096212)
		(width 0.14224)
		(layer "In2.Cu")
		(net "M_G_DQS_DN<14>")
	)
	(segment
		(start 114.152172 -31.378144)
		(end 114.329718 -31.55569)
		(width 0.14224)
		(layer "In2.Cu")
		(net "M_G_DQS_DN<14>")
	)
	(segment
		(start 115.18011 -30.705298)
		(end 115.002564 -30.527752)
		(width 0.14224)
		(layer "In2.Cu")
		(net "M_G_DQS_DN<14>")
	)
	(segment
		(start 123.807982 -25.99944)
		(end 124.445268 -25.99944)
		(width 0.14224)
		(layer "In2.Cu")
		(net "M_G_DQS_DN<14>")
	)
	(segment
		(start 127.843788 -17.60728)
		(end 127.59436 -17.60728)
		(width 0.14224)
		(layer "In2.Cu")
		(net "M_G_DQS_DN<14>")
	)
	(segment
		(start 109.256068 -38.3794)
		(end 109.141768 -38.2651)
		(width 0.14224)
		(layer "In2.Cu")
		(net "M_G_DQS_DN<14>")
	)
	(segment
		(start 118.387368 -27.85364)
		(end 118.651528 -28.1178)
		(width 0.14224)
		(layer "In2.Cu")
		(net "M_G_DQS_DN<14>")
	)
	(segment
		(start 109.256068 -42.1894)
		(end 109.141768 -42.0751)
		(width 0.14224)
		(layer "In2.Cu")
		(net "M_G_DQS_DN<14>")
	)
	(segment
		(start 122.36958 -27.437842)
		(end 122.531378 -27.437842)
		(width 0.14224)
		(layer "In2.Cu")
		(net "M_G_DQS_DN<14>")
	)
	(segment
		(start 113.860834 -32.466534)
		(end 113.860834 -32.024574)
		(width 0.14224)
		(layer "In2.Cu")
		(net "M_G_DQS_DN<14>")
	)
	(segment
		(start 112.258602 -34.195766)
		(end 112.258602 -33.753806)
		(width 0.14224)
		(layer "In2.Cu")
		(net "M_G_DQS_DN<14>")
	)
	(segment
		(start 109.141768 -41.3385)
		(end 109.141768 -41.085008)
		(width 0.14224)
		(layer "In2.Cu")
		(net "M_G_DQS_DN<14>")
	)
	(segment
		(start 127.392176 -22.8346)
		(end 128.1811 -22.045676)
		(width 0.14224)
		(layer "In2.Cu")
		(net "M_G_DQS_DN<14>")
	)
	(segment
		(start 127.59436 -17.60728)
		(end 127.39878 -17.4117)
		(width 0.14224)
		(layer "In2.Cu")
		(net "M_G_DQS_DN<14>")
	)
	(segment
		(start 112.017556 -33.293812)
		(end 112.613948 -32.69742)
		(width 0.14224)
		(layer "In2.Cu")
		(net "M_G_DQS_DN<14>")
	)
	(segment
		(start 109.141768 -44.2849)
		(end 109.141768 -44.0309)
		(width 0.14224)
		(layer "In2.Cu")
		(net "M_G_DQS_DN<14>")
	)
	(segment
		(start 111.85017 -34.604198)
		(end 112.258602 -34.195766)
		(width 0.14224)
		(layer "In2.Cu")
		(net "M_G_DQS_DN<14>")
	)
	(segment
		(start 110.69828 -34.832036)
		(end 110.69828 -34.613088)
		(width 0.14224)
		(layer "In2.Cu")
		(net "M_G_DQS_DN<14>")
	)
	(segment
		(start 110.948216 -34.363152)
		(end 111.167164 -34.363152)
		(width 0.14224)
		(layer "In2.Cu")
		(net "M_G_DQS_DN<14>")
	)
	(segment
		(start 127.83058 -23.273004)
		(end 127.392176 -22.8346)
		(width 0.14224)
		(layer "In2.Cu")
		(net "M_G_DQS_DN<14>")
	)
	(segment
		(start 113.933224 -31.378144)
		(end 114.152172 -31.378144)
		(width 0.14224)
		(layer "In2.Cu")
		(net "M_G_DQS_DN<14>")
	)
	(segment
		(start 114.771678 -31.55569)
		(end 115.18011 -31.147258)
		(width 0.14224)
		(layer "In2.Cu")
		(net "M_G_DQS_DN<14>")
	)
	(segment
		(start 109.256068 -40.7162)
		(end 109.141768 -40.6019)
		(width 0.14224)
		(layer "In2.Cu")
		(net "M_G_DQS_DN<14>")
	)
	(segment
		(start 109.141768 -38.7477)
		(end 109.256068 -38.6334)
		(width 0.14224)
		(layer "In2.Cu")
		(net "M_G_DQS_DN<14>")
	)
	(segment
		(start 109.256068 -41.4528)
		(end 109.141768 -41.3385)
		(width 0.14224)
		(layer "In2.Cu")
		(net "M_G_DQS_DN<14>")
	)
	(segment
		(start 113.683288 -31.847028)
		(end 113.683288 -31.62808)
		(width 0.14224)
		(layer "In2.Cu")
		(net "M_G_DQS_DN<14>")
	)
	(segment
		(start 111.094774 -52.977542)
		(end 110.355126 -52.237894)
		(width 0.0889)
		(layer "In2.Cu")
		(net "M_G_DQS_DN<14>")
	)
	(segment
		(start 114.329718 -31.55569)
		(end 114.771678 -31.55569)
		(width 0.14224)
		(layer "In2.Cu")
		(net "M_G_DQS_DN<14>")
	)
	(segment
		(start 109.296708 -50.076608)
		(end 109.296708 -47.102268)
		(width 0.0889)
		(layer "In2.Cu")
		(net "M_G_DQS_DN<14>")
	)
	(segment
		(start 112.258602 -33.753806)
		(end 112.017556 -33.51276)
		(width 0.14224)
		(layer "In2.Cu")
		(net "M_G_DQS_DN<14>")
	)
	(segment
		(start 127.16002 -25.30602)
		(end 127.16002 -24.8412)
		(width 0.14224)
		(layer "In2.Cu")
		(net "M_G_DQS_DN<14>")
	)
	(segment
		(start 111.40821 -34.604198)
		(end 111.85017 -34.604198)
		(width 0.14224)
		(layer "In2.Cu")
		(net "M_G_DQS_DN<14>")
	)
	(segment
		(start 109.141768 -44.0309)
		(end 109.256068 -43.9166)
		(width 0.14224)
		(layer "In2.Cu")
		(net "M_G_DQS_DN<14>")
	)
	(segment
		(start 109.256068 -43.6626)
		(end 109.141768 -43.5483)
		(width 0.14224)
		(layer "In2.Cu")
		(net "M_G_DQS_DN<14>")
	)
	(segment
		(start 115.18011 -31.147258)
		(end 115.18011 -30.705298)
		(width 0.14224)
		(layer "In2.Cu")
		(net "M_G_DQS_DN<14>")
	)
	(segment
		(start 120.434608 -28.1178)
		(end 120.698768 -27.85364)
		(width 0.14224)
		(layer "In2.Cu")
		(net "M_G_DQS_DN<14>")
	)
	(segment
		(start 110.939326 -35.073082)
		(end 110.69828 -34.832036)
		(width 0.14224)
		(layer "In2.Cu")
		(net "M_G_DQS_DN<14>")
	)
	(segment
		(start 109.256068 -45.3898)
		(end 109.256068 -45.1358)
		(width 0.14224)
		(layer "In2.Cu")
		(net "M_G_DQS_DN<14>")
	)
	(segment
		(start 110.088934 -35.923474)
		(end 110.530894 -35.923474)
		(width 0.14224)
		(layer "In2.Cu")
		(net "M_G_DQS_DN<14>")
	)
	(segment
		(start 109.141768 -42.0751)
		(end 109.141768 -41.8211)
		(width 0.14224)
		(layer "In2.Cu")
		(net "M_G_DQS_DN<14>")
	)
	(segment
		(start 127.27432 -24.7269)
		(end 127.27432 -24.4729)
		(width 0.14224)
		(layer "In2.Cu")
		(net "M_G_DQS_DN<14>")
	)
	(segment
		(start 109.62894 -35.682428)
		(end 109.847888 -35.682428)
		(width 0.14224)
		(layer "In2.Cu")
		(net "M_G_DQS_DN<14>")
	)
	(segment
		(start 110.355126 -52.237894)
		(end 110.355126 -51.135026)
		(width 0.0889)
		(layer "In2.Cu")
		(net "M_G_DQS_DN<14>")
	)
	(segment
		(start 109.141768 -38.2651)
		(end 109.141768 -36.1696)
		(width 0.14224)
		(layer "In2.Cu")
		(net "M_G_DQS_DN<14>")
	)
	(segment
		(start 128.1811 -17.944592)
		(end 127.843788 -17.60728)
		(width 0.14224)
		(layer "In2.Cu")
		(net "M_G_DQS_DN<14>")
	)
	(segment
		(start 122.531378 -27.437842)
		(end 122.71121 -27.25801)
		(width 0.14224)
		(layer "In2.Cu")
		(net "M_G_DQS_DN<14>")
	)
	(segment
		(start 109.141768 -46.51629)
		(end 109.141768 -46.2407)
		(width 0.14224)
		(layer "In2.Cu")
		(net "M_G_DQS_DN<14>")
	)
	(segment
		(start 109.141768 -40.3479)
		(end 109.256068 -40.2336)
		(width 0.14224)
		(layer "In2.Cu")
		(net "M_G_DQS_DN<14>")
	)
	(segment
		(start 110.530894 -35.923474)
		(end 110.939326 -35.515042)
		(width 0.14224)
		(layer "In2.Cu")
		(net "M_G_DQS_DN<14>")
	)
	(segment
		(start 111.47552 -55.085996)
		(end 111.36249 -54.749446)
		(width 0.0889)
		(layer "In2.Cu")
		(net "M_G_DQS_DN<14>")
	)
	(segment
		(start 117.457728 -27.85364)
		(end 118.387368 -27.85364)
		(width 0.14224)
		(layer "In2.Cu")
		(net "M_G_DQS_DN<14>")
	)
	(segment
		(start 109.141768 -43.2943)
		(end 109.256068 -43.18)
		(width 0.14224)
		(layer "In2.Cu")
		(net "M_G_DQS_DN<14>")
	)
	(segment
		(start 112.832896 -32.69742)
		(end 113.010442 -32.874966)
		(width 0.14224)
		(layer "In2.Cu")
		(net "M_G_DQS_DN<14>")
	)
	(segment
		(start 109.256068 -38.6334)
		(end 109.256068 -38.3794)
		(width 0.14224)
		(layer "In2.Cu")
		(net "M_G_DQS_DN<14>")
	)
	(segment
		(start 111.281464 -54.61381)
		(end 111.279432 -54.610254)
		(width 0.0889)
		(layer "In2.Cu")
		(net "M_G_DQS_DN<14>")
	)
	(segment
		(start 109.256068 -45.1358)
		(end 109.141768 -45.0215)
		(width 0.14224)
		(layer "In2.Cu")
		(net "M_G_DQS_DN<14>")
	)
	(segment
		(start 111.36249 -54.749446)
		(end 111.281464 -54.61381)
		(width 0.0889)
		(layer "In2.Cu")
		(net "M_G_DQS_DN<14>")
	)
	(segment
		(start 121.953782 -27.85364)
		(end 122.36958 -27.437842)
		(width 0.14224)
		(layer "In2.Cu")
		(net "M_G_DQS_DN<14>")
	)
	(segment
		(start 111.094774 -53.299106)
		(end 111.094774 -52.977542)
		(width 0.0889)
		(layer "In2.Cu")
		(net "M_G_DQS_DN<14>")
	)
	(segment
		(start 109.141768 -41.8211)
		(end 109.256068 -41.7068)
		(width 0.14224)
		(layer "In2.Cu")
		(net "M_G_DQS_DN<14>")
	)
	(segment
		(start 111.279432 -54.610254)
		(end 111.279686 -54.61)
		(width 0.0889)
		(layer "In2.Cu")
		(net "M_G_DQS_DN<14>")
	)
	(segment
		(start 109.256068 -42.926)
		(end 109.141768 -42.8117)
		(width 0.14224)
		(layer "In2.Cu")
		(net "M_G_DQS_DN<14>")
	)
	(segment
		(start 109.141768 -39.5097)
		(end 109.256068 -39.3954)
		(width 0.14224)
		(layer "In2.Cu")
		(net "M_G_DQS_DN<14>")
	)
	(segment
		(start 113.010442 -32.874966)
		(end 113.452402 -32.874966)
		(width 0.14224)
		(layer "In2.Cu")
		(net "M_G_DQS_DN<14>")
	)
	(segment
		(start 127.16002 -24.1046)
		(end 127.26162 -24.003)
		(width 0.14224)
		(layer "In2.Cu")
		(net "M_G_DQS_DN<14>")
	)
	(segment
		(start 109.256068 -43.18)
		(end 109.256068 -42.926)
		(width 0.14224)
		(layer "In2.Cu")
		(net "M_G_DQS_DN<14>")
	)
	(segment
		(start 109.141768 -36.1696)
		(end 109.62894 -35.682428)
		(width 0.14224)
		(layer "In2.Cu")
		(net "M_G_DQS_DN<14>")
	)
	(segment
		(start 122.71121 -27.096212)
		(end 123.807982 -25.99944)
		(width 0.14224)
		(layer "In2.Cu")
		(net "M_G_DQS_DN<14>")
	)
	(segment
		(start 124.559568 -26.11374)
		(end 124.813568 -26.11374)
		(width 0.14224)
		(layer "In2.Cu")
		(net "M_G_DQS_DN<14>")
	)
	(segment
		(start 110.355126 -51.135026)
		(end 109.296708 -50.076608)
		(width 0.0889)
		(layer "In2.Cu")
		(net "M_G_DQS_DN<14>")
	)
	(segment
		(start 115.002564 -30.527752)
		(end 115.002564 -30.308804)
		(width 0.14224)
		(layer "In2.Cu")
		(net "M_G_DQS_DN<14>")
	)
	(segment
		(start 109.141768 -44.7675)
		(end 109.256068 -44.6532)
		(width 0.14224)
		(layer "In2.Cu")
		(net "M_G_DQS_DN<14>")
	)
	(segment
		(start 111.284512 -53.628036)
		(end 111.094774 -53.299106)
		(width 0.0889)
		(layer "In2.Cu")
		(net "M_G_DQS_DN<14>")
	)
	(segment
		(start 109.256068 -40.970708)
		(end 109.256068 -40.7162)
		(width 0.14224)
		(layer "In2.Cu")
		(net "M_G_DQS_DN<14>")
	)
	(segment
		(start 127.490728 -24.003)
		(end 127.83058 -23.663148)
		(width 0.14224)
		(layer "In2.Cu")
		(net "M_G_DQS_DN<14>")
	)
	(segment
		(start 109.141768 -43.5483)
		(end 109.141768 -43.2943)
		(width 0.14224)
		(layer "In2.Cu")
		(net "M_G_DQS_DN<14>")
	)
	(segment
		(start 109.256068 -45.8724)
		(end 109.141768 -45.7581)
		(width 0.14224)
		(layer "In2.Cu")
		(net "M_G_DQS_DN<14>")
	)
	(segment
		(start 110.939326 -35.515042)
		(end 110.939326 -35.073082)
		(width 0.14224)
		(layer "In2.Cu")
		(net "M_G_DQS_DN<14>")
	)
	(segment
		(start 109.256068 -39.9796)
		(end 109.141768 -39.8653)
		(width 0.14224)
		(layer "In2.Cu")
		(net "M_G_DQS_DN<14>")
	)
	(segment
		(start 112.017556 -33.51276)
		(end 112.017556 -33.293812)
		(width 0.14224)
		(layer "In2.Cu")
		(net "M_G_DQS_DN<14>")
	)
	(segment
		(start 124.445268 -25.99944)
		(end 124.559568 -26.11374)
		(width 0.14224)
		(layer "In2.Cu")
		(net "M_G_DQS_DN<14>")
	)
	(segment
		(start 109.141768 -45.5041)
		(end 109.256068 -45.3898)
		(width 0.14224)
		(layer "In2.Cu")
		(net "M_G_DQS_DN<14>")
	)
	(segment
		(start 109.256068 -40.2336)
		(end 109.256068 -39.9796)
		(width 0.14224)
		(layer "In2.Cu")
		(net "M_G_DQS_DN<14>")
	)
	(segment
		(start 127.27432 -24.4729)
		(end 127.16002 -24.3586)
		(width 0.14224)
		(layer "In2.Cu")
		(net "M_G_DQS_DN<14>")
	)
	(segment
		(start 113.860834 -32.024574)
		(end 113.683288 -31.847028)
		(width 0.14224)
		(layer "In2.Cu")
		(net "M_G_DQS_DN<14>")
	)
	(segment
		(start 109.256068 -42.4434)
		(end 109.256068 -42.1894)
		(width 0.14224)
		(layer "In2.Cu")
		(net "M_G_DQS_DN<14>")
	)
	(segment
		(start 113.683288 -31.62808)
		(end 113.933224 -31.378144)
		(width 0.14224)
		(layer "In2.Cu")
		(net "M_G_DQS_DN<14>")
	)
	(segment
		(start 109.296708 -47.102268)
		(end 109.336078 -47.062898)
		(width 0.0889)
		(layer "In2.Cu")
		(net "M_G_DQS_DN<14>")
	)
	(segment
		(start 109.847888 -35.682428)
		(end 110.088934 -35.923474)
		(width 0.14224)
		(layer "In2.Cu")
		(net "M_G_DQS_DN<14>")
	)
	(segment
		(start 111.167164 -34.363152)
		(end 111.40821 -34.604198)
		(width 0.14224)
		(layer "In2.Cu")
		(net "M_G_DQS_DN<14>")
	)
	(segment
		(start 115.002564 -30.308804)
		(end 117.457728 -27.85364)
		(width 0.14224)
		(layer "In2.Cu")
		(net "M_G_DQS_DN<14>")
	)
	(segment
		(start 113.452402 -32.874966)
		(end 113.860834 -32.466534)
		(width 0.14224)
		(layer "In2.Cu")
		(net "M_G_DQS_DN<14>")
	)
	(segment
		(start 109.141768 -45.7581)
		(end 109.141768 -45.5041)
		(width 0.14224)
		(layer "In2.Cu")
		(net "M_G_DQS_DN<14>")
	)
	(segment
		(start 109.256068 -39.1414)
		(end 109.141768 -39.0271)
		(width 0.14224)
		(layer "In2.Cu")
		(net "M_G_DQS_DN<14>")
	)
	(segment
		(start 126.4666 -25.99944)
		(end 127.16002 -25.30602)
		(width 0.14224)
		(layer "In2.Cu")
		(net "M_G_DQS_DN<14>")
	)
	(segment
		(start 109.141768 -41.085008)
		(end 109.256068 -40.970708)
		(width 0.14224)
		(layer "In2.Cu")
		(net "M_G_DQS_DN<14>")
	)
	(segment
		(start 109.141768 -46.2407)
		(end 109.256068 -46.1264)
		(width 0.14224)
		(layer "In2.Cu")
		(net "M_G_DQS_DN<14>")
	)
	(segment
		(start 128.1811 -22.045676)
		(end 128.1811 -17.944592)
		(width 0.14224)
		(layer "In2.Cu")
		(net "M_G_DQS_DN<14>")
	)
	(segment
		(start 127.83058 -23.663148)
		(end 127.83058 -23.273004)
		(width 0.14224)
		(layer "In2.Cu")
		(net "M_G_DQS_DN<14>")
	)
	(segment
		(start 109.256068 -39.3954)
		(end 109.256068 -39.1414)
		(width 0.14224)
		(layer "In2.Cu")
		(net "M_G_DQS_DN<14>")
	)
	(segment
		(start 109.256068 -41.7068)
		(end 109.256068 -41.4528)
		(width 0.14224)
		(layer "In2.Cu")
		(net "M_G_DQS_DN<14>")
	)
	(segment
		(start 112.613948 -32.69742)
		(end 112.832896 -32.69742)
		(width 0.14224)
		(layer "In2.Cu")
		(net "M_G_DQS_DN<14>")
	)
	(segment
		(start 127.26162 -24.003)
		(end 127.490728 -24.003)
		(width 0.14224)
		(layer "In2.Cu")
		(net "M_G_DQS_DN<14>")
	)
	(segment
		(start 124.813568 -26.11374)
		(end 124.927868 -25.99944)
		(width 0.14224)
		(layer "In2.Cu")
		(net "M_G_DQS_DN<14>")
	)
	(segment
		(start 109.256068 -44.6532)
		(end 109.256068 -44.3992)
		(width 0.14224)
		(layer "In2.Cu")
		(net "M_G_DQS_DN<14>")
	)
	(segment
		(start 109.141768 -40.6019)
		(end 109.141768 -40.3479)
		(width 0.14224)
		(layer "In2.Cu")
		(net "M_G_DQS_DN<14>")
	)
	(arc
		(start 111.279686 -54.61)
		(mid 111.231054 -54.413792)
		(end 111.284512 -54.21884)
		(width 0.0889)
		(layer "In2.Cu")
		(net "M_G_DQS_DN<14>")
	)
	(arc
		(start 111.284512 -54.21884)
		(mid 111.363575 -53.923438)
		(end 111.284512 -53.628036)
		(width 0.0889)
		(layer "In2.Cu")
		(net "M_G_DQS_DN<14>")
	)
	(segment
		(start 112.051846 -34.238692)
		(end 112.42675 -33.863788)
		(width 0.1651)
		(layer "F.Cu")
		(net "M_G_DQS_DN<13>")
	)
	(segment
		(start 111.591852 -35.617658)
		(end 112.138206 -35.071304)
		(width 0.1651)
		(layer "F.Cu")
		(net "M_G_DQS_DN<13>")
	)
	(segment
		(start 110.007654 -36.53409)
		(end 110.007654 -36.354258)
		(width 0.1651)
		(layer "F.Cu")
		(net "M_G_DQS_DN<13>")
	)
	(segment
		(start 114.346228 -32.196278)
		(end 114.432588 -32.282638)
		(width 0.1651)
		(layer "F.Cu")
		(net "M_G_DQS_DN<13>")
	)
	(segment
		(start 108.768896 -51.778408)
		(end 108.70565 -51.841654)
		(width 0.0889)
		(layer "F.Cu")
		(net "M_G_DQS_DN<13>")
	)
	(segment
		(start 113.719356 -32.82315)
		(end 113.719356 -32.571182)
		(width 0.1651)
		(layer "F.Cu")
		(net "M_G_DQS_DN<13>")
	)
	(segment
		(start 109.389926 -36.971986)
		(end 109.648244 -36.713668)
		(width 0.1651)
		(layer "F.Cu")
		(net "M_G_DQS_DN<13>")
	)
	(segment
		(start 118.491762 -22.9997)
		(end 118.326662 -22.8346)
		(width 0.1651)
		(layer "F.Cu")
		(net "M_G_DQS_DN<13>")
	)
	(segment
		(start 113.805716 -33.403794)
		(end 113.805716 -32.90951)
		(width 0.1651)
		(layer "F.Cu")
		(net "M_G_DQS_DN<13>")
	)
	(segment
		(start 118.067582 -17.4117)
		(end 118.048532 -17.4117)
		(width 0.1651)
		(layer "F.Cu")
		(net "M_G_DQS_DN<13>")
	)
	(segment
		(start 108.519722 -37.84219)
		(end 109.030516 -37.331396)
		(width 0.1651)
		(layer "F.Cu")
		(net "M_G_DQS_DN<13>")
	)
	(segment
		(start 108.500672 -49.902618)
		(end 108.590842 -49.812448)
		(width 0.0889)
		(layer "F.Cu")
		(net "M_G_DQS_DN<13>")
	)
	(segment
		(start 110.007654 -36.354258)
		(end 110.744254 -35.617658)
		(width 0.1651)
		(layer "F.Cu")
		(net "M_G_DQS_DN<13>")
	)
	(segment
		(start 115.386866 -31.15564)
		(end 115.386866 -30.903672)
		(width 0.1651)
		(layer "F.Cu")
		(net "M_G_DQS_DN<13>")
	)
	(segment
		(start 112.138206 -35.071304)
		(end 112.138206 -34.57702)
		(width 0.1651)
		(layer "F.Cu")
		(net "M_G_DQS_DN<13>")
	)
	(segment
		(start 109.030516 -37.331396)
		(end 109.210094 -37.331396)
		(width 0.1651)
		(layer "F.Cu")
		(net "M_G_DQS_DN<13>")
	)
	(segment
		(start 118.94947 -16.07693)
		(end 118.531132 -16.495268)
		(width 0.1651)
		(layer "F.Cu")
		(net "M_G_DQS_DN<13>")
	)
	(segment
		(start 113.719356 -32.571182)
		(end 114.09426 -32.196278)
		(width 0.1651)
		(layer "F.Cu")
		(net "M_G_DQS_DN<13>")
	)
	(segment
		(start 108.500672 -50.95875)
		(end 108.500672 -50.6222)
		(width 0.0889)
		(layer "F.Cu")
		(net "M_G_DQS_DN<13>")
	)
	(segment
		(start 112.765078 -33.950148)
		(end 113.259362 -33.950148)
		(width 0.1651)
		(layer "F.Cu")
		(net "M_G_DQS_DN<13>")
	)
	(segment
		(start 118.71706 -17.102328)
		(end 118.71706 -17.348962)
		(width 0.1651)
		(layer "F.Cu")
		(net "M_G_DQS_DN<13>")
	)
	(segment
		(start 108.519722 -40.4114)
		(end 108.519722 -40.350694)
		(width 0.1016)
		(layer "F.Cu")
		(net "M_G_DQS_DN<13>")
	)
	(segment
		(start 117.003068 -28.079446)
		(end 117.003068 -27.553158)
		(width 0.1651)
		(layer "F.Cu")
		(net "M_G_DQS_DN<13>")
	)
	(segment
		(start 108.602272 -50.5206)
		(end 108.602272 -50.3682)
		(width 0.0889)
		(layer "F.Cu")
		(net "M_G_DQS_DN<13>")
	)
	(segment
		(start 118.71706 -17.348962)
		(end 118.465092 -17.60093)
		(width 0.1651)
		(layer "F.Cu")
		(net "M_G_DQS_DN<13>")
	)
	(segment
		(start 117.206268 -28.282646)
		(end 117.003068 -28.079446)
		(width 0.1651)
		(layer "F.Cu")
		(net "M_G_DQS_DN<13>")
	)
	(segment
		(start 115.386866 -30.903672)
		(end 115.76177 -30.528768)
		(width 0.1651)
		(layer "F.Cu")
		(net "M_G_DQS_DN<13>")
	)
	(segment
		(start 110.744254 -35.617658)
		(end 111.591852 -35.617658)
		(width 0.1651)
		(layer "F.Cu")
		(net "M_G_DQS_DN<13>")
	)
	(segment
		(start 118.531132 -16.495268)
		(end 118.531132 -16.9164)
		(width 0.1651)
		(layer "F.Cu")
		(net "M_G_DQS_DN<13>")
	)
	(segment
		(start 108.500672 -50.6222)
		(end 108.602272 -50.5206)
		(width 0.0889)
		(layer "F.Cu")
		(net "M_G_DQS_DN<13>")
	)
	(segment
		(start 115.76177 -30.528768)
		(end 116.013738 -30.528768)
		(width 0.1651)
		(layer "F.Cu")
		(net "M_G_DQS_DN<13>")
	)
	(segment
		(start 112.678718 -33.863788)
		(end 112.765078 -33.950148)
		(width 0.1651)
		(layer "F.Cu")
		(net "M_G_DQS_DN<13>")
	)
	(segment
		(start 109.210094 -37.331396)
		(end 109.389926 -37.151564)
		(width 0.1651)
		(layer "F.Cu")
		(net "M_G_DQS_DN<13>")
	)
	(segment
		(start 112.42675 -33.863788)
		(end 112.678718 -33.863788)
		(width 0.1651)
		(layer "F.Cu")
		(net "M_G_DQS_DN<13>")
	)
	(segment
		(start 108.768896 -51.446938)
		(end 108.768896 -51.778408)
		(width 0.0889)
		(layer "F.Cu")
		(net "M_G_DQS_DN<13>")
	)
	(segment
		(start 108.602272 -50.3682)
		(end 108.500672 -50.2666)
		(width 0.0889)
		(layer "F.Cu")
		(net "M_G_DQS_DN<13>")
	)
	(segment
		(start 118.94947 -15.423642)
		(end 118.94947 -16.07693)
		(width 0.1651)
		(layer "F.Cu")
		(net "M_G_DQS_DN<13>")
	)
	(segment
		(start 114.09426 -32.196278)
		(end 114.346228 -32.196278)
		(width 0.1651)
		(layer "F.Cu")
		(net "M_G_DQS_DN<13>")
	)
	(segment
		(start 108.500672 -50.2666)
		(end 108.500672 -49.902618)
		(width 0.0889)
		(layer "F.Cu")
		(net "M_G_DQS_DN<13>")
	)
	(segment
		(start 108.519722 -40.350694)
		(end 108.519722 -37.84219)
		(width 0.1651)
		(layer "F.Cu")
		(net "M_G_DQS_DN<13>")
	)
	(segment
		(start 114.432588 -32.282638)
		(end 114.926872 -32.282638)
		(width 0.1651)
		(layer "F.Cu")
		(net "M_G_DQS_DN<13>")
	)
	(segment
		(start 109.389926 -37.151564)
		(end 109.389926 -36.971986)
		(width 0.1651)
		(layer "F.Cu")
		(net "M_G_DQS_DN<13>")
	)
	(segment
		(start 117.81028 -24.1554)
		(end 118.031768 -24.1554)
		(width 0.1651)
		(layer "F.Cu")
		(net "M_G_DQS_DN<13>")
	)
	(segment
		(start 114.926872 -32.282638)
		(end 115.473226 -31.736284)
		(width 0.1651)
		(layer "F.Cu")
		(net "M_G_DQS_DN<13>")
	)
	(segment
		(start 118.326662 -22.8346)
		(end 118.041928 -22.8346)
		(width 0.1651)
		(layer "F.Cu")
		(net "M_G_DQS_DN<13>")
	)
	(segment
		(start 118.256812 -17.60093)
		(end 118.067582 -17.4117)
		(width 0.1651)
		(layer "F.Cu")
		(net "M_G_DQS_DN<13>")
	)
	(segment
		(start 108.590842 -49.812448)
		(end 108.590842 -40.48252)
		(width 0.1016)
		(layer "F.Cu")
		(net "M_G_DQS_DN<13>")
	)
	(segment
		(start 118.465092 -17.60093)
		(end 118.256812 -17.60093)
		(width 0.1651)
		(layer "F.Cu")
		(net "M_G_DQS_DN<13>")
	)
	(segment
		(start 118.531132 -16.9164)
		(end 118.71706 -17.102328)
		(width 0.1651)
		(layer "F.Cu")
		(net "M_G_DQS_DN<13>")
	)
	(segment
		(start 115.473226 -31.736284)
		(end 115.473226 -31.242)
		(width 0.1651)
		(layer "F.Cu")
		(net "M_G_DQS_DN<13>")
	)
	(segment
		(start 117.206268 -30.003242)
		(end 117.206268 -28.282646)
		(width 0.1651)
		(layer "F.Cu")
		(net "M_G_DQS_DN<13>")
	)
	(segment
		(start 108.391706 -51.148742)
		(end 108.500672 -50.95875)
		(width 0.0889)
		(layer "F.Cu")
		(net "M_G_DQS_DN<13>")
	)
	(segment
		(start 117.003068 -27.553158)
		(end 117.676168 -26.880058)
		(width 0.1651)
		(layer "F.Cu")
		(net "M_G_DQS_DN<13>")
	)
	(segment
		(start 118.031768 -24.1554)
		(end 118.491762 -23.695406)
		(width 0.1651)
		(layer "F.Cu")
		(net "M_G_DQS_DN<13>")
	)
	(segment
		(start 116.013738 -30.528768)
		(end 116.100098 -30.615128)
		(width 0.1651)
		(layer "F.Cu")
		(net "M_G_DQS_DN<13>")
	)
	(segment
		(start 116.594382 -30.615128)
		(end 117.206268 -30.003242)
		(width 0.1651)
		(layer "F.Cu")
		(net "M_G_DQS_DN<13>")
	)
	(segment
		(start 112.138206 -34.57702)
		(end 112.051846 -34.49066)
		(width 0.1651)
		(layer "F.Cu")
		(net "M_G_DQS_DN<13>")
	)
	(segment
		(start 109.648244 -36.713668)
		(end 109.828076 -36.713668)
		(width 0.1651)
		(layer "F.Cu")
		(net "M_G_DQS_DN<13>")
	)
	(segment
		(start 113.805716 -32.90951)
		(end 113.719356 -32.82315)
		(width 0.1651)
		(layer "F.Cu")
		(net "M_G_DQS_DN<13>")
	)
	(segment
		(start 118.491762 -23.695406)
		(end 118.491762 -22.9997)
		(width 0.1651)
		(layer "F.Cu")
		(net "M_G_DQS_DN<13>")
	)
	(segment
		(start 116.100098 -30.615128)
		(end 116.594382 -30.615128)
		(width 0.1651)
		(layer "F.Cu")
		(net "M_G_DQS_DN<13>")
	)
	(segment
		(start 117.676168 -26.880058)
		(end 117.676168 -24.289512)
		(width 0.1651)
		(layer "F.Cu")
		(net "M_G_DQS_DN<13>")
	)
	(segment
		(start 117.676168 -24.289512)
		(end 117.81028 -24.1554)
		(width 0.1651)
		(layer "F.Cu")
		(net "M_G_DQS_DN<13>")
	)
	(segment
		(start 113.259362 -33.950148)
		(end 113.805716 -33.403794)
		(width 0.1651)
		(layer "F.Cu")
		(net "M_G_DQS_DN<13>")
	)
	(segment
		(start 112.051846 -34.49066)
		(end 112.051846 -34.238692)
		(width 0.1651)
		(layer "F.Cu")
		(net "M_G_DQS_DN<13>")
	)
	(segment
		(start 108.590842 -40.48252)
		(end 108.519722 -40.4114)
		(width 0.1016)
		(layer "F.Cu")
		(net "M_G_DQS_DN<13>")
	)
	(segment
		(start 108.391706 -51.527456)
		(end 108.391706 -51.148742)
		(width 0.0889)
		(layer "F.Cu")
		(net "M_G_DQS_DN<13>")
	)
	(segment
		(start 115.473226 -31.242)
		(end 115.386866 -31.15564)
		(width 0.1651)
		(layer "F.Cu")
		(net "M_G_DQS_DN<13>")
	)
	(segment
		(start 109.828076 -36.713668)
		(end 110.007654 -36.53409)
		(width 0.1651)
		(layer "F.Cu")
		(net "M_G_DQS_DN<13>")
	)
	(via
		(at 118.048532 -17.4117)
		(size 0.508)
		(drill 0.254)
		(layers "F.Cu" "B.Cu")
		(net "M_G_DQS_DN<13>")
	)
	(via
		(at 118.041928 -22.8346)
		(size 0.508)
		(drill 0.254)
		(layers "F.Cu" "B.Cu")
		(net "M_G_DQS_DN<13>")
	)
	(arc
		(start 108.428028 -51.65598)
		(mid 108.400941 -51.594239)
		(end 108.391706 -51.527456)
		(width 0.0889)
		(layer "F.Cu")
		(net "M_G_DQS_DN<13>")
	)
	(arc
		(start 108.70565 -51.841654)
		(mid 108.546569 -51.779134)
		(end 108.428028 -51.65598)
		(width 0.0889)
		(layer "F.Cu")
		(net "M_G_DQS_DN<13>")
	)
	(segment
		(start 118.94947 -24.824182)
		(end 118.94947 -24.167592)
		(width 0.1651)
		(layer "B.Cu")
		(net "M_G_DQS_DN<13>")
	)
	(segment
		(start 118.463568 -22.640036)
		(end 118.236492 -22.640036)
		(width 0.1651)
		(layer "B.Cu")
		(net "M_G_DQS_DN<13>")
	)
	(segment
		(start 118.683532 -23.1902)
		(end 118.683532 -22.86)
		(width 0.1651)
		(layer "B.Cu")
		(net "M_G_DQS_DN<13>")
	)
	(segment
		(start 118.236492 -22.640036)
		(end 118.041928 -22.8346)
		(width 0.1651)
		(layer "B.Cu")
		(net "M_G_DQS_DN<13>")
	)
	(segment
		(start 118.683532 -22.86)
		(end 118.463568 -22.640036)
		(width 0.1651)
		(layer "B.Cu")
		(net "M_G_DQS_DN<13>")
	)
	(segment
		(start 118.505732 -23.723854)
		(end 118.505732 -23.368)
		(width 0.1651)
		(layer "B.Cu")
		(net "M_G_DQS_DN<13>")
	)
	(segment
		(start 118.505732 -23.368)
		(end 118.683532 -23.1902)
		(width 0.1651)
		(layer "B.Cu")
		(net "M_G_DQS_DN<13>")
	)
	(segment
		(start 118.94947 -24.167592)
		(end 118.505732 -23.723854)
		(width 0.1651)
		(layer "B.Cu")
		(net "M_G_DQS_DN<13>")
	)
	(segment
		(start 118.041928 -22.8346)
		(end 118.830852 -22.045676)
		(width 0.14224)
		(layer "In2.Cu")
		(net "M_G_DQS_DN<13>")
	)
	(segment
		(start 118.244112 -17.60728)
		(end 118.048532 -17.4117)
		(width 0.14224)
		(layer "In2.Cu")
		(net "M_G_DQS_DN<13>")
	)
	(segment
		(start 118.830852 -22.045676)
		(end 118.830852 -17.944592)
		(width 0.14224)
		(layer "In2.Cu")
		(net "M_G_DQS_DN<13>")
	)
	(segment
		(start 118.830852 -17.944592)
		(end 118.49354 -17.60728)
		(width 0.14224)
		(layer "In2.Cu")
		(net "M_G_DQS_DN<13>")
	)
	(segment
		(start 118.49354 -17.60728)
		(end 118.244112 -17.60728)
		(width 0.14224)
		(layer "In2.Cu")
		(net "M_G_DQS_DN<13>")
	)
	(segment
		(start 62.817756 -17.4117)
		(end 62.798706 -17.4117)
		(width 0.1651)
		(layer "F.Cu")
		(net "M_G_DQS_DN<12>")
	)
	(segment
		(start 63.467234 -17.102328)
		(end 63.467234 -17.348962)
		(width 0.1651)
		(layer "F.Cu")
		(net "M_G_DQS_DN<12>")
	)
	(segment
		(start 63.281306 -16.9164)
		(end 63.467234 -17.102328)
		(width 0.1651)
		(layer "F.Cu")
		(net "M_G_DQS_DN<12>")
	)
	(segment
		(start 63.69939 -16.077184)
		(end 63.281306 -16.495268)
		(width 0.1651)
		(layer "F.Cu")
		(net "M_G_DQS_DN<12>")
	)
	(segment
		(start 63.69939 -15.423642)
		(end 63.69939 -16.077184)
		(width 0.1651)
		(layer "F.Cu")
		(net "M_G_DQS_DN<12>")
	)
	(segment
		(start 63.006986 -17.60093)
		(end 62.817756 -17.4117)
		(width 0.1651)
		(layer "F.Cu")
		(net "M_G_DQS_DN<12>")
	)
	(segment
		(start 63.281306 -16.495268)
		(end 63.281306 -16.9164)
		(width 0.1651)
		(layer "F.Cu")
		(net "M_G_DQS_DN<12>")
	)
	(segment
		(start 63.467234 -17.348962)
		(end 63.215266 -17.60093)
		(width 0.1651)
		(layer "F.Cu")
		(net "M_G_DQS_DN<12>")
	)
	(segment
		(start 77.192886 -54.104286)
		(end 76.621386 -54.104286)
		(width 0.1016)
		(layer "F.Cu")
		(net "M_G_DQS_DN<12>")
	)
	(segment
		(start 63.215266 -17.60093)
		(end 63.006986 -17.60093)
		(width 0.1651)
		(layer "F.Cu")
		(net "M_G_DQS_DN<12>")
	)
	(via
		(at 62.792102 -22.8346)
		(size 0.508)
		(drill 0.254)
		(layers "F.Cu" "B.Cu")
		(net "M_G_DQS_DN<12>")
	)
	(via
		(at 76.621386 -54.104286)
		(size 0.508)
		(drill 0.254)
		(layers "F.Cu" "B.Cu")
		(net "M_G_DQS_DN<12>")
	)
	(via
		(at 62.798706 -17.4117)
		(size 0.508)
		(drill 0.254)
		(layers "F.Cu" "B.Cu")
		(net "M_G_DQS_DN<12>")
	)
	(segment
		(start 63.69939 -24.824182)
		(end 63.699644 -24.823928)
		(width 0.1651)
		(layer "B.Cu")
		(net "M_G_DQS_DN<12>")
	)
	(segment
		(start 63.699644 -24.167592)
		(end 63.255906 -23.723854)
		(width 0.1651)
		(layer "B.Cu")
		(net "M_G_DQS_DN<12>")
	)
	(segment
		(start 63.433706 -22.86)
		(end 63.213742 -22.640036)
		(width 0.1651)
		(layer "B.Cu")
		(net "M_G_DQS_DN<12>")
	)
	(segment
		(start 63.213742 -22.640036)
		(end 62.986666 -22.640036)
		(width 0.1651)
		(layer "B.Cu")
		(net "M_G_DQS_DN<12>")
	)
	(segment
		(start 63.699644 -24.823928)
		(end 63.699644 -24.167592)
		(width 0.1651)
		(layer "B.Cu")
		(net "M_G_DQS_DN<12>")
	)
	(segment
		(start 63.255906 -23.723854)
		(end 63.255906 -23.368)
		(width 0.1651)
		(layer "B.Cu")
		(net "M_G_DQS_DN<12>")
	)
	(segment
		(start 63.255906 -23.368)
		(end 63.433706 -23.1902)
		(width 0.1651)
		(layer "B.Cu")
		(net "M_G_DQS_DN<12>")
	)
	(segment
		(start 63.433706 -23.1902)
		(end 63.433706 -22.86)
		(width 0.1651)
		(layer "B.Cu")
		(net "M_G_DQS_DN<12>")
	)
	(segment
		(start 62.986666 -22.640036)
		(end 62.792102 -22.8346)
		(width 0.1651)
		(layer "B.Cu")
		(net "M_G_DQS_DN<12>")
	)
	(segment
		(start 67.491356 -45.420788)
		(end 67.66306 -45.592492)
		(width 0.14224)
		(layer "In2.Cu")
		(net "M_G_DQS_DN<12>")
	)
	(segment
		(start 63.581026 -17.944592)
		(end 63.581026 -22.045676)
		(width 0.14224)
		(layer "In2.Cu")
		(net "M_G_DQS_DN<12>")
	)
	(segment
		(start 63.562484 -30.84068)
		(end 63.562484 -31.03372)
		(width 0.14224)
		(layer "In2.Cu")
		(net "M_G_DQS_DN<12>")
	)
	(segment
		(start 63.51905 -40.779192)
		(end 63.897256 -41.157398)
		(width 0.14224)
		(layer "In2.Cu")
		(net "M_G_DQS_DN<12>")
	)
	(segment
		(start 63.562484 -32.36468)
		(end 63.562484 -33.685988)
		(width 0.14224)
		(layer "In2.Cu")
		(net "M_G_DQS_DN<12>")
	)
	(segment
		(start 71.340472 -49.264824)
		(end 71.340472 -49.353724)
		(width 0.0889)
		(layer "In2.Cu")
		(net "M_G_DQS_DN<12>")
	)
	(segment
		(start 69.371718 -47.110142)
		(end 69.522086 -47.26051)
		(width 0.14224)
		(layer "In2.Cu")
		(net "M_G_DQS_DN<12>")
	)
	(segment
		(start 75.75169 -53.018436)
		(end 75.77582 -53.018436)
		(width 0.0889)
		(layer "In2.Cu")
		(net "M_G_DQS_DN<12>")
	)
	(segment
		(start 63.562484 -29.37002)
		(end 63.719964 -29.5275)
		(width 0.14224)
		(layer "In2.Cu")
		(net "M_G_DQS_DN<12>")
	)
	(segment
		(start 62.792102 -22.8346)
		(end 63.230506 -23.273004)
		(width 0.14224)
		(layer "In2.Cu")
		(net "M_G_DQS_DN<12>")
	)
	(segment
		(start 68.507356 -46.436788)
		(end 68.67779 -46.607222)
		(width 0.14224)
		(layer "In2.Cu")
		(net "M_G_DQS_DN<12>")
	)
	(segment
		(start 67.26428 -45.079412)
		(end 67.491356 -45.306488)
		(width 0.14224)
		(layer "In2.Cu")
		(net "M_G_DQS_DN<12>")
	)
	(segment
		(start 71.173848 -48.912272)
		(end 71.173848 -49.10328)
		(width 0.14224)
		(layer "In2.Cu")
		(net "M_G_DQS_DN<12>")
	)
	(segment
		(start 62.994286 -17.60728)
		(end 63.243714 -17.60728)
		(width 0.14224)
		(layer "In2.Cu")
		(net "M_G_DQS_DN<12>")
	)
	(segment
		(start 63.897256 -39.324026)
		(end 63.51905 -39.702232)
		(width 0.14224)
		(layer "In2.Cu")
		(net "M_G_DQS_DN<12>")
	)
	(segment
		(start 68.507356 -46.24578)
		(end 68.507356 -46.436788)
		(width 0.14224)
		(layer "In2.Cu")
		(net "M_G_DQS_DN<12>")
	)
	(segment
		(start 62.798706 -17.4117)
		(end 62.994286 -17.60728)
		(width 0.14224)
		(layer "In2.Cu")
		(net "M_G_DQS_DN<12>")
	)
	(segment
		(start 63.562484 -30.27172)
		(end 63.719964 -30.4292)
		(width 0.14224)
		(layer "In2.Cu")
		(net "M_G_DQS_DN<12>")
	)
	(segment
		(start 71.335392 -49.264824)
		(end 71.340472 -49.264824)
		(width 0.14224)
		(layer "In2.Cu")
		(net "M_G_DQS_DN<12>")
	)
	(segment
		(start 68.004436 -45.933868)
		(end 68.16598 -46.095412)
		(width 0.14224)
		(layer "In2.Cu")
		(net "M_G_DQS_DN<12>")
	)
	(segment
		(start 63.719964 -29.5275)
		(end 63.719964 -29.9212)
		(width 0.14224)
		(layer "In2.Cu")
		(net "M_G_DQS_DN<12>")
	)
	(segment
		(start 68.67779 -46.607222)
		(end 68.868798 -46.607222)
		(width 0.14224)
		(layer "In2.Cu")
		(net "M_G_DQS_DN<12>")
	)
	(segment
		(start 63.562484 -30.07868)
		(end 63.562484 -30.27172)
		(width 0.14224)
		(layer "In2.Cu")
		(net "M_G_DQS_DN<12>")
	)
	(segment
		(start 71.927212 -50.742088)
		(end 71.982076 -50.837338)
		(width 0.0889)
		(layer "In2.Cu")
		(net "M_G_DQS_DN<12>")
	)
	(segment
		(start 62.830456 -37.865304)
		(end 63.051944 -38.086792)
		(width 0.14224)
		(layer "In2.Cu")
		(net "M_G_DQS_DN<12>")
	)
	(segment
		(start 68.868798 -46.607222)
		(end 69.019166 -46.75759)
		(width 0.14224)
		(layer "In2.Cu")
		(net "M_G_DQS_DN<12>")
	)
	(segment
		(start 66.957956 -44.887388)
		(end 67.14998 -45.079412)
		(width 0.14224)
		(layer "In2.Cu")
		(net "M_G_DQS_DN<12>")
	)
	(segment
		(start 63.230506 -23.736808)
		(end 62.964314 -24.003)
		(width 0.14224)
		(layer "In2.Cu")
		(net "M_G_DQS_DN<12>")
	)
	(segment
		(start 63.719964 -30.4292)
		(end 63.719964 -30.6832)
		(width 0.14224)
		(layer "In2.Cu")
		(net "M_G_DQS_DN<12>")
	)
	(segment
		(start 70.025006 -47.76343)
		(end 70.025006 -47.954438)
		(width 0.14224)
		(layer "In2.Cu")
		(net "M_G_DQS_DN<12>")
	)
	(segment
		(start 70.408038 -48.146462)
		(end 70.558406 -48.29683)
		(width 0.14224)
		(layer "In2.Cu")
		(net "M_G_DQS_DN<12>")
	)
	(segment
		(start 63.897256 -38.464998)
		(end 63.897256 -39.324026)
		(width 0.14224)
		(layer "In2.Cu")
		(net "M_G_DQS_DN<12>")
	)
	(segment
		(start 62.830456 -40.557704)
		(end 63.051944 -40.779192)
		(width 0.14224)
		(layer "In2.Cu")
		(net "M_G_DQS_DN<12>")
	)
	(segment
		(start 71.927212 -49.940464)
		(end 71.927212 -50.742088)
		(width 0.0889)
		(layer "In2.Cu")
		(net "M_G_DQS_DN<12>")
	)
	(segment
		(start 74.027792 -52.027836)
		(end 74.063606 -52.027836)
		(width 0.0889)
		(layer "In2.Cu")
		(net "M_G_DQS_DN<12>")
	)
	(segment
		(start 62.830456 -39.92372)
		(end 62.830456 -40.557704)
		(width 0.14224)
		(layer "In2.Cu")
		(net "M_G_DQS_DN<12>")
	)
	(segment
		(start 71.02348 -48.761904)
		(end 71.173848 -48.912272)
		(width 0.14224)
		(layer "In2.Cu")
		(net "M_G_DQS_DN<12>")
	)
	(segment
		(start 63.897256 -41.826688)
		(end 66.61658 -44.546012)
		(width 0.14224)
		(layer "In2.Cu")
		(net "M_G_DQS_DN<12>")
	)
	(segment
		(start 63.051944 -39.702232)
		(end 62.830456 -39.92372)
		(width 0.14224)
		(layer "In2.Cu")
		(net "M_G_DQS_DN<12>")
	)
	(segment
		(start 68.004436 -45.74286)
		(end 68.004436 -45.933868)
		(width 0.14224)
		(layer "In2.Cu")
		(net "M_G_DQS_DN<12>")
	)
	(segment
		(start 66.75628 -44.546012)
		(end 66.957956 -44.747688)
		(width 0.14224)
		(layer "In2.Cu")
		(net "M_G_DQS_DN<12>")
	)
	(segment
		(start 69.522086 -47.26051)
		(end 69.522086 -47.451518)
		(width 0.14224)
		(layer "In2.Cu")
		(net "M_G_DQS_DN<12>")
	)
	(segment
		(start 62.964314 -24.003)
		(end 62.773306 -24.003)
		(width 0.14224)
		(layer "In2.Cu")
		(net "M_G_DQS_DN<12>")
	)
	(segment
		(start 63.581026 -22.045676)
		(end 62.792102 -22.8346)
		(width 0.14224)
		(layer "In2.Cu")
		(net "M_G_DQS_DN<12>")
	)
	(segment
		(start 63.230506 -23.273004)
		(end 63.230506 -23.736808)
		(width 0.14224)
		(layer "In2.Cu")
		(net "M_G_DQS_DN<12>")
	)
	(segment
		(start 63.051944 -38.086792)
		(end 63.51905 -38.086792)
		(width 0.14224)
		(layer "In2.Cu")
		(net "M_G_DQS_DN<12>")
	)
	(segment
		(start 63.562484 -33.685988)
		(end 63.643256 -33.76676)
		(width 0.14224)
		(layer "In2.Cu")
		(net "M_G_DQS_DN<12>")
	)
	(segment
		(start 63.719964 -29.9212)
		(end 63.562484 -30.07868)
		(width 0.14224)
		(layer "In2.Cu")
		(net "M_G_DQS_DN<12>")
	)
	(segment
		(start 63.719964 -30.6832)
		(end 63.562484 -30.84068)
		(width 0.14224)
		(layer "In2.Cu")
		(net "M_G_DQS_DN<12>")
	)
	(segment
		(start 63.719964 -31.1912)
		(end 63.719964 -31.4452)
		(width 0.14224)
		(layer "In2.Cu")
		(net "M_G_DQS_DN<12>")
	)
	(segment
		(start 69.019166 -46.75759)
		(end 69.019166 -46.948598)
		(width 0.14224)
		(layer "In2.Cu")
		(net "M_G_DQS_DN<12>")
	)
	(segment
		(start 67.14998 -45.079412)
		(end 67.26428 -45.079412)
		(width 0.14224)
		(layer "In2.Cu")
		(net "M_G_DQS_DN<12>")
	)
	(segment
		(start 70.21703 -48.146462)
		(end 70.408038 -48.146462)
		(width 0.14224)
		(layer "In2.Cu")
		(net "M_G_DQS_DN<12>")
	)
	(segment
		(start 66.61658 -44.546012)
		(end 66.75628 -44.546012)
		(width 0.14224)
		(layer "In2.Cu")
		(net "M_G_DQS_DN<12>")
	)
	(segment
		(start 63.719964 -31.9532)
		(end 63.719964 -32.2072)
		(width 0.14224)
		(layer "In2.Cu")
		(net "M_G_DQS_DN<12>")
	)
	(segment
		(start 62.590426 -24.609552)
		(end 63.562484 -25.58161)
		(width 0.14224)
		(layer "In2.Cu")
		(net "M_G_DQS_DN<12>")
	)
	(segment
		(start 63.51905 -39.702232)
		(end 63.051944 -39.702232)
		(width 0.14224)
		(layer "In2.Cu")
		(net "M_G_DQS_DN<12>")
	)
	(segment
		(start 69.522086 -47.451518)
		(end 69.68363 -47.613062)
		(width 0.14224)
		(layer "In2.Cu")
		(net "M_G_DQS_DN<12>")
	)
	(segment
		(start 70.025006 -47.954438)
		(end 70.21703 -48.146462)
		(width 0.14224)
		(layer "In2.Cu")
		(net "M_G_DQS_DN<12>")
	)
	(segment
		(start 63.51905 -38.086792)
		(end 63.897256 -38.464998)
		(width 0.14224)
		(layer "In2.Cu")
		(net "M_G_DQS_DN<12>")
	)
	(segment
		(start 63.243714 -17.60728)
		(end 63.581026 -17.944592)
		(width 0.14224)
		(layer "In2.Cu")
		(net "M_G_DQS_DN<12>")
	)
	(segment
		(start 66.957956 -44.747688)
		(end 66.957956 -44.887388)
		(width 0.14224)
		(layer "In2.Cu")
		(net "M_G_DQS_DN<12>")
	)
	(segment
		(start 68.356988 -46.095412)
		(end 68.507356 -46.24578)
		(width 0.14224)
		(layer "In2.Cu")
		(net "M_G_DQS_DN<12>")
	)
	(segment
		(start 70.558406 -48.29683)
		(end 70.558406 -48.487838)
		(width 0.14224)
		(layer "In2.Cu")
		(net "M_G_DQS_DN<12>")
	)
	(segment
		(start 69.18071 -47.110142)
		(end 69.371718 -47.110142)
		(width 0.14224)
		(layer "In2.Cu")
		(net "M_G_DQS_DN<12>")
	)
	(segment
		(start 69.68363 -47.613062)
		(end 69.874638 -47.613062)
		(width 0.14224)
		(layer "In2.Cu")
		(net "M_G_DQS_DN<12>")
	)
	(segment
		(start 68.16598 -46.095412)
		(end 68.356988 -46.095412)
		(width 0.14224)
		(layer "In2.Cu")
		(net "M_G_DQS_DN<12>")
	)
	(segment
		(start 71.173848 -49.10328)
		(end 71.335392 -49.264824)
		(width 0.14224)
		(layer "In2.Cu")
		(net "M_G_DQS_DN<12>")
	)
	(segment
		(start 71.340472 -49.353724)
		(end 71.927212 -49.940464)
		(width 0.0889)
		(layer "In2.Cu")
		(net "M_G_DQS_DN<12>")
	)
	(segment
		(start 63.562484 -31.79572)
		(end 63.719964 -31.9532)
		(width 0.14224)
		(layer "In2.Cu")
		(net "M_G_DQS_DN<12>")
	)
	(segment
		(start 63.29045 -37.009832)
		(end 63.051944 -37.009832)
		(width 0.14224)
		(layer "In2.Cu")
		(net "M_G_DQS_DN<12>")
	)
	(segment
		(start 63.562484 -25.58161)
		(end 63.562484 -29.37002)
		(width 0.14224)
		(layer "In2.Cu")
		(net "M_G_DQS_DN<12>")
	)
	(segment
		(start 70.832472 -48.761904)
		(end 71.02348 -48.761904)
		(width 0.14224)
		(layer "In2.Cu")
		(net "M_G_DQS_DN<12>")
	)
	(segment
		(start 63.643256 -33.76676)
		(end 63.643256 -36.657026)
		(width 0.14224)
		(layer "In2.Cu")
		(net "M_G_DQS_DN<12>")
	)
	(segment
		(start 73.17232 -51.532536)
		(end 73.20026 -51.532536)
		(width 0.0889)
		(layer "In2.Cu")
		(net "M_G_DQS_DN<12>")
	)
	(segment
		(start 62.830456 -37.23132)
		(end 62.830456 -37.865304)
		(width 0.14224)
		(layer "In2.Cu")
		(net "M_G_DQS_DN<12>")
	)
	(segment
		(start 63.719964 -32.2072)
		(end 63.562484 -32.36468)
		(width 0.14224)
		(layer "In2.Cu")
		(net "M_G_DQS_DN<12>")
	)
	(segment
		(start 72.31761 -51.03749)
		(end 72.350376 -51.03749)
		(width 0.0889)
		(layer "In2.Cu")
		(net "M_G_DQS_DN<12>")
	)
	(segment
		(start 63.643256 -36.657026)
		(end 63.29045 -37.009832)
		(width 0.14224)
		(layer "In2.Cu")
		(net "M_G_DQS_DN<12>")
	)
	(segment
		(start 67.854068 -45.592492)
		(end 68.004436 -45.74286)
		(width 0.14224)
		(layer "In2.Cu")
		(net "M_G_DQS_DN<12>")
	)
	(segment
		(start 70.558406 -48.487838)
		(end 70.832472 -48.761904)
		(width 0.14224)
		(layer "In2.Cu")
		(net "M_G_DQS_DN<12>")
	)
	(segment
		(start 63.897256 -41.157398)
		(end 63.897256 -41.826688)
		(width 0.14224)
		(layer "In2.Cu")
		(net "M_G_DQS_DN<12>")
	)
	(segment
		(start 62.773306 -24.003)
		(end 62.590426 -24.18588)
		(width 0.14224)
		(layer "In2.Cu")
		(net "M_G_DQS_DN<12>")
	)
	(segment
		(start 63.562484 -31.60268)
		(end 63.562484 -31.79572)
		(width 0.14224)
		(layer "In2.Cu")
		(net "M_G_DQS_DN<12>")
	)
	(segment
		(start 67.491356 -45.306488)
		(end 67.491356 -45.420788)
		(width 0.14224)
		(layer "In2.Cu")
		(net "M_G_DQS_DN<12>")
	)
	(segment
		(start 76.440284 -53.524912)
		(end 76.621386 -54.104286)
		(width 0.0889)
		(layer "In2.Cu")
		(net "M_G_DQS_DN<12>")
	)
	(segment
		(start 63.051944 -37.009832)
		(end 62.830456 -37.23132)
		(width 0.14224)
		(layer "In2.Cu")
		(net "M_G_DQS_DN<12>")
	)
	(segment
		(start 69.874638 -47.613062)
		(end 70.025006 -47.76343)
		(width 0.14224)
		(layer "In2.Cu")
		(net "M_G_DQS_DN<12>")
	)
	(segment
		(start 63.051944 -40.779192)
		(end 63.51905 -40.779192)
		(width 0.14224)
		(layer "In2.Cu")
		(net "M_G_DQS_DN<12>")
	)
	(segment
		(start 63.719964 -31.4452)
		(end 63.562484 -31.60268)
		(width 0.14224)
		(layer "In2.Cu")
		(net "M_G_DQS_DN<12>")
	)
	(segment
		(start 74.886312 -52.523136)
		(end 74.925936 -52.523136)
		(width 0.0889)
		(layer "In2.Cu")
		(net "M_G_DQS_DN<12>")
	)
	(segment
		(start 67.66306 -45.592492)
		(end 67.854068 -45.592492)
		(width 0.14224)
		(layer "In2.Cu")
		(net "M_G_DQS_DN<12>")
	)
	(segment
		(start 63.562484 -31.03372)
		(end 63.719964 -31.1912)
		(width 0.14224)
		(layer "In2.Cu")
		(net "M_G_DQS_DN<12>")
	)
	(segment
		(start 69.019166 -46.948598)
		(end 69.18071 -47.110142)
		(width 0.14224)
		(layer "In2.Cu")
		(net "M_G_DQS_DN<12>")
	)
	(segment
		(start 62.590426 -24.18588)
		(end 62.590426 -24.609552)
		(width 0.14224)
		(layer "In2.Cu")
		(net "M_G_DQS_DN<12>")
	)
	(arc
		(start 75.77582 -53.018436)
		(mid 76.063965 -53.100755)
		(end 76.274676 -53.313838)
		(width 0.0889)
		(layer "In2.Cu")
		(net "M_G_DQS_DN<12>")
	)
	(arc
		(start 75.416156 -52.818284)
		(mid 75.557839 -52.962088)
		(end 75.75169 -53.018436)
		(width 0.0889)
		(layer "In2.Cu")
		(net "M_G_DQS_DN<12>")
	)
	(arc
		(start 74.063606 -52.027836)
		(mid 74.34903 -52.111303)
		(end 74.557636 -52.323238)
		(width 0.0889)
		(layer "In2.Cu")
		(net "M_G_DQS_DN<12>")
	)
	(arc
		(start 76.274676 -53.313838)
		(mid 76.350005 -53.425238)
		(end 76.440284 -53.524912)
		(width 0.0889)
		(layer "In2.Cu")
		(net "M_G_DQS_DN<12>")
	)
	(arc
		(start 72.350376 -51.03749)
		(mid 72.633593 -51.121771)
		(end 72.840596 -51.332638)
		(width 0.0889)
		(layer "In2.Cu")
		(net "M_G_DQS_DN<12>")
	)
	(arc
		(start 74.557636 -52.323238)
		(mid 74.69638 -52.465271)
		(end 74.886312 -52.523136)
		(width 0.0889)
		(layer "In2.Cu")
		(net "M_G_DQS_DN<12>")
	)
	(arc
		(start 72.840596 -51.332638)
		(mid 72.980675 -51.475374)
		(end 73.17232 -51.532536)
		(width 0.0889)
		(layer "In2.Cu")
		(net "M_G_DQS_DN<12>")
	)
	(arc
		(start 74.925936 -52.523136)
		(mid 75.209153 -52.607417)
		(end 75.416156 -52.818284)
		(width 0.0889)
		(layer "In2.Cu")
		(net "M_G_DQS_DN<12>")
	)
	(arc
		(start 73.20026 -51.532536)
		(mid 73.488405 -51.614855)
		(end 73.699116 -51.827938)
		(width 0.0889)
		(layer "In2.Cu")
		(net "M_G_DQS_DN<12>")
	)
	(arc
		(start 71.982076 -50.837338)
		(mid 72.123759 -50.981142)
		(end 72.31761 -51.03749)
		(width 0.0889)
		(layer "In2.Cu")
		(net "M_G_DQS_DN<12>")
	)
	(arc
		(start 73.699116 -51.827938)
		(mid 73.83786 -51.969971)
		(end 74.027792 -52.027836)
		(width 0.0889)
		(layer "In2.Cu")
		(net "M_G_DQS_DN<12>")
	)
	(segment
		(start 53.656992 -17.60093)
		(end 53.467762 -17.4117)
		(width 0.1651)
		(layer "F.Cu")
		(net "M_G_DQS_DN<11>")
	)
	(segment
		(start 53.467762 -17.4117)
		(end 53.448712 -17.4117)
		(width 0.1651)
		(layer "F.Cu")
		(net "M_G_DQS_DN<11>")
	)
	(segment
		(start 53.931312 -16.495268)
		(end 53.931312 -16.9164)
		(width 0.1651)
		(layer "F.Cu")
		(net "M_G_DQS_DN<11>")
	)
	(segment
		(start 54.11724 -17.348962)
		(end 53.865272 -17.60093)
		(width 0.1651)
		(layer "F.Cu")
		(net "M_G_DQS_DN<11>")
	)
	(segment
		(start 71.183246 -57.57164)
		(end 70.611746 -57.57164)
		(width 0.1016)
		(layer "F.Cu")
		(net "M_G_DQS_DN<11>")
	)
	(segment
		(start 54.349396 -16.077184)
		(end 53.931312 -16.495268)
		(width 0.1651)
		(layer "F.Cu")
		(net "M_G_DQS_DN<11>")
	)
	(segment
		(start 54.11724 -17.102328)
		(end 54.11724 -17.348962)
		(width 0.1651)
		(layer "F.Cu")
		(net "M_G_DQS_DN<11>")
	)
	(segment
		(start 53.865272 -17.60093)
		(end 53.656992 -17.60093)
		(width 0.1651)
		(layer "F.Cu")
		(net "M_G_DQS_DN<11>")
	)
	(segment
		(start 53.931312 -16.9164)
		(end 54.11724 -17.102328)
		(width 0.1651)
		(layer "F.Cu")
		(net "M_G_DQS_DN<11>")
	)
	(segment
		(start 54.349396 -15.423642)
		(end 54.349396 -16.077184)
		(width 0.1651)
		(layer "F.Cu")
		(net "M_G_DQS_DN<11>")
	)
	(via
		(at 53.442108 -22.8346)
		(size 0.508)
		(drill 0.254)
		(layers "F.Cu" "B.Cu")
		(net "M_G_DQS_DN<11>")
	)
	(via
		(at 70.611746 -57.57164)
		(size 0.508)
		(drill 0.254)
		(layers "F.Cu" "B.Cu")
		(net "M_G_DQS_DN<11>")
	)
	(via
		(at 53.448712 -17.4117)
		(size 0.508)
		(drill 0.254)
		(layers "F.Cu" "B.Cu")
		(net "M_G_DQS_DN<11>")
	)
	(segment
		(start 54.349396 -24.824182)
		(end 54.34965 -24.823928)
		(width 0.1651)
		(layer "B.Cu")
		(net "M_G_DQS_DN<11>")
	)
	(segment
		(start 53.905912 -23.723854)
		(end 53.905912 -23.368)
		(width 0.1651)
		(layer "B.Cu")
		(net "M_G_DQS_DN<11>")
	)
	(segment
		(start 53.863748 -22.640036)
		(end 53.636672 -22.640036)
		(width 0.1651)
		(layer "B.Cu")
		(net "M_G_DQS_DN<11>")
	)
	(segment
		(start 53.905912 -23.368)
		(end 54.083712 -23.1902)
		(width 0.1651)
		(layer "B.Cu")
		(net "M_G_DQS_DN<11>")
	)
	(segment
		(start 54.34965 -24.167592)
		(end 53.905912 -23.723854)
		(width 0.1651)
		(layer "B.Cu")
		(net "M_G_DQS_DN<11>")
	)
	(segment
		(start 54.083712 -22.86)
		(end 53.863748 -22.640036)
		(width 0.1651)
		(layer "B.Cu")
		(net "M_G_DQS_DN<11>")
	)
	(segment
		(start 53.636672 -22.640036)
		(end 53.442108 -22.8346)
		(width 0.1651)
		(layer "B.Cu")
		(net "M_G_DQS_DN<11>")
	)
	(segment
		(start 54.34965 -24.823928)
		(end 54.34965 -24.167592)
		(width 0.1651)
		(layer "B.Cu")
		(net "M_G_DQS_DN<11>")
	)
	(segment
		(start 54.083712 -23.1902)
		(end 54.083712 -22.86)
		(width 0.1651)
		(layer "B.Cu")
		(net "M_G_DQS_DN<11>")
	)
	(segment
		(start 53.630068 -38.304216)
		(end 53.269642 -37.94379)
		(width 0.14224)
		(layer "In2.Cu")
		(net "M_G_DQS_DN<11>")
	)
	(segment
		(start 52.975256 -32.9692)
		(end 52.975256 -27.499056)
		(width 0.14224)
		(layer "In2.Cu")
		(net "M_G_DQS_DN<11>")
	)
	(segment
		(start 52.850288 -42.24528)
		(end 53.457856 -41.637712)
		(width 0.14224)
		(layer "In2.Cu")
		(net "M_G_DQS_DN<11>")
	)
	(segment
		(start 60.15101 -49.978056)
		(end 59.989212 -49.816258)
		(width 0.14224)
		(layer "In2.Cu")
		(net "M_G_DQS_DN<11>")
	)
	(segment
		(start 52.975256 -26.930096)
		(end 52.975256 -26.737056)
		(width 0.14224)
		(layer "In2.Cu")
		(net "M_G_DQS_DN<11>")
	)
	(segment
		(start 63.778892 -53.605938)
		(end 63.59906 -53.605938)
		(width 0.14224)
		(layer "In2.Cu")
		(net "M_G_DQS_DN<11>")
	)
	(segment
		(start 66.917316 -56.98109)
		(end 66.143886 -56.206898)
		(width 0.0889)
		(layer "In2.Cu")
		(net "M_G_DQS_DN<11>")
	)
	(segment
		(start 65.64122 -55.703978)
		(end 65.64122 -55.648098)
		(width 0.0889)
		(layer "In2.Cu")
		(net "M_G_DQS_DN<11>")
	)
	(segment
		(start 65.982342 -55.865268)
		(end 65.80251 -55.865268)
		(width 0.0889)
		(layer "In2.Cu")
		(net "M_G_DQS_DN<11>")
	)
	(segment
		(start 65.80251 -55.865268)
		(end 65.64122 -55.703978)
		(width 0.0889)
		(layer "In2.Cu")
		(net "M_G_DQS_DN<11>")
	)
	(segment
		(start 60.66536 -50.672238)
		(end 60.66536 -50.492406)
		(width 0.14224)
		(layer "In2.Cu")
		(net "M_G_DQS_DN<11>")
	)
	(segment
		(start 52.652676 -39.55923)
		(end 53.251862 -39.55923)
		(width 0.14224)
		(layer "In2.Cu")
		(net "M_G_DQS_DN<11>")
	)
	(segment
		(start 65.122552 -55.12943)
		(end 64.961008 -54.967886)
		(width 0.14224)
		(layer "In2.Cu")
		(net "M_G_DQS_DN<11>")
	)
	(segment
		(start 52.619656 -37.74567)
		(end 52.619656 -33.3248)
		(width 0.14224)
		(layer "In2.Cu")
		(net "M_G_DQS_DN<11>")
	)
	(segment
		(start 59.647836 -49.474882)
		(end 59.486292 -49.313338)
		(width 0.14224)
		(layer "In2.Cu")
		(net "M_G_DQS_DN<11>")
	)
	(segment
		(start 53.132736 -27.087576)
		(end 52.975256 -26.930096)
		(width 0.14224)
		(layer "In2.Cu")
		(net "M_G_DQS_DN<11>")
	)
	(segment
		(start 64.44361 -54.450488)
		(end 64.44361 -54.270656)
		(width 0.14224)
		(layer "In2.Cu")
		(net "M_G_DQS_DN<11>")
	)
	(segment
		(start 52.817776 -37.94379)
		(end 52.619656 -37.74567)
		(width 0.14224)
		(layer "In2.Cu")
		(net "M_G_DQS_DN<11>")
	)
	(segment
		(start 52.474368 -39.737538)
		(end 52.652676 -39.55923)
		(width 0.14224)
		(layer "In2.Cu")
		(net "M_G_DQS_DN<11>")
	)
	(segment
		(start 61.78931 -51.796188)
		(end 61.78931 -51.616356)
		(width 0.14224)
		(layer "In2.Cu")
		(net "M_G_DQS_DN<11>")
	)
	(segment
		(start 52.619656 -33.3248)
		(end 52.975256 -32.9692)
		(width 0.14224)
		(layer "In2.Cu")
		(net "M_G_DQS_DN<11>")
	)
	(segment
		(start 53.880512 -23.273004)
		(end 53.442108 -22.8346)
		(width 0.14224)
		(layer "In2.Cu")
		(net "M_G_DQS_DN<11>")
	)
	(segment
		(start 63.437516 -53.264562)
		(end 63.275972 -53.103018)
		(width 0.14224)
		(layer "In2.Cu")
		(net "M_G_DQS_DN<11>")
	)
	(segment
		(start 64.10198 -54.108858)
		(end 63.940436 -53.947314)
		(width 0.14224)
		(layer "In2.Cu")
		(net "M_G_DQS_DN<11>")
	)
	(segment
		(start 64.619632 -54.62651)
		(end 64.44361 -54.450488)
		(width 0.14224)
		(layer "In2.Cu")
		(net "M_G_DQS_DN<11>")
	)
	(segment
		(start 60.15101 -50.157888)
		(end 60.15101 -49.978056)
		(width 0.14224)
		(layer "In2.Cu")
		(net "M_G_DQS_DN<11>")
	)
	(segment
		(start 52.975256 -26.168096)
		(end 52.975256 -25.975056)
		(width 0.14224)
		(layer "In2.Cu")
		(net "M_G_DQS_DN<11>")
	)
	(segment
		(start 70.611746 -57.57164)
		(end 70.4723 -57.711086)
		(width 0.0889)
		(layer "In2.Cu")
		(net "M_G_DQS_DN<11>")
	)
	(segment
		(start 63.275972 -53.103018)
		(end 63.09614 -53.103018)
		(width 0.14224)
		(layer "In2.Cu")
		(net "M_G_DQS_DN<11>")
	)
	(segment
		(start 61.78931 -51.616356)
		(end 61.627512 -51.454558)
		(width 0.14224)
		(layer "In2.Cu")
		(net "M_G_DQS_DN<11>")
	)
	(segment
		(start 58.926222 -48.793908)
		(end 58.78703 -48.793908)
		(width 0.14224)
		(layer "In2.Cu")
		(net "M_G_DQS_DN<11>")
	)
	(segment
		(start 60.32373 -50.330608)
		(end 60.15101 -50.157888)
		(width 0.14224)
		(layer "In2.Cu")
		(net "M_G_DQS_DN<11>")
	)
	(segment
		(start 59.80938 -49.816258)
		(end 59.647836 -49.654714)
		(width 0.14224)
		(layer "In2.Cu")
		(net "M_G_DQS_DN<11>")
	)
	(segment
		(start 53.269642 -37.94379)
		(end 52.817776 -37.94379)
		(width 0.14224)
		(layer "In2.Cu")
		(net "M_G_DQS_DN<11>")
	)
	(segment
		(start 53.457856 -41.637712)
		(end 53.457856 -41.015158)
		(width 0.14224)
		(layer "In2.Cu")
		(net "M_G_DQS_DN<11>")
	)
	(segment
		(start 60.83173 -50.838608)
		(end 60.66536 -50.672238)
		(width 0.14224)
		(layer "In2.Cu")
		(net "M_G_DQS_DN<11>")
	)
	(segment
		(start 58.25998 -48.266858)
		(end 53.457856 -43.464734)
		(width 0.14224)
		(layer "In2.Cu")
		(net "M_G_DQS_DN<11>")
	)
	(segment
		(start 53.132736 -24.801576)
		(end 52.975256 -24.644096)
		(width 0.14224)
		(layer "In2.Cu")
		(net "M_G_DQS_DN<11>")
	)
	(segment
		(start 62.90056 -52.727606)
		(end 62.738762 -52.565808)
		(width 0.14224)
		(layer "In2.Cu")
		(net "M_G_DQS_DN<11>")
	)
	(segment
		(start 58.38698 -48.266858)
		(end 58.25998 -48.266858)
		(width 0.14224)
		(layer "In2.Cu")
		(net "M_G_DQS_DN<11>")
	)
	(segment
		(start 52.695856 -40.63619)
		(end 52.474368 -40.414702)
		(width 0.14224)
		(layer "In2.Cu")
		(net "M_G_DQS_DN<11>")
	)
	(segment
		(start 58.78703 -48.793908)
		(end 58.60161 -48.608488)
		(width 0.14224)
		(layer "In2.Cu")
		(net "M_G_DQS_DN<11>")
	)
	(segment
		(start 62.738762 -52.565808)
		(end 62.55893 -52.565808)
		(width 0.14224)
		(layer "In2.Cu")
		(net "M_G_DQS_DN<11>")
	)
	(segment
		(start 62.00013 -52.007008)
		(end 61.78931 -51.796188)
		(width 0.14224)
		(layer "In2.Cu")
		(net "M_G_DQS_DN<11>")
	)
	(segment
		(start 53.132736 -26.579576)
		(end 53.132736 -26.325576)
		(width 0.14224)
		(layer "In2.Cu")
		(net "M_G_DQS_DN<11>")
	)
	(segment
		(start 64.961008 -54.967886)
		(end 64.961008 -54.788054)
		(width 0.14224)
		(layer "In2.Cu")
		(net "M_G_DQS_DN<11>")
	)
	(segment
		(start 64.961008 -54.788054)
		(end 64.799464 -54.62651)
		(width 0.14224)
		(layer "In2.Cu")
		(net "M_G_DQS_DN<11>")
	)
	(segment
		(start 68.780914 -57.476136)
		(end 68.285868 -56.98109)
		(width 0.0889)
		(layer "In2.Cu")
		(net "M_G_DQS_DN<11>")
	)
	(segment
		(start 59.647836 -49.654714)
		(end 59.647836 -49.474882)
		(width 0.14224)
		(layer "In2.Cu")
		(net "M_G_DQS_DN<11>")
	)
	(segment
		(start 53.078888 -40.63619)
		(end 52.695856 -40.63619)
		(width 0.14224)
		(layer "In2.Cu")
		(net "M_G_DQS_DN<11>")
	)
	(segment
		(start 60.503562 -50.330608)
		(end 60.32373 -50.330608)
		(width 0.14224)
		(layer "In2.Cu")
		(net "M_G_DQS_DN<11>")
	)
	(segment
		(start 58.60161 -48.608488)
		(end 58.60161 -48.481488)
		(width 0.14224)
		(layer "In2.Cu")
		(net "M_G_DQS_DN<11>")
	)
	(segment
		(start 53.132736 -25.817576)
		(end 53.132736 -25.563576)
		(width 0.14224)
		(layer "In2.Cu")
		(net "M_G_DQS_DN<11>")
	)
	(segment
		(start 63.09614 -53.103018)
		(end 62.90056 -52.907438)
		(width 0.14224)
		(layer "In2.Cu")
		(net "M_G_DQS_DN<11>")
	)
	(segment
		(start 63.940436 -53.947314)
		(end 63.940436 -53.767482)
		(width 0.14224)
		(layer "In2.Cu")
		(net "M_G_DQS_DN<11>")
	)
	(segment
		(start 65.625472 -55.63235)
		(end 65.463928 -55.470806)
		(width 0.14224)
		(layer "In2.Cu")
		(net "M_G_DQS_DN<11>")
	)
	(segment
		(start 53.457856 -41.015158)
		(end 53.078888 -40.63619)
		(width 0.14224)
		(layer "In2.Cu")
		(net "M_G_DQS_DN<11>")
	)
	(segment
		(start 53.457856 -43.071288)
		(end 52.850288 -42.46372)
		(width 0.14224)
		(layer "In2.Cu")
		(net "M_G_DQS_DN<11>")
	)
	(segment
		(start 62.34176 -52.348638)
		(end 62.34176 -52.168806)
		(width 0.14224)
		(layer "In2.Cu")
		(net "M_G_DQS_DN<11>")
	)
	(segment
		(start 63.59906 -53.605938)
		(end 63.437516 -53.444394)
		(width 0.14224)
		(layer "In2.Cu")
		(net "M_G_DQS_DN<11>")
	)
	(segment
		(start 53.132736 -26.325576)
		(end 52.975256 -26.168096)
		(width 0.14224)
		(layer "In2.Cu")
		(net "M_G_DQS_DN<11>")
	)
	(segment
		(start 63.437516 -53.444394)
		(end 63.437516 -53.264562)
		(width 0.14224)
		(layer "In2.Cu")
		(net "M_G_DQS_DN<11>")
	)
	(segment
		(start 64.799464 -54.62651)
		(end 64.619632 -54.62651)
		(width 0.14224)
		(layer "In2.Cu")
		(net "M_G_DQS_DN<11>")
	)
	(segment
		(start 52.850288 -42.46372)
		(end 52.850288 -42.24528)
		(width 0.14224)
		(layer "In2.Cu")
		(net "M_G_DQS_DN<11>")
	)
	(segment
		(start 53.677312 -24.003)
		(end 53.880512 -23.7998)
		(width 0.14224)
		(layer "In2.Cu")
		(net "M_G_DQS_DN<11>")
	)
	(segment
		(start 53.644292 -17.60728)
		(end 53.448712 -17.4117)
		(width 0.14224)
		(layer "In2.Cu")
		(net "M_G_DQS_DN<11>")
	)
	(segment
		(start 59.989212 -49.816258)
		(end 59.80938 -49.816258)
		(width 0.14224)
		(layer "In2.Cu")
		(net "M_G_DQS_DN<11>")
	)
	(segment
		(start 59.12866 -48.996346)
		(end 58.926222 -48.793908)
		(width 0.14224)
		(layer "In2.Cu")
		(net "M_G_DQS_DN<11>")
	)
	(segment
		(start 52.975256 -24.644096)
		(end 52.975256 -24.408384)
		(width 0.14224)
		(layer "In2.Cu")
		(net "M_G_DQS_DN<11>")
	)
	(segment
		(start 53.630068 -39.181024)
		(end 53.630068 -38.304216)
		(width 0.14224)
		(layer "In2.Cu")
		(net "M_G_DQS_DN<11>")
	)
	(segment
		(start 53.89372 -17.60728)
		(end 53.644292 -17.60728)
		(width 0.14224)
		(layer "In2.Cu")
		(net "M_G_DQS_DN<11>")
	)
	(segment
		(start 64.281812 -54.108858)
		(end 64.10198 -54.108858)
		(width 0.14224)
		(layer "In2.Cu")
		(net "M_G_DQS_DN<11>")
	)
	(segment
		(start 59.486292 -49.313338)
		(end 59.30646 -49.313338)
		(width 0.14224)
		(layer "In2.Cu")
		(net "M_G_DQS_DN<11>")
	)
	(segment
		(start 59.12866 -49.135538)
		(end 59.12866 -48.996346)
		(width 0.14224)
		(layer "In2.Cu")
		(net "M_G_DQS_DN<11>")
	)
	(segment
		(start 59.30646 -49.313338)
		(end 59.12866 -49.135538)
		(width 0.14224)
		(layer "In2.Cu")
		(net "M_G_DQS_DN<11>")
	)
	(segment
		(start 65.463928 -55.470806)
		(end 65.463928 -55.290974)
		(width 0.14224)
		(layer "In2.Cu")
		(net "M_G_DQS_DN<11>")
	)
	(segment
		(start 62.179962 -52.007008)
		(end 62.00013 -52.007008)
		(width 0.14224)
		(layer "In2.Cu")
		(net "M_G_DQS_DN<11>")
	)
	(segment
		(start 61.011562 -50.838608)
		(end 60.83173 -50.838608)
		(width 0.14224)
		(layer "In2.Cu")
		(net "M_G_DQS_DN<11>")
	)
	(segment
		(start 70.4723 -57.711086)
		(end 70.471792 -57.711086)
		(width 0.0889)
		(layer "In2.Cu")
		(net "M_G_DQS_DN<11>")
	)
	(segment
		(start 61.17336 -51.000406)
		(end 61.011562 -50.838608)
		(width 0.14224)
		(layer "In2.Cu")
		(net "M_G_DQS_DN<11>")
	)
	(segment
		(start 65.463928 -55.290974)
		(end 65.302384 -55.12943)
		(width 0.14224)
		(layer "In2.Cu")
		(net "M_G_DQS_DN<11>")
	)
	(segment
		(start 65.302384 -55.12943)
		(end 65.122552 -55.12943)
		(width 0.14224)
		(layer "In2.Cu")
		(net "M_G_DQS_DN<11>")
	)
	(segment
		(start 52.975256 -27.499056)
		(end 53.132736 -27.341576)
		(width 0.14224)
		(layer "In2.Cu")
		(net "M_G_DQS_DN<11>")
	)
	(segment
		(start 63.940436 -53.767482)
		(end 63.778892 -53.605938)
		(width 0.14224)
		(layer "In2.Cu")
		(net "M_G_DQS_DN<11>")
	)
	(segment
		(start 54.231032 -22.045676)
		(end 54.231032 -17.944592)
		(width 0.14224)
		(layer "In2.Cu")
		(net "M_G_DQS_DN<11>")
	)
	(segment
		(start 61.44768 -51.454558)
		(end 61.17336 -51.180238)
		(width 0.14224)
		(layer "In2.Cu")
		(net "M_G_DQS_DN<11>")
	)
	(segment
		(start 70.055232 -57.558686)
		(end 70.054978 -57.55894)
		(width 0.0889)
		(layer "In2.Cu")
		(net "M_G_DQS_DN<11>")
	)
	(segment
		(start 53.132736 -25.563576)
		(end 52.975256 -25.406096)
		(width 0.14224)
		(layer "In2.Cu")
		(net "M_G_DQS_DN<11>")
	)
	(segment
		(start 54.231032 -17.944592)
		(end 53.89372 -17.60728)
		(width 0.14224)
		(layer "In2.Cu")
		(net "M_G_DQS_DN<11>")
	)
	(segment
		(start 53.880512 -23.7998)
		(end 53.880512 -23.273004)
		(width 0.14224)
		(layer "In2.Cu")
		(net "M_G_DQS_DN<11>")
	)
	(segment
		(start 68.285868 -56.98109)
		(end 66.917316 -56.98109)
		(width 0.0889)
		(layer "In2.Cu")
		(net "M_G_DQS_DN<11>")
	)
	(segment
		(start 52.975256 -25.213056)
		(end 53.132736 -25.055576)
		(width 0.14224)
		(layer "In2.Cu")
		(net "M_G_DQS_DN<11>")
	)
	(segment
		(start 52.975256 -25.975056)
		(end 53.132736 -25.817576)
		(width 0.14224)
		(layer "In2.Cu")
		(net "M_G_DQS_DN<11>")
	)
	(segment
		(start 52.474368 -40.414702)
		(end 52.474368 -39.737538)
		(width 0.14224)
		(layer "In2.Cu")
		(net "M_G_DQS_DN<11>")
	)
	(segment
		(start 62.55893 -52.565808)
		(end 62.34176 -52.348638)
		(width 0.14224)
		(layer "In2.Cu")
		(net "M_G_DQS_DN<11>")
	)
	(segment
		(start 58.60161 -48.481488)
		(end 58.38698 -48.266858)
		(width 0.14224)
		(layer "In2.Cu")
		(net "M_G_DQS_DN<11>")
	)
	(segment
		(start 53.38064 -24.003)
		(end 53.677312 -24.003)
		(width 0.14224)
		(layer "In2.Cu")
		(net "M_G_DQS_DN<11>")
	)
	(segment
		(start 60.66536 -50.492406)
		(end 60.503562 -50.330608)
		(width 0.14224)
		(layer "In2.Cu")
		(net "M_G_DQS_DN<11>")
	)
	(segment
		(start 62.90056 -52.907438)
		(end 62.90056 -52.727606)
		(width 0.14224)
		(layer "In2.Cu")
		(net "M_G_DQS_DN<11>")
	)
	(segment
		(start 66.143886 -56.206898)
		(end 66.143886 -56.027066)
		(width 0.0889)
		(layer "In2.Cu")
		(net "M_G_DQS_DN<11>")
	)
	(segment
		(start 53.132736 -27.341576)
		(end 53.132736 -27.087576)
		(width 0.14224)
		(layer "In2.Cu")
		(net "M_G_DQS_DN<11>")
	)
	(segment
		(start 53.442108 -22.8346)
		(end 54.231032 -22.045676)
		(width 0.14224)
		(layer "In2.Cu")
		(net "M_G_DQS_DN<11>")
	)
	(segment
		(start 52.975256 -26.737056)
		(end 53.132736 -26.579576)
		(width 0.14224)
		(layer "In2.Cu")
		(net "M_G_DQS_DN<11>")
	)
	(segment
		(start 52.975256 -25.406096)
		(end 52.975256 -25.213056)
		(width 0.14224)
		(layer "In2.Cu")
		(net "M_G_DQS_DN<11>")
	)
	(segment
		(start 64.44361 -54.270656)
		(end 64.281812 -54.108858)
		(width 0.14224)
		(layer "In2.Cu")
		(net "M_G_DQS_DN<11>")
	)
	(segment
		(start 62.34176 -52.168806)
		(end 62.179962 -52.007008)
		(width 0.14224)
		(layer "In2.Cu")
		(net "M_G_DQS_DN<11>")
	)
	(segment
		(start 52.975256 -24.408384)
		(end 53.38064 -24.003)
		(width 0.14224)
		(layer "In2.Cu")
		(net "M_G_DQS_DN<11>")
	)
	(segment
		(start 61.627512 -51.454558)
		(end 61.44768 -51.454558)
		(width 0.14224)
		(layer "In2.Cu")
		(net "M_G_DQS_DN<11>")
	)
	(segment
		(start 53.457856 -43.464734)
		(end 53.457856 -43.071288)
		(width 0.14224)
		(layer "In2.Cu")
		(net "M_G_DQS_DN<11>")
	)
	(segment
		(start 53.251862 -39.55923)
		(end 53.630068 -39.181024)
		(width 0.14224)
		(layer "In2.Cu")
		(net "M_G_DQS_DN<11>")
	)
	(segment
		(start 69.76618 -57.476136)
		(end 68.780914 -57.476136)
		(width 0.0889)
		(layer "In2.Cu")
		(net "M_G_DQS_DN<11>")
	)
	(segment
		(start 53.132736 -25.055576)
		(end 53.132736 -24.801576)
		(width 0.14224)
		(layer "In2.Cu")
		(net "M_G_DQS_DN<11>")
	)
	(segment
		(start 65.64122 -55.648098)
		(end 65.625472 -55.63235)
		(width 0.0889)
		(layer "In2.Cu")
		(net "M_G_DQS_DN<11>")
	)
	(segment
		(start 66.143886 -56.027066)
		(end 65.982342 -55.865268)
		(width 0.0889)
		(layer "In2.Cu")
		(net "M_G_DQS_DN<11>")
	)
	(segment
		(start 61.17336 -51.180238)
		(end 61.17336 -51.000406)
		(width 0.14224)
		(layer "In2.Cu")
		(net "M_G_DQS_DN<11>")
	)
	(arc
		(start 70.054978 -57.55894)
		(mid 69.915932 -57.498859)
		(end 69.76618 -57.476136)
		(width 0.0889)
		(layer "In2.Cu")
		(net "M_G_DQS_DN<11>")
	)
	(arc
		(start 70.471792 -57.711086)
		(mid 70.277657 -57.680149)
		(end 70.10273 -57.590436)
		(width 0.0889)
		(layer "In2.Cu")
		(net "M_G_DQS_DN<11>")
	)
	(arc
		(start 70.10273 -57.590436)
		(mid 70.079373 -57.573975)
		(end 70.055232 -57.558686)
		(width 0.0889)
		(layer "In2.Cu")
		(net "M_G_DQS_DN<11>")
	)
	(segment
		(start 50.0253 -32.1691)
		(end 51.786536 -33.930336)
		(width 0.1651)
		(layer "F.Cu")
		(net "M_G_DQS_DN<10>")
	)
	(segment
		(start 69.14007 -57.57164)
		(end 69.466206 -57.57164)
		(width 0.0889)
		(layer "F.Cu")
		(net "M_G_DQS_DN<10>")
	)
	(segment
		(start 52.674774 -43.942)
		(end 52.801774 -44.069)
		(width 0.1651)
		(layer "F.Cu")
		(net "M_G_DQS_DN<10>")
	)
	(segment
		(start 51.7906 -37.46246)
		(end 52.674774 -38.346634)
		(width 0.1651)
		(layer "F.Cu")
		(net "M_G_DQS_DN<10>")
	)
	(segment
		(start 44.999402 -15.423642)
		(end 44.999402 -16.077184)
		(width 0.1651)
		(layer "F.Cu")
		(net "M_G_DQS_DN<10>")
	)
	(segment
		(start 51.7906 -36.375086)
		(end 51.7906 -37.46246)
		(width 0.1651)
		(layer "F.Cu")
		(net "M_G_DQS_DN<10>")
	)
	(segment
		(start 44.9834 -26.3652)
		(end 45.1612 -26.543)
		(width 0.1651)
		(layer "F.Cu")
		(net "M_G_DQS_DN<10>")
	)
	(segment
		(start 44.767246 -17.102328)
		(end 44.767246 -17.348962)
		(width 0.1651)
		(layer "F.Cu")
		(net "M_G_DQS_DN<10>")
	)
	(segment
		(start 47.022512 -28.575)
		(end 47.3202 -28.575)
		(width 0.1651)
		(layer "F.Cu")
		(net "M_G_DQS_DN<10>")
	)
	(segment
		(start 44.581318 -16.9164)
		(end 44.767246 -17.102328)
		(width 0.1651)
		(layer "F.Cu")
		(net "M_G_DQS_DN<10>")
	)
	(segment
		(start 44.6278 -25.9334)
		(end 44.6278 -26.180288)
		(width 0.1651)
		(layer "F.Cu")
		(net "M_G_DQS_DN<10>")
	)
	(segment
		(start 44.767246 -17.348962)
		(end 44.515278 -17.60093)
		(width 0.1651)
		(layer "F.Cu")
		(net "M_G_DQS_DN<10>")
	)
	(segment
		(start 43.722036 -24.424132)
		(end 43.857418 -24.559514)
		(width 0.1651)
		(layer "F.Cu")
		(net "M_G_DQS_DN<10>")
	)
	(segment
		(start 52.674774 -38.346634)
		(end 52.674774 -43.942)
		(width 0.1651)
		(layer "F.Cu")
		(net "M_G_DQS_DN<10>")
	)
	(segment
		(start 44.812712 -26.3652)
		(end 44.9834 -26.3652)
		(width 0.1651)
		(layer "F.Cu")
		(net "M_G_DQS_DN<10>")
	)
	(segment
		(start 50.931064 -35.207194)
		(end 50.931064 -35.51555)
		(width 0.1651)
		(layer "F.Cu")
		(net "M_G_DQS_DN<10>")
	)
	(segment
		(start 47.5234 -28.3718)
		(end 48.006 -28.3718)
		(width 0.1651)
		(layer "F.Cu")
		(net "M_G_DQS_DN<10>")
	)
	(segment
		(start 44.581318 -16.495268)
		(end 44.581318 -16.9164)
		(width 0.1651)
		(layer "F.Cu")
		(net "M_G_DQS_DN<10>")
	)
	(segment
		(start 52.801774 -44.069)
		(end 53.321204 -44.069)
		(width 0.1651)
		(layer "F.Cu")
		(net "M_G_DQS_DN<10>")
	)
	(segment
		(start 53.6194 -45.541184)
		(end 65.01003 -56.931814)
		(width 0.1651)
		(layer "F.Cu")
		(net "M_G_DQS_DN<10>")
	)
	(segment
		(start 51.786536 -34.351722)
		(end 50.931064 -35.207194)
		(width 0.1651)
		(layer "F.Cu")
		(net "M_G_DQS_DN<10>")
	)
	(segment
		(start 43.914568 -23.9776)
		(end 43.722036 -24.170132)
		(width 0.1651)
		(layer "F.Cu")
		(net "M_G_DQS_DN<10>")
	)
	(segment
		(start 45.9232 -27.475688)
		(end 47.022512 -28.575)
		(width 0.1651)
		(layer "F.Cu")
		(net "M_G_DQS_DN<10>")
	)
	(segment
		(start 51.786536 -33.930336)
		(end 51.786536 -34.351722)
		(width 0.1651)
		(layer "F.Cu")
		(net "M_G_DQS_DN<10>")
	)
	(segment
		(start 65.01003 -56.931814)
		(end 66.678048 -56.931814)
		(width 0.1651)
		(layer "F.Cu")
		(net "M_G_DQS_DN<10>")
	)
	(segment
		(start 44.999402 -16.077184)
		(end 44.581318 -16.495268)
		(width 0.1651)
		(layer "F.Cu")
		(net "M_G_DQS_DN<10>")
	)
	(segment
		(start 45.1612 -26.543)
		(end 45.1612 -26.713688)
		(width 0.1651)
		(layer "F.Cu")
		(net "M_G_DQS_DN<10>")
	)
	(segment
		(start 48.006 -28.3718)
		(end 48.2092 -28.575)
		(width 0.1651)
		(layer "F.Cu")
		(net "M_G_DQS_DN<10>")
	)
	(segment
		(start 53.321204 -44.069)
		(end 53.6194 -44.367196)
		(width 0.1651)
		(layer "F.Cu")
		(net "M_G_DQS_DN<10>")
	)
	(segment
		(start 53.6194 -44.367196)
		(end 53.6194 -45.541184)
		(width 0.1651)
		(layer "F.Cu")
		(net "M_G_DQS_DN<10>")
	)
	(segment
		(start 44.6278 -26.180288)
		(end 44.812712 -26.3652)
		(width 0.1651)
		(layer "F.Cu")
		(net "M_G_DQS_DN<10>")
	)
	(segment
		(start 48.514 -28.575)
		(end 50.0253 -30.0863)
		(width 0.1651)
		(layer "F.Cu")
		(net "M_G_DQS_DN<10>")
	)
	(segment
		(start 45.9232 -27.2288)
		(end 45.9232 -27.475688)
		(width 0.1651)
		(layer "F.Cu")
		(net "M_G_DQS_DN<10>")
	)
	(segment
		(start 48.2092 -28.575)
		(end 48.514 -28.575)
		(width 0.1651)
		(layer "F.Cu")
		(net "M_G_DQS_DN<10>")
	)
	(segment
		(start 47.3202 -28.575)
		(end 47.5234 -28.3718)
		(width 0.1651)
		(layer "F.Cu")
		(net "M_G_DQS_DN<10>")
	)
	(segment
		(start 43.722036 -24.170132)
		(end 43.722036 -24.424132)
		(width 0.1651)
		(layer "F.Cu")
		(net "M_G_DQS_DN<10>")
	)
	(segment
		(start 50.931064 -35.51555)
		(end 51.7906 -36.375086)
		(width 0.1651)
		(layer "F.Cu")
		(net "M_G_DQS_DN<10>")
	)
	(segment
		(start 44.270422 -22.8346)
		(end 44.541948 -23.106126)
		(width 0.1651)
		(layer "F.Cu")
		(net "M_G_DQS_DN<10>")
	)
	(segment
		(start 44.515278 -17.60093)
		(end 44.306998 -17.60093)
		(width 0.1651)
		(layer "F.Cu")
		(net "M_G_DQS_DN<10>")
	)
	(segment
		(start 43.722036 -24.932132)
		(end 43.722036 -25.274524)
		(width 0.1651)
		(layer "F.Cu")
		(net "M_G_DQS_DN<10>")
	)
	(segment
		(start 44.237656 -25.790144)
		(end 44.484544 -25.790144)
		(width 0.1651)
		(layer "F.Cu")
		(net "M_G_DQS_DN<10>")
	)
	(segment
		(start 44.295568 -23.9776)
		(end 43.914568 -23.9776)
		(width 0.1651)
		(layer "F.Cu")
		(net "M_G_DQS_DN<10>")
	)
	(segment
		(start 68.597272 -57.47639)
		(end 68.716398 -57.47639)
		(width 0.0889)
		(layer "F.Cu")
		(net "M_G_DQS_DN<10>")
	)
	(segment
		(start 66.678048 -56.931814)
		(end 66.727324 -56.98109)
		(width 0.0889)
		(layer "F.Cu")
		(net "M_G_DQS_DN<10>")
	)
	(segment
		(start 43.857418 -24.79675)
		(end 43.722036 -24.932132)
		(width 0.1651)
		(layer "F.Cu")
		(net "M_G_DQS_DN<10>")
	)
	(segment
		(start 45.422312 -26.9748)
		(end 45.6692 -26.9748)
		(width 0.1651)
		(layer "F.Cu")
		(net "M_G_DQS_DN<10>")
	)
	(segment
		(start 66.727324 -56.98109)
		(end 67.770756 -56.98109)
		(width 0.0889)
		(layer "F.Cu")
		(net "M_G_DQS_DN<10>")
	)
	(segment
		(start 44.092114 -22.8346)
		(end 44.270422 -22.8346)
		(width 0.1651)
		(layer "F.Cu")
		(net "M_G_DQS_DN<10>")
	)
	(segment
		(start 44.541948 -23.106126)
		(end 44.541948 -23.73122)
		(width 0.1651)
		(layer "F.Cu")
		(net "M_G_DQS_DN<10>")
	)
	(segment
		(start 44.541948 -23.73122)
		(end 44.295568 -23.9776)
		(width 0.1651)
		(layer "F.Cu")
		(net "M_G_DQS_DN<10>")
	)
	(segment
		(start 50.0253 -30.0863)
		(end 50.0253 -32.1691)
		(width 0.1651)
		(layer "F.Cu")
		(net "M_G_DQS_DN<10>")
	)
	(segment
		(start 44.117768 -17.4117)
		(end 44.098718 -17.4117)
		(width 0.1651)
		(layer "F.Cu")
		(net "M_G_DQS_DN<10>")
	)
	(segment
		(start 43.857418 -24.559514)
		(end 43.857418 -24.79675)
		(width 0.1651)
		(layer "F.Cu")
		(net "M_G_DQS_DN<10>")
	)
	(segment
		(start 45.1612 -26.713688)
		(end 45.422312 -26.9748)
		(width 0.1651)
		(layer "F.Cu")
		(net "M_G_DQS_DN<10>")
	)
	(segment
		(start 44.306998 -17.60093)
		(end 44.117768 -17.4117)
		(width 0.1651)
		(layer "F.Cu")
		(net "M_G_DQS_DN<10>")
	)
	(segment
		(start 44.484544 -25.790144)
		(end 44.6278 -25.9334)
		(width 0.1651)
		(layer "F.Cu")
		(net "M_G_DQS_DN<10>")
	)
	(segment
		(start 43.722036 -25.274524)
		(end 44.237656 -25.790144)
		(width 0.1651)
		(layer "F.Cu")
		(net "M_G_DQS_DN<10>")
	)
	(segment
		(start 45.6692 -26.9748)
		(end 45.9232 -27.2288)
		(width 0.1651)
		(layer "F.Cu")
		(net "M_G_DQS_DN<10>")
	)
	(via
		(at 44.098718 -17.4117)
		(size 0.508)
		(drill 0.254)
		(layers "F.Cu" "B.Cu")
		(net "M_G_DQS_DN<10>")
	)
	(via
		(at 44.092114 -22.8346)
		(size 0.508)
		(drill 0.254)
		(layers "F.Cu" "B.Cu")
		(net "M_G_DQS_DN<10>")
	)
	(arc
		(start 68.716398 -57.47639)
		(mid 68.802055 -57.485897)
		(end 68.88353 -57.513982)
		(width 0.0889)
		(layer "F.Cu")
		(net "M_G_DQS_DN<10>")
	)
	(arc
		(start 68.88353 -57.513982)
		(mid 69.008602 -57.557037)
		(end 69.14007 -57.57164)
		(width 0.0889)
		(layer "F.Cu")
		(net "M_G_DQS_DN<10>")
	)
	(arc
		(start 67.770756 -56.98109)
		(mid 68.053973 -57.065371)
		(end 68.260976 -57.276238)
		(width 0.0889)
		(layer "F.Cu")
		(net "M_G_DQS_DN<10>")
	)
	(arc
		(start 68.260976 -57.276238)
		(mid 68.403019 -57.42015)
		(end 68.597272 -57.47639)
		(width 0.0889)
		(layer "F.Cu")
		(net "M_G_DQS_DN<10>")
	)
	(segment
		(start 44.555918 -23.368)
		(end 44.733718 -23.1902)
		(width 0.1651)
		(layer "B.Cu")
		(net "M_G_DQS_DN<10>")
	)
	(segment
		(start 44.286678 -22.640036)
		(end 44.092114 -22.8346)
		(width 0.1651)
		(layer "B.Cu")
		(net "M_G_DQS_DN<10>")
	)
	(segment
		(start 44.733718 -23.1902)
		(end 44.733718 -22.86)
		(width 0.1651)
		(layer "B.Cu")
		(net "M_G_DQS_DN<10>")
	)
	(segment
		(start 44.555918 -23.723854)
		(end 44.555918 -23.368)
		(width 0.1651)
		(layer "B.Cu")
		(net "M_G_DQS_DN<10>")
	)
	(segment
		(start 44.513754 -22.640036)
		(end 44.286678 -22.640036)
		(width 0.1651)
		(layer "B.Cu")
		(net "M_G_DQS_DN<10>")
	)
	(segment
		(start 44.999402 -24.824182)
		(end 44.999656 -24.823928)
		(width 0.1651)
		(layer "B.Cu")
		(net "M_G_DQS_DN<10>")
	)
	(segment
		(start 44.733718 -22.86)
		(end 44.513754 -22.640036)
		(width 0.1651)
		(layer "B.Cu")
		(net "M_G_DQS_DN<10>")
	)
	(segment
		(start 44.999656 -24.167592)
		(end 44.555918 -23.723854)
		(width 0.1651)
		(layer "B.Cu")
		(net "M_G_DQS_DN<10>")
	)
	(segment
		(start 44.999656 -24.823928)
		(end 44.999656 -24.167592)
		(width 0.1651)
		(layer "B.Cu")
		(net "M_G_DQS_DN<10>")
	)
	(segment
		(start 44.881038 -17.944592)
		(end 44.543726 -17.60728)
		(width 0.14224)
		(layer "In2.Cu")
		(net "M_G_DQS_DN<10>")
	)
	(segment
		(start 44.543726 -17.60728)
		(end 44.294298 -17.60728)
		(width 0.14224)
		(layer "In2.Cu")
		(net "M_G_DQS_DN<10>")
	)
	(segment
		(start 44.881038 -22.045676)
		(end 44.881038 -17.944592)
		(width 0.14224)
		(layer "In2.Cu")
		(net "M_G_DQS_DN<10>")
	)
	(segment
		(start 44.092114 -22.8346)
		(end 44.881038 -22.045676)
		(width 0.14224)
		(layer "In2.Cu")
		(net "M_G_DQS_DN<10>")
	)
	(segment
		(start 44.294298 -17.60728)
		(end 44.098718 -17.4117)
		(width 0.14224)
		(layer "In2.Cu")
		(net "M_G_DQS_DN<10>")
	)
	(segment
		(start 35.267392 -18.567654)
		(end 35.267392 -18.135854)
		(width 0.1651)
		(layer "F.Cu")
		(net "M_G_DQS_DN<0>")
	)
	(segment
		(start 35.649408 -20.023582)
		(end 35.649408 -18.94967)
		(width 0.1651)
		(layer "F.Cu")
		(net "M_G_DQS_DN<0>")
	)
	(segment
		(start 35.649408 -18.94967)
		(end 35.267392 -18.567654)
		(width 0.1651)
		(layer "F.Cu")
		(net "M_G_DQS_DN<0>")
	)
	(segment
		(start 35.597846 -17.8054)
		(end 35.821874 -17.8054)
		(width 0.1651)
		(layer "F.Cu")
		(net "M_G_DQS_DN<0>")
	)
	(segment
		(start 35.267392 -18.135854)
		(end 35.597846 -17.8054)
		(width 0.1651)
		(layer "F.Cu")
		(net "M_G_DQS_DN<0>")
	)
	(segment
		(start 69.466206 -63.51524)
		(end 68.894706 -63.51524)
		(width 0.1016)
		(layer "F.Cu")
		(net "M_G_DQS_DN<0>")
	)
	(segment
		(start 35.821874 -17.8054)
		(end 36.03752 -18.021046)
		(width 0.1651)
		(layer "F.Cu")
		(net "M_G_DQS_DN<0>")
	)
	(via
		(at 36.03752 -18.021046)
		(size 0.508)
		(drill 0.254)
		(layers "F.Cu" "B.Cu")
		(net "M_G_DQS_DN<0>")
	)
	(via
		(at 68.894706 -63.51524)
		(size 0.508)
		(drill 0.254)
		(layers "F.Cu" "B.Cu")
		(net "M_G_DQS_DN<0>")
	)
	(via
		(at 36.03752 -22.228556)
		(size 0.508)
		(drill 0.254)
		(layers "F.Cu" "B.Cu")
		(net "M_G_DQS_DN<0>")
	)
	(segment
		(start 35.521392 -21.513546)
		(end 35.267392 -21.767546)
		(width 0.1651)
		(layer "B.Cu")
		(net "M_G_DQS_DN<0>")
	)
	(segment
		(start 35.649408 -21.13153)
		(end 35.521392 -21.259546)
		(width 0.1651)
		(layer "B.Cu")
		(net "M_G_DQS_DN<0>")
	)
	(segment
		(start 35.622992 -22.4536)
		(end 35.812476 -22.4536)
		(width 0.1651)
		(layer "B.Cu")
		(net "M_G_DQS_DN<0>")
	)
	(segment
		(start 35.812476 -22.4536)
		(end 36.03752 -22.228556)
		(width 0.1651)
		(layer "B.Cu")
		(net "M_G_DQS_DN<0>")
	)
	(segment
		(start 35.267392 -21.767546)
		(end 35.267392 -22.098)
		(width 0.1651)
		(layer "B.Cu")
		(net "M_G_DQS_DN<0>")
	)
	(segment
		(start 35.521392 -21.259546)
		(end 35.521392 -21.513546)
		(width 0.1651)
		(layer "B.Cu")
		(net "M_G_DQS_DN<0>")
	)
	(segment
		(start 35.649408 -20.224242)
		(end 35.649408 -21.13153)
		(width 0.1651)
		(layer "B.Cu")
		(net "M_G_DQS_DN<0>")
	)
	(segment
		(start 35.267392 -22.098)
		(end 35.622992 -22.4536)
		(width 0.1651)
		(layer "B.Cu")
		(net "M_G_DQS_DN<0>")
	)
	(segment
		(start 38.786816 -35.257232)
		(end 38.786816 -35.713416)
		(width 0.14224)
		(layer "In2.Cu")
		(net "M_G_DQS_DN<0>")
	)
	(segment
		(start 35.967416 -34.276792)
		(end 36.370768 -34.680144)
		(width 0.14224)
		(layer "In2.Cu")
		(net "M_G_DQS_DN<0>")
	)
	(segment
		(start 36.579048 -21.966174)
		(end 36.579048 -21.261324)
		(width 0.14224)
		(layer "In2.Cu")
		(net "M_G_DQS_DN<0>")
	)
	(segment
		(start 35.967416 -25.141682)
		(end 35.967416 -34.276792)
		(width 0.14224)
		(layer "In2.Cu")
		(net "M_G_DQS_DN<0>")
	)
	(segment
		(start 66.048636 -63.806324)
		(end 66.222118 -63.806324)
		(width 0.0889)
		(layer "In2.Cu")
		(net "M_G_DQS_DN<0>")
	)
	(segment
		(start 36.316412 -22.22881)
		(end 36.579048 -21.966174)
		(width 0.14224)
		(layer "In2.Cu")
		(net "M_G_DQS_DN<0>")
	)
	(segment
		(start 35.592004 -22.674072)
		(end 35.592004 -24.76627)
		(width 0.14224)
		(layer "In2.Cu")
		(net "M_G_DQS_DN<0>")
	)
	(segment
		(start 37.948616 -37.315394)
		(end 38.377622 -37.7444)
		(width 0.14224)
		(layer "In2.Cu")
		(net "M_G_DQS_DN<0>")
	)
	(segment
		(start 36.269168 -21.082)
		(end 36.091368 -20.9042)
		(width 0.14224)
		(layer "In2.Cu")
		(net "M_G_DQS_DN<0>")
	)
	(segment
		(start 36.091368 -20.6502)
		(end 36.269168 -20.4724)
		(width 0.14224)
		(layer "In2.Cu")
		(net "M_G_DQS_DN<0>")
	)
	(segment
		(start 36.319206 -18.021046)
		(end 36.03752 -18.021046)
		(width 0.14224)
		(layer "In2.Cu")
		(net "M_G_DQS_DN<0>")
	)
	(segment
		(start 36.269168 -20.4724)
		(end 36.396168 -20.4724)
		(width 0.14224)
		(layer "In2.Cu")
		(net "M_G_DQS_DN<0>")
	)
	(segment
		(start 66.000884 -63.854076)
		(end 66.048636 -63.806324)
		(width 0.0889)
		(layer "In2.Cu")
		(net "M_G_DQS_DN<0>")
	)
	(segment
		(start 36.39947 -19.1262)
		(end 36.579048 -18.946622)
		(width 0.14224)
		(layer "In2.Cu")
		(net "M_G_DQS_DN<0>")
	)
	(segment
		(start 38.209728 -34.680144)
		(end 38.786816 -35.257232)
		(width 0.14224)
		(layer "In2.Cu")
		(net "M_G_DQS_DN<0>")
	)
	(segment
		(start 36.399724 -21.082)
		(end 36.269168 -21.082)
		(width 0.14224)
		(layer "In2.Cu")
		(net "M_G_DQS_DN<0>")
	)
	(segment
		(start 67.287648 -63.11519)
		(end 67.782694 -63.610236)
		(width 0.0889)
		(layer "In2.Cu")
		(net "M_G_DQS_DN<0>")
	)
	(segment
		(start 37.948616 -36.551616)
		(end 37.948616 -37.315394)
		(width 0.14224)
		(layer "In2.Cu")
		(net "M_G_DQS_DN<0>")
	)
	(segment
		(start 38.913816 -38.797738)
		(end 63.970154 -63.854076)
		(width 0.14224)
		(layer "In2.Cu")
		(net "M_G_DQS_DN<0>")
	)
	(segment
		(start 36.196778 -19.1262)
		(end 36.39947 -19.1262)
		(width 0.14224)
		(layer "In2.Cu")
		(net "M_G_DQS_DN<0>")
	)
	(segment
		(start 36.03752 -22.228556)
		(end 35.592004 -22.674072)
		(width 0.14224)
		(layer "In2.Cu")
		(net "M_G_DQS_DN<0>")
	)
	(segment
		(start 68.68795 -63.51524)
		(end 68.894706 -63.51524)
		(width 0.0889)
		(layer "In2.Cu")
		(net "M_G_DQS_DN<0>")
	)
	(segment
		(start 36.579048 -18.280888)
		(end 36.319206 -18.021046)
		(width 0.14224)
		(layer "In2.Cu")
		(net "M_G_DQS_DN<0>")
	)
	(segment
		(start 36.196778 -19.7358)
		(end 36.044124 -19.583146)
		(width 0.14224)
		(layer "In2.Cu")
		(net "M_G_DQS_DN<0>")
	)
	(segment
		(start 36.03752 -22.22881)
		(end 36.316412 -22.22881)
		(width 0.14224)
		(layer "In2.Cu")
		(net "M_G_DQS_DN<0>")
	)
	(segment
		(start 66.222118 -63.806324)
		(end 66.913252 -63.11519)
		(width 0.0889)
		(layer "In2.Cu")
		(net "M_G_DQS_DN<0>")
	)
	(segment
		(start 36.579048 -21.261324)
		(end 36.399724 -21.082)
		(width 0.14224)
		(layer "In2.Cu")
		(net "M_G_DQS_DN<0>")
	)
	(segment
		(start 36.579048 -19.940778)
		(end 36.37407 -19.7358)
		(width 0.14224)
		(layer "In2.Cu")
		(net "M_G_DQS_DN<0>")
	)
	(segment
		(start 36.044124 -19.278854)
		(end 36.196778 -19.1262)
		(width 0.14224)
		(layer "In2.Cu")
		(net "M_G_DQS_DN<0>")
	)
	(segment
		(start 36.579048 -18.946622)
		(end 36.579048 -18.280888)
		(width 0.14224)
		(layer "In2.Cu")
		(net "M_G_DQS_DN<0>")
	)
	(segment
		(start 38.377622 -37.7444)
		(end 38.692328 -37.7444)
		(width 0.14224)
		(layer "In2.Cu")
		(net "M_G_DQS_DN<0>")
	)
	(segment
		(start 36.396168 -20.4724)
		(end 36.579048 -20.28952)
		(width 0.14224)
		(layer "In2.Cu")
		(net "M_G_DQS_DN<0>")
	)
	(segment
		(start 35.592004 -24.76627)
		(end 35.967416 -25.141682)
		(width 0.14224)
		(layer "In2.Cu")
		(net "M_G_DQS_DN<0>")
	)
	(segment
		(start 36.370768 -34.680144)
		(end 38.209728 -34.680144)
		(width 0.14224)
		(layer "In2.Cu")
		(net "M_G_DQS_DN<0>")
	)
	(segment
		(start 67.782694 -63.610236)
		(end 68.172076 -63.610236)
		(width 0.0889)
		(layer "In2.Cu")
		(net "M_G_DQS_DN<0>")
	)
	(segment
		(start 38.786816 -35.713416)
		(end 37.948616 -36.551616)
		(width 0.14224)
		(layer "In2.Cu")
		(net "M_G_DQS_DN<0>")
	)
	(segment
		(start 36.091368 -20.9042)
		(end 36.091368 -20.6502)
		(width 0.14224)
		(layer "In2.Cu")
		(net "M_G_DQS_DN<0>")
	)
	(segment
		(start 36.37407 -19.7358)
		(end 36.196778 -19.7358)
		(width 0.14224)
		(layer "In2.Cu")
		(net "M_G_DQS_DN<0>")
	)
	(segment
		(start 66.913252 -63.11519)
		(end 67.287648 -63.11519)
		(width 0.0889)
		(layer "In2.Cu")
		(net "M_G_DQS_DN<0>")
	)
	(segment
		(start 36.03752 -22.228556)
		(end 36.03752 -22.22881)
		(width 0.14224)
		(layer "In2.Cu")
		(net "M_G_DQS_DN<0>")
	)
	(segment
		(start 36.579048 -20.28952)
		(end 36.579048 -19.940778)
		(width 0.14224)
		(layer "In2.Cu")
		(net "M_G_DQS_DN<0>")
	)
	(segment
		(start 63.970154 -63.854076)
		(end 66.000884 -63.854076)
		(width 0.14224)
		(layer "In2.Cu")
		(net "M_G_DQS_DN<0>")
	)
	(segment
		(start 36.044124 -19.583146)
		(end 36.044124 -19.278854)
		(width 0.14224)
		(layer "In2.Cu")
		(net "M_G_DQS_DN<0>")
	)
	(segment
		(start 38.913816 -37.965888)
		(end 38.913816 -38.797738)
		(width 0.14224)
		(layer "In2.Cu")
		(net "M_G_DQS_DN<0>")
	)
	(segment
		(start 38.692328 -37.7444)
		(end 38.913816 -37.965888)
		(width 0.14224)
		(layer "In2.Cu")
		(net "M_G_DQS_DN<0>")
	)
	(arc
		(start 68.311522 -63.584582)
		(mid 68.496569 -63.532719)
		(end 68.68795 -63.51524)
		(width 0.0889)
		(layer "In2.Cu")
		(net "M_G_DQS_DN<0>")
	)
	(arc
		(start 68.172076 -63.610236)
		(mid 68.242975 -63.603795)
		(end 68.311522 -63.584582)
		(width 0.0889)
		(layer "In2.Cu")
		(net "M_G_DQS_DN<0>")
	)
	(segment
		(start 43.12158 -22.279356)
		(end 42.612564 -22.788372)
		(width 0.1651)
		(layer "F.Cu")
		(net "M_G_DQ<9>")
	)
	(segment
		(start 42.917364 -23.767796)
		(end 42.749978 -23.935182)
		(width 0.1651)
		(layer "F.Cu")
		(net "M_G_DQ<9>")
	)
	(segment
		(start 64.578738 -57.875424)
		(end 66.746882 -57.875424)
		(width 0.1651)
		(layer "F.Cu")
		(net "M_G_DQ<9>")
	)
	(segment
		(start 50.8254 -36.7284)
		(end 50.8254 -37.81552)
		(width 0.1651)
		(layer "F.Cu")
		(net "M_G_DQ<9>")
	)
	(segment
		(start 42.612564 -22.788372)
		(end 42.612564 -23.081996)
		(width 0.1651)
		(layer "F.Cu")
		(net "M_G_DQ<9>")
	)
	(segment
		(start 66.842894 -57.971436)
		(end 67.828414 -57.971436)
		(width 0.0889)
		(layer "F.Cu")
		(net "M_G_DQ<9>")
	)
	(segment
		(start 50.8254 -37.81552)
		(end 51.742848 -38.732968)
		(width 0.1651)
		(layer "F.Cu")
		(net "M_G_DQ<9>")
	)
	(segment
		(start 49.936908 -33.731708)
		(end 49.936908 -35.839908)
		(width 0.1651)
		(layer "F.Cu")
		(net "M_G_DQ<9>")
	)
	(segment
		(start 42.917364 -23.386796)
		(end 42.917364 -23.767796)
		(width 0.1651)
		(layer "F.Cu")
		(net "M_G_DQ<9>")
	)
	(segment
		(start 66.746882 -57.875424)
		(end 66.842894 -57.971436)
		(width 0.0889)
		(layer "F.Cu")
		(net "M_G_DQ<9>")
	)
	(segment
		(start 46.635162 -29.540454)
		(end 48.006 -29.5402)
		(width 0.1651)
		(layer "F.Cu")
		(net "M_G_DQ<9>")
	)
	(segment
		(start 42.449496 -15.423642)
		(end 42.449496 -16.687546)
		(width 0.1651)
		(layer "F.Cu")
		(net "M_G_DQ<9>")
	)
	(segment
		(start 42.612564 -23.081996)
		(end 42.917364 -23.386796)
		(width 0.1651)
		(layer "F.Cu")
		(net "M_G_DQ<9>")
	)
	(segment
		(start 42.749978 -25.656032)
		(end 46.635162 -29.540454)
		(width 0.1651)
		(layer "F.Cu")
		(net "M_G_DQ<9>")
	)
	(segment
		(start 48.006 -29.5402)
		(end 49.093374 -30.627574)
		(width 0.1651)
		(layer "F.Cu")
		(net "M_G_DQ<9>")
	)
	(segment
		(start 51.742848 -38.732968)
		(end 51.742848 -45.039534)
		(width 0.1651)
		(layer "F.Cu")
		(net "M_G_DQ<9>")
	)
	(segment
		(start 67.828414 -57.971436)
		(end 68.418964 -58.561986)
		(width 0.0889)
		(layer "F.Cu")
		(net "M_G_DQ<9>")
	)
	(segment
		(start 49.093374 -30.627574)
		(end 49.093374 -32.888174)
		(width 0.1651)
		(layer "F.Cu")
		(net "M_G_DQ<9>")
	)
	(segment
		(start 49.093374 -32.888174)
		(end 49.936908 -33.731708)
		(width 0.1651)
		(layer "F.Cu")
		(net "M_G_DQ<9>")
	)
	(segment
		(start 42.749978 -23.935182)
		(end 42.749978 -25.656032)
		(width 0.1651)
		(layer "F.Cu")
		(net "M_G_DQ<9>")
	)
	(segment
		(start 51.742848 -45.039534)
		(end 64.578738 -57.875424)
		(width 0.1651)
		(layer "F.Cu")
		(net "M_G_DQ<9>")
	)
	(segment
		(start 49.936908 -35.839908)
		(end 50.8254 -36.7284)
		(width 0.1651)
		(layer "F.Cu")
		(net "M_G_DQ<9>")
	)
	(segment
		(start 68.418964 -58.561986)
		(end 69.466206 -58.561986)
		(width 0.0889)
		(layer "F.Cu")
		(net "M_G_DQ<9>")
	)
	(via
		(at 42.449496 -16.687546)
		(size 0.508)
		(drill 0.254)
		(layers "F.Cu" "B.Cu")
		(net "M_G_DQ<9>")
	)
	(via
		(at 43.12158 -22.279356)
		(size 0.508)
		(drill 0.254)
		(layers "F.Cu" "B.Cu")
		(net "M_G_DQ<9>")
	)
	(segment
		(start 43.29938 -21.598382)
		(end 43.12158 -21.776182)
		(width 0.1651)
		(layer "B.Cu")
		(net "M_G_DQ<9>")
	)
	(segment
		(start 43.12158 -21.776182)
		(end 43.12158 -22.279356)
		(width 0.1651)
		(layer "B.Cu")
		(net "M_G_DQ<9>")
	)
	(segment
		(start 43.29938 -20.224242)
		(end 43.29938 -21.598382)
		(width 0.1651)
		(layer "B.Cu")
		(net "M_G_DQ<9>")
	)
	(segment
		(start 43.495722 -18.571464)
		(end 43.652186 -18.415)
		(width 0.14224)
		(layer "In2.Cu")
		(net "M_G_DQ<9>")
	)
	(segment
		(start 43.495722 -21.905214)
		(end 43.495722 -18.571464)
		(width 0.14224)
		(layer "In2.Cu")
		(net "M_G_DQ<9>")
	)
	(segment
		(start 42.449496 -17.226534)
		(end 42.449496 -16.687546)
		(width 0.14224)
		(layer "In2.Cu")
		(net "M_G_DQ<9>")
	)
	(segment
		(start 43.12158 -22.279356)
		(end 43.495722 -21.905214)
		(width 0.14224)
		(layer "In2.Cu")
		(net "M_G_DQ<9>")
	)
	(segment
		(start 43.282362 -17.7038)
		(end 42.926762 -17.7038)
		(width 0.14224)
		(layer "In2.Cu")
		(net "M_G_DQ<9>")
	)
	(segment
		(start 43.652186 -18.073624)
		(end 43.282362 -17.7038)
		(width 0.14224)
		(layer "In2.Cu")
		(net "M_G_DQ<9>")
	)
	(segment
		(start 42.926762 -17.7038)
		(end 42.449496 -17.226534)
		(width 0.14224)
		(layer "In2.Cu")
		(net "M_G_DQ<9>")
	)
	(segment
		(start 43.652186 -18.415)
		(end 43.652186 -18.073624)
		(width 0.14224)
		(layer "In2.Cu")
		(net "M_G_DQ<9>")
	)
	(segment
		(start 47.1551 -31.438088)
		(end 46.99 -31.603188)
		(width 0.1651)
		(layer "F.Cu")
		(net "M_G_DQ<8>")
	)
	(segment
		(start 48.288448 -31.438088)
		(end 47.1551 -31.438088)
		(width 0.1651)
		(layer "F.Cu")
		(net "M_G_DQ<8>")
	)
	(segment
		(start 49.297082 -33.997138)
		(end 49.297082 -36.413186)
		(width 0.1651)
		(layer "F.Cu")
		(net "M_G_DQ<8>")
	)
	(segment
		(start 42.058336 -25.903936)
		(end 46.33468 -30.18028)
		(width 0.1651)
		(layer "F.Cu")
		(net "M_G_DQ<8>")
	)
	(segment
		(start 51.103022 -45.35424)
		(end 64.310768 -58.561986)
		(width 0.1651)
		(layer "F.Cu")
		(net "M_G_DQ<8>")
	)
	(segment
		(start 50.185574 -38.29812)
		(end 51.103022 -39.215568)
		(width 0.1651)
		(layer "F.Cu")
		(net "M_G_DQ<8>")
	)
	(segment
		(start 48.453548 -33.153604)
		(end 49.297082 -33.997138)
		(width 0.1651)
		(layer "F.Cu")
		(net "M_G_DQ<8>")
	)
	(segment
		(start 64.310768 -58.561986)
		(end 66.799968 -58.561986)
		(width 0.1651)
		(layer "F.Cu")
		(net "M_G_DQ<8>")
	)
	(segment
		(start 48.453548 -31.272988)
		(end 48.288448 -31.438088)
		(width 0.1651)
		(layer "F.Cu")
		(net "M_G_DQ<8>")
	)
	(segment
		(start 42.058336 -23.951438)
		(end 42.058336 -25.903936)
		(width 0.1651)
		(layer "F.Cu")
		(net "M_G_DQ<8>")
	)
	(segment
		(start 47.68088 -30.18028)
		(end 48.453548 -30.952948)
		(width 0.1651)
		(layer "F.Cu")
		(net "M_G_DQ<8>")
	)
	(segment
		(start 46.99 -31.603188)
		(end 46.99 -31.946088)
		(width 0.1651)
		(layer "F.Cu")
		(net "M_G_DQ<8>")
	)
	(segment
		(start 48.453548 -30.952948)
		(end 48.453548 -31.272988)
		(width 0.1651)
		(layer "F.Cu")
		(net "M_G_DQ<8>")
	)
	(segment
		(start 43.29938 -20.023582)
		(end 43.218608 -19.177)
		(width 0.1651)
		(layer "F.Cu")
		(net "M_G_DQ<8>")
	)
	(segment
		(start 51.103022 -39.215568)
		(end 51.103022 -45.35424)
		(width 0.1651)
		(layer "F.Cu")
		(net "M_G_DQ<8>")
	)
	(segment
		(start 46.33468 -30.18028)
		(end 47.68088 -30.18028)
		(width 0.1651)
		(layer "F.Cu")
		(net "M_G_DQ<8>")
	)
	(segment
		(start 49.297082 -36.413186)
		(end 50.185574 -37.301678)
		(width 0.1651)
		(layer "F.Cu")
		(net "M_G_DQ<8>")
	)
	(segment
		(start 43.218608 -19.177)
		(end 43.12158 -18.161)
		(width 0.1651)
		(layer "F.Cu")
		(net "M_G_DQ<8>")
	)
	(segment
		(start 48.453548 -32.276288)
		(end 48.453548 -33.153604)
		(width 0.1651)
		(layer "F.Cu")
		(net "M_G_DQ<8>")
	)
	(segment
		(start 66.799968 -58.561986)
		(end 67.749166 -58.561986)
		(width 0.0889)
		(layer "F.Cu")
		(net "M_G_DQ<8>")
	)
	(segment
		(start 46.99 -31.946088)
		(end 47.1551 -32.111188)
		(width 0.1651)
		(layer "F.Cu")
		(net "M_G_DQ<8>")
	)
	(segment
		(start 42.449496 -23.560278)
		(end 42.058336 -23.951438)
		(width 0.1651)
		(layer "F.Cu")
		(net "M_G_DQ<8>")
	)
	(segment
		(start 47.1551 -32.111188)
		(end 48.288448 -32.111188)
		(width 0.1651)
		(layer "F.Cu")
		(net "M_G_DQ<8>")
	)
	(segment
		(start 50.185574 -37.301678)
		(end 50.185574 -38.29812)
		(width 0.1651)
		(layer "F.Cu")
		(net "M_G_DQ<8>")
	)
	(segment
		(start 48.288448 -32.111188)
		(end 48.453548 -32.276288)
		(width 0.1651)
		(layer "F.Cu")
		(net "M_G_DQ<8>")
	)
	(via
		(at 42.449496 -23.560278)
		(size 0.508)
		(drill 0.254)
		(layers "F.Cu" "B.Cu")
		(net "M_G_DQ<8>")
	)
	(via
		(at 43.12158 -18.161)
		(size 0.508)
		(drill 0.254)
		(layers "F.Cu" "B.Cu")
		(net "M_G_DQ<8>")
	)
	(segment
		(start 42.449496 -23.560278)
		(end 42.449496 -24.824182)
		(width 0.1651)
		(layer "B.Cu")
		(net "M_G_DQ<8>")
	)
	(segment
		(start 42.82948 -20.0533)
		(end 42.48658 -19.7104)
		(width 0.14224)
		(layer "In2.Cu")
		(net "M_G_DQ<8>")
	)
	(segment
		(start 42.901362 -18.381218)
		(end 43.12158 -18.161)
		(width 0.14224)
		(layer "In2.Cu")
		(net "M_G_DQ<8>")
	)
	(segment
		(start 42.164762 -23.275544)
		(end 42.164762 -22.5298)
		(width 0.14224)
		(layer "In2.Cu")
		(net "M_G_DQ<8>")
	)
	(segment
		(start 42.901362 -18.965672)
		(end 42.901362 -18.381218)
		(width 0.14224)
		(layer "In2.Cu")
		(net "M_G_DQ<8>")
	)
	(segment
		(start 42.164762 -22.5298)
		(end 42.901362 -21.7932)
		(width 0.14224)
		(layer "In2.Cu")
		(net "M_G_DQ<8>")
	)
	(segment
		(start 42.901362 -21.293328)
		(end 42.51198 -20.903946)
		(width 0.14224)
		(layer "In2.Cu")
		(net "M_G_DQ<8>")
	)
	(segment
		(start 42.51198 -20.5994)
		(end 42.82948 -20.2819)
		(width 0.14224)
		(layer "In2.Cu")
		(net "M_G_DQ<8>")
	)
	(segment
		(start 42.51198 -20.903946)
		(end 42.51198 -20.5994)
		(width 0.14224)
		(layer "In2.Cu")
		(net "M_G_DQ<8>")
	)
	(segment
		(start 42.48658 -19.380454)
		(end 42.901362 -18.965672)
		(width 0.14224)
		(layer "In2.Cu")
		(net "M_G_DQ<8>")
	)
	(segment
		(start 42.48658 -19.7104)
		(end 42.48658 -19.380454)
		(width 0.14224)
		(layer "In2.Cu")
		(net "M_G_DQ<8>")
	)
	(segment
		(start 42.901362 -21.7932)
		(end 42.901362 -21.293328)
		(width 0.14224)
		(layer "In2.Cu")
		(net "M_G_DQ<8>")
	)
	(segment
		(start 42.82948 -20.2819)
		(end 42.82948 -20.0533)
		(width 0.14224)
		(layer "In2.Cu")
		(net "M_G_DQ<8>")
	)
	(segment
		(start 42.449496 -23.560278)
		(end 42.164762 -23.275544)
		(width 0.14224)
		(layer "In2.Cu")
		(net "M_G_DQ<8>")
	)
	(segment
		(start 69.466206 -62.52464)
		(end 68.894706 -62.52464)
		(width 0.1016)
		(layer "F.Cu")
		(net "M_G_DQ<7>")
	)
	(segment
		(start 37.34943 -15.423642)
		(end 37.34943 -16.687546)
		(width 0.1651)
		(layer "F.Cu")
		(net "M_G_DQ<7>")
	)
	(via
		(at 37.34943 -16.687546)
		(size 0.508)
		(drill 0.254)
		(layers "F.Cu" "B.Cu")
		(net "M_G_DQ<7>")
	)
	(via
		(at 38.199314 -22.279356)
		(size 0.508)
		(drill 0.254)
		(layers "F.Cu" "B.Cu")
		(net "M_G_DQ<7>")
	)
	(via
		(at 68.894706 -62.52464)
		(size 0.508)
		(drill 0.254)
		(layers "F.Cu" "B.Cu")
		(net "M_G_DQ<7>")
	)
	(segment
		(start 38.199314 -20.224496)
		(end 38.199314 -22.279356)
		(width 0.1651)
		(layer "B.Cu")
		(net "M_G_DQ<7>")
	)
	(segment
		(start 38.199568 -20.224242)
		(end 38.199314 -20.224496)
		(width 0.1651)
		(layer "B.Cu")
		(net "M_G_DQ<7>")
	)
	(segment
		(start 39.492936 -25.714706)
		(end 39.492936 -32.027368)
		(width 0.14224)
		(layer "In2.Cu")
		(net "M_G_DQ<7>")
	)
	(segment
		(start 38.707568 -18.1102)
		(end 38.707568 -18.4658)
		(width 0.14224)
		(layer "In2.Cu")
		(net "M_G_DQ<7>")
	)
	(segment
		(start 37.740336 -22.738334)
		(end 37.740336 -23.153624)
		(width 0.14224)
		(layer "In2.Cu")
		(net "M_G_DQ<7>")
	)
	(segment
		(start 37.666168 -17.3228)
		(end 37.996368 -17.653)
		(width 0.14224)
		(layer "In2.Cu")
		(net "M_G_DQ<7>")
	)
	(segment
		(start 38.69563 -25.6286)
		(end 38.89883 -25.4254)
		(width 0.14224)
		(layer "In2.Cu")
		(net "M_G_DQ<7>")
	)
	(segment
		(start 38.69563 -28.4734)
		(end 38.69563 -25.6286)
		(width 0.14224)
		(layer "In2.Cu")
		(net "M_G_DQ<7>")
	)
	(segment
		(start 40.635936 -33.170368)
		(end 40.635936 -38.265862)
		(width 0.14224)
		(layer "In2.Cu")
		(net "M_G_DQ<7>")
	)
	(segment
		(start 37.740336 -23.153624)
		(end 37.98443 -23.397718)
		(width 0.14224)
		(layer "In2.Cu")
		(net "M_G_DQ<7>")
	)
	(segment
		(start 37.666168 -17.004284)
		(end 37.666168 -17.3228)
		(width 0.14224)
		(layer "In2.Cu")
		(net "M_G_DQ<7>")
	)
	(segment
		(start 39.492936 -32.027368)
		(end 40.635936 -33.170368)
		(width 0.14224)
		(layer "In2.Cu")
		(net "M_G_DQ<7>")
	)
	(segment
		(start 67.356482 -62.041024)
		(end 67.840098 -62.52464)
		(width 0.0889)
		(layer "In2.Cu")
		(net "M_G_DQ<7>")
	)
	(segment
		(start 38.18763 -28.6766)
		(end 38.49243 -28.6766)
		(width 0.14224)
		(layer "In2.Cu")
		(net "M_G_DQ<7>")
	)
	(segment
		(start 38.199314 -22.279356)
		(end 37.740336 -22.738334)
		(width 0.14224)
		(layer "In2.Cu")
		(net "M_G_DQ<7>")
	)
	(segment
		(start 66.035428 -62.270386)
		(end 66.26479 -62.041024)
		(width 0.0889)
		(layer "In2.Cu")
		(net "M_G_DQ<7>")
	)
	(segment
		(start 38.250368 -17.653)
		(end 38.707568 -18.1102)
		(width 0.14224)
		(layer "In2.Cu")
		(net "M_G_DQ<7>")
	)
	(segment
		(start 38.55212 -21.92655)
		(end 38.199314 -22.279356)
		(width 0.14224)
		(layer "In2.Cu")
		(net "M_G_DQ<7>")
	)
	(segment
		(start 37.34943 -16.687546)
		(end 37.666168 -17.004284)
		(width 0.14224)
		(layer "In2.Cu")
		(net "M_G_DQ<7>")
	)
	(segment
		(start 38.49243 -28.6766)
		(end 38.69563 -28.4734)
		(width 0.14224)
		(layer "In2.Cu")
		(net "M_G_DQ<7>")
	)
	(segment
		(start 38.55212 -18.621248)
		(end 38.55212 -21.92655)
		(width 0.14224)
		(layer "In2.Cu")
		(net "M_G_DQ<7>")
	)
	(segment
		(start 38.707568 -18.4658)
		(end 38.55212 -18.621248)
		(width 0.14224)
		(layer "In2.Cu")
		(net "M_G_DQ<7>")
	)
	(segment
		(start 66.26479 -62.041024)
		(end 67.356482 -62.041024)
		(width 0.0889)
		(layer "In2.Cu")
		(net "M_G_DQ<7>")
	)
	(segment
		(start 37.996368 -17.653)
		(end 38.250368 -17.653)
		(width 0.14224)
		(layer "In2.Cu")
		(net "M_G_DQ<7>")
	)
	(segment
		(start 37.98443 -23.397718)
		(end 37.98443 -28.4734)
		(width 0.14224)
		(layer "In2.Cu")
		(net "M_G_DQ<7>")
	)
	(segment
		(start 40.635936 -38.265862)
		(end 64.64046 -62.270386)
		(width 0.14224)
		(layer "In2.Cu")
		(net "M_G_DQ<7>")
	)
	(segment
		(start 38.89883 -25.4254)
		(end 39.20363 -25.4254)
		(width 0.14224)
		(layer "In2.Cu")
		(net "M_G_DQ<7>")
	)
	(segment
		(start 65.631568 -62.270386)
		(end 66.035428 -62.270386)
		(width 0.0889)
		(layer "In2.Cu")
		(net "M_G_DQ<7>")
	)
	(segment
		(start 37.98443 -28.4734)
		(end 38.18763 -28.6766)
		(width 0.14224)
		(layer "In2.Cu")
		(net "M_G_DQ<7>")
	)
	(segment
		(start 39.20363 -25.4254)
		(end 39.492936 -25.714706)
		(width 0.14224)
		(layer "In2.Cu")
		(net "M_G_DQ<7>")
	)
	(segment
		(start 67.840098 -62.52464)
		(end 68.894706 -62.52464)
		(width 0.0889)
		(layer "In2.Cu")
		(net "M_G_DQ<7>")
	)
	(segment
		(start 64.64046 -62.270386)
		(end 65.631568 -62.270386)
		(width 0.14224)
		(layer "In2.Cu")
		(net "M_G_DQ<7>")
	)
	(segment
		(start 38.331648 -18.69948)
		(end 38.199568 -18.5674)
		(width 0.1651)
		(layer "F.Cu")
		(net "M_G_DQ<6>")
	)
	(segment
		(start 38.199568 -19.05)
		(end 38.331648 -18.91792)
		(width 0.1651)
		(layer "F.Cu")
		(net "M_G_DQ<6>")
	)
	(segment
		(start 38.199568 -18.262854)
		(end 38.199314 -18.2626)
		(width 0.1651)
		(layer "F.Cu")
		(net "M_G_DQ<6>")
	)
	(segment
		(start 38.199568 -18.5674)
		(end 38.199568 -18.262854)
		(width 0.1651)
		(layer "F.Cu")
		(net "M_G_DQ<6>")
	)
	(segment
		(start 38.331648 -18.91792)
		(end 38.331648 -18.69948)
		(width 0.1651)
		(layer "F.Cu")
		(net "M_G_DQ<6>")
	)
	(segment
		(start 38.199568 -20.023582)
		(end 38.199568 -19.05)
		(width 0.1651)
		(layer "F.Cu")
		(net "M_G_DQ<6>")
	)
	(segment
		(start 67.749166 -62.52464)
		(end 67.101466 -62.52464)
		(width 0.1016)
		(layer "F.Cu")
		(net "M_G_DQ<6>")
	)
	(via
		(at 67.101466 -62.52464)
		(size 0.508)
		(drill 0.254)
		(layers "F.Cu" "B.Cu")
		(net "M_G_DQ<6>")
	)
	(via
		(at 37.34943 -23.560278)
		(size 0.508)
		(drill 0.254)
		(layers "F.Cu" "B.Cu")
		(net "M_G_DQ<6>")
	)
	(via
		(at 38.199314 -18.2626)
		(size 0.508)
		(drill 0.254)
		(layers "F.Cu" "B.Cu")
		(net "M_G_DQ<6>")
	)
	(segment
		(start 37.34943 -23.560278)
		(end 37.34943 -24.824182)
		(width 0.1651)
		(layer "B.Cu")
		(net "M_G_DQ<6>")
	)
	(segment
		(start 37.886386 -21.757386)
		(end 37.113718 -22.530054)
		(width 0.14224)
		(layer "In2.Cu")
		(net "M_G_DQ<6>")
	)
	(segment
		(start 37.841936 -20.313904)
		(end 37.460936 -20.694904)
		(width 0.14224)
		(layer "In2.Cu")
		(net "M_G_DQ<6>")
	)
	(segment
		(start 66.085974 -62.905386)
		(end 66.46672 -62.52464)
		(width 0.0889)
		(layer "In2.Cu")
		(net "M_G_DQ<6>")
	)
	(segment
		(start 38.06063 -33.3756)
		(end 38.06063 -29.5656)
		(width 0.14224)
		(layer "In2.Cu")
		(net "M_G_DQ<6>")
	)
	(segment
		(start 37.55263 -33.5788)
		(end 37.85743 -33.5788)
		(width 0.14224)
		(layer "In2.Cu")
		(net "M_G_DQ<6>")
	)
	(segment
		(start 37.824918 -18.636996)
		(end 37.824918 -18.914872)
		(width 0.14224)
		(layer "In2.Cu")
		(net "M_G_DQ<6>")
	)
	(segment
		(start 37.34943 -33.3756)
		(end 37.55263 -33.5788)
		(width 0.14224)
		(layer "In2.Cu")
		(net "M_G_DQ<6>")
	)
	(segment
		(start 39.317168 -37.0078)
		(end 39.924736 -37.615368)
		(width 0.14224)
		(layer "In2.Cu")
		(net "M_G_DQ<6>")
	)
	(segment
		(start 39.317168 -36.576)
		(end 39.317168 -37.0078)
		(width 0.14224)
		(layer "In2.Cu")
		(net "M_G_DQ<6>")
	)
	(segment
		(start 37.113718 -23.324566)
		(end 37.34943 -23.560278)
		(width 0.14224)
		(layer "In2.Cu")
		(net "M_G_DQ<6>")
	)
	(segment
		(start 39.924736 -38.452806)
		(end 64.377316 -62.905386)
		(width 0.14224)
		(layer "In2.Cu")
		(net "M_G_DQ<6>")
	)
	(segment
		(start 37.886386 -21.405596)
		(end 37.886386 -21.757386)
		(width 0.14224)
		(layer "In2.Cu")
		(net "M_G_DQ<6>")
	)
	(segment
		(start 39.924736 -35.968432)
		(end 39.317168 -36.576)
		(width 0.14224)
		(layer "In2.Cu")
		(net "M_G_DQ<6>")
	)
	(segment
		(start 38.199314 -18.2626)
		(end 37.824918 -18.636996)
		(width 0.14224)
		(layer "In2.Cu")
		(net "M_G_DQ<6>")
	)
	(segment
		(start 37.824918 -18.914872)
		(end 37.460936 -19.278854)
		(width 0.14224)
		(layer "In2.Cu")
		(net "M_G_DQ<6>")
	)
	(segment
		(start 65.631568 -62.905386)
		(end 66.085974 -62.905386)
		(width 0.0889)
		(layer "In2.Cu")
		(net "M_G_DQ<6>")
	)
	(segment
		(start 64.377316 -62.905386)
		(end 65.631568 -62.905386)
		(width 0.14224)
		(layer "In2.Cu")
		(net "M_G_DQ<6>")
	)
	(segment
		(start 37.460936 -19.589496)
		(end 37.841936 -19.970496)
		(width 0.14224)
		(layer "In2.Cu")
		(net "M_G_DQ<6>")
	)
	(segment
		(start 37.460936 -20.980146)
		(end 37.886386 -21.405596)
		(width 0.14224)
		(layer "In2.Cu")
		(net "M_G_DQ<6>")
	)
	(segment
		(start 38.77183 -32.246062)
		(end 39.924736 -33.398968)
		(width 0.14224)
		(layer "In2.Cu")
		(net "M_G_DQ<6>")
	)
	(segment
		(start 37.841936 -19.970496)
		(end 37.841936 -20.313904)
		(width 0.14224)
		(layer "In2.Cu")
		(net "M_G_DQ<6>")
	)
	(segment
		(start 37.113718 -22.530054)
		(end 37.113718 -23.324566)
		(width 0.14224)
		(layer "In2.Cu")
		(net "M_G_DQ<6>")
	)
	(segment
		(start 38.56863 -29.3624)
		(end 38.77183 -29.5656)
		(width 0.14224)
		(layer "In2.Cu")
		(net "M_G_DQ<6>")
	)
	(segment
		(start 37.460936 -20.694904)
		(end 37.460936 -20.980146)
		(width 0.14224)
		(layer "In2.Cu")
		(net "M_G_DQ<6>")
	)
	(segment
		(start 37.85743 -33.5788)
		(end 38.06063 -33.3756)
		(width 0.14224)
		(layer "In2.Cu")
		(net "M_G_DQ<6>")
	)
	(segment
		(start 38.26383 -29.3624)
		(end 38.56863 -29.3624)
		(width 0.14224)
		(layer "In2.Cu")
		(net "M_G_DQ<6>")
	)
	(segment
		(start 66.46672 -62.52464)
		(end 67.101466 -62.52464)
		(width 0.0889)
		(layer "In2.Cu")
		(net "M_G_DQ<6>")
	)
	(segment
		(start 37.34943 -23.560278)
		(end 37.34943 -33.3756)
		(width 0.14224)
		(layer "In2.Cu")
		(net "M_G_DQ<6>")
	)
	(segment
		(start 38.06063 -29.5656)
		(end 38.26383 -29.3624)
		(width 0.14224)
		(layer "In2.Cu")
		(net "M_G_DQ<6>")
	)
	(segment
		(start 39.924736 -33.398968)
		(end 39.924736 -35.968432)
		(width 0.14224)
		(layer "In2.Cu")
		(net "M_G_DQ<6>")
	)
	(segment
		(start 37.460936 -19.278854)
		(end 37.460936 -19.589496)
		(width 0.14224)
		(layer "In2.Cu")
		(net "M_G_DQ<6>")
	)
	(segment
		(start 39.924736 -37.615368)
		(end 39.924736 -38.452806)
		(width 0.14224)
		(layer "In2.Cu")
		(net "M_G_DQ<6>")
	)
	(segment
		(start 38.77183 -29.5656)
		(end 38.77183 -32.246062)
		(width 0.14224)
		(layer "In2.Cu")
		(net "M_G_DQ<6>")
	)
	(segment
		(start 123.363228 -55.904384)
		(end 122.791728 -55.904384)
		(width 0.1651)
		(layer "F.Cu")
		(net "M_G_DQ<63>")
	)
	(segment
		(start 148.699474 -15.423642)
		(end 148.699474 -16.687546)
		(width 0.1651)
		(layer "F.Cu")
		(net "M_G_DQ<63>")
	)
	(via
		(at 122.791728 -55.904384)
		(size 0.508)
		(drill 0.254)
		(layers "F.Cu" "B.Cu")
		(net "M_G_DQ<63>")
	)
	(via
		(at 148.699474 -16.687546)
		(size 0.508)
		(drill 0.254)
		(layers "F.Cu" "B.Cu")
		(net "M_G_DQ<63>")
	)
	(via
		(at 149.549358 -22.279356)
		(size 0.508)
		(drill 0.254)
		(layers "F.Cu" "B.Cu")
		(net "M_G_DQ<63>")
	)
	(segment
		(start 149.549358 -22.279356)
		(end 149.549358 -20.224242)
		(width 0.1651)
		(layer "B.Cu")
		(net "M_G_DQ<63>")
	)
	(segment
		(start 123.632468 -55.999888)
		(end 123.650248 -55.999888)
		(width 0.0889)
		(layer "In2.Cu")
		(net "M_G_DQ<63>")
	)
	(segment
		(start 149.063964 -23.1267)
		(end 149.063964 -22.76475)
		(width 0.14224)
		(layer "In2.Cu")
		(net "M_G_DQ<63>")
	)
	(segment
		(start 149.754336 -23.817072)
		(end 149.063964 -23.1267)
		(width 0.14224)
		(layer "In2.Cu")
		(net "M_G_DQ<63>")
	)
	(segment
		(start 150.057612 -18.1102)
		(end 149.600412 -17.653)
		(width 0.14224)
		(layer "In2.Cu")
		(net "M_G_DQ<63>")
	)
	(segment
		(start 149.121368 -32.51962)
		(end 149.551136 -32.51962)
		(width 0.14224)
		(layer "In2.Cu")
		(net "M_G_DQ<63>")
	)
	(segment
		(start 129.559304 -48.568864)
		(end 131.184904 -48.568864)
		(width 0.14224)
		(layer "In2.Cu")
		(net "M_G_DQ<63>")
	)
	(segment
		(start 149.551136 -33.33242)
		(end 149.121368 -33.33242)
		(width 0.14224)
		(layer "In2.Cu")
		(net "M_G_DQ<63>")
	)
	(segment
		(start 148.918168 -38.061392)
		(end 148.918168 -34.34842)
		(width 0.14224)
		(layer "In2.Cu")
		(net "M_G_DQ<63>")
	)
	(segment
		(start 126.10592 -51.7906)
		(end 126.337568 -51.7906)
		(width 0.0889)
		(layer "In2.Cu")
		(net "M_G_DQ<63>")
	)
	(segment
		(start 132.484368 -47.2694)
		(end 137.132568 -47.2694)
		(width 0.14224)
		(layer "In2.Cu")
		(net "M_G_DQ<63>")
	)
	(segment
		(start 149.346412 -17.653)
		(end 148.699474 -17.006062)
		(width 0.14224)
		(layer "In2.Cu")
		(net "M_G_DQ<63>")
	)
	(segment
		(start 131.184904 -48.568864)
		(end 132.484368 -47.2694)
		(width 0.14224)
		(layer "In2.Cu")
		(net "M_G_DQ<63>")
	)
	(segment
		(start 149.902164 -21.92655)
		(end 149.902164 -18.621248)
		(width 0.14224)
		(layer "In2.Cu")
		(net "M_G_DQ<63>")
	)
	(segment
		(start 150.057612 -18.4658)
		(end 150.057612 -18.1102)
		(width 0.14224)
		(layer "In2.Cu")
		(net "M_G_DQ<63>")
	)
	(segment
		(start 123.650756 -55.99938)
		(end 123.900946 -55.99938)
		(width 0.0889)
		(layer "In2.Cu")
		(net "M_G_DQ<63>")
	)
	(segment
		(start 122.791728 -55.56631)
		(end 122.84964 -55.508398)
		(width 0.0889)
		(layer "In2.Cu")
		(net "M_G_DQ<63>")
	)
	(segment
		(start 148.918168 -34.34842)
		(end 149.121368 -34.14522)
		(width 0.14224)
		(layer "In2.Cu")
		(net "M_G_DQ<63>")
	)
	(segment
		(start 148.918168 -33.12922)
		(end 148.918168 -32.72282)
		(width 0.14224)
		(layer "In2.Cu")
		(net "M_G_DQ<63>")
	)
	(segment
		(start 123.650248 -55.999888)
		(end 123.650756 -55.99938)
		(width 0.0889)
		(layer "In2.Cu")
		(net "M_G_DQ<63>")
	)
	(segment
		(start 149.551136 -34.14522)
		(end 149.705568 -33.990788)
		(width 0.14224)
		(layer "In2.Cu")
		(net "M_G_DQ<63>")
	)
	(segment
		(start 149.600412 -17.653)
		(end 149.346412 -17.653)
		(width 0.14224)
		(layer "In2.Cu")
		(net "M_G_DQ<63>")
	)
	(segment
		(start 149.551136 -32.51962)
		(end 149.754336 -32.31642)
		(width 0.14224)
		(layer "In2.Cu")
		(net "M_G_DQ<63>")
	)
	(segment
		(start 149.549358 -22.279356)
		(end 149.902164 -21.92655)
		(width 0.14224)
		(layer "In2.Cu")
		(net "M_G_DQ<63>")
	)
	(segment
		(start 146.485864 -40.493696)
		(end 148.918168 -38.061392)
		(width 0.14224)
		(layer "In2.Cu")
		(net "M_G_DQ<63>")
	)
	(segment
		(start 122.791728 -55.904384)
		(end 122.791728 -55.56631)
		(width 0.0889)
		(layer "In2.Cu")
		(net "M_G_DQ<63>")
	)
	(segment
		(start 124.253752 -53.642768)
		(end 126.10592 -51.7906)
		(width 0.0889)
		(layer "In2.Cu")
		(net "M_G_DQ<63>")
	)
	(segment
		(start 143.908272 -40.493696)
		(end 146.485864 -40.493696)
		(width 0.14224)
		(layer "In2.Cu")
		(net "M_G_DQ<63>")
	)
	(segment
		(start 126.337568 -51.7906)
		(end 129.559304 -48.568864)
		(width 0.14224)
		(layer "In2.Cu")
		(net "M_G_DQ<63>")
	)
	(segment
		(start 148.699474 -17.006062)
		(end 148.699474 -16.687546)
		(width 0.14224)
		(layer "In2.Cu")
		(net "M_G_DQ<63>")
	)
	(segment
		(start 149.705568 -33.990788)
		(end 149.705568 -33.486852)
		(width 0.14224)
		(layer "In2.Cu")
		(net "M_G_DQ<63>")
	)
	(segment
		(start 137.132568 -47.2694)
		(end 143.908272 -40.493696)
		(width 0.14224)
		(layer "In2.Cu")
		(net "M_G_DQ<63>")
	)
	(segment
		(start 149.121368 -33.33242)
		(end 148.918168 -33.12922)
		(width 0.14224)
		(layer "In2.Cu")
		(net "M_G_DQ<63>")
	)
	(segment
		(start 148.918168 -32.72282)
		(end 149.121368 -32.51962)
		(width 0.14224)
		(layer "In2.Cu")
		(net "M_G_DQ<63>")
	)
	(segment
		(start 149.705568 -33.486852)
		(end 149.551136 -33.33242)
		(width 0.14224)
		(layer "In2.Cu")
		(net "M_G_DQ<63>")
	)
	(segment
		(start 149.121368 -34.14522)
		(end 149.551136 -34.14522)
		(width 0.14224)
		(layer "In2.Cu")
		(net "M_G_DQ<63>")
	)
	(segment
		(start 123.900946 -55.99938)
		(end 124.253752 -55.646574)
		(width 0.0889)
		(layer "In2.Cu")
		(net "M_G_DQ<63>")
	)
	(segment
		(start 149.902164 -18.621248)
		(end 150.057612 -18.4658)
		(width 0.14224)
		(layer "In2.Cu")
		(net "M_G_DQ<63>")
	)
	(segment
		(start 149.063964 -22.76475)
		(end 149.549358 -22.279356)
		(width 0.14224)
		(layer "In2.Cu")
		(net "M_G_DQ<63>")
	)
	(segment
		(start 124.253752 -55.646574)
		(end 124.253752 -53.642768)
		(width 0.0889)
		(layer "In2.Cu")
		(net "M_G_DQ<63>")
	)
	(segment
		(start 149.754336 -32.31642)
		(end 149.754336 -23.817072)
		(width 0.14224)
		(layer "In2.Cu")
		(net "M_G_DQ<63>")
	)
	(arc
		(start 122.84964 -55.508398)
		(mid 122.982847 -55.55277)
		(end 123.092464 -55.640478)
		(width 0.0889)
		(layer "In2.Cu")
		(net "M_G_DQ<63>")
	)
	(arc
		(start 123.138438 -55.704486)
		(mid 123.347046 -55.916418)
		(end 123.632468 -55.999888)
		(width 0.0889)
		(layer "In2.Cu")
		(net "M_G_DQ<63>")
	)
	(arc
		(start 123.092464 -55.640478)
		(mid 123.117008 -55.671364)
		(end 123.138438 -55.704486)
		(width 0.0889)
		(layer "In2.Cu")
		(net "M_G_DQ<63>")
	)
	(segment
		(start 149.681692 -18.91792)
		(end 149.681692 -18.69948)
		(width 0.1651)
		(layer "F.Cu")
		(net "M_G_DQ<62>")
	)
	(segment
		(start 149.681692 -18.69948)
		(end 149.549612 -18.5674)
		(width 0.1651)
		(layer "F.Cu")
		(net "M_G_DQ<62>")
	)
	(segment
		(start 149.549612 -19.05)
		(end 149.681692 -18.91792)
		(width 0.1651)
		(layer "F.Cu")
		(net "M_G_DQ<62>")
	)
	(segment
		(start 149.549612 -20.023328)
		(end 149.549612 -19.05)
		(width 0.1651)
		(layer "F.Cu")
		(net "M_G_DQ<62>")
	)
	(segment
		(start 149.549612 -18.5674)
		(end 149.549612 -18.262854)
		(width 0.1651)
		(layer "F.Cu")
		(net "M_G_DQ<62>")
	)
	(segment
		(start 123.363228 -54.913784)
		(end 122.791728 -54.913784)
		(width 0.1651)
		(layer "F.Cu")
		(net "M_G_DQ<62>")
	)
	(segment
		(start 149.549612 -18.262854)
		(end 149.549358 -18.2626)
		(width 0.1651)
		(layer "F.Cu")
		(net "M_G_DQ<62>")
	)
	(segment
		(start 149.549358 -20.023582)
		(end 149.549612 -20.023328)
		(width 0.1651)
		(layer "F.Cu")
		(net "M_G_DQ<62>")
	)
	(via
		(at 148.699474 -23.560278)
		(size 0.508)
		(drill 0.254)
		(layers "F.Cu" "B.Cu")
		(net "M_G_DQ<62>")
	)
	(via
		(at 149.549358 -18.2626)
		(size 0.508)
		(drill 0.254)
		(layers "F.Cu" "B.Cu")
		(net "M_G_DQ<62>")
	)
	(via
		(at 122.791728 -54.913784)
		(size 0.4826)
		(drill 0.254)
		(layers "F.Cu" "B.Cu")
		(net "M_G_DQ<62>")
	)
	(segment
		(start 148.699474 -23.560278)
		(end 148.699474 -24.824182)
		(width 0.1651)
		(layer "B.Cu")
		(net "M_G_DQ<62>")
	)
	(segment
		(start 146.435572 -39.515796)
		(end 148.283168 -37.6682)
		(width 0.14224)
		(layer "In2.Cu")
		(net "M_G_DQ<62>")
	)
	(segment
		(start 148.699474 -23.560278)
		(end 148.463762 -23.324566)
		(width 0.14224)
		(layer "In2.Cu")
		(net "M_G_DQ<62>")
	)
	(segment
		(start 148.890736 -24.602186)
		(end 148.662136 -24.602186)
		(width 0.14224)
		(layer "In2.Cu")
		(net "M_G_DQ<62>")
	)
	(segment
		(start 124.063252 -55.567834)
		(end 124.063252 -53.563774)
		(width 0.0889)
		(layer "In2.Cu")
		(net "M_G_DQ<62>")
	)
	(segment
		(start 129.512568 -47.9044)
		(end 130.680968 -47.9044)
		(width 0.14224)
		(layer "In2.Cu")
		(net "M_G_DQ<62>")
	)
	(segment
		(start 148.458936 -24.081232)
		(end 148.699474 -23.840694)
		(width 0.14224)
		(layer "In2.Cu")
		(net "M_G_DQ<62>")
	)
	(segment
		(start 148.283168 -27.243786)
		(end 148.486368 -27.040586)
		(width 0.14224)
		(layer "In2.Cu")
		(net "M_G_DQ<62>")
	)
	(segment
		(start 148.283168 -27.652218)
		(end 148.283168 -27.243786)
		(width 0.14224)
		(layer "In2.Cu")
		(net "M_G_DQ<62>")
	)
	(segment
		(start 149.19198 -19.970496)
		(end 148.81098 -19.589496)
		(width 0.14224)
		(layer "In2.Cu")
		(net "M_G_DQ<62>")
	)
	(segment
		(start 148.486368 -27.040586)
		(end 148.890736 -27.040586)
		(width 0.14224)
		(layer "In2.Cu")
		(net "M_G_DQ<62>")
	)
	(segment
		(start 123.639072 -55.809388)
		(end 123.821698 -55.809388)
		(width 0.0889)
		(layer "In2.Cu")
		(net "M_G_DQ<62>")
	)
	(segment
		(start 148.662136 -24.602186)
		(end 148.458936 -24.398986)
		(width 0.14224)
		(layer "In2.Cu")
		(net "M_G_DQ<62>")
	)
	(segment
		(start 148.283168 -29.277818)
		(end 148.283168 -28.871418)
		(width 0.14224)
		(layer "In2.Cu")
		(net "M_G_DQ<62>")
	)
	(segment
		(start 149.174962 -18.636996)
		(end 149.549358 -18.2626)
		(width 0.14224)
		(layer "In2.Cu")
		(net "M_G_DQ<62>")
	)
	(segment
		(start 149.095968 -29.684218)
		(end 148.892768 -29.481018)
		(width 0.14224)
		(layer "In2.Cu")
		(net "M_G_DQ<62>")
	)
	(segment
		(start 125.880368 -51.746658)
		(end 125.880368 -51.5366)
		(width 0.0889)
		(layer "In2.Cu")
		(net "M_G_DQ<62>")
	)
	(segment
		(start 148.458936 -26.202386)
		(end 148.458936 -25.618186)
		(width 0.14224)
		(layer "In2.Cu")
		(net "M_G_DQ<62>")
	)
	(segment
		(start 149.095968 -28.465018)
		(end 149.095968 -28.058618)
		(width 0.14224)
		(layer "In2.Cu")
		(net "M_G_DQ<62>")
	)
	(segment
		(start 149.174962 -18.914872)
		(end 149.174962 -18.636996)
		(width 0.14224)
		(layer "In2.Cu")
		(net "M_G_DQ<62>")
	)
	(segment
		(start 148.890736 -25.4)
		(end 149.093936 -25.1968)
		(width 0.14224)
		(layer "In2.Cu")
		(net "M_G_DQ<62>")
	)
	(segment
		(start 148.892768 -27.855418)
		(end 148.486368 -27.855418)
		(width 0.14224)
		(layer "In2.Cu")
		(net "M_G_DQ<62>")
	)
	(segment
		(start 131.950968 -46.6344)
		(end 136.776968 -46.6344)
		(width 0.14224)
		(layer "In2.Cu")
		(net "M_G_DQ<62>")
	)
	(segment
		(start 148.81098 -19.278854)
		(end 149.174962 -18.914872)
		(width 0.14224)
		(layer "In2.Cu")
		(net "M_G_DQ<62>")
	)
	(segment
		(start 124.063252 -53.563774)
		(end 125.880368 -51.746658)
		(width 0.0889)
		(layer "In2.Cu")
		(net "M_G_DQ<62>")
	)
	(segment
		(start 149.23643 -21.405596)
		(end 148.81098 -20.980146)
		(width 0.14224)
		(layer "In2.Cu")
		(net "M_G_DQ<62>")
	)
	(segment
		(start 125.880368 -51.5366)
		(end 129.512568 -47.9044)
		(width 0.14224)
		(layer "In2.Cu")
		(net "M_G_DQ<62>")
	)
	(segment
		(start 148.81098 -20.694904)
		(end 149.19198 -20.313904)
		(width 0.14224)
		(layer "In2.Cu")
		(net "M_G_DQ<62>")
	)
	(segment
		(start 148.486368 -27.855418)
		(end 148.283168 -27.652218)
		(width 0.14224)
		(layer "In2.Cu")
		(net "M_G_DQ<62>")
	)
	(segment
		(start 149.093936 -26.608786)
		(end 148.916136 -26.430986)
		(width 0.14224)
		(layer "In2.Cu")
		(net "M_G_DQ<62>")
	)
	(segment
		(start 149.19198 -20.313904)
		(end 149.19198 -19.970496)
		(width 0.14224)
		(layer "In2.Cu")
		(net "M_G_DQ<62>")
	)
	(segment
		(start 148.892768 -30.293818)
		(end 149.095968 -30.090618)
		(width 0.14224)
		(layer "In2.Cu")
		(net "M_G_DQ<62>")
	)
	(segment
		(start 122.791728 -55.251858)
		(end 122.857006 -55.317136)
		(width 0.0889)
		(layer "In2.Cu")
		(net "M_G_DQ<62>")
	)
	(segment
		(start 148.283168 -28.871418)
		(end 148.486368 -28.668218)
		(width 0.14224)
		(layer "In2.Cu")
		(net "M_G_DQ<62>")
	)
	(segment
		(start 149.093936 -26.837386)
		(end 149.093936 -26.608786)
		(width 0.14224)
		(layer "In2.Cu")
		(net "M_G_DQ<62>")
	)
	(segment
		(start 122.791728 -54.913784)
		(end 122.791728 -55.251858)
		(width 0.0889)
		(layer "In2.Cu")
		(net "M_G_DQ<62>")
	)
	(segment
		(start 149.095968 -30.090618)
		(end 149.095968 -29.684218)
		(width 0.14224)
		(layer "In2.Cu")
		(net "M_G_DQ<62>")
	)
	(segment
		(start 149.095968 -28.058618)
		(end 148.892768 -27.855418)
		(width 0.14224)
		(layer "In2.Cu")
		(net "M_G_DQ<62>")
	)
	(segment
		(start 148.486368 -30.293818)
		(end 148.892768 -30.293818)
		(width 0.14224)
		(layer "In2.Cu")
		(net "M_G_DQ<62>")
	)
	(segment
		(start 136.776968 -46.6344)
		(end 143.895572 -39.515796)
		(width 0.14224)
		(layer "In2.Cu")
		(net "M_G_DQ<62>")
	)
	(segment
		(start 148.486368 -29.481018)
		(end 148.283168 -29.277818)
		(width 0.14224)
		(layer "In2.Cu")
		(net "M_G_DQ<62>")
	)
	(segment
		(start 148.463762 -22.530054)
		(end 149.23643 -21.757386)
		(width 0.14224)
		(layer "In2.Cu")
		(net "M_G_DQ<62>")
	)
	(segment
		(start 148.81098 -20.980146)
		(end 148.81098 -20.694904)
		(width 0.14224)
		(layer "In2.Cu")
		(net "M_G_DQ<62>")
	)
	(segment
		(start 148.463762 -23.324566)
		(end 148.463762 -22.530054)
		(width 0.14224)
		(layer "In2.Cu")
		(net "M_G_DQ<62>")
	)
	(segment
		(start 148.687536 -26.430986)
		(end 148.458936 -26.202386)
		(width 0.14224)
		(layer "In2.Cu")
		(net "M_G_DQ<62>")
	)
	(segment
		(start 149.23643 -21.757386)
		(end 149.23643 -21.405596)
		(width 0.14224)
		(layer "In2.Cu")
		(net "M_G_DQ<62>")
	)
	(segment
		(start 143.895572 -39.515796)
		(end 146.435572 -39.515796)
		(width 0.14224)
		(layer "In2.Cu")
		(net "M_G_DQ<62>")
	)
	(segment
		(start 148.699474 -23.840694)
		(end 148.699474 -23.560278)
		(width 0.14224)
		(layer "In2.Cu")
		(net "M_G_DQ<62>")
	)
	(segment
		(start 148.892768 -28.668218)
		(end 149.095968 -28.465018)
		(width 0.14224)
		(layer "In2.Cu")
		(net "M_G_DQ<62>")
	)
	(segment
		(start 148.283168 -37.6682)
		(end 148.283168 -30.497018)
		(width 0.14224)
		(layer "In2.Cu")
		(net "M_G_DQ<62>")
	)
	(segment
		(start 148.916136 -26.430986)
		(end 148.687536 -26.430986)
		(width 0.14224)
		(layer "In2.Cu")
		(net "M_G_DQ<62>")
	)
	(segment
		(start 148.890736 -27.040586)
		(end 149.093936 -26.837386)
		(width 0.14224)
		(layer "In2.Cu")
		(net "M_G_DQ<62>")
	)
	(segment
		(start 149.093936 -24.805386)
		(end 148.890736 -24.602186)
		(width 0.14224)
		(layer "In2.Cu")
		(net "M_G_DQ<62>")
	)
	(segment
		(start 149.093936 -25.1968)
		(end 149.093936 -24.805386)
		(width 0.14224)
		(layer "In2.Cu")
		(net "M_G_DQ<62>")
	)
	(segment
		(start 123.821698 -55.809388)
		(end 124.063252 -55.567834)
		(width 0.0889)
		(layer "In2.Cu")
		(net "M_G_DQ<62>")
	)
	(segment
		(start 148.458936 -24.398986)
		(end 148.458936 -24.081232)
		(width 0.14224)
		(layer "In2.Cu")
		(net "M_G_DQ<62>")
	)
	(segment
		(start 148.283168 -30.497018)
		(end 148.486368 -30.293818)
		(width 0.14224)
		(layer "In2.Cu")
		(net "M_G_DQ<62>")
	)
	(segment
		(start 148.458936 -25.618186)
		(end 148.677122 -25.4)
		(width 0.14224)
		(layer "In2.Cu")
		(net "M_G_DQ<62>")
	)
	(segment
		(start 148.81098 -19.589496)
		(end 148.81098 -19.278854)
		(width 0.14224)
		(layer "In2.Cu")
		(net "M_G_DQ<62>")
	)
	(segment
		(start 130.680968 -47.9044)
		(end 131.950968 -46.6344)
		(width 0.14224)
		(layer "In2.Cu")
		(net "M_G_DQ<62>")
	)
	(segment
		(start 148.677122 -25.4)
		(end 148.890736 -25.4)
		(width 0.14224)
		(layer "In2.Cu")
		(net "M_G_DQ<62>")
	)
	(segment
		(start 148.892768 -29.481018)
		(end 148.486368 -29.481018)
		(width 0.14224)
		(layer "In2.Cu")
		(net "M_G_DQ<62>")
	)
	(segment
		(start 148.486368 -28.668218)
		(end 148.892768 -28.668218)
		(width 0.14224)
		(layer "In2.Cu")
		(net "M_G_DQ<62>")
	)
	(arc
		(start 123.303538 -55.609236)
		(mid 123.445221 -55.75304)
		(end 123.639072 -55.809388)
		(width 0.0889)
		(layer "In2.Cu")
		(net "M_G_DQ<62>")
	)
	(arc
		(start 122.857006 -55.317136)
		(mid 123.115143 -55.40989)
		(end 123.303538 -55.609236)
		(width 0.0889)
		(layer "In2.Cu")
		(net "M_G_DQ<62>")
	)
	(segment
		(start 142.749524 -15.423642)
		(end 142.749524 -16.687546)
		(width 0.1651)
		(layer "F.Cu")
		(net "M_G_DQ<61>")
	)
	(segment
		(start 120.216168 -57.390538)
		(end 120.787668 -57.390538)
		(width 0.1016)
		(layer "F.Cu")
		(net "M_G_DQ<61>")
	)
	(via
		(at 143.577564 -22.192996)
		(size 0.508)
		(drill 0.254)
		(layers "F.Cu" "B.Cu")
		(net "M_G_DQ<61>")
	)
	(via
		(at 120.216168 -57.390538)
		(size 0.508)
		(drill 0.254)
		(layers "F.Cu" "B.Cu")
		(net "M_G_DQ<61>")
	)
	(via
		(at 142.749524 -16.687546)
		(size 0.508)
		(drill 0.254)
		(layers "F.Cu" "B.Cu")
		(net "M_G_DQ<61>")
	)
	(segment
		(start 143.599408 -20.224242)
		(end 143.599408 -22.171152)
		(width 0.1651)
		(layer "B.Cu")
		(net "M_G_DQ<61>")
	)
	(segment
		(start 143.599408 -22.171152)
		(end 143.577564 -22.192996)
		(width 0.1651)
		(layer "B.Cu")
		(net "M_G_DQ<61>")
	)
	(segment
		(start 143.834612 -21.935948)
		(end 143.834612 -18.66265)
		(width 0.14224)
		(layer "In2.Cu")
		(net "M_G_DQ<61>")
	)
	(segment
		(start 144.034764 -33.179004)
		(end 144.034764 -32.650684)
		(width 0.14224)
		(layer "In2.Cu")
		(net "M_G_DQ<61>")
	)
	(segment
		(start 144.031462 -18.4658)
		(end 144.031462 -18.053304)
		(width 0.14224)
		(layer "In2.Cu")
		(net "M_G_DQ<61>")
	)
	(segment
		(start 121.765568 -50.8508)
		(end 121.765568 -50.114454)
		(width 0.0889)
		(layer "In2.Cu")
		(net "M_G_DQ<61>")
	)
	(segment
		(start 143.228568 -31.014924)
		(end 143.228568 -30.661864)
		(width 0.14224)
		(layer "In2.Cu")
		(net "M_G_DQ<61>")
	)
	(segment
		(start 143.834612 -18.66265)
		(end 144.031462 -18.4658)
		(width 0.14224)
		(layer "In2.Cu")
		(net "M_G_DQ<61>")
	)
	(segment
		(start 143.406368 -31.832804)
		(end 143.879824 -31.832804)
		(width 0.14224)
		(layer "In2.Cu")
		(net "M_G_DQ<61>")
	)
	(segment
		(start 128.045972 -44.951396)
		(end 131.925568 -41.0718)
		(width 0.14224)
		(layer "In2.Cu")
		(net "M_G_DQ<61>")
	)
	(segment
		(start 143.279368 -31.959804)
		(end 143.406368 -31.832804)
		(width 0.14224)
		(layer "In2.Cu")
		(net "M_G_DQ<61>")
	)
	(segment
		(start 120.016016 -55.809896)
		(end 119.910606 -55.68061)
		(width 0.0889)
		(layer "In2.Cu")
		(net "M_G_DQ<61>")
	)
	(segment
		(start 143.879824 -32.495744)
		(end 143.406368 -32.495744)
		(width 0.14224)
		(layer "In2.Cu")
		(net "M_G_DQ<61>")
	)
	(segment
		(start 122.222768 -49.860454)
		(end 123.416568 -48.666654)
		(width 0.14224)
		(layer "In2.Cu")
		(net "M_G_DQ<61>")
	)
	(segment
		(start 143.383508 -31.169864)
		(end 143.228568 -31.014924)
		(width 0.14224)
		(layer "In2.Cu")
		(net "M_G_DQ<61>")
	)
	(segment
		(start 143.523208 -22.247352)
		(end 143.577564 -22.192996)
		(width 0.14224)
		(layer "In2.Cu")
		(net "M_G_DQ<61>")
	)
	(segment
		(start 119.910606 -55.68061)
		(end 119.864632 -55.6006)
		(width 0.0889)
		(layer "In2.Cu")
		(net "M_G_DQ<61>")
	)
	(segment
		(start 143.279368 -32.368744)
		(end 143.279368 -31.959804)
		(width 0.14224)
		(layer "In2.Cu")
		(net "M_G_DQ<61>")
	)
	(segment
		(start 143.406368 -32.495744)
		(end 143.279368 -32.368744)
		(width 0.14224)
		(layer "In2.Cu")
		(net "M_G_DQ<61>")
	)
	(segment
		(start 144.034764 -25.46985)
		(end 143.679164 -25.11425)
		(width 0.14224)
		(layer "In2.Cu")
		(net "M_G_DQ<61>")
	)
	(segment
		(start 119.949468 -53.458618)
		(end 120.805194 -52.602892)
		(width 0.0889)
		(layer "In2.Cu")
		(net "M_G_DQ<61>")
	)
	(segment
		(start 123.779026 -44.951396)
		(end 128.045972 -44.951396)
		(width 0.14224)
		(layer "In2.Cu")
		(net "M_G_DQ<61>")
	)
	(segment
		(start 119.875808 -54.629304)
		(end 119.869458 -54.618636)
		(width 0.0889)
		(layer "In2.Cu")
		(net "M_G_DQ<61>")
	)
	(segment
		(start 143.320262 -17.653)
		(end 142.749524 -17.082262)
		(width 0.14224)
		(layer "In2.Cu")
		(net "M_G_DQ<61>")
	)
	(segment
		(start 144.034764 -30.351984)
		(end 144.034764 -25.46985)
		(width 0.14224)
		(layer "In2.Cu")
		(net "M_G_DQ<61>")
	)
	(segment
		(start 120.545606 -56.629554)
		(end 120.567704 -56.5912)
		(width 0.0889)
		(layer "In2.Cu")
		(net "M_G_DQ<61>")
	)
	(segment
		(start 143.679164 -25.11425)
		(end 143.679164 -23.68804)
		(width 0.14224)
		(layer "In2.Cu")
		(net "M_G_DQ<61>")
	)
	(segment
		(start 120.172226 -55.950612)
		(end 120.016016 -55.809896)
		(width 0.0889)
		(layer "In2.Cu")
		(net "M_G_DQ<61>")
	)
	(segment
		(start 143.228568 -30.661864)
		(end 143.383508 -30.506924)
		(width 0.14224)
		(layer "In2.Cu")
		(net "M_G_DQ<61>")
	)
	(segment
		(start 119.869458 -54.618636)
		(end 119.864632 -54.61)
		(width 0.0889)
		(layer "In2.Cu")
		(net "M_G_DQ<61>")
	)
	(segment
		(start 143.383508 -30.506924)
		(end 143.879824 -30.506924)
		(width 0.14224)
		(layer "In2.Cu")
		(net "M_G_DQ<61>")
	)
	(segment
		(start 143.631158 -17.653)
		(end 143.320262 -17.653)
		(width 0.14224)
		(layer "In2.Cu")
		(net "M_G_DQ<61>")
	)
	(segment
		(start 143.879824 -31.169864)
		(end 143.383508 -31.169864)
		(width 0.14224)
		(layer "In2.Cu")
		(net "M_G_DQ<61>")
	)
	(segment
		(start 143.879824 -31.832804)
		(end 144.034764 -31.677864)
		(width 0.14224)
		(layer "In2.Cu")
		(net "M_G_DQ<61>")
	)
	(segment
		(start 131.925568 -41.0718)
		(end 136.141968 -41.0718)
		(width 0.14224)
		(layer "In2.Cu")
		(net "M_G_DQ<61>")
	)
	(segment
		(start 143.577564 -22.192996)
		(end 143.834612 -21.935948)
		(width 0.14224)
		(layer "In2.Cu")
		(net "M_G_DQ<61>")
	)
	(segment
		(start 121.765568 -50.114454)
		(end 122.019568 -49.860454)
		(width 0.0889)
		(layer "In2.Cu")
		(net "M_G_DQ<61>")
	)
	(segment
		(start 136.141968 -41.0718)
		(end 144.034764 -33.179004)
		(width 0.14224)
		(layer "In2.Cu")
		(net "M_G_DQ<61>")
	)
	(segment
		(start 144.034764 -31.324804)
		(end 143.879824 -31.169864)
		(width 0.14224)
		(layer "In2.Cu")
		(net "M_G_DQ<61>")
	)
	(segment
		(start 120.37949 -56.034432)
		(end 120.172226 -55.950612)
		(width 0.0889)
		(layer "In2.Cu")
		(net "M_G_DQ<61>")
	)
	(segment
		(start 123.416568 -48.666654)
		(end 123.416568 -45.313854)
		(width 0.14224)
		(layer "In2.Cu")
		(net "M_G_DQ<61>")
	)
	(segment
		(start 119.869458 -54.218586)
		(end 119.949468 -54.092602)
		(width 0.0889)
		(layer "In2.Cu")
		(net "M_G_DQ<61>")
	)
	(segment
		(start 122.019568 -49.860454)
		(end 122.222768 -49.860454)
		(width 0.0889)
		(layer "In2.Cu")
		(net "M_G_DQ<61>")
	)
	(segment
		(start 120.805194 -51.811174)
		(end 121.765568 -50.8508)
		(width 0.0889)
		(layer "In2.Cu")
		(net "M_G_DQ<61>")
	)
	(segment
		(start 119.949468 -54.092602)
		(end 119.949468 -53.458618)
		(width 0.0889)
		(layer "In2.Cu")
		(net "M_G_DQ<61>")
	)
	(segment
		(start 143.523208 -23.532084)
		(end 143.523208 -22.247352)
		(width 0.14224)
		(layer "In2.Cu")
		(net "M_G_DQ<61>")
	)
	(segment
		(start 120.216168 -57.390538)
		(end 120.545606 -56.629554)
		(width 0.0889)
		(layer "In2.Cu")
		(net "M_G_DQ<61>")
	)
	(segment
		(start 123.416568 -45.313854)
		(end 123.779026 -44.951396)
		(width 0.14224)
		(layer "In2.Cu")
		(net "M_G_DQ<61>")
	)
	(segment
		(start 143.679164 -23.68804)
		(end 143.523208 -23.532084)
		(width 0.14224)
		(layer "In2.Cu")
		(net "M_G_DQ<61>")
	)
	(segment
		(start 120.805194 -52.602892)
		(end 120.805194 -51.811174)
		(width 0.0889)
		(layer "In2.Cu")
		(net "M_G_DQ<61>")
	)
	(segment
		(start 142.749524 -17.082262)
		(end 142.749524 -16.687546)
		(width 0.14224)
		(layer "In2.Cu")
		(net "M_G_DQ<61>")
	)
	(segment
		(start 144.031462 -18.053304)
		(end 143.631158 -17.653)
		(width 0.14224)
		(layer "In2.Cu")
		(net "M_G_DQ<61>")
	)
	(segment
		(start 144.034764 -31.677864)
		(end 144.034764 -31.324804)
		(width 0.14224)
		(layer "In2.Cu")
		(net "M_G_DQ<61>")
	)
	(segment
		(start 143.879824 -30.506924)
		(end 144.034764 -30.351984)
		(width 0.14224)
		(layer "In2.Cu")
		(net "M_G_DQ<61>")
	)
	(segment
		(start 144.034764 -32.650684)
		(end 143.879824 -32.495744)
		(width 0.14224)
		(layer "In2.Cu")
		(net "M_G_DQ<61>")
	)
	(arc
		(start 119.864632 -54.61)
		(mid 119.815877 -54.413648)
		(end 119.869458 -54.218586)
		(width 0.0889)
		(layer "In2.Cu")
		(net "M_G_DQ<61>")
	)
	(arc
		(start 119.864632 -55.6006)
		(mid 119.815877 -55.404248)
		(end 119.869458 -55.209186)
		(width 0.0889)
		(layer "In2.Cu")
		(net "M_G_DQ<61>")
	)
	(arc
		(start 119.869458 -55.209186)
		(mid 119.94868 -54.920068)
		(end 119.875808 -54.629304)
		(width 0.0889)
		(layer "In2.Cu")
		(net "M_G_DQ<61>")
	)
	(arc
		(start 120.567704 -56.5912)
		(mid 120.59527 -56.271717)
		(end 120.37949 -56.034432)
		(width 0.0889)
		(layer "In2.Cu")
		(net "M_G_DQ<61>")
	)
	(segment
		(start 143.599408 -20.023582)
		(end 143.599408 -18.692368)
		(width 0.1651)
		(layer "F.Cu")
		(net "M_G_DQ<60>")
	)
	(segment
		(start 120.216168 -56.399938)
		(end 120.787668 -56.399938)
		(width 0.1016)
		(layer "F.Cu")
		(net "M_G_DQ<60>")
	)
	(segment
		(start 143.599408 -18.692368)
		(end 143.501364 -18.161)
		(width 0.1651)
		(layer "F.Cu")
		(net "M_G_DQ<60>")
	)
	(via
		(at 142.749524 -23.560278)
		(size 0.508)
		(drill 0.254)
		(layers "F.Cu" "B.Cu")
		(net "M_G_DQ<60>")
	)
	(via
		(at 120.216168 -56.399938)
		(size 0.508)
		(drill 0.254)
		(layers "F.Cu" "B.Cu")
		(net "M_G_DQ<60>")
	)
	(via
		(at 143.501364 -18.161)
		(size 0.508)
		(drill 0.254)
		(layers "F.Cu" "B.Cu")
		(net "M_G_DQ<60>")
	)
	(segment
		(start 142.749524 -23.560278)
		(end 142.749524 -24.824182)
		(width 0.1651)
		(layer "B.Cu")
		(net "M_G_DQ<60>")
	)
	(segment
		(start 121.232168 -47.581058)
		(end 121.232168 -47.227998)
		(width 0.14224)
		(layer "In2.Cu")
		(net "M_G_DQ<60>")
	)
	(segment
		(start 122.857768 -46.918118)
		(end 122.857768 -46.565058)
		(width 0.14224)
		(layer "In2.Cu")
		(net "M_G_DQ<60>")
	)
	(segment
		(start 119.704358 -54.713886)
		(end 119.698008 -54.703218)
		(width 0.0889)
		(layer "In2.Cu")
		(net "M_G_DQ<60>")
	)
	(segment
		(start 121.841768 -49.403254)
		(end 121.841768 -48.553878)
		(width 0.14224)
		(layer "In2.Cu")
		(net "M_G_DQ<60>")
	)
	(segment
		(start 142.513812 -23.324566)
		(end 142.513812 -22.530054)
		(width 0.14224)
		(layer "In2.Cu")
		(net "M_G_DQ<60>")
	)
	(segment
		(start 122.702828 -47.073058)
		(end 122.857768 -46.918118)
		(width 0.14224)
		(layer "In2.Cu")
		(net "M_G_DQ<60>")
	)
	(segment
		(start 142.749524 -23.560278)
		(end 142.513812 -23.324566)
		(width 0.14224)
		(layer "In2.Cu")
		(net "M_G_DQ<60>")
	)
	(segment
		(start 143.24203 -20.2692)
		(end 143.24203 -19.9644)
		(width 0.14224)
		(layer "In2.Cu")
		(net "M_G_DQ<60>")
	)
	(segment
		(start 143.225012 -18.437352)
		(end 143.501364 -18.161)
		(width 0.14224)
		(layer "In2.Cu")
		(net "M_G_DQ<60>")
	)
	(segment
		(start 142.86103 -19.5834)
		(end 142.86103 -19.278854)
		(width 0.14224)
		(layer "In2.Cu")
		(net "M_G_DQ<60>")
	)
	(segment
		(start 122.753628 -48.398938)
		(end 122.908568 -48.243998)
		(width 0.14224)
		(layer "In2.Cu")
		(net "M_G_DQ<60>")
	)
	(segment
		(start 121.996708 -48.398938)
		(end 122.753628 -48.398938)
		(width 0.14224)
		(layer "In2.Cu")
		(net "M_G_DQ<60>")
	)
	(segment
		(start 121.841768 -48.553878)
		(end 121.996708 -48.398938)
		(width 0.14224)
		(layer "In2.Cu")
		(net "M_G_DQ<60>")
	)
	(segment
		(start 119.78386 -55.84444)
		(end 119.704358 -55.704486)
		(width 0.0889)
		(layer "In2.Cu")
		(net "M_G_DQ<60>")
	)
	(segment
		(start 122.908568 -48.243998)
		(end 122.908568 -47.890938)
		(width 0.14224)
		(layer "In2.Cu")
		(net "M_G_DQ<60>")
	)
	(segment
		(start 143.399764 -25.697942)
		(end 143.044164 -25.342342)
		(width 0.14224)
		(layer "In2.Cu")
		(net "M_G_DQ<60>")
	)
	(segment
		(start 121.232168 -47.227998)
		(end 121.387108 -47.073058)
		(width 0.14224)
		(layer "In2.Cu")
		(net "M_G_DQ<60>")
	)
	(segment
		(start 119.758968 -54.028848)
		(end 119.758968 -53.379624)
		(width 0.0889)
		(layer "In2.Cu")
		(net "M_G_DQ<60>")
	)
	(segment
		(start 121.56313 -49.911)
		(end 121.841768 -49.632362)
		(width 0.0889)
		(layer "In2.Cu")
		(net "M_G_DQ<60>")
	)
	(segment
		(start 143.399764 -29.140404)
		(end 143.399764 -25.697942)
		(width 0.14224)
		(layer "In2.Cu")
		(net "M_G_DQ<60>")
	)
	(segment
		(start 119.804942 -56.346344)
		(end 119.804942 -55.923434)
		(width 0.0889)
		(layer "In2.Cu")
		(net "M_G_DQ<60>")
	)
	(segment
		(start 121.56313 -50.783236)
		(end 121.56313 -49.911)
		(width 0.0889)
		(layer "In2.Cu")
		(net "M_G_DQ<60>")
	)
	(segment
		(start 142.87373 -20.6375)
		(end 143.24203 -20.2692)
		(width 0.14224)
		(layer "In2.Cu")
		(net "M_G_DQ<60>")
	)
	(segment
		(start 119.858536 -56.399938)
		(end 119.804942 -56.346344)
		(width 0.0889)
		(layer "In2.Cu")
		(net "M_G_DQ<60>")
	)
	(segment
		(start 143.24203 -19.9644)
		(end 142.86103 -19.5834)
		(width 0.14224)
		(layer "In2.Cu")
		(net "M_G_DQ<60>")
	)
	(segment
		(start 142.87373 -20.992846)
		(end 142.87373 -20.6375)
		(width 0.14224)
		(layer "In2.Cu")
		(net "M_G_DQ<60>")
	)
	(segment
		(start 119.704358 -54.123336)
		(end 119.758968 -54.028848)
		(width 0.0889)
		(layer "In2.Cu")
		(net "M_G_DQ<60>")
	)
	(segment
		(start 135.989568 -40.259)
		(end 142.466568 -33.782)
		(width 0.14224)
		(layer "In2.Cu")
		(net "M_G_DQ<60>")
	)
	(segment
		(start 119.709184 -54.722522)
		(end 119.704358 -54.713886)
		(width 0.0889)
		(layer "In2.Cu")
		(net "M_G_DQ<60>")
	)
	(segment
		(start 142.466568 -33.782)
		(end 142.466568 -30.0736)
		(width 0.14224)
		(layer "In2.Cu")
		(net "M_G_DQ<60>")
	)
	(segment
		(start 119.704358 -55.704486)
		(end 119.698008 -55.693818)
		(width 0.0889)
		(layer "In2.Cu")
		(net "M_G_DQ<60>")
	)
	(segment
		(start 122.857768 -46.565058)
		(end 122.702828 -46.410118)
		(width 0.14224)
		(layer "In2.Cu")
		(net "M_G_DQ<60>")
	)
	(segment
		(start 143.225012 -18.914872)
		(end 143.225012 -18.437352)
		(width 0.14224)
		(layer "In2.Cu")
		(net "M_G_DQ<60>")
	)
	(segment
		(start 121.996708 -46.410118)
		(end 121.841768 -46.255178)
		(width 0.14224)
		(layer "In2.Cu")
		(net "M_G_DQ<60>")
	)
	(segment
		(start 121.387108 -47.073058)
		(end 122.702828 -47.073058)
		(width 0.14224)
		(layer "In2.Cu")
		(net "M_G_DQ<60>")
	)
	(segment
		(start 121.387108 -47.735998)
		(end 121.232168 -47.581058)
		(width 0.14224)
		(layer "In2.Cu")
		(net "M_G_DQ<60>")
	)
	(segment
		(start 122.680222 -44.3992)
		(end 127.760222 -44.3992)
		(width 0.14224)
		(layer "In2.Cu")
		(net "M_G_DQ<60>")
	)
	(segment
		(start 122.753628 -47.735998)
		(end 121.387108 -47.735998)
		(width 0.14224)
		(layer "In2.Cu")
		(net "M_G_DQ<60>")
	)
	(segment
		(start 121.841768 -46.255178)
		(end 121.841768 -45.237654)
		(width 0.14224)
		(layer "In2.Cu")
		(net "M_G_DQ<60>")
	)
	(segment
		(start 131.900422 -40.259)
		(end 135.989568 -40.259)
		(width 0.14224)
		(layer "In2.Cu")
		(net "M_G_DQ<60>")
	)
	(segment
		(start 122.702828 -46.410118)
		(end 121.996708 -46.410118)
		(width 0.14224)
		(layer "In2.Cu")
		(net "M_G_DQ<60>")
	)
	(segment
		(start 143.225012 -21.818854)
		(end 143.225012 -21.344128)
		(width 0.14224)
		(layer "In2.Cu")
		(net "M_G_DQ<60>")
	)
	(segment
		(start 143.044164 -23.854918)
		(end 142.749524 -23.560278)
		(width 0.14224)
		(layer "In2.Cu")
		(net "M_G_DQ<60>")
	)
	(segment
		(start 142.513812 -22.530054)
		(end 143.225012 -21.818854)
		(width 0.14224)
		(layer "In2.Cu")
		(net "M_G_DQ<60>")
	)
	(segment
		(start 143.044164 -25.342342)
		(end 143.044164 -23.854918)
		(width 0.14224)
		(layer "In2.Cu")
		(net "M_G_DQ<60>")
	)
	(segment
		(start 127.760222 -44.3992)
		(end 131.900422 -40.259)
		(width 0.14224)
		(layer "In2.Cu")
		(net "M_G_DQ<60>")
	)
	(segment
		(start 121.841768 -45.237654)
		(end 122.680222 -44.3992)
		(width 0.14224)
		(layer "In2.Cu")
		(net "M_G_DQ<60>")
	)
	(segment
		(start 120.614694 -51.731672)
		(end 121.56313 -50.783236)
		(width 0.0889)
		(layer "In2.Cu")
		(net "M_G_DQ<60>")
	)
	(segment
		(start 143.225012 -21.344128)
		(end 142.87373 -20.992846)
		(width 0.14224)
		(layer "In2.Cu")
		(net "M_G_DQ<60>")
	)
	(segment
		(start 142.466568 -30.0736)
		(end 143.399764 -29.140404)
		(width 0.14224)
		(layer "In2.Cu")
		(net "M_G_DQ<60>")
	)
	(segment
		(start 120.614694 -52.523898)
		(end 120.614694 -51.731672)
		(width 0.0889)
		(layer "In2.Cu")
		(net "M_G_DQ<60>")
	)
	(segment
		(start 119.758968 -53.379624)
		(end 120.614694 -52.523898)
		(width 0.0889)
		(layer "In2.Cu")
		(net "M_G_DQ<60>")
	)
	(segment
		(start 120.216168 -56.399938)
		(end 119.858536 -56.399938)
		(width 0.0889)
		(layer "In2.Cu")
		(net "M_G_DQ<60>")
	)
	(segment
		(start 122.908568 -47.890938)
		(end 122.753628 -47.735998)
		(width 0.14224)
		(layer "In2.Cu")
		(net "M_G_DQ<60>")
	)
	(segment
		(start 121.841768 -49.632362)
		(end 121.841768 -49.403254)
		(width 0.0889)
		(layer "In2.Cu")
		(net "M_G_DQ<60>")
	)
	(segment
		(start 142.86103 -19.278854)
		(end 143.225012 -18.914872)
		(width 0.14224)
		(layer "In2.Cu")
		(net "M_G_DQ<60>")
	)
	(arc
		(start 119.698008 -55.693818)
		(mid 119.62521 -55.403055)
		(end 119.704358 -55.113936)
		(width 0.0889)
		(layer "In2.Cu")
		(net "M_G_DQ<60>")
	)
	(arc
		(start 119.698008 -54.703218)
		(mid 119.62521 -54.412455)
		(end 119.704358 -54.123336)
		(width 0.0889)
		(layer "In2.Cu")
		(net "M_G_DQ<60>")
	)
	(arc
		(start 119.804942 -55.923434)
		(mid 119.799491 -55.882577)
		(end 119.78386 -55.84444)
		(width 0.0889)
		(layer "In2.Cu")
		(net "M_G_DQ<60>")
	)
	(arc
		(start 119.704358 -55.113936)
		(mid 119.757828 -54.918873)
		(end 119.709184 -54.722522)
		(width 0.0889)
		(layer "In2.Cu")
		(net "M_G_DQ<60>")
	)
	(segment
		(start 69.466206 -66.48704)
		(end 68.894706 -66.48704)
		(width 0.1651)
		(layer "F.Cu")
		(net "M_G_DQ<5>")
	)
	(segment
		(start 31.39948 -16.687546)
		(end 31.39948 -15.423642)
		(width 0.1651)
		(layer "F.Cu")
		(net "M_G_DQ<5>")
	)
	(via
		(at 32.173164 -22.279356)
		(size 0.508)
		(drill 0.254)
		(layers "F.Cu" "B.Cu")
		(net "M_G_DQ<5>")
	)
	(via
		(at 68.894706 -66.48704)
		(size 0.508)
		(drill 0.254)
		(layers "F.Cu" "B.Cu")
		(net "M_G_DQ<5>")
	)
	(via
		(at 31.39948 -16.687546)
		(size 0.508)
		(drill 0.254)
		(layers "F.Cu" "B.Cu")
		(net "M_G_DQ<5>")
	)
	(segment
		(start 32.249364 -22.203156)
		(end 32.173164 -22.279356)
		(width 0.1651)
		(layer "B.Cu")
		(net "M_G_DQ<5>")
	)
	(segment
		(start 32.249364 -20.224242)
		(end 32.249364 -22.203156)
		(width 0.1651)
		(layer "B.Cu")
		(net "M_G_DQ<5>")
	)
	(segment
		(start 32.863536 -32.942022)
		(end 32.863536 -36.854384)
		(width 0.14224)
		(layer "In2.Cu")
		(net "M_G_DQ<5>")
	)
	(segment
		(start 62.776354 -66.767202)
		(end 65.504568 -66.767202)
		(width 0.14224)
		(layer "In2.Cu")
		(net "M_G_DQ<5>")
	)
	(segment
		(start 66.938398 -66.003424)
		(end 67.375786 -66.003424)
		(width 0.0889)
		(layer "In2.Cu")
		(net "M_G_DQ<5>")
	)
	(segment
		(start 32.681418 -18.053304)
		(end 32.681418 -18.4658)
		(width 0.14224)
		(layer "In2.Cu")
		(net "M_G_DQ<5>")
	)
	(segment
		(start 32.863536 -36.854384)
		(end 62.776354 -66.767202)
		(width 0.14224)
		(layer "In2.Cu")
		(net "M_G_DQ<5>")
	)
	(segment
		(start 32.484568 -18.66265)
		(end 32.484568 -21.967952)
		(width 0.14224)
		(layer "In2.Cu")
		(net "M_G_DQ<5>")
	)
	(segment
		(start 31.39948 -16.687546)
		(end 31.39948 -17.082262)
		(width 0.14224)
		(layer "In2.Cu")
		(net "M_G_DQ<5>")
	)
	(segment
		(start 31.39948 -17.082262)
		(end 31.970218 -17.653)
		(width 0.14224)
		(layer "In2.Cu")
		(net "M_G_DQ<5>")
	)
	(segment
		(start 31.970218 -17.653)
		(end 32.281114 -17.653)
		(width 0.14224)
		(layer "In2.Cu")
		(net "M_G_DQ<5>")
	)
	(segment
		(start 67.375786 -66.003424)
		(end 67.859402 -66.48704)
		(width 0.0889)
		(layer "In2.Cu")
		(net "M_G_DQ<5>")
	)
	(segment
		(start 32.484568 -21.967952)
		(end 32.173164 -22.279356)
		(width 0.14224)
		(layer "In2.Cu")
		(net "M_G_DQ<5>")
	)
	(segment
		(start 66.17462 -66.767202)
		(end 66.938398 -66.003424)
		(width 0.0889)
		(layer "In2.Cu")
		(net "M_G_DQ<5>")
	)
	(segment
		(start 67.859402 -66.48704)
		(end 68.894706 -66.48704)
		(width 0.0889)
		(layer "In2.Cu")
		(net "M_G_DQ<5>")
	)
	(segment
		(start 32.173164 -22.279356)
		(end 31.695136 -22.757384)
		(width 0.14224)
		(layer "In2.Cu")
		(net "M_G_DQ<5>")
	)
	(segment
		(start 32.681418 -18.4658)
		(end 32.484568 -18.66265)
		(width 0.14224)
		(layer "In2.Cu")
		(net "M_G_DQ<5>")
	)
	(segment
		(start 31.695136 -22.757384)
		(end 31.695136 -23.128224)
		(width 0.14224)
		(layer "In2.Cu")
		(net "M_G_DQ<5>")
	)
	(segment
		(start 31.695136 -23.128224)
		(end 31.85668 -23.289768)
		(width 0.14224)
		(layer "In2.Cu")
		(net "M_G_DQ<5>")
	)
	(segment
		(start 31.85668 -23.289768)
		(end 31.85668 -31.935166)
		(width 0.14224)
		(layer "In2.Cu")
		(net "M_G_DQ<5>")
	)
	(segment
		(start 31.85668 -31.935166)
		(end 32.863536 -32.942022)
		(width 0.14224)
		(layer "In2.Cu")
		(net "M_G_DQ<5>")
	)
	(segment
		(start 65.504568 -66.767202)
		(end 66.17462 -66.767202)
		(width 0.0889)
		(layer "In2.Cu")
		(net "M_G_DQ<5>")
	)
	(segment
		(start 32.281114 -17.653)
		(end 32.681418 -18.053304)
		(width 0.14224)
		(layer "In2.Cu")
		(net "M_G_DQ<5>")
	)
	(segment
		(start 123.363228 -58.876438)
		(end 122.791728 -58.876438)
		(width 0.1016)
		(layer "F.Cu")
		(net "M_G_DQ<59>")
	)
	(segment
		(start 150.399496 -15.423642)
		(end 150.399496 -16.687546)
		(width 0.1651)
		(layer "F.Cu")
		(net "M_G_DQ<59>")
	)
	(via
		(at 122.791728 -58.876438)
		(size 0.4826)
		(drill 0.254)
		(layers "F.Cu" "B.Cu")
		(net "M_G_DQ<59>")
	)
	(via
		(at 151.24938 -22.279356)
		(size 0.508)
		(drill 0.254)
		(layers "F.Cu" "B.Cu")
		(net "M_G_DQ<59>")
	)
	(via
		(at 150.399496 -16.687546)
		(size 0.508)
		(drill 0.254)
		(layers "F.Cu" "B.Cu")
		(net "M_G_DQ<59>")
	)
	(segment
		(start 151.24938 -22.279356)
		(end 151.24938 -20.224242)
		(width 0.1651)
		(layer "B.Cu")
		(net "M_G_DQ<59>")
	)
	(segment
		(start 128.492504 -51.642264)
		(end 137.183368 -49.149)
		(width 0.14224)
		(layer "In2.Cu")
		(net "M_G_DQ<59>")
	)
	(segment
		(start 150.399496 -17.006062)
		(end 150.399496 -16.687546)
		(width 0.14224)
		(layer "In2.Cu")
		(net "M_G_DQ<59>")
	)
	(segment
		(start 124.294392 -56.990488)
		(end 125.020832 -56.264048)
		(width 0.0889)
		(layer "In2.Cu")
		(net "M_G_DQ<59>")
	)
	(segment
		(start 150.797768 -23.1648)
		(end 150.797768 -22.730968)
		(width 0.14224)
		(layer "In2.Cu")
		(net "M_G_DQ<59>")
	)
	(segment
		(start 123.635262 -56.990488)
		(end 124.294392 -56.990488)
		(width 0.0889)
		(layer "In2.Cu")
		(net "M_G_DQ<59>")
	)
	(segment
		(start 151.046434 -17.653)
		(end 150.399496 -17.006062)
		(width 0.14224)
		(layer "In2.Cu")
		(net "M_G_DQ<59>")
	)
	(segment
		(start 151.051768 -37.807392)
		(end 151.051768 -23.4188)
		(width 0.14224)
		(layer "In2.Cu")
		(net "M_G_DQ<59>")
	)
	(segment
		(start 151.051768 -23.4188)
		(end 150.797768 -23.1648)
		(width 0.14224)
		(layer "In2.Cu")
		(net "M_G_DQ<59>")
	)
	(segment
		(start 137.183368 -49.149)
		(end 143.832072 -42.500296)
		(width 0.14224)
		(layer "In2.Cu")
		(net "M_G_DQ<59>")
	)
	(segment
		(start 151.300434 -17.653)
		(end 151.046434 -17.653)
		(width 0.14224)
		(layer "In2.Cu")
		(net "M_G_DQ<59>")
	)
	(segment
		(start 125.020832 -53.95976)
		(end 126.427992 -52.5526)
		(width 0.0889)
		(layer "In2.Cu")
		(net "M_G_DQ<59>")
	)
	(segment
		(start 151.757634 -18.4658)
		(end 151.757634 -18.1102)
		(width 0.14224)
		(layer "In2.Cu")
		(net "M_G_DQ<59>")
	)
	(segment
		(start 150.797768 -22.730968)
		(end 151.24938 -22.279356)
		(width 0.14224)
		(layer "In2.Cu")
		(net "M_G_DQ<59>")
	)
	(segment
		(start 146.358864 -42.500296)
		(end 151.051768 -37.807392)
		(width 0.14224)
		(layer "In2.Cu")
		(net "M_G_DQ<59>")
	)
	(segment
		(start 122.791728 -58.876438)
		(end 122.791728 -58.538364)
		(width 0.0889)
		(layer "In2.Cu")
		(net "M_G_DQ<59>")
	)
	(segment
		(start 123.309888 -57.601104)
		(end 123.303538 -57.590436)
		(width 0.0889)
		(layer "In2.Cu")
		(net "M_G_DQ<59>")
	)
	(segment
		(start 122.791728 -58.538364)
		(end 122.857006 -58.473086)
		(width 0.0889)
		(layer "In2.Cu")
		(net "M_G_DQ<59>")
	)
	(segment
		(start 151.602186 -18.621248)
		(end 151.757634 -18.4658)
		(width 0.14224)
		(layer "In2.Cu")
		(net "M_G_DQ<59>")
	)
	(segment
		(start 151.757634 -18.1102)
		(end 151.300434 -17.653)
		(width 0.14224)
		(layer "In2.Cu")
		(net "M_G_DQ<59>")
	)
	(segment
		(start 123.303538 -57.590436)
		(end 123.298712 -57.5818)
		(width 0.0889)
		(layer "In2.Cu")
		(net "M_G_DQ<59>")
	)
	(segment
		(start 126.427992 -52.5526)
		(end 127.582168 -52.5526)
		(width 0.0889)
		(layer "In2.Cu")
		(net "M_G_DQ<59>")
	)
	(segment
		(start 151.24938 -22.279356)
		(end 151.602186 -21.92655)
		(width 0.14224)
		(layer "In2.Cu")
		(net "M_G_DQ<59>")
	)
	(segment
		(start 151.602186 -21.92655)
		(end 151.602186 -18.621248)
		(width 0.14224)
		(layer "In2.Cu")
		(net "M_G_DQ<59>")
	)
	(segment
		(start 143.832072 -42.500296)
		(end 146.358864 -42.500296)
		(width 0.14224)
		(layer "In2.Cu")
		(net "M_G_DQ<59>")
	)
	(segment
		(start 125.020832 -56.264048)
		(end 125.020832 -53.95976)
		(width 0.0889)
		(layer "In2.Cu")
		(net "M_G_DQ<59>")
	)
	(segment
		(start 127.582168 -52.5526)
		(end 128.492504 -51.642264)
		(width 0.14224)
		(layer "In2.Cu")
		(net "M_G_DQ<59>")
	)
	(arc
		(start 123.298712 -57.5818)
		(mid 123.302459 -57.192544)
		(end 123.635262 -56.990488)
		(width 0.0889)
		(layer "In2.Cu")
		(net "M_G_DQ<59>")
	)
	(arc
		(start 122.857006 -58.473086)
		(mid 123.115143 -58.380332)
		(end 123.303538 -58.180986)
		(width 0.0889)
		(layer "In2.Cu")
		(net "M_G_DQ<59>")
	)
	(arc
		(start 123.303538 -58.180986)
		(mid 123.38276 -57.891868)
		(end 123.309888 -57.601104)
		(width 0.0889)
		(layer "In2.Cu")
		(net "M_G_DQ<59>")
	)
	(segment
		(start 123.363228 -57.885584)
		(end 122.791728 -57.885584)
		(width 0.1651)
		(layer "F.Cu")
		(net "M_G_DQ<58>")
	)
	(segment
		(start 151.24938 -18.539968)
		(end 151.24938 -18.2626)
		(width 0.1651)
		(layer "F.Cu")
		(net "M_G_DQ<58>")
	)
	(segment
		(start 151.24938 -19.026632)
		(end 151.380952 -18.89506)
		(width 0.1651)
		(layer "F.Cu")
		(net "M_G_DQ<58>")
	)
	(segment
		(start 151.380952 -18.67154)
		(end 151.24938 -18.539968)
		(width 0.1651)
		(layer "F.Cu")
		(net "M_G_DQ<58>")
	)
	(segment
		(start 151.24938 -20.023582)
		(end 151.24938 -19.026632)
		(width 0.1651)
		(layer "F.Cu")
		(net "M_G_DQ<58>")
	)
	(segment
		(start 151.380952 -18.89506)
		(end 151.380952 -18.67154)
		(width 0.1651)
		(layer "F.Cu")
		(net "M_G_DQ<58>")
	)
	(via
		(at 122.791728 -57.885584)
		(size 0.508)
		(drill 0.254)
		(layers "F.Cu" "B.Cu")
		(net "M_G_DQ<58>")
	)
	(via
		(at 150.399496 -23.560278)
		(size 0.508)
		(drill 0.254)
		(layers "F.Cu" "B.Cu")
		(net "M_G_DQ<58>")
	)
	(via
		(at 151.24938 -18.2626)
		(size 0.508)
		(drill 0.254)
		(layers "F.Cu" "B.Cu")
		(net "M_G_DQ<58>")
	)
	(segment
		(start 150.399496 -23.560278)
		(end 150.399496 -24.824182)
		(width 0.1651)
		(layer "B.Cu")
		(net "M_G_DQ<58>")
	)
	(segment
		(start 134.614158 -47.8282)
		(end 137.411968 -47.8282)
		(width 0.14224)
		(layer "In2.Cu")
		(net "M_G_DQ<58>")
	)
	(segment
		(start 124.830332 -56.185054)
		(end 124.830332 -53.880512)
		(width 0.0889)
		(layer "In2.Cu")
		(net "M_G_DQ<58>")
	)
	(segment
		(start 150.851362 -18.660618)
		(end 151.24938 -18.2626)
		(width 0.14224)
		(layer "In2.Cu")
		(net "M_G_DQ<58>")
	)
	(segment
		(start 150.399496 -23.560278)
		(end 150.114762 -23.275544)
		(width 0.14224)
		(layer "In2.Cu")
		(net "M_G_DQ<58>")
	)
	(segment
		(start 133.821678 -48.70196)
		(end 133.963918 -48.8442)
		(width 0.14224)
		(layer "In2.Cu")
		(net "M_G_DQ<58>")
	)
	(segment
		(start 146.574764 -41.369996)
		(end 150.399496 -37.545264)
		(width 0.14224)
		(layer "In2.Cu")
		(net "M_G_DQ<58>")
	)
	(segment
		(start 133.821678 -47.97044)
		(end 133.821678 -48.70196)
		(width 0.14224)
		(layer "In2.Cu")
		(net "M_G_DQ<58>")
	)
	(segment
		(start 133.963918 -48.8442)
		(end 134.329678 -48.8442)
		(width 0.14224)
		(layer "In2.Cu")
		(net "M_G_DQ<58>")
	)
	(segment
		(start 129.980944 -49.44237)
		(end 131.403344 -49.44237)
		(width 0.14224)
		(layer "In2.Cu")
		(net "M_G_DQ<58>")
	)
	(segment
		(start 134.471918 -48.70196)
		(end 134.471918 -47.97044)
		(width 0.14224)
		(layer "In2.Cu")
		(net "M_G_DQ<58>")
	)
	(segment
		(start 123.628658 -56.799988)
		(end 124.215398 -56.799988)
		(width 0.0889)
		(layer "In2.Cu")
		(net "M_G_DQ<58>")
	)
	(segment
		(start 150.50643 -19.659346)
		(end 150.50643 -19.310604)
		(width 0.14224)
		(layer "In2.Cu")
		(net "M_G_DQ<58>")
	)
	(segment
		(start 122.791728 -57.885584)
		(end 123.063254 -57.322466)
		(width 0.0889)
		(layer "In2.Cu")
		(net "M_G_DQ<58>")
	)
	(segment
		(start 134.471918 -47.97044)
		(end 134.614158 -47.8282)
		(width 0.14224)
		(layer "In2.Cu")
		(net "M_G_DQ<58>")
	)
	(segment
		(start 126.361444 -52.3494)
		(end 127.073914 -52.3494)
		(width 0.0889)
		(layer "In2.Cu")
		(net "M_G_DQ<58>")
	)
	(segment
		(start 134.329678 -48.8442)
		(end 134.471918 -48.70196)
		(width 0.14224)
		(layer "In2.Cu")
		(net "M_G_DQ<58>")
	)
	(segment
		(start 150.81123 -19.964146)
		(end 150.50643 -19.659346)
		(width 0.14224)
		(layer "In2.Cu")
		(net "M_G_DQ<58>")
	)
	(segment
		(start 133.017514 -47.8282)
		(end 133.679438 -47.8282)
		(width 0.14224)
		(layer "In2.Cu")
		(net "M_G_DQ<58>")
	)
	(segment
		(start 124.215398 -56.799988)
		(end 124.830332 -56.185054)
		(width 0.0889)
		(layer "In2.Cu")
		(net "M_G_DQ<58>")
	)
	(segment
		(start 137.411968 -47.8282)
		(end 143.870172 -41.369996)
		(width 0.14224)
		(layer "In2.Cu")
		(net "M_G_DQ<58>")
	)
	(segment
		(start 150.114762 -22.5298)
		(end 150.96363 -21.680932)
		(width 0.14224)
		(layer "In2.Cu")
		(net "M_G_DQ<58>")
	)
	(segment
		(start 131.403344 -49.44237)
		(end 133.017514 -47.8282)
		(width 0.14224)
		(layer "In2.Cu")
		(net "M_G_DQ<58>")
	)
	(segment
		(start 150.114762 -23.275544)
		(end 150.114762 -22.5298)
		(width 0.14224)
		(layer "In2.Cu")
		(net "M_G_DQ<58>")
	)
	(segment
		(start 124.830332 -53.880512)
		(end 126.361444 -52.3494)
		(width 0.0889)
		(layer "In2.Cu")
		(net "M_G_DQ<58>")
	)
	(segment
		(start 127.278638 -52.144676)
		(end 129.980944 -49.44237)
		(width 0.14224)
		(layer "In2.Cu")
		(net "M_G_DQ<58>")
	)
	(segment
		(start 143.870172 -41.369996)
		(end 146.574764 -41.369996)
		(width 0.14224)
		(layer "In2.Cu")
		(net "M_G_DQ<58>")
	)
	(segment
		(start 150.851362 -18.965672)
		(end 150.851362 -18.660618)
		(width 0.14224)
		(layer "In2.Cu")
		(net "M_G_DQ<58>")
	)
	(segment
		(start 150.96363 -21.4122)
		(end 150.50643 -20.955)
		(width 0.14224)
		(layer "In2.Cu")
		(net "M_G_DQ<58>")
	)
	(segment
		(start 150.96363 -21.680932)
		(end 150.96363 -21.4122)
		(width 0.14224)
		(layer "In2.Cu")
		(net "M_G_DQ<58>")
	)
	(segment
		(start 150.50643 -19.310604)
		(end 150.851362 -18.965672)
		(width 0.14224)
		(layer "In2.Cu")
		(net "M_G_DQ<58>")
	)
	(segment
		(start 150.399496 -37.545264)
		(end 150.399496 -23.560278)
		(width 0.14224)
		(layer "In2.Cu")
		(net "M_G_DQ<58>")
	)
	(segment
		(start 127.073914 -52.3494)
		(end 127.278638 -52.144676)
		(width 0.0889)
		(layer "In2.Cu")
		(net "M_G_DQ<58>")
	)
	(segment
		(start 150.81123 -20.25015)
		(end 150.81123 -19.964146)
		(width 0.14224)
		(layer "In2.Cu")
		(net "M_G_DQ<58>")
	)
	(segment
		(start 150.50643 -20.955)
		(end 150.50643 -20.55495)
		(width 0.14224)
		(layer "In2.Cu")
		(net "M_G_DQ<58>")
	)
	(segment
		(start 150.50643 -20.55495)
		(end 150.81123 -20.25015)
		(width 0.14224)
		(layer "In2.Cu")
		(net "M_G_DQ<58>")
	)
	(segment
		(start 133.679438 -47.8282)
		(end 133.821678 -47.97044)
		(width 0.14224)
		(layer "In2.Cu")
		(net "M_G_DQ<58>")
	)
	(arc
		(start 123.063254 -57.322466)
		(mid 123.249206 -56.956532)
		(end 123.628658 -56.799988)
		(width 0.0889)
		(layer "In2.Cu")
		(net "M_G_DQ<58>")
	)
	(segment
		(start 121.646188 -57.885584)
		(end 121.074688 -57.885584)
		(width 0.1016)
		(layer "F.Cu")
		(net "M_G_DQ<57>")
	)
	(segment
		(start 144.449546 -15.423642)
		(end 144.449546 -16.687546)
		(width 0.1651)
		(layer "F.Cu")
		(net "M_G_DQ<57>")
	)
	(via
		(at 145.12163 -22.279356)
		(size 0.508)
		(drill 0.254)
		(layers "F.Cu" "B.Cu")
		(net "M_G_DQ<57>")
	)
	(via
		(at 121.074688 -57.885584)
		(size 0.508)
		(drill 0.254)
		(layers "F.Cu" "B.Cu")
		(net "M_G_DQ<57>")
	)
	(via
		(at 144.449546 -16.687546)
		(size 0.508)
		(drill 0.254)
		(layers "F.Cu" "B.Cu")
		(net "M_G_DQ<57>")
	)
	(segment
		(start 145.29943 -20.224242)
		(end 145.29943 -21.598382)
		(width 0.1651)
		(layer "B.Cu")
		(net "M_G_DQ<57>")
	)
	(segment
		(start 145.12163 -21.776182)
		(end 145.12163 -22.279356)
		(width 0.1651)
		(layer "B.Cu")
		(net "M_G_DQ<57>")
	)
	(segment
		(start 145.29943 -21.598382)
		(end 145.12163 -21.776182)
		(width 0.1651)
		(layer "B.Cu")
		(net "M_G_DQ<57>")
	)
	(segment
		(start 120.660668 -53.99278)
		(end 120.660668 -53.75275)
		(width 0.0889)
		(layer "In2.Cu")
		(net "M_G_DQ<57>")
	)
	(segment
		(start 121.074688 -57.885584)
		(end 121.404634 -57.123838)
		(width 0.0889)
		(layer "In2.Cu")
		(net "M_G_DQ<57>")
	)
	(segment
		(start 136.294368 -43.0276)
		(end 143.431768 -35.8902)
		(width 0.14224)
		(layer "In2.Cu")
		(net "M_G_DQ<57>")
	)
	(segment
		(start 127.799592 -45.908976)
		(end 128.841246 -45.908976)
		(width 0.14224)
		(layer "In2.Cu")
		(net "M_G_DQ<57>")
	)
	(segment
		(start 121.53011 -52.883308)
		(end 121.53011 -52.194206)
		(width 0.0889)
		(layer "In2.Cu")
		(net "M_G_DQ<57>")
	)
	(segment
		(start 132.60197 -43.0276)
		(end 132.75691 -42.87266)
		(width 0.14224)
		(layer "In2.Cu")
		(net "M_G_DQ<57>")
	)
	(segment
		(start 145.652236 -18.415)
		(end 145.652236 -18.073624)
		(width 0.14224)
		(layer "In2.Cu")
		(net "M_G_DQ<57>")
	)
	(segment
		(start 144.974564 -23.437596)
		(end 144.618964 -23.081996)
		(width 0.14224)
		(layer "In2.Cu")
		(net "M_G_DQ<57>")
	)
	(segment
		(start 121.426224 -56.703722)
		(end 121.421398 -56.695086)
		(width 0.0889)
		(layer "In2.Cu")
		(net "M_G_DQ<57>")
	)
	(segment
		(start 144.926812 -17.7038)
		(end 144.449546 -17.226534)
		(width 0.14224)
		(layer "In2.Cu")
		(net "M_G_DQ<57>")
	)
	(segment
		(start 132.75691 -42.54754)
		(end 132.91185 -42.3926)
		(width 0.14224)
		(layer "In2.Cu")
		(net "M_G_DQ<57>")
	)
	(segment
		(start 131.722622 -43.0276)
		(end 132.60197 -43.0276)
		(width 0.14224)
		(layer "In2.Cu")
		(net "M_G_DQ<57>")
	)
	(segment
		(start 145.495772 -21.905214)
		(end 145.495772 -18.571464)
		(width 0.14224)
		(layer "In2.Cu")
		(net "M_G_DQ<57>")
	)
	(segment
		(start 128.841246 -45.908976)
		(end 131.722622 -43.0276)
		(width 0.14224)
		(layer "In2.Cu")
		(net "M_G_DQ<57>")
	)
	(segment
		(start 133.41985 -42.87266)
		(end 133.57479 -43.0276)
		(width 0.14224)
		(layer "In2.Cu")
		(net "M_G_DQ<57>")
	)
	(segment
		(start 144.449546 -17.226534)
		(end 144.449546 -16.687546)
		(width 0.14224)
		(layer "In2.Cu")
		(net "M_G_DQ<57>")
	)
	(segment
		(start 123.187968 -50.5206)
		(end 127.799592 -45.908976)
		(width 0.14224)
		(layer "In2.Cu")
		(net "M_G_DQ<57>")
	)
	(segment
		(start 120.723152 -54.722522)
		(end 120.727978 -54.713886)
		(width 0.0889)
		(layer "In2.Cu")
		(net "M_G_DQ<57>")
	)
	(segment
		(start 145.692368 -35.128454)
		(end 145.692368 -25.46731)
		(width 0.14224)
		(layer "In2.Cu")
		(net "M_G_DQ<57>")
	)
	(segment
		(start 121.096532 -55.479442)
		(end 120.913144 -55.343806)
		(width 0.0889)
		(layer "In2.Cu")
		(net "M_G_DQ<57>")
	)
	(segment
		(start 133.92785 -43.0276)
		(end 134.08279 -42.87266)
		(width 0.14224)
		(layer "In2.Cu")
		(net "M_G_DQ<57>")
	)
	(segment
		(start 133.41985 -42.54754)
		(end 133.41985 -42.87266)
		(width 0.14224)
		(layer "In2.Cu")
		(net "M_G_DQ<57>")
	)
	(segment
		(start 121.404634 -57.123838)
		(end 121.421398 -57.095136)
		(width 0.0889)
		(layer "In2.Cu")
		(net "M_G_DQ<57>")
	)
	(segment
		(start 120.727978 -54.713886)
		(end 120.734328 -54.703218)
		(width 0.0889)
		(layer "In2.Cu")
		(net "M_G_DQ<57>")
	)
	(segment
		(start 134.08279 -42.87266)
		(end 134.08279 -42.54754)
		(width 0.14224)
		(layer "In2.Cu")
		(net "M_G_DQ<57>")
	)
	(segment
		(start 145.652236 -18.073624)
		(end 145.282412 -17.7038)
		(width 0.14224)
		(layer "In2.Cu")
		(net "M_G_DQ<57>")
	)
	(segment
		(start 134.90067 -43.0276)
		(end 136.294368 -43.0276)
		(width 0.14224)
		(layer "In2.Cu")
		(net "M_G_DQ<57>")
	)
	(segment
		(start 120.774714 -55.194962)
		(end 120.727978 -55.113936)
		(width 0.0889)
		(layer "In2.Cu")
		(net "M_G_DQ<57>")
	)
	(segment
		(start 144.618964 -23.081996)
		(end 144.618964 -22.782022)
		(width 0.14224)
		(layer "In2.Cu")
		(net "M_G_DQ<57>")
	)
	(segment
		(start 133.26491 -42.3926)
		(end 133.41985 -42.54754)
		(width 0.14224)
		(layer "In2.Cu")
		(net "M_G_DQ<57>")
	)
	(segment
		(start 120.660668 -53.75275)
		(end 121.53011 -52.883308)
		(width 0.0889)
		(layer "In2.Cu")
		(net "M_G_DQ<57>")
	)
	(segment
		(start 134.59079 -42.3926)
		(end 134.74573 -42.54754)
		(width 0.14224)
		(layer "In2.Cu")
		(net "M_G_DQ<57>")
	)
	(segment
		(start 145.692368 -25.46731)
		(end 144.974564 -24.749506)
		(width 0.14224)
		(layer "In2.Cu")
		(net "M_G_DQ<57>")
	)
	(segment
		(start 121.22023 -55.531512)
		(end 121.096532 -55.479442)
		(width 0.0889)
		(layer "In2.Cu")
		(net "M_G_DQ<57>")
	)
	(segment
		(start 134.74573 -42.54754)
		(end 134.74573 -42.87266)
		(width 0.14224)
		(layer "In2.Cu")
		(net "M_G_DQ<57>")
	)
	(segment
		(start 134.23773 -42.3926)
		(end 134.59079 -42.3926)
		(width 0.14224)
		(layer "In2.Cu")
		(net "M_G_DQ<57>")
	)
	(segment
		(start 145.282412 -17.7038)
		(end 144.926812 -17.7038)
		(width 0.14224)
		(layer "In2.Cu")
		(net "M_G_DQ<57>")
	)
	(segment
		(start 121.421398 -56.695086)
		(end 121.415048 -56.684418)
		(width 0.0889)
		(layer "In2.Cu")
		(net "M_G_DQ<57>")
	)
	(segment
		(start 123.187968 -50.536348)
		(end 123.187968 -50.5206)
		(width 0.14224)
		(layer "In2.Cu")
		(net "M_G_DQ<57>")
	)
	(segment
		(start 132.91185 -42.3926)
		(end 133.26491 -42.3926)
		(width 0.14224)
		(layer "In2.Cu")
		(net "M_G_DQ<57>")
	)
	(segment
		(start 134.74573 -42.87266)
		(end 134.90067 -43.0276)
		(width 0.14224)
		(layer "In2.Cu")
		(net "M_G_DQ<57>")
	)
	(segment
		(start 132.75691 -42.87266)
		(end 132.75691 -42.54754)
		(width 0.14224)
		(layer "In2.Cu")
		(net "M_G_DQ<57>")
	)
	(segment
		(start 144.974564 -24.749506)
		(end 144.974564 -23.437596)
		(width 0.14224)
		(layer "In2.Cu")
		(net "M_G_DQ<57>")
	)
	(segment
		(start 133.57479 -43.0276)
		(end 133.92785 -43.0276)
		(width 0.14224)
		(layer "In2.Cu")
		(net "M_G_DQ<57>")
	)
	(segment
		(start 143.431768 -35.8902)
		(end 144.930622 -35.8902)
		(width 0.14224)
		(layer "In2.Cu")
		(net "M_G_DQ<57>")
	)
	(segment
		(start 145.12163 -22.279356)
		(end 145.495772 -21.905214)
		(width 0.14224)
		(layer "In2.Cu")
		(net "M_G_DQ<57>")
	)
	(segment
		(start 134.08279 -42.54754)
		(end 134.23773 -42.3926)
		(width 0.14224)
		(layer "In2.Cu")
		(net "M_G_DQ<57>")
	)
	(segment
		(start 121.53011 -52.194206)
		(end 123.187968 -50.536348)
		(width 0.0889)
		(layer "In2.Cu")
		(net "M_G_DQ<57>")
	)
	(segment
		(start 144.930622 -35.8902)
		(end 145.692368 -35.128454)
		(width 0.14224)
		(layer "In2.Cu")
		(net "M_G_DQ<57>")
	)
	(segment
		(start 144.618964 -22.782022)
		(end 145.12163 -22.279356)
		(width 0.14224)
		(layer "In2.Cu")
		(net "M_G_DQ<57>")
	)
	(segment
		(start 120.727978 -54.123336)
		(end 120.660668 -53.99278)
		(width 0.0889)
		(layer "In2.Cu")
		(net "M_G_DQ<57>")
	)
	(segment
		(start 145.495772 -18.571464)
		(end 145.652236 -18.415)
		(width 0.14224)
		(layer "In2.Cu")
		(net "M_G_DQ<57>")
	)
	(segment
		(start 120.913144 -55.343806)
		(end 120.774714 -55.194962)
		(width 0.0889)
		(layer "In2.Cu")
		(net "M_G_DQ<57>")
	)
	(arc
		(start 120.734328 -54.703218)
		(mid 120.807126 -54.412455)
		(end 120.727978 -54.123336)
		(width 0.0889)
		(layer "In2.Cu")
		(net "M_G_DQ<57>")
	)
	(arc
		(start 121.421398 -56.104536)
		(mid 121.452432 -55.771802)
		(end 121.22023 -55.531512)
		(width 0.0889)
		(layer "In2.Cu")
		(net "M_G_DQ<57>")
	)
	(arc
		(start 120.727978 -55.113936)
		(mid 120.674508 -54.918873)
		(end 120.723152 -54.722522)
		(width 0.0889)
		(layer "In2.Cu")
		(net "M_G_DQ<57>")
	)
	(arc
		(start 121.421398 -57.095136)
		(mid 121.474868 -56.900073)
		(end 121.426224 -56.703722)
		(width 0.0889)
		(layer "In2.Cu")
		(net "M_G_DQ<57>")
	)
	(arc
		(start 121.415048 -56.684418)
		(mid 121.34225 -56.393655)
		(end 121.421398 -56.104536)
		(width 0.0889)
		(layer "In2.Cu")
		(net "M_G_DQ<57>")
	)
	(segment
		(start 145.218658 -19.177)
		(end 145.12163 -18.161)
		(width 0.1651)
		(layer "F.Cu")
		(net "M_G_DQ<56>")
	)
	(segment
		(start 145.29943 -20.023582)
		(end 145.218658 -19.177)
		(width 0.1651)
		(layer "F.Cu")
		(net "M_G_DQ<56>")
	)
	(segment
		(start 121.646188 -55.904384)
		(end 121.074688 -55.904384)
		(width 0.1016)
		(layer "F.Cu")
		(net "M_G_DQ<56>")
	)
	(via
		(at 144.449546 -23.560278)
		(size 0.508)
		(drill 0.254)
		(layers "F.Cu" "B.Cu")
		(net "M_G_DQ<56>")
	)
	(via
		(at 121.074688 -55.904384)
		(size 0.4826)
		(drill 0.254)
		(layers "F.Cu" "B.Cu")
		(net "M_G_DQ<56>")
	)
	(via
		(at 145.12163 -18.161)
		(size 0.508)
		(drill 0.254)
		(layers "F.Cu" "B.Cu")
		(net "M_G_DQ<56>")
	)
	(segment
		(start 144.449546 -23.560278)
		(end 144.449546 -24.824182)
		(width 0.1651)
		(layer "B.Cu")
		(net "M_G_DQ<56>")
	)
	(segment
		(start 124.181108 -48.227996)
		(end 124.582428 -48.227996)
		(width 0.14224)
		(layer "In2.Cu")
		(net "M_G_DQ<56>")
	)
	(segment
		(start 145.057368 -25.926288)
		(end 144.669764 -25.538684)
		(width 0.14224)
		(layer "In2.Cu")
		(net "M_G_DQ<56>")
	)
	(segment
		(start 136.370822 -41.7322)
		(end 142.931134 -35.171888)
		(width 0.14224)
		(layer "In2.Cu")
		(net "M_G_DQ<56>")
	)
	(segment
		(start 124.838968 -46.675294)
		(end 124.838968 -46.309534)
		(width 0.14224)
		(layer "In2.Cu")
		(net "M_G_DQ<56>")
	)
	(segment
		(start 124.838968 -46.309534)
		(end 124.696728 -46.167294)
		(width 0.14224)
		(layer "In2.Cu")
		(net "M_G_DQ<56>")
	)
	(segment
		(start 142.931134 -35.171888)
		(end 144.669764 -35.171888)
		(width 0.14224)
		(layer "In2.Cu")
		(net "M_G_DQ<56>")
	)
	(segment
		(start 144.164812 -22.5298)
		(end 144.901412 -21.7932)
		(width 0.14224)
		(layer "In2.Cu")
		(net "M_G_DQ<56>")
	)
	(segment
		(start 120.6246 -55.317644)
		(end 120.562878 -55.209186)
		(width 0.0889)
		(layer "In2.Cu")
		(net "M_G_DQ<56>")
	)
	(segment
		(start 124.026168 -47.410116)
		(end 124.026168 -46.959774)
		(width 0.14224)
		(layer "In2.Cu")
		(net "M_G_DQ<56>")
	)
	(segment
		(start 145.057368 -29.094684)
		(end 145.057368 -28.771088)
		(width 0.14224)
		(layer "In2.Cu")
		(net "M_G_DQ<56>")
	)
	(segment
		(start 124.582428 -47.565056)
		(end 124.181108 -47.565056)
		(width 0.14224)
		(layer "In2.Cu")
		(net "M_G_DQ<56>")
	)
	(segment
		(start 144.48663 -19.380454)
		(end 144.901412 -18.965672)
		(width 0.14224)
		(layer "In2.Cu")
		(net "M_G_DQ<56>")
	)
	(segment
		(start 144.449546 -23.560278)
		(end 144.164812 -23.275544)
		(width 0.14224)
		(layer "In2.Cu")
		(net "M_G_DQ<56>")
	)
	(segment
		(start 144.669764 -32.327088)
		(end 145.057368 -31.939484)
		(width 0.14224)
		(layer "In2.Cu")
		(net "M_G_DQ<56>")
	)
	(segment
		(start 144.901412 -18.965672)
		(end 144.901412 -18.381218)
		(width 0.14224)
		(layer "In2.Cu")
		(net "M_G_DQ<56>")
	)
	(segment
		(start 144.669764 -26.961084)
		(end 144.669764 -26.637488)
		(width 0.14224)
		(layer "In2.Cu")
		(net "M_G_DQ<56>")
	)
	(segment
		(start 144.164812 -23.275544)
		(end 144.164812 -22.5298)
		(width 0.14224)
		(layer "In2.Cu")
		(net "M_G_DQ<56>")
	)
	(segment
		(start 132.129022 -41.7322)
		(end 136.370822 -41.7322)
		(width 0.14224)
		(layer "In2.Cu")
		(net "M_G_DQ<56>")
	)
	(segment
		(start 144.217136 -24.864314)
		(end 144.217136 -23.792688)
		(width 0.14224)
		(layer "In2.Cu")
		(net "M_G_DQ<56>")
	)
	(segment
		(start 144.51203 -20.903946)
		(end 144.51203 -20.5994)
		(width 0.14224)
		(layer "In2.Cu")
		(net "M_G_DQ<56>")
	)
	(segment
		(start 145.057368 -27.348688)
		(end 144.669764 -26.961084)
		(width 0.14224)
		(layer "In2.Cu")
		(net "M_G_DQ<56>")
	)
	(segment
		(start 144.82953 -20.2819)
		(end 144.82953 -20.0533)
		(width 0.14224)
		(layer "In2.Cu")
		(net "M_G_DQ<56>")
	)
	(segment
		(start 145.057368 -27.672284)
		(end 145.057368 -27.348688)
		(width 0.14224)
		(layer "In2.Cu")
		(net "M_G_DQ<56>")
	)
	(segment
		(start 145.057368 -31.939484)
		(end 145.057368 -31.615888)
		(width 0.14224)
		(layer "In2.Cu")
		(net "M_G_DQ<56>")
	)
	(segment
		(start 144.669764 -28.059888)
		(end 145.057368 -27.672284)
		(width 0.14224)
		(layer "In2.Cu")
		(net "M_G_DQ<56>")
	)
	(segment
		(start 120.562878 -54.218586)
		(end 120.470168 -54.039008)
		(width 0.0889)
		(layer "In2.Cu")
		(net "M_G_DQ<56>")
	)
	(segment
		(start 124.582428 -48.227996)
		(end 124.737368 -48.073056)
		(width 0.14224)
		(layer "In2.Cu")
		(net "M_G_DQ<56>")
	)
	(segment
		(start 145.057368 -26.249884)
		(end 145.057368 -25.926288)
		(width 0.14224)
		(layer "In2.Cu")
		(net "M_G_DQ<56>")
	)
	(segment
		(start 124.026168 -48.971454)
		(end 124.026168 -48.382936)
		(width 0.14224)
		(layer "In2.Cu")
		(net "M_G_DQ<56>")
	)
	(segment
		(start 124.366782 -45.430186)
		(end 128.431036 -45.430186)
		(width 0.14224)
		(layer "In2.Cu")
		(net "M_G_DQ<56>")
	)
	(segment
		(start 144.669764 -29.805884)
		(end 144.669764 -29.482288)
		(width 0.14224)
		(layer "In2.Cu")
		(net "M_G_DQ<56>")
	)
	(segment
		(start 124.737368 -47.719996)
		(end 124.582428 -47.565056)
		(width 0.14224)
		(layer "In2.Cu")
		(net "M_G_DQ<56>")
	)
	(segment
		(start 121.074688 -55.904384)
		(end 121.059194 -55.902098)
		(width 0.0889)
		(layer "In2.Cu")
		(net "M_G_DQ<56>")
	)
	(segment
		(start 120.470168 -54.039008)
		(end 120.470168 -53.673502)
		(width 0.0889)
		(layer "In2.Cu")
		(net "M_G_DQ<56>")
	)
	(segment
		(start 144.669764 -34.073084)
		(end 144.669764 -33.749488)
		(width 0.14224)
		(layer "In2.Cu")
		(net "M_G_DQ<56>")
	)
	(segment
		(start 144.669764 -28.383484)
		(end 144.669764 -28.059888)
		(width 0.14224)
		(layer "In2.Cu")
		(net "M_G_DQ<56>")
	)
	(segment
		(start 144.82953 -20.0533)
		(end 144.48663 -19.7104)
		(width 0.14224)
		(layer "In2.Cu")
		(net "M_G_DQ<56>")
	)
	(segment
		(start 144.669764 -32.650684)
		(end 144.669764 -32.327088)
		(width 0.14224)
		(layer "In2.Cu")
		(net "M_G_DQ<56>")
	)
	(segment
		(start 122.781568 -50.216054)
		(end 124.026168 -48.971454)
		(width 0.14224)
		(layer "In2.Cu")
		(net "M_G_DQ<56>")
	)
	(segment
		(start 120.562878 -54.618636)
		(end 120.567704 -54.61)
		(width 0.0889)
		(layer "In2.Cu")
		(net "M_G_DQ<56>")
	)
	(segment
		(start 145.057368 -30.517084)
		(end 145.057368 -30.193488)
		(width 0.14224)
		(layer "In2.Cu")
		(net "M_G_DQ<56>")
	)
	(segment
		(start 124.696728 -46.167294)
		(end 124.168408 -46.167294)
		(width 0.14224)
		(layer "In2.Cu")
		(net "M_G_DQ<56>")
	)
	(segment
		(start 145.057368 -28.771088)
		(end 144.669764 -28.383484)
		(width 0.14224)
		(layer "In2.Cu")
		(net "M_G_DQ<56>")
	)
	(segment
		(start 124.696728 -46.817534)
		(end 124.838968 -46.675294)
		(width 0.14224)
		(layer "In2.Cu")
		(net "M_G_DQ<56>")
	)
	(segment
		(start 120.470168 -53.673502)
		(end 121.33961 -52.80406)
		(width 0.0889)
		(layer "In2.Cu")
		(net "M_G_DQ<56>")
	)
	(segment
		(start 124.737368 -48.073056)
		(end 124.737368 -47.719996)
		(width 0.14224)
		(layer "In2.Cu")
		(net "M_G_DQ<56>")
	)
	(segment
		(start 121.33961 -52.114196)
		(end 122.781568 -50.672238)
		(width 0.0889)
		(layer "In2.Cu")
		(net "M_G_DQ<56>")
	)
	(segment
		(start 144.669764 -30.904688)
		(end 145.057368 -30.517084)
		(width 0.14224)
		(layer "In2.Cu")
		(net "M_G_DQ<56>")
	)
	(segment
		(start 145.057368 -33.361884)
		(end 145.057368 -33.038288)
		(width 0.14224)
		(layer "In2.Cu")
		(net "M_G_DQ<56>")
	)
	(segment
		(start 145.057368 -34.460688)
		(end 144.669764 -34.073084)
		(width 0.14224)
		(layer "In2.Cu")
		(net "M_G_DQ<56>")
	)
	(segment
		(start 124.168408 -46.817534)
		(end 124.696728 -46.817534)
		(width 0.14224)
		(layer "In2.Cu")
		(net "M_G_DQ<56>")
	)
	(segment
		(start 121.059194 -55.902098)
		(end 120.6246 -55.317644)
		(width 0.0889)
		(layer "In2.Cu")
		(net "M_G_DQ<56>")
	)
	(segment
		(start 144.48663 -19.7104)
		(end 144.48663 -19.380454)
		(width 0.14224)
		(layer "In2.Cu")
		(net "M_G_DQ<56>")
	)
	(segment
		(start 124.026168 -46.959774)
		(end 124.168408 -46.817534)
		(width 0.14224)
		(layer "In2.Cu")
		(net "M_G_DQ<56>")
	)
	(segment
		(start 121.33961 -52.80406)
		(end 121.33961 -52.114196)
		(width 0.0889)
		(layer "In2.Cu")
		(net "M_G_DQ<56>")
	)
	(segment
		(start 144.217136 -23.792688)
		(end 144.449546 -23.560278)
		(width 0.14224)
		(layer "In2.Cu")
		(net "M_G_DQ<56>")
	)
	(segment
		(start 144.669764 -25.316942)
		(end 144.217136 -24.864314)
		(width 0.14224)
		(layer "In2.Cu")
		(net "M_G_DQ<56>")
	)
	(segment
		(start 144.901412 -21.7932)
		(end 144.901412 -21.293328)
		(width 0.14224)
		(layer "In2.Cu")
		(net "M_G_DQ<56>")
	)
	(segment
		(start 120.556528 -54.629304)
		(end 120.562878 -54.618636)
		(width 0.0889)
		(layer "In2.Cu")
		(net "M_G_DQ<56>")
	)
	(segment
		(start 145.057368 -34.784284)
		(end 145.057368 -34.460688)
		(width 0.14224)
		(layer "In2.Cu")
		(net "M_G_DQ<56>")
	)
	(segment
		(start 122.781568 -50.672238)
		(end 122.781568 -50.216054)
		(width 0.0889)
		(layer "In2.Cu")
		(net "M_G_DQ<56>")
	)
	(segment
		(start 144.669764 -33.749488)
		(end 145.057368 -33.361884)
		(width 0.14224)
		(layer "In2.Cu")
		(net "M_G_DQ<56>")
	)
	(segment
		(start 144.669764 -25.538684)
		(end 144.669764 -25.316942)
		(width 0.14224)
		(layer "In2.Cu")
		(net "M_G_DQ<56>")
	)
	(segment
		(start 128.431036 -45.430186)
		(end 132.129022 -41.7322)
		(width 0.14224)
		(layer "In2.Cu")
		(net "M_G_DQ<56>")
	)
	(segment
		(start 145.057368 -30.193488)
		(end 144.669764 -29.805884)
		(width 0.14224)
		(layer "In2.Cu")
		(net "M_G_DQ<56>")
	)
	(segment
		(start 144.901412 -18.381218)
		(end 145.12163 -18.161)
		(width 0.14224)
		(layer "In2.Cu")
		(net "M_G_DQ<56>")
	)
	(segment
		(start 144.901412 -21.293328)
		(end 144.51203 -20.903946)
		(width 0.14224)
		(layer "In2.Cu")
		(net "M_G_DQ<56>")
	)
	(segment
		(start 124.026168 -46.025054)
		(end 124.026168 -45.7708)
		(width 0.14224)
		(layer "In2.Cu")
		(net "M_G_DQ<56>")
	)
	(segment
		(start 144.669764 -31.228284)
		(end 144.669764 -30.904688)
		(width 0.14224)
		(layer "In2.Cu")
		(net "M_G_DQ<56>")
	)
	(segment
		(start 124.026168 -48.382936)
		(end 124.181108 -48.227996)
		(width 0.14224)
		(layer "In2.Cu")
		(net "M_G_DQ<56>")
	)
	(segment
		(start 145.057368 -33.038288)
		(end 144.669764 -32.650684)
		(width 0.14224)
		(layer "In2.Cu")
		(net "M_G_DQ<56>")
	)
	(segment
		(start 124.181108 -47.565056)
		(end 124.026168 -47.410116)
		(width 0.14224)
		(layer "In2.Cu")
		(net "M_G_DQ<56>")
	)
	(segment
		(start 144.669764 -26.637488)
		(end 145.057368 -26.249884)
		(width 0.14224)
		(layer "In2.Cu")
		(net "M_G_DQ<56>")
	)
	(segment
		(start 124.168408 -46.167294)
		(end 124.026168 -46.025054)
		(width 0.14224)
		(layer "In2.Cu")
		(net "M_G_DQ<56>")
	)
	(segment
		(start 144.51203 -20.5994)
		(end 144.82953 -20.2819)
		(width 0.14224)
		(layer "In2.Cu")
		(net "M_G_DQ<56>")
	)
	(segment
		(start 144.669764 -35.171888)
		(end 145.057368 -34.784284)
		(width 0.14224)
		(layer "In2.Cu")
		(net "M_G_DQ<56>")
	)
	(segment
		(start 144.669764 -29.482288)
		(end 145.057368 -29.094684)
		(width 0.14224)
		(layer "In2.Cu")
		(net "M_G_DQ<56>")
	)
	(segment
		(start 124.026168 -45.7708)
		(end 124.366782 -45.430186)
		(width 0.14224)
		(layer "In2.Cu")
		(net "M_G_DQ<56>")
	)
	(segment
		(start 145.057368 -31.615888)
		(end 144.669764 -31.228284)
		(width 0.14224)
		(layer "In2.Cu")
		(net "M_G_DQ<56>")
	)
	(arc
		(start 120.567704 -54.61)
		(mid 120.616459 -54.413648)
		(end 120.562878 -54.218586)
		(width 0.0889)
		(layer "In2.Cu")
		(net "M_G_DQ<56>")
	)
	(arc
		(start 120.562878 -55.209186)
		(mid 120.483656 -54.920068)
		(end 120.556528 -54.629304)
		(width 0.0889)
		(layer "In2.Cu")
		(net "M_G_DQ<56>")
	)
	(segment
		(start 118.212362 -57.885584)
		(end 117.640862 -57.885584)
		(width 0.1016)
		(layer "F.Cu")
		(net "M_G_DQ<55>")
	)
	(segment
		(start 139.34948 -15.423642)
		(end 139.34948 -16.687546)
		(width 0.1651)
		(layer "F.Cu")
		(net "M_G_DQ<55>")
	)
	(via
		(at 139.34948 -16.687546)
		(size 0.508)
		(drill 0.254)
		(layers "F.Cu" "B.Cu")
		(net "M_G_DQ<55>")
	)
	(via
		(at 140.199364 -22.279356)
		(size 0.508)
		(drill 0.254)
		(layers "F.Cu" "B.Cu")
		(net "M_G_DQ<55>")
	)
	(via
		(at 117.640862 -57.885584)
		(size 0.508)
		(drill 0.254)
		(layers "F.Cu" "B.Cu")
		(net "M_G_DQ<55>")
	)
	(segment
		(start 140.199364 -22.279356)
		(end 140.199364 -20.224242)
		(width 0.1651)
		(layer "B.Cu")
		(net "M_G_DQ<55>")
	)
	(segment
		(start 139.996418 -17.653)
		(end 139.34948 -17.006062)
		(width 0.14224)
		(layer "In2.Cu")
		(net "M_G_DQ<55>")
	)
	(segment
		(start 140.707618 -18.4658)
		(end 140.707618 -18.1102)
		(width 0.14224)
		(layer "In2.Cu")
		(net "M_G_DQ<55>")
	)
	(segment
		(start 139.34948 -17.006062)
		(end 139.34948 -16.687546)
		(width 0.14224)
		(layer "In2.Cu")
		(net "M_G_DQ<55>")
	)
	(segment
		(start 140.250418 -17.653)
		(end 139.996418 -17.653)
		(width 0.14224)
		(layer "In2.Cu")
		(net "M_G_DQ<55>")
	)
	(segment
		(start 125.042168 -38.0746)
		(end 134.059168 -38.0746)
		(width 0.14224)
		(layer "In2.Cu")
		(net "M_G_DQ<55>")
	)
	(segment
		(start 118.099332 -53.368702)
		(end 118.099332 -51.662838)
		(width 0.0889)
		(layer "In2.Cu")
		(net "M_G_DQ<55>")
	)
	(segment
		(start 118.76659 -50.99558)
		(end 118.76659 -48.658526)
		(width 0.0889)
		(layer "In2.Cu")
		(net "M_G_DQ<55>")
	)
	(segment
		(start 140.55217 -21.92655)
		(end 140.55217 -18.621248)
		(width 0.14224)
		(layer "In2.Cu")
		(net "M_G_DQ<55>")
	)
	(segment
		(start 140.656564 -26.790396)
		(end 140.529564 -26.663396)
		(width 0.14224)
		(layer "In2.Cu")
		(net "M_G_DQ<55>")
	)
	(segment
		(start 119.013732 -44.103036)
		(end 125.042168 -38.0746)
		(width 0.14224)
		(layer "In2.Cu")
		(net "M_G_DQ<55>")
	)
	(segment
		(start 140.250164 -31.883604)
		(end 140.250164 -29.165804)
		(width 0.14224)
		(layer "In2.Cu")
		(net "M_G_DQ<55>")
	)
	(segment
		(start 134.059168 -38.0746)
		(end 140.250164 -31.883604)
		(width 0.14224)
		(layer "In2.Cu")
		(net "M_G_DQ<55>")
	)
	(segment
		(start 139.850368 -23.3934)
		(end 139.723368 -23.2664)
		(width 0.14224)
		(layer "In2.Cu")
		(net "M_G_DQ<55>")
	)
	(segment
		(start 140.199364 -22.279356)
		(end 140.55217 -21.92655)
		(width 0.14224)
		(layer "In2.Cu")
		(net "M_G_DQ<55>")
	)
	(segment
		(start 117.640862 -57.885584)
		(end 117.987572 -57.095136)
		(width 0.0889)
		(layer "In2.Cu")
		(net "M_G_DQ<55>")
	)
	(segment
		(start 140.529564 -26.663396)
		(end 140.529564 -24.749252)
		(width 0.14224)
		(layer "In2.Cu")
		(net "M_G_DQ<55>")
	)
	(segment
		(start 119.013732 -48.411384)
		(end 119.013732 -44.103036)
		(width 0.14224)
		(layer "In2.Cu")
		(net "M_G_DQ<55>")
	)
	(segment
		(start 140.55217 -18.621248)
		(end 140.707618 -18.4658)
		(width 0.14224)
		(layer "In2.Cu")
		(net "M_G_DQ<55>")
	)
	(segment
		(start 118.76659 -48.658526)
		(end 119.013732 -48.411384)
		(width 0.0889)
		(layer "In2.Cu")
		(net "M_G_DQ<55>")
	)
	(segment
		(start 139.723368 -22.755352)
		(end 140.199364 -22.279356)
		(width 0.14224)
		(layer "In2.Cu")
		(net "M_G_DQ<55>")
	)
	(segment
		(start 139.850368 -24.342852)
		(end 139.850368 -23.3934)
		(width 0.14224)
		(layer "In2.Cu")
		(net "M_G_DQ<55>")
	)
	(segment
		(start 140.554964 -28.861004)
		(end 140.554964 -28.339796)
		(width 0.14224)
		(layer "In2.Cu")
		(net "M_G_DQ<55>")
	)
	(segment
		(start 139.723368 -23.2664)
		(end 139.723368 -22.755352)
		(width 0.14224)
		(layer "In2.Cu")
		(net "M_G_DQ<55>")
	)
	(segment
		(start 140.053568 -24.546052)
		(end 139.850368 -24.342852)
		(width 0.14224)
		(layer "In2.Cu")
		(net "M_G_DQ<55>")
	)
	(segment
		(start 118.099332 -51.662838)
		(end 118.76659 -50.99558)
		(width 0.0889)
		(layer "In2.Cu")
		(net "M_G_DQ<55>")
	)
	(segment
		(start 140.707618 -18.1102)
		(end 140.250418 -17.653)
		(width 0.14224)
		(layer "In2.Cu")
		(net "M_G_DQ<55>")
	)
	(segment
		(start 118.23192 -53.50129)
		(end 118.099332 -53.368702)
		(width 0.0889)
		(layer "In2.Cu")
		(net "M_G_DQ<55>")
	)
	(segment
		(start 140.250164 -29.165804)
		(end 140.554964 -28.861004)
		(width 0.14224)
		(layer "In2.Cu")
		(net "M_G_DQ<55>")
	)
	(segment
		(start 140.326364 -24.546052)
		(end 140.053568 -24.546052)
		(width 0.14224)
		(layer "In2.Cu")
		(net "M_G_DQ<55>")
	)
	(segment
		(start 140.656564 -28.238196)
		(end 140.656564 -26.790396)
		(width 0.14224)
		(layer "In2.Cu")
		(net "M_G_DQ<55>")
	)
	(segment
		(start 140.529564 -24.749252)
		(end 140.326364 -24.546052)
		(width 0.14224)
		(layer "In2.Cu")
		(net "M_G_DQ<55>")
	)
	(segment
		(start 140.554964 -28.339796)
		(end 140.656564 -28.238196)
		(width 0.14224)
		(layer "In2.Cu")
		(net "M_G_DQ<55>")
	)
	(segment
		(start 118.23192 -54.913784)
		(end 118.23192 -53.50129)
		(width 0.0889)
		(layer "In2.Cu")
		(net "M_G_DQ<55>")
	)
	(arc
		(start 117.987572 -57.095136)
		(mid 118.034932 -56.965067)
		(end 118.03507 -56.826658)
		(width 0.0889)
		(layer "In2.Cu")
		(net "M_G_DQ<55>")
	)
	(arc
		(start 118.152672 -55.609236)
		(mid 118.099173 -55.409338)
		(end 118.152672 -55.20944)
		(width 0.0889)
		(layer "In2.Cu")
		(net "M_G_DQ<55>")
	)
	(arc
		(start 118.03507 -56.826658)
		(mid 118.040401 -56.503312)
		(end 118.152672 -56.20004)
		(width 0.0889)
		(layer "In2.Cu")
		(net "M_G_DQ<55>")
	)
	(arc
		(start 118.171468 -55.173626)
		(mid 118.216491 -55.047148)
		(end 118.23192 -54.913784)
		(width 0.0889)
		(layer "In2.Cu")
		(net "M_G_DQ<55>")
	)
	(arc
		(start 118.152672 -55.20944)
		(mid 118.162425 -55.191719)
		(end 118.171468 -55.173626)
		(width 0.0889)
		(layer "In2.Cu")
		(net "M_G_DQ<55>")
	)
	(arc
		(start 118.152672 -56.20004)
		(mid 118.231803 -55.904638)
		(end 118.152672 -55.609236)
		(width 0.0889)
		(layer "In2.Cu")
		(net "M_G_DQ<55>")
	)
	(segment
		(start 140.199618 -19.05)
		(end 140.331698 -18.91792)
		(width 0.1651)
		(layer "F.Cu")
		(net "M_G_DQ<54>")
	)
	(segment
		(start 140.199618 -18.5674)
		(end 140.199618 -18.262854)
		(width 0.1651)
		(layer "F.Cu")
		(net "M_G_DQ<54>")
	)
	(segment
		(start 140.331698 -18.69948)
		(end 140.199618 -18.5674)
		(width 0.1651)
		(layer "F.Cu")
		(net "M_G_DQ<54>")
	)
	(segment
		(start 140.199364 -20.023582)
		(end 140.199618 -20.023328)
		(width 0.1651)
		(layer "F.Cu")
		(net "M_G_DQ<54>")
	)
	(segment
		(start 118.212362 -55.904384)
		(end 117.640862 -55.904384)
		(width 0.1016)
		(layer "F.Cu")
		(net "M_G_DQ<54>")
	)
	(segment
		(start 140.331698 -18.91792)
		(end 140.331698 -18.69948)
		(width 0.1651)
		(layer "F.Cu")
		(net "M_G_DQ<54>")
	)
	(segment
		(start 140.199618 -18.262854)
		(end 140.199364 -18.2626)
		(width 0.1651)
		(layer "F.Cu")
		(net "M_G_DQ<54>")
	)
	(segment
		(start 140.199618 -20.023328)
		(end 140.199618 -19.05)
		(width 0.1651)
		(layer "F.Cu")
		(net "M_G_DQ<54>")
	)
	(via
		(at 139.34948 -23.560278)
		(size 0.508)
		(drill 0.254)
		(layers "F.Cu" "B.Cu")
		(net "M_G_DQ<54>")
	)
	(via
		(at 117.640862 -55.904384)
		(size 0.508)
		(drill 0.254)
		(layers "F.Cu" "B.Cu")
		(net "M_G_DQ<54>")
	)
	(via
		(at 140.199364 -18.2626)
		(size 0.508)
		(drill 0.254)
		(layers "F.Cu" "B.Cu")
		(net "M_G_DQ<54>")
	)
	(segment
		(start 139.34948 -24.824182)
		(end 139.34948 -23.560278)
		(width 0.1651)
		(layer "B.Cu")
		(net "M_G_DQ<54>")
	)
	(segment
		(start 139.80668 -25.280366)
		(end 138.8618 -24.335486)
		(width 0.14224)
		(layer "In2.Cu")
		(net "M_G_DQ<54>")
	)
	(segment
		(start 133.896608 -37.204904)
		(end 134.115556 -37.204904)
		(width 0.14224)
		(layer "In2.Cu")
		(net "M_G_DQ<54>")
	)
	(segment
		(start 136.237472 -34.856674)
		(end 135.99033 -34.609532)
		(width 0.14224)
		(layer "In2.Cu")
		(net "M_G_DQ<54>")
	)
	(segment
		(start 133.426962 -36.953952)
		(end 133.64591 -36.953952)
		(width 0.14224)
		(layer "In2.Cu")
		(net "M_G_DQ<54>")
	)
	(segment
		(start 118.57609 -50.908712)
		(end 118.57609 -48.621442)
		(width 0.0889)
		(layer "In2.Cu")
		(net "M_G_DQ<54>")
	)
	(segment
		(start 134.114794 -36.485068)
		(end 134.114794 -36.26612)
		(width 0.14224)
		(layer "In2.Cu")
		(net "M_G_DQ<54>")
	)
	(segment
		(start 135.052562 -35.5473)
		(end 135.052562 -35.328352)
		(width 0.14224)
		(layer "In2.Cu")
		(net "M_G_DQ<54>")
	)
	(segment
		(start 135.053324 -36.267136)
		(end 135.30326 -36.0172)
		(width 0.14224)
		(layer "In2.Cu")
		(net "M_G_DQ<54>")
	)
	(segment
		(start 139.885928 -28.7782)
		(end 139.885928 -28.40736)
		(width 0.14224)
		(layer "In2.Cu")
		(net "M_G_DQ<54>")
	)
	(segment
		(start 135.97001 -35.325558)
		(end 136.237472 -35.058096)
		(width 0.14224)
		(layer "In2.Cu")
		(net "M_G_DQ<54>")
	)
	(segment
		(start 139.742164 -28.263596)
		(end 139.742164 -26.866596)
		(width 0.14224)
		(layer "In2.Cu")
		(net "M_G_DQ<54>")
	)
	(segment
		(start 117.908578 -51.576224)
		(end 118.57609 -50.908712)
		(width 0.0889)
		(layer "In2.Cu")
		(net "M_G_DQ<54>")
	)
	(segment
		(start 139.841986 -19.970496)
		(end 139.460986 -19.589496)
		(width 0.14224)
		(layer "In2.Cu")
		(net "M_G_DQ<54>")
	)
	(segment
		(start 139.34948 -23.560278)
		(end 139.113768 -23.324566)
		(width 0.14224)
		(layer "In2.Cu")
		(net "M_G_DQ<54>")
	)
	(segment
		(start 135.30326 -36.0172)
		(end 135.30326 -35.798252)
		(width 0.14224)
		(layer "In2.Cu")
		(net "M_G_DQ<54>")
	)
	(segment
		(start 118.366032 -44.064936)
		(end 124.864368 -37.5666)
		(width 0.14224)
		(layer "In2.Cu")
		(net "M_G_DQ<54>")
	)
	(segment
		(start 139.460986 -19.589496)
		(end 139.460986 -19.278854)
		(width 0.14224)
		(layer "In2.Cu")
		(net "M_G_DQ<54>")
	)
	(segment
		(start 135.302498 -35.078416)
		(end 135.521446 -35.078416)
		(width 0.14224)
		(layer "In2.Cu")
		(net "M_G_DQ<54>")
	)
	(segment
		(start 135.30326 -35.798252)
		(end 135.052562 -35.5473)
		(width 0.14224)
		(layer "In2.Cu")
		(net "M_G_DQ<54>")
	)
	(segment
		(start 139.841986 -20.313904)
		(end 139.841986 -19.970496)
		(width 0.14224)
		(layer "In2.Cu")
		(net "M_G_DQ<54>")
	)
	(segment
		(start 132.814314 -37.5666)
		(end 133.426962 -36.953952)
		(width 0.14224)
		(layer "In2.Cu")
		(net "M_G_DQ<54>")
	)
	(segment
		(start 139.113768 -22.530054)
		(end 139.886436 -21.757386)
		(width 0.14224)
		(layer "In2.Cu")
		(net "M_G_DQ<54>")
	)
	(segment
		(start 117.908578 -53.471064)
		(end 117.908578 -51.576224)
		(width 0.0889)
		(layer "In2.Cu")
		(net "M_G_DQ<54>")
	)
	(segment
		(start 139.460986 -20.694904)
		(end 139.841986 -20.313904)
		(width 0.14224)
		(layer "In2.Cu")
		(net "M_G_DQ<54>")
	)
	(segment
		(start 135.521446 -35.078416)
		(end 135.768588 -35.325558)
		(width 0.14224)
		(layer "In2.Cu")
		(net "M_G_DQ<54>")
	)
	(segment
		(start 139.885928 -28.40736)
		(end 139.742164 -28.263596)
		(width 0.14224)
		(layer "In2.Cu")
		(net "M_G_DQ<54>")
	)
	(segment
		(start 137.02792 -34.140648)
		(end 137.462768 -33.7058)
		(width 0.14224)
		(layer "In2.Cu")
		(net "M_G_DQ<54>")
	)
	(segment
		(start 135.052562 -35.328352)
		(end 135.302498 -35.078416)
		(width 0.14224)
		(layer "In2.Cu")
		(net "M_G_DQ<54>")
	)
	(segment
		(start 139.824968 -18.914872)
		(end 139.824968 -18.636996)
		(width 0.14224)
		(layer "In2.Cu")
		(net "M_G_DQ<54>")
	)
	(segment
		(start 117.640862 -55.904384)
		(end 117.955314 -55.178452)
		(width 0.0889)
		(layer "In2.Cu")
		(net "M_G_DQ<54>")
	)
	(segment
		(start 139.113768 -23.324566)
		(end 139.113768 -22.530054)
		(width 0.14224)
		(layer "In2.Cu")
		(net "M_G_DQ<54>")
	)
	(segment
		(start 138.8618 -24.335486)
		(end 138.8618 -24.047958)
		(width 0.14224)
		(layer "In2.Cu")
		(net "M_G_DQ<54>")
	)
	(segment
		(start 118.041166 -53.603652)
		(end 117.908578 -53.471064)
		(width 0.0889)
		(layer "In2.Cu")
		(net "M_G_DQ<54>")
	)
	(segment
		(start 134.365492 -36.73602)
		(end 134.114794 -36.485068)
		(width 0.14224)
		(layer "In2.Cu")
		(net "M_G_DQ<54>")
	)
	(segment
		(start 139.302236 -23.607268)
		(end 139.34948 -23.560278)
		(width 0.14224)
		(layer "In2.Cu")
		(net "M_G_DQ<54>")
	)
	(segment
		(start 139.80668 -26.80208)
		(end 139.80668 -25.280366)
		(width 0.14224)
		(layer "In2.Cu")
		(net "M_G_DQ<54>")
	)
	(segment
		(start 134.114794 -36.26612)
		(end 134.36473 -36.016184)
		(width 0.14224)
		(layer "In2.Cu")
		(net "M_G_DQ<54>")
	)
	(segment
		(start 137.462768 -33.7058)
		(end 137.462768 -32.918146)
		(width 0.14224)
		(layer "In2.Cu")
		(net "M_G_DQ<54>")
	)
	(segment
		(start 134.834376 -36.267136)
		(end 135.053324 -36.267136)
		(width 0.14224)
		(layer "In2.Cu")
		(net "M_G_DQ<54>")
	)
	(segment
		(start 139.886436 -21.405596)
		(end 139.460986 -20.980146)
		(width 0.14224)
		(layer "In2.Cu")
		(net "M_G_DQ<54>")
	)
	(segment
		(start 124.864368 -37.5666)
		(end 132.814314 -37.5666)
		(width 0.14224)
		(layer "In2.Cu")
		(net "M_G_DQ<54>")
	)
	(segment
		(start 134.365492 -36.954968)
		(end 134.365492 -36.73602)
		(width 0.14224)
		(layer "In2.Cu")
		(net "M_G_DQ<54>")
	)
	(segment
		(start 139.041378 -23.86838)
		(end 139.302236 -23.607268)
		(width 0.14224)
		(layer "In2.Cu")
		(net "M_G_DQ<54>")
	)
	(segment
		(start 134.583678 -36.016184)
		(end 134.834376 -36.267136)
		(width 0.14224)
		(layer "In2.Cu")
		(net "M_G_DQ<54>")
	)
	(segment
		(start 135.99033 -34.609532)
		(end 135.99033 -34.390584)
		(width 0.14224)
		(layer "In2.Cu")
		(net "M_G_DQ<54>")
	)
	(segment
		(start 135.99033 -34.390584)
		(end 136.240266 -34.140648)
		(width 0.14224)
		(layer "In2.Cu")
		(net "M_G_DQ<54>")
	)
	(segment
		(start 138.8618 -24.047958)
		(end 139.041378 -23.86838)
		(width 0.14224)
		(layer "In2.Cu")
		(net "M_G_DQ<54>")
	)
	(segment
		(start 139.742164 -26.866596)
		(end 139.80668 -26.80208)
		(width 0.14224)
		(layer "In2.Cu")
		(net "M_G_DQ<54>")
	)
	(segment
		(start 137.462768 -32.918146)
		(end 139.615164 -30.76575)
		(width 0.14224)
		(layer "In2.Cu")
		(net "M_G_DQ<54>")
	)
	(segment
		(start 139.824968 -18.636996)
		(end 140.199364 -18.2626)
		(width 0.14224)
		(layer "In2.Cu")
		(net "M_G_DQ<54>")
	)
	(segment
		(start 136.240266 -34.140648)
		(end 137.02792 -34.140648)
		(width 0.14224)
		(layer "In2.Cu")
		(net "M_G_DQ<54>")
	)
	(segment
		(start 134.36473 -36.016184)
		(end 134.583678 -36.016184)
		(width 0.14224)
		(layer "In2.Cu")
		(net "M_G_DQ<54>")
	)
	(segment
		(start 139.886436 -21.757386)
		(end 139.886436 -21.405596)
		(width 0.14224)
		(layer "In2.Cu")
		(net "M_G_DQ<54>")
	)
	(segment
		(start 134.115556 -37.204904)
		(end 134.365492 -36.954968)
		(width 0.14224)
		(layer "In2.Cu")
		(net "M_G_DQ<54>")
	)
	(segment
		(start 139.615164 -30.76575)
		(end 139.615164 -29.048964)
		(width 0.14224)
		(layer "In2.Cu")
		(net "M_G_DQ<54>")
	)
	(segment
		(start 139.615164 -29.048964)
		(end 139.885928 -28.7782)
		(width 0.14224)
		(layer "In2.Cu")
		(net "M_G_DQ<54>")
	)
	(segment
		(start 118.366032 -48.411384)
		(end 118.366032 -44.064936)
		(width 0.14224)
		(layer "In2.Cu")
		(net "M_G_DQ<54>")
	)
	(segment
		(start 139.460986 -20.980146)
		(end 139.460986 -20.694904)
		(width 0.14224)
		(layer "In2.Cu")
		(net "M_G_DQ<54>")
	)
	(segment
		(start 136.237472 -35.058096)
		(end 136.237472 -34.856674)
		(width 0.14224)
		(layer "In2.Cu")
		(net "M_G_DQ<54>")
	)
	(segment
		(start 139.460986 -19.278854)
		(end 139.824968 -18.914872)
		(width 0.14224)
		(layer "In2.Cu")
		(net "M_G_DQ<54>")
	)
	(segment
		(start 135.768588 -35.325558)
		(end 135.97001 -35.325558)
		(width 0.14224)
		(layer "In2.Cu")
		(net "M_G_DQ<54>")
	)
	(segment
		(start 118.57609 -48.621442)
		(end 118.366032 -48.411384)
		(width 0.0889)
		(layer "In2.Cu")
		(net "M_G_DQ<54>")
	)
	(segment
		(start 133.64591 -36.953952)
		(end 133.896608 -37.204904)
		(width 0.14224)
		(layer "In2.Cu")
		(net "M_G_DQ<54>")
	)
	(segment
		(start 118.041166 -54.913784)
		(end 118.041166 -53.603652)
		(width 0.0889)
		(layer "In2.Cu")
		(net "M_G_DQ<54>")
	)
	(arc
		(start 117.987572 -55.113936)
		(mid 118.027559 -55.01739)
		(end 118.041166 -54.913784)
		(width 0.0889)
		(layer "In2.Cu")
		(net "M_G_DQ<54>")
	)
	(arc
		(start 117.955314 -55.178452)
		(mid 117.970461 -55.145703)
		(end 117.987572 -55.113936)
		(width 0.0889)
		(layer "In2.Cu")
		(net "M_G_DQ<54>")
	)
	(segment
		(start 133.39953 -15.423642)
		(end 133.39953 -16.687546)
		(width 0.1651)
		(layer "F.Cu")
		(net "M_G_DQ<53>")
	)
	(segment
		(start 115.636802 -57.390538)
		(end 115.065302 -57.390538)
		(width 0.1016)
		(layer "F.Cu")
		(net "M_G_DQ<53>")
	)
	(via
		(at 115.065302 -57.390538)
		(size 0.508)
		(drill 0.254)
		(layers "F.Cu" "B.Cu")
		(net "M_G_DQ<53>")
	)
	(via
		(at 134.173214 -22.279356)
		(size 0.508)
		(drill 0.254)
		(layers "F.Cu" "B.Cu")
		(net "M_G_DQ<53>")
	)
	(via
		(at 133.39953 -16.687546)
		(size 0.508)
		(drill 0.254)
		(layers "F.Cu" "B.Cu")
		(net "M_G_DQ<53>")
	)
	(segment
		(start 134.249414 -20.224242)
		(end 134.249414 -22.203156)
		(width 0.1651)
		(layer "B.Cu")
		(net "M_G_DQ<53>")
	)
	(segment
		(start 134.249414 -22.203156)
		(end 134.173214 -22.279356)
		(width 0.1651)
		(layer "B.Cu")
		(net "M_G_DQ<53>")
	)
	(segment
		(start 134.636764 -26.841196)
		(end 134.585964 -26.790396)
		(width 0.14224)
		(layer "In2.Cu")
		(net "M_G_DQ<53>")
	)
	(segment
		(start 114.718592 -54.218586)
		(end 114.808508 -54.076854)
		(width 0.0889)
		(layer "In2.Cu")
		(net "M_G_DQ<53>")
	)
	(segment
		(start 115.228624 -56.034432)
		(end 115.02136 -55.950612)
		(width 0.0889)
		(layer "In2.Cu")
		(net "M_G_DQ<53>")
	)
	(segment
		(start 133.970268 -17.653)
		(end 133.39953 -17.082262)
		(width 0.14224)
		(layer "In2.Cu")
		(net "M_G_DQ<53>")
	)
	(segment
		(start 133.982714 -23.714202)
		(end 133.982714 -23.418546)
		(width 0.14224)
		(layer "In2.Cu")
		(net "M_G_DQ<53>")
	)
	(segment
		(start 133.671564 -23.107396)
		(end 133.671564 -22.781006)
		(width 0.14224)
		(layer "In2.Cu")
		(net "M_G_DQ<53>")
	)
	(segment
		(start 134.484618 -21.967952)
		(end 134.484618 -18.66265)
		(width 0.14224)
		(layer "In2.Cu")
		(net "M_G_DQ<53>")
	)
	(segment
		(start 114.022124 -49.601374)
		(end 114.022124 -49.351692)
		(width 0.0889)
		(layer "In2.Cu")
		(net "M_G_DQ<53>")
	)
	(segment
		(start 133.982714 -23.418546)
		(end 133.671564 -23.107396)
		(width 0.14224)
		(layer "In2.Cu")
		(net "M_G_DQ<53>")
	)
	(segment
		(start 115.065302 -57.390538)
		(end 115.39474 -56.629554)
		(width 0.0889)
		(layer "In2.Cu")
		(net "M_G_DQ<53>")
	)
	(segment
		(start 134.285736 -24.502872)
		(end 134.382764 -24.502872)
		(width 0.14224)
		(layer "In2.Cu")
		(net "M_G_DQ<53>")
	)
	(segment
		(start 119.212868 -36.461954)
		(end 120.127268 -36.461954)
		(width 0.14224)
		(layer "In2.Cu")
		(net "M_G_DQ<53>")
	)
	(segment
		(start 134.585964 -25.518872)
		(end 134.382764 -25.315672)
		(width 0.14224)
		(layer "In2.Cu")
		(net "M_G_DQ<53>")
	)
	(segment
		(start 134.484618 -18.66265)
		(end 134.681468 -18.4658)
		(width 0.14224)
		(layer "In2.Cu")
		(net "M_G_DQ<53>")
	)
	(segment
		(start 134.585964 -24.299672)
		(end 134.585964 -24.059896)
		(width 0.14224)
		(layer "In2.Cu")
		(net "M_G_DQ<53>")
	)
	(segment
		(start 115.39474 -56.629554)
		(end 115.416838 -56.5912)
		(width 0.0889)
		(layer "In2.Cu")
		(net "M_G_DQ<53>")
	)
	(segment
		(start 134.082536 -25.112472)
		(end 134.082536 -24.706072)
		(width 0.14224)
		(layer "In2.Cu")
		(net "M_G_DQ<53>")
	)
	(segment
		(start 114.196368 -49.08804)
		(end 114.196368 -41.478454)
		(width 0.14224)
		(layer "In2.Cu")
		(net "M_G_DQ<53>")
	)
	(segment
		(start 122.934222 -33.655)
		(end 129.817114 -33.655)
		(width 0.14224)
		(layer "In2.Cu")
		(net "M_G_DQ<53>")
	)
	(segment
		(start 114.718592 -54.618636)
		(end 114.713766 -54.61)
		(width 0.0889)
		(layer "In2.Cu")
		(net "M_G_DQ<53>")
	)
	(segment
		(start 114.629184 -51.812952)
		(end 114.629184 -51.142138)
		(width 0.0889)
		(layer "In2.Cu")
		(net "M_G_DQ<53>")
	)
	(segment
		(start 114.433604 -50.012854)
		(end 114.022124 -49.601374)
		(width 0.0889)
		(layer "In2.Cu")
		(net "M_G_DQ<53>")
	)
	(segment
		(start 114.75974 -55.68061)
		(end 114.713766 -55.6006)
		(width 0.0889)
		(layer "In2.Cu")
		(net "M_G_DQ<53>")
	)
	(segment
		(start 114.629184 -51.142138)
		(end 114.433604 -50.946558)
		(width 0.0889)
		(layer "In2.Cu")
		(net "M_G_DQ<53>")
	)
	(segment
		(start 134.281164 -17.653)
		(end 133.970268 -17.653)
		(width 0.14224)
		(layer "In2.Cu")
		(net "M_G_DQ<53>")
	)
	(segment
		(start 134.585964 -24.059896)
		(end 134.390892 -23.864824)
		(width 0.14224)
		(layer "In2.Cu")
		(net "M_G_DQ<53>")
	)
	(segment
		(start 134.382764 -25.315672)
		(end 134.285736 -25.315672)
		(width 0.14224)
		(layer "In2.Cu")
		(net "M_G_DQ<53>")
	)
	(segment
		(start 114.196368 -41.478454)
		(end 119.212868 -36.461954)
		(width 0.14224)
		(layer "In2.Cu")
		(net "M_G_DQ<53>")
	)
	(segment
		(start 134.173214 -22.279356)
		(end 134.484618 -21.967952)
		(width 0.14224)
		(layer "In2.Cu")
		(net "M_G_DQ<53>")
	)
	(segment
		(start 134.133336 -23.864824)
		(end 133.982714 -23.714202)
		(width 0.14224)
		(layer "In2.Cu")
		(net "M_G_DQ<53>")
	)
	(segment
		(start 114.86515 -55.809896)
		(end 114.75974 -55.68061)
		(width 0.0889)
		(layer "In2.Cu")
		(net "M_G_DQ<53>")
	)
	(segment
		(start 129.817114 -33.655)
		(end 134.636764 -28.83535)
		(width 0.14224)
		(layer "In2.Cu")
		(net "M_G_DQ<53>")
	)
	(segment
		(start 134.390892 -23.864824)
		(end 134.133336 -23.864824)
		(width 0.14224)
		(layer "In2.Cu")
		(net "M_G_DQ<53>")
	)
	(segment
		(start 120.127268 -36.461954)
		(end 122.934222 -33.655)
		(width 0.14224)
		(layer "In2.Cu")
		(net "M_G_DQ<53>")
	)
	(segment
		(start 134.681468 -18.053304)
		(end 134.281164 -17.653)
		(width 0.14224)
		(layer "In2.Cu")
		(net "M_G_DQ<53>")
	)
	(segment
		(start 114.724942 -54.629304)
		(end 114.718592 -54.618636)
		(width 0.0889)
		(layer "In2.Cu")
		(net "M_G_DQ<53>")
	)
	(segment
		(start 115.02136 -55.950612)
		(end 114.86515 -55.809896)
		(width 0.0889)
		(layer "In2.Cu")
		(net "M_G_DQ<53>")
	)
	(segment
		(start 134.082536 -24.706072)
		(end 134.285736 -24.502872)
		(width 0.14224)
		(layer "In2.Cu")
		(net "M_G_DQ<53>")
	)
	(segment
		(start 134.636764 -28.83535)
		(end 134.636764 -26.841196)
		(width 0.14224)
		(layer "In2.Cu")
		(net "M_G_DQ<53>")
	)
	(segment
		(start 134.382764 -24.502872)
		(end 134.585964 -24.299672)
		(width 0.14224)
		(layer "In2.Cu")
		(net "M_G_DQ<53>")
	)
	(segment
		(start 134.585964 -26.790396)
		(end 134.585964 -25.518872)
		(width 0.14224)
		(layer "In2.Cu")
		(net "M_G_DQ<53>")
	)
	(segment
		(start 114.808508 -51.992276)
		(end 114.629184 -51.812952)
		(width 0.0889)
		(layer "In2.Cu")
		(net "M_G_DQ<53>")
	)
	(segment
		(start 134.681468 -18.4658)
		(end 134.681468 -18.053304)
		(width 0.14224)
		(layer "In2.Cu")
		(net "M_G_DQ<53>")
	)
	(segment
		(start 133.671564 -22.781006)
		(end 134.173214 -22.279356)
		(width 0.14224)
		(layer "In2.Cu")
		(net "M_G_DQ<53>")
	)
	(segment
		(start 114.241072 -49.132744)
		(end 114.196368 -49.08804)
		(width 0.14224)
		(layer "In2.Cu")
		(net "M_G_DQ<53>")
	)
	(segment
		(start 114.808508 -54.076854)
		(end 114.808508 -51.992276)
		(width 0.0889)
		(layer "In2.Cu")
		(net "M_G_DQ<53>")
	)
	(segment
		(start 114.022124 -49.351692)
		(end 114.241072 -49.132744)
		(width 0.0889)
		(layer "In2.Cu")
		(net "M_G_DQ<53>")
	)
	(segment
		(start 133.39953 -17.082262)
		(end 133.39953 -16.687546)
		(width 0.14224)
		(layer "In2.Cu")
		(net "M_G_DQ<53>")
	)
	(segment
		(start 134.285736 -25.315672)
		(end 134.082536 -25.112472)
		(width 0.14224)
		(layer "In2.Cu")
		(net "M_G_DQ<53>")
	)
	(segment
		(start 114.433604 -50.946558)
		(end 114.433604 -50.012854)
		(width 0.0889)
		(layer "In2.Cu")
		(net "M_G_DQ<53>")
	)
	(arc
		(start 115.416838 -56.5912)
		(mid 115.444404 -56.271717)
		(end 115.228624 -56.034432)
		(width 0.0889)
		(layer "In2.Cu")
		(net "M_G_DQ<53>")
	)
	(arc
		(start 114.713766 -54.61)
		(mid 114.665011 -54.413648)
		(end 114.718592 -54.218586)
		(width 0.0889)
		(layer "In2.Cu")
		(net "M_G_DQ<53>")
	)
	(arc
		(start 114.713766 -55.6006)
		(mid 114.665011 -55.404248)
		(end 114.718592 -55.209186)
		(width 0.0889)
		(layer "In2.Cu")
		(net "M_G_DQ<53>")
	)
	(arc
		(start 114.718592 -55.209186)
		(mid 114.797814 -54.920068)
		(end 114.724942 -54.629304)
		(width 0.0889)
		(layer "In2.Cu")
		(net "M_G_DQ<53>")
	)
	(segment
		(start 134.249414 -18.692368)
		(end 134.15137 -18.161)
		(width 0.1651)
		(layer "F.Cu")
		(net "M_G_DQ<52>")
	)
	(segment
		(start 115.636802 -56.399938)
		(end 115.065302 -56.399938)
		(width 0.1016)
		(layer "F.Cu")
		(net "M_G_DQ<52>")
	)
	(segment
		(start 134.249414 -20.023582)
		(end 134.249414 -18.692368)
		(width 0.1651)
		(layer "F.Cu")
		(net "M_G_DQ<52>")
	)
	(via
		(at 133.39953 -23.560278)
		(size 0.508)
		(drill 0.254)
		(layers "F.Cu" "B.Cu")
		(net "M_G_DQ<52>")
	)
	(via
		(at 134.15137 -18.161)
		(size 0.508)
		(drill 0.254)
		(layers "F.Cu" "B.Cu")
		(net "M_G_DQ<52>")
	)
	(via
		(at 115.065302 -56.399938)
		(size 0.508)
		(drill 0.254)
		(layers "F.Cu" "B.Cu")
		(net "M_G_DQ<52>")
	)
	(segment
		(start 133.39953 -23.560278)
		(end 133.39953 -24.824182)
		(width 0.1651)
		(layer "B.Cu")
		(net "M_G_DQ<52>")
	)
	(segment
		(start 133.39953 -23.893018)
		(end 133.39953 -23.560278)
		(width 0.14224)
		(layer "In2.Cu")
		(net "M_G_DQ<52>")
	)
	(segment
		(start 114.243104 -50.092102)
		(end 113.831624 -49.680622)
		(width 0.0889)
		(layer "In2.Cu")
		(net "M_G_DQ<52>")
	)
	(segment
		(start 113.688368 -43.171364)
		(end 113.688368 -41.224454)
		(width 0.14224)
		(layer "In2.Cu")
		(net "M_G_DQ<52>")
	)
	(segment
		(start 113.533428 -46.248574)
		(end 113.688368 -46.093634)
		(width 0.14224)
		(layer "In2.Cu")
		(net "M_G_DQ<52>")
	)
	(segment
		(start 114.553492 -55.704486)
		(end 114.547142 -55.693818)
		(width 0.0889)
		(layer "In2.Cu")
		(net "M_G_DQ<52>")
	)
	(segment
		(start 133.549136 -25.846024)
		(end 133.549136 -24.042624)
		(width 0.14224)
		(layer "In2.Cu")
		(net "M_G_DQ<52>")
	)
	(segment
		(start 113.533428 -45.585634)
		(end 113.208308 -45.585634)
		(width 0.14224)
		(layer "In2.Cu")
		(net "M_G_DQ<52>")
	)
	(segment
		(start 115.043712 -56.396636)
		(end 114.632994 -55.84444)
		(width 0.0889)
		(layer "In2.Cu")
		(net "M_G_DQ<52>")
	)
	(segment
		(start 113.688368 -41.224454)
		(end 122.121422 -32.7914)
		(width 0.14224)
		(layer "In2.Cu")
		(net "M_G_DQ<52>")
	)
	(segment
		(start 113.208308 -44.922694)
		(end 113.533428 -44.922694)
		(width 0.14224)
		(layer "In2.Cu")
		(net "M_G_DQ<52>")
	)
	(segment
		(start 133.163818 -22.530054)
		(end 133.875018 -21.818854)
		(width 0.14224)
		(layer "In2.Cu")
		(net "M_G_DQ<52>")
	)
	(segment
		(start 113.831624 -49.680622)
		(end 113.831624 -49.370996)
		(width 0.0889)
		(layer "In2.Cu")
		(net "M_G_DQ<52>")
	)
	(segment
		(start 113.688368 -44.767754)
		(end 113.688368 -44.106084)
		(width 0.14224)
		(layer "In2.Cu")
		(net "M_G_DQ<52>")
	)
	(segment
		(start 133.511036 -19.5834)
		(end 133.511036 -19.278854)
		(width 0.14224)
		(layer "In2.Cu")
		(net "M_G_DQ<52>")
	)
	(segment
		(start 114.438684 -51.221386)
		(end 114.243104 -51.025806)
		(width 0.0889)
		(layer "In2.Cu")
		(net "M_G_DQ<52>")
	)
	(segment
		(start 134.001764 -28.683204)
		(end 134.001764 -28.441396)
		(width 0.14224)
		(layer "In2.Cu")
		(net "M_G_DQ<52>")
	)
	(segment
		(start 114.553492 -54.713886)
		(end 114.547142 -54.703218)
		(width 0.0889)
		(layer "In2.Cu")
		(net "M_G_DQ<52>")
	)
	(segment
		(start 113.688368 -47.066454)
		(end 113.533428 -46.911514)
		(width 0.14224)
		(layer "In2.Cu")
		(net "M_G_DQ<52>")
	)
	(segment
		(start 113.831624 -49.370996)
		(end 113.593372 -49.132744)
		(width 0.0889)
		(layer "In2.Cu")
		(net "M_G_DQ<52>")
	)
	(segment
		(start 113.688368 -45.740574)
		(end 113.533428 -45.585634)
		(width 0.14224)
		(layer "In2.Cu")
		(net "M_G_DQ<52>")
	)
	(segment
		(start 113.053368 -47.729394)
		(end 113.208308 -47.574454)
		(width 0.14224)
		(layer "In2.Cu")
		(net "M_G_DQ<52>")
	)
	(segment
		(start 113.208308 -46.248574)
		(end 113.533428 -46.248574)
		(width 0.14224)
		(layer "In2.Cu")
		(net "M_G_DQ<52>")
	)
	(segment
		(start 113.546128 -43.963844)
		(end 113.170208 -43.963844)
		(width 0.14224)
		(layer "In2.Cu")
		(net "M_G_DQ<52>")
	)
	(segment
		(start 133.875018 -18.437352)
		(end 134.15137 -18.161)
		(width 0.14224)
		(layer "In2.Cu")
		(net "M_G_DQ<52>")
	)
	(segment
		(start 133.523736 -20.6375)
		(end 133.892036 -20.2692)
		(width 0.14224)
		(layer "In2.Cu")
		(net "M_G_DQ<52>")
	)
	(segment
		(start 113.053368 -46.756574)
		(end 113.053368 -46.403514)
		(width 0.14224)
		(layer "In2.Cu")
		(net "M_G_DQ<52>")
	)
	(segment
		(start 113.170208 -43.313604)
		(end 113.546128 -43.313604)
		(width 0.14224)
		(layer "In2.Cu")
		(net "M_G_DQ<52>")
	)
	(segment
		(start 113.208308 -46.911514)
		(end 113.053368 -46.756574)
		(width 0.14224)
		(layer "In2.Cu")
		(net "M_G_DQ<52>")
	)
	(segment
		(start 133.925564 -26.222452)
		(end 133.549136 -25.846024)
		(width 0.14224)
		(layer "In2.Cu")
		(net "M_G_DQ<52>")
	)
	(segment
		(start 133.163818 -23.324566)
		(end 133.163818 -22.530054)
		(width 0.14224)
		(layer "In2.Cu")
		(net "M_G_DQ<52>")
	)
	(segment
		(start 113.546128 -43.313604)
		(end 113.688368 -43.171364)
		(width 0.14224)
		(layer "In2.Cu")
		(net "M_G_DQ<52>")
	)
	(segment
		(start 113.688368 -44.106084)
		(end 113.546128 -43.963844)
		(width 0.14224)
		(layer "In2.Cu")
		(net "M_G_DQ<52>")
	)
	(segment
		(start 113.688368 -46.093634)
		(end 113.688368 -45.740574)
		(width 0.14224)
		(layer "In2.Cu")
		(net "M_G_DQ<52>")
	)
	(segment
		(start 114.553492 -54.123336)
		(end 114.618008 -54.011576)
		(width 0.0889)
		(layer "In2.Cu")
		(net "M_G_DQ<52>")
	)
	(segment
		(start 114.438684 -51.891946)
		(end 114.438684 -51.221386)
		(width 0.0889)
		(layer "In2.Cu")
		(net "M_G_DQ<52>")
	)
	(segment
		(start 113.027968 -43.821604)
		(end 113.027968 -43.455844)
		(width 0.14224)
		(layer "In2.Cu")
		(net "M_G_DQ<52>")
	)
	(segment
		(start 133.549136 -24.042624)
		(end 133.39953 -23.893018)
		(width 0.14224)
		(layer "In2.Cu")
		(net "M_G_DQ<52>")
	)
	(segment
		(start 129.893568 -32.7914)
		(end 134.001764 -28.683204)
		(width 0.14224)
		(layer "In2.Cu")
		(net "M_G_DQ<52>")
	)
	(segment
		(start 113.170208 -43.963844)
		(end 113.027968 -43.821604)
		(width 0.14224)
		(layer "In2.Cu")
		(net "M_G_DQ<52>")
	)
	(segment
		(start 113.533428 -46.911514)
		(end 113.208308 -46.911514)
		(width 0.14224)
		(layer "In2.Cu")
		(net "M_G_DQ<52>")
	)
	(segment
		(start 133.892036 -20.2692)
		(end 133.892036 -19.9644)
		(width 0.14224)
		(layer "In2.Cu")
		(net "M_G_DQ<52>")
	)
	(segment
		(start 133.523736 -20.992846)
		(end 133.523736 -20.6375)
		(width 0.14224)
		(layer "In2.Cu")
		(net "M_G_DQ<52>")
	)
	(segment
		(start 113.593372 -49.132744)
		(end 113.053368 -48.59274)
		(width 0.14224)
		(layer "In2.Cu")
		(net "M_G_DQ<52>")
	)
	(segment
		(start 133.39953 -23.560278)
		(end 133.163818 -23.324566)
		(width 0.14224)
		(layer "In2.Cu")
		(net "M_G_DQ<52>")
	)
	(segment
		(start 113.053368 -46.403514)
		(end 113.208308 -46.248574)
		(width 0.14224)
		(layer "In2.Cu")
		(net "M_G_DQ<52>")
	)
	(segment
		(start 114.618008 -54.011576)
		(end 114.618008 -52.07127)
		(width 0.0889)
		(layer "In2.Cu")
		(net "M_G_DQ<52>")
	)
	(segment
		(start 133.875018 -21.818854)
		(end 133.875018 -21.344128)
		(width 0.14224)
		(layer "In2.Cu")
		(net "M_G_DQ<52>")
	)
	(segment
		(start 113.208308 -45.585634)
		(end 113.053368 -45.430694)
		(width 0.14224)
		(layer "In2.Cu")
		(net "M_G_DQ<52>")
	)
	(segment
		(start 113.053368 -48.59274)
		(end 113.053368 -47.729394)
		(width 0.14224)
		(layer "In2.Cu")
		(net "M_G_DQ<52>")
	)
	(segment
		(start 114.632994 -55.84444)
		(end 114.553492 -55.704486)
		(width 0.0889)
		(layer "In2.Cu")
		(net "M_G_DQ<52>")
	)
	(segment
		(start 113.688368 -47.419514)
		(end 113.688368 -47.066454)
		(width 0.14224)
		(layer "In2.Cu")
		(net "M_G_DQ<52>")
	)
	(segment
		(start 133.892036 -19.9644)
		(end 133.511036 -19.5834)
		(width 0.14224)
		(layer "In2.Cu")
		(net "M_G_DQ<52>")
	)
	(segment
		(start 113.027968 -43.455844)
		(end 113.170208 -43.313604)
		(width 0.14224)
		(layer "In2.Cu")
		(net "M_G_DQ<52>")
	)
	(segment
		(start 133.875018 -18.914872)
		(end 133.875018 -18.437352)
		(width 0.14224)
		(layer "In2.Cu")
		(net "M_G_DQ<52>")
	)
	(segment
		(start 133.875018 -21.344128)
		(end 133.523736 -20.992846)
		(width 0.14224)
		(layer "In2.Cu")
		(net "M_G_DQ<52>")
	)
	(segment
		(start 133.696964 -26.993596)
		(end 133.925564 -26.764996)
		(width 0.14224)
		(layer "In2.Cu")
		(net "M_G_DQ<52>")
	)
	(segment
		(start 133.925564 -26.764996)
		(end 133.925564 -26.222452)
		(width 0.14224)
		(layer "In2.Cu")
		(net "M_G_DQ<52>")
	)
	(segment
		(start 134.001764 -28.441396)
		(end 133.696964 -28.136596)
		(width 0.14224)
		(layer "In2.Cu")
		(net "M_G_DQ<52>")
	)
	(segment
		(start 114.243104 -51.025806)
		(end 114.243104 -50.092102)
		(width 0.0889)
		(layer "In2.Cu")
		(net "M_G_DQ<52>")
	)
	(segment
		(start 113.208308 -47.574454)
		(end 113.533428 -47.574454)
		(width 0.14224)
		(layer "In2.Cu")
		(net "M_G_DQ<52>")
	)
	(segment
		(start 113.053368 -45.077634)
		(end 113.208308 -44.922694)
		(width 0.14224)
		(layer "In2.Cu")
		(net "M_G_DQ<52>")
	)
	(segment
		(start 114.558318 -54.722522)
		(end 114.553492 -54.713886)
		(width 0.0889)
		(layer "In2.Cu")
		(net "M_G_DQ<52>")
	)
	(segment
		(start 122.121422 -32.7914)
		(end 129.893568 -32.7914)
		(width 0.14224)
		(layer "In2.Cu")
		(net "M_G_DQ<52>")
	)
	(segment
		(start 113.533428 -44.922694)
		(end 113.688368 -44.767754)
		(width 0.14224)
		(layer "In2.Cu")
		(net "M_G_DQ<52>")
	)
	(segment
		(start 113.053368 -45.430694)
		(end 113.053368 -45.077634)
		(width 0.14224)
		(layer "In2.Cu")
		(net "M_G_DQ<52>")
	)
	(segment
		(start 114.618008 -52.07127)
		(end 114.438684 -51.891946)
		(width 0.0889)
		(layer "In2.Cu")
		(net "M_G_DQ<52>")
	)
	(segment
		(start 115.065302 -56.399938)
		(end 115.043712 -56.396636)
		(width 0.0889)
		(layer "In2.Cu")
		(net "M_G_DQ<52>")
	)
	(segment
		(start 113.533428 -47.574454)
		(end 113.688368 -47.419514)
		(width 0.14224)
		(layer "In2.Cu")
		(net "M_G_DQ<52>")
	)
	(segment
		(start 133.696964 -28.136596)
		(end 133.696964 -26.993596)
		(width 0.14224)
		(layer "In2.Cu")
		(net "M_G_DQ<52>")
	)
	(segment
		(start 133.511036 -19.278854)
		(end 133.875018 -18.914872)
		(width 0.14224)
		(layer "In2.Cu")
		(net "M_G_DQ<52>")
	)
	(arc
		(start 114.547142 -55.693818)
		(mid 114.474344 -55.403055)
		(end 114.553492 -55.113936)
		(width 0.0889)
		(layer "In2.Cu")
		(net "M_G_DQ<52>")
	)
	(arc
		(start 114.553492 -55.113936)
		(mid 114.606962 -54.918873)
		(end 114.558318 -54.722522)
		(width 0.0889)
		(layer "In2.Cu")
		(net "M_G_DQ<52>")
	)
	(arc
		(start 114.547142 -54.703218)
		(mid 114.474344 -54.412455)
		(end 114.553492 -54.123336)
		(width 0.0889)
		(layer "In2.Cu")
		(net "M_G_DQ<52>")
	)
	(segment
		(start 141.049502 -15.423642)
		(end 141.049502 -16.687546)
		(width 0.1651)
		(layer "F.Cu")
		(net "M_G_DQ<51>")
	)
	(segment
		(start 119.070882 -57.390538)
		(end 118.499382 -57.390538)
		(width 0.1016)
		(layer "F.Cu")
		(net "M_G_DQ<51>")
	)
	(via
		(at 118.499382 -57.390538)
		(size 0.508)
		(drill 0.254)
		(layers "F.Cu" "B.Cu")
		(net "M_G_DQ<51>")
	)
	(via
		(at 141.899386 -22.279356)
		(size 0.508)
		(drill 0.254)
		(layers "F.Cu" "B.Cu")
		(net "M_G_DQ<51>")
	)
	(via
		(at 141.049502 -16.687546)
		(size 0.508)
		(drill 0.254)
		(layers "F.Cu" "B.Cu")
		(net "M_G_DQ<51>")
	)
	(segment
		(start 141.899386 -22.279356)
		(end 141.899386 -20.224242)
		(width 0.1651)
		(layer "B.Cu")
		(net "M_G_DQ<51>")
	)
	(segment
		(start 142.40764 -18.1102)
		(end 141.95044 -17.653)
		(width 0.14224)
		(layer "In2.Cu")
		(net "M_G_DQ<51>")
	)
	(segment
		(start 142.383764 -28.965144)
		(end 142.383764 -24.216106)
		(width 0.14224)
		(layer "In2.Cu")
		(net "M_G_DQ<51>")
	)
	(segment
		(start 118.946676 -55.002176)
		(end 118.946676 -53.692044)
		(width 0.0889)
		(layer "In2.Cu")
		(net "M_G_DQ<51>")
	)
	(segment
		(start 119.53367 -51.313588)
		(end 119.53367 -50.240184)
		(width 0.0889)
		(layer "In2.Cu")
		(net "M_G_DQ<51>")
	)
	(segment
		(start 118.499382 -57.390538)
		(end 118.93169 -56.802782)
		(width 0.0889)
		(layer "In2.Cu")
		(net "M_G_DQ<51>")
	)
	(segment
		(start 141.95044 -17.653)
		(end 141.69644 -17.653)
		(width 0.14224)
		(layer "In2.Cu")
		(net "M_G_DQ<51>")
	)
	(segment
		(start 142.252192 -18.621248)
		(end 142.40764 -18.4658)
		(width 0.14224)
		(layer "In2.Cu")
		(net "M_G_DQ<51>")
	)
	(segment
		(start 119.53367 -50.240184)
		(end 120.042432 -49.731422)
		(width 0.0889)
		(layer "In2.Cu")
		(net "M_G_DQ<51>")
	)
	(segment
		(start 141.450568 -22.728174)
		(end 141.899386 -22.279356)
		(width 0.14224)
		(layer "In2.Cu")
		(net "M_G_DQ<51>")
	)
	(segment
		(start 141.899386 -22.279356)
		(end 142.252192 -21.92655)
		(width 0.14224)
		(layer "In2.Cu")
		(net "M_G_DQ<51>")
	)
	(segment
		(start 119.112792 -53.525928)
		(end 119.112792 -51.734466)
		(width 0.0889)
		(layer "In2.Cu")
		(net "M_G_DQ<51>")
	)
	(segment
		(start 120.309132 -44.483782)
		(end 125.626114 -39.1668)
		(width 0.14224)
		(layer "In2.Cu")
		(net "M_G_DQ<51>")
	)
	(segment
		(start 141.575536 -33.352232)
		(end 141.575536 -29.773372)
		(width 0.14224)
		(layer "In2.Cu")
		(net "M_G_DQ<51>")
	)
	(segment
		(start 141.450568 -23.28291)
		(end 141.450568 -22.728174)
		(width 0.14224)
		(layer "In2.Cu")
		(net "M_G_DQ<51>")
	)
	(segment
		(start 119.006366 -55.713122)
		(end 119.011192 -55.704486)
		(width 0.0889)
		(layer "In2.Cu")
		(net "M_G_DQ<51>")
	)
	(segment
		(start 125.626114 -39.1668)
		(end 135.760968 -39.1668)
		(width 0.14224)
		(layer "In2.Cu")
		(net "M_G_DQ<51>")
	)
	(segment
		(start 119.011192 -55.113936)
		(end 118.946676 -55.002176)
		(width 0.0889)
		(layer "In2.Cu")
		(net "M_G_DQ<51>")
	)
	(segment
		(start 118.946676 -53.692044)
		(end 119.112792 -53.525928)
		(width 0.0889)
		(layer "In2.Cu")
		(net "M_G_DQ<51>")
	)
	(segment
		(start 120.042432 -49.440084)
		(end 120.309132 -49.173384)
		(width 0.0889)
		(layer "In2.Cu")
		(net "M_G_DQ<51>")
	)
	(segment
		(start 119.011192 -55.704486)
		(end 119.017542 -55.693818)
		(width 0.0889)
		(layer "In2.Cu")
		(net "M_G_DQ<51>")
	)
	(segment
		(start 119.112792 -51.734466)
		(end 119.53367 -51.313588)
		(width 0.0889)
		(layer "In2.Cu")
		(net "M_G_DQ<51>")
	)
	(segment
		(start 142.40764 -18.4658)
		(end 142.40764 -18.1102)
		(width 0.14224)
		(layer "In2.Cu")
		(net "M_G_DQ<51>")
	)
	(segment
		(start 141.049502 -17.006062)
		(end 141.049502 -16.687546)
		(width 0.14224)
		(layer "In2.Cu")
		(net "M_G_DQ<51>")
	)
	(segment
		(start 142.383764 -24.216106)
		(end 141.450568 -23.28291)
		(width 0.14224)
		(layer "In2.Cu")
		(net "M_G_DQ<51>")
	)
	(segment
		(start 141.575536 -29.773372)
		(end 142.383764 -28.965144)
		(width 0.14224)
		(layer "In2.Cu")
		(net "M_G_DQ<51>")
	)
	(segment
		(start 142.252192 -21.92655)
		(end 142.252192 -18.621248)
		(width 0.14224)
		(layer "In2.Cu")
		(net "M_G_DQ<51>")
	)
	(segment
		(start 135.760968 -39.1668)
		(end 141.575536 -33.352232)
		(width 0.14224)
		(layer "In2.Cu")
		(net "M_G_DQ<51>")
	)
	(segment
		(start 120.042432 -49.731422)
		(end 120.042432 -49.440084)
		(width 0.0889)
		(layer "In2.Cu")
		(net "M_G_DQ<51>")
	)
	(segment
		(start 120.309132 -49.173384)
		(end 120.309132 -44.483782)
		(width 0.14224)
		(layer "In2.Cu")
		(net "M_G_DQ<51>")
	)
	(segment
		(start 141.69644 -17.653)
		(end 141.049502 -17.006062)
		(width 0.14224)
		(layer "In2.Cu")
		(net "M_G_DQ<51>")
	)
	(arc
		(start 119.017542 -55.693818)
		(mid 119.09034 -55.403055)
		(end 119.011192 -55.113936)
		(width 0.0889)
		(layer "In2.Cu")
		(net "M_G_DQ<51>")
	)
	(arc
		(start 118.93169 -56.802782)
		(mid 119.0865 -56.466765)
		(end 119.011192 -56.104536)
		(width 0.0889)
		(layer "In2.Cu")
		(net "M_G_DQ<51>")
	)
	(arc
		(start 119.011192 -56.104536)
		(mid 118.957722 -55.909473)
		(end 119.006366 -55.713122)
		(width 0.0889)
		(layer "In2.Cu")
		(net "M_G_DQ<51>")
	)
	(segment
		(start 142.030958 -18.89506)
		(end 142.030958 -18.67154)
		(width 0.1651)
		(layer "F.Cu")
		(net "M_G_DQ<50>")
	)
	(segment
		(start 141.899386 -19.026632)
		(end 142.030958 -18.89506)
		(width 0.1651)
		(layer "F.Cu")
		(net "M_G_DQ<50>")
	)
	(segment
		(start 141.899386 -18.539968)
		(end 141.899386 -18.2626)
		(width 0.1651)
		(layer "F.Cu")
		(net "M_G_DQ<50>")
	)
	(segment
		(start 119.070882 -56.399938)
		(end 118.499382 -56.399938)
		(width 0.1016)
		(layer "F.Cu")
		(net "M_G_DQ<50>")
	)
	(segment
		(start 141.899386 -20.023582)
		(end 141.899386 -19.026632)
		(width 0.1651)
		(layer "F.Cu")
		(net "M_G_DQ<50>")
	)
	(segment
		(start 142.030958 -18.67154)
		(end 141.899386 -18.539968)
		(width 0.1651)
		(layer "F.Cu")
		(net "M_G_DQ<50>")
	)
	(via
		(at 118.499382 -56.399938)
		(size 0.508)
		(drill 0.254)
		(layers "F.Cu" "B.Cu")
		(net "M_G_DQ<50>")
	)
	(via
		(at 141.049502 -23.560278)
		(size 0.508)
		(drill 0.254)
		(layers "F.Cu" "B.Cu")
		(net "M_G_DQ<50>")
	)
	(via
		(at 141.899386 -18.2626)
		(size 0.508)
		(drill 0.254)
		(layers "F.Cu" "B.Cu")
		(net "M_G_DQ<50>")
	)
	(segment
		(start 141.049502 -23.560278)
		(end 141.049502 -24.824182)
		(width 0.1651)
		(layer "B.Cu")
		(net "M_G_DQ<50>")
	)
	(segment
		(start 140.885164 -29.533596)
		(end 141.520164 -28.898596)
		(width 0.14224)
		(layer "In2.Cu")
		(net "M_G_DQ<50>")
	)
	(segment
		(start 141.804136 -26.557224)
		(end 141.804136 -26.049224)
		(width 0.14224)
		(layer "In2.Cu")
		(net "M_G_DQ<50>")
	)
	(segment
		(start 119.661432 -49.173384)
		(end 119.661432 -44.267882)
		(width 0.14224)
		(layer "In2.Cu")
		(net "M_G_DQ<50>")
	)
	(segment
		(start 141.520164 -28.288996)
		(end 141.393164 -28.161996)
		(width 0.14224)
		(layer "In2.Cu")
		(net "M_G_DQ<50>")
	)
	(segment
		(start 125.321314 -38.608)
		(end 135.241792 -38.608)
		(width 0.14224)
		(layer "In2.Cu")
		(net "M_G_DQ<50>")
	)
	(segment
		(start 141.501368 -18.965672)
		(end 141.501368 -18.660618)
		(width 0.14224)
		(layer "In2.Cu")
		(net "M_G_DQ<50>")
	)
	(segment
		(start 118.922292 -53.446934)
		(end 118.922292 -51.655218)
		(width 0.0889)
		(layer "In2.Cu")
		(net "M_G_DQ<50>")
	)
	(segment
		(start 141.613636 -21.4122)
		(end 141.156436 -20.955)
		(width 0.14224)
		(layer "In2.Cu")
		(net "M_G_DQ<50>")
	)
	(segment
		(start 140.32357 -32.698944)
		(end 140.885164 -32.13735)
		(width 0.14224)
		(layer "In2.Cu")
		(net "M_G_DQ<50>")
	)
	(segment
		(start 141.296136 -25.871424)
		(end 141.092936 -25.668224)
		(width 0.14224)
		(layer "In2.Cu")
		(net "M_G_DQ<50>")
	)
	(segment
		(start 141.156436 -20.955)
		(end 141.156436 -20.55495)
		(width 0.14224)
		(layer "In2.Cu")
		(net "M_G_DQ<50>")
	)
	(segment
		(start 141.613636 -21.680932)
		(end 141.613636 -21.4122)
		(width 0.14224)
		(layer "In2.Cu")
		(net "M_G_DQ<50>")
	)
	(segment
		(start 141.049502 -23.560278)
		(end 140.764768 -23.275544)
		(width 0.14224)
		(layer "In2.Cu")
		(net "M_G_DQ<50>")
	)
	(segment
		(start 141.461236 -20.25015)
		(end 141.461236 -19.964146)
		(width 0.14224)
		(layer "In2.Cu")
		(net "M_G_DQ<50>")
	)
	(segment
		(start 141.626336 -25.871424)
		(end 141.296136 -25.871424)
		(width 0.14224)
		(layer "In2.Cu")
		(net "M_G_DQ<50>")
	)
	(segment
		(start 118.846092 -55.609236)
		(end 118.850918 -55.6006)
		(width 0.0889)
		(layer "In2.Cu")
		(net "M_G_DQ<50>")
	)
	(segment
		(start 135.241792 -38.608)
		(end 139.589256 -34.260536)
		(width 0.14224)
		(layer "In2.Cu")
		(net "M_G_DQ<50>")
	)
	(segment
		(start 118.839742 -55.619904)
		(end 118.846092 -55.609236)
		(width 0.0889)
		(layer "In2.Cu")
		(net "M_G_DQ<50>")
	)
	(segment
		(start 141.092936 -25.363424)
		(end 141.245336 -25.211024)
		(width 0.14224)
		(layer "In2.Cu")
		(net "M_G_DQ<50>")
	)
	(segment
		(start 141.049502 -24.389334)
		(end 141.049502 -23.560278)
		(width 0.14224)
		(layer "In2.Cu")
		(net "M_G_DQ<50>")
	)
	(segment
		(start 118.756176 -53.61305)
		(end 118.922292 -53.446934)
		(width 0.0889)
		(layer "In2.Cu")
		(net "M_G_DQ<50>")
	)
	(segment
		(start 139.885928 -33.619186)
		(end 140.087096 -33.619186)
		(width 0.14224)
		(layer "In2.Cu")
		(net "M_G_DQ<50>")
	)
	(segment
		(start 140.087096 -33.619186)
		(end 140.118338 -33.650428)
		(width 0.14224)
		(layer "In2.Cu")
		(net "M_G_DQ<50>")
	)
	(segment
		(start 118.499382 -56.399938)
		(end 118.80088 -55.706518)
		(width 0.0889)
		(layer "In2.Cu")
		(net "M_G_DQ<50>")
	)
	(segment
		(start 141.156436 -20.55495)
		(end 141.461236 -20.25015)
		(width 0.14224)
		(layer "In2.Cu")
		(net "M_G_DQ<50>")
	)
	(segment
		(start 119.34317 -50.160936)
		(end 119.851932 -49.652174)
		(width 0.0889)
		(layer "In2.Cu")
		(net "M_G_DQ<50>")
	)
	(segment
		(start 139.589256 -33.915858)
		(end 139.885928 -33.619186)
		(width 0.14224)
		(layer "In2.Cu")
		(net "M_G_DQ<50>")
	)
	(segment
		(start 140.118338 -33.650428)
		(end 140.337032 -33.650428)
		(width 0.14224)
		(layer "In2.Cu")
		(net "M_G_DQ<50>")
	)
	(segment
		(start 141.092936 -25.668224)
		(end 141.092936 -25.363424)
		(width 0.14224)
		(layer "In2.Cu")
		(net "M_G_DQ<50>")
	)
	(segment
		(start 118.846092 -55.209186)
		(end 118.756176 -55.05323)
		(width 0.0889)
		(layer "In2.Cu")
		(net "M_G_DQ<50>")
	)
	(segment
		(start 141.804136 -25.007824)
		(end 141.804136 -24.779224)
		(width 0.14224)
		(layer "In2.Cu")
		(net "M_G_DQ<50>")
	)
	(segment
		(start 141.501368 -18.660618)
		(end 141.899386 -18.2626)
		(width 0.14224)
		(layer "In2.Cu")
		(net "M_G_DQ<50>")
	)
	(segment
		(start 141.520164 -28.898596)
		(end 141.520164 -28.288996)
		(width 0.14224)
		(layer "In2.Cu")
		(net "M_G_DQ<50>")
	)
	(segment
		(start 141.156436 -19.310604)
		(end 141.501368 -18.965672)
		(width 0.14224)
		(layer "In2.Cu")
		(net "M_G_DQ<50>")
	)
	(segment
		(start 119.34317 -51.23434)
		(end 119.34317 -50.160936)
		(width 0.0889)
		(layer "In2.Cu")
		(net "M_G_DQ<50>")
	)
	(segment
		(start 119.851932 -49.363884)
		(end 119.661432 -49.173384)
		(width 0.0889)
		(layer "In2.Cu")
		(net "M_G_DQ<50>")
	)
	(segment
		(start 141.156436 -19.659346)
		(end 141.156436 -19.310604)
		(width 0.14224)
		(layer "In2.Cu")
		(net "M_G_DQ<50>")
	)
	(segment
		(start 141.159992 -24.499824)
		(end 141.049502 -24.389334)
		(width 0.14224)
		(layer "In2.Cu")
		(net "M_G_DQ<50>")
	)
	(segment
		(start 140.764768 -23.275544)
		(end 140.764768 -22.5298)
		(width 0.14224)
		(layer "In2.Cu")
		(net "M_G_DQ<50>")
	)
	(segment
		(start 140.586968 -33.400492)
		(end 140.586968 -33.181544)
		(width 0.14224)
		(layer "In2.Cu")
		(net "M_G_DQ<50>")
	)
	(segment
		(start 118.922292 -51.655218)
		(end 119.34317 -51.23434)
		(width 0.0889)
		(layer "In2.Cu")
		(net "M_G_DQ<50>")
	)
	(segment
		(start 141.804136 -24.779224)
		(end 141.524736 -24.499824)
		(width 0.14224)
		(layer "In2.Cu")
		(net "M_G_DQ<50>")
	)
	(segment
		(start 141.600936 -25.211024)
		(end 141.804136 -25.007824)
		(width 0.14224)
		(layer "In2.Cu")
		(net "M_G_DQ<50>")
	)
	(segment
		(start 141.245336 -25.211024)
		(end 141.600936 -25.211024)
		(width 0.14224)
		(layer "In2.Cu")
		(net "M_G_DQ<50>")
	)
	(segment
		(start 141.393164 -26.968196)
		(end 141.804136 -26.557224)
		(width 0.14224)
		(layer "In2.Cu")
		(net "M_G_DQ<50>")
	)
	(segment
		(start 141.804136 -26.049224)
		(end 141.626336 -25.871424)
		(width 0.14224)
		(layer "In2.Cu")
		(net "M_G_DQ<50>")
	)
	(segment
		(start 141.461236 -19.964146)
		(end 141.156436 -19.659346)
		(width 0.14224)
		(layer "In2.Cu")
		(net "M_G_DQ<50>")
	)
	(segment
		(start 141.524736 -24.499824)
		(end 141.159992 -24.499824)
		(width 0.14224)
		(layer "In2.Cu")
		(net "M_G_DQ<50>")
	)
	(segment
		(start 119.661432 -44.267882)
		(end 125.321314 -38.608)
		(width 0.14224)
		(layer "In2.Cu")
		(net "M_G_DQ<50>")
	)
	(segment
		(start 119.851932 -49.652174)
		(end 119.851932 -49.363884)
		(width 0.0889)
		(layer "In2.Cu")
		(net "M_G_DQ<50>")
	)
	(segment
		(start 140.32357 -32.917892)
		(end 140.32357 -32.698944)
		(width 0.14224)
		(layer "In2.Cu")
		(net "M_G_DQ<50>")
	)
	(segment
		(start 118.756176 -55.05323)
		(end 118.756176 -53.61305)
		(width 0.0889)
		(layer "In2.Cu")
		(net "M_G_DQ<50>")
	)
	(segment
		(start 140.586968 -33.181544)
		(end 140.32357 -32.917892)
		(width 0.14224)
		(layer "In2.Cu")
		(net "M_G_DQ<50>")
	)
	(segment
		(start 140.337032 -33.650428)
		(end 140.586968 -33.400492)
		(width 0.14224)
		(layer "In2.Cu")
		(net "M_G_DQ<50>")
	)
	(segment
		(start 139.589256 -34.260536)
		(end 139.589256 -33.915858)
		(width 0.14224)
		(layer "In2.Cu")
		(net "M_G_DQ<50>")
	)
	(segment
		(start 141.393164 -28.161996)
		(end 141.393164 -26.968196)
		(width 0.14224)
		(layer "In2.Cu")
		(net "M_G_DQ<50>")
	)
	(segment
		(start 140.764768 -22.5298)
		(end 141.613636 -21.680932)
		(width 0.14224)
		(layer "In2.Cu")
		(net "M_G_DQ<50>")
	)
	(segment
		(start 140.885164 -32.13735)
		(end 140.885164 -29.533596)
		(width 0.14224)
		(layer "In2.Cu")
		(net "M_G_DQ<50>")
	)
	(arc
		(start 118.850918 -55.6006)
		(mid 118.899673 -55.404248)
		(end 118.846092 -55.209186)
		(width 0.0889)
		(layer "In2.Cu")
		(net "M_G_DQ<50>")
	)
	(arc
		(start 118.80088 -55.706518)
		(mid 118.818567 -55.662428)
		(end 118.839742 -55.619904)
		(width 0.0889)
		(layer "In2.Cu")
		(net "M_G_DQ<50>")
	)
	(segment
		(start 67.749166 -66.48704)
		(end 67.101466 -66.48704)
		(width 0.1016)
		(layer "F.Cu")
		(net "M_G_DQ<4>")
	)
	(segment
		(start 32.249364 -20.023582)
		(end 32.249364 -18.692368)
		(width 0.1651)
		(layer "F.Cu")
		(net "M_G_DQ<4>")
	)
	(segment
		(start 32.249364 -18.692368)
		(end 32.15132 -18.161)
		(width 0.1651)
		(layer "F.Cu")
		(net "M_G_DQ<4>")
	)
	(via
		(at 67.101466 -66.48704)
		(size 0.508)
		(drill 0.254)
		(layers "F.Cu" "B.Cu")
		(net "M_G_DQ<4>")
	)
	(via
		(at 32.15132 -18.161)
		(size 0.508)
		(drill 0.254)
		(layers "F.Cu" "B.Cu")
		(net "M_G_DQ<4>")
	)
	(via
		(at 31.39948 -23.560278)
		(size 0.508)
		(drill 0.254)
		(layers "F.Cu" "B.Cu")
		(net "M_G_DQ<4>")
	)
	(segment
		(start 31.39948 -23.560278)
		(end 31.39948 -24.824182)
		(width 0.1651)
		(layer "B.Cu")
		(net "M_G_DQ<4>")
	)
	(segment
		(start 31.523686 -20.992846)
		(end 31.874968 -21.344128)
		(width 0.14224)
		(layer "In2.Cu")
		(net "M_G_DQ<4>")
	)
	(segment
		(start 31.347664 -34.138616)
		(end 31.205424 -34.280856)
		(width 0.14224)
		(layer "In2.Cu")
		(net "M_G_DQ<4>")
	)
	(segment
		(start 31.163768 -23.324566)
		(end 31.39948 -23.560278)
		(width 0.14224)
		(layer "In2.Cu")
		(net "M_G_DQ<4>")
	)
	(segment
		(start 31.783528 -33.488376)
		(end 31.925768 -33.630616)
		(width 0.14224)
		(layer "In2.Cu")
		(net "M_G_DQ<4>")
	)
	(segment
		(start 31.874968 -18.914872)
		(end 31.510986 -19.278854)
		(width 0.14224)
		(layer "In2.Cu")
		(net "M_G_DQ<4>")
	)
	(segment
		(start 65.504568 -67.402202)
		(end 66.186304 -67.402202)
		(width 0.0889)
		(layer "In2.Cu")
		(net "M_G_DQ<4>")
	)
	(segment
		(start 31.205424 -36.094416)
		(end 62.51321 -67.402202)
		(width 0.14224)
		(layer "In2.Cu")
		(net "M_G_DQ<4>")
	)
	(segment
		(start 32.15132 -18.161)
		(end 31.874968 -18.437352)
		(width 0.14224)
		(layer "In2.Cu")
		(net "M_G_DQ<4>")
	)
	(segment
		(start 31.205424 -23.754334)
		(end 31.205424 -33.346136)
		(width 0.14224)
		(layer "In2.Cu")
		(net "M_G_DQ<4>")
	)
	(segment
		(start 31.39948 -23.560278)
		(end 31.205424 -23.754334)
		(width 0.14224)
		(layer "In2.Cu")
		(net "M_G_DQ<4>")
	)
	(segment
		(start 31.874968 -21.818854)
		(end 31.163768 -22.530054)
		(width 0.14224)
		(layer "In2.Cu")
		(net "M_G_DQ<4>")
	)
	(segment
		(start 31.163768 -22.530054)
		(end 31.163768 -23.324566)
		(width 0.14224)
		(layer "In2.Cu")
		(net "M_G_DQ<4>")
	)
	(segment
		(start 31.205424 -34.280856)
		(end 31.205424 -36.094416)
		(width 0.14224)
		(layer "In2.Cu")
		(net "M_G_DQ<4>")
	)
	(segment
		(start 31.347664 -33.488376)
		(end 31.783528 -33.488376)
		(width 0.14224)
		(layer "In2.Cu")
		(net "M_G_DQ<4>")
	)
	(segment
		(start 62.51321 -67.402202)
		(end 65.504568 -67.402202)
		(width 0.14224)
		(layer "In2.Cu")
		(net "M_G_DQ<4>")
	)
	(segment
		(start 66.186304 -67.402202)
		(end 67.101466 -66.48704)
		(width 0.0889)
		(layer "In2.Cu")
		(net "M_G_DQ<4>")
	)
	(segment
		(start 31.891986 -20.2692)
		(end 31.523686 -20.6375)
		(width 0.14224)
		(layer "In2.Cu")
		(net "M_G_DQ<4>")
	)
	(segment
		(start 31.783528 -34.138616)
		(end 31.347664 -34.138616)
		(width 0.14224)
		(layer "In2.Cu")
		(net "M_G_DQ<4>")
	)
	(segment
		(start 31.925768 -33.630616)
		(end 31.925768 -33.996376)
		(width 0.14224)
		(layer "In2.Cu")
		(net "M_G_DQ<4>")
	)
	(segment
		(start 31.510986 -19.278854)
		(end 31.510986 -19.5834)
		(width 0.14224)
		(layer "In2.Cu")
		(net "M_G_DQ<4>")
	)
	(segment
		(start 31.874968 -21.344128)
		(end 31.874968 -21.818854)
		(width 0.14224)
		(layer "In2.Cu")
		(net "M_G_DQ<4>")
	)
	(segment
		(start 31.891986 -19.9644)
		(end 31.891986 -20.2692)
		(width 0.14224)
		(layer "In2.Cu")
		(net "M_G_DQ<4>")
	)
	(segment
		(start 31.925768 -33.996376)
		(end 31.783528 -34.138616)
		(width 0.14224)
		(layer "In2.Cu")
		(net "M_G_DQ<4>")
	)
	(segment
		(start 31.874968 -18.437352)
		(end 31.874968 -18.914872)
		(width 0.14224)
		(layer "In2.Cu")
		(net "M_G_DQ<4>")
	)
	(segment
		(start 31.523686 -20.6375)
		(end 31.523686 -20.992846)
		(width 0.14224)
		(layer "In2.Cu")
		(net "M_G_DQ<4>")
	)
	(segment
		(start 31.205424 -33.346136)
		(end 31.347664 -33.488376)
		(width 0.14224)
		(layer "In2.Cu")
		(net "M_G_DQ<4>")
	)
	(segment
		(start 31.510986 -19.5834)
		(end 31.891986 -19.9644)
		(width 0.14224)
		(layer "In2.Cu")
		(net "M_G_DQ<4>")
	)
	(segment
		(start 135.099552 -15.423642)
		(end 135.099552 -16.687546)
		(width 0.1651)
		(layer "F.Cu")
		(net "M_G_DQ<49>")
	)
	(segment
		(start 116.495322 -57.885584)
		(end 115.923822 -57.885584)
		(width 0.1016)
		(layer "F.Cu")
		(net "M_G_DQ<49>")
	)
	(via
		(at 135.771636 -22.279356)
		(size 0.508)
		(drill 0.254)
		(layers "F.Cu" "B.Cu")
		(net "M_G_DQ<49>")
	)
	(via
		(at 115.923822 -57.885584)
		(size 0.508)
		(drill 0.254)
		(layers "F.Cu" "B.Cu")
		(net "M_G_DQ<49>")
	)
	(via
		(at 135.099552 -16.687546)
		(size 0.508)
		(drill 0.254)
		(layers "F.Cu" "B.Cu")
		(net "M_G_DQ<49>")
	)
	(segment
		(start 135.949436 -21.598382)
		(end 135.771636 -21.776182)
		(width 0.1651)
		(layer "B.Cu")
		(net "M_G_DQ<49>")
	)
	(segment
		(start 135.771636 -21.776182)
		(end 135.771636 -22.279356)
		(width 0.1651)
		(layer "B.Cu")
		(net "M_G_DQ<49>")
	)
	(segment
		(start 135.949436 -20.224242)
		(end 135.949436 -21.598382)
		(width 0.1651)
		(layer "B.Cu")
		(net "M_G_DQ<49>")
	)
	(segment
		(start 116.044472 -56.330596)
		(end 115.687602 -56.571896)
		(width 0.0889)
		(layer "In2.Cu")
		(net "M_G_DQ<49>")
	)
	(segment
		(start 129.944368 -35.0266)
		(end 130.452368 -35.0266)
		(width 0.14224)
		(layer "In2.Cu")
		(net "M_G_DQ<49>")
	)
	(segment
		(start 115.575588 -53.68798)
		(end 115.575588 -51.735482)
		(width 0.0889)
		(layer "In2.Cu")
		(net "M_G_DQ<49>")
	)
	(segment
		(start 116.228368 -56.177688)
		(end 116.270532 -56.104536)
		(width 0.0889)
		(layer "In2.Cu")
		(net "M_G_DQ<49>")
	)
	(segment
		(start 115.277392 -48.248824)
		(end 115.536472 -47.989744)
		(width 0.0889)
		(layer "In2.Cu")
		(net "M_G_DQ<49>")
	)
	(segment
		(start 115.575588 -51.735482)
		(end 115.352576 -51.51247)
		(width 0.0889)
		(layer "In2.Cu")
		(net "M_G_DQ<49>")
	)
	(segment
		(start 129.639568 -34.7218)
		(end 129.944368 -35.0266)
		(width 0.14224)
		(layer "In2.Cu")
		(net "M_G_DQ<49>")
	)
	(segment
		(start 115.593876 -57.123838)
		(end 115.923822 -57.885584)
		(width 0.0889)
		(layer "In2.Cu")
		(net "M_G_DQ<49>")
	)
	(segment
		(start 128.242568 -34.7218)
		(end 129.639568 -34.7218)
		(width 0.14224)
		(layer "In2.Cu")
		(net "M_G_DQ<49>")
	)
	(segment
		(start 116.228368 -56.177688)
		(end 116.044472 -56.330596)
		(width 0.0889)
		(layer "In2.Cu")
		(net "M_G_DQ<49>")
	)
	(segment
		(start 135.271764 -22.779228)
		(end 135.771636 -22.279356)
		(width 0.14224)
		(layer "In2.Cu")
		(net "M_G_DQ<49>")
	)
	(segment
		(start 115.577112 -57.095136)
		(end 115.593876 -57.123838)
		(width 0.0889)
		(layer "In2.Cu")
		(net "M_G_DQ<49>")
	)
	(segment
		(start 115.352576 -51.51247)
		(end 115.352576 -50.842418)
		(width 0.0889)
		(layer "In2.Cu")
		(net "M_G_DQ<49>")
	)
	(segment
		(start 115.577112 -54.713886)
		(end 115.583462 -54.703218)
		(width 0.0889)
		(layer "In2.Cu")
		(net "M_G_DQ<49>")
	)
	(segment
		(start 135.099552 -17.226534)
		(end 135.099552 -16.687546)
		(width 0.14224)
		(layer "In2.Cu")
		(net "M_G_DQ<49>")
	)
	(segment
		(start 136.302242 -18.415)
		(end 136.302242 -18.073624)
		(width 0.14224)
		(layer "In2.Cu")
		(net "M_G_DQ<49>")
	)
	(segment
		(start 130.452368 -35.0266)
		(end 136.262364 -29.216604)
		(width 0.14224)
		(layer "In2.Cu")
		(net "M_G_DQ<49>")
	)
	(segment
		(start 135.576818 -17.7038)
		(end 135.099552 -17.226534)
		(width 0.14224)
		(layer "In2.Cu")
		(net "M_G_DQ<49>")
	)
	(segment
		(start 116.208556 -55.597298)
		(end 115.713002 -55.254144)
		(width 0.0889)
		(layer "In2.Cu")
		(net "M_G_DQ<49>")
	)
	(segment
		(start 116.275358 -55.713122)
		(end 116.208556 -55.597298)
		(width 0.0889)
		(layer "In2.Cu")
		(net "M_G_DQ<49>")
	)
	(segment
		(start 115.572286 -54.722522)
		(end 115.577112 -54.713886)
		(width 0.0889)
		(layer "In2.Cu")
		(net "M_G_DQ<49>")
	)
	(segment
		(start 136.262364 -29.216604)
		(end 136.262364 -26.095452)
		(width 0.14224)
		(layer "In2.Cu")
		(net "M_G_DQ<49>")
	)
	(segment
		(start 127.937768 -35.0266)
		(end 128.242568 -34.7218)
		(width 0.14224)
		(layer "In2.Cu")
		(net "M_G_DQ<49>")
	)
	(segment
		(start 123.391168 -35.0266)
		(end 127.937768 -35.0266)
		(width 0.14224)
		(layer "In2.Cu")
		(net "M_G_DQ<49>")
	)
	(segment
		(start 115.277392 -49.939194)
		(end 115.277392 -48.248824)
		(width 0.0889)
		(layer "In2.Cu")
		(net "M_G_DQ<49>")
	)
	(segment
		(start 115.20297 -50.692812)
		(end 115.20297 -50.013616)
		(width 0.0889)
		(layer "In2.Cu")
		(net "M_G_DQ<49>")
	)
	(segment
		(start 115.523518 -53.923184)
		(end 115.523518 -53.74005)
		(width 0.0889)
		(layer "In2.Cu")
		(net "M_G_DQ<49>")
	)
	(segment
		(start 115.523518 -53.74005)
		(end 115.575588 -53.68798)
		(width 0.0889)
		(layer "In2.Cu")
		(net "M_G_DQ<49>")
	)
	(segment
		(start 115.20297 -50.013616)
		(end 115.277392 -49.939194)
		(width 0.0889)
		(layer "In2.Cu")
		(net "M_G_DQ<49>")
	)
	(segment
		(start 136.262364 -26.095452)
		(end 135.652764 -25.485852)
		(width 0.14224)
		(layer "In2.Cu")
		(net "M_G_DQ<49>")
	)
	(segment
		(start 135.932418 -17.7038)
		(end 135.576818 -17.7038)
		(width 0.14224)
		(layer "In2.Cu")
		(net "M_G_DQ<49>")
	)
	(segment
		(start 136.145778 -18.571464)
		(end 136.302242 -18.415)
		(width 0.14224)
		(layer "In2.Cu")
		(net "M_G_DQ<49>")
	)
	(segment
		(start 135.652764 -23.488396)
		(end 135.271764 -23.107396)
		(width 0.14224)
		(layer "In2.Cu")
		(net "M_G_DQ<49>")
	)
	(segment
		(start 115.536472 -47.989744)
		(end 115.536472 -42.881296)
		(width 0.14224)
		(layer "In2.Cu")
		(net "M_G_DQ<49>")
	)
	(segment
		(start 135.271764 -23.107396)
		(end 135.271764 -22.779228)
		(width 0.14224)
		(layer "In2.Cu")
		(net "M_G_DQ<49>")
	)
	(segment
		(start 136.145778 -21.905214)
		(end 136.145778 -18.571464)
		(width 0.14224)
		(layer "In2.Cu")
		(net "M_G_DQ<49>")
	)
	(segment
		(start 135.771636 -22.279356)
		(end 136.145778 -21.905214)
		(width 0.14224)
		(layer "In2.Cu")
		(net "M_G_DQ<49>")
	)
	(segment
		(start 115.536472 -42.881296)
		(end 123.391168 -35.0266)
		(width 0.14224)
		(layer "In2.Cu")
		(net "M_G_DQ<49>")
	)
	(segment
		(start 136.302242 -18.073624)
		(end 135.932418 -17.7038)
		(width 0.14224)
		(layer "In2.Cu")
		(net "M_G_DQ<49>")
	)
	(segment
		(start 115.352576 -50.842418)
		(end 115.20297 -50.692812)
		(width 0.0889)
		(layer "In2.Cu")
		(net "M_G_DQ<49>")
	)
	(segment
		(start 135.652764 -25.485852)
		(end 135.652764 -23.488396)
		(width 0.14224)
		(layer "In2.Cu")
		(net "M_G_DQ<49>")
	)
	(arc
		(start 115.713002 -55.254144)
		(mid 115.53681 -55.016313)
		(end 115.572286 -54.722522)
		(width 0.0889)
		(layer "In2.Cu")
		(net "M_G_DQ<49>")
	)
	(arc
		(start 115.577112 -54.123336)
		(mid 115.537125 -54.02679)
		(end 115.523518 -53.923184)
		(width 0.0889)
		(layer "In2.Cu")
		(net "M_G_DQ<49>")
	)
	(arc
		(start 115.583462 -54.703218)
		(mid 115.65626 -54.412455)
		(end 115.577112 -54.123336)
		(width 0.0889)
		(layer "In2.Cu")
		(net "M_G_DQ<49>")
	)
	(arc
		(start 116.270532 -56.104536)
		(mid 116.324002 -55.909473)
		(end 116.275358 -55.713122)
		(width 0.0889)
		(layer "In2.Cu")
		(net "M_G_DQ<49>")
	)
	(arc
		(start 115.687602 -56.571896)
		(mid 115.532214 -56.812349)
		(end 115.577112 -57.095136)
		(width 0.0889)
		(layer "In2.Cu")
		(net "M_G_DQ<49>")
	)
	(segment
		(start 135.949436 -20.023582)
		(end 135.868664 -19.177)
		(width 0.1651)
		(layer "F.Cu")
		(net "M_G_DQ<48>")
	)
	(segment
		(start 135.868664 -19.177)
		(end 135.771636 -18.161)
		(width 0.1651)
		(layer "F.Cu")
		(net "M_G_DQ<48>")
	)
	(segment
		(start 116.495322 -55.904384)
		(end 115.923822 -55.904384)
		(width 0.1016)
		(layer "F.Cu")
		(net "M_G_DQ<48>")
	)
	(via
		(at 135.771636 -18.161)
		(size 0.508)
		(drill 0.254)
		(layers "F.Cu" "B.Cu")
		(net "M_G_DQ<48>")
	)
	(via
		(at 115.923822 -55.904384)
		(size 0.508)
		(drill 0.254)
		(layers "F.Cu" "B.Cu")
		(net "M_G_DQ<48>")
	)
	(via
		(at 135.099552 -23.560278)
		(size 0.508)
		(drill 0.254)
		(layers "F.Cu" "B.Cu")
		(net "M_G_DQ<48>")
	)
	(segment
		(start 135.099552 -23.560278)
		(end 135.099552 -24.824182)
		(width 0.1651)
		(layer "B.Cu")
		(net "M_G_DQ<48>")
	)
	(segment
		(start 118.764558 -37.899086)
		(end 118.764558 -37.697664)
		(width 0.14224)
		(layer "In2.Cu")
		(net "M_G_DQ<48>")
	)
	(segment
		(start 119.03202 -37.430202)
		(end 119.233442 -37.430202)
		(width 0.14224)
		(layer "In2.Cu")
		(net "M_G_DQ<48>")
	)
	(segment
		(start 115.947444 -40.708326)
		(end 115.947444 -40.489378)
		(width 0.14224)
		(layer "In2.Cu")
		(net "M_G_DQ<48>")
	)
	(segment
		(start 123.16206 -34.1884)
		(end 130.426968 -34.1884)
		(width 0.14224)
		(layer "In2.Cu")
		(net "M_G_DQ<48>")
	)
	(segment
		(start 117.122956 -40.227504)
		(end 117.122956 -40.008556)
		(width 0.14224)
		(layer "In2.Cu")
		(net "M_G_DQ<48>")
	)
	(segment
		(start 135.136636 -19.380454)
		(end 135.551418 -18.965672)
		(width 0.14224)
		(layer "In2.Cu")
		(net "M_G_DQ<48>")
	)
	(segment
		(start 135.479536 -20.2819)
		(end 135.479536 -20.0533)
		(width 0.14224)
		(layer "In2.Cu")
		(net "M_G_DQ<48>")
	)
	(segment
		(start 114.888772 -47.989744)
		(end 114.888772 -41.54805)
		(width 0.14224)
		(layer "In2.Cu")
		(net "M_G_DQ<48>")
	)
	(segment
		(start 115.385088 -53.608478)
		(end 115.385088 -51.814476)
		(width 0.0889)
		(layer "In2.Cu")
		(net "M_G_DQ<48>")
	)
	(segment
		(start 135.583168 -28.3718)
		(end 135.271764 -28.060396)
		(width 0.14224)
		(layer "In2.Cu")
		(net "M_G_DQ<48>")
	)
	(segment
		(start 115.259612 -41.17721)
		(end 115.47856 -41.17721)
		(width 0.14224)
		(layer "In2.Cu")
		(net "M_G_DQ<48>")
	)
	(segment
		(start 135.551418 -21.7932)
		(end 135.551418 -21.293328)
		(width 0.14224)
		(layer "In2.Cu")
		(net "M_G_DQ<48>")
	)
	(segment
		(start 135.162036 -20.5994)
		(end 135.479536 -20.2819)
		(width 0.14224)
		(layer "In2.Cu")
		(net "M_G_DQ<48>")
	)
	(segment
		(start 135.479536 -20.0533)
		(end 135.136636 -19.7104)
		(width 0.14224)
		(layer "In2.Cu")
		(net "M_G_DQ<48>")
	)
	(segment
		(start 116.885212 -39.55161)
		(end 117.135148 -39.301674)
		(width 0.14224)
		(layer "In2.Cu")
		(net "M_G_DQ<48>")
	)
	(segment
		(start 118.291864 -38.363906)
		(end 118.529608 -38.601904)
		(width 0.14224)
		(layer "In2.Cu")
		(net "M_G_DQ<48>")
	)
	(segment
		(start 135.099552 -23.560278)
		(end 134.814818 -23.275544)
		(width 0.14224)
		(layer "In2.Cu")
		(net "M_G_DQ<48>")
	)
	(segment
		(start 117.82298 -38.83279)
		(end 117.82298 -38.613842)
		(width 0.14224)
		(layer "In2.Cu")
		(net "M_G_DQ<48>")
	)
	(segment
		(start 115.01247 -50.77206)
		(end 115.01247 -49.934368)
		(width 0.0889)
		(layer "In2.Cu")
		(net "M_G_DQ<48>")
	)
	(segment
		(start 134.814818 -23.275544)
		(end 134.814818 -22.5298)
		(width 0.14224)
		(layer "In2.Cu")
		(net "M_G_DQ<48>")
	)
	(segment
		(start 115.162076 -50.921666)
		(end 115.01247 -50.77206)
		(width 0.0889)
		(layer "In2.Cu")
		(net "M_G_DQ<48>")
	)
	(segment
		(start 119.467376 -37.664136)
		(end 119.686324 -37.664136)
		(width 0.14224)
		(layer "In2.Cu")
		(net "M_G_DQ<48>")
	)
	(segment
		(start 116.885212 -39.770558)
		(end 116.885212 -39.55161)
		(width 0.14224)
		(layer "In2.Cu")
		(net "M_G_DQ<48>")
	)
	(segment
		(start 119.686324 -37.664136)
		(end 123.16206 -34.1884)
		(width 0.14224)
		(layer "In2.Cu")
		(net "M_G_DQ<48>")
	)
	(segment
		(start 118.529608 -38.601904)
		(end 118.748556 -38.601904)
		(width 0.14224)
		(layer "In2.Cu")
		(net "M_G_DQ<48>")
	)
	(segment
		(start 116.654072 -40.47744)
		(end 116.87302 -40.47744)
		(width 0.14224)
		(layer "In2.Cu")
		(net "M_G_DQ<48>")
	)
	(segment
		(start 116.19738 -40.239442)
		(end 116.416328 -40.239442)
		(width 0.14224)
		(layer "In2.Cu")
		(net "M_G_DQ<48>")
	)
	(segment
		(start 135.099552 -25.79624)
		(end 135.099552 -23.560278)
		(width 0.14224)
		(layer "In2.Cu")
		(net "M_G_DQ<48>")
	)
	(segment
		(start 119.233442 -37.430202)
		(end 119.467376 -37.664136)
		(width 0.14224)
		(layer "In2.Cu")
		(net "M_G_DQ<48>")
	)
	(segment
		(start 115.47856 -41.17721)
		(end 115.716304 -41.415208)
		(width 0.14224)
		(layer "In2.Cu")
		(net "M_G_DQ<48>")
	)
	(segment
		(start 135.162036 -20.903946)
		(end 135.162036 -20.5994)
		(width 0.14224)
		(layer "In2.Cu")
		(net "M_G_DQ<48>")
	)
	(segment
		(start 117.122956 -40.008556)
		(end 116.885212 -39.770558)
		(width 0.14224)
		(layer "In2.Cu")
		(net "M_G_DQ<48>")
	)
	(segment
		(start 115.412012 -54.618636)
		(end 115.416838 -54.61)
		(width 0.0889)
		(layer "In2.Cu")
		(net "M_G_DQ<48>")
	)
	(segment
		(start 116.185188 -41.165272)
		(end 116.185188 -40.946324)
		(width 0.14224)
		(layer "In2.Cu")
		(net "M_G_DQ<48>")
	)
	(segment
		(start 117.59184 -39.539672)
		(end 117.810788 -39.539672)
		(width 0.14224)
		(layer "In2.Cu")
		(net "M_G_DQ<48>")
	)
	(segment
		(start 118.998492 -38.13302)
		(end 118.764558 -37.899086)
		(width 0.14224)
		(layer "In2.Cu")
		(net "M_G_DQ<48>")
	)
	(segment
		(start 118.764558 -37.697664)
		(end 119.03202 -37.430202)
		(width 0.14224)
		(layer "In2.Cu")
		(net "M_G_DQ<48>")
	)
	(segment
		(start 135.136636 -19.7104)
		(end 135.136636 -19.380454)
		(width 0.14224)
		(layer "In2.Cu")
		(net "M_G_DQ<48>")
	)
	(segment
		(start 117.354096 -39.301674)
		(end 117.59184 -39.539672)
		(width 0.14224)
		(layer "In2.Cu")
		(net "M_G_DQ<48>")
	)
	(segment
		(start 117.135148 -39.301674)
		(end 117.354096 -39.301674)
		(width 0.14224)
		(layer "In2.Cu")
		(net "M_G_DQ<48>")
	)
	(segment
		(start 114.888772 -41.54805)
		(end 115.259612 -41.17721)
		(width 0.14224)
		(layer "In2.Cu")
		(net "M_G_DQ<48>")
	)
	(segment
		(start 115.923822 -55.904384)
		(end 115.428776 -55.23865)
		(width 0.0889)
		(layer "In2.Cu")
		(net "M_G_DQ<48>")
	)
	(segment
		(start 118.748556 -38.601904)
		(end 118.998492 -38.351968)
		(width 0.14224)
		(layer "In2.Cu")
		(net "M_G_DQ<48>")
	)
	(segment
		(start 118.060724 -39.070788)
		(end 117.82298 -38.83279)
		(width 0.14224)
		(layer "In2.Cu")
		(net "M_G_DQ<48>")
	)
	(segment
		(start 115.162076 -51.591464)
		(end 115.162076 -50.921666)
		(width 0.0889)
		(layer "In2.Cu")
		(net "M_G_DQ<48>")
	)
	(segment
		(start 115.332764 -53.660802)
		(end 115.385088 -53.608478)
		(width 0.0889)
		(layer "In2.Cu")
		(net "M_G_DQ<48>")
	)
	(segment
		(start 117.810788 -39.539672)
		(end 118.060724 -39.289736)
		(width 0.14224)
		(layer "In2.Cu")
		(net "M_G_DQ<48>")
	)
	(segment
		(start 135.551418 -18.381218)
		(end 135.771636 -18.161)
		(width 0.14224)
		(layer "In2.Cu")
		(net "M_G_DQ<48>")
	)
	(segment
		(start 115.086892 -48.187864)
		(end 114.888772 -47.989744)
		(width 0.0889)
		(layer "In2.Cu")
		(net "M_G_DQ<48>")
	)
	(segment
		(start 118.072916 -38.363906)
		(end 118.291864 -38.363906)
		(width 0.14224)
		(layer "In2.Cu")
		(net "M_G_DQ<48>")
	)
	(segment
		(start 115.405662 -54.629304)
		(end 115.412012 -54.618636)
		(width 0.0889)
		(layer "In2.Cu")
		(net "M_G_DQ<48>")
	)
	(segment
		(start 115.428776 -55.23865)
		(end 115.412012 -55.209186)
		(width 0.0889)
		(layer "In2.Cu")
		(net "M_G_DQ<48>")
	)
	(segment
		(start 116.416328 -40.239442)
		(end 116.654072 -40.47744)
		(width 0.14224)
		(layer "In2.Cu")
		(net "M_G_DQ<48>")
	)
	(segment
		(start 117.82298 -38.613842)
		(end 118.072916 -38.363906)
		(width 0.14224)
		(layer "In2.Cu")
		(net "M_G_DQ<48>")
	)
	(segment
		(start 115.935252 -41.415208)
		(end 116.185188 -41.165272)
		(width 0.14224)
		(layer "In2.Cu")
		(net "M_G_DQ<48>")
	)
	(segment
		(start 135.271764 -26.942796)
		(end 135.525764 -26.688796)
		(width 0.14224)
		(layer "In2.Cu")
		(net "M_G_DQ<48>")
	)
	(segment
		(start 118.060724 -39.289736)
		(end 118.060724 -39.070788)
		(width 0.14224)
		(layer "In2.Cu")
		(net "M_G_DQ<48>")
	)
	(segment
		(start 115.947444 -40.489378)
		(end 116.19738 -40.239442)
		(width 0.14224)
		(layer "In2.Cu")
		(net "M_G_DQ<48>")
	)
	(segment
		(start 135.525764 -26.222452)
		(end 135.099552 -25.79624)
		(width 0.14224)
		(layer "In2.Cu")
		(net "M_G_DQ<48>")
	)
	(segment
		(start 115.086892 -49.859946)
		(end 115.086892 -48.187864)
		(width 0.0889)
		(layer "In2.Cu")
		(net "M_G_DQ<48>")
	)
	(segment
		(start 115.385088 -51.814476)
		(end 115.162076 -51.591464)
		(width 0.0889)
		(layer "In2.Cu")
		(net "M_G_DQ<48>")
	)
	(segment
		(start 134.814818 -22.5298)
		(end 135.551418 -21.7932)
		(width 0.14224)
		(layer "In2.Cu")
		(net "M_G_DQ<48>")
	)
	(segment
		(start 135.551418 -21.293328)
		(end 135.162036 -20.903946)
		(width 0.14224)
		(layer "In2.Cu")
		(net "M_G_DQ<48>")
	)
	(segment
		(start 135.583168 -29.0322)
		(end 135.583168 -28.3718)
		(width 0.14224)
		(layer "In2.Cu")
		(net "M_G_DQ<48>")
	)
	(segment
		(start 115.01247 -49.934368)
		(end 115.086892 -49.859946)
		(width 0.0889)
		(layer "In2.Cu")
		(net "M_G_DQ<48>")
	)
	(segment
		(start 118.998492 -38.351968)
		(end 118.998492 -38.13302)
		(width 0.14224)
		(layer "In2.Cu")
		(net "M_G_DQ<48>")
	)
	(segment
		(start 116.185188 -40.946324)
		(end 115.947444 -40.708326)
		(width 0.14224)
		(layer "In2.Cu")
		(net "M_G_DQ<48>")
	)
	(segment
		(start 130.426968 -34.1884)
		(end 135.583168 -29.0322)
		(width 0.14224)
		(layer "In2.Cu")
		(net "M_G_DQ<48>")
	)
	(segment
		(start 135.551418 -18.965672)
		(end 135.551418 -18.381218)
		(width 0.14224)
		(layer "In2.Cu")
		(net "M_G_DQ<48>")
	)
	(segment
		(start 116.87302 -40.47744)
		(end 117.122956 -40.227504)
		(width 0.14224)
		(layer "In2.Cu")
		(net "M_G_DQ<48>")
	)
	(segment
		(start 135.525764 -26.688796)
		(end 135.525764 -26.222452)
		(width 0.14224)
		(layer "In2.Cu")
		(net "M_G_DQ<48>")
	)
	(segment
		(start 115.332764 -53.923184)
		(end 115.332764 -53.660802)
		(width 0.0889)
		(layer "In2.Cu")
		(net "M_G_DQ<48>")
	)
	(segment
		(start 135.271764 -28.060396)
		(end 135.271764 -26.942796)
		(width 0.14224)
		(layer "In2.Cu")
		(net "M_G_DQ<48>")
	)
	(segment
		(start 115.716304 -41.415208)
		(end 115.935252 -41.415208)
		(width 0.14224)
		(layer "In2.Cu")
		(net "M_G_DQ<48>")
	)
	(arc
		(start 115.412012 -54.218586)
		(mid 115.352945 -54.0761)
		(end 115.332764 -53.923184)
		(width 0.0889)
		(layer "In2.Cu")
		(net "M_G_DQ<48>")
	)
	(arc
		(start 115.416838 -54.61)
		(mid 115.465593 -54.413648)
		(end 115.412012 -54.218586)
		(width 0.0889)
		(layer "In2.Cu")
		(net "M_G_DQ<48>")
	)
	(arc
		(start 115.412012 -55.209186)
		(mid 115.33279 -54.920068)
		(end 115.405662 -54.629304)
		(width 0.0889)
		(layer "In2.Cu")
		(net "M_G_DQ<48>")
	)
	(segment
		(start 129.999486 -15.423642)
		(end 129.999486 -16.687546)
		(width 0.1651)
		(layer "F.Cu")
		(net "M_G_DQ<47>")
	)
	(segment
		(start 113.061242 -57.885584)
		(end 112.489742 -57.885584)
		(width 0.1016)
		(layer "F.Cu")
		(net "M_G_DQ<47>")
	)
	(via
		(at 129.999486 -16.687546)
		(size 0.508)
		(drill 0.254)
		(layers "F.Cu" "B.Cu")
		(net "M_G_DQ<47>")
	)
	(via
		(at 112.489742 -57.885584)
		(size 0.508)
		(drill 0.254)
		(layers "F.Cu" "B.Cu")
		(net "M_G_DQ<47>")
	)
	(via
		(at 130.84937 -22.279356)
		(size 0.508)
		(drill 0.254)
		(layers "F.Cu" "B.Cu")
		(net "M_G_DQ<47>")
	)
	(segment
		(start 130.84937 -22.279356)
		(end 130.84937 -20.224242)
		(width 0.1651)
		(layer "B.Cu")
		(net "M_G_DQ<47>")
	)
	(segment
		(start 111.300768 -39.4462)
		(end 120.089168 -30.6578)
		(width 0.14224)
		(layer "In2.Cu")
		(net "M_G_DQ<47>")
	)
	(segment
		(start 130.900424 -17.653)
		(end 130.646424 -17.653)
		(width 0.14224)
		(layer "In2.Cu")
		(net "M_G_DQ<47>")
	)
	(segment
		(start 112.923066 -57.536842)
		(end 112.923066 -57.822592)
		(width 0.0889)
		(layer "In2.Cu")
		(net "M_G_DQ<47>")
	)
	(segment
		(start 111.802672 -49.920398)
		(end 110.87354 -48.991266)
		(width 0.0889)
		(layer "In2.Cu")
		(net "M_G_DQ<47>")
	)
	(segment
		(start 111.802672 -51.629818)
		(end 111.802672 -49.920398)
		(width 0.0889)
		(layer "In2.Cu")
		(net "M_G_DQ<47>")
	)
	(segment
		(start 130.518916 -28.737052)
		(end 130.518916 -28.260548)
		(width 0.14224)
		(layer "In2.Cu")
		(net "M_G_DQ<47>")
	)
	(segment
		(start 131.202176 -18.621248)
		(end 131.357624 -18.4658)
		(width 0.14224)
		(layer "In2.Cu")
		(net "M_G_DQ<47>")
	)
	(segment
		(start 112.802924 -57.4167)
		(end 112.923066 -57.536842)
		(width 0.0889)
		(layer "In2.Cu")
		(net "M_G_DQ<47>")
	)
	(segment
		(start 128.598168 -30.6578)
		(end 130.518916 -28.737052)
		(width 0.14224)
		(layer "In2.Cu")
		(net "M_G_DQ<47>")
	)
	(segment
		(start 130.518916 -28.260548)
		(end 130.247136 -27.988768)
		(width 0.14224)
		(layer "In2.Cu")
		(net "M_G_DQ<47>")
	)
	(segment
		(start 120.089168 -30.6578)
		(end 128.598168 -30.6578)
		(width 0.14224)
		(layer "In2.Cu")
		(net "M_G_DQ<47>")
	)
	(segment
		(start 130.731768 -23.5458)
		(end 130.376168 -23.1902)
		(width 0.14224)
		(layer "In2.Cu")
		(net "M_G_DQ<47>")
	)
	(segment
		(start 130.376168 -23.1902)
		(end 130.376168 -22.752558)
		(width 0.14224)
		(layer "In2.Cu")
		(net "M_G_DQ<47>")
	)
	(segment
		(start 113.080546 -54.925214)
		(end 113.080546 -52.907692)
		(width 0.0889)
		(layer "In2.Cu")
		(net "M_G_DQ<47>")
	)
	(segment
		(start 112.860074 -57.885584)
		(end 112.489742 -57.885584)
		(width 0.0889)
		(layer "In2.Cu")
		(net "M_G_DQ<47>")
	)
	(segment
		(start 130.731768 -26.554684)
		(end 130.731768 -23.5458)
		(width 0.14224)
		(layer "In2.Cu")
		(net "M_G_DQ<47>")
	)
	(segment
		(start 110.87354 -47.722028)
		(end 111.300768 -47.2948)
		(width 0.0889)
		(layer "In2.Cu")
		(net "M_G_DQ<47>")
	)
	(segment
		(start 130.84937 -22.279356)
		(end 131.202176 -21.92655)
		(width 0.14224)
		(layer "In2.Cu")
		(net "M_G_DQ<47>")
	)
	(segment
		(start 131.202176 -21.92655)
		(end 131.202176 -18.621248)
		(width 0.14224)
		(layer "In2.Cu")
		(net "M_G_DQ<47>")
	)
	(segment
		(start 112.923066 -57.822592)
		(end 112.860074 -57.885584)
		(width 0.0889)
		(layer "In2.Cu")
		(net "M_G_DQ<47>")
	)
	(segment
		(start 130.247136 -27.039316)
		(end 130.731768 -26.554684)
		(width 0.14224)
		(layer "In2.Cu")
		(net "M_G_DQ<47>")
	)
	(segment
		(start 129.999486 -17.006062)
		(end 129.999486 -16.687546)
		(width 0.14224)
		(layer "In2.Cu")
		(net "M_G_DQ<47>")
	)
	(segment
		(start 131.357624 -18.4658)
		(end 131.357624 -18.1102)
		(width 0.14224)
		(layer "In2.Cu")
		(net "M_G_DQ<47>")
	)
	(segment
		(start 111.300768 -47.2948)
		(end 111.300768 -39.4462)
		(width 0.14224)
		(layer "In2.Cu")
		(net "M_G_DQ<47>")
	)
	(segment
		(start 130.247136 -27.988768)
		(end 130.247136 -27.039316)
		(width 0.14224)
		(layer "In2.Cu")
		(net "M_G_DQ<47>")
	)
	(segment
		(start 113.080546 -52.907692)
		(end 111.802672 -51.629818)
		(width 0.0889)
		(layer "In2.Cu")
		(net "M_G_DQ<47>")
	)
	(segment
		(start 110.87354 -48.991266)
		(end 110.87354 -47.722028)
		(width 0.0889)
		(layer "In2.Cu")
		(net "M_G_DQ<47>")
	)
	(segment
		(start 130.376168 -22.752558)
		(end 130.84937 -22.279356)
		(width 0.14224)
		(layer "In2.Cu")
		(net "M_G_DQ<47>")
	)
	(segment
		(start 131.357624 -18.1102)
		(end 130.900424 -17.653)
		(width 0.14224)
		(layer "In2.Cu")
		(net "M_G_DQ<47>")
	)
	(segment
		(start 130.646424 -17.653)
		(end 129.999486 -17.006062)
		(width 0.14224)
		(layer "In2.Cu")
		(net "M_G_DQ<47>")
	)
	(arc
		(start 113.001552 -55.609236)
		(mid 113.080683 -55.904638)
		(end 113.001552 -56.20004)
		(width 0.0889)
		(layer "In2.Cu")
		(net "M_G_DQ<47>")
	)
	(arc
		(start 112.88395 -56.826658)
		(mid 112.883733 -56.965053)
		(end 112.836452 -57.095136)
		(width 0.0889)
		(layer "In2.Cu")
		(net "M_G_DQ<47>")
	)
	(arc
		(start 113.080546 -54.925214)
		(mid 113.059056 -55.072329)
		(end 113.001552 -55.20944)
		(width 0.0889)
		(layer "In2.Cu")
		(net "M_G_DQ<47>")
	)
	(arc
		(start 113.001552 -55.20944)
		(mid 112.948053 -55.409338)
		(end 113.001552 -55.609236)
		(width 0.0889)
		(layer "In2.Cu")
		(net "M_G_DQ<47>")
	)
	(arc
		(start 112.836452 -57.095136)
		(mid 112.785513 -57.252351)
		(end 112.802924 -57.4167)
		(width 0.0889)
		(layer "In2.Cu")
		(net "M_G_DQ<47>")
	)
	(arc
		(start 113.001552 -56.20004)
		(mid 112.889306 -56.503316)
		(end 112.88395 -56.826658)
		(width 0.0889)
		(layer "In2.Cu")
		(net "M_G_DQ<47>")
	)
	(segment
		(start 130.84937 -20.023582)
		(end 130.849624 -20.023328)
		(width 0.1651)
		(layer "F.Cu")
		(net "M_G_DQ<46>")
	)
	(segment
		(start 130.849624 -18.262854)
		(end 130.84937 -18.2626)
		(width 0.1651)
		(layer "F.Cu")
		(net "M_G_DQ<46>")
	)
	(segment
		(start 130.981704 -18.69948)
		(end 130.849624 -18.5674)
		(width 0.1651)
		(layer "F.Cu")
		(net "M_G_DQ<46>")
	)
	(segment
		(start 130.981704 -18.91792)
		(end 130.981704 -18.69948)
		(width 0.1651)
		(layer "F.Cu")
		(net "M_G_DQ<46>")
	)
	(segment
		(start 130.849624 -20.023328)
		(end 130.849624 -19.05)
		(width 0.1651)
		(layer "F.Cu")
		(net "M_G_DQ<46>")
	)
	(segment
		(start 113.061242 -55.904384)
		(end 112.489742 -55.904384)
		(width 0.1016)
		(layer "F.Cu")
		(net "M_G_DQ<46>")
	)
	(segment
		(start 130.849624 -18.5674)
		(end 130.849624 -18.262854)
		(width 0.1651)
		(layer "F.Cu")
		(net "M_G_DQ<46>")
	)
	(segment
		(start 130.849624 -19.05)
		(end 130.981704 -18.91792)
		(width 0.1651)
		(layer "F.Cu")
		(net "M_G_DQ<46>")
	)
	(via
		(at 112.489742 -55.904384)
		(size 0.508)
		(drill 0.254)
		(layers "F.Cu" "B.Cu")
		(net "M_G_DQ<46>")
	)
	(via
		(at 129.999486 -23.560278)
		(size 0.508)
		(drill 0.254)
		(layers "F.Cu" "B.Cu")
		(net "M_G_DQ<46>")
	)
	(via
		(at 130.84937 -18.2626)
		(size 0.508)
		(drill 0.254)
		(layers "F.Cu" "B.Cu")
		(net "M_G_DQ<46>")
	)
	(segment
		(start 129.999486 -23.560278)
		(end 129.999486 -24.824182)
		(width 0.1651)
		(layer "B.Cu")
		(net "M_G_DQ<46>")
	)
	(segment
		(start 112.890046 -54.913784)
		(end 112.890046 -52.987956)
		(width 0.0889)
		(layer "In2.Cu")
		(net "M_G_DQ<46>")
	)
	(segment
		(start 130.147568 -25.527)
		(end 129.983992 -25.363424)
		(width 0.14224)
		(layer "In2.Cu")
		(net "M_G_DQ<46>")
	)
	(segment
		(start 129.999486 -23.560278)
		(end 129.763774 -23.324566)
		(width 0.14224)
		(layer "In2.Cu")
		(net "M_G_DQ<46>")
	)
	(segment
		(start 110.68304 -47.353728)
		(end 110.818168 -47.2186)
		(width 0.0889)
		(layer "In2.Cu")
		(net "M_G_DQ<46>")
	)
	(segment
		(start 130.491992 -20.313904)
		(end 130.491992 -19.970496)
		(width 0.14224)
		(layer "In2.Cu")
		(net "M_G_DQ<46>")
	)
	(segment
		(start 129.4638 -25.363424)
		(end 129.2352 -25.134824)
		(width 0.14224)
		(layer "In2.Cu")
		(net "M_G_DQ<46>")
	)
	(segment
		(start 130.474974 -18.914872)
		(end 130.474974 -18.636996)
		(width 0.14224)
		(layer "In2.Cu")
		(net "M_G_DQ<46>")
	)
	(segment
		(start 129.715768 -27.570938)
		(end 129.715768 -27.164538)
		(width 0.14224)
		(layer "In2.Cu")
		(net "M_G_DQ<46>")
	)
	(segment
		(start 110.818168 -37.947346)
		(end 111.196374 -37.56914)
		(width 0.14224)
		(layer "In2.Cu")
		(net "M_G_DQ<46>")
	)
	(segment
		(start 129.512568 -26.961338)
		(end 129.360168 -26.961338)
		(width 0.14224)
		(layer "In2.Cu")
		(net "M_G_DQ<46>")
	)
	(segment
		(start 130.172968 -23.734776)
		(end 129.999486 -23.561294)
		(width 0.14224)
		(layer "In2.Cu")
		(net "M_G_DQ<46>")
	)
	(segment
		(start 129.2352 -25.134824)
		(end 129.2352 -24.728424)
		(width 0.14224)
		(layer "In2.Cu")
		(net "M_G_DQ<46>")
	)
	(segment
		(start 129.182368 -28.2448)
		(end 129.182368 -27.951938)
		(width 0.14224)
		(layer "In2.Cu")
		(net "M_G_DQ<46>")
	)
	(segment
		(start 118.717314 -30.0482)
		(end 128.309624 -30.0482)
		(width 0.14224)
		(layer "In2.Cu")
		(net "M_G_DQ<46>")
	)
	(segment
		(start 130.110992 -19.589496)
		(end 130.110992 -19.278854)
		(width 0.14224)
		(layer "In2.Cu")
		(net "M_G_DQ<46>")
	)
	(segment
		(start 111.653828 -37.56914)
		(end 112.392968 -36.83)
		(width 0.14224)
		(layer "In2.Cu")
		(net "M_G_DQ<46>")
	)
	(segment
		(start 129.182368 -27.951938)
		(end 129.360168 -27.774138)
		(width 0.14224)
		(layer "In2.Cu")
		(net "M_G_DQ<46>")
	)
	(segment
		(start 129.4384 -24.525224)
		(end 130.031998 -24.525224)
		(width 0.14224)
		(layer "In2.Cu")
		(net "M_G_DQ<46>")
	)
	(segment
		(start 129.763774 -23.324566)
		(end 129.763774 -22.530054)
		(width 0.14224)
		(layer "In2.Cu")
		(net "M_G_DQ<46>")
	)
	(segment
		(start 111.612172 -49.999392)
		(end 110.68304 -49.07026)
		(width 0.0889)
		(layer "In2.Cu")
		(net "M_G_DQ<46>")
	)
	(segment
		(start 130.474974 -18.636996)
		(end 130.84937 -18.2626)
		(width 0.14224)
		(layer "In2.Cu")
		(net "M_G_DQ<46>")
	)
	(segment
		(start 111.196374 -37.56914)
		(end 111.653828 -37.56914)
		(width 0.14224)
		(layer "In2.Cu")
		(net "M_G_DQ<46>")
	)
	(segment
		(start 129.512568 -28.575)
		(end 129.182368 -28.2448)
		(width 0.14224)
		(layer "In2.Cu")
		(net "M_G_DQ<46>")
	)
	(segment
		(start 129.360168 -27.774138)
		(end 129.512568 -27.774138)
		(width 0.14224)
		(layer "In2.Cu")
		(net "M_G_DQ<46>")
	)
	(segment
		(start 130.536442 -21.757386)
		(end 130.536442 -21.405596)
		(width 0.14224)
		(layer "In2.Cu")
		(net "M_G_DQ<46>")
	)
	(segment
		(start 129.2352 -24.728424)
		(end 129.4384 -24.525224)
		(width 0.14224)
		(layer "In2.Cu")
		(net "M_G_DQ<46>")
	)
	(segment
		(start 112.489742 -55.904384)
		(end 112.798352 -55.193184)
		(width 0.0889)
		(layer "In2.Cu")
		(net "M_G_DQ<46>")
	)
	(segment
		(start 130.031998 -24.525224)
		(end 130.172968 -24.384254)
		(width 0.14224)
		(layer "In2.Cu")
		(net "M_G_DQ<46>")
	)
	(segment
		(start 129.182368 -26.2636)
		(end 129.309368 -26.1366)
		(width 0.14224)
		(layer "In2.Cu")
		(net "M_G_DQ<46>")
	)
	(segment
		(start 130.172968 -24.384254)
		(end 130.172968 -23.734776)
		(width 0.14224)
		(layer "In2.Cu")
		(net "M_G_DQ<46>")
	)
	(segment
		(start 129.360168 -26.961338)
		(end 129.182368 -26.783538)
		(width 0.14224)
		(layer "In2.Cu")
		(net "M_G_DQ<46>")
	)
	(segment
		(start 129.182368 -26.783538)
		(end 129.182368 -26.2636)
		(width 0.14224)
		(layer "In2.Cu")
		(net "M_G_DQ<46>")
	)
	(segment
		(start 129.512568 -27.774138)
		(end 129.715768 -27.570938)
		(width 0.14224)
		(layer "In2.Cu")
		(net "M_G_DQ<46>")
	)
	(segment
		(start 130.147568 -25.7556)
		(end 130.147568 -25.527)
		(width 0.14224)
		(layer "In2.Cu")
		(net "M_G_DQ<46>")
	)
	(segment
		(start 130.110992 -19.278854)
		(end 130.474974 -18.914872)
		(width 0.14224)
		(layer "In2.Cu")
		(net "M_G_DQ<46>")
	)
	(segment
		(start 128.309624 -30.0482)
		(end 129.512568 -28.845256)
		(width 0.14224)
		(layer "In2.Cu")
		(net "M_G_DQ<46>")
	)
	(segment
		(start 130.536442 -21.405596)
		(end 130.110992 -20.980146)
		(width 0.14224)
		(layer "In2.Cu")
		(net "M_G_DQ<46>")
	)
	(segment
		(start 129.309368 -26.1366)
		(end 129.766568 -26.1366)
		(width 0.14224)
		(layer "In2.Cu")
		(net "M_G_DQ<46>")
	)
	(segment
		(start 112.392968 -36.83)
		(end 112.392968 -36.372546)
		(width 0.14224)
		(layer "In2.Cu")
		(net "M_G_DQ<46>")
	)
	(segment
		(start 130.491992 -19.970496)
		(end 130.110992 -19.589496)
		(width 0.14224)
		(layer "In2.Cu")
		(net "M_G_DQ<46>")
	)
	(segment
		(start 112.890046 -52.987956)
		(end 111.612172 -51.710082)
		(width 0.0889)
		(layer "In2.Cu")
		(net "M_G_DQ<46>")
	)
	(segment
		(start 129.999486 -23.561294)
		(end 129.999486 -23.560278)
		(width 0.14224)
		(layer "In2.Cu")
		(net "M_G_DQ<46>")
	)
	(segment
		(start 129.715768 -27.164538)
		(end 129.512568 -26.961338)
		(width 0.14224)
		(layer "In2.Cu")
		(net "M_G_DQ<46>")
	)
	(segment
		(start 110.68304 -49.07026)
		(end 110.68304 -47.353728)
		(width 0.0889)
		(layer "In2.Cu")
		(net "M_G_DQ<46>")
	)
	(segment
		(start 130.110992 -20.694904)
		(end 130.491992 -20.313904)
		(width 0.14224)
		(layer "In2.Cu")
		(net "M_G_DQ<46>")
	)
	(segment
		(start 129.983992 -25.363424)
		(end 129.4638 -25.363424)
		(width 0.14224)
		(layer "In2.Cu")
		(net "M_G_DQ<46>")
	)
	(segment
		(start 129.766568 -26.1366)
		(end 130.147568 -25.7556)
		(width 0.14224)
		(layer "In2.Cu")
		(net "M_G_DQ<46>")
	)
	(segment
		(start 130.110992 -20.980146)
		(end 130.110992 -20.694904)
		(width 0.14224)
		(layer "In2.Cu")
		(net "M_G_DQ<46>")
	)
	(segment
		(start 111.612172 -51.710082)
		(end 111.612172 -49.999392)
		(width 0.0889)
		(layer "In2.Cu")
		(net "M_G_DQ<46>")
	)
	(segment
		(start 112.392968 -36.372546)
		(end 118.717314 -30.0482)
		(width 0.14224)
		(layer "In2.Cu")
		(net "M_G_DQ<46>")
	)
	(segment
		(start 129.512568 -28.845256)
		(end 129.512568 -28.575)
		(width 0.14224)
		(layer "In2.Cu")
		(net "M_G_DQ<46>")
	)
	(segment
		(start 110.818168 -47.2186)
		(end 110.818168 -37.947346)
		(width 0.14224)
		(layer "In2.Cu")
		(net "M_G_DQ<46>")
	)
	(segment
		(start 129.763774 -22.530054)
		(end 130.536442 -21.757386)
		(width 0.14224)
		(layer "In2.Cu")
		(net "M_G_DQ<46>")
	)
	(arc
		(start 112.798352 -55.193184)
		(mid 112.815922 -55.152848)
		(end 112.836452 -55.113936)
		(width 0.0889)
		(layer "In2.Cu")
		(net "M_G_DQ<46>")
	)
	(arc
		(start 112.836452 -55.113936)
		(mid 112.876439 -55.01739)
		(end 112.890046 -54.913784)
		(width 0.0889)
		(layer "In2.Cu")
		(net "M_G_DQ<46>")
	)
	(segment
		(start 110.485682 -57.390538)
		(end 109.914182 -57.390538)
		(width 0.1016)
		(layer "F.Cu")
		(net "M_G_DQ<45>")
	)
	(segment
		(start 124.049536 -15.423642)
		(end 124.049536 -16.687546)
		(width 0.1651)
		(layer "F.Cu")
		(net "M_G_DQ<45>")
	)
	(via
		(at 109.914182 -57.390538)
		(size 0.508)
		(drill 0.254)
		(layers "F.Cu" "B.Cu")
		(net "M_G_DQ<45>")
	)
	(via
		(at 124.82322 -22.279356)
		(size 0.508)
		(drill 0.254)
		(layers "F.Cu" "B.Cu")
		(net "M_G_DQ<45>")
	)
	(via
		(at 124.049536 -16.687546)
		(size 0.508)
		(drill 0.254)
		(layers "F.Cu" "B.Cu")
		(net "M_G_DQ<45>")
	)
	(segment
		(start 124.89942 -22.203156)
		(end 124.82322 -22.279356)
		(width 0.1651)
		(layer "B.Cu")
		(net "M_G_DQ<45>")
	)
	(segment
		(start 124.89942 -20.224242)
		(end 124.89942 -22.203156)
		(width 0.1651)
		(layer "B.Cu")
		(net "M_G_DQ<45>")
	)
	(segment
		(start 109.567726 -54.618636)
		(end 109.5629 -54.61)
		(width 0.0889)
		(layer "In2.Cu")
		(net "M_G_DQ<45>")
	)
	(segment
		(start 109.914182 -57.390538)
		(end 110.24362 -56.629554)
		(width 0.0889)
		(layer "In2.Cu")
		(net "M_G_DQ<45>")
	)
	(segment
		(start 120.088914 -25.3238)
		(end 120.546622 -25.3238)
		(width 0.14224)
		(layer "In2.Cu")
		(net "M_G_DQ<45>")
	)
	(segment
		(start 116.659914 -24.9174)
		(end 116.888514 -25.146)
		(width 0.14224)
		(layer "In2.Cu")
		(net "M_G_DQ<45>")
	)
	(segment
		(start 117.729254 -24.9174)
		(end 118.158514 -24.9174)
		(width 0.14224)
		(layer "In2.Cu")
		(net "M_G_DQ<45>")
	)
	(segment
		(start 118.564914 -25.3238)
		(end 118.921022 -25.3238)
		(width 0.14224)
		(layer "In2.Cu")
		(net "M_G_DQ<45>")
	)
	(segment
		(start 124.756164 -24.047196)
		(end 124.883164 -23.920196)
		(width 0.14224)
		(layer "In2.Cu")
		(net "M_G_DQ<45>")
	)
	(segment
		(start 107.766104 -50.593752)
		(end 107.766104 -47.570136)
		(width 0.0889)
		(layer "In2.Cu")
		(net "M_G_DQ<45>")
	)
	(segment
		(start 107.109768 -46.9138)
		(end 107.109768 -33.4518)
		(width 0.14224)
		(layer "In2.Cu")
		(net "M_G_DQ<45>")
	)
	(segment
		(start 125.134624 -21.967952)
		(end 125.134624 -18.66265)
		(width 0.14224)
		(layer "In2.Cu")
		(net "M_G_DQ<45>")
	)
	(segment
		(start 109.656372 -54.065932)
		(end 109.656372 -53.594)
		(width 0.0889)
		(layer "In2.Cu")
		(net "M_G_DQ<45>")
	)
	(segment
		(start 117.500654 -25.146)
		(end 117.729254 -24.9174)
		(width 0.14224)
		(layer "In2.Cu")
		(net "M_G_DQ<45>")
	)
	(segment
		(start 115.644168 -24.9174)
		(end 116.659914 -24.9174)
		(width 0.14224)
		(layer "In2.Cu")
		(net "M_G_DQ<45>")
	)
	(segment
		(start 124.35332 -23.174452)
		(end 124.35332 -22.749256)
		(width 0.14224)
		(layer "In2.Cu")
		(net "M_G_DQ<45>")
	)
	(segment
		(start 120.953022 -24.9174)
		(end 121.816368 -24.9174)
		(width 0.14224)
		(layer "In2.Cu")
		(net "M_G_DQ<45>")
	)
	(segment
		(start 118.158514 -24.9174)
		(end 118.564914 -25.3238)
		(width 0.14224)
		(layer "In2.Cu")
		(net "M_G_DQ<45>")
	)
	(segment
		(start 123.189746 -24.047196)
		(end 124.756164 -24.047196)
		(width 0.14224)
		(layer "In2.Cu")
		(net "M_G_DQ<45>")
	)
	(segment
		(start 109.576616 -54.633876)
		(end 109.567726 -54.618636)
		(width 0.0889)
		(layer "In2.Cu")
		(net "M_G_DQ<45>")
	)
	(segment
		(start 108.907326 -51.734974)
		(end 107.766104 -50.593752)
		(width 0.0889)
		(layer "In2.Cu")
		(net "M_G_DQ<45>")
	)
	(segment
		(start 122.762264 -24.474678)
		(end 123.189746 -24.047196)
		(width 0.14224)
		(layer "In2.Cu")
		(net "M_G_DQ<45>")
	)
	(segment
		(start 122.25909 -24.474678)
		(end 122.762264 -24.474678)
		(width 0.14224)
		(layer "In2.Cu")
		(net "M_G_DQ<45>")
	)
	(segment
		(start 116.888514 -25.146)
		(end 117.500654 -25.146)
		(width 0.14224)
		(layer "In2.Cu")
		(net "M_G_DQ<45>")
	)
	(segment
		(start 125.331474 -18.053304)
		(end 124.93117 -17.653)
		(width 0.14224)
		(layer "In2.Cu")
		(net "M_G_DQ<45>")
	)
	(segment
		(start 125.331474 -18.4658)
		(end 125.331474 -18.053304)
		(width 0.14224)
		(layer "In2.Cu")
		(net "M_G_DQ<45>")
	)
	(segment
		(start 124.82322 -22.279356)
		(end 125.134624 -21.967952)
		(width 0.14224)
		(layer "In2.Cu")
		(net "M_G_DQ<45>")
	)
	(segment
		(start 109.567726 -54.218586)
		(end 109.656372 -54.065932)
		(width 0.0889)
		(layer "In2.Cu")
		(net "M_G_DQ<45>")
	)
	(segment
		(start 107.766104 -47.570136)
		(end 107.109768 -46.9138)
		(width 0.0889)
		(layer "In2.Cu")
		(net "M_G_DQ<45>")
	)
	(segment
		(start 124.883164 -23.920196)
		(end 124.883164 -23.704296)
		(width 0.14224)
		(layer "In2.Cu")
		(net "M_G_DQ<45>")
	)
	(segment
		(start 118.921022 -25.3238)
		(end 119.327422 -24.9174)
		(width 0.14224)
		(layer "In2.Cu")
		(net "M_G_DQ<45>")
	)
	(segment
		(start 110.24362 -56.629554)
		(end 110.265718 -56.5912)
		(width 0.0889)
		(layer "In2.Cu")
		(net "M_G_DQ<45>")
	)
	(segment
		(start 121.816368 -24.9174)
		(end 122.25909 -24.474678)
		(width 0.14224)
		(layer "In2.Cu")
		(net "M_G_DQ<45>")
	)
	(segment
		(start 124.35332 -22.749256)
		(end 124.82322 -22.279356)
		(width 0.14224)
		(layer "In2.Cu")
		(net "M_G_DQ<45>")
	)
	(segment
		(start 124.620274 -17.653)
		(end 124.049536 -17.082262)
		(width 0.14224)
		(layer "In2.Cu")
		(net "M_G_DQ<45>")
	)
	(segment
		(start 109.656372 -53.594)
		(end 108.907326 -52.844954)
		(width 0.0889)
		(layer "In2.Cu")
		(net "M_G_DQ<45>")
	)
	(segment
		(start 119.682514 -24.9174)
		(end 120.088914 -25.3238)
		(width 0.14224)
		(layer "In2.Cu")
		(net "M_G_DQ<45>")
	)
	(segment
		(start 120.546622 -25.3238)
		(end 120.953022 -24.9174)
		(width 0.14224)
		(layer "In2.Cu")
		(net "M_G_DQ<45>")
	)
	(segment
		(start 108.907326 -52.844954)
		(end 108.907326 -51.734974)
		(width 0.0889)
		(layer "In2.Cu")
		(net "M_G_DQ<45>")
	)
	(segment
		(start 110.260892 -56.199786)
		(end 110.232444 -56.150256)
		(width 0.0889)
		(layer "In2.Cu")
		(net "M_G_DQ<45>")
	)
	(segment
		(start 124.883164 -23.704296)
		(end 124.35332 -23.174452)
		(width 0.14224)
		(layer "In2.Cu")
		(net "M_G_DQ<45>")
	)
	(segment
		(start 119.327422 -24.9174)
		(end 119.682514 -24.9174)
		(width 0.14224)
		(layer "In2.Cu")
		(net "M_G_DQ<45>")
	)
	(segment
		(start 125.134624 -18.66265)
		(end 125.331474 -18.4658)
		(width 0.14224)
		(layer "In2.Cu")
		(net "M_G_DQ<45>")
	)
	(segment
		(start 124.049536 -17.082262)
		(end 124.049536 -16.687546)
		(width 0.14224)
		(layer "In2.Cu")
		(net "M_G_DQ<45>")
	)
	(segment
		(start 124.93117 -17.653)
		(end 124.620274 -17.653)
		(width 0.14224)
		(layer "In2.Cu")
		(net "M_G_DQ<45>")
	)
	(segment
		(start 107.109768 -33.4518)
		(end 115.644168 -24.9174)
		(width 0.14224)
		(layer "In2.Cu")
		(net "M_G_DQ<45>")
	)
	(arc
		(start 109.54258 -55.556912)
		(mid 109.515294 -55.380284)
		(end 109.567726 -55.20944)
		(width 0.0889)
		(layer "In2.Cu")
		(net "M_G_DQ<45>")
	)
	(arc
		(start 109.5629 -54.61)
		(mid 109.514114 -54.413648)
		(end 109.567726 -54.218586)
		(width 0.0889)
		(layer "In2.Cu")
		(net "M_G_DQ<45>")
	)
	(arc
		(start 110.265718 -56.5912)
		(mid 110.314473 -56.394848)
		(end 110.260892 -56.199786)
		(width 0.0889)
		(layer "In2.Cu")
		(net "M_G_DQ<45>")
	)
	(arc
		(start 109.81436 -55.796688)
		(mid 109.695837 -55.744405)
		(end 109.600238 -55.656988)
		(width 0.0889)
		(layer "In2.Cu")
		(net "M_G_DQ<45>")
	)
	(arc
		(start 110.232444 -56.150256)
		(mid 110.063806 -55.925683)
		(end 109.81436 -55.796688)
		(width 0.0889)
		(layer "In2.Cu")
		(net "M_G_DQ<45>")
	)
	(arc
		(start 109.600238 -55.656988)
		(mid 109.5678 -55.609029)
		(end 109.54258 -55.556912)
		(width 0.0889)
		(layer "In2.Cu")
		(net "M_G_DQ<45>")
	)
	(arc
		(start 109.567726 -55.20944)
		(mid 109.646915 -54.922825)
		(end 109.576616 -54.633876)
		(width 0.0889)
		(layer "In2.Cu")
		(net "M_G_DQ<45>")
	)
	(segment
		(start 110.485682 -56.399938)
		(end 109.914182 -56.399938)
		(width 0.1016)
		(layer "F.Cu")
		(net "M_G_DQ<44>")
	)
	(segment
		(start 124.89942 -18.692368)
		(end 124.801376 -18.161)
		(width 0.1651)
		(layer "F.Cu")
		(net "M_G_DQ<44>")
	)
	(segment
		(start 124.89942 -20.023582)
		(end 124.89942 -18.692368)
		(width 0.1651)
		(layer "F.Cu")
		(net "M_G_DQ<44>")
	)
	(via
		(at 124.049536 -23.560278)
		(size 0.508)
		(drill 0.254)
		(layers "F.Cu" "B.Cu")
		(net "M_G_DQ<44>")
	)
	(via
		(at 124.801376 -18.161)
		(size 0.508)
		(drill 0.254)
		(layers "F.Cu" "B.Cu")
		(net "M_G_DQ<44>")
	)
	(via
		(at 109.914182 -56.399938)
		(size 0.508)
		(drill 0.254)
		(layers "F.Cu" "B.Cu")
		(net "M_G_DQ<44>")
	)
	(segment
		(start 124.049536 -23.560278)
		(end 124.049536 -24.824182)
		(width 0.1651)
		(layer "B.Cu")
		(net "M_G_DQ<44>")
	)
	(segment
		(start 105.966768 -44.776644)
		(end 105.966768 -44.423584)
		(width 0.14224)
		(layer "In2.Cu")
		(net "M_G_DQ<44>")
	)
	(segment
		(start 106.421428 -40.291004)
		(end 106.576368 -40.136064)
		(width 0.14224)
		(layer "In2.Cu")
		(net "M_G_DQ<44>")
	)
	(segment
		(start 106.421428 -44.268644)
		(end 106.576368 -44.113704)
		(width 0.14224)
		(layer "In2.Cu")
		(net "M_G_DQ<44>")
	)
	(segment
		(start 105.966768 -41.771824)
		(end 106.121708 -41.616884)
		(width 0.14224)
		(layer "In2.Cu")
		(net "M_G_DQ<44>")
	)
	(segment
		(start 106.576368 -44.113704)
		(end 106.576368 -43.760644)
		(width 0.14224)
		(layer "In2.Cu")
		(net "M_G_DQ<44>")
	)
	(segment
		(start 106.576368 -42.434764)
		(end 106.421428 -42.279824)
		(width 0.14224)
		(layer "In2.Cu")
		(net "M_G_DQ<44>")
	)
	(segment
		(start 105.966768 -43.450764)
		(end 105.966768 -43.097704)
		(width 0.14224)
		(layer "In2.Cu")
		(net "M_G_DQ<44>")
	)
	(segment
		(start 106.421428 -39.628064)
		(end 106.121708 -39.628064)
		(width 0.14224)
		(layer "In2.Cu")
		(net "M_G_DQ<44>")
	)
	(segment
		(start 105.966768 -39.473124)
		(end 105.966768 -33.857946)
		(width 0.14224)
		(layer "In2.Cu")
		(net "M_G_DQ<44>")
	)
	(segment
		(start 106.421428 -44.931584)
		(end 106.121708 -44.931584)
		(width 0.14224)
		(layer "In2.Cu")
		(net "M_G_DQ<44>")
	)
	(segment
		(start 124.161042 -19.5834)
		(end 124.161042 -19.278854)
		(width 0.14224)
		(layer "In2.Cu")
		(net "M_G_DQ<44>")
	)
	(segment
		(start 106.576368 -39.783004)
		(end 106.421428 -39.628064)
		(width 0.14224)
		(layer "In2.Cu")
		(net "M_G_DQ<44>")
	)
	(segment
		(start 123.813824 -22.530054)
		(end 124.525024 -21.818854)
		(width 0.14224)
		(layer "In2.Cu")
		(net "M_G_DQ<44>")
	)
	(segment
		(start 106.121708 -39.628064)
		(end 105.966768 -39.473124)
		(width 0.14224)
		(layer "In2.Cu")
		(net "M_G_DQ<44>")
	)
	(segment
		(start 106.576368 -45.086524)
		(end 106.421428 -44.931584)
		(width 0.14224)
		(layer "In2.Cu")
		(net "M_G_DQ<44>")
	)
	(segment
		(start 123.813824 -23.324566)
		(end 123.813824 -22.530054)
		(width 0.14224)
		(layer "In2.Cu")
		(net "M_G_DQ<44>")
	)
	(segment
		(start 124.525024 -21.818854)
		(end 124.525024 -21.344128)
		(width 0.14224)
		(layer "In2.Cu")
		(net "M_G_DQ<44>")
	)
	(segment
		(start 121.818146 -24.017478)
		(end 122.57278 -24.017478)
		(width 0.14224)
		(layer "In2.Cu")
		(net "M_G_DQ<44>")
	)
	(segment
		(start 124.173742 -20.992846)
		(end 124.173742 -20.6375)
		(width 0.14224)
		(layer "In2.Cu")
		(net "M_G_DQ<44>")
	)
	(segment
		(start 106.576368 -43.760644)
		(end 106.421428 -43.605704)
		(width 0.14224)
		(layer "In2.Cu")
		(net "M_G_DQ<44>")
	)
	(segment
		(start 105.966768 -44.423584)
		(end 106.121708 -44.268644)
		(width 0.14224)
		(layer "In2.Cu")
		(net "M_G_DQ<44>")
	)
	(segment
		(start 106.121708 -42.942764)
		(end 106.421428 -42.942764)
		(width 0.14224)
		(layer "In2.Cu")
		(net "M_G_DQ<44>")
	)
	(segment
		(start 123.025662 -23.564596)
		(end 124.045218 -23.564596)
		(width 0.14224)
		(layer "In2.Cu")
		(net "M_G_DQ<44>")
	)
	(segment
		(start 109.402372 -54.713886)
		(end 109.391704 -54.695344)
		(width 0.0889)
		(layer "In2.Cu")
		(net "M_G_DQ<44>")
	)
	(segment
		(start 106.121708 -44.268644)
		(end 106.421428 -44.268644)
		(width 0.14224)
		(layer "In2.Cu")
		(net "M_G_DQ<44>")
	)
	(segment
		(start 107.575604 -48.125126)
		(end 106.576368 -47.12589)
		(width 0.0889)
		(layer "In2.Cu")
		(net "M_G_DQ<44>")
	)
	(segment
		(start 124.542042 -20.2692)
		(end 124.542042 -19.9644)
		(width 0.14224)
		(layer "In2.Cu")
		(net "M_G_DQ<44>")
	)
	(segment
		(start 109.465872 -54.013608)
		(end 109.465872 -53.672994)
		(width 0.0889)
		(layer "In2.Cu")
		(net "M_G_DQ<44>")
	)
	(segment
		(start 106.421428 -42.279824)
		(end 106.121708 -42.279824)
		(width 0.14224)
		(layer "In2.Cu")
		(net "M_G_DQ<44>")
	)
	(segment
		(start 109.465872 -53.672994)
		(end 108.716826 -52.923948)
		(width 0.0889)
		(layer "In2.Cu")
		(net "M_G_DQ<44>")
	)
	(segment
		(start 106.576368 -42.787824)
		(end 106.576368 -42.434764)
		(width 0.14224)
		(layer "In2.Cu")
		(net "M_G_DQ<44>")
	)
	(segment
		(start 109.402372 -54.122828)
		(end 109.465872 -54.013608)
		(width 0.0889)
		(layer "In2.Cu")
		(net "M_G_DQ<44>")
	)
	(segment
		(start 106.121708 -40.291004)
		(end 106.421428 -40.291004)
		(width 0.14224)
		(layer "In2.Cu")
		(net "M_G_DQ<44>")
	)
	(segment
		(start 106.121708 -40.953944)
		(end 105.966768 -40.799004)
		(width 0.14224)
		(layer "In2.Cu")
		(net "M_G_DQ<44>")
	)
	(segment
		(start 106.576368 -41.461944)
		(end 106.576368 -41.108884)
		(width 0.14224)
		(layer "In2.Cu")
		(net "M_G_DQ<44>")
	)
	(segment
		(start 107.575604 -50.672746)
		(end 107.575604 -48.125126)
		(width 0.0889)
		(layer "In2.Cu")
		(net "M_G_DQ<44>")
	)
	(segment
		(start 124.525024 -18.437352)
		(end 124.801376 -18.161)
		(width 0.14224)
		(layer "In2.Cu")
		(net "M_G_DQ<44>")
	)
	(segment
		(start 121.502424 -24.3332)
		(end 121.818146 -24.017478)
		(width 0.14224)
		(layer "In2.Cu")
		(net "M_G_DQ<44>")
	)
	(segment
		(start 106.421428 -42.942764)
		(end 106.576368 -42.787824)
		(width 0.14224)
		(layer "In2.Cu")
		(net "M_G_DQ<44>")
	)
	(segment
		(start 115.491514 -24.3332)
		(end 121.502424 -24.3332)
		(width 0.14224)
		(layer "In2.Cu")
		(net "M_G_DQ<44>")
	)
	(segment
		(start 106.576368 -47.12589)
		(end 106.576368 -45.086524)
		(width 0.14224)
		(layer "In2.Cu")
		(net "M_G_DQ<44>")
	)
	(segment
		(start 105.966768 -33.857946)
		(end 115.491514 -24.3332)
		(width 0.14224)
		(layer "In2.Cu")
		(net "M_G_DQ<44>")
	)
	(segment
		(start 106.576368 -40.136064)
		(end 106.576368 -39.783004)
		(width 0.14224)
		(layer "In2.Cu")
		(net "M_G_DQ<44>")
	)
	(segment
		(start 105.966768 -42.124884)
		(end 105.966768 -41.771824)
		(width 0.14224)
		(layer "In2.Cu")
		(net "M_G_DQ<44>")
	)
	(segment
		(start 106.421428 -40.953944)
		(end 106.121708 -40.953944)
		(width 0.14224)
		(layer "In2.Cu")
		(net "M_G_DQ<44>")
	)
	(segment
		(start 106.121708 -41.616884)
		(end 106.421428 -41.616884)
		(width 0.14224)
		(layer "In2.Cu")
		(net "M_G_DQ<44>")
	)
	(segment
		(start 106.121708 -44.931584)
		(end 105.966768 -44.776644)
		(width 0.14224)
		(layer "In2.Cu")
		(net "M_G_DQ<44>")
	)
	(segment
		(start 105.966768 -40.799004)
		(end 105.966768 -40.445944)
		(width 0.14224)
		(layer "In2.Cu")
		(net "M_G_DQ<44>")
	)
	(segment
		(start 124.173742 -20.6375)
		(end 124.542042 -20.2692)
		(width 0.14224)
		(layer "In2.Cu")
		(net "M_G_DQ<44>")
	)
	(segment
		(start 108.716826 -52.923948)
		(end 108.716826 -51.813968)
		(width 0.0889)
		(layer "In2.Cu")
		(net "M_G_DQ<44>")
	)
	(segment
		(start 108.716826 -51.813968)
		(end 107.575604 -50.672746)
		(width 0.0889)
		(layer "In2.Cu")
		(net "M_G_DQ<44>")
	)
	(segment
		(start 106.121708 -43.605704)
		(end 105.966768 -43.450764)
		(width 0.14224)
		(layer "In2.Cu")
		(net "M_G_DQ<44>")
	)
	(segment
		(start 106.121708 -42.279824)
		(end 105.966768 -42.124884)
		(width 0.14224)
		(layer "In2.Cu")
		(net "M_G_DQ<44>")
	)
	(segment
		(start 106.576368 -41.108884)
		(end 106.421428 -40.953944)
		(width 0.14224)
		(layer "In2.Cu")
		(net "M_G_DQ<44>")
	)
	(segment
		(start 106.421428 -43.605704)
		(end 106.121708 -43.605704)
		(width 0.14224)
		(layer "In2.Cu")
		(net "M_G_DQ<44>")
	)
	(segment
		(start 124.525024 -18.914872)
		(end 124.525024 -18.437352)
		(width 0.14224)
		(layer "In2.Cu")
		(net "M_G_DQ<44>")
	)
	(segment
		(start 122.57278 -24.017478)
		(end 123.025662 -23.564596)
		(width 0.14224)
		(layer "In2.Cu")
		(net "M_G_DQ<44>")
	)
	(segment
		(start 124.542042 -19.9644)
		(end 124.161042 -19.5834)
		(width 0.14224)
		(layer "In2.Cu")
		(net "M_G_DQ<44>")
	)
	(segment
		(start 105.966768 -43.097704)
		(end 106.121708 -42.942764)
		(width 0.14224)
		(layer "In2.Cu")
		(net "M_G_DQ<44>")
	)
	(segment
		(start 109.418628 -55.733188)
		(end 109.402372 -55.704486)
		(width 0.0889)
		(layer "In2.Cu")
		(net "M_G_DQ<44>")
	)
	(segment
		(start 106.421428 -41.616884)
		(end 106.576368 -41.461944)
		(width 0.14224)
		(layer "In2.Cu")
		(net "M_G_DQ<44>")
	)
	(segment
		(start 105.966768 -40.445944)
		(end 106.121708 -40.291004)
		(width 0.14224)
		(layer "In2.Cu")
		(net "M_G_DQ<44>")
	)
	(segment
		(start 124.161042 -19.278854)
		(end 124.525024 -18.914872)
		(width 0.14224)
		(layer "In2.Cu")
		(net "M_G_DQ<44>")
	)
	(segment
		(start 124.525024 -21.344128)
		(end 124.173742 -20.992846)
		(width 0.14224)
		(layer "In2.Cu")
		(net "M_G_DQ<44>")
	)
	(segment
		(start 124.049536 -23.560278)
		(end 123.813824 -23.324566)
		(width 0.14224)
		(layer "In2.Cu")
		(net "M_G_DQ<44>")
	)
	(segment
		(start 109.914182 -56.399938)
		(end 109.418628 -55.733188)
		(width 0.0889)
		(layer "In2.Cu")
		(net "M_G_DQ<44>")
	)
	(segment
		(start 124.045218 -23.564596)
		(end 124.049536 -23.560278)
		(width 0.14224)
		(layer "In2.Cu")
		(net "M_G_DQ<44>")
	)
	(arc
		(start 109.402372 -55.704486)
		(mid 109.386628 -55.675984)
		(end 109.372654 -55.646574)
		(width 0.0889)
		(layer "In2.Cu")
		(net "M_G_DQ<44>")
	)
	(arc
		(start 109.372654 -55.646574)
		(mid 109.323992 -55.376596)
		(end 109.402372 -55.113682)
		(width 0.0889)
		(layer "In2.Cu")
		(net "M_G_DQ<44>")
	)
	(arc
		(start 109.402372 -55.113682)
		(mid 109.455905 -54.913784)
		(end 109.402372 -54.713886)
		(width 0.0889)
		(layer "In2.Cu")
		(net "M_G_DQ<44>")
	)
	(arc
		(start 109.391704 -54.695344)
		(mid 109.323105 -54.40771)
		(end 109.402372 -54.122828)
		(width 0.0889)
		(layer "In2.Cu")
		(net "M_G_DQ<44>")
	)
	(segment
		(start 113.919762 -57.390538)
		(end 113.348262 -57.390538)
		(width 0.1016)
		(layer "F.Cu")
		(net "M_G_DQ<43>")
	)
	(segment
		(start 131.699508 -15.423642)
		(end 131.699508 -16.687546)
		(width 0.1651)
		(layer "F.Cu")
		(net "M_G_DQ<43>")
	)
	(via
		(at 113.348262 -57.390538)
		(size 0.508)
		(drill 0.254)
		(layers "F.Cu" "B.Cu")
		(net "M_G_DQ<43>")
	)
	(via
		(at 132.549392 -22.279356)
		(size 0.508)
		(drill 0.254)
		(layers "F.Cu" "B.Cu")
		(net "M_G_DQ<43>")
	)
	(via
		(at 131.699508 -16.687546)
		(size 0.508)
		(drill 0.254)
		(layers "F.Cu" "B.Cu")
		(net "M_G_DQ<43>")
	)
	(segment
		(start 132.549392 -22.279356)
		(end 132.549392 -20.224242)
		(width 0.1651)
		(layer "B.Cu")
		(net "M_G_DQ<43>")
	)
	(segment
		(start 112.265968 -40.5892)
		(end 120.851168 -32.004)
		(width 0.14224)
		(layer "In2.Cu")
		(net "M_G_DQ<43>")
	)
	(segment
		(start 113.938812 -52.870862)
		(end 113.938812 -52.180998)
		(width 0.0889)
		(layer "In2.Cu")
		(net "M_G_DQ<43>")
	)
	(segment
		(start 112.955578 -50.04943)
		(end 111.701072 -48.794924)
		(width 0.0889)
		(layer "In2.Cu")
		(net "M_G_DQ<43>")
	)
	(segment
		(start 131.699508 -17.006062)
		(end 131.699508 -16.687546)
		(width 0.14224)
		(layer "In2.Cu")
		(net "M_G_DQ<43>")
	)
	(segment
		(start 113.348262 -57.052464)
		(end 113.41354 -56.987186)
		(width 0.0889)
		(layer "In2.Cu")
		(net "M_G_DQ<43>")
	)
	(segment
		(start 111.701072 -48.087534)
		(end 112.265968 -47.522638)
		(width 0.0889)
		(layer "In2.Cu")
		(net "M_G_DQ<43>")
	)
	(segment
		(start 132.020564 -22.808184)
		(end 132.549392 -22.279356)
		(width 0.14224)
		(layer "In2.Cu")
		(net "M_G_DQ<43>")
	)
	(segment
		(start 132.839968 -28.212796)
		(end 132.839968 -26.7462)
		(width 0.14224)
		(layer "In2.Cu")
		(net "M_G_DQ<43>")
	)
	(segment
		(start 132.807964 -26.714196)
		(end 132.807964 -23.970996)
		(width 0.14224)
		(layer "In2.Cu")
		(net "M_G_DQ<43>")
	)
	(segment
		(start 113.860072 -56.695086)
		(end 113.866422 -56.684418)
		(width 0.0889)
		(layer "In2.Cu")
		(net "M_G_DQ<43>")
	)
	(segment
		(start 132.600446 -17.653)
		(end 132.346446 -17.653)
		(width 0.14224)
		(layer "In2.Cu")
		(net "M_G_DQ<43>")
	)
	(segment
		(start 132.839968 -26.7462)
		(end 132.807964 -26.714196)
		(width 0.14224)
		(layer "In2.Cu")
		(net "M_G_DQ<43>")
	)
	(segment
		(start 133.057646 -18.1102)
		(end 132.600446 -17.653)
		(width 0.14224)
		(layer "In2.Cu")
		(net "M_G_DQ<43>")
	)
	(segment
		(start 113.860072 -55.704486)
		(end 113.866422 -55.693818)
		(width 0.0889)
		(layer "In2.Cu")
		(net "M_G_DQ<43>")
	)
	(segment
		(start 112.955578 -51.197764)
		(end 112.955578 -50.04943)
		(width 0.0889)
		(layer "In2.Cu")
		(net "M_G_DQ<43>")
	)
	(segment
		(start 113.806732 -55.018686)
		(end 113.806732 -53.002942)
		(width 0.0889)
		(layer "In2.Cu")
		(net "M_G_DQ<43>")
	)
	(segment
		(start 111.701072 -48.794924)
		(end 111.701072 -48.087534)
		(width 0.0889)
		(layer "In2.Cu")
		(net "M_G_DQ<43>")
	)
	(segment
		(start 113.348262 -57.390538)
		(end 113.348262 -57.052464)
		(width 0.0889)
		(layer "In2.Cu")
		(net "M_G_DQ<43>")
	)
	(segment
		(start 120.851168 -32.004)
		(end 129.048764 -32.004)
		(width 0.14224)
		(layer "In2.Cu")
		(net "M_G_DQ<43>")
	)
	(segment
		(start 113.938812 -52.180998)
		(end 112.955578 -51.197764)
		(width 0.0889)
		(layer "In2.Cu")
		(net "M_G_DQ<43>")
	)
	(segment
		(start 132.020564 -23.183596)
		(end 132.020564 -22.808184)
		(width 0.14224)
		(layer "In2.Cu")
		(net "M_G_DQ<43>")
	)
	(segment
		(start 132.807964 -23.970996)
		(end 132.020564 -23.183596)
		(width 0.14224)
		(layer "In2.Cu")
		(net "M_G_DQ<43>")
	)
	(segment
		(start 132.902198 -21.92655)
		(end 132.902198 -18.621248)
		(width 0.14224)
		(layer "In2.Cu")
		(net "M_G_DQ<43>")
	)
	(segment
		(start 113.860072 -55.113936)
		(end 113.806732 -55.018686)
		(width 0.0889)
		(layer "In2.Cu")
		(net "M_G_DQ<43>")
	)
	(segment
		(start 132.902198 -18.621248)
		(end 133.057646 -18.4658)
		(width 0.14224)
		(layer "In2.Cu")
		(net "M_G_DQ<43>")
	)
	(segment
		(start 129.048764 -32.004)
		(end 132.839968 -28.212796)
		(width 0.14224)
		(layer "In2.Cu")
		(net "M_G_DQ<43>")
	)
	(segment
		(start 112.265968 -47.522638)
		(end 112.265968 -40.5892)
		(width 0.14224)
		(layer "In2.Cu")
		(net "M_G_DQ<43>")
	)
	(segment
		(start 133.057646 -18.4658)
		(end 133.057646 -18.1102)
		(width 0.14224)
		(layer "In2.Cu")
		(net "M_G_DQ<43>")
	)
	(segment
		(start 113.855246 -55.713122)
		(end 113.860072 -55.704486)
		(width 0.0889)
		(layer "In2.Cu")
		(net "M_G_DQ<43>")
	)
	(segment
		(start 113.806732 -53.002942)
		(end 113.938812 -52.870862)
		(width 0.0889)
		(layer "In2.Cu")
		(net "M_G_DQ<43>")
	)
	(segment
		(start 132.346446 -17.653)
		(end 131.699508 -17.006062)
		(width 0.14224)
		(layer "In2.Cu")
		(net "M_G_DQ<43>")
	)
	(segment
		(start 132.549392 -22.279356)
		(end 132.902198 -21.92655)
		(width 0.14224)
		(layer "In2.Cu")
		(net "M_G_DQ<43>")
	)
	(arc
		(start 113.866422 -56.684418)
		(mid 113.93922 -56.393655)
		(end 113.860072 -56.104536)
		(width 0.0889)
		(layer "In2.Cu")
		(net "M_G_DQ<43>")
	)
	(arc
		(start 113.866422 -55.693818)
		(mid 113.93922 -55.403055)
		(end 113.860072 -55.113936)
		(width 0.0889)
		(layer "In2.Cu")
		(net "M_G_DQ<43>")
	)
	(arc
		(start 113.860072 -56.104536)
		(mid 113.806602 -55.909473)
		(end 113.855246 -55.713122)
		(width 0.0889)
		(layer "In2.Cu")
		(net "M_G_DQ<43>")
	)
	(arc
		(start 113.41354 -56.987186)
		(mid 113.671677 -56.894432)
		(end 113.860072 -56.695086)
		(width 0.0889)
		(layer "In2.Cu")
		(net "M_G_DQ<43>")
	)
	(segment
		(start 113.919762 -56.399938)
		(end 113.348262 -56.399938)
		(width 0.1016)
		(layer "F.Cu")
		(net "M_G_DQ<42>")
	)
	(segment
		(start 132.680964 -18.89506)
		(end 132.680964 -18.67154)
		(width 0.1651)
		(layer "F.Cu")
		(net "M_G_DQ<42>")
	)
	(segment
		(start 132.549392 -19.026632)
		(end 132.680964 -18.89506)
		(width 0.1651)
		(layer "F.Cu")
		(net "M_G_DQ<42>")
	)
	(segment
		(start 132.549392 -20.023582)
		(end 132.549392 -19.026632)
		(width 0.1651)
		(layer "F.Cu")
		(net "M_G_DQ<42>")
	)
	(segment
		(start 132.549392 -18.539968)
		(end 132.549392 -18.2626)
		(width 0.1651)
		(layer "F.Cu")
		(net "M_G_DQ<42>")
	)
	(segment
		(start 132.680964 -18.67154)
		(end 132.549392 -18.539968)
		(width 0.1651)
		(layer "F.Cu")
		(net "M_G_DQ<42>")
	)
	(via
		(at 132.549392 -18.2626)
		(size 0.508)
		(drill 0.254)
		(layers "F.Cu" "B.Cu")
		(net "M_G_DQ<42>")
	)
	(via
		(at 113.348262 -56.399938)
		(size 0.508)
		(drill 0.254)
		(layers "F.Cu" "B.Cu")
		(net "M_G_DQ<42>")
	)
	(via
		(at 131.699508 -23.560278)
		(size 0.508)
		(drill 0.254)
		(layers "F.Cu" "B.Cu")
		(net "M_G_DQ<42>")
	)
	(segment
		(start 131.699508 -23.560278)
		(end 131.699508 -24.824182)
		(width 0.1651)
		(layer "B.Cu")
		(net "M_G_DQ<42>")
	)
	(segment
		(start 132.151374 -18.965672)
		(end 132.151374 -18.660618)
		(width 0.14224)
		(layer "In2.Cu")
		(net "M_G_DQ<42>")
	)
	(segment
		(start 113.616232 -52.923694)
		(end 113.748312 -52.791614)
		(width 0.0889)
		(layer "In2.Cu")
		(net "M_G_DQ<42>")
	)
	(segment
		(start 113.748312 -52.791614)
		(end 113.748312 -52.260754)
		(width 0.0889)
		(layer "In2.Cu")
		(net "M_G_DQ<42>")
	)
	(segment
		(start 131.195318 -28.959048)
		(end 131.195318 -28.301442)
		(width 0.14224)
		(layer "In2.Cu")
		(net "M_G_DQ<42>")
	)
	(segment
		(start 131.699508 -23.560278)
		(end 131.414774 -23.275544)
		(width 0.14224)
		(layer "In2.Cu")
		(net "M_G_DQ<42>")
	)
	(segment
		(start 132.111242 -20.25015)
		(end 132.111242 -19.964146)
		(width 0.14224)
		(layer "In2.Cu")
		(net "M_G_DQ<42>")
	)
	(segment
		(start 131.392168 -27.326336)
		(end 131.743704 -26.9748)
		(width 0.14224)
		(layer "In2.Cu")
		(net "M_G_DQ<42>")
	)
	(segment
		(start 131.392168 -24.2824)
		(end 131.392168 -23.867618)
		(width 0.14224)
		(layer "In2.Cu")
		(net "M_G_DQ<42>")
	)
	(segment
		(start 132.151374 -18.660618)
		(end 132.549392 -18.2626)
		(width 0.14224)
		(layer "In2.Cu")
		(net "M_G_DQ<42>")
	)
	(segment
		(start 132.172964 -26.702004)
		(end 132.172964 -24.605996)
		(width 0.14224)
		(layer "In2.Cu")
		(net "M_G_DQ<42>")
	)
	(segment
		(start 131.900168 -26.9748)
		(end 132.172964 -26.702004)
		(width 0.14224)
		(layer "In2.Cu")
		(net "M_G_DQ<42>")
	)
	(segment
		(start 111.510572 -48.873918)
		(end 111.510572 -47.669196)
		(width 0.0889)
		(layer "In2.Cu")
		(net "M_G_DQ<42>")
	)
	(segment
		(start 131.195318 -28.301442)
		(end 131.392168 -28.104592)
		(width 0.14224)
		(layer "In2.Cu")
		(net "M_G_DQ<42>")
	)
	(segment
		(start 131.806442 -19.659346)
		(end 131.806442 -19.310604)
		(width 0.14224)
		(layer "In2.Cu")
		(net "M_G_DQ<42>")
	)
	(segment
		(start 131.392168 -23.867618)
		(end 131.699508 -23.560278)
		(width 0.14224)
		(layer "In2.Cu")
		(net "M_G_DQ<42>")
	)
	(segment
		(start 132.172964 -24.605996)
		(end 132.001768 -24.4348)
		(width 0.14224)
		(layer "In2.Cu")
		(net "M_G_DQ<42>")
	)
	(segment
		(start 132.263642 -21.680932)
		(end 132.263642 -21.4122)
		(width 0.14224)
		(layer "In2.Cu")
		(net "M_G_DQ<42>")
	)
	(segment
		(start 112.765078 -50.128424)
		(end 111.510572 -48.873918)
		(width 0.0889)
		(layer "In2.Cu")
		(net "M_G_DQ<42>")
	)
	(segment
		(start 113.348262 -56.399938)
		(end 113.348262 -56.738012)
		(width 0.0889)
		(layer "In2.Cu")
		(net "M_G_DQ<42>")
	)
	(segment
		(start 120.495568 -31.2928)
		(end 128.861566 -31.2928)
		(width 0.14224)
		(layer "In2.Cu")
		(net "M_G_DQ<42>")
	)
	(segment
		(start 131.806442 -20.955)
		(end 131.806442 -20.55495)
		(width 0.14224)
		(layer "In2.Cu")
		(net "M_G_DQ<42>")
	)
	(segment
		(start 131.414774 -23.275544)
		(end 131.414774 -22.5298)
		(width 0.14224)
		(layer "In2.Cu")
		(net "M_G_DQ<42>")
	)
	(segment
		(start 132.111242 -19.964146)
		(end 131.806442 -19.659346)
		(width 0.14224)
		(layer "In2.Cu")
		(net "M_G_DQ<42>")
	)
	(segment
		(start 113.616232 -55.072788)
		(end 113.616232 -52.923694)
		(width 0.0889)
		(layer "In2.Cu")
		(net "M_G_DQ<42>")
	)
	(segment
		(start 131.806442 -20.55495)
		(end 132.111242 -20.25015)
		(width 0.14224)
		(layer "In2.Cu")
		(net "M_G_DQ<42>")
	)
	(segment
		(start 113.694972 -55.209186)
		(end 113.616232 -55.072788)
		(width 0.0889)
		(layer "In2.Cu")
		(net "M_G_DQ<42>")
	)
	(segment
		(start 131.392168 -28.104592)
		(end 131.392168 -27.326336)
		(width 0.14224)
		(layer "In2.Cu")
		(net "M_G_DQ<42>")
	)
	(segment
		(start 111.783368 -47.3964)
		(end 111.783368 -40.005)
		(width 0.14224)
		(layer "In2.Cu")
		(net "M_G_DQ<42>")
	)
	(segment
		(start 132.263642 -21.4122)
		(end 131.806442 -20.955)
		(width 0.14224)
		(layer "In2.Cu")
		(net "M_G_DQ<42>")
	)
	(segment
		(start 111.783368 -40.005)
		(end 120.495568 -31.2928)
		(width 0.14224)
		(layer "In2.Cu")
		(net "M_G_DQ<42>")
	)
	(segment
		(start 131.743704 -26.9748)
		(end 131.900168 -26.9748)
		(width 0.14224)
		(layer "In2.Cu")
		(net "M_G_DQ<42>")
	)
	(segment
		(start 132.001768 -24.4348)
		(end 131.544568 -24.4348)
		(width 0.14224)
		(layer "In2.Cu")
		(net "M_G_DQ<42>")
	)
	(segment
		(start 113.748312 -52.260754)
		(end 112.765078 -51.27752)
		(width 0.0889)
		(layer "In2.Cu")
		(net "M_G_DQ<42>")
	)
	(segment
		(start 128.861566 -31.2928)
		(end 131.195318 -28.959048)
		(width 0.14224)
		(layer "In2.Cu")
		(net "M_G_DQ<42>")
	)
	(segment
		(start 131.544568 -24.4348)
		(end 131.392168 -24.2824)
		(width 0.14224)
		(layer "In2.Cu")
		(net "M_G_DQ<42>")
	)
	(segment
		(start 111.510572 -47.669196)
		(end 111.783368 -47.3964)
		(width 0.0889)
		(layer "In2.Cu")
		(net "M_G_DQ<42>")
	)
	(segment
		(start 113.348262 -56.738012)
		(end 113.406174 -56.795924)
		(width 0.0889)
		(layer "In2.Cu")
		(net "M_G_DQ<42>")
	)
	(segment
		(start 131.806442 -19.310604)
		(end 132.151374 -18.965672)
		(width 0.14224)
		(layer "In2.Cu")
		(net "M_G_DQ<42>")
	)
	(segment
		(start 131.414774 -22.5298)
		(end 132.263642 -21.680932)
		(width 0.14224)
		(layer "In2.Cu")
		(net "M_G_DQ<42>")
	)
	(segment
		(start 112.765078 -51.27752)
		(end 112.765078 -50.128424)
		(width 0.0889)
		(layer "In2.Cu")
		(net "M_G_DQ<42>")
	)
	(arc
		(start 113.406174 -56.795924)
		(mid 113.708443 -56.574375)
		(end 113.694972 -56.199786)
		(width 0.0889)
		(layer "In2.Cu")
		(net "M_G_DQ<42>")
	)
	(arc
		(start 113.688622 -55.619904)
		(mid 113.694099 -55.610188)
		(end 113.699798 -55.6006)
		(width 0.0889)
		(layer "In2.Cu")
		(net "M_G_DQ<42>")
	)
	(arc
		(start 113.694972 -56.199786)
		(mid 113.61575 -55.910668)
		(end 113.688622 -55.619904)
		(width 0.0889)
		(layer "In2.Cu")
		(net "M_G_DQ<42>")
	)
	(arc
		(start 113.699798 -55.6006)
		(mid 113.748553 -55.404248)
		(end 113.694972 -55.209186)
		(width 0.0889)
		(layer "In2.Cu")
		(net "M_G_DQ<42>")
	)
	(segment
		(start 110.772702 -57.885584)
		(end 111.344202 -57.885584)
		(width 0.1016)
		(layer "F.Cu")
		(net "M_G_DQ<41>")
	)
	(segment
		(start 125.749558 -15.423642)
		(end 125.749558 -16.687546)
		(width 0.1651)
		(layer "F.Cu")
		(net "M_G_DQ<41>")
	)
	(via
		(at 125.749558 -16.687546)
		(size 0.508)
		(drill 0.254)
		(layers "F.Cu" "B.Cu")
		(net "M_G_DQ<41>")
	)
	(via
		(at 110.772702 -57.885584)
		(size 0.508)
		(drill 0.254)
		(layers "F.Cu" "B.Cu")
		(net "M_G_DQ<41>")
	)
	(via
		(at 126.421642 -22.279356)
		(size 0.508)
		(drill 0.254)
		(layers "F.Cu" "B.Cu")
		(net "M_G_DQ<41>")
	)
	(segment
		(start 126.421642 -21.776182)
		(end 126.421642 -22.279356)
		(width 0.1651)
		(layer "B.Cu")
		(net "M_G_DQ<41>")
	)
	(segment
		(start 126.599442 -21.598382)
		(end 126.421642 -21.776182)
		(width 0.1651)
		(layer "B.Cu")
		(net "M_G_DQ<41>")
	)
	(segment
		(start 126.599442 -20.224242)
		(end 126.599442 -21.598382)
		(width 0.1651)
		(layer "B.Cu")
		(net "M_G_DQ<41>")
	)
	(segment
		(start 125.749558 -17.226534)
		(end 125.749558 -16.687546)
		(width 0.14224)
		(layer "In2.Cu")
		(net "M_G_DQ<41>")
	)
	(segment
		(start 108.354368 -46.989746)
		(end 108.354368 -35.7632)
		(width 0.14224)
		(layer "In2.Cu")
		(net "M_G_DQ<41>")
	)
	(segment
		(start 116.44376 -27.673808)
		(end 116.44376 -27.45486)
		(width 0.14224)
		(layer "In2.Cu")
		(net "M_G_DQ<41>")
	)
	(segment
		(start 123.56211 -24.9682)
		(end 125.931168 -24.9682)
		(width 0.14224)
		(layer "In2.Cu")
		(net "M_G_DQ<41>")
	)
	(segment
		(start 110.772702 -57.885584)
		(end 110.425992 -57.095136)
		(width 0.0889)
		(layer "In2.Cu")
		(net "M_G_DQ<41>")
	)
	(segment
		(start 116.091208 -27.102308)
		(end 116.091208 -26.88336)
		(width 0.14224)
		(layer "In2.Cu")
		(net "M_G_DQ<41>")
	)
	(segment
		(start 126.795784 -21.905214)
		(end 126.795784 -18.571464)
		(width 0.14224)
		(layer "In2.Cu")
		(net "M_G_DQ<41>")
	)
	(segment
		(start 114.951256 -28.861512)
		(end 115.256056 -28.861512)
		(width 0.14224)
		(layer "In2.Cu")
		(net "M_G_DQ<41>")
	)
	(segment
		(start 110.425484 -54.12359)
		(end 110.336584 -53.969412)
		(width 0.0889)
		(layer "In2.Cu")
		(net "M_G_DQ<41>")
	)
	(segment
		(start 126.254764 -23.412196)
		(end 125.937264 -23.094696)
		(width 0.14224)
		(layer "In2.Cu")
		(net "M_G_DQ<41>")
	)
	(segment
		(start 109.631226 -51.435)
		(end 108.515404 -50.319178)
		(width 0.0889)
		(layer "In2.Cu")
		(net "M_G_DQ<41>")
	)
	(segment
		(start 109.631226 -52.545234)
		(end 109.631226 -51.435)
		(width 0.0889)
		(layer "In2.Cu")
		(net "M_G_DQ<41>")
	)
	(segment
		(start 126.795784 -18.571464)
		(end 126.952248 -18.415)
		(width 0.14224)
		(layer "In2.Cu")
		(net "M_G_DQ<41>")
	)
	(segment
		(start 126.254764 -24.644604)
		(end 126.254764 -23.412196)
		(width 0.14224)
		(layer "In2.Cu")
		(net "M_G_DQ<41>")
	)
	(segment
		(start 108.354368 -35.7632)
		(end 114.568224 -29.549344)
		(width 0.14224)
		(layer "In2.Cu")
		(net "M_G_DQ<41>")
	)
	(segment
		(start 117.131592 -26.985976)
		(end 117.472968 -26.6446)
		(width 0.14224)
		(layer "In2.Cu")
		(net "M_G_DQ<41>")
	)
	(segment
		(start 115.256056 -28.861512)
		(end 116.44376 -27.673808)
		(width 0.14224)
		(layer "In2.Cu")
		(net "M_G_DQ<41>")
	)
	(segment
		(start 110.336584 -53.969412)
		(end 110.336584 -53.250592)
		(width 0.0889)
		(layer "In2.Cu")
		(net "M_G_DQ<41>")
	)
	(segment
		(start 110.425992 -54.123336)
		(end 110.425484 -54.12359)
		(width 0.0889)
		(layer "In2.Cu")
		(net "M_G_DQ<41>")
	)
	(segment
		(start 110.336584 -53.250592)
		(end 109.631226 -52.545234)
		(width 0.0889)
		(layer "In2.Cu")
		(net "M_G_DQ<41>")
	)
	(segment
		(start 116.341144 -26.633424)
		(end 116.560092 -26.633424)
		(width 0.14224)
		(layer "In2.Cu")
		(net "M_G_DQ<41>")
	)
	(segment
		(start 126.952248 -18.415)
		(end 126.952248 -18.073624)
		(width 0.14224)
		(layer "In2.Cu")
		(net "M_G_DQ<41>")
	)
	(segment
		(start 125.931168 -24.9682)
		(end 126.254764 -24.644604)
		(width 0.14224)
		(layer "In2.Cu")
		(net "M_G_DQ<41>")
	)
	(segment
		(start 125.937264 -23.094696)
		(end 125.937264 -22.763734)
		(width 0.14224)
		(layer "In2.Cu")
		(net "M_G_DQ<41>")
	)
	(segment
		(start 126.421642 -22.279356)
		(end 126.795784 -21.905214)
		(width 0.14224)
		(layer "In2.Cu")
		(net "M_G_DQ<41>")
	)
	(segment
		(start 117.472968 -26.6446)
		(end 121.88571 -26.6446)
		(width 0.14224)
		(layer "In2.Cu")
		(net "M_G_DQ<41>")
	)
	(segment
		(start 116.091208 -26.88336)
		(end 116.341144 -26.633424)
		(width 0.14224)
		(layer "In2.Cu")
		(net "M_G_DQ<41>")
	)
	(segment
		(start 116.912644 -26.985976)
		(end 117.131592 -26.985976)
		(width 0.14224)
		(layer "In2.Cu")
		(net "M_G_DQ<41>")
	)
	(segment
		(start 108.515404 -47.150782)
		(end 108.354368 -46.989746)
		(width 0.0889)
		(layer "In2.Cu")
		(net "M_G_DQ<41>")
	)
	(segment
		(start 116.44376 -27.45486)
		(end 116.091208 -27.102308)
		(width 0.14224)
		(layer "In2.Cu")
		(net "M_G_DQ<41>")
	)
	(segment
		(start 116.560092 -26.633424)
		(end 116.912644 -26.985976)
		(width 0.14224)
		(layer "In2.Cu")
		(net "M_G_DQ<41>")
	)
	(segment
		(start 126.226824 -17.7038)
		(end 125.749558 -17.226534)
		(width 0.14224)
		(layer "In2.Cu")
		(net "M_G_DQ<41>")
	)
	(segment
		(start 114.568224 -29.549344)
		(end 114.568224 -29.244544)
		(width 0.14224)
		(layer "In2.Cu")
		(net "M_G_DQ<41>")
	)
	(segment
		(start 121.88571 -26.6446)
		(end 123.56211 -24.9682)
		(width 0.14224)
		(layer "In2.Cu")
		(net "M_G_DQ<41>")
	)
	(segment
		(start 126.582424 -17.7038)
		(end 126.226824 -17.7038)
		(width 0.14224)
		(layer "In2.Cu")
		(net "M_G_DQ<41>")
	)
	(segment
		(start 126.952248 -18.073624)
		(end 126.582424 -17.7038)
		(width 0.14224)
		(layer "In2.Cu")
		(net "M_G_DQ<41>")
	)
	(segment
		(start 114.568224 -29.244544)
		(end 114.951256 -28.861512)
		(width 0.14224)
		(layer "In2.Cu")
		(net "M_G_DQ<41>")
	)
	(segment
		(start 108.515404 -50.319178)
		(end 108.515404 -47.150782)
		(width 0.0889)
		(layer "In2.Cu")
		(net "M_G_DQ<41>")
	)
	(segment
		(start 125.937264 -22.763734)
		(end 126.421642 -22.279356)
		(width 0.14224)
		(layer "In2.Cu")
		(net "M_G_DQ<41>")
	)
	(arc
		(start 110.619286 -56.525668)
		(mid 110.881527 -56.370369)
		(end 111.090202 -56.148224)
		(width 0.0889)
		(layer "In2.Cu")
		(net "M_G_DQ<41>")
	)
	(arc
		(start 110.918498 -55.53202)
		(mid 110.635915 -55.365767)
		(end 110.425992 -55.113936)
		(width 0.0889)
		(layer "In2.Cu")
		(net "M_G_DQ<41>")
	)
	(arc
		(start 110.425992 -55.113936)
		(mid 110.372493 -54.914038)
		(end 110.425992 -54.71414)
		(width 0.0889)
		(layer "In2.Cu")
		(net "M_G_DQ<41>")
	)
	(arc
		(start 110.425992 -57.095136)
		(mid 110.393721 -56.766629)
		(end 110.619286 -56.525668)
		(width 0.0889)
		(layer "In2.Cu")
		(net "M_G_DQ<41>")
	)
	(arc
		(start 111.090202 -56.148224)
		(mid 111.158197 -55.79724)
		(end 110.918498 -55.53202)
		(width 0.0889)
		(layer "In2.Cu")
		(net "M_G_DQ<41>")
	)
	(arc
		(start 110.425992 -54.71414)
		(mid 110.505055 -54.418738)
		(end 110.425992 -54.123336)
		(width 0.0889)
		(layer "In2.Cu")
		(net "M_G_DQ<41>")
	)
	(segment
		(start 111.344202 -55.904384)
		(end 110.772702 -55.904384)
		(width 0.1016)
		(layer "F.Cu")
		(net "M_G_DQ<40>")
	)
	(segment
		(start 126.599442 -20.023582)
		(end 126.51867 -19.177)
		(width 0.1651)
		(layer "F.Cu")
		(net "M_G_DQ<40>")
	)
	(segment
		(start 126.51867 -19.177)
		(end 126.421642 -18.161)
		(width 0.1651)
		(layer "F.Cu")
		(net "M_G_DQ<40>")
	)
	(via
		(at 125.749558 -23.560278)
		(size 0.508)
		(drill 0.254)
		(layers "F.Cu" "B.Cu")
		(net "M_G_DQ<40>")
	)
	(via
		(at 126.421642 -18.161)
		(size 0.508)
		(drill 0.254)
		(layers "F.Cu" "B.Cu")
		(net "M_G_DQ<40>")
	)
	(via
		(at 110.772702 -55.904384)
		(size 0.508)
		(drill 0.254)
		(layers "F.Cu" "B.Cu")
		(net "M_G_DQ<40>")
	)
	(segment
		(start 125.749558 -23.560278)
		(end 125.749558 -24.824182)
		(width 0.1651)
		(layer "B.Cu")
		(net "M_G_DQ<40>")
	)
	(segment
		(start 111.366554 -30.201362)
		(end 111.731806 -30.566614)
		(width 0.14224)
		(layer "In2.Cu")
		(net "M_G_DQ<40>")
	)
	(segment
		(start 110.260892 -54.218586)
		(end 110.146084 -54.019704)
		(width 0.0889)
		(layer "In2.Cu")
		(net "M_G_DQ<40>")
	)
	(segment
		(start 111.950754 -30.566614)
		(end 112.20069 -30.316678)
		(width 0.14224)
		(layer "In2.Cu")
		(net "M_G_DQ<40>")
	)
	(segment
		(start 111.835438 -29.732478)
		(end 111.835438 -29.51353)
		(width 0.14224)
		(layer "In2.Cu")
		(net "M_G_DQ<40>")
	)
	(segment
		(start 125.749558 -23.560278)
		(end 125.464824 -23.275544)
		(width 0.14224)
		(layer "In2.Cu")
		(net "M_G_DQ<40>")
	)
	(segment
		(start 126.201424 -18.965672)
		(end 126.201424 -18.381218)
		(width 0.14224)
		(layer "In2.Cu")
		(net "M_G_DQ<40>")
	)
	(segment
		(start 125.786642 -19.380454)
		(end 126.201424 -18.965672)
		(width 0.14224)
		(layer "In2.Cu")
		(net "M_G_DQ<40>")
	)
	(segment
		(start 125.464824 -22.5298)
		(end 126.201424 -21.7932)
		(width 0.14224)
		(layer "In2.Cu")
		(net "M_G_DQ<40>")
	)
	(segment
		(start 125.786642 -19.7104)
		(end 125.786642 -19.380454)
		(width 0.14224)
		(layer "In2.Cu")
		(net "M_G_DQ<40>")
	)
	(segment
		(start 108.324904 -48.074326)
		(end 108.241592 -47.991014)
		(width 0.0889)
		(layer "In2.Cu")
		(net "M_G_DQ<40>")
	)
	(segment
		(start 109.491018 -32.076898)
		(end 109.85627 -32.44215)
		(width 0.14224)
		(layer "In2.Cu")
		(net "M_G_DQ<40>")
	)
	(segment
		(start 110.325154 -32.192214)
		(end 110.325154 -31.973266)
		(width 0.14224)
		(layer "In2.Cu")
		(net "M_G_DQ<40>")
	)
	(segment
		(start 109.440726 -51.513994)
		(end 108.324904 -50.398172)
		(width 0.0889)
		(layer "In2.Cu")
		(net "M_G_DQ<40>")
	)
	(segment
		(start 112.20069 -30.09773)
		(end 111.835438 -29.732478)
		(width 0.14224)
		(layer "In2.Cu")
		(net "M_G_DQ<40>")
	)
	(segment
		(start 111.262922 -31.254446)
		(end 111.262922 -31.035498)
		(width 0.14224)
		(layer "In2.Cu")
		(net "M_G_DQ<40>")
	)
	(segment
		(start 109.440726 -52.624228)
		(end 109.440726 -51.513994)
		(width 0.0889)
		(layer "In2.Cu")
		(net "M_G_DQ<40>")
	)
	(segment
		(start 111.262922 -31.035498)
		(end 110.89767 -30.670246)
		(width 0.14224)
		(layer "In2.Cu")
		(net "M_G_DQ<40>")
	)
	(segment
		(start 109.959902 -31.608014)
		(end 109.959902 -31.389066)
		(width 0.14224)
		(layer "In2.Cu")
		(net "M_G_DQ<40>")
	)
	(segment
		(start 122.951748 -24.931878)
		(end 123.37923 -24.504396)
		(width 0.14224)
		(layer "In2.Cu")
		(net "M_G_DQ<40>")
	)
	(segment
		(start 126.129542 -20.2819)
		(end 126.129542 -20.0533)
		(width 0.14224)
		(layer "In2.Cu")
		(net "M_G_DQ<40>")
	)
	(segment
		(start 110.89767 -30.451298)
		(end 111.147606 -30.201362)
		(width 0.14224)
		(layer "In2.Cu")
		(net "M_G_DQ<40>")
	)
	(segment
		(start 111.731806 -30.566614)
		(end 111.950754 -30.566614)
		(width 0.14224)
		(layer "In2.Cu")
		(net "M_G_DQ<40>")
	)
	(segment
		(start 121.800112 -25.8318)
		(end 122.700034 -24.931878)
		(width 0.14224)
		(layer "In2.Cu")
		(net "M_G_DQ<40>")
	)
	(segment
		(start 108.241592 -47.436024)
		(end 107.871768 -47.0662)
		(width 0.0889)
		(layer "In2.Cu")
		(net "M_G_DQ<40>")
	)
	(segment
		(start 111.012986 -31.504382)
		(end 111.262922 -31.254446)
		(width 0.14224)
		(layer "In2.Cu")
		(net "M_G_DQ<40>")
	)
	(segment
		(start 123.37923 -24.504396)
		(end 125.505972 -24.504396)
		(width 0.14224)
		(layer "In2.Cu")
		(net "M_G_DQ<40>")
	)
	(segment
		(start 125.505972 -24.504396)
		(end 125.749558 -24.26081)
		(width 0.14224)
		(layer "In2.Cu")
		(net "M_G_DQ<40>")
	)
	(segment
		(start 125.464824 -23.275544)
		(end 125.464824 -22.5298)
		(width 0.14224)
		(layer "In2.Cu")
		(net "M_G_DQ<40>")
	)
	(segment
		(start 108.241592 -47.991014)
		(end 108.241592 -47.436024)
		(width 0.0889)
		(layer "In2.Cu")
		(net "M_G_DQ<40>")
	)
	(segment
		(start 126.201424 -21.7932)
		(end 126.201424 -21.293328)
		(width 0.14224)
		(layer "In2.Cu")
		(net "M_G_DQ<40>")
	)
	(segment
		(start 126.201424 -18.381218)
		(end 126.421642 -18.161)
		(width 0.14224)
		(layer "In2.Cu")
		(net "M_G_DQ<40>")
	)
	(segment
		(start 122.700034 -24.931878)
		(end 122.951748 -24.931878)
		(width 0.14224)
		(layer "In2.Cu")
		(net "M_G_DQ<40>")
	)
	(segment
		(start 110.428786 -31.13913)
		(end 110.794038 -31.504382)
		(width 0.14224)
		(layer "In2.Cu")
		(net "M_G_DQ<40>")
	)
	(segment
		(start 109.959902 -31.389066)
		(end 110.209838 -31.13913)
		(width 0.14224)
		(layer "In2.Cu")
		(net "M_G_DQ<40>")
	)
	(segment
		(start 110.772702 -55.904384)
		(end 110.730538 -55.85968)
		(width 0.0889)
		(layer "In2.Cu")
		(net "M_G_DQ<40>")
	)
	(segment
		(start 110.794038 -31.504382)
		(end 111.012986 -31.504382)
		(width 0.14224)
		(layer "In2.Cu")
		(net "M_G_DQ<40>")
	)
	(segment
		(start 115.517168 -25.8318)
		(end 121.800112 -25.8318)
		(width 0.14224)
		(layer "In2.Cu")
		(net "M_G_DQ<40>")
	)
	(segment
		(start 107.871768 -47.0662)
		(end 107.871768 -33.4772)
		(width 0.14224)
		(layer "In2.Cu")
		(net "M_G_DQ<40>")
	)
	(segment
		(start 111.835438 -29.51353)
		(end 115.517168 -25.8318)
		(width 0.14224)
		(layer "In2.Cu")
		(net "M_G_DQ<40>")
	)
	(segment
		(start 108.324904 -50.398172)
		(end 108.324904 -48.074326)
		(width 0.0889)
		(layer "In2.Cu")
		(net "M_G_DQ<40>")
	)
	(segment
		(start 110.264956 -55.216552)
		(end 110.260892 -55.20944)
		(width 0.0889)
		(layer "In2.Cu")
		(net "M_G_DQ<40>")
	)
	(segment
		(start 125.812042 -20.5994)
		(end 126.129542 -20.2819)
		(width 0.14224)
		(layer "In2.Cu")
		(net "M_G_DQ<40>")
	)
	(segment
		(start 111.147606 -30.201362)
		(end 111.366554 -30.201362)
		(width 0.14224)
		(layer "In2.Cu")
		(net "M_G_DQ<40>")
	)
	(segment
		(start 126.201424 -21.293328)
		(end 125.812042 -20.903946)
		(width 0.14224)
		(layer "In2.Cu")
		(net "M_G_DQ<40>")
	)
	(segment
		(start 109.85627 -32.44215)
		(end 110.075218 -32.44215)
		(width 0.14224)
		(layer "In2.Cu")
		(net "M_G_DQ<40>")
	)
	(segment
		(start 107.871768 -33.4772)
		(end 109.27207 -32.076898)
		(width 0.14224)
		(layer "In2.Cu")
		(net "M_G_DQ<40>")
	)
	(segment
		(start 110.146084 -54.019704)
		(end 110.146084 -53.329586)
		(width 0.0889)
		(layer "In2.Cu")
		(net "M_G_DQ<40>")
	)
	(segment
		(start 125.812042 -20.903946)
		(end 125.812042 -20.5994)
		(width 0.14224)
		(layer "In2.Cu")
		(net "M_G_DQ<40>")
	)
	(segment
		(start 110.325154 -31.973266)
		(end 109.959902 -31.608014)
		(width 0.14224)
		(layer "In2.Cu")
		(net "M_G_DQ<40>")
	)
	(segment
		(start 125.749558 -24.26081)
		(end 125.749558 -23.560278)
		(width 0.14224)
		(layer "In2.Cu")
		(net "M_G_DQ<40>")
	)
	(segment
		(start 126.129542 -20.0533)
		(end 125.786642 -19.7104)
		(width 0.14224)
		(layer "In2.Cu")
		(net "M_G_DQ<40>")
	)
	(segment
		(start 110.89767 -30.670246)
		(end 110.89767 -30.451298)
		(width 0.14224)
		(layer "In2.Cu")
		(net "M_G_DQ<40>")
	)
	(segment
		(start 112.20069 -30.316678)
		(end 112.20069 -30.09773)
		(width 0.14224)
		(layer "In2.Cu")
		(net "M_G_DQ<40>")
	)
	(segment
		(start 110.146084 -53.329586)
		(end 109.440726 -52.624228)
		(width 0.0889)
		(layer "In2.Cu")
		(net "M_G_DQ<40>")
	)
	(segment
		(start 109.27207 -32.076898)
		(end 109.491018 -32.076898)
		(width 0.14224)
		(layer "In2.Cu")
		(net "M_G_DQ<40>")
	)
	(segment
		(start 110.075218 -32.44215)
		(end 110.325154 -32.192214)
		(width 0.14224)
		(layer "In2.Cu")
		(net "M_G_DQ<40>")
	)
	(segment
		(start 110.209838 -31.13913)
		(end 110.428786 -31.13913)
		(width 0.14224)
		(layer "In2.Cu")
		(net "M_G_DQ<40>")
	)
	(arc
		(start 110.260892 -54.618636)
		(mid 110.314425 -54.418628)
		(end 110.260892 -54.218586)
		(width 0.0889)
		(layer "In2.Cu")
		(net "M_G_DQ<40>")
	)
	(arc
		(start 110.730538 -55.85968)
		(mid 110.481171 -55.550116)
		(end 110.264956 -55.216552)
		(width 0.0889)
		(layer "In2.Cu")
		(net "M_G_DQ<40>")
	)
	(arc
		(start 110.260892 -55.20944)
		(mid 110.181761 -54.914038)
		(end 110.260892 -54.618636)
		(width 0.0889)
		(layer "In2.Cu")
		(net "M_G_DQ<40>")
	)
	(segment
		(start 39.049452 -15.423642)
		(end 39.049452 -16.687546)
		(width 0.1651)
		(layer "F.Cu")
		(net "M_G_DQ<3>")
	)
	(segment
		(start 69.466206 -61.53404)
		(end 68.894706 -61.53404)
		(width 0.1016)
		(layer "F.Cu")
		(net "M_G_DQ<3>")
	)
	(via
		(at 39.049452 -16.687546)
		(size 0.508)
		(drill 0.254)
		(layers "F.Cu" "B.Cu")
		(net "M_G_DQ<3>")
	)
	(via
		(at 68.894706 -61.53404)
		(size 0.508)
		(drill 0.254)
		(layers "F.Cu" "B.Cu")
		(net "M_G_DQ<3>")
	)
	(via
		(at 39.899336 -22.279356)
		(size 0.508)
		(drill 0.254)
		(layers "F.Cu" "B.Cu")
		(net "M_G_DQ<3>")
	)
	(segment
		(start 39.899336 -22.279356)
		(end 39.899336 -20.224242)
		(width 0.1651)
		(layer "B.Cu")
		(net "M_G_DQ<3>")
	)
	(segment
		(start 39.418768 -22.759924)
		(end 39.418768 -23.1902)
		(width 0.14224)
		(layer "In2.Cu")
		(net "M_G_DQ<3>")
	)
	(segment
		(start 43.252136 -33.745424)
		(end 43.556936 -33.745424)
		(width 0.14224)
		(layer "In2.Cu")
		(net "M_G_DQ<3>")
	)
	(segment
		(start 43.556936 -33.745424)
		(end 43.760136 -33.948624)
		(width 0.14224)
		(layer "In2.Cu")
		(net "M_G_DQ<3>")
	)
	(segment
		(start 65.504568 -61.000386)
		(end 67.300348 -61.000386)
		(width 0.0889)
		(layer "In2.Cu")
		(net "M_G_DQ<3>")
	)
	(segment
		(start 42.337736 -25.093168)
		(end 42.337736 -37.809424)
		(width 0.14224)
		(layer "In2.Cu")
		(net "M_G_DQ<3>")
	)
	(segment
		(start 42.845736 -38.012624)
		(end 43.048936 -37.809424)
		(width 0.14224)
		(layer "In2.Cu")
		(net "M_G_DQ<3>")
	)
	(segment
		(start 42.540936 -38.012624)
		(end 42.845736 -38.012624)
		(width 0.14224)
		(layer "In2.Cu")
		(net "M_G_DQ<3>")
	)
	(segment
		(start 39.899336 -22.279356)
		(end 39.418768 -22.759924)
		(width 0.14224)
		(layer "In2.Cu")
		(net "M_G_DQ<3>")
	)
	(segment
		(start 39.36619 -17.3228)
		(end 39.69639 -17.653)
		(width 0.14224)
		(layer "In2.Cu")
		(net "M_G_DQ<3>")
	)
	(segment
		(start 40.587168 -24.3586)
		(end 41.603168 -24.3586)
		(width 0.14224)
		(layer "In2.Cu")
		(net "M_G_DQ<3>")
	)
	(segment
		(start 39.049452 -16.687546)
		(end 39.36619 -17.004284)
		(width 0.14224)
		(layer "In2.Cu")
		(net "M_G_DQ<3>")
	)
	(segment
		(start 43.048936 -33.948624)
		(end 43.252136 -33.745424)
		(width 0.14224)
		(layer "In2.Cu")
		(net "M_G_DQ<3>")
	)
	(segment
		(start 42.337736 -37.809424)
		(end 42.540936 -38.012624)
		(width 0.14224)
		(layer "In2.Cu")
		(net "M_G_DQ<3>")
	)
	(segment
		(start 40.40759 -18.1102)
		(end 40.40759 -18.4658)
		(width 0.14224)
		(layer "In2.Cu")
		(net "M_G_DQ<3>")
	)
	(segment
		(start 43.760136 -39.593774)
		(end 65.166748 -61.000386)
		(width 0.14224)
		(layer "In2.Cu")
		(net "M_G_DQ<3>")
	)
	(segment
		(start 67.300348 -61.000386)
		(end 67.834002 -61.53404)
		(width 0.0889)
		(layer "In2.Cu")
		(net "M_G_DQ<3>")
	)
	(segment
		(start 41.603168 -24.3586)
		(end 42.337736 -25.093168)
		(width 0.14224)
		(layer "In2.Cu")
		(net "M_G_DQ<3>")
	)
	(segment
		(start 43.048936 -37.809424)
		(end 43.048936 -33.948624)
		(width 0.14224)
		(layer "In2.Cu")
		(net "M_G_DQ<3>")
	)
	(segment
		(start 40.252142 -21.92655)
		(end 39.899336 -22.279356)
		(width 0.14224)
		(layer "In2.Cu")
		(net "M_G_DQ<3>")
	)
	(segment
		(start 39.95039 -17.653)
		(end 40.40759 -18.1102)
		(width 0.14224)
		(layer "In2.Cu")
		(net "M_G_DQ<3>")
	)
	(segment
		(start 65.166748 -61.000386)
		(end 65.504568 -61.000386)
		(width 0.14224)
		(layer "In2.Cu")
		(net "M_G_DQ<3>")
	)
	(segment
		(start 67.834002 -61.53404)
		(end 68.894706 -61.53404)
		(width 0.0889)
		(layer "In2.Cu")
		(net "M_G_DQ<3>")
	)
	(segment
		(start 39.418768 -23.1902)
		(end 40.587168 -24.3586)
		(width 0.14224)
		(layer "In2.Cu")
		(net "M_G_DQ<3>")
	)
	(segment
		(start 40.40759 -18.4658)
		(end 40.252142 -18.621248)
		(width 0.14224)
		(layer "In2.Cu")
		(net "M_G_DQ<3>")
	)
	(segment
		(start 39.69639 -17.653)
		(end 39.95039 -17.653)
		(width 0.14224)
		(layer "In2.Cu")
		(net "M_G_DQ<3>")
	)
	(segment
		(start 39.36619 -17.004284)
		(end 39.36619 -17.3228)
		(width 0.14224)
		(layer "In2.Cu")
		(net "M_G_DQ<3>")
	)
	(segment
		(start 40.252142 -18.621248)
		(end 40.252142 -21.92655)
		(width 0.14224)
		(layer "In2.Cu")
		(net "M_G_DQ<3>")
	)
	(segment
		(start 43.760136 -33.948624)
		(end 43.760136 -39.593774)
		(width 0.14224)
		(layer "In2.Cu")
		(net "M_G_DQ<3>")
	)
	(segment
		(start 110.165642 -41.521126)
		(end 110.7313 -40.955468)
		(width 0.1016)
		(layer "F.Cu")
		(net "M_G_DQ<39>")
	)
	(segment
		(start 121.689368 -26.667968)
		(end 121.689368 -23.9014)
		(width 0.1651)
		(layer "F.Cu")
		(net "M_G_DQ<39>")
	)
	(segment
		(start 120.952768 -23.1648)
		(end 120.952768 -22.444456)
		(width 0.1651)
		(layer "F.Cu")
		(net "M_G_DQ<39>")
	)
	(segment
		(start 120.478804 -29.933392)
		(end 120.478804 -28.575)
		(width 0.1651)
		(layer "F.Cu")
		(net "M_G_DQ<39>")
	)
	(segment
		(start 121.117868 -22.279356)
		(end 121.499376 -22.279356)
		(width 0.1651)
		(layer "F.Cu")
		(net "M_G_DQ<39>")
	)
	(segment
		(start 110.7313 -40.955468)
		(end 110.7313 -40.4114)
		(width 0.1016)
		(layer "F.Cu")
		(net "M_G_DQ<39>")
	)
	(segment
		(start 110.7313 -40.4114)
		(end 110.7313 -39.680896)
		(width 0.1651)
		(layer "F.Cu")
		(net "M_G_DQ<39>")
	)
	(segment
		(start 110.7313 -39.680896)
		(end 120.478804 -29.933392)
		(width 0.1651)
		(layer "F.Cu")
		(net "M_G_DQ<39>")
	)
	(segment
		(start 120.478804 -28.575)
		(end 120.478804 -27.878532)
		(width 0.1651)
		(layer "F.Cu")
		(net "M_G_DQ<39>")
	)
	(segment
		(start 110.008416 -53.542184)
		(end 110.008416 -50.26279)
		(width 0.0889)
		(layer "F.Cu")
		(net "M_G_DQ<39>")
	)
	(segment
		(start 109.627416 -53.923184)
		(end 110.008416 -53.542184)
		(width 0.0889)
		(layer "F.Cu")
		(net "M_G_DQ<39>")
	)
	(segment
		(start 120.952768 -22.444456)
		(end 121.117868 -22.279356)
		(width 0.1651)
		(layer "F.Cu")
		(net "M_G_DQ<39>")
	)
	(segment
		(start 110.165642 -49.812448)
		(end 110.165642 -41.521126)
		(width 0.1016)
		(layer "F.Cu")
		(net "M_G_DQ<39>")
	)
	(segment
		(start 110.008416 -50.26279)
		(end 110.165642 -50.105564)
		(width 0.0889)
		(layer "F.Cu")
		(net "M_G_DQ<39>")
	)
	(segment
		(start 120.649492 -15.423642)
		(end 120.649492 -16.687546)
		(width 0.1651)
		(layer "F.Cu")
		(net "M_G_DQ<39>")
	)
	(segment
		(start 121.689368 -23.9014)
		(end 120.952768 -23.1648)
		(width 0.1651)
		(layer "F.Cu")
		(net "M_G_DQ<39>")
	)
	(segment
		(start 120.478804 -27.878532)
		(end 121.689368 -26.667968)
		(width 0.1651)
		(layer "F.Cu")
		(net "M_G_DQ<39>")
	)
	(segment
		(start 110.165642 -50.105564)
		(end 110.165642 -49.812448)
		(width 0.0889)
		(layer "F.Cu")
		(net "M_G_DQ<39>")
	)
	(via
		(at 121.499376 -22.279356)
		(size 0.508)
		(drill 0.254)
		(layers "F.Cu" "B.Cu")
		(net "M_G_DQ<39>")
	)
	(via
		(at 120.649492 -16.687546)
		(size 0.508)
		(drill 0.254)
		(layers "F.Cu" "B.Cu")
		(net "M_G_DQ<39>")
	)
	(via
		(at 120.478804 -28.575)
		(size 0.508)
		(drill 0.254)
		(layers "F.Cu" "B.Cu")
		(net "M_G_DQ<39>")
	)
	(segment
		(start 121.499376 -22.279356)
		(end 121.499376 -20.224242)
		(width 0.1651)
		(layer "B.Cu")
		(net "M_G_DQ<39>")
	)
	(segment
		(start 121.499376 -22.279356)
		(end 121.852182 -21.92655)
		(width 0.14224)
		(layer "In2.Cu")
		(net "M_G_DQ<39>")
	)
	(segment
		(start 122.00763 -18.4658)
		(end 122.00763 -18.1102)
		(width 0.14224)
		(layer "In2.Cu")
		(net "M_G_DQ<39>")
	)
	(segment
		(start 120.649492 -17.006062)
		(end 120.649492 -16.687546)
		(width 0.14224)
		(layer "In2.Cu")
		(net "M_G_DQ<39>")
	)
	(segment
		(start 121.29643 -17.653)
		(end 120.649492 -17.006062)
		(width 0.14224)
		(layer "In2.Cu")
		(net "M_G_DQ<39>")
	)
	(segment
		(start 121.55043 -17.653)
		(end 121.29643 -17.653)
		(width 0.14224)
		(layer "In2.Cu")
		(net "M_G_DQ<39>")
	)
	(segment
		(start 121.852182 -18.621248)
		(end 122.00763 -18.4658)
		(width 0.14224)
		(layer "In2.Cu")
		(net "M_G_DQ<39>")
	)
	(segment
		(start 122.00763 -18.1102)
		(end 121.55043 -17.653)
		(width 0.14224)
		(layer "In2.Cu")
		(net "M_G_DQ<39>")
	)
	(segment
		(start 121.852182 -21.92655)
		(end 121.852182 -18.621248)
		(width 0.14224)
		(layer "In2.Cu")
		(net "M_G_DQ<39>")
	)
	(segment
		(start 119.352568 -25.3619)
		(end 119.352568 -24.8412)
		(width 0.1651)
		(layer "F.Cu")
		(net "M_G_DQ<38>")
	)
	(segment
		(start 119.352568 -24.8412)
		(end 119.555768 -24.638)
		(width 0.1651)
		(layer "F.Cu")
		(net "M_G_DQ<38>")
	)
	(segment
		(start 121.028968 -25.6667)
		(end 120.863868 -25.5016)
		(width 0.1651)
		(layer "F.Cu")
		(net "M_G_DQ<38>")
	)
	(segment
		(start 110.091474 -41.01084)
		(end 110.091474 -40.4114)
		(width 0.1016)
		(layer "F.Cu")
		(net "M_G_DQ<38>")
	)
	(segment
		(start 119.403368 -26.340054)
		(end 119.530622 -26.2128)
		(width 0.1651)
		(layer "F.Cu")
		(net "M_G_DQ<38>")
	)
	(segment
		(start 121.49963 -19.05)
		(end 121.63171 -18.91792)
		(width 0.1651)
		(layer "F.Cu")
		(net "M_G_DQ<38>")
	)
	(segment
		(start 120.863868 -26.2128)
		(end 121.028968 -26.0477)
		(width 0.1651)
		(layer "F.Cu")
		(net "M_G_DQ<38>")
	)
	(segment
		(start 120.978168 -24.282146)
		(end 120.649492 -23.95347)
		(width 0.1651)
		(layer "F.Cu")
		(net "M_G_DQ<38>")
	)
	(segment
		(start 110.091474 -39.415466)
		(end 119.403368 -30.103572)
		(width 0.1651)
		(layer "F.Cu")
		(net "M_G_DQ<38>")
	)
	(segment
		(start 119.555768 -24.638)
		(end 120.851422 -24.638)
		(width 0.1651)
		(layer "F.Cu")
		(net "M_G_DQ<38>")
	)
	(segment
		(start 121.49963 -18.262854)
		(end 121.499376 -18.2626)
		(width 0.1651)
		(layer "F.Cu")
		(net "M_G_DQ<38>")
	)
	(segment
		(start 110.091474 -40.4114)
		(end 110.091474 -39.415466)
		(width 0.1651)
		(layer "F.Cu")
		(net "M_G_DQ<38>")
	)
	(segment
		(start 120.978168 -24.511254)
		(end 120.978168 -24.282146)
		(width 0.1651)
		(layer "F.Cu")
		(net "M_G_DQ<38>")
	)
	(segment
		(start 121.499376 -20.023582)
		(end 121.49963 -20.023328)
		(width 0.1651)
		(layer "F.Cu")
		(net "M_G_DQ<38>")
	)
	(segment
		(start 120.649492 -23.95347)
		(end 120.649492 -23.560278)
		(width 0.1651)
		(layer "F.Cu")
		(net "M_G_DQ<38>")
	)
	(segment
		(start 121.028968 -26.0477)
		(end 121.028968 -25.6667)
		(width 0.1651)
		(layer "F.Cu")
		(net "M_G_DQ<38>")
	)
	(segment
		(start 121.49963 -20.023328)
		(end 121.49963 -19.05)
		(width 0.1651)
		(layer "F.Cu")
		(net "M_G_DQ<38>")
	)
	(segment
		(start 109.771942 -49.812448)
		(end 109.771942 -41.330372)
		(width 0.1016)
		(layer "F.Cu")
		(net "M_G_DQ<38>")
	)
	(segment
		(start 121.63171 -18.91792)
		(end 121.63171 -18.69948)
		(width 0.1651)
		(layer "F.Cu")
		(net "M_G_DQ<38>")
	)
	(segment
		(start 121.63171 -18.69948)
		(end 121.49963 -18.5674)
		(width 0.1651)
		(layer "F.Cu")
		(net "M_G_DQ<38>")
	)
	(segment
		(start 109.627416 -51.941984)
		(end 109.817916 -51.751484)
		(width 0.0889)
		(layer "F.Cu")
		(net "M_G_DQ<38>")
	)
	(segment
		(start 109.771942 -41.330372)
		(end 110.091474 -41.01084)
		(width 0.1016)
		(layer "F.Cu")
		(net "M_G_DQ<38>")
	)
	(segment
		(start 119.403368 -30.103572)
		(end 119.403368 -26.340054)
		(width 0.1651)
		(layer "F.Cu")
		(net "M_G_DQ<38>")
	)
	(segment
		(start 120.863868 -25.5016)
		(end 119.492268 -25.5016)
		(width 0.1651)
		(layer "F.Cu")
		(net "M_G_DQ<38>")
	)
	(segment
		(start 119.530622 -26.2128)
		(end 120.863868 -26.2128)
		(width 0.1651)
		(layer "F.Cu")
		(net "M_G_DQ<38>")
	)
	(segment
		(start 109.817916 -51.751484)
		(end 109.817916 -50.233326)
		(width 0.0889)
		(layer "F.Cu")
		(net "M_G_DQ<38>")
	)
	(segment
		(start 109.817916 -50.233326)
		(end 109.771942 -50.187352)
		(width 0.0889)
		(layer "F.Cu")
		(net "M_G_DQ<38>")
	)
	(segment
		(start 119.492268 -25.5016)
		(end 119.352568 -25.3619)
		(width 0.1651)
		(layer "F.Cu")
		(net "M_G_DQ<38>")
	)
	(segment
		(start 120.851422 -24.638)
		(end 120.978168 -24.511254)
		(width 0.1651)
		(layer "F.Cu")
		(net "M_G_DQ<38>")
	)
	(segment
		(start 109.771942 -50.187352)
		(end 109.771942 -49.812448)
		(width 0.0889)
		(layer "F.Cu")
		(net "M_G_DQ<38>")
	)
	(segment
		(start 121.49963 -18.5674)
		(end 121.49963 -18.262854)
		(width 0.1651)
		(layer "F.Cu")
		(net "M_G_DQ<38>")
	)
	(via
		(at 121.499376 -18.2626)
		(size 0.508)
		(drill 0.254)
		(layers "F.Cu" "B.Cu")
		(net "M_G_DQ<38>")
	)
	(via
		(at 120.649492 -23.560278)
		(size 0.508)
		(drill 0.254)
		(layers "F.Cu" "B.Cu")
		(net "M_G_DQ<38>")
	)
	(segment
		(start 120.649492 -23.560278)
		(end 120.649492 -24.824182)
		(width 0.1651)
		(layer "B.Cu")
		(net "M_G_DQ<38>")
	)
	(segment
		(start 121.12498 -18.914872)
		(end 121.12498 -18.636996)
		(width 0.14224)
		(layer "In2.Cu")
		(net "M_G_DQ<38>")
	)
	(segment
		(start 120.41378 -23.324566)
		(end 120.41378 -22.530054)
		(width 0.14224)
		(layer "In2.Cu")
		(net "M_G_DQ<38>")
	)
	(segment
		(start 121.186448 -21.757386)
		(end 121.186448 -21.405596)
		(width 0.14224)
		(layer "In2.Cu")
		(net "M_G_DQ<38>")
	)
	(segment
		(start 121.12498 -18.636996)
		(end 121.499376 -18.2626)
		(width 0.14224)
		(layer "In2.Cu")
		(net "M_G_DQ<38>")
	)
	(segment
		(start 120.41378 -22.530054)
		(end 121.186448 -21.757386)
		(width 0.14224)
		(layer "In2.Cu")
		(net "M_G_DQ<38>")
	)
	(segment
		(start 120.760998 -19.278854)
		(end 121.12498 -18.914872)
		(width 0.14224)
		(layer "In2.Cu")
		(net "M_G_DQ<38>")
	)
	(segment
		(start 120.760998 -20.980146)
		(end 120.760998 -20.694904)
		(width 0.14224)
		(layer "In2.Cu")
		(net "M_G_DQ<38>")
	)
	(segment
		(start 121.141998 -19.970496)
		(end 120.760998 -19.589496)
		(width 0.14224)
		(layer "In2.Cu")
		(net "M_G_DQ<38>")
	)
	(segment
		(start 120.760998 -19.589496)
		(end 120.760998 -19.278854)
		(width 0.14224)
		(layer "In2.Cu")
		(net "M_G_DQ<38>")
	)
	(segment
		(start 121.141998 -20.313904)
		(end 121.141998 -19.970496)
		(width 0.14224)
		(layer "In2.Cu")
		(net "M_G_DQ<38>")
	)
	(segment
		(start 121.186448 -21.405596)
		(end 120.760998 -20.980146)
		(width 0.14224)
		(layer "In2.Cu")
		(net "M_G_DQ<38>")
	)
	(segment
		(start 120.649492 -23.560278)
		(end 120.41378 -23.324566)
		(width 0.14224)
		(layer "In2.Cu")
		(net "M_G_DQ<38>")
	)
	(segment
		(start 120.760998 -20.694904)
		(end 121.141998 -20.313904)
		(width 0.14224)
		(layer "In2.Cu")
		(net "M_G_DQ<38>")
	)
	(segment
		(start 107.016042 -41.714674)
		(end 106.308144 -41.006776)
		(width 0.1016)
		(layer "F.Cu")
		(net "M_G_DQ<37>")
	)
	(segment
		(start 107.659932 -53.67274)
		(end 107.659932 -53.340508)
		(width 0.0889)
		(layer "F.Cu")
		(net "M_G_DQ<37>")
	)
	(segment
		(start 107.659932 -53.340508)
		(end 107.569254 -53.129434)
		(width 0.0889)
		(layer "F.Cu")
		(net "M_G_DQ<37>")
	)
	(segment
		(start 107.910376 -53.923184)
		(end 107.659932 -53.67274)
		(width 0.0889)
		(layer "F.Cu")
		(net "M_G_DQ<37>")
	)
	(segment
		(start 106.308144 -40.4114)
		(end 106.308144 -36.693094)
		(width 0.1651)
		(layer "F.Cu")
		(net "M_G_DQ<37>")
	)
	(segment
		(start 108.887768 -32.18053)
		(end 115.352068 -25.71623)
		(width 0.1651)
		(layer "F.Cu")
		(net "M_G_DQ<37>")
	)
	(segment
		(start 115.352068 -25.71623)
		(end 115.352068 -23.7617)
		(width 0.1651)
		(layer "F.Cu")
		(net "M_G_DQ<37>")
	)
	(segment
		(start 115.973352 -23.140416)
		(end 115.973352 -22.779482)
		(width 0.1651)
		(layer "F.Cu")
		(net "M_G_DQ<37>")
	)
	(segment
		(start 107.073954 -52.830984)
		(end 107.041188 -52.830984)
		(width 0.0889)
		(layer "F.Cu")
		(net "M_G_DQ<37>")
	)
	(segment
		(start 106.519472 -51.338734)
		(end 106.519472 -50.653442)
		(width 0.0889)
		(layer "F.Cu")
		(net "M_G_DQ<37>")
	)
	(segment
		(start 106.308144 -36.693094)
		(end 108.887768 -34.11347)
		(width 0.1651)
		(layer "F.Cu")
		(net "M_G_DQ<37>")
	)
	(segment
		(start 106.519472 -50.653442)
		(end 107.016042 -50.156872)
		(width 0.0889)
		(layer "F.Cu")
		(net "M_G_DQ<37>")
	)
	(segment
		(start 115.973352 -22.779482)
		(end 115.473226 -22.279356)
		(width 0.1651)
		(layer "F.Cu")
		(net "M_G_DQ<37>")
	)
	(segment
		(start 107.016042 -49.812448)
		(end 107.016042 -41.714674)
		(width 0.1016)
		(layer "F.Cu")
		(net "M_G_DQ<37>")
	)
	(segment
		(start 115.352068 -23.7617)
		(end 115.973352 -23.140416)
		(width 0.1651)
		(layer "F.Cu")
		(net "M_G_DQ<37>")
	)
	(segment
		(start 108.887768 -34.11347)
		(end 108.887768 -32.18053)
		(width 0.1651)
		(layer "F.Cu")
		(net "M_G_DQ<37>")
	)
	(segment
		(start 106.308144 -41.006776)
		(end 106.308144 -40.4114)
		(width 0.1016)
		(layer "F.Cu")
		(net "M_G_DQ<37>")
	)
	(segment
		(start 106.710734 -51.670458)
		(end 106.519472 -51.338734)
		(width 0.0889)
		(layer "F.Cu")
		(net "M_G_DQ<37>")
	)
	(segment
		(start 114.699542 -15.423642)
		(end 114.699542 -16.687546)
		(width 0.1651)
		(layer "F.Cu")
		(net "M_G_DQ<37>")
	)
	(segment
		(start 107.016042 -50.156872)
		(end 107.016042 -49.812448)
		(width 0.0889)
		(layer "F.Cu")
		(net "M_G_DQ<37>")
	)
	(via
		(at 114.699542 -16.687546)
		(size 0.508)
		(drill 0.254)
		(layers "F.Cu" "B.Cu")
		(net "M_G_DQ<37>")
	)
	(via
		(at 115.473226 -22.279356)
		(size 0.508)
		(drill 0.254)
		(layers "F.Cu" "B.Cu")
		(net "M_G_DQ<37>")
	)
	(arc
		(start 106.710734 -52.240434)
		(mid 106.787041 -51.955446)
		(end 106.710734 -51.670458)
		(width 0.0889)
		(layer "F.Cu")
		(net "M_G_DQ<37>")
	)
	(arc
		(start 107.569254 -53.129434)
		(mid 107.360128 -52.916277)
		(end 107.073954 -52.830984)
		(width 0.0889)
		(layer "F.Cu")
		(net "M_G_DQ<37>")
	)
	(arc
		(start 107.041188 -52.830984)
		(mid 106.708161 -52.629605)
		(end 106.710734 -52.240434)
		(width 0.0889)
		(layer "F.Cu")
		(net "M_G_DQ<37>")
	)
	(segment
		(start 115.549426 -20.224242)
		(end 115.549426 -22.203156)
		(width 0.1651)
		(layer "B.Cu")
		(net "M_G_DQ<37>")
	)
	(segment
		(start 115.549426 -22.203156)
		(end 115.473226 -22.279356)
		(width 0.1651)
		(layer "B.Cu")
		(net "M_G_DQ<37>")
	)
	(segment
		(start 115.78463 -18.66265)
		(end 115.98148 -18.4658)
		(width 0.14224)
		(layer "In2.Cu")
		(net "M_G_DQ<37>")
	)
	(segment
		(start 115.98148 -18.053304)
		(end 115.581176 -17.653)
		(width 0.14224)
		(layer "In2.Cu")
		(net "M_G_DQ<37>")
	)
	(segment
		(start 115.78463 -21.967952)
		(end 115.78463 -18.66265)
		(width 0.14224)
		(layer "In2.Cu")
		(net "M_G_DQ<37>")
	)
	(segment
		(start 115.98148 -18.4658)
		(end 115.98148 -18.053304)
		(width 0.14224)
		(layer "In2.Cu")
		(net "M_G_DQ<37>")
	)
	(segment
		(start 114.699542 -17.082262)
		(end 114.699542 -16.687546)
		(width 0.14224)
		(layer "In2.Cu")
		(net "M_G_DQ<37>")
	)
	(segment
		(start 115.581176 -17.653)
		(end 115.27028 -17.653)
		(width 0.14224)
		(layer "In2.Cu")
		(net "M_G_DQ<37>")
	)
	(segment
		(start 115.473226 -22.279356)
		(end 115.78463 -21.967952)
		(width 0.14224)
		(layer "In2.Cu")
		(net "M_G_DQ<37>")
	)
	(segment
		(start 115.27028 -17.653)
		(end 114.699542 -17.082262)
		(width 0.14224)
		(layer "In2.Cu")
		(net "M_G_DQ<37>")
	)
	(segment
		(start 114.686842 -23.572978)
		(end 114.699542 -23.560278)
		(width 0.1651)
		(layer "F.Cu")
		(net "M_G_DQ<36>")
	)
	(segment
		(start 106.316018 -50.399696)
		(end 106.609642 -50.106072)
		(width 0.0889)
		(layer "F.Cu")
		(net "M_G_DQ<36>")
	)
	(segment
		(start 107.828588 -33.485074)
		(end 107.594908 -33.485074)
		(width 0.1651)
		(layer "F.Cu")
		(net "M_G_DQ<36>")
	)
	(segment
		(start 107.025186 -33.874964)
		(end 106.72191 -33.571688)
		(width 0.1651)
		(layer "F.Cu")
		(net "M_G_DQ<36>")
	)
	(segment
		(start 105.668318 -40.4622)
		(end 105.668318 -36.378388)
		(width 0.1651)
		(layer "F.Cu")
		(net "M_G_DQ<36>")
	)
	(segment
		(start 106.622342 -49.799748)
		(end 106.622342 -41.930828)
		(width 0.1016)
		(layer "F.Cu")
		(net "M_G_DQ<36>")
	)
	(segment
		(start 105.668318 -40.976804)
		(end 105.668318 -40.4622)
		(width 0.1016)
		(layer "F.Cu")
		(net "M_G_DQ<36>")
	)
	(segment
		(start 106.316018 -51.393344)
		(end 106.316018 -50.399696)
		(width 0.0889)
		(layer "F.Cu")
		(net "M_G_DQ<36>")
	)
	(segment
		(start 108.07827 -33.968436)
		(end 108.07827 -33.734756)
		(width 0.1651)
		(layer "F.Cu")
		(net "M_G_DQ<36>")
	)
	(segment
		(start 115.549426 -20.023582)
		(end 115.549426 -18.692368)
		(width 0.1651)
		(layer "F.Cu")
		(net "M_G_DQ<36>")
	)
	(segment
		(start 107.594908 -33.485074)
		(end 107.205018 -33.874964)
		(width 0.1651)
		(layer "F.Cu")
		(net "M_G_DQ<36>")
	)
	(segment
		(start 108.07827 -33.734756)
		(end 107.828588 -33.485074)
		(width 0.1651)
		(layer "F.Cu")
		(net "M_G_DQ<36>")
	)
	(segment
		(start 106.72191 -33.571688)
		(end 106.72191 -33.391856)
		(width 0.1651)
		(layer "F.Cu")
		(net "M_G_DQ<36>")
	)
	(segment
		(start 106.72191 -33.391856)
		(end 114.686842 -25.426924)
		(width 0.1651)
		(layer "F.Cu")
		(net "M_G_DQ<36>")
	)
	(segment
		(start 115.549426 -18.692368)
		(end 115.451382 -18.161)
		(width 0.1651)
		(layer "F.Cu")
		(net "M_G_DQ<36>")
	)
	(segment
		(start 105.668318 -36.378388)
		(end 108.07827 -33.968436)
		(width 0.1651)
		(layer "F.Cu")
		(net "M_G_DQ<36>")
	)
	(segment
		(start 106.609642 -49.812448)
		(end 106.622342 -49.799748)
		(width 0.1016)
		(layer "F.Cu")
		(net "M_G_DQ<36>")
	)
	(segment
		(start 107.205018 -33.874964)
		(end 107.025186 -33.874964)
		(width 0.1651)
		(layer "F.Cu")
		(net "M_G_DQ<36>")
	)
	(segment
		(start 106.534458 -51.772058)
		(end 106.316018 -51.393344)
		(width 0.0889)
		(layer "F.Cu")
		(net "M_G_DQ<36>")
	)
	(segment
		(start 114.686842 -25.426924)
		(end 114.686842 -23.572978)
		(width 0.1651)
		(layer "F.Cu")
		(net "M_G_DQ<36>")
	)
	(segment
		(start 106.622342 -41.930828)
		(end 105.668318 -40.976804)
		(width 0.1016)
		(layer "F.Cu")
		(net "M_G_DQ<36>")
	)
	(segment
		(start 107.051856 -53.427884)
		(end 106.572558 -52.793646)
		(width 0.0889)
		(layer "F.Cu")
		(net "M_G_DQ<36>")
	)
	(segment
		(start 106.609642 -50.106072)
		(end 106.609642 -49.812448)
		(width 0.0889)
		(layer "F.Cu")
		(net "M_G_DQ<36>")
	)
	(via
		(at 114.699542 -23.560278)
		(size 0.508)
		(drill 0.254)
		(layers "F.Cu" "B.Cu")
		(net "M_G_DQ<36>")
	)
	(via
		(at 115.451382 -18.161)
		(size 0.508)
		(drill 0.254)
		(layers "F.Cu" "B.Cu")
		(net "M_G_DQ<36>")
	)
	(arc
		(start 106.534458 -52.138834)
		(mid 106.583581 -51.955446)
		(end 106.534458 -51.772058)
		(width 0.0889)
		(layer "F.Cu")
		(net "M_G_DQ<36>")
	)
	(arc
		(start 106.572558 -52.793646)
		(mid 106.552668 -52.765242)
		(end 106.534458 -52.735734)
		(width 0.0889)
		(layer "F.Cu")
		(net "M_G_DQ<36>")
	)
	(arc
		(start 106.534458 -52.735734)
		(mid 106.454551 -52.437284)
		(end 106.534458 -52.138834)
		(width 0.0889)
		(layer "F.Cu")
		(net "M_G_DQ<36>")
	)
	(segment
		(start 114.699542 -23.560278)
		(end 114.699542 -24.824182)
		(width 0.1651)
		(layer "B.Cu")
		(net "M_G_DQ<36>")
	)
	(segment
		(start 115.17503 -21.344128)
		(end 114.823748 -20.992846)
		(width 0.14224)
		(layer "In2.Cu")
		(net "M_G_DQ<36>")
	)
	(segment
		(start 115.17503 -18.437352)
		(end 115.451382 -18.161)
		(width 0.14224)
		(layer "In2.Cu")
		(net "M_G_DQ<36>")
	)
	(segment
		(start 115.192048 -20.2692)
		(end 115.192048 -19.9644)
		(width 0.14224)
		(layer "In2.Cu")
		(net "M_G_DQ<36>")
	)
	(segment
		(start 114.823748 -20.992846)
		(end 114.823748 -20.6375)
		(width 0.14224)
		(layer "In2.Cu")
		(net "M_G_DQ<36>")
	)
	(segment
		(start 114.699542 -23.560278)
		(end 114.46383 -23.324566)
		(width 0.14224)
		(layer "In2.Cu")
		(net "M_G_DQ<36>")
	)
	(segment
		(start 114.811048 -19.278854)
		(end 115.17503 -18.914872)
		(width 0.14224)
		(layer "In2.Cu")
		(net "M_G_DQ<36>")
	)
	(segment
		(start 114.823748 -20.6375)
		(end 115.192048 -20.2692)
		(width 0.14224)
		(layer "In2.Cu")
		(net "M_G_DQ<36>")
	)
	(segment
		(start 115.192048 -19.9644)
		(end 114.811048 -19.5834)
		(width 0.14224)
		(layer "In2.Cu")
		(net "M_G_DQ<36>")
	)
	(segment
		(start 114.46383 -23.324566)
		(end 114.46383 -22.530054)
		(width 0.14224)
		(layer "In2.Cu")
		(net "M_G_DQ<36>")
	)
	(segment
		(start 115.17503 -21.818854)
		(end 115.17503 -21.344128)
		(width 0.14224)
		(layer "In2.Cu")
		(net "M_G_DQ<36>")
	)
	(segment
		(start 115.17503 -18.914872)
		(end 115.17503 -18.437352)
		(width 0.14224)
		(layer "In2.Cu")
		(net "M_G_DQ<36>")
	)
	(segment
		(start 114.811048 -19.5834)
		(end 114.811048 -19.278854)
		(width 0.14224)
		(layer "In2.Cu")
		(net "M_G_DQ<36>")
	)
	(segment
		(start 114.46383 -22.530054)
		(end 115.17503 -21.818854)
		(width 0.14224)
		(layer "In2.Cu")
		(net "M_G_DQ<36>")
	)
	(segment
		(start 110.953042 -49.799748)
		(end 110.953042 -41.876726)
		(width 0.1016)
		(layer "F.Cu")
		(net "M_G_DQ<35>")
	)
	(segment
		(start 110.953042 -41.876726)
		(end 112.010952 -40.818816)
		(width 0.1016)
		(layer "F.Cu")
		(net "M_G_DQ<35>")
	)
	(segment
		(start 110.485682 -53.427884)
		(end 110.949486 -52.357274)
		(width 0.0889)
		(layer "F.Cu")
		(net "M_G_DQ<35>")
	)
	(segment
		(start 123.060968 -27.9908)
		(end 123.060968 -25.8318)
		(width 0.1651)
		(layer "F.Cu")
		(net "M_G_DQ<35>")
	)
	(segment
		(start 111.076486 -49.923192)
		(end 110.953042 -49.799748)
		(width 0.0889)
		(layer "F.Cu")
		(net "M_G_DQ<35>")
	)
	(segment
		(start 110.949486 -52.357274)
		(end 110.949486 -51.919886)
		(width 0.0889)
		(layer "F.Cu")
		(net "M_G_DQ<35>")
	)
	(segment
		(start 123.060968 -25.8318)
		(end 124.647452 -24.245316)
		(width 0.1651)
		(layer "F.Cu")
		(net "M_G_DQ<35>")
	)
	(segment
		(start 110.992666 -51.750722)
		(end 111.076486 -51.600862)
		(width 0.0889)
		(layer "F.Cu")
		(net "M_G_DQ<35>")
	)
	(segment
		(start 112.010952 -40.5384)
		(end 112.010952 -40.211756)
		(width 0.1651)
		(layer "F.Cu")
		(net "M_G_DQ<35>")
	)
	(segment
		(start 122.375168 -28.6766)
		(end 123.060968 -27.9908)
		(width 0.1651)
		(layer "F.Cu")
		(net "M_G_DQ<35>")
	)
	(segment
		(start 112.010952 -40.211756)
		(end 121.758456 -30.464252)
		(width 0.1651)
		(layer "F.Cu")
		(net "M_G_DQ<35>")
	)
	(segment
		(start 123.942094 -22.801326)
		(end 123.721368 -22.801326)
		(width 0.1651)
		(layer "F.Cu")
		(net "M_G_DQ<35>")
	)
	(segment
		(start 112.010952 -40.818816)
		(end 112.010952 -40.5384)
		(width 0.1016)
		(layer "F.Cu")
		(net "M_G_DQ<35>")
	)
	(segment
		(start 121.758456 -29.293312)
		(end 122.375168 -28.6766)
		(width 0.1651)
		(layer "F.Cu")
		(net "M_G_DQ<35>")
	)
	(segment
		(start 111.076486 -51.600862)
		(end 111.076486 -49.923192)
		(width 0.0889)
		(layer "F.Cu")
		(net "M_G_DQ<35>")
	)
	(segment
		(start 123.721368 -22.801326)
		(end 123.199398 -22.279356)
		(width 0.1651)
		(layer "F.Cu")
		(net "M_G_DQ<35>")
	)
	(segment
		(start 124.647452 -24.245316)
		(end 124.647452 -23.506684)
		(width 0.1651)
		(layer "F.Cu")
		(net "M_G_DQ<35>")
	)
	(segment
		(start 122.349514 -15.423642)
		(end 122.349514 -16.687546)
		(width 0.1651)
		(layer "F.Cu")
		(net "M_G_DQ<35>")
	)
	(segment
		(start 121.758456 -30.464252)
		(end 121.758456 -29.293312)
		(width 0.1651)
		(layer "F.Cu")
		(net "M_G_DQ<35>")
	)
	(segment
		(start 124.647452 -23.506684)
		(end 123.942094 -22.801326)
		(width 0.1651)
		(layer "F.Cu")
		(net "M_G_DQ<35>")
	)
	(via
		(at 122.375168 -28.6766)
		(size 0.508)
		(drill 0.254)
		(layers "F.Cu" "B.Cu")
		(net "M_G_DQ<35>")
	)
	(via
		(at 122.349514 -16.687546)
		(size 0.508)
		(drill 0.254)
		(layers "F.Cu" "B.Cu")
		(net "M_G_DQ<35>")
	)
	(via
		(at 123.199398 -22.279356)
		(size 0.508)
		(drill 0.254)
		(layers "F.Cu" "B.Cu")
		(net "M_G_DQ<35>")
	)
	(arc
		(start 110.949486 -51.919886)
		(mid 110.960441 -51.832587)
		(end 110.992666 -51.750722)
		(width 0.0889)
		(layer "F.Cu")
		(net "M_G_DQ<35>")
	)
	(segment
		(start 123.199398 -22.279356)
		(end 123.199398 -20.224242)
		(width 0.1651)
		(layer "B.Cu")
		(net "M_G_DQ<35>")
	)
	(segment
		(start 123.250452 -17.653)
		(end 122.996452 -17.653)
		(width 0.14224)
		(layer "In2.Cu")
		(net "M_G_DQ<35>")
	)
	(segment
		(start 123.707652 -18.4658)
		(end 123.707652 -18.1102)
		(width 0.14224)
		(layer "In2.Cu")
		(net "M_G_DQ<35>")
	)
	(segment
		(start 122.996452 -17.653)
		(end 122.349514 -17.006062)
		(width 0.14224)
		(layer "In2.Cu")
		(net "M_G_DQ<35>")
	)
	(segment
		(start 123.199398 -22.279356)
		(end 123.552204 -21.92655)
		(width 0.14224)
		(layer "In2.Cu")
		(net "M_G_DQ<35>")
	)
	(segment
		(start 122.349514 -17.006062)
		(end 122.349514 -16.687546)
		(width 0.14224)
		(layer "In2.Cu")
		(net "M_G_DQ<35>")
	)
	(segment
		(start 123.552204 -21.92655)
		(end 123.552204 -18.621248)
		(width 0.14224)
		(layer "In2.Cu")
		(net "M_G_DQ<35>")
	)
	(segment
		(start 123.552204 -18.621248)
		(end 123.707652 -18.4658)
		(width 0.14224)
		(layer "In2.Cu")
		(net "M_G_DQ<35>")
	)
	(segment
		(start 123.707652 -18.1102)
		(end 123.250452 -17.653)
		(width 0.14224)
		(layer "In2.Cu")
		(net "M_G_DQ<35>")
	)
	(segment
		(start 123.33097 -18.67154)
		(end 123.199398 -18.539968)
		(width 0.1651)
		(layer "F.Cu")
		(net "M_G_DQ<34>")
	)
	(segment
		(start 110.485682 -52.437538)
		(end 110.885986 -51.512978)
		(width 0.0889)
		(layer "F.Cu")
		(net "M_G_DQ<34>")
	)
	(segment
		(start 122.349514 -26.416)
		(end 122.349514 -24.689054)
		(width 0.1651)
		(layer "F.Cu")
		(net "M_G_DQ<34>")
	)
	(segment
		(start 122.806968 -23.23846)
		(end 122.727212 -23.158704)
		(width 0.1651)
		(layer "F.Cu")
		(net "M_G_DQ<34>")
	)
	(segment
		(start 110.559342 -41.685972)
		(end 111.371126 -40.874188)
		(width 0.1016)
		(layer "F.Cu")
		(net "M_G_DQ<34>")
	)
	(segment
		(start 121.11863 -28.624784)
		(end 122.349514 -27.3939)
		(width 0.1651)
		(layer "F.Cu")
		(net "M_G_DQ<34>")
	)
	(segment
		(start 110.559342 -49.812448)
		(end 110.559342 -41.685972)
		(width 0.1016)
		(layer "F.Cu")
		(net "M_G_DQ<34>")
	)
	(segment
		(start 122.727212 -22.919436)
		(end 122.502168 -22.694392)
		(width 0.1651)
		(layer "F.Cu")
		(net "M_G_DQ<34>")
	)
	(segment
		(start 122.349514 -24.689054)
		(end 122.984768 -24.0538)
		(width 0.1651)
		(layer "F.Cu")
		(net "M_G_DQ<34>")
	)
	(segment
		(start 123.199398 -19.026632)
		(end 123.33097 -18.89506)
		(width 0.1651)
		(layer "F.Cu")
		(net "M_G_DQ<34>")
	)
	(segment
		(start 122.070368 -23.281132)
		(end 122.349514 -23.560278)
		(width 0.1651)
		(layer "F.Cu")
		(net "M_G_DQ<34>")
	)
	(segment
		(start 122.984768 -23.571454)
		(end 122.806968 -23.393654)
		(width 0.1651)
		(layer "F.Cu")
		(net "M_G_DQ<34>")
	)
	(segment
		(start 122.502168 -22.694392)
		(end 122.322336 -22.694392)
		(width 0.1651)
		(layer "F.Cu")
		(net "M_G_DQ<34>")
	)
	(segment
		(start 121.11863 -30.198822)
		(end 121.11863 -28.624784)
		(width 0.1651)
		(layer "F.Cu")
		(net "M_G_DQ<34>")
	)
	(segment
		(start 123.199398 -20.023582)
		(end 123.199398 -19.026632)
		(width 0.1651)
		(layer "F.Cu")
		(net "M_G_DQ<34>")
	)
	(segment
		(start 122.070368 -22.94636)
		(end 122.070368 -23.281132)
		(width 0.1651)
		(layer "F.Cu")
		(net "M_G_DQ<34>")
	)
	(segment
		(start 123.199398 -18.539968)
		(end 123.199398 -18.2626)
		(width 0.1651)
		(layer "F.Cu")
		(net "M_G_DQ<34>")
	)
	(segment
		(start 122.984768 -24.0538)
		(end 122.984768 -23.571454)
		(width 0.1651)
		(layer "F.Cu")
		(net "M_G_DQ<34>")
	)
	(segment
		(start 110.885986 -50.289968)
		(end 110.559342 -49.963324)
		(width 0.0889)
		(layer "F.Cu")
		(net "M_G_DQ<34>")
	)
	(segment
		(start 122.806968 -23.393654)
		(end 122.806968 -23.23846)
		(width 0.1651)
		(layer "F.Cu")
		(net "M_G_DQ<34>")
	)
	(segment
		(start 111.371126 -39.946326)
		(end 121.11863 -30.198822)
		(width 0.1651)
		(layer "F.Cu")
		(net "M_G_DQ<34>")
	)
	(segment
		(start 122.349514 -27.3939)
		(end 122.349514 -26.416)
		(width 0.1651)
		(layer "F.Cu")
		(net "M_G_DQ<34>")
	)
	(segment
		(start 122.727212 -23.158704)
		(end 122.727212 -22.919436)
		(width 0.1651)
		(layer "F.Cu")
		(net "M_G_DQ<34>")
	)
	(segment
		(start 111.371126 -40.4622)
		(end 111.371126 -39.946326)
		(width 0.1651)
		(layer "F.Cu")
		(net "M_G_DQ<34>")
	)
	(segment
		(start 123.33097 -18.89506)
		(end 123.33097 -18.67154)
		(width 0.1651)
		(layer "F.Cu")
		(net "M_G_DQ<34>")
	)
	(segment
		(start 110.559342 -49.963324)
		(end 110.559342 -49.812448)
		(width 0.0889)
		(layer "F.Cu")
		(net "M_G_DQ<34>")
	)
	(segment
		(start 122.322336 -22.694392)
		(end 122.070368 -22.94636)
		(width 0.1651)
		(layer "F.Cu")
		(net "M_G_DQ<34>")
	)
	(segment
		(start 110.885986 -51.512978)
		(end 110.885986 -50.289968)
		(width 0.0889)
		(layer "F.Cu")
		(net "M_G_DQ<34>")
	)
	(segment
		(start 111.371126 -40.874188)
		(end 111.371126 -40.4622)
		(width 0.1016)
		(layer "F.Cu")
		(net "M_G_DQ<34>")
	)
	(via
		(at 123.199398 -18.2626)
		(size 0.508)
		(drill 0.254)
		(layers "F.Cu" "B.Cu")
		(net "M_G_DQ<34>")
	)
	(via
		(at 122.349514 -26.416)
		(size 0.508)
		(drill 0.254)
		(layers "F.Cu" "B.Cu")
		(net "M_G_DQ<34>")
	)
	(via
		(at 122.349514 -23.560278)
		(size 0.508)
		(drill 0.254)
		(layers "F.Cu" "B.Cu")
		(net "M_G_DQ<34>")
	)
	(segment
		(start 122.349514 -23.560278)
		(end 122.349514 -24.824182)
		(width 0.1651)
		(layer "B.Cu")
		(net "M_G_DQ<34>")
	)
	(segment
		(start 122.456448 -20.55495)
		(end 122.761248 -20.25015)
		(width 0.14224)
		(layer "In2.Cu")
		(net "M_G_DQ<34>")
	)
	(segment
		(start 122.761248 -20.25015)
		(end 122.761248 -19.964146)
		(width 0.14224)
		(layer "In2.Cu")
		(net "M_G_DQ<34>")
	)
	(segment
		(start 122.913648 -21.4122)
		(end 122.456448 -20.955)
		(width 0.14224)
		(layer "In2.Cu")
		(net "M_G_DQ<34>")
	)
	(segment
		(start 122.761248 -19.964146)
		(end 122.456448 -19.659346)
		(width 0.14224)
		(layer "In2.Cu")
		(net "M_G_DQ<34>")
	)
	(segment
		(start 122.06478 -22.5298)
		(end 122.913648 -21.680932)
		(width 0.14224)
		(layer "In2.Cu")
		(net "M_G_DQ<34>")
	)
	(segment
		(start 122.80138 -18.660618)
		(end 123.199398 -18.2626)
		(width 0.14224)
		(layer "In2.Cu")
		(net "M_G_DQ<34>")
	)
	(segment
		(start 122.913648 -21.680932)
		(end 122.913648 -21.4122)
		(width 0.14224)
		(layer "In2.Cu")
		(net "M_G_DQ<34>")
	)
	(segment
		(start 122.06478 -23.275544)
		(end 122.06478 -22.5298)
		(width 0.14224)
		(layer "In2.Cu")
		(net "M_G_DQ<34>")
	)
	(segment
		(start 122.456448 -19.659346)
		(end 122.456448 -19.310604)
		(width 0.14224)
		(layer "In2.Cu")
		(net "M_G_DQ<34>")
	)
	(segment
		(start 122.80138 -18.965672)
		(end 122.80138 -18.660618)
		(width 0.14224)
		(layer "In2.Cu")
		(net "M_G_DQ<34>")
	)
	(segment
		(start 122.349514 -23.560278)
		(end 122.06478 -23.275544)
		(width 0.14224)
		(layer "In2.Cu")
		(net "M_G_DQ<34>")
	)
	(segment
		(start 122.456448 -20.955)
		(end 122.456448 -20.55495)
		(width 0.14224)
		(layer "In2.Cu")
		(net "M_G_DQ<34>")
	)
	(segment
		(start 122.456448 -19.310604)
		(end 122.80138 -18.965672)
		(width 0.14224)
		(layer "In2.Cu")
		(net "M_G_DQ<34>")
	)
	(segment
		(start 115.149376 -29.761942)
		(end 115.149376 -29.528262)
		(width 0.1651)
		(layer "F.Cu")
		(net "M_G_DQ<33>")
	)
	(segment
		(start 113.846356 -29.850842)
		(end 113.610644 -29.61513)
		(width 0.1651)
		(layer "F.Cu")
		(net "M_G_DQ<33>")
	)
	(segment
		(start 116.930932 -23.448264)
		(end 116.562632 -23.079964)
		(width 0.1651)
		(layer "F.Cu")
		(net "M_G_DQ<33>")
	)
	(segment
		(start 113.610644 -29.367734)
		(end 116.672868 -26.30551)
		(width 0.1651)
		(layer "F.Cu")
		(net "M_G_DQ<33>")
	)
	(segment
		(start 107.797092 -51.8287)
		(end 107.797092 -49.818798)
		(width 0.0889)
		(layer "F.Cu")
		(net "M_G_DQ<33>")
	)
	(segment
		(start 116.562632 -22.788372)
		(end 117.071648 -22.279356)
		(width 0.1651)
		(layer "F.Cu")
		(net "M_G_DQ<33>")
	)
	(segment
		(start 114.899948 -29.278834)
		(end 114.666268 -29.278834)
		(width 0.1651)
		(layer "F.Cu")
		(net "M_G_DQ<33>")
	)
	(segment
		(start 116.399564 -15.423642)
		(end 116.399564 -16.687546)
		(width 0.1651)
		(layer "F.Cu")
		(net "M_G_DQ<33>")
	)
	(segment
		(start 107.910376 -51.941984)
		(end 107.797092 -51.8287)
		(width 0.0889)
		(layer "F.Cu")
		(net "M_G_DQ<33>")
	)
	(segment
		(start 114.09426 -29.850842)
		(end 113.846356 -29.850842)
		(width 0.1651)
		(layer "F.Cu")
		(net "M_G_DQ<33>")
	)
	(segment
		(start 107.587796 -37.323522)
		(end 115.149376 -29.761942)
		(width 0.1651)
		(layer "F.Cu")
		(net "M_G_DQ<33>")
	)
	(segment
		(start 107.587796 -40.991028)
		(end 107.587796 -40.3606)
		(width 0.1016)
		(layer "F.Cu")
		(net "M_G_DQ<33>")
	)
	(segment
		(start 116.672868 -26.30551)
		(end 116.672868 -24.097488)
		(width 0.1651)
		(layer "F.Cu")
		(net "M_G_DQ<33>")
	)
	(segment
		(start 107.797092 -49.818798)
		(end 107.803442 -49.812448)
		(width 0.0889)
		(layer "F.Cu")
		(net "M_G_DQ<33>")
	)
	(segment
		(start 107.803442 -41.206674)
		(end 107.587796 -40.991028)
		(width 0.1016)
		(layer "F.Cu")
		(net "M_G_DQ<33>")
	)
	(segment
		(start 116.672868 -24.097488)
		(end 116.930932 -23.839424)
		(width 0.1651)
		(layer "F.Cu")
		(net "M_G_DQ<33>")
	)
	(segment
		(start 115.149376 -29.528262)
		(end 114.899948 -29.278834)
		(width 0.1651)
		(layer "F.Cu")
		(net "M_G_DQ<33>")
	)
	(segment
		(start 113.610644 -29.61513)
		(end 113.610644 -29.367734)
		(width 0.1651)
		(layer "F.Cu")
		(net "M_G_DQ<33>")
	)
	(segment
		(start 116.930932 -23.839424)
		(end 116.930932 -23.448264)
		(width 0.1651)
		(layer "F.Cu")
		(net "M_G_DQ<33>")
	)
	(segment
		(start 107.587796 -40.3606)
		(end 107.587796 -37.323522)
		(width 0.1651)
		(layer "F.Cu")
		(net "M_G_DQ<33>")
	)
	(segment
		(start 116.562632 -23.079964)
		(end 116.562632 -22.788372)
		(width 0.1651)
		(layer "F.Cu")
		(net "M_G_DQ<33>")
	)
	(segment
		(start 114.666268 -29.278834)
		(end 114.09426 -29.850842)
		(width 0.1651)
		(layer "F.Cu")
		(net "M_G_DQ<33>")
	)
	(segment
		(start 107.803442 -49.812448)
		(end 107.803442 -41.206674)
		(width 0.1016)
		(layer "F.Cu")
		(net "M_G_DQ<33>")
	)
	(via
		(at 116.399564 -16.687546)
		(size 0.508)
		(drill 0.254)
		(layers "F.Cu" "B.Cu")
		(net "M_G_DQ<33>")
	)
	(via
		(at 117.071648 -22.279356)
		(size 0.508)
		(drill 0.254)
		(layers "F.Cu" "B.Cu")
		(net "M_G_DQ<33>")
	)
	(segment
		(start 117.249448 -21.598382)
		(end 117.071648 -21.776182)
		(width 0.1651)
		(layer "B.Cu")
		(net "M_G_DQ<33>")
	)
	(segment
		(start 117.071648 -21.776182)
		(end 117.071648 -22.279356)
		(width 0.1651)
		(layer "B.Cu")
		(net "M_G_DQ<33>")
	)
	(segment
		(start 117.249448 -20.224242)
		(end 117.249448 -21.598382)
		(width 0.1651)
		(layer "B.Cu")
		(net "M_G_DQ<33>")
	)
	(segment
		(start 117.44579 -18.571464)
		(end 117.602254 -18.415)
		(width 0.14224)
		(layer "In2.Cu")
		(net "M_G_DQ<33>")
	)
	(segment
		(start 116.399564 -17.226534)
		(end 116.399564 -16.687546)
		(width 0.14224)
		(layer "In2.Cu")
		(net "M_G_DQ<33>")
	)
	(segment
		(start 117.44579 -21.905214)
		(end 117.44579 -18.571464)
		(width 0.14224)
		(layer "In2.Cu")
		(net "M_G_DQ<33>")
	)
	(segment
		(start 117.071648 -22.279356)
		(end 117.44579 -21.905214)
		(width 0.14224)
		(layer "In2.Cu")
		(net "M_G_DQ<33>")
	)
	(segment
		(start 117.602254 -18.415)
		(end 117.602254 -18.073624)
		(width 0.14224)
		(layer "In2.Cu")
		(net "M_G_DQ<33>")
	)
	(segment
		(start 116.87683 -17.7038)
		(end 116.399564 -17.226534)
		(width 0.14224)
		(layer "In2.Cu")
		(net "M_G_DQ<33>")
	)
	(segment
		(start 117.23243 -17.7038)
		(end 116.87683 -17.7038)
		(width 0.14224)
		(layer "In2.Cu")
		(net "M_G_DQ<33>")
	)
	(segment
		(start 117.602254 -18.073624)
		(end 117.23243 -17.7038)
		(width 0.14224)
		(layer "In2.Cu")
		(net "M_G_DQ<33>")
	)
	(segment
		(start 107.099608 -52.39004)
		(end 107.389168 -52.100226)
		(width 0.0889)
		(layer "F.Cu")
		(net "M_G_DQ<32>")
	)
	(segment
		(start 110.822232 -31.47441)
		(end 110.822232 -31.201106)
		(width 0.1651)
		(layer "F.Cu")
		(net "M_G_DQ<32>")
	)
	(segment
		(start 106.94797 -40.960548)
		(end 106.94797 -40.386)
		(width 0.1016)
		(layer "F.Cu")
		(net "M_G_DQ<32>")
	)
	(segment
		(start 111.305848 -31.684468)
		(end 111.03229 -31.684468)
		(width 0.1651)
		(layer "F.Cu")
		(net "M_G_DQ<32>")
	)
	(segment
		(start 107.409742 -50.10912)
		(end 107.409742 -41.42232)
		(width 0.1016)
		(layer "F.Cu")
		(net "M_G_DQ<32>")
	)
	(segment
		(start 106.94797 -37.008562)
		(end 112.53851 -31.418022)
		(width 0.1651)
		(layer "F.Cu")
		(net "M_G_DQ<32>")
	)
	(segment
		(start 112.53851 -31.184342)
		(end 112.289082 -30.934914)
		(width 0.1651)
		(layer "F.Cu")
		(net "M_G_DQ<32>")
	)
	(segment
		(start 115.44808 -26.575258)
		(end 116.012468 -26.01087)
		(width 0.1651)
		(layer "F.Cu")
		(net "M_G_DQ<32>")
	)
	(segment
		(start 117.168676 -19.177)
		(end 117.071648 -18.161)
		(width 0.1651)
		(layer "F.Cu")
		(net "M_G_DQ<32>")
	)
	(segment
		(start 107.409742 -41.42232)
		(end 106.94797 -40.960548)
		(width 0.1016)
		(layer "F.Cu")
		(net "M_G_DQ<32>")
	)
	(segment
		(start 107.051856 -52.437538)
		(end 107.099608 -52.39004)
		(width 0.0889)
		(layer "F.Cu")
		(net "M_G_DQ<32>")
	)
	(segment
		(start 107.389168 -51.835558)
		(end 107.606592 -51.618134)
		(width 0.0889)
		(layer "F.Cu")
		(net "M_G_DQ<32>")
	)
	(segment
		(start 107.606592 -50.30597)
		(end 107.409742 -50.10912)
		(width 0.0889)
		(layer "F.Cu")
		(net "M_G_DQ<32>")
	)
	(segment
		(start 116.012468 -23.947374)
		(end 116.399564 -23.560278)
		(width 0.1651)
		(layer "F.Cu")
		(net "M_G_DQ<32>")
	)
	(segment
		(start 111.03229 -31.684468)
		(end 110.822232 -31.47441)
		(width 0.1651)
		(layer "F.Cu")
		(net "M_G_DQ<32>")
	)
	(segment
		(start 107.606592 -51.618134)
		(end 107.606592 -50.30597)
		(width 0.0889)
		(layer "F.Cu")
		(net "M_G_DQ<32>")
	)
	(segment
		(start 117.249448 -20.023582)
		(end 117.168676 -19.177)
		(width 0.1651)
		(layer "F.Cu")
		(net "M_G_DQ<32>")
	)
	(segment
		(start 112.055402 -30.934914)
		(end 111.305848 -31.684468)
		(width 0.1651)
		(layer "F.Cu")
		(net "M_G_DQ<32>")
	)
	(segment
		(start 106.94797 -40.386)
		(end 106.94797 -37.008562)
		(width 0.1651)
		(layer "F.Cu")
		(net "M_G_DQ<32>")
	)
	(segment
		(start 116.012468 -26.01087)
		(end 116.012468 -23.947374)
		(width 0.1651)
		(layer "F.Cu")
		(net "M_G_DQ<32>")
	)
	(segment
		(start 112.289082 -30.934914)
		(end 112.055402 -30.934914)
		(width 0.1651)
		(layer "F.Cu")
		(net "M_G_DQ<32>")
	)
	(segment
		(start 110.822232 -31.201106)
		(end 115.44808 -26.575258)
		(width 0.1651)
		(layer "F.Cu")
		(net "M_G_DQ<32>")
	)
	(segment
		(start 107.389168 -52.100226)
		(end 107.389168 -51.835558)
		(width 0.0889)
		(layer "F.Cu")
		(net "M_G_DQ<32>")
	)
	(segment
		(start 112.53851 -31.418022)
		(end 112.53851 -31.184342)
		(width 0.1651)
		(layer "F.Cu")
		(net "M_G_DQ<32>")
	)
	(via
		(at 117.071648 -18.161)
		(size 0.508)
		(drill 0.254)
		(layers "F.Cu" "B.Cu")
		(net "M_G_DQ<32>")
	)
	(via
		(at 116.399564 -23.560278)
		(size 0.508)
		(drill 0.254)
		(layers "F.Cu" "B.Cu")
		(net "M_G_DQ<32>")
	)
	(via
		(at 115.44808 -26.575258)
		(size 0.508)
		(drill 0.254)
		(layers "F.Cu" "B.Cu")
		(net "M_G_DQ<32>")
	)
	(segment
		(start 116.399564 -23.560278)
		(end 116.399564 -24.824182)
		(width 0.1651)
		(layer "B.Cu")
		(net "M_G_DQ<32>")
	)
	(segment
		(start 116.85143 -21.293328)
		(end 116.462048 -20.903946)
		(width 0.14224)
		(layer "In2.Cu")
		(net "M_G_DQ<32>")
	)
	(segment
		(start 116.85143 -21.7932)
		(end 116.85143 -21.293328)
		(width 0.14224)
		(layer "In2.Cu")
		(net "M_G_DQ<32>")
	)
	(segment
		(start 116.436648 -19.380454)
		(end 116.85143 -18.965672)
		(width 0.14224)
		(layer "In2.Cu")
		(net "M_G_DQ<32>")
	)
	(segment
		(start 116.436648 -19.7104)
		(end 116.436648 -19.380454)
		(width 0.14224)
		(layer "In2.Cu")
		(net "M_G_DQ<32>")
	)
	(segment
		(start 116.85143 -18.381218)
		(end 117.071648 -18.161)
		(width 0.14224)
		(layer "In2.Cu")
		(net "M_G_DQ<32>")
	)
	(segment
		(start 116.85143 -18.965672)
		(end 116.85143 -18.381218)
		(width 0.14224)
		(layer "In2.Cu")
		(net "M_G_DQ<32>")
	)
	(segment
		(start 116.11483 -22.5298)
		(end 116.85143 -21.7932)
		(width 0.14224)
		(layer "In2.Cu")
		(net "M_G_DQ<32>")
	)
	(segment
		(start 116.462048 -20.903946)
		(end 116.462048 -20.5994)
		(width 0.14224)
		(layer "In2.Cu")
		(net "M_G_DQ<32>")
	)
	(segment
		(start 116.462048 -20.5994)
		(end 116.779548 -20.2819)
		(width 0.14224)
		(layer "In2.Cu")
		(net "M_G_DQ<32>")
	)
	(segment
		(start 116.779548 -20.0533)
		(end 116.436648 -19.7104)
		(width 0.14224)
		(layer "In2.Cu")
		(net "M_G_DQ<32>")
	)
	(segment
		(start 116.779548 -20.2819)
		(end 116.779548 -20.0533)
		(width 0.14224)
		(layer "In2.Cu")
		(net "M_G_DQ<32>")
	)
	(segment
		(start 116.11483 -23.275544)
		(end 116.11483 -22.5298)
		(width 0.14224)
		(layer "In2.Cu")
		(net "M_G_DQ<32>")
	)
	(segment
		(start 116.399564 -23.560278)
		(end 116.11483 -23.275544)
		(width 0.14224)
		(layer "In2.Cu")
		(net "M_G_DQ<32>")
	)
	(segment
		(start 78.051406 -56.58104)
		(end 77.479906 -56.58104)
		(width 0.1016)
		(layer "F.Cu")
		(net "M_G_DQ<31>")
	)
	(segment
		(start 65.399412 -15.423642)
		(end 65.399412 -16.687546)
		(width 0.1651)
		(layer "F.Cu")
		(net "M_G_DQ<31>")
	)
	(via
		(at 77.479906 -56.58104)
		(size 0.508)
		(drill 0.254)
		(layers "F.Cu" "B.Cu")
		(net "M_G_DQ<31>")
	)
	(via
		(at 66.249296 -22.279356)
		(size 0.508)
		(drill 0.254)
		(layers "F.Cu" "B.Cu")
		(net "M_G_DQ<31>")
	)
	(via
		(at 65.399412 -16.687546)
		(size 0.508)
		(drill 0.254)
		(layers "F.Cu" "B.Cu")
		(net "M_G_DQ<31>")
	)
	(segment
		(start 66.249296 -20.224496)
		(end 66.249296 -22.279356)
		(width 0.1651)
		(layer "B.Cu")
		(net "M_G_DQ<31>")
	)
	(segment
		(start 66.24955 -20.224242)
		(end 66.249296 -20.224496)
		(width 0.1651)
		(layer "B.Cu")
		(net "M_G_DQ<31>")
	)
	(segment
		(start 74.370692 -50.017934)
		(end 74.557636 -50.342038)
		(width 0.0889)
		(layer "In2.Cu")
		(net "M_G_DQ<31>")
	)
	(segment
		(start 66.733928 -28.145232)
		(end 66.590164 -28.288996)
		(width 0.14224)
		(layer "In2.Cu")
		(net "M_G_DQ<31>")
	)
	(segment
		(start 65.790064 -23.221696)
		(end 66.348864 -23.780496)
		(width 0.14224)
		(layer "In2.Cu")
		(net "M_G_DQ<31>")
	)
	(segment
		(start 74.307192 -48.83277)
		(end 74.307192 -49.210214)
		(width 0.0889)
		(layer "In2.Cu")
		(net "M_G_DQ<31>")
	)
	(segment
		(start 74.184256 -48.767492)
		(end 74.241914 -48.767492)
		(width 0.14224)
		(layer "In2.Cu")
		(net "M_G_DQ<31>")
	)
	(segment
		(start 66.75755 -18.1102)
		(end 66.75755 -18.4658)
		(width 0.14224)
		(layer "In2.Cu")
		(net "M_G_DQ<31>")
	)
	(segment
		(start 66.733928 -26.98496)
		(end 66.733928 -28.145232)
		(width 0.14224)
		(layer "In2.Cu")
		(net "M_G_DQ<31>")
	)
	(segment
		(start 74.307192 -49.210214)
		(end 74.370692 -49.273714)
		(width 0.0889)
		(layer "In2.Cu")
		(net "M_G_DQ<31>")
	)
	(segment
		(start 66.183764 -34.855404)
		(end 66.183764 -37.44976)
		(width 0.14224)
		(layer "In2.Cu")
		(net "M_G_DQ<31>")
	)
	(segment
		(start 75.75169 -51.03749)
		(end 76.383134 -51.03749)
		(width 0.0889)
		(layer "In2.Cu")
		(net "M_G_DQ<31>")
	)
	(segment
		(start 66.30035 -17.653)
		(end 66.75755 -18.1102)
		(width 0.14224)
		(layer "In2.Cu")
		(net "M_G_DQ<31>")
	)
	(segment
		(start 66.183764 -37.44976)
		(end 66.326004 -37.592)
		(width 0.14224)
		(layer "In2.Cu")
		(net "M_G_DQ<31>")
	)
	(segment
		(start 78.070964 -52.72532)
		(end 78.07071 -52.725574)
		(width 0.0889)
		(layer "In2.Cu")
		(net "M_G_DQ<31>")
	)
	(segment
		(start 68.247768 -38.862)
		(end 68.247768 -42.831004)
		(width 0.14224)
		(layer "In2.Cu")
		(net "M_G_DQ<31>")
	)
	(segment
		(start 66.602102 -18.621248)
		(end 66.602102 -21.92655)
		(width 0.14224)
		(layer "In2.Cu")
		(net "M_G_DQ<31>")
	)
	(segment
		(start 74.370692 -49.273714)
		(end 74.370692 -50.017934)
		(width 0.0889)
		(layer "In2.Cu")
		(net "M_G_DQ<31>")
	)
	(segment
		(start 74.241914 -48.767492)
		(end 74.307192 -48.83277)
		(width 0.0889)
		(layer "In2.Cu")
		(net "M_G_DQ<31>")
	)
	(segment
		(start 66.391536 -29.270452)
		(end 66.391536 -34.647632)
		(width 0.14224)
		(layer "In2.Cu")
		(net "M_G_DQ<31>")
	)
	(segment
		(start 66.602102 -21.92655)
		(end 66.249296 -22.279356)
		(width 0.14224)
		(layer "In2.Cu")
		(net "M_G_DQ<31>")
	)
	(segment
		(start 65.71615 -17.3228)
		(end 66.04635 -17.653)
		(width 0.14224)
		(layer "In2.Cu")
		(net "M_G_DQ<31>")
	)
	(segment
		(start 66.75755 -18.4658)
		(end 66.602102 -18.621248)
		(width 0.14224)
		(layer "In2.Cu")
		(net "M_G_DQ<31>")
	)
	(segment
		(start 65.790064 -22.738588)
		(end 65.790064 -23.221696)
		(width 0.14224)
		(layer "In2.Cu")
		(net "M_G_DQ<31>")
	)
	(segment
		(start 74.88936 -50.541936)
		(end 74.922126 -50.541936)
		(width 0.0889)
		(layer "In2.Cu")
		(net "M_G_DQ<31>")
	)
	(segment
		(start 66.590164 -28.288996)
		(end 66.590164 -29.071824)
		(width 0.14224)
		(layer "In2.Cu")
		(net "M_G_DQ<31>")
	)
	(segment
		(start 77.802486 -56.58104)
		(end 77.479906 -56.58104)
		(width 0.0889)
		(layer "In2.Cu")
		(net "M_G_DQ<31>")
	)
	(segment
		(start 66.348864 -25.803352)
		(end 66.539364 -25.993852)
		(width 0.14224)
		(layer "In2.Cu")
		(net "M_G_DQ<31>")
	)
	(segment
		(start 66.04635 -17.653)
		(end 66.30035 -17.653)
		(width 0.14224)
		(layer "In2.Cu")
		(net "M_G_DQ<31>")
	)
	(segment
		(start 66.249296 -22.279356)
		(end 65.790064 -22.738588)
		(width 0.14224)
		(layer "In2.Cu")
		(net "M_G_DQ<31>")
	)
	(segment
		(start 78.07071 -52.725574)
		(end 78.07071 -53.60924)
		(width 0.0889)
		(layer "In2.Cu")
		(net "M_G_DQ<31>")
	)
	(segment
		(start 66.539364 -25.993852)
		(end 66.539364 -26.790396)
		(width 0.14224)
		(layer "In2.Cu")
		(net "M_G_DQ<31>")
	)
	(segment
		(start 66.348864 -23.780496)
		(end 66.348864 -25.803352)
		(width 0.14224)
		(layer "In2.Cu")
		(net "M_G_DQ<31>")
	)
	(segment
		(start 68.247768 -42.831004)
		(end 74.184256 -48.767492)
		(width 0.14224)
		(layer "In2.Cu")
		(net "M_G_DQ<31>")
	)
	(segment
		(start 65.71615 -17.004284)
		(end 65.71615 -17.3228)
		(width 0.14224)
		(layer "In2.Cu")
		(net "M_G_DQ<31>")
	)
	(segment
		(start 66.539364 -26.790396)
		(end 66.733928 -26.98496)
		(width 0.14224)
		(layer "In2.Cu")
		(net "M_G_DQ<31>")
	)
	(segment
		(start 76.383134 -51.03749)
		(end 78.070964 -52.72532)
		(width 0.0889)
		(layer "In2.Cu")
		(net "M_G_DQ<31>")
	)
	(segment
		(start 65.399412 -16.687546)
		(end 65.71615 -17.004284)
		(width 0.14224)
		(layer "In2.Cu")
		(net "M_G_DQ<31>")
	)
	(segment
		(start 66.977768 -37.592)
		(end 68.247768 -38.862)
		(width 0.14224)
		(layer "In2.Cu")
		(net "M_G_DQ<31>")
	)
	(segment
		(start 66.391536 -34.647632)
		(end 66.183764 -34.855404)
		(width 0.14224)
		(layer "In2.Cu")
		(net "M_G_DQ<31>")
	)
	(segment
		(start 66.590164 -29.071824)
		(end 66.391536 -29.270452)
		(width 0.14224)
		(layer "In2.Cu")
		(net "M_G_DQ<31>")
	)
	(segment
		(start 77.857604 -56.525922)
		(end 77.802486 -56.58104)
		(width 0.0889)
		(layer "In2.Cu")
		(net "M_G_DQ<31>")
	)
	(segment
		(start 66.326004 -37.592)
		(end 66.977768 -37.592)
		(width 0.14224)
		(layer "In2.Cu")
		(net "M_G_DQ<31>")
	)
	(segment
		(start 77.857604 -55.721758)
		(end 77.857604 -56.525922)
		(width 0.0889)
		(layer "In2.Cu")
		(net "M_G_DQ<31>")
	)
	(arc
		(start 74.557636 -50.342038)
		(mid 74.697715 -50.484774)
		(end 74.88936 -50.541936)
		(width 0.0889)
		(layer "In2.Cu")
		(net "M_G_DQ<31>")
	)
	(arc
		(start 77.87386 -55.52186)
		(mid 77.878467 -55.622845)
		(end 77.857604 -55.721758)
		(width 0.0889)
		(layer "In2.Cu")
		(net "M_G_DQ<31>")
	)
	(arc
		(start 77.991462 -53.904642)
		(mid 77.937963 -54.10454)
		(end 77.991462 -54.304438)
		(width 0.0889)
		(layer "In2.Cu")
		(net "M_G_DQ<31>")
	)
	(arc
		(start 77.991462 -54.895242)
		(mid 77.879216 -55.198518)
		(end 77.87386 -55.52186)
		(width 0.0889)
		(layer "In2.Cu")
		(net "M_G_DQ<31>")
	)
	(arc
		(start 77.991462 -54.304438)
		(mid 78.070593 -54.59984)
		(end 77.991462 -54.895242)
		(width 0.0889)
		(layer "In2.Cu")
		(net "M_G_DQ<31>")
	)
	(arc
		(start 75.416156 -50.837338)
		(mid 75.557839 -50.981142)
		(end 75.75169 -51.03749)
		(width 0.0889)
		(layer "In2.Cu")
		(net "M_G_DQ<31>")
	)
	(arc
		(start 78.07071 -53.60924)
		(mid 78.050519 -53.762154)
		(end 77.991462 -53.904642)
		(width 0.0889)
		(layer "In2.Cu")
		(net "M_G_DQ<31>")
	)
	(arc
		(start 74.922126 -50.541936)
		(mid 75.20755 -50.625403)
		(end 75.416156 -50.837338)
		(width 0.0889)
		(layer "In2.Cu")
		(net "M_G_DQ<31>")
	)
	(segment
		(start 66.24955 -19.05)
		(end 66.38163 -18.91792)
		(width 0.1651)
		(layer "F.Cu")
		(net "M_G_DQ<30>")
	)
	(segment
		(start 66.24955 -18.5674)
		(end 66.24955 -18.262854)
		(width 0.1651)
		(layer "F.Cu")
		(net "M_G_DQ<30>")
	)
	(segment
		(start 78.051406 -54.59984)
		(end 77.479906 -54.59984)
		(width 0.1016)
		(layer "F.Cu")
		(net "M_G_DQ<30>")
	)
	(segment
		(start 66.24955 -18.262854)
		(end 66.249296 -18.2626)
		(width 0.1651)
		(layer "F.Cu")
		(net "M_G_DQ<30>")
	)
	(segment
		(start 66.24955 -20.023582)
		(end 66.24955 -19.05)
		(width 0.1651)
		(layer "F.Cu")
		(net "M_G_DQ<30>")
	)
	(segment
		(start 66.38163 -18.91792)
		(end 66.38163 -18.69948)
		(width 0.1651)
		(layer "F.Cu")
		(net "M_G_DQ<30>")
	)
	(segment
		(start 66.38163 -18.69948)
		(end 66.24955 -18.5674)
		(width 0.1651)
		(layer "F.Cu")
		(net "M_G_DQ<30>")
	)
	(via
		(at 65.399412 -23.560278)
		(size 0.508)
		(drill 0.254)
		(layers "F.Cu" "B.Cu")
		(net "M_G_DQ<30>")
	)
	(via
		(at 77.479906 -54.59984)
		(size 0.508)
		(drill 0.254)
		(layers "F.Cu" "B.Cu")
		(net "M_G_DQ<30>")
	)
	(via
		(at 66.249296 -18.2626)
		(size 0.508)
		(drill 0.254)
		(layers "F.Cu" "B.Cu")
		(net "M_G_DQ<30>")
	)
	(segment
		(start 65.399412 -23.560278)
		(end 65.399412 -24.824182)
		(width 0.1651)
		(layer "B.Cu")
		(net "M_G_DQ<30>")
	)
	(segment
		(start 67.546728 -41.844468)
		(end 66.624708 -41.844468)
		(width 0.14224)
		(layer "In2.Cu")
		(net "M_G_DQ<30>")
	)
	(segment
		(start 66.469768 -41.336468)
		(end 66.624708 -41.181528)
		(width 0.14224)
		(layer "In2.Cu")
		(net "M_G_DQ<30>")
	)
	(segment
		(start 66.091308 -39.855648)
		(end 66.683128 -39.855648)
		(width 0.14224)
		(layer "In2.Cu")
		(net "M_G_DQ<30>")
	)
	(segment
		(start 65.904364 -26.714196)
		(end 65.904364 -26.273252)
		(width 0.14224)
		(layer "In2.Cu")
		(net "M_G_DQ<30>")
	)
	(segment
		(start 73.796398 -49.238408)
		(end 67.701668 -43.143678)
		(width 0.14224)
		(layer "In2.Cu")
		(net "M_G_DQ<30>")
	)
	(segment
		(start 65.399412 -23.560278)
		(end 65.1637 -23.324566)
		(width 0.14224)
		(layer "In2.Cu")
		(net "M_G_DQ<30>")
	)
	(segment
		(start 65.1637 -22.530054)
		(end 65.936368 -21.757386)
		(width 0.14224)
		(layer "In2.Cu")
		(net "M_G_DQ<30>")
	)
	(segment
		(start 66.091308 -40.518588)
		(end 65.936368 -40.363648)
		(width 0.14224)
		(layer "In2.Cu")
		(net "M_G_DQ<30>")
	)
	(segment
		(start 67.701668 -41.999408)
		(end 67.546728 -41.844468)
		(width 0.14224)
		(layer "In2.Cu")
		(net "M_G_DQ<30>")
	)
	(segment
		(start 65.8749 -18.914872)
		(end 65.8749 -18.636996)
		(width 0.14224)
		(layer "In2.Cu")
		(net "M_G_DQ<30>")
	)
	(segment
		(start 65.548764 -38.89756)
		(end 65.548764 -34.576004)
		(width 0.14224)
		(layer "In2.Cu")
		(net "M_G_DQ<30>")
	)
	(segment
		(start 65.399412 -23.948644)
		(end 65.399412 -23.560278)
		(width 0.14224)
		(layer "In2.Cu")
		(net "M_G_DQ<30>")
	)
	(segment
		(start 65.701164 -26.917396)
		(end 65.904364 -26.714196)
		(width 0.14224)
		(layer "In2.Cu")
		(net "M_G_DQ<30>")
	)
	(segment
		(start 65.936368 -21.405596)
		(end 65.510918 -20.980146)
		(width 0.14224)
		(layer "In2.Cu")
		(net "M_G_DQ<30>")
	)
	(segment
		(start 65.642236 -24.191468)
		(end 65.399412 -23.948644)
		(width 0.14224)
		(layer "In2.Cu")
		(net "M_G_DQ<30>")
	)
	(segment
		(start 74.392536 -50.437288)
		(end 74.180192 -50.069242)
		(width 0.0889)
		(layer "In2.Cu")
		(net "M_G_DQ<30>")
	)
	(segment
		(start 77.879956 -53.60924)
		(end 77.88021 -53.124608)
		(width 0.0889)
		(layer "In2.Cu")
		(net "M_G_DQ<30>")
	)
	(segment
		(start 65.891918 -20.313904)
		(end 65.891918 -19.970496)
		(width 0.14224)
		(layer "In2.Cu")
		(net "M_G_DQ<30>")
	)
	(segment
		(start 73.844404 -49.286414)
		(end 73.796398 -49.238408)
		(width 0.0889)
		(layer "In2.Cu")
		(net "M_G_DQ<30>")
	)
	(segment
		(start 66.624708 -41.844468)
		(end 66.469768 -41.689528)
		(width 0.14224)
		(layer "In2.Cu")
		(net "M_G_DQ<30>")
	)
	(segment
		(start 65.891918 -19.970496)
		(end 65.510918 -19.589496)
		(width 0.14224)
		(layer "In2.Cu")
		(net "M_G_DQ<30>")
	)
	(segment
		(start 65.642236 -26.011124)
		(end 65.642236 -24.191468)
		(width 0.14224)
		(layer "In2.Cu")
		(net "M_G_DQ<30>")
	)
	(segment
		(start 65.703704 -39.0525)
		(end 65.548764 -38.89756)
		(width 0.14224)
		(layer "In2.Cu")
		(net "M_G_DQ<30>")
	)
	(segment
		(start 65.548764 -34.576004)
		(end 65.756536 -34.368232)
		(width 0.14224)
		(layer "In2.Cu")
		(net "M_G_DQ<30>")
	)
	(segment
		(start 67.546728 -40.518588)
		(end 66.091308 -40.518588)
		(width 0.14224)
		(layer "In2.Cu")
		(net "M_G_DQ<30>")
	)
	(segment
		(start 67.701668 -40.673528)
		(end 67.546728 -40.518588)
		(width 0.14224)
		(layer "In2.Cu")
		(net "M_G_DQ<30>")
	)
	(segment
		(start 65.510918 -20.980146)
		(end 65.510918 -20.694904)
		(width 0.14224)
		(layer "In2.Cu")
		(net "M_G_DQ<30>")
	)
	(segment
		(start 66.624708 -41.181528)
		(end 67.546728 -41.181528)
		(width 0.14224)
		(layer "In2.Cu")
		(net "M_G_DQ<30>")
	)
	(segment
		(start 65.756536 -34.368232)
		(end 65.756536 -28.914852)
		(width 0.14224)
		(layer "In2.Cu")
		(net "M_G_DQ<30>")
	)
	(segment
		(start 74.915522 -50.732436)
		(end 74.882756 -50.732436)
		(width 0.0889)
		(layer "In2.Cu")
		(net "M_G_DQ<30>")
	)
	(segment
		(start 65.929764 -28.741624)
		(end 65.929764 -28.365196)
		(width 0.14224)
		(layer "In2.Cu")
		(net "M_G_DQ<30>")
	)
	(segment
		(start 76.30414 -51.22799)
		(end 75.745086 -51.22799)
		(width 0.0889)
		(layer "In2.Cu")
		(net "M_G_DQ<30>")
	)
	(segment
		(start 67.546728 -41.181528)
		(end 67.701668 -41.026588)
		(width 0.14224)
		(layer "In2.Cu")
		(net "M_G_DQ<30>")
	)
	(segment
		(start 66.825368 -39.713408)
		(end 66.825368 -39.19474)
		(width 0.14224)
		(layer "In2.Cu")
		(net "M_G_DQ<30>")
	)
	(segment
		(start 65.904364 -26.273252)
		(end 65.642236 -26.011124)
		(width 0.14224)
		(layer "In2.Cu")
		(net "M_G_DQ<30>")
	)
	(segment
		(start 77.880464 -52.804314)
		(end 76.30414 -51.22799)
		(width 0.0889)
		(layer "In2.Cu")
		(net "M_G_DQ<30>")
	)
	(segment
		(start 77.479906 -54.59984)
		(end 77.785214 -53.895752)
		(width 0.0889)
		(layer "In2.Cu")
		(net "M_G_DQ<30>")
	)
	(segment
		(start 65.936368 -40.010588)
		(end 66.091308 -39.855648)
		(width 0.14224)
		(layer "In2.Cu")
		(net "M_G_DQ<30>")
	)
	(segment
		(start 77.880464 -53.124354)
		(end 77.880464 -52.804314)
		(width 0.0889)
		(layer "In2.Cu")
		(net "M_G_DQ<30>")
	)
	(segment
		(start 74.180192 -50.069242)
		(end 74.180192 -49.362614)
		(width 0.0889)
		(layer "In2.Cu")
		(net "M_G_DQ<30>")
	)
	(segment
		(start 74.180192 -49.362614)
		(end 74.103992 -49.286414)
		(width 0.0889)
		(layer "In2.Cu")
		(net "M_G_DQ<30>")
	)
	(segment
		(start 65.756536 -28.914852)
		(end 65.929764 -28.741624)
		(width 0.14224)
		(layer "In2.Cu")
		(net "M_G_DQ<30>")
	)
	(segment
		(start 66.825368 -39.19474)
		(end 66.683128 -39.0525)
		(width 0.14224)
		(layer "In2.Cu")
		(net "M_G_DQ<30>")
	)
	(segment
		(start 65.8749 -18.636996)
		(end 66.249296 -18.2626)
		(width 0.14224)
		(layer "In2.Cu")
		(net "M_G_DQ<30>")
	)
	(segment
		(start 65.929764 -28.365196)
		(end 65.701164 -28.136596)
		(width 0.14224)
		(layer "In2.Cu")
		(net "M_G_DQ<30>")
	)
	(segment
		(start 66.683128 -39.0525)
		(end 65.703704 -39.0525)
		(width 0.14224)
		(layer "In2.Cu")
		(net "M_G_DQ<30>")
	)
	(segment
		(start 66.469768 -41.689528)
		(end 66.469768 -41.336468)
		(width 0.14224)
		(layer "In2.Cu")
		(net "M_G_DQ<30>")
	)
	(segment
		(start 65.510918 -19.589496)
		(end 65.510918 -19.278854)
		(width 0.14224)
		(layer "In2.Cu")
		(net "M_G_DQ<30>")
	)
	(segment
		(start 65.1637 -23.324566)
		(end 65.1637 -22.530054)
		(width 0.14224)
		(layer "In2.Cu")
		(net "M_G_DQ<30>")
	)
	(segment
		(start 74.103992 -49.286414)
		(end 73.844404 -49.286414)
		(width 0.0889)
		(layer "In2.Cu")
		(net "M_G_DQ<30>")
	)
	(segment
		(start 66.683128 -39.855648)
		(end 66.825368 -39.713408)
		(width 0.14224)
		(layer "In2.Cu")
		(net "M_G_DQ<30>")
	)
	(segment
		(start 65.701164 -28.136596)
		(end 65.701164 -26.917396)
		(width 0.14224)
		(layer "In2.Cu")
		(net "M_G_DQ<30>")
	)
	(segment
		(start 67.701668 -43.143678)
		(end 67.701668 -41.999408)
		(width 0.14224)
		(layer "In2.Cu")
		(net "M_G_DQ<30>")
	)
	(segment
		(start 65.936368 -21.757386)
		(end 65.936368 -21.405596)
		(width 0.14224)
		(layer "In2.Cu")
		(net "M_G_DQ<30>")
	)
	(segment
		(start 65.510918 -19.278854)
		(end 65.8749 -18.914872)
		(width 0.14224)
		(layer "In2.Cu")
		(net "M_G_DQ<30>")
	)
	(segment
		(start 65.936368 -40.363648)
		(end 65.936368 -40.010588)
		(width 0.14224)
		(layer "In2.Cu")
		(net "M_G_DQ<30>")
	)
	(segment
		(start 65.510918 -20.694904)
		(end 65.891918 -20.313904)
		(width 0.14224)
		(layer "In2.Cu")
		(net "M_G_DQ<30>")
	)
	(segment
		(start 77.88021 -53.124608)
		(end 77.880464 -53.124354)
		(width 0.0889)
		(layer "In2.Cu")
		(net "M_G_DQ<30>")
	)
	(segment
		(start 67.701668 -41.026588)
		(end 67.701668 -40.673528)
		(width 0.14224)
		(layer "In2.Cu")
		(net "M_G_DQ<30>")
	)
	(arc
		(start 74.882756 -50.732436)
		(mid 74.599539 -50.648155)
		(end 74.392536 -50.437288)
		(width 0.0889)
		(layer "In2.Cu")
		(net "M_G_DQ<30>")
	)
	(arc
		(start 77.785214 -53.895752)
		(mid 77.804032 -53.851611)
		(end 77.826362 -53.809138)
		(width 0.0889)
		(layer "In2.Cu")
		(net "M_G_DQ<30>")
	)
	(arc
		(start 77.826362 -53.809138)
		(mid 77.866316 -53.712714)
		(end 77.879956 -53.60924)
		(width 0.0889)
		(layer "In2.Cu")
		(net "M_G_DQ<30>")
	)
	(arc
		(start 75.745086 -51.22799)
		(mid 75.459662 -51.144523)
		(end 75.251056 -50.932588)
		(width 0.0889)
		(layer "In2.Cu")
		(net "M_G_DQ<30>")
	)
	(arc
		(start 75.251056 -50.932588)
		(mid 75.109373 -50.788784)
		(end 74.915522 -50.732436)
		(width 0.0889)
		(layer "In2.Cu")
		(net "M_G_DQ<30>")
	)
	(segment
		(start 40.030908 -18.67154)
		(end 39.899336 -18.539968)
		(width 0.1651)
		(layer "F.Cu")
		(net "M_G_DQ<2>")
	)
	(segment
		(start 39.899336 -20.023582)
		(end 39.899336 -19.026632)
		(width 0.1651)
		(layer "F.Cu")
		(net "M_G_DQ<2>")
	)
	(segment
		(start 67.749166 -61.53404)
		(end 67.079368 -61.53404)
		(width 0.1016)
		(layer "F.Cu")
		(net "M_G_DQ<2>")
	)
	(segment
		(start 40.030908 -18.89506)
		(end 40.030908 -18.67154)
		(width 0.1651)
		(layer "F.Cu")
		(net "M_G_DQ<2>")
	)
	(segment
		(start 39.899336 -19.026632)
		(end 40.030908 -18.89506)
		(width 0.1651)
		(layer "F.Cu")
		(net "M_G_DQ<2>")
	)
	(segment
		(start 39.899336 -18.539968)
		(end 39.899336 -18.2626)
		(width 0.1651)
		(layer "F.Cu")
		(net "M_G_DQ<2>")
	)
	(via
		(at 39.899336 -18.2626)
		(size 0.508)
		(drill 0.254)
		(layers "F.Cu" "B.Cu")
		(net "M_G_DQ<2>")
	)
	(via
		(at 67.079368 -61.53404)
		(size 0.508)
		(drill 0.254)
		(layers "F.Cu" "B.Cu")
		(net "M_G_DQ<2>")
	)
	(via
		(at 39.049452 -23.560278)
		(size 0.508)
		(drill 0.254)
		(layers "F.Cu" "B.Cu")
		(net "M_G_DQ<2>")
	)
	(segment
		(start 39.049452 -23.560278)
		(end 39.049452 -24.824182)
		(width 0.1651)
		(layer "B.Cu")
		(net "M_G_DQ<2>")
	)
	(segment
		(start 39.481252 -23.992078)
		(end 39.481252 -24.472138)
		(width 0.14224)
		(layer "In2.Cu")
		(net "M_G_DQ<2>")
	)
	(segment
		(start 40.127936 -31.623)
		(end 40.331136 -31.8262)
		(width 0.14224)
		(layer "In2.Cu")
		(net "M_G_DQ<2>")
	)
	(segment
		(start 39.049452 -23.560278)
		(end 39.481252 -23.992078)
		(width 0.14224)
		(layer "In2.Cu")
		(net "M_G_DQ<2>")
	)
	(segment
		(start 38.764718 -22.5298)
		(end 39.613586 -21.680932)
		(width 0.14224)
		(layer "In2.Cu")
		(net "M_G_DQ<2>")
	)
	(segment
		(start 40.635936 -31.8262)
		(end 40.839136 -31.623)
		(width 0.14224)
		(layer "In2.Cu")
		(net "M_G_DQ<2>")
	)
	(segment
		(start 65.958974 -61.635386)
		(end 66.06032 -61.53404)
		(width 0.0889)
		(layer "In2.Cu")
		(net "M_G_DQ<2>")
	)
	(segment
		(start 41.042336 -26.0096)
		(end 41.347136 -26.0096)
		(width 0.14224)
		(layer "In2.Cu")
		(net "M_G_DQ<2>")
	)
	(segment
		(start 39.461186 -20.25015)
		(end 39.461186 -19.964146)
		(width 0.14224)
		(layer "In2.Cu")
		(net "M_G_DQ<2>")
	)
	(segment
		(start 39.501318 -18.965672)
		(end 39.501318 -18.660618)
		(width 0.14224)
		(layer "In2.Cu")
		(net "M_G_DQ<2>")
	)
	(segment
		(start 39.461186 -19.964146)
		(end 39.156386 -19.659346)
		(width 0.14224)
		(layer "In2.Cu")
		(net "M_G_DQ<2>")
	)
	(segment
		(start 40.331136 -31.8262)
		(end 40.635936 -31.8262)
		(width 0.14224)
		(layer "In2.Cu")
		(net "M_G_DQ<2>")
	)
	(segment
		(start 39.156386 -20.955)
		(end 39.156386 -20.55495)
		(width 0.14224)
		(layer "In2.Cu")
		(net "M_G_DQ<2>")
	)
	(segment
		(start 64.903604 -61.635386)
		(end 65.631568 -61.635386)
		(width 0.14224)
		(layer "In2.Cu")
		(net "M_G_DQ<2>")
	)
	(segment
		(start 39.156386 -19.310604)
		(end 39.501318 -18.965672)
		(width 0.14224)
		(layer "In2.Cu")
		(net "M_G_DQ<2>")
	)
	(segment
		(start 39.049452 -23.560278)
		(end 38.764718 -23.275544)
		(width 0.14224)
		(layer "In2.Cu")
		(net "M_G_DQ<2>")
	)
	(segment
		(start 41.347136 -26.0096)
		(end 41.550336 -26.2128)
		(width 0.14224)
		(layer "In2.Cu")
		(net "M_G_DQ<2>")
	)
	(segment
		(start 39.501318 -18.660618)
		(end 39.899336 -18.2626)
		(width 0.14224)
		(layer "In2.Cu")
		(net "M_G_DQ<2>")
	)
	(segment
		(start 41.550336 -26.2128)
		(end 41.550336 -38.282118)
		(width 0.14224)
		(layer "In2.Cu")
		(net "M_G_DQ<2>")
	)
	(segment
		(start 40.839136 -31.623)
		(end 40.839136 -26.2128)
		(width 0.14224)
		(layer "In2.Cu")
		(net "M_G_DQ<2>")
	)
	(segment
		(start 39.156386 -20.55495)
		(end 39.461186 -20.25015)
		(width 0.14224)
		(layer "In2.Cu")
		(net "M_G_DQ<2>")
	)
	(segment
		(start 40.127936 -25.118822)
		(end 40.127936 -31.623)
		(width 0.14224)
		(layer "In2.Cu")
		(net "M_G_DQ<2>")
	)
	(segment
		(start 40.839136 -26.2128)
		(end 41.042336 -26.0096)
		(width 0.14224)
		(layer "In2.Cu")
		(net "M_G_DQ<2>")
	)
	(segment
		(start 39.613586 -21.4122)
		(end 39.156386 -20.955)
		(width 0.14224)
		(layer "In2.Cu")
		(net "M_G_DQ<2>")
	)
	(segment
		(start 39.481252 -24.472138)
		(end 40.127936 -25.118822)
		(width 0.14224)
		(layer "In2.Cu")
		(net "M_G_DQ<2>")
	)
	(segment
		(start 39.156386 -19.659346)
		(end 39.156386 -19.310604)
		(width 0.14224)
		(layer "In2.Cu")
		(net "M_G_DQ<2>")
	)
	(segment
		(start 66.06032 -61.53404)
		(end 67.079368 -61.53404)
		(width 0.0889)
		(layer "In2.Cu")
		(net "M_G_DQ<2>")
	)
	(segment
		(start 65.631568 -61.635386)
		(end 65.958974 -61.635386)
		(width 0.0889)
		(layer "In2.Cu")
		(net "M_G_DQ<2>")
	)
	(segment
		(start 39.613586 -21.680932)
		(end 39.613586 -21.4122)
		(width 0.14224)
		(layer "In2.Cu")
		(net "M_G_DQ<2>")
	)
	(segment
		(start 41.550336 -38.282118)
		(end 64.903604 -61.635386)
		(width 0.14224)
		(layer "In2.Cu")
		(net "M_G_DQ<2>")
	)
	(segment
		(start 38.764718 -23.275544)
		(end 38.764718 -22.5298)
		(width 0.14224)
		(layer "In2.Cu")
		(net "M_G_DQ<2>")
	)
	(segment
		(start 59.449462 -15.423642)
		(end 59.449462 -16.687546)
		(width 0.1651)
		(layer "F.Cu")
		(net "M_G_DQ<29>")
	)
	(segment
		(start 75.475846 -56.085486)
		(end 74.904346 -56.085486)
		(width 0.1016)
		(layer "F.Cu")
		(net "M_G_DQ<29>")
	)
	(via
		(at 59.449462 -16.687546)
		(size 0.508)
		(drill 0.254)
		(layers "F.Cu" "B.Cu")
		(net "M_G_DQ<29>")
	)
	(via
		(at 74.904346 -56.085486)
		(size 0.508)
		(drill 0.254)
		(layers "F.Cu" "B.Cu")
		(net "M_G_DQ<29>")
	)
	(via
		(at 60.223146 -22.279356)
		(size 0.508)
		(drill 0.254)
		(layers "F.Cu" "B.Cu")
		(net "M_G_DQ<29>")
	)
	(segment
		(start 60.299346 -22.203156)
		(end 60.223146 -22.279356)
		(width 0.1651)
		(layer "B.Cu")
		(net "M_G_DQ<29>")
	)
	(segment
		(start 60.299346 -20.224242)
		(end 60.299346 -22.203156)
		(width 0.1651)
		(layer "B.Cu")
		(net "M_G_DQ<29>")
	)
	(segment
		(start 60.595764 -26.968196)
		(end 60.697364 -27.069796)
		(width 0.14224)
		(layer "In2.Cu")
		(net "M_G_DQ<29>")
	)
	(segment
		(start 60.7314 -18.053304)
		(end 60.7314 -18.4658)
		(width 0.14224)
		(layer "In2.Cu")
		(net "M_G_DQ<29>")
	)
	(segment
		(start 60.697364 -27.069796)
		(end 60.697364 -28.212796)
		(width 0.14224)
		(layer "In2.Cu")
		(net "M_G_DQ<29>")
	)
	(segment
		(start 60.697364 -28.212796)
		(end 60.549536 -28.360624)
		(width 0.14224)
		(layer "In2.Cu")
		(net "M_G_DQ<29>")
	)
	(segment
		(start 60.549536 -28.360624)
		(end 60.549536 -28.938474)
		(width 0.14224)
		(layer "In2.Cu")
		(net "M_G_DQ<29>")
	)
	(segment
		(start 69.73824 -51.532536)
		(end 69.76618 -51.532536)
		(width 0.0889)
		(layer "In2.Cu")
		(net "M_G_DQ<29>")
	)
	(segment
		(start 60.7314 -18.4658)
		(end 60.53455 -18.66265)
		(width 0.14224)
		(layer "In2.Cu")
		(net "M_G_DQ<29>")
	)
	(segment
		(start 60.549536 -31.364174)
		(end 60.549536 -42.69867)
		(width 0.14224)
		(layer "In2.Cu")
		(net "M_G_DQ<29>")
	)
	(segment
		(start 69.298312 -51.143154)
		(end 69.406516 -51.332638)
		(width 0.0889)
		(layer "In2.Cu")
		(net "M_G_DQ<29>")
	)
	(segment
		(start 61.034168 -29.270706)
		(end 61.034168 -29.774642)
		(width 0.14224)
		(layer "In2.Cu")
		(net "M_G_DQ<29>")
	)
	(segment
		(start 75.251056 -55.295038)
		(end 75.234292 -55.32374)
		(width 0.0889)
		(layer "In2.Cu")
		(net "M_G_DQ<29>")
	)
	(segment
		(start 59.449462 -16.687546)
		(end 59.449462 -17.082262)
		(width 0.14224)
		(layer "In2.Cu")
		(net "M_G_DQ<29>")
	)
	(segment
		(start 74.03465 -54.00929)
		(end 74.067416 -54.00929)
		(width 0.0889)
		(layer "In2.Cu")
		(net "M_G_DQ<29>")
	)
	(segment
		(start 60.549536 -42.69867)
		(end 62.123066 -44.2722)
		(width 0.14224)
		(layer "In2.Cu")
		(net "M_G_DQ<29>")
	)
	(segment
		(start 60.53455 -18.66265)
		(end 60.53455 -21.967952)
		(width 0.14224)
		(layer "In2.Cu")
		(net "M_G_DQ<29>")
	)
	(segment
		(start 70.593712 -52.027836)
		(end 70.629526 -52.027836)
		(width 0.0889)
		(layer "In2.Cu")
		(net "M_G_DQ<29>")
	)
	(segment
		(start 60.549536 -28.938474)
		(end 60.752736 -29.141674)
		(width 0.14224)
		(layer "In2.Cu")
		(net "M_G_DQ<29>")
	)
	(segment
		(start 60.0202 -17.653)
		(end 60.331096 -17.653)
		(width 0.14224)
		(layer "In2.Cu")
		(net "M_G_DQ<29>")
	)
	(segment
		(start 60.223146 -22.279356)
		(end 60.179458 -22.279356)
		(width 0.14224)
		(layer "In2.Cu")
		(net "M_G_DQ<29>")
	)
	(segment
		(start 60.595764 -24.021796)
		(end 60.595764 -26.968196)
		(width 0.14224)
		(layer "In2.Cu")
		(net "M_G_DQ<29>")
	)
	(segment
		(start 75.086464 -54.609492)
		(end 75.251056 -54.894988)
		(width 0.0889)
		(layer "In2.Cu")
		(net "M_G_DQ<29>")
	)
	(segment
		(start 59.706764 -23.132796)
		(end 60.595764 -24.021796)
		(width 0.14224)
		(layer "In2.Cu")
		(net "M_G_DQ<29>")
	)
	(segment
		(start 60.879736 -31.033974)
		(end 60.549536 -31.364174)
		(width 0.14224)
		(layer "In2.Cu")
		(net "M_G_DQ<29>")
	)
	(segment
		(start 75.234292 -55.32374)
		(end 74.904346 -56.085486)
		(width 0.0889)
		(layer "In2.Cu")
		(net "M_G_DQ<29>")
	)
	(segment
		(start 60.752736 -29.141674)
		(end 60.905136 -29.141674)
		(width 0.14224)
		(layer "In2.Cu")
		(net "M_G_DQ<29>")
	)
	(segment
		(start 59.449462 -17.082262)
		(end 60.0202 -17.653)
		(width 0.14224)
		(layer "In2.Cu")
		(net "M_G_DQ<29>")
	)
	(segment
		(start 69.02577 -50.140616)
		(end 69.298312 -50.413158)
		(width 0.0889)
		(layer "In2.Cu")
		(net "M_G_DQ<29>")
	)
	(segment
		(start 60.549536 -30.157674)
		(end 60.549536 -30.392624)
		(width 0.14224)
		(layer "In2.Cu")
		(net "M_G_DQ<29>")
	)
	(segment
		(start 59.706764 -22.75205)
		(end 59.706764 -23.132796)
		(width 0.14224)
		(layer "In2.Cu")
		(net "M_G_DQ<29>")
	)
	(segment
		(start 63.157354 -44.2722)
		(end 69.02577 -50.140616)
		(width 0.14224)
		(layer "In2.Cu")
		(net "M_G_DQ<29>")
	)
	(segment
		(start 73.17232 -53.513736)
		(end 73.205086 -53.513736)
		(width 0.0889)
		(layer "In2.Cu")
		(net "M_G_DQ<29>")
	)
	(segment
		(start 60.752736 -29.954474)
		(end 60.549536 -30.157674)
		(width 0.14224)
		(layer "In2.Cu")
		(net "M_G_DQ<29>")
	)
	(segment
		(start 60.905136 -29.141674)
		(end 61.034168 -29.270706)
		(width 0.14224)
		(layer "In2.Cu")
		(net "M_G_DQ<29>")
	)
	(segment
		(start 74.88936 -54.504336)
		(end 74.904346 -54.504336)
		(width 0.0889)
		(layer "In2.Cu")
		(net "M_G_DQ<29>")
	)
	(segment
		(start 60.331096 -17.653)
		(end 60.7314 -18.053304)
		(width 0.14224)
		(layer "In2.Cu")
		(net "M_G_DQ<29>")
	)
	(segment
		(start 60.549536 -30.392624)
		(end 60.879736 -30.722824)
		(width 0.14224)
		(layer "In2.Cu")
		(net "M_G_DQ<29>")
	)
	(segment
		(start 72.31761 -53.018436)
		(end 72.34174 -53.018436)
		(width 0.0889)
		(layer "In2.Cu")
		(net "M_G_DQ<29>")
	)
	(segment
		(start 62.123066 -44.2722)
		(end 63.157354 -44.2722)
		(width 0.14224)
		(layer "In2.Cu")
		(net "M_G_DQ<29>")
	)
	(segment
		(start 71.452232 -52.523136)
		(end 71.491856 -52.523136)
		(width 0.0889)
		(layer "In2.Cu")
		(net "M_G_DQ<29>")
	)
	(segment
		(start 69.298312 -50.413158)
		(end 69.298312 -51.143154)
		(width 0.0889)
		(layer "In2.Cu")
		(net "M_G_DQ<29>")
	)
	(segment
		(start 75.251056 -54.894988)
		(end 75.255882 -54.903624)
		(width 0.0889)
		(layer "In2.Cu")
		(net "M_G_DQ<29>")
	)
	(segment
		(start 61.034168 -29.774642)
		(end 60.854336 -29.954474)
		(width 0.14224)
		(layer "In2.Cu")
		(net "M_G_DQ<29>")
	)
	(segment
		(start 60.879736 -30.722824)
		(end 60.879736 -31.033974)
		(width 0.14224)
		(layer "In2.Cu")
		(net "M_G_DQ<29>")
	)
	(segment
		(start 60.53455 -21.967952)
		(end 60.223146 -22.279356)
		(width 0.14224)
		(layer "In2.Cu")
		(net "M_G_DQ<29>")
	)
	(segment
		(start 60.854336 -29.954474)
		(end 60.752736 -29.954474)
		(width 0.14224)
		(layer "In2.Cu")
		(net "M_G_DQ<29>")
	)
	(segment
		(start 60.179458 -22.279356)
		(end 59.706764 -22.75205)
		(width 0.14224)
		(layer "In2.Cu")
		(net "M_G_DQ<29>")
	)
	(arc
		(start 69.406516 -51.332638)
		(mid 69.546595 -51.475374)
		(end 69.73824 -51.532536)
		(width 0.0889)
		(layer "In2.Cu")
		(net "M_G_DQ<29>")
	)
	(arc
		(start 72.840596 -53.313838)
		(mid 72.980675 -53.456574)
		(end 73.17232 -53.513736)
		(width 0.0889)
		(layer "In2.Cu")
		(net "M_G_DQ<29>")
	)
	(arc
		(start 71.491856 -52.523136)
		(mid 71.775073 -52.607417)
		(end 71.982076 -52.818284)
		(width 0.0889)
		(layer "In2.Cu")
		(net "M_G_DQ<29>")
	)
	(arc
		(start 73.205086 -53.513736)
		(mid 73.49051 -53.597203)
		(end 73.699116 -53.809138)
		(width 0.0889)
		(layer "In2.Cu")
		(net "M_G_DQ<29>")
	)
	(arc
		(start 71.982076 -52.818284)
		(mid 72.123759 -52.962088)
		(end 72.31761 -53.018436)
		(width 0.0889)
		(layer "In2.Cu")
		(net "M_G_DQ<29>")
	)
	(arc
		(start 74.557636 -54.304438)
		(mid 74.697715 -54.447174)
		(end 74.88936 -54.504336)
		(width 0.0889)
		(layer "In2.Cu")
		(net "M_G_DQ<29>")
	)
	(arc
		(start 73.699116 -53.809138)
		(mid 73.840799 -53.952942)
		(end 74.03465 -54.00929)
		(width 0.0889)
		(layer "In2.Cu")
		(net "M_G_DQ<29>")
	)
	(arc
		(start 75.255882 -54.903624)
		(mid 75.304637 -55.099976)
		(end 75.251056 -55.295038)
		(width 0.0889)
		(layer "In2.Cu")
		(net "M_G_DQ<29>")
	)
	(arc
		(start 72.34174 -53.018436)
		(mid 72.629885 -53.100755)
		(end 72.840596 -53.313838)
		(width 0.0889)
		(layer "In2.Cu")
		(net "M_G_DQ<29>")
	)
	(arc
		(start 71.123556 -52.323238)
		(mid 71.2623 -52.465271)
		(end 71.452232 -52.523136)
		(width 0.0889)
		(layer "In2.Cu")
		(net "M_G_DQ<29>")
	)
	(arc
		(start 74.067416 -54.00929)
		(mid 74.350633 -54.093571)
		(end 74.557636 -54.304438)
		(width 0.0889)
		(layer "In2.Cu")
		(net "M_G_DQ<29>")
	)
	(arc
		(start 74.904346 -54.504336)
		(mid 75.009498 -54.53251)
		(end 75.086464 -54.609492)
		(width 0.0889)
		(layer "In2.Cu")
		(net "M_G_DQ<29>")
	)
	(arc
		(start 70.265036 -51.827938)
		(mid 70.40378 -51.969971)
		(end 70.593712 -52.027836)
		(width 0.0889)
		(layer "In2.Cu")
		(net "M_G_DQ<29>")
	)
	(arc
		(start 69.76618 -51.532536)
		(mid 70.054325 -51.614855)
		(end 70.265036 -51.827938)
		(width 0.0889)
		(layer "In2.Cu")
		(net "M_G_DQ<29>")
	)
	(arc
		(start 70.629526 -52.027836)
		(mid 70.91495 -52.111303)
		(end 71.123556 -52.323238)
		(width 0.0889)
		(layer "In2.Cu")
		(net "M_G_DQ<29>")
	)
	(segment
		(start 75.475846 -55.094886)
		(end 74.904346 -55.094886)
		(width 0.1016)
		(layer "F.Cu")
		(net "M_G_DQ<28>")
	)
	(segment
		(start 60.299346 -20.023582)
		(end 60.299346 -18.692368)
		(width 0.1651)
		(layer "F.Cu")
		(net "M_G_DQ<28>")
	)
	(segment
		(start 60.299346 -18.692368)
		(end 60.201302 -18.161)
		(width 0.1651)
		(layer "F.Cu")
		(net "M_G_DQ<28>")
	)
	(via
		(at 74.904346 -55.094886)
		(size 0.508)
		(drill 0.254)
		(layers "F.Cu" "B.Cu")
		(net "M_G_DQ<28>")
	)
	(via
		(at 59.449462 -23.560278)
		(size 0.508)
		(drill 0.254)
		(layers "F.Cu" "B.Cu")
		(net "M_G_DQ<28>")
	)
	(via
		(at 60.201302 -18.161)
		(size 0.508)
		(drill 0.254)
		(layers "F.Cu" "B.Cu")
		(net "M_G_DQ<28>")
	)
	(segment
		(start 59.449462 -23.560278)
		(end 59.449462 -24.824182)
		(width 0.1651)
		(layer "B.Cu")
		(net "M_G_DQ<28>")
	)
	(segment
		(start 60.201302 -18.161)
		(end 59.92495 -18.437352)
		(width 0.14224)
		(layer "In2.Cu")
		(net "M_G_DQ<28>")
	)
	(segment
		(start 59.21375 -22.530054)
		(end 59.21375 -23.324566)
		(width 0.14224)
		(layer "In2.Cu")
		(net "M_G_DQ<28>")
	)
	(segment
		(start 59.755024 -31.548578)
		(end 59.909964 -31.703518)
		(width 0.14224)
		(layer "In2.Cu")
		(net "M_G_DQ<28>")
	)
	(segment
		(start 59.573668 -20.6375)
		(end 59.573668 -20.992846)
		(width 0.14224)
		(layer "In2.Cu")
		(net "M_G_DQ<28>")
	)
	(segment
		(start 74.4093 -54.429152)
		(end 74.904346 -55.094886)
		(width 0.0889)
		(layer "In2.Cu")
		(net "M_G_DQ<28>")
	)
	(segment
		(start 59.909964 -42.957242)
		(end 62.113922 -45.1612)
		(width 0.14224)
		(layer "In2.Cu")
		(net "M_G_DQ<28>")
	)
	(segment
		(start 59.909964 -28.314396)
		(end 59.909964 -29.404818)
		(width 0.14224)
		(layer "In2.Cu")
		(net "M_G_DQ<28>")
	)
	(segment
		(start 59.92495 -21.344128)
		(end 59.92495 -21.818854)
		(width 0.14224)
		(layer "In2.Cu")
		(net "M_G_DQ<28>")
	)
	(segment
		(start 59.21375 -23.324566)
		(end 59.449462 -23.560278)
		(width 0.14224)
		(layer "In2.Cu")
		(net "M_G_DQ<28>")
	)
	(segment
		(start 59.960764 -26.663396)
		(end 59.706764 -26.917396)
		(width 0.14224)
		(layer "In2.Cu")
		(net "M_G_DQ<28>")
	)
	(segment
		(start 59.960764 -24.07158)
		(end 59.960764 -24.526748)
		(width 0.14224)
		(layer "In2.Cu")
		(net "M_G_DQ<28>")
	)
	(segment
		(start 59.706764 -26.917396)
		(end 59.706764 -28.111196)
		(width 0.14224)
		(layer "In2.Cu")
		(net "M_G_DQ<28>")
	)
	(segment
		(start 59.573668 -20.992846)
		(end 59.92495 -21.344128)
		(width 0.14224)
		(layer "In2.Cu")
		(net "M_G_DQ<28>")
	)
	(segment
		(start 59.319668 -30.067758)
		(end 59.474608 -30.222698)
		(width 0.14224)
		(layer "In2.Cu")
		(net "M_G_DQ<28>")
	)
	(segment
		(start 70.590156 -52.21859)
		(end 70.62978 -52.21859)
		(width 0.0889)
		(layer "In2.Cu")
		(net "M_G_DQ<28>")
	)
	(segment
		(start 59.755024 -32.211518)
		(end 59.601608 -32.211518)
		(width 0.14224)
		(layer "In2.Cu")
		(net "M_G_DQ<28>")
	)
	(segment
		(start 59.755024 -30.222698)
		(end 59.909964 -30.377638)
		(width 0.14224)
		(layer "In2.Cu")
		(net "M_G_DQ<28>")
	)
	(segment
		(start 68.990972 -51.021234)
		(end 69.241416 -51.427888)
		(width 0.0889)
		(layer "In2.Cu")
		(net "M_G_DQ<28>")
	)
	(segment
		(start 62.113922 -45.1612)
		(end 63.130176 -45.1612)
		(width 0.14224)
		(layer "In2.Cu")
		(net "M_G_DQ<28>")
	)
	(segment
		(start 72.315832 -53.20919)
		(end 72.343772 -53.20919)
		(width 0.0889)
		(layer "In2.Cu")
		(net "M_G_DQ<28>")
	)
	(segment
		(start 59.909964 -30.730698)
		(end 59.755024 -30.885638)
		(width 0.14224)
		(layer "In2.Cu")
		(net "M_G_DQ<28>")
	)
	(segment
		(start 59.319668 -29.714698)
		(end 59.319668 -30.067758)
		(width 0.14224)
		(layer "In2.Cu")
		(net "M_G_DQ<28>")
	)
	(segment
		(start 59.459368 -32.353758)
		(end 59.459368 -32.732218)
		(width 0.14224)
		(layer "In2.Cu")
		(net "M_G_DQ<28>")
	)
	(segment
		(start 59.941968 -20.2692)
		(end 59.573668 -20.6375)
		(width 0.14224)
		(layer "In2.Cu")
		(net "M_G_DQ<28>")
	)
	(segment
		(start 59.319668 -31.393638)
		(end 59.474608 -31.548578)
		(width 0.14224)
		(layer "In2.Cu")
		(net "M_G_DQ<28>")
	)
	(segment
		(start 59.560968 -19.278854)
		(end 59.560968 -19.5834)
		(width 0.14224)
		(layer "In2.Cu")
		(net "M_G_DQ<28>")
	)
	(segment
		(start 59.909964 -30.377638)
		(end 59.909964 -30.730698)
		(width 0.14224)
		(layer "In2.Cu")
		(net "M_G_DQ<28>")
	)
	(segment
		(start 68.763642 -50.794666)
		(end 68.946014 -50.977038)
		(width 0.0889)
		(layer "In2.Cu")
		(net "M_G_DQ<28>")
	)
	(segment
		(start 59.711336 -24.776176)
		(end 59.711336 -25.339548)
		(width 0.14224)
		(layer "In2.Cu")
		(net "M_G_DQ<28>")
	)
	(segment
		(start 59.474608 -31.548578)
		(end 59.755024 -31.548578)
		(width 0.14224)
		(layer "In2.Cu")
		(net "M_G_DQ<28>")
	)
	(segment
		(start 59.474608 -30.885638)
		(end 59.319668 -31.040578)
		(width 0.14224)
		(layer "In2.Cu")
		(net "M_G_DQ<28>")
	)
	(segment
		(start 59.755024 -32.874458)
		(end 59.909964 -33.029398)
		(width 0.14224)
		(layer "In2.Cu")
		(net "M_G_DQ<28>")
	)
	(segment
		(start 59.319668 -31.040578)
		(end 59.319668 -31.393638)
		(width 0.14224)
		(layer "In2.Cu")
		(net "M_G_DQ<28>")
	)
	(segment
		(start 59.755024 -30.885638)
		(end 59.474608 -30.885638)
		(width 0.14224)
		(layer "In2.Cu")
		(net "M_G_DQ<28>")
	)
	(segment
		(start 59.960764 -24.526748)
		(end 59.711336 -24.776176)
		(width 0.14224)
		(layer "In2.Cu")
		(net "M_G_DQ<28>")
	)
	(segment
		(start 71.452486 -52.71389)
		(end 71.4883 -52.71389)
		(width 0.0889)
		(layer "In2.Cu")
		(net "M_G_DQ<28>")
	)
	(segment
		(start 69.740272 -51.72329)
		(end 69.764402 -51.72329)
		(width 0.0889)
		(layer "In2.Cu")
		(net "M_G_DQ<28>")
	)
	(segment
		(start 59.459368 -32.732218)
		(end 59.601608 -32.874458)
		(width 0.14224)
		(layer "In2.Cu")
		(net "M_G_DQ<28>")
	)
	(segment
		(start 59.474608 -29.559758)
		(end 59.319668 -29.714698)
		(width 0.14224)
		(layer "In2.Cu")
		(net "M_G_DQ<28>")
	)
	(segment
		(start 59.960764 -25.588976)
		(end 59.960764 -26.663396)
		(width 0.14224)
		(layer "In2.Cu")
		(net "M_G_DQ<28>")
	)
	(segment
		(start 59.474608 -30.222698)
		(end 59.755024 -30.222698)
		(width 0.14224)
		(layer "In2.Cu")
		(net "M_G_DQ<28>")
	)
	(segment
		(start 59.909964 -29.404818)
		(end 59.755024 -29.559758)
		(width 0.14224)
		(layer "In2.Cu")
		(net "M_G_DQ<28>")
	)
	(segment
		(start 59.755024 -29.559758)
		(end 59.474608 -29.559758)
		(width 0.14224)
		(layer "In2.Cu")
		(net "M_G_DQ<28>")
	)
	(segment
		(start 59.92495 -18.914872)
		(end 59.560968 -19.278854)
		(width 0.14224)
		(layer "In2.Cu")
		(net "M_G_DQ<28>")
	)
	(segment
		(start 74.392536 -54.399688)
		(end 74.4093 -54.429152)
		(width 0.0889)
		(layer "In2.Cu")
		(net "M_G_DQ<28>")
	)
	(segment
		(start 59.706764 -28.111196)
		(end 59.909964 -28.314396)
		(width 0.14224)
		(layer "In2.Cu")
		(net "M_G_DQ<28>")
	)
	(segment
		(start 59.909964 -33.029398)
		(end 59.909964 -42.957242)
		(width 0.14224)
		(layer "In2.Cu")
		(net "M_G_DQ<28>")
	)
	(segment
		(start 59.449462 -23.560278)
		(end 59.960764 -24.07158)
		(width 0.14224)
		(layer "In2.Cu")
		(net "M_G_DQ<28>")
	)
	(segment
		(start 74.028046 -54.19979)
		(end 74.060812 -54.19979)
		(width 0.0889)
		(layer "In2.Cu")
		(net "M_G_DQ<28>")
	)
	(segment
		(start 59.92495 -21.818854)
		(end 59.21375 -22.530054)
		(width 0.14224)
		(layer "In2.Cu")
		(net "M_G_DQ<28>")
	)
	(segment
		(start 59.909964 -31.703518)
		(end 59.909964 -32.056578)
		(width 0.14224)
		(layer "In2.Cu")
		(net "M_G_DQ<28>")
	)
	(segment
		(start 59.941968 -19.9644)
		(end 59.941968 -20.2692)
		(width 0.14224)
		(layer "In2.Cu")
		(net "M_G_DQ<28>")
	)
	(segment
		(start 63.130176 -45.1612)
		(end 68.763642 -50.794666)
		(width 0.14224)
		(layer "In2.Cu")
		(net "M_G_DQ<28>")
	)
	(segment
		(start 59.909964 -32.056578)
		(end 59.755024 -32.211518)
		(width 0.14224)
		(layer "In2.Cu")
		(net "M_G_DQ<28>")
	)
	(segment
		(start 59.601608 -32.211518)
		(end 59.459368 -32.353758)
		(width 0.14224)
		(layer "In2.Cu")
		(net "M_G_DQ<28>")
	)
	(segment
		(start 68.946014 -50.977038)
		(end 68.990972 -51.021234)
		(width 0.0889)
		(layer "In2.Cu")
		(net "M_G_DQ<28>")
	)
	(segment
		(start 73.165716 -53.704236)
		(end 73.198482 -53.704236)
		(width 0.0889)
		(layer "In2.Cu")
		(net "M_G_DQ<28>")
	)
	(segment
		(start 59.560968 -19.5834)
		(end 59.941968 -19.9644)
		(width 0.14224)
		(layer "In2.Cu")
		(net "M_G_DQ<28>")
	)
	(segment
		(start 59.711336 -25.339548)
		(end 59.960764 -25.588976)
		(width 0.14224)
		(layer "In2.Cu")
		(net "M_G_DQ<28>")
	)
	(segment
		(start 59.92495 -18.437352)
		(end 59.92495 -18.914872)
		(width 0.14224)
		(layer "In2.Cu")
		(net "M_G_DQ<28>")
	)
	(segment
		(start 59.601608 -32.874458)
		(end 59.755024 -32.874458)
		(width 0.14224)
		(layer "In2.Cu")
		(net "M_G_DQ<28>")
	)
	(arc
		(start 69.241416 -51.427888)
		(mid 69.452129 -51.640967)
		(end 69.740272 -51.72329)
		(width 0.0889)
		(layer "In2.Cu")
		(net "M_G_DQ<28>")
	)
	(arc
		(start 70.62978 -52.21859)
		(mid 70.819709 -52.27646)
		(end 70.958456 -52.418488)
		(width 0.0889)
		(layer "In2.Cu")
		(net "M_G_DQ<28>")
	)
	(arc
		(start 73.198482 -53.704236)
		(mid 73.392332 -53.760586)
		(end 73.534016 -53.904388)
		(width 0.0889)
		(layer "In2.Cu")
		(net "M_G_DQ<28>")
	)
	(arc
		(start 71.4883 -52.71389)
		(mid 71.678229 -52.77176)
		(end 71.816976 -52.913788)
		(width 0.0889)
		(layer "In2.Cu")
		(net "M_G_DQ<28>")
	)
	(arc
		(start 69.764402 -51.72329)
		(mid 69.958252 -51.77964)
		(end 70.099936 -51.923442)
		(width 0.0889)
		(layer "In2.Cu")
		(net "M_G_DQ<28>")
	)
	(arc
		(start 71.816976 -52.913788)
		(mid 72.027689 -53.126867)
		(end 72.315832 -53.20919)
		(width 0.0889)
		(layer "In2.Cu")
		(net "M_G_DQ<28>")
	)
	(arc
		(start 72.343772 -53.20919)
		(mid 72.535414 -53.266356)
		(end 72.675496 -53.409088)
		(width 0.0889)
		(layer "In2.Cu")
		(net "M_G_DQ<28>")
	)
	(arc
		(start 73.534016 -53.904388)
		(mid 73.742624 -54.11632)
		(end 74.028046 -54.19979)
		(width 0.0889)
		(layer "In2.Cu")
		(net "M_G_DQ<28>")
	)
	(arc
		(start 70.099936 -51.923442)
		(mid 70.30694 -52.134306)
		(end 70.590156 -52.21859)
		(width 0.0889)
		(layer "In2.Cu")
		(net "M_G_DQ<28>")
	)
	(arc
		(start 74.060812 -54.19979)
		(mid 74.252454 -54.256956)
		(end 74.392536 -54.399688)
		(width 0.0889)
		(layer "In2.Cu")
		(net "M_G_DQ<28>")
	)
	(arc
		(start 70.958456 -52.418488)
		(mid 71.167064 -52.63042)
		(end 71.452486 -52.71389)
		(width 0.0889)
		(layer "In2.Cu")
		(net "M_G_DQ<28>")
	)
	(arc
		(start 72.675496 -53.409088)
		(mid 72.8825 -53.619952)
		(end 73.165716 -53.704236)
		(width 0.0889)
		(layer "In2.Cu")
		(net "M_G_DQ<28>")
	)
	(segment
		(start 78.909672 -56.085486)
		(end 78.338172 -56.085486)
		(width 0.1016)
		(layer "F.Cu")
		(net "M_G_DQ<27>")
	)
	(segment
		(start 67.099434 -15.423642)
		(end 67.099434 -16.687546)
		(width 0.1651)
		(layer "F.Cu")
		(net "M_G_DQ<27>")
	)
	(via
		(at 78.338172 -56.085486)
		(size 0.508)
		(drill 0.254)
		(layers "F.Cu" "B.Cu")
		(net "M_G_DQ<27>")
	)
	(via
		(at 67.949318 -22.279356)
		(size 0.508)
		(drill 0.254)
		(layers "F.Cu" "B.Cu")
		(net "M_G_DQ<27>")
	)
	(via
		(at 67.099434 -16.687546)
		(size 0.508)
		(drill 0.254)
		(layers "F.Cu" "B.Cu")
		(net "M_G_DQ<27>")
	)
	(segment
		(start 67.949572 -20.224242)
		(end 67.949318 -20.224496)
		(width 0.1651)
		(layer "B.Cu")
		(net "M_G_DQ<27>")
	)
	(segment
		(start 67.949318 -20.224496)
		(end 67.949318 -22.279356)
		(width 0.1651)
		(layer "B.Cu")
		(net "M_G_DQ<27>")
	)
	(segment
		(start 76.453492 -50.02149)
		(end 78.79588 -52.363878)
		(width 0.0889)
		(layer "In2.Cu")
		(net "M_G_DQ<27>")
	)
	(segment
		(start 67.099434 -16.687546)
		(end 67.416172 -17.004284)
		(width 0.14224)
		(layer "In2.Cu")
		(net "M_G_DQ<27>")
	)
	(segment
		(start 75.119992 -48.092614)
		(end 75.348592 -48.321214)
		(width 0.0889)
		(layer "In2.Cu")
		(net "M_G_DQ<27>")
	)
	(segment
		(start 68.266564 -23.996396)
		(end 68.266564 -24.22271)
		(width 0.14224)
		(layer "In2.Cu")
		(net "M_G_DQ<27>")
	)
	(segment
		(start 69.287136 -33.514284)
		(end 69.287136 -41.980358)
		(width 0.14224)
		(layer "In2.Cu")
		(net "M_G_DQ<27>")
	)
	(segment
		(start 78.849982 -53.808884)
		(end 78.856332 -53.819552)
		(width 0.0889)
		(layer "In2.Cu")
		(net "M_G_DQ<27>")
	)
	(segment
		(start 68.266564 -26.803096)
		(end 68.444364 -26.980896)
		(width 0.14224)
		(layer "In2.Cu")
		(net "M_G_DQ<27>")
	)
	(segment
		(start 68.302124 -21.92655)
		(end 67.949318 -22.279356)
		(width 0.14224)
		(layer "In2.Cu")
		(net "M_G_DQ<27>")
	)
	(segment
		(start 67.815968 -32.851344)
		(end 67.815968 -33.204404)
		(width 0.14224)
		(layer "In2.Cu")
		(net "M_G_DQ<27>")
	)
	(segment
		(start 67.746372 -17.653)
		(end 68.000372 -17.653)
		(width 0.14224)
		(layer "In2.Cu")
		(net "M_G_DQ<27>")
	)
	(segment
		(start 78.67396 -56.085486)
		(end 78.338172 -56.085486)
		(width 0.0889)
		(layer "In2.Cu")
		(net "M_G_DQ<27>")
	)
	(segment
		(start 75.119992 -47.813214)
		(end 75.119992 -48.092614)
		(width 0.0889)
		(layer "In2.Cu")
		(net "M_G_DQ<27>")
	)
	(segment
		(start 78.79588 -52.363878)
		(end 78.79588 -53.126894)
		(width 0.0889)
		(layer "In2.Cu")
		(net "M_G_DQ<27>")
	)
	(segment
		(start 78.74 -54.596538)
		(end 78.74 -56.019446)
		(width 0.0889)
		(layer "In2.Cu")
		(net "M_G_DQ<27>")
	)
	(segment
		(start 75.348592 -49.13249)
		(end 76.237592 -50.02149)
		(width 0.0889)
		(layer "In2.Cu")
		(net "M_G_DQ<27>")
	)
	(segment
		(start 67.949318 -22.279356)
		(end 67.483736 -22.744938)
		(width 0.14224)
		(layer "In2.Cu")
		(net "M_G_DQ<27>")
	)
	(segment
		(start 69.287136 -41.980358)
		(end 75.119992 -47.813214)
		(width 0.14224)
		(layer "In2.Cu")
		(net "M_G_DQ<27>")
	)
	(segment
		(start 67.661536 -31.77286)
		(end 67.816476 -31.9278)
		(width 0.14224)
		(layer "In2.Cu")
		(net "M_G_DQ<27>")
	)
	(segment
		(start 75.348592 -48.775366)
		(end 75.348592 -49.13249)
		(width 0.0889)
		(layer "In2.Cu")
		(net "M_G_DQ<27>")
	)
	(segment
		(start 69.132196 -33.359344)
		(end 69.287136 -33.514284)
		(width 0.14224)
		(layer "In2.Cu")
		(net "M_G_DQ<27>")
	)
	(segment
		(start 67.712336 -25.54097)
		(end 68.266564 -26.095198)
		(width 0.14224)
		(layer "In2.Cu")
		(net "M_G_DQ<27>")
	)
	(segment
		(start 68.000372 -17.653)
		(end 68.457572 -18.1102)
		(width 0.14224)
		(layer "In2.Cu")
		(net "M_G_DQ<27>")
	)
	(segment
		(start 67.416172 -17.004284)
		(end 67.416172 -17.3228)
		(width 0.14224)
		(layer "In2.Cu")
		(net "M_G_DQ<27>")
	)
	(segment
		(start 68.457572 -18.1102)
		(end 68.457572 -18.4658)
		(width 0.14224)
		(layer "In2.Cu")
		(net "M_G_DQ<27>")
	)
	(segment
		(start 68.892928 -31.9278)
		(end 69.035168 -32.07004)
		(width 0.14224)
		(layer "In2.Cu")
		(net "M_G_DQ<27>")
	)
	(segment
		(start 67.815968 -33.204404)
		(end 67.970908 -33.359344)
		(width 0.14224)
		(layer "In2.Cu")
		(net "M_G_DQ<27>")
	)
	(segment
		(start 67.970908 -33.359344)
		(end 69.132196 -33.359344)
		(width 0.14224)
		(layer "In2.Cu")
		(net "M_G_DQ<27>")
	)
	(segment
		(start 68.302124 -18.621248)
		(end 68.302124 -21.92655)
		(width 0.14224)
		(layer "In2.Cu")
		(net "M_G_DQ<27>")
	)
	(segment
		(start 67.816476 -31.9278)
		(end 68.892928 -31.9278)
		(width 0.14224)
		(layer "In2.Cu")
		(net "M_G_DQ<27>")
	)
	(segment
		(start 76.237592 -50.02149)
		(end 76.453492 -50.02149)
		(width 0.0889)
		(layer "In2.Cu")
		(net "M_G_DQ<27>")
	)
	(segment
		(start 78.74 -56.019446)
		(end 78.67396 -56.085486)
		(width 0.0889)
		(layer "In2.Cu")
		(net "M_G_DQ<27>")
	)
	(segment
		(start 67.712336 -24.776938)
		(end 67.712336 -25.54097)
		(width 0.14224)
		(layer "In2.Cu")
		(net "M_G_DQ<27>")
	)
	(segment
		(start 75.348592 -48.321214)
		(end 75.348592 -48.775366)
		(width 0.0889)
		(layer "In2.Cu")
		(net "M_G_DQ<27>")
	)
	(segment
		(start 67.483736 -23.213568)
		(end 68.266564 -23.996396)
		(width 0.14224)
		(layer "In2.Cu")
		(net "M_G_DQ<27>")
	)
	(segment
		(start 67.483736 -22.744938)
		(end 67.483736 -23.213568)
		(width 0.14224)
		(layer "In2.Cu")
		(net "M_G_DQ<27>")
	)
	(segment
		(start 78.849982 -54.399434)
		(end 78.74 -54.596538)
		(width 0.0889)
		(layer "In2.Cu")
		(net "M_G_DQ<27>")
	)
	(segment
		(start 67.416172 -17.3228)
		(end 67.746372 -17.653)
		(width 0.14224)
		(layer "In2.Cu")
		(net "M_G_DQ<27>")
	)
	(segment
		(start 68.444364 -26.980896)
		(end 68.444364 -28.174696)
		(width 0.14224)
		(layer "In2.Cu")
		(net "M_G_DQ<27>")
	)
	(segment
		(start 68.321936 -28.297124)
		(end 68.321936 -29.177996)
		(width 0.14224)
		(layer "In2.Cu")
		(net "M_G_DQ<27>")
	)
	(segment
		(start 78.79588 -53.126894)
		(end 78.796388 -53.60924)
		(width 0.0889)
		(layer "In2.Cu")
		(net "M_G_DQ<27>")
	)
	(segment
		(start 68.444364 -28.174696)
		(end 68.321936 -28.297124)
		(width 0.14224)
		(layer "In2.Cu")
		(net "M_G_DQ<27>")
	)
	(segment
		(start 67.661536 -29.838396)
		(end 67.661536 -31.77286)
		(width 0.14224)
		(layer "In2.Cu")
		(net "M_G_DQ<27>")
	)
	(segment
		(start 67.970908 -32.696404)
		(end 67.815968 -32.851344)
		(width 0.14224)
		(layer "In2.Cu")
		(net "M_G_DQ<27>")
	)
	(segment
		(start 68.892928 -32.696404)
		(end 67.970908 -32.696404)
		(width 0.14224)
		(layer "In2.Cu")
		(net "M_G_DQ<27>")
	)
	(segment
		(start 69.035168 -32.554164)
		(end 68.892928 -32.696404)
		(width 0.14224)
		(layer "In2.Cu")
		(net "M_G_DQ<27>")
	)
	(segment
		(start 68.266564 -24.22271)
		(end 67.712336 -24.776938)
		(width 0.14224)
		(layer "In2.Cu")
		(net "M_G_DQ<27>")
	)
	(segment
		(start 68.457572 -18.4658)
		(end 68.302124 -18.621248)
		(width 0.14224)
		(layer "In2.Cu")
		(net "M_G_DQ<27>")
	)
	(segment
		(start 68.321936 -29.177996)
		(end 67.661536 -29.838396)
		(width 0.14224)
		(layer "In2.Cu")
		(net "M_G_DQ<27>")
	)
	(segment
		(start 68.266564 -26.095198)
		(end 68.266564 -26.803096)
		(width 0.14224)
		(layer "In2.Cu")
		(net "M_G_DQ<27>")
	)
	(segment
		(start 69.035168 -32.07004)
		(end 69.035168 -32.554164)
		(width 0.14224)
		(layer "In2.Cu")
		(net "M_G_DQ<27>")
	)
	(arc
		(start 78.856332 -53.819552)
		(mid 78.92913 -54.110315)
		(end 78.849982 -54.399434)
		(width 0.0889)
		(layer "In2.Cu")
		(net "M_G_DQ<27>")
	)
	(arc
		(start 78.796388 -53.60924)
		(mid 78.810091 -53.712575)
		(end 78.849982 -53.808884)
		(width 0.0889)
		(layer "In2.Cu")
		(net "M_G_DQ<27>")
	)
	(segment
		(start 67.949318 -20.023328)
		(end 67.949318 -19.026632)
		(width 0.1651)
		(layer "F.Cu")
		(net "M_G_DQ<26>")
	)
	(segment
		(start 68.08089 -18.89506)
		(end 68.08089 -18.67154)
		(width 0.1651)
		(layer "F.Cu")
		(net "M_G_DQ<26>")
	)
	(segment
		(start 67.949318 -19.026632)
		(end 68.08089 -18.89506)
		(width 0.1651)
		(layer "F.Cu")
		(net "M_G_DQ<26>")
	)
	(segment
		(start 67.949318 -18.539968)
		(end 67.949318 -18.2626)
		(width 0.1651)
		(layer "F.Cu")
		(net "M_G_DQ<26>")
	)
	(segment
		(start 68.08089 -18.67154)
		(end 67.949318 -18.539968)
		(width 0.1651)
		(layer "F.Cu")
		(net "M_G_DQ<26>")
	)
	(segment
		(start 78.909672 -55.094886)
		(end 78.338172 -55.094886)
		(width 0.1016)
		(layer "F.Cu")
		(net "M_G_DQ<26>")
	)
	(segment
		(start 67.949572 -20.023582)
		(end 67.949318 -20.023328)
		(width 0.1651)
		(layer "F.Cu")
		(net "M_G_DQ<26>")
	)
	(via
		(at 78.338172 -55.094886)
		(size 0.508)
		(drill 0.254)
		(layers "F.Cu" "B.Cu")
		(net "M_G_DQ<26>")
	)
	(via
		(at 67.099434 -23.560278)
		(size 0.508)
		(drill 0.254)
		(layers "F.Cu" "B.Cu")
		(net "M_G_DQ<26>")
	)
	(via
		(at 67.949318 -18.2626)
		(size 0.508)
		(drill 0.254)
		(layers "F.Cu" "B.Cu")
		(net "M_G_DQ<26>")
	)
	(segment
		(start 67.099434 -23.560278)
		(end 67.099434 -24.824182)
		(width 0.1651)
		(layer "B.Cu")
		(net "M_G_DQ<26>")
	)
	(segment
		(start 68.730368 -35.89401)
		(end 68.730368 -36.24707)
		(width 0.14224)
		(layer "In2.Cu")
		(net "M_G_DQ<26>")
	)
	(segment
		(start 68.575428 -35.73907)
		(end 68.730368 -35.89401)
		(width 0.14224)
		(layer "In2.Cu")
		(net "M_G_DQ<26>")
	)
	(segment
		(start 67.5513 -18.965672)
		(end 67.206368 -19.310604)
		(width 0.14224)
		(layer "In2.Cu")
		(net "M_G_DQ<26>")
	)
	(segment
		(start 67.297808 -37.06495)
		(end 68.575428 -37.06495)
		(width 0.14224)
		(layer "In2.Cu")
		(net "M_G_DQ<26>")
	)
	(segment
		(start 78.338172 -55.094886)
		(end 78.515464 -54.596538)
		(width 0.0889)
		(layer "In2.Cu")
		(net "M_G_DQ<26>")
	)
	(segment
		(start 67.026536 -33.923224)
		(end 67.305936 -34.202624)
		(width 0.14224)
		(layer "In2.Cu")
		(net "M_G_DQ<26>")
	)
	(segment
		(start 67.453764 -26.917396)
		(end 67.453764 -28.161996)
		(width 0.14224)
		(layer "In2.Cu")
		(net "M_G_DQ<26>")
	)
	(segment
		(start 67.297808 -36.40201)
		(end 67.142868 -36.55695)
		(width 0.14224)
		(layer "In2.Cu")
		(net "M_G_DQ<26>")
	)
	(segment
		(start 67.511168 -19.964146)
		(end 67.511168 -20.25015)
		(width 0.14224)
		(layer "In2.Cu")
		(net "M_G_DQ<26>")
	)
	(segment
		(start 78.60538 -52.442872)
		(end 76.374498 -50.21199)
		(width 0.0889)
		(layer "In2.Cu")
		(net "M_G_DQ<26>")
	)
	(segment
		(start 74.635614 -48.245014)
		(end 74.967338 -48.245014)
		(width 0.0889)
		(layer "In2.Cu")
		(net "M_G_DQ<26>")
	)
	(segment
		(start 68.730368 -36.24707)
		(end 68.575428 -36.40201)
		(width 0.14224)
		(layer "In2.Cu")
		(net "M_G_DQ<26>")
	)
	(segment
		(start 67.142868 -36.91001)
		(end 67.297808 -37.06495)
		(width 0.14224)
		(layer "In2.Cu")
		(net "M_G_DQ<26>")
	)
	(segment
		(start 67.206368 -20.55495)
		(end 67.206368 -20.955)
		(width 0.14224)
		(layer "In2.Cu")
		(net "M_G_DQ<26>")
	)
	(segment
		(start 66.8147 -23.275544)
		(end 67.099434 -23.560278)
		(width 0.14224)
		(layer "In2.Cu")
		(net "M_G_DQ<26>")
	)
	(segment
		(start 67.631564 -26.739596)
		(end 67.453764 -26.917396)
		(width 0.14224)
		(layer "In2.Cu")
		(net "M_G_DQ<26>")
	)
	(segment
		(start 67.305936 -34.202624)
		(end 67.775328 -34.202624)
		(width 0.14224)
		(layer "In2.Cu")
		(net "M_G_DQ<26>")
	)
	(segment
		(start 67.631564 -26.373328)
		(end 67.631564 -26.739596)
		(width 0.14224)
		(layer "In2.Cu")
		(net "M_G_DQ<26>")
	)
	(segment
		(start 76.158598 -50.21199)
		(end 75.158092 -49.211484)
		(width 0.0889)
		(layer "In2.Cu")
		(net "M_G_DQ<26>")
	)
	(segment
		(start 67.297808 -35.73907)
		(end 68.575428 -35.73907)
		(width 0.14224)
		(layer "In2.Cu")
		(net "M_G_DQ<26>")
	)
	(segment
		(start 68.730368 -42.339768)
		(end 74.635614 -48.245014)
		(width 0.14224)
		(layer "In2.Cu")
		(net "M_G_DQ<26>")
	)
	(segment
		(start 67.099434 -25.841198)
		(end 67.631564 -26.373328)
		(width 0.14224)
		(layer "In2.Cu")
		(net "M_G_DQ<26>")
	)
	(segment
		(start 67.663568 -21.680932)
		(end 66.8147 -22.5298)
		(width 0.14224)
		(layer "In2.Cu")
		(net "M_G_DQ<26>")
	)
	(segment
		(start 67.206368 -19.310604)
		(end 67.206368 -19.659346)
		(width 0.14224)
		(layer "In2.Cu")
		(net "M_G_DQ<26>")
	)
	(segment
		(start 67.949318 -18.2626)
		(end 67.5513 -18.660618)
		(width 0.14224)
		(layer "In2.Cu")
		(net "M_G_DQ<26>")
	)
	(segment
		(start 67.142868 -36.55695)
		(end 67.142868 -36.91001)
		(width 0.14224)
		(layer "In2.Cu")
		(net "M_G_DQ<26>")
	)
	(segment
		(start 75.158092 -49.211484)
		(end 75.158092 -48.775366)
		(width 0.0889)
		(layer "In2.Cu")
		(net "M_G_DQ<26>")
	)
	(segment
		(start 78.515464 -54.596538)
		(end 78.684882 -54.30393)
		(width 0.0889)
		(layer "In2.Cu")
		(net "M_G_DQ<26>")
	)
	(segment
		(start 67.606164 -28.995624)
		(end 67.026536 -29.575252)
		(width 0.14224)
		(layer "In2.Cu")
		(net "M_G_DQ<26>")
	)
	(segment
		(start 67.142868 -35.23107)
		(end 67.142868 -35.58413)
		(width 0.14224)
		(layer "In2.Cu")
		(net "M_G_DQ<26>")
	)
	(segment
		(start 67.775328 -35.07613)
		(end 67.297808 -35.07613)
		(width 0.14224)
		(layer "In2.Cu")
		(net "M_G_DQ<26>")
	)
	(segment
		(start 66.8147 -22.5298)
		(end 66.8147 -23.275544)
		(width 0.14224)
		(layer "In2.Cu")
		(net "M_G_DQ<26>")
	)
	(segment
		(start 78.60538 -53.608224)
		(end 78.60538 -52.442872)
		(width 0.0889)
		(layer "In2.Cu")
		(net "M_G_DQ<26>")
	)
	(segment
		(start 67.206368 -20.955)
		(end 67.663568 -21.4122)
		(width 0.14224)
		(layer "In2.Cu")
		(net "M_G_DQ<26>")
	)
	(segment
		(start 67.511168 -20.25015)
		(end 67.206368 -20.55495)
		(width 0.14224)
		(layer "In2.Cu")
		(net "M_G_DQ<26>")
	)
	(segment
		(start 67.297808 -35.07613)
		(end 67.142868 -35.23107)
		(width 0.14224)
		(layer "In2.Cu")
		(net "M_G_DQ<26>")
	)
	(segment
		(start 74.967338 -48.245014)
		(end 75.158092 -48.435768)
		(width 0.0889)
		(layer "In2.Cu")
		(net "M_G_DQ<26>")
	)
	(segment
		(start 67.099434 -23.560278)
		(end 67.099434 -25.841198)
		(width 0.14224)
		(layer "In2.Cu")
		(net "M_G_DQ<26>")
	)
	(segment
		(start 67.917568 -34.344864)
		(end 67.917568 -34.93389)
		(width 0.14224)
		(layer "In2.Cu")
		(net "M_G_DQ<26>")
	)
	(segment
		(start 67.026536 -29.575252)
		(end 67.026536 -33.923224)
		(width 0.14224)
		(layer "In2.Cu")
		(net "M_G_DQ<26>")
	)
	(segment
		(start 67.917568 -34.93389)
		(end 67.775328 -35.07613)
		(width 0.14224)
		(layer "In2.Cu")
		(net "M_G_DQ<26>")
	)
	(segment
		(start 67.206368 -19.659346)
		(end 67.511168 -19.964146)
		(width 0.14224)
		(layer "In2.Cu")
		(net "M_G_DQ<26>")
	)
	(segment
		(start 67.5513 -18.660618)
		(end 67.5513 -18.965672)
		(width 0.14224)
		(layer "In2.Cu")
		(net "M_G_DQ<26>")
	)
	(segment
		(start 68.575428 -37.06495)
		(end 68.730368 -37.21989)
		(width 0.14224)
		(layer "In2.Cu")
		(net "M_G_DQ<26>")
	)
	(segment
		(start 67.142868 -35.58413)
		(end 67.297808 -35.73907)
		(width 0.14224)
		(layer "In2.Cu")
		(net "M_G_DQ<26>")
	)
	(segment
		(start 75.158092 -48.435768)
		(end 75.158092 -48.775366)
		(width 0.0889)
		(layer "In2.Cu")
		(net "M_G_DQ<26>")
	)
	(segment
		(start 67.775328 -34.202624)
		(end 67.917568 -34.344864)
		(width 0.14224)
		(layer "In2.Cu")
		(net "M_G_DQ<26>")
	)
	(segment
		(start 68.575428 -36.40201)
		(end 67.297808 -36.40201)
		(width 0.14224)
		(layer "In2.Cu")
		(net "M_G_DQ<26>")
	)
	(segment
		(start 78.684882 -53.904134)
		(end 78.678532 -53.893466)
		(width 0.0889)
		(layer "In2.Cu")
		(net "M_G_DQ<26>")
	)
	(segment
		(start 68.730368 -37.21989)
		(end 68.730368 -42.339768)
		(width 0.14224)
		(layer "In2.Cu")
		(net "M_G_DQ<26>")
	)
	(segment
		(start 76.374498 -50.21199)
		(end 76.158598 -50.21199)
		(width 0.0889)
		(layer "In2.Cu")
		(net "M_G_DQ<26>")
	)
	(segment
		(start 67.606164 -28.314396)
		(end 67.606164 -28.995624)
		(width 0.14224)
		(layer "In2.Cu")
		(net "M_G_DQ<26>")
	)
	(segment
		(start 67.453764 -28.161996)
		(end 67.606164 -28.314396)
		(width 0.14224)
		(layer "In2.Cu")
		(net "M_G_DQ<26>")
	)
	(segment
		(start 67.663568 -21.4122)
		(end 67.663568 -21.680932)
		(width 0.14224)
		(layer "In2.Cu")
		(net "M_G_DQ<26>")
	)
	(arc
		(start 78.678532 -53.893466)
		(mid 78.623995 -53.755454)
		(end 78.60538 -53.608224)
		(width 0.0889)
		(layer "In2.Cu")
		(net "M_G_DQ<26>")
	)
	(arc
		(start 78.684882 -54.30393)
		(mid 78.738381 -54.104032)
		(end 78.684882 -53.904134)
		(width 0.0889)
		(layer "In2.Cu")
		(net "M_G_DQ<26>")
	)
	(segment
		(start 76.334366 -56.58104)
		(end 75.762866 -56.58104)
		(width 0.1016)
		(layer "F.Cu")
		(net "M_G_DQ<25>")
	)
	(segment
		(start 61.149484 -15.423642)
		(end 61.149484 -16.687546)
		(width 0.1651)
		(layer "F.Cu")
		(net "M_G_DQ<25>")
	)
	(via
		(at 75.762866 -56.58104)
		(size 0.508)
		(drill 0.254)
		(layers "F.Cu" "B.Cu")
		(net "M_G_DQ<25>")
	)
	(via
		(at 61.821568 -22.279356)
		(size 0.508)
		(drill 0.254)
		(layers "F.Cu" "B.Cu")
		(net "M_G_DQ<25>")
	)
	(via
		(at 61.149484 -16.687546)
		(size 0.508)
		(drill 0.254)
		(layers "F.Cu" "B.Cu")
		(net "M_G_DQ<25>")
	)
	(segment
		(start 61.999368 -20.224242)
		(end 61.999368 -21.598382)
		(width 0.1651)
		(layer "B.Cu")
		(net "M_G_DQ<25>")
	)
	(segment
		(start 61.821568 -21.776182)
		(end 61.821568 -22.279356)
		(width 0.1651)
		(layer "B.Cu")
		(net "M_G_DQ<25>")
	)
	(segment
		(start 61.999368 -21.598382)
		(end 61.821568 -21.776182)
		(width 0.1651)
		(layer "B.Cu")
		(net "M_G_DQ<25>")
	)
	(segment
		(start 71.024496 -51.141884)
		(end 71.123556 -51.332638)
		(width 0.0889)
		(layer "In2.Cu")
		(net "M_G_DQ<25>")
	)
	(segment
		(start 74.88936 -53.513736)
		(end 74.922126 -53.513736)
		(width 0.0889)
		(layer "In2.Cu")
		(net "M_G_DQ<25>")
	)
	(segment
		(start 72.310752 -52.027836)
		(end 72.346566 -52.027836)
		(width 0.0889)
		(layer "In2.Cu")
		(net "M_G_DQ<25>")
	)
	(segment
		(start 61.819536 -41.340532)
		(end 63.176404 -42.6974)
		(width 0.14224)
		(layer "In2.Cu")
		(net "M_G_DQ<25>")
	)
	(segment
		(start 70.704964 -49.987454)
		(end 71.024496 -50.306986)
		(width 0.0889)
		(layer "In2.Cu")
		(net "M_G_DQ<25>")
	)
	(segment
		(start 75.433428 -55.820056)
		(end 75.762866 -56.58104)
		(width 0.0889)
		(layer "In2.Cu")
		(net "M_G_DQ<25>")
	)
	(segment
		(start 62.19571 -21.905214)
		(end 61.821568 -22.279356)
		(width 0.14224)
		(layer "In2.Cu")
		(net "M_G_DQ<25>")
	)
	(segment
		(start 61.62675 -17.7038)
		(end 61.98235 -17.7038)
		(width 0.14224)
		(layer "In2.Cu")
		(net "M_G_DQ<25>")
	)
	(segment
		(start 62.310264 -26.117296)
		(end 62.310264 -28.962096)
		(width 0.14224)
		(layer "In2.Cu")
		(net "M_G_DQ<25>")
	)
	(segment
		(start 62.19571 -18.571464)
		(end 62.19571 -21.905214)
		(width 0.14224)
		(layer "In2.Cu")
		(net "M_G_DQ<25>")
	)
	(segment
		(start 63.176404 -42.6974)
		(end 63.41491 -42.6974)
		(width 0.14224)
		(layer "In2.Cu")
		(net "M_G_DQ<25>")
	)
	(segment
		(start 73.169272 -52.523136)
		(end 73.208896 -52.523136)
		(width 0.0889)
		(layer "In2.Cu")
		(net "M_G_DQ<25>")
	)
	(segment
		(start 61.764164 -25.571196)
		(end 62.310264 -26.117296)
		(width 0.14224)
		(layer "In2.Cu")
		(net "M_G_DQ<25>")
	)
	(segment
		(start 62.627764 -29.279596)
		(end 62.627764 -36.111434)
		(width 0.14224)
		(layer "In2.Cu")
		(net "M_G_DQ<25>")
	)
	(segment
		(start 62.352174 -18.073624)
		(end 62.352174 -18.415)
		(width 0.14224)
		(layer "In2.Cu")
		(net "M_G_DQ<25>")
	)
	(segment
		(start 61.98235 -17.7038)
		(end 62.352174 -18.073624)
		(width 0.14224)
		(layer "In2.Cu")
		(net "M_G_DQ<25>")
	)
	(segment
		(start 61.819536 -36.919662)
		(end 61.819536 -41.340532)
		(width 0.14224)
		(layer "In2.Cu")
		(net "M_G_DQ<25>")
	)
	(segment
		(start 61.149484 -17.226534)
		(end 61.62675 -17.7038)
		(width 0.14224)
		(layer "In2.Cu")
		(net "M_G_DQ<25>")
	)
	(segment
		(start 61.821568 -22.279356)
		(end 61.332364 -22.76856)
		(width 0.14224)
		(layer "In2.Cu")
		(net "M_G_DQ<25>")
	)
	(segment
		(start 62.627764 -36.111434)
		(end 61.819536 -36.919662)
		(width 0.14224)
		(layer "In2.Cu")
		(net "M_G_DQ<25>")
	)
	(segment
		(start 74.03465 -53.018436)
		(end 74.05878 -53.018436)
		(width 0.0889)
		(layer "In2.Cu")
		(net "M_G_DQ<25>")
	)
	(segment
		(start 71.024496 -50.306986)
		(end 71.024496 -51.141884)
		(width 0.0889)
		(layer "In2.Cu")
		(net "M_G_DQ<25>")
	)
	(segment
		(start 61.332364 -22.76856)
		(end 61.332364 -23.107396)
		(width 0.14224)
		(layer "In2.Cu")
		(net "M_G_DQ<25>")
	)
	(segment
		(start 61.764164 -23.539196)
		(end 61.764164 -25.571196)
		(width 0.14224)
		(layer "In2.Cu")
		(net "M_G_DQ<25>")
	)
	(segment
		(start 62.352174 -18.415)
		(end 62.19571 -18.571464)
		(width 0.14224)
		(layer "In2.Cu")
		(net "M_G_DQ<25>")
	)
	(segment
		(start 61.332364 -23.107396)
		(end 61.764164 -23.539196)
		(width 0.14224)
		(layer "In2.Cu")
		(net "M_G_DQ<25>")
	)
	(segment
		(start 71.45528 -51.532536)
		(end 71.48322 -51.532536)
		(width 0.0889)
		(layer "In2.Cu")
		(net "M_G_DQ<25>")
	)
	(segment
		(start 61.149484 -16.687546)
		(end 61.149484 -17.226534)
		(width 0.14224)
		(layer "In2.Cu")
		(net "M_G_DQ<25>")
	)
	(segment
		(start 62.310264 -28.962096)
		(end 62.627764 -29.279596)
		(width 0.14224)
		(layer "In2.Cu")
		(net "M_G_DQ<25>")
	)
	(segment
		(start 75.41133 -55.781702)
		(end 75.433428 -55.820056)
		(width 0.0889)
		(layer "In2.Cu")
		(net "M_G_DQ<25>")
	)
	(segment
		(start 63.41491 -42.6974)
		(end 70.704964 -49.987454)
		(width 0.14224)
		(layer "In2.Cu")
		(net "M_G_DQ<25>")
	)
	(arc
		(start 72.346566 -52.027836)
		(mid 72.63199 -52.111303)
		(end 72.840596 -52.323238)
		(width 0.0889)
		(layer "In2.Cu")
		(net "M_G_DQ<25>")
	)
	(arc
		(start 75.51928 -53.926486)
		(mid 75.658979 -54.024931)
		(end 75.805792 -54.112414)
		(width 0.0889)
		(layer "In2.Cu")
		(net "M_G_DQ<25>")
	)
	(arc
		(start 75.937364 -54.960012)
		(mid 75.690466 -55.111613)
		(end 75.478386 -55.309008)
		(width 0.0889)
		(layer "In2.Cu")
		(net "M_G_DQ<25>")
	)
	(arc
		(start 74.05878 -53.018436)
		(mid 74.346925 -53.100755)
		(end 74.557636 -53.313838)
		(width 0.0889)
		(layer "In2.Cu")
		(net "M_G_DQ<25>")
	)
	(arc
		(start 75.478386 -55.309008)
		(mid 75.366664 -55.534257)
		(end 75.41133 -55.781702)
		(width 0.0889)
		(layer "In2.Cu")
		(net "M_G_DQ<25>")
	)
	(arc
		(start 74.557636 -53.313838)
		(mid 74.697715 -53.456574)
		(end 74.88936 -53.513736)
		(width 0.0889)
		(layer "In2.Cu")
		(net "M_G_DQ<25>")
	)
	(arc
		(start 71.48322 -51.532536)
		(mid 71.771365 -51.614855)
		(end 71.982076 -51.827938)
		(width 0.0889)
		(layer "In2.Cu")
		(net "M_G_DQ<25>")
	)
	(arc
		(start 75.416156 -53.809138)
		(mid 75.461883 -53.872941)
		(end 75.51928 -53.926486)
		(width 0.0889)
		(layer "In2.Cu")
		(net "M_G_DQ<25>")
	)
	(arc
		(start 75.805792 -54.112414)
		(mid 75.97862 -54.233907)
		(end 76.109576 -54.399688)
		(width 0.0889)
		(layer "In2.Cu")
		(net "M_G_DQ<25>")
	)
	(arc
		(start 73.699116 -52.818284)
		(mid 73.840799 -52.962088)
		(end 74.03465 -53.018436)
		(width 0.0889)
		(layer "In2.Cu")
		(net "M_G_DQ<25>")
	)
	(arc
		(start 71.982076 -51.827938)
		(mid 72.12082 -51.969971)
		(end 72.310752 -52.027836)
		(width 0.0889)
		(layer "In2.Cu")
		(net "M_G_DQ<25>")
	)
	(arc
		(start 71.123556 -51.332638)
		(mid 71.263635 -51.475374)
		(end 71.45528 -51.532536)
		(width 0.0889)
		(layer "In2.Cu")
		(net "M_G_DQ<25>")
	)
	(arc
		(start 74.922126 -53.513736)
		(mid 75.20755 -53.597203)
		(end 75.416156 -53.809138)
		(width 0.0889)
		(layer "In2.Cu")
		(net "M_G_DQ<25>")
	)
	(arc
		(start 73.208896 -52.523136)
		(mid 73.492113 -52.607417)
		(end 73.699116 -52.818284)
		(width 0.0889)
		(layer "In2.Cu")
		(net "M_G_DQ<25>")
	)
	(arc
		(start 76.109576 -54.399688)
		(mid 76.145552 -54.717398)
		(end 75.937364 -54.960012)
		(width 0.0889)
		(layer "In2.Cu")
		(net "M_G_DQ<25>")
	)
	(arc
		(start 72.840596 -52.323238)
		(mid 72.97934 -52.465271)
		(end 73.169272 -52.523136)
		(width 0.0889)
		(layer "In2.Cu")
		(net "M_G_DQ<25>")
	)
	(segment
		(start 76.334366 -54.59984)
		(end 75.762866 -54.59984)
		(width 0.1016)
		(layer "F.Cu")
		(net "M_G_DQ<24>")
	)
	(segment
		(start 61.918596 -19.177)
		(end 61.821568 -18.161)
		(width 0.1651)
		(layer "F.Cu")
		(net "M_G_DQ<24>")
	)
	(segment
		(start 61.999368 -20.023582)
		(end 61.918596 -19.177)
		(width 0.1651)
		(layer "F.Cu")
		(net "M_G_DQ<24>")
	)
	(via
		(at 61.821568 -18.161)
		(size 0.508)
		(drill 0.254)
		(layers "F.Cu" "B.Cu")
		(net "M_G_DQ<24>")
	)
	(via
		(at 61.149484 -23.560278)
		(size 0.508)
		(drill 0.254)
		(layers "F.Cu" "B.Cu")
		(net "M_G_DQ<24>")
	)
	(via
		(at 75.762866 -54.59984)
		(size 0.508)
		(drill 0.254)
		(layers "F.Cu" "B.Cu")
		(net "M_G_DQ<24>")
	)
	(segment
		(start 61.149484 -23.560278)
		(end 61.149484 -24.824182)
		(width 0.1651)
		(layer "B.Cu")
		(net "M_G_DQ<24>")
	)
	(segment
		(start 61.184536 -36.656518)
		(end 61.184536 -41.730422)
		(width 0.14224)
		(layer "In2.Cu")
		(net "M_G_DQ<24>")
	)
	(segment
		(start 61.332364 -26.968196)
		(end 61.332364 -28.060396)
		(width 0.14224)
		(layer "In2.Cu")
		(net "M_G_DQ<24>")
	)
	(segment
		(start 61.694568 -36.146486)
		(end 61.184536 -36.656518)
		(width 0.14224)
		(layer "In2.Cu")
		(net "M_G_DQ<24>")
	)
	(segment
		(start 61.149484 -25.836372)
		(end 61.611764 -26.298652)
		(width 0.14224)
		(layer "In2.Cu")
		(net "M_G_DQ<24>")
	)
	(segment
		(start 61.186568 -19.380454)
		(end 61.186568 -19.7104)
		(width 0.14224)
		(layer "In2.Cu")
		(net "M_G_DQ<24>")
	)
	(segment
		(start 61.184536 -34.878518)
		(end 61.184536 -35.284918)
		(width 0.14224)
		(layer "In2.Cu")
		(net "M_G_DQ<24>")
	)
	(segment
		(start 71.457312 -51.72329)
		(end 71.481442 -51.72329)
		(width 0.0889)
		(layer "In2.Cu")
		(net "M_G_DQ<24>")
	)
	(segment
		(start 61.529468 -20.0533)
		(end 61.529468 -20.2819)
		(width 0.14224)
		(layer "In2.Cu")
		(net "M_G_DQ<24>")
	)
	(segment
		(start 61.184536 -32.033718)
		(end 61.387736 -32.236918)
		(width 0.14224)
		(layer "In2.Cu")
		(net "M_G_DQ<24>")
	)
	(segment
		(start 61.211968 -20.903946)
		(end 61.60135 -21.293328)
		(width 0.14224)
		(layer "In2.Cu")
		(net "M_G_DQ<24>")
	)
	(segment
		(start 61.789564 -33.049718)
		(end 61.387736 -33.049718)
		(width 0.14224)
		(layer "In2.Cu")
		(net "M_G_DQ<24>")
	)
	(segment
		(start 75.26782 -53.933852)
		(end 75.762866 -54.59984)
		(width 0.0889)
		(layer "In2.Cu")
		(net "M_G_DQ<24>")
	)
	(segment
		(start 61.821568 -18.161)
		(end 61.60135 -18.381218)
		(width 0.14224)
		(layer "In2.Cu")
		(net "M_G_DQ<24>")
	)
	(segment
		(start 63.159132 -43.3578)
		(end 69.865494 -50.064162)
		(width 0.14224)
		(layer "In2.Cu")
		(net "M_G_DQ<24>")
	)
	(segment
		(start 61.184536 -41.730422)
		(end 62.811914 -43.3578)
		(width 0.14224)
		(layer "In2.Cu")
		(net "M_G_DQ<24>")
	)
	(segment
		(start 61.681868 -29.2227)
		(end 61.992764 -29.533596)
		(width 0.14224)
		(layer "In2.Cu")
		(net "M_G_DQ<24>")
	)
	(segment
		(start 61.387736 -33.862518)
		(end 61.789564 -33.862518)
		(width 0.14224)
		(layer "In2.Cu")
		(net "M_G_DQ<24>")
	)
	(segment
		(start 61.694568 -35.630358)
		(end 61.694568 -36.146486)
		(width 0.14224)
		(layer "In2.Cu")
		(net "M_G_DQ<24>")
	)
	(segment
		(start 74.032872 -53.20919)
		(end 74.060812 -53.20919)
		(width 0.0889)
		(layer "In2.Cu")
		(net "M_G_DQ<24>")
	)
	(segment
		(start 61.186568 -19.7104)
		(end 61.529468 -20.0533)
		(width 0.14224)
		(layer "In2.Cu")
		(net "M_G_DQ<24>")
	)
	(segment
		(start 61.149484 -23.560278)
		(end 61.149484 -25.836372)
		(width 0.14224)
		(layer "In2.Cu")
		(net "M_G_DQ<24>")
	)
	(segment
		(start 69.865494 -50.064162)
		(end 69.964808 -50.163476)
		(width 0.0889)
		(layer "In2.Cu")
		(net "M_G_DQ<24>")
	)
	(segment
		(start 61.789564 -34.675318)
		(end 61.387736 -34.675318)
		(width 0.14224)
		(layer "In2.Cu")
		(net "M_G_DQ<24>")
	)
	(segment
		(start 60.86475 -23.275544)
		(end 61.149484 -23.560278)
		(width 0.14224)
		(layer "In2.Cu")
		(net "M_G_DQ<24>")
	)
	(segment
		(start 75.251056 -53.904388)
		(end 75.26782 -53.933852)
		(width 0.0889)
		(layer "In2.Cu")
		(net "M_G_DQ<24>")
	)
	(segment
		(start 61.60135 -18.965672)
		(end 61.186568 -19.380454)
		(width 0.14224)
		(layer "In2.Cu")
		(net "M_G_DQ<24>")
	)
	(segment
		(start 61.992764 -32.440118)
		(end 61.992764 -32.846518)
		(width 0.14224)
		(layer "In2.Cu")
		(net "M_G_DQ<24>")
	)
	(segment
		(start 73.169526 -52.71389)
		(end 73.20534 -52.71389)
		(width 0.0889)
		(layer "In2.Cu")
		(net "M_G_DQ<24>")
	)
	(segment
		(start 61.184536 -31.627318)
		(end 61.184536 -32.033718)
		(width 0.14224)
		(layer "In2.Cu")
		(net "M_G_DQ<24>")
	)
	(segment
		(start 61.387736 -35.488118)
		(end 61.552328 -35.488118)
		(width 0.14224)
		(layer "In2.Cu")
		(net "M_G_DQ<24>")
	)
	(segment
		(start 61.184536 -33.659318)
		(end 61.387736 -33.862518)
		(width 0.14224)
		(layer "In2.Cu")
		(net "M_G_DQ<24>")
	)
	(segment
		(start 61.332364 -28.060396)
		(end 61.681868 -28.4099)
		(width 0.14224)
		(layer "In2.Cu")
		(net "M_G_DQ<24>")
	)
	(segment
		(start 74.882756 -53.704236)
		(end 74.915522 -53.704236)
		(width 0.0889)
		(layer "In2.Cu")
		(net "M_G_DQ<24>")
	)
	(segment
		(start 72.307196 -52.21859)
		(end 72.34682 -52.21859)
		(width 0.0889)
		(layer "In2.Cu")
		(net "M_G_DQ<24>")
	)
	(segment
		(start 61.60135 -21.293328)
		(end 61.60135 -21.7932)
		(width 0.14224)
		(layer "In2.Cu")
		(net "M_G_DQ<24>")
	)
	(segment
		(start 61.184536 -33.252918)
		(end 61.184536 -33.659318)
		(width 0.14224)
		(layer "In2.Cu")
		(net "M_G_DQ<24>")
	)
	(segment
		(start 61.611764 -26.688796)
		(end 61.332364 -26.968196)
		(width 0.14224)
		(layer "In2.Cu")
		(net "M_G_DQ<24>")
	)
	(segment
		(start 61.387736 -31.424118)
		(end 61.184536 -31.627318)
		(width 0.14224)
		(layer "In2.Cu")
		(net "M_G_DQ<24>")
	)
	(segment
		(start 61.60135 -21.7932)
		(end 60.86475 -22.5298)
		(width 0.14224)
		(layer "In2.Cu")
		(net "M_G_DQ<24>")
	)
	(segment
		(start 61.992764 -34.472118)
		(end 61.789564 -34.675318)
		(width 0.14224)
		(layer "In2.Cu")
		(net "M_G_DQ<24>")
	)
	(segment
		(start 61.992764 -34.065718)
		(end 61.992764 -34.472118)
		(width 0.14224)
		(layer "In2.Cu")
		(net "M_G_DQ<24>")
	)
	(segment
		(start 61.211968 -20.5994)
		(end 61.211968 -20.903946)
		(width 0.14224)
		(layer "In2.Cu")
		(net "M_G_DQ<24>")
	)
	(segment
		(start 61.789564 -32.236918)
		(end 61.992764 -32.440118)
		(width 0.14224)
		(layer "In2.Cu")
		(net "M_G_DQ<24>")
	)
	(segment
		(start 60.86475 -22.5298)
		(end 60.86475 -23.275544)
		(width 0.14224)
		(layer "In2.Cu")
		(net "M_G_DQ<24>")
	)
	(segment
		(start 61.992764 -32.846518)
		(end 61.789564 -33.049718)
		(width 0.14224)
		(layer "In2.Cu")
		(net "M_G_DQ<24>")
	)
	(segment
		(start 61.60135 -18.381218)
		(end 61.60135 -18.965672)
		(width 0.14224)
		(layer "In2.Cu")
		(net "M_G_DQ<24>")
	)
	(segment
		(start 61.992764 -29.533596)
		(end 61.992764 -31.220918)
		(width 0.14224)
		(layer "In2.Cu")
		(net "M_G_DQ<24>")
	)
	(segment
		(start 61.387736 -33.049718)
		(end 61.184536 -33.252918)
		(width 0.14224)
		(layer "In2.Cu")
		(net "M_G_DQ<24>")
	)
	(segment
		(start 61.789564 -33.862518)
		(end 61.992764 -34.065718)
		(width 0.14224)
		(layer "In2.Cu")
		(net "M_G_DQ<24>")
	)
	(segment
		(start 69.964808 -50.163476)
		(end 69.964808 -50.575464)
		(width 0.0889)
		(layer "In2.Cu")
		(net "M_G_DQ<24>")
	)
	(segment
		(start 69.964808 -50.575464)
		(end 70.081902 -50.779426)
		(width 0.0889)
		(layer "In2.Cu")
		(net "M_G_DQ<24>")
	)
	(segment
		(start 61.387736 -32.236918)
		(end 61.789564 -32.236918)
		(width 0.14224)
		(layer "In2.Cu")
		(net "M_G_DQ<24>")
	)
	(segment
		(start 61.611764 -26.298652)
		(end 61.611764 -26.688796)
		(width 0.14224)
		(layer "In2.Cu")
		(net "M_G_DQ<24>")
	)
	(segment
		(start 61.789564 -31.424118)
		(end 61.387736 -31.424118)
		(width 0.14224)
		(layer "In2.Cu")
		(net "M_G_DQ<24>")
	)
	(segment
		(start 61.387736 -34.675318)
		(end 61.184536 -34.878518)
		(width 0.14224)
		(layer "In2.Cu")
		(net "M_G_DQ<24>")
	)
	(segment
		(start 61.992764 -31.220918)
		(end 61.789564 -31.424118)
		(width 0.14224)
		(layer "In2.Cu")
		(net "M_G_DQ<24>")
	)
	(segment
		(start 61.681868 -28.4099)
		(end 61.681868 -29.2227)
		(width 0.14224)
		(layer "In2.Cu")
		(net "M_G_DQ<24>")
	)
	(segment
		(start 61.184536 -35.284918)
		(end 61.387736 -35.488118)
		(width 0.14224)
		(layer "In2.Cu")
		(net "M_G_DQ<24>")
	)
	(segment
		(start 61.529468 -20.2819)
		(end 61.211968 -20.5994)
		(width 0.14224)
		(layer "In2.Cu")
		(net "M_G_DQ<24>")
	)
	(segment
		(start 62.811914 -43.3578)
		(end 63.159132 -43.3578)
		(width 0.14224)
		(layer "In2.Cu")
		(net "M_G_DQ<24>")
	)
	(segment
		(start 61.552328 -35.488118)
		(end 61.694568 -35.630358)
		(width 0.14224)
		(layer "In2.Cu")
		(net "M_G_DQ<24>")
	)
	(arc
		(start 74.060812 -53.20919)
		(mid 74.252454 -53.266356)
		(end 74.392536 -53.409088)
		(width 0.0889)
		(layer "In2.Cu")
		(net "M_G_DQ<24>")
	)
	(arc
		(start 74.392536 -53.409088)
		(mid 74.59954 -53.619952)
		(end 74.882756 -53.704236)
		(width 0.0889)
		(layer "In2.Cu")
		(net "M_G_DQ<24>")
	)
	(arc
		(start 72.34682 -52.21859)
		(mid 72.536749 -52.27646)
		(end 72.675496 -52.418488)
		(width 0.0889)
		(layer "In2.Cu")
		(net "M_G_DQ<24>")
	)
	(arc
		(start 73.20534 -52.71389)
		(mid 73.395269 -52.77176)
		(end 73.534016 -52.913788)
		(width 0.0889)
		(layer "In2.Cu")
		(net "M_G_DQ<24>")
	)
	(arc
		(start 70.71868 -51.242214)
		(mid 70.856842 -51.311458)
		(end 70.958456 -51.427888)
		(width 0.0889)
		(layer "In2.Cu")
		(net "M_G_DQ<24>")
	)
	(arc
		(start 70.958456 -51.427888)
		(mid 71.169169 -51.640967)
		(end 71.457312 -51.72329)
		(width 0.0889)
		(layer "In2.Cu")
		(net "M_G_DQ<24>")
	)
	(arc
		(start 73.534016 -52.913788)
		(mid 73.744729 -53.126867)
		(end 74.032872 -53.20919)
		(width 0.0889)
		(layer "In2.Cu")
		(net "M_G_DQ<24>")
	)
	(arc
		(start 70.081902 -50.779426)
		(mid 70.358422 -51.068427)
		(end 70.71868 -51.242214)
		(width 0.0889)
		(layer "In2.Cu")
		(net "M_G_DQ<24>")
	)
	(arc
		(start 71.481442 -51.72329)
		(mid 71.675292 -51.77964)
		(end 71.816976 -51.923442)
		(width 0.0889)
		(layer "In2.Cu")
		(net "M_G_DQ<24>")
	)
	(arc
		(start 74.915522 -53.704236)
		(mid 75.109372 -53.760586)
		(end 75.251056 -53.904388)
		(width 0.0889)
		(layer "In2.Cu")
		(net "M_G_DQ<24>")
	)
	(arc
		(start 72.675496 -52.418488)
		(mid 72.884104 -52.63042)
		(end 73.169526 -52.71389)
		(width 0.0889)
		(layer "In2.Cu")
		(net "M_G_DQ<24>")
	)
	(arc
		(start 71.816976 -51.923442)
		(mid 72.02398 -52.134306)
		(end 72.307196 -52.21859)
		(width 0.0889)
		(layer "In2.Cu")
		(net "M_G_DQ<24>")
	)
	(segment
		(start 72.900286 -55.59044)
		(end 72.328786 -55.59044)
		(width 0.1016)
		(layer "F.Cu")
		(net "M_G_DQ<23>")
	)
	(segment
		(start 56.049418 -15.423642)
		(end 56.049418 -16.687546)
		(width 0.1651)
		(layer "F.Cu")
		(net "M_G_DQ<23>")
	)
	(via
		(at 72.328786 -55.59044)
		(size 0.508)
		(drill 0.254)
		(layers "F.Cu" "B.Cu")
		(net "M_G_DQ<23>")
	)
	(via
		(at 56.899302 -22.279356)
		(size 0.508)
		(drill 0.254)
		(layers "F.Cu" "B.Cu")
		(net "M_G_DQ<23>")
	)
	(via
		(at 56.049418 -16.687546)
		(size 0.508)
		(drill 0.254)
		(layers "F.Cu" "B.Cu")
		(net "M_G_DQ<23>")
	)
	(segment
		(start 56.899556 -20.224242)
		(end 56.899302 -20.224496)
		(width 0.1651)
		(layer "B.Cu")
		(net "M_G_DQ<23>")
	)
	(segment
		(start 56.899302 -20.224496)
		(end 56.899302 -22.279356)
		(width 0.1651)
		(layer "B.Cu")
		(net "M_G_DQ<23>")
	)
	(segment
		(start 55.774336 -24.995632)
		(end 55.774336 -37.996876)
		(width 0.14224)
		(layer "In2.Cu")
		(net "M_G_DQ<23>")
	)
	(segment
		(start 56.434736 -22.743922)
		(end 56.434736 -23.137368)
		(width 0.14224)
		(layer "In2.Cu")
		(net "M_G_DQ<23>")
	)
	(segment
		(start 71.377302 -55.59044)
		(end 72.328786 -55.59044)
		(width 0.0889)
		(layer "In2.Cu")
		(net "M_G_DQ<23>")
	)
	(segment
		(start 71.006462 -55.866792)
		(end 71.377302 -55.59044)
		(width 0.0889)
		(layer "In2.Cu")
		(net "M_G_DQ<23>")
	)
	(segment
		(start 55.962296 -38.184836)
		(end 56.267096 -38.184836)
		(width 0.14224)
		(layer "In2.Cu")
		(net "M_G_DQ<23>")
	)
	(segment
		(start 56.434736 -23.137368)
		(end 56.637936 -23.340568)
		(width 0.14224)
		(layer "In2.Cu")
		(net "M_G_DQ<23>")
	)
	(segment
		(start 56.696356 -17.653)
		(end 56.950356 -17.653)
		(width 0.14224)
		(layer "In2.Cu")
		(net "M_G_DQ<23>")
	)
	(segment
		(start 56.899302 -22.279356)
		(end 56.434736 -22.743922)
		(width 0.14224)
		(layer "In2.Cu")
		(net "M_G_DQ<23>")
	)
	(segment
		(start 67.242944 -53.29682)
		(end 67.499738 -53.553614)
		(width 0.0889)
		(layer "In2.Cu")
		(net "M_G_DQ<23>")
	)
	(segment
		(start 70.60057 -55.99049)
		(end 70.633336 -55.99049)
		(width 0.0889)
		(layer "In2.Cu")
		(net "M_G_DQ<23>")
	)
	(segment
		(start 57.00903 -34.3154)
		(end 57.21223 -34.5186)
		(width 0.14224)
		(layer "In2.Cu")
		(net "M_G_DQ<23>")
	)
	(segment
		(start 57.21223 -34.5186)
		(end 57.21223 -43.599862)
		(width 0.14224)
		(layer "In2.Cu")
		(net "M_G_DQ<23>")
	)
	(segment
		(start 57.407556 -18.4658)
		(end 57.252108 -18.621248)
		(width 0.14224)
		(layer "In2.Cu")
		(net "M_G_DQ<23>")
	)
	(segment
		(start 62.126368 -48.514)
		(end 63.447168 -48.514)
		(width 0.14224)
		(layer "In2.Cu")
		(net "M_G_DQ<23>")
	)
	(segment
		(start 66.839846 -51.906678)
		(end 66.839846 -52.893722)
		(width 0.14224)
		(layer "In2.Cu")
		(net "M_G_DQ<23>")
	)
	(segment
		(start 56.50103 -34.5186)
		(end 56.70423 -34.3154)
		(width 0.14224)
		(layer "In2.Cu")
		(net "M_G_DQ<23>")
	)
	(segment
		(start 57.252108 -18.621248)
		(end 57.252108 -21.92655)
		(width 0.14224)
		(layer "In2.Cu")
		(net "M_G_DQ<23>")
	)
	(segment
		(start 56.267096 -38.184836)
		(end 56.50103 -37.950902)
		(width 0.14224)
		(layer "In2.Cu")
		(net "M_G_DQ<23>")
	)
	(segment
		(start 56.366156 -17.3228)
		(end 56.696356 -17.653)
		(width 0.14224)
		(layer "In2.Cu")
		(net "M_G_DQ<23>")
	)
	(segment
		(start 56.637936 -23.340568)
		(end 56.637936 -24.132032)
		(width 0.14224)
		(layer "In2.Cu")
		(net "M_G_DQ<23>")
	)
	(segment
		(start 56.049418 -16.687546)
		(end 56.366156 -17.004284)
		(width 0.14224)
		(layer "In2.Cu")
		(net "M_G_DQ<23>")
	)
	(segment
		(start 55.774336 -37.996876)
		(end 55.962296 -38.184836)
		(width 0.14224)
		(layer "In2.Cu")
		(net "M_G_DQ<23>")
	)
	(segment
		(start 63.447168 -48.514)
		(end 66.839846 -51.906678)
		(width 0.14224)
		(layer "In2.Cu")
		(net "M_G_DQ<23>")
	)
	(segment
		(start 69.582538 -55.494936)
		(end 69.771006 -55.494936)
		(width 0.0889)
		(layer "In2.Cu")
		(net "M_G_DQ<23>")
	)
	(segment
		(start 66.839846 -52.893722)
		(end 67.242944 -53.29682)
		(width 0.14224)
		(layer "In2.Cu")
		(net "M_G_DQ<23>")
	)
	(segment
		(start 56.637936 -24.132032)
		(end 55.774336 -24.995632)
		(width 0.14224)
		(layer "In2.Cu")
		(net "M_G_DQ<23>")
	)
	(segment
		(start 67.641216 -53.553614)
		(end 69.582538 -55.494936)
		(width 0.0889)
		(layer "In2.Cu")
		(net "M_G_DQ<23>")
	)
	(segment
		(start 56.366156 -17.004284)
		(end 56.366156 -17.3228)
		(width 0.14224)
		(layer "In2.Cu")
		(net "M_G_DQ<23>")
	)
	(segment
		(start 57.21223 -43.599862)
		(end 62.126368 -48.514)
		(width 0.14224)
		(layer "In2.Cu")
		(net "M_G_DQ<23>")
	)
	(segment
		(start 56.50103 -37.950902)
		(end 56.50103 -34.5186)
		(width 0.14224)
		(layer "In2.Cu")
		(net "M_G_DQ<23>")
	)
	(segment
		(start 56.70423 -34.3154)
		(end 57.00903 -34.3154)
		(width 0.14224)
		(layer "In2.Cu")
		(net "M_G_DQ<23>")
	)
	(segment
		(start 67.499738 -53.553614)
		(end 67.641216 -53.553614)
		(width 0.0889)
		(layer "In2.Cu")
		(net "M_G_DQ<23>")
	)
	(segment
		(start 57.252108 -21.92655)
		(end 56.899302 -22.279356)
		(width 0.14224)
		(layer "In2.Cu")
		(net "M_G_DQ<23>")
	)
	(segment
		(start 56.950356 -17.653)
		(end 57.407556 -18.1102)
		(width 0.14224)
		(layer "In2.Cu")
		(net "M_G_DQ<23>")
	)
	(segment
		(start 57.407556 -18.1102)
		(end 57.407556 -18.4658)
		(width 0.14224)
		(layer "In2.Cu")
		(net "M_G_DQ<23>")
	)
	(arc
		(start 69.771006 -55.494936)
		(mid 70.05643 -55.578403)
		(end 70.265036 -55.790338)
		(width 0.0889)
		(layer "In2.Cu")
		(net "M_G_DQ<23>")
	)
	(arc
		(start 70.265036 -55.790338)
		(mid 70.406719 -55.934142)
		(end 70.60057 -55.99049)
		(width 0.0889)
		(layer "In2.Cu")
		(net "M_G_DQ<23>")
	)
	(arc
		(start 70.633336 -55.99049)
		(mid 70.829883 -55.958759)
		(end 71.006462 -55.866792)
		(width 0.0889)
		(layer "In2.Cu")
		(net "M_G_DQ<23>")
	)
	(segment
		(start 56.899556 -19.05)
		(end 57.031636 -18.91792)
		(width 0.1651)
		(layer "F.Cu")
		(net "M_G_DQ<22>")
	)
	(segment
		(start 56.899556 -18.5674)
		(end 56.899556 -18.262854)
		(width 0.1651)
		(layer "F.Cu")
		(net "M_G_DQ<22>")
	)
	(segment
		(start 57.031636 -18.91792)
		(end 57.031636 -18.69948)
		(width 0.1651)
		(layer "F.Cu")
		(net "M_G_DQ<22>")
	)
	(segment
		(start 56.899556 -18.262854)
		(end 56.899302 -18.2626)
		(width 0.1651)
		(layer "F.Cu")
		(net "M_G_DQ<22>")
	)
	(segment
		(start 57.031636 -18.69948)
		(end 56.899556 -18.5674)
		(width 0.1651)
		(layer "F.Cu")
		(net "M_G_DQ<22>")
	)
	(segment
		(start 56.899556 -20.023582)
		(end 56.899556 -19.05)
		(width 0.1651)
		(layer "F.Cu")
		(net "M_G_DQ<22>")
	)
	(segment
		(start 71.183246 -56.58104)
		(end 70.611746 -56.58104)
		(width 0.1016)
		(layer "F.Cu")
		(net "M_G_DQ<22>")
	)
	(via
		(at 56.899302 -18.2626)
		(size 0.508)
		(drill 0.254)
		(layers "F.Cu" "B.Cu")
		(net "M_G_DQ<22>")
	)
	(via
		(at 70.611746 -56.58104)
		(size 0.508)
		(drill 0.254)
		(layers "F.Cu" "B.Cu")
		(net "M_G_DQ<22>")
	)
	(via
		(at 56.049418 -23.561294)
		(size 0.508)
		(drill 0.254)
		(layers "F.Cu" "B.Cu")
		(net "M_G_DQ<22>")
	)
	(segment
		(start 56.049418 -23.561294)
		(end 56.049418 -24.824182)
		(width 0.1651)
		(layer "B.Cu")
		(net "M_G_DQ<22>")
	)
	(segment
		(start 56.716168 -41.84142)
		(end 56.716168 -41.47566)
		(width 0.14224)
		(layer "In2.Cu")
		(net "M_G_DQ<22>")
	)
	(segment
		(start 55.113936 -39.52494)
		(end 55.256176 -39.3827)
		(width 0.14224)
		(layer "In2.Cu")
		(net "M_G_DQ<22>")
	)
	(segment
		(start 55.256176 -38.73246)
		(end 55.113936 -38.59022)
		(width 0.14224)
		(layer "In2.Cu")
		(net "M_G_DQ<22>")
	)
	(segment
		(start 56.573928 -40.03294)
		(end 55.256176 -40.03294)
		(width 0.14224)
		(layer "In2.Cu")
		(net "M_G_DQ<22>")
	)
	(segment
		(start 56.541924 -19.970496)
		(end 56.160924 -19.589496)
		(width 0.14224)
		(layer "In2.Cu")
		(net "M_G_DQ<22>")
	)
	(segment
		(start 56.524906 -18.914872)
		(end 56.524906 -18.636996)
		(width 0.14224)
		(layer "In2.Cu")
		(net "M_G_DQ<22>")
	)
	(segment
		(start 55.113936 -42.720768)
		(end 55.113936 -42.1259)
		(width 0.14224)
		(layer "In2.Cu")
		(net "M_G_DQ<22>")
	)
	(segment
		(start 67.411346 -53.743606)
		(end 67.210432 -53.94452)
		(width 0.0889)
		(layer "In2.Cu")
		(net "M_G_DQ<22>")
	)
	(segment
		(start 56.573928 -41.33342)
		(end 55.256176 -41.33342)
		(width 0.14224)
		(layer "In2.Cu")
		(net "M_G_DQ<22>")
	)
	(segment
		(start 56.716168 -40.54094)
		(end 56.716168 -40.17518)
		(width 0.14224)
		(layer "In2.Cu")
		(net "M_G_DQ<22>")
	)
	(segment
		(start 70.626732 -56.18099)
		(end 70.593966 -56.18099)
		(width 0.0889)
		(layer "In2.Cu")
		(net "M_G_DQ<22>")
	)
	(segment
		(start 56.716168 -38.8747)
		(end 56.573928 -38.73246)
		(width 0.14224)
		(layer "In2.Cu")
		(net "M_G_DQ<22>")
	)
	(segment
		(start 55.813706 -23.325582)
		(end 55.813706 -22.530054)
		(width 0.14224)
		(layer "In2.Cu")
		(net "M_G_DQ<22>")
	)
	(segment
		(start 56.586374 -21.757386)
		(end 56.586374 -21.405596)
		(width 0.14224)
		(layer "In2.Cu")
		(net "M_G_DQ<22>")
	)
	(segment
		(start 62.18682 -49.793652)
		(end 55.113936 -42.720768)
		(width 0.14224)
		(layer "In2.Cu")
		(net "M_G_DQ<22>")
	)
	(segment
		(start 63.599568 -51.2064)
		(end 62.847982 -50.454814)
		(width 0.14224)
		(layer "In2.Cu")
		(net "M_G_DQ<22>")
	)
	(segment
		(start 56.573928 -41.98366)
		(end 56.716168 -41.84142)
		(width 0.14224)
		(layer "In2.Cu")
		(net "M_G_DQ<22>")
	)
	(segment
		(start 56.160924 -20.694904)
		(end 56.541924 -20.313904)
		(width 0.14224)
		(layer "In2.Cu")
		(net "M_G_DQ<22>")
	)
	(segment
		(start 55.813706 -22.530054)
		(end 56.586374 -21.757386)
		(width 0.14224)
		(layer "In2.Cu")
		(net "M_G_DQ<22>")
	)
	(segment
		(start 67.562476 -53.743606)
		(end 67.411346 -53.743606)
		(width 0.0889)
		(layer "In2.Cu")
		(net "M_G_DQ<22>")
	)
	(segment
		(start 55.256176 -40.03294)
		(end 55.113936 -39.8907)
		(width 0.14224)
		(layer "In2.Cu")
		(net "M_G_DQ<22>")
	)
	(segment
		(start 55.113936 -41.19118)
		(end 55.113936 -40.82542)
		(width 0.14224)
		(layer "In2.Cu")
		(net "M_G_DQ<22>")
	)
	(segment
		(start 69.504306 -55.685436)
		(end 67.562476 -53.743606)
		(width 0.0889)
		(layer "In2.Cu")
		(net "M_G_DQ<22>")
	)
	(segment
		(start 55.113936 -24.894032)
		(end 56.049418 -23.95855)
		(width 0.14224)
		(layer "In2.Cu")
		(net "M_G_DQ<22>")
	)
	(segment
		(start 56.524906 -18.636996)
		(end 56.899302 -18.2626)
		(width 0.14224)
		(layer "In2.Cu")
		(net "M_G_DQ<22>")
	)
	(segment
		(start 55.113936 -40.82542)
		(end 55.256176 -40.68318)
		(width 0.14224)
		(layer "In2.Cu")
		(net "M_G_DQ<22>")
	)
	(segment
		(start 63.142114 -49.959514)
		(end 63.142114 -49.758346)
		(width 0.14224)
		(layer "In2.Cu")
		(net "M_G_DQ<22>")
	)
	(segment
		(start 70.904862 -56.411876)
		(end 70.925944 -56.333136)
		(width 0.0889)
		(layer "In2.Cu")
		(net "M_G_DQ<22>")
	)
	(segment
		(start 56.160924 -20.980146)
		(end 56.160924 -20.694904)
		(width 0.14224)
		(layer "In2.Cu")
		(net "M_G_DQ<22>")
	)
	(segment
		(start 67.210432 -53.94452)
		(end 66.947288 -53.94452)
		(width 0.14224)
		(layer "In2.Cu")
		(net "M_G_DQ<22>")
	)
	(segment
		(start 64.209168 -51.2064)
		(end 63.599568 -51.2064)
		(width 0.14224)
		(layer "In2.Cu")
		(net "M_G_DQ<22>")
	)
	(segment
		(start 55.256176 -41.33342)
		(end 55.113936 -41.19118)
		(width 0.14224)
		(layer "In2.Cu")
		(net "M_G_DQ<22>")
	)
	(segment
		(start 69.764402 -55.685436)
		(end 69.504306 -55.685436)
		(width 0.0889)
		(layer "In2.Cu")
		(net "M_G_DQ<22>")
	)
	(segment
		(start 56.716168 -39.24046)
		(end 56.716168 -38.8747)
		(width 0.14224)
		(layer "In2.Cu")
		(net "M_G_DQ<22>")
	)
	(segment
		(start 56.586374 -21.405596)
		(end 56.160924 -20.980146)
		(width 0.14224)
		(layer "In2.Cu")
		(net "M_G_DQ<22>")
	)
	(segment
		(start 55.256176 -40.68318)
		(end 56.573928 -40.68318)
		(width 0.14224)
		(layer "In2.Cu")
		(net "M_G_DQ<22>")
	)
	(segment
		(start 55.113936 -39.8907)
		(end 55.113936 -39.52494)
		(width 0.14224)
		(layer "In2.Cu")
		(net "M_G_DQ<22>")
	)
	(segment
		(start 56.573928 -40.68318)
		(end 56.716168 -40.54094)
		(width 0.14224)
		(layer "In2.Cu")
		(net "M_G_DQ<22>")
	)
	(segment
		(start 56.573928 -38.73246)
		(end 55.256176 -38.73246)
		(width 0.14224)
		(layer "In2.Cu")
		(net "M_G_DQ<22>")
	)
	(segment
		(start 56.541924 -20.313904)
		(end 56.541924 -19.970496)
		(width 0.14224)
		(layer "In2.Cu")
		(net "M_G_DQ<22>")
	)
	(segment
		(start 56.716168 -40.17518)
		(end 56.573928 -40.03294)
		(width 0.14224)
		(layer "In2.Cu")
		(net "M_G_DQ<22>")
	)
	(segment
		(start 62.68212 -49.49952)
		(end 62.387988 -49.793652)
		(width 0.14224)
		(layer "In2.Cu")
		(net "M_G_DQ<22>")
	)
	(segment
		(start 66.947288 -53.94452)
		(end 64.209168 -51.2064)
		(width 0.14224)
		(layer "In2.Cu")
		(net "M_G_DQ<22>")
	)
	(segment
		(start 55.113936 -42.1259)
		(end 55.256176 -41.98366)
		(width 0.14224)
		(layer "In2.Cu")
		(net "M_G_DQ<22>")
	)
	(segment
		(start 55.256176 -39.3827)
		(end 56.573928 -39.3827)
		(width 0.14224)
		(layer "In2.Cu")
		(net "M_G_DQ<22>")
	)
	(segment
		(start 56.716168 -41.47566)
		(end 56.573928 -41.33342)
		(width 0.14224)
		(layer "In2.Cu")
		(net "M_G_DQ<22>")
	)
	(segment
		(start 62.847982 -50.253646)
		(end 63.142114 -49.959514)
		(width 0.14224)
		(layer "In2.Cu")
		(net "M_G_DQ<22>")
	)
	(segment
		(start 56.049418 -23.95855)
		(end 56.049418 -23.561294)
		(width 0.14224)
		(layer "In2.Cu")
		(net "M_G_DQ<22>")
	)
	(segment
		(start 63.142114 -49.758346)
		(end 62.883288 -49.49952)
		(width 0.14224)
		(layer "In2.Cu")
		(net "M_G_DQ<22>")
	)
	(segment
		(start 55.256176 -41.98366)
		(end 56.573928 -41.98366)
		(width 0.14224)
		(layer "In2.Cu")
		(net "M_G_DQ<22>")
	)
	(segment
		(start 55.113936 -38.59022)
		(end 55.113936 -24.894032)
		(width 0.14224)
		(layer "In2.Cu")
		(net "M_G_DQ<22>")
	)
	(segment
		(start 56.160924 -19.589496)
		(end 56.160924 -19.278854)
		(width 0.14224)
		(layer "In2.Cu")
		(net "M_G_DQ<22>")
	)
	(segment
		(start 56.049418 -23.561294)
		(end 55.813706 -23.325582)
		(width 0.14224)
		(layer "In2.Cu")
		(net "M_G_DQ<22>")
	)
	(segment
		(start 56.573928 -39.3827)
		(end 56.716168 -39.24046)
		(width 0.14224)
		(layer "In2.Cu")
		(net "M_G_DQ<22>")
	)
	(segment
		(start 62.847982 -50.454814)
		(end 62.847982 -50.253646)
		(width 0.14224)
		(layer "In2.Cu")
		(net "M_G_DQ<22>")
	)
	(segment
		(start 62.387988 -49.793652)
		(end 62.18682 -49.793652)
		(width 0.14224)
		(layer "In2.Cu")
		(net "M_G_DQ<22>")
	)
	(segment
		(start 56.160924 -19.278854)
		(end 56.524906 -18.914872)
		(width 0.14224)
		(layer "In2.Cu")
		(net "M_G_DQ<22>")
	)
	(segment
		(start 70.611746 -56.58104)
		(end 70.904862 -56.411876)
		(width 0.0889)
		(layer "In2.Cu")
		(net "M_G_DQ<22>")
	)
	(segment
		(start 62.883288 -49.49952)
		(end 62.68212 -49.49952)
		(width 0.14224)
		(layer "In2.Cu")
		(net "M_G_DQ<22>")
	)
	(arc
		(start 70.099936 -55.885588)
		(mid 69.958253 -55.741784)
		(end 69.764402 -55.685436)
		(width 0.0889)
		(layer "In2.Cu")
		(net "M_G_DQ<22>")
	)
	(arc
		(start 70.925944 -56.333136)
		(mid 70.793063 -56.224153)
		(end 70.626732 -56.18099)
		(width 0.0889)
		(layer "In2.Cu")
		(net "M_G_DQ<22>")
	)
	(arc
		(start 70.593966 -56.18099)
		(mid 70.308542 -56.097523)
		(end 70.099936 -55.885588)
		(width 0.0889)
		(layer "In2.Cu")
		(net "M_G_DQ<22>")
	)
	(segment
		(start 73.758806 -58.06694)
		(end 73.187306 -58.06694)
		(width 0.1016)
		(layer "F.Cu")
		(net "M_G_DQ<21>")
	)
	(segment
		(start 50.099468 -15.423642)
		(end 50.099468 -16.687546)
		(width 0.1651)
		(layer "F.Cu")
		(net "M_G_DQ<21>")
	)
	(via
		(at 50.099468 -16.687546)
		(size 0.508)
		(drill 0.254)
		(layers "F.Cu" "B.Cu")
		(net "M_G_DQ<21>")
	)
	(via
		(at 50.873152 -22.279356)
		(size 0.508)
		(drill 0.254)
		(layers "F.Cu" "B.Cu")
		(net "M_G_DQ<21>")
	)
	(via
		(at 73.187306 -58.06694)
		(size 0.508)
		(drill 0.254)
		(layers "F.Cu" "B.Cu")
		(net "M_G_DQ<21>")
	)
	(segment
		(start 50.949352 -22.203156)
		(end 50.873152 -22.279356)
		(width 0.1651)
		(layer "B.Cu")
		(net "M_G_DQ<21>")
	)
	(segment
		(start 50.949352 -20.224242)
		(end 50.949352 -22.203156)
		(width 0.1651)
		(layer "B.Cu")
		(net "M_G_DQ<21>")
	)
	(segment
		(start 72.310752 -58.16219)
		(end 72.365362 -58.16219)
		(width 0.0889)
		(layer "In2.Cu")
		(net "M_G_DQ<21>")
	)
	(segment
		(start 50.981102 -17.653)
		(end 51.381406 -18.053304)
		(width 0.14224)
		(layer "In2.Cu")
		(net "M_G_DQ<21>")
	)
	(segment
		(start 71.866506 -59.114182)
		(end 71.935086 -58.443622)
		(width 0.0889)
		(layer "In2.Cu")
		(net "M_G_DQ<21>")
	)
	(segment
		(start 50.455068 -43.764454)
		(end 65.212722 -58.522108)
		(width 0.14224)
		(layer "In2.Cu")
		(net "M_G_DQ<21>")
	)
	(segment
		(start 50.099468 -16.687546)
		(end 50.099468 -17.082262)
		(width 0.14224)
		(layer "In2.Cu")
		(net "M_G_DQ<21>")
	)
	(segment
		(start 50.389536 -23.162768)
		(end 50.592736 -23.365968)
		(width 0.14224)
		(layer "In2.Cu")
		(net "M_G_DQ<21>")
	)
	(segment
		(start 67.68973 -58.874152)
		(end 68.272914 -59.457336)
		(width 0.0889)
		(layer "In2.Cu")
		(net "M_G_DQ<21>")
	)
	(segment
		(start 66.268092 -58.522108)
		(end 66.346832 -58.522108)
		(width 0.0889)
		(layer "In2.Cu")
		(net "M_G_DQ<21>")
	)
	(segment
		(start 50.099468 -17.082262)
		(end 50.670206 -17.653)
		(width 0.14224)
		(layer "In2.Cu")
		(net "M_G_DQ<21>")
	)
	(segment
		(start 50.670206 -17.653)
		(end 50.981102 -17.653)
		(width 0.14224)
		(layer "In2.Cu")
		(net "M_G_DQ<21>")
	)
	(segment
		(start 51.381406 -18.053304)
		(end 51.381406 -18.4658)
		(width 0.14224)
		(layer "In2.Cu")
		(net "M_G_DQ<21>")
	)
	(segment
		(start 50.592736 -23.365968)
		(end 50.592736 -24.333454)
		(width 0.14224)
		(layer "In2.Cu")
		(net "M_G_DQ<21>")
	)
	(segment
		(start 50.455068 -24.471122)
		(end 50.455068 -43.764454)
		(width 0.14224)
		(layer "In2.Cu")
		(net "M_G_DQ<21>")
	)
	(segment
		(start 50.873152 -22.279356)
		(end 50.389536 -22.762972)
		(width 0.14224)
		(layer "In2.Cu")
		(net "M_G_DQ<21>")
	)
	(segment
		(start 51.381406 -18.4658)
		(end 51.184556 -18.66265)
		(width 0.14224)
		(layer "In2.Cu")
		(net "M_G_DQ<21>")
	)
	(segment
		(start 51.184556 -18.66265)
		(end 51.184556 -21.967952)
		(width 0.14224)
		(layer "In2.Cu")
		(net "M_G_DQ<21>")
	)
	(segment
		(start 66.698876 -58.874152)
		(end 67.68973 -58.874152)
		(width 0.0889)
		(layer "In2.Cu")
		(net "M_G_DQ<21>")
	)
	(segment
		(start 71.452486 -59.457336)
		(end 71.485252 -59.457336)
		(width 0.0889)
		(layer "In2.Cu")
		(net "M_G_DQ<21>")
	)
	(segment
		(start 65.212722 -58.522108)
		(end 66.268092 -58.522108)
		(width 0.14224)
		(layer "In2.Cu")
		(net "M_G_DQ<21>")
	)
	(segment
		(start 66.346832 -58.522108)
		(end 66.698876 -58.874152)
		(width 0.0889)
		(layer "In2.Cu")
		(net "M_G_DQ<21>")
	)
	(segment
		(start 50.389536 -22.762972)
		(end 50.389536 -23.162768)
		(width 0.14224)
		(layer "In2.Cu")
		(net "M_G_DQ<21>")
	)
	(segment
		(start 51.184556 -21.967952)
		(end 50.873152 -22.279356)
		(width 0.14224)
		(layer "In2.Cu")
		(net "M_G_DQ<21>")
	)
	(segment
		(start 71.935086 -58.443622)
		(end 71.982076 -58.362088)
		(width 0.0889)
		(layer "In2.Cu")
		(net "M_G_DQ<21>")
	)
	(segment
		(start 72.365362 -58.16219)
		(end 73.187306 -58.06694)
		(width 0.0889)
		(layer "In2.Cu")
		(net "M_G_DQ<21>")
	)
	(segment
		(start 68.272914 -59.457336)
		(end 69.771006 -59.457336)
		(width 0.0889)
		(layer "In2.Cu")
		(net "M_G_DQ<21>")
	)
	(segment
		(start 50.592736 -24.333454)
		(end 50.455068 -24.471122)
		(width 0.14224)
		(layer "In2.Cu")
		(net "M_G_DQ<21>")
	)
	(arc
		(start 71.485252 -59.457336)
		(mid 71.676894 -59.40017)
		(end 71.816976 -59.257438)
		(width 0.0889)
		(layer "In2.Cu")
		(net "M_G_DQ<21>")
	)
	(arc
		(start 70.958456 -59.752738)
		(mid 71.167064 -59.540806)
		(end 71.452486 -59.457336)
		(width 0.0889)
		(layer "In2.Cu")
		(net "M_G_DQ<21>")
	)
	(arc
		(start 70.265036 -59.752738)
		(mid 70.416397 -59.902133)
		(end 70.622922 -59.95289)
		(width 0.0889)
		(layer "In2.Cu")
		(net "M_G_DQ<21>")
	)
	(arc
		(start 69.771006 -59.457336)
		(mid 70.05643 -59.540803)
		(end 70.265036 -59.752738)
		(width 0.0889)
		(layer "In2.Cu")
		(net "M_G_DQ<21>")
	)
	(arc
		(start 71.982076 -58.362088)
		(mid 72.12082 -58.220055)
		(end 72.310752 -58.16219)
		(width 0.0889)
		(layer "In2.Cu")
		(net "M_G_DQ<21>")
	)
	(arc
		(start 71.816976 -59.257438)
		(mid 71.848599 -59.188179)
		(end 71.866506 -59.114182)
		(width 0.0889)
		(layer "In2.Cu")
		(net "M_G_DQ<21>")
	)
	(arc
		(start 70.622922 -59.95289)
		(mid 70.816772 -59.89654)
		(end 70.958456 -59.752738)
		(width 0.0889)
		(layer "In2.Cu")
		(net "M_G_DQ<21>")
	)
	(segment
		(start 72.900286 -58.561986)
		(end 72.328786 -58.561986)
		(width 0.1016)
		(layer "F.Cu")
		(net "M_G_DQ<20>")
	)
	(segment
		(start 50.949352 -20.023582)
		(end 50.949352 -18.692368)
		(width 0.1651)
		(layer "F.Cu")
		(net "M_G_DQ<20>")
	)
	(segment
		(start 50.949352 -18.692368)
		(end 50.851308 -18.161)
		(width 0.1651)
		(layer "F.Cu")
		(net "M_G_DQ<20>")
	)
	(via
		(at 50.851308 -18.161)
		(size 0.508)
		(drill 0.254)
		(layers "F.Cu" "B.Cu")
		(net "M_G_DQ<20>")
	)
	(via
		(at 72.328786 -58.561986)
		(size 0.508)
		(drill 0.254)
		(layers "F.Cu" "B.Cu")
		(net "M_G_DQ<20>")
	)
	(via
		(at 50.099468 -23.560278)
		(size 0.508)
		(drill 0.254)
		(layers "F.Cu" "B.Cu")
		(net "M_G_DQ<20>")
	)
	(segment
		(start 50.099468 -23.560278)
		(end 50.099468 -24.824182)
		(width 0.1651)
		(layer "B.Cu")
		(net "M_G_DQ<20>")
	)
	(segment
		(start 50.591974 -19.9644)
		(end 50.591974 -20.2692)
		(width 0.14224)
		(layer "In2.Cu")
		(net "M_G_DQ<20>")
	)
	(segment
		(start 50.574956 -18.914872)
		(end 50.210974 -19.278854)
		(width 0.14224)
		(layer "In2.Cu")
		(net "M_G_DQ<20>")
	)
	(segment
		(start 49.863756 -22.530054)
		(end 49.863756 -23.324566)
		(width 0.14224)
		(layer "In2.Cu")
		(net "M_G_DQ<20>")
	)
	(segment
		(start 49.703736 -23.95601)
		(end 49.703736 -44.028614)
		(width 0.14224)
		(layer "In2.Cu")
		(net "M_G_DQ<20>")
	)
	(segment
		(start 50.223674 -20.992846)
		(end 50.574956 -21.344128)
		(width 0.14224)
		(layer "In2.Cu")
		(net "M_G_DQ<20>")
	)
	(segment
		(start 67.611498 -59.064652)
		(end 68.194682 -59.647836)
		(width 0.0889)
		(layer "In2.Cu")
		(net "M_G_DQ<20>")
	)
	(segment
		(start 50.574956 -21.344128)
		(end 50.574956 -21.818854)
		(width 0.14224)
		(layer "In2.Cu")
		(net "M_G_DQ<20>")
	)
	(segment
		(start 66.30543 -59.169808)
		(end 66.404744 -59.169808)
		(width 0.0889)
		(layer "In2.Cu")
		(net "M_G_DQ<20>")
	)
	(segment
		(start 66.5099 -59.064652)
		(end 67.611498 -59.064652)
		(width 0.0889)
		(layer "In2.Cu")
		(net "M_G_DQ<20>")
	)
	(segment
		(start 64.84493 -59.169808)
		(end 66.30543 -59.169808)
		(width 0.14224)
		(layer "In2.Cu")
		(net "M_G_DQ<20>")
	)
	(segment
		(start 71.45909 -59.647836)
		(end 71.491856 -59.647836)
		(width 0.0889)
		(layer "In2.Cu")
		(net "M_G_DQ<20>")
	)
	(segment
		(start 50.223674 -20.6375)
		(end 50.223674 -20.992846)
		(width 0.14224)
		(layer "In2.Cu")
		(net "M_G_DQ<20>")
	)
	(segment
		(start 50.574956 -18.437352)
		(end 50.574956 -18.914872)
		(width 0.14224)
		(layer "In2.Cu")
		(net "M_G_DQ<20>")
	)
	(segment
		(start 50.210974 -19.5834)
		(end 50.591974 -19.9644)
		(width 0.14224)
		(layer "In2.Cu")
		(net "M_G_DQ<20>")
	)
	(segment
		(start 68.194682 -59.647836)
		(end 69.764402 -59.647836)
		(width 0.0889)
		(layer "In2.Cu")
		(net "M_G_DQ<20>")
	)
	(segment
		(start 50.574956 -21.818854)
		(end 49.863756 -22.530054)
		(width 0.14224)
		(layer "In2.Cu")
		(net "M_G_DQ<20>")
	)
	(segment
		(start 50.099468 -23.560278)
		(end 49.703736 -23.95601)
		(width 0.14224)
		(layer "In2.Cu")
		(net "M_G_DQ<20>")
	)
	(segment
		(start 72.017636 -59.27979)
		(end 72.328786 -58.561986)
		(width 0.0889)
		(layer "In2.Cu")
		(net "M_G_DQ<20>")
	)
	(segment
		(start 50.851308 -18.161)
		(end 50.574956 -18.437352)
		(width 0.14224)
		(layer "In2.Cu")
		(net "M_G_DQ<20>")
	)
	(segment
		(start 70.593966 -60.14339)
		(end 70.629526 -60.14339)
		(width 0.0889)
		(layer "In2.Cu")
		(net "M_G_DQ<20>")
	)
	(segment
		(start 49.863756 -23.324566)
		(end 50.099468 -23.560278)
		(width 0.14224)
		(layer "In2.Cu")
		(net "M_G_DQ<20>")
	)
	(segment
		(start 49.703736 -44.028614)
		(end 64.84493 -59.169808)
		(width 0.14224)
		(layer "In2.Cu")
		(net "M_G_DQ<20>")
	)
	(segment
		(start 50.210974 -19.278854)
		(end 50.210974 -19.5834)
		(width 0.14224)
		(layer "In2.Cu")
		(net "M_G_DQ<20>")
	)
	(segment
		(start 66.404744 -59.169808)
		(end 66.5099 -59.064652)
		(width 0.0889)
		(layer "In2.Cu")
		(net "M_G_DQ<20>")
	)
	(segment
		(start 50.591974 -20.2692)
		(end 50.223674 -20.6375)
		(width 0.14224)
		(layer "In2.Cu")
		(net "M_G_DQ<20>")
	)
	(arc
		(start 71.982076 -59.352688)
		(mid 72.001107 -59.316849)
		(end 72.017636 -59.27979)
		(width 0.0889)
		(layer "In2.Cu")
		(net "M_G_DQ<20>")
	)
	(arc
		(start 71.123556 -59.847988)
		(mid 71.265239 -59.704184)
		(end 71.45909 -59.647836)
		(width 0.0889)
		(layer "In2.Cu")
		(net "M_G_DQ<20>")
	)
	(arc
		(start 70.099936 -59.847988)
		(mid 70.308544 -60.05992)
		(end 70.593966 -60.14339)
		(width 0.0889)
		(layer "In2.Cu")
		(net "M_G_DQ<20>")
	)
	(arc
		(start 69.764402 -59.647836)
		(mid 69.958252 -59.704186)
		(end 70.099936 -59.847988)
		(width 0.0889)
		(layer "In2.Cu")
		(net "M_G_DQ<20>")
	)
	(arc
		(start 71.491856 -59.647836)
		(mid 71.775073 -59.563555)
		(end 71.982076 -59.352688)
		(width 0.0889)
		(layer "In2.Cu")
		(net "M_G_DQ<20>")
	)
	(arc
		(start 70.629526 -60.14339)
		(mid 70.91495 -60.059923)
		(end 71.123556 -59.847988)
		(width 0.0889)
		(layer "In2.Cu")
		(net "M_G_DQ<20>")
	)
	(segment
		(start 69.466206 -65.49644)
		(end 68.894706 -65.49644)
		(width 0.1016)
		(layer "F.Cu")
		(net "M_G_DQ<1>")
	)
	(segment
		(start 33.099502 -15.423642)
		(end 33.099502 -16.687546)
		(width 0.1651)
		(layer "F.Cu")
		(net "M_G_DQ<1>")
	)
	(via
		(at 33.099502 -16.687546)
		(size 0.508)
		(drill 0.254)
		(layers "F.Cu" "B.Cu")
		(net "M_G_DQ<1>")
	)
	(via
		(at 33.771586 -22.279356)
		(size 0.508)
		(drill 0.254)
		(layers "F.Cu" "B.Cu")
		(net "M_G_DQ<1>")
	)
	(via
		(at 68.894706 -65.49644)
		(size 0.508)
		(drill 0.254)
		(layers "F.Cu" "B.Cu")
		(net "M_G_DQ<1>")
	)
	(segment
		(start 33.771586 -21.776182)
		(end 33.771586 -22.279356)
		(width 0.1651)
		(layer "B.Cu")
		(net "M_G_DQ<1>")
	)
	(segment
		(start 33.949386 -20.224242)
		(end 33.949386 -21.598382)
		(width 0.1651)
		(layer "B.Cu")
		(net "M_G_DQ<1>")
	)
	(segment
		(start 33.949386 -21.598382)
		(end 33.771586 -21.776182)
		(width 0.1651)
		(layer "B.Cu")
		(net "M_G_DQ<1>")
	)
	(segment
		(start 33.244536 -26.256742)
		(end 33.041336 -26.459942)
		(width 0.14224)
		(layer "In2.Cu")
		(net "M_G_DQ<1>")
	)
	(segment
		(start 65.631568 -65.497202)
		(end 66.263012 -65.497202)
		(width 0.0889)
		(layer "In2.Cu")
		(net "M_G_DQ<1>")
	)
	(segment
		(start 33.099502 -16.687546)
		(end 33.099502 -17.226534)
		(width 0.14224)
		(layer "In2.Cu")
		(net "M_G_DQ<1>")
	)
	(segment
		(start 67.358514 -65.014602)
		(end 67.840352 -65.49644)
		(width 0.0889)
		(layer "In2.Cu")
		(net "M_G_DQ<1>")
	)
	(segment
		(start 34.133536 -27.272742)
		(end 34.133536 -36.328096)
		(width 0.14224)
		(layer "In2.Cu")
		(net "M_G_DQ<1>")
	)
	(segment
		(start 67.840352 -65.49644)
		(end 68.894706 -65.49644)
		(width 0.0889)
		(layer "In2.Cu")
		(net "M_G_DQ<1>")
	)
	(segment
		(start 33.295336 -23.137368)
		(end 33.62452 -23.466552)
		(width 0.14224)
		(layer "In2.Cu")
		(net "M_G_DQ<1>")
	)
	(segment
		(start 33.041336 -26.764742)
		(end 33.244536 -26.967942)
		(width 0.14224)
		(layer "In2.Cu")
		(net "M_G_DQ<1>")
	)
	(segment
		(start 33.828736 -26.256742)
		(end 33.244536 -26.256742)
		(width 0.14224)
		(layer "In2.Cu")
		(net "M_G_DQ<1>")
	)
	(segment
		(start 33.295336 -22.755606)
		(end 33.295336 -23.137368)
		(width 0.14224)
		(layer "In2.Cu")
		(net "M_G_DQ<1>")
	)
	(segment
		(start 66.745612 -65.014602)
		(end 67.358514 -65.014602)
		(width 0.0889)
		(layer "In2.Cu")
		(net "M_G_DQ<1>")
	)
	(segment
		(start 33.62452 -25.337008)
		(end 34.031936 -25.744424)
		(width 0.14224)
		(layer "In2.Cu")
		(net "M_G_DQ<1>")
	)
	(segment
		(start 33.244536 -26.967942)
		(end 33.828736 -26.967942)
		(width 0.14224)
		(layer "In2.Cu")
		(net "M_G_DQ<1>")
	)
	(segment
		(start 34.031936 -25.744424)
		(end 34.031936 -26.053542)
		(width 0.14224)
		(layer "In2.Cu")
		(net "M_G_DQ<1>")
	)
	(segment
		(start 63.302642 -65.497202)
		(end 65.631568 -65.497202)
		(width 0.14224)
		(layer "In2.Cu")
		(net "M_G_DQ<1>")
	)
	(segment
		(start 33.932368 -17.7038)
		(end 34.302192 -18.073624)
		(width 0.14224)
		(layer "In2.Cu")
		(net "M_G_DQ<1>")
	)
	(segment
		(start 33.041336 -26.459942)
		(end 33.041336 -26.764742)
		(width 0.14224)
		(layer "In2.Cu")
		(net "M_G_DQ<1>")
	)
	(segment
		(start 34.145728 -18.571464)
		(end 34.145728 -21.905214)
		(width 0.14224)
		(layer "In2.Cu")
		(net "M_G_DQ<1>")
	)
	(segment
		(start 34.302192 -18.073624)
		(end 34.302192 -18.415)
		(width 0.14224)
		(layer "In2.Cu")
		(net "M_G_DQ<1>")
	)
	(segment
		(start 66.263012 -65.497202)
		(end 66.745612 -65.014602)
		(width 0.0889)
		(layer "In2.Cu")
		(net "M_G_DQ<1>")
	)
	(segment
		(start 34.133536 -36.328096)
		(end 63.302642 -65.497202)
		(width 0.14224)
		(layer "In2.Cu")
		(net "M_G_DQ<1>")
	)
	(segment
		(start 33.771586 -22.279356)
		(end 33.295336 -22.755606)
		(width 0.14224)
		(layer "In2.Cu")
		(net "M_G_DQ<1>")
	)
	(segment
		(start 33.099502 -17.226534)
		(end 33.576768 -17.7038)
		(width 0.14224)
		(layer "In2.Cu")
		(net "M_G_DQ<1>")
	)
	(segment
		(start 33.828736 -26.967942)
		(end 34.133536 -27.272742)
		(width 0.14224)
		(layer "In2.Cu")
		(net "M_G_DQ<1>")
	)
	(segment
		(start 33.576768 -17.7038)
		(end 33.932368 -17.7038)
		(width 0.14224)
		(layer "In2.Cu")
		(net "M_G_DQ<1>")
	)
	(segment
		(start 33.62452 -23.466552)
		(end 33.62452 -25.337008)
		(width 0.14224)
		(layer "In2.Cu")
		(net "M_G_DQ<1>")
	)
	(segment
		(start 34.031936 -26.053542)
		(end 33.828736 -26.256742)
		(width 0.14224)
		(layer "In2.Cu")
		(net "M_G_DQ<1>")
	)
	(segment
		(start 34.302192 -18.415)
		(end 34.145728 -18.571464)
		(width 0.14224)
		(layer "In2.Cu")
		(net "M_G_DQ<1>")
	)
	(segment
		(start 34.145728 -21.905214)
		(end 33.771586 -22.279356)
		(width 0.14224)
		(layer "In2.Cu")
		(net "M_G_DQ<1>")
	)
	(segment
		(start 72.041766 -55.094886)
		(end 71.470266 -55.094886)
		(width 0.1016)
		(layer "F.Cu")
		(net "M_G_DQ<19>")
	)
	(segment
		(start 57.74944 -15.423642)
		(end 57.74944 -16.687546)
		(width 0.1651)
		(layer "F.Cu")
		(net "M_G_DQ<19>")
	)
	(via
		(at 71.470266 -55.094886)
		(size 0.508)
		(drill 0.254)
		(layers "F.Cu" "B.Cu")
		(net "M_G_DQ<19>")
	)
	(via
		(at 58.599324 -22.279356)
		(size 0.508)
		(drill 0.254)
		(layers "F.Cu" "B.Cu")
		(net "M_G_DQ<19>")
	)
	(via
		(at 57.74944 -16.687546)
		(size 0.508)
		(drill 0.254)
		(layers "F.Cu" "B.Cu")
		(net "M_G_DQ<19>")
	)
	(segment
		(start 58.599324 -20.224496)
		(end 58.599324 -22.279356)
		(width 0.1651)
		(layer "B.Cu")
		(net "M_G_DQ<19>")
	)
	(segment
		(start 58.599578 -20.224242)
		(end 58.599324 -20.224496)
		(width 0.1651)
		(layer "B.Cu")
		(net "M_G_DQ<19>")
	)
	(segment
		(start 57.05983 -25.308306)
		(end 57.05983 -27.6352)
		(width 0.14224)
		(layer "In2.Cu")
		(net "M_G_DQ<19>")
	)
	(segment
		(start 59.078368 -37.734748)
		(end 58.923428 -37.889688)
		(width 0.14224)
		(layer "In2.Cu")
		(net "M_G_DQ<19>")
	)
	(segment
		(start 59.078368 -41.359328)
		(end 59.078368 -41.712388)
		(width 0.14224)
		(layer "In2.Cu")
		(net "M_G_DQ<19>")
	)
	(segment
		(start 58.923428 -37.889688)
		(end 58.63717 -37.889688)
		(width 0.14224)
		(layer "In2.Cu")
		(net "M_G_DQ<19>")
	)
	(segment
		(start 58.48223 -39.723568)
		(end 58.63717 -39.878508)
		(width 0.14224)
		(layer "In2.Cu")
		(net "M_G_DQ<19>")
	)
	(segment
		(start 68.501768 -52.729384)
		(end 68.547996 -52.818284)
		(width 0.0889)
		(layer "In2.Cu")
		(net "M_G_DQ<19>")
	)
	(segment
		(start 58.64479 -27.178)
		(end 58.21807 -27.178)
		(width 0.14224)
		(layer "In2.Cu")
		(net "M_G_DQ<19>")
	)
	(segment
		(start 59.107578 -18.1102)
		(end 59.107578 -18.4658)
		(width 0.14224)
		(layer "In2.Cu")
		(net "M_G_DQ<19>")
	)
	(segment
		(start 68.428362 -51.842416)
		(end 68.428362 -52.58816)
		(width 0.0889)
		(layer "In2.Cu")
		(net "M_G_DQ<19>")
	)
	(segment
		(start 58.115708 -22.762972)
		(end 58.115708 -23.169372)
		(width 0.14224)
		(layer "In2.Cu")
		(net "M_G_DQ<19>")
	)
	(segment
		(start 70.60057 -54.99989)
		(end 70.633336 -54.99989)
		(width 0.0889)
		(layer "In2.Cu")
		(net "M_G_DQ<19>")
	)
	(segment
		(start 58.07583 -25.362662)
		(end 57.818274 -25.105106)
		(width 0.14224)
		(layer "In2.Cu")
		(net "M_G_DQ<19>")
	)
	(segment
		(start 58.48223 -42.685462)
		(end 62.177168 -46.3804)
		(width 0.14224)
		(layer "In2.Cu")
		(net "M_G_DQ<19>")
	)
	(segment
		(start 62.966346 -46.3804)
		(end 68.227448 -51.641502)
		(width 0.14224)
		(layer "In2.Cu")
		(net "M_G_DQ<19>")
	)
	(segment
		(start 58.923428 -41.204388)
		(end 59.078368 -41.359328)
		(width 0.14224)
		(layer "In2.Cu")
		(net "M_G_DQ<19>")
	)
	(segment
		(start 58.48223 -42.022268)
		(end 58.48223 -42.685462)
		(width 0.14224)
		(layer "In2.Cu")
		(net "M_G_DQ<19>")
	)
	(segment
		(start 68.88353 -53.018436)
		(end 68.90766 -53.018436)
		(width 0.0889)
		(layer "In2.Cu")
		(net "M_G_DQ<19>")
	)
	(segment
		(start 58.48223 -39.370508)
		(end 58.48223 -39.723568)
		(width 0.14224)
		(layer "In2.Cu")
		(net "M_G_DQ<19>")
	)
	(segment
		(start 58.95213 -18.621248)
		(end 58.95213 -21.92655)
		(width 0.14224)
		(layer "In2.Cu")
		(net "M_G_DQ<19>")
	)
	(segment
		(start 58.314336 -23.368)
		(end 58.314336 -24.419306)
		(width 0.14224)
		(layer "In2.Cu")
		(net "M_G_DQ<19>")
	)
	(segment
		(start 58.63717 -41.204388)
		(end 58.923428 -41.204388)
		(width 0.14224)
		(layer "In2.Cu")
		(net "M_G_DQ<19>")
	)
	(segment
		(start 58.650378 -17.653)
		(end 59.107578 -18.1102)
		(width 0.14224)
		(layer "In2.Cu")
		(net "M_G_DQ<19>")
	)
	(segment
		(start 68.227448 -51.641502)
		(end 68.428362 -51.842416)
		(width 0.0889)
		(layer "In2.Cu")
		(net "M_G_DQ<19>")
	)
	(segment
		(start 69.73824 -53.513736)
		(end 69.771006 -53.513736)
		(width 0.0889)
		(layer "In2.Cu")
		(net "M_G_DQ<19>")
	)
	(segment
		(start 58.923428 -38.552628)
		(end 59.078368 -38.707568)
		(width 0.14224)
		(layer "In2.Cu")
		(net "M_G_DQ<19>")
	)
	(segment
		(start 71.087742 -55.23992)
		(end 71.17715 -55.26405)
		(width 0.0889)
		(layer "In2.Cu")
		(net "M_G_DQ<19>")
	)
	(segment
		(start 57.26303 -27.8384)
		(end 58.27903 -27.8384)
		(width 0.14224)
		(layer "In2.Cu")
		(net "M_G_DQ<19>")
	)
	(segment
		(start 58.923428 -41.867328)
		(end 58.63717 -41.867328)
		(width 0.14224)
		(layer "In2.Cu")
		(net "M_G_DQ<19>")
	)
	(segment
		(start 59.078368 -39.060628)
		(end 58.923428 -39.215568)
		(width 0.14224)
		(layer "In2.Cu")
		(net "M_G_DQ<19>")
	)
	(segment
		(start 58.066178 -17.004284)
		(end 58.066178 -17.3228)
		(width 0.14224)
		(layer "In2.Cu")
		(net "M_G_DQ<19>")
	)
	(segment
		(start 58.599324 -22.279356)
		(end 58.115708 -22.762972)
		(width 0.14224)
		(layer "In2.Cu")
		(net "M_G_DQ<19>")
	)
	(segment
		(start 58.115708 -23.169372)
		(end 58.314336 -23.368)
		(width 0.14224)
		(layer "In2.Cu")
		(net "M_G_DQ<19>")
	)
	(segment
		(start 58.63717 -40.541448)
		(end 58.48223 -40.696388)
		(width 0.14224)
		(layer "In2.Cu")
		(net "M_G_DQ<19>")
	)
	(segment
		(start 58.63717 -39.215568)
		(end 58.48223 -39.370508)
		(width 0.14224)
		(layer "In2.Cu")
		(net "M_G_DQ<19>")
	)
	(segment
		(start 58.48223 -28.0416)
		(end 58.48223 -37.071808)
		(width 0.14224)
		(layer "In2.Cu")
		(net "M_G_DQ<19>")
	)
	(segment
		(start 59.078368 -40.033448)
		(end 59.078368 -40.386508)
		(width 0.14224)
		(layer "In2.Cu")
		(net "M_G_DQ<19>")
	)
	(segment
		(start 58.48223 -38.044628)
		(end 58.48223 -38.397688)
		(width 0.14224)
		(layer "In2.Cu")
		(net "M_G_DQ<19>")
	)
	(segment
		(start 58.21807 -27.178)
		(end 58.07583 -27.03576)
		(width 0.14224)
		(layer "In2.Cu")
		(net "M_G_DQ<19>")
	)
	(segment
		(start 58.923428 -37.226748)
		(end 59.078368 -37.381688)
		(width 0.14224)
		(layer "In2.Cu")
		(net "M_G_DQ<19>")
	)
	(segment
		(start 62.177168 -46.3804)
		(end 62.966346 -46.3804)
		(width 0.14224)
		(layer "In2.Cu")
		(net "M_G_DQ<19>")
	)
	(segment
		(start 59.078368 -41.712388)
		(end 58.923428 -41.867328)
		(width 0.14224)
		(layer "In2.Cu")
		(net "M_G_DQ<19>")
	)
	(segment
		(start 57.26303 -25.105106)
		(end 57.05983 -25.308306)
		(width 0.14224)
		(layer "In2.Cu")
		(net "M_G_DQ<19>")
	)
	(segment
		(start 58.63717 -41.867328)
		(end 58.48223 -42.022268)
		(width 0.14224)
		(layer "In2.Cu")
		(net "M_G_DQ<19>")
	)
	(segment
		(start 57.818274 -25.105106)
		(end 57.26303 -25.105106)
		(width 0.14224)
		(layer "In2.Cu")
		(net "M_G_DQ<19>")
	)
	(segment
		(start 58.27903 -27.8384)
		(end 58.48223 -28.0416)
		(width 0.14224)
		(layer "In2.Cu")
		(net "M_G_DQ<19>")
	)
	(segment
		(start 71.17715 -55.26405)
		(end 71.470266 -55.094886)
		(width 0.0889)
		(layer "In2.Cu")
		(net "M_G_DQ<19>")
	)
	(segment
		(start 58.95213 -21.92655)
		(end 58.599324 -22.279356)
		(width 0.14224)
		(layer "In2.Cu")
		(net "M_G_DQ<19>")
	)
	(segment
		(start 58.923428 -39.215568)
		(end 58.63717 -39.215568)
		(width 0.14224)
		(layer "In2.Cu")
		(net "M_G_DQ<19>")
	)
	(segment
		(start 58.07583 -27.03576)
		(end 58.07583 -25.362662)
		(width 0.14224)
		(layer "In2.Cu")
		(net "M_G_DQ<19>")
	)
	(segment
		(start 58.63717 -38.552628)
		(end 58.923428 -38.552628)
		(width 0.14224)
		(layer "In2.Cu")
		(net "M_G_DQ<19>")
	)
	(segment
		(start 58.314336 -24.419306)
		(end 58.78703 -24.892)
		(width 0.14224)
		(layer "In2.Cu")
		(net "M_G_DQ<19>")
	)
	(segment
		(start 58.48223 -40.696388)
		(end 58.48223 -41.049448)
		(width 0.14224)
		(layer "In2.Cu")
		(net "M_G_DQ<19>")
	)
	(segment
		(start 57.74944 -16.687546)
		(end 58.066178 -17.004284)
		(width 0.14224)
		(layer "In2.Cu")
		(net "M_G_DQ<19>")
	)
	(segment
		(start 59.078368 -38.707568)
		(end 59.078368 -39.060628)
		(width 0.14224)
		(layer "In2.Cu")
		(net "M_G_DQ<19>")
	)
	(segment
		(start 59.078368 -40.386508)
		(end 58.923428 -40.541448)
		(width 0.14224)
		(layer "In2.Cu")
		(net "M_G_DQ<19>")
	)
	(segment
		(start 58.48223 -41.049448)
		(end 58.63717 -41.204388)
		(width 0.14224)
		(layer "In2.Cu")
		(net "M_G_DQ<19>")
	)
	(segment
		(start 59.107578 -18.4658)
		(end 58.95213 -18.621248)
		(width 0.14224)
		(layer "In2.Cu")
		(net "M_G_DQ<19>")
	)
	(segment
		(start 57.05983 -27.6352)
		(end 57.26303 -27.8384)
		(width 0.14224)
		(layer "In2.Cu")
		(net "M_G_DQ<19>")
	)
	(segment
		(start 68.428362 -52.58816)
		(end 68.501768 -52.729384)
		(width 0.0889)
		(layer "In2.Cu")
		(net "M_G_DQ<19>")
	)
	(segment
		(start 58.48223 -37.071808)
		(end 58.63717 -37.226748)
		(width 0.14224)
		(layer "In2.Cu")
		(net "M_G_DQ<19>")
	)
	(segment
		(start 58.78703 -27.03576)
		(end 58.64479 -27.178)
		(width 0.14224)
		(layer "In2.Cu")
		(net "M_G_DQ<19>")
	)
	(segment
		(start 58.396378 -17.653)
		(end 58.650378 -17.653)
		(width 0.14224)
		(layer "In2.Cu")
		(net "M_G_DQ<19>")
	)
	(segment
		(start 58.63717 -37.226748)
		(end 58.923428 -37.226748)
		(width 0.14224)
		(layer "In2.Cu")
		(net "M_G_DQ<19>")
	)
	(segment
		(start 59.078368 -37.381688)
		(end 59.078368 -37.734748)
		(width 0.14224)
		(layer "In2.Cu")
		(net "M_G_DQ<19>")
	)
	(segment
		(start 58.63717 -39.878508)
		(end 58.923428 -39.878508)
		(width 0.14224)
		(layer "In2.Cu")
		(net "M_G_DQ<19>")
	)
	(segment
		(start 58.066178 -17.3228)
		(end 58.396378 -17.653)
		(width 0.14224)
		(layer "In2.Cu")
		(net "M_G_DQ<19>")
	)
	(segment
		(start 58.923428 -40.541448)
		(end 58.63717 -40.541448)
		(width 0.14224)
		(layer "In2.Cu")
		(net "M_G_DQ<19>")
	)
	(segment
		(start 58.923428 -39.878508)
		(end 59.078368 -40.033448)
		(width 0.14224)
		(layer "In2.Cu")
		(net "M_G_DQ<19>")
	)
	(segment
		(start 58.48223 -38.397688)
		(end 58.63717 -38.552628)
		(width 0.14224)
		(layer "In2.Cu")
		(net "M_G_DQ<19>")
	)
	(segment
		(start 58.63717 -37.889688)
		(end 58.48223 -38.044628)
		(width 0.14224)
		(layer "In2.Cu")
		(net "M_G_DQ<19>")
	)
	(segment
		(start 58.78703 -24.892)
		(end 58.78703 -27.03576)
		(width 0.14224)
		(layer "In2.Cu")
		(net "M_G_DQ<19>")
	)
	(arc
		(start 68.547996 -52.818284)
		(mid 68.689679 -52.962088)
		(end 68.88353 -53.018436)
		(width 0.0889)
		(layer "In2.Cu")
		(net "M_G_DQ<19>")
	)
	(arc
		(start 69.771006 -53.513736)
		(mid 70.269257 -53.816576)
		(end 70.265036 -54.399688)
		(width 0.0889)
		(layer "In2.Cu")
		(net "M_G_DQ<19>")
	)
	(arc
		(start 68.90766 -53.018436)
		(mid 69.195805 -53.100755)
		(end 69.406516 -53.313838)
		(width 0.0889)
		(layer "In2.Cu")
		(net "M_G_DQ<19>")
	)
	(arc
		(start 69.406516 -53.313838)
		(mid 69.546595 -53.456574)
		(end 69.73824 -53.513736)
		(width 0.0889)
		(layer "In2.Cu")
		(net "M_G_DQ<19>")
	)
	(arc
		(start 70.633336 -54.99989)
		(mid 70.888001 -55.067919)
		(end 71.087742 -55.23992)
		(width 0.0889)
		(layer "In2.Cu")
		(net "M_G_DQ<19>")
	)
	(arc
		(start 70.265036 -54.399688)
		(mid 70.262288 -54.795155)
		(end 70.60057 -54.99989)
		(width 0.0889)
		(layer "In2.Cu")
		(net "M_G_DQ<19>")
	)
	(segment
		(start 58.599324 -19.026632)
		(end 58.730896 -18.89506)
		(width 0.1651)
		(layer "F.Cu")
		(net "M_G_DQ<18>")
	)
	(segment
		(start 71.183246 -55.59044)
		(end 70.611746 -55.59044)
		(width 0.1016)
		(layer "F.Cu")
		(net "M_G_DQ<18>")
	)
	(segment
		(start 58.730896 -18.67154)
		(end 58.599324 -18.539968)
		(width 0.1651)
		(layer "F.Cu")
		(net "M_G_DQ<18>")
	)
	(segment
		(start 58.730896 -18.89506)
		(end 58.730896 -18.67154)
		(width 0.1651)
		(layer "F.Cu")
		(net "M_G_DQ<18>")
	)
	(segment
		(start 58.599578 -20.023582)
		(end 58.599324 -20.023328)
		(width 0.1651)
		(layer "F.Cu")
		(net "M_G_DQ<18>")
	)
	(segment
		(start 58.599324 -20.023328)
		(end 58.599324 -19.026632)
		(width 0.1651)
		(layer "F.Cu")
		(net "M_G_DQ<18>")
	)
	(segment
		(start 58.599324 -18.539968)
		(end 58.599324 -18.2626)
		(width 0.1651)
		(layer "F.Cu")
		(net "M_G_DQ<18>")
	)
	(via
		(at 70.611746 -55.59044)
		(size 0.508)
		(drill 0.254)
		(layers "F.Cu" "B.Cu")
		(net "M_G_DQ<18>")
	)
	(via
		(at 57.74944 -23.560278)
		(size 0.508)
		(drill 0.254)
		(layers "F.Cu" "B.Cu")
		(net "M_G_DQ<18>")
	)
	(via
		(at 58.599324 -18.2626)
		(size 0.508)
		(drill 0.254)
		(layers "F.Cu" "B.Cu")
		(net "M_G_DQ<18>")
	)
	(segment
		(start 57.74944 -23.560278)
		(end 57.74944 -24.824182)
		(width 0.1651)
		(layer "B.Cu")
		(net "M_G_DQ<18>")
	)
	(segment
		(start 58.313574 -21.680932)
		(end 57.464706 -22.5298)
		(width 0.14224)
		(layer "In2.Cu")
		(net "M_G_DQ<18>")
	)
	(segment
		(start 57.74944 -23.82012)
		(end 56.409336 -25.160224)
		(width 0.14224)
		(layer "In2.Cu")
		(net "M_G_DQ<18>")
	)
	(segment
		(start 57.84723 -42.990262)
		(end 62.253368 -47.3964)
		(width 0.14224)
		(layer "In2.Cu")
		(net "M_G_DQ<18>")
	)
	(segment
		(start 68.264024 -52.729384)
		(end 68.349368 -52.861718)
		(width 0.0889)
		(layer "In2.Cu")
		(net "M_G_DQ<18>")
	)
	(segment
		(start 68.349368 -52.861718)
		(end 68.382896 -52.913788)
		(width 0.0889)
		(layer "In2.Cu")
		(net "M_G_DQ<18>")
	)
	(segment
		(start 57.33923 -28.3972)
		(end 57.64403 -28.3972)
		(width 0.14224)
		(layer "In2.Cu")
		(net "M_G_DQ<18>")
	)
	(segment
		(start 67.931792 -52.262024)
		(end 68.264024 -52.729384)
		(width 0.0889)
		(layer "In2.Cu")
		(net "M_G_DQ<18>")
	)
	(segment
		(start 57.64403 -28.3972)
		(end 57.84723 -28.6004)
		(width 0.14224)
		(layer "In2.Cu")
		(net "M_G_DQ<18>")
	)
	(segment
		(start 58.313574 -21.4122)
		(end 58.313574 -21.680932)
		(width 0.14224)
		(layer "In2.Cu")
		(net "M_G_DQ<18>")
	)
	(segment
		(start 68.881752 -53.20919)
		(end 68.909692 -53.20919)
		(width 0.0889)
		(layer "In2.Cu")
		(net "M_G_DQ<18>")
	)
	(segment
		(start 70.904862 -55.421276)
		(end 70.611746 -55.59044)
		(width 0.0889)
		(layer "In2.Cu")
		(net "M_G_DQ<18>")
	)
	(segment
		(start 57.856374 -19.310604)
		(end 57.856374 -19.659346)
		(width 0.14224)
		(layer "In2.Cu")
		(net "M_G_DQ<18>")
	)
	(segment
		(start 56.62803 -33.8328)
		(end 56.93283 -33.8328)
		(width 0.14224)
		(layer "In2.Cu")
		(net "M_G_DQ<18>")
	)
	(segment
		(start 57.856374 -20.55495)
		(end 57.856374 -20.955)
		(width 0.14224)
		(layer "In2.Cu")
		(net "M_G_DQ<18>")
	)
	(segment
		(start 70.593966 -55.19039)
		(end 70.626732 -55.19039)
		(width 0.0889)
		(layer "In2.Cu")
		(net "M_G_DQ<18>")
	)
	(segment
		(start 57.856374 -20.955)
		(end 58.313574 -21.4122)
		(width 0.14224)
		(layer "In2.Cu")
		(net "M_G_DQ<18>")
	)
	(segment
		(start 62.253368 -47.3964)
		(end 63.066168 -47.3964)
		(width 0.14224)
		(layer "In2.Cu")
		(net "M_G_DQ<18>")
	)
	(segment
		(start 58.161174 -20.25015)
		(end 57.856374 -20.55495)
		(width 0.14224)
		(layer "In2.Cu")
		(net "M_G_DQ<18>")
	)
	(segment
		(start 57.464706 -22.5298)
		(end 57.464706 -23.275544)
		(width 0.14224)
		(layer "In2.Cu")
		(net "M_G_DQ<18>")
	)
	(segment
		(start 58.201306 -18.965672)
		(end 57.856374 -19.310604)
		(width 0.14224)
		(layer "In2.Cu")
		(net "M_G_DQ<18>")
	)
	(segment
		(start 58.599324 -18.2626)
		(end 58.201306 -18.660618)
		(width 0.14224)
		(layer "In2.Cu")
		(net "M_G_DQ<18>")
	)
	(segment
		(start 56.409336 -33.614106)
		(end 56.62803 -33.8328)
		(width 0.14224)
		(layer "In2.Cu")
		(net "M_G_DQ<18>")
	)
	(segment
		(start 58.201306 -18.660618)
		(end 58.201306 -18.965672)
		(width 0.14224)
		(layer "In2.Cu")
		(net "M_G_DQ<18>")
	)
	(segment
		(start 57.13603 -28.6004)
		(end 57.33923 -28.3972)
		(width 0.14224)
		(layer "In2.Cu")
		(net "M_G_DQ<18>")
	)
	(segment
		(start 57.464706 -23.275544)
		(end 57.74944 -23.560278)
		(width 0.14224)
		(layer "In2.Cu")
		(net "M_G_DQ<18>")
	)
	(segment
		(start 70.925944 -55.342536)
		(end 70.904862 -55.421276)
		(width 0.0889)
		(layer "In2.Cu")
		(net "M_G_DQ<18>")
	)
	(segment
		(start 56.409336 -25.160224)
		(end 56.409336 -33.614106)
		(width 0.14224)
		(layer "In2.Cu")
		(net "M_G_DQ<18>")
	)
	(segment
		(start 57.84723 -28.6004)
		(end 57.84723 -42.990262)
		(width 0.14224)
		(layer "In2.Cu")
		(net "M_G_DQ<18>")
	)
	(segment
		(start 57.13603 -33.6296)
		(end 57.13603 -28.6004)
		(width 0.14224)
		(layer "In2.Cu")
		(net "M_G_DQ<18>")
	)
	(segment
		(start 56.93283 -33.8328)
		(end 57.13603 -33.6296)
		(width 0.14224)
		(layer "In2.Cu")
		(net "M_G_DQ<18>")
	)
	(segment
		(start 63.066168 -47.3964)
		(end 67.931792 -52.262024)
		(width 0.14224)
		(layer "In2.Cu")
		(net "M_G_DQ<18>")
	)
	(segment
		(start 57.74944 -23.560278)
		(end 57.74944 -23.82012)
		(width 0.14224)
		(layer "In2.Cu")
		(net "M_G_DQ<18>")
	)
	(segment
		(start 69.731636 -53.704236)
		(end 69.764402 -53.704236)
		(width 0.0889)
		(layer "In2.Cu")
		(net "M_G_DQ<18>")
	)
	(segment
		(start 57.856374 -19.659346)
		(end 58.161174 -19.964146)
		(width 0.14224)
		(layer "In2.Cu")
		(net "M_G_DQ<18>")
	)
	(segment
		(start 58.161174 -19.964146)
		(end 58.161174 -20.25015)
		(width 0.14224)
		(layer "In2.Cu")
		(net "M_G_DQ<18>")
	)
	(arc
		(start 68.909692 -53.20919)
		(mid 69.101334 -53.266356)
		(end 69.241416 -53.409088)
		(width 0.0889)
		(layer "In2.Cu")
		(net "M_G_DQ<18>")
	)
	(arc
		(start 69.241416 -53.409088)
		(mid 69.44842 -53.619952)
		(end 69.731636 -53.704236)
		(width 0.0889)
		(layer "In2.Cu")
		(net "M_G_DQ<18>")
	)
	(arc
		(start 69.764402 -53.704236)
		(mid 70.102571 -53.909034)
		(end 70.099936 -54.304438)
		(width 0.0889)
		(layer "In2.Cu")
		(net "M_G_DQ<18>")
	)
	(arc
		(start 70.626732 -55.19039)
		(mid 70.793026 -55.233624)
		(end 70.925944 -55.342536)
		(width 0.0889)
		(layer "In2.Cu")
		(net "M_G_DQ<18>")
	)
	(arc
		(start 68.382896 -52.913788)
		(mid 68.593609 -53.126867)
		(end 68.881752 -53.20919)
		(width 0.0889)
		(layer "In2.Cu")
		(net "M_G_DQ<18>")
	)
	(arc
		(start 70.099936 -54.304438)
		(mid 70.095607 -54.88761)
		(end 70.593966 -55.19039)
		(width 0.0889)
		(layer "In2.Cu")
		(net "M_G_DQ<18>")
	)
	(segment
		(start 73.758806 -57.076086)
		(end 73.187306 -57.076086)
		(width 0.1016)
		(layer "F.Cu")
		(net "M_G_DQ<17>")
	)
	(segment
		(start 51.79949 -15.423642)
		(end 51.79949 -16.687546)
		(width 0.1651)
		(layer "F.Cu")
		(net "M_G_DQ<17>")
	)
	(via
		(at 51.79949 -16.687546)
		(size 0.508)
		(drill 0.254)
		(layers "F.Cu" "B.Cu")
		(net "M_G_DQ<17>")
	)
	(via
		(at 73.187306 -57.076086)
		(size 0.508)
		(drill 0.254)
		(layers "F.Cu" "B.Cu")
		(net "M_G_DQ<17>")
	)
	(via
		(at 52.471574 -22.279356)
		(size 0.508)
		(drill 0.254)
		(layers "F.Cu" "B.Cu")
		(net "M_G_DQ<17>")
	)
	(segment
		(start 52.471574 -21.776182)
		(end 52.471574 -22.279356)
		(width 0.1651)
		(layer "B.Cu")
		(net "M_G_DQ<17>")
	)
	(segment
		(start 52.649374 -21.598382)
		(end 52.471574 -21.776182)
		(width 0.1651)
		(layer "B.Cu")
		(net "M_G_DQ<17>")
	)
	(segment
		(start 52.649374 -20.224242)
		(end 52.649374 -21.598382)
		(width 0.1651)
		(layer "B.Cu")
		(net "M_G_DQ<17>")
	)
	(segment
		(start 51.659536 -42.746168)
		(end 65.301368 -56.388)
		(width 0.14224)
		(layer "In2.Cu")
		(net "M_G_DQ<17>")
	)
	(segment
		(start 51.659536 -32.962342)
		(end 51.659536 -42.746168)
		(width 0.14224)
		(layer "In2.Cu")
		(net "M_G_DQ<17>")
	)
	(segment
		(start 52.845716 -18.571464)
		(end 52.845716 -21.905214)
		(width 0.14224)
		(layer "In2.Cu")
		(net "M_G_DQ<17>")
	)
	(segment
		(start 66.928492 -58.062114)
		(end 68.020692 -58.062114)
		(width 0.0889)
		(layer "In2.Cu")
		(net "M_G_DQ<17>")
	)
	(segment
		(start 51.79949 -17.226534)
		(end 52.276756 -17.7038)
		(width 0.14224)
		(layer "In2.Cu")
		(net "M_G_DQ<17>")
	)
	(segment
		(start 72.310752 -57.971436)
		(end 72.34682 -57.971436)
		(width 0.0889)
		(layer "In2.Cu")
		(net "M_G_DQ<17>")
	)
	(segment
		(start 65.555876 -57.226708)
		(end 66.093086 -57.226708)
		(width 0.14224)
		(layer "In2.Cu")
		(net "M_G_DQ<17>")
	)
	(segment
		(start 52.015136 -32.606742)
		(end 51.659536 -32.962342)
		(width 0.14224)
		(layer "In2.Cu")
		(net "M_G_DQ<17>")
	)
	(segment
		(start 51.989736 -23.111968)
		(end 52.289964 -23.412196)
		(width 0.14224)
		(layer "In2.Cu")
		(net "M_G_DQ<17>")
	)
	(segment
		(start 71.879714 -57.768744)
		(end 72.122284 -57.91454)
		(width 0.0889)
		(layer "In2.Cu")
		(net "M_G_DQ<17>")
	)
	(segment
		(start 53.00218 -18.073624)
		(end 53.00218 -18.415)
		(width 0.14224)
		(layer "In2.Cu")
		(net "M_G_DQ<17>")
	)
	(segment
		(start 66.093086 -57.226708)
		(end 66.928492 -58.062114)
		(width 0.0889)
		(layer "In2.Cu")
		(net "M_G_DQ<17>")
	)
	(segment
		(start 65.301368 -56.9722)
		(end 65.555876 -57.226708)
		(width 0.14224)
		(layer "In2.Cu")
		(net "M_G_DQ<17>")
	)
	(segment
		(start 71.45909 -57.66689)
		(end 71.48322 -57.66689)
		(width 0.0889)
		(layer "In2.Cu")
		(net "M_G_DQ<17>")
	)
	(segment
		(start 70.099936 -58.266838)
		(end 70.204584 -58.16219)
		(width 0.0889)
		(layer "In2.Cu")
		(net "M_G_DQ<17>")
	)
	(segment
		(start 68.425314 -58.466736)
		(end 69.77126 -58.466736)
		(width 0.0889)
		(layer "In2.Cu")
		(net "M_G_DQ<17>")
	)
	(segment
		(start 53.00218 -18.415)
		(end 52.845716 -18.571464)
		(width 0.14224)
		(layer "In2.Cu")
		(net "M_G_DQ<17>")
	)
	(segment
		(start 68.020692 -58.062114)
		(end 68.425314 -58.466736)
		(width 0.0889)
		(layer "In2.Cu")
		(net "M_G_DQ<17>")
	)
	(segment
		(start 65.301368 -56.388)
		(end 65.301368 -56.9722)
		(width 0.14224)
		(layer "In2.Cu")
		(net "M_G_DQ<17>")
	)
	(segment
		(start 52.632356 -17.7038)
		(end 53.00218 -18.073624)
		(width 0.14224)
		(layer "In2.Cu")
		(net "M_G_DQ<17>")
	)
	(segment
		(start 72.692006 -57.742836)
		(end 73.187306 -57.076086)
		(width 0.0889)
		(layer "In2.Cu")
		(net "M_G_DQ<17>")
	)
	(segment
		(start 52.289964 -23.818596)
		(end 52.015136 -24.093424)
		(width 0.14224)
		(layer "In2.Cu")
		(net "M_G_DQ<17>")
	)
	(segment
		(start 52.276756 -17.7038)
		(end 52.632356 -17.7038)
		(width 0.14224)
		(layer "In2.Cu")
		(net "M_G_DQ<17>")
	)
	(segment
		(start 72.675496 -57.771538)
		(end 72.692006 -57.742836)
		(width 0.0889)
		(layer "In2.Cu")
		(net "M_G_DQ<17>")
	)
	(segment
		(start 52.471574 -22.279356)
		(end 51.989736 -22.761194)
		(width 0.14224)
		(layer "In2.Cu")
		(net "M_G_DQ<17>")
	)
	(segment
		(start 70.204584 -58.16219)
		(end 70.633336 -58.16219)
		(width 0.0889)
		(layer "In2.Cu")
		(net "M_G_DQ<17>")
	)
	(segment
		(start 52.015136 -24.093424)
		(end 52.015136 -32.606742)
		(width 0.14224)
		(layer "In2.Cu")
		(net "M_G_DQ<17>")
	)
	(segment
		(start 52.289964 -23.412196)
		(end 52.289964 -23.818596)
		(width 0.14224)
		(layer "In2.Cu")
		(net "M_G_DQ<17>")
	)
	(segment
		(start 51.79949 -16.687546)
		(end 51.79949 -17.226534)
		(width 0.14224)
		(layer "In2.Cu")
		(net "M_G_DQ<17>")
	)
	(segment
		(start 51.989736 -22.761194)
		(end 51.989736 -23.111968)
		(width 0.14224)
		(layer "In2.Cu")
		(net "M_G_DQ<17>")
	)
	(segment
		(start 52.845716 -21.905214)
		(end 52.471574 -22.279356)
		(width 0.14224)
		(layer "In2.Cu")
		(net "M_G_DQ<17>")
	)
	(arc
		(start 72.34682 -57.971436)
		(mid 72.536749 -57.913566)
		(end 72.675496 -57.771538)
		(width 0.0889)
		(layer "In2.Cu")
		(net "M_G_DQ<17>")
	)
	(arc
		(start 72.122284 -57.91454)
		(mid 72.212968 -57.954737)
		(end 72.310752 -57.971436)
		(width 0.0889)
		(layer "In2.Cu")
		(net "M_G_DQ<17>")
	)
	(arc
		(start 71.48322 -57.66689)
		(mid 71.688895 -57.688896)
		(end 71.879714 -57.768744)
		(width 0.0889)
		(layer "In2.Cu")
		(net "M_G_DQ<17>")
	)
	(arc
		(start 69.77126 -58.466736)
		(mid 69.961189 -58.408866)
		(end 70.099936 -58.266838)
		(width 0.0889)
		(layer "In2.Cu")
		(net "M_G_DQ<17>")
	)
	(arc
		(start 71.123556 -57.867042)
		(mid 71.265239 -57.723238)
		(end 71.45909 -57.66689)
		(width 0.0889)
		(layer "In2.Cu")
		(net "M_G_DQ<17>")
	)
	(arc
		(start 70.633336 -58.16219)
		(mid 70.916553 -58.077909)
		(end 71.123556 -57.867042)
		(width 0.0889)
		(layer "In2.Cu")
		(net "M_G_DQ<17>")
	)
	(segment
		(start 72.041766 -58.06694)
		(end 71.470266 -58.06694)
		(width 0.1016)
		(layer "F.Cu")
		(net "M_G_DQ<16>")
	)
	(segment
		(start 52.649374 -20.023582)
		(end 52.568602 -19.177)
		(width 0.1651)
		(layer "F.Cu")
		(net "M_G_DQ<16>")
	)
	(segment
		(start 52.568602 -19.177)
		(end 52.471574 -18.161)
		(width 0.1651)
		(layer "F.Cu")
		(net "M_G_DQ<16>")
	)
	(via
		(at 71.470266 -58.06694)
		(size 0.508)
		(drill 0.254)
		(layers "F.Cu" "B.Cu")
		(net "M_G_DQ<16>")
	)
	(via
		(at 52.471574 -18.161)
		(size 0.508)
		(drill 0.254)
		(layers "F.Cu" "B.Cu")
		(net "M_G_DQ<16>")
	)
	(via
		(at 51.79949 -23.560278)
		(size 0.508)
		(drill 0.254)
		(layers "F.Cu" "B.Cu")
		(net "M_G_DQ<16>")
	)
	(segment
		(start 51.79949 -23.560278)
		(end 51.79949 -24.824182)
		(width 0.1651)
		(layer "B.Cu")
		(net "M_G_DQ<16>")
	)
	(segment
		(start 70.974966 -58.732928)
		(end 71.470266 -58.06694)
		(width 0.0889)
		(layer "In2.Cu")
		(net "M_G_DQ<16>")
	)
	(segment
		(start 52.251356 -18.965672)
		(end 51.836574 -19.380454)
		(width 0.14224)
		(layer "In2.Cu")
		(net "M_G_DQ<16>")
	)
	(segment
		(start 51.128168 -24.6634)
		(end 50.950368 -24.8412)
		(width 0.14224)
		(layer "In2.Cu")
		(net "M_G_DQ<16>")
	)
	(segment
		(start 51.341528 -26.16327)
		(end 51.092608 -26.16327)
		(width 0.14224)
		(layer "In2.Cu")
		(net "M_G_DQ<16>")
	)
	(segment
		(start 51.092608 -25.51303)
		(end 51.341528 -25.51303)
		(width 0.14224)
		(layer "In2.Cu")
		(net "M_G_DQ<16>")
	)
	(segment
		(start 51.341528 -27.46375)
		(end 51.092608 -27.46375)
		(width 0.14224)
		(layer "In2.Cu")
		(net "M_G_DQ<16>")
	)
	(segment
		(start 51.341528 -31.36519)
		(end 51.092608 -31.36519)
		(width 0.14224)
		(layer "In2.Cu")
		(net "M_G_DQ<16>")
	)
	(segment
		(start 50.950368 -30.57271)
		(end 51.092608 -30.71495)
		(width 0.14224)
		(layer "In2.Cu")
		(net "M_G_DQ<16>")
	)
	(segment
		(start 66.46799 -57.874408)
		(end 66.846196 -58.252614)
		(width 0.0889)
		(layer "In2.Cu")
		(net "M_G_DQ<16>")
	)
	(segment
		(start 67.94246 -58.252614)
		(end 68.347082 -58.657236)
		(width 0.0889)
		(layer "In2.Cu")
		(net "M_G_DQ<16>")
	)
	(segment
		(start 69.920358 -58.633614)
		(end 70.136766 -58.633614)
		(width 0.0889)
		(layer "In2.Cu")
		(net "M_G_DQ<16>")
	)
	(segment
		(start 50.950368 -28.90647)
		(end 50.950368 -29.27223)
		(width 0.14224)
		(layer "In2.Cu")
		(net "M_G_DQ<16>")
	)
	(segment
		(start 51.836574 -19.380454)
		(end 51.836574 -19.7104)
		(width 0.14224)
		(layer "In2.Cu")
		(net "M_G_DQ<16>")
	)
	(segment
		(start 50.950368 -25.37079)
		(end 51.092608 -25.51303)
		(width 0.14224)
		(layer "In2.Cu")
		(net "M_G_DQ<16>")
	)
	(segment
		(start 51.483768 -25.65527)
		(end 51.483768 -26.02103)
		(width 0.14224)
		(layer "In2.Cu")
		(net "M_G_DQ<16>")
	)
	(segment
		(start 51.483768 -27.32151)
		(end 51.341528 -27.46375)
		(width 0.14224)
		(layer "In2.Cu")
		(net "M_G_DQ<16>")
	)
	(segment
		(start 51.341528 -28.76423)
		(end 51.092608 -28.76423)
		(width 0.14224)
		(layer "In2.Cu")
		(net "M_G_DQ<16>")
	)
	(segment
		(start 51.128168 -24.2316)
		(end 51.128168 -24.6634)
		(width 0.14224)
		(layer "In2.Cu")
		(net "M_G_DQ<16>")
	)
	(segment
		(start 51.483768 -26.95575)
		(end 51.483768 -27.32151)
		(width 0.14224)
		(layer "In2.Cu")
		(net "M_G_DQ<16>")
	)
	(segment
		(start 51.483768 -28.25623)
		(end 51.483768 -28.62199)
		(width 0.14224)
		(layer "In2.Cu")
		(net "M_G_DQ<16>")
	)
	(segment
		(start 66.846196 -58.252614)
		(end 67.94246 -58.252614)
		(width 0.0889)
		(layer "In2.Cu")
		(net "M_G_DQ<16>")
	)
	(segment
		(start 52.251356 -18.381218)
		(end 52.251356 -18.965672)
		(width 0.14224)
		(layer "In2.Cu")
		(net "M_G_DQ<16>")
	)
	(segment
		(start 50.950368 -30.20695)
		(end 50.950368 -30.57271)
		(width 0.14224)
		(layer "In2.Cu")
		(net "M_G_DQ<16>")
	)
	(segment
		(start 51.341528 -26.81351)
		(end 51.483768 -26.95575)
		(width 0.14224)
		(layer "In2.Cu")
		(net "M_G_DQ<16>")
	)
	(segment
		(start 51.483768 -29.55671)
		(end 51.483768 -29.92247)
		(width 0.14224)
		(layer "In2.Cu")
		(net "M_G_DQ<16>")
	)
	(segment
		(start 52.179474 -20.0533)
		(end 52.179474 -20.2819)
		(width 0.14224)
		(layer "In2.Cu")
		(net "M_G_DQ<16>")
	)
	(segment
		(start 50.950368 -26.30551)
		(end 50.950368 -26.67127)
		(width 0.14224)
		(layer "In2.Cu")
		(net "M_G_DQ<16>")
	)
	(segment
		(start 52.471574 -18.161)
		(end 52.251356 -18.381218)
		(width 0.14224)
		(layer "In2.Cu")
		(net "M_G_DQ<16>")
	)
	(segment
		(start 70.958456 -58.761884)
		(end 70.974966 -58.732928)
		(width 0.0889)
		(layer "In2.Cu")
		(net "M_G_DQ<16>")
	)
	(segment
		(start 51.483768 -26.02103)
		(end 51.341528 -26.16327)
		(width 0.14224)
		(layer "In2.Cu")
		(net "M_G_DQ<16>")
	)
	(segment
		(start 51.341528 -25.51303)
		(end 51.483768 -25.65527)
		(width 0.14224)
		(layer "In2.Cu")
		(net "M_G_DQ<16>")
	)
	(segment
		(start 51.341528 -30.06471)
		(end 51.092608 -30.06471)
		(width 0.14224)
		(layer "In2.Cu")
		(net "M_G_DQ<16>")
	)
	(segment
		(start 51.092608 -26.16327)
		(end 50.950368 -26.30551)
		(width 0.14224)
		(layer "In2.Cu")
		(net "M_G_DQ<16>")
	)
	(segment
		(start 51.092608 -28.11399)
		(end 51.341528 -28.11399)
		(width 0.14224)
		(layer "In2.Cu")
		(net "M_G_DQ<16>")
	)
	(segment
		(start 52.251356 -21.293328)
		(end 52.251356 -21.7932)
		(width 0.14224)
		(layer "In2.Cu")
		(net "M_G_DQ<16>")
	)
	(segment
		(start 51.092608 -28.76423)
		(end 50.950368 -28.90647)
		(width 0.14224)
		(layer "In2.Cu")
		(net "M_G_DQ<16>")
	)
	(segment
		(start 70.136766 -58.633614)
		(end 70.265036 -58.761884)
		(width 0.0889)
		(layer "In2.Cu")
		(net "M_G_DQ<16>")
	)
	(segment
		(start 50.950368 -43.519344)
		(end 65.305432 -57.874408)
		(width 0.14224)
		(layer "In2.Cu")
		(net "M_G_DQ<16>")
	)
	(segment
		(start 50.950368 -27.60599)
		(end 50.950368 -27.97175)
		(width 0.14224)
		(layer "In2.Cu")
		(net "M_G_DQ<16>")
	)
	(segment
		(start 51.483768 -30.85719)
		(end 51.483768 -31.22295)
		(width 0.14224)
		(layer "In2.Cu")
		(net "M_G_DQ<16>")
	)
	(segment
		(start 50.950368 -26.67127)
		(end 51.092608 -26.81351)
		(width 0.14224)
		(layer "In2.Cu")
		(net "M_G_DQ<16>")
	)
	(segment
		(start 52.251356 -21.7932)
		(end 51.514756 -22.5298)
		(width 0.14224)
		(layer "In2.Cu")
		(net "M_G_DQ<16>")
	)
	(segment
		(start 51.861974 -20.903946)
		(end 52.251356 -21.293328)
		(width 0.14224)
		(layer "In2.Cu")
		(net "M_G_DQ<16>")
	)
	(segment
		(start 51.092608 -30.06471)
		(end 50.950368 -30.20695)
		(width 0.14224)
		(layer "In2.Cu")
		(net "M_G_DQ<16>")
	)
	(segment
		(start 51.483768 -29.92247)
		(end 51.341528 -30.06471)
		(width 0.14224)
		(layer "In2.Cu")
		(net "M_G_DQ<16>")
	)
	(segment
		(start 52.179474 -20.2819)
		(end 51.861974 -20.5994)
		(width 0.14224)
		(layer "In2.Cu")
		(net "M_G_DQ<16>")
	)
	(segment
		(start 65.305432 -57.874408)
		(end 66.25336 -57.874408)
		(width 0.14224)
		(layer "In2.Cu")
		(net "M_G_DQ<16>")
	)
	(segment
		(start 51.514756 -22.5298)
		(end 51.514756 -23.275544)
		(width 0.14224)
		(layer "In2.Cu")
		(net "M_G_DQ<16>")
	)
	(segment
		(start 69.608192 -58.657236)
		(end 69.608446 -58.65749)
		(width 0.0889)
		(layer "In2.Cu")
		(net "M_G_DQ<16>")
	)
	(segment
		(start 50.950368 -29.27223)
		(end 51.092608 -29.41447)
		(width 0.14224)
		(layer "In2.Cu")
		(net "M_G_DQ<16>")
	)
	(segment
		(start 68.347082 -58.657236)
		(end 69.608192 -58.657236)
		(width 0.0889)
		(layer "In2.Cu")
		(net "M_G_DQ<16>")
	)
	(segment
		(start 51.861974 -20.5994)
		(end 51.861974 -20.903946)
		(width 0.14224)
		(layer "In2.Cu")
		(net "M_G_DQ<16>")
	)
	(segment
		(start 51.092608 -27.46375)
		(end 50.950368 -27.60599)
		(width 0.14224)
		(layer "In2.Cu")
		(net "M_G_DQ<16>")
	)
	(segment
		(start 51.836574 -19.7104)
		(end 52.179474 -20.0533)
		(width 0.14224)
		(layer "In2.Cu")
		(net "M_G_DQ<16>")
	)
	(segment
		(start 69.608446 -58.65749)
		(end 69.771006 -58.65749)
		(width 0.0889)
		(layer "In2.Cu")
		(net "M_G_DQ<16>")
	)
	(segment
		(start 51.483768 -28.62199)
		(end 51.341528 -28.76423)
		(width 0.14224)
		(layer "In2.Cu")
		(net "M_G_DQ<16>")
	)
	(segment
		(start 51.092608 -29.41447)
		(end 51.341528 -29.41447)
		(width 0.14224)
		(layer "In2.Cu")
		(net "M_G_DQ<16>")
	)
	(segment
		(start 51.79949 -23.560278)
		(end 51.128168 -24.2316)
		(width 0.14224)
		(layer "In2.Cu")
		(net "M_G_DQ<16>")
	)
	(segment
		(start 51.092608 -30.71495)
		(end 51.341528 -30.71495)
		(width 0.14224)
		(layer "In2.Cu")
		(net "M_G_DQ<16>")
	)
	(segment
		(start 51.092608 -31.36519)
		(end 50.950368 -31.50743)
		(width 0.14224)
		(layer "In2.Cu")
		(net "M_G_DQ<16>")
	)
	(segment
		(start 50.950368 -24.8412)
		(end 50.950368 -25.37079)
		(width 0.14224)
		(layer "In2.Cu")
		(net "M_G_DQ<16>")
	)
	(segment
		(start 51.483768 -31.22295)
		(end 51.341528 -31.36519)
		(width 0.14224)
		(layer "In2.Cu")
		(net "M_G_DQ<16>")
	)
	(segment
		(start 51.341528 -30.71495)
		(end 51.483768 -30.85719)
		(width 0.14224)
		(layer "In2.Cu")
		(net "M_G_DQ<16>")
	)
	(segment
		(start 51.092608 -26.81351)
		(end 51.341528 -26.81351)
		(width 0.14224)
		(layer "In2.Cu")
		(net "M_G_DQ<16>")
	)
	(segment
		(start 50.950368 -31.50743)
		(end 50.950368 -43.519344)
		(width 0.14224)
		(layer "In2.Cu")
		(net "M_G_DQ<16>")
	)
	(segment
		(start 51.341528 -28.11399)
		(end 51.483768 -28.25623)
		(width 0.14224)
		(layer "In2.Cu")
		(net "M_G_DQ<16>")
	)
	(segment
		(start 51.341528 -29.41447)
		(end 51.483768 -29.55671)
		(width 0.14224)
		(layer "In2.Cu")
		(net "M_G_DQ<16>")
	)
	(segment
		(start 51.514756 -23.275544)
		(end 51.79949 -23.560278)
		(width 0.14224)
		(layer "In2.Cu")
		(net "M_G_DQ<16>")
	)
	(segment
		(start 50.950368 -27.97175)
		(end 51.092608 -28.11399)
		(width 0.14224)
		(layer "In2.Cu")
		(net "M_G_DQ<16>")
	)
	(segment
		(start 66.25336 -57.874408)
		(end 66.46799 -57.874408)
		(width 0.0889)
		(layer "In2.Cu")
		(net "M_G_DQ<16>")
	)
	(arc
		(start 70.265036 -58.761884)
		(mid 70.611746 -58.962195)
		(end 70.958456 -58.761884)
		(width 0.0889)
		(layer "In2.Cu")
		(net "M_G_DQ<16>")
	)
	(arc
		(start 69.771006 -58.65749)
		(mid 69.846451 -58.650359)
		(end 69.920358 -58.633614)
		(width 0.0889)
		(layer "In2.Cu")
		(net "M_G_DQ<16>")
	)
	(segment
		(start 56.7436 -45.343318)
		(end 65.883282 -54.483)
		(width 0.1651)
		(layer "F.Cu")
		(net "M_G_DQ<15>")
	)
	(segment
		(start 54.312312 -32.925512)
		(end 54.312312 -34.2646)
		(width 0.1651)
		(layer "F.Cu")
		(net "M_G_DQ<15>")
	)
	(segment
		(start 55.112412 -33.5534)
		(end 55.8292 -33.5534)
		(width 0.1651)
		(layer "F.Cu")
		(net "M_G_DQ<15>")
	)
	(segment
		(start 54.439312 -35.9156)
		(end 54.858412 -35.9156)
		(width 0.1651)
		(layer "F.Cu")
		(net "M_G_DQ<15>")
	)
	(segment
		(start 52.578 -29.2354)
		(end 52.578 -31.1912)
		(width 0.1651)
		(layer "F.Cu")
		(net "M_G_DQ<15>")
	)
	(segment
		(start 55.9562 -33.6804)
		(end 55.9562 -36.735512)
		(width 0.1651)
		(layer "F.Cu")
		(net "M_G_DQ<15>")
	)
	(segment
		(start 50.8127 -25.3619)
		(end 51.689 -26.2382)
		(width 0.1651)
		(layer "F.Cu")
		(net "M_G_DQ<15>")
	)
	(segment
		(start 47.216568 -23.3426)
		(end 47.216568 -24.178768)
		(width 0.1651)
		(layer "F.Cu")
		(net "M_G_DQ<15>")
	)
	(segment
		(start 46.699424 -15.423642)
		(end 46.699424 -16.687546)
		(width 0.1651)
		(layer "F.Cu")
		(net "M_G_DQ<15>")
	)
	(segment
		(start 47.216568 -24.178768)
		(end 48.3997 -25.3619)
		(width 0.1651)
		(layer "F.Cu")
		(net "M_G_DQ<15>")
	)
	(segment
		(start 47.032164 -22.7965)
		(end 47.032164 -23.158196)
		(width 0.1651)
		(layer "F.Cu")
		(net "M_G_DQ<15>")
	)
	(segment
		(start 54.312312 -35.7886)
		(end 54.439312 -35.9156)
		(width 0.1651)
		(layer "F.Cu")
		(net "M_G_DQ<15>")
	)
	(segment
		(start 68.444618 -55.59044)
		(end 69.466206 -55.59044)
		(width 0.0889)
		(layer "F.Cu")
		(net "M_G_DQ<15>")
	)
	(segment
		(start 55.9562 -36.735512)
		(end 56.7436 -37.522912)
		(width 0.1651)
		(layer "F.Cu")
		(net "M_G_DQ<15>")
	)
	(segment
		(start 56.7436 -37.522912)
		(end 56.7436 -45.343318)
		(width 0.1651)
		(layer "F.Cu")
		(net "M_G_DQ<15>")
	)
	(segment
		(start 51.689 -28.3464)
		(end 52.578 -29.2354)
		(width 0.1651)
		(layer "F.Cu")
		(net "M_G_DQ<15>")
	)
	(segment
		(start 68.062602 -55.208424)
		(end 68.444618 -55.59044)
		(width 0.0889)
		(layer "F.Cu")
		(net "M_G_DQ<15>")
	)
	(segment
		(start 47.549308 -22.279356)
		(end 47.032164 -22.7965)
		(width 0.1651)
		(layer "F.Cu")
		(net "M_G_DQ<15>")
	)
	(segment
		(start 67.481704 -55.208424)
		(end 68.062602 -55.208424)
		(width 0.0889)
		(layer "F.Cu")
		(net "M_G_DQ<15>")
	)
	(segment
		(start 48.3997 -25.3619)
		(end 50.8127 -25.3619)
		(width 0.1651)
		(layer "F.Cu")
		(net "M_G_DQ<15>")
	)
	(segment
		(start 47.032164 -23.158196)
		(end 47.216568 -23.3426)
		(width 0.1651)
		(layer "F.Cu")
		(net "M_G_DQ<15>")
	)
	(segment
		(start 51.689 -26.2382)
		(end 51.689 -28.3464)
		(width 0.1651)
		(layer "F.Cu")
		(net "M_G_DQ<15>")
	)
	(segment
		(start 55.8292 -33.5534)
		(end 55.9562 -33.6804)
		(width 0.1651)
		(layer "F.Cu")
		(net "M_G_DQ<15>")
	)
	(segment
		(start 54.985412 -35.7886)
		(end 54.985412 -33.6804)
		(width 0.1651)
		(layer "F.Cu")
		(net "M_G_DQ<15>")
	)
	(segment
		(start 54.858412 -35.9156)
		(end 54.985412 -35.7886)
		(width 0.1651)
		(layer "F.Cu")
		(net "M_G_DQ<15>")
	)
	(segment
		(start 66.75628 -54.483)
		(end 67.481704 -55.208424)
		(width 0.0889)
		(layer "F.Cu")
		(net "M_G_DQ<15>")
	)
	(segment
		(start 52.578 -31.1912)
		(end 54.312312 -32.925512)
		(width 0.1651)
		(layer "F.Cu")
		(net "M_G_DQ<15>")
	)
	(segment
		(start 54.312312 -34.2646)
		(end 54.312312 -35.7886)
		(width 0.1651)
		(layer "F.Cu")
		(net "M_G_DQ<15>")
	)
	(segment
		(start 65.883282 -54.483)
		(end 66.75628 -54.483)
		(width 0.0889)
		(layer "F.Cu")
		(net "M_G_DQ<15>")
	)
	(segment
		(start 54.985412 -33.6804)
		(end 55.112412 -33.5534)
		(width 0.1651)
		(layer "F.Cu")
		(net "M_G_DQ<15>")
	)
	(via
		(at 54.312312 -34.2646)
		(size 0.508)
		(drill 0.254)
		(layers "F.Cu" "B.Cu")
		(net "M_G_DQ<15>")
	)
	(via
		(at 46.699424 -16.687546)
		(size 0.508)
		(drill 0.254)
		(layers "F.Cu" "B.Cu")
		(net "M_G_DQ<15>")
	)
	(via
		(at 47.549308 -22.279356)
		(size 0.508)
		(drill 0.254)
		(layers "F.Cu" "B.Cu")
		(net "M_G_DQ<15>")
	)
	(segment
		(start 47.549562 -20.224242)
		(end 47.549308 -20.224496)
		(width 0.1651)
		(layer "B.Cu")
		(net "M_G_DQ<15>")
	)
	(segment
		(start 47.549308 -20.224496)
		(end 47.549308 -22.279356)
		(width 0.1651)
		(layer "B.Cu")
		(net "M_G_DQ<15>")
	)
	(segment
		(start 47.902114 -18.621248)
		(end 48.057562 -18.4658)
		(width 0.14224)
		(layer "In2.Cu")
		(net "M_G_DQ<15>")
	)
	(segment
		(start 47.016162 -17.004284)
		(end 46.699424 -16.687546)
		(width 0.14224)
		(layer "In2.Cu")
		(net "M_G_DQ<15>")
	)
	(segment
		(start 48.057562 -18.1102)
		(end 47.600362 -17.653)
		(width 0.14224)
		(layer "In2.Cu")
		(net "M_G_DQ<15>")
	)
	(segment
		(start 47.600362 -17.653)
		(end 47.346362 -17.653)
		(width 0.14224)
		(layer "In2.Cu")
		(net "M_G_DQ<15>")
	)
	(segment
		(start 48.057562 -18.4658)
		(end 48.057562 -18.1102)
		(width 0.14224)
		(layer "In2.Cu")
		(net "M_G_DQ<15>")
	)
	(segment
		(start 47.902114 -21.92655)
		(end 47.902114 -18.621248)
		(width 0.14224)
		(layer "In2.Cu")
		(net "M_G_DQ<15>")
	)
	(segment
		(start 47.346362 -17.653)
		(end 47.016162 -17.3228)
		(width 0.14224)
		(layer "In2.Cu")
		(net "M_G_DQ<15>")
	)
	(segment
		(start 47.016162 -17.3228)
		(end 47.016162 -17.004284)
		(width 0.14224)
		(layer "In2.Cu")
		(net "M_G_DQ<15>")
	)
	(segment
		(start 47.549308 -22.279356)
		(end 47.902114 -21.92655)
		(width 0.14224)
		(layer "In2.Cu")
		(net "M_G_DQ<15>")
	)
	(segment
		(start 53.567584 -33.171638)
		(end 53.567584 -35.6362)
		(width 0.1651)
		(layer "F.Cu")
		(net "M_G_DQ<14>")
	)
	(segment
		(start 54.4322 -40.1574)
		(end 55.8546 -40.1574)
		(width 0.1651)
		(layer "F.Cu")
		(net "M_G_DQ<14>")
	)
	(segment
		(start 47.681642 -18.69948)
		(end 47.549562 -18.5674)
		(width 0.1651)
		(layer "F.Cu")
		(net "M_G_DQ<14>")
	)
	(segment
		(start 50.13325 -27.770582)
		(end 50.13325 -27.59075)
		(width 0.1651)
		(layer "F.Cu")
		(net "M_G_DQ<14>")
	)
	(segment
		(start 50.13325 -27.59075)
		(end 50.925984 -26.798016)
		(width 0.1651)
		(layer "F.Cu")
		(net "M_G_DQ<14>")
	)
	(segment
		(start 50.602134 -28.239466)
		(end 51.816 -29.453332)
		(width 0.1651)
		(layer "F.Cu")
		(net "M_G_DQ<14>")
	)
	(segment
		(start 46.454568 -23.805134)
		(end 46.699424 -23.560278)
		(width 0.1651)
		(layer "F.Cu")
		(net "M_G_DQ<14>")
	)
	(segment
		(start 48.975518 -26.61285)
		(end 46.454568 -24.0919)
		(width 0.1651)
		(layer "F.Cu")
		(net "M_G_DQ<14>")
	)
	(segment
		(start 54.0639 -36.7665)
		(end 54.991 -36.7665)
		(width 0.1651)
		(layer "F.Cu")
		(net "M_G_DQ<14>")
	)
	(segment
		(start 54.991 -36.7665)
		(end 56.103774 -37.879274)
		(width 0.1651)
		(layer "F.Cu")
		(net "M_G_DQ<14>")
	)
	(segment
		(start 54.3052 -40.0304)
		(end 54.4322 -40.1574)
		(width 0.1651)
		(layer "F.Cu")
		(net "M_G_DQ<14>")
	)
	(segment
		(start 56.103774 -39.273226)
		(end 55.9308 -39.4462)
		(width 0.1651)
		(layer "F.Cu")
		(net "M_G_DQ<14>")
	)
	(segment
		(start 55.1434 -38.0746)
		(end 54.4322 -38.0746)
		(width 0.1651)
		(layer "F.Cu")
		(net "M_G_DQ<14>")
	)
	(segment
		(start 67.483482 -55.59044)
		(end 67.749166 -55.59044)
		(width 0.0889)
		(layer "F.Cu")
		(net "M_G_DQ<14>")
	)
	(segment
		(start 46.454568 -24.0919)
		(end 46.454568 -23.805134)
		(width 0.1651)
		(layer "F.Cu")
		(net "M_G_DQ<14>")
	)
	(segment
		(start 51.816 -29.453332)
		(end 51.816 -31.420054)
		(width 0.1651)
		(layer "F.Cu")
		(net "M_G_DQ<14>")
	)
	(segment
		(start 47.549562 -18.262854)
		(end 47.549308 -18.2626)
		(width 0.1651)
		(layer "F.Cu")
		(net "M_G_DQ<14>")
	)
	(segment
		(start 55.9308 -39.4462)
		(end 55.585614 -39.4462)
		(width 0.1651)
		(layer "F.Cu")
		(net "M_G_DQ<14>")
	)
	(segment
		(start 47.549562 -18.5674)
		(end 47.549562 -18.262854)
		(width 0.1651)
		(layer "F.Cu")
		(net "M_G_DQ<14>")
	)
	(segment
		(start 56.103774 -37.879274)
		(end 56.103774 -39.273226)
		(width 0.1651)
		(layer "F.Cu")
		(net "M_G_DQ<14>")
	)
	(segment
		(start 54.3052 -38.2016)
		(end 54.3052 -40.0304)
		(width 0.1651)
		(layer "F.Cu")
		(net "M_G_DQ<14>")
	)
	(segment
		(start 50.925984 -26.618184)
		(end 50.15484 -25.84704)
		(width 0.1651)
		(layer "F.Cu")
		(net "M_G_DQ<14>")
	)
	(segment
		(start 54.4322 -38.0746)
		(end 54.3052 -38.2016)
		(width 0.1651)
		(layer "F.Cu")
		(net "M_G_DQ<14>")
	)
	(segment
		(start 50.925984 -26.798016)
		(end 50.925984 -26.618184)
		(width 0.1651)
		(layer "F.Cu")
		(net "M_G_DQ<14>")
	)
	(segment
		(start 55.8546 -40.1574)
		(end 55.9816 -40.2844)
		(width 0.1651)
		(layer "F.Cu")
		(net "M_G_DQ<14>")
	)
	(segment
		(start 50.602134 -28.239466)
		(end 50.13325 -27.770582)
		(width 0.1651)
		(layer "F.Cu")
		(net "M_G_DQ<14>")
	)
	(segment
		(start 55.224426 -43.835574)
		(end 55.224426 -44.778676)
		(width 0.1651)
		(layer "F.Cu")
		(net "M_G_DQ<14>")
	)
	(segment
		(start 49.15535 -26.61285)
		(end 48.975518 -26.61285)
		(width 0.1651)
		(layer "F.Cu")
		(net "M_G_DQ<14>")
	)
	(segment
		(start 55.9816 -40.2844)
		(end 55.9816 -43.0784)
		(width 0.1651)
		(layer "F.Cu")
		(net "M_G_DQ<14>")
	)
	(segment
		(start 55.458614 -38.389814)
		(end 55.1434 -38.0746)
		(width 0.1651)
		(layer "F.Cu")
		(net "M_G_DQ<14>")
	)
	(segment
		(start 55.224426 -44.778676)
		(end 65.56375 -55.118)
		(width 0.1651)
		(layer "F.Cu")
		(net "M_G_DQ<14>")
	)
	(segment
		(start 55.585614 -39.4462)
		(end 55.458614 -39.3192)
		(width 0.1651)
		(layer "F.Cu")
		(net "M_G_DQ<14>")
	)
	(segment
		(start 67.011042 -55.118)
		(end 67.483482 -55.59044)
		(width 0.0889)
		(layer "F.Cu")
		(net "M_G_DQ<14>")
	)
	(segment
		(start 50.15484 -25.84704)
		(end 49.92116 -25.84704)
		(width 0.1651)
		(layer "F.Cu")
		(net "M_G_DQ<14>")
	)
	(segment
		(start 53.567584 -36.270184)
		(end 54.0639 -36.7665)
		(width 0.1651)
		(layer "F.Cu")
		(net "M_G_DQ<14>")
	)
	(segment
		(start 55.458614 -39.3192)
		(end 55.458614 -38.389814)
		(width 0.1651)
		(layer "F.Cu")
		(net "M_G_DQ<14>")
	)
	(segment
		(start 53.567584 -35.6362)
		(end 53.567584 -36.270184)
		(width 0.1651)
		(layer "F.Cu")
		(net "M_G_DQ<14>")
	)
	(segment
		(start 49.92116 -25.84704)
		(end 49.15535 -26.61285)
		(width 0.1651)
		(layer "F.Cu")
		(net "M_G_DQ<14>")
	)
	(segment
		(start 51.816 -31.420054)
		(end 53.567584 -33.171638)
		(width 0.1651)
		(layer "F.Cu")
		(net "M_G_DQ<14>")
	)
	(segment
		(start 47.549562 -19.05)
		(end 47.681642 -18.91792)
		(width 0.1651)
		(layer "F.Cu")
		(net "M_G_DQ<14>")
	)
	(segment
		(start 65.56375 -55.118)
		(end 67.011042 -55.118)
		(width 0.0889)
		(layer "F.Cu")
		(net "M_G_DQ<14>")
	)
	(segment
		(start 47.681642 -18.91792)
		(end 47.681642 -18.69948)
		(width 0.1651)
		(layer "F.Cu")
		(net "M_G_DQ<14>")
	)
	(segment
		(start 47.549562 -20.023582)
		(end 47.549562 -19.05)
		(width 0.1651)
		(layer "F.Cu")
		(net "M_G_DQ<14>")
	)
	(segment
		(start 55.9816 -43.0784)
		(end 55.224426 -43.835574)
		(width 0.1651)
		(layer "F.Cu")
		(net "M_G_DQ<14>")
	)
	(via
		(at 53.567584 -35.6362)
		(size 0.508)
		(drill 0.254)
		(layers "F.Cu" "B.Cu")
		(net "M_G_DQ<14>")
	)
	(via
		(at 50.602134 -28.239466)
		(size 0.508)
		(drill 0.254)
		(layers "F.Cu" "B.Cu")
		(net "M_G_DQ<14>")
	)
	(via
		(at 46.699424 -23.560278)
		(size 0.508)
		(drill 0.254)
		(layers "F.Cu" "B.Cu")
		(net "M_G_DQ<14>")
	)
	(via
		(at 47.549308 -18.2626)
		(size 0.508)
		(drill 0.254)
		(layers "F.Cu" "B.Cu")
		(net "M_G_DQ<14>")
	)
	(segment
		(start 46.699424 -23.560278)
		(end 46.699424 -24.824182)
		(width 0.1651)
		(layer "B.Cu")
		(net "M_G_DQ<14>")
	)
	(segment
		(start 46.81093 -20.980146)
		(end 47.23638 -21.405596)
		(width 0.14224)
		(layer "In2.Cu")
		(net "M_G_DQ<14>")
	)
	(segment
		(start 47.549308 -18.2626)
		(end 47.174912 -18.636996)
		(width 0.14224)
		(layer "In2.Cu")
		(net "M_G_DQ<14>")
	)
	(segment
		(start 46.463712 -23.324566)
		(end 46.699424 -23.560278)
		(width 0.14224)
		(layer "In2.Cu")
		(net "M_G_DQ<14>")
	)
	(segment
		(start 46.81093 -20.694904)
		(end 46.81093 -20.980146)
		(width 0.14224)
		(layer "In2.Cu")
		(net "M_G_DQ<14>")
	)
	(segment
		(start 47.174912 -18.914872)
		(end 46.81093 -19.278854)
		(width 0.14224)
		(layer "In2.Cu")
		(net "M_G_DQ<14>")
	)
	(segment
		(start 46.81093 -19.278854)
		(end 46.81093 -19.589496)
		(width 0.14224)
		(layer "In2.Cu")
		(net "M_G_DQ<14>")
	)
	(segment
		(start 47.19193 -19.970496)
		(end 47.19193 -20.313904)
		(width 0.14224)
		(layer "In2.Cu")
		(net "M_G_DQ<14>")
	)
	(segment
		(start 47.23638 -21.405596)
		(end 47.23638 -21.757386)
		(width 0.14224)
		(layer "In2.Cu")
		(net "M_G_DQ<14>")
	)
	(segment
		(start 47.174912 -18.636996)
		(end 47.174912 -18.914872)
		(width 0.14224)
		(layer "In2.Cu")
		(net "M_G_DQ<14>")
	)
	(segment
		(start 46.463712 -22.530054)
		(end 46.463712 -23.324566)
		(width 0.14224)
		(layer "In2.Cu")
		(net "M_G_DQ<14>")
	)
	(segment
		(start 47.19193 -20.313904)
		(end 46.81093 -20.694904)
		(width 0.14224)
		(layer "In2.Cu")
		(net "M_G_DQ<14>")
	)
	(segment
		(start 46.81093 -19.589496)
		(end 47.19193 -19.970496)
		(width 0.14224)
		(layer "In2.Cu")
		(net "M_G_DQ<14>")
	)
	(segment
		(start 47.23638 -21.757386)
		(end 46.463712 -22.530054)
		(width 0.14224)
		(layer "In2.Cu")
		(net "M_G_DQ<14>")
	)
	(segment
		(start 40.749474 -15.423642)
		(end 40.749474 -16.687546)
		(width 0.1651)
		(layer "F.Cu")
		(net "M_G_DQ<13>")
	)
	(segment
		(start 41.374568 -26.159968)
		(end 45.851826 -30.637226)
		(width 0.1651)
		(layer "F.Cu")
		(net "M_G_DQ<13>")
	)
	(segment
		(start 67.195954 -59.090814)
		(end 67.982592 -59.090814)
		(width 0.0889)
		(layer "F.Cu")
		(net "M_G_DQ<13>")
	)
	(segment
		(start 41.374568 -23.8252)
		(end 41.374568 -26.159968)
		(width 0.1651)
		(layer "F.Cu")
		(net "M_G_DQ<13>")
	)
	(segment
		(start 45.851826 -32.135826)
		(end 48.657256 -34.941256)
		(width 0.1651)
		(layer "F.Cu")
		(net "M_G_DQ<13>")
	)
	(segment
		(start 67.982592 -59.090814)
		(end 68.444618 -59.55284)
		(width 0.0889)
		(layer "F.Cu")
		(net "M_G_DQ<13>")
	)
	(segment
		(start 41.054528 -23.04288)
		(end 41.374568 -23.8252)
		(width 0.1651)
		(layer "F.Cu")
		(net "M_G_DQ<13>")
	)
	(segment
		(start 45.851826 -30.637226)
		(end 45.851826 -32.135826)
		(width 0.1651)
		(layer "F.Cu")
		(net "M_G_DQ<13>")
	)
	(segment
		(start 48.657256 -34.941256)
		(end 48.657256 -37.674804)
		(width 0.1651)
		(layer "F.Cu")
		(net "M_G_DQ<13>")
	)
	(segment
		(start 41.054528 -22.747986)
		(end 41.054528 -23.04288)
		(width 0.1651)
		(layer "F.Cu")
		(net "M_G_DQ<13>")
	)
	(segment
		(start 41.523158 -22.279356)
		(end 41.054528 -22.747986)
		(width 0.1651)
		(layer "F.Cu")
		(net "M_G_DQ<13>")
	)
	(segment
		(start 67.065144 -59.221624)
		(end 67.195954 -59.090814)
		(width 0.0889)
		(layer "F.Cu")
		(net "M_G_DQ<13>")
	)
	(segment
		(start 64.015874 -59.221624)
		(end 67.065144 -59.221624)
		(width 0.1651)
		(layer "F.Cu")
		(net "M_G_DQ<13>")
	)
	(segment
		(start 48.657256 -37.674804)
		(end 50.463196 -39.480744)
		(width 0.1651)
		(layer "F.Cu")
		(net "M_G_DQ<13>")
	)
	(segment
		(start 50.463196 -39.480744)
		(end 50.463196 -45.668946)
		(width 0.1651)
		(layer "F.Cu")
		(net "M_G_DQ<13>")
	)
	(segment
		(start 68.444618 -59.55284)
		(end 69.466206 -59.55284)
		(width 0.0889)
		(layer "F.Cu")
		(net "M_G_DQ<13>")
	)
	(segment
		(start 50.463196 -45.668946)
		(end 64.015874 -59.221624)
		(width 0.1651)
		(layer "F.Cu")
		(net "M_G_DQ<13>")
	)
	(via
		(at 41.523158 -22.279356)
		(size 0.508)
		(drill 0.254)
		(layers "F.Cu" "B.Cu")
		(net "M_G_DQ<13>")
	)
	(via
		(at 40.749474 -16.687546)
		(size 0.508)
		(drill 0.254)
		(layers "F.Cu" "B.Cu")
		(net "M_G_DQ<13>")
	)
	(segment
		(start 41.599358 -20.224242)
		(end 41.599358 -22.203156)
		(width 0.1651)
		(layer "B.Cu")
		(net "M_G_DQ<13>")
	)
	(segment
		(start 41.599358 -22.203156)
		(end 41.523158 -22.279356)
		(width 0.1651)
		(layer "B.Cu")
		(net "M_G_DQ<13>")
	)
	(segment
		(start 42.031412 -18.4658)
		(end 42.031412 -18.053304)
		(width 0.14224)
		(layer "In2.Cu")
		(net "M_G_DQ<13>")
	)
	(segment
		(start 41.834562 -18.66265)
		(end 42.031412 -18.4658)
		(width 0.14224)
		(layer "In2.Cu")
		(net "M_G_DQ<13>")
	)
	(segment
		(start 41.834562 -21.967952)
		(end 41.834562 -18.66265)
		(width 0.14224)
		(layer "In2.Cu")
		(net "M_G_DQ<13>")
	)
	(segment
		(start 41.523158 -22.279356)
		(end 41.834562 -21.967952)
		(width 0.14224)
		(layer "In2.Cu")
		(net "M_G_DQ<13>")
	)
	(segment
		(start 42.031412 -18.053304)
		(end 41.631108 -17.653)
		(width 0.14224)
		(layer "In2.Cu")
		(net "M_G_DQ<13>")
	)
	(segment
		(start 41.320212 -17.653)
		(end 40.749474 -17.082262)
		(width 0.14224)
		(layer "In2.Cu")
		(net "M_G_DQ<13>")
	)
	(segment
		(start 40.749474 -17.082262)
		(end 40.749474 -16.687546)
		(width 0.14224)
		(layer "In2.Cu")
		(net "M_G_DQ<13>")
	)
	(segment
		(start 41.631108 -17.653)
		(end 41.320212 -17.653)
		(width 0.14224)
		(layer "In2.Cu")
		(net "M_G_DQ<13>")
	)
	(segment
		(start 45.212 -32.401256)
		(end 48.01743 -35.206686)
		(width 0.1651)
		(layer "F.Cu")
		(net "M_G_DQ<12>")
	)
	(segment
		(start 51.039268 -48.44796)
		(end 51.27244 -48.44796)
		(width 0.1651)
		(layer "F.Cu")
		(net "M_G_DQ<12>")
	)
	(segment
		(start 49.82337 -39.746174)
		(end 49.82337 -45.983652)
		(width 0.1651)
		(layer "F.Cu")
		(net "M_G_DQ<12>")
	)
	(segment
		(start 67.432682 -59.869324)
		(end 67.749166 -59.55284)
		(width 0.0889)
		(layer "F.Cu")
		(net "M_G_DQ<12>")
	)
	(segment
		(start 45.212 -30.9118)
		(end 45.212 -32.401256)
		(width 0.1651)
		(layer "F.Cu")
		(net "M_G_DQ<12>")
	)
	(segment
		(start 51.663346 -48.0568)
		(end 51.896518 -48.0568)
		(width 0.1651)
		(layer "F.Cu")
		(net "M_G_DQ<12>")
	)
	(segment
		(start 50.796444 -47.971964)
		(end 50.796444 -48.205136)
		(width 0.1651)
		(layer "F.Cu")
		(net "M_G_DQ<12>")
	)
	(segment
		(start 50.796444 -48.205136)
		(end 51.039268 -48.44796)
		(width 0.1651)
		(layer "F.Cu")
		(net "M_G_DQ<12>")
	)
	(segment
		(start 48.01743 -35.206686)
		(end 48.01743 -37.940234)
		(width 0.1651)
		(layer "F.Cu")
		(net "M_G_DQ<12>")
	)
	(segment
		(start 51.18735 -47.347632)
		(end 51.18735 -47.580804)
		(width 0.1651)
		(layer "F.Cu")
		(net "M_G_DQ<12>")
	)
	(segment
		(start 40.688768 -23.620984)
		(end 40.688768 -26.388568)
		(width 0.1651)
		(layer "F.Cu")
		(net "M_G_DQ<12>")
	)
	(segment
		(start 41.599358 -18.692368)
		(end 41.501314 -18.161)
		(width 0.1651)
		(layer "F.Cu")
		(net "M_G_DQ<12>")
	)
	(segment
		(start 63.709042 -59.869324)
		(end 67.079368 -59.869324)
		(width 0.1651)
		(layer "F.Cu")
		(net "M_G_DQ<12>")
	)
	(segment
		(start 41.599358 -20.023582)
		(end 41.599358 -18.692368)
		(width 0.1651)
		(layer "F.Cu")
		(net "M_G_DQ<12>")
	)
	(segment
		(start 51.18735 -47.580804)
		(end 50.796444 -47.971964)
		(width 0.1651)
		(layer "F.Cu")
		(net "M_G_DQ<12>")
	)
	(segment
		(start 51.27244 -48.44796)
		(end 51.663346 -48.0568)
		(width 0.1651)
		(layer "F.Cu")
		(net "M_G_DQ<12>")
	)
	(segment
		(start 51.896518 -48.0568)
		(end 63.709042 -59.869324)
		(width 0.1651)
		(layer "F.Cu")
		(net "M_G_DQ<12>")
	)
	(segment
		(start 40.749474 -23.560278)
		(end 40.688768 -23.620984)
		(width 0.1651)
		(layer "F.Cu")
		(net "M_G_DQ<12>")
	)
	(segment
		(start 67.079368 -59.869324)
		(end 67.432682 -59.869324)
		(width 0.0889)
		(layer "F.Cu")
		(net "M_G_DQ<12>")
	)
	(segment
		(start 48.01743 -37.940234)
		(end 49.82337 -39.746174)
		(width 0.1651)
		(layer "F.Cu")
		(net "M_G_DQ<12>")
	)
	(segment
		(start 49.82337 -45.983652)
		(end 51.18735 -47.347632)
		(width 0.1651)
		(layer "F.Cu")
		(net "M_G_DQ<12>")
	)
	(segment
		(start 40.688768 -26.388568)
		(end 45.212 -30.9118)
		(width 0.1651)
		(layer "F.Cu")
		(net "M_G_DQ<12>")
	)
	(via
		(at 40.749474 -23.560278)
		(size 0.508)
		(drill 0.254)
		(layers "F.Cu" "B.Cu")
		(net "M_G_DQ<12>")
	)
	(via
		(at 41.501314 -18.161)
		(size 0.508)
		(drill 0.254)
		(layers "F.Cu" "B.Cu")
		(net "M_G_DQ<12>")
	)
	(segment
		(start 40.749474 -23.560278)
		(end 40.749474 -24.824182)
		(width 0.1651)
		(layer "B.Cu")
		(net "M_G_DQ<12>")
	)
	(segment
		(start 41.224962 -18.437352)
		(end 41.501314 -18.161)
		(width 0.14224)
		(layer "In2.Cu")
		(net "M_G_DQ<12>")
	)
	(segment
		(start 40.513762 -23.324566)
		(end 40.513762 -22.530054)
		(width 0.14224)
		(layer "In2.Cu")
		(net "M_G_DQ<12>")
	)
	(segment
		(start 41.24198 -19.9644)
		(end 40.86098 -19.5834)
		(width 0.14224)
		(layer "In2.Cu")
		(net "M_G_DQ<12>")
	)
	(segment
		(start 40.749474 -23.560278)
		(end 40.513762 -23.324566)
		(width 0.14224)
		(layer "In2.Cu")
		(net "M_G_DQ<12>")
	)
	(segment
		(start 40.86098 -19.5834)
		(end 40.86098 -19.278854)
		(width 0.14224)
		(layer "In2.Cu")
		(net "M_G_DQ<12>")
	)
	(segment
		(start 41.224962 -21.344128)
		(end 40.87368 -20.992846)
		(width 0.14224)
		(layer "In2.Cu")
		(net "M_G_DQ<12>")
	)
	(segment
		(start 41.224962 -18.914872)
		(end 41.224962 -18.437352)
		(width 0.14224)
		(layer "In2.Cu")
		(net "M_G_DQ<12>")
	)
	(segment
		(start 40.87368 -20.6375)
		(end 41.24198 -20.2692)
		(width 0.14224)
		(layer "In2.Cu")
		(net "M_G_DQ<12>")
	)
	(segment
		(start 40.87368 -20.992846)
		(end 40.87368 -20.6375)
		(width 0.14224)
		(layer "In2.Cu")
		(net "M_G_DQ<12>")
	)
	(segment
		(start 40.513762 -22.530054)
		(end 41.224962 -21.818854)
		(width 0.14224)
		(layer "In2.Cu")
		(net "M_G_DQ<12>")
	)
	(segment
		(start 40.86098 -19.278854)
		(end 41.224962 -18.914872)
		(width 0.14224)
		(layer "In2.Cu")
		(net "M_G_DQ<12>")
	)
	(segment
		(start 41.24198 -20.2692)
		(end 41.24198 -19.9644)
		(width 0.14224)
		(layer "In2.Cu")
		(net "M_G_DQ<12>")
	)
	(segment
		(start 41.224962 -21.818854)
		(end 41.224962 -21.344128)
		(width 0.14224)
		(layer "In2.Cu")
		(net "M_G_DQ<12>")
	)
	(segment
		(start 55.172356 -31.506668)
		(end 54.938676 -31.506668)
		(width 0.1651)
		(layer "F.Cu")
		(net "M_G_DQ<11>")
	)
	(segment
		(start 56.598566 -35.8902)
		(end 56.598566 -36.472876)
		(width 0.1651)
		(layer "F.Cu")
		(net "M_G_DQ<11>")
	)
	(segment
		(start 66.294 -53.939186)
		(end 66.482214 -53.939186)
		(width 0.0889)
		(layer "F.Cu")
		(net "M_G_DQ<11>")
	)
	(segment
		(start 55.414672 -31.264352)
		(end 55.172356 -31.506668)
		(width 0.1651)
		(layer "F.Cu")
		(net "M_G_DQ<11>")
	)
	(segment
		(start 53.381148 -30.667452)
		(end 53.381148 -30.901132)
		(width 0.1651)
		(layer "F.Cu")
		(net "M_G_DQ<11>")
	)
	(segment
		(start 56.598566 -32.214566)
		(end 56.598566 -35.8902)
		(width 0.1651)
		(layer "F.Cu")
		(net "M_G_DQ<11>")
	)
	(segment
		(start 54.938676 -31.506668)
		(end 53.857144 -30.425136)
		(width 0.1651)
		(layer "F.Cu")
		(net "M_G_DQ<11>")
	)
	(segment
		(start 53.381148 -30.901132)
		(end 54.938676 -32.45866)
		(width 0.1651)
		(layer "F.Cu")
		(net "M_G_DQ<11>")
	)
	(segment
		(start 48.616362 -22.912324)
		(end 48.370236 -22.912324)
		(width 0.1651)
		(layer "F.Cu")
		(net "M_G_DQ<11>")
	)
	(segment
		(start 55.414672 -31.030672)
		(end 55.414672 -31.264352)
		(width 0.1651)
		(layer "F.Cu")
		(net "M_G_DQ<11>")
	)
	(segment
		(start 49.24933 -22.279356)
		(end 48.616362 -22.912324)
		(width 0.1651)
		(layer "F.Cu")
		(net "M_G_DQ<11>")
	)
	(segment
		(start 56.124348 -31.740348)
		(end 56.598566 -32.214566)
		(width 0.1651)
		(layer "F.Cu")
		(net "M_G_DQ<11>")
	)
	(segment
		(start 55.172356 -32.45866)
		(end 55.890668 -31.740348)
		(width 0.1651)
		(layer "F.Cu")
		(net "M_G_DQ<11>")
	)
	(segment
		(start 66.482214 -53.939186)
		(end 67.522852 -54.979824)
		(width 0.0889)
		(layer "F.Cu")
		(net "M_G_DQ<11>")
	)
	(segment
		(start 56.598566 -36.472876)
		(end 57.531 -37.40531)
		(width 0.1651)
		(layer "F.Cu")
		(net "M_G_DQ<11>")
	)
	(segment
		(start 48.370236 -22.912324)
		(end 47.925736 -23.356824)
		(width 0.1651)
		(layer "F.Cu")
		(net "M_G_DQ<11>")
	)
	(segment
		(start 54.938676 -32.45866)
		(end 55.172356 -32.45866)
		(width 0.1651)
		(layer "F.Cu")
		(net "M_G_DQ<11>")
	)
	(segment
		(start 52.5018 -26.0858)
		(end 52.5018 -28.1178)
		(width 0.1651)
		(layer "F.Cu")
		(net "M_G_DQ<11>")
	)
	(segment
		(start 53.857144 -30.425136)
		(end 53.623464 -30.425136)
		(width 0.1651)
		(layer "F.Cu")
		(net "M_G_DQ<11>")
	)
	(segment
		(start 52.5018 -28.1178)
		(end 55.414672 -31.030672)
		(width 0.1651)
		(layer "F.Cu")
		(net "M_G_DQ<11>")
	)
	(segment
		(start 67.522852 -54.979824)
		(end 68.09359 -54.979824)
		(width 0.0889)
		(layer "F.Cu")
		(net "M_G_DQ<11>")
	)
	(segment
		(start 68.473574 -54.59984)
		(end 69.466206 -54.59984)
		(width 0.0889)
		(layer "F.Cu")
		(net "M_G_DQ<11>")
	)
	(segment
		(start 57.531 -37.40531)
		(end 57.531 -45.176186)
		(width 0.1651)
		(layer "F.Cu")
		(net "M_G_DQ<11>")
	)
	(segment
		(start 55.890668 -31.740348)
		(end 56.124348 -31.740348)
		(width 0.1651)
		(layer "F.Cu")
		(net "M_G_DQ<11>")
	)
	(segment
		(start 50.9778 -24.5618)
		(end 52.5018 -26.0858)
		(width 0.1651)
		(layer "F.Cu")
		(net "M_G_DQ<11>")
	)
	(segment
		(start 48.399446 -15.423642)
		(end 48.399446 -16.687546)
		(width 0.1651)
		(layer "F.Cu")
		(net "M_G_DQ<11>")
	)
	(segment
		(start 53.623464 -30.425136)
		(end 53.381148 -30.667452)
		(width 0.1651)
		(layer "F.Cu")
		(net "M_G_DQ<11>")
	)
	(segment
		(start 57.531 -45.176186)
		(end 66.294 -53.939186)
		(width 0.1651)
		(layer "F.Cu")
		(net "M_G_DQ<11>")
	)
	(segment
		(start 48.4378 -24.5618)
		(end 50.9778 -24.5618)
		(width 0.1651)
		(layer "F.Cu")
		(net "M_G_DQ<11>")
	)
	(segment
		(start 47.925736 -23.356824)
		(end 47.925736 -24.049736)
		(width 0.1651)
		(layer "F.Cu")
		(net "M_G_DQ<11>")
	)
	(segment
		(start 47.925736 -24.049736)
		(end 48.4378 -24.5618)
		(width 0.1651)
		(layer "F.Cu")
		(net "M_G_DQ<11>")
	)
	(segment
		(start 68.09359 -54.979824)
		(end 68.473574 -54.59984)
		(width 0.0889)
		(layer "F.Cu")
		(net "M_G_DQ<11>")
	)
	(via
		(at 56.598566 -35.8902)
		(size 0.508)
		(drill 0.254)
		(layers "F.Cu" "B.Cu")
		(net "M_G_DQ<11>")
	)
	(via
		(at 49.24933 -22.279356)
		(size 0.508)
		(drill 0.254)
		(layers "F.Cu" "B.Cu")
		(net "M_G_DQ<11>")
	)
	(via
		(at 48.399446 -16.687546)
		(size 0.508)
		(drill 0.254)
		(layers "F.Cu" "B.Cu")
		(net "M_G_DQ<11>")
	)
	(segment
		(start 49.24933 -20.224496)
		(end 49.24933 -22.279356)
		(width 0.1651)
		(layer "B.Cu")
		(net "M_G_DQ<11>")
	)
	(segment
		(start 49.249584 -20.224242)
		(end 49.24933 -20.224496)
		(width 0.1651)
		(layer "B.Cu")
		(net "M_G_DQ<11>")
	)
	(segment
		(start 48.716184 -17.3228)
		(end 48.716184 -17.004284)
		(width 0.14224)
		(layer "In2.Cu")
		(net "M_G_DQ<11>")
	)
	(segment
		(start 48.716184 -17.004284)
		(end 48.399446 -16.687546)
		(width 0.14224)
		(layer "In2.Cu")
		(net "M_G_DQ<11>")
	)
	(segment
		(start 49.602136 -18.621248)
		(end 49.757584 -18.4658)
		(width 0.14224)
		(layer "In2.Cu")
		(net "M_G_DQ<11>")
	)
	(segment
		(start 49.24933 -22.279356)
		(end 49.602136 -21.92655)
		(width 0.14224)
		(layer "In2.Cu")
		(net "M_G_DQ<11>")
	)
	(segment
		(start 49.757584 -18.4658)
		(end 49.757584 -18.1102)
		(width 0.14224)
		(layer "In2.Cu")
		(net "M_G_DQ<11>")
	)
	(segment
		(start 49.602136 -21.92655)
		(end 49.602136 -18.621248)
		(width 0.14224)
		(layer "In2.Cu")
		(net "M_G_DQ<11>")
	)
	(segment
		(start 49.046384 -17.653)
		(end 48.716184 -17.3228)
		(width 0.14224)
		(layer "In2.Cu")
		(net "M_G_DQ<11>")
	)
	(segment
		(start 49.757584 -18.1102)
		(end 49.300384 -17.653)
		(width 0.14224)
		(layer "In2.Cu")
		(net "M_G_DQ<11>")
	)
	(segment
		(start 49.300384 -17.653)
		(end 49.046384 -17.653)
		(width 0.14224)
		(layer "In2.Cu")
		(net "M_G_DQ<11>")
	)
	(segment
		(start 53.176424 -27.702256)
		(end 57.332372 -31.858204)
		(width 0.1651)
		(layer "F.Cu")
		(net "M_G_DQ<10>")
	)
	(segment
		(start 49.380902 -18.67154)
		(end 49.24933 -18.539968)
		(width 0.1651)
		(layer "F.Cu")
		(net "M_G_DQ<10>")
	)
	(segment
		(start 57.8104 -36.779708)
		(end 58.293 -37.262308)
		(width 0.1651)
		(layer "F.Cu")
		(net "M_G_DQ<10>")
	)
	(segment
		(start 48.916336 -24.077168)
		(end 51.45532 -24.077168)
		(width 0.1651)
		(layer "F.Cu")
		(net "M_G_DQ<10>")
	)
	(segment
		(start 57.8104 -34.1122)
		(end 57.8104 -36.779708)
		(width 0.1651)
		(layer "F.Cu")
		(net "M_G_DQ<10>")
	)
	(segment
		(start 58.293 -44.9834)
		(end 66.787776 -53.478176)
		(width 0.1651)
		(layer "F.Cu")
		(net "M_G_DQ<10>")
	)
	(segment
		(start 51.45532 -24.077168)
		(end 57.48782 -30.109668)
		(width 0.1651)
		(layer "F.Cu")
		(net "M_G_DQ<10>")
	)
	(segment
		(start 53.41874 -27.22626)
		(end 53.176424 -27.468576)
		(width 0.1651)
		(layer "F.Cu")
		(net "M_G_DQ<10>")
	)
	(segment
		(start 48.399446 -23.560278)
		(end 48.916336 -24.077168)
		(width 0.1651)
		(layer "F.Cu")
		(net "M_G_DQ<10>")
	)
	(segment
		(start 57.245504 -30.585664)
		(end 57.011824 -30.585664)
		(width 0.1651)
		(layer "F.Cu")
		(net "M_G_DQ<10>")
	)
	(segment
		(start 53.176424 -27.468576)
		(end 53.176424 -27.702256)
		(width 0.1651)
		(layer "F.Cu")
		(net "M_G_DQ<10>")
	)
	(segment
		(start 66.787776 -53.478176)
		(end 67.34302 -54.03342)
		(width 0.0889)
		(layer "F.Cu")
		(net "M_G_DQ<10>")
	)
	(segment
		(start 57.332372 -33.0708)
		(end 57.332372 -33.634172)
		(width 0.1651)
		(layer "F.Cu")
		(net "M_G_DQ<10>")
	)
	(segment
		(start 57.332372 -33.634172)
		(end 57.8104 -34.1122)
		(width 0.1651)
		(layer "F.Cu")
		(net "M_G_DQ<10>")
	)
	(segment
		(start 49.24933 -18.539968)
		(end 49.24933 -18.2626)
		(width 0.1651)
		(layer "F.Cu")
		(net "M_G_DQ<10>")
	)
	(segment
		(start 49.249584 -20.023582)
		(end 49.24933 -20.023328)
		(width 0.1651)
		(layer "F.Cu")
		(net "M_G_DQ<10>")
	)
	(segment
		(start 49.24933 -19.026632)
		(end 49.380902 -18.89506)
		(width 0.1651)
		(layer "F.Cu")
		(net "M_G_DQ<10>")
	)
	(segment
		(start 67.34302 -54.03342)
		(end 67.34302 -54.193694)
		(width 0.0889)
		(layer "F.Cu")
		(net "M_G_DQ<10>")
	)
	(segment
		(start 53.65242 -27.22626)
		(end 53.41874 -27.22626)
		(width 0.1651)
		(layer "F.Cu")
		(net "M_G_DQ<10>")
	)
	(segment
		(start 67.34302 -54.193694)
		(end 67.749166 -54.59984)
		(width 0.0889)
		(layer "F.Cu")
		(net "M_G_DQ<10>")
	)
	(segment
		(start 57.332372 -31.858204)
		(end 57.332372 -33.0708)
		(width 0.1651)
		(layer "F.Cu")
		(net "M_G_DQ<10>")
	)
	(segment
		(start 57.48782 -30.109668)
		(end 57.48782 -30.343348)
		(width 0.1651)
		(layer "F.Cu")
		(net "M_G_DQ<10>")
	)
	(segment
		(start 49.380902 -18.89506)
		(end 49.380902 -18.67154)
		(width 0.1651)
		(layer "F.Cu")
		(net "M_G_DQ<10>")
	)
	(segment
		(start 57.011824 -30.585664)
		(end 53.65242 -27.22626)
		(width 0.1651)
		(layer "F.Cu")
		(net "M_G_DQ<10>")
	)
	(segment
		(start 57.48782 -30.343348)
		(end 57.245504 -30.585664)
		(width 0.1651)
		(layer "F.Cu")
		(net "M_G_DQ<10>")
	)
	(segment
		(start 58.293 -37.262308)
		(end 58.293 -44.9834)
		(width 0.1651)
		(layer "F.Cu")
		(net "M_G_DQ<10>")
	)
	(segment
		(start 49.24933 -20.023328)
		(end 49.24933 -19.026632)
		(width 0.1651)
		(layer "F.Cu")
		(net "M_G_DQ<10>")
	)
	(via
		(at 48.399446 -23.560278)
		(size 0.508)
		(drill 0.254)
		(layers "F.Cu" "B.Cu")
		(net "M_G_DQ<10>")
	)
	(via
		(at 49.24933 -18.2626)
		(size 0.508)
		(drill 0.254)
		(layers "F.Cu" "B.Cu")
		(net "M_G_DQ<10>")
	)
	(via
		(at 57.332372 -33.0708)
		(size 0.508)
		(drill 0.254)
		(layers "F.Cu" "B.Cu")
		(net "M_G_DQ<10>")
	)
	(segment
		(start 48.399446 -23.560278)
		(end 48.399446 -24.824182)
		(width 0.1651)
		(layer "B.Cu")
		(net "M_G_DQ<10>")
	)
	(segment
		(start 48.114712 -23.275544)
		(end 48.114712 -22.5298)
		(width 0.14224)
		(layer "In2.Cu")
		(net "M_G_DQ<10>")
	)
	(segment
		(start 48.50638 -19.310604)
		(end 48.851312 -18.965672)
		(width 0.14224)
		(layer "In2.Cu")
		(net "M_G_DQ<10>")
	)
	(segment
		(start 48.81118 -19.964146)
		(end 48.50638 -19.659346)
		(width 0.14224)
		(layer "In2.Cu")
		(net "M_G_DQ<10>")
	)
	(segment
		(start 48.96358 -21.4122)
		(end 48.50638 -20.955)
		(width 0.14224)
		(layer "In2.Cu")
		(net "M_G_DQ<10>")
	)
	(segment
		(start 48.399446 -23.560278)
		(end 48.114712 -23.275544)
		(width 0.14224)
		(layer "In2.Cu")
		(net "M_G_DQ<10>")
	)
	(segment
		(start 48.851312 -18.965672)
		(end 48.851312 -18.660618)
		(width 0.14224)
		(layer "In2.Cu")
		(net "M_G_DQ<10>")
	)
	(segment
		(start 48.81118 -20.25015)
		(end 48.81118 -19.964146)
		(width 0.14224)
		(layer "In2.Cu")
		(net "M_G_DQ<10>")
	)
	(segment
		(start 48.50638 -20.55495)
		(end 48.81118 -20.25015)
		(width 0.14224)
		(layer "In2.Cu")
		(net "M_G_DQ<10>")
	)
	(segment
		(start 48.114712 -22.5298)
		(end 48.96358 -21.680932)
		(width 0.14224)
		(layer "In2.Cu")
		(net "M_G_DQ<10>")
	)
	(segment
		(start 48.50638 -19.659346)
		(end 48.50638 -19.310604)
		(width 0.14224)
		(layer "In2.Cu")
		(net "M_G_DQ<10>")
	)
	(segment
		(start 48.96358 -21.680932)
		(end 48.96358 -21.4122)
		(width 0.14224)
		(layer "In2.Cu")
		(net "M_G_DQ<10>")
	)
	(segment
		(start 48.50638 -20.955)
		(end 48.50638 -20.55495)
		(width 0.14224)
		(layer "In2.Cu")
		(net "M_G_DQ<10>")
	)
	(segment
		(start 48.851312 -18.660618)
		(end 49.24933 -18.2626)
		(width 0.14224)
		(layer "In2.Cu")
		(net "M_G_DQ<10>")
	)
	(segment
		(start 33.949386 -20.023582)
		(end 33.868614 -19.177)
		(width 0.1651)
		(layer "F.Cu")
		(net "M_G_DQ<0>")
	)
	(segment
		(start 67.749166 -65.49644)
		(end 67.101466 -65.49644)
		(width 0.1016)
		(layer "F.Cu")
		(net "M_G_DQ<0>")
	)
	(segment
		(start 33.868614 -19.177)
		(end 33.771586 -18.161)
		(width 0.1651)
		(layer "F.Cu")
		(net "M_G_DQ<0>")
	)
	(via
		(at 33.771586 -18.161)
		(size 0.508)
		(drill 0.254)
		(layers "F.Cu" "B.Cu")
		(net "M_G_DQ<0>")
	)
	(via
		(at 33.099502 -23.560278)
		(size 0.508)
		(drill 0.254)
		(layers "F.Cu" "B.Cu")
		(net "M_G_DQ<0>")
	)
	(via
		(at 67.101466 -65.49644)
		(size 0.508)
		(drill 0.254)
		(layers "F.Cu" "B.Cu")
		(net "M_G_DQ<0>")
	)
	(segment
		(start 33.099502 -23.560278)
		(end 33.099502 -24.824182)
		(width 0.1651)
		(layer "B.Cu")
		(net "M_G_DQ<0>")
	)
	(segment
		(start 33.378648 -27.7368)
		(end 33.498536 -27.856688)
		(width 0.14224)
		(layer "In2.Cu")
		(net "M_G_DQ<0>")
	)
	(segment
		(start 33.356296 -28.769056)
		(end 33.007808 -28.769056)
		(width 0.14224)
		(layer "In2.Cu")
		(net "M_G_DQ<0>")
	)
	(segment
		(start 32.814768 -22.5298)
		(end 33.551368 -21.7932)
		(width 0.14224)
		(layer "In2.Cu")
		(net "M_G_DQ<0>")
	)
	(segment
		(start 33.007808 -30.719776)
		(end 33.356296 -30.719776)
		(width 0.14224)
		(layer "In2.Cu")
		(net "M_G_DQ<0>")
	)
	(segment
		(start 33.498536 -28.626816)
		(end 33.356296 -28.769056)
		(width 0.14224)
		(layer "In2.Cu")
		(net "M_G_DQ<0>")
	)
	(segment
		(start 33.479486 -20.2819)
		(end 33.479486 -20.0533)
		(width 0.14224)
		(layer "In2.Cu")
		(net "M_G_DQ<0>")
	)
	(segment
		(start 32.865568 -31.512256)
		(end 32.865568 -31.878016)
		(width 0.14224)
		(layer "In2.Cu")
		(net "M_G_DQ<0>")
	)
	(segment
		(start 33.007808 -31.370016)
		(end 32.865568 -31.512256)
		(width 0.14224)
		(layer "In2.Cu")
		(net "M_G_DQ<0>")
	)
	(segment
		(start 32.49168 -27.50439)
		(end 32.72409 -27.7368)
		(width 0.14224)
		(layer "In2.Cu")
		(net "M_G_DQ<0>")
	)
	(segment
		(start 33.099502 -23.560278)
		(end 32.814768 -23.275544)
		(width 0.14224)
		(layer "In2.Cu")
		(net "M_G_DQ<0>")
	)
	(segment
		(start 66.873374 -65.49644)
		(end 67.101466 -65.49644)
		(width 0.0889)
		(layer "In2.Cu")
		(net "M_G_DQ<0>")
	)
	(segment
		(start 33.161986 -20.5994)
		(end 33.479486 -20.2819)
		(width 0.14224)
		(layer "In2.Cu")
		(net "M_G_DQ<0>")
	)
	(segment
		(start 33.498536 -29.561536)
		(end 33.498536 -29.927296)
		(width 0.14224)
		(layer "In2.Cu")
		(net "M_G_DQ<0>")
	)
	(segment
		(start 32.814768 -23.275544)
		(end 32.814768 -22.5298)
		(width 0.14224)
		(layer "In2.Cu")
		(net "M_G_DQ<0>")
	)
	(segment
		(start 33.551368 -21.293328)
		(end 33.161986 -20.903946)
		(width 0.14224)
		(layer "In2.Cu")
		(net "M_G_DQ<0>")
	)
	(segment
		(start 32.865568 -30.577536)
		(end 33.007808 -30.719776)
		(width 0.14224)
		(layer "In2.Cu")
		(net "M_G_DQ<0>")
	)
	(segment
		(start 33.498536 -32.162496)
		(end 33.498536 -36.59124)
		(width 0.14224)
		(layer "In2.Cu")
		(net "M_G_DQ<0>")
	)
	(segment
		(start 63.039498 -66.132202)
		(end 65.631568 -66.132202)
		(width 0.14224)
		(layer "In2.Cu")
		(net "M_G_DQ<0>")
	)
	(segment
		(start 32.72409 -27.7368)
		(end 33.378648 -27.7368)
		(width 0.14224)
		(layer "In2.Cu")
		(net "M_G_DQ<0>")
	)
	(segment
		(start 33.551368 -18.381218)
		(end 33.771586 -18.161)
		(width 0.14224)
		(layer "In2.Cu")
		(net "M_G_DQ<0>")
	)
	(segment
		(start 33.356296 -31.370016)
		(end 33.007808 -31.370016)
		(width 0.14224)
		(layer "In2.Cu")
		(net "M_G_DQ<0>")
	)
	(segment
		(start 32.49168 -24.1681)
		(end 32.49168 -27.50439)
		(width 0.14224)
		(layer "In2.Cu")
		(net "M_G_DQ<0>")
	)
	(segment
		(start 33.498536 -27.856688)
		(end 33.498536 -28.626816)
		(width 0.14224)
		(layer "In2.Cu")
		(net "M_G_DQ<0>")
	)
	(segment
		(start 66.237612 -66.132202)
		(end 66.873374 -65.49644)
		(width 0.0889)
		(layer "In2.Cu")
		(net "M_G_DQ<0>")
	)
	(segment
		(start 33.007808 -30.069536)
		(end 32.865568 -30.211776)
		(width 0.14224)
		(layer "In2.Cu")
		(net "M_G_DQ<0>")
	)
	(segment
		(start 32.865568 -29.277056)
		(end 33.007808 -29.419296)
		(width 0.14224)
		(layer "In2.Cu")
		(net "M_G_DQ<0>")
	)
	(segment
		(start 33.007808 -28.769056)
		(end 32.865568 -28.911296)
		(width 0.14224)
		(layer "In2.Cu")
		(net "M_G_DQ<0>")
	)
	(segment
		(start 32.865568 -31.878016)
		(end 33.007808 -32.020256)
		(width 0.14224)
		(layer "In2.Cu")
		(net "M_G_DQ<0>")
	)
	(segment
		(start 33.136586 -19.7104)
		(end 33.136586 -19.380454)
		(width 0.14224)
		(layer "In2.Cu")
		(net "M_G_DQ<0>")
	)
	(segment
		(start 33.356296 -29.419296)
		(end 33.498536 -29.561536)
		(width 0.14224)
		(layer "In2.Cu")
		(net "M_G_DQ<0>")
	)
	(segment
		(start 33.356296 -30.719776)
		(end 33.498536 -30.862016)
		(width 0.14224)
		(layer "In2.Cu")
		(net "M_G_DQ<0>")
	)
	(segment
		(start 33.551368 -18.965672)
		(end 33.551368 -18.381218)
		(width 0.14224)
		(layer "In2.Cu")
		(net "M_G_DQ<0>")
	)
	(segment
		(start 33.498536 -31.227776)
		(end 33.356296 -31.370016)
		(width 0.14224)
		(layer "In2.Cu")
		(net "M_G_DQ<0>")
	)
	(segment
		(start 33.161986 -20.903946)
		(end 33.161986 -20.5994)
		(width 0.14224)
		(layer "In2.Cu")
		(net "M_G_DQ<0>")
	)
	(segment
		(start 33.007808 -32.020256)
		(end 33.356296 -32.020256)
		(width 0.14224)
		(layer "In2.Cu")
		(net "M_G_DQ<0>")
	)
	(segment
		(start 33.356296 -32.020256)
		(end 33.498536 -32.162496)
		(width 0.14224)
		(layer "In2.Cu")
		(net "M_G_DQ<0>")
	)
	(segment
		(start 33.498536 -29.927296)
		(end 33.356296 -30.069536)
		(width 0.14224)
		(layer "In2.Cu")
		(net "M_G_DQ<0>")
	)
	(segment
		(start 33.551368 -21.7932)
		(end 33.551368 -21.293328)
		(width 0.14224)
		(layer "In2.Cu")
		(net "M_G_DQ<0>")
	)
	(segment
		(start 33.479486 -20.0533)
		(end 33.136586 -19.7104)
		(width 0.14224)
		(layer "In2.Cu")
		(net "M_G_DQ<0>")
	)
	(segment
		(start 33.007808 -29.419296)
		(end 33.356296 -29.419296)
		(width 0.14224)
		(layer "In2.Cu")
		(net "M_G_DQ<0>")
	)
	(segment
		(start 32.865568 -28.911296)
		(end 32.865568 -29.277056)
		(width 0.14224)
		(layer "In2.Cu")
		(net "M_G_DQ<0>")
	)
	(segment
		(start 33.498536 -36.59124)
		(end 63.039498 -66.132202)
		(width 0.14224)
		(layer "In2.Cu")
		(net "M_G_DQ<0>")
	)
	(segment
		(start 33.099502 -23.560278)
		(end 32.49168 -24.1681)
		(width 0.14224)
		(layer "In2.Cu")
		(net "M_G_DQ<0>")
	)
	(segment
		(start 65.631568 -66.132202)
		(end 66.237612 -66.132202)
		(width 0.0889)
		(layer "In2.Cu")
		(net "M_G_DQ<0>")
	)
	(segment
		(start 33.136586 -19.380454)
		(end 33.551368 -18.965672)
		(width 0.14224)
		(layer "In2.Cu")
		(net "M_G_DQ<0>")
	)
	(segment
		(start 32.865568 -30.211776)
		(end 32.865568 -30.577536)
		(width 0.14224)
		(layer "In2.Cu")
		(net "M_G_DQ<0>")
	)
	(segment
		(start 33.356296 -30.069536)
		(end 33.007808 -30.069536)
		(width 0.14224)
		(layer "In2.Cu")
		(net "M_G_DQ<0>")
	)
	(segment
		(start 33.498536 -30.862016)
		(end 33.498536 -31.227776)
		(width 0.14224)
		(layer "In2.Cu")
		(net "M_G_DQ<0>")
	)
	(segment
		(start 104.518968 -49.885346)
		(end 104.690418 -49.713896)
		(width 0.1651)
		(layer "F.Cu")
		(net "M_G_CS_N<7>")
	)
	(segment
		(start 102.947724 -54.104286)
		(end 103.348282 -54.104286)
		(width 0.1651)
		(layer "F.Cu")
		(net "M_G_CS_N<7>")
	)
	(segment
		(start 104.518968 -52.9336)
		(end 104.518968 -49.885346)
		(width 0.1651)
		(layer "F.Cu")
		(net "M_G_CS_N<7>")
	)
	(segment
		(start 104.690418 -33.720532)
		(end 111.700818 -26.710132)
		(width 0.1651)
		(layer "F.Cu")
		(net "M_G_CS_N<7>")
	)
	(segment
		(start 103.348282 -54.104286)
		(end 104.518968 -52.9336)
		(width 0.1651)
		(layer "F.Cu")
		(net "M_G_CS_N<7>")
	)
	(segment
		(start 113.485168 -24.925782)
		(end 113.485168 -22.6314)
		(width 0.1651)
		(layer "F.Cu")
		(net "M_G_CS_N<7>")
	)
	(segment
		(start 113.282222 -22.428454)
		(end 113.282222 -21.800058)
		(width 0.1651)
		(layer "F.Cu")
		(net "M_G_CS_N<7>")
	)
	(segment
		(start 111.700818 -26.710132)
		(end 113.485168 -24.925782)
		(width 0.1651)
		(layer "F.Cu")
		(net "M_G_CS_N<7>")
	)
	(segment
		(start 113.282222 -21.800058)
		(end 112.99952 -21.517356)
		(width 0.1651)
		(layer "F.Cu")
		(net "M_G_CS_N<7>")
	)
	(segment
		(start 113.485168 -22.6314)
		(end 113.282222 -22.428454)
		(width 0.1651)
		(layer "F.Cu")
		(net "M_G_CS_N<7>")
	)
	(segment
		(start 104.690418 -49.713896)
		(end 104.690418 -33.720532)
		(width 0.1651)
		(layer "F.Cu")
		(net "M_G_CS_N<7>")
	)
	(via
		(at 112.99952 -21.517356)
		(size 0.508)
		(drill 0.254)
		(layers "F.Cu" "B.Cu")
		(net "M_G_CS_N<7>")
	)
	(via
		(at 111.700818 -26.710132)
		(size 0.508)
		(drill 0.254)
		(layers "F.Cu" "B.Cu")
		(net "M_G_CS_N<7>")
	)
	(segment
		(start 112.99952 -21.517356)
		(end 112.99952 -20.224242)
		(width 0.1651)
		(layer "B.Cu")
		(net "M_G_CS_N<7>")
	)
	(segment
		(start 111.398812 -25.154636)
		(end 111.398812 -24.920956)
		(width 0.1651)
		(layer "F.Cu")
		(net "M_G_CS_N<6>")
	)
	(segment
		(start 103.960168 -51.90744)
		(end 103.960168 -49.657)
		(width 0.1651)
		(layer "F.Cu")
		(net "M_G_CS_N<6>")
	)
	(segment
		(start 110.919768 -26.73858)
		(end 110.919768 -26.549604)
		(width 0.1651)
		(layer "F.Cu")
		(net "M_G_CS_N<6>")
	)
	(segment
		(start 103.744268 -52.12334)
		(end 103.960168 -51.90744)
		(width 0.1651)
		(layer "F.Cu")
		(net "M_G_CS_N<6>")
	)
	(segment
		(start 112.799368 -24.88692)
		(end 112.799368 -23.051008)
		(width 0.1651)
		(layer "F.Cu")
		(net "M_G_CS_N<6>")
	)
	(segment
		(start 111.378492 -26.074116)
		(end 111.612172 -26.074116)
		(width 0.1651)
		(layer "F.Cu")
		(net "M_G_CS_N<6>")
	)
	(segment
		(start 112.549178 -25.13711)
		(end 112.799368 -24.88692)
		(width 0.1651)
		(layer "F.Cu")
		(net "M_G_CS_N<6>")
	)
	(segment
		(start 110.464854 -26.09469)
		(end 110.464854 -25.86101)
		(width 0.1651)
		(layer "F.Cu")
		(net "M_G_CS_N<6>")
	)
	(segment
		(start 111.848392 -25.837896)
		(end 111.848392 -25.604216)
		(width 0.1651)
		(layer "F.Cu")
		(net "M_G_CS_N<6>")
	)
	(segment
		(start 111.612172 -26.074116)
		(end 111.848392 -25.837896)
		(width 0.1651)
		(layer "F.Cu")
		(net "M_G_CS_N<6>")
	)
	(segment
		(start 111.848392 -25.604216)
		(end 111.398812 -25.154636)
		(width 0.1651)
		(layer "F.Cu")
		(net "M_G_CS_N<6>")
	)
	(segment
		(start 110.919768 -26.549604)
		(end 110.464854 -26.09469)
		(width 0.1651)
		(layer "F.Cu")
		(net "M_G_CS_N<6>")
	)
	(segment
		(start 111.865918 -24.68753)
		(end 112.315498 -25.13711)
		(width 0.1651)
		(layer "F.Cu")
		(net "M_G_CS_N<6>")
	)
	(segment
		(start 110.025688 -27.63266)
		(end 110.919768 -26.73858)
		(width 0.1651)
		(layer "F.Cu")
		(net "M_G_CS_N<6>")
	)
	(segment
		(start 102.947724 -52.12334)
		(end 103.744268 -52.12334)
		(width 0.1651)
		(layer "F.Cu")
		(net "M_G_CS_N<6>")
	)
	(segment
		(start 110.69828 -25.627584)
		(end 110.93196 -25.627584)
		(width 0.1651)
		(layer "F.Cu")
		(net "M_G_CS_N<6>")
	)
	(segment
		(start 111.632238 -24.68753)
		(end 111.865918 -24.68753)
		(width 0.1651)
		(layer "F.Cu")
		(net "M_G_CS_N<6>")
	)
	(segment
		(start 110.93196 -25.627584)
		(end 111.378492 -26.074116)
		(width 0.1651)
		(layer "F.Cu")
		(net "M_G_CS_N<6>")
	)
	(segment
		(start 112.315498 -25.13711)
		(end 112.549178 -25.13711)
		(width 0.1651)
		(layer "F.Cu")
		(net "M_G_CS_N<6>")
	)
	(segment
		(start 104.186228 -33.47212)
		(end 110.025688 -27.63266)
		(width 0.1651)
		(layer "F.Cu")
		(net "M_G_CS_N<6>")
	)
	(segment
		(start 103.960168 -49.657)
		(end 104.186228 -49.43094)
		(width 0.1651)
		(layer "F.Cu")
		(net "M_G_CS_N<6>")
	)
	(segment
		(start 110.464854 -25.86101)
		(end 110.69828 -25.627584)
		(width 0.1651)
		(layer "F.Cu")
		(net "M_G_CS_N<6>")
	)
	(segment
		(start 111.398812 -24.920956)
		(end 111.632238 -24.68753)
		(width 0.1651)
		(layer "F.Cu")
		(net "M_G_CS_N<6>")
	)
	(segment
		(start 112.799368 -23.051008)
		(end 112.99952 -22.850856)
		(width 0.1651)
		(layer "F.Cu")
		(net "M_G_CS_N<6>")
	)
	(segment
		(start 104.186228 -49.43094)
		(end 104.186228 -33.47212)
		(width 0.1651)
		(layer "F.Cu")
		(net "M_G_CS_N<6>")
	)
	(via
		(at 110.025688 -27.63266)
		(size 0.508)
		(drill 0.254)
		(layers "F.Cu" "B.Cu")
		(net "M_G_CS_N<6>")
	)
	(via
		(at 112.99952 -22.850856)
		(size 0.508)
		(drill 0.254)
		(layers "F.Cu" "B.Cu")
		(net "M_G_CS_N<6>")
	)
	(segment
		(start 112.99952 -22.850856)
		(end 112.99952 -24.824182)
		(width 0.1651)
		(layer "B.Cu")
		(net "M_G_CS_N<6>")
	)
	(segment
		(start 100.185474 -49.7078)
		(end 99.952048 -50.270918)
		(width 0.0889)
		(layer "F.Cu")
		(net "M_G_CS_N<5>")
	)
	(segment
		(start 109.11078 -24.923242)
		(end 108.773722 -24.923242)
		(width 0.1651)
		(layer "F.Cu")
		(net "M_G_CS_N<5>")
	)
	(segment
		(start 108.608368 -24.276304)
		(end 108.443268 -24.111204)
		(width 0.1651)
		(layer "F.Cu")
		(net "M_G_CS_N<5>")
	)
	(segment
		(start 108.608368 -24.757888)
		(end 108.608368 -24.276304)
		(width 0.1651)
		(layer "F.Cu")
		(net "M_G_CS_N<5>")
	)
	(segment
		(start 101.665278 -48.113188)
		(end 100.304346 -49.47412)
		(width 0.0889)
		(layer "F.Cu")
		(net "M_G_CS_N<5>")
	)
	(segment
		(start 109.319568 -24.714454)
		(end 109.11078 -24.923242)
		(width 0.1651)
		(layer "F.Cu")
		(net "M_G_CS_N<5>")
	)
	(segment
		(start 100.304346 -49.47412)
		(end 100.185474 -49.7078)
		(width 0.0889)
		(layer "F.Cu")
		(net "M_G_CS_N<5>")
	)
	(segment
		(start 101.665278 -47.720758)
		(end 101.665278 -48.113188)
		(width 0.0889)
		(layer "F.Cu")
		(net "M_G_CS_N<5>")
	)
	(segment
		(start 107.908852 -24.307546)
		(end 107.908852 -25.23617)
		(width 0.1651)
		(layer "F.Cu")
		(net "M_G_CS_N<5>")
	)
	(segment
		(start 107.541822 -25.6032)
		(end 106.881168 -25.6032)
		(width 0.1651)
		(layer "F.Cu")
		(net "M_G_CS_N<5>")
	)
	(segment
		(start 109.599476 -22.850856)
		(end 109.599476 -23.342092)
		(width 0.1651)
		(layer "F.Cu")
		(net "M_G_CS_N<5>")
	)
	(segment
		(start 106.449368 -26.035)
		(end 106.449368 -26.59253)
		(width 0.1651)
		(layer "F.Cu")
		(net "M_G_CS_N<5>")
	)
	(segment
		(start 109.319568 -23.622)
		(end 109.319568 -24.714454)
		(width 0.1651)
		(layer "F.Cu")
		(net "M_G_CS_N<5>")
	)
	(segment
		(start 99.952048 -50.270918)
		(end 99.513898 -51.132486)
		(width 0.0889)
		(layer "F.Cu")
		(net "M_G_CS_N<5>")
	)
	(segment
		(start 106.881168 -25.6032)
		(end 106.449368 -26.035)
		(width 0.1651)
		(layer "F.Cu")
		(net "M_G_CS_N<5>")
	)
	(segment
		(start 108.773722 -24.923242)
		(end 108.608368 -24.757888)
		(width 0.1651)
		(layer "F.Cu")
		(net "M_G_CS_N<5>")
	)
	(segment
		(start 109.599476 -23.342092)
		(end 109.319568 -23.622)
		(width 0.1651)
		(layer "F.Cu")
		(net "M_G_CS_N<5>")
	)
	(segment
		(start 106.449368 -26.59253)
		(end 106.449368 -27.185874)
		(width 0.1651)
		(layer "F.Cu")
		(net "M_G_CS_N<5>")
	)
	(segment
		(start 107.908852 -25.23617)
		(end 107.541822 -25.6032)
		(width 0.1651)
		(layer "F.Cu")
		(net "M_G_CS_N<5>")
	)
	(segment
		(start 106.449368 -27.185874)
		(end 101.665278 -31.969964)
		(width 0.1651)
		(layer "F.Cu")
		(net "M_G_CS_N<5>")
	)
	(segment
		(start 108.443268 -24.111204)
		(end 108.105194 -24.111204)
		(width 0.1651)
		(layer "F.Cu")
		(net "M_G_CS_N<5>")
	)
	(segment
		(start 108.105194 -24.111204)
		(end 107.908852 -24.307546)
		(width 0.1651)
		(layer "F.Cu")
		(net "M_G_CS_N<5>")
	)
	(segment
		(start 101.665278 -31.969964)
		(end 101.665278 -47.720758)
		(width 0.1651)
		(layer "F.Cu")
		(net "M_G_CS_N<5>")
	)
	(via
		(at 106.449368 -26.59253)
		(size 0.508)
		(drill 0.254)
		(layers "F.Cu" "B.Cu")
		(net "M_G_CS_N<5>")
	)
	(via
		(at 109.599476 -22.850856)
		(size 0.508)
		(drill 0.254)
		(layers "F.Cu" "B.Cu")
		(net "M_G_CS_N<5>")
	)
	(segment
		(start 109.599476 -22.850856)
		(end 109.599476 -24.824182)
		(width 0.1651)
		(layer "B.Cu")
		(net "M_G_CS_N<5>")
	)
	(segment
		(start 101.719888 -27.41676)
		(end 101.935788 -27.63266)
		(width 0.1651)
		(layer "F.Cu")
		(net "M_G_CS_N<4>")
	)
	(segment
		(start 102.410768 -27.404822)
		(end 102.410768 -25.6794)
		(width 0.1651)
		(layer "F.Cu")
		(net "M_G_CS_N<4>")
	)
	(segment
		(start 104.645968 -24.426672)
		(end 104.645968 -24.1554)
		(width 0.1651)
		(layer "F.Cu")
		(net "M_G_CS_N<4>")
	)
	(segment
		(start 99.144328 -47.470568)
		(end 99.144328 -30.671262)
		(width 0.1651)
		(layer "F.Cu")
		(net "M_G_CS_N<4>")
	)
	(segment
		(start 103.826818 -24.49703)
		(end 104.050338 -24.72055)
		(width 0.1651)
		(layer "F.Cu")
		(net "M_G_CS_N<4>")
	)
	(segment
		(start 103.862632 -22.991064)
		(end 103.862632 -22.69236)
		(width 0.1651)
		(layer "F.Cu")
		(net "M_G_CS_N<4>")
	)
	(segment
		(start 97.796858 -49.419764)
		(end 99.144328 -48.072294)
		(width 0.0889)
		(layer "F.Cu")
		(net "M_G_CS_N<4>")
	)
	(segment
		(start 104.638856 -22.195028)
		(end 104.976168 -22.53234)
		(width 0.1651)
		(layer "F.Cu")
		(net "M_G_CS_N<4>")
	)
	(segment
		(start 103.862632 -22.69236)
		(end 104.359964 -22.195028)
		(width 0.1651)
		(layer "F.Cu")
		(net "M_G_CS_N<4>")
	)
	(segment
		(start 100.795328 -29.020262)
		(end 101.403912 -28.411678)
		(width 0.1651)
		(layer "F.Cu")
		(net "M_G_CS_N<4>")
	)
	(segment
		(start 104.359964 -22.195028)
		(end 104.638856 -22.195028)
		(width 0.1651)
		(layer "F.Cu")
		(net "M_G_CS_N<4>")
	)
	(segment
		(start 104.293924 -23.803356)
		(end 104.293924 -23.422356)
		(width 0.1651)
		(layer "F.Cu")
		(net "M_G_CS_N<4>")
	)
	(segment
		(start 104.35209 -24.72055)
		(end 104.645968 -24.426672)
		(width 0.1651)
		(layer "F.Cu")
		(net "M_G_CS_N<4>")
	)
	(segment
		(start 101.486208 -27.41676)
		(end 101.719888 -27.41676)
		(width 0.1651)
		(layer "F.Cu")
		(net "M_G_CS_N<4>")
	)
	(segment
		(start 104.293924 -23.422356)
		(end 103.862632 -22.991064)
		(width 0.1651)
		(layer "F.Cu")
		(net "M_G_CS_N<4>")
	)
	(segment
		(start 101.403912 -28.228544)
		(end 101.168708 -27.99334)
		(width 0.1651)
		(layer "F.Cu")
		(net "M_G_CS_N<4>")
	)
	(segment
		(start 102.410768 -25.6794)
		(end 103.593138 -24.49703)
		(width 0.1651)
		(layer "F.Cu")
		(net "M_G_CS_N<4>")
	)
	(segment
		(start 101.935788 -27.63266)
		(end 102.18293 -27.63266)
		(width 0.1651)
		(layer "F.Cu")
		(net "M_G_CS_N<4>")
	)
	(segment
		(start 97.796858 -50.141886)
		(end 97.796858 -49.419764)
		(width 0.0889)
		(layer "F.Cu")
		(net "M_G_CS_N<4>")
	)
	(segment
		(start 101.168708 -27.73426)
		(end 101.486208 -27.41676)
		(width 0.1651)
		(layer "F.Cu")
		(net "M_G_CS_N<4>")
	)
	(segment
		(start 99.144328 -30.671262)
		(end 100.795328 -29.020262)
		(width 0.1651)
		(layer "F.Cu")
		(net "M_G_CS_N<4>")
	)
	(segment
		(start 102.18293 -27.63266)
		(end 102.410768 -27.404822)
		(width 0.1651)
		(layer "F.Cu")
		(net "M_G_CS_N<4>")
	)
	(segment
		(start 104.976168 -22.53234)
		(end 104.976168 -23.187152)
		(width 0.1651)
		(layer "F.Cu")
		(net "M_G_CS_N<4>")
	)
	(segment
		(start 104.976168 -23.187152)
		(end 105.349294 -23.560278)
		(width 0.1651)
		(layer "F.Cu")
		(net "M_G_CS_N<4>")
	)
	(segment
		(start 104.645968 -24.1554)
		(end 104.293924 -23.803356)
		(width 0.1651)
		(layer "F.Cu")
		(net "M_G_CS_N<4>")
	)
	(segment
		(start 101.403912 -28.411678)
		(end 101.403912 -28.228544)
		(width 0.1651)
		(layer "F.Cu")
		(net "M_G_CS_N<4>")
	)
	(segment
		(start 101.168708 -27.99334)
		(end 101.168708 -27.73426)
		(width 0.1651)
		(layer "F.Cu")
		(net "M_G_CS_N<4>")
	)
	(segment
		(start 103.593138 -24.49703)
		(end 103.826818 -24.49703)
		(width 0.1651)
		(layer "F.Cu")
		(net "M_G_CS_N<4>")
	)
	(segment
		(start 99.144328 -48.072294)
		(end 99.144328 -47.470568)
		(width 0.0889)
		(layer "F.Cu")
		(net "M_G_CS_N<4>")
	)
	(segment
		(start 104.050338 -24.72055)
		(end 104.35209 -24.72055)
		(width 0.1651)
		(layer "F.Cu")
		(net "M_G_CS_N<4>")
	)
	(via
		(at 105.349294 -23.560278)
		(size 0.508)
		(drill 0.254)
		(layers "F.Cu" "B.Cu")
		(net "M_G_CS_N<4>")
	)
	(via
		(at 100.795328 -29.020262)
		(size 0.508)
		(drill 0.254)
		(layers "F.Cu" "B.Cu")
		(net "M_G_CS_N<4>")
	)
	(segment
		(start 105.349548 -23.560532)
		(end 105.349294 -23.560278)
		(width 0.1651)
		(layer "B.Cu")
		(net "M_G_CS_N<4>")
	)
	(segment
		(start 105.349548 -24.824182)
		(end 105.349548 -23.560532)
		(width 0.1651)
		(layer "B.Cu")
		(net "M_G_CS_N<4>")
	)
	(segment
		(start 111.656368 -23.2918)
		(end 111.656368 -23.8506)
		(width 0.1651)
		(layer "F.Cu")
		(net "M_G_CS_N<3>")
	)
	(segment
		(start 109.759496 -25.747472)
		(end 109.759496 -27.14625)
		(width 0.1651)
		(layer "F.Cu")
		(net "M_G_CS_N<3>")
	)
	(segment
		(start 112.469168 -21.8186)
		(end 112.621568 -21.971)
		(width 0.1651)
		(layer "F.Cu")
		(net "M_G_CS_N<3>")
	)
	(segment
		(start 103.426768 -51.238404)
		(end 103.06177 -51.603402)
		(width 0.1651)
		(layer "F.Cu")
		(net "M_G_CS_N<3>")
	)
	(segment
		(start 107.341924 -29.563822)
		(end 103.682038 -33.223708)
		(width 0.1651)
		(layer "F.Cu")
		(net "M_G_CS_N<3>")
	)
	(segment
		(start 102.204774 -52.123594)
		(end 101.230938 -52.123594)
		(width 0.1651)
		(layer "F.Cu")
		(net "M_G_CS_N<3>")
	)
	(segment
		(start 101.230938 -52.123594)
		(end 101.230684 -52.12334)
		(width 0.1651)
		(layer "F.Cu")
		(net "M_G_CS_N<3>")
	)
	(segment
		(start 111.656368 -23.8506)
		(end 109.759496 -25.747472)
		(width 0.1651)
		(layer "F.Cu")
		(net "M_G_CS_N<3>")
	)
	(segment
		(start 112.99952 -20.780502)
		(end 112.469168 -21.310854)
		(width 0.1651)
		(layer "F.Cu")
		(net "M_G_CS_N<3>")
	)
	(segment
		(start 112.469168 -21.310854)
		(end 112.469168 -21.8186)
		(width 0.1651)
		(layer "F.Cu")
		(net "M_G_CS_N<3>")
	)
	(segment
		(start 103.682038 -33.223708)
		(end 103.682038 -49.17313)
		(width 0.1651)
		(layer "F.Cu")
		(net "M_G_CS_N<3>")
	)
	(segment
		(start 112.621568 -21.971)
		(end 112.621568 -22.4028)
		(width 0.1651)
		(layer "F.Cu")
		(net "M_G_CS_N<3>")
	)
	(segment
		(start 103.06177 -51.603402)
		(end 102.724966 -51.603402)
		(width 0.1651)
		(layer "F.Cu")
		(net "M_G_CS_N<3>")
	)
	(segment
		(start 109.759496 -27.14625)
		(end 107.341924 -29.563822)
		(width 0.1651)
		(layer "F.Cu")
		(net "M_G_CS_N<3>")
	)
	(segment
		(start 102.724966 -51.603402)
		(end 102.204774 -52.123594)
		(width 0.1651)
		(layer "F.Cu")
		(net "M_G_CS_N<3>")
	)
	(segment
		(start 112.291368 -22.6568)
		(end 111.656368 -23.2918)
		(width 0.1651)
		(layer "F.Cu")
		(net "M_G_CS_N<3>")
	)
	(segment
		(start 103.682038 -49.17313)
		(end 103.426768 -49.4284)
		(width 0.1651)
		(layer "F.Cu")
		(net "M_G_CS_N<3>")
	)
	(segment
		(start 103.426768 -49.4284)
		(end 103.426768 -51.238404)
		(width 0.1651)
		(layer "F.Cu")
		(net "M_G_CS_N<3>")
	)
	(segment
		(start 112.367568 -22.6568)
		(end 112.291368 -22.6568)
		(width 0.1651)
		(layer "F.Cu")
		(net "M_G_CS_N<3>")
	)
	(segment
		(start 112.99952 -20.023582)
		(end 112.99952 -20.780502)
		(width 0.1651)
		(layer "F.Cu")
		(net "M_G_CS_N<3>")
	)
	(segment
		(start 112.621568 -22.4028)
		(end 112.367568 -22.6568)
		(width 0.1651)
		(layer "F.Cu")
		(net "M_G_CS_N<3>")
	)
	(via
		(at 107.341924 -29.563822)
		(size 0.508)
		(drill 0.254)
		(layers "F.Cu" "B.Cu")
		(net "M_G_CS_N<3>")
	)
	(segment
		(start 101.914706 -50.197512)
		(end 101.72573 -50.466752)
		(width 0.0889)
		(layer "F.Cu")
		(net "M_G_CS_N<2>")
	)
	(segment
		(start 109.100112 -27.053032)
		(end 107.903518 -28.249626)
		(width 0.1651)
		(layer "F.Cu")
		(net "M_G_CS_N<2>")
	)
	(segment
		(start 109.100112 -26.652728)
		(end 109.100112 -27.053032)
		(width 0.1651)
		(layer "F.Cu")
		(net "M_G_CS_N<2>")
	)
	(segment
		(start 112.99952 -16.718788)
		(end 112.99952 -15.423642)
		(width 0.1651)
		(layer "F.Cu")
		(net "M_G_CS_N<2>")
	)
	(segment
		(start 108.634784 -26.1874)
		(end 109.100112 -26.652728)
		(width 0.1651)
		(layer "F.Cu")
		(net "M_G_CS_N<2>")
	)
	(segment
		(start 103.177848 -48.438054)
		(end 103.177848 -48.93437)
		(width 0.0889)
		(layer "F.Cu")
		(net "M_G_CS_N<2>")
	)
	(segment
		(start 101.72573 -50.466752)
		(end 101.230684 -51.132486)
		(width 0.0889)
		(layer "F.Cu")
		(net "M_G_CS_N<2>")
	)
	(segment
		(start 103.177848 -48.93437)
		(end 101.914706 -50.197512)
		(width 0.0889)
		(layer "F.Cu")
		(net "M_G_CS_N<2>")
	)
	(segment
		(start 107.903518 -28.249626)
		(end 103.177848 -32.975296)
		(width 0.1651)
		(layer "F.Cu")
		(net "M_G_CS_N<2>")
	)
	(segment
		(start 103.177848 -32.975296)
		(end 103.177848 -48.438054)
		(width 0.1651)
		(layer "F.Cu")
		(net "M_G_CS_N<2>")
	)
	(via
		(at 112.99952 -16.718788)
		(size 0.4572)
		(drill 0.2032)
		(layers "F.Cu" "B.Cu")
		(net "M_G_CS_N<2>")
	)
	(via
		(at 108.634784 -26.1874)
		(size 0.508)
		(drill 0.254)
		(layers "F.Cu" "B.Cu")
		(net "M_G_CS_N<2>")
	)
	(via
		(at 107.903518 -28.249626)
		(size 0.508)
		(drill 0.254)
		(layers "F.Cu" "B.Cu")
		(net "M_G_CS_N<2>")
	)
	(segment
		(start 112.621568 -22.4028)
		(end 112.621568 -21.9202)
		(width 0.14224)
		(layer "In9.Cu")
		(net "M_G_CS_N<2>")
	)
	(segment
		(start 112.589056 -17.129252)
		(end 112.99952 -16.718788)
		(width 0.14224)
		(layer "In9.Cu")
		(net "M_G_CS_N<2>")
	)
	(segment
		(start 112.589056 -19.336512)
		(end 112.589056 -17.129252)
		(width 0.14224)
		(layer "In9.Cu")
		(net "M_G_CS_N<2>")
	)
	(segment
		(start 112.519968 -21.8186)
		(end 112.519968 -19.4056)
		(width 0.14224)
		(layer "In9.Cu")
		(net "M_G_CS_N<2>")
	)
	(segment
		(start 109.268768 -25.7556)
		(end 112.621568 -22.4028)
		(width 0.14224)
		(layer "In9.Cu")
		(net "M_G_CS_N<2>")
	)
	(segment
		(start 109.066584 -25.7556)
		(end 109.268768 -25.7556)
		(width 0.14224)
		(layer "In9.Cu")
		(net "M_G_CS_N<2>")
	)
	(segment
		(start 112.621568 -21.9202)
		(end 112.519968 -21.8186)
		(width 0.14224)
		(layer "In9.Cu")
		(net "M_G_CS_N<2>")
	)
	(segment
		(start 108.634784 -26.1874)
		(end 109.066584 -25.7556)
		(width 0.14224)
		(layer "In9.Cu")
		(net "M_G_CS_N<2>")
	)
	(segment
		(start 112.519968 -19.4056)
		(end 112.589056 -19.336512)
		(width 0.14224)
		(layer "In9.Cu")
		(net "M_G_CS_N<2>")
	)
	(segment
		(start 99.513898 -52.12334)
		(end 99.183952 -51.361594)
		(width 0.0889)
		(layer "F.Cu")
		(net "M_G_CS_N<1>")
	)
	(segment
		(start 109.599476 -16.714978)
		(end 109.599476 -15.423642)
		(width 0.1651)
		(layer "F.Cu")
		(net "M_G_CS_N<1>")
	)
	(segment
		(start 99.786948 -48.9712)
		(end 100.175568 -48.9712)
		(width 0.0889)
		(layer "F.Cu")
		(net "M_G_CS_N<1>")
	)
	(segment
		(start 104.277922 -28.604718)
		(end 105.839768 -27.042872)
		(width 0.1651)
		(layer "F.Cu")
		(net "M_G_CS_N<1>")
	)
	(segment
		(start 100.175568 -48.9712)
		(end 101.161088 -47.98568)
		(width 0.0889)
		(layer "F.Cu")
		(net "M_G_CS_N<1>")
	)
	(segment
		(start 99.183952 -51.361594)
		(end 99.167188 -51.332638)
		(width 0.0889)
		(layer "F.Cu")
		(net "M_G_CS_N<1>")
	)
	(segment
		(start 101.161088 -47.624492)
		(end 101.161088 -31.721552)
		(width 0.1651)
		(layer "F.Cu")
		(net "M_G_CS_N<1>")
	)
	(segment
		(start 105.839768 -26.667206)
		(end 105.364026 -26.191464)
		(width 0.1651)
		(layer "F.Cu")
		(net "M_G_CS_N<1>")
	)
	(segment
		(start 101.161088 -31.721552)
		(end 104.277922 -28.604718)
		(width 0.1651)
		(layer "F.Cu")
		(net "M_G_CS_N<1>")
	)
	(segment
		(start 99.167188 -50.932588)
		(end 99.173538 -50.92192)
		(width 0.0889)
		(layer "F.Cu")
		(net "M_G_CS_N<1>")
	)
	(segment
		(start 101.161088 -47.98568)
		(end 101.161088 -47.624492)
		(width 0.0889)
		(layer "F.Cu")
		(net "M_G_CS_N<1>")
	)
	(segment
		(start 99.162362 -50.941224)
		(end 99.167188 -50.932588)
		(width 0.0889)
		(layer "F.Cu")
		(net "M_G_CS_N<1>")
	)
	(segment
		(start 99.092512 -49.665636)
		(end 99.786948 -48.9712)
		(width 0.0889)
		(layer "F.Cu")
		(net "M_G_CS_N<1>")
	)
	(segment
		(start 99.092512 -50.0634)
		(end 99.092512 -49.665636)
		(width 0.0889)
		(layer "F.Cu")
		(net "M_G_CS_N<1>")
	)
	(segment
		(start 105.839768 -27.042872)
		(end 105.839768 -26.667206)
		(width 0.1651)
		(layer "F.Cu")
		(net "M_G_CS_N<1>")
	)
	(via
		(at 109.599476 -16.714978)
		(size 0.508)
		(drill 0.254)
		(layers "F.Cu" "B.Cu")
		(net "M_G_CS_N<1>")
	)
	(via
		(at 105.364026 -26.191464)
		(size 0.508)
		(drill 0.254)
		(layers "F.Cu" "B.Cu")
		(net "M_G_CS_N<1>")
	)
	(via
		(at 104.277922 -28.604718)
		(size 0.508)
		(drill 0.254)
		(layers "F.Cu" "B.Cu")
		(net "M_G_CS_N<1>")
	)
	(arc
		(start 99.167188 -50.342038)
		(mid 99.111539 -50.20763)
		(end 99.092512 -50.0634)
		(width 0.0889)
		(layer "F.Cu")
		(net "M_G_CS_N<1>")
	)
	(arc
		(start 99.167188 -51.332638)
		(mid 99.113718 -51.137575)
		(end 99.162362 -50.941224)
		(width 0.0889)
		(layer "F.Cu")
		(net "M_G_CS_N<1>")
	)
	(arc
		(start 99.173538 -50.92192)
		(mid 99.246336 -50.631157)
		(end 99.167188 -50.342038)
		(width 0.0889)
		(layer "F.Cu")
		(net "M_G_CS_N<1>")
	)
	(segment
		(start 109.040168 -21.6662)
		(end 109.040168 -21.1836)
		(width 0.14224)
		(layer "In9.Cu")
		(net "M_G_CS_N<1>")
	)
	(segment
		(start 109.040168 -21.1836)
		(end 109.268768 -20.955)
		(width 0.14224)
		(layer "In9.Cu")
		(net "M_G_CS_N<1>")
	)
	(segment
		(start 109.163358 -17.75841)
		(end 109.599476 -17.322292)
		(width 0.14224)
		(layer "In9.Cu")
		(net "M_G_CS_N<1>")
	)
	(segment
		(start 109.268768 -20.955)
		(end 109.268768 -19.345402)
		(width 0.14224)
		(layer "In9.Cu")
		(net "M_G_CS_N<1>")
	)
	(segment
		(start 109.294168 -22.3012)
		(end 109.294168 -21.9202)
		(width 0.14224)
		(layer "In9.Cu")
		(net "M_G_CS_N<1>")
	)
	(segment
		(start 105.87609 -25.6794)
		(end 105.915968 -25.6794)
		(width 0.14224)
		(layer "In9.Cu")
		(net "M_G_CS_N<1>")
	)
	(segment
		(start 109.294168 -21.9202)
		(end 109.040168 -21.6662)
		(width 0.14224)
		(layer "In9.Cu")
		(net "M_G_CS_N<1>")
	)
	(segment
		(start 105.915968 -25.6794)
		(end 109.294168 -22.3012)
		(width 0.14224)
		(layer "In9.Cu")
		(net "M_G_CS_N<1>")
	)
	(segment
		(start 105.364026 -26.191464)
		(end 105.87609 -25.6794)
		(width 0.14224)
		(layer "In9.Cu")
		(net "M_G_CS_N<1>")
	)
	(segment
		(start 109.599476 -17.322292)
		(end 109.599476 -16.714978)
		(width 0.14224)
		(layer "In9.Cu")
		(net "M_G_CS_N<1>")
	)
	(segment
		(start 109.268768 -19.345402)
		(end 109.163358 -19.239992)
		(width 0.14224)
		(layer "In9.Cu")
		(net "M_G_CS_N<1>")
	)
	(segment
		(start 109.163358 -19.239992)
		(end 109.163358 -17.75841)
		(width 0.14224)
		(layer "In9.Cu")
		(net "M_G_CS_N<1>")
	)
	(segment
		(start 97.388426 -49.446942)
		(end 98.640138 -48.19523)
		(width 0.0889)
		(layer "F.Cu")
		(net "M_G_CS_N<0>")
	)
	(segment
		(start 97.229168 -52.160932)
		(end 97.7138 -51.6763)
		(width 0.0889)
		(layer "F.Cu")
		(net "M_G_CS_N<0>")
	)
	(segment
		(start 105.349548 -16.718534)
		(end 105.349802 -16.718788)
		(width 0.1651)
		(layer "F.Cu")
		(net "M_G_CS_N<0>")
	)
	(segment
		(start 100.503736 -27.636978)
		(end 101.195632 -26.945082)
		(width 0.1651)
		(layer "F.Cu")
		(net "M_G_CS_N<0>")
	)
	(segment
		(start 96.938338 -52.618386)
		(end 97.229168 -52.327556)
		(width 0.0889)
		(layer "F.Cu")
		(net "M_G_CS_N<0>")
	)
	(segment
		(start 97.229168 -52.327556)
		(end 97.229168 -52.160932)
		(width 0.0889)
		(layer "F.Cu")
		(net "M_G_CS_N<0>")
	)
	(segment
		(start 97.588578 -50.52441)
		(end 97.450148 -50.342038)
		(width 0.0889)
		(layer "F.Cu")
		(net "M_G_CS_N<0>")
	)
	(segment
		(start 97.388426 -50.114454)
		(end 97.388426 -49.446942)
		(width 0.0889)
		(layer "F.Cu")
		(net "M_G_CS_N<0>")
	)
	(segment
		(start 98.640138 -45.621702)
		(end 98.640138 -30.426152)
		(width 0.1651)
		(layer "F.Cu")
		(net "M_G_CS_N<0>")
	)
	(segment
		(start 97.804732 -51.6763)
		(end 98.136202 -51.34483)
		(width 0.0889)
		(layer "F.Cu")
		(net "M_G_CS_N<0>")
	)
	(segment
		(start 98.640138 -30.426152)
		(end 100.503736 -27.636978)
		(width 0.1651)
		(layer "F.Cu")
		(net "M_G_CS_N<0>")
	)
	(segment
		(start 97.891854 -50.743612)
		(end 97.748852 -50.652426)
		(width 0.0889)
		(layer "F.Cu")
		(net "M_G_CS_N<0>")
	)
	(segment
		(start 97.748852 -50.652426)
		(end 97.588578 -50.52441)
		(width 0.0889)
		(layer "F.Cu")
		(net "M_G_CS_N<0>")
	)
	(segment
		(start 101.195632 -26.945082)
		(end 101.94925 -26.191464)
		(width 0.1651)
		(layer "F.Cu")
		(net "M_G_CS_N<0>")
	)
	(segment
		(start 105.349548 -15.423642)
		(end 105.349548 -16.718534)
		(width 0.1651)
		(layer "F.Cu")
		(net "M_G_CS_N<0>")
	)
	(segment
		(start 97.7138 -51.6763)
		(end 97.804732 -51.6763)
		(width 0.0889)
		(layer "F.Cu")
		(net "M_G_CS_N<0>")
	)
	(segment
		(start 98.640138 -48.19523)
		(end 98.640138 -45.621702)
		(width 0.0889)
		(layer "F.Cu")
		(net "M_G_CS_N<0>")
	)
	(via
		(at 101.94925 -26.191464)
		(size 0.508)
		(drill 0.254)
		(layers "F.Cu" "B.Cu")
		(net "M_G_CS_N<0>")
	)
	(via
		(at 105.349802 -16.718788)
		(size 0.4572)
		(drill 0.2032)
		(layers "F.Cu" "B.Cu")
		(net "M_G_CS_N<0>")
	)
	(via
		(at 101.195632 -26.945082)
		(size 0.508)
		(drill 0.254)
		(layers "F.Cu" "B.Cu")
		(net "M_G_CS_N<0>")
	)
	(arc
		(start 98.136202 -51.34483)
		(mid 98.167705 -50.981764)
		(end 97.891854 -50.743612)
		(width 0.0889)
		(layer "F.Cu")
		(net "M_G_CS_N<0>")
	)
	(arc
		(start 97.450148 -50.342038)
		(mid 97.404508 -50.232257)
		(end 97.388426 -50.114454)
		(width 0.0889)
		(layer "F.Cu")
		(net "M_G_CS_N<0>")
	)
	(segment
		(start 105.349294 -16.719296)
		(end 105.349802 -16.718788)
		(width 0.14224)
		(layer "In9.Cu")
		(net "M_G_CS_N<0>")
	)
	(segment
		(start 105.687368 -21.1582)
		(end 105.760266 -21.085302)
		(width 0.14224)
		(layer "In9.Cu")
		(net "M_G_CS_N<0>")
	)
	(segment
		(start 105.687368 -21.6916)
		(end 105.687368 -21.1582)
		(width 0.14224)
		(layer "In9.Cu")
		(net "M_G_CS_N<0>")
	)
	(segment
		(start 102.690168 -25.5524)
		(end 105.839768 -22.4028)
		(width 0.14224)
		(layer "In9.Cu")
		(net "M_G_CS_N<0>")
	)
	(segment
		(start 105.839768 -22.4028)
		(end 105.839768 -21.844)
		(width 0.14224)
		(layer "In9.Cu")
		(net "M_G_CS_N<0>")
	)
	(segment
		(start 105.760266 -21.085302)
		(end 105.760266 -18.411698)
		(width 0.14224)
		(layer "In9.Cu")
		(net "M_G_CS_N<0>")
	)
	(segment
		(start 105.349294 -18.000726)
		(end 105.349294 -16.719296)
		(width 0.14224)
		(layer "In9.Cu")
		(net "M_G_CS_N<0>")
	)
	(segment
		(start 105.760266 -18.411698)
		(end 105.349294 -18.000726)
		(width 0.14224)
		(layer "In9.Cu")
		(net "M_G_CS_N<0>")
	)
	(segment
		(start 102.588314 -25.5524)
		(end 102.690168 -25.5524)
		(width 0.14224)
		(layer "In9.Cu")
		(net "M_G_CS_N<0>")
	)
	(segment
		(start 101.94925 -26.191464)
		(end 102.588314 -25.5524)
		(width 0.14224)
		(layer "In9.Cu")
		(net "M_G_CS_N<0>")
	)
	(segment
		(start 105.839768 -21.844)
		(end 105.687368 -21.6916)
		(width 0.14224)
		(layer "In9.Cu")
		(net "M_G_CS_N<0>")
	)
	(segment
		(start 92.268802 -22.568408)
		(end 92.268802 -22.435312)
		(width 0.1651)
		(layer "F.Cu")
		(net "M_G_CLK_DP<3>")
	)
	(segment
		(start 91.406218 -23.01494)
		(end 91.70416 -22.716998)
		(width 0.1651)
		(layer "F.Cu")
		(net "M_G_CLK_DP<3>")
	)
	(segment
		(start 91.304618 -24.099012)
		(end 91.406218 -23.997412)
		(width 0.1651)
		(layer "F.Cu")
		(net "M_G_CLK_DP<3>")
	)
	(segment
		(start 92.268802 -22.435312)
		(end 92.05849 -22.225)
		(width 0.1651)
		(layer "F.Cu")
		(net "M_G_CLK_DP<3>")
	)
	(segment
		(start 93.489018 -46.922182)
		(end 93.438218 -46.871382)
		(width 0.0889)
		(layer "F.Cu")
		(net "M_G_CLK_DP<3>")
	)
	(segment
		(start 92.120212 -22.716998)
		(end 92.268802 -22.568408)
		(width 0.1651)
		(layer "F.Cu")
		(net "M_G_CLK_DP<3>")
	)
	(segment
		(start 93.054678 -50.295556)
		(end 93.15196 -50.105818)
		(width 0.0889)
		(layer "F.Cu")
		(net "M_G_CLK_DP<3>")
	)
	(segment
		(start 92.932504 -50.307494)
		(end 93.04274 -50.307494)
		(width 0.0889)
		(layer "F.Cu")
		(net "M_G_CLK_DP<3>")
	)
	(segment
		(start 93.04274 -50.307494)
		(end 93.054678 -50.295556)
		(width 0.0889)
		(layer "F.Cu")
		(net "M_G_CLK_DP<3>")
	)
	(segment
		(start 91.406218 -23.997412)
		(end 91.406218 -23.01494)
		(width 0.1651)
		(layer "F.Cu")
		(net "M_G_CLK_DP<3>")
	)
	(segment
		(start 93.15196 -48.562768)
		(end 93.489018 -48.22571)
		(width 0.0889)
		(layer "F.Cu")
		(net "M_G_CLK_DP<3>")
	)
	(segment
		(start 93.489018 -48.22571)
		(end 93.489018 -46.922182)
		(width 0.0889)
		(layer "F.Cu")
		(net "M_G_CLK_DP<3>")
	)
	(segment
		(start 92.645738 -50.141886)
		(end 92.932504 -50.307494)
		(width 0.0889)
		(layer "F.Cu")
		(net "M_G_CLK_DP<3>")
	)
	(segment
		(start 93.438218 -30.448758)
		(end 91.897962 -28.908502)
		(width 0.1651)
		(layer "F.Cu")
		(net "M_G_CLK_DP<3>")
	)
	(segment
		(start 91.70416 -22.716998)
		(end 92.120212 -22.716998)
		(width 0.1651)
		(layer "F.Cu")
		(net "M_G_CLK_DP<3>")
	)
	(segment
		(start 91.897962 -28.908502)
		(end 91.304618 -28.315158)
		(width 0.1651)
		(layer "F.Cu")
		(net "M_G_CLK_DP<3>")
	)
	(segment
		(start 93.438218 -46.871382)
		(end 93.438218 -30.448758)
		(width 0.1651)
		(layer "F.Cu")
		(net "M_G_CLK_DP<3>")
	)
	(segment
		(start 91.304618 -28.315158)
		(end 91.304618 -24.099012)
		(width 0.1651)
		(layer "F.Cu")
		(net "M_G_CLK_DP<3>")
	)
	(segment
		(start 93.15196 -50.105818)
		(end 93.15196 -48.562768)
		(width 0.0889)
		(layer "F.Cu")
		(net "M_G_CLK_DP<3>")
	)
	(via
		(at 92.05849 -22.225)
		(size 0.508)
		(drill 0.254)
		(layers "F.Cu" "B.Cu")
		(net "M_G_CLK_DP<3>")
	)
	(via
		(at 91.897962 -28.908502)
		(size 0.508)
		(drill 0.254)
		(layers "F.Cu" "B.Cu")
		(net "M_G_CLK_DP<3>")
	)
	(segment
		(start 92.183966 -21.345144)
		(end 92.183966 -22.099524)
		(width 0.1651)
		(layer "B.Cu")
		(net "M_G_CLK_DP<3>")
	)
	(segment
		(start 91.749372 -20.224242)
		(end 91.749372 -20.91055)
		(width 0.1651)
		(layer "B.Cu")
		(net "M_G_CLK_DP<3>")
	)
	(segment
		(start 92.183966 -22.099524)
		(end 92.05849 -22.225)
		(width 0.1651)
		(layer "B.Cu")
		(net "M_G_CLK_DP<3>")
	)
	(segment
		(start 91.749372 -20.91055)
		(end 92.183966 -21.345144)
		(width 0.1651)
		(layer "B.Cu")
		(net "M_G_CLK_DP<3>")
	)
	(segment
		(start 94.08541 -21.6281)
		(end 94.339918 -21.882608)
		(width 0.1651)
		(layer "F.Cu")
		(net "M_G_CLK_DP<1>")
	)
	(segment
		(start 95.087694 -46.576742)
		(end 95.030798 -46.519846)
		(width 0.0889)
		(layer "F.Cu")
		(net "M_G_CLK_DP<1>")
	)
	(segment
		(start 95.49003 -47.828454)
		(end 95.57893 -47.739554)
		(width 0.0889)
		(layer "F.Cu")
		(net "M_G_CLK_DP<1>")
	)
	(segment
		(start 93.397832 -23.981918)
		(end 93.06179 -24.31796)
		(width 0.1651)
		(layer "F.Cu")
		(net "M_G_CLK_DP<1>")
	)
	(segment
		(start 94.859856 -50.207418)
		(end 94.859856 -49.821338)
		(width 0.0889)
		(layer "F.Cu")
		(net "M_G_CLK_DP<1>")
	)
	(segment
		(start 95.030798 -26.26741)
		(end 94.865698 -26.43251)
		(width 0.1651)
		(layer "F.Cu")
		(net "M_G_CLK_DP<1>")
	)
	(segment
		(start 94.339918 -21.882608)
		(end 94.339918 -22.568662)
		(width 0.1651)
		(layer "F.Cu")
		(net "M_G_CLK_DP<1>")
	)
	(segment
		(start 94.718886 -50.348388)
		(end 94.859856 -50.207418)
		(width 0.0889)
		(layer "F.Cu")
		(net "M_G_CLK_DP<1>")
	)
	(segment
		(start 94.541594 -48.883824)
		(end 94.884748 -48.54067)
		(width 0.0889)
		(layer "F.Cu")
		(net "M_G_CLK_DP<1>")
	)
	(segment
		(start 93.045534 -26.768552)
		(end 93.045534 -27.353768)
		(width 0.1651)
		(layer "F.Cu")
		(net "M_G_CLK_DP<1>")
	)
	(segment
		(start 95.030798 -26.018998)
		(end 95.030798 -26.26741)
		(width 0.1651)
		(layer "F.Cu")
		(net "M_G_CLK_DP<1>")
	)
	(segment
		(start 94.362778 -50.141886)
		(end 94.362778 -50.14341)
		(width 0.0889)
		(layer "F.Cu")
		(net "M_G_CLK_DP<1>")
	)
	(segment
		(start 95.49003 -47.231554)
		(end 95.2881 -47.231554)
		(width 0.0889)
		(layer "F.Cu")
		(net "M_G_CLK_DP<1>")
	)
	(segment
		(start 94.362778 -50.14341)
		(end 94.567756 -50.348388)
		(width 0.0889)
		(layer "F.Cu")
		(net "M_G_CLK_DP<1>")
	)
	(segment
		(start 93.06179 -25.400508)
		(end 93.397832 -25.73655)
		(width 0.1651)
		(layer "F.Cu")
		(net "M_G_CLK_DP<1>")
	)
	(segment
		(start 94.859856 -49.821338)
		(end 94.541594 -49.503076)
		(width 0.0889)
		(layer "F.Cu")
		(net "M_G_CLK_DP<1>")
	)
	(segment
		(start 93.381576 -27.68981)
		(end 94.865698 -27.68981)
		(width 0.1651)
		(layer "F.Cu")
		(net "M_G_CLK_DP<1>")
	)
	(segment
		(start 95.2881 -47.231554)
		(end 95.087694 -47.031148)
		(width 0.0889)
		(layer "F.Cu")
		(net "M_G_CLK_DP<1>")
	)
	(segment
		(start 94.649036 -23.981918)
		(end 93.397832 -23.981918)
		(width 0.1651)
		(layer "F.Cu")
		(net "M_G_CLK_DP<1>")
	)
	(segment
		(start 95.030798 -46.50867)
		(end 95.030798 -35.745928)
		(width 0.1651)
		(layer "F.Cu")
		(net "M_G_CLK_DP<1>")
	)
	(segment
		(start 94.79915 -23.027894)
		(end 94.79915 -23.831804)
		(width 0.1651)
		(layer "F.Cu")
		(net "M_G_CLK_DP<1>")
	)
	(segment
		(start 95.030798 -46.519846)
		(end 95.030798 -46.50867)
		(width 0.0889)
		(layer "F.Cu")
		(net "M_G_CLK_DP<1>")
	)
	(segment
		(start 91.749372 -20.023582)
		(end 91.749372 -20.678394)
		(width 0.1651)
		(layer "F.Cu")
		(net "M_G_CLK_DP<1>")
	)
	(segment
		(start 94.339918 -22.568662)
		(end 94.79915 -23.027894)
		(width 0.1651)
		(layer "F.Cu")
		(net "M_G_CLK_DP<1>")
	)
	(segment
		(start 94.884748 -48.54067)
		(end 94.884748 -48.067214)
		(width 0.0889)
		(layer "F.Cu")
		(net "M_G_CLK_DP<1>")
	)
	(segment
		(start 93.397832 -25.73655)
		(end 94.054168 -25.73655)
		(width 0.1651)
		(layer "F.Cu")
		(net "M_G_CLK_DP<1>")
	)
	(segment
		(start 93.045534 -27.353768)
		(end 93.381576 -27.68981)
		(width 0.1651)
		(layer "F.Cu")
		(net "M_G_CLK_DP<1>")
	)
	(segment
		(start 95.087694 -47.031148)
		(end 95.087694 -46.576742)
		(width 0.0889)
		(layer "F.Cu")
		(net "M_G_CLK_DP<1>")
	)
	(segment
		(start 92.364306 -21.6281)
		(end 94.08541 -21.6281)
		(width 0.1651)
		(layer "F.Cu")
		(net "M_G_CLK_DP<1>")
	)
	(segment
		(start 94.054168 -25.73655)
		(end 94.162118 -25.6286)
		(width 0.1651)
		(layer "F.Cu")
		(net "M_G_CLK_DP<1>")
	)
	(segment
		(start 95.57893 -47.320454)
		(end 95.49003 -47.231554)
		(width 0.0889)
		(layer "F.Cu")
		(net "M_G_CLK_DP<1>")
	)
	(segment
		(start 94.541594 -49.503076)
		(end 94.541594 -48.883824)
		(width 0.0889)
		(layer "F.Cu")
		(net "M_G_CLK_DP<1>")
	)
	(segment
		(start 94.6404 -25.6286)
		(end 95.030798 -26.018998)
		(width 0.1651)
		(layer "F.Cu")
		(net "M_G_CLK_DP<1>")
	)
	(segment
		(start 94.567756 -50.348388)
		(end 94.718886 -50.348388)
		(width 0.0889)
		(layer "F.Cu")
		(net "M_G_CLK_DP<1>")
	)
	(segment
		(start 93.06179 -24.31796)
		(end 93.06179 -25.400508)
		(width 0.1651)
		(layer "F.Cu")
		(net "M_G_CLK_DP<1>")
	)
	(segment
		(start 94.162118 -25.6286)
		(end 94.6404 -25.6286)
		(width 0.1651)
		(layer "F.Cu")
		(net "M_G_CLK_DP<1>")
	)
	(segment
		(start 93.381576 -26.43251)
		(end 93.045534 -26.768552)
		(width 0.1651)
		(layer "F.Cu")
		(net "M_G_CLK_DP<1>")
	)
	(segment
		(start 95.123508 -47.828454)
		(end 95.49003 -47.828454)
		(width 0.0889)
		(layer "F.Cu")
		(net "M_G_CLK_DP<1>")
	)
	(segment
		(start 95.57893 -47.739554)
		(end 95.57893 -47.320454)
		(width 0.0889)
		(layer "F.Cu")
		(net "M_G_CLK_DP<1>")
	)
	(segment
		(start 92.028264 -21.292058)
		(end 92.364306 -21.6281)
		(width 0.1651)
		(layer "F.Cu")
		(net "M_G_CLK_DP<1>")
	)
	(segment
		(start 94.884748 -48.067214)
		(end 95.123508 -47.828454)
		(width 0.0889)
		(layer "F.Cu")
		(net "M_G_CLK_DP<1>")
	)
	(segment
		(start 94.865698 -27.68981)
		(end 95.030798 -27.85491)
		(width 0.1651)
		(layer "F.Cu")
		(net "M_G_CLK_DP<1>")
	)
	(segment
		(start 92.028264 -20.957286)
		(end 92.028264 -21.292058)
		(width 0.1651)
		(layer "F.Cu")
		(net "M_G_CLK_DP<1>")
	)
	(segment
		(start 95.030798 -27.85491)
		(end 95.030798 -35.745928)
		(width 0.1651)
		(layer "F.Cu")
		(net "M_G_CLK_DP<1>")
	)
	(segment
		(start 94.79915 -23.831804)
		(end 94.649036 -23.981918)
		(width 0.1651)
		(layer "F.Cu")
		(net "M_G_CLK_DP<1>")
	)
	(segment
		(start 91.749372 -20.678394)
		(end 92.028264 -20.957286)
		(width 0.1651)
		(layer "F.Cu")
		(net "M_G_CLK_DP<1>")
	)
	(segment
		(start 94.865698 -26.43251)
		(end 93.381576 -26.43251)
		(width 0.1651)
		(layer "F.Cu")
		(net "M_G_CLK_DP<1>")
	)
	(via
		(at 95.030798 -35.745928)
		(size 0.508)
		(drill 0.254)
		(layers "F.Cu" "B.Cu")
		(net "M_G_CLK_DP<1>")
	)
	(segment
		(start 93.857064 -29.439108)
		(end 93.681042 -29.439108)
		(width 0.1651)
		(layer "F.Cu")
		(net "M_G_CLK_DP<2>")
	)
	(segment
		(start 93.382338 -28.964382)
		(end 92.249244 -27.831288)
		(width 0.1651)
		(layer "F.Cu")
		(net "M_G_CLK_DP<2>")
	)
	(segment
		(start 93.914468 -48.714152)
		(end 94.304104 -48.324516)
		(width 0.0889)
		(layer "F.Cu")
		(net "M_G_CLK_DP<2>")
	)
	(segment
		(start 92.249244 -27.831288)
		(end 92.249244 -27.435556)
		(width 0.1651)
		(layer "F.Cu")
		(net "M_G_CLK_DP<2>")
	)
	(segment
		(start 94.234508 -29.816552)
		(end 93.857064 -29.439108)
		(width 0.1651)
		(layer "F.Cu")
		(net "M_G_CLK_DP<2>")
	)
	(segment
		(start 94.234508 -46.402244)
		(end 94.234508 -29.816552)
		(width 0.1651)
		(layer "F.Cu")
		(net "M_G_CLK_DP<2>")
	)
	(segment
		(start 93.504258 -52.950618)
		(end 93.567504 -53.013864)
		(width 0.0889)
		(layer "F.Cu")
		(net "M_G_CLK_DP<2>")
	)
	(segment
		(start 92.249244 -24.50084)
		(end 92.249244 -23.595076)
		(width 0.1651)
		(layer "F.Cu")
		(net "M_G_CLK_DP<2>")
	)
	(segment
		(start 92.249244 -23.595076)
		(end 92.149168 -23.495)
		(width 0.1651)
		(layer "F.Cu")
		(net "M_G_CLK_DP<2>")
	)
	(segment
		(start 92.249244 -26.093674)
		(end 92.12453 -25.96896)
		(width 0.1651)
		(layer "F.Cu")
		(net "M_G_CLK_DP<2>")
	)
	(segment
		(start 93.681042 -29.439108)
		(end 93.382338 -29.140404)
		(width 0.1651)
		(layer "F.Cu")
		(net "M_G_CLK_DP<2>")
	)
	(segment
		(start 93.382338 -29.140404)
		(end 93.382338 -28.964382)
		(width 0.1651)
		(layer "F.Cu")
		(net "M_G_CLK_DP<2>")
	)
	(segment
		(start 92.12453 -25.96896)
		(end 92.12453 -25.591516)
		(width 0.1651)
		(layer "F.Cu")
		(net "M_G_CLK_DP<2>")
	)
	(segment
		(start 92.249244 -25.466802)
		(end 92.249244 -25.104852)
		(width 0.1651)
		(layer "F.Cu")
		(net "M_G_CLK_DP<2>")
	)
	(segment
		(start 92.249244 -25.104852)
		(end 92.124784 -24.980392)
		(width 0.1651)
		(layer "F.Cu")
		(net "M_G_CLK_DP<2>")
	)
	(segment
		(start 92.249244 -27.435556)
		(end 92.249244 -26.093674)
		(width 0.1651)
		(layer "F.Cu")
		(net "M_G_CLK_DP<2>")
	)
	(segment
		(start 92.124784 -24.6253)
		(end 92.249244 -24.50084)
		(width 0.1651)
		(layer "F.Cu")
		(net "M_G_CLK_DP<2>")
	)
	(segment
		(start 94.304104 -48.324516)
		(end 94.304104 -46.47184)
		(width 0.0889)
		(layer "F.Cu")
		(net "M_G_CLK_DP<2>")
	)
	(segment
		(start 92.12453 -25.591516)
		(end 92.249244 -25.466802)
		(width 0.1651)
		(layer "F.Cu")
		(net "M_G_CLK_DP<2>")
	)
	(segment
		(start 92.124784 -24.980392)
		(end 92.124784 -24.6253)
		(width 0.1651)
		(layer "F.Cu")
		(net "M_G_CLK_DP<2>")
	)
	(segment
		(start 93.77172 -50.137822)
		(end 93.772228 -50.137314)
		(width 0.0889)
		(layer "F.Cu")
		(net "M_G_CLK_DP<2>")
	)
	(segment
		(start 93.914468 -49.679606)
		(end 93.914468 -48.714152)
		(width 0.0889)
		(layer "F.Cu")
		(net "M_G_CLK_DP<2>")
	)
	(segment
		(start 93.772228 -50.137314)
		(end 93.772228 -49.821846)
		(width 0.0889)
		(layer "F.Cu")
		(net "M_G_CLK_DP<2>")
	)
	(segment
		(start 93.850968 -50.837592)
		(end 93.850968 -50.837846)
		(width 0.0889)
		(layer "F.Cu")
		(net "M_G_CLK_DP<2>")
	)
	(segment
		(start 94.304104 -46.47184)
		(end 94.234508 -46.402244)
		(width 0.0889)
		(layer "F.Cu")
		(net "M_G_CLK_DP<2>")
	)
	(segment
		(start 93.772228 -49.821846)
		(end 93.914468 -49.679606)
		(width 0.0889)
		(layer "F.Cu")
		(net "M_G_CLK_DP<2>")
	)
	(segment
		(start 93.504258 -52.618386)
		(end 93.504258 -52.950618)
		(width 0.0889)
		(layer "F.Cu")
		(net "M_G_CLK_DP<2>")
	)
	(via
		(at 92.149168 -23.495)
		(size 0.508)
		(drill 0.254)
		(layers "F.Cu" "B.Cu")
		(net "M_G_CLK_DP<2>")
	)
	(via
		(at 92.249244 -27.435556)
		(size 0.508)
		(drill 0.254)
		(layers "F.Cu" "B.Cu")
		(net "M_G_CLK_DP<2>")
	)
	(arc
		(start 93.850968 -52.418996)
		(mid 93.771837 -52.123594)
		(end 93.850968 -51.828192)
		(width 0.0889)
		(layer "F.Cu")
		(net "M_G_CLK_DP<2>")
	)
	(arc
		(start 93.567504 -53.013864)
		(mid 93.865559 -52.790871)
		(end 93.850968 -52.418996)
		(width 0.0889)
		(layer "F.Cu")
		(net "M_G_CLK_DP<2>")
	)
	(arc
		(start 93.850968 -50.837846)
		(mid 93.904594 -50.637694)
		(end 93.850968 -50.437542)
		(width 0.0889)
		(layer "F.Cu")
		(net "M_G_CLK_DP<2>")
	)
	(arc
		(start 93.850968 -50.437542)
		(mid 93.79132 -50.292974)
		(end 93.77172 -50.137822)
		(width 0.0889)
		(layer "F.Cu")
		(net "M_G_CLK_DP<2>")
	)
	(arc
		(start 93.850968 -51.428396)
		(mid 93.771837 -51.132994)
		(end 93.850968 -50.837592)
		(width 0.0889)
		(layer "F.Cu")
		(net "M_G_CLK_DP<2>")
	)
	(arc
		(start 93.850968 -51.828192)
		(mid 93.904467 -51.628294)
		(end 93.850968 -51.428396)
		(width 0.0889)
		(layer "F.Cu")
		(net "M_G_CLK_DP<2>")
	)
	(segment
		(start 91.749372 -23.894796)
		(end 92.149168 -23.495)
		(width 0.1651)
		(layer "B.Cu")
		(net "M_G_CLK_DP<2>")
	)
	(segment
		(start 91.749372 -24.824182)
		(end 91.749372 -23.894796)
		(width 0.1651)
		(layer "B.Cu")
		(net "M_G_CLK_DP<2>")
	)
	(segment
		(start 94.362778 -51.46421)
		(end 94.362778 -51.132486)
		(width 0.0889)
		(layer "F.Cu")
		(net "M_G_CLK_DP<0>")
	)
	(segment
		(start 95.827088 -27.436318)
		(end 95.827088 -29.716984)
		(width 0.1651)
		(layer "F.Cu")
		(net "M_G_CLK_DP<0>")
	)
	(segment
		(start 95.827088 -25.680416)
		(end 95.827088 -26.883106)
		(width 0.1651)
		(layer "F.Cu")
		(net "M_G_CLK_DP<0>")
	)
	(segment
		(start 95.846646 -22.165564)
		(end 95.55226 -22.876256)
		(width 0.1651)
		(layer "F.Cu")
		(net "M_G_CLK_DP<0>")
	)
	(segment
		(start 95.723456 -27.332686)
		(end 95.827088 -27.436318)
		(width 0.1651)
		(layer "F.Cu")
		(net "M_G_CLK_DP<0>")
	)
	(segment
		(start 91.749372 -15.423642)
		(end 91.749372 -16.567658)
		(width 0.1651)
		(layer "F.Cu")
		(net "M_G_CLK_DP<0>")
	)
	(segment
		(start 95.876872 -46.093888)
		(end 95.876872 -46.453552)
		(width 0.0889)
		(layer "F.Cu")
		(net "M_G_CLK_DP<0>")
	)
	(segment
		(start 95.926148 -19.451066)
		(end 95.926148 -20.032726)
		(width 0.1651)
		(layer "F.Cu")
		(net "M_G_CLK_DP<0>")
	)
	(segment
		(start 95.827088 -29.716984)
		(end 95.827088 -46.042072)
		(width 0.1651)
		(layer "F.Cu")
		(net "M_G_CLK_DP<0>")
	)
	(segment
		(start 95.804228 -20.154646)
		(end 95.804228 -20.649946)
		(width 0.1651)
		(layer "F.Cu")
		(net "M_G_CLK_DP<0>")
	)
	(segment
		(start 95.591376 -18.642838)
		(end 95.926148 -19.451066)
		(width 0.1651)
		(layer "F.Cu")
		(net "M_G_CLK_DP<0>")
	)
	(segment
		(start 95.232474 -51.03749)
		(end 95.199708 -51.03749)
		(width 0.0889)
		(layer "F.Cu")
		(net "M_G_CLK_DP<0>")
	)
	(segment
		(start 95.804228 -20.649946)
		(end 95.926148 -20.771866)
		(width 0.1651)
		(layer "F.Cu")
		(net "M_G_CLK_DP<0>")
	)
	(segment
		(start 95.827088 -26.883106)
		(end 95.723456 -26.986738)
		(width 0.1651)
		(layer "F.Cu")
		(net "M_G_CLK_DP<0>")
	)
	(segment
		(start 95.55226 -24.937466)
		(end 95.55226 -25.405588)
		(width 0.1651)
		(layer "F.Cu")
		(net "M_G_CLK_DP<0>")
	)
	(segment
		(start 95.926148 -20.032726)
		(end 95.804228 -20.154646)
		(width 0.1651)
		(layer "F.Cu")
		(net "M_G_CLK_DP<0>")
	)
	(segment
		(start 95.439484 -24.82469)
		(end 95.55226 -24.937466)
		(width 0.1651)
		(layer "F.Cu")
		(net "M_G_CLK_DP<0>")
	)
	(segment
		(start 95.827088 -46.044104)
		(end 95.876872 -46.093888)
		(width 0.0889)
		(layer "F.Cu")
		(net "M_G_CLK_DP<0>")
	)
	(segment
		(start 92.028264 -17.215612)
		(end 92.377768 -17.565116)
		(width 0.1651)
		(layer "F.Cu")
		(net "M_G_CLK_DP<0>")
	)
	(segment
		(start 95.55226 -25.405588)
		(end 95.827088 -25.680416)
		(width 0.1651)
		(layer "F.Cu")
		(net "M_G_CLK_DP<0>")
	)
	(segment
		(start 95.926148 -20.771866)
		(end 95.926148 -21.97354)
		(width 0.1651)
		(layer "F.Cu")
		(net "M_G_CLK_DP<0>")
	)
	(segment
		(start 96.164908 -46.741588)
		(end 96.164908 -48.216566)
		(width 0.0889)
		(layer "F.Cu")
		(net "M_G_CLK_DP<0>")
	)
	(segment
		(start 95.55226 -22.876256)
		(end 95.55226 -24.216614)
		(width 0.1651)
		(layer "F.Cu")
		(net "M_G_CLK_DP<0>")
	)
	(segment
		(start 92.377768 -17.565116)
		(end 92.988638 -17.8181)
		(width 0.1651)
		(layer "F.Cu")
		(net "M_G_CLK_DP<0>")
	)
	(segment
		(start 95.439484 -24.32939)
		(end 95.439484 -24.82469)
		(width 0.1651)
		(layer "F.Cu")
		(net "M_G_CLK_DP<0>")
	)
	(segment
		(start 94.426278 -51.52771)
		(end 94.362778 -51.46421)
		(width 0.0889)
		(layer "F.Cu")
		(net "M_G_CLK_DP<0>")
	)
	(segment
		(start 95.55226 -24.216614)
		(end 95.439484 -24.32939)
		(width 0.1651)
		(layer "F.Cu")
		(net "M_G_CLK_DP<0>")
	)
	(segment
		(start 95.445072 -48.936402)
		(end 95.445072 -50.224944)
		(width 0.0889)
		(layer "F.Cu")
		(net "M_G_CLK_DP<0>")
	)
	(segment
		(start 92.988638 -17.8181)
		(end 93.97492 -17.8181)
		(width 0.1651)
		(layer "F.Cu")
		(net "M_G_CLK_DP<0>")
	)
	(segment
		(start 95.3262 -18.377662)
		(end 95.591376 -18.642838)
		(width 0.1651)
		(layer "F.Cu")
		(net "M_G_CLK_DP<0>")
	)
	(segment
		(start 92.028264 -16.84655)
		(end 92.028264 -17.215612)
		(width 0.1651)
		(layer "F.Cu")
		(net "M_G_CLK_DP<0>")
	)
	(segment
		(start 91.749372 -16.567658)
		(end 92.028264 -16.84655)
		(width 0.1651)
		(layer "F.Cu")
		(net "M_G_CLK_DP<0>")
	)
	(segment
		(start 95.926148 -21.97354)
		(end 95.846646 -22.165564)
		(width 0.1651)
		(layer "F.Cu")
		(net "M_G_CLK_DP<0>")
	)
	(segment
		(start 95.445072 -50.224944)
		(end 95.568008 -50.437542)
		(width 0.0889)
		(layer "F.Cu")
		(net "M_G_CLK_DP<0>")
	)
	(segment
		(start 95.827088 -46.042072)
		(end 95.827088 -46.044104)
		(width 0.0889)
		(layer "F.Cu")
		(net "M_G_CLK_DP<0>")
	)
	(segment
		(start 95.723456 -26.986738)
		(end 95.723456 -27.332686)
		(width 0.1651)
		(layer "F.Cu")
		(net "M_G_CLK_DP<0>")
	)
	(segment
		(start 96.164908 -48.216566)
		(end 95.445072 -48.936402)
		(width 0.0889)
		(layer "F.Cu")
		(net "M_G_CLK_DP<0>")
	)
	(segment
		(start 93.97492 -17.8181)
		(end 95.3262 -18.377662)
		(width 0.1651)
		(layer "F.Cu")
		(net "M_G_CLK_DP<0>")
	)
	(segment
		(start 95.876872 -46.453552)
		(end 96.164908 -46.741588)
		(width 0.0889)
		(layer "F.Cu")
		(net "M_G_CLK_DP<0>")
	)
	(via
		(at 95.827088 -29.716984)
		(size 0.508)
		(drill 0.254)
		(layers "F.Cu" "B.Cu")
		(net "M_G_CLK_DP<0>")
	)
	(arc
		(start 94.709488 -51.332638)
		(mid 94.589905 -51.462155)
		(end 94.426278 -51.52771)
		(width 0.0889)
		(layer "F.Cu")
		(net "M_G_CLK_DP<0>")
	)
	(arc
		(start 95.568008 -50.437542)
		(mid 95.621485 -50.633233)
		(end 95.572072 -50.829972)
		(width 0.0889)
		(layer "F.Cu")
		(net "M_G_CLK_DP<0>")
	)
	(arc
		(start 95.199708 -51.03749)
		(mid 94.916491 -51.121771)
		(end 94.709488 -51.332638)
		(width 0.0889)
		(layer "F.Cu")
		(net "M_G_CLK_DP<0>")
	)
	(arc
		(start 95.572072 -50.829972)
		(mid 95.42989 -50.978908)
		(end 95.232474 -51.03749)
		(width 0.0889)
		(layer "F.Cu")
		(net "M_G_CLK_DP<0>")
	)
	(segment
		(start 91.825318 -23.009098)
		(end 92.24137 -23.009098)
		(width 0.1651)
		(layer "F.Cu")
		(net "M_G_CLK_DN<3>")
	)
	(segment
		(start 93.730318 -46.871382)
		(end 93.730318 -30.3276)
		(width 0.1651)
		(layer "F.Cu")
		(net "M_G_CLK_DN<3>")
	)
	(segment
		(start 93.679518 -46.94428)
		(end 93.730318 -46.89348)
		(width 0.0889)
		(layer "F.Cu")
		(net "M_G_CLK_DN<3>")
	)
	(segment
		(start 93.504258 -50.63744)
		(end 93.262704 -50.497994)
		(width 0.0889)
		(layer "F.Cu")
		(net "M_G_CLK_DN<3>")
	)
	(segment
		(start 92.560902 -22.433534)
		(end 92.769436 -22.225)
		(width 0.1651)
		(layer "F.Cu")
		(net "M_G_CLK_DN<3>")
	)
	(segment
		(start 91.596718 -28.194)
		(end 91.596718 -26.337006)
		(width 0.1651)
		(layer "F.Cu")
		(net "M_G_CLK_DN<3>")
	)
	(segment
		(start 93.262704 -50.497994)
		(end 93.227144 -50.37709)
		(width 0.0889)
		(layer "F.Cu")
		(net "M_G_CLK_DN<3>")
	)
	(segment
		(start 91.596718 -24.22017)
		(end 91.698318 -24.11857)
		(width 0.1651)
		(layer "F.Cu")
		(net "M_G_CLK_DN<3>")
	)
	(segment
		(start 92.24137 -23.009098)
		(end 92.560902 -22.689566)
		(width 0.1651)
		(layer "F.Cu")
		(net "M_G_CLK_DN<3>")
	)
	(segment
		(start 93.227144 -50.37709)
		(end 93.34246 -50.151792)
		(width 0.0889)
		(layer "F.Cu")
		(net "M_G_CLK_DN<3>")
	)
	(segment
		(start 93.730318 -30.3276)
		(end 91.596718 -28.194)
		(width 0.1651)
		(layer "F.Cu")
		(net "M_G_CLK_DN<3>")
	)
	(segment
		(start 93.679518 -48.304704)
		(end 93.679518 -46.94428)
		(width 0.0889)
		(layer "F.Cu")
		(net "M_G_CLK_DN<3>")
	)
	(segment
		(start 91.698318 -24.11857)
		(end 91.698318 -23.136098)
		(width 0.1651)
		(layer "F.Cu")
		(net "M_G_CLK_DN<3>")
	)
	(segment
		(start 91.596718 -26.337006)
		(end 91.596718 -24.22017)
		(width 0.1651)
		(layer "F.Cu")
		(net "M_G_CLK_DN<3>")
	)
	(segment
		(start 93.730318 -46.89348)
		(end 93.730318 -46.871382)
		(width 0.0889)
		(layer "F.Cu")
		(net "M_G_CLK_DN<3>")
	)
	(segment
		(start 91.698318 -23.136098)
		(end 91.825318 -23.009098)
		(width 0.1651)
		(layer "F.Cu")
		(net "M_G_CLK_DN<3>")
	)
	(segment
		(start 93.34246 -48.641762)
		(end 93.679518 -48.304704)
		(width 0.0889)
		(layer "F.Cu")
		(net "M_G_CLK_DN<3>")
	)
	(segment
		(start 92.560902 -22.689566)
		(end 92.560902 -22.433534)
		(width 0.1651)
		(layer "F.Cu")
		(net "M_G_CLK_DN<3>")
	)
	(segment
		(start 93.34246 -50.151792)
		(end 93.34246 -48.641762)
		(width 0.0889)
		(layer "F.Cu")
		(net "M_G_CLK_DN<3>")
	)
	(via
		(at 91.596718 -26.337006)
		(size 0.508)
		(drill 0.254)
		(layers "F.Cu" "B.Cu")
		(net "M_G_CLK_DN<3>")
	)
	(via
		(at 92.769436 -22.225)
		(size 0.508)
		(drill 0.254)
		(layers "F.Cu" "B.Cu")
		(net "M_G_CLK_DN<3>")
	)
	(segment
		(start 92.59951 -21.216112)
		(end 92.476066 -21.339556)
		(width 0.1651)
		(layer "B.Cu")
		(net "M_G_CLK_DN<3>")
	)
	(segment
		(start 92.476066 -21.339556)
		(end 92.476066 -21.93163)
		(width 0.1651)
		(layer "B.Cu")
		(net "M_G_CLK_DN<3>")
	)
	(segment
		(start 92.476066 -21.93163)
		(end 92.769436 -22.225)
		(width 0.1651)
		(layer "B.Cu")
		(net "M_G_CLK_DN<3>")
	)
	(segment
		(start 92.59951 -20.224242)
		(end 92.59951 -21.216112)
		(width 0.1651)
		(layer "B.Cu")
		(net "M_G_CLK_DN<3>")
	)
	(segment
		(start 95.202502 -48.018954)
		(end 95.569024 -48.018954)
		(width 0.0889)
		(layer "F.Cu")
		(net "M_G_CLK_DN<1>")
	)
	(segment
		(start 94.986856 -27.39771)
		(end 95.322898 -27.733752)
		(width 0.1651)
		(layer "F.Cu")
		(net "M_G_CLK_DN<1>")
	)
	(segment
		(start 95.075248 -48.619664)
		(end 95.075248 -48.146208)
		(width 0.0889)
		(layer "F.Cu")
		(net "M_G_CLK_DN<1>")
	)
	(segment
		(start 93.337634 -26.88971)
		(end 93.337634 -27.23261)
		(width 0.1651)
		(layer "F.Cu")
		(net "M_G_CLK_DN<1>")
	)
	(segment
		(start 95.322898 -46.50867)
		(end 95.322898 -32.434784)
		(width 0.1651)
		(layer "F.Cu")
		(net "M_G_CLK_DN<1>")
	)
	(segment
		(start 94.206568 -21.336)
		(end 94.632018 -21.76145)
		(width 0.1651)
		(layer "F.Cu")
		(net "M_G_CLK_DN<1>")
	)
	(segment
		(start 95.367094 -47.041054)
		(end 95.278194 -46.952154)
		(width 0.0889)
		(layer "F.Cu")
		(net "M_G_CLK_DN<1>")
	)
	(segment
		(start 93.337634 -27.23261)
		(end 93.502734 -27.39771)
		(width 0.1651)
		(layer "F.Cu")
		(net "M_G_CLK_DN<1>")
	)
	(segment
		(start 94.761558 -25.3365)
		(end 95.322898 -25.89784)
		(width 0.1651)
		(layer "F.Cu")
		(net "M_G_CLK_DN<1>")
	)
	(segment
		(start 95.76943 -47.24146)
		(end 95.569024 -47.041054)
		(width 0.0889)
		(layer "F.Cu")
		(net "M_G_CLK_DN<1>")
	)
	(segment
		(start 94.986856 -26.72461)
		(end 93.502734 -26.72461)
		(width 0.1651)
		(layer "F.Cu")
		(net "M_G_CLK_DN<1>")
	)
	(segment
		(start 92.59951 -20.61464)
		(end 92.320364 -20.893786)
		(width 0.1651)
		(layer "F.Cu")
		(net "M_G_CLK_DN<1>")
	)
	(segment
		(start 94.770194 -24.274018)
		(end 93.51899 -24.274018)
		(width 0.1651)
		(layer "F.Cu")
		(net "M_G_CLK_DN<1>")
	)
	(segment
		(start 95.050356 -50.286412)
		(end 95.050356 -49.742344)
		(width 0.0889)
		(layer "F.Cu")
		(net "M_G_CLK_DN<1>")
	)
	(segment
		(start 94.96806 -50.520092)
		(end 94.96806 -50.368708)
		(width 0.0889)
		(layer "F.Cu")
		(net "M_G_CLK_DN<1>")
	)
	(segment
		(start 92.320364 -21.1709)
		(end 92.485464 -21.336)
		(width 0.1651)
		(layer "F.Cu")
		(net "M_G_CLK_DN<1>")
	)
	(segment
		(start 94.96806 -50.368708)
		(end 95.050356 -50.286412)
		(width 0.0889)
		(layer "F.Cu")
		(net "M_G_CLK_DN<1>")
	)
	(segment
		(start 95.278194 -46.553374)
		(end 95.322898 -46.50867)
		(width 0.0889)
		(layer "F.Cu")
		(net "M_G_CLK_DN<1>")
	)
	(segment
		(start 95.085408 -50.63744)
		(end 94.96806 -50.520092)
		(width 0.0889)
		(layer "F.Cu")
		(net "M_G_CLK_DN<1>")
	)
	(segment
		(start 95.278194 -46.952154)
		(end 95.278194 -46.553374)
		(width 0.0889)
		(layer "F.Cu")
		(net "M_G_CLK_DN<1>")
	)
	(segment
		(start 95.322898 -25.89784)
		(end 95.322898 -26.388568)
		(width 0.1651)
		(layer "F.Cu")
		(net "M_G_CLK_DN<1>")
	)
	(segment
		(start 92.320364 -20.893786)
		(end 92.320364 -21.1709)
		(width 0.1651)
		(layer "F.Cu")
		(net "M_G_CLK_DN<1>")
	)
	(segment
		(start 93.502734 -26.72461)
		(end 93.337634 -26.88971)
		(width 0.1651)
		(layer "F.Cu")
		(net "M_G_CLK_DN<1>")
	)
	(segment
		(start 95.76943 -47.818548)
		(end 95.76943 -47.24146)
		(width 0.0889)
		(layer "F.Cu")
		(net "M_G_CLK_DN<1>")
	)
	(segment
		(start 94.04096 -25.3365)
		(end 94.761558 -25.3365)
		(width 0.1651)
		(layer "F.Cu")
		(net "M_G_CLK_DN<1>")
	)
	(segment
		(start 93.35389 -25.27935)
		(end 93.51899 -25.44445)
		(width 0.1651)
		(layer "F.Cu")
		(net "M_G_CLK_DN<1>")
	)
	(segment
		(start 92.59951 -20.023582)
		(end 92.59951 -20.61464)
		(width 0.1651)
		(layer "F.Cu")
		(net "M_G_CLK_DN<1>")
	)
	(segment
		(start 95.569024 -47.041054)
		(end 95.367094 -47.041054)
		(width 0.0889)
		(layer "F.Cu")
		(net "M_G_CLK_DN<1>")
	)
	(segment
		(start 93.51899 -24.274018)
		(end 93.35389 -24.439118)
		(width 0.1651)
		(layer "F.Cu")
		(net "M_G_CLK_DN<1>")
	)
	(segment
		(start 94.632018 -21.76145)
		(end 94.632018 -22.447504)
		(width 0.1651)
		(layer "F.Cu")
		(net "M_G_CLK_DN<1>")
	)
	(segment
		(start 95.569024 -48.018954)
		(end 95.76943 -47.818548)
		(width 0.0889)
		(layer "F.Cu")
		(net "M_G_CLK_DN<1>")
	)
	(segment
		(start 92.485464 -21.336)
		(end 94.206568 -21.336)
		(width 0.1651)
		(layer "F.Cu")
		(net "M_G_CLK_DN<1>")
	)
	(segment
		(start 94.632018 -22.447504)
		(end 95.09125 -22.906736)
		(width 0.1651)
		(layer "F.Cu")
		(net "M_G_CLK_DN<1>")
	)
	(segment
		(start 95.050356 -49.742344)
		(end 94.732094 -49.424082)
		(width 0.0889)
		(layer "F.Cu")
		(net "M_G_CLK_DN<1>")
	)
	(segment
		(start 95.322898 -26.388568)
		(end 94.986856 -26.72461)
		(width 0.1651)
		(layer "F.Cu")
		(net "M_G_CLK_DN<1>")
	)
	(segment
		(start 95.09125 -22.906736)
		(end 95.09125 -23.952962)
		(width 0.1651)
		(layer "F.Cu")
		(net "M_G_CLK_DN<1>")
	)
	(segment
		(start 95.322898 -27.733752)
		(end 95.322898 -32.434784)
		(width 0.1651)
		(layer "F.Cu")
		(net "M_G_CLK_DN<1>")
	)
	(segment
		(start 95.221298 -50.63744)
		(end 95.085408 -50.63744)
		(width 0.0889)
		(layer "F.Cu")
		(net "M_G_CLK_DN<1>")
	)
	(segment
		(start 93.51899 -25.44445)
		(end 93.93301 -25.44445)
		(width 0.1651)
		(layer "F.Cu")
		(net "M_G_CLK_DN<1>")
	)
	(segment
		(start 93.502734 -27.39771)
		(end 94.986856 -27.39771)
		(width 0.1651)
		(layer "F.Cu")
		(net "M_G_CLK_DN<1>")
	)
	(segment
		(start 95.09125 -23.952962)
		(end 94.770194 -24.274018)
		(width 0.1651)
		(layer "F.Cu")
		(net "M_G_CLK_DN<1>")
	)
	(segment
		(start 93.93301 -25.44445)
		(end 94.04096 -25.3365)
		(width 0.1651)
		(layer "F.Cu")
		(net "M_G_CLK_DN<1>")
	)
	(segment
		(start 95.075248 -48.146208)
		(end 95.202502 -48.018954)
		(width 0.0889)
		(layer "F.Cu")
		(net "M_G_CLK_DN<1>")
	)
	(segment
		(start 93.35389 -24.439118)
		(end 93.35389 -25.27935)
		(width 0.1651)
		(layer "F.Cu")
		(net "M_G_CLK_DN<1>")
	)
	(segment
		(start 94.732094 -48.962818)
		(end 95.075248 -48.619664)
		(width 0.0889)
		(layer "F.Cu")
		(net "M_G_CLK_DN<1>")
	)
	(segment
		(start 94.732094 -49.424082)
		(end 94.732094 -48.962818)
		(width 0.0889)
		(layer "F.Cu")
		(net "M_G_CLK_DN<1>")
	)
	(via
		(at 95.322898 -32.434784)
		(size 0.508)
		(drill 0.254)
		(layers "F.Cu" "B.Cu")
		(net "M_G_CLK_DN<1>")
	)
	(segment
		(start 92.541344 -27.71013)
		(end 92.541344 -23.817834)
		(width 0.1651)
		(layer "F.Cu")
		(net "M_G_CLK_DN<2>")
	)
	(segment
		(start 93.962728 -49.90084)
		(end 94.104968 -49.7586)
		(width 0.0889)
		(layer "F.Cu")
		(net "M_G_CLK_DN<2>")
	)
	(segment
		(start 94.494604 -48.40351)
		(end 94.494604 -46.439328)
		(width 0.0889)
		(layer "F.Cu")
		(net "M_G_CLK_DN<2>")
	)
	(segment
		(start 94.104968 -48.793146)
		(end 94.494604 -48.40351)
		(width 0.0889)
		(layer "F.Cu")
		(net "M_G_CLK_DN<2>")
	)
	(segment
		(start 93.962728 -50.139346)
		(end 93.962728 -49.90084)
		(width 0.0889)
		(layer "F.Cu")
		(net "M_G_CLK_DN<2>")
	)
	(segment
		(start 93.504258 -53.60924)
		(end 93.504258 -53.27777)
		(width 0.0889)
		(layer "F.Cu")
		(net "M_G_CLK_DN<2>")
	)
	(segment
		(start 94.526608 -29.695394)
		(end 94.029022 -29.197808)
		(width 0.1651)
		(layer "F.Cu")
		(net "M_G_CLK_DN<2>")
	)
	(segment
		(start 94.029022 -29.197808)
		(end 92.541344 -27.71013)
		(width 0.1651)
		(layer "F.Cu")
		(net "M_G_CLK_DN<2>")
	)
	(segment
		(start 92.541344 -23.817834)
		(end 92.864178 -23.495)
		(width 0.1651)
		(layer "F.Cu")
		(net "M_G_CLK_DN<2>")
	)
	(segment
		(start 93.504258 -53.27777)
		(end 93.576394 -53.205634)
		(width 0.0889)
		(layer "F.Cu")
		(net "M_G_CLK_DN<2>")
	)
	(segment
		(start 94.526608 -46.407324)
		(end 94.526608 -29.695394)
		(width 0.1651)
		(layer "F.Cu")
		(net "M_G_CLK_DN<2>")
	)
	(segment
		(start 94.104968 -49.7586)
		(end 94.104968 -48.793146)
		(width 0.0889)
		(layer "F.Cu")
		(net "M_G_CLK_DN<2>")
	)
	(segment
		(start 94.494604 -46.439328)
		(end 94.526608 -46.407324)
		(width 0.0889)
		(layer "F.Cu")
		(net "M_G_CLK_DN<2>")
	)
	(via
		(at 92.864178 -23.495)
		(size 0.508)
		(drill 0.254)
		(layers "F.Cu" "B.Cu")
		(net "M_G_CLK_DN<2>")
	)
	(via
		(at 94.029022 -29.197808)
		(size 0.508)
		(drill 0.254)
		(layers "F.Cu" "B.Cu")
		(net "M_G_CLK_DN<2>")
	)
	(arc
		(start 94.016068 -52.323492)
		(mid 93.962569 -52.123594)
		(end 94.016068 -51.923696)
		(width 0.0889)
		(layer "F.Cu")
		(net "M_G_CLK_DN<2>")
	)
	(arc
		(start 93.59773 -53.202586)
		(mid 94.038003 -52.872961)
		(end 94.016068 -52.323492)
		(width 0.0889)
		(layer "F.Cu")
		(net "M_G_CLK_DN<2>")
	)
	(arc
		(start 94.016068 -51.923696)
		(mid 94.095199 -51.628294)
		(end 94.016068 -51.332892)
		(width 0.0889)
		(layer "F.Cu")
		(net "M_G_CLK_DN<2>")
	)
	(arc
		(start 94.016068 -50.933096)
		(mid 94.095199 -50.637694)
		(end 94.016068 -50.342292)
		(width 0.0889)
		(layer "F.Cu")
		(net "M_G_CLK_DN<2>")
	)
	(arc
		(start 94.016068 -50.342292)
		(mid 93.975846 -50.24438)
		(end 93.962728 -50.139346)
		(width 0.0889)
		(layer "F.Cu")
		(net "M_G_CLK_DN<2>")
	)
	(arc
		(start 93.576394 -53.205634)
		(mid 93.587076 -53.204207)
		(end 93.59773 -53.202586)
		(width 0.0889)
		(layer "F.Cu")
		(net "M_G_CLK_DN<2>")
	)
	(arc
		(start 94.016068 -51.332892)
		(mid 93.962569 -51.132994)
		(end 94.016068 -50.933096)
		(width 0.0889)
		(layer "F.Cu")
		(net "M_G_CLK_DN<2>")
	)
	(segment
		(start 92.59951 -24.824182)
		(end 92.59951 -23.759668)
		(width 0.1651)
		(layer "B.Cu")
		(net "M_G_CLK_DN<2>")
	)
	(segment
		(start 92.59951 -23.759668)
		(end 92.864178 -23.495)
		(width 0.1651)
		(layer "B.Cu")
		(net "M_G_CLK_DN<2>")
	)
	(segment
		(start 95.635572 -49.015396)
		(end 95.635572 -50.173636)
		(width 0.0889)
		(layer "F.Cu")
		(net "M_G_CLK_DN<0>")
	)
	(segment
		(start 94.033086 -17.526)
		(end 95.491808 -18.129758)
		(width 0.1651)
		(layer "F.Cu")
		(net "M_G_CLK_DN<0>")
	)
	(segment
		(start 96.218248 -19.3929)
		(end 96.218248 -22.031706)
		(width 0.1651)
		(layer "F.Cu")
		(net "M_G_CLK_DN<0>")
	)
	(segment
		(start 96.067372 -46.374558)
		(end 96.355408 -46.662594)
		(width 0.0889)
		(layer "F.Cu")
		(net "M_G_CLK_DN<0>")
	)
	(segment
		(start 96.119188 -25.559258)
		(end 96.119188 -27.05227)
		(width 0.1651)
		(layer "F.Cu")
		(net "M_G_CLK_DN<0>")
	)
	(segment
		(start 96.162876 -22.165564)
		(end 95.84436 -22.934422)
		(width 0.1651)
		(layer "F.Cu")
		(net "M_G_CLK_DN<0>")
	)
	(segment
		(start 95.84436 -25.28443)
		(end 96.119188 -25.559258)
		(width 0.1651)
		(layer "F.Cu")
		(net "M_G_CLK_DN<0>")
	)
	(segment
		(start 93.046804 -17.526)
		(end 94.033086 -17.526)
		(width 0.1651)
		(layer "F.Cu")
		(net "M_G_CLK_DN<0>")
	)
	(segment
		(start 92.59951 -16.542258)
		(end 92.320364 -16.821404)
		(width 0.1651)
		(layer "F.Cu")
		(net "M_G_CLK_DN<0>")
	)
	(segment
		(start 95.84436 -22.934422)
		(end 95.84436 -25.28443)
		(width 0.1651)
		(layer "F.Cu")
		(net "M_G_CLK_DN<0>")
	)
	(segment
		(start 94.362778 -51.791616)
		(end 94.362778 -52.12334)
		(width 0.0889)
		(layer "F.Cu")
		(net "M_G_CLK_DN<0>")
	)
	(segment
		(start 95.491808 -18.129758)
		(end 95.83928 -18.47723)
		(width 0.1651)
		(layer "F.Cu")
		(net "M_G_CLK_DN<0>")
	)
	(segment
		(start 96.067372 -46.112938)
		(end 96.067372 -46.374558)
		(width 0.0889)
		(layer "F.Cu")
		(net "M_G_CLK_DN<0>")
	)
	(segment
		(start 96.119188 -27.05227)
		(end 96.119188 -46.041564)
		(width 0.1651)
		(layer "F.Cu")
		(net "M_G_CLK_DN<0>")
	)
	(segment
		(start 95.635572 -50.173636)
		(end 95.732854 -50.341784)
		(width 0.0889)
		(layer "F.Cu")
		(net "M_G_CLK_DN<0>")
	)
	(segment
		(start 96.119188 -46.061122)
		(end 96.067372 -46.112938)
		(width 0.0889)
		(layer "F.Cu")
		(net "M_G_CLK_DN<0>")
	)
	(segment
		(start 95.83928 -18.47723)
		(end 96.218248 -19.3929)
		(width 0.1651)
		(layer "F.Cu")
		(net "M_G_CLK_DN<0>")
	)
	(segment
		(start 96.218248 -22.031706)
		(end 96.162876 -22.165564)
		(width 0.1651)
		(layer "F.Cu")
		(net "M_G_CLK_DN<0>")
	)
	(segment
		(start 94.435422 -51.718972)
		(end 94.362778 -51.791616)
		(width 0.0889)
		(layer "F.Cu")
		(net "M_G_CLK_DN<0>")
	)
	(segment
		(start 96.355408 -48.29556)
		(end 95.635572 -49.015396)
		(width 0.0889)
		(layer "F.Cu")
		(net "M_G_CLK_DN<0>")
	)
	(segment
		(start 95.239078 -51.22799)
		(end 95.206312 -51.22799)
		(width 0.0889)
		(layer "F.Cu")
		(net "M_G_CLK_DN<0>")
	)
	(segment
		(start 92.320364 -17.094454)
		(end 92.543376 -17.317212)
		(width 0.1651)
		(layer "F.Cu")
		(net "M_G_CLK_DN<0>")
	)
	(segment
		(start 95.732854 -50.341784)
		(end 95.733108 -50.342038)
		(width 0.0889)
		(layer "F.Cu")
		(net "M_G_CLK_DN<0>")
	)
	(segment
		(start 92.320364 -16.821404)
		(end 92.320364 -17.094454)
		(width 0.1651)
		(layer "F.Cu")
		(net "M_G_CLK_DN<0>")
	)
	(segment
		(start 96.355408 -46.662594)
		(end 96.355408 -48.29556)
		(width 0.0889)
		(layer "F.Cu")
		(net "M_G_CLK_DN<0>")
	)
	(segment
		(start 96.119188 -46.041564)
		(end 96.119188 -46.061122)
		(width 0.0889)
		(layer "F.Cu")
		(net "M_G_CLK_DN<0>")
	)
	(segment
		(start 92.59951 -15.423642)
		(end 92.59951 -16.542258)
		(width 0.1651)
		(layer "F.Cu")
		(net "M_G_CLK_DN<0>")
	)
	(segment
		(start 92.543376 -17.317212)
		(end 93.046804 -17.526)
		(width 0.1651)
		(layer "F.Cu")
		(net "M_G_CLK_DN<0>")
	)
	(via
		(at 96.119188 -27.05227)
		(size 0.508)
		(drill 0.254)
		(layers "F.Cu" "B.Cu")
		(net "M_G_CLK_DN<0>")
	)
	(arc
		(start 94.874588 -51.427888)
		(mid 94.69806 -51.619105)
		(end 94.456504 -51.715924)
		(width 0.0889)
		(layer "F.Cu")
		(net "M_G_CLK_DN<0>")
	)
	(arc
		(start 95.739458 -50.92192)
		(mid 95.529943 -51.141474)
		(end 95.239078 -51.22799)
		(width 0.0889)
		(layer "F.Cu")
		(net "M_G_CLK_DN<0>")
	)
	(arc
		(start 95.733108 -50.342038)
		(mid 95.81233 -50.631156)
		(end 95.739458 -50.92192)
		(width 0.0889)
		(layer "F.Cu")
		(net "M_G_CLK_DN<0>")
	)
	(arc
		(start 94.456504 -51.715924)
		(mid 94.445977 -51.717542)
		(end 94.435422 -51.718972)
		(width 0.0889)
		(layer "F.Cu")
		(net "M_G_CLK_DN<0>")
	)
	(arc
		(start 95.206312 -51.22799)
		(mid 95.01467 -51.285156)
		(end 94.874588 -51.427888)
		(width 0.0889)
		(layer "F.Cu")
		(net "M_G_CLK_DN<0>")
	)
	(segment
		(start 82.471768 -30.734)
		(end 82.471768 -29.180028)
		(width 0.1651)
		(layer "F.Cu")
		(net "M_G_CKE<3>")
	)
	(segment
		(start 87.494872 -50.844958)
		(end 86.992968 -50.343054)
		(width 0.0889)
		(layer "F.Cu")
		(net "M_G_CKE<3>")
	)
	(segment
		(start 80.744568 -26.797)
		(end 80.744568 -26.491946)
		(width 0.1651)
		(layer "F.Cu")
		(net "M_G_CKE<3>")
	)
	(segment
		(start 82.471768 -28.5242)
		(end 80.744568 -26.797)
		(width 0.1651)
		(layer "F.Cu")
		(net "M_G_CKE<3>")
	)
	(segment
		(start 87.143082 -49.583086)
		(end 87.143082 -48.78324)
		(width 0.0889)
		(layer "F.Cu")
		(net "M_G_CKE<3>")
	)
	(segment
		(start 79.499968 -23.0378)
		(end 79.499968 -22.6568)
		(width 0.1651)
		(layer "F.Cu")
		(net "M_G_CKE<3>")
	)
	(segment
		(start 79.322168 -21.84019)
		(end 78.999334 -21.517356)
		(width 0.1651)
		(layer "F.Cu")
		(net "M_G_CKE<3>")
	)
	(segment
		(start 79.499968 -22.6568)
		(end 79.322168 -22.479)
		(width 0.1651)
		(layer "F.Cu")
		(net "M_G_CKE<3>")
	)
	(segment
		(start 86.433914 -46.852078)
		(end 86.379558 -46.797722)
		(width 0.0889)
		(layer "F.Cu")
		(net "M_G_CKE<3>")
	)
	(segment
		(start 79.322168 -22.479)
		(end 79.322168 -21.84019)
		(width 0.1651)
		(layer "F.Cu")
		(net "M_G_CKE<3>")
	)
	(segment
		(start 79.296768 -25.044146)
		(end 79.296768 -23.241)
		(width 0.1651)
		(layer "F.Cu")
		(net "M_G_CKE<3>")
	)
	(segment
		(start 86.992968 -49.7332)
		(end 87.143082 -49.583086)
		(width 0.0889)
		(layer "F.Cu")
		(net "M_G_CKE<3>")
	)
	(segment
		(start 86.433914 -48.074072)
		(end 86.433914 -46.852078)
		(width 0.0889)
		(layer "F.Cu")
		(net "M_G_CKE<3>")
	)
	(segment
		(start 86.379558 -34.64179)
		(end 82.471768 -30.734)
		(width 0.1651)
		(layer "F.Cu")
		(net "M_G_CKE<3>")
	)
	(segment
		(start 87.143082 -48.78324)
		(end 86.433914 -48.074072)
		(width 0.0889)
		(layer "F.Cu")
		(net "M_G_CKE<3>")
	)
	(segment
		(start 80.744568 -26.491946)
		(end 79.296768 -25.044146)
		(width 0.1651)
		(layer "F.Cu")
		(net "M_G_CKE<3>")
	)
	(segment
		(start 79.296768 -23.241)
		(end 79.499968 -23.0378)
		(width 0.1651)
		(layer "F.Cu")
		(net "M_G_CKE<3>")
	)
	(segment
		(start 86.379558 -46.338744)
		(end 86.379558 -34.64179)
		(width 0.1651)
		(layer "F.Cu")
		(net "M_G_CKE<3>")
	)
	(segment
		(start 82.471768 -29.180028)
		(end 82.471768 -28.5242)
		(width 0.1651)
		(layer "F.Cu")
		(net "M_G_CKE<3>")
	)
	(segment
		(start 86.992968 -50.343054)
		(end 86.992968 -49.7332)
		(width 0.0889)
		(layer "F.Cu")
		(net "M_G_CKE<3>")
	)
	(segment
		(start 87.494872 -51.132486)
		(end 87.494872 -50.844958)
		(width 0.0889)
		(layer "F.Cu")
		(net "M_G_CKE<3>")
	)
	(segment
		(start 86.379558 -46.797722)
		(end 86.379558 -46.338744)
		(width 0.0889)
		(layer "F.Cu")
		(net "M_G_CKE<3>")
	)
	(via
		(at 78.999334 -21.517356)
		(size 0.508)
		(drill 0.254)
		(layers "F.Cu" "B.Cu")
		(net "M_G_CKE<3>")
	)
	(via
		(at 82.471768 -29.180028)
		(size 0.508)
		(drill 0.254)
		(layers "F.Cu" "B.Cu")
		(net "M_G_CKE<3>")
	)
	(segment
		(start 78.999334 -21.517356)
		(end 78.999334 -20.224242)
		(width 0.1651)
		(layer "B.Cu")
		(net "M_G_CKE<3>")
	)
	(segment
		(start 83.005168 -30.505654)
		(end 86.883748 -34.384234)
		(width 0.1651)
		(layer "F.Cu")
		(net "M_G_CKE<2>")
	)
	(segment
		(start 79.849472 -23.534878)
		(end 79.849472 -24.682704)
		(width 0.1651)
		(layer "F.Cu")
		(net "M_G_CKE<2>")
	)
	(segment
		(start 83.005168 -28.1686)
		(end 83.005168 -30.505654)
		(width 0.1651)
		(layer "F.Cu")
		(net "M_G_CKE<2>")
	)
	(segment
		(start 86.883748 -46.385226)
		(end 86.883748 -47.864268)
		(width 0.0889)
		(layer "F.Cu")
		(net "M_G_CKE<2>")
	)
	(segment
		(start 81.290668 -26.1239)
		(end 81.290668 -26.4541)
		(width 0.1651)
		(layer "F.Cu")
		(net "M_G_CKE<2>")
	)
	(segment
		(start 79.849472 -24.682704)
		(end 81.290668 -26.1239)
		(width 0.1651)
		(layer "F.Cu")
		(net "M_G_CKE<2>")
	)
	(segment
		(start 81.290668 -26.4541)
		(end 82.307684 -27.471116)
		(width 0.1651)
		(layer "F.Cu")
		(net "M_G_CKE<2>")
	)
	(segment
		(start 87.675212 -48.655732)
		(end 87.675212 -49.961546)
		(width 0.0889)
		(layer "F.Cu")
		(net "M_G_CKE<2>")
	)
	(segment
		(start 86.883748 -47.864268)
		(end 87.675212 -48.655732)
		(width 0.0889)
		(layer "F.Cu")
		(net "M_G_CKE<2>")
	)
	(segment
		(start 86.883748 -34.384234)
		(end 86.883748 -46.385226)
		(width 0.1651)
		(layer "F.Cu")
		(net "M_G_CKE<2>")
	)
	(segment
		(start 87.675212 -49.961546)
		(end 87.494872 -50.141886)
		(width 0.0889)
		(layer "F.Cu")
		(net "M_G_CKE<2>")
	)
	(segment
		(start 82.307684 -27.471116)
		(end 83.005168 -28.1686)
		(width 0.1651)
		(layer "F.Cu")
		(net "M_G_CKE<2>")
	)
	(via
		(at 82.307684 -27.471116)
		(size 0.508)
		(drill 0.254)
		(layers "F.Cu" "B.Cu")
		(net "M_G_CKE<2>")
	)
	(via
		(at 79.849472 -23.534878)
		(size 0.508)
		(drill 0.254)
		(layers "F.Cu" "B.Cu")
		(net "M_G_CKE<2>")
	)
	(segment
		(start 79.849472 -23.534878)
		(end 79.849472 -24.824182)
		(width 0.1651)
		(layer "B.Cu")
		(net "M_G_CKE<2>")
	)
	(segment
		(start 78.483968 -23.0378)
		(end 78.788768 -23.3426)
		(width 0.1651)
		(layer "F.Cu")
		(net "M_G_CKE<1>")
	)
	(segment
		(start 86.561168 -48.860964)
		(end 86.561168 -50.562256)
		(width 0.0889)
		(layer "F.Cu")
		(net "M_G_CKE<1>")
	)
	(segment
		(start 86.005924 -47.00651)
		(end 86.005924 -48.30572)
		(width 0.0889)
		(layer "F.Cu")
		(net "M_G_CKE<1>")
	)
	(segment
		(start 86.561168 -50.562256)
		(end 86.636352 -50.63744)
		(width 0.0889)
		(layer "F.Cu")
		(net "M_G_CKE<1>")
	)
	(segment
		(start 78.407768 -21.6662)
		(end 78.737968 -21.9964)
		(width 0.1651)
		(layer "F.Cu")
		(net "M_G_CKE<1>")
	)
	(segment
		(start 85.875368 -35.091624)
		(end 85.875368 -46.371002)
		(width 0.1651)
		(layer "F.Cu")
		(net "M_G_CKE<1>")
	)
	(segment
		(start 80.236568 -27.051)
		(end 80.749648 -27.56408)
		(width 0.1651)
		(layer "F.Cu")
		(net "M_G_CKE<1>")
	)
	(segment
		(start 78.737968 -21.9964)
		(end 78.737968 -22.4536)
		(width 0.1651)
		(layer "F.Cu")
		(net "M_G_CKE<1>")
	)
	(segment
		(start 78.407768 -21.3614)
		(end 78.407768 -21.6662)
		(width 0.1651)
		(layer "F.Cu")
		(net "M_G_CKE<1>")
	)
	(segment
		(start 78.483968 -22.7076)
		(end 78.483968 -23.0378)
		(width 0.1651)
		(layer "F.Cu")
		(net "M_G_CKE<1>")
	)
	(segment
		(start 78.999334 -20.023582)
		(end 78.999334 -20.769834)
		(width 0.1651)
		(layer "F.Cu")
		(net "M_G_CKE<1>")
	)
	(segment
		(start 80.236568 -26.7208)
		(end 80.236568 -27.051)
		(width 0.1651)
		(layer "F.Cu")
		(net "M_G_CKE<1>")
	)
	(segment
		(start 78.737968 -22.4536)
		(end 78.483968 -22.7076)
		(width 0.1651)
		(layer "F.Cu")
		(net "M_G_CKE<1>")
	)
	(segment
		(start 80.749648 -27.56408)
		(end 81.963768 -28.7782)
		(width 0.1651)
		(layer "F.Cu")
		(net "M_G_CKE<1>")
	)
	(segment
		(start 78.788768 -23.3426)
		(end 78.788768 -25.273)
		(width 0.1651)
		(layer "F.Cu")
		(net "M_G_CKE<1>")
	)
	(segment
		(start 78.999334 -20.769834)
		(end 78.407768 -21.3614)
		(width 0.1651)
		(layer "F.Cu")
		(net "M_G_CKE<1>")
	)
	(segment
		(start 85.07222 -35.115246)
		(end 85.395562 -34.791904)
		(width 0.1651)
		(layer "F.Cu")
		(net "M_G_CKE<1>")
	)
	(segment
		(start 84.83219 -35.115246)
		(end 85.07222 -35.115246)
		(width 0.1651)
		(layer "F.Cu")
		(net "M_G_CKE<1>")
	)
	(segment
		(start 85.395562 -34.791904)
		(end 85.575648 -34.791904)
		(width 0.1651)
		(layer "F.Cu")
		(net "M_G_CKE<1>")
	)
	(segment
		(start 86.005924 -48.30572)
		(end 86.561168 -48.860964)
		(width 0.0889)
		(layer "F.Cu")
		(net "M_G_CKE<1>")
	)
	(segment
		(start 78.788768 -25.273)
		(end 80.236568 -26.7208)
		(width 0.1651)
		(layer "F.Cu")
		(net "M_G_CKE<1>")
	)
	(segment
		(start 85.015578 -34.03981)
		(end 85.015578 -34.219896)
		(width 0.1651)
		(layer "F.Cu")
		(net "M_G_CKE<1>")
	)
	(segment
		(start 84.589874 -34.6456)
		(end 84.589874 -34.87293)
		(width 0.1651)
		(layer "F.Cu")
		(net "M_G_CKE<1>")
	)
	(segment
		(start 85.875368 -46.875954)
		(end 86.005924 -47.00651)
		(width 0.0889)
		(layer "F.Cu")
		(net "M_G_CKE<1>")
	)
	(segment
		(start 81.963768 -30.988)
		(end 85.015578 -34.03981)
		(width 0.1651)
		(layer "F.Cu")
		(net "M_G_CKE<1>")
	)
	(segment
		(start 85.015578 -34.219896)
		(end 84.589874 -34.6456)
		(width 0.1651)
		(layer "F.Cu")
		(net "M_G_CKE<1>")
	)
	(segment
		(start 84.589874 -34.87293)
		(end 84.83219 -35.115246)
		(width 0.1651)
		(layer "F.Cu")
		(net "M_G_CKE<1>")
	)
	(segment
		(start 81.963768 -28.7782)
		(end 81.963768 -30.988)
		(width 0.1651)
		(layer "F.Cu")
		(net "M_G_CKE<1>")
	)
	(segment
		(start 85.875368 -46.371002)
		(end 85.875368 -46.875954)
		(width 0.0889)
		(layer "F.Cu")
		(net "M_G_CKE<1>")
	)
	(segment
		(start 85.575648 -34.791904)
		(end 85.875368 -35.091624)
		(width 0.1651)
		(layer "F.Cu")
		(net "M_G_CKE<1>")
	)
	(via
		(at 80.749648 -27.56408)
		(size 0.508)
		(drill 0.254)
		(layers "F.Cu" "B.Cu")
		(net "M_G_CKE<1>")
	)
	(segment
		(start 87.387938 -34.136838)
		(end 87.387938 -47.430944)
		(width 0.1651)
		(layer "F.Cu")
		(net "M_G_CKE<0>")
	)
	(segment
		(start 87.387938 -47.430944)
		(end 87.387938 -47.70882)
		(width 0.0889)
		(layer "F.Cu")
		(net "M_G_CKE<0>")
	)
	(segment
		(start 83.081368 -26.167334)
		(end 83.711542 -26.797508)
		(width 0.1651)
		(layer "F.Cu")
		(net "M_G_CKE<0>")
	)
	(segment
		(start 87.387938 -47.70882)
		(end 88.207342 -48.528224)
		(width 0.0889)
		(layer "F.Cu")
		(net "M_G_CKE<0>")
	)
	(segment
		(start 88.207342 -48.528224)
		(end 88.207342 -50.49139)
		(width 0.0889)
		(layer "F.Cu")
		(net "M_G_CKE<0>")
	)
	(segment
		(start 88.207342 -50.49139)
		(end 88.353392 -50.63744)
		(width 0.0889)
		(layer "F.Cu")
		(net "M_G_CKE<0>")
	)
	(segment
		(start 83.711542 -27.183588)
		(end 83.711542 -30.460442)
		(width 0.1651)
		(layer "F.Cu")
		(net "M_G_CKE<0>")
	)
	(segment
		(start 83.711542 -30.460442)
		(end 87.387938 -34.136838)
		(width 0.1651)
		(layer "F.Cu")
		(net "M_G_CKE<0>")
	)
	(segment
		(start 79.849472 -15.423642)
		(end 79.849472 -16.716756)
		(width 0.1651)
		(layer "F.Cu")
		(net "M_G_CKE<0>")
	)
	(segment
		(start 83.711542 -26.797508)
		(end 83.711542 -27.183588)
		(width 0.1651)
		(layer "F.Cu")
		(net "M_G_CKE<0>")
	)
	(via
		(at 83.711542 -27.183588)
		(size 0.508)
		(drill 0.254)
		(layers "F.Cu" "B.Cu")
		(net "M_G_CKE<0>")
	)
	(via
		(at 79.849472 -16.716756)
		(size 0.4572)
		(drill 0.2032)
		(layers "F.Cu" "B.Cu")
		(net "M_G_CKE<0>")
	)
	(via
		(at 83.081368 -26.167334)
		(size 0.508)
		(drill 0.254)
		(layers "F.Cu" "B.Cu")
		(net "M_G_CKE<0>")
	)
	(segment
		(start 80.566768 -23.778464)
		(end 80.566768 -23.4442)
		(width 0.14224)
		(layer "In11.Cu")
		(net "M_G_CKE<0>")
	)
	(segment
		(start 80.566768 -23.4442)
		(end 80.185768 -23.0632)
		(width 0.14224)
		(layer "In11.Cu")
		(net "M_G_CKE<0>")
	)
	(segment
		(start 79.849472 -17.977104)
		(end 79.849472 -16.716756)
		(width 0.14224)
		(layer "In11.Cu")
		(net "M_G_CKE<0>")
	)
	(segment
		(start 80.287114 -18.414746)
		(end 79.849472 -17.977104)
		(width 0.14224)
		(layer "In11.Cu")
		(net "M_G_CKE<0>")
	)
	(segment
		(start 80.185768 -23.0632)
		(end 80.185768 -22.6568)
		(width 0.14224)
		(layer "In11.Cu")
		(net "M_G_CKE<0>")
	)
	(segment
		(start 80.219804 -21.852636)
		(end 80.219804 -21.276564)
		(width 0.14224)
		(layer "In11.Cu")
		(net "M_G_CKE<0>")
	)
	(segment
		(start 80.185768 -22.6568)
		(end 80.388968 -22.4536)
		(width 0.14224)
		(layer "In11.Cu")
		(net "M_G_CKE<0>")
	)
	(segment
		(start 80.388968 -22.0218)
		(end 80.219804 -21.852636)
		(width 0.14224)
		(layer "In11.Cu")
		(net "M_G_CKE<0>")
	)
	(segment
		(start 82.491834 -25.5778)
		(end 82.366104 -25.5778)
		(width 0.14224)
		(layer "In11.Cu")
		(net "M_G_CKE<0>")
	)
	(segment
		(start 80.287114 -21.209254)
		(end 80.287114 -18.414746)
		(width 0.14224)
		(layer "In11.Cu")
		(net "M_G_CKE<0>")
	)
	(segment
		(start 83.081368 -26.167334)
		(end 82.491834 -25.5778)
		(width 0.14224)
		(layer "In11.Cu")
		(net "M_G_CKE<0>")
	)
	(segment
		(start 80.388968 -22.4536)
		(end 80.388968 -22.0218)
		(width 0.14224)
		(layer "In11.Cu")
		(net "M_G_CKE<0>")
	)
	(segment
		(start 80.219804 -21.276564)
		(end 80.287114 -21.209254)
		(width 0.14224)
		(layer "In11.Cu")
		(net "M_G_CKE<0>")
	)
	(segment
		(start 82.366104 -25.5778)
		(end 80.566768 -23.778464)
		(width 0.14224)
		(layer "In11.Cu")
		(net "M_G_CKE<0>")
	)
	(segment
		(start 111.299498 -18.734786)
		(end 111.300006 -18.734278)
		(width 0.10795)
		(layer "F.Cu")
		(net "M_G_C<2>")
	)
	(segment
		(start 111.299498 -20.023582)
		(end 111.299498 -18.734786)
		(width 0.10795)
		(layer "F.Cu")
		(net "M_G_C<2>")
	)
	(segment
		(start 102.089204 -52.618386)
		(end 101.517704 -52.618386)
		(width 0.1016)
		(layer "F.Cu")
		(net "M_G_C<2>")
	)
	(via
		(at 101.517704 -52.618386)
		(size 0.508)
		(drill 0.254)
		(layers "F.Cu" "B.Cu")
		(net "M_G_C<2>")
	)
	(via
		(at 111.300006 -18.734278)
		(size 0.4572)
		(drill 0.2032)
		(layers "F.Cu" "B.Cu")
		(net "M_G_C<2>")
	)
	(via
		(at 111.299498 -21.517356)
		(size 0.508)
		(drill 0.254)
		(layers "F.Cu" "B.Cu")
		(net "M_G_C<2>")
	)
	(segment
		(start 111.299498 -20.224242)
		(end 111.299498 -21.517356)
		(width 0.1651)
		(layer "B.Cu")
		(net "M_G_C<2>")
	)
	(segment
		(start 111.76381 -27.714194)
		(end 111.76381 -27.407108)
		(width 0.14224)
		(layer "In11.Cu")
		(net "M_G_C<2>")
	)
	(segment
		(start 111.005874 -27.083004)
		(end 111.005874 -26.587196)
		(width 0.14224)
		(layer "In11.Cu")
		(net "M_G_C<2>")
	)
	(segment
		(start 103.682292 -48.868076)
		(end 103.682292 -48.552354)
		(width 0.0889)
		(layer "In11.Cu")
		(net "M_G_C<2>")
	)
	(segment
		(start 111.76381 -27.407108)
		(end 111.59617 -27.239468)
		(width 0.14224)
		(layer "In11.Cu")
		(net "M_G_C<2>")
	)
	(segment
		(start 111.162338 -27.239468)
		(end 111.005874 -27.083004)
		(width 0.14224)
		(layer "In11.Cu")
		(net "M_G_C<2>")
	)
	(segment
		(start 111.181896 -26.411174)
		(end 111.588042 -26.411174)
		(width 0.14224)
		(layer "In11.Cu")
		(net "M_G_C<2>")
	)
	(segment
		(start 111.377222 -20.074382)
		(end 111.783368 -19.668236)
		(width 0.14224)
		(layer "In11.Cu")
		(net "M_G_C<2>")
	)
	(segment
		(start 111.681768 -22.5298)
		(end 111.681768 -22.250146)
		(width 0.14224)
		(layer "In11.Cu")
		(net "M_G_C<2>")
	)
	(segment
		(start 111.783368 -19.668236)
		(end 111.783368 -19.21764)
		(width 0.14224)
		(layer "In11.Cu")
		(net "M_G_C<2>")
	)
	(segment
		(start 111.783368 -19.21764)
		(end 111.300006 -18.734278)
		(width 0.14224)
		(layer "In11.Cu")
		(net "M_G_C<2>")
	)
	(segment
		(start 111.485934 -23.335234)
		(end 111.8743 -22.946868)
		(width 0.14224)
		(layer "In11.Cu")
		(net "M_G_C<2>")
	)
	(segment
		(start 111.757968 -24.321516)
		(end 111.485934 -24.049482)
		(width 0.14224)
		(layer "In11.Cu")
		(net "M_G_C<2>")
	)
	(segment
		(start 111.62919 -21.187664)
		(end 111.62919 -20.798536)
		(width 0.14224)
		(layer "In11.Cu")
		(net "M_G_C<2>")
	)
	(segment
		(start 111.005874 -26.587196)
		(end 111.181896 -26.411174)
		(width 0.14224)
		(layer "In11.Cu")
		(net "M_G_C<2>")
	)
	(segment
		(start 111.59617 -27.239468)
		(end 111.162338 -27.239468)
		(width 0.14224)
		(layer "In11.Cu")
		(net "M_G_C<2>")
	)
	(segment
		(start 111.485934 -24.049482)
		(end 111.485934 -23.335234)
		(width 0.14224)
		(layer "In11.Cu")
		(net "M_G_C<2>")
	)
	(segment
		(start 111.299498 -21.517356)
		(end 111.62919 -21.187664)
		(width 0.14224)
		(layer "In11.Cu")
		(net "M_G_C<2>")
	)
	(segment
		(start 111.681768 -22.250146)
		(end 111.453168 -22.021546)
		(width 0.14224)
		(layer "In11.Cu")
		(net "M_G_C<2>")
	)
	(segment
		(start 111.453168 -22.021546)
		(end 111.453168 -21.671026)
		(width 0.14224)
		(layer "In11.Cu")
		(net "M_G_C<2>")
	)
	(segment
		(start 111.757968 -26.241248)
		(end 111.757968 -24.321516)
		(width 0.14224)
		(layer "In11.Cu")
		(net "M_G_C<2>")
	)
	(segment
		(start 111.8743 -22.946868)
		(end 111.8743 -22.722332)
		(width 0.14224)
		(layer "In11.Cu")
		(net "M_G_C<2>")
	)
	(segment
		(start 102.156768 -50.3936)
		(end 103.682292 -48.868076)
		(width 0.0889)
		(layer "In11.Cu")
		(net "M_G_C<2>")
	)
	(segment
		(start 111.453168 -21.671026)
		(end 111.299498 -21.517356)
		(width 0.14224)
		(layer "In11.Cu")
		(net "M_G_C<2>")
	)
	(segment
		(start 111.377222 -20.546568)
		(end 111.377222 -20.074382)
		(width 0.14224)
		(layer "In11.Cu")
		(net "M_G_C<2>")
	)
	(segment
		(start 101.517704 -52.618386)
		(end 102.156768 -51.979322)
		(width 0.0889)
		(layer "In11.Cu")
		(net "M_G_C<2>")
	)
	(segment
		(start 103.682292 -48.552354)
		(end 103.682292 -35.795712)
		(width 0.14224)
		(layer "In11.Cu")
		(net "M_G_C<2>")
	)
	(segment
		(start 111.588042 -26.411174)
		(end 111.757968 -26.241248)
		(width 0.14224)
		(layer "In11.Cu")
		(net "M_G_C<2>")
	)
	(segment
		(start 102.156768 -51.979322)
		(end 102.156768 -50.3936)
		(width 0.0889)
		(layer "In11.Cu")
		(net "M_G_C<2>")
	)
	(segment
		(start 111.62919 -20.798536)
		(end 111.377222 -20.546568)
		(width 0.14224)
		(layer "In11.Cu")
		(net "M_G_C<2>")
	)
	(segment
		(start 111.8743 -22.722332)
		(end 111.681768 -22.5298)
		(width 0.14224)
		(layer "In11.Cu")
		(net "M_G_C<2>")
	)
	(segment
		(start 103.682292 -35.795712)
		(end 111.76381 -27.714194)
		(width 0.14224)
		(layer "In11.Cu")
		(net "M_G_C<2>")
	)
	(segment
		(start 82.399378 -20.023582)
		(end 82.399378 -18.734278)
		(width 0.1651)
		(layer "F.Cu")
		(net "M_G_BG<1>")
	)
	(segment
		(start 87.494872 -52.12334)
		(end 86.923372 -52.12334)
		(width 0.1016)
		(layer "F.Cu")
		(net "M_G_BG<1>")
	)
	(via
		(at 82.399378 -18.734278)
		(size 0.4572)
		(drill 0.2032)
		(layers "F.Cu" "B.Cu")
		(net "M_G_BG<1>")
	)
	(via
		(at 82.399378 -21.488146)
		(size 0.508)
		(drill 0.254)
		(layers "F.Cu" "B.Cu")
		(net "M_G_BG<1>")
	)
	(via
		(at 86.923372 -52.12334)
		(size 0.508)
		(drill 0.254)
		(layers "F.Cu" "B.Cu")
		(net "M_G_BG<1>")
	)
	(segment
		(start 82.399378 -20.224242)
		(end 82.399378 -21.488146)
		(width 0.1651)
		(layer "B.Cu")
		(net "M_G_BG<1>")
	)
	(segment
		(start 83.652868 -25.5905)
		(end 83.652868 -26.8732)
		(width 0.14224)
		(layer "In11.Cu")
		(net "M_G_BG<1>")
	)
	(segment
		(start 82.399378 -21.212302)
		(end 82.399378 -21.488146)
		(width 0.14224)
		(layer "In11.Cu")
		(net "M_G_BG<1>")
	)
	(segment
		(start 82.399378 -21.488146)
		(end 82.399378 -22.12721)
		(width 0.14224)
		(layer "In11.Cu")
		(net "M_G_BG<1>")
	)
	(segment
		(start 82.878168 -23.1648)
		(end 82.620358 -23.42261)
		(width 0.14224)
		(layer "In11.Cu")
		(net "M_G_BG<1>")
	)
	(segment
		(start 82.620358 -24.55799)
		(end 83.652868 -25.5905)
		(width 0.14224)
		(layer "In11.Cu")
		(net "M_G_BG<1>")
	)
	(segment
		(start 82.399378 -18.734278)
		(end 82.734658 -19.069558)
		(width 0.14224)
		(layer "In11.Cu")
		(net "M_G_BG<1>")
	)
	(segment
		(start 86.610952 -33.771078)
		(end 86.610952 -50.931826)
		(width 0.14224)
		(layer "In11.Cu")
		(net "M_G_BG<1>")
	)
	(segment
		(start 82.734658 -19.069558)
		(end 82.734658 -20.877022)
		(width 0.14224)
		(layer "In11.Cu")
		(net "M_G_BG<1>")
	)
	(segment
		(start 82.878168 -22.606)
		(end 82.878168 -23.1648)
		(width 0.14224)
		(layer "In11.Cu")
		(net "M_G_BG<1>")
	)
	(segment
		(start 82.620358 -23.42261)
		(end 82.620358 -24.55799)
		(width 0.14224)
		(layer "In11.Cu")
		(net "M_G_BG<1>")
	)
	(segment
		(start 86.610952 -51.1302)
		(end 86.923372 -52.12334)
		(width 0.0889)
		(layer "In11.Cu")
		(net "M_G_BG<1>")
	)
	(segment
		(start 82.649568 -29.809694)
		(end 86.610952 -33.771078)
		(width 0.14224)
		(layer "In11.Cu")
		(net "M_G_BG<1>")
	)
	(segment
		(start 82.399378 -22.12721)
		(end 82.878168 -22.606)
		(width 0.14224)
		(layer "In11.Cu")
		(net "M_G_BG<1>")
	)
	(segment
		(start 82.734658 -20.877022)
		(end 82.399378 -21.212302)
		(width 0.14224)
		(layer "In11.Cu")
		(net "M_G_BG<1>")
	)
	(segment
		(start 86.610952 -50.931826)
		(end 86.610952 -51.1302)
		(width 0.0889)
		(layer "In11.Cu")
		(net "M_G_BG<1>")
	)
	(segment
		(start 82.649568 -27.8765)
		(end 82.649568 -29.809694)
		(width 0.14224)
		(layer "In11.Cu")
		(net "M_G_BG<1>")
	)
	(segment
		(start 83.652868 -26.8732)
		(end 82.649568 -27.8765)
		(width 0.14224)
		(layer "In11.Cu")
		(net "M_G_BG<1>")
	)
	(segment
		(start 84.363306 -25.06345)
		(end 84.65058 -25.350724)
		(width 0.1651)
		(layer "F.Cu")
		(net "M_G_BG<0>")
	)
	(segment
		(start 88.821768 -49.8856)
		(end 88.821768 -50.179986)
		(width 0.0889)
		(layer "F.Cu")
		(net "M_G_BG<0>")
	)
	(segment
		(start 84.390484 -25.790652)
		(end 84.390484 -26.024332)
		(width 0.1651)
		(layer "F.Cu")
		(net "M_G_BG<0>")
	)
	(segment
		(start 82.399378 -22.850856)
		(end 82.399378 -24.125428)
		(width 0.1651)
		(layer "F.Cu")
		(net "M_G_BG<0>")
	)
	(segment
		(start 84.390484 -26.024332)
		(end 84.757768 -26.391616)
		(width 0.1651)
		(layer "F.Cu")
		(net "M_G_BG<0>")
	)
	(segment
		(start 83.678522 -24.454358)
		(end 83.678522 -24.63419)
		(width 0.1651)
		(layer "F.Cu")
		(net "M_G_BG<0>")
	)
	(segment
		(start 84.65058 -25.350724)
		(end 84.65058 -25.530556)
		(width 0.1651)
		(layer "F.Cu")
		(net "M_G_BG<0>")
	)
	(segment
		(start 84.757768 -30.001464)
		(end 88.396318 -33.640014)
		(width 0.1651)
		(layer "F.Cu")
		(net "M_G_BG<0>")
	)
	(segment
		(start 82.655918 -24.381968)
		(end 82.996532 -24.381968)
		(width 0.1651)
		(layer "F.Cu")
		(net "M_G_BG<0>")
	)
	(segment
		(start 83.391248 -24.167084)
		(end 83.678522 -24.454358)
		(width 0.1651)
		(layer "F.Cu")
		(net "M_G_BG<0>")
	)
	(segment
		(start 83.456272 -25.09012)
		(end 83.689698 -25.323546)
		(width 0.1651)
		(layer "F.Cu")
		(net "M_G_BG<0>")
	)
	(segment
		(start 89.024968 -49.6824)
		(end 88.821768 -49.8856)
		(width 0.0889)
		(layer "F.Cu")
		(net "M_G_BG<0>")
	)
	(segment
		(start 89.024968 -48.158654)
		(end 89.024968 -49.6824)
		(width 0.0889)
		(layer "F.Cu")
		(net "M_G_BG<0>")
	)
	(segment
		(start 84.757768 -27.98826)
		(end 84.757768 -30.001464)
		(width 0.1651)
		(layer "F.Cu")
		(net "M_G_BG<0>")
	)
	(segment
		(start 88.865202 -50.342038)
		(end 88.881966 -50.37074)
		(width 0.0889)
		(layer "F.Cu")
		(net "M_G_BG<0>")
	)
	(segment
		(start 83.923378 -25.323546)
		(end 84.183474 -25.06345)
		(width 0.1651)
		(layer "F.Cu")
		(net "M_G_BG<0>")
	)
	(segment
		(start 84.183474 -25.06345)
		(end 84.363306 -25.06345)
		(width 0.1651)
		(layer "F.Cu")
		(net "M_G_BG<0>")
	)
	(segment
		(start 83.456272 -24.85644)
		(end 83.456272 -25.09012)
		(width 0.1651)
		(layer "F.Cu")
		(net "M_G_BG<0>")
	)
	(segment
		(start 83.689698 -25.323546)
		(end 83.923378 -25.323546)
		(width 0.1651)
		(layer "F.Cu")
		(net "M_G_BG<0>")
	)
	(segment
		(start 82.996532 -24.381968)
		(end 83.211416 -24.167084)
		(width 0.1651)
		(layer "F.Cu")
		(net "M_G_BG<0>")
	)
	(segment
		(start 84.757768 -26.391616)
		(end 84.757768 -27.98826)
		(width 0.1651)
		(layer "F.Cu")
		(net "M_G_BG<0>")
	)
	(segment
		(start 82.399378 -24.125428)
		(end 82.655918 -24.381968)
		(width 0.1651)
		(layer "F.Cu")
		(net "M_G_BG<0>")
	)
	(segment
		(start 88.396318 -47.32274)
		(end 88.396318 -47.530004)
		(width 0.0889)
		(layer "F.Cu")
		(net "M_G_BG<0>")
	)
	(segment
		(start 83.211416 -24.167084)
		(end 83.391248 -24.167084)
		(width 0.1651)
		(layer "F.Cu")
		(net "M_G_BG<0>")
	)
	(segment
		(start 88.396318 -33.640014)
		(end 88.396318 -47.32274)
		(width 0.1651)
		(layer "F.Cu")
		(net "M_G_BG<0>")
	)
	(segment
		(start 88.396318 -47.530004)
		(end 89.024968 -48.158654)
		(width 0.0889)
		(layer "F.Cu")
		(net "M_G_BG<0>")
	)
	(segment
		(start 83.678522 -24.63419)
		(end 83.456272 -24.85644)
		(width 0.1651)
		(layer "F.Cu")
		(net "M_G_BG<0>")
	)
	(segment
		(start 88.881966 -50.37074)
		(end 89.211912 -51.132486)
		(width 0.0889)
		(layer "F.Cu")
		(net "M_G_BG<0>")
	)
	(segment
		(start 84.65058 -25.530556)
		(end 84.390484 -25.790652)
		(width 0.1651)
		(layer "F.Cu")
		(net "M_G_BG<0>")
	)
	(segment
		(start 82.399378 -15.423642)
		(end 82.399378 -16.716756)
		(width 0.1651)
		(layer "F.Cu")
		(net "M_G_BG<0>")
	)
	(via
		(at 82.399378 -16.716756)
		(size 0.4572)
		(drill 0.2032)
		(layers "F.Cu" "B.Cu")
		(net "M_G_BG<0>")
	)
	(via
		(at 84.757768 -27.98826)
		(size 0.508)
		(drill 0.254)
		(layers "F.Cu" "B.Cu")
		(net "M_G_BG<0>")
	)
	(via
		(at 82.399378 -22.850856)
		(size 0.508)
		(drill 0.254)
		(layers "F.Cu" "B.Cu")
		(net "M_G_BG<0>")
	)
	(arc
		(start 88.821768 -50.179986)
		(mid 88.832805 -50.263878)
		(end 88.865202 -50.342038)
		(width 0.0889)
		(layer "F.Cu")
		(net "M_G_BG<0>")
	)
	(segment
		(start 82.399378 -22.850856)
		(end 82.399378 -24.824182)
		(width 0.1651)
		(layer "B.Cu")
		(net "M_G_BG<0>")
	)
	(segment
		(start 81.966308 -20.098258)
		(end 81.811368 -19.943318)
		(width 0.14224)
		(layer "In9.Cu")
		(net "M_G_BG<0>")
	)
	(segment
		(start 82.236818 -20.761198)
		(end 82.363818 -20.634198)
		(width 0.14224)
		(layer "In9.Cu")
		(net "M_G_BG<0>")
	)
	(segment
		(start 82.236818 -20.098258)
		(end 81.966308 -20.098258)
		(width 0.14224)
		(layer "In9.Cu")
		(net "M_G_BG<0>")
	)
	(segment
		(start 81.811368 -19.359626)
		(end 81.98993 -19.181064)
		(width 0.14224)
		(layer "In9.Cu")
		(net "M_G_BG<0>")
	)
	(segment
		(start 82.291682 -18.197576)
		(end 82.738722 -18.197576)
		(width 0.14224)
		(layer "In9.Cu")
		(net "M_G_BG<0>")
	)
	(segment
		(start 82.399378 -22.25421)
		(end 81.811368 -21.6662)
		(width 0.14224)
		(layer "In9.Cu")
		(net "M_G_BG<0>")
	)
	(segment
		(start 82.911442 -17.574514)
		(end 82.399378 -17.06245)
		(width 0.14224)
		(layer "In9.Cu")
		(net "M_G_BG<0>")
	)
	(segment
		(start 82.399378 -22.850856)
		(end 82.399378 -22.25421)
		(width 0.14224)
		(layer "In9.Cu")
		(net "M_G_BG<0>")
	)
	(segment
		(start 81.811368 -20.916138)
		(end 81.966308 -20.761198)
		(width 0.14224)
		(layer "In9.Cu")
		(net "M_G_BG<0>")
	)
	(segment
		(start 82.738722 -18.197576)
		(end 82.911442 -18.024856)
		(width 0.14224)
		(layer "In9.Cu")
		(net "M_G_BG<0>")
	)
	(segment
		(start 81.966308 -20.761198)
		(end 82.236818 -20.761198)
		(width 0.14224)
		(layer "In9.Cu")
		(net "M_G_BG<0>")
	)
	(segment
		(start 82.911442 -18.024856)
		(end 82.911442 -17.574514)
		(width 0.14224)
		(layer "In9.Cu")
		(net "M_G_BG<0>")
	)
	(segment
		(start 82.363818 -20.225258)
		(end 82.236818 -20.098258)
		(width 0.14224)
		(layer "In9.Cu")
		(net "M_G_BG<0>")
	)
	(segment
		(start 81.811368 -19.943318)
		(end 81.811368 -19.359626)
		(width 0.14224)
		(layer "In9.Cu")
		(net "M_G_BG<0>")
	)
	(segment
		(start 82.399378 -17.06245)
		(end 82.399378 -16.716756)
		(width 0.14224)
		(layer "In9.Cu")
		(net "M_G_BG<0>")
	)
	(segment
		(start 81.811368 -21.6662)
		(end 81.811368 -20.916138)
		(width 0.14224)
		(layer "In9.Cu")
		(net "M_G_BG<0>")
	)
	(segment
		(start 82.363818 -20.634198)
		(end 82.363818 -20.225258)
		(width 0.14224)
		(layer "In9.Cu")
		(net "M_G_BG<0>")
	)
	(segment
		(start 81.98993 -18.499328)
		(end 82.291682 -18.197576)
		(width 0.14224)
		(layer "In9.Cu")
		(net "M_G_BG<0>")
	)
	(segment
		(start 81.98993 -19.181064)
		(end 81.98993 -18.499328)
		(width 0.14224)
		(layer "In9.Cu")
		(net "M_G_BG<0>")
	)
	(segment
		(start 101.949504 -18.734532)
		(end 101.949758 -18.734278)
		(width 0.1651)
		(layer "F.Cu")
		(net "M_G_BA<1>")
	)
	(segment
		(start 95.221298 -52.618386)
		(end 94.649798 -52.618386)
		(width 0.1016)
		(layer "F.Cu")
		(net "M_G_BA<1>")
	)
	(segment
		(start 101.949504 -20.023582)
		(end 101.949504 -18.734532)
		(width 0.1651)
		(layer "F.Cu")
		(net "M_G_BA<1>")
	)
	(via
		(at 101.94925 -22.197568)
		(size 0.508)
		(drill 0.254)
		(layers "F.Cu" "B.Cu")
		(net "M_G_BA<1>")
	)
	(via
		(at 94.649798 -52.618386)
		(size 0.508)
		(drill 0.254)
		(layers "F.Cu" "B.Cu")
		(net "M_G_BA<1>")
	)
	(via
		(at 101.949758 -18.734278)
		(size 0.4572)
		(drill 0.2032)
		(layers "F.Cu" "B.Cu")
		(net "M_G_BA<1>")
	)
	(segment
		(start 101.949504 -20.224242)
		(end 101.949504 -22.197314)
		(width 0.1651)
		(layer "B.Cu")
		(net "M_G_BA<1>")
	)
	(segment
		(start 101.949504 -22.197314)
		(end 101.94925 -22.197568)
		(width 0.1651)
		(layer "B.Cu")
		(net "M_G_BA<1>")
	)
	(segment
		(start 96.346772 -31.057596)
		(end 100.498148 -26.90622)
		(width 0.14224)
		(layer "In11.Cu")
		(net "M_G_BA<1>")
	)
	(segment
		(start 96.499172 -48.929036)
		(end 96.346772 -48.776636)
		(width 0.0889)
		(layer "In11.Cu")
		(net "M_G_BA<1>")
	)
	(segment
		(start 100.279454 -26.36393)
		(end 99.843844 -26.36393)
		(width 0.14224)
		(layer "In11.Cu")
		(net "M_G_BA<1>")
	)
	(segment
		(start 96.346772 -48.776636)
		(end 96.346772 -48.570642)
		(width 0.0889)
		(layer "In11.Cu")
		(net "M_G_BA<1>")
	)
	(segment
		(start 94.649798 -52.618386)
		(end 94.649798 -51.673252)
		(width 0.0889)
		(layer "In11.Cu")
		(net "M_G_BA<1>")
	)
	(segment
		(start 94.649798 -51.673252)
		(end 95.106236 -51.217068)
		(width 0.0889)
		(layer "In11.Cu")
		(net "M_G_BA<1>")
	)
	(segment
		(start 99.828604 -25.55113)
		(end 100.302568 -25.55113)
		(width 0.14224)
		(layer "In11.Cu")
		(net "M_G_BA<1>")
	)
	(segment
		(start 101.94925 -18.734786)
		(end 101.949758 -18.734278)
		(width 0.14224)
		(layer "In11.Cu")
		(net "M_G_BA<1>")
	)
	(segment
		(start 99.843844 -26.36393)
		(end 99.633024 -26.15311)
		(width 0.14224)
		(layer "In11.Cu")
		(net "M_G_BA<1>")
	)
	(segment
		(start 99.633024 -25.74671)
		(end 99.828604 -25.55113)
		(width 0.14224)
		(layer "In11.Cu")
		(net "M_G_BA<1>")
	)
	(segment
		(start 96.499172 -49.823878)
		(end 96.499172 -48.929036)
		(width 0.0889)
		(layer "In11.Cu")
		(net "M_G_BA<1>")
	)
	(segment
		(start 100.498148 -26.90622)
		(end 100.498148 -26.582624)
		(width 0.14224)
		(layer "In11.Cu")
		(net "M_G_BA<1>")
	)
	(segment
		(start 100.498148 -26.582624)
		(end 100.279454 -26.36393)
		(width 0.14224)
		(layer "In11.Cu")
		(net "M_G_BA<1>")
	)
	(segment
		(start 101.674168 -23.1394)
		(end 101.674168 -22.47265)
		(width 0.14224)
		(layer "In11.Cu")
		(net "M_G_BA<1>")
	)
	(segment
		(start 100.302568 -25.55113)
		(end 100.505768 -25.34793)
		(width 0.14224)
		(layer "In11.Cu")
		(net "M_G_BA<1>")
	)
	(segment
		(start 100.505768 -24.3078)
		(end 101.674168 -23.1394)
		(width 0.14224)
		(layer "In11.Cu")
		(net "M_G_BA<1>")
	)
	(segment
		(start 101.674168 -22.47265)
		(end 101.94925 -22.197568)
		(width 0.14224)
		(layer "In11.Cu")
		(net "M_G_BA<1>")
	)
	(segment
		(start 100.505768 -25.34793)
		(end 100.505768 -24.3078)
		(width 0.14224)
		(layer "In11.Cu")
		(net "M_G_BA<1>")
	)
	(segment
		(start 96.346772 -48.570642)
		(end 96.346772 -31.057596)
		(width 0.14224)
		(layer "In11.Cu")
		(net "M_G_BA<1>")
	)
	(segment
		(start 95.106236 -51.217068)
		(end 96.499172 -49.823878)
		(width 0.0889)
		(layer "In11.Cu")
		(net "M_G_BA<1>")
	)
	(segment
		(start 101.94925 -22.197568)
		(end 101.94925 -18.734786)
		(width 0.14224)
		(layer "In11.Cu")
		(net "M_G_BA<1>")
	)
	(segment
		(start 99.633024 -26.15311)
		(end 99.633024 -25.74671)
		(width 0.14224)
		(layer "In11.Cu")
		(net "M_G_BA<1>")
	)
	(segment
		(start 99.870768 -25.8826)
		(end 99.607116 -26.146252)
		(width 0.1651)
		(layer "F.Cu")
		(net "M_G_BA<0>")
	)
	(segment
		(start 101.985572 -22.671532)
		(end 101.438456 -23.218648)
		(width 0.1651)
		(layer "F.Cu")
		(net "M_G_BA<0>")
	)
	(segment
		(start 99.200716 -26.146252)
		(end 97.631758 -27.71521)
		(width 0.1651)
		(layer "F.Cu")
		(net "M_G_BA<0>")
	)
	(segment
		(start 97.631758 -29.179774)
		(end 97.631758 -45.843444)
		(width 0.1651)
		(layer "F.Cu")
		(net "M_G_BA<0>")
	)
	(segment
		(start 101.438456 -23.908512)
		(end 99.870768 -25.4762)
		(width 0.1651)
		(layer "F.Cu")
		(net "M_G_BA<0>")
	)
	(segment
		(start 97.972372 -48.100996)
		(end 96.938338 -49.13503)
		(width 0.0889)
		(layer "F.Cu")
		(net "M_G_BA<0>")
	)
	(segment
		(start 102.799388 -15.423642)
		(end 102.799388 -16.718534)
		(width 0.1651)
		(layer "F.Cu")
		(net "M_G_BA<0>")
	)
	(segment
		(start 102.620064 -22.671532)
		(end 101.985572 -22.671532)
		(width 0.1651)
		(layer "F.Cu")
		(net "M_G_BA<0>")
	)
	(segment
		(start 99.607116 -26.146252)
		(end 99.200716 -26.146252)
		(width 0.1651)
		(layer "F.Cu")
		(net "M_G_BA<0>")
	)
	(segment
		(start 102.799388 -16.718534)
		(end 102.799642 -16.718788)
		(width 0.1651)
		(layer "F.Cu")
		(net "M_G_BA<0>")
	)
	(segment
		(start 97.631758 -46.125892)
		(end 97.972372 -46.466506)
		(width 0.0889)
		(layer "F.Cu")
		(net "M_G_BA<0>")
	)
	(segment
		(start 97.972372 -46.466506)
		(end 97.972372 -48.100996)
		(width 0.0889)
		(layer "F.Cu")
		(net "M_G_BA<0>")
	)
	(segment
		(start 96.938338 -49.13503)
		(end 96.938338 -50.63744)
		(width 0.0889)
		(layer "F.Cu")
		(net "M_G_BA<0>")
	)
	(segment
		(start 97.631758 -45.843444)
		(end 97.631758 -46.125892)
		(width 0.0889)
		(layer "F.Cu")
		(net "M_G_BA<0>")
	)
	(segment
		(start 99.870768 -25.4762)
		(end 99.870768 -25.8826)
		(width 0.1651)
		(layer "F.Cu")
		(net "M_G_BA<0>")
	)
	(segment
		(start 97.631758 -27.71521)
		(end 97.631758 -29.179774)
		(width 0.1651)
		(layer "F.Cu")
		(net "M_G_BA<0>")
	)
	(segment
		(start 101.438456 -23.218648)
		(end 101.438456 -23.908512)
		(width 0.1651)
		(layer "F.Cu")
		(net "M_G_BA<0>")
	)
	(segment
		(start 102.799388 -22.850856)
		(end 102.620064 -22.671532)
		(width 0.1651)
		(layer "F.Cu")
		(net "M_G_BA<0>")
	)
	(via
		(at 97.631758 -29.179774)
		(size 0.508)
		(drill 0.254)
		(layers "F.Cu" "B.Cu")
		(net "M_G_BA<0>")
	)
	(via
		(at 102.799388 -22.850856)
		(size 0.508)
		(drill 0.254)
		(layers "F.Cu" "B.Cu")
		(net "M_G_BA<0>")
	)
	(via
		(at 102.799642 -16.718788)
		(size 0.4572)
		(drill 0.2032)
		(layers "F.Cu" "B.Cu")
		(net "M_G_BA<0>")
	)
	(segment
		(start 102.799388 -22.850856)
		(end 102.799388 -24.824182)
		(width 0.1651)
		(layer "B.Cu")
		(net "M_G_BA<0>")
	)
	(segment
		(start 102.54107 -22.592538)
		(end 102.54107 -21.974302)
		(width 0.14224)
		(layer "In9.Cu")
		(net "M_G_BA<0>")
	)
	(segment
		(start 102.54107 -21.974302)
		(end 102.275894 -21.709126)
		(width 0.14224)
		(layer "In9.Cu")
		(net "M_G_BA<0>")
	)
	(segment
		(start 102.275894 -20.712938)
		(end 102.389686 -20.599146)
		(width 0.14224)
		(layer "In9.Cu")
		(net "M_G_BA<0>")
	)
	(segment
		(start 102.389686 -20.599146)
		(end 102.389686 -17.128744)
		(width 0.14224)
		(layer "In9.Cu")
		(net "M_G_BA<0>")
	)
	(segment
		(start 102.389686 -17.128744)
		(end 102.799642 -16.718788)
		(width 0.14224)
		(layer "In9.Cu")
		(net "M_G_BA<0>")
	)
	(segment
		(start 102.275894 -21.709126)
		(end 102.275894 -20.712938)
		(width 0.14224)
		(layer "In9.Cu")
		(net "M_G_BA<0>")
	)
	(segment
		(start 102.799388 -22.850856)
		(end 102.54107 -22.592538)
		(width 0.14224)
		(layer "In9.Cu")
		(net "M_G_BA<0>")
	)
	(segment
		(start 88.900508 -47.33544)
		(end 88.900508 -47.55134)
		(width 0.0889)
		(layer "F.Cu")
		(net "M_G_ALERT_N")
	)
	(segment
		(start 83.249516 -20.023582)
		(end 83.249516 -18.734278)
		(width 0.1651)
		(layer "F.Cu")
		(net "M_G_ALERT_N")
	)
	(segment
		(start 88.900508 -33.391602)
		(end 88.900508 -47.33544)
		(width 0.1651)
		(layer "F.Cu")
		(net "M_G_ALERT_N")
	)
	(segment
		(start 85.291168 -26.433526)
		(end 85.291168 -29.782262)
		(width 0.1651)
		(layer "F.Cu")
		(net "M_G_ALERT_N")
	)
	(segment
		(start 85.291168 -24.851868)
		(end 85.291168 -26.433526)
		(width 0.1651)
		(layer "F.Cu")
		(net "M_G_ALERT_N")
	)
	(segment
		(start 89.329768 -47.9806)
		(end 89.329768 -50.02403)
		(width 0.0889)
		(layer "F.Cu")
		(net "M_G_ALERT_N")
	)
	(segment
		(start 83.249516 -22.810216)
		(end 85.291168 -24.851868)
		(width 0.1651)
		(layer "F.Cu")
		(net "M_G_ALERT_N")
	)
	(segment
		(start 85.291168 -29.782262)
		(end 88.900508 -33.391602)
		(width 0.1651)
		(layer "F.Cu")
		(net "M_G_ALERT_N")
	)
	(segment
		(start 83.249516 -22.197568)
		(end 83.249516 -22.810216)
		(width 0.1651)
		(layer "F.Cu")
		(net "M_G_ALERT_N")
	)
	(segment
		(start 88.900508 -47.55134)
		(end 89.329768 -47.9806)
		(width 0.0889)
		(layer "F.Cu")
		(net "M_G_ALERT_N")
	)
	(segment
		(start 89.329768 -50.02403)
		(end 89.211912 -50.141886)
		(width 0.0889)
		(layer "F.Cu")
		(net "M_G_ALERT_N")
	)
	(via
		(at 83.249516 -22.197568)
		(size 0.508)
		(drill 0.254)
		(layers "F.Cu" "B.Cu")
		(net "M_G_ALERT_N")
	)
	(via
		(at 85.291168 -26.433526)
		(size 0.508)
		(drill 0.254)
		(layers "F.Cu" "B.Cu")
		(net "M_G_ALERT_N")
	)
	(via
		(at 83.249516 -18.734278)
		(size 0.4572)
		(drill 0.2032)
		(layers "F.Cu" "B.Cu")
		(net "M_G_ALERT_N")
	)
	(segment
		(start 83.249516 -22.197568)
		(end 83.249516 -20.224242)
		(width 0.1651)
		(layer "B.Cu")
		(net "M_G_ALERT_N")
	)
	(segment
		(start 83.249516 -22.197568)
		(end 83.030568 -21.97862)
		(width 0.14224)
		(layer "In9.Cu")
		(net "M_G_ALERT_N")
	)
	(segment
		(start 83.030568 -18.953226)
		(end 83.249516 -18.734278)
		(width 0.14224)
		(layer "In9.Cu")
		(net "M_G_ALERT_N")
	)
	(segment
		(start 83.030568 -21.97862)
		(end 83.030568 -18.953226)
		(width 0.14224)
		(layer "In9.Cu")
		(net "M_G_ALERT_N")
	)
	(segment
		(start 89.729056 -53.025294)
		(end 90.06967 -53.608224)
		(width 0.0889)
		(layer "F.Cu")
		(net "M_G_ACT_N")
	)
	(segment
		(start 87.892128 -47.553372)
		(end 88.620854 -48.282098)
		(width 0.0889)
		(layer "F.Cu")
		(net "M_G_ACT_N")
	)
	(segment
		(start 84.224368 -29.145992)
		(end 84.224368 -30.220666)
		(width 0.1651)
		(layer "F.Cu")
		(net "M_G_ACT_N")
	)
	(segment
		(start 89.145872 -51.645566)
		(end 89.349072 -51.74742)
		(width 0.0889)
		(layer "F.Cu")
		(net "M_G_ACT_N")
	)
	(segment
		(start 87.892128 -33.888426)
		(end 87.892128 -47.40275)
		(width 0.1651)
		(layer "F.Cu")
		(net "M_G_ACT_N")
	)
	(segment
		(start 90.06967 -53.608224)
		(end 90.070178 -53.60924)
		(width 0.0889)
		(layer "F.Cu")
		(net "M_G_ACT_N")
	)
	(segment
		(start 82.776568 -25.146)
		(end 84.224368 -26.5938)
		(width 0.1651)
		(layer "F.Cu")
		(net "M_G_ACT_N")
	)
	(segment
		(start 81.549494 -23.560278)
		(end 81.549494 -24.452326)
		(width 0.1651)
		(layer "F.Cu")
		(net "M_G_ACT_N")
	)
	(segment
		(start 88.620854 -48.282098)
		(end 88.620854 -50.1396)
		(width 0.0889)
		(layer "F.Cu")
		(net "M_G_ACT_N")
	)
	(segment
		(start 81.549494 -15.423642)
		(end 81.549494 -16.716756)
		(width 0.1651)
		(layer "F.Cu")
		(net "M_G_ACT_N")
	)
	(segment
		(start 89.611962 -52.12842)
		(end 89.729056 -53.025294)
		(width 0.0889)
		(layer "F.Cu")
		(net "M_G_ACT_N")
	)
	(segment
		(start 81.549494 -24.452326)
		(end 82.243168 -25.146)
		(width 0.1651)
		(layer "F.Cu")
		(net "M_G_ACT_N")
	)
	(segment
		(start 84.224368 -26.5938)
		(end 84.224368 -29.145992)
		(width 0.1651)
		(layer "F.Cu")
		(net "M_G_ACT_N")
	)
	(segment
		(start 88.753442 -50.646584)
		(end 88.753442 -51.253136)
		(width 0.0889)
		(layer "F.Cu")
		(net "M_G_ACT_N")
	)
	(segment
		(start 87.892128 -47.40275)
		(end 87.892128 -47.553372)
		(width 0.0889)
		(layer "F.Cu")
		(net "M_G_ACT_N")
	)
	(segment
		(start 88.753442 -51.253136)
		(end 89.145872 -51.645566)
		(width 0.0889)
		(layer "F.Cu")
		(net "M_G_ACT_N")
	)
	(segment
		(start 84.224368 -30.220666)
		(end 87.892128 -33.888426)
		(width 0.1651)
		(layer "F.Cu")
		(net "M_G_ACT_N")
	)
	(segment
		(start 82.243168 -25.146)
		(end 82.776568 -25.146)
		(width 0.1651)
		(layer "F.Cu")
		(net "M_G_ACT_N")
	)
	(via
		(at 84.224368 -29.145992)
		(size 0.508)
		(drill 0.254)
		(layers "F.Cu" "B.Cu")
		(net "M_G_ACT_N")
	)
	(via
		(at 81.549494 -23.560278)
		(size 0.508)
		(drill 0.254)
		(layers "F.Cu" "B.Cu")
		(net "M_G_ACT_N")
	)
	(via
		(at 81.549494 -16.716756)
		(size 0.4572)
		(drill 0.2032)
		(layers "F.Cu" "B.Cu")
		(net "M_G_ACT_N")
	)
	(arc
		(start 88.620854 -50.1396)
		(mid 88.640746 -50.293696)
		(end 88.700102 -50.437288)
		(width 0.0889)
		(layer "F.Cu")
		(net "M_G_ACT_N")
	)
	(arc
		(start 88.700102 -50.437288)
		(mid 88.741183 -50.538267)
		(end 88.753442 -50.646584)
		(width 0.0889)
		(layer "F.Cu")
		(net "M_G_ACT_N")
	)
	(arc
		(start 89.349072 -51.74742)
		(mid 89.541245 -51.896033)
		(end 89.611962 -52.12842)
		(width 0.0889)
		(layer "F.Cu")
		(net "M_G_ACT_N")
	)
	(segment
		(start 81.549494 -23.560278)
		(end 81.549494 -24.824182)
		(width 0.1651)
		(layer "B.Cu")
		(net "M_G_ACT_N")
	)
	(segment
		(start 81.109312 -19.309334)
		(end 81.109312 -17.156938)
		(width 0.14224)
		(layer "In9.Cu")
		(net "M_G_ACT_N")
	)
	(segment
		(start 81.023968 -21.995892)
		(end 81.201768 -21.818092)
		(width 0.14224)
		(layer "In9.Cu")
		(net "M_G_ACT_N")
	)
	(segment
		(start 81.109312 -17.156938)
		(end 81.549494 -16.716756)
		(width 0.14224)
		(layer "In9.Cu")
		(net "M_G_ACT_N")
	)
	(segment
		(start 81.023968 -22.3774)
		(end 81.023968 -21.995892)
		(width 0.14224)
		(layer "In9.Cu")
		(net "M_G_ACT_N")
	)
	(segment
		(start 81.201768 -19.40179)
		(end 81.109312 -19.309334)
		(width 0.14224)
		(layer "In9.Cu")
		(net "M_G_ACT_N")
	)
	(segment
		(start 81.549494 -23.560278)
		(end 81.549494 -22.902926)
		(width 0.14224)
		(layer "In9.Cu")
		(net "M_G_ACT_N")
	)
	(segment
		(start 81.201768 -21.818092)
		(end 81.201768 -19.40179)
		(width 0.14224)
		(layer "In9.Cu")
		(net "M_G_ACT_N")
	)
	(segment
		(start 81.549494 -22.902926)
		(end 81.023968 -22.3774)
		(width 0.14224)
		(layer "In9.Cu")
		(net "M_G_ACT_N")
	)
	(segment
		(start 78.14945 3.778758)
		(end 78.14945 1.946148)
		(width 0.10795)
		(layer "F.Cu")
		(net "M_GHJ_RST_N")
	)
	(segment
		(start 78.14945 -15.423642)
		(end 78.14945 -17.157446)
		(width 0.10795)
		(layer "F.Cu")
		(net "M_GHJ_RST_N")
	)
	(segment
		(start 78.14945 -17.157446)
		(end 78.213712 -17.221708)
		(width 0.10795)
		(layer "F.Cu")
		(net "M_GHJ_RST_N")
	)
	(segment
		(start 78.14945 -5.822442)
		(end 78.14945 -7.115556)
		(width 0.10795)
		(layer "F.Cu")
		(net "M_GHJ_RST_N")
	)
	(segment
		(start 78.14945 1.946148)
		(end 78.271878 1.82372)
		(width 0.10795)
		(layer "F.Cu")
		(net "M_GHJ_RST_N")
	)
	(segment
		(start 86.636352 -57.57164)
		(end 86.064852 -58.56224)
		(width 0.1016)
		(layer "F.Cu")
		(net "M_GHJ_RST_N")
	)
	(via
		(at 86.064852 -58.56224)
		(size 0.508)
		(drill 0.254)
		(layers "F.Cu" "B.Cu")
		(net "M_GHJ_RST_N")
	)
	(via
		(at 78.213712 -17.221708)
		(size 0.4572)
		(drill 0.2032)
		(layers "F.Cu" "B.Cu")
		(net "M_GHJ_RST_N")
	)
	(via
		(at 78.14945 -7.115556)
		(size 0.4572)
		(drill 0.2032)
		(layers "F.Cu" "B.Cu")
		(net "M_GHJ_RST_N")
	)
	(via
		(at 78.14945 -4.332478)
		(size 0.4572)
		(drill 0.2032)
		(layers "F.Cu" "B.Cu")
		(net "M_GHJ_RST_N")
	)
	(via
		(at 78.14945 -13.933678)
		(size 0.4572)
		(drill 0.2032)
		(layers "F.Cu" "B.Cu")
		(net "M_GHJ_RST_N")
	)
	(via
		(at 78.271878 1.82372)
		(size 0.508)
		(drill 0.254)
		(layers "F.Cu" "B.Cu")
		(net "M_GHJ_RST_N")
	)
	(via
		(at 78.14945 -23.534878)
		(size 0.508)
		(drill 0.254)
		(layers "F.Cu" "B.Cu")
		(net "M_GHJ_RST_N")
	)
	(segment
		(start 78.14945 -24.824182)
		(end 78.14945 -23.534878)
		(width 0.10795)
		(layer "B.Cu")
		(net "M_GHJ_RST_N")
	)
	(segment
		(start 78.14945 -5.621782)
		(end 78.14945 -4.332478)
		(width 0.10795)
		(layer "B.Cu")
		(net "M_GHJ_RST_N")
	)
	(segment
		(start 78.14945 -15.222982)
		(end 78.14945 -13.933678)
		(width 0.10795)
		(layer "B.Cu")
		(net "M_GHJ_RST_N")
	)
	(segment
		(start 85.621368 -34.093912)
		(end 79.220568 -27.693112)
		(width 0.089408)
		(layer "In4.Cu")
		(net "M_GHJ_RST_N")
	)
	(segment
		(start 79.220568 -27.693112)
		(end 79.220568 -25.393142)
		(width 0.089408)
		(layer "In4.Cu")
		(net "M_GHJ_RST_N")
	)
	(segment
		(start 85.443568 -56.642)
		(end 85.189568 -56.642)
		(width 0.089408)
		(layer "In4.Cu")
		(net "M_GHJ_RST_N")
	)
	(segment
		(start 86.064852 -58.56224)
		(end 86.064852 -57.263284)
		(width 0.089408)
		(layer "In4.Cu")
		(net "M_GHJ_RST_N")
	)
	(segment
		(start 85.316568 -50.1904)
		(end 85.316568 -46.406054)
		(width 0.089408)
		(layer "In4.Cu")
		(net "M_GHJ_RST_N")
	)
	(segment
		(start 85.316568 -46.406054)
		(end 85.621368 -46.101254)
		(width 0.089408)
		(layer "In4.Cu")
		(net "M_GHJ_RST_N")
	)
	(segment
		(start 85.405468 -50.8889)
		(end 85.405468 -50.2793)
		(width 0.089408)
		(layer "In4.Cu")
		(net "M_GHJ_RST_N")
	)
	(segment
		(start 84.783168 -54.9402)
		(end 85.316568 -54.4068)
		(width 0.089408)
		(layer "In4.Cu")
		(net "M_GHJ_RST_N")
	)
	(segment
		(start 79.220568 -25.393142)
		(end 78.14945 -24.322024)
		(width 0.089408)
		(layer "In4.Cu")
		(net "M_GHJ_RST_N")
	)
	(segment
		(start 86.064852 -57.263284)
		(end 85.443568 -56.642)
		(width 0.089408)
		(layer "In4.Cu")
		(net "M_GHJ_RST_N")
	)
	(segment
		(start 84.783168 -56.2356)
		(end 84.783168 -54.9402)
		(width 0.089408)
		(layer "In4.Cu")
		(net "M_GHJ_RST_N")
	)
	(segment
		(start 85.405468 -50.2793)
		(end 85.316568 -50.1904)
		(width 0.089408)
		(layer "In4.Cu")
		(net "M_GHJ_RST_N")
	)
	(segment
		(start 85.621368 -46.101254)
		(end 85.621368 -34.093912)
		(width 0.089408)
		(layer "In4.Cu")
		(net "M_GHJ_RST_N")
	)
	(segment
		(start 85.316568 -50.9778)
		(end 85.405468 -50.8889)
		(width 0.089408)
		(layer "In4.Cu")
		(net "M_GHJ_RST_N")
	)
	(segment
		(start 78.14945 -24.322024)
		(end 78.14945 -23.534878)
		(width 0.089408)
		(layer "In4.Cu")
		(net "M_GHJ_RST_N")
	)
	(segment
		(start 85.316568 -54.4068)
		(end 85.316568 -50.9778)
		(width 0.089408)
		(layer "In4.Cu")
		(net "M_GHJ_RST_N")
	)
	(segment
		(start 85.189568 -56.642)
		(end 84.783168 -56.2356)
		(width 0.089408)
		(layer "In4.Cu")
		(net "M_GHJ_RST_N")
	)
	(segment
		(start 78.560168 -20.1422)
		(end 78.560168 -21.76526)
		(width 0.089408)
		(layer "In11.Cu")
		(net "M_GHJ_RST_N")
	)
	(segment
		(start 78.585568 -4.768596)
		(end 78.585568 -6.679438)
		(width 0.089408)
		(layer "In11.Cu")
		(net "M_GHJ_RST_N")
	)
	(segment
		(start 78.271878 1.011682)
		(end 78.588616 0.694944)
		(width 0.089408)
		(layer "In11.Cu")
		(net "M_GHJ_RST_N")
	)
	(segment
		(start 78.271878 1.82372)
		(end 78.271878 1.011682)
		(width 0.089408)
		(layer "In11.Cu")
		(net "M_GHJ_RST_N")
	)
	(segment
		(start 78.560168 -16.875252)
		(end 78.213712 -17.221708)
		(width 0.089408)
		(layer "In11.Cu")
		(net "M_GHJ_RST_N")
	)
	(segment
		(start 78.14945 -4.332478)
		(end 78.585568 -4.768596)
		(width 0.089408)
		(layer "In11.Cu")
		(net "M_GHJ_RST_N")
	)
	(segment
		(start 78.560168 -14.344396)
		(end 78.560168 -16.875252)
		(width 0.089408)
		(layer "In11.Cu")
		(net "M_GHJ_RST_N")
	)
	(segment
		(start 78.14945 -13.933678)
		(end 78.560168 -14.344396)
		(width 0.089408)
		(layer "In11.Cu")
		(net "M_GHJ_RST_N")
	)
	(segment
		(start 78.14945 -4.274566)
		(end 78.14945 -4.332478)
		(width 0.089408)
		(layer "In11.Cu")
		(net "M_GHJ_RST_N")
	)
	(segment
		(start 78.560168 -12.4206)
		(end 78.712568 -12.573)
		(width 0.089408)
		(layer "In11.Cu")
		(net "M_GHJ_RST_N")
	)
	(segment
		(start 78.712568 -12.573)
		(end 78.712568 -13.37056)
		(width 0.089408)
		(layer "In11.Cu")
		(net "M_GHJ_RST_N")
	)
	(segment
		(start 78.509368 -23.17496)
		(end 78.14945 -23.534878)
		(width 0.089408)
		(layer "In11.Cu")
		(net "M_GHJ_RST_N")
	)
	(segment
		(start 78.509368 -22.6568)
		(end 78.509368 -23.17496)
		(width 0.089408)
		(layer "In11.Cu")
		(net "M_GHJ_RST_N")
	)
	(segment
		(start 78.654402 -17.221708)
		(end 78.77556 -17.342866)
		(width 0.089408)
		(layer "In11.Cu")
		(net "M_GHJ_RST_N")
	)
	(segment
		(start 78.77556 -19.926808)
		(end 78.560168 -20.1422)
		(width 0.089408)
		(layer "In11.Cu")
		(net "M_GHJ_RST_N")
	)
	(segment
		(start 78.712568 -8.711946)
		(end 78.560168 -8.864346)
		(width 0.089408)
		(layer "In11.Cu")
		(net "M_GHJ_RST_N")
	)
	(segment
		(start 78.712568 -13.37056)
		(end 78.14945 -13.933678)
		(width 0.089408)
		(layer "In11.Cu")
		(net "M_GHJ_RST_N")
	)
	(segment
		(start 78.687168 -21.89226)
		(end 78.687168 -22.479)
		(width 0.089408)
		(layer "In11.Cu")
		(net "M_GHJ_RST_N")
	)
	(segment
		(start 78.77556 -17.342866)
		(end 78.77556 -19.926808)
		(width 0.089408)
		(layer "In11.Cu")
		(net "M_GHJ_RST_N")
	)
	(segment
		(start 78.14945 -7.115556)
		(end 78.712568 -7.678674)
		(width 0.089408)
		(layer "In11.Cu")
		(net "M_GHJ_RST_N")
	)
	(segment
		(start 78.560168 -8.864346)
		(end 78.560168 -12.4206)
		(width 0.089408)
		(layer "In11.Cu")
		(net "M_GHJ_RST_N")
	)
	(segment
		(start 78.661768 -2.667)
		(end 78.661768 -3.762248)
		(width 0.089408)
		(layer "In11.Cu")
		(net "M_GHJ_RST_N")
	)
	(segment
		(start 78.560168 -21.76526)
		(end 78.687168 -21.89226)
		(width 0.089408)
		(layer "In11.Cu")
		(net "M_GHJ_RST_N")
	)
	(segment
		(start 78.712568 -7.678674)
		(end 78.712568 -8.711946)
		(width 0.089408)
		(layer "In11.Cu")
		(net "M_GHJ_RST_N")
	)
	(segment
		(start 78.588616 -2.593848)
		(end 78.661768 -2.667)
		(width 0.089408)
		(layer "In11.Cu")
		(net "M_GHJ_RST_N")
	)
	(segment
		(start 78.661768 -3.762248)
		(end 78.14945 -4.274566)
		(width 0.089408)
		(layer "In11.Cu")
		(net "M_GHJ_RST_N")
	)
	(segment
		(start 78.687168 -22.479)
		(end 78.509368 -22.6568)
		(width 0.089408)
		(layer "In11.Cu")
		(net "M_GHJ_RST_N")
	)
	(segment
		(start 78.213712 -17.221708)
		(end 78.654402 -17.221708)
		(width 0.089408)
		(layer "In11.Cu")
		(net "M_GHJ_RST_N")
	)
	(segment
		(start 78.588616 0.694944)
		(end 78.588616 -2.593848)
		(width 0.089408)
		(layer "In11.Cu")
		(net "M_GHJ_RST_N")
	)
	(segment
		(start 78.585568 -6.679438)
		(end 78.14945 -7.115556)
		(width 0.089408)
		(layer "In11.Cu")
		(net "M_GHJ_RST_N")
	)
	(segment
		(start 27.451558 -22.952456)
		(end 27.802078 -22.952456)
		(width 0.254)
		(layer "F.Cu")
		(net "M_G_CPU_VREF")
	)
	(segment
		(start 27.451558 -22.952456)
		(end 27.451558 -23.315676)
		(width 0.254)
		(layer "F.Cu")
		(net "M_G_CPU_VREF")
	)
	(segment
		(start 27.802078 -22.952456)
		(end 27.813 -22.941534)
		(width 0.254)
		(layer "F.Cu")
		(net "M_G_CPU_VREF")
	)
	(segment
		(start 27.813 -22.941534)
		(end 28.242006 -22.941534)
		(width 0.254)
		(layer "F.Cu")
		(net "M_G_CPU_VREF")
	)
	(segment
		(start 27.451558 -23.315676)
		(end 27.700478 -23.564596)
		(width 0.254)
		(layer "F.Cu")
		(net "M_G_CPU_VREF")
	)
	(segment
		(start 86.636352 -63.51524)
		(end 86.064852 -63.51524)
		(width 0.254)
		(layer "F.Cu")
		(net "M_G_CPU_VREF")
	)
	(via
		(at 86.064852 -63.51524)
		(size 0.508)
		(drill 0.254)
		(layers "F.Cu" "B.Cu")
		(net "M_G_CPU_VREF")
	)
	(via
		(at 27.700478 -23.564596)
		(size 0.508)
		(drill 0.254)
		(layers "F.Cu" "B.Cu")
		(net "M_G_CPU_VREF")
	)
	(segment
		(start 75.931776 -55.069486)
		(end 75.613514 -55.069486)
		(width 0.2286)
		(layer "In9.Cu")
		(net "M_G_CPU_VREF")
	)
	(segment
		(start 68.453 -55.6006)
		(end 65.23482 -52.38242)
		(width 0.254)
		(layer "In9.Cu")
		(net "M_G_CPU_VREF")
	)
	(segment
		(start 71.2724 -55.6006)
		(end 70.7644 -56.1086)
		(width 0.2286)
		(layer "In9.Cu")
		(net "M_G_CPU_VREF")
	)
	(segment
		(start 65.23482 -49.004474)
		(end 46.296072 -30.065726)
		(width 0.254)
		(layer "In9.Cu")
		(net "M_G_CPU_VREF")
	)
	(segment
		(start 81.966816 -59.57824)
		(end 81.603342 -59.57824)
		(width 0.2286)
		(layer "In9.Cu")
		(net "M_G_CPU_VREF")
	)
	(segment
		(start 82.487516 -61.064394)
		(end 82.161126 -60.738004)
		(width 0.2286)
		(layer "In9.Cu")
		(net "M_G_CPU_VREF")
	)
	(segment
		(start 80.719168 -59.031632)
		(end 80.275176 -58.58764)
		(width 0.2286)
		(layer "In9.Cu")
		(net "M_G_CPU_VREF")
	)
	(segment
		(start 72.1614 -56.1086)
		(end 71.6534 -55.6006)
		(width 0.2286)
		(layer "In9.Cu")
		(net "M_G_CPU_VREF")
	)
	(segment
		(start 73.886314 -55.069486)
		(end 73.3552 -55.6006)
		(width 0.2286)
		(layer "In9.Cu")
		(net "M_G_CPU_VREF")
	)
	(segment
		(start 78.807818 -56.881522)
		(end 78.481428 -56.555132)
		(width 0.2286)
		(layer "In9.Cu")
		(net "M_G_CPU_VREF")
	)
	(segment
		(start 82.241898 -59.853322)
		(end 81.966816 -59.57824)
		(width 0.2286)
		(layer "In9.Cu")
		(net "M_G_CPU_VREF")
	)
	(segment
		(start 78.143608 -56.555132)
		(end 77.69987 -56.111394)
		(width 0.2286)
		(layer "In9.Cu")
		(net "M_G_CPU_VREF")
	)
	(segment
		(start 28.212034 -24.176228)
		(end 27.700478 -23.664672)
		(width 0.254)
		(layer "In9.Cu")
		(net "M_G_CPU_VREF")
	)
	(segment
		(start 71.6534 -55.6006)
		(end 71.2724 -55.6006)
		(width 0.2286)
		(layer "In9.Cu")
		(net "M_G_CPU_VREF")
	)
	(segment
		(start 82.161126 -60.323222)
		(end 82.241898 -60.24245)
		(width 0.2286)
		(layer "In9.Cu")
		(net "M_G_CPU_VREF")
	)
	(segment
		(start 72.4916 -56.1086)
		(end 72.1614 -56.1086)
		(width 0.2286)
		(layer "In9.Cu")
		(net "M_G_CPU_VREF")
	)
	(segment
		(start 46.296072 -30.065726)
		(end 35.221672 -25.478486)
		(width 0.254)
		(layer "In9.Cu")
		(net "M_G_CPU_VREF")
	)
	(segment
		(start 76.47813 -55.61584)
		(end 75.931776 -55.069486)
		(width 0.2286)
		(layer "In9.Cu")
		(net "M_G_CPU_VREF")
	)
	(segment
		(start 80.275176 -58.58764)
		(end 79.886556 -58.58764)
		(width 0.2286)
		(layer "In9.Cu")
		(net "M_G_CPU_VREF")
	)
	(segment
		(start 83.958938 -62.24905)
		(end 83.958938 -61.834522)
		(width 0.2286)
		(layer "In9.Cu")
		(net "M_G_CPU_VREF")
	)
	(segment
		(start 78.727046 -57.766204)
		(end 78.727046 -57.377076)
		(width 0.2286)
		(layer "In9.Cu")
		(net "M_G_CPU_VREF")
	)
	(segment
		(start 79.053182 -58.09234)
		(end 78.727046 -57.766204)
		(width 0.2286)
		(layer "In9.Cu")
		(net "M_G_CPU_VREF")
	)
	(segment
		(start 79.391256 -58.09234)
		(end 79.053182 -58.09234)
		(width 0.2286)
		(layer "In9.Cu")
		(net "M_G_CPU_VREF")
	)
	(segment
		(start 72.9996 -55.6006)
		(end 72.4916 -56.1086)
		(width 0.2286)
		(layer "In9.Cu")
		(net "M_G_CPU_VREF")
	)
	(segment
		(start 86.064852 -63.51524)
		(end 85.037676 -63.51524)
		(width 0.2286)
		(layer "In9.Cu")
		(net "M_G_CPU_VREF")
	)
	(segment
		(start 82.161126 -60.738004)
		(end 82.161126 -60.323222)
		(width 0.2286)
		(layer "In9.Cu")
		(net "M_G_CPU_VREF")
	)
	(segment
		(start 83.320382 -61.55944)
		(end 82.825336 -61.064394)
		(width 0.2286)
		(layer "In9.Cu")
		(net "M_G_CPU_VREF")
	)
	(segment
		(start 73.3552 -55.6006)
		(end 72.9996 -55.6006)
		(width 0.2286)
		(layer "In9.Cu")
		(net "M_G_CPU_VREF")
	)
	(segment
		(start 76.81595 -55.61584)
		(end 76.47813 -55.61584)
		(width 0.2286)
		(layer "In9.Cu")
		(net "M_G_CPU_VREF")
	)
	(segment
		(start 84.153248 -62.994286)
		(end 83.878166 -62.719204)
		(width 0.2286)
		(layer "In9.Cu")
		(net "M_G_CPU_VREF")
	)
	(segment
		(start 70.4596 -56.1086)
		(end 69.9516 -55.6006)
		(width 0.2286)
		(layer "In9.Cu")
		(net "M_G_CPU_VREF")
	)
	(segment
		(start 65.23482 -52.38242)
		(end 65.23482 -49.004474)
		(width 0.254)
		(layer "In9.Cu")
		(net "M_G_CPU_VREF")
	)
	(segment
		(start 79.886556 -58.58764)
		(end 79.391256 -58.09234)
		(width 0.2286)
		(layer "In9.Cu")
		(net "M_G_CPU_VREF")
	)
	(segment
		(start 81.603342 -59.57824)
		(end 81.056734 -59.031632)
		(width 0.2286)
		(layer "In9.Cu")
		(net "M_G_CPU_VREF")
	)
	(segment
		(start 82.825336 -61.064394)
		(end 82.487516 -61.064394)
		(width 0.2286)
		(layer "In9.Cu")
		(net "M_G_CPU_VREF")
	)
	(segment
		(start 75.0824 -55.6006)
		(end 74.7268 -55.6006)
		(width 0.2286)
		(layer "In9.Cu")
		(net "M_G_CPU_VREF")
	)
	(segment
		(start 70.7644 -56.1086)
		(end 70.4596 -56.1086)
		(width 0.2286)
		(layer "In9.Cu")
		(net "M_G_CPU_VREF")
	)
	(segment
		(start 83.878166 -62.330076)
		(end 83.958938 -62.24905)
		(width 0.2286)
		(layer "In9.Cu")
		(net "M_G_CPU_VREF")
	)
	(segment
		(start 33.919414 -24.176228)
		(end 28.212034 -24.176228)
		(width 0.254)
		(layer "In9.Cu")
		(net "M_G_CPU_VREF")
	)
	(segment
		(start 69.9516 -55.6006)
		(end 69.469 -55.6006)
		(width 0.2286)
		(layer "In9.Cu")
		(net "M_G_CPU_VREF")
	)
	(segment
		(start 78.727046 -57.377076)
		(end 78.807818 -57.296304)
		(width 0.2286)
		(layer "In9.Cu")
		(net "M_G_CPU_VREF")
	)
	(segment
		(start 84.516722 -62.994286)
		(end 84.153248 -62.994286)
		(width 0.2286)
		(layer "In9.Cu")
		(net "M_G_CPU_VREF")
	)
	(segment
		(start 69.469 -55.6006)
		(end 68.453 -55.6006)
		(width 0.254)
		(layer "In9.Cu")
		(net "M_G_CPU_VREF")
	)
	(segment
		(start 78.807818 -57.296304)
		(end 78.807818 -56.881522)
		(width 0.2286)
		(layer "In9.Cu")
		(net "M_G_CPU_VREF")
	)
	(segment
		(start 74.195686 -55.069486)
		(end 73.886314 -55.069486)
		(width 0.2286)
		(layer "In9.Cu")
		(net "M_G_CPU_VREF")
	)
	(segment
		(start 83.958938 -61.834522)
		(end 83.683856 -61.55944)
		(width 0.2286)
		(layer "In9.Cu")
		(net "M_G_CPU_VREF")
	)
	(segment
		(start 27.700478 -23.664672)
		(end 27.700478 -23.564596)
		(width 0.254)
		(layer "In9.Cu")
		(net "M_G_CPU_VREF")
	)
	(segment
		(start 83.683856 -61.55944)
		(end 83.320382 -61.55944)
		(width 0.2286)
		(layer "In9.Cu")
		(net "M_G_CPU_VREF")
	)
	(segment
		(start 75.613514 -55.069486)
		(end 75.0824 -55.6006)
		(width 0.2286)
		(layer "In9.Cu")
		(net "M_G_CPU_VREF")
	)
	(segment
		(start 74.7268 -55.6006)
		(end 74.195686 -55.069486)
		(width 0.2286)
		(layer "In9.Cu")
		(net "M_G_CPU_VREF")
	)
	(segment
		(start 35.221672 -25.478486)
		(end 33.919414 -24.176228)
		(width 0.254)
		(layer "In9.Cu")
		(net "M_G_CPU_VREF")
	)
	(segment
		(start 83.878166 -62.719204)
		(end 83.878166 -62.330076)
		(width 0.2286)
		(layer "In9.Cu")
		(net "M_G_CPU_VREF")
	)
	(segment
		(start 85.037676 -63.51524)
		(end 84.516722 -62.994286)
		(width 0.2286)
		(layer "In9.Cu")
		(net "M_G_CPU_VREF")
	)
	(segment
		(start 77.311504 -56.111394)
		(end 76.81595 -55.61584)
		(width 0.2286)
		(layer "In9.Cu")
		(net "M_G_CPU_VREF")
	)
	(segment
		(start 81.056734 -59.031632)
		(end 80.719168 -59.031632)
		(width 0.2286)
		(layer "In9.Cu")
		(net "M_G_CPU_VREF")
	)
	(segment
		(start 78.481428 -56.555132)
		(end 78.143608 -56.555132)
		(width 0.2286)
		(layer "In9.Cu")
		(net "M_G_CPU_VREF")
	)
	(segment
		(start 82.241898 -60.24245)
		(end 82.241898 -59.853322)
		(width 0.2286)
		(layer "In9.Cu")
		(net "M_G_CPU_VREF")
	)
	(segment
		(start 77.69987 -56.111394)
		(end 77.311504 -56.111394)
		(width 0.2286)
		(layer "In9.Cu")
		(net "M_G_CPU_VREF")
	)
	(segment
		(start 265.249914 -156.87294)
		(end 265.249914 -155.615132)
		(width 0.1651)
		(layer "F.Cu")
		(net "M_F_PAR")
	)
	(segment
		(start 261.08025 -93.72854)
		(end 260.50875 -93.72854)
		(width 0.1651)
		(layer "F.Cu")
		(net "M_F_PAR")
	)
	(segment
		(start 265.250422 -156.87294)
		(end 265.249914 -156.87294)
		(width 0.1651)
		(layer "F.Cu")
		(net "M_F_PAR")
	)
	(via
		(at 265.24966 -149.451568)
		(size 0.508)
		(drill 0.254)
		(layers "F.Cu" "B.Cu")
		(net "M_F_PAR")
	)
	(via
		(at 260.50875 -93.72854)
		(size 0.508)
		(drill 0.254)
		(layers "F.Cu" "B.Cu")
		(net "M_F_PAR")
	)
	(via
		(at 265.249914 -155.615132)
		(size 0.508)
		(drill 0.254)
		(layers "F.Cu" "B.Cu")
		(net "M_F_PAR")
	)
	(segment
		(start 265.250422 -149.450806)
		(end 265.24966 -149.451568)
		(width 0.1651)
		(layer "B.Cu")
		(net "M_F_PAR")
	)
	(segment
		(start 265.250422 -147.478496)
		(end 265.250422 -149.450806)
		(width 0.1651)
		(layer "B.Cu")
		(net "M_F_PAR")
	)
	(segment
		(start 265.688318 -154.029918)
		(end 265.688318 -154.503882)
		(width 0.14224)
		(layer "In2.Cu")
		(net "M_F_PAR")
	)
	(segment
		(start 264.7696 -148.971508)
		(end 265.24966 -149.451568)
		(width 0.14224)
		(layer "In2.Cu")
		(net "M_F_PAR")
	)
	(segment
		(start 261.486904 -102.04958)
		(end 261.486904 -102.520496)
		(width 0.0889)
		(layer "In2.Cu")
		(net "M_F_PAR")
	)
	(segment
		(start 261.486904 -102.520496)
		(end 261.3152 -102.6922)
		(width 0.0889)
		(layer "In2.Cu")
		(net "M_F_PAR")
	)
	(segment
		(start 265.24966 -151.313388)
		(end 265.59891 -151.662638)
		(width 0.14224)
		(layer "In2.Cu")
		(net "M_F_PAR")
	)
	(segment
		(start 260.9088 -99.671378)
		(end 260.9088 -101.471476)
		(width 0.0889)
		(layer "In2.Cu")
		(net "M_F_PAR")
	)
	(segment
		(start 260.85546 -95.509588)
		(end 260.860286 -95.518224)
		(width 0.0889)
		(layer "In2.Cu")
		(net "M_F_PAR")
	)
	(segment
		(start 264.7696 -128.82118)
		(end 264.7696 -148.971508)
		(width 0.14224)
		(layer "In2.Cu")
		(net "M_F_PAR")
	)
	(segment
		(start 265.24966 -155.614878)
		(end 265.249914 -155.615132)
		(width 0.14224)
		(layer "In2.Cu")
		(net "M_F_PAR")
	)
	(segment
		(start 265.59891 -153.94051)
		(end 265.688318 -154.029918)
		(width 0.14224)
		(layer "In2.Cu")
		(net "M_F_PAR")
	)
	(segment
		(start 261.3152 -102.6922)
		(end 261.3152 -102.938834)
		(width 0.0889)
		(layer "In2.Cu")
		(net "M_F_PAR")
	)
	(segment
		(start 260.83895 -94.49054)
		(end 260.860286 -94.527624)
		(width 0.0889)
		(layer "In2.Cu")
		(net "M_F_PAR")
	)
	(segment
		(start 260.84911 -96.48952)
		(end 260.85546 -96.500188)
		(width 0.0889)
		(layer "In2.Cu")
		(net "M_F_PAR")
	)
	(segment
		(start 260.85546 -98.481388)
		(end 260.860286 -98.490024)
		(width 0.0889)
		(layer "In2.Cu")
		(net "M_F_PAR")
	)
	(segment
		(start 261.3152 -102.938834)
		(end 261.3152 -125.36678)
		(width 0.14224)
		(layer "In2.Cu")
		(net "M_F_PAR")
	)
	(segment
		(start 260.85546 -97.490788)
		(end 260.860286 -97.499424)
		(width 0.0889)
		(layer "In2.Cu")
		(net "M_F_PAR")
	)
	(segment
		(start 261.3152 -125.36678)
		(end 264.7696 -128.82118)
		(width 0.14224)
		(layer "In2.Cu")
		(net "M_F_PAR")
	)
	(segment
		(start 265.24966 -154.94254)
		(end 265.24966 -155.614878)
		(width 0.14224)
		(layer "In2.Cu")
		(net "M_F_PAR")
	)
	(segment
		(start 265.59891 -151.662638)
		(end 265.59891 -153.94051)
		(width 0.14224)
		(layer "In2.Cu")
		(net "M_F_PAR")
	)
	(segment
		(start 260.84911 -97.48012)
		(end 260.85546 -97.490788)
		(width 0.0889)
		(layer "In2.Cu")
		(net "M_F_PAR")
	)
	(segment
		(start 265.688318 -154.503882)
		(end 265.24966 -154.94254)
		(width 0.14224)
		(layer "In2.Cu")
		(net "M_F_PAR")
	)
	(segment
		(start 260.84911 -98.47072)
		(end 260.85546 -98.481388)
		(width 0.0889)
		(layer "In2.Cu")
		(net "M_F_PAR")
	)
	(segment
		(start 260.50875 -93.72854)
		(end 260.83895 -94.49054)
		(width 0.0889)
		(layer "In2.Cu")
		(net "M_F_PAR")
	)
	(segment
		(start 260.84911 -95.49892)
		(end 260.85546 -95.509588)
		(width 0.0889)
		(layer "In2.Cu")
		(net "M_F_PAR")
	)
	(segment
		(start 260.9088 -101.471476)
		(end 261.486904 -102.04958)
		(width 0.0889)
		(layer "In2.Cu")
		(net "M_F_PAR")
	)
	(segment
		(start 265.24966 -149.451568)
		(end 265.24966 -151.313388)
		(width 0.14224)
		(layer "In2.Cu")
		(net "M_F_PAR")
	)
	(segment
		(start 260.85546 -96.500188)
		(end 260.860286 -96.508824)
		(width 0.0889)
		(layer "In2.Cu")
		(net "M_F_PAR")
	)
	(arc
		(start 260.860286 -98.490024)
		(mid 260.909041 -98.686376)
		(end 260.85546 -98.881438)
		(width 0.0889)
		(layer "In2.Cu")
		(net "M_F_PAR")
	)
	(arc
		(start 260.85546 -99.472242)
		(mid 260.895246 -99.568298)
		(end 260.9088 -99.671378)
		(width 0.0889)
		(layer "In2.Cu")
		(net "M_F_PAR")
	)
	(arc
		(start 260.85546 -96.900238)
		(mid 260.776238 -97.189356)
		(end 260.84911 -97.48012)
		(width 0.0889)
		(layer "In2.Cu")
		(net "M_F_PAR")
	)
	(arc
		(start 260.85546 -97.890838)
		(mid 260.776238 -98.179956)
		(end 260.84911 -98.47072)
		(width 0.0889)
		(layer "In2.Cu")
		(net "M_F_PAR")
	)
	(arc
		(start 260.860286 -96.508824)
		(mid 260.909041 -96.705176)
		(end 260.85546 -96.900238)
		(width 0.0889)
		(layer "In2.Cu")
		(net "M_F_PAR")
	)
	(arc
		(start 260.85546 -95.909638)
		(mid 260.776238 -96.198756)
		(end 260.84911 -96.48952)
		(width 0.0889)
		(layer "In2.Cu")
		(net "M_F_PAR")
	)
	(arc
		(start 260.85546 -98.881438)
		(mid 260.776329 -99.17684)
		(end 260.85546 -99.472242)
		(width 0.0889)
		(layer "In2.Cu")
		(net "M_F_PAR")
	)
	(arc
		(start 260.860286 -94.527624)
		(mid 260.909041 -94.723976)
		(end 260.85546 -94.919038)
		(width 0.0889)
		(layer "In2.Cu")
		(net "M_F_PAR")
	)
	(arc
		(start 260.860286 -95.518224)
		(mid 260.909041 -95.714576)
		(end 260.85546 -95.909638)
		(width 0.0889)
		(layer "In2.Cu")
		(net "M_F_PAR")
	)
	(arc
		(start 260.860286 -97.499424)
		(mid 260.909041 -97.695776)
		(end 260.85546 -97.890838)
		(width 0.0889)
		(layer "In2.Cu")
		(net "M_F_PAR")
	)
	(arc
		(start 260.85546 -94.919038)
		(mid 260.776238 -95.208156)
		(end 260.84911 -95.49892)
		(width 0.0889)
		(layer "In2.Cu")
		(net "M_F_PAR")
	)
	(segment
		(start 266.231116 -91.747086)
		(end 265.659616 -91.747086)
		(width 0.1016)
		(layer "F.Cu")
		(net "M_F_ODT<3>")
	)
	(via
		(at 276.29993 -150.789386)
		(size 0.4572)
		(drill 0.2032)
		(layers "F.Cu" "B.Cu")
		(net "M_F_ODT<3>")
	)
	(via
		(at 265.659616 -91.747086)
		(size 0.508)
		(drill 0.254)
		(layers "F.Cu" "B.Cu")
		(net "M_F_ODT<3>")
	)
	(segment
		(start 276.29993 -152.078182)
		(end 276.29993 -150.789386)
		(width 0.1651)
		(layer "B.Cu")
		(net "M_F_ODT<3>")
	)
	(segment
		(start 276.300438 -152.078436)
		(end 276.29993 -152.078182)
		(width 0.1651)
		(layer "B.Cu")
		(net "M_F_ODT<3>")
	)
	(segment
		(start 267.0302 -99.3648)
		(end 266.8778 -99.5172)
		(width 0.14224)
		(layer "In2.Cu")
		(net "M_F_ODT<3>")
	)
	(segment
		(start 275.082 -130.7338)
		(end 275.082 -131.2164)
		(width 0.14224)
		(layer "In2.Cu")
		(net "M_F_ODT<3>")
	)
	(segment
		(start 266.1412 -96.8756)
		(end 266.0142 -97.0026)
		(width 0.14224)
		(layer "In2.Cu")
		(net "M_F_ODT<3>")
	)
	(segment
		(start 266.005564 -93.387164)
		(end 266.1412 -93.5228)
		(width 0.14224)
		(layer "In2.Cu")
		(net "M_F_ODT<3>")
	)
	(segment
		(start 274.9804 -131.318)
		(end 274.9804 -132.1816)
		(width 0.14224)
		(layer "In2.Cu")
		(net "M_F_ODT<3>")
	)
	(segment
		(start 266.0142 -96.0374)
		(end 266.0142 -96.393)
		(width 0.14224)
		(layer "In2.Cu")
		(net "M_F_ODT<3>")
	)
	(segment
		(start 275.036788 -145.67662)
		(end 275.036788 -146.538188)
		(width 0.14224)
		(layer "In2.Cu")
		(net "M_F_ODT<3>")
	)
	(segment
		(start 266.1412 -92.5576)
		(end 266.1412 -92.964)
		(width 0.14224)
		(layer "In2.Cu")
		(net "M_F_ODT<3>")
	)
	(segment
		(start 275.014182 -140.834618)
		(end 275.014182 -142.807182)
		(width 0.14224)
		(layer "In2.Cu")
		(net "M_F_ODT<3>")
	)
	(segment
		(start 267.0302 -98.9838)
		(end 267.0302 -99.3648)
		(width 0.14224)
		(layer "In2.Cu")
		(net "M_F_ODT<3>")
	)
	(segment
		(start 274.6629 -144.531588)
		(end 274.6629 -145.302732)
		(width 0.14224)
		(layer "In2.Cu")
		(net "M_F_ODT<3>")
	)
	(segment
		(start 267.4366 -102.9462)
		(end 267.4366 -120.603264)
		(width 0.14224)
		(layer "In2.Cu")
		(net "M_F_ODT<3>")
	)
	(segment
		(start 266.1412 -92.964)
		(end 266.005564 -93.099636)
		(width 0.14224)
		(layer "In2.Cu")
		(net "M_F_ODT<3>")
	)
	(segment
		(start 266.0396 -95.4278)
		(end 266.1412 -95.5294)
		(width 0.14224)
		(layer "In2.Cu")
		(net "M_F_ODT<3>")
	)
	(segment
		(start 275.037042 -142.830042)
		(end 275.037042 -144.157446)
		(width 0.14224)
		(layer "In2.Cu")
		(net "M_F_ODT<3>")
	)
	(segment
		(start 266.8778 -99.5172)
		(end 266.8778 -101.9048)
		(width 0.14224)
		(layer "In2.Cu")
		(net "M_F_ODT<3>")
	)
	(segment
		(start 275.876258 -149.054058)
		(end 276.29993 -149.47773)
		(width 0.14224)
		(layer "In2.Cu")
		(net "M_F_ODT<3>")
	)
	(segment
		(start 266.861036 -98.543364)
		(end 266.861036 -98.814636)
		(width 0.14224)
		(layer "In2.Cu")
		(net "M_F_ODT<3>")
	)
	(segment
		(start 266.1412 -93.5228)
		(end 266.1412 -93.9292)
		(width 0.14224)
		(layer "In2.Cu")
		(net "M_F_ODT<3>")
	)
	(segment
		(start 266.1412 -93.9292)
		(end 266.0396 -94.0308)
		(width 0.14224)
		(layer "In2.Cu")
		(net "M_F_ODT<3>")
	)
	(segment
		(start 271.116806 -124.28347)
		(end 271.116806 -125.320806)
		(width 0.14224)
		(layer "In2.Cu")
		(net "M_F_ODT<3>")
	)
	(segment
		(start 274.955 -130.6068)
		(end 275.082 -130.7338)
		(width 0.14224)
		(layer "In2.Cu")
		(net "M_F_ODT<3>")
	)
	(segment
		(start 271.116806 -125.320806)
		(end 275.0566 -129.2606)
		(width 0.14224)
		(layer "In2.Cu")
		(net "M_F_ODT<3>")
	)
	(segment
		(start 266.8778 -101.9048)
		(end 267.1572 -102.1842)
		(width 0.14224)
		(layer "In2.Cu")
		(net "M_F_ODT<3>")
	)
	(segment
		(start 275.036788 -136.062212)
		(end 275.036788 -139.440412)
		(width 0.14224)
		(layer "In2.Cu")
		(net "M_F_ODT<3>")
	)
	(segment
		(start 274.955 -129.9718)
		(end 274.955 -130.6068)
		(width 0.14224)
		(layer "In2.Cu")
		(net "M_F_ODT<3>")
	)
	(segment
		(start 266.1412 -96.52)
		(end 266.1412 -96.8756)
		(width 0.14224)
		(layer "In2.Cu")
		(net "M_F_ODT<3>")
	)
	(segment
		(start 266.1412 -95.5294)
		(end 266.1412 -95.9104)
		(width 0.14224)
		(layer "In2.Cu")
		(net "M_F_ODT<3>")
	)
	(segment
		(start 275.876258 -147.377658)
		(end 275.876258 -149.054058)
		(width 0.14224)
		(layer "In2.Cu")
		(net "M_F_ODT<3>")
	)
	(segment
		(start 275.0566 -129.8702)
		(end 274.955 -129.9718)
		(width 0.14224)
		(layer "In2.Cu")
		(net "M_F_ODT<3>")
	)
	(segment
		(start 266.0142 -97.0026)
		(end 266.0142 -97.3582)
		(width 0.14224)
		(layer "In2.Cu")
		(net "M_F_ODT<3>")
	)
	(segment
		(start 275.036788 -146.538188)
		(end 275.876258 -147.377658)
		(width 0.14224)
		(layer "In2.Cu")
		(net "M_F_ODT<3>")
	)
	(segment
		(start 275.036534 -132.237734)
		(end 275.036534 -134.76097)
		(width 0.14224)
		(layer "In2.Cu")
		(net "M_F_ODT<3>")
	)
	(segment
		(start 266.0396 -94.0308)
		(end 266.0396 -94.4118)
		(width 0.14224)
		(layer "In2.Cu")
		(net "M_F_ODT<3>")
	)
	(segment
		(start 266.319 -97.663)
		(end 266.6746 -97.663)
		(width 0.14224)
		(layer "In2.Cu")
		(net "M_F_ODT<3>")
	)
	(segment
		(start 266.005564 -93.099636)
		(end 266.005564 -93.387164)
		(width 0.14224)
		(layer "In2.Cu")
		(net "M_F_ODT<3>")
	)
	(segment
		(start 274.670774 -139.806426)
		(end 274.670774 -140.49121)
		(width 0.14224)
		(layer "In2.Cu")
		(net "M_F_ODT<3>")
	)
	(segment
		(start 266.0396 -95.0214)
		(end 266.0396 -95.4278)
		(width 0.14224)
		(layer "In2.Cu")
		(net "M_F_ODT<3>")
	)
	(segment
		(start 267.0048 -98.3996)
		(end 266.861036 -98.543364)
		(width 0.14224)
		(layer "In2.Cu")
		(net "M_F_ODT<3>")
	)
	(segment
		(start 266.1412 -94.5134)
		(end 266.1412 -94.9198)
		(width 0.14224)
		(layer "In2.Cu")
		(net "M_F_ODT<3>")
	)
	(segment
		(start 274.644612 -135.152892)
		(end 274.644612 -135.670036)
		(width 0.14224)
		(layer "In2.Cu")
		(net "M_F_ODT<3>")
	)
	(segment
		(start 267.1572 -102.6668)
		(end 267.4366 -102.9462)
		(width 0.14224)
		(layer "In2.Cu")
		(net "M_F_ODT<3>")
	)
	(segment
		(start 265.659616 -91.747086)
		(end 265.659616 -92.076016)
		(width 0.14224)
		(layer "In2.Cu")
		(net "M_F_ODT<3>")
	)
	(segment
		(start 274.6629 -145.302732)
		(end 275.036788 -145.67662)
		(width 0.14224)
		(layer "In2.Cu")
		(net "M_F_ODT<3>")
	)
	(segment
		(start 266.0142 -97.3582)
		(end 266.319 -97.663)
		(width 0.14224)
		(layer "In2.Cu")
		(net "M_F_ODT<3>")
	)
	(segment
		(start 275.082 -131.2164)
		(end 274.9804 -131.318)
		(width 0.14224)
		(layer "In2.Cu")
		(net "M_F_ODT<3>")
	)
	(segment
		(start 266.1412 -95.9104)
		(end 266.0142 -96.0374)
		(width 0.14224)
		(layer "In2.Cu")
		(net "M_F_ODT<3>")
	)
	(segment
		(start 275.0566 -129.2606)
		(end 275.0566 -129.8702)
		(width 0.14224)
		(layer "In2.Cu")
		(net "M_F_ODT<3>")
	)
	(segment
		(start 275.036534 -134.76097)
		(end 274.644612 -135.152892)
		(width 0.14224)
		(layer "In2.Cu")
		(net "M_F_ODT<3>")
	)
	(segment
		(start 267.1572 -102.1842)
		(end 267.1572 -102.6668)
		(width 0.14224)
		(layer "In2.Cu")
		(net "M_F_ODT<3>")
	)
	(segment
		(start 266.0142 -96.393)
		(end 266.1412 -96.52)
		(width 0.14224)
		(layer "In2.Cu")
		(net "M_F_ODT<3>")
	)
	(segment
		(start 276.29993 -149.47773)
		(end 276.29993 -150.789386)
		(width 0.14224)
		(layer "In2.Cu")
		(net "M_F_ODT<3>")
	)
	(segment
		(start 274.670774 -140.49121)
		(end 275.014182 -140.834618)
		(width 0.14224)
		(layer "In2.Cu")
		(net "M_F_ODT<3>")
	)
	(segment
		(start 275.037042 -144.157446)
		(end 274.6629 -144.531588)
		(width 0.14224)
		(layer "In2.Cu")
		(net "M_F_ODT<3>")
	)
	(segment
		(start 267.0048 -97.9932)
		(end 267.0048 -98.3996)
		(width 0.14224)
		(layer "In2.Cu")
		(net "M_F_ODT<3>")
	)
	(segment
		(start 266.1412 -94.9198)
		(end 266.0396 -95.0214)
		(width 0.14224)
		(layer "In2.Cu")
		(net "M_F_ODT<3>")
	)
	(segment
		(start 265.659616 -92.076016)
		(end 266.1412 -92.5576)
		(width 0.14224)
		(layer "In2.Cu")
		(net "M_F_ODT<3>")
	)
	(segment
		(start 266.861036 -98.814636)
		(end 267.0302 -98.9838)
		(width 0.14224)
		(layer "In2.Cu")
		(net "M_F_ODT<3>")
	)
	(segment
		(start 275.036788 -139.440412)
		(end 274.670774 -139.806426)
		(width 0.14224)
		(layer "In2.Cu")
		(net "M_F_ODT<3>")
	)
	(segment
		(start 275.014182 -142.807182)
		(end 275.037042 -142.830042)
		(width 0.14224)
		(layer "In2.Cu")
		(net "M_F_ODT<3>")
	)
	(segment
		(start 274.9804 -132.1816)
		(end 275.036534 -132.237734)
		(width 0.14224)
		(layer "In2.Cu")
		(net "M_F_ODT<3>")
	)
	(segment
		(start 267.4366 -120.603264)
		(end 271.116806 -124.28347)
		(width 0.14224)
		(layer "In2.Cu")
		(net "M_F_ODT<3>")
	)
	(segment
		(start 274.644612 -135.670036)
		(end 275.036788 -136.062212)
		(width 0.14224)
		(layer "In2.Cu")
		(net "M_F_ODT<3>")
	)
	(segment
		(start 266.6746 -97.663)
		(end 267.0048 -97.9932)
		(width 0.14224)
		(layer "In2.Cu")
		(net "M_F_ODT<3>")
	)
	(segment
		(start 266.0396 -94.4118)
		(end 266.1412 -94.5134)
		(width 0.14224)
		(layer "In2.Cu")
		(net "M_F_ODT<3>")
	)
	(segment
		(start 264.51433 -93.72854)
		(end 263.94283 -93.72854)
		(width 0.1016)
		(layer "F.Cu")
		(net "M_F_ODT<2>")
	)
	(via
		(at 263.94283 -93.72854)
		(size 0.508)
		(drill 0.254)
		(layers "F.Cu" "B.Cu")
		(net "M_F_ODT<2>")
	)
	(via
		(at 272.899886 -150.785068)
		(size 0.508)
		(drill 0.254)
		(layers "F.Cu" "B.Cu")
		(net "M_F_ODT<2>")
	)
	(segment
		(start 272.899886 -152.078182)
		(end 272.899886 -150.785068)
		(width 0.1651)
		(layer "B.Cu")
		(net "M_F_ODT<2>")
	)
	(segment
		(start 272.900394 -152.078436)
		(end 272.899886 -152.078182)
		(width 0.1651)
		(layer "B.Cu")
		(net "M_F_ODT<2>")
	)
	(segment
		(start 271.636998 -145.685002)
		(end 271.636998 -146.719798)
		(width 0.14224)
		(layer "In2.Cu")
		(net "M_F_ODT<2>")
	)
	(segment
		(start 269.802102 -127.689102)
		(end 270.08963 -127.689102)
		(width 0.14224)
		(layer "In2.Cu")
		(net "M_F_ODT<2>")
	)
	(segment
		(start 265.4046 -122.483372)
		(end 269.631414 -126.710186)
		(width 0.14224)
		(layer "In2.Cu")
		(net "M_F_ODT<2>")
	)
	(segment
		(start 264.273284 -94.491556)
		(end 264.289286 -94.518988)
		(width 0.0889)
		(layer "In2.Cu")
		(net "M_F_ODT<2>")
	)
	(segment
		(start 271.640554 -140.924026)
		(end 271.640554 -144.259046)
		(width 0.14224)
		(layer "In2.Cu")
		(net "M_F_ODT<2>")
	)
	(segment
		(start 270.951706 -128.838706)
		(end 271.239234 -128.838706)
		(width 0.14224)
		(layer "In2.Cu")
		(net "M_F_ODT<2>")
	)
	(segment
		(start 265.4046 -103.19131)
		(end 265.4046 -122.483372)
		(width 0.14224)
		(layer "In2.Cu")
		(net "M_F_ODT<2>")
	)
	(segment
		(start 272.461482 -147.544282)
		(end 272.461482 -149.068282)
		(width 0.14224)
		(layer "In2.Cu")
		(net "M_F_ODT<2>")
	)
	(segment
		(start 265.1252 -102.616)
		(end 265.4046 -102.8954)
		(width 0.0889)
		(layer "In2.Cu")
		(net "M_F_ODT<2>")
	)
	(segment
		(start 271.636744 -132.216144)
		(end 271.636744 -134.636256)
		(width 0.14224)
		(layer "In2.Cu")
		(net "M_F_ODT<2>")
	)
	(segment
		(start 263.94283 -93.72854)
		(end 264.273284 -94.491556)
		(width 0.0889)
		(layer "In2.Cu")
		(net "M_F_ODT<2>")
	)
	(segment
		(start 271.640554 -144.259046)
		(end 271.5006 -144.399)
		(width 0.14224)
		(layer "In2.Cu")
		(net "M_F_ODT<2>")
	)
	(segment
		(start 271.526 -130.386328)
		(end 271.777206 -130.637534)
		(width 0.14224)
		(layer "In2.Cu")
		(net "M_F_ODT<2>")
	)
	(segment
		(start 271.927066 -129.005838)
		(end 271.927066 -129.570734)
		(width 0.14224)
		(layer "In2.Cu")
		(net "M_F_ODT<2>")
	)
	(segment
		(start 270.493744 -127.572516)
		(end 270.781018 -127.85979)
		(width 0.14224)
		(layer "In2.Cu")
		(net "M_F_ODT<2>")
	)
	(segment
		(start 265.1252 -100.4316)
		(end 265.1252 -102.616)
		(width 0.0889)
		(layer "In2.Cu")
		(net "M_F_ODT<2>")
	)
	(segment
		(start 271.5006 -144.399)
		(end 271.5006 -145.548604)
		(width 0.14224)
		(layer "In2.Cu")
		(net "M_F_ODT<2>")
	)
	(segment
		(start 271.5514 -132.1308)
		(end 271.636744 -132.216144)
		(width 0.14224)
		(layer "In2.Cu")
		(net "M_F_ODT<2>")
	)
	(segment
		(start 270.781018 -127.85979)
		(end 270.781018 -128.147318)
		(width 0.14224)
		(layer "In2.Cu")
		(net "M_F_ODT<2>")
	)
	(segment
		(start 271.927066 -129.570734)
		(end 271.526 -129.9718)
		(width 0.14224)
		(layer "In2.Cu")
		(net "M_F_ODT<2>")
	)
	(segment
		(start 271.636744 -134.636256)
		(end 271.502632 -134.770368)
		(width 0.14224)
		(layer "In2.Cu")
		(net "M_F_ODT<2>")
	)
	(segment
		(start 269.631414 -126.710186)
		(end 269.631414 -126.997714)
		(width 0.14224)
		(layer "In2.Cu")
		(net "M_F_ODT<2>")
	)
	(segment
		(start 271.643348 -128.72212)
		(end 271.927066 -129.005838)
		(width 0.14224)
		(layer "In2.Cu")
		(net "M_F_ODT<2>")
	)
	(segment
		(start 270.206216 -127.572516)
		(end 270.493744 -127.572516)
		(width 0.14224)
		(layer "In2.Cu")
		(net "M_F_ODT<2>")
	)
	(segment
		(start 271.239234 -128.838706)
		(end 271.35582 -128.72212)
		(width 0.14224)
		(layer "In2.Cu")
		(net "M_F_ODT<2>")
	)
	(segment
		(start 265.4046 -102.8954)
		(end 265.4046 -103.19131)
		(width 0.0889)
		(layer "In2.Cu")
		(net "M_F_ODT<2>")
	)
	(segment
		(start 269.514828 -127.401828)
		(end 269.802102 -127.689102)
		(width 0.14224)
		(layer "In2.Cu")
		(net "M_F_ODT<2>")
	)
	(segment
		(start 264.7442 -100.0506)
		(end 265.1252 -100.4316)
		(width 0.0889)
		(layer "In2.Cu")
		(net "M_F_ODT<2>")
	)
	(segment
		(start 271.502632 -140.786104)
		(end 271.640554 -140.924026)
		(width 0.14224)
		(layer "In2.Cu")
		(net "M_F_ODT<2>")
	)
	(segment
		(start 272.461482 -149.068282)
		(end 272.899886 -149.506686)
		(width 0.14224)
		(layer "In2.Cu")
		(net "M_F_ODT<2>")
	)
	(segment
		(start 271.502632 -134.770368)
		(end 271.502632 -135.931656)
		(width 0.14224)
		(layer "In2.Cu")
		(net "M_F_ODT<2>")
	)
	(segment
		(start 264.280396 -96.484948)
		(end 264.289286 -96.500188)
		(width 0.0889)
		(layer "In2.Cu")
		(net "M_F_ODT<2>")
	)
	(segment
		(start 269.514828 -127.1143)
		(end 269.514828 -127.401828)
		(width 0.14224)
		(layer "In2.Cu")
		(net "M_F_ODT<2>")
	)
	(segment
		(start 272.899886 -149.506686)
		(end 272.899886 -150.785068)
		(width 0.14224)
		(layer "In2.Cu")
		(net "M_F_ODT<2>")
	)
	(segment
		(start 270.781018 -128.147318)
		(end 270.664432 -128.263904)
		(width 0.14224)
		(layer "In2.Cu")
		(net "M_F_ODT<2>")
	)
	(segment
		(start 270.08963 -127.689102)
		(end 270.206216 -127.572516)
		(width 0.14224)
		(layer "In2.Cu")
		(net "M_F_ODT<2>")
	)
	(segment
		(start 271.777206 -130.637534)
		(end 271.777206 -131.066794)
		(width 0.14224)
		(layer "In2.Cu")
		(net "M_F_ODT<2>")
	)
	(segment
		(start 270.664432 -128.551432)
		(end 270.951706 -128.838706)
		(width 0.14224)
		(layer "In2.Cu")
		(net "M_F_ODT<2>")
	)
	(segment
		(start 271.777206 -131.066794)
		(end 271.5514 -131.2926)
		(width 0.14224)
		(layer "In2.Cu")
		(net "M_F_ODT<2>")
	)
	(segment
		(start 271.502632 -135.931656)
		(end 271.633188 -136.062212)
		(width 0.14224)
		(layer "In2.Cu")
		(net "M_F_ODT<2>")
	)
	(segment
		(start 264.280396 -95.494348)
		(end 264.289286 -95.509588)
		(width 0.0889)
		(layer "In2.Cu")
		(net "M_F_ODT<2>")
	)
	(segment
		(start 271.5006 -145.548604)
		(end 271.636998 -145.685002)
		(width 0.14224)
		(layer "In2.Cu")
		(net "M_F_ODT<2>")
	)
	(segment
		(start 271.636998 -146.719798)
		(end 272.461482 -147.544282)
		(width 0.14224)
		(layer "In2.Cu")
		(net "M_F_ODT<2>")
	)
	(segment
		(start 270.664432 -128.263904)
		(end 270.664432 -128.551432)
		(width 0.14224)
		(layer "In2.Cu")
		(net "M_F_ODT<2>")
	)
	(segment
		(start 271.526 -129.9718)
		(end 271.526 -130.386328)
		(width 0.14224)
		(layer "In2.Cu")
		(net "M_F_ODT<2>")
	)
	(segment
		(start 271.35582 -128.72212)
		(end 271.643348 -128.72212)
		(width 0.14224)
		(layer "In2.Cu")
		(net "M_F_ODT<2>")
	)
	(segment
		(start 264.280396 -98.466148)
		(end 264.289286 -98.481388)
		(width 0.0889)
		(layer "In2.Cu")
		(net "M_F_ODT<2>")
	)
	(segment
		(start 269.631414 -126.997714)
		(end 269.514828 -127.1143)
		(width 0.14224)
		(layer "In2.Cu")
		(net "M_F_ODT<2>")
	)
	(segment
		(start 264.280396 -97.475548)
		(end 264.289286 -97.490788)
		(width 0.0889)
		(layer "In2.Cu")
		(net "M_F_ODT<2>")
	)
	(segment
		(start 271.502632 -139.697968)
		(end 271.502632 -140.786104)
		(width 0.14224)
		(layer "In2.Cu")
		(net "M_F_ODT<2>")
	)
	(segment
		(start 271.633188 -136.062212)
		(end 271.633188 -139.567412)
		(width 0.14224)
		(layer "In2.Cu")
		(net "M_F_ODT<2>")
	)
	(segment
		(start 271.633188 -139.567412)
		(end 271.502632 -139.697968)
		(width 0.14224)
		(layer "In2.Cu")
		(net "M_F_ODT<2>")
	)
	(segment
		(start 271.5514 -131.2926)
		(end 271.5514 -132.1308)
		(width 0.14224)
		(layer "In2.Cu")
		(net "M_F_ODT<2>")
	)
	(arc
		(start 264.289286 -94.518988)
		(mid 264.342819 -94.718886)
		(end 264.289286 -94.918784)
		(width 0.0889)
		(layer "In2.Cu")
		(net "M_F_ODT<2>")
	)
	(arc
		(start 264.289286 -95.909384)
		(mid 264.210097 -96.195999)
		(end 264.280396 -96.484948)
		(width 0.0889)
		(layer "In2.Cu")
		(net "M_F_ODT<2>")
	)
	(arc
		(start 264.289286 -98.881184)
		(mid 264.210136 -99.165528)
		(end 264.278364 -99.452684)
		(width 0.0889)
		(layer "In2.Cu")
		(net "M_F_ODT<2>")
	)
	(arc
		(start 264.289286 -96.500188)
		(mid 264.342819 -96.700086)
		(end 264.289286 -96.899984)
		(width 0.0889)
		(layer "In2.Cu")
		(net "M_F_ODT<2>")
	)
	(arc
		(start 264.289286 -98.481388)
		(mid 264.342819 -98.681286)
		(end 264.289286 -98.881184)
		(width 0.0889)
		(layer "In2.Cu")
		(net "M_F_ODT<2>")
	)
	(arc
		(start 264.289286 -97.890584)
		(mid 264.210097 -98.177199)
		(end 264.280396 -98.466148)
		(width 0.0889)
		(layer "In2.Cu")
		(net "M_F_ODT<2>")
	)
	(arc
		(start 264.289286 -95.509588)
		(mid 264.342819 -95.709486)
		(end 264.289286 -95.909384)
		(width 0.0889)
		(layer "In2.Cu")
		(net "M_F_ODT<2>")
	)
	(arc
		(start 264.289286 -97.490788)
		(mid 264.342819 -97.690686)
		(end 264.289286 -97.890584)
		(width 0.0889)
		(layer "In2.Cu")
		(net "M_F_ODT<2>")
	)
	(arc
		(start 264.289286 -96.899984)
		(mid 264.210097 -97.186599)
		(end 264.280396 -97.475548)
		(width 0.0889)
		(layer "In2.Cu")
		(net "M_F_ODT<2>")
	)
	(arc
		(start 264.289286 -94.918784)
		(mid 264.210097 -95.205399)
		(end 264.280396 -95.494348)
		(width 0.0889)
		(layer "In2.Cu")
		(net "M_F_ODT<2>")
	)
	(arc
		(start 264.278364 -99.452684)
		(mid 264.484847 -99.772239)
		(end 264.7442 -100.0506)
		(width 0.0889)
		(layer "In2.Cu")
		(net "M_F_ODT<2>")
	)
	(segment
		(start 265.372596 -92.24264)
		(end 264.801096 -92.24264)
		(width 0.1016)
		(layer "F.Cu")
		(net "M_F_ODT<1>")
	)
	(segment
		(start 276.29993 -152.278842)
		(end 276.29993 -153.571956)
		(width 0.1651)
		(layer "F.Cu")
		(net "M_F_ODT<1>")
	)
	(segment
		(start 276.300438 -152.273)
		(end 276.29993 -152.278842)
		(width 0.1651)
		(layer "F.Cu")
		(net "M_F_ODT<1>")
	)
	(via
		(at 276.29993 -153.571956)
		(size 0.508)
		(drill 0.254)
		(layers "F.Cu" "B.Cu")
		(net "M_F_ODT<1>")
	)
	(via
		(at 264.801096 -92.24264)
		(size 0.508)
		(drill 0.254)
		(layers "F.Cu" "B.Cu")
		(net "M_F_ODT<1>")
	)
	(segment
		(start 274.066 -129.794)
		(end 274.291044 -130.019044)
		(width 0.14224)
		(layer "In2.Cu")
		(net "M_F_ODT<1>")
	)
	(segment
		(start 265.312906 -95.509588)
		(end 265.30808 -95.518224)
		(width 0.0889)
		(layer "In2.Cu")
		(net "M_F_ODT<1>")
	)
	(segment
		(start 274.291044 -130.019044)
		(end 274.291044 -130.432556)
		(width 0.14224)
		(layer "In2.Cu")
		(net "M_F_ODT<1>")
	)
	(segment
		(start 265.312906 -94.518988)
		(end 265.30808 -94.527624)
		(width 0.0889)
		(layer "In2.Cu")
		(net "M_F_ODT<1>")
	)
	(segment
		(start 274.185634 -142.07109)
		(end 274.161758 -142.094966)
		(width 0.14224)
		(layer "In2.Cu")
		(net "M_F_ODT<1>")
	)
	(segment
		(start 266.1158 -101.6508)
		(end 266.6746 -102.2096)
		(width 0.0889)
		(layer "In2.Cu")
		(net "M_F_ODT<1>")
	)
	(segment
		(start 274.159726 -140.835126)
		(end 274.185634 -140.861034)
		(width 0.14224)
		(layer "In2.Cu")
		(net "M_F_ODT<1>")
	)
	(segment
		(start 265.319256 -96.48952)
		(end 265.312906 -96.500188)
		(width 0.0889)
		(layer "In2.Cu")
		(net "M_F_ODT<1>")
	)
	(segment
		(start 274.185634 -140.861034)
		(end 274.185634 -142.07109)
		(width 0.14224)
		(layer "In2.Cu")
		(net "M_F_ODT<1>")
	)
	(segment
		(start 274.044918 -130.678682)
		(end 274.044918 -131.119118)
		(width 0.14224)
		(layer "In2.Cu")
		(net "M_F_ODT<1>")
	)
	(segment
		(start 274.161758 -142.094966)
		(end 274.161758 -146.475958)
		(width 0.14224)
		(layer "In2.Cu")
		(net "M_F_ODT<1>")
	)
	(segment
		(start 270.608806 -124.494036)
		(end 270.608806 -125.531626)
		(width 0.14224)
		(layer "In2.Cu")
		(net "M_F_ODT<1>")
	)
	(segment
		(start 266.9286 -103.406194)
		(end 266.9286 -120.81383)
		(width 0.14224)
		(layer "In2.Cu")
		(net "M_F_ODT<1>")
	)
	(segment
		(start 274.2692 -131.3434)
		(end 274.2692 -133.9342)
		(width 0.14224)
		(layer "In2.Cu")
		(net "M_F_ODT<1>")
	)
	(segment
		(start 265.351768 -97.97161)
		(end 265.624818 -98.24466)
		(width 0.0889)
		(layer "In2.Cu")
		(net "M_F_ODT<1>")
	)
	(segment
		(start 274.161758 -146.475958)
		(end 275.040344 -147.354544)
		(width 0.14224)
		(layer "In2.Cu")
		(net "M_F_ODT<1>")
	)
	(segment
		(start 265.312906 -96.500188)
		(end 265.30808 -96.508824)
		(width 0.0889)
		(layer "In2.Cu")
		(net "M_F_ODT<1>")
	)
	(segment
		(start 275.89099 -153.163016)
		(end 276.29993 -153.571956)
		(width 0.14224)
		(layer "In2.Cu")
		(net "M_F_ODT<1>")
	)
	(segment
		(start 265.319256 -97.48012)
		(end 265.312906 -97.490788)
		(width 0.0889)
		(layer "In2.Cu")
		(net "M_F_ODT<1>")
	)
	(segment
		(start 265.312906 -93.928438)
		(end 265.319256 -93.939106)
		(width 0.0889)
		(layer "In2.Cu")
		(net "M_F_ODT<1>")
	)
	(segment
		(start 270.608806 -125.531626)
		(end 274.066 -128.98882)
		(width 0.14224)
		(layer "In2.Cu")
		(net "M_F_ODT<1>")
	)
	(segment
		(start 266.9286 -120.81383)
		(end 270.608806 -124.494036)
		(width 0.14224)
		(layer "In2.Cu")
		(net "M_F_ODT<1>")
	)
	(segment
		(start 275.89099 -149.923246)
		(end 275.89099 -153.163016)
		(width 0.14224)
		(layer "In2.Cu")
		(net "M_F_ODT<1>")
	)
	(segment
		(start 275.040344 -149.0726)
		(end 275.89099 -149.923246)
		(width 0.14224)
		(layer "In2.Cu")
		(net "M_F_ODT<1>")
	)
	(segment
		(start 274.291044 -130.432556)
		(end 274.044918 -130.678682)
		(width 0.14224)
		(layer "In2.Cu")
		(net "M_F_ODT<1>")
	)
	(segment
		(start 265.845544 -98.24466)
		(end 266.1158 -98.514916)
		(width 0.0889)
		(layer "In2.Cu")
		(net "M_F_ODT<1>")
	)
	(segment
		(start 265.319256 -95.49892)
		(end 265.312906 -95.509588)
		(width 0.0889)
		(layer "In2.Cu")
		(net "M_F_ODT<1>")
	)
	(segment
		(start 265.312906 -97.490788)
		(end 265.30808 -97.499424)
		(width 0.0889)
		(layer "In2.Cu")
		(net "M_F_ODT<1>")
	)
	(segment
		(start 265.624818 -98.24466)
		(end 265.845544 -98.24466)
		(width 0.0889)
		(layer "In2.Cu")
		(net "M_F_ODT<1>")
	)
	(segment
		(start 266.6746 -102.902512)
		(end 266.9286 -103.156512)
		(width 0.0889)
		(layer "In2.Cu")
		(net "M_F_ODT<1>")
	)
	(segment
		(start 264.801096 -92.24264)
		(end 265.287252 -92.897198)
		(width 0.0889)
		(layer "In2.Cu")
		(net "M_F_ODT<1>")
	)
	(segment
		(start 266.1158 -98.514916)
		(end 266.1158 -101.6508)
		(width 0.0889)
		(layer "In2.Cu")
		(net "M_F_ODT<1>")
	)
	(segment
		(start 274.159726 -134.043674)
		(end 274.159726 -140.835126)
		(width 0.14224)
		(layer "In2.Cu")
		(net "M_F_ODT<1>")
	)
	(segment
		(start 266.6746 -102.2096)
		(end 266.6746 -102.902512)
		(width 0.0889)
		(layer "In2.Cu")
		(net "M_F_ODT<1>")
	)
	(segment
		(start 274.066 -128.98882)
		(end 274.066 -129.794)
		(width 0.14224)
		(layer "In2.Cu")
		(net "M_F_ODT<1>")
	)
	(segment
		(start 275.040344 -147.354544)
		(end 275.040344 -149.0726)
		(width 0.14224)
		(layer "In2.Cu")
		(net "M_F_ODT<1>")
	)
	(segment
		(start 274.2692 -133.9342)
		(end 274.159726 -134.043674)
		(width 0.14224)
		(layer "In2.Cu")
		(net "M_F_ODT<1>")
	)
	(segment
		(start 266.9286 -103.156512)
		(end 266.9286 -103.406194)
		(width 0.0889)
		(layer "In2.Cu")
		(net "M_F_ODT<1>")
	)
	(segment
		(start 274.044918 -131.119118)
		(end 274.2692 -131.3434)
		(width 0.14224)
		(layer "In2.Cu")
		(net "M_F_ODT<1>")
	)
	(arc
		(start 265.312906 -94.919038)
		(mid 265.392128 -95.208156)
		(end 265.319256 -95.49892)
		(width 0.0889)
		(layer "In2.Cu")
		(net "M_F_ODT<1>")
	)
	(arc
		(start 265.30808 -96.508824)
		(mid 265.259325 -96.705176)
		(end 265.312906 -96.900238)
		(width 0.0889)
		(layer "In2.Cu")
		(net "M_F_ODT<1>")
	)
	(arc
		(start 265.30808 -94.527624)
		(mid 265.259325 -94.723976)
		(end 265.312906 -94.919038)
		(width 0.0889)
		(layer "In2.Cu")
		(net "M_F_ODT<1>")
	)
	(arc
		(start 265.312906 -96.900238)
		(mid 265.392128 -97.189356)
		(end 265.319256 -97.48012)
		(width 0.0889)
		(layer "In2.Cu")
		(net "M_F_ODT<1>")
	)
	(arc
		(start 265.312906 -97.890838)
		(mid 265.333874 -97.930485)
		(end 265.351768 -97.97161)
		(width 0.0889)
		(layer "In2.Cu")
		(net "M_F_ODT<1>")
	)
	(arc
		(start 265.312906 -95.909638)
		(mid 265.392128 -96.198756)
		(end 265.319256 -96.48952)
		(width 0.0889)
		(layer "In2.Cu")
		(net "M_F_ODT<1>")
	)
	(arc
		(start 265.30808 -97.499424)
		(mid 265.259325 -97.695776)
		(end 265.312906 -97.890838)
		(width 0.0889)
		(layer "In2.Cu")
		(net "M_F_ODT<1>")
	)
	(arc
		(start 265.319256 -93.939106)
		(mid 265.392054 -94.229869)
		(end 265.312906 -94.518988)
		(width 0.0889)
		(layer "In2.Cu")
		(net "M_F_ODT<1>")
	)
	(arc
		(start 265.312906 -93.528642)
		(mid 265.259407 -93.72854)
		(end 265.312906 -93.928438)
		(width 0.0889)
		(layer "In2.Cu")
		(net "M_F_ODT<1>")
	)
	(arc
		(start 265.30808 -95.518224)
		(mid 265.259325 -95.714576)
		(end 265.312906 -95.909638)
		(width 0.0889)
		(layer "In2.Cu")
		(net "M_F_ODT<1>")
	)
	(arc
		(start 265.287252 -92.897198)
		(mid 265.3916 -93.209209)
		(end 265.312906 -93.528642)
		(width 0.0889)
		(layer "In2.Cu")
		(net "M_F_ODT<1>")
	)
	(segment
		(start 272.900394 -152.273)
		(end 272.899886 -152.278842)
		(width 0.1651)
		(layer "F.Cu")
		(net "M_F_ODT<0>")
	)
	(segment
		(start 263.65581 -92.24264)
		(end 263.08431 -92.24264)
		(width 0.1016)
		(layer "F.Cu")
		(net "M_F_ODT<0>")
	)
	(segment
		(start 272.899886 -152.278842)
		(end 272.899886 -153.571956)
		(width 0.1651)
		(layer "F.Cu")
		(net "M_F_ODT<0>")
	)
	(via
		(at 263.08431 -92.24264)
		(size 0.508)
		(drill 0.254)
		(layers "F.Cu" "B.Cu")
		(net "M_F_ODT<0>")
	)
	(via
		(at 272.899886 -153.571956)
		(size 0.508)
		(drill 0.254)
		(layers "F.Cu" "B.Cu")
		(net "M_F_ODT<0>")
	)
	(segment
		(start 263.08431 -92.57411)
		(end 263.08431 -92.24264)
		(width 0.0889)
		(layer "In2.Cu")
		(net "M_F_ODT<0>")
	)
	(segment
		(start 272.899886 -153.571956)
		(end 272.899886 -151.768048)
		(width 0.14224)
		(layer "In2.Cu")
		(net "M_F_ODT<0>")
	)
	(segment
		(start 271.0434 -143.1798)
		(end 271.0434 -141.659356)
		(width 0.14224)
		(layer "In2.Cu")
		(net "M_F_ODT<0>")
	)
	(segment
		(start 263.59612 -96.500188)
		(end 263.60247 -96.48952)
		(width 0.0889)
		(layer "In2.Cu")
		(net "M_F_ODT<0>")
	)
	(segment
		(start 270.4973 -129.714244)
		(end 270.4973 -129.20091)
		(width 0.14224)
		(layer "In2.Cu")
		(net "M_F_ODT<0>")
	)
	(segment
		(start 272.46326 -151.331422)
		(end 272.46326 -149.768052)
		(width 0.14224)
		(layer "In2.Cu")
		(net "M_F_ODT<0>")
	)
	(segment
		(start 263.591294 -94.527624)
		(end 263.59612 -94.518988)
		(width 0.0889)
		(layer "In2.Cu")
		(net "M_F_ODT<0>")
	)
	(segment
		(start 271.018 -133.6548)
		(end 271.018 -131.4704)
		(width 0.14224)
		(layer "In2.Cu")
		(net "M_F_ODT<0>")
	)
	(segment
		(start 270.763746 -139.496546)
		(end 270.763746 -133.909054)
		(width 0.14224)
		(layer "In2.Cu")
		(net "M_F_ODT<0>")
	)
	(segment
		(start 270.763746 -133.909054)
		(end 271.018 -133.6548)
		(width 0.14224)
		(layer "In2.Cu")
		(net "M_F_ODT<0>")
	)
	(segment
		(start 264.8966 -103.058214)
		(end 264.8966 -102.6922)
		(width 0.0889)
		(layer "In2.Cu")
		(net "M_F_ODT<0>")
	)
	(segment
		(start 271.6276 -148.932392)
		(end 271.6276 -147.6756)
		(width 0.14224)
		(layer "In2.Cu")
		(net "M_F_ODT<0>")
	)
	(segment
		(start 270.6878 -130.6576)
		(end 270.829786 -130.515614)
		(width 0.14224)
		(layer "In2.Cu")
		(net "M_F_ODT<0>")
	)
	(segment
		(start 271.0434 -141.659356)
		(end 270.759936 -141.375892)
		(width 0.14224)
		(layer "In2.Cu")
		(net "M_F_ODT<0>")
	)
	(segment
		(start 263.591294 -98.490024)
		(end 263.59612 -98.481388)
		(width 0.0889)
		(layer "In2.Cu")
		(net "M_F_ODT<0>")
	)
	(segment
		(start 270.763746 -143.459454)
		(end 271.0434 -143.1798)
		(width 0.14224)
		(layer "In2.Cu")
		(net "M_F_ODT<0>")
	)
	(segment
		(start 264.922 -102.6668)
		(end 264.922 -101.494336)
		(width 0.0889)
		(layer "In2.Cu")
		(net "M_F_ODT<0>")
	)
	(segment
		(start 263.6774 -100.249736)
		(end 263.6774 -99.6696)
		(width 0.0889)
		(layer "In2.Cu")
		(net "M_F_ODT<0>")
	)
	(segment
		(start 270.763746 -146.811746)
		(end 270.763746 -143.459454)
		(width 0.14224)
		(layer "In2.Cu")
		(net "M_F_ODT<0>")
	)
	(segment
		(start 271.018 -131.4704)
		(end 270.6878 -131.1402)
		(width 0.14224)
		(layer "In2.Cu")
		(net "M_F_ODT<0>")
	)
	(segment
		(start 270.759936 -139.500356)
		(end 270.763746 -139.496546)
		(width 0.14224)
		(layer "In2.Cu")
		(net "M_F_ODT<0>")
	)
	(segment
		(start 263.557766 -93.61932)
		(end 263.557766 -93.047566)
		(width 0.0889)
		(layer "In2.Cu")
		(net "M_F_ODT<0>")
	)
	(segment
		(start 263.59612 -98.481388)
		(end 263.60247 -98.47072)
		(width 0.0889)
		(layer "In2.Cu")
		(net "M_F_ODT<0>")
	)
	(segment
		(start 270.759936 -141.375892)
		(end 270.759936 -139.500356)
		(width 0.14224)
		(layer "In2.Cu")
		(net "M_F_ODT<0>")
	)
	(segment
		(start 271.6276 -147.6756)
		(end 270.763746 -146.811746)
		(width 0.14224)
		(layer "In2.Cu")
		(net "M_F_ODT<0>")
	)
	(segment
		(start 263.60247 -93.939106)
		(end 263.59612 -93.928438)
		(width 0.0889)
		(layer "In2.Cu")
		(net "M_F_ODT<0>")
	)
	(segment
		(start 263.557766 -93.047566)
		(end 263.08431 -92.57411)
		(width 0.0889)
		(layer "In2.Cu")
		(net "M_F_ODT<0>")
	)
	(segment
		(start 263.59612 -95.509588)
		(end 263.60247 -95.49892)
		(width 0.0889)
		(layer "In2.Cu")
		(net "M_F_ODT<0>")
	)
	(segment
		(start 263.6774 -99.6696)
		(end 263.7028 -99.6442)
		(width 0.0889)
		(layer "In2.Cu")
		(net "M_F_ODT<0>")
	)
	(segment
		(start 263.591294 -95.518224)
		(end 263.59612 -95.509588)
		(width 0.0889)
		(layer "In2.Cu")
		(net "M_F_ODT<0>")
	)
	(segment
		(start 263.59612 -97.490788)
		(end 263.60247 -97.48012)
		(width 0.0889)
		(layer "In2.Cu")
		(net "M_F_ODT<0>")
	)
	(segment
		(start 263.591294 -96.508824)
		(end 263.59612 -96.500188)
		(width 0.0889)
		(layer "In2.Cu")
		(net "M_F_ODT<0>")
	)
	(segment
		(start 264.8966 -122.693938)
		(end 264.8966 -103.058214)
		(width 0.14224)
		(layer "In2.Cu")
		(net "M_F_ODT<0>")
	)
	(segment
		(start 270.6878 -131.1402)
		(end 270.6878 -130.6576)
		(width 0.14224)
		(layer "In2.Cu")
		(net "M_F_ODT<0>")
	)
	(segment
		(start 270.4973 -129.20091)
		(end 268.9098 -127.61341)
		(width 0.14224)
		(layer "In2.Cu")
		(net "M_F_ODT<0>")
	)
	(segment
		(start 272.899886 -151.768048)
		(end 272.46326 -151.331422)
		(width 0.14224)
		(layer "In2.Cu")
		(net "M_F_ODT<0>")
	)
	(segment
		(start 268.9098 -126.707138)
		(end 264.8966 -122.693938)
		(width 0.14224)
		(layer "In2.Cu")
		(net "M_F_ODT<0>")
	)
	(segment
		(start 263.591294 -97.499424)
		(end 263.59612 -97.490788)
		(width 0.0889)
		(layer "In2.Cu")
		(net "M_F_ODT<0>")
	)
	(segment
		(start 270.829786 -130.515614)
		(end 270.829786 -130.04673)
		(width 0.14224)
		(layer "In2.Cu")
		(net "M_F_ODT<0>")
	)
	(segment
		(start 264.922 -101.494336)
		(end 263.6774 -100.249736)
		(width 0.0889)
		(layer "In2.Cu")
		(net "M_F_ODT<0>")
	)
	(segment
		(start 270.829786 -130.04673)
		(end 270.4973 -129.714244)
		(width 0.14224)
		(layer "In2.Cu")
		(net "M_F_ODT<0>")
	)
	(segment
		(start 268.9098 -127.61341)
		(end 268.9098 -126.707138)
		(width 0.14224)
		(layer "In2.Cu")
		(net "M_F_ODT<0>")
	)
	(segment
		(start 264.8966 -102.6922)
		(end 264.922 -102.6668)
		(width 0.0889)
		(layer "In2.Cu")
		(net "M_F_ODT<0>")
	)
	(segment
		(start 272.46326 -149.768052)
		(end 271.6276 -148.932392)
		(width 0.14224)
		(layer "In2.Cu")
		(net "M_F_ODT<0>")
	)
	(arc
		(start 263.59612 -96.900238)
		(mid 263.54265 -96.705175)
		(end 263.591294 -96.508824)
		(width 0.0889)
		(layer "In2.Cu")
		(net "M_F_ODT<0>")
	)
	(arc
		(start 263.59612 -94.919038)
		(mid 263.54265 -94.723975)
		(end 263.591294 -94.527624)
		(width 0.0889)
		(layer "In2.Cu")
		(net "M_F_ODT<0>")
	)
	(arc
		(start 263.59612 -98.881438)
		(mid 263.54265 -98.686375)
		(end 263.591294 -98.490024)
		(width 0.0889)
		(layer "In2.Cu")
		(net "M_F_ODT<0>")
	)
	(arc
		(start 263.59612 -94.518988)
		(mid 263.675342 -94.22987)
		(end 263.60247 -93.939106)
		(width 0.0889)
		(layer "In2.Cu")
		(net "M_F_ODT<0>")
	)
	(arc
		(start 263.59612 -95.909638)
		(mid 263.54265 -95.714575)
		(end 263.591294 -95.518224)
		(width 0.0889)
		(layer "In2.Cu")
		(net "M_F_ODT<0>")
	)
	(arc
		(start 263.60247 -98.47072)
		(mid 263.675268 -98.179957)
		(end 263.59612 -97.890838)
		(width 0.0889)
		(layer "In2.Cu")
		(net "M_F_ODT<0>")
	)
	(arc
		(start 263.60247 -97.48012)
		(mid 263.675268 -97.189357)
		(end 263.59612 -96.900238)
		(width 0.0889)
		(layer "In2.Cu")
		(net "M_F_ODT<0>")
	)
	(arc
		(start 263.59612 -93.928438)
		(mid 263.54566 -93.777765)
		(end 263.557766 -93.61932)
		(width 0.0889)
		(layer "In2.Cu")
		(net "M_F_ODT<0>")
	)
	(arc
		(start 263.7028 -99.6442)
		(mid 263.72362 -99.252443)
		(end 263.59612 -98.881438)
		(width 0.0889)
		(layer "In2.Cu")
		(net "M_F_ODT<0>")
	)
	(arc
		(start 263.60247 -95.49892)
		(mid 263.675268 -95.208157)
		(end 263.59612 -94.919038)
		(width 0.0889)
		(layer "In2.Cu")
		(net "M_F_ODT<0>")
	)
	(arc
		(start 263.60247 -96.48952)
		(mid 263.675268 -96.198757)
		(end 263.59612 -95.909638)
		(width 0.0889)
		(layer "In2.Cu")
		(net "M_F_ODT<0>")
	)
	(arc
		(start 263.59612 -97.890838)
		(mid 263.54265 -97.695775)
		(end 263.591294 -97.499424)
		(width 0.0889)
		(layer "In2.Cu")
		(net "M_F_ODT<0>")
	)
	(segment
		(start 249.94997 -152.278842)
		(end 249.94997 -154.252168)
		(width 0.1651)
		(layer "F.Cu")
		(net "M_F_MA<9>")
	)
	(segment
		(start 256.78765 -89.27084)
		(end 256.21615 -89.27084)
		(width 0.1016)
		(layer "F.Cu")
		(net "M_F_MA<9>")
	)
	(segment
		(start 249.950478 -152.273)
		(end 249.94997 -152.278842)
		(width 0.1651)
		(layer "F.Cu")
		(net "M_F_MA<9>")
	)
	(via
		(at 256.21615 -89.27084)
		(size 0.508)
		(drill 0.254)
		(layers "F.Cu" "B.Cu")
		(net "M_F_MA<9>")
	)
	(via
		(at 249.94997 -154.252168)
		(size 0.508)
		(drill 0.254)
		(layers "F.Cu" "B.Cu")
		(net "M_F_MA<9>")
	)
	(via
		(at 249.94997 -150.788878)
		(size 0.4572)
		(drill 0.2032)
		(layers "F.Cu" "B.Cu")
		(net "M_F_MA<9>")
	)
	(segment
		(start 249.950478 -152.078436)
		(end 249.94997 -152.078182)
		(width 0.1651)
		(layer "B.Cu")
		(net "M_F_MA<9>")
	)
	(segment
		(start 249.94997 -152.078182)
		(end 249.94997 -150.788878)
		(width 0.1651)
		(layer "B.Cu")
		(net "M_F_MA<9>")
	)
	(segment
		(start 256.21615 -89.27084)
		(end 256.213864 -89.27084)
		(width 0.0889)
		(layer "In11.Cu")
		(net "M_F_MA<9>")
	)
	(segment
		(start 258.9276 -139.6238)
		(end 259.4864 -140.1826)
		(width 0.14224)
		(layer "In11.Cu")
		(net "M_F_MA<9>")
	)
	(segment
		(start 258.9276 -146.117818)
		(end 258.544314 -146.501104)
		(width 0.14224)
		(layer "In11.Cu")
		(net "M_F_MA<9>")
	)
	(segment
		(start 255.816354 -89.66835)
		(end 255.816354 -93.235018)
		(width 0.0889)
		(layer "In11.Cu")
		(net "M_F_MA<9>")
	)
	(segment
		(start 258.9276 -134.137146)
		(end 258.9276 -139.6238)
		(width 0.14224)
		(layer "In11.Cu")
		(net "M_F_MA<9>")
	)
	(segment
		(start 258.544314 -146.501104)
		(end 254.23114 -146.501104)
		(width 0.14224)
		(layer "In11.Cu")
		(net "M_F_MA<9>")
	)
	(segment
		(start 256.72796 -97.490788)
		(end 256.723134 -97.499424)
		(width 0.0889)
		(layer "In11.Cu")
		(net "M_F_MA<9>")
	)
	(segment
		(start 252.2728 -149.5044)
		(end 251.454666 -150.322534)
		(width 0.14224)
		(layer "In11.Cu")
		(net "M_F_MA<9>")
	)
	(segment
		(start 249.94997 -150.788878)
		(end 249.94997 -154.252168)
		(width 0.14224)
		(layer "In11.Cu")
		(net "M_F_MA<9>")
	)
	(segment
		(start 256.72796 -96.500188)
		(end 256.723134 -96.508824)
		(width 0.0889)
		(layer "In11.Cu")
		(net "M_F_MA<9>")
	)
	(segment
		(start 259.4864 -140.1826)
		(end 259.4864 -141.351)
		(width 0.14224)
		(layer "In11.Cu")
		(net "M_F_MA<9>")
	)
	(segment
		(start 251.454666 -150.322534)
		(end 250.416314 -150.322534)
		(width 0.14224)
		(layer "In11.Cu")
		(net "M_F_MA<9>")
	)
	(segment
		(start 258.155948 -128.675892)
		(end 258.691126 -129.21107)
		(width 0.14224)
		(layer "In11.Cu")
		(net "M_F_MA<9>")
	)
	(segment
		(start 256.73431 -95.49892)
		(end 256.72796 -95.509588)
		(width 0.0889)
		(layer "In11.Cu")
		(net "M_F_MA<9>")
	)
	(segment
		(start 250.416314 -150.322534)
		(end 249.94997 -150.788878)
		(width 0.14224)
		(layer "In11.Cu")
		(net "M_F_MA<9>")
	)
	(segment
		(start 256.73431 -97.48012)
		(end 256.72796 -97.490788)
		(width 0.0889)
		(layer "In11.Cu")
		(net "M_F_MA<9>")
	)
	(segment
		(start 258.9276 -141.9098)
		(end 258.9276 -146.117818)
		(width 0.14224)
		(layer "In11.Cu")
		(net "M_F_MA<9>")
	)
	(segment
		(start 256.213864 -89.27084)
		(end 255.816354 -89.66835)
		(width 0.0889)
		(layer "In11.Cu")
		(net "M_F_MA<9>")
	)
	(segment
		(start 256.734564 -98.469704)
		(end 256.627884 -98.660204)
		(width 0.0889)
		(layer "In11.Cu")
		(net "M_F_MA<9>")
	)
	(segment
		(start 256.629662 -100.876862)
		(end 257.0226 -101.2698)
		(width 0.0889)
		(layer "In11.Cu")
		(net "M_F_MA<9>")
	)
	(segment
		(start 254.23114 -146.501104)
		(end 252.922278 -147.809966)
		(width 0.14224)
		(layer "In11.Cu")
		(net "M_F_MA<9>")
	)
	(segment
		(start 256.198116 -93.633036)
		(end 256.23393 -93.633036)
		(width 0.0889)
		(layer "In11.Cu")
		(net "M_F_MA<9>")
	)
	(segment
		(start 252.922278 -149.108922)
		(end 252.5268 -149.5044)
		(width 0.14224)
		(layer "In11.Cu")
		(net "M_F_MA<9>")
	)
	(segment
		(start 256.629662 -99.0346)
		(end 256.629662 -100.876862)
		(width 0.0889)
		(layer "In11.Cu")
		(net "M_F_MA<9>")
	)
	(segment
		(start 258.155948 -102.403148)
		(end 258.155948 -128.675892)
		(width 0.14224)
		(layer "In11.Cu")
		(net "M_F_MA<9>")
	)
	(segment
		(start 255.864614 -93.424502)
		(end 255.86944 -93.433138)
		(width 0.0889)
		(layer "In11.Cu")
		(net "M_F_MA<9>")
	)
	(segment
		(start 252.5268 -149.5044)
		(end 252.2728 -149.5044)
		(width 0.14224)
		(layer "In11.Cu")
		(net "M_F_MA<9>")
	)
	(segment
		(start 252.922278 -147.809966)
		(end 252.922278 -149.108922)
		(width 0.14224)
		(layer "In11.Cu")
		(net "M_F_MA<9>")
	)
	(segment
		(start 257.0226 -101.2698)
		(end 258.155948 -102.403148)
		(width 0.14224)
		(layer "In11.Cu")
		(net "M_F_MA<9>")
	)
	(segment
		(start 256.73431 -96.48952)
		(end 256.72796 -96.500188)
		(width 0.0889)
		(layer "In11.Cu")
		(net "M_F_MA<9>")
	)
	(segment
		(start 258.691126 -133.900672)
		(end 258.9276 -134.137146)
		(width 0.14224)
		(layer "In11.Cu")
		(net "M_F_MA<9>")
	)
	(segment
		(start 256.627884 -98.660204)
		(end 256.627884 -99.032822)
		(width 0.0889)
		(layer "In11.Cu")
		(net "M_F_MA<9>")
	)
	(segment
		(start 256.72796 -94.518988)
		(end 256.723134 -94.527624)
		(width 0.0889)
		(layer "In11.Cu")
		(net "M_F_MA<9>")
	)
	(segment
		(start 259.4864 -141.351)
		(end 258.9276 -141.9098)
		(width 0.14224)
		(layer "In11.Cu")
		(net "M_F_MA<9>")
	)
	(segment
		(start 256.72796 -95.509588)
		(end 256.723134 -95.518224)
		(width 0.0889)
		(layer "In11.Cu")
		(net "M_F_MA<9>")
	)
	(segment
		(start 256.627884 -99.032822)
		(end 256.629662 -99.0346)
		(width 0.0889)
		(layer "In11.Cu")
		(net "M_F_MA<9>")
	)
	(segment
		(start 258.691126 -129.21107)
		(end 258.691126 -133.900672)
		(width 0.14224)
		(layer "In11.Cu")
		(net "M_F_MA<9>")
	)
	(arc
		(start 256.72796 -96.900238)
		(mid 256.807182 -97.189356)
		(end 256.73431 -97.48012)
		(width 0.0889)
		(layer "In11.Cu")
		(net "M_F_MA<9>")
	)
	(arc
		(start 256.723134 -95.518224)
		(mid 256.674379 -95.714576)
		(end 256.72796 -95.909638)
		(width 0.0889)
		(layer "In11.Cu")
		(net "M_F_MA<9>")
	)
	(arc
		(start 256.723134 -96.508824)
		(mid 256.674379 -96.705176)
		(end 256.72796 -96.900238)
		(width 0.0889)
		(layer "In11.Cu")
		(net "M_F_MA<9>")
	)
	(arc
		(start 256.723134 -97.499424)
		(mid 256.674379 -97.695776)
		(end 256.72796 -97.890838)
		(width 0.0889)
		(layer "In11.Cu")
		(net "M_F_MA<9>")
	)
	(arc
		(start 255.816354 -93.235018)
		(mid 255.828598 -93.33279)
		(end 255.864614 -93.424502)
		(width 0.0889)
		(layer "In11.Cu")
		(net "M_F_MA<9>")
	)
	(arc
		(start 256.23393 -93.633036)
		(mid 256.732181 -93.935876)
		(end 256.72796 -94.518988)
		(width 0.0889)
		(layer "In11.Cu")
		(net "M_F_MA<9>")
	)
	(arc
		(start 255.86944 -93.433138)
		(mid 256.008184 -93.575171)
		(end 256.198116 -93.633036)
		(width 0.0889)
		(layer "In11.Cu")
		(net "M_F_MA<9>")
	)
	(arc
		(start 256.72796 -95.909638)
		(mid 256.807182 -96.198756)
		(end 256.73431 -96.48952)
		(width 0.0889)
		(layer "In11.Cu")
		(net "M_F_MA<9>")
	)
	(arc
		(start 256.72796 -97.890838)
		(mid 256.807052 -98.179418)
		(end 256.734564 -98.469704)
		(width 0.0889)
		(layer "In11.Cu")
		(net "M_F_MA<9>")
	)
	(arc
		(start 256.72796 -94.919038)
		(mid 256.807182 -95.208156)
		(end 256.73431 -95.49892)
		(width 0.0889)
		(layer "In11.Cu")
		(net "M_F_MA<9>")
	)
	(arc
		(start 256.723134 -94.527624)
		(mid 256.674379 -94.723976)
		(end 256.72796 -94.919038)
		(width 0.0889)
		(layer "In11.Cu")
		(net "M_F_MA<9>")
	)
	(segment
		(start 255.92913 -90.756486)
		(end 255.35763 -90.756486)
		(width 0.1016)
		(layer "F.Cu")
		(net "M_F_MA<8>")
	)
	(segment
		(start 251.6505 -152.273)
		(end 251.649992 -152.278842)
		(width 0.1651)
		(layer "F.Cu")
		(net "M_F_MA<8>")
	)
	(segment
		(start 251.649992 -152.278842)
		(end 251.649992 -154.252168)
		(width 0.1651)
		(layer "F.Cu")
		(net "M_F_MA<8>")
	)
	(via
		(at 255.35763 -90.756486)
		(size 0.508)
		(drill 0.254)
		(layers "F.Cu" "B.Cu")
		(net "M_F_MA<8>")
	)
	(via
		(at 251.649992 -150.788878)
		(size 0.4572)
		(drill 0.2032)
		(layers "F.Cu" "B.Cu")
		(net "M_F_MA<8>")
	)
	(via
		(at 251.649992 -154.252168)
		(size 0.508)
		(drill 0.254)
		(layers "F.Cu" "B.Cu")
		(net "M_F_MA<8>")
	)
	(segment
		(start 251.649992 -152.078182)
		(end 251.649992 -150.788878)
		(width 0.1651)
		(layer "B.Cu")
		(net "M_F_MA<8>")
	)
	(segment
		(start 251.6505 -152.078436)
		(end 251.649992 -152.078182)
		(width 0.1651)
		(layer "B.Cu")
		(net "M_F_MA<8>")
	)
	(segment
		(start 251.8664 -154.955748)
		(end 251.8664 -154.468576)
		(width 0.14224)
		(layer "In2.Cu")
		(net "M_F_MA<8>")
	)
	(segment
		(start 251.2822 -154.74696)
		(end 251.2822 -154.955748)
		(width 0.14224)
		(layer "In2.Cu")
		(net "M_F_MA<8>")
	)
	(segment
		(start 255.01727 -92.52712)
		(end 255.01092 -92.537788)
		(width 0.0889)
		(layer "In2.Cu")
		(net "M_F_MA<8>")
	)
	(segment
		(start 252.063504 -132.594096)
		(end 252.063504 -136.061704)
		(width 0.14224)
		(layer "In2.Cu")
		(net "M_F_MA<8>")
	)
	(segment
		(start 251.9426 -129.7686)
		(end 252.1458 -129.9718)
		(width 0.14224)
		(layer "In2.Cu")
		(net "M_F_MA<8>")
	)
	(segment
		(start 255.3716 -105.0544)
		(end 255.3716 -125.042168)
		(width 0.14224)
		(layer "In2.Cu")
		(net "M_F_MA<8>")
	)
	(segment
		(start 250.850654 -152.946862)
		(end 251.257054 -153.353262)
		(width 0.14224)
		(layer "In2.Cu")
		(net "M_F_MA<8>")
	)
	(segment
		(start 252.089666 -136.087866)
		(end 252.089666 -146.563334)
		(width 0.14224)
		(layer "In2.Cu")
		(net "M_F_MA<8>")
	)
	(segment
		(start 252.063504 -136.061704)
		(end 252.089666 -136.087866)
		(width 0.14224)
		(layer "In2.Cu")
		(net "M_F_MA<8>")
	)
	(segment
		(start 255.01092 -96.500188)
		(end 255.006094 -96.508824)
		(width 0.0889)
		(layer "In2.Cu")
		(net "M_F_MA<8>")
	)
	(segment
		(start 254.946404 -99.90582)
		(end 255.143 -100.102416)
		(width 0.0889)
		(layer "In2.Cu")
		(net "M_F_MA<8>")
	)
	(segment
		(start 251.257054 -153.353262)
		(end 251.257054 -153.73223)
		(width 0.14224)
		(layer "In2.Cu")
		(net "M_F_MA<8>")
	)
	(segment
		(start 255.01092 -95.509588)
		(end 255.006094 -95.518224)
		(width 0.0889)
		(layer "In2.Cu")
		(net "M_F_MA<8>")
	)
	(segment
		(start 251.9934 -131.191)
		(end 252.1204 -131.318)
		(width 0.14224)
		(layer "In2.Cu")
		(net "M_F_MA<8>")
	)
	(segment
		(start 255.01727 -97.48012)
		(end 255.01092 -97.490788)
		(width 0.0889)
		(layer "In2.Cu")
		(net "M_F_MA<8>")
	)
	(segment
		(start 251.7394 -155.082748)
		(end 251.8664 -154.955748)
		(width 0.14224)
		(layer "In2.Cu")
		(net "M_F_MA<8>")
	)
	(segment
		(start 252.1204 -131.318)
		(end 252.1204 -132.5372)
		(width 0.14224)
		(layer "In2.Cu")
		(net "M_F_MA<8>")
	)
	(segment
		(start 255.01092 -93.928438)
		(end 255.01727 -93.939106)
		(width 0.0889)
		(layer "In2.Cu")
		(net "M_F_MA<8>")
	)
	(segment
		(start 250.959874 -154.02941)
		(end 250.959874 -154.424634)
		(width 0.14224)
		(layer "In2.Cu")
		(net "M_F_MA<8>")
	)
	(segment
		(start 255.01727 -96.48952)
		(end 255.01092 -96.500188)
		(width 0.0889)
		(layer "In2.Cu")
		(net "M_F_MA<8>")
	)
	(segment
		(start 252.1204 -132.5372)
		(end 252.063504 -132.594096)
		(width 0.14224)
		(layer "In2.Cu")
		(net "M_F_MA<8>")
	)
	(segment
		(start 251.9426 -128.471168)
		(end 251.9426 -129.7686)
		(width 0.14224)
		(layer "In2.Cu")
		(net "M_F_MA<8>")
	)
	(segment
		(start 255.028192 -91.51747)
		(end 255.006094 -91.555824)
		(width 0.0889)
		(layer "In2.Cu")
		(net "M_F_MA<8>")
	)
	(segment
		(start 255.01727 -95.49892)
		(end 255.01092 -95.509588)
		(width 0.0889)
		(layer "In2.Cu")
		(net "M_F_MA<8>")
	)
	(segment
		(start 255.3716 -102.775512)
		(end 255.3716 -105.0544)
		(width 0.0889)
		(layer "In2.Cu")
		(net "M_F_MA<8>")
	)
	(segment
		(start 251.212858 -149.739858)
		(end 251.649992 -150.176992)
		(width 0.14224)
		(layer "In2.Cu")
		(net "M_F_MA<8>")
	)
	(segment
		(start 252.089666 -146.563334)
		(end 251.212858 -147.440142)
		(width 0.14224)
		(layer "In2.Cu")
		(net "M_F_MA<8>")
	)
	(segment
		(start 255.35763 -90.756486)
		(end 255.028192 -91.51747)
		(width 0.0889)
		(layer "In2.Cu")
		(net "M_F_MA<8>")
	)
	(segment
		(start 255.01092 -97.490788)
		(end 255.006094 -97.499424)
		(width 0.0889)
		(layer "In2.Cu")
		(net "M_F_MA<8>")
	)
	(segment
		(start 251.2822 -154.955748)
		(end 251.4092 -155.082748)
		(width 0.14224)
		(layer "In2.Cu")
		(net "M_F_MA<8>")
	)
	(segment
		(start 255.3716 -125.042168)
		(end 251.9426 -128.471168)
		(width 0.14224)
		(layer "In2.Cu")
		(net "M_F_MA<8>")
	)
	(segment
		(start 255.143 -102.546912)
		(end 255.3716 -102.775512)
		(width 0.0889)
		(layer "In2.Cu")
		(net "M_F_MA<8>")
	)
	(segment
		(start 251.8664 -154.468576)
		(end 251.649992 -154.252168)
		(width 0.14224)
		(layer "In2.Cu")
		(net "M_F_MA<8>")
	)
	(segment
		(start 254.946404 -98.728276)
		(end 254.946404 -99.90582)
		(width 0.0889)
		(layer "In2.Cu")
		(net "M_F_MA<8>")
	)
	(segment
		(start 251.212858 -147.440142)
		(end 251.212858 -149.739858)
		(width 0.14224)
		(layer "In2.Cu")
		(net "M_F_MA<8>")
	)
	(segment
		(start 251.4092 -155.082748)
		(end 251.7394 -155.082748)
		(width 0.14224)
		(layer "In2.Cu")
		(net "M_F_MA<8>")
	)
	(segment
		(start 251.649992 -150.788878)
		(end 251.444252 -150.788878)
		(width 0.14224)
		(layer "In2.Cu")
		(net "M_F_MA<8>")
	)
	(segment
		(start 251.9934 -130.6576)
		(end 251.9934 -131.191)
		(width 0.14224)
		(layer "In2.Cu")
		(net "M_F_MA<8>")
	)
	(segment
		(start 252.1458 -129.9718)
		(end 252.1458 -130.5052)
		(width 0.14224)
		(layer "In2.Cu")
		(net "M_F_MA<8>")
	)
	(segment
		(start 251.649992 -150.176992)
		(end 251.649992 -150.788878)
		(width 0.14224)
		(layer "In2.Cu")
		(net "M_F_MA<8>")
	)
	(segment
		(start 255.143 -100.102416)
		(end 255.143 -102.546912)
		(width 0.0889)
		(layer "In2.Cu")
		(net "M_F_MA<8>")
	)
	(segment
		(start 252.1458 -130.5052)
		(end 251.9934 -130.6576)
		(width 0.14224)
		(layer "In2.Cu")
		(net "M_F_MA<8>")
	)
	(segment
		(start 251.444252 -150.788878)
		(end 250.850654 -151.382476)
		(width 0.14224)
		(layer "In2.Cu")
		(net "M_F_MA<8>")
	)
	(segment
		(start 251.257054 -153.73223)
		(end 250.959874 -154.02941)
		(width 0.14224)
		(layer "In2.Cu")
		(net "M_F_MA<8>")
	)
	(segment
		(start 250.959874 -154.424634)
		(end 251.2822 -154.74696)
		(width 0.14224)
		(layer "In2.Cu")
		(net "M_F_MA<8>")
	)
	(segment
		(start 255.01092 -92.537788)
		(end 255.006094 -92.546424)
		(width 0.0889)
		(layer "In2.Cu")
		(net "M_F_MA<8>")
	)
	(segment
		(start 250.850654 -151.382476)
		(end 250.850654 -152.946862)
		(width 0.14224)
		(layer "In2.Cu")
		(net "M_F_MA<8>")
	)
	(segment
		(start 255.01092 -94.518988)
		(end 255.006094 -94.527624)
		(width 0.0889)
		(layer "In2.Cu")
		(net "M_F_MA<8>")
	)
	(arc
		(start 255.006094 -94.527624)
		(mid 254.957339 -94.723976)
		(end 255.01092 -94.919038)
		(width 0.0889)
		(layer "In2.Cu")
		(net "M_F_MA<8>")
	)
	(arc
		(start 255.006094 -91.555824)
		(mid 254.957339 -91.752176)
		(end 255.01092 -91.947238)
		(width 0.0889)
		(layer "In2.Cu")
		(net "M_F_MA<8>")
	)
	(arc
		(start 255.01092 -95.909638)
		(mid 255.090142 -96.198756)
		(end 255.01727 -96.48952)
		(width 0.0889)
		(layer "In2.Cu")
		(net "M_F_MA<8>")
	)
	(arc
		(start 255.01092 -97.890838)
		(mid 255.090142 -98.179956)
		(end 255.01727 -98.47072)
		(width 0.0889)
		(layer "In2.Cu")
		(net "M_F_MA<8>")
	)
	(arc
		(start 255.006094 -92.546424)
		(mid 254.957339 -92.742776)
		(end 255.01092 -92.937838)
		(width 0.0889)
		(layer "In2.Cu")
		(net "M_F_MA<8>")
	)
	(arc
		(start 255.01092 -93.528642)
		(mid 254.957421 -93.72854)
		(end 255.01092 -93.928438)
		(width 0.0889)
		(layer "In2.Cu")
		(net "M_F_MA<8>")
	)
	(arc
		(start 255.006094 -96.508824)
		(mid 254.957339 -96.705176)
		(end 255.01092 -96.900238)
		(width 0.0889)
		(layer "In2.Cu")
		(net "M_F_MA<8>")
	)
	(arc
		(start 255.01727 -98.47072)
		(mid 254.96444 -98.594712)
		(end 254.946404 -98.728276)
		(width 0.0889)
		(layer "In2.Cu")
		(net "M_F_MA<8>")
	)
	(arc
		(start 255.01092 -96.900238)
		(mid 255.090142 -97.189356)
		(end 255.01727 -97.48012)
		(width 0.0889)
		(layer "In2.Cu")
		(net "M_F_MA<8>")
	)
	(arc
		(start 255.01727 -93.939106)
		(mid 255.090068 -94.229869)
		(end 255.01092 -94.518988)
		(width 0.0889)
		(layer "In2.Cu")
		(net "M_F_MA<8>")
	)
	(arc
		(start 255.01092 -92.937838)
		(mid 255.090051 -93.23324)
		(end 255.01092 -93.528642)
		(width 0.0889)
		(layer "In2.Cu")
		(net "M_F_MA<8>")
	)
	(arc
		(start 255.006094 -97.499424)
		(mid 254.957339 -97.695776)
		(end 255.01092 -97.890838)
		(width 0.0889)
		(layer "In2.Cu")
		(net "M_F_MA<8>")
	)
	(arc
		(start 255.01092 -94.919038)
		(mid 255.090142 -95.208156)
		(end 255.01727 -95.49892)
		(width 0.0889)
		(layer "In2.Cu")
		(net "M_F_MA<8>")
	)
	(arc
		(start 255.01092 -91.947238)
		(mid 255.090142 -92.236356)
		(end 255.01727 -92.52712)
		(width 0.0889)
		(layer "In2.Cu")
		(net "M_F_MA<8>")
	)
	(arc
		(start 255.006094 -95.518224)
		(mid 254.957339 -95.714576)
		(end 255.01092 -95.909638)
		(width 0.0889)
		(layer "In2.Cu")
		(net "M_F_MA<8>")
	)
	(segment
		(start 255.07061 -90.26144)
		(end 254.49911 -90.26144)
		(width 0.1016)
		(layer "F.Cu")
		(net "M_F_MA<7>")
	)
	(segment
		(start 250.799854 -156.87294)
		(end 250.800362 -156.87294)
		(width 0.1651)
		(layer "F.Cu")
		(net "M_F_MA<7>")
	)
	(segment
		(start 250.799854 -154.905456)
		(end 250.799854 -156.87294)
		(width 0.1651)
		(layer "F.Cu")
		(net "M_F_MA<7>")
	)
	(via
		(at 250.799854 -154.905456)
		(size 0.508)
		(drill 0.254)
		(layers "F.Cu" "B.Cu")
		(net "M_F_MA<7>")
	)
	(via
		(at 250.799854 -148.771356)
		(size 0.4572)
		(drill 0.2032)
		(layers "F.Cu" "B.Cu")
		(net "M_F_MA<7>")
	)
	(via
		(at 254.49911 -90.26144)
		(size 0.508)
		(drill 0.254)
		(layers "F.Cu" "B.Cu")
		(net "M_F_MA<7>")
	)
	(segment
		(start 250.799854 -147.478496)
		(end 250.799854 -148.771356)
		(width 0.1651)
		(layer "B.Cu")
		(net "M_F_MA<7>")
	)
	(segment
		(start 250.800362 -147.478496)
		(end 250.799854 -147.478496)
		(width 0.1651)
		(layer "B.Cu")
		(net "M_F_MA<7>")
	)
	(segment
		(start 252.476 -126.740412)
		(end 252.019816 -127.196596)
		(width 0.14224)
		(layer "In2.Cu")
		(net "M_F_MA<7>")
	)
	(segment
		(start 254.84582 -95.414338)
		(end 254.83947 -95.425006)
		(width 0.0889)
		(layer "In2.Cu")
		(net "M_F_MA<7>")
	)
	(segment
		(start 254.49911 -90.26144)
		(end 254.829056 -91.023186)
		(width 0.0889)
		(layer "In2.Cu")
		(net "M_F_MA<7>")
	)
	(segment
		(start 254.850646 -96.396302)
		(end 254.84582 -96.404938)
		(width 0.0889)
		(layer "In2.Cu")
		(net "M_F_MA<7>")
	)
	(segment
		(start 253.54153 -125.46965)
		(end 253.713742 -125.641862)
		(width 0.14224)
		(layer "In2.Cu")
		(net "M_F_MA<7>")
	)
	(segment
		(start 251.2822 -127.584708)
		(end 251.2822 -129.8448)
		(width 0.14224)
		(layer "In2.Cu")
		(net "M_F_MA<7>")
	)
	(segment
		(start 251.209048 -146.377152)
		(end 250.799854 -146.786346)
		(width 0.14224)
		(layer "In2.Cu")
		(net "M_F_MA<7>")
	)
	(segment
		(start 254.850646 -91.443302)
		(end 254.84582 -91.451938)
		(width 0.0889)
		(layer "In2.Cu")
		(net "M_F_MA<7>")
	)
	(segment
		(start 254.829056 -91.023186)
		(end 254.84582 -91.051888)
		(width 0.0889)
		(layer "In2.Cu")
		(net "M_F_MA<7>")
	)
	(segment
		(start 254.121666 -124.900182)
		(end 253.87427 -124.900182)
		(width 0.14224)
		(layer "In2.Cu")
		(net "M_F_MA<7>")
	)
	(segment
		(start 254.8636 -124.873512)
		(end 254.62103 -125.116082)
		(width 0.14224)
		(layer "In2.Cu")
		(net "M_F_MA<7>")
	)
	(segment
		(start 254.337566 -125.116082)
		(end 254.121666 -124.900182)
		(width 0.14224)
		(layer "In2.Cu")
		(net "M_F_MA<7>")
	)
	(segment
		(start 250.342654 -151.048466)
		(end 250.342654 -153.822146)
		(width 0.14224)
		(layer "In2.Cu")
		(net "M_F_MA<7>")
	)
	(segment
		(start 253.87427 -124.900182)
		(end 253.54153 -125.232922)
		(width 0.14224)
		(layer "In2.Cu")
		(net "M_F_MA<7>")
	)
	(segment
		(start 251.240544 -144.288256)
		(end 251.209048 -144.319752)
		(width 0.14224)
		(layer "In2.Cu")
		(net "M_F_MA<7>")
	)
	(segment
		(start 251.0028 -132.2832)
		(end 251.234956 -132.515356)
		(width 0.14224)
		(layer "In2.Cu")
		(net "M_F_MA<7>")
	)
	(segment
		(start 254.84582 -96.404938)
		(end 254.83947 -96.415606)
		(width 0.0889)
		(layer "In2.Cu")
		(net "M_F_MA<7>")
	)
	(segment
		(start 254.8636 -103.051356)
		(end 254.8636 -124.873512)
		(width 0.14224)
		(layer "In2.Cu")
		(net "M_F_MA<7>")
	)
	(segment
		(start 254.62103 -125.116082)
		(end 254.337566 -125.116082)
		(width 0.14224)
		(layer "In2.Cu")
		(net "M_F_MA<7>")
	)
	(segment
		(start 254.84582 -92.442538)
		(end 254.83947 -92.453206)
		(width 0.0889)
		(layer "In2.Cu")
		(net "M_F_MA<7>")
	)
	(segment
		(start 253.54153 -125.232922)
		(end 253.54153 -125.46965)
		(width 0.14224)
		(layer "In2.Cu")
		(net "M_F_MA<7>")
	)
	(segment
		(start 253.713742 -125.925834)
		(end 253.426468 -126.213108)
		(width 0.14224)
		(layer "In2.Cu")
		(net "M_F_MA<7>")
	)
	(segment
		(start 253.426468 -126.213108)
		(end 253.135384 -126.213108)
		(width 0.14224)
		(layer "In2.Cu")
		(net "M_F_MA<7>")
	)
	(segment
		(start 251.2822 -129.8448)
		(end 251.1552 -129.9718)
		(width 0.14224)
		(layer "In2.Cu")
		(net "M_F_MA<7>")
	)
	(segment
		(start 251.1552 -129.9718)
		(end 251.1552 -130.4798)
		(width 0.14224)
		(layer "In2.Cu")
		(net "M_F_MA<7>")
	)
	(segment
		(start 254.6858 -99.000564)
		(end 254.6858 -99.962716)
		(width 0.0889)
		(layer "In2.Cu")
		(net "M_F_MA<7>")
	)
	(segment
		(start 250.40717 -153.886662)
		(end 250.40717 -154.512772)
		(width 0.14224)
		(layer "In2.Cu")
		(net "M_F_MA<7>")
	)
	(segment
		(start 251.3076 -130.6322)
		(end 251.3076 -131.191)
		(width 0.14224)
		(layer "In2.Cu")
		(net "M_F_MA<7>")
	)
	(segment
		(start 250.361704 -151.029416)
		(end 250.342654 -151.048466)
		(width 0.14224)
		(layer "In2.Cu")
		(net "M_F_MA<7>")
	)
	(segment
		(start 251.234956 -136.064244)
		(end 251.210826 -136.088374)
		(width 0.14224)
		(layer "In2.Cu")
		(net "M_F_MA<7>")
	)
	(segment
		(start 253.713742 -125.641862)
		(end 253.713742 -125.925834)
		(width 0.14224)
		(layer "In2.Cu")
		(net "M_F_MA<7>")
	)
	(segment
		(start 250.799854 -148.771356)
		(end 250.5964 -148.97481)
		(width 0.14224)
		(layer "In2.Cu")
		(net "M_F_MA<7>")
	)
	(segment
		(start 251.1552 -130.4798)
		(end 251.3076 -130.6322)
		(width 0.14224)
		(layer "In2.Cu")
		(net "M_F_MA<7>")
	)
	(segment
		(start 251.234956 -132.515356)
		(end 251.234956 -136.064244)
		(width 0.14224)
		(layer "In2.Cu")
		(net "M_F_MA<7>")
	)
	(segment
		(start 254.8636 -100.140516)
		(end 254.8636 -103.051356)
		(width 0.0889)
		(layer "In2.Cu")
		(net "M_F_MA<7>")
	)
	(segment
		(start 252.68174 -126.046992)
		(end 252.476 -126.252732)
		(width 0.14224)
		(layer "In2.Cu")
		(net "M_F_MA<7>")
	)
	(segment
		(start 250.342654 -153.822146)
		(end 250.40717 -153.886662)
		(width 0.14224)
		(layer "In2.Cu")
		(net "M_F_MA<7>")
	)
	(segment
		(start 251.3076 -131.191)
		(end 251.0028 -131.4958)
		(width 0.14224)
		(layer "In2.Cu")
		(net "M_F_MA<7>")
	)
	(segment
		(start 250.361704 -150.493984)
		(end 250.361704 -151.029416)
		(width 0.14224)
		(layer "In2.Cu")
		(net "M_F_MA<7>")
	)
	(segment
		(start 251.0028 -131.4958)
		(end 251.0028 -132.2832)
		(width 0.14224)
		(layer "In2.Cu")
		(net "M_F_MA<7>")
	)
	(segment
		(start 251.240544 -139.99464)
		(end 251.240544 -144.288256)
		(width 0.14224)
		(layer "In2.Cu")
		(net "M_F_MA<7>")
	)
	(segment
		(start 250.799854 -146.786346)
		(end 250.799854 -148.771356)
		(width 0.14224)
		(layer "In2.Cu")
		(net "M_F_MA<7>")
	)
	(segment
		(start 251.670312 -127.196596)
		(end 251.2822 -127.584708)
		(width 0.14224)
		(layer "In2.Cu")
		(net "M_F_MA<7>")
	)
	(segment
		(start 252.969268 -126.046992)
		(end 252.68174 -126.046992)
		(width 0.14224)
		(layer "In2.Cu")
		(net "M_F_MA<7>")
	)
	(segment
		(start 254.84582 -91.451938)
		(end 254.83947 -91.462606)
		(width 0.0889)
		(layer "In2.Cu")
		(net "M_F_MA<7>")
	)
	(segment
		(start 253.135384 -126.213108)
		(end 252.969268 -126.046992)
		(width 0.14224)
		(layer "In2.Cu")
		(net "M_F_MA<7>")
	)
	(segment
		(start 254.6858 -99.962716)
		(end 254.8636 -100.140516)
		(width 0.0889)
		(layer "In2.Cu")
		(net "M_F_MA<7>")
	)
	(segment
		(start 250.40717 -154.512772)
		(end 250.799854 -154.905456)
		(width 0.14224)
		(layer "In2.Cu")
		(net "M_F_MA<7>")
	)
	(segment
		(start 250.5964 -150.259288)
		(end 250.361704 -150.493984)
		(width 0.14224)
		(layer "In2.Cu")
		(net "M_F_MA<7>")
	)
	(segment
		(start 251.210826 -139.964922)
		(end 251.240544 -139.99464)
		(width 0.14224)
		(layer "In2.Cu")
		(net "M_F_MA<7>")
	)
	(segment
		(start 252.019816 -127.196596)
		(end 251.670312 -127.196596)
		(width 0.14224)
		(layer "In2.Cu")
		(net "M_F_MA<7>")
	)
	(segment
		(start 254.850646 -98.377502)
		(end 254.84582 -98.386138)
		(width 0.0889)
		(layer "In2.Cu")
		(net "M_F_MA<7>")
	)
	(segment
		(start 251.210826 -136.088374)
		(end 251.210826 -139.964922)
		(width 0.14224)
		(layer "In2.Cu")
		(net "M_F_MA<7>")
	)
	(segment
		(start 250.5964 -148.97481)
		(end 250.5964 -150.259288)
		(width 0.14224)
		(layer "In2.Cu")
		(net "M_F_MA<7>")
	)
	(segment
		(start 254.850646 -92.433902)
		(end 254.84582 -92.442538)
		(width 0.0889)
		(layer "In2.Cu")
		(net "M_F_MA<7>")
	)
	(segment
		(start 254.850646 -97.386902)
		(end 254.84582 -97.395538)
		(width 0.0889)
		(layer "In2.Cu")
		(net "M_F_MA<7>")
	)
	(segment
		(start 254.850646 -93.424502)
		(end 254.84582 -93.433138)
		(width 0.0889)
		(layer "In2.Cu")
		(net "M_F_MA<7>")
	)
	(segment
		(start 254.83947 -94.01302)
		(end 254.84582 -94.023688)
		(width 0.0889)
		(layer "In2.Cu")
		(net "M_F_MA<7>")
	)
	(segment
		(start 252.476 -126.252732)
		(end 252.476 -126.740412)
		(width 0.14224)
		(layer "In2.Cu")
		(net "M_F_MA<7>")
	)
	(segment
		(start 251.209048 -144.319752)
		(end 251.209048 -146.377152)
		(width 0.14224)
		(layer "In2.Cu")
		(net "M_F_MA<7>")
	)
	(segment
		(start 254.850646 -95.405702)
		(end 254.84582 -95.414338)
		(width 0.0889)
		(layer "In2.Cu")
		(net "M_F_MA<7>")
	)
	(segment
		(start 254.84582 -97.395538)
		(end 254.83947 -97.406206)
		(width 0.0889)
		(layer "In2.Cu")
		(net "M_F_MA<7>")
	)
	(arc
		(start 254.84582 -96.004888)
		(mid 254.89929 -96.199951)
		(end 254.850646 -96.396302)
		(width 0.0889)
		(layer "In2.Cu")
		(net "M_F_MA<7>")
	)
	(arc
		(start 254.83947 -97.406206)
		(mid 254.766672 -97.696969)
		(end 254.84582 -97.986088)
		(width 0.0889)
		(layer "In2.Cu")
		(net "M_F_MA<7>")
	)
	(arc
		(start 254.83947 -95.425006)
		(mid 254.766672 -95.715769)
		(end 254.84582 -96.004888)
		(width 0.0889)
		(layer "In2.Cu")
		(net "M_F_MA<7>")
	)
	(arc
		(start 254.84582 -94.423484)
		(mid 254.766689 -94.718886)
		(end 254.84582 -95.014288)
		(width 0.0889)
		(layer "In2.Cu")
		(net "M_F_MA<7>")
	)
	(arc
		(start 254.84582 -98.386138)
		(mid 254.726435 -98.683099)
		(end 254.6858 -99.000564)
		(width 0.0889)
		(layer "In2.Cu")
		(net "M_F_MA<7>")
	)
	(arc
		(start 254.83947 -96.415606)
		(mid 254.766672 -96.706369)
		(end 254.84582 -96.995488)
		(width 0.0889)
		(layer "In2.Cu")
		(net "M_F_MA<7>")
	)
	(arc
		(start 254.83947 -92.453206)
		(mid 254.766672 -92.743969)
		(end 254.84582 -93.033088)
		(width 0.0889)
		(layer "In2.Cu")
		(net "M_F_MA<7>")
	)
	(arc
		(start 254.84582 -92.042488)
		(mid 254.89929 -92.237551)
		(end 254.850646 -92.433902)
		(width 0.0889)
		(layer "In2.Cu")
		(net "M_F_MA<7>")
	)
	(arc
		(start 254.84582 -96.995488)
		(mid 254.89929 -97.190551)
		(end 254.850646 -97.386902)
		(width 0.0889)
		(layer "In2.Cu")
		(net "M_F_MA<7>")
	)
	(arc
		(start 254.84582 -93.033088)
		(mid 254.89929 -93.228151)
		(end 254.850646 -93.424502)
		(width 0.0889)
		(layer "In2.Cu")
		(net "M_F_MA<7>")
	)
	(arc
		(start 254.84582 -97.986088)
		(mid 254.89929 -98.181151)
		(end 254.850646 -98.377502)
		(width 0.0889)
		(layer "In2.Cu")
		(net "M_F_MA<7>")
	)
	(arc
		(start 254.84582 -91.051888)
		(mid 254.89929 -91.246951)
		(end 254.850646 -91.443302)
		(width 0.0889)
		(layer "In2.Cu")
		(net "M_F_MA<7>")
	)
	(arc
		(start 254.83947 -91.462606)
		(mid 254.766672 -91.753369)
		(end 254.84582 -92.042488)
		(width 0.0889)
		(layer "In2.Cu")
		(net "M_F_MA<7>")
	)
	(arc
		(start 254.84582 -94.023688)
		(mid 254.899319 -94.223586)
		(end 254.84582 -94.423484)
		(width 0.0889)
		(layer "In2.Cu")
		(net "M_F_MA<7>")
	)
	(arc
		(start 254.84582 -93.433138)
		(mid 254.766598 -93.722256)
		(end 254.83947 -94.01302)
		(width 0.0889)
		(layer "In2.Cu")
		(net "M_F_MA<7>")
	)
	(arc
		(start 254.84582 -95.014288)
		(mid 254.89929 -95.209351)
		(end 254.850646 -95.405702)
		(width 0.0889)
		(layer "In2.Cu")
		(net "M_F_MA<7>")
	)
	(segment
		(start 252.500384 -152.273)
		(end 252.499876 -152.278842)
		(width 0.1651)
		(layer "F.Cu")
		(net "M_F_MA<6>")
	)
	(segment
		(start 255.92913 -93.72854)
		(end 255.35763 -93.72854)
		(width 0.1016)
		(layer "F.Cu")
		(net "M_F_MA<6>")
	)
	(segment
		(start 252.499876 -152.278842)
		(end 252.499876 -153.571956)
		(width 0.1651)
		(layer "F.Cu")
		(net "M_F_MA<6>")
	)
	(via
		(at 252.499876 -150.788878)
		(size 0.4572)
		(drill 0.2032)
		(layers "F.Cu" "B.Cu")
		(net "M_F_MA<6>")
	)
	(via
		(at 252.499876 -153.571956)
		(size 0.508)
		(drill 0.254)
		(layers "F.Cu" "B.Cu")
		(net "M_F_MA<6>")
	)
	(via
		(at 255.35763 -93.72854)
		(size 0.508)
		(drill 0.254)
		(layers "F.Cu" "B.Cu")
		(net "M_F_MA<6>")
	)
	(segment
		(start 252.499876 -152.078182)
		(end 252.499876 -150.788878)
		(width 0.1651)
		(layer "B.Cu")
		(net "M_F_MA<6>")
	)
	(segment
		(start 252.500384 -152.078436)
		(end 252.499876 -152.078182)
		(width 0.1651)
		(layer "B.Cu")
		(net "M_F_MA<6>")
	)
	(segment
		(start 252.91415 -145.01495)
		(end 252.91415 -140.18895)
		(width 0.14224)
		(layer "In2.Cu")
		(net "M_F_MA<6>")
	)
	(segment
		(start 252.93701 -136.06399)
		(end 253.0094 -135.9916)
		(width 0.14224)
		(layer "In2.Cu")
		(net "M_F_MA<6>")
	)
	(segment
		(start 252.8062 -132.2832)
		(end 252.8062 -131.3688)
		(width 0.14224)
		(layer "In2.Cu")
		(net "M_F_MA<6>")
	)
	(segment
		(start 252.818138 -129.221738)
		(end 252.818138 -128.562354)
		(width 0.14224)
		(layer "In2.Cu")
		(net "M_F_MA<6>")
	)
	(segment
		(start 255.709166 -97.499424)
		(end 255.70434 -97.490788)
		(width 0.0889)
		(layer "In2.Cu")
		(net "M_F_MA<6>")
	)
	(segment
		(start 252.9586 -130.5814)
		(end 252.899672 -130.522472)
		(width 0.14224)
		(layer "In2.Cu")
		(net "M_F_MA<6>")
	)
	(segment
		(start 252.198632 -153.8732)
		(end 252.499876 -153.571956)
		(width 0.14224)
		(layer "In2.Cu")
		(net "M_F_MA<6>")
	)
	(segment
		(start 255.709166 -95.518224)
		(end 255.70434 -95.509588)
		(width 0.0889)
		(layer "In2.Cu")
		(net "M_F_MA<6>")
	)
	(segment
		(start 253.0094 -135.9916)
		(end 253.0094 -135.4836)
		(width 0.14224)
		(layer "In2.Cu")
		(net "M_F_MA<6>")
	)
	(segment
		(start 255.68783 -94.49054)
		(end 255.35763 -93.72854)
		(width 0.0889)
		(layer "In2.Cu")
		(net "M_F_MA<6>")
	)
	(segment
		(start 252.089666 -147.376134)
		(end 252.932946 -146.532854)
		(width 0.14224)
		(layer "In2.Cu")
		(net "M_F_MA<6>")
	)
	(segment
		(start 253.0094 -135.4836)
		(end 252.914658 -135.388858)
		(width 0.14224)
		(layer "In2.Cu")
		(net "M_F_MA<6>")
	)
	(segment
		(start 255.709166 -96.508824)
		(end 255.70434 -96.500188)
		(width 0.0889)
		(layer "In2.Cu")
		(net "M_F_MA<6>")
	)
	(segment
		(start 251.266706 -151.60371)
		(end 251.266706 -152.019508)
		(width 0.14224)
		(layer "In2.Cu")
		(net "M_F_MA<6>")
	)
	(segment
		(start 252.986032 -152.301702)
		(end 252.986032 -152.69337)
		(width 0.14224)
		(layer "In2.Cu")
		(net "M_F_MA<6>")
	)
	(segment
		(start 251.418344 -152.171146)
		(end 252.855476 -152.171146)
		(width 0.14224)
		(layer "In2.Cu")
		(net "M_F_MA<6>")
	)
	(segment
		(start 253.662688 -127.387604)
		(end 254.14097 -126.909322)
		(width 0.14224)
		(layer "In2.Cu")
		(net "M_F_MA<6>")
	)
	(segment
		(start 255.709166 -94.527624)
		(end 255.68783 -94.49054)
		(width 0.0889)
		(layer "In2.Cu")
		(net "M_F_MA<6>")
	)
	(segment
		(start 251.398278 -151.472138)
		(end 251.266706 -151.60371)
		(width 0.14224)
		(layer "In2.Cu")
		(net "M_F_MA<6>")
	)
	(segment
		(start 255.60528 -104.566466)
		(end 255.60528 -102.57028)
		(width 0.0889)
		(layer "In2.Cu")
		(net "M_F_MA<6>")
	)
	(segment
		(start 252.855476 -152.171146)
		(end 252.986032 -152.301702)
		(width 0.14224)
		(layer "In2.Cu")
		(net "M_F_MA<6>")
	)
	(segment
		(start 255.8796 -105.109264)
		(end 255.8796 -104.840786)
		(width 0.0889)
		(layer "In2.Cu")
		(net "M_F_MA<6>")
	)
	(segment
		(start 252.984 -129.8956)
		(end 252.984 -129.3876)
		(width 0.14224)
		(layer "In2.Cu")
		(net "M_F_MA<6>")
	)
	(segment
		(start 252.313948 -151.472138)
		(end 251.398278 -151.472138)
		(width 0.14224)
		(layer "In2.Cu")
		(net "M_F_MA<6>")
	)
	(segment
		(start 252.984 -129.3876)
		(end 252.818138 -129.221738)
		(width 0.14224)
		(layer "In2.Cu")
		(net "M_F_MA<6>")
	)
	(segment
		(start 251.71019 -152.988264)
		(end 251.71019 -153.618438)
		(width 0.14224)
		(layer "In2.Cu")
		(net "M_F_MA<6>")
	)
	(segment
		(start 255.70434 -98.481388)
		(end 255.69799 -98.47072)
		(width 0.0889)
		(layer "In2.Cu")
		(net "M_F_MA<6>")
	)
	(segment
		(start 255.757934 -99.43973)
		(end 255.757934 -98.679254)
		(width 0.0889)
		(layer "In2.Cu")
		(net "M_F_MA<6>")
	)
	(segment
		(start 255.70434 -95.509588)
		(end 255.69799 -95.49892)
		(width 0.0889)
		(layer "In2.Cu")
		(net "M_F_MA<6>")
	)
	(segment
		(start 252.932946 -146.532854)
		(end 252.932946 -145.033746)
		(width 0.14224)
		(layer "In2.Cu")
		(net "M_F_MA<6>")
	)
	(segment
		(start 252.899672 -129.979928)
		(end 252.984 -129.8956)
		(width 0.14224)
		(layer "In2.Cu")
		(net "M_F_MA<6>")
	)
	(segment
		(start 252.93701 -140.16609)
		(end 252.93701 -136.06399)
		(width 0.14224)
		(layer "In2.Cu")
		(net "M_F_MA<6>")
	)
	(segment
		(start 252.845316 -152.834086)
		(end 251.864368 -152.834086)
		(width 0.14224)
		(layer "In2.Cu")
		(net "M_F_MA<6>")
	)
	(segment
		(start 254.812292 -126.20752)
		(end 255.8796 -125.140212)
		(width 0.14224)
		(layer "In2.Cu")
		(net "M_F_MA<6>")
	)
	(segment
		(start 251.266706 -152.019508)
		(end 251.418344 -152.171146)
		(width 0.14224)
		(layer "In2.Cu")
		(net "M_F_MA<6>")
	)
	(segment
		(start 252.818138 -128.562354)
		(end 253.662688 -127.717804)
		(width 0.14224)
		(layer "In2.Cu")
		(net "M_F_MA<6>")
	)
	(segment
		(start 252.914658 -135.388858)
		(end 252.914658 -132.391658)
		(width 0.14224)
		(layer "In2.Cu")
		(net "M_F_MA<6>")
	)
	(segment
		(start 253.662688 -127.717804)
		(end 253.662688 -127.387604)
		(width 0.14224)
		(layer "In2.Cu")
		(net "M_F_MA<6>")
	)
	(segment
		(start 252.986032 -152.69337)
		(end 252.845316 -152.834086)
		(width 0.14224)
		(layer "In2.Cu")
		(net "M_F_MA<6>")
	)
	(segment
		(start 255.4732 -102.4382)
		(end 255.4732 -100.478844)
		(width 0.0889)
		(layer "In2.Cu")
		(net "M_F_MA<6>")
	)
	(segment
		(start 252.932946 -145.033746)
		(end 252.91415 -145.01495)
		(width 0.14224)
		(layer "In2.Cu")
		(net "M_F_MA<6>")
	)
	(segment
		(start 254.14097 -126.909322)
		(end 254.356362 -126.909322)
		(width 0.14224)
		(layer "In2.Cu")
		(net "M_F_MA<6>")
	)
	(segment
		(start 255.759204 -100.19284)
		(end 255.759204 -99.441)
		(width 0.0889)
		(layer "In2.Cu")
		(net "M_F_MA<6>")
	)
	(segment
		(start 252.499876 -150.788878)
		(end 252.089666 -150.378668)
		(width 0.14224)
		(layer "In2.Cu")
		(net "M_F_MA<6>")
	)
	(segment
		(start 252.089666 -150.378668)
		(end 252.089666 -147.376134)
		(width 0.14224)
		(layer "In2.Cu")
		(net "M_F_MA<6>")
	)
	(segment
		(start 255.70434 -96.500188)
		(end 255.69799 -96.48952)
		(width 0.0889)
		(layer "In2.Cu")
		(net "M_F_MA<6>")
	)
	(segment
		(start 255.759204 -99.441)
		(end 255.757934 -99.43973)
		(width 0.0889)
		(layer "In2.Cu")
		(net "M_F_MA<6>")
	)
	(segment
		(start 252.9586 -131.2164)
		(end 252.9586 -130.5814)
		(width 0.14224)
		(layer "In2.Cu")
		(net "M_F_MA<6>")
	)
	(segment
		(start 252.899672 -130.522472)
		(end 252.899672 -129.979928)
		(width 0.14224)
		(layer "In2.Cu")
		(net "M_F_MA<6>")
	)
	(segment
		(start 255.70434 -97.490788)
		(end 255.69799 -97.48012)
		(width 0.0889)
		(layer "In2.Cu")
		(net "M_F_MA<6>")
	)
	(segment
		(start 252.499876 -151.28621)
		(end 252.313948 -151.472138)
		(width 0.14224)
		(layer "In2.Cu")
		(net "M_F_MA<6>")
	)
	(segment
		(start 254.812292 -126.453392)
		(end 254.812292 -126.20752)
		(width 0.14224)
		(layer "In2.Cu")
		(net "M_F_MA<6>")
	)
	(segment
		(start 252.499876 -150.788878)
		(end 252.499876 -151.28621)
		(width 0.14224)
		(layer "In2.Cu")
		(net "M_F_MA<6>")
	)
	(segment
		(start 252.91415 -140.18895)
		(end 252.93701 -140.16609)
		(width 0.14224)
		(layer "In2.Cu")
		(net "M_F_MA<6>")
	)
	(segment
		(start 255.8796 -104.840786)
		(end 255.60528 -104.566466)
		(width 0.0889)
		(layer "In2.Cu")
		(net "M_F_MA<6>")
	)
	(segment
		(start 251.864368 -152.834086)
		(end 251.71019 -152.988264)
		(width 0.14224)
		(layer "In2.Cu")
		(net "M_F_MA<6>")
	)
	(segment
		(start 255.8796 -125.140212)
		(end 255.8796 -105.109264)
		(width 0.14224)
		(layer "In2.Cu")
		(net "M_F_MA<6>")
	)
	(segment
		(start 251.964952 -153.8732)
		(end 252.198632 -153.8732)
		(width 0.14224)
		(layer "In2.Cu")
		(net "M_F_MA<6>")
	)
	(segment
		(start 252.914658 -132.391658)
		(end 252.8062 -132.2832)
		(width 0.14224)
		(layer "In2.Cu")
		(net "M_F_MA<6>")
	)
	(segment
		(start 252.8062 -131.3688)
		(end 252.9586 -131.2164)
		(width 0.14224)
		(layer "In2.Cu")
		(net "M_F_MA<6>")
	)
	(segment
		(start 251.71019 -153.618438)
		(end 251.964952 -153.8732)
		(width 0.14224)
		(layer "In2.Cu")
		(net "M_F_MA<6>")
	)
	(segment
		(start 254.356362 -126.909322)
		(end 254.812292 -126.453392)
		(width 0.14224)
		(layer "In2.Cu")
		(net "M_F_MA<6>")
	)
	(segment
		(start 255.4732 -100.478844)
		(end 255.759204 -100.19284)
		(width 0.0889)
		(layer "In2.Cu")
		(net "M_F_MA<6>")
	)
	(segment
		(start 255.60528 -102.57028)
		(end 255.4732 -102.4382)
		(width 0.0889)
		(layer "In2.Cu")
		(net "M_F_MA<6>")
	)
	(arc
		(start 255.69799 -97.48012)
		(mid 255.625192 -97.189357)
		(end 255.70434 -96.900238)
		(width 0.0889)
		(layer "In2.Cu")
		(net "M_F_MA<6>")
	)
	(arc
		(start 255.70434 -95.909638)
		(mid 255.75781 -95.714575)
		(end 255.709166 -95.518224)
		(width 0.0889)
		(layer "In2.Cu")
		(net "M_F_MA<6>")
	)
	(arc
		(start 255.757934 -98.679254)
		(mid 255.744005 -98.576837)
		(end 255.70434 -98.481388)
		(width 0.0889)
		(layer "In2.Cu")
		(net "M_F_MA<6>")
	)
	(arc
		(start 255.69799 -98.47072)
		(mid 255.625192 -98.179957)
		(end 255.70434 -97.890838)
		(width 0.0889)
		(layer "In2.Cu")
		(net "M_F_MA<6>")
	)
	(arc
		(start 255.70434 -97.890838)
		(mid 255.75781 -97.695775)
		(end 255.709166 -97.499424)
		(width 0.0889)
		(layer "In2.Cu")
		(net "M_F_MA<6>")
	)
	(arc
		(start 255.69799 -96.48952)
		(mid 255.625192 -96.198757)
		(end 255.70434 -95.909638)
		(width 0.0889)
		(layer "In2.Cu")
		(net "M_F_MA<6>")
	)
	(arc
		(start 255.69799 -95.49892)
		(mid 255.625192 -95.208157)
		(end 255.70434 -94.919038)
		(width 0.0889)
		(layer "In2.Cu")
		(net "M_F_MA<6>")
	)
	(arc
		(start 255.70434 -96.900238)
		(mid 255.75781 -96.705175)
		(end 255.709166 -96.508824)
		(width 0.0889)
		(layer "In2.Cu")
		(net "M_F_MA<6>")
	)
	(arc
		(start 255.70434 -94.919038)
		(mid 255.75781 -94.723975)
		(end 255.709166 -94.527624)
		(width 0.0889)
		(layer "In2.Cu")
		(net "M_F_MA<6>")
	)
	(segment
		(start 255.92913 -91.747086)
		(end 255.35763 -91.747086)
		(width 0.1016)
		(layer "F.Cu")
		(net "M_F_MA<5>")
	)
	(segment
		(start 252.499876 -156.87294)
		(end 252.500384 -156.87294)
		(width 0.1651)
		(layer "F.Cu")
		(net "M_F_MA<5>")
	)
	(segment
		(start 252.499876 -154.905456)
		(end 252.499876 -156.87294)
		(width 0.1651)
		(layer "F.Cu")
		(net "M_F_MA<5>")
	)
	(via
		(at 252.499876 -148.773388)
		(size 0.4572)
		(drill 0.2032)
		(layers "F.Cu" "B.Cu")
		(net "M_F_MA<5>")
	)
	(via
		(at 255.35763 -91.747086)
		(size 0.508)
		(drill 0.254)
		(layers "F.Cu" "B.Cu")
		(net "M_F_MA<5>")
	)
	(via
		(at 252.499876 -154.905456)
		(size 0.508)
		(drill 0.254)
		(layers "F.Cu" "B.Cu")
		(net "M_F_MA<5>")
	)
	(segment
		(start 252.499876 -147.478496)
		(end 252.499876 -148.773388)
		(width 0.1651)
		(layer "B.Cu")
		(net "M_F_MA<5>")
	)
	(segment
		(start 252.500384 -147.478496)
		(end 252.499876 -147.478496)
		(width 0.1651)
		(layer "B.Cu")
		(net "M_F_MA<5>")
	)
	(segment
		(start 253.7206 -130.7084)
		(end 253.823724 -130.605276)
		(width 0.14224)
		(layer "In2.Cu")
		(net "M_F_MA<5>")
	)
	(segment
		(start 253.431802 -151.535638)
		(end 253.431802 -153.461974)
		(width 0.14224)
		(layer "In2.Cu")
		(net "M_F_MA<5>")
	)
	(segment
		(start 253.757938 -145.655538)
		(end 253.7841 -145.629376)
		(width 0.14224)
		(layer "In2.Cu")
		(net "M_F_MA<5>")
	)
	(segment
		(start 253.544324 -128.554988)
		(end 256.3876 -125.711712)
		(width 0.14224)
		(layer "In2.Cu")
		(net "M_F_MA<5>")
	)
	(segment
		(start 255.86944 -96.404938)
		(end 255.864614 -96.396302)
		(width 0.0889)
		(layer "In2.Cu")
		(net "M_F_MA<5>")
	)
	(segment
		(start 255.87579 -95.425006)
		(end 255.86944 -95.414338)
		(width 0.0889)
		(layer "In2.Cu")
		(net "M_F_MA<5>")
	)
	(segment
		(start 253.0094 -149.8346)
		(end 253.0094 -150.4442)
		(width 0.14224)
		(layer "In2.Cu")
		(net "M_F_MA<5>")
	)
	(segment
		(start 256.3622 -102.450392)
		(end 256.3622 -102.108)
		(width 0.0889)
		(layer "In2.Cu")
		(net "M_F_MA<5>")
	)
	(segment
		(start 253.431802 -153.461974)
		(end 252.861826 -154.03195)
		(width 0.14224)
		(layer "In2.Cu")
		(net "M_F_MA<5>")
	)
	(segment
		(start 256.3876 -104.603804)
		(end 256.059686 -104.27589)
		(width 0.14224)
		(layer "In2.Cu")
		(net "M_F_MA<5>")
	)
	(segment
		(start 252.499876 -149.325076)
		(end 253.0094 -149.8346)
		(width 0.14224)
		(layer "In2.Cu")
		(net "M_F_MA<5>")
	)
	(segment
		(start 252.499876 -147.854924)
		(end 253.757938 -146.596862)
		(width 0.14224)
		(layer "In2.Cu")
		(net "M_F_MA<5>")
	)
	(segment
		(start 253.7206 -131.1402)
		(end 253.7206 -130.7084)
		(width 0.14224)
		(layer "In2.Cu")
		(net "M_F_MA<5>")
	)
	(segment
		(start 255.852676 -92.413074)
		(end 255.35763 -91.747086)
		(width 0.0889)
		(layer "In2.Cu")
		(net "M_F_MA<5>")
	)
	(segment
		(start 252.861826 -154.03195)
		(end 252.499876 -154.905456)
		(width 0.14224)
		(layer "In2.Cu")
		(net "M_F_MA<5>")
	)
	(segment
		(start 255.86944 -93.433138)
		(end 255.864614 -93.424502)
		(width 0.0889)
		(layer "In2.Cu")
		(net "M_F_MA<5>")
	)
	(segment
		(start 255.86944 -98.386138)
		(end 255.864614 -98.377502)
		(width 0.0889)
		(layer "In2.Cu")
		(net "M_F_MA<5>")
	)
	(segment
		(start 255.87579 -92.453206)
		(end 255.86944 -92.442538)
		(width 0.0889)
		(layer "In2.Cu")
		(net "M_F_MA<5>")
	)
	(segment
		(start 253.9746 -131.3942)
		(end 253.7206 -131.1402)
		(width 0.14224)
		(layer "In2.Cu")
		(net "M_F_MA<5>")
	)
	(segment
		(start 256.059686 -102.94747)
		(end 256.059686 -102.752906)
		(width 0.0889)
		(layer "In2.Cu")
		(net "M_F_MA<5>")
	)
	(segment
		(start 256.064004 -101.809804)
		(end 256.064004 -99.113086)
		(width 0.0889)
		(layer "In2.Cu")
		(net "M_F_MA<5>")
	)
	(segment
		(start 253.757938 -146.596862)
		(end 253.757938 -145.655538)
		(width 0.14224)
		(layer "In2.Cu")
		(net "M_F_MA<5>")
	)
	(segment
		(start 255.86944 -97.395538)
		(end 255.864614 -97.386902)
		(width 0.0889)
		(layer "In2.Cu")
		(net "M_F_MA<5>")
	)
	(segment
		(start 255.87579 -96.415606)
		(end 255.86944 -96.404938)
		(width 0.0889)
		(layer "In2.Cu")
		(net "M_F_MA<5>")
	)
	(segment
		(start 253.765304 -135.362696)
		(end 253.787402 -135.340598)
		(width 0.14224)
		(layer "In2.Cu")
		(net "M_F_MA<5>")
	)
	(segment
		(start 255.87579 -97.406206)
		(end 255.86944 -97.395538)
		(width 0.0889)
		(layer "In2.Cu")
		(net "M_F_MA<5>")
	)
	(segment
		(start 255.86944 -95.414338)
		(end 255.864614 -95.405702)
		(width 0.0889)
		(layer "In2.Cu")
		(net "M_F_MA<5>")
	)
	(segment
		(start 252.499876 -148.773388)
		(end 252.499876 -147.854924)
		(width 0.14224)
		(layer "In2.Cu")
		(net "M_F_MA<5>")
	)
	(segment
		(start 252.91415 -151.017986)
		(end 253.431802 -151.535638)
		(width 0.14224)
		(layer "In2.Cu")
		(net "M_F_MA<5>")
	)
	(segment
		(start 255.86944 -94.023688)
		(end 255.87579 -94.01302)
		(width 0.0889)
		(layer "In2.Cu")
		(net "M_F_MA<5>")
	)
	(segment
		(start 256.059686 -104.27589)
		(end 256.059686 -102.94747)
		(width 0.14224)
		(layer "In2.Cu")
		(net "M_F_MA<5>")
	)
	(segment
		(start 253.0094 -150.4442)
		(end 252.91415 -150.53945)
		(width 0.14224)
		(layer "In2.Cu")
		(net "M_F_MA<5>")
	)
	(segment
		(start 253.7841 -140.8811)
		(end 253.765304 -140.862304)
		(width 0.14224)
		(layer "In2.Cu")
		(net "M_F_MA<5>")
	)
	(segment
		(start 253.544324 -129.693924)
		(end 253.544324 -128.554988)
		(width 0.14224)
		(layer "In2.Cu")
		(net "M_F_MA<5>")
	)
	(segment
		(start 256.3622 -102.108)
		(end 256.064004 -101.809804)
		(width 0.0889)
		(layer "In2.Cu")
		(net "M_F_MA<5>")
	)
	(segment
		(start 253.9746 -133.1468)
		(end 253.9746 -131.3942)
		(width 0.14224)
		(layer "In2.Cu")
		(net "M_F_MA<5>")
	)
	(segment
		(start 256.3876 -125.711712)
		(end 256.3876 -104.603804)
		(width 0.14224)
		(layer "In2.Cu")
		(net "M_F_MA<5>")
	)
	(segment
		(start 253.7841 -145.629376)
		(end 253.7841 -140.8811)
		(width 0.14224)
		(layer "In2.Cu")
		(net "M_F_MA<5>")
	)
	(segment
		(start 253.823724 -130.605276)
		(end 253.823724 -129.973324)
		(width 0.14224)
		(layer "In2.Cu")
		(net "M_F_MA<5>")
	)
	(segment
		(start 253.765304 -140.862304)
		(end 253.765304 -135.362696)
		(width 0.14224)
		(layer "In2.Cu")
		(net "M_F_MA<5>")
	)
	(segment
		(start 252.91415 -150.53945)
		(end 252.91415 -151.017986)
		(width 0.14224)
		(layer "In2.Cu")
		(net "M_F_MA<5>")
	)
	(segment
		(start 252.499876 -148.773388)
		(end 252.499876 -149.325076)
		(width 0.14224)
		(layer "In2.Cu")
		(net "M_F_MA<5>")
	)
	(segment
		(start 253.823724 -129.973324)
		(end 253.544324 -129.693924)
		(width 0.14224)
		(layer "In2.Cu")
		(net "M_F_MA<5>")
	)
	(segment
		(start 253.787402 -133.333998)
		(end 253.9746 -133.1468)
		(width 0.14224)
		(layer "In2.Cu")
		(net "M_F_MA<5>")
	)
	(segment
		(start 253.787402 -135.340598)
		(end 253.787402 -133.333998)
		(width 0.14224)
		(layer "In2.Cu")
		(net "M_F_MA<5>")
	)
	(segment
		(start 255.86944 -92.442538)
		(end 255.852676 -92.413074)
		(width 0.0889)
		(layer "In2.Cu")
		(net "M_F_MA<5>")
	)
	(segment
		(start 256.059686 -102.752906)
		(end 256.3622 -102.450392)
		(width 0.0889)
		(layer "In2.Cu")
		(net "M_F_MA<5>")
	)
	(arc
		(start 255.86944 -95.014288)
		(mid 255.948571 -94.718886)
		(end 255.86944 -94.423484)
		(width 0.0889)
		(layer "In2.Cu")
		(net "M_F_MA<5>")
	)
	(arc
		(start 255.86944 -97.986088)
		(mid 255.948662 -97.69697)
		(end 255.87579 -97.406206)
		(width 0.0889)
		(layer "In2.Cu")
		(net "M_F_MA<5>")
	)
	(arc
		(start 255.864614 -98.377502)
		(mid 255.815859 -98.18115)
		(end 255.86944 -97.986088)
		(width 0.0889)
		(layer "In2.Cu")
		(net "M_F_MA<5>")
	)
	(arc
		(start 255.86944 -93.033088)
		(mid 255.948662 -92.74397)
		(end 255.87579 -92.453206)
		(width 0.0889)
		(layer "In2.Cu")
		(net "M_F_MA<5>")
	)
	(arc
		(start 255.86944 -96.004888)
		(mid 255.948662 -95.71577)
		(end 255.87579 -95.425006)
		(width 0.0889)
		(layer "In2.Cu")
		(net "M_F_MA<5>")
	)
	(arc
		(start 255.864614 -95.405702)
		(mid 255.815859 -95.20935)
		(end 255.86944 -95.014288)
		(width 0.0889)
		(layer "In2.Cu")
		(net "M_F_MA<5>")
	)
	(arc
		(start 256.064004 -99.113086)
		(mid 256.014517 -98.736821)
		(end 255.86944 -98.386138)
		(width 0.0889)
		(layer "In2.Cu")
		(net "M_F_MA<5>")
	)
	(arc
		(start 255.86944 -96.995488)
		(mid 255.948662 -96.70637)
		(end 255.87579 -96.415606)
		(width 0.0889)
		(layer "In2.Cu")
		(net "M_F_MA<5>")
	)
	(arc
		(start 255.87579 -94.01302)
		(mid 255.948588 -93.722257)
		(end 255.86944 -93.433138)
		(width 0.0889)
		(layer "In2.Cu")
		(net "M_F_MA<5>")
	)
	(arc
		(start 255.864614 -96.396302)
		(mid 255.815859 -96.19995)
		(end 255.86944 -96.004888)
		(width 0.0889)
		(layer "In2.Cu")
		(net "M_F_MA<5>")
	)
	(arc
		(start 255.864614 -93.424502)
		(mid 255.815859 -93.22815)
		(end 255.86944 -93.033088)
		(width 0.0889)
		(layer "In2.Cu")
		(net "M_F_MA<5>")
	)
	(arc
		(start 255.864614 -97.386902)
		(mid 255.815859 -97.19055)
		(end 255.86944 -96.995488)
		(width 0.0889)
		(layer "In2.Cu")
		(net "M_F_MA<5>")
	)
	(arc
		(start 255.86944 -94.423484)
		(mid 255.815941 -94.223586)
		(end 255.86944 -94.023688)
		(width 0.0889)
		(layer "In2.Cu")
		(net "M_F_MA<5>")
	)
	(segment
		(start 256.78765 -93.23324)
		(end 256.21615 -93.23324)
		(width 0.1016)
		(layer "F.Cu")
		(net "M_F_MA<4>")
	)
	(segment
		(start 253.350014 -156.87294)
		(end 253.350522 -156.87294)
		(width 0.1651)
		(layer "F.Cu")
		(net "M_F_MA<4>")
	)
	(segment
		(start 253.350014 -155.538678)
		(end 253.350014 -156.87294)
		(width 0.1651)
		(layer "F.Cu")
		(net "M_F_MA<4>")
	)
	(via
		(at 256.21615 -93.23324)
		(size 0.508)
		(drill 0.254)
		(layers "F.Cu" "B.Cu")
		(net "M_F_MA<4>")
	)
	(via
		(at 253.350014 -148.773388)
		(size 0.4572)
		(drill 0.2032)
		(layers "F.Cu" "B.Cu")
		(net "M_F_MA<4>")
	)
	(via
		(at 253.350014 -155.538678)
		(size 0.508)
		(drill 0.254)
		(layers "F.Cu" "B.Cu")
		(net "M_F_MA<4>")
	)
	(segment
		(start 253.350014 -147.478496)
		(end 253.350014 -148.773388)
		(width 0.1651)
		(layer "B.Cu")
		(net "M_F_MA<4>")
	)
	(segment
		(start 253.350522 -147.478496)
		(end 253.350014 -147.478496)
		(width 0.1651)
		(layer "B.Cu")
		(net "M_F_MA<4>")
	)
	(segment
		(start 253.851918 -154.503882)
		(end 253.851918 -153.979118)
		(width 0.14224)
		(layer "In11.Cu")
		(net "M_F_MA<4>")
	)
	(segment
		(start 254.39243 -147.577048)
		(end 258.11734 -147.577048)
		(width 0.14224)
		(layer "In11.Cu")
		(net "M_F_MA<4>")
	)
	(segment
		(start 257.42138 -96.500188)
		(end 257.41503 -96.48952)
		(width 0.0889)
		(layer "In11.Cu")
		(net "M_F_MA<4>")
	)
	(segment
		(start 257.42138 -97.490788)
		(end 257.41503 -97.48012)
		(width 0.0889)
		(layer "In11.Cu")
		(net "M_F_MA<4>")
	)
	(segment
		(start 257.426206 -96.508824)
		(end 257.42138 -96.500188)
		(width 0.0889)
		(layer "In11.Cu")
		(net "M_F_MA<4>")
	)
	(segment
		(start 257.493516 -101.004116)
		(end 257.3528 -100.8634)
		(width 0.0889)
		(layer "In11.Cu")
		(net "M_F_MA<4>")
	)
	(segment
		(start 257.480816 -99.998784)
		(end 257.480816 -97.596706)
		(width 0.0889)
		(layer "In11.Cu")
		(net "M_F_MA<4>")
	)
	(segment
		(start 253.350014 -148.773388)
		(end 253.350014 -148.619464)
		(width 0.14224)
		(layer "In11.Cu")
		(net "M_F_MA<4>")
	)
	(segment
		(start 259.9182 -141.5288)
		(end 259.9182 -140.0048)
		(width 0.14224)
		(layer "In11.Cu")
		(net "M_F_MA<4>")
	)
	(segment
		(start 259.207254 -133.604254)
		(end 259.207254 -127.526288)
		(width 0.14224)
		(layer "In11.Cu")
		(net "M_F_MA<4>")
	)
	(segment
		(start 259.9182 -140.0048)
		(end 259.4356 -139.5222)
		(width 0.14224)
		(layer "In11.Cu")
		(net "M_F_MA<4>")
	)
	(segment
		(start 259.4356 -142.0114)
		(end 259.9182 -141.5288)
		(width 0.14224)
		(layer "In11.Cu")
		(net "M_F_MA<4>")
	)
	(segment
		(start 257.41503 -93.939106)
		(end 257.42138 -93.928438)
		(width 0.0889)
		(layer "In11.Cu")
		(net "M_F_MA<4>")
	)
	(segment
		(start 257.3528 -100.1268)
		(end 257.480816 -99.998784)
		(width 0.0889)
		(layer "In11.Cu")
		(net "M_F_MA<4>")
	)
	(segment
		(start 257.085846 -93.32849)
		(end 257.039872 -93.32849)
		(width 0.0889)
		(layer "In11.Cu")
		(net "M_F_MA<4>")
	)
	(segment
		(start 259.4356 -133.8326)
		(end 259.207254 -133.604254)
		(width 0.14224)
		(layer "In11.Cu")
		(net "M_F_MA<4>")
	)
	(segment
		(start 257.42138 -95.509588)
		(end 257.41503 -95.49892)
		(width 0.0889)
		(layer "In11.Cu")
		(net "M_F_MA<4>")
	)
	(segment
		(start 257.480816 -97.596706)
		(end 257.42138 -97.490788)
		(width 0.0889)
		(layer "In11.Cu")
		(net "M_F_MA<4>")
	)
	(segment
		(start 253.5428 -153.67)
		(end 253.5428 -151.999696)
		(width 0.14224)
		(layer "In11.Cu")
		(net "M_F_MA<4>")
	)
	(segment
		(start 252.910848 -151.367744)
		(end 252.910848 -150.51278)
		(width 0.14224)
		(layer "In11.Cu")
		(net "M_F_MA<4>")
	)
	(segment
		(start 258.663948 -126.982982)
		(end 258.663948 -102.174548)
		(width 0.14224)
		(layer "In11.Cu")
		(net "M_F_MA<4>")
	)
	(segment
		(start 257.3528 -100.8634)
		(end 257.3528 -100.1268)
		(width 0.0889)
		(layer "In11.Cu")
		(net "M_F_MA<4>")
	)
	(segment
		(start 253.350014 -155.005786)
		(end 253.851918 -154.503882)
		(width 0.14224)
		(layer "In11.Cu")
		(net "M_F_MA<4>")
	)
	(segment
		(start 253.350014 -155.538678)
		(end 253.350014 -155.005786)
		(width 0.14224)
		(layer "In11.Cu")
		(net "M_F_MA<4>")
	)
	(segment
		(start 258.11734 -147.577048)
		(end 259.4356 -146.258788)
		(width 0.14224)
		(layer "In11.Cu")
		(net "M_F_MA<4>")
	)
	(segment
		(start 253.5428 -151.999696)
		(end 252.910848 -151.367744)
		(width 0.14224)
		(layer "In11.Cu")
		(net "M_F_MA<4>")
	)
	(segment
		(start 253.851918 -153.979118)
		(end 253.5428 -153.67)
		(width 0.14224)
		(layer "In11.Cu")
		(net "M_F_MA<4>")
	)
	(segment
		(start 259.207254 -127.526288)
		(end 258.663948 -126.982982)
		(width 0.14224)
		(layer "In11.Cu")
		(net "M_F_MA<4>")
	)
	(segment
		(start 258.663948 -102.174548)
		(end 257.493516 -101.004116)
		(width 0.14224)
		(layer "In11.Cu")
		(net "M_F_MA<4>")
	)
	(segment
		(start 253.350014 -148.619464)
		(end 254.39243 -147.577048)
		(width 0.14224)
		(layer "In11.Cu")
		(net "M_F_MA<4>")
	)
	(segment
		(start 257.426206 -94.527624)
		(end 257.42138 -94.518988)
		(width 0.0889)
		(layer "In11.Cu")
		(net "M_F_MA<4>")
	)
	(segment
		(start 259.4356 -139.5222)
		(end 259.4356 -133.8326)
		(width 0.14224)
		(layer "In11.Cu")
		(net "M_F_MA<4>")
	)
	(segment
		(start 257.039872 -93.32849)
		(end 256.21615 -93.23324)
		(width 0.0889)
		(layer "In11.Cu")
		(net "M_F_MA<4>")
	)
	(segment
		(start 253.350014 -150.073614)
		(end 253.350014 -148.773388)
		(width 0.14224)
		(layer "In11.Cu")
		(net "M_F_MA<4>")
	)
	(segment
		(start 259.4356 -146.258788)
		(end 259.4356 -142.0114)
		(width 0.14224)
		(layer "In11.Cu")
		(net "M_F_MA<4>")
	)
	(segment
		(start 252.910848 -150.51278)
		(end 253.350014 -150.073614)
		(width 0.14224)
		(layer "In11.Cu")
		(net "M_F_MA<4>")
	)
	(segment
		(start 257.426206 -95.518224)
		(end 257.42138 -95.509588)
		(width 0.0889)
		(layer "In11.Cu")
		(net "M_F_MA<4>")
	)
	(arc
		(start 257.41503 -96.48952)
		(mid 257.342232 -96.198757)
		(end 257.42138 -95.909638)
		(width 0.0889)
		(layer "In11.Cu")
		(net "M_F_MA<4>")
	)
	(arc
		(start 257.41503 -95.49892)
		(mid 257.342232 -95.208157)
		(end 257.42138 -94.919038)
		(width 0.0889)
		(layer "In11.Cu")
		(net "M_F_MA<4>")
	)
	(arc
		(start 257.42138 -96.900238)
		(mid 257.47485 -96.705175)
		(end 257.426206 -96.508824)
		(width 0.0889)
		(layer "In11.Cu")
		(net "M_F_MA<4>")
	)
	(arc
		(start 257.41503 -97.48012)
		(mid 257.342232 -97.189357)
		(end 257.42138 -96.900238)
		(width 0.0889)
		(layer "In11.Cu")
		(net "M_F_MA<4>")
	)
	(arc
		(start 257.42138 -94.919038)
		(mid 257.47485 -94.723975)
		(end 257.426206 -94.527624)
		(width 0.0889)
		(layer "In11.Cu")
		(net "M_F_MA<4>")
	)
	(arc
		(start 257.42138 -94.518988)
		(mid 257.342158 -94.22987)
		(end 257.41503 -93.939106)
		(width 0.0889)
		(layer "In11.Cu")
		(net "M_F_MA<4>")
	)
	(arc
		(start 257.42138 -95.909638)
		(mid 257.47485 -95.714575)
		(end 257.426206 -95.518224)
		(width 0.0889)
		(layer "In11.Cu")
		(net "M_F_MA<4>")
	)
	(arc
		(start 257.42138 -93.928438)
		(mid 257.423963 -93.533191)
		(end 257.085846 -93.32849)
		(width 0.0889)
		(layer "In11.Cu")
		(net "M_F_MA<4>")
	)
	(segment
		(start 256.78765 -92.24264)
		(end 256.21615 -92.24264)
		(width 0.1016)
		(layer "F.Cu")
		(net "M_F_MA<3>")
	)
	(segment
		(start 254.199898 -152.278842)
		(end 254.199898 -153.542746)
		(width 0.1651)
		(layer "F.Cu")
		(net "M_F_MA<3>")
	)
	(segment
		(start 254.200406 -152.273)
		(end 254.199898 -152.278842)
		(width 0.1651)
		(layer "F.Cu")
		(net "M_F_MA<3>")
	)
	(via
		(at 254.199898 -150.788878)
		(size 0.4572)
		(drill 0.2032)
		(layers "F.Cu" "B.Cu")
		(net "M_F_MA<3>")
	)
	(via
		(at 254.199898 -153.542746)
		(size 0.508)
		(drill 0.254)
		(layers "F.Cu" "B.Cu")
		(net "M_F_MA<3>")
	)
	(via
		(at 256.21615 -92.24264)
		(size 0.508)
		(drill 0.254)
		(layers "F.Cu" "B.Cu")
		(net "M_F_MA<3>")
	)
	(segment
		(start 254.200406 -152.078436)
		(end 254.199898 -152.078182)
		(width 0.1651)
		(layer "B.Cu")
		(net "M_F_MA<3>")
	)
	(segment
		(start 254.199898 -152.078182)
		(end 254.199898 -150.788878)
		(width 0.1651)
		(layer "B.Cu")
		(net "M_F_MA<3>")
	)
	(segment
		(start 256.56286 -95.414338)
		(end 256.55651 -95.425006)
		(width 0.0889)
		(layer "In2.Cu")
		(net "M_F_MA<3>")
	)
	(segment
		(start 254.032004 -151.750268)
		(end 253.877064 -151.905208)
		(width 0.14224)
		(layer "In2.Cu")
		(net "M_F_MA<3>")
	)
	(segment
		(start 256.368804 -101.606604)
		(end 256.57556 -101.81336)
		(width 0.0889)
		(layer "In2.Cu")
		(net "M_F_MA<3>")
	)
	(segment
		(start 255.856486 -128.175766)
		(end 255.856486 -128.418336)
		(width 0.14224)
		(layer "In2.Cu")
		(net "M_F_MA<3>")
	)
	(segment
		(start 254.444754 -152.413208)
		(end 254.599694 -152.568148)
		(width 0.14224)
		(layer "In2.Cu")
		(net "M_F_MA<3>")
	)
	(segment
		(start 256.57683 -127.448564)
		(end 256.278888 -127.448564)
		(width 0.14224)
		(layer "In2.Cu")
		(net "M_F_MA<3>")
	)
	(segment
		(start 255.764284 -127.179578)
		(end 255.47701 -127.466852)
		(width 0.14224)
		(layer "In2.Cu")
		(net "M_F_MA<3>")
	)
	(segment
		(start 254.599694 -151.188674)
		(end 254.599694 -151.595328)
		(width 0.14224)
		(layer "In2.Cu")
		(net "M_F_MA<3>")
	)
	(segment
		(start 256.37236 -98.727006)
		(end 256.368804 -98.730562)
		(width 0.0889)
		(layer "In2.Cu")
		(net "M_F_MA<3>")
	)
	(segment
		(start 256.009902 -127.179578)
		(end 255.764284 -127.179578)
		(width 0.14224)
		(layer "In2.Cu")
		(net "M_F_MA<3>")
	)
	(segment
		(start 256.546096 -93.004386)
		(end 256.56286 -93.033088)
		(width 0.0889)
		(layer "In2.Cu")
		(net "M_F_MA<3>")
	)
	(segment
		(start 256.8956 -104.393238)
		(end 256.8956 -125.922532)
		(width 0.14224)
		(layer "In2.Cu")
		(net "M_F_MA<3>")
	)
	(segment
		(start 254.508 -132.0546)
		(end 254.635 -132.1816)
		(width 0.14224)
		(layer "In2.Cu")
		(net "M_F_MA<3>")
	)
	(segment
		(start 256.542794 -126.275338)
		(end 256.542794 -126.562866)
		(width 0.14224)
		(layer "In2.Cu")
		(net "M_F_MA<3>")
	)
	(segment
		(start 254.508 -131.4196)
		(end 254.508 -132.0546)
		(width 0.14224)
		(layer "In2.Cu")
		(net "M_F_MA<3>")
	)
	(segment
		(start 254.7112 -130.683)
		(end 254.7112 -131.2164)
		(width 0.14224)
		(layer "In2.Cu")
		(net "M_F_MA<3>")
	)
	(segment
		(start 256.567686 -96.396302)
		(end 256.56286 -96.404938)
		(width 0.0889)
		(layer "In2.Cu")
		(net "M_F_MA<3>")
	)
	(segment
		(start 255.271524 -128.740408)
		(end 254.958088 -128.426972)
		(width 0.14224)
		(layer "In2.Cu")
		(net "M_F_MA<3>")
	)
	(segment
		(start 256.542794 -126.562866)
		(end 256.864104 -126.884176)
		(width 0.14224)
		(layer "In2.Cu")
		(net "M_F_MA<3>")
	)
	(segment
		(start 254.599694 -153.14295)
		(end 254.199898 -153.542746)
		(width 0.14224)
		(layer "In2.Cu")
		(net "M_F_MA<3>")
	)
	(segment
		(start 254.691642 -128.426972)
		(end 254.363982 -128.754632)
		(width 0.14224)
		(layer "In2.Cu")
		(net "M_F_MA<3>")
	)
	(segment
		(start 256.567686 -95.405702)
		(end 256.56286 -95.414338)
		(width 0.0889)
		(layer "In2.Cu")
		(net "M_F_MA<3>")
	)
	(segment
		(start 256.57556 -104.073198)
		(end 256.8956 -104.393238)
		(width 0.14224)
		(layer "In2.Cu")
		(net "M_F_MA<3>")
	)
	(segment
		(start 253.761494 -147.431506)
		(end 253.761494 -150.350474)
		(width 0.14224)
		(layer "In2.Cu")
		(net "M_F_MA<3>")
	)
	(segment
		(start 256.56286 -97.395538)
		(end 256.55651 -97.406206)
		(width 0.0889)
		(layer "In2.Cu")
		(net "M_F_MA<3>")
	)
	(segment
		(start 253.761494 -150.350474)
		(end 254.199898 -150.788878)
		(width 0.14224)
		(layer "In2.Cu")
		(net "M_F_MA<3>")
	)
	(segment
		(start 256.864104 -127.16129)
		(end 256.57683 -127.448564)
		(width 0.14224)
		(layer "In2.Cu")
		(net "M_F_MA<3>")
	)
	(segment
		(start 256.57556 -101.81336)
		(end 256.57556 -102.80904)
		(width 0.0889)
		(layer "In2.Cu")
		(net "M_F_MA<3>")
	)
	(segment
		(start 254.5334 -129.9464)
		(end 254.5334 -130.5052)
		(width 0.14224)
		(layer "In2.Cu")
		(net "M_F_MA<3>")
	)
	(segment
		(start 254.599694 -152.568148)
		(end 254.599694 -153.14295)
		(width 0.14224)
		(layer "In2.Cu")
		(net "M_F_MA<3>")
	)
	(segment
		(start 254.199898 -150.788878)
		(end 254.599694 -151.188674)
		(width 0.14224)
		(layer "In2.Cu")
		(net "M_F_MA<3>")
	)
	(segment
		(start 256.55651 -94.01302)
		(end 256.56286 -94.023688)
		(width 0.0889)
		(layer "In2.Cu")
		(net "M_F_MA<3>")
	)
	(segment
		(start 256.57556 -102.80904)
		(end 256.57556 -104.073198)
		(width 0.14224)
		(layer "In2.Cu")
		(net "M_F_MA<3>")
	)
	(segment
		(start 256.567686 -97.386902)
		(end 256.56286 -97.395538)
		(width 0.0889)
		(layer "In2.Cu")
		(net "M_F_MA<3>")
	)
	(segment
		(start 254.363982 -129.057146)
		(end 254.676656 -129.36982)
		(width 0.14224)
		(layer "In2.Cu")
		(net "M_F_MA<3>")
	)
	(segment
		(start 256.567686 -98.377502)
		(end 256.37236 -98.727006)
		(width 0.0889)
		(layer "In2.Cu")
		(net "M_F_MA<3>")
	)
	(segment
		(start 255.47701 -127.466852)
		(end 255.47701 -127.79629)
		(width 0.14224)
		(layer "In2.Cu")
		(net "M_F_MA<3>")
	)
	(segment
		(start 253.877064 -152.258268)
		(end 254.032004 -152.413208)
		(width 0.14224)
		(layer "In2.Cu")
		(net "M_F_MA<3>")
	)
	(segment
		(start 256.21615 -92.24264)
		(end 256.546096 -93.004386)
		(width 0.0889)
		(layer "In2.Cu")
		(net "M_F_MA<3>")
	)
	(segment
		(start 254.444754 -151.750268)
		(end 254.032004 -151.750268)
		(width 0.14224)
		(layer "In2.Cu")
		(net "M_F_MA<3>")
	)
	(segment
		(start 255.856486 -128.418336)
		(end 255.534414 -128.740408)
		(width 0.14224)
		(layer "In2.Cu")
		(net "M_F_MA<3>")
	)
	(segment
		(start 256.864104 -126.884176)
		(end 256.864104 -127.16129)
		(width 0.14224)
		(layer "In2.Cu")
		(net "M_F_MA<3>")
	)
	(segment
		(start 256.278888 -127.448564)
		(end 256.009902 -127.179578)
		(width 0.14224)
		(layer "In2.Cu")
		(net "M_F_MA<3>")
	)
	(segment
		(start 254.676656 -129.803144)
		(end 254.5334 -129.9464)
		(width 0.14224)
		(layer "In2.Cu")
		(net "M_F_MA<3>")
	)
	(segment
		(start 254.635 -146.558)
		(end 253.761494 -147.431506)
		(width 0.14224)
		(layer "In2.Cu")
		(net "M_F_MA<3>")
	)
	(segment
		(start 256.368804 -98.730562)
		(end 256.368804 -101.606604)
		(width 0.0889)
		(layer "In2.Cu")
		(net "M_F_MA<3>")
	)
	(segment
		(start 253.877064 -151.905208)
		(end 253.877064 -152.258268)
		(width 0.14224)
		(layer "In2.Cu")
		(net "M_F_MA<3>")
	)
	(segment
		(start 254.032004 -152.413208)
		(end 254.444754 -152.413208)
		(width 0.14224)
		(layer "In2.Cu")
		(net "M_F_MA<3>")
	)
	(segment
		(start 254.7112 -131.2164)
		(end 254.508 -131.4196)
		(width 0.14224)
		(layer "In2.Cu")
		(net "M_F_MA<3>")
	)
	(segment
		(start 254.363982 -128.754632)
		(end 254.363982 -129.057146)
		(width 0.14224)
		(layer "In2.Cu")
		(net "M_F_MA<3>")
	)
	(segment
		(start 256.56286 -96.404938)
		(end 256.55651 -96.415606)
		(width 0.0889)
		(layer "In2.Cu")
		(net "M_F_MA<3>")
	)
	(segment
		(start 256.567686 -93.424502)
		(end 256.56286 -93.433138)
		(width 0.0889)
		(layer "In2.Cu")
		(net "M_F_MA<3>")
	)
	(segment
		(start 254.635 -132.1816)
		(end 254.635 -146.558)
		(width 0.14224)
		(layer "In2.Cu")
		(net "M_F_MA<3>")
	)
	(segment
		(start 254.5334 -130.5052)
		(end 254.7112 -130.683)
		(width 0.14224)
		(layer "In2.Cu")
		(net "M_F_MA<3>")
	)
	(segment
		(start 255.534414 -128.740408)
		(end 255.271524 -128.740408)
		(width 0.14224)
		(layer "In2.Cu")
		(net "M_F_MA<3>")
	)
	(segment
		(start 254.599694 -151.595328)
		(end 254.444754 -151.750268)
		(width 0.14224)
		(layer "In2.Cu")
		(net "M_F_MA<3>")
	)
	(segment
		(start 254.958088 -128.426972)
		(end 254.691642 -128.426972)
		(width 0.14224)
		(layer "In2.Cu")
		(net "M_F_MA<3>")
	)
	(segment
		(start 255.47701 -127.79629)
		(end 255.856486 -128.175766)
		(width 0.14224)
		(layer "In2.Cu")
		(net "M_F_MA<3>")
	)
	(segment
		(start 256.8956 -125.922532)
		(end 256.542794 -126.275338)
		(width 0.14224)
		(layer "In2.Cu")
		(net "M_F_MA<3>")
	)
	(segment
		(start 254.676656 -129.36982)
		(end 254.676656 -129.803144)
		(width 0.14224)
		(layer "In2.Cu")
		(net "M_F_MA<3>")
	)
	(arc
		(start 256.55651 -95.425006)
		(mid 256.483712 -95.715769)
		(end 256.56286 -96.004888)
		(width 0.0889)
		(layer "In2.Cu")
		(net "M_F_MA<3>")
	)
	(arc
		(start 256.56286 -93.433138)
		(mid 256.483638 -93.722256)
		(end 256.55651 -94.01302)
		(width 0.0889)
		(layer "In2.Cu")
		(net "M_F_MA<3>")
	)
	(arc
		(start 256.56286 -96.004888)
		(mid 256.61633 -96.199951)
		(end 256.567686 -96.396302)
		(width 0.0889)
		(layer "In2.Cu")
		(net "M_F_MA<3>")
	)
	(arc
		(start 256.55651 -97.406206)
		(mid 256.483712 -97.696969)
		(end 256.56286 -97.986088)
		(width 0.0889)
		(layer "In2.Cu")
		(net "M_F_MA<3>")
	)
	(arc
		(start 256.55651 -96.415606)
		(mid 256.483712 -96.706369)
		(end 256.56286 -96.995488)
		(width 0.0889)
		(layer "In2.Cu")
		(net "M_F_MA<3>")
	)
	(arc
		(start 256.56286 -96.995488)
		(mid 256.61633 -97.190551)
		(end 256.567686 -97.386902)
		(width 0.0889)
		(layer "In2.Cu")
		(net "M_F_MA<3>")
	)
	(arc
		(start 256.56286 -97.986088)
		(mid 256.61633 -98.181151)
		(end 256.567686 -98.377502)
		(width 0.0889)
		(layer "In2.Cu")
		(net "M_F_MA<3>")
	)
	(arc
		(start 256.56286 -93.033088)
		(mid 256.61633 -93.228151)
		(end 256.567686 -93.424502)
		(width 0.0889)
		(layer "In2.Cu")
		(net "M_F_MA<3>")
	)
	(arc
		(start 256.56286 -94.423484)
		(mid 256.483729 -94.718886)
		(end 256.56286 -95.014288)
		(width 0.0889)
		(layer "In2.Cu")
		(net "M_F_MA<3>")
	)
	(arc
		(start 256.56286 -94.023688)
		(mid 256.616359 -94.223586)
		(end 256.56286 -94.423484)
		(width 0.0889)
		(layer "In2.Cu")
		(net "M_F_MA<3>")
	)
	(arc
		(start 256.56286 -95.014288)
		(mid 256.61633 -95.209351)
		(end 256.567686 -95.405702)
		(width 0.0889)
		(layer "In2.Cu")
		(net "M_F_MA<3>")
	)
	(segment
		(start 257.64617 -90.756486)
		(end 257.07467 -90.756486)
		(width 0.1016)
		(layer "F.Cu")
		(net "M_F_MA<2>")
	)
	(segment
		(start 255.049782 -155.538932)
		(end 255.049782 -156.87294)
		(width 0.1651)
		(layer "F.Cu")
		(net "M_F_MA<2>")
	)
	(segment
		(start 255.049782 -156.87294)
		(end 255.05029 -156.87294)
		(width 0.1651)
		(layer "F.Cu")
		(net "M_F_MA<2>")
	)
	(via
		(at 255.049782 -155.538932)
		(size 0.508)
		(drill 0.254)
		(layers "F.Cu" "B.Cu")
		(net "M_F_MA<2>")
	)
	(via
		(at 255.049782 -148.773388)
		(size 0.4572)
		(drill 0.2032)
		(layers "F.Cu" "B.Cu")
		(net "M_F_MA<2>")
	)
	(via
		(at 257.07467 -90.756486)
		(size 0.508)
		(drill 0.254)
		(layers "F.Cu" "B.Cu")
		(net "M_F_MA<2>")
	)
	(segment
		(start 255.05029 -147.478496)
		(end 255.049782 -147.478496)
		(width 0.1651)
		(layer "B.Cu")
		(net "M_F_MA<2>")
	)
	(segment
		(start 255.049782 -147.478496)
		(end 255.049782 -148.773388)
		(width 0.1651)
		(layer "B.Cu")
		(net "M_F_MA<2>")
	)
	(segment
		(start 259.171948 -101.958648)
		(end 259.171948 -126.772416)
		(width 0.14224)
		(layer "In11.Cu")
		(net "M_F_MA<2>")
	)
	(segment
		(start 259.9436 -139.4206)
		(end 260.4008 -139.8778)
		(width 0.14224)
		(layer "In11.Cu")
		(net "M_F_MA<2>")
	)
	(segment
		(start 257.07467 -90.756486)
		(end 257.532886 -91.52636)
		(width 0.0889)
		(layer "In11.Cu")
		(net "M_F_MA<2>")
	)
	(segment
		(start 259.171948 -126.772416)
		(end 259.715254 -127.315722)
		(width 0.14224)
		(layer "In11.Cu")
		(net "M_F_MA<2>")
	)
	(segment
		(start 257.791204 -100.577904)
		(end 257.87985 -100.66655)
		(width 0.0889)
		(layer "In11.Cu")
		(net "M_F_MA<2>")
	)
	(segment
		(start 257.59283 -94.01302)
		(end 257.58648 -94.023688)
		(width 0.0889)
		(layer "In11.Cu")
		(net "M_F_MA<2>")
	)
	(segment
		(start 260.4008 -139.8778)
		(end 260.4008 -145.8722)
		(width 0.14224)
		(layer "In11.Cu")
		(net "M_F_MA<2>")
	)
	(segment
		(start 257.581654 -93.424502)
		(end 257.58648 -93.433138)
		(width 0.0889)
		(layer "In11.Cu")
		(net "M_F_MA<2>")
	)
	(segment
		(start 257.58648 -95.414338)
		(end 257.59283 -95.425006)
		(width 0.0889)
		(layer "In11.Cu")
		(net "M_F_MA<2>")
	)
	(segment
		(start 255.049782 -154.957018)
		(end 255.049782 -155.538932)
		(width 0.14224)
		(layer "In11.Cu")
		(net "M_F_MA<2>")
	)
	(segment
		(start 255.049782 -149.401276)
		(end 254.612394 -149.838664)
		(width 0.14224)
		(layer "In11.Cu")
		(net "M_F_MA<2>")
	)
	(segment
		(start 257.532886 -91.52636)
		(end 257.532886 -93.2307)
		(width 0.0889)
		(layer "In11.Cu")
		(net "M_F_MA<2>")
	)
	(segment
		(start 259.9436 -133.604254)
		(end 259.9436 -139.4206)
		(width 0.14224)
		(layer "In11.Cu")
		(net "M_F_MA<2>")
	)
	(segment
		(start 254.612394 -153.088594)
		(end 255.507998 -153.984198)
		(width 0.14224)
		(layer "In11.Cu")
		(net "M_F_MA<2>")
	)
	(segment
		(start 259.715254 -127.315722)
		(end 259.715254 -133.375908)
		(width 0.14224)
		(layer "In11.Cu")
		(net "M_F_MA<2>")
	)
	(segment
		(start 257.581654 -96.396302)
		(end 257.58648 -96.404938)
		(width 0.0889)
		(layer "In11.Cu")
		(net "M_F_MA<2>")
	)
	(segment
		(start 260.4008 -145.8722)
		(end 258.287012 -147.985988)
		(width 0.14224)
		(layer "In11.Cu")
		(net "M_F_MA<2>")
	)
	(segment
		(start 254.612394 -149.838664)
		(end 254.612394 -153.088594)
		(width 0.14224)
		(layer "In11.Cu")
		(net "M_F_MA<2>")
	)
	(segment
		(start 255.837182 -147.985988)
		(end 255.049782 -148.773388)
		(width 0.14224)
		(layer "In11.Cu")
		(net "M_F_MA<2>")
	)
	(segment
		(start 257.87985 -100.66655)
		(end 259.171948 -101.958648)
		(width 0.14224)
		(layer "In11.Cu")
		(net "M_F_MA<2>")
	)
	(segment
		(start 257.58648 -96.404938)
		(end 257.59283 -96.415606)
		(width 0.0889)
		(layer "In11.Cu")
		(net "M_F_MA<2>")
	)
	(segment
		(start 258.287012 -147.985988)
		(end 255.837182 -147.985988)
		(width 0.14224)
		(layer "In11.Cu")
		(net "M_F_MA<2>")
	)
	(segment
		(start 257.791204 -97.752662)
		(end 257.791204 -100.577904)
		(width 0.0889)
		(layer "In11.Cu")
		(net "M_F_MA<2>")
	)
	(segment
		(start 257.581654 -95.405702)
		(end 257.58648 -95.414338)
		(width 0.0889)
		(layer "In11.Cu")
		(net "M_F_MA<2>")
	)
	(segment
		(start 255.049782 -148.773388)
		(end 255.049782 -149.401276)
		(width 0.14224)
		(layer "In11.Cu")
		(net "M_F_MA<2>")
	)
	(segment
		(start 255.507998 -154.498802)
		(end 255.049782 -154.957018)
		(width 0.14224)
		(layer "In11.Cu")
		(net "M_F_MA<2>")
	)
	(segment
		(start 257.581654 -97.386902)
		(end 257.791204 -97.752662)
		(width 0.0889)
		(layer "In11.Cu")
		(net "M_F_MA<2>")
	)
	(segment
		(start 259.715254 -133.375908)
		(end 259.9436 -133.604254)
		(width 0.14224)
		(layer "In11.Cu")
		(net "M_F_MA<2>")
	)
	(segment
		(start 255.507998 -153.984198)
		(end 255.507998 -154.498802)
		(width 0.14224)
		(layer "In11.Cu")
		(net "M_F_MA<2>")
	)
	(arc
		(start 257.58648 -95.014288)
		(mid 257.53301 -95.209351)
		(end 257.581654 -95.405702)
		(width 0.0889)
		(layer "In11.Cu")
		(net "M_F_MA<2>")
	)
	(arc
		(start 257.532886 -93.2307)
		(mid 257.544986 -93.330691)
		(end 257.581654 -93.424502)
		(width 0.0889)
		(layer "In11.Cu")
		(net "M_F_MA<2>")
	)
	(arc
		(start 257.59283 -96.415606)
		(mid 257.665628 -96.706369)
		(end 257.58648 -96.995488)
		(width 0.0889)
		(layer "In11.Cu")
		(net "M_F_MA<2>")
	)
	(arc
		(start 257.58648 -96.995488)
		(mid 257.53301 -97.190551)
		(end 257.581654 -97.386902)
		(width 0.0889)
		(layer "In11.Cu")
		(net "M_F_MA<2>")
	)
	(arc
		(start 257.58648 -96.004888)
		(mid 257.53301 -96.199951)
		(end 257.581654 -96.396302)
		(width 0.0889)
		(layer "In11.Cu")
		(net "M_F_MA<2>")
	)
	(arc
		(start 257.59283 -95.425006)
		(mid 257.665628 -95.715769)
		(end 257.58648 -96.004888)
		(width 0.0889)
		(layer "In11.Cu")
		(net "M_F_MA<2>")
	)
	(arc
		(start 257.58648 -94.023688)
		(mid 257.532981 -94.223586)
		(end 257.58648 -94.423484)
		(width 0.0889)
		(layer "In11.Cu")
		(net "M_F_MA<2>")
	)
	(arc
		(start 257.58648 -93.433138)
		(mid 257.665702 -93.722256)
		(end 257.59283 -94.01302)
		(width 0.0889)
		(layer "In11.Cu")
		(net "M_F_MA<2>")
	)
	(arc
		(start 257.58648 -94.423484)
		(mid 257.665611 -94.718886)
		(end 257.58648 -95.014288)
		(width 0.0889)
		(layer "In11.Cu")
		(net "M_F_MA<2>")
	)
	(segment
		(start 255.05029 -152.273)
		(end 255.049782 -152.278842)
		(width 0.1651)
		(layer "F.Cu")
		(net "M_F_MA<1>")
	)
	(segment
		(start 256.78765 -90.26144)
		(end 256.21615 -90.26144)
		(width 0.1016)
		(layer "F.Cu")
		(net "M_F_MA<1>")
	)
	(segment
		(start 255.050036 -152.279096)
		(end 255.050036 -154.252168)
		(width 0.1651)
		(layer "F.Cu")
		(net "M_F_MA<1>")
	)
	(segment
		(start 255.049782 -152.278842)
		(end 255.050036 -152.279096)
		(width 0.1651)
		(layer "F.Cu")
		(net "M_F_MA<1>")
	)
	(via
		(at 256.21615 -90.26144)
		(size 0.508)
		(drill 0.254)
		(layers "F.Cu" "B.Cu")
		(net "M_F_MA<1>")
	)
	(via
		(at 255.050036 -150.788878)
		(size 0.4572)
		(drill 0.2032)
		(layers "F.Cu" "B.Cu")
		(net "M_F_MA<1>")
	)
	(via
		(at 255.050036 -154.252168)
		(size 0.508)
		(drill 0.254)
		(layers "F.Cu" "B.Cu")
		(net "M_F_MA<1>")
	)
	(segment
		(start 255.050036 -150.814278)
		(end 255.050036 -150.788878)
		(width 0.1651)
		(layer "B.Cu")
		(net "M_F_MA<1>")
	)
	(segment
		(start 255.049782 -152.078182)
		(end 255.049782 -150.814532)
		(width 0.1651)
		(layer "B.Cu")
		(net "M_F_MA<1>")
	)
	(segment
		(start 255.05029 -152.078436)
		(end 255.049782 -152.078182)
		(width 0.1651)
		(layer "B.Cu")
		(net "M_F_MA<1>")
	)
	(segment
		(start 255.049782 -150.814532)
		(end 255.050036 -150.814278)
		(width 0.1651)
		(layer "B.Cu")
		(net "M_F_MA<1>")
	)
	(segment
		(start 256.342642 -134.022338)
		(end 255.6256 -133.305296)
		(width 0.14224)
		(layer "In2.Cu")
		(net "M_F_MA<1>")
	)
	(segment
		(start 255.36271 -144.362678)
		(end 255.463294 -144.262094)
		(width 0.14224)
		(layer "In2.Cu")
		(net "M_F_MA<1>")
	)
	(segment
		(start 255.36271 -145.698718)
		(end 255.36271 -144.362678)
		(width 0.14224)
		(layer "In2.Cu")
		(net "M_F_MA<1>")
	)
	(segment
		(start 256.723134 -94.527624)
		(end 256.72796 -94.518988)
		(width 0.0889)
		(layer "In2.Cu")
		(net "M_F_MA<1>")
	)
	(segment
		(start 255.050036 -150.788878)
		(end 255.050036 -154.252168)
		(width 0.14224)
		(layer "In2.Cu")
		(net "M_F_MA<1>")
	)
	(segment
		(start 257.08356 -103.862632)
		(end 257.08356 -102.035102)
		(width 0.14224)
		(layer "In2.Cu")
		(net "M_F_MA<1>")
	)
	(segment
		(start 254.5588 -150.297642)
		(end 254.5588 -149.225)
		(width 0.14224)
		(layer "In2.Cu")
		(net "M_F_MA<1>")
	)
	(segment
		(start 256.72796 -96.500188)
		(end 256.73431 -96.48952)
		(width 0.0889)
		(layer "In2.Cu")
		(net "M_F_MA<1>")
	)
	(segment
		(start 256.73431 -93.939106)
		(end 256.72796 -93.928438)
		(width 0.0889)
		(layer "In2.Cu")
		(net "M_F_MA<1>")
	)
	(segment
		(start 256.673604 -101.37775)
		(end 256.673604 -98.58121)
		(width 0.0889)
		(layer "In2.Cu")
		(net "M_F_MA<1>")
	)
	(segment
		(start 256.72796 -98.481388)
		(end 256.73431 -98.47072)
		(width 0.0889)
		(layer "In2.Cu")
		(net "M_F_MA<1>")
	)
	(segment
		(start 256.723134 -97.499424)
		(end 256.72796 -97.490788)
		(width 0.0889)
		(layer "In2.Cu")
		(net "M_F_MA<1>")
	)
	(segment
		(start 257.4036 -104.182672)
		(end 257.08356 -103.862632)
		(width 0.14224)
		(layer "In2.Cu")
		(net "M_F_MA<1>")
	)
	(segment
		(start 254.5588 -149.225)
		(end 254.634746 -149.149054)
		(width 0.14224)
		(layer "In2.Cu")
		(net "M_F_MA<1>")
	)
	(segment
		(start 255.050036 -150.788878)
		(end 254.5588 -150.297642)
		(width 0.14224)
		(layer "In2.Cu")
		(net "M_F_MA<1>")
	)
	(segment
		(start 255.6256 -133.305296)
		(end 255.6256 -129.397252)
		(width 0.14224)
		(layer "In2.Cu")
		(net "M_F_MA<1>")
	)
	(segment
		(start 256.723134 -95.518224)
		(end 256.72796 -95.509588)
		(width 0.0889)
		(layer "In2.Cu")
		(net "M_F_MA<1>")
	)
	(segment
		(start 257.08356 -101.787706)
		(end 256.673604 -101.37775)
		(width 0.0889)
		(layer "In2.Cu")
		(net "M_F_MA<1>")
	)
	(segment
		(start 255.463294 -142.33271)
		(end 256.342642 -141.453362)
		(width 0.14224)
		(layer "In2.Cu")
		(net "M_F_MA<1>")
	)
	(segment
		(start 255.464056 -146.643344)
		(end 255.464056 -145.800064)
		(width 0.14224)
		(layer "In2.Cu")
		(net "M_F_MA<1>")
	)
	(segment
		(start 256.671064 -91.173554)
		(end 256.21615 -90.26144)
		(width 0.0889)
		(layer "In2.Cu")
		(net "M_F_MA<1>")
	)
	(segment
		(start 256.72796 -97.490788)
		(end 256.73431 -97.48012)
		(width 0.0889)
		(layer "In2.Cu")
		(net "M_F_MA<1>")
	)
	(segment
		(start 256.342642 -141.453362)
		(end 256.342642 -134.022338)
		(width 0.14224)
		(layer "In2.Cu")
		(net "M_F_MA<1>")
	)
	(segment
		(start 256.72796 -95.509588)
		(end 256.73431 -95.49892)
		(width 0.0889)
		(layer "In2.Cu")
		(net "M_F_MA<1>")
	)
	(segment
		(start 257.4036 -127.619252)
		(end 257.4036 -104.182672)
		(width 0.14224)
		(layer "In2.Cu")
		(net "M_F_MA<1>")
	)
	(segment
		(start 256.673604 -98.58121)
		(end 256.72796 -98.481388)
		(width 0.0889)
		(layer "In2.Cu")
		(net "M_F_MA<1>")
	)
	(segment
		(start 255.464056 -145.800064)
		(end 255.36271 -145.698718)
		(width 0.14224)
		(layer "In2.Cu")
		(net "M_F_MA<1>")
	)
	(segment
		(start 256.723134 -96.508824)
		(end 256.72796 -96.500188)
		(width 0.0889)
		(layer "In2.Cu")
		(net "M_F_MA<1>")
	)
	(segment
		(start 255.463294 -144.262094)
		(end 255.463294 -142.33271)
		(width 0.14224)
		(layer "In2.Cu")
		(net "M_F_MA<1>")
	)
	(segment
		(start 254.634746 -147.472654)
		(end 255.464056 -146.643344)
		(width 0.14224)
		(layer "In2.Cu")
		(net "M_F_MA<1>")
	)
	(segment
		(start 257.08356 -102.035102)
		(end 257.08356 -101.787706)
		(width 0.0889)
		(layer "In2.Cu")
		(net "M_F_MA<1>")
	)
	(segment
		(start 256.671064 -92.72524)
		(end 256.671064 -91.173554)
		(width 0.0889)
		(layer "In2.Cu")
		(net "M_F_MA<1>")
	)
	(segment
		(start 254.634746 -149.149054)
		(end 254.634746 -147.472654)
		(width 0.14224)
		(layer "In2.Cu")
		(net "M_F_MA<1>")
	)
	(segment
		(start 255.6256 -129.397252)
		(end 257.4036 -127.619252)
		(width 0.14224)
		(layer "In2.Cu")
		(net "M_F_MA<1>")
	)
	(arc
		(start 256.73431 -95.49892)
		(mid 256.807108 -95.208157)
		(end 256.72796 -94.919038)
		(width 0.0889)
		(layer "In2.Cu")
		(net "M_F_MA<1>")
	)
	(arc
		(start 256.72796 -92.937838)
		(mid 256.685565 -92.835274)
		(end 256.671064 -92.72524)
		(width 0.0889)
		(layer "In2.Cu")
		(net "M_F_MA<1>")
	)
	(arc
		(start 256.72796 -95.909638)
		(mid 256.67449 -95.714575)
		(end 256.723134 -95.518224)
		(width 0.0889)
		(layer "In2.Cu")
		(net "M_F_MA<1>")
	)
	(arc
		(start 256.72796 -93.928438)
		(mid 256.674461 -93.72854)
		(end 256.72796 -93.528642)
		(width 0.0889)
		(layer "In2.Cu")
		(net "M_F_MA<1>")
	)
	(arc
		(start 256.73431 -97.48012)
		(mid 256.807108 -97.189357)
		(end 256.72796 -96.900238)
		(width 0.0889)
		(layer "In2.Cu")
		(net "M_F_MA<1>")
	)
	(arc
		(start 256.72796 -94.518988)
		(mid 256.807182 -94.22987)
		(end 256.73431 -93.939106)
		(width 0.0889)
		(layer "In2.Cu")
		(net "M_F_MA<1>")
	)
	(arc
		(start 256.72796 -96.900238)
		(mid 256.67449 -96.705175)
		(end 256.723134 -96.508824)
		(width 0.0889)
		(layer "In2.Cu")
		(net "M_F_MA<1>")
	)
	(arc
		(start 256.73431 -98.47072)
		(mid 256.807108 -98.179957)
		(end 256.72796 -97.890838)
		(width 0.0889)
		(layer "In2.Cu")
		(net "M_F_MA<1>")
	)
	(arc
		(start 256.72796 -97.890838)
		(mid 256.67449 -97.695775)
		(end 256.723134 -97.499424)
		(width 0.0889)
		(layer "In2.Cu")
		(net "M_F_MA<1>")
	)
	(arc
		(start 256.72796 -94.919038)
		(mid 256.67449 -94.723975)
		(end 256.723134 -94.527624)
		(width 0.0889)
		(layer "In2.Cu")
		(net "M_F_MA<1>")
	)
	(arc
		(start 256.72796 -93.528642)
		(mid 256.807091 -93.23324)
		(end 256.72796 -92.937838)
		(width 0.0889)
		(layer "In2.Cu")
		(net "M_F_MA<1>")
	)
	(arc
		(start 256.73431 -96.48952)
		(mid 256.807108 -96.198757)
		(end 256.72796 -95.909638)
		(width 0.0889)
		(layer "In2.Cu")
		(net "M_F_MA<1>")
	)
	(segment
		(start 267.089636 -91.25204)
		(end 266.518136 -91.25204)
		(width 0.10795)
		(layer "F.Cu")
		(net "M_F_MA<17>")
	)
	(segment
		(start 275.449792 -156.87294)
		(end 275.4503 -156.87294)
		(width 0.1651)
		(layer "F.Cu")
		(net "M_F_MA<17>")
	)
	(segment
		(start 275.449792 -155.614878)
		(end 275.449792 -156.87294)
		(width 0.1651)
		(layer "F.Cu")
		(net "M_F_MA<17>")
	)
	(via
		(at 275.449792 -155.614878)
		(size 0.508)
		(drill 0.254)
		(layers "F.Cu" "B.Cu")
		(net "M_F_MA<17>")
	)
	(via
		(at 275.4503 -148.773388)
		(size 0.4572)
		(drill 0.2032)
		(layers "F.Cu" "B.Cu")
		(net "M_F_MA<17>")
	)
	(via
		(at 266.518136 -91.25204)
		(size 0.508)
		(drill 0.254)
		(layers "F.Cu" "B.Cu")
		(net "M_F_MA<17>")
	)
	(segment
		(start 275.449792 -147.478496)
		(end 275.449792 -148.77288)
		(width 0.1651)
		(layer "B.Cu")
		(net "M_F_MA<17>")
	)
	(segment
		(start 275.449792 -148.77288)
		(end 275.4503 -148.773388)
		(width 0.1651)
		(layer "B.Cu")
		(net "M_F_MA<17>")
	)
	(segment
		(start 275.4503 -147.478496)
		(end 275.449792 -147.478496)
		(width 0.1651)
		(layer "B.Cu")
		(net "M_F_MA<17>")
	)
	(segment
		(start 275.087588 -151.186388)
		(end 275.087588 -153.842212)
		(width 0.14224)
		(layer "In11.Cu")
		(net "M_F_MA<17>")
	)
	(segment
		(start 275.559012 -150.018496)
		(end 275.014436 -150.563072)
		(width 0.14224)
		(layer "In11.Cu")
		(net "M_F_MA<17>")
	)
	(segment
		(start 277.6982 -131.3434)
		(end 277.6982 -131.8006)
		(width 0.14224)
		(layer "In11.Cu")
		(net "M_F_MA<17>")
	)
	(segment
		(start 267.199872 -92.244672)
		(end 267.6906 -92.244672)
		(width 0.0889)
		(layer "In11.Cu")
		(net "M_F_MA<17>")
	)
	(segment
		(start 274.992084 -153.937716)
		(end 274.992084 -154.545284)
		(width 0.14224)
		(layer "In11.Cu")
		(net "M_F_MA<17>")
	)
	(segment
		(start 275.087588 -153.842212)
		(end 274.992084 -153.937716)
		(width 0.14224)
		(layer "In11.Cu")
		(net "M_F_MA<17>")
	)
	(segment
		(start 277.589234 -131.909566)
		(end 277.589234 -134.714234)
		(width 0.14224)
		(layer "In11.Cu")
		(net "M_F_MA<17>")
	)
	(segment
		(start 275.014436 -150.563072)
		(end 275.014436 -151.113236)
		(width 0.14224)
		(layer "In11.Cu")
		(net "M_F_MA<17>")
	)
	(segment
		(start 274.992084 -154.545284)
		(end 275.449792 -155.002992)
		(width 0.14224)
		(layer "In11.Cu")
		(net "M_F_MA<17>")
	)
	(segment
		(start 277.6982 -130.0988)
		(end 277.6982 -130.4544)
		(width 0.14224)
		(layer "In11.Cu")
		(net "M_F_MA<17>")
	)
	(segment
		(start 277.576026 -126.29388)
		(end 277.576026 -129.255266)
		(width 0.14224)
		(layer "In11.Cu")
		(net "M_F_MA<17>")
	)
	(segment
		(start 277.495 -129.8956)
		(end 277.6982 -130.0988)
		(width 0.14224)
		(layer "In11.Cu")
		(net "M_F_MA<17>")
	)
	(segment
		(start 270.307054 -119.024908)
		(end 277.576026 -126.29388)
		(width 0.14224)
		(layer "In11.Cu")
		(net "M_F_MA<17>")
	)
	(segment
		(start 277.5204 -136.0424)
		(end 277.58517 -136.10717)
		(width 0.14224)
		(layer "In11.Cu")
		(net "M_F_MA<17>")
	)
	(segment
		(start 276.712172 -145.740628)
		(end 276.712172 -147.511516)
		(width 0.14224)
		(layer "In11.Cu")
		(net "M_F_MA<17>")
	)
	(segment
		(start 277.6982 -134.8232)
		(end 277.6982 -135.255)
		(width 0.14224)
		(layer "In11.Cu")
		(net "M_F_MA<17>")
	)
	(segment
		(start 277.6982 -131.8006)
		(end 277.589234 -131.909566)
		(width 0.14224)
		(layer "In11.Cu")
		(net "M_F_MA<17>")
	)
	(segment
		(start 266.7254 -91.7702)
		(end 267.199872 -92.244672)
		(width 0.0889)
		(layer "In11.Cu")
		(net "M_F_MA<17>")
	)
	(segment
		(start 266.7254 -91.459304)
		(end 266.7254 -91.7702)
		(width 0.0889)
		(layer "In11.Cu")
		(net "M_F_MA<17>")
	)
	(segment
		(start 277.6982 -135.255)
		(end 277.5204 -135.4328)
		(width 0.14224)
		(layer "In11.Cu")
		(net "M_F_MA<17>")
	)
	(segment
		(start 277.5204 -130.6322)
		(end 277.5204 -131.1656)
		(width 0.14224)
		(layer "In11.Cu")
		(net "M_F_MA<17>")
	)
	(segment
		(start 277.589234 -134.714234)
		(end 277.6982 -134.8232)
		(width 0.14224)
		(layer "In11.Cu")
		(net "M_F_MA<17>")
	)
	(segment
		(start 270.307054 -101.981254)
		(end 270.307054 -102.27056)
		(width 0.0889)
		(layer "In11.Cu")
		(net "M_F_MA<17>")
	)
	(segment
		(start 277.58517 -144.86763)
		(end 276.712172 -145.740628)
		(width 0.14224)
		(layer "In11.Cu")
		(net "M_F_MA<17>")
	)
	(segment
		(start 275.4503 -149.32914)
		(end 275.559012 -149.437852)
		(width 0.14224)
		(layer "In11.Cu")
		(net "M_F_MA<17>")
	)
	(segment
		(start 277.6982 -130.4544)
		(end 277.5204 -130.6322)
		(width 0.14224)
		(layer "In11.Cu")
		(net "M_F_MA<17>")
	)
	(segment
		(start 275.4503 -148.773388)
		(end 275.4503 -149.32914)
		(width 0.14224)
		(layer "In11.Cu")
		(net "M_F_MA<17>")
	)
	(segment
		(start 270.307054 -102.27056)
		(end 270.307054 -119.024908)
		(width 0.14224)
		(layer "In11.Cu")
		(net "M_F_MA<17>")
	)
	(segment
		(start 268.2494 -99.9236)
		(end 270.307054 -101.981254)
		(width 0.0889)
		(layer "In11.Cu")
		(net "M_F_MA<17>")
	)
	(segment
		(start 266.518136 -91.25204)
		(end 266.7254 -91.459304)
		(width 0.0889)
		(layer "In11.Cu")
		(net "M_F_MA<17>")
	)
	(segment
		(start 275.449792 -155.002992)
		(end 275.449792 -155.614878)
		(width 0.14224)
		(layer "In11.Cu")
		(net "M_F_MA<17>")
	)
	(segment
		(start 277.576026 -129.255266)
		(end 277.495 -129.336292)
		(width 0.14224)
		(layer "In11.Cu")
		(net "M_F_MA<17>")
	)
	(segment
		(start 277.5204 -135.4328)
		(end 277.5204 -136.0424)
		(width 0.14224)
		(layer "In11.Cu")
		(net "M_F_MA<17>")
	)
	(segment
		(start 275.559012 -149.437852)
		(end 275.559012 -150.018496)
		(width 0.14224)
		(layer "In11.Cu")
		(net "M_F_MA<17>")
	)
	(segment
		(start 268.2494 -92.803472)
		(end 268.2494 -99.9236)
		(width 0.0889)
		(layer "In11.Cu")
		(net "M_F_MA<17>")
	)
	(segment
		(start 276.712172 -147.511516)
		(end 275.4503 -148.773388)
		(width 0.14224)
		(layer "In11.Cu")
		(net "M_F_MA<17>")
	)
	(segment
		(start 277.58517 -136.10717)
		(end 277.58517 -144.86763)
		(width 0.14224)
		(layer "In11.Cu")
		(net "M_F_MA<17>")
	)
	(segment
		(start 277.495 -129.336292)
		(end 277.495 -129.8956)
		(width 0.14224)
		(layer "In11.Cu")
		(net "M_F_MA<17>")
	)
	(segment
		(start 267.6906 -92.244672)
		(end 268.2494 -92.803472)
		(width 0.0889)
		(layer "In11.Cu")
		(net "M_F_MA<17>")
	)
	(segment
		(start 277.5204 -131.1656)
		(end 277.6982 -131.3434)
		(width 0.14224)
		(layer "In11.Cu")
		(net "M_F_MA<17>")
	)
	(segment
		(start 275.014436 -151.113236)
		(end 275.087588 -151.186388)
		(width 0.14224)
		(layer "In11.Cu")
		(net "M_F_MA<17>")
	)
	(segment
		(start 268.650466 -152.273)
		(end 268.649958 -152.278842)
		(width 0.1651)
		(layer "F.Cu")
		(net "M_F_MA<16>")
	)
	(segment
		(start 268.649958 -154.251914)
		(end 268.649704 -154.252168)
		(width 0.1651)
		(layer "F.Cu")
		(net "M_F_MA<16>")
	)
	(segment
		(start 268.649958 -152.278842)
		(end 268.649958 -154.251914)
		(width 0.1651)
		(layer "F.Cu")
		(net "M_F_MA<16>")
	)
	(segment
		(start 261.93877 -92.24264)
		(end 261.36727 -92.24264)
		(width 0.1016)
		(layer "F.Cu")
		(net "M_F_MA<16>")
	)
	(via
		(at 261.36727 -92.24264)
		(size 0.508)
		(drill 0.254)
		(layers "F.Cu" "B.Cu")
		(net "M_F_MA<16>")
	)
	(via
		(at 268.649704 -154.252168)
		(size 0.508)
		(drill 0.254)
		(layers "F.Cu" "B.Cu")
		(net "M_F_MA<16>")
	)
	(via
		(at 268.649958 -150.785068)
		(size 0.4572)
		(drill 0.2032)
		(layers "F.Cu" "B.Cu")
		(net "M_F_MA<16>")
	)
	(segment
		(start 268.649958 -152.078182)
		(end 268.649958 -150.785068)
		(width 0.1651)
		(layer "B.Cu")
		(net "M_F_MA<16>")
	)
	(segment
		(start 268.650466 -152.078436)
		(end 268.649958 -152.078182)
		(width 0.1651)
		(layer "B.Cu")
		(net "M_F_MA<16>")
	)
	(segment
		(start 262.0518 -100.882196)
		(end 262.8392 -101.669596)
		(width 0.0889)
		(layer "In2.Cu")
		(net "M_F_MA<16>")
	)
	(segment
		(start 267.3096 -131.2164)
		(end 267.4112 -131.318)
		(width 0.14224)
		(layer "In2.Cu")
		(net "M_F_MA<16>")
	)
	(segment
		(start 267.390118 -141.67231)
		(end 267.462 -141.744192)
		(width 0.14224)
		(layer "In2.Cu")
		(net "M_F_MA<16>")
	)
	(segment
		(start 268.522958 -151.472392)
		(end 268.260322 -151.472392)
		(width 0.14224)
		(layer "In2.Cu")
		(net "M_F_MA<16>")
	)
	(segment
		(start 264.253472 -124.925074)
		(end 264.253472 -126.149354)
		(width 0.14224)
		(layer "In2.Cu")
		(net "M_F_MA<16>")
	)
	(segment
		(start 267.3096 -130.683)
		(end 267.3096 -131.2164)
		(width 0.14224)
		(layer "In2.Cu")
		(net "M_F_MA<16>")
	)
	(segment
		(start 261.87908 -97.490788)
		(end 261.874254 -97.499424)
		(width 0.0889)
		(layer "In2.Cu")
		(net "M_F_MA<16>")
	)
	(segment
		(start 262.8392 -101.669596)
		(end 262.8392 -102.8954)
		(width 0.0889)
		(layer "In2.Cu")
		(net "M_F_MA<16>")
	)
	(segment
		(start 267.371322 -147.21205)
		(end 268.211046 -148.051774)
		(width 0.14224)
		(layer "In2.Cu")
		(net "M_F_MA<16>")
	)
	(segment
		(start 261.88543 -96.48952)
		(end 261.87908 -96.500188)
		(width 0.0889)
		(layer "In2.Cu")
		(net "M_F_MA<16>")
	)
	(segment
		(start 268.260322 -151.472392)
		(end 268.078204 -151.65451)
		(width 0.14224)
		(layer "In2.Cu")
		(net "M_F_MA<16>")
	)
	(segment
		(start 261.87908 -95.509588)
		(end 261.874254 -95.518224)
		(width 0.0889)
		(layer "In2.Cu")
		(net "M_F_MA<16>")
	)
	(segment
		(start 267.382498 -144.935702)
		(end 267.371322 -144.946878)
		(width 0.14224)
		(layer "In2.Cu")
		(net "M_F_MA<16>")
	)
	(segment
		(start 268.265148 -152.325578)
		(end 269.486126 -152.325578)
		(width 0.14224)
		(layer "In2.Cu")
		(net "M_F_MA<16>")
	)
	(segment
		(start 267.4112 -131.318)
		(end 267.4112 -132.1816)
		(width 0.14224)
		(layer "In2.Cu")
		(net "M_F_MA<16>")
	)
	(segment
		(start 268.547596 -153.05913)
		(end 268.321028 -153.285698)
		(width 0.14224)
		(layer "In2.Cu")
		(net "M_F_MA<16>")
	)
	(segment
		(start 261.87908 -93.928438)
		(end 261.88543 -93.939106)
		(width 0.0889)
		(layer "In2.Cu")
		(net "M_F_MA<16>")
	)
	(segment
		(start 262.8392 -123.510802)
		(end 264.253472 -124.925074)
		(width 0.14224)
		(layer "In2.Cu")
		(net "M_F_MA<16>")
	)
	(segment
		(start 267.367766 -139.504166)
		(end 267.390118 -139.526518)
		(width 0.14224)
		(layer "In2.Cu")
		(net "M_F_MA<16>")
	)
	(segment
		(start 268.321028 -153.923492)
		(end 268.649704 -154.252168)
		(width 0.14224)
		(layer "In2.Cu")
		(net "M_F_MA<16>")
	)
	(segment
		(start 267.367766 -135.349234)
		(end 267.367766 -139.504166)
		(width 0.14224)
		(layer "In2.Cu")
		(net "M_F_MA<16>")
	)
	(segment
		(start 268.321028 -153.285698)
		(end 268.321028 -153.923492)
		(width 0.14224)
		(layer "In2.Cu")
		(net "M_F_MA<16>")
	)
	(segment
		(start 262.8392 -102.8954)
		(end 262.8392 -123.510802)
		(width 0.14224)
		(layer "In2.Cu")
		(net "M_F_MA<16>")
	)
	(segment
		(start 261.87908 -94.518988)
		(end 261.874254 -94.527624)
		(width 0.0889)
		(layer "In2.Cu")
		(net "M_F_MA<16>")
	)
	(segment
		(start 267.3096 -129.8194)
		(end 267.5128 -130.0226)
		(width 0.14224)
		(layer "In2.Cu")
		(net "M_F_MA<16>")
	)
	(segment
		(start 267.5128 -130.0226)
		(end 267.5128 -130.4798)
		(width 0.14224)
		(layer "In2.Cu")
		(net "M_F_MA<16>")
	)
	(segment
		(start 261.88543 -98.47072)
		(end 261.87908 -98.481388)
		(width 0.0889)
		(layer "In2.Cu")
		(net "M_F_MA<16>")
	)
	(segment
		(start 268.649958 -150.785068)
		(end 268.649958 -151.345392)
		(width 0.14224)
		(layer "In2.Cu")
		(net "M_F_MA<16>")
	)
	(segment
		(start 267.4112 -134.6962)
		(end 267.4112 -135.3058)
		(width 0.14224)
		(layer "In2.Cu")
		(net "M_F_MA<16>")
	)
	(segment
		(start 267.4112 -132.1816)
		(end 267.375132 -132.217668)
		(width 0.14224)
		(layer "In2.Cu")
		(net "M_F_MA<16>")
	)
	(segment
		(start 267.3096 -129.205482)
		(end 267.3096 -129.8194)
		(width 0.14224)
		(layer "In2.Cu")
		(net "M_F_MA<16>")
	)
	(segment
		(start 267.4112 -135.3058)
		(end 267.367766 -135.349234)
		(width 0.14224)
		(layer "In2.Cu")
		(net "M_F_MA<16>")
	)
	(segment
		(start 267.371322 -144.946878)
		(end 267.371322 -147.21205)
		(width 0.14224)
		(layer "In2.Cu")
		(net "M_F_MA<16>")
	)
	(segment
		(start 267.375132 -134.660132)
		(end 267.4112 -134.6962)
		(width 0.14224)
		(layer "In2.Cu")
		(net "M_F_MA<16>")
	)
	(segment
		(start 267.462 -143.129)
		(end 267.382498 -143.208502)
		(width 0.14224)
		(layer "In2.Cu")
		(net "M_F_MA<16>")
	)
	(segment
		(start 268.078204 -151.65451)
		(end 268.078204 -152.138634)
		(width 0.14224)
		(layer "In2.Cu")
		(net "M_F_MA<16>")
	)
	(segment
		(start 269.677896 -152.8953)
		(end 269.514066 -153.05913)
		(width 0.14224)
		(layer "In2.Cu")
		(net "M_F_MA<16>")
	)
	(segment
		(start 261.36727 -92.24264)
		(end 261.872222 -92.9259)
		(width 0.0889)
		(layer "In2.Cu")
		(net "M_F_MA<16>")
	)
	(segment
		(start 268.211046 -148.051774)
		(end 268.211046 -150.346156)
		(width 0.14224)
		(layer "In2.Cu")
		(net "M_F_MA<16>")
	)
	(segment
		(start 269.486126 -152.325578)
		(end 269.677896 -152.517348)
		(width 0.14224)
		(layer "In2.Cu")
		(net "M_F_MA<16>")
	)
	(segment
		(start 261.88543 -97.48012)
		(end 261.87908 -97.490788)
		(width 0.0889)
		(layer "In2.Cu")
		(net "M_F_MA<16>")
	)
	(segment
		(start 267.375132 -132.217668)
		(end 267.375132 -134.660132)
		(width 0.14224)
		(layer "In2.Cu")
		(net "M_F_MA<16>")
	)
	(segment
		(start 269.677896 -152.517348)
		(end 269.677896 -152.8953)
		(width 0.14224)
		(layer "In2.Cu")
		(net "M_F_MA<16>")
	)
	(segment
		(start 267.382498 -143.208502)
		(end 267.382498 -144.935702)
		(width 0.14224)
		(layer "In2.Cu")
		(net "M_F_MA<16>")
	)
	(segment
		(start 261.88543 -95.49892)
		(end 261.87908 -95.509588)
		(width 0.0889)
		(layer "In2.Cu")
		(net "M_F_MA<16>")
	)
	(segment
		(start 267.390118 -139.526518)
		(end 267.390118 -141.67231)
		(width 0.14224)
		(layer "In2.Cu")
		(net "M_F_MA<16>")
	)
	(segment
		(start 267.462 -141.744192)
		(end 267.462 -143.129)
		(width 0.14224)
		(layer "In2.Cu")
		(net "M_F_MA<16>")
	)
	(segment
		(start 262.0518 -99.526852)
		(end 262.0518 -100.882196)
		(width 0.0889)
		(layer "In2.Cu")
		(net "M_F_MA<16>")
	)
	(segment
		(start 261.87908 -96.500188)
		(end 261.874254 -96.508824)
		(width 0.0889)
		(layer "In2.Cu")
		(net "M_F_MA<16>")
	)
	(segment
		(start 269.514066 -153.05913)
		(end 268.547596 -153.05913)
		(width 0.14224)
		(layer "In2.Cu")
		(net "M_F_MA<16>")
	)
	(segment
		(start 268.649958 -151.345392)
		(end 268.522958 -151.472392)
		(width 0.14224)
		(layer "In2.Cu")
		(net "M_F_MA<16>")
	)
	(segment
		(start 267.5128 -130.4798)
		(end 267.3096 -130.683)
		(width 0.14224)
		(layer "In2.Cu")
		(net "M_F_MA<16>")
	)
	(segment
		(start 264.253472 -126.149354)
		(end 267.3096 -129.205482)
		(width 0.14224)
		(layer "In2.Cu")
		(net "M_F_MA<16>")
	)
	(segment
		(start 268.078204 -152.138634)
		(end 268.265148 -152.325578)
		(width 0.14224)
		(layer "In2.Cu")
		(net "M_F_MA<16>")
	)
	(segment
		(start 261.87908 -98.481388)
		(end 261.874254 -98.490024)
		(width 0.0889)
		(layer "In2.Cu")
		(net "M_F_MA<16>")
	)
	(segment
		(start 268.211046 -150.346156)
		(end 268.649958 -150.785068)
		(width 0.14224)
		(layer "In2.Cu")
		(net "M_F_MA<16>")
	)
	(arc
		(start 261.87908 -93.528642)
		(mid 261.825581 -93.72854)
		(end 261.87908 -93.928438)
		(width 0.0889)
		(layer "In2.Cu")
		(net "M_F_MA<16>")
	)
	(arc
		(start 261.87908 -96.900238)
		(mid 261.958302 -97.189356)
		(end 261.88543 -97.48012)
		(width 0.0889)
		(layer "In2.Cu")
		(net "M_F_MA<16>")
	)
	(arc
		(start 261.874254 -94.527624)
		(mid 261.825499 -94.723976)
		(end 261.87908 -94.919038)
		(width 0.0889)
		(layer "In2.Cu")
		(net "M_F_MA<16>")
	)
	(arc
		(start 261.874254 -98.490024)
		(mid 261.825499 -98.686376)
		(end 261.87908 -98.881438)
		(width 0.0889)
		(layer "In2.Cu")
		(net "M_F_MA<16>")
	)
	(arc
		(start 261.87908 -98.881438)
		(mid 262.007887 -99.192787)
		(end 262.0518 -99.526852)
		(width 0.0889)
		(layer "In2.Cu")
		(net "M_F_MA<16>")
	)
	(arc
		(start 261.874254 -96.508824)
		(mid 261.825499 -96.705176)
		(end 261.87908 -96.900238)
		(width 0.0889)
		(layer "In2.Cu")
		(net "M_F_MA<16>")
	)
	(arc
		(start 261.87908 -94.919038)
		(mid 261.958302 -95.208156)
		(end 261.88543 -95.49892)
		(width 0.0889)
		(layer "In2.Cu")
		(net "M_F_MA<16>")
	)
	(arc
		(start 261.88543 -93.939106)
		(mid 261.958228 -94.229869)
		(end 261.87908 -94.518988)
		(width 0.0889)
		(layer "In2.Cu")
		(net "M_F_MA<16>")
	)
	(arc
		(start 261.87908 -95.909638)
		(mid 261.958302 -96.198756)
		(end 261.88543 -96.48952)
		(width 0.0889)
		(layer "In2.Cu")
		(net "M_F_MA<16>")
	)
	(arc
		(start 261.872222 -92.9259)
		(mid 261.95823 -93.226322)
		(end 261.87908 -93.528642)
		(width 0.0889)
		(layer "In2.Cu")
		(net "M_F_MA<16>")
	)
	(arc
		(start 261.874254 -97.499424)
		(mid 261.825499 -97.695776)
		(end 261.87908 -97.890838)
		(width 0.0889)
		(layer "In2.Cu")
		(net "M_F_MA<16>")
	)
	(arc
		(start 261.874254 -95.518224)
		(mid 261.825499 -95.714576)
		(end 261.87908 -95.909638)
		(width 0.0889)
		(layer "In2.Cu")
		(net "M_F_MA<16>")
	)
	(arc
		(start 261.87908 -97.890838)
		(mid 261.958302 -98.179956)
		(end 261.88543 -98.47072)
		(width 0.0889)
		(layer "In2.Cu")
		(net "M_F_MA<16>")
	)
	(segment
		(start 259.65023 -90.26144)
		(end 260.22173 -90.26144)
		(width 0.1016)
		(layer "F.Cu")
		(net "M_F_MA<15>")
	)
	(segment
		(start 272.050002 -152.278842)
		(end 272.050002 -154.251914)
		(width 0.1651)
		(layer "F.Cu")
		(net "M_F_MA<15>")
	)
	(segment
		(start 272.050002 -154.251914)
		(end 272.049748 -154.252168)
		(width 0.1651)
		(layer "F.Cu")
		(net "M_F_MA<15>")
	)
	(segment
		(start 272.05051 -152.273)
		(end 272.050002 -152.278842)
		(width 0.1651)
		(layer "F.Cu")
		(net "M_F_MA<15>")
	)
	(via
		(at 259.65023 -90.26144)
		(size 0.508)
		(drill 0.254)
		(layers "F.Cu" "B.Cu")
		(net "M_F_MA<15>")
	)
	(via
		(at 272.049748 -154.252168)
		(size 0.508)
		(drill 0.254)
		(layers "F.Cu" "B.Cu")
		(net "M_F_MA<15>")
	)
	(via
		(at 272.050256 -150.788878)
		(size 0.4572)
		(drill 0.2032)
		(layers "F.Cu" "B.Cu")
		(net "M_F_MA<15>")
	)
	(segment
		(start 272.050002 -152.078182)
		(end 272.050002 -150.789132)
		(width 0.10795)
		(layer "B.Cu")
		(net "M_F_MA<15>")
	)
	(segment
		(start 272.050002 -150.789132)
		(end 272.050256 -150.788878)
		(width 0.10795)
		(layer "B.Cu")
		(net "M_F_MA<15>")
	)
	(segment
		(start 272.05051 -152.078436)
		(end 272.050002 -152.078182)
		(width 0.10795)
		(layer "B.Cu")
		(net "M_F_MA<15>")
	)
	(segment
		(start 261.401052 -100.269294)
		(end 262.6995 -101.567742)
		(width 0.14224)
		(layer "In11.Cu")
		(net "M_F_MA<15>")
	)
	(segment
		(start 269.091918 -138.723878)
		(end 269.091918 -139.450318)
		(width 0.14224)
		(layer "In11.Cu")
		(net "M_F_MA<15>")
	)
	(segment
		(start 271.787112 -151.78151)
		(end 270.58239 -151.78151)
		(width 0.14224)
		(layer "In11.Cu")
		(net "M_F_MA<15>")
	)
	(segment
		(start 268.1478 -131.8006)
		(end 268.211046 -131.863846)
		(width 0.14224)
		(layer "In11.Cu")
		(net "M_F_MA<15>")
	)
	(segment
		(start 269.8496 -144.8054)
		(end 270.763746 -145.719546)
		(width 0.14224)
		(layer "In11.Cu")
		(net "M_F_MA<15>")
	)
	(segment
		(start 262.6995 -103.1621)
		(end 263.642348 -104.104948)
		(width 0.14224)
		(layer "In11.Cu")
		(net "M_F_MA<15>")
	)
	(segment
		(start 268.3002 -130.683)
		(end 268.3002 -131.1402)
		(width 0.14224)
		(layer "In11.Cu")
		(net "M_F_MA<15>")
	)
	(segment
		(start 263.642348 -104.104948)
		(end 263.642348 -122.335544)
		(width 0.14224)
		(layer "In11.Cu")
		(net "M_F_MA<15>")
	)
	(segment
		(start 270.763746 -149.502368)
		(end 272.050256 -150.788878)
		(width 0.14224)
		(layer "In11.Cu")
		(net "M_F_MA<15>")
	)
	(segment
		(start 268.1478 -130.5306)
		(end 268.3002 -130.683)
		(width 0.14224)
		(layer "In11.Cu")
		(net "M_F_MA<15>")
	)
	(segment
		(start 269.8496 -144.3736)
		(end 269.8496 -144.8054)
		(width 0.14224)
		(layer "In11.Cu")
		(net "M_F_MA<15>")
	)
	(segment
		(start 270.59001 -152.59431)
		(end 272.119344 -152.59431)
		(width 0.14224)
		(layer "In11.Cu")
		(net "M_F_MA<15>")
	)
	(segment
		(start 269.1384 -139.4968)
		(end 269.1384 -140.1064)
		(width 0.14224)
		(layer "In11.Cu")
		(net "M_F_MA<15>")
	)
	(segment
		(start 260.85546 -99.471988)
		(end 261.200646 -100.068888)
		(width 0.0889)
		(layer "In11.Cu")
		(net "M_F_MA<15>")
	)
	(segment
		(start 268.4018 -137.033)
		(end 268.4018 -138.03376)
		(width 0.14224)
		(layer "In11.Cu")
		(net "M_F_MA<15>")
	)
	(segment
		(start 259.65023 -90.26144)
		(end 259.95757 -90.969846)
		(width 0.0889)
		(layer "In11.Cu")
		(net "M_F_MA<15>")
	)
	(segment
		(start 272.119344 -152.59431)
		(end 272.388076 -152.863042)
		(width 0.14224)
		(layer "In11.Cu")
		(net "M_F_MA<15>")
	)
	(segment
		(start 259.99694 -91.451938)
		(end 259.99059 -91.462606)
		(width 0.0889)
		(layer "In11.Cu")
		(net "M_F_MA<15>")
	)
	(segment
		(start 269.1384 -140.1064)
		(end 269.942564 -140.910564)
		(width 0.14224)
		(layer "In11.Cu")
		(net "M_F_MA<15>")
	)
	(segment
		(start 272.388076 -152.863042)
		(end 272.388076 -153.91384)
		(width 0.14224)
		(layer "In11.Cu")
		(net "M_F_MA<15>")
	)
	(segment
		(start 270.763746 -145.719546)
		(end 270.763746 -149.502368)
		(width 0.14224)
		(layer "In11.Cu")
		(net "M_F_MA<15>")
	)
	(segment
		(start 268.351 -129.794)
		(end 268.1478 -129.9972)
		(width 0.14224)
		(layer "In11.Cu")
		(net "M_F_MA<15>")
	)
	(segment
		(start 268.1478 -131.2926)
		(end 268.1478 -131.8006)
		(width 0.14224)
		(layer "In11.Cu")
		(net "M_F_MA<15>")
	)
	(segment
		(start 272.049748 -151.518874)
		(end 271.787112 -151.78151)
		(width 0.14224)
		(layer "In11.Cu")
		(net "M_F_MA<15>")
	)
	(segment
		(start 268.211046 -136.842246)
		(end 268.4018 -137.033)
		(width 0.14224)
		(layer "In11.Cu")
		(net "M_F_MA<15>")
	)
	(segment
		(start 270.368268 -151.995632)
		(end 270.368268 -152.372568)
		(width 0.14224)
		(layer "In11.Cu")
		(net "M_F_MA<15>")
	)
	(segment
		(start 268.4018 -138.03376)
		(end 269.091918 -138.723878)
		(width 0.14224)
		(layer "In11.Cu")
		(net "M_F_MA<15>")
	)
	(segment
		(start 268.351 -127.044196)
		(end 268.351 -129.794)
		(width 0.14224)
		(layer "In11.Cu")
		(net "M_F_MA<15>")
	)
	(segment
		(start 272.388076 -153.91384)
		(end 272.049748 -154.252168)
		(width 0.14224)
		(layer "In11.Cu")
		(net "M_F_MA<15>")
	)
	(segment
		(start 268.1478 -129.9972)
		(end 268.1478 -130.5306)
		(width 0.14224)
		(layer "In11.Cu")
		(net "M_F_MA<15>")
	)
	(segment
		(start 272.049748 -150.789386)
		(end 272.049748 -151.518874)
		(width 0.14224)
		(layer "In11.Cu")
		(net "M_F_MA<15>")
	)
	(segment
		(start 268.211046 -131.863846)
		(end 268.211046 -136.842246)
		(width 0.14224)
		(layer "In11.Cu")
		(net "M_F_MA<15>")
	)
	(segment
		(start 260.001766 -91.443302)
		(end 259.99694 -91.451938)
		(width 0.0889)
		(layer "In11.Cu")
		(net "M_F_MA<15>")
	)
	(segment
		(start 269.942564 -140.910564)
		(end 269.942564 -144.280636)
		(width 0.14224)
		(layer "In11.Cu")
		(net "M_F_MA<15>")
	)
	(segment
		(start 270.368268 -152.372568)
		(end 270.59001 -152.59431)
		(width 0.14224)
		(layer "In11.Cu")
		(net "M_F_MA<15>")
	)
	(segment
		(start 269.091918 -139.450318)
		(end 269.1384 -139.4968)
		(width 0.14224)
		(layer "In11.Cu")
		(net "M_F_MA<15>")
	)
	(segment
		(start 260.48716 -96.300036)
		(end 260.519926 -96.300036)
		(width 0.0889)
		(layer "In11.Cu")
		(net "M_F_MA<15>")
	)
	(segment
		(start 268.3002 -131.1402)
		(end 268.1478 -131.2926)
		(width 0.14224)
		(layer "In11.Cu")
		(net "M_F_MA<15>")
	)
	(segment
		(start 272.050256 -150.788878)
		(end 272.049748 -150.789386)
		(width 0.14224)
		(layer "In11.Cu")
		(net "M_F_MA<15>")
	)
	(segment
		(start 261.200646 -100.068888)
		(end 261.401052 -100.269294)
		(width 0.0889)
		(layer "In11.Cu")
		(net "M_F_MA<15>")
	)
	(segment
		(start 270.58239 -151.78151)
		(end 270.368268 -151.995632)
		(width 0.14224)
		(layer "In11.Cu")
		(net "M_F_MA<15>")
	)
	(segment
		(start 269.942564 -144.280636)
		(end 269.8496 -144.3736)
		(width 0.14224)
		(layer "In11.Cu")
		(net "M_F_MA<15>")
	)
	(segment
		(start 263.642348 -122.335544)
		(end 268.351 -127.044196)
		(width 0.14224)
		(layer "In11.Cu")
		(net "M_F_MA<15>")
	)
	(segment
		(start 262.6995 -101.567742)
		(end 262.6995 -103.1621)
		(width 0.14224)
		(layer "In11.Cu")
		(net "M_F_MA<15>")
	)
	(arc
		(start 259.99694 -95.014288)
		(mid 260.050439 -95.214186)
		(end 259.99694 -95.414084)
		(width 0.0889)
		(layer "In11.Cu")
		(net "M_F_MA<15>")
	)
	(arc
		(start 260.519926 -96.300036)
		(mid 260.858041 -96.504738)
		(end 260.85546 -96.899984)
		(width 0.0889)
		(layer "In11.Cu")
		(net "M_F_MA<15>")
	)
	(arc
		(start 260.85546 -96.899984)
		(mid 260.776329 -97.195386)
		(end 260.85546 -97.490788)
		(width 0.0889)
		(layer "In11.Cu")
		(net "M_F_MA<15>")
	)
	(arc
		(start 260.85546 -98.481388)
		(mid 260.908959 -98.681286)
		(end 260.85546 -98.881184)
		(width 0.0889)
		(layer "In11.Cu")
		(net "M_F_MA<15>")
	)
	(arc
		(start 259.99694 -93.033088)
		(mid 260.050439 -93.232986)
		(end 259.99694 -93.432884)
		(width 0.0889)
		(layer "In11.Cu")
		(net "M_F_MA<15>")
	)
	(arc
		(start 259.99694 -93.432884)
		(mid 259.917809 -93.728286)
		(end 259.99694 -94.023688)
		(width 0.0889)
		(layer "In11.Cu")
		(net "M_F_MA<15>")
	)
	(arc
		(start 259.99059 -91.462606)
		(mid 259.917792 -91.753369)
		(end 259.99694 -92.042488)
		(width 0.0889)
		(layer "In11.Cu")
		(net "M_F_MA<15>")
	)
	(arc
		(start 260.85546 -98.881184)
		(mid 260.776329 -99.176586)
		(end 260.85546 -99.471988)
		(width 0.0889)
		(layer "In11.Cu")
		(net "M_F_MA<15>")
	)
	(arc
		(start 260.85546 -97.490788)
		(mid 260.908959 -97.690686)
		(end 260.85546 -97.890584)
		(width 0.0889)
		(layer "In11.Cu")
		(net "M_F_MA<15>")
	)
	(arc
		(start 259.99694 -94.023688)
		(mid 260.050439 -94.223586)
		(end 259.99694 -94.423484)
		(width 0.0889)
		(layer "In11.Cu")
		(net "M_F_MA<15>")
	)
	(arc
		(start 259.99694 -94.423484)
		(mid 259.917809 -94.718886)
		(end 259.99694 -95.014288)
		(width 0.0889)
		(layer "In11.Cu")
		(net "M_F_MA<15>")
	)
	(arc
		(start 259.99694 -92.442284)
		(mid 259.917809 -92.737686)
		(end 259.99694 -93.033088)
		(width 0.0889)
		(layer "In11.Cu")
		(net "M_F_MA<15>")
	)
	(arc
		(start 259.99694 -91.051888)
		(mid 260.05041 -91.246951)
		(end 260.001766 -91.443302)
		(width 0.0889)
		(layer "In11.Cu")
		(net "M_F_MA<15>")
	)
	(arc
		(start 259.95757 -90.969846)
		(mid 259.975671 -91.011627)
		(end 259.99694 -91.051888)
		(width 0.0889)
		(layer "In11.Cu")
		(net "M_F_MA<15>")
	)
	(arc
		(start 260.85546 -97.890584)
		(mid 260.776329 -98.185986)
		(end 260.85546 -98.481388)
		(width 0.0889)
		(layer "In11.Cu")
		(net "M_F_MA<15>")
	)
	(arc
		(start 259.99694 -95.414084)
		(mid 259.991686 -95.995592)
		(end 260.48716 -96.300036)
		(width 0.0889)
		(layer "In11.Cu")
		(net "M_F_MA<15>")
	)
	(arc
		(start 259.99694 -92.042488)
		(mid 260.050439 -92.242386)
		(end 259.99694 -92.442284)
		(width 0.0889)
		(layer "In11.Cu")
		(net "M_F_MA<15>")
	)
	(segment
		(start 270.34998 -155.615132)
		(end 270.34998 -156.87294)
		(width 0.1651)
		(layer "F.Cu")
		(net "M_F_MA<14>")
	)
	(segment
		(start 263.65581 -93.23324)
		(end 263.08431 -93.23324)
		(width 0.1016)
		(layer "F.Cu")
		(net "M_F_MA<14>")
	)
	(segment
		(start 270.34998 -156.87294)
		(end 270.350488 -156.87294)
		(width 0.1651)
		(layer "F.Cu")
		(net "M_F_MA<14>")
	)
	(segment
		(start 270.349726 -155.614878)
		(end 270.34998 -155.615132)
		(width 0.1651)
		(layer "F.Cu")
		(net "M_F_MA<14>")
	)
	(via
		(at 270.349726 -155.614878)
		(size 0.508)
		(drill 0.254)
		(layers "F.Cu" "B.Cu")
		(net "M_F_MA<14>")
	)
	(via
		(at 263.08431 -93.23324)
		(size 0.508)
		(drill 0.254)
		(layers "F.Cu" "B.Cu")
		(net "M_F_MA<14>")
	)
	(via
		(at 270.350234 -148.773388)
		(size 0.4572)
		(drill 0.2032)
		(layers "F.Cu" "B.Cu")
		(net "M_F_MA<14>")
	)
	(segment
		(start 270.34998 -148.773134)
		(end 270.350234 -148.773388)
		(width 0.1651)
		(layer "B.Cu")
		(net "M_F_MA<14>")
	)
	(segment
		(start 270.34998 -147.478496)
		(end 270.34998 -148.773134)
		(width 0.1651)
		(layer "B.Cu")
		(net "M_F_MA<14>")
	)
	(segment
		(start 270.350488 -147.478496)
		(end 270.34998 -147.478496)
		(width 0.1651)
		(layer "B.Cu")
		(net "M_F_MA<14>")
	)
	(segment
		(start 263.43102 -97.395538)
		(end 263.42467 -97.406206)
		(width 0.0889)
		(layer "In2.Cu")
		(net "M_F_MA<14>")
	)
	(segment
		(start 264.0838 -101.219)
		(end 264.0838 -102.544626)
		(width 0.0889)
		(layer "In2.Cu")
		(net "M_F_MA<14>")
	)
	(segment
		(start 263.435846 -95.405702)
		(end 263.43102 -95.414338)
		(width 0.0889)
		(layer "In2.Cu")
		(net "M_F_MA<14>")
	)
	(segment
		(start 269.912846 -133.947154)
		(end 269.912846 -137.020046)
		(width 0.14224)
		(layer "In2.Cu")
		(net "M_F_MA<14>")
	)
	(segment
		(start 270.380714 -141.86154)
		(end 270.54175 -142.022576)
		(width 0.14224)
		(layer "In2.Cu")
		(net "M_F_MA<14>")
	)
	(segment
		(start 263.435846 -97.386902)
		(end 263.43102 -97.395538)
		(width 0.0889)
		(layer "In2.Cu")
		(net "M_F_MA<14>")
	)
	(segment
		(start 269.920212 -144.901412)
		(end 269.920212 -147.184364)
		(width 0.14224)
		(layer "In2.Cu")
		(net "M_F_MA<14>")
	)
	(segment
		(start 269.89659 -131.22021)
		(end 269.89659 -131.92379)
		(width 0.14224)
		(layer "In2.Cu")
		(net "M_F_MA<14>")
	)
	(segment
		(start 270.350234 -148.773388)
		(end 270.765524 -149.188678)
		(width 0.14224)
		(layer "In2.Cu")
		(net "M_F_MA<14>")
	)
	(segment
		(start 263.43102 -98.386138)
		(end 263.42467 -98.396806)
		(width 0.0889)
		(layer "In2.Cu")
		(net "M_F_MA<14>")
	)
	(segment
		(start 264.379964 -103.023924)
		(end 264.379964 -122.895868)
		(width 0.14224)
		(layer "In2.Cu")
		(net "M_F_MA<14>")
	)
	(segment
		(start 263.435846 -98.377502)
		(end 263.43102 -98.386138)
		(width 0.0889)
		(layer "In2.Cu")
		(net "M_F_MA<14>")
	)
	(segment
		(start 263.43102 -96.404938)
		(end 263.42467 -96.415606)
		(width 0.0889)
		(layer "In2.Cu")
		(net "M_F_MA<14>")
	)
	(segment
		(start 264.379964 -102.84079)
		(end 264.379964 -103.023924)
		(width 0.0889)
		(layer "In2.Cu")
		(net "M_F_MA<14>")
	)
	(segment
		(start 270.806926 -153.865326)
		(end 270.806926 -154.498294)
		(width 0.14224)
		(layer "In2.Cu")
		(net "M_F_MA<14>")
	)
	(segment
		(start 267.346684 -125.862588)
		(end 267.346684 -126.150116)
		(width 0.14224)
		(layer "In2.Cu")
		(net "M_F_MA<14>")
	)
	(segment
		(start 270.188436 -132.215636)
		(end 270.188436 -133.671564)
		(width 0.14224)
		(layer "In2.Cu")
		(net "M_F_MA<14>")
	)
	(segment
		(start 267.914628 -126.731776)
		(end 268.205458 -126.731776)
		(width 0.14224)
		(layer "In2.Cu")
		(net "M_F_MA<14>")
	)
	(segment
		(start 270.505174 -148.210524)
		(end 270.350234 -148.365464)
		(width 0.14224)
		(layer "In2.Cu")
		(net "M_F_MA<14>")
	)
	(segment
		(start 269.941294 -129.880106)
		(end 269.880588 -129.940812)
		(width 0.14224)
		(layer "In2.Cu")
		(net "M_F_MA<14>")
	)
	(segment
		(start 270.84147 -147.547584)
		(end 270.989806 -147.69592)
		(width 0.14224)
		(layer "In2.Cu")
		(net "M_F_MA<14>")
	)
	(segment
		(start 268.205458 -126.731776)
		(end 268.4018 -126.928118)
		(width 0.14224)
		(layer "In2.Cu")
		(net "M_F_MA<14>")
	)
	(segment
		(start 263.08431 -93.23324)
		(end 263.414002 -93.994478)
		(width 0.0889)
		(layer "In2.Cu")
		(net "M_F_MA<14>")
	)
	(segment
		(start 270.765524 -151.661876)
		(end 270.742664 -151.684736)
		(width 0.14224)
		(layer "In2.Cu")
		(net "M_F_MA<14>")
	)
	(segment
		(start 269.89659 -131.92379)
		(end 270.188436 -132.215636)
		(width 0.14224)
		(layer "In2.Cu")
		(net "M_F_MA<14>")
	)
	(segment
		(start 270.742664 -153.801064)
		(end 270.806926 -153.865326)
		(width 0.14224)
		(layer "In2.Cu")
		(net "M_F_MA<14>")
	)
	(segment
		(start 269.935198 -137.042398)
		(end 269.935198 -140.115798)
		(width 0.14224)
		(layer "In2.Cu")
		(net "M_F_MA<14>")
	)
	(segment
		(start 270.765524 -149.188678)
		(end 270.765524 -151.661876)
		(width 0.14224)
		(layer "In2.Cu")
		(net "M_F_MA<14>")
	)
	(segment
		(start 270.188436 -133.671564)
		(end 269.912846 -133.947154)
		(width 0.14224)
		(layer "In2.Cu")
		(net "M_F_MA<14>")
	)
	(segment
		(start 270.350234 -148.365464)
		(end 270.350234 -148.773388)
		(width 0.14224)
		(layer "In2.Cu")
		(net "M_F_MA<14>")
	)
	(segment
		(start 269.927832 -144.893792)
		(end 269.920212 -144.901412)
		(width 0.14224)
		(layer "In2.Cu")
		(net "M_F_MA<14>")
	)
	(segment
		(start 267.130022 -126.366778)
		(end 267.130022 -126.66091)
		(width 0.14224)
		(layer "In2.Cu")
		(net "M_F_MA<14>")
	)
	(segment
		(start 263.43102 -95.414338)
		(end 263.42467 -95.425006)
		(width 0.0889)
		(layer "In2.Cu")
		(net "M_F_MA<14>")
	)
	(segment
		(start 269.927832 -142.867634)
		(end 269.927832 -144.893792)
		(width 0.14224)
		(layer "In2.Cu")
		(net "M_F_MA<14>")
	)
	(segment
		(start 268.4018 -126.928118)
		(end 268.4018 -127.823976)
		(width 0.14224)
		(layer "In2.Cu")
		(net "M_F_MA<14>")
	)
	(segment
		(start 270.989806 -147.69592)
		(end 270.989806 -148.04898)
		(width 0.14224)
		(layer "In2.Cu")
		(net "M_F_MA<14>")
	)
	(segment
		(start 270.283432 -147.547584)
		(end 270.84147 -147.547584)
		(width 0.14224)
		(layer "In2.Cu")
		(net "M_F_MA<14>")
	)
	(segment
		(start 270.376142 -142.67434)
		(end 270.121126 -142.67434)
		(width 0.14224)
		(layer "In2.Cu")
		(net "M_F_MA<14>")
	)
	(segment
		(start 263.216644 -100.351844)
		(end 264.0838 -101.219)
		(width 0.0889)
		(layer "In2.Cu")
		(net "M_F_MA<14>")
	)
	(segment
		(start 269.880588 -130.536188)
		(end 269.971774 -130.627374)
		(width 0.14224)
		(layer "In2.Cu")
		(net "M_F_MA<14>")
	)
	(segment
		(start 270.828262 -148.210524)
		(end 270.505174 -148.210524)
		(width 0.14224)
		(layer "In2.Cu")
		(net "M_F_MA<14>")
	)
	(segment
		(start 269.938754 -140.119354)
		(end 269.938754 -141.656816)
		(width 0.14224)
		(layer "In2.Cu")
		(net "M_F_MA<14>")
	)
	(segment
		(start 268.4018 -127.823976)
		(end 269.941294 -129.36347)
		(width 0.14224)
		(layer "In2.Cu")
		(net "M_F_MA<14>")
	)
	(segment
		(start 269.971774 -130.627374)
		(end 269.971774 -131.145026)
		(width 0.14224)
		(layer "In2.Cu")
		(net "M_F_MA<14>")
	)
	(segment
		(start 270.742664 -151.684736)
		(end 270.742664 -153.801064)
		(width 0.14224)
		(layer "In2.Cu")
		(net "M_F_MA<14>")
	)
	(segment
		(start 270.143478 -141.86154)
		(end 270.380714 -141.86154)
		(width 0.14224)
		(layer "In2.Cu")
		(net "M_F_MA<14>")
	)
	(segment
		(start 269.941294 -129.36347)
		(end 269.941294 -129.880106)
		(width 0.14224)
		(layer "In2.Cu")
		(net "M_F_MA<14>")
	)
	(segment
		(start 270.989806 -148.04898)
		(end 270.828262 -148.210524)
		(width 0.14224)
		(layer "In2.Cu")
		(net "M_F_MA<14>")
	)
	(segment
		(start 263.216644 -99.673156)
		(end 263.216644 -100.351844)
		(width 0.0889)
		(layer "In2.Cu")
		(net "M_F_MA<14>")
	)
	(segment
		(start 269.912846 -137.020046)
		(end 269.935198 -137.042398)
		(width 0.14224)
		(layer "In2.Cu")
		(net "M_F_MA<14>")
	)
	(segment
		(start 263.414002 -93.994478)
		(end 263.43102 -94.023688)
		(width 0.0889)
		(layer "In2.Cu")
		(net "M_F_MA<14>")
	)
	(segment
		(start 263.3726 -99.5172)
		(end 263.216644 -99.673156)
		(width 0.0889)
		(layer "In2.Cu")
		(net "M_F_MA<14>")
	)
	(segment
		(start 267.69822 -126.948184)
		(end 267.914628 -126.731776)
		(width 0.14224)
		(layer "In2.Cu")
		(net "M_F_MA<14>")
	)
	(segment
		(start 269.920212 -147.184364)
		(end 270.283432 -147.547584)
		(width 0.14224)
		(layer "In2.Cu")
		(net "M_F_MA<14>")
	)
	(segment
		(start 264.379964 -122.895868)
		(end 267.346684 -125.862588)
		(width 0.14224)
		(layer "In2.Cu")
		(net "M_F_MA<14>")
	)
	(segment
		(start 270.121126 -142.67434)
		(end 269.927832 -142.867634)
		(width 0.14224)
		(layer "In2.Cu")
		(net "M_F_MA<14>")
	)
	(segment
		(start 269.880588 -129.940812)
		(end 269.880588 -130.536188)
		(width 0.14224)
		(layer "In2.Cu")
		(net "M_F_MA<14>")
	)
	(segment
		(start 270.349726 -154.955494)
		(end 270.349726 -155.614878)
		(width 0.14224)
		(layer "In2.Cu")
		(net "M_F_MA<14>")
	)
	(segment
		(start 269.971774 -131.145026)
		(end 269.89659 -131.22021)
		(width 0.14224)
		(layer "In2.Cu")
		(net "M_F_MA<14>")
	)
	(segment
		(start 267.417296 -126.948184)
		(end 267.69822 -126.948184)
		(width 0.14224)
		(layer "In2.Cu")
		(net "M_F_MA<14>")
	)
	(segment
		(start 269.935198 -140.115798)
		(end 269.938754 -140.119354)
		(width 0.14224)
		(layer "In2.Cu")
		(net "M_F_MA<14>")
	)
	(segment
		(start 270.806926 -154.498294)
		(end 270.349726 -154.955494)
		(width 0.14224)
		(layer "In2.Cu")
		(net "M_F_MA<14>")
	)
	(segment
		(start 270.54175 -142.508732)
		(end 270.376142 -142.67434)
		(width 0.14224)
		(layer "In2.Cu")
		(net "M_F_MA<14>")
	)
	(segment
		(start 270.54175 -142.022576)
		(end 270.54175 -142.508732)
		(width 0.14224)
		(layer "In2.Cu")
		(net "M_F_MA<14>")
	)
	(segment
		(start 263.435846 -96.396302)
		(end 263.43102 -96.404938)
		(width 0.0889)
		(layer "In2.Cu")
		(net "M_F_MA<14>")
	)
	(segment
		(start 267.346684 -126.150116)
		(end 267.130022 -126.366778)
		(width 0.14224)
		(layer "In2.Cu")
		(net "M_F_MA<14>")
	)
	(segment
		(start 264.0838 -102.544626)
		(end 264.379964 -102.84079)
		(width 0.0889)
		(layer "In2.Cu")
		(net "M_F_MA<14>")
	)
	(segment
		(start 269.938754 -141.656816)
		(end 270.143478 -141.86154)
		(width 0.14224)
		(layer "In2.Cu")
		(net "M_F_MA<14>")
	)
	(segment
		(start 267.130022 -126.66091)
		(end 267.417296 -126.948184)
		(width 0.14224)
		(layer "In2.Cu")
		(net "M_F_MA<14>")
	)
	(arc
		(start 263.43102 -98.976688)
		(mid 263.490122 -99.256502)
		(end 263.3726 -99.5172)
		(width 0.0889)
		(layer "In2.Cu")
		(net "M_F_MA<14>")
	)
	(arc
		(start 263.43102 -95.014288)
		(mid 263.48449 -95.209351)
		(end 263.435846 -95.405702)
		(width 0.0889)
		(layer "In2.Cu")
		(net "M_F_MA<14>")
	)
	(arc
		(start 263.42467 -95.425006)
		(mid 263.351872 -95.715769)
		(end 263.43102 -96.004888)
		(width 0.0889)
		(layer "In2.Cu")
		(net "M_F_MA<14>")
	)
	(arc
		(start 263.43102 -96.995488)
		(mid 263.48449 -97.190551)
		(end 263.435846 -97.386902)
		(width 0.0889)
		(layer "In2.Cu")
		(net "M_F_MA<14>")
	)
	(arc
		(start 263.43102 -94.423484)
		(mid 263.351889 -94.718886)
		(end 263.43102 -95.014288)
		(width 0.0889)
		(layer "In2.Cu")
		(net "M_F_MA<14>")
	)
	(arc
		(start 263.42467 -96.415606)
		(mid 263.351872 -96.706369)
		(end 263.43102 -96.995488)
		(width 0.0889)
		(layer "In2.Cu")
		(net "M_F_MA<14>")
	)
	(arc
		(start 263.42467 -97.406206)
		(mid 263.351872 -97.696969)
		(end 263.43102 -97.986088)
		(width 0.0889)
		(layer "In2.Cu")
		(net "M_F_MA<14>")
	)
	(arc
		(start 263.43102 -97.986088)
		(mid 263.48449 -98.181151)
		(end 263.435846 -98.377502)
		(width 0.0889)
		(layer "In2.Cu")
		(net "M_F_MA<14>")
	)
	(arc
		(start 263.42467 -98.396806)
		(mid 263.351872 -98.687569)
		(end 263.43102 -98.976688)
		(width 0.0889)
		(layer "In2.Cu")
		(net "M_F_MA<14>")
	)
	(arc
		(start 263.43102 -94.023688)
		(mid 263.484519 -94.223586)
		(end 263.43102 -94.423484)
		(width 0.0889)
		(layer "In2.Cu")
		(net "M_F_MA<14>")
	)
	(arc
		(start 263.43102 -96.004888)
		(mid 263.48449 -96.199951)
		(end 263.435846 -96.396302)
		(width 0.0889)
		(layer "In2.Cu")
		(net "M_F_MA<14>")
	)
	(segment
		(start 273.750278 -156.87294)
		(end 273.74977 -156.87294)
		(width 0.1651)
		(layer "F.Cu")
		(net "M_F_MA<13>")
	)
	(segment
		(start 260.50875 -90.756486)
		(end 261.08025 -90.756486)
		(width 0.1016)
		(layer "F.Cu")
		(net "M_F_MA<13>")
	)
	(segment
		(start 273.74977 -156.87294)
		(end 273.74977 -155.614878)
		(width 0.1651)
		(layer "F.Cu")
		(net "M_F_MA<13>")
	)
	(via
		(at 273.74977 -155.614878)
		(size 0.508)
		(drill 0.254)
		(layers "F.Cu" "B.Cu")
		(net "M_F_MA<13>")
	)
	(via
		(at 273.750278 -148.773388)
		(size 0.4572)
		(drill 0.2032)
		(layers "F.Cu" "B.Cu")
		(net "M_F_MA<13>")
	)
	(via
		(at 260.50875 -90.756486)
		(size 0.508)
		(drill 0.254)
		(layers "F.Cu" "B.Cu")
		(net "M_F_MA<13>")
	)
	(segment
		(start 273.750278 -148.773388)
		(end 273.74977 -148.77288)
		(width 0.1651)
		(layer "B.Cu")
		(net "M_F_MA<13>")
	)
	(segment
		(start 273.74977 -147.478496)
		(end 273.750278 -147.478496)
		(width 0.1651)
		(layer "B.Cu")
		(net "M_F_MA<13>")
	)
	(segment
		(start 273.74977 -148.77288)
		(end 273.74977 -147.478496)
		(width 0.1651)
		(layer "B.Cu")
		(net "M_F_MA<13>")
	)
	(segment
		(start 269.927832 -140.108432)
		(end 270.759682 -140.940282)
		(width 0.14224)
		(layer "In11.Cu")
		(net "M_F_MA<13>")
	)
	(segment
		(start 273.232372 -147.024344)
		(end 273.529806 -147.024344)
		(width 0.14224)
		(layer "In11.Cu")
		(net "M_F_MA<13>")
	)
	(segment
		(start 273.8882 -153.6192)
		(end 274.223226 -153.954226)
		(width 0.14224)
		(layer "In11.Cu")
		(net "M_F_MA<13>")
	)
	(segment
		(start 261.4168 -99.822)
		(end 261.8232 -99.822)
		(width 0.0889)
		(layer "In11.Cu")
		(net "M_F_MA<13>")
	)
	(segment
		(start 274.185888 -151.137112)
		(end 273.8882 -151.4348)
		(width 0.14224)
		(layer "In11.Cu")
		(net "M_F_MA<13>")
	)
	(segment
		(start 269.084298 -136.064498)
		(end 269.084298 -138.020298)
		(width 0.14224)
		(layer "In11.Cu")
		(net "M_F_MA<13>")
	)
	(segment
		(start 274.223226 -153.954226)
		(end 274.223226 -154.528774)
		(width 0.14224)
		(layer "In11.Cu")
		(net "M_F_MA<13>")
	)
	(segment
		(start 273.529806 -147.024344)
		(end 273.90344 -147.397978)
		(width 0.14224)
		(layer "In11.Cu")
		(net "M_F_MA<13>")
	)
	(segment
		(start 273.447764 -148.470874)
		(end 273.750278 -148.773388)
		(width 0.14224)
		(layer "In11.Cu")
		(net "M_F_MA<13>")
	)
	(segment
		(start 272.155412 -145.4785)
		(end 272.465292 -145.78838)
		(width 0.14224)
		(layer "In11.Cu")
		(net "M_F_MA<13>")
	)
	(segment
		(start 261.02056 -98.386138)
		(end 261.02691 -98.396806)
		(width 0.0889)
		(layer "In11.Cu")
		(net "M_F_MA<13>")
	)
	(segment
		(start 269.084552 -134.743952)
		(end 269.1384 -134.7978)
		(width 0.14224)
		(layer "In11.Cu")
		(net "M_F_MA<13>")
	)
	(segment
		(start 261.015734 -96.396302)
		(end 261.02056 -96.404938)
		(width 0.0889)
		(layer "In11.Cu")
		(net "M_F_MA<13>")
	)
	(segment
		(start 270.759682 -140.940282)
		(end 270.759682 -144.68348)
		(width 0.14224)
		(layer "In11.Cu")
		(net "M_F_MA<13>")
	)
	(segment
		(start 261.02056 -96.404938)
		(end 261.02691 -96.415606)
		(width 0.0889)
		(layer "In11.Cu")
		(net "M_F_MA<13>")
	)
	(segment
		(start 269.1384 -134.7978)
		(end 269.1384 -136.010396)
		(width 0.14224)
		(layer "In11.Cu")
		(net "M_F_MA<13>")
	)
	(segment
		(start 269.1638 -130.5306)
		(end 269.0114 -130.683)
		(width 0.14224)
		(layer "In11.Cu")
		(net "M_F_MA<13>")
	)
	(segment
		(start 269.084552 -131.213352)
		(end 269.084552 -134.743952)
		(width 0.14224)
		(layer "In11.Cu")
		(net "M_F_MA<13>")
	)
	(segment
		(start 273.750278 -150.026878)
		(end 274.185888 -150.462488)
		(width 0.14224)
		(layer "In11.Cu")
		(net "M_F_MA<13>")
	)
	(segment
		(start 261.286244 -99.691444)
		(end 261.4168 -99.822)
		(width 0.0889)
		(layer "In11.Cu")
		(net "M_F_MA<13>")
	)
	(segment
		(start 264.150348 -122.124978)
		(end 269.0114 -126.98603)
		(width 0.14224)
		(layer "In11.Cu")
		(net "M_F_MA<13>")
	)
	(segment
		(start 269.0114 -126.98603)
		(end 269.0114 -129.921)
		(width 0.14224)
		(layer "In11.Cu")
		(net "M_F_MA<13>")
	)
	(segment
		(start 274.223226 -154.528774)
		(end 273.74977 -155.00223)
		(width 0.14224)
		(layer "In11.Cu")
		(net "M_F_MA<13>")
	)
	(segment
		(start 264.150348 -103.927148)
		(end 264.150348 -122.124978)
		(width 0.14224)
		(layer "In11.Cu")
		(net "M_F_MA<13>")
	)
	(segment
		(start 273.447764 -148.15185)
		(end 273.447764 -148.470874)
		(width 0.14224)
		(layer "In11.Cu")
		(net "M_F_MA<13>")
	)
	(segment
		(start 261.153402 -99.599242)
		(end 261.286244 -99.691444)
		(width 0.0889)
		(layer "In11.Cu")
		(net "M_F_MA<13>")
	)
	(segment
		(start 273.74977 -155.00223)
		(end 273.74977 -155.614878)
		(width 0.14224)
		(layer "In11.Cu")
		(net "M_F_MA<13>")
	)
	(segment
		(start 272.465292 -146.315938)
		(end 271.988534 -146.792696)
		(width 0.14224)
		(layer "In11.Cu")
		(net "M_F_MA<13>")
	)
	(segment
		(start 273.8882 -151.4348)
		(end 273.8882 -153.6192)
		(width 0.14224)
		(layer "In11.Cu")
		(net "M_F_MA<13>")
	)
	(segment
		(start 269.1638 -130.0734)
		(end 269.1638 -130.5306)
		(width 0.14224)
		(layer "In11.Cu")
		(net "M_F_MA<13>")
	)
	(segment
		(start 261.8232 -99.822)
		(end 262.149336 -100.148136)
		(width 0.0889)
		(layer "In11.Cu")
		(net "M_F_MA<13>")
	)
	(segment
		(start 273.750278 -148.773388)
		(end 273.750278 -150.026878)
		(width 0.14224)
		(layer "In11.Cu")
		(net "M_F_MA<13>")
	)
	(segment
		(start 273.90344 -147.696174)
		(end 273.447764 -148.15185)
		(width 0.14224)
		(layer "In11.Cu")
		(net "M_F_MA<13>")
	)
	(segment
		(start 260.96849 -92.075762)
		(end 260.967474 -92.076778)
		(width 0.0889)
		(layer "In11.Cu")
		(net "M_F_MA<13>")
	)
	(segment
		(start 272.396458 -147.51558)
		(end 272.741136 -147.51558)
		(width 0.14224)
		(layer "In11.Cu")
		(net "M_F_MA<13>")
	)
	(segment
		(start 272.465292 -145.78838)
		(end 272.465292 -146.315938)
		(width 0.14224)
		(layer "In11.Cu")
		(net "M_F_MA<13>")
	)
	(segment
		(start 271.554702 -145.4785)
		(end 272.155412 -145.4785)
		(width 0.14224)
		(layer "In11.Cu")
		(net "M_F_MA<13>")
	)
	(segment
		(start 269.084298 -138.020298)
		(end 269.927832 -138.863832)
		(width 0.14224)
		(layer "In11.Cu")
		(net "M_F_MA<13>")
	)
	(segment
		(start 272.741136 -147.51558)
		(end 273.232372 -147.024344)
		(width 0.14224)
		(layer "In11.Cu")
		(net "M_F_MA<13>")
	)
	(segment
		(start 273.90344 -147.397978)
		(end 273.90344 -147.696174)
		(width 0.14224)
		(layer "In11.Cu")
		(net "M_F_MA<13>")
	)
	(segment
		(start 262.149336 -100.148136)
		(end 263.0932 -101.092)
		(width 0.14224)
		(layer "In11.Cu")
		(net "M_F_MA<13>")
	)
	(segment
		(start 274.185888 -150.462488)
		(end 274.185888 -151.137112)
		(width 0.14224)
		(layer "In11.Cu")
		(net "M_F_MA<13>")
	)
	(segment
		(start 261.015734 -99.368102)
		(end 261.02056 -99.376738)
		(width 0.0889)
		(layer "In11.Cu")
		(net "M_F_MA<13>")
	)
	(segment
		(start 269.0114 -129.921)
		(end 269.1638 -130.0734)
		(width 0.14224)
		(layer "In11.Cu")
		(net "M_F_MA<13>")
	)
	(segment
		(start 260.967474 -92.076778)
		(end 260.967474 -96.206564)
		(width 0.0889)
		(layer "In11.Cu")
		(net "M_F_MA<13>")
	)
	(segment
		(start 261.015734 -98.377502)
		(end 261.02056 -98.386138)
		(width 0.0889)
		(layer "In11.Cu")
		(net "M_F_MA<13>")
	)
	(segment
		(start 263.0932 -102.87)
		(end 264.150348 -103.927148)
		(width 0.14224)
		(layer "In11.Cu")
		(net "M_F_MA<13>")
	)
	(segment
		(start 269.1384 -136.010396)
		(end 269.084298 -136.064498)
		(width 0.14224)
		(layer "In11.Cu")
		(net "M_F_MA<13>")
	)
	(segment
		(start 260.50875 -90.756486)
		(end 260.96849 -91.538806)
		(width 0.0889)
		(layer "In11.Cu")
		(net "M_F_MA<13>")
	)
	(segment
		(start 269.0114 -131.1402)
		(end 269.084552 -131.213352)
		(width 0.14224)
		(layer "In11.Cu")
		(net "M_F_MA<13>")
	)
	(segment
		(start 261.02056 -97.395538)
		(end 261.02691 -97.406206)
		(width 0.0889)
		(layer "In11.Cu")
		(net "M_F_MA<13>")
	)
	(segment
		(start 271.988534 -147.107656)
		(end 272.396458 -147.51558)
		(width 0.14224)
		(layer "In11.Cu")
		(net "M_F_MA<13>")
	)
	(segment
		(start 263.0932 -101.092)
		(end 263.0932 -102.87)
		(width 0.14224)
		(layer "In11.Cu")
		(net "M_F_MA<13>")
	)
	(segment
		(start 270.759682 -144.68348)
		(end 271.554702 -145.4785)
		(width 0.14224)
		(layer "In11.Cu")
		(net "M_F_MA<13>")
	)
	(segment
		(start 261.015734 -97.386902)
		(end 261.02056 -97.395538)
		(width 0.0889)
		(layer "In11.Cu")
		(net "M_F_MA<13>")
	)
	(segment
		(start 269.927832 -138.863832)
		(end 269.927832 -140.108432)
		(width 0.14224)
		(layer "In11.Cu")
		(net "M_F_MA<13>")
	)
	(segment
		(start 269.0114 -130.683)
		(end 269.0114 -131.1402)
		(width 0.14224)
		(layer "In11.Cu")
		(net "M_F_MA<13>")
	)
	(segment
		(start 260.96849 -91.538806)
		(end 260.96849 -92.075762)
		(width 0.0889)
		(layer "In11.Cu")
		(net "M_F_MA<13>")
	)
	(segment
		(start 261.02056 -99.376738)
		(end 261.153402 -99.599242)
		(width 0.0889)
		(layer "In11.Cu")
		(net "M_F_MA<13>")
	)
	(segment
		(start 271.988534 -146.792696)
		(end 271.988534 -147.107656)
		(width 0.14224)
		(layer "In11.Cu")
		(net "M_F_MA<13>")
	)
	(arc
		(start 260.967474 -96.206564)
		(mid 260.979738 -96.304448)
		(end 261.015734 -96.396302)
		(width 0.0889)
		(layer "In11.Cu")
		(net "M_F_MA<13>")
	)
	(arc
		(start 261.02691 -96.415606)
		(mid 261.099708 -96.706369)
		(end 261.02056 -96.995488)
		(width 0.0889)
		(layer "In11.Cu")
		(net "M_F_MA<13>")
	)
	(arc
		(start 261.02056 -96.995488)
		(mid 260.96709 -97.190551)
		(end 261.015734 -97.386902)
		(width 0.0889)
		(layer "In11.Cu")
		(net "M_F_MA<13>")
	)
	(arc
		(start 261.02056 -98.976688)
		(mid 260.96709 -99.171751)
		(end 261.015734 -99.368102)
		(width 0.0889)
		(layer "In11.Cu")
		(net "M_F_MA<13>")
	)
	(arc
		(start 261.02056 -97.986088)
		(mid 260.96709 -98.181151)
		(end 261.015734 -98.377502)
		(width 0.0889)
		(layer "In11.Cu")
		(net "M_F_MA<13>")
	)
	(arc
		(start 261.02691 -97.406206)
		(mid 261.099708 -97.696969)
		(end 261.02056 -97.986088)
		(width 0.0889)
		(layer "In11.Cu")
		(net "M_F_MA<13>")
	)
	(arc
		(start 261.02691 -98.396806)
		(mid 261.099708 -98.687569)
		(end 261.02056 -98.976688)
		(width 0.0889)
		(layer "In11.Cu")
		(net "M_F_MA<13>")
	)
	(segment
		(start 249.099832 -152.278842)
		(end 249.099832 -153.571956)
		(width 0.1651)
		(layer "F.Cu")
		(net "M_F_MA<12>")
	)
	(segment
		(start 249.10034 -152.273)
		(end 249.099832 -152.278842)
		(width 0.1651)
		(layer "F.Cu")
		(net "M_F_MA<12>")
	)
	(segment
		(start 255.07061 -92.24264)
		(end 254.49911 -92.24264)
		(width 0.1016)
		(layer "F.Cu")
		(net "M_F_MA<12>")
	)
	(via
		(at 249.099832 -153.571956)
		(size 0.508)
		(drill 0.254)
		(layers "F.Cu" "B.Cu")
		(net "M_F_MA<12>")
	)
	(via
		(at 254.49911 -92.24264)
		(size 0.508)
		(drill 0.254)
		(layers "F.Cu" "B.Cu")
		(net "M_F_MA<12>")
	)
	(via
		(at 249.099832 -150.788878)
		(size 0.4572)
		(drill 0.2032)
		(layers "F.Cu" "B.Cu")
		(net "M_F_MA<12>")
	)
	(segment
		(start 249.099832 -152.078182)
		(end 249.099832 -150.788878)
		(width 0.1651)
		(layer "B.Cu")
		(net "M_F_MA<12>")
	)
	(segment
		(start 249.10034 -152.078436)
		(end 249.099832 -152.078182)
		(width 0.1651)
		(layer "B.Cu")
		(net "M_F_MA<12>")
	)
	(segment
		(start 256.56286 -95.414338)
		(end 256.567686 -95.405702)
		(width 0.0889)
		(layer "In11.Cu")
		(net "M_F_MA<12>")
	)
	(segment
		(start 254.616204 -144.343882)
		(end 254.616204 -143.753586)
		(width 0.14224)
		(layer "In11.Cu")
		(net "M_F_MA<12>")
	)
	(segment
		(start 248.96064 -151.953214)
		(end 249.099832 -151.814022)
		(width 0.14224)
		(layer "In11.Cu")
		(net "M_F_MA<12>")
	)
	(segment
		(start 256.68605 -101.65715)
		(end 256.371344 -101.342444)
		(width 0.0889)
		(layer "In11.Cu")
		(net "M_F_MA<12>")
	)
	(segment
		(start 250.663202 -147.856956)
		(end 250.663202 -147.5105)
		(width 0.14224)
		(layer "In11.Cu")
		(net "M_F_MA<12>")
	)
	(segment
		(start 254.51181 -143.086836)
		(end 254.51181 -142.867888)
		(width 0.14224)
		(layer "In11.Cu")
		(net "M_F_MA<12>")
	)
	(segment
		(start 251.77242 -149.284944)
		(end 252.089666 -148.967698)
		(width 0.14224)
		(layer "In11.Cu")
		(net "M_F_MA<12>")
	)
	(segment
		(start 249.099832 -149.714712)
		(end 249.5296 -149.284944)
		(width 0.14224)
		(layer "In11.Cu")
		(net "M_F_MA<12>")
	)
	(segment
		(start 251.780548 -148.066506)
		(end 250.872752 -148.066506)
		(width 0.14224)
		(layer "In11.Cu")
		(net "M_F_MA<12>")
	)
	(segment
		(start 252.089666 -148.967698)
		(end 252.089666 -148.375624)
		(width 0.14224)
		(layer "In11.Cu")
		(net "M_F_MA<12>")
	)
	(segment
		(start 256.55651 -96.415606)
		(end 256.56286 -96.404938)
		(width 0.0889)
		(layer "In11.Cu")
		(net "M_F_MA<12>")
	)
	(segment
		(start 253.372112 -145.2372)
		(end 253.722886 -145.2372)
		(width 0.14224)
		(layer "In11.Cu")
		(net "M_F_MA<12>")
	)
	(segment
		(start 257.647948 -127.290576)
		(end 257.647948 -102.619048)
		(width 0.14224)
		(layer "In11.Cu")
		(net "M_F_MA<12>")
	)
	(segment
		(start 248.22658 -152.644094)
		(end 248.22658 -152.120854)
		(width 0.14224)
		(layer "In11.Cu")
		(net "M_F_MA<12>")
	)
	(segment
		(start 256.56286 -97.395538)
		(end 256.567686 -97.386902)
		(width 0.0889)
		(layer "In11.Cu")
		(net "M_F_MA<12>")
	)
	(segment
		(start 255.545844 -129.39268)
		(end 257.647948 -127.290576)
		(width 0.14224)
		(layer "In11.Cu")
		(net "M_F_MA<12>")
	)
	(segment
		(start 255.368806 -93.32849)
		(end 255.344676 -93.32849)
		(width 0.0889)
		(layer "In11.Cu")
		(net "M_F_MA<12>")
	)
	(segment
		(start 255.256792 -142.89405)
		(end 255.47574 -142.89405)
		(width 0.14224)
		(layer "In11.Cu")
		(net "M_F_MA<12>")
	)
	(segment
		(start 254.84582 -93.033088)
		(end 254.829056 -93.004386)
		(width 0.0889)
		(layer "In11.Cu")
		(net "M_F_MA<12>")
	)
	(segment
		(start 254.829056 -93.004386)
		(end 254.49911 -92.24264)
		(width 0.0889)
		(layer "In11.Cu")
		(net "M_F_MA<12>")
	)
	(segment
		(start 256.234184 -93.82379)
		(end 256.19456 -93.82379)
		(width 0.0889)
		(layer "In11.Cu")
		(net "M_F_MA<12>")
	)
	(segment
		(start 256.413 -134.112)
		(end 256.1082 -133.8072)
		(width 0.14224)
		(layer "In11.Cu")
		(net "M_F_MA<12>")
	)
	(segment
		(start 254.980694 -142.617952)
		(end 255.256792 -142.89405)
		(width 0.14224)
		(layer "In11.Cu")
		(net "M_F_MA<12>")
	)
	(segment
		(start 256.44094 -98.60407)
		(end 256.567686 -98.377502)
		(width 0.0889)
		(layer "In11.Cu")
		(net "M_F_MA<12>")
	)
	(segment
		(start 253.722886 -145.2372)
		(end 254.616204 -144.343882)
		(width 0.14224)
		(layer "In11.Cu")
		(net "M_F_MA<12>")
	)
	(segment
		(start 254.787908 -143.362934)
		(end 254.51181 -143.086836)
		(width 0.14224)
		(layer "In11.Cu")
		(net "M_F_MA<12>")
	)
	(segment
		(start 250.919996 -147.253706)
		(end 252.027436 -147.253706)
		(width 0.14224)
		(layer "In11.Cu")
		(net "M_F_MA<12>")
	)
	(segment
		(start 256.1082 -132.833872)
		(end 255.545844 -132.271516)
		(width 0.14224)
		(layer "In11.Cu")
		(net "M_F_MA<12>")
	)
	(segment
		(start 252.089666 -148.375624)
		(end 251.780548 -148.066506)
		(width 0.14224)
		(layer "In11.Cu")
		(net "M_F_MA<12>")
	)
	(segment
		(start 257.331464 -135.160766)
		(end 257.0734 -134.902702)
		(width 0.14224)
		(layer "In11.Cu")
		(net "M_F_MA<12>")
	)
	(segment
		(start 254.51181 -142.867888)
		(end 254.761746 -142.617952)
		(width 0.14224)
		(layer "In11.Cu")
		(net "M_F_MA<12>")
	)
	(segment
		(start 257.0734 -134.902702)
		(end 256.6162 -134.902702)
		(width 0.14224)
		(layer "In11.Cu")
		(net "M_F_MA<12>")
	)
	(segment
		(start 256.371344 -98.80981)
		(end 256.368804 -98.80727)
		(width 0.0889)
		(layer "In11.Cu")
		(net "M_F_MA<12>")
	)
	(segment
		(start 249.099832 -153.571956)
		(end 249.099832 -153.053288)
		(width 0.14224)
		(layer "In11.Cu")
		(net "M_F_MA<12>")
	)
	(segment
		(start 249.099832 -153.053288)
		(end 248.890028 -152.843484)
		(width 0.14224)
		(layer "In11.Cu")
		(net "M_F_MA<12>")
	)
	(segment
		(start 252.918214 -146.362928)
		(end 252.918214 -145.691098)
		(width 0.14224)
		(layer "In11.Cu")
		(net "M_F_MA<12>")
	)
	(segment
		(start 252.027436 -147.253706)
		(end 252.918214 -146.362928)
		(width 0.14224)
		(layer "In11.Cu")
		(net "M_F_MA<12>")
	)
	(segment
		(start 257.125216 -135.768334)
		(end 257.331464 -135.562086)
		(width 0.14224)
		(layer "In11.Cu")
		(net "M_F_MA<12>")
	)
	(segment
		(start 256.795016 -135.768334)
		(end 257.125216 -135.768334)
		(width 0.14224)
		(layer "In11.Cu")
		(net "M_F_MA<12>")
	)
	(segment
		(start 250.872752 -148.066506)
		(end 250.663202 -147.856956)
		(width 0.14224)
		(layer "In11.Cu")
		(net "M_F_MA<12>")
	)
	(segment
		(start 256.413 -134.699502)
		(end 256.413 -134.112)
		(width 0.14224)
		(layer "In11.Cu")
		(net "M_F_MA<12>")
	)
	(segment
		(start 256.342642 -142.027148)
		(end 256.342642 -136.220708)
		(width 0.14224)
		(layer "In11.Cu")
		(net "M_F_MA<12>")
	)
	(segment
		(start 249.099832 -150.788878)
		(end 249.099832 -149.714712)
		(width 0.14224)
		(layer "In11.Cu")
		(net "M_F_MA<12>")
	)
	(segment
		(start 256.6162 -134.902702)
		(end 256.413 -134.699502)
		(width 0.14224)
		(layer "In11.Cu")
		(net "M_F_MA<12>")
	)
	(segment
		(start 256.56286 -96.404938)
		(end 256.567686 -96.396302)
		(width 0.0889)
		(layer "In11.Cu")
		(net "M_F_MA<12>")
	)
	(segment
		(start 249.5296 -149.284944)
		(end 251.77242 -149.284944)
		(width 0.14224)
		(layer "In11.Cu")
		(net "M_F_MA<12>")
	)
	(segment
		(start 250.663202 -147.5105)
		(end 250.919996 -147.253706)
		(width 0.14224)
		(layer "In11.Cu")
		(net "M_F_MA<12>")
	)
	(segment
		(start 248.39422 -151.953214)
		(end 248.96064 -151.953214)
		(width 0.14224)
		(layer "In11.Cu")
		(net "M_F_MA<12>")
	)
	(segment
		(start 248.22658 -152.120854)
		(end 248.39422 -151.953214)
		(width 0.14224)
		(layer "In11.Cu")
		(net "M_F_MA<12>")
	)
	(segment
		(start 257.331464 -135.562086)
		(end 257.331464 -135.160766)
		(width 0.14224)
		(layer "In11.Cu")
		(net "M_F_MA<12>")
	)
	(segment
		(start 255.545844 -132.271516)
		(end 255.545844 -129.39268)
		(width 0.14224)
		(layer "In11.Cu")
		(net "M_F_MA<12>")
	)
	(segment
		(start 256.1082 -133.8072)
		(end 256.1082 -132.833872)
		(width 0.14224)
		(layer "In11.Cu")
		(net "M_F_MA<12>")
	)
	(segment
		(start 249.099832 -151.814022)
		(end 249.099832 -150.788878)
		(width 0.14224)
		(layer "In11.Cu")
		(net "M_F_MA<12>")
	)
	(segment
		(start 254.761746 -142.617952)
		(end 254.980694 -142.617952)
		(width 0.14224)
		(layer "In11.Cu")
		(net "M_F_MA<12>")
	)
	(segment
		(start 254.616204 -143.753586)
		(end 254.787908 -143.581882)
		(width 0.14224)
		(layer "In11.Cu")
		(net "M_F_MA<12>")
	)
	(segment
		(start 256.342642 -136.220708)
		(end 256.795016 -135.768334)
		(width 0.14224)
		(layer "In11.Cu")
		(net "M_F_MA<12>")
	)
	(segment
		(start 256.55651 -97.406206)
		(end 256.56286 -97.395538)
		(width 0.0889)
		(layer "In11.Cu")
		(net "M_F_MA<12>")
	)
	(segment
		(start 256.55651 -95.425006)
		(end 256.56286 -95.414338)
		(width 0.0889)
		(layer "In11.Cu")
		(net "M_F_MA<12>")
	)
	(segment
		(start 255.47574 -142.89405)
		(end 256.342642 -142.027148)
		(width 0.14224)
		(layer "In11.Cu")
		(net "M_F_MA<12>")
	)
	(segment
		(start 254.787908 -143.581882)
		(end 254.787908 -143.362934)
		(width 0.14224)
		(layer "In11.Cu")
		(net "M_F_MA<12>")
	)
	(segment
		(start 252.918214 -145.691098)
		(end 253.372112 -145.2372)
		(width 0.14224)
		(layer "In11.Cu")
		(net "M_F_MA<12>")
	)
	(segment
		(start 256.371344 -101.342444)
		(end 256.371344 -98.80981)
		(width 0.0889)
		(layer "In11.Cu")
		(net "M_F_MA<12>")
	)
	(segment
		(start 257.647948 -102.619048)
		(end 256.68605 -101.65715)
		(width 0.14224)
		(layer "In11.Cu")
		(net "M_F_MA<12>")
	)
	(segment
		(start 248.890028 -152.843484)
		(end 248.42597 -152.843484)
		(width 0.14224)
		(layer "In11.Cu")
		(net "M_F_MA<12>")
	)
	(segment
		(start 248.42597 -152.843484)
		(end 248.22658 -152.644094)
		(width 0.14224)
		(layer "In11.Cu")
		(net "M_F_MA<12>")
	)
	(arc
		(start 256.56286 -97.986088)
		(mid 256.483638 -97.69697)
		(end 256.55651 -97.406206)
		(width 0.0889)
		(layer "In11.Cu")
		(net "M_F_MA<12>")
	)
	(arc
		(start 256.56286 -94.423484)
		(mid 256.567105 -94.031239)
		(end 256.234184 -93.82379)
		(width 0.0889)
		(layer "In11.Cu")
		(net "M_F_MA<12>")
	)
	(arc
		(start 256.567686 -98.377502)
		(mid 256.616441 -98.18115)
		(end 256.56286 -97.986088)
		(width 0.0889)
		(layer "In11.Cu")
		(net "M_F_MA<12>")
	)
	(arc
		(start 255.344676 -93.32849)
		(mid 255.056531 -93.246171)
		(end 254.84582 -93.033088)
		(width 0.0889)
		(layer "In11.Cu")
		(net "M_F_MA<12>")
	)
	(arc
		(start 256.56286 -96.995488)
		(mid 256.483638 -96.70637)
		(end 256.55651 -96.415606)
		(width 0.0889)
		(layer "In11.Cu")
		(net "M_F_MA<12>")
	)
	(arc
		(start 256.368804 -98.80727)
		(mid 256.396261 -98.702613)
		(end 256.44094 -98.60407)
		(width 0.0889)
		(layer "In11.Cu")
		(net "M_F_MA<12>")
	)
	(arc
		(start 256.567686 -96.396302)
		(mid 256.616441 -96.19995)
		(end 256.56286 -96.004888)
		(width 0.0889)
		(layer "In11.Cu")
		(net "M_F_MA<12>")
	)
	(arc
		(start 256.567686 -95.405702)
		(mid 256.616441 -95.20935)
		(end 256.56286 -95.014288)
		(width 0.0889)
		(layer "In11.Cu")
		(net "M_F_MA<12>")
	)
	(arc
		(start 255.70434 -93.528642)
		(mid 255.562657 -93.384838)
		(end 255.368806 -93.32849)
		(width 0.0889)
		(layer "In11.Cu")
		(net "M_F_MA<12>")
	)
	(arc
		(start 256.56286 -95.014288)
		(mid 256.483729 -94.718886)
		(end 256.56286 -94.423484)
		(width 0.0889)
		(layer "In11.Cu")
		(net "M_F_MA<12>")
	)
	(arc
		(start 256.19456 -93.82379)
		(mid 255.911343 -93.739509)
		(end 255.70434 -93.528642)
		(width 0.0889)
		(layer "In11.Cu")
		(net "M_F_MA<12>")
	)
	(arc
		(start 256.567686 -97.386902)
		(mid 256.616441 -97.19055)
		(end 256.56286 -96.995488)
		(width 0.0889)
		(layer "In11.Cu")
		(net "M_F_MA<12>")
	)
	(arc
		(start 256.56286 -96.004888)
		(mid 256.483638 -95.71577)
		(end 256.55651 -95.425006)
		(width 0.0889)
		(layer "In11.Cu")
		(net "M_F_MA<12>")
	)
	(segment
		(start 249.94997 -156.87294)
		(end 249.950478 -156.87294)
		(width 0.1651)
		(layer "F.Cu")
		(net "M_F_MA<11>")
	)
	(segment
		(start 249.94997 -155.564078)
		(end 249.94997 -156.87294)
		(width 0.1651)
		(layer "F.Cu")
		(net "M_F_MA<11>")
	)
	(segment
		(start 255.07061 -89.27084)
		(end 254.49911 -89.27084)
		(width 0.1016)
		(layer "F.Cu")
		(net "M_F_MA<11>")
	)
	(via
		(at 249.94997 -155.564078)
		(size 0.508)
		(drill 0.254)
		(layers "F.Cu" "B.Cu")
		(net "M_F_MA<11>")
	)
	(via
		(at 254.49911 -89.27084)
		(size 0.508)
		(drill 0.254)
		(layers "F.Cu" "B.Cu")
		(net "M_F_MA<11>")
	)
	(via
		(at 249.949716 -148.771356)
		(size 0.4572)
		(drill 0.2032)
		(layers "F.Cu" "B.Cu")
		(net "M_F_MA<11>")
	)
	(segment
		(start 249.94997 -148.771102)
		(end 249.949716 -148.771356)
		(width 0.1651)
		(layer "B.Cu")
		(net "M_F_MA<11>")
	)
	(segment
		(start 249.94997 -147.478496)
		(end 249.94997 -148.771102)
		(width 0.1651)
		(layer "B.Cu")
		(net "M_F_MA<11>")
	)
	(segment
		(start 249.950478 -147.478496)
		(end 249.94997 -147.478496)
		(width 0.1651)
		(layer "B.Cu")
		(net "M_F_MA<11>")
	)
	(segment
		(start 250.317 -129.375916)
		(end 250.6218 -129.071116)
		(width 0.14224)
		(layer "In2.Cu")
		(net "M_F_MA<11>")
	)
	(segment
		(start 250.5202 -131.3688)
		(end 250.2916 -131.1402)
		(width 0.14224)
		(layer "In2.Cu")
		(net "M_F_MA<11>")
	)
	(segment
		(start 254.349504 -98.60026)
		(end 254.277876 -98.528632)
		(width 0.0889)
		(layer "In2.Cu")
		(net "M_F_MA<11>")
	)
	(segment
		(start 254.6096 -101.346254)
		(end 254.349504 -101.086158)
		(width 0.0889)
		(layer "In2.Cu")
		(net "M_F_MA<11>")
	)
	(segment
		(start 254.161544 -97.410778)
		(end 254.152654 -97.395538)
		(width 0.0889)
		(layer "In2.Cu")
		(net "M_F_MA<11>")
	)
	(segment
		(start 249.949716 -148.771356)
		(end 249.949716 -146.696684)
		(width 0.14224)
		(layer "In2.Cu")
		(net "M_F_MA<11>")
	)
	(segment
		(start 254.159004 -94.434152)
		(end 254.152654 -94.423484)
		(width 0.0889)
		(layer "In2.Cu")
		(net "M_F_MA<11>")
	)
	(segment
		(start 250.4186 -130.5306)
		(end 250.4186 -129.921)
		(width 0.14224)
		(layer "In2.Cu")
		(net "M_F_MA<11>")
	)
	(segment
		(start 250.361704 -140.4112)
		(end 250.4694 -140.303504)
		(width 0.14224)
		(layer "In2.Cu")
		(net "M_F_MA<11>")
	)
	(segment
		(start 254.161544 -92.457778)
		(end 254.152654 -92.442538)
		(width 0.0889)
		(layer "In2.Cu")
		(net "M_F_MA<11>")
	)
	(segment
		(start 250.6218 -127.388112)
		(end 254.3556 -123.654312)
		(width 0.14224)
		(layer "In2.Cu")
		(net "M_F_MA<11>")
	)
	(segment
		(start 250.38431 -145.385282)
		(end 250.4694 -145.300192)
		(width 0.14224)
		(layer "In2.Cu")
		(net "M_F_MA<11>")
	)
	(segment
		(start 250.4694 -144.4244)
		(end 250.361704 -144.316704)
		(width 0.14224)
		(layer "In2.Cu")
		(net "M_F_MA<11>")
	)
	(segment
		(start 254.6096 -102.5144)
		(end 254.6096 -101.346254)
		(width 0.0889)
		(layer "In2.Cu")
		(net "M_F_MA<11>")
	)
	(segment
		(start 250.4694 -140.303504)
		(end 250.4694 -139.6238)
		(width 0.14224)
		(layer "In2.Cu")
		(net "M_F_MA<11>")
	)
	(segment
		(start 250.4694 -145.300192)
		(end 250.4694 -144.4244)
		(width 0.14224)
		(layer "In2.Cu")
		(net "M_F_MA<11>")
	)
	(segment
		(start 254.09906 -92.247466)
		(end 254.09906 -89.97823)
		(width 0.0889)
		(layer "In2.Cu")
		(net "M_F_MA<11>")
	)
	(segment
		(start 254.3556 -103.1494)
		(end 254.3556 -102.7684)
		(width 0.0889)
		(layer "In2.Cu")
		(net "M_F_MA<11>")
	)
	(segment
		(start 250.365768 -133.453632)
		(end 250.5202 -133.2992)
		(width 0.14224)
		(layer "In2.Cu")
		(net "M_F_MA<11>")
	)
	(segment
		(start 249.4788 -154.559)
		(end 249.94997 -155.03017)
		(width 0.14224)
		(layer "In2.Cu")
		(net "M_F_MA<11>")
	)
	(segment
		(start 250.5202 -133.2992)
		(end 250.5202 -131.3688)
		(width 0.14224)
		(layer "In2.Cu")
		(net "M_F_MA<11>")
	)
	(segment
		(start 250.6218 -129.071116)
		(end 250.6218 -127.388112)
		(width 0.14224)
		(layer "In2.Cu")
		(net "M_F_MA<11>")
	)
	(segment
		(start 254.3556 -123.654312)
		(end 254.3556 -103.1494)
		(width 0.14224)
		(layer "In2.Cu")
		(net "M_F_MA<11>")
	)
	(segment
		(start 249.949716 -148.771356)
		(end 249.40641 -149.314662)
		(width 0.14224)
		(layer "In2.Cu")
		(net "M_F_MA<11>")
	)
	(segment
		(start 249.6058 -152.3238)
		(end 249.6058 -153.8224)
		(width 0.14224)
		(layer "In2.Cu")
		(net "M_F_MA<11>")
	)
	(segment
		(start 254.349504 -101.086158)
		(end 254.349504 -98.60026)
		(width 0.0889)
		(layer "In2.Cu")
		(net "M_F_MA<11>")
	)
	(segment
		(start 254.3556 -102.7684)
		(end 254.6096 -102.5144)
		(width 0.0889)
		(layer "In2.Cu")
		(net "M_F_MA<11>")
	)
	(segment
		(start 249.4788 -153.9494)
		(end 249.4788 -154.559)
		(width 0.14224)
		(layer "In2.Cu")
		(net "M_F_MA<11>")
	)
	(segment
		(start 249.40641 -150.307294)
		(end 249.510804 -150.411688)
		(width 0.14224)
		(layer "In2.Cu")
		(net "M_F_MA<11>")
	)
	(segment
		(start 249.94997 -155.03017)
		(end 249.94997 -155.564078)
		(width 0.14224)
		(layer "In2.Cu")
		(net "M_F_MA<11>")
	)
	(segment
		(start 250.2916 -131.1402)
		(end 250.2916 -130.6576)
		(width 0.14224)
		(layer "In2.Cu")
		(net "M_F_MA<11>")
	)
	(segment
		(start 249.510804 -150.411688)
		(end 249.510804 -152.228804)
		(width 0.14224)
		(layer "In2.Cu")
		(net "M_F_MA<11>")
	)
	(segment
		(start 249.949716 -146.696684)
		(end 250.38431 -146.26209)
		(width 0.14224)
		(layer "In2.Cu")
		(net "M_F_MA<11>")
	)
	(segment
		(start 250.365768 -139.520168)
		(end 250.365768 -133.453632)
		(width 0.14224)
		(layer "In2.Cu")
		(net "M_F_MA<11>")
	)
	(segment
		(start 254.161544 -96.420178)
		(end 254.152654 -96.404938)
		(width 0.0889)
		(layer "In2.Cu")
		(net "M_F_MA<11>")
	)
	(segment
		(start 250.317 -129.8194)
		(end 250.317 -129.375916)
		(width 0.14224)
		(layer "In2.Cu")
		(net "M_F_MA<11>")
	)
	(segment
		(start 254.161544 -95.429578)
		(end 254.152654 -95.414338)
		(width 0.0889)
		(layer "In2.Cu")
		(net "M_F_MA<11>")
	)
	(segment
		(start 254.09906 -89.97823)
		(end 254.49911 -89.27084)
		(width 0.0889)
		(layer "In2.Cu")
		(net "M_F_MA<11>")
	)
	(segment
		(start 250.2916 -130.6576)
		(end 250.4186 -130.5306)
		(width 0.14224)
		(layer "In2.Cu")
		(net "M_F_MA<11>")
	)
	(segment
		(start 254.152654 -94.023688)
		(end 254.159004 -94.01302)
		(width 0.0889)
		(layer "In2.Cu")
		(net "M_F_MA<11>")
	)
	(segment
		(start 250.38431 -146.26209)
		(end 250.38431 -145.385282)
		(width 0.14224)
		(layer "In2.Cu")
		(net "M_F_MA<11>")
	)
	(segment
		(start 249.510804 -152.228804)
		(end 249.6058 -152.3238)
		(width 0.14224)
		(layer "In2.Cu")
		(net "M_F_MA<11>")
	)
	(segment
		(start 250.361704 -144.316704)
		(end 250.361704 -140.4112)
		(width 0.14224)
		(layer "In2.Cu")
		(net "M_F_MA<11>")
	)
	(segment
		(start 250.4694 -139.6238)
		(end 250.365768 -139.520168)
		(width 0.14224)
		(layer "In2.Cu")
		(net "M_F_MA<11>")
	)
	(segment
		(start 249.6058 -153.8224)
		(end 249.4788 -153.9494)
		(width 0.14224)
		(layer "In2.Cu")
		(net "M_F_MA<11>")
	)
	(segment
		(start 249.40641 -149.314662)
		(end 249.40641 -150.307294)
		(width 0.14224)
		(layer "In2.Cu")
		(net "M_F_MA<11>")
	)
	(segment
		(start 250.4186 -129.921)
		(end 250.317 -129.8194)
		(width 0.14224)
		(layer "In2.Cu")
		(net "M_F_MA<11>")
	)
	(arc
		(start 254.152654 -95.014542)
		(mid 254.232003 -94.72517)
		(end 254.159004 -94.434152)
		(width 0.0889)
		(layer "In2.Cu")
		(net "M_F_MA<11>")
	)
	(arc
		(start 254.152654 -98.386138)
		(mid 254.099121 -98.18624)
		(end 254.152654 -97.986342)
		(width 0.0889)
		(layer "In2.Cu")
		(net "M_F_MA<11>")
	)
	(arc
		(start 254.152654 -96.404938)
		(mid 254.099121 -96.20504)
		(end 254.152654 -96.005142)
		(width 0.0889)
		(layer "In2.Cu")
		(net "M_F_MA<11>")
	)
	(arc
		(start 254.152654 -95.414338)
		(mid 254.099121 -95.21444)
		(end 254.152654 -95.014542)
		(width 0.0889)
		(layer "In2.Cu")
		(net "M_F_MA<11>")
	)
	(arc
		(start 254.152654 -94.423484)
		(mid 254.099121 -94.223586)
		(end 254.152654 -94.023688)
		(width 0.0889)
		(layer "In2.Cu")
		(net "M_F_MA<11>")
	)
	(arc
		(start 254.277876 -98.528632)
		(mid 254.208215 -98.463579)
		(end 254.152654 -98.386138)
		(width 0.0889)
		(layer "In2.Cu")
		(net "M_F_MA<11>")
	)
	(arc
		(start 254.152654 -92.442538)
		(mid 254.113308 -92.348448)
		(end 254.09906 -92.247466)
		(width 0.0889)
		(layer "In2.Cu")
		(net "M_F_MA<11>")
	)
	(arc
		(start 254.152654 -93.433138)
		(mid 254.099121 -93.23324)
		(end 254.152654 -93.033342)
		(width 0.0889)
		(layer "In2.Cu")
		(net "M_F_MA<11>")
	)
	(arc
		(start 254.152654 -97.395538)
		(mid 254.099121 -97.19564)
		(end 254.152654 -96.995742)
		(width 0.0889)
		(layer "In2.Cu")
		(net "M_F_MA<11>")
	)
	(arc
		(start 254.152654 -96.005142)
		(mid 254.231843 -95.718527)
		(end 254.161544 -95.429578)
		(width 0.0889)
		(layer "In2.Cu")
		(net "M_F_MA<11>")
	)
	(arc
		(start 254.152654 -97.986342)
		(mid 254.231843 -97.699727)
		(end 254.161544 -97.410778)
		(width 0.0889)
		(layer "In2.Cu")
		(net "M_F_MA<11>")
	)
	(arc
		(start 254.152654 -93.033342)
		(mid 254.231843 -92.746727)
		(end 254.161544 -92.457778)
		(width 0.0889)
		(layer "In2.Cu")
		(net "M_F_MA<11>")
	)
	(arc
		(start 254.152654 -96.995742)
		(mid 254.231843 -96.709127)
		(end 254.161544 -96.420178)
		(width 0.0889)
		(layer "In2.Cu")
		(net "M_F_MA<11>")
	)
	(arc
		(start 254.159004 -94.01302)
		(mid 254.231802 -93.722257)
		(end 254.152654 -93.433138)
		(width 0.0889)
		(layer "In2.Cu")
		(net "M_F_MA<11>")
	)
	(segment
		(start 267.79982 -154.905456)
		(end 267.79982 -156.87294)
		(width 0.1651)
		(layer "F.Cu")
		(net "M_F_MA<10>")
	)
	(segment
		(start 259.36321 -90.756486)
		(end 258.79171 -90.756486)
		(width 0.1016)
		(layer "F.Cu")
		(net "M_F_MA<10>")
	)
	(segment
		(start 267.79982 -156.87294)
		(end 267.800328 -156.87294)
		(width 0.1651)
		(layer "F.Cu")
		(net "M_F_MA<10>")
	)
	(via
		(at 267.79982 -154.905456)
		(size 0.508)
		(drill 0.254)
		(layers "F.Cu" "B.Cu")
		(net "M_F_MA<10>")
	)
	(via
		(at 267.800074 -148.773388)
		(size 0.4572)
		(drill 0.2032)
		(layers "F.Cu" "B.Cu")
		(net "M_F_MA<10>")
	)
	(via
		(at 258.79171 -90.756486)
		(size 0.508)
		(drill 0.254)
		(layers "F.Cu" "B.Cu")
		(net "M_F_MA<10>")
	)
	(segment
		(start 267.79982 -148.773134)
		(end 267.800074 -148.773388)
		(width 0.1651)
		(layer "B.Cu")
		(net "M_F_MA<10>")
	)
	(segment
		(start 267.79982 -147.478496)
		(end 267.79982 -148.773134)
		(width 0.1651)
		(layer "B.Cu")
		(net "M_F_MA<10>")
	)
	(segment
		(start 267.800328 -147.478496)
		(end 267.79982 -147.478496)
		(width 0.1651)
		(layer "B.Cu")
		(net "M_F_MA<10>")
	)
	(segment
		(start 258.902454 -100.2284)
		(end 260.187948 -101.513894)
		(width 0.14224)
		(layer "In11.Cu")
		(net "M_F_MA<10>")
	)
	(segment
		(start 258.3688 -97.775268)
		(end 258.3688 -98.1202)
		(width 0.0889)
		(layer "In11.Cu")
		(net "M_F_MA<10>")
	)
	(segment
		(start 261.9756 -145.6944)
		(end 263.0424 -146.7612)
		(width 0.14224)
		(layer "In11.Cu")
		(net "M_F_MA<10>")
	)
	(segment
		(start 258.699 -90.96629)
		(end 258.50215 -91.411552)
		(width 0.0889)
		(layer "In11.Cu")
		(net "M_F_MA<10>")
	)
	(segment
		(start 258.3688 -98.1202)
		(end 258.374388 -98.125788)
		(width 0.0889)
		(layer "In11.Cu")
		(net "M_F_MA<10>")
	)
	(segment
		(start 260.187948 -126.202948)
		(end 261.4168 -127.4318)
		(width 0.14224)
		(layer "In11.Cu")
		(net "M_F_MA<10>")
	)
	(segment
		(start 267.800074 -148.529548)
		(end 267.800074 -148.773388)
		(width 0.14224)
		(layer "In11.Cu")
		(net "M_F_MA<10>")
	)
	(segment
		(start 268.224 -152.46096)
		(end 268.32179 -152.55875)
		(width 0.14224)
		(layer "In11.Cu")
		(net "M_F_MA<10>")
	)
	(segment
		(start 258.79171 -90.756486)
		(end 258.699 -90.96629)
		(width 0.0889)
		(layer "In11.Cu")
		(net "M_F_MA<10>")
	)
	(segment
		(start 260.187948 -101.513894)
		(end 260.187948 -126.202948)
		(width 0.14224)
		(layer "In11.Cu")
		(net "M_F_MA<10>")
	)
	(segment
		(start 258.7752 -100.101146)
		(end 258.902454 -100.2284)
		(width 0.0889)
		(layer "In11.Cu")
		(net "M_F_MA<10>")
	)
	(segment
		(start 258.6482 -100.101146)
		(end 258.7752 -100.101146)
		(width 0.0889)
		(layer "In11.Cu")
		(net "M_F_MA<10>")
	)
	(segment
		(start 268.224 -149.197314)
		(end 268.224 -152.46096)
		(width 0.14224)
		(layer "In11.Cu")
		(net "M_F_MA<10>")
	)
	(segment
		(start 261.4168 -135.9916)
		(end 261.9756 -136.5504)
		(width 0.14224)
		(layer "In11.Cu")
		(net "M_F_MA<10>")
	)
	(segment
		(start 258.374388 -98.125788)
		(end 258.374388 -99.827334)
		(width 0.0889)
		(layer "In11.Cu")
		(net "M_F_MA<10>")
	)
	(segment
		(start 268.32179 -153.808938)
		(end 267.79982 -154.330908)
		(width 0.14224)
		(layer "In11.Cu")
		(net "M_F_MA<10>")
	)
	(segment
		(start 263.0424 -146.7612)
		(end 266.031726 -146.7612)
		(width 0.14224)
		(layer "In11.Cu")
		(net "M_F_MA<10>")
	)
	(segment
		(start 261.9756 -136.5504)
		(end 261.9756 -145.6944)
		(width 0.14224)
		(layer "In11.Cu")
		(net "M_F_MA<10>")
	)
	(segment
		(start 267.800074 -148.773388)
		(end 268.224 -149.197314)
		(width 0.14224)
		(layer "In11.Cu")
		(net "M_F_MA<10>")
	)
	(segment
		(start 266.031726 -146.7612)
		(end 267.800074 -148.529548)
		(width 0.14224)
		(layer "In11.Cu")
		(net "M_F_MA<10>")
	)
	(segment
		(start 267.79982 -154.330908)
		(end 267.79982 -154.905456)
		(width 0.14224)
		(layer "In11.Cu")
		(net "M_F_MA<10>")
	)
	(segment
		(start 258.374388 -99.827334)
		(end 258.6482 -100.101146)
		(width 0.0889)
		(layer "In11.Cu")
		(net "M_F_MA<10>")
	)
	(segment
		(start 268.32179 -152.55875)
		(end 268.32179 -153.808938)
		(width 0.14224)
		(layer "In11.Cu")
		(net "M_F_MA<10>")
	)
	(segment
		(start 261.4168 -127.4318)
		(end 261.4168 -135.9916)
		(width 0.14224)
		(layer "In11.Cu")
		(net "M_F_MA<10>")
	)
	(arc
		(start 258.445 -95.909384)
		(mid 258.524131 -96.204786)
		(end 258.445 -96.500188)
		(width 0.0889)
		(layer "In11.Cu")
		(net "M_F_MA<10>")
	)
	(arc
		(start 258.445 -91.547188)
		(mid 258.391501 -91.747086)
		(end 258.445 -91.946984)
		(width 0.0889)
		(layer "In11.Cu")
		(net "M_F_MA<10>")
	)
	(arc
		(start 258.445 -92.537788)
		(mid 258.391501 -92.737686)
		(end 258.445 -92.937584)
		(width 0.0889)
		(layer "In11.Cu")
		(net "M_F_MA<10>")
	)
	(arc
		(start 258.445 -94.518988)
		(mid 258.391501 -94.718886)
		(end 258.445 -94.918784)
		(width 0.0889)
		(layer "In11.Cu")
		(net "M_F_MA<10>")
	)
	(arc
		(start 258.445 -96.899984)
		(mid 258.524131 -97.195386)
		(end 258.445 -97.490788)
		(width 0.0889)
		(layer "In11.Cu")
		(net "M_F_MA<10>")
	)
	(arc
		(start 258.50215 -91.411552)
		(mid 258.477825 -91.481162)
		(end 258.445 -91.547188)
		(width 0.0889)
		(layer "In11.Cu")
		(net "M_F_MA<10>")
	)
	(arc
		(start 258.445 -93.928184)
		(mid 258.524131 -94.223586)
		(end 258.445 -94.518988)
		(width 0.0889)
		(layer "In11.Cu")
		(net "M_F_MA<10>")
	)
	(arc
		(start 258.445 -94.918784)
		(mid 258.524131 -95.214186)
		(end 258.445 -95.509588)
		(width 0.0889)
		(layer "In11.Cu")
		(net "M_F_MA<10>")
	)
	(arc
		(start 258.445 -97.490788)
		(mid 258.388163 -97.628011)
		(end 258.3688 -97.775268)
		(width 0.0889)
		(layer "In11.Cu")
		(net "M_F_MA<10>")
	)
	(arc
		(start 258.445 -95.509588)
		(mid 258.391501 -95.709486)
		(end 258.445 -95.909384)
		(width 0.0889)
		(layer "In11.Cu")
		(net "M_F_MA<10>")
	)
	(arc
		(start 258.445 -91.946984)
		(mid 258.524131 -92.242386)
		(end 258.445 -92.537788)
		(width 0.0889)
		(layer "In11.Cu")
		(net "M_F_MA<10>")
	)
	(arc
		(start 258.445 -92.937584)
		(mid 258.524131 -93.232986)
		(end 258.445 -93.528388)
		(width 0.0889)
		(layer "In11.Cu")
		(net "M_F_MA<10>")
	)
	(arc
		(start 258.445 -93.528388)
		(mid 258.391501 -93.728286)
		(end 258.445 -93.928184)
		(width 0.0889)
		(layer "In11.Cu")
		(net "M_F_MA<10>")
	)
	(arc
		(start 258.445 -96.500188)
		(mid 258.391501 -96.700086)
		(end 258.445 -96.899984)
		(width 0.0889)
		(layer "In11.Cu")
		(net "M_F_MA<10>")
	)
	(segment
		(start 261.08025 -91.747086)
		(end 260.50875 -91.747086)
		(width 0.1016)
		(layer "F.Cu")
		(net "M_F_MA<0>")
	)
	(segment
		(start 266.100306 -152.273)
		(end 266.099798 -152.278842)
		(width 0.1651)
		(layer "F.Cu")
		(net "M_F_MA<0>")
	)
	(segment
		(start 266.099798 -152.278842)
		(end 266.099798 -153.542746)
		(width 0.1651)
		(layer "F.Cu")
		(net "M_F_MA<0>")
	)
	(via
		(at 266.099798 -150.785068)
		(size 0.4572)
		(drill 0.2032)
		(layers "F.Cu" "B.Cu")
		(net "M_F_MA<0>")
	)
	(via
		(at 266.099798 -153.542746)
		(size 0.508)
		(drill 0.254)
		(layers "F.Cu" "B.Cu")
		(net "M_F_MA<0>")
	)
	(via
		(at 260.50875 -91.747086)
		(size 0.508)
		(drill 0.254)
		(layers "F.Cu" "B.Cu")
		(net "M_F_MA<0>")
	)
	(segment
		(start 266.099798 -152.078182)
		(end 266.099798 -150.785068)
		(width 0.1651)
		(layer "B.Cu")
		(net "M_F_MA<0>")
	)
	(segment
		(start 266.100306 -152.078436)
		(end 266.099798 -152.078182)
		(width 0.1651)
		(layer "B.Cu")
		(net "M_F_MA<0>")
	)
	(segment
		(start 261.02056 -96.404938)
		(end 261.02691 -96.415606)
		(width 0.0889)
		(layer "In2.Cu")
		(net "M_F_MA<0>")
	)
	(segment
		(start 261.032498 -92.655898)
		(end 261.032498 -92.988638)
		(width 0.0889)
		(layer "In2.Cu")
		(net "M_F_MA<0>")
	)
	(segment
		(start 261.8232 -102.921816)
		(end 261.8232 -125.156214)
		(width 0.14224)
		(layer "In2.Cu")
		(net "M_F_MA<0>")
	)
	(segment
		(start 265.66241 -134.566914)
		(end 265.665966 -134.57047)
		(width 0.14224)
		(layer "In2.Cu")
		(net "M_F_MA<0>")
	)
	(segment
		(start 265.6332 -138.7348)
		(end 265.6332 -139.5222)
		(width 0.14224)
		(layer "In2.Cu")
		(net "M_F_MA<0>")
	)
	(segment
		(start 260.50875 -91.747086)
		(end 260.50875 -92.13215)
		(width 0.0889)
		(layer "In2.Cu")
		(net "M_F_MA<0>")
	)
	(segment
		(start 261.015734 -98.377502)
		(end 261.02056 -98.386138)
		(width 0.0889)
		(layer "In2.Cu")
		(net "M_F_MA<0>")
	)
	(segment
		(start 261.02056 -97.395538)
		(end 261.02691 -97.406206)
		(width 0.0889)
		(layer "In2.Cu")
		(net "M_F_MA<0>")
	)
	(segment
		(start 265.6078 -128.940814)
		(end 265.6078 -129.771648)
		(width 0.14224)
		(layer "In2.Cu")
		(net "M_F_MA<0>")
	)
	(segment
		(start 265.722354 -129.886202)
		(end 265.722354 -130.543046)
		(width 0.14224)
		(layer "In2.Cu")
		(net "M_F_MA<0>")
	)
	(segment
		(start 261.8232 -125.156214)
		(end 265.6078 -128.940814)
		(width 0.14224)
		(layer "In2.Cu")
		(net "M_F_MA<0>")
	)
	(segment
		(start 265.6332 -139.5222)
		(end 265.688318 -139.577318)
		(width 0.14224)
		(layer "In2.Cu")
		(net "M_F_MA<0>")
	)
	(segment
		(start 265.662156 -149.101556)
		(end 266.099798 -149.539198)
		(width 0.14224)
		(layer "In2.Cu")
		(net "M_F_MA<0>")
	)
	(segment
		(start 265.619992 -131.152392)
		(end 265.66241 -131.19481)
		(width 0.14224)
		(layer "In2.Cu")
		(net "M_F_MA<0>")
	)
	(segment
		(start 265.66241 -131.19481)
		(end 265.66241 -134.566914)
		(width 0.14224)
		(layer "In2.Cu")
		(net "M_F_MA<0>")
	)
	(segment
		(start 265.633708 -143.250412)
		(end 265.633708 -144.272508)
		(width 0.14224)
		(layer "In2.Cu")
		(net "M_F_MA<0>")
	)
	(segment
		(start 261.02691 -94.01302)
		(end 261.02056 -94.023688)
		(width 0.0889)
		(layer "In2.Cu")
		(net "M_F_MA<0>")
	)
	(segment
		(start 261.015734 -95.405702)
		(end 261.02056 -95.414338)
		(width 0.0889)
		(layer "In2.Cu")
		(net "M_F_MA<0>")
	)
	(segment
		(start 265.71067 -145.00733)
		(end 265.662156 -145.055844)
		(width 0.14224)
		(layer "In2.Cu")
		(net "M_F_MA<0>")
	)
	(segment
		(start 266.227306 -150.912576)
		(end 266.227306 -153.415238)
		(width 0.14224)
		(layer "In2.Cu")
		(net "M_F_MA<0>")
	)
	(segment
		(start 261.015734 -97.386902)
		(end 261.02056 -97.395538)
		(width 0.0889)
		(layer "In2.Cu")
		(net "M_F_MA<0>")
	)
	(segment
		(start 265.633708 -144.272508)
		(end 265.71067 -144.34947)
		(width 0.14224)
		(layer "In2.Cu")
		(net "M_F_MA<0>")
	)
	(segment
		(start 261.015734 -99.368102)
		(end 261.02056 -99.376738)
		(width 0.0889)
		(layer "In2.Cu")
		(net "M_F_MA<0>")
	)
	(segment
		(start 261.02056 -98.386138)
		(end 261.02691 -98.396806)
		(width 0.0889)
		(layer "In2.Cu")
		(net "M_F_MA<0>")
	)
	(segment
		(start 265.688318 -143.195802)
		(end 265.633708 -143.250412)
		(width 0.14224)
		(layer "In2.Cu")
		(net "M_F_MA<0>")
	)
	(segment
		(start 265.6078 -129.771648)
		(end 265.722354 -129.886202)
		(width 0.14224)
		(layer "In2.Cu")
		(net "M_F_MA<0>")
	)
	(segment
		(start 265.619992 -130.645408)
		(end 265.619992 -131.152392)
		(width 0.14224)
		(layer "In2.Cu")
		(net "M_F_MA<0>")
	)
	(segment
		(start 261.015734 -96.396302)
		(end 261.02056 -96.404938)
		(width 0.0889)
		(layer "In2.Cu")
		(net "M_F_MA<0>")
	)
	(segment
		(start 261.015734 -93.424502)
		(end 261.02056 -93.433138)
		(width 0.0889)
		(layer "In2.Cu")
		(net "M_F_MA<0>")
	)
	(segment
		(start 261.02056 -95.414338)
		(end 261.02691 -95.425006)
		(width 0.0889)
		(layer "In2.Cu")
		(net "M_F_MA<0>")
	)
	(segment
		(start 265.71067 -144.34947)
		(end 265.71067 -145.00733)
		(width 0.14224)
		(layer "In2.Cu")
		(net "M_F_MA<0>")
	)
	(segment
		(start 265.688318 -139.577318)
		(end 265.688318 -143.195802)
		(width 0.14224)
		(layer "In2.Cu")
		(net "M_F_MA<0>")
	)
	(segment
		(start 265.665966 -134.57047)
		(end 265.665966 -138.702034)
		(width 0.14224)
		(layer "In2.Cu")
		(net "M_F_MA<0>")
	)
	(segment
		(start 261.226808 -101.233224)
		(end 261.8232 -101.829616)
		(width 0.0889)
		(layer "In2.Cu")
		(net "M_F_MA<0>")
	)
	(segment
		(start 266.099798 -150.785068)
		(end 266.227306 -150.912576)
		(width 0.14224)
		(layer "In2.Cu")
		(net "M_F_MA<0>")
	)
	(segment
		(start 261.226808 -99.610164)
		(end 261.226808 -101.233224)
		(width 0.0889)
		(layer "In2.Cu")
		(net "M_F_MA<0>")
	)
	(segment
		(start 265.662156 -145.055844)
		(end 265.662156 -149.101556)
		(width 0.14224)
		(layer "In2.Cu")
		(net "M_F_MA<0>")
	)
	(segment
		(start 265.665966 -138.702034)
		(end 265.6332 -138.7348)
		(width 0.14224)
		(layer "In2.Cu")
		(net "M_F_MA<0>")
	)
	(segment
		(start 266.227306 -153.415238)
		(end 266.099798 -153.542746)
		(width 0.14224)
		(layer "In2.Cu")
		(net "M_F_MA<0>")
	)
	(segment
		(start 260.50875 -92.13215)
		(end 261.032498 -92.655898)
		(width 0.0889)
		(layer "In2.Cu")
		(net "M_F_MA<0>")
	)
	(segment
		(start 265.722354 -130.543046)
		(end 265.619992 -130.645408)
		(width 0.14224)
		(layer "In2.Cu")
		(net "M_F_MA<0>")
	)
	(segment
		(start 266.099798 -149.539198)
		(end 266.099798 -150.785068)
		(width 0.14224)
		(layer "In2.Cu")
		(net "M_F_MA<0>")
	)
	(segment
		(start 261.8232 -101.829616)
		(end 261.8232 -102.921816)
		(width 0.0889)
		(layer "In2.Cu")
		(net "M_F_MA<0>")
	)
	(arc
		(start 261.02056 -98.976688)
		(mid 260.96709 -99.171751)
		(end 261.015734 -99.368102)
		(width 0.0889)
		(layer "In2.Cu")
		(net "M_F_MA<0>")
	)
	(arc
		(start 261.02056 -95.014288)
		(mid 260.96709 -95.209351)
		(end 261.015734 -95.405702)
		(width 0.0889)
		(layer "In2.Cu")
		(net "M_F_MA<0>")
	)
	(arc
		(start 261.02056 -93.033088)
		(mid 260.96709 -93.228151)
		(end 261.015734 -93.424502)
		(width 0.0889)
		(layer "In2.Cu")
		(net "M_F_MA<0>")
	)
	(arc
		(start 261.02056 -96.995488)
		(mid 260.96709 -97.190551)
		(end 261.015734 -97.386902)
		(width 0.0889)
		(layer "In2.Cu")
		(net "M_F_MA<0>")
	)
	(arc
		(start 261.02056 -94.423484)
		(mid 261.099691 -94.718886)
		(end 261.02056 -95.014288)
		(width 0.0889)
		(layer "In2.Cu")
		(net "M_F_MA<0>")
	)
	(arc
		(start 261.02056 -93.433138)
		(mid 261.099782 -93.722256)
		(end 261.02691 -94.01302)
		(width 0.0889)
		(layer "In2.Cu")
		(net "M_F_MA<0>")
	)
	(arc
		(start 261.02691 -96.415606)
		(mid 261.099708 -96.706369)
		(end 261.02056 -96.995488)
		(width 0.0889)
		(layer "In2.Cu")
		(net "M_F_MA<0>")
	)
	(arc
		(start 261.02691 -97.406206)
		(mid 261.099708 -97.696969)
		(end 261.02056 -97.986088)
		(width 0.0889)
		(layer "In2.Cu")
		(net "M_F_MA<0>")
	)
	(arc
		(start 261.02056 -94.023688)
		(mid 260.967061 -94.223586)
		(end 261.02056 -94.423484)
		(width 0.0889)
		(layer "In2.Cu")
		(net "M_F_MA<0>")
	)
	(arc
		(start 261.032498 -92.988638)
		(mid 261.029475 -93.011658)
		(end 261.02056 -93.033088)
		(width 0.0889)
		(layer "In2.Cu")
		(net "M_F_MA<0>")
	)
	(arc
		(start 261.02056 -99.376738)
		(mid 261.111107 -99.504568)
		(end 261.226808 -99.610164)
		(width 0.0889)
		(layer "In2.Cu")
		(net "M_F_MA<0>")
	)
	(arc
		(start 261.02691 -95.425006)
		(mid 261.099708 -95.715769)
		(end 261.02056 -96.004888)
		(width 0.0889)
		(layer "In2.Cu")
		(net "M_F_MA<0>")
	)
	(arc
		(start 261.02691 -98.396806)
		(mid 261.099708 -98.687569)
		(end 261.02056 -98.976688)
		(width 0.0889)
		(layer "In2.Cu")
		(net "M_F_MA<0>")
	)
	(arc
		(start 261.02056 -97.986088)
		(mid 260.96709 -98.181151)
		(end 261.015734 -98.377502)
		(width 0.0889)
		(layer "In2.Cu")
		(net "M_F_MA<0>")
	)
	(arc
		(start 261.02056 -96.004888)
		(mid 260.96709 -96.199951)
		(end 261.015734 -96.396302)
		(width 0.0889)
		(layer "In2.Cu")
		(net "M_F_MA<0>")
	)
	(segment
		(start 239.749838 -152.278842)
		(end 239.749838 -153.542746)
		(width 0.1651)
		(layer "F.Cu")
		(net "M_F_ECC<7>")
	)
	(segment
		(start 247.344184 -84.812886)
		(end 246.772684 -84.812886)
		(width 0.1651)
		(layer "F.Cu")
		(net "M_F_ECC<7>")
	)
	(segment
		(start 239.750346 -152.273)
		(end 239.749838 -152.278842)
		(width 0.1651)
		(layer "F.Cu")
		(net "M_F_ECC<7>")
	)
	(via
		(at 239.749838 -153.542746)
		(size 0.508)
		(drill 0.254)
		(layers "F.Cu" "B.Cu")
		(net "M_F_ECC<7>")
	)
	(via
		(at 240.599722 -149.533356)
		(size 0.508)
		(drill 0.254)
		(layers "F.Cu" "B.Cu")
		(net "M_F_ECC<7>")
	)
	(via
		(at 246.772684 -84.812886)
		(size 0.508)
		(drill 0.254)
		(layers "F.Cu" "B.Cu")
		(net "M_F_ECC<7>")
	)
	(segment
		(start 240.600484 -147.478496)
		(end 240.599722 -147.478496)
		(width 0.1651)
		(layer "B.Cu")
		(net "M_F_ECC<7>")
	)
	(segment
		(start 240.599722 -147.478496)
		(end 240.599722 -149.533356)
		(width 0.1651)
		(layer "B.Cu")
		(net "M_F_ECC<7>")
	)
	(segment
		(start 240.977928 -131.408678)
		(end 240.977928 -134.579868)
		(width 0.14224)
		(layer "In4.Cu")
		(net "M_F_ECC<7>")
	)
	(segment
		(start 247.469152 -102.346252)
		(end 247.703848 -102.580948)
		(width 0.0889)
		(layer "In4.Cu")
		(net "M_F_ECC<7>")
	)
	(segment
		(start 239.7252 -122.36704)
		(end 240.952528 -123.594368)
		(width 0.14224)
		(layer "In4.Cu")
		(net "M_F_ECC<7>")
	)
	(segment
		(start 240.952528 -148.531072)
		(end 240.952528 -149.191472)
		(width 0.14224)
		(layer "In4.Cu")
		(net "M_F_ECC<7>")
	)
	(segment
		(start 241.0206 -138.7348)
		(end 240.952528 -138.802872)
		(width 0.14224)
		(layer "In4.Cu")
		(net "M_F_ECC<7>")
	)
	(segment
		(start 247.284494 -92.442538)
		(end 247.290844 -92.453206)
		(width 0.0889)
		(layer "In4.Cu")
		(net "M_F_ECC<7>")
	)
	(segment
		(start 241.0206 -136.6774)
		(end 241.0206 -138.7348)
		(width 0.14224)
		(layer "In4.Cu")
		(net "M_F_ECC<7>")
	)
	(segment
		(start 241.750342 -113.392966)
		(end 241.905282 -113.547906)
		(width 0.14224)
		(layer "In4.Cu")
		(net "M_F_ECC<7>")
	)
	(segment
		(start 240.952528 -129.859278)
		(end 241.181128 -130.087878)
		(width 0.14224)
		(layer "In4.Cu")
		(net "M_F_ECC<7>")
	)
	(segment
		(start 247.279668 -96.396302)
		(end 247.408446 -96.62668)
		(width 0.0889)
		(layer "In4.Cu")
		(net "M_F_ECC<7>")
	)
	(segment
		(start 241.750342 -114.205766)
		(end 241.53749 -114.205766)
		(width 0.14224)
		(layer "In4.Cu")
		(net "M_F_ECC<7>")
	)
	(segment
		(start 240.952528 -126.839472)
		(end 240.952528 -129.859278)
		(width 0.14224)
		(layer "In4.Cu")
		(net "M_F_ECC<7>")
	)
	(segment
		(start 241.275108 -118.101364)
		(end 241.44351 -118.269766)
		(width 0.14224)
		(layer "In4.Cu")
		(net "M_F_ECC<7>")
	)
	(segment
		(start 240.952528 -136.212072)
		(end 240.952528 -136.609328)
		(width 0.14224)
		(layer "In4.Cu")
		(net "M_F_ECC<7>")
	)
	(segment
		(start 247.284494 -87.489538)
		(end 247.290844 -87.500206)
		(width 0.0889)
		(layer "In4.Cu")
		(net "M_F_ECC<7>")
	)
	(segment
		(start 241.297968 -112.358424)
		(end 241.297968 -113.159794)
		(width 0.14224)
		(layer "In4.Cu")
		(net "M_F_ECC<7>")
	)
	(segment
		(start 241.53749 -115.018566)
		(end 241.750342 -115.018566)
		(width 0.14224)
		(layer "In4.Cu")
		(net "M_F_ECC<7>")
	)
	(segment
		(start 241.0206 -146.2786)
		(end 241.0206 -148.463)
		(width 0.14224)
		(layer "In4.Cu")
		(net "M_F_ECC<7>")
	)
	(segment
		(start 241.709956 -116.644166)
		(end 241.864896 -116.799106)
		(width 0.14224)
		(layer "In4.Cu")
		(net "M_F_ECC<7>")
	)
	(segment
		(start 247.279668 -95.405702)
		(end 247.284494 -95.414338)
		(width 0.0889)
		(layer "In4.Cu")
		(net "M_F_ECC<7>")
	)
	(segment
		(start 247.284494 -91.451938)
		(end 247.290844 -91.462606)
		(width 0.0889)
		(layer "In4.Cu")
		(net "M_F_ECC<7>")
	)
	(segment
		(start 241.750342 -115.018566)
		(end 241.905282 -115.173506)
		(width 0.14224)
		(layer "In4.Cu")
		(net "M_F_ECC<7>")
	)
	(segment
		(start 247.279668 -87.480902)
		(end 247.284494 -87.489538)
		(width 0.0889)
		(layer "In4.Cu")
		(net "M_F_ECC<7>")
	)
	(segment
		(start 241.248184 -115.986306)
		(end 241.248184 -116.489226)
		(width 0.14224)
		(layer "In4.Cu")
		(net "M_F_ECC<7>")
	)
	(segment
		(start 247.279668 -89.462102)
		(end 247.284494 -89.470738)
		(width 0.0889)
		(layer "In4.Cu")
		(net "M_F_ECC<7>")
	)
	(segment
		(start 241.905282 -115.173506)
		(end 241.905282 -115.676426)
		(width 0.14224)
		(layer "In4.Cu")
		(net "M_F_ECC<7>")
	)
	(segment
		(start 241.864896 -116.799106)
		(end 241.864896 -117.302026)
		(width 0.14224)
		(layer "In4.Cu")
		(net "M_F_ECC<7>")
	)
	(segment
		(start 241.121692 -145.643854)
		(end 240.952528 -145.813018)
		(width 0.14224)
		(layer "In4.Cu")
		(net "M_F_ECC<7>")
	)
	(segment
		(start 241.750342 -118.269766)
		(end 241.905282 -118.424706)
		(width 0.14224)
		(layer "In4.Cu")
		(net "M_F_ECC<7>")
	)
	(segment
		(start 241.905282 -115.676426)
		(end 241.750342 -115.831366)
		(width 0.14224)
		(layer "In4.Cu")
		(net "M_F_ECC<7>")
	)
	(segment
		(start 241.121692 -144.313402)
		(end 241.121692 -145.643854)
		(width 0.14224)
		(layer "In4.Cu")
		(net "M_F_ECC<7>")
	)
	(segment
		(start 241.905282 -118.424706)
		(end 241.905282 -118.927626)
		(width 0.14224)
		(layer "In4.Cu")
		(net "M_F_ECC<7>")
	)
	(segment
		(start 247.219216 -97.980754)
		(end 247.219216 -100.673154)
		(width 0.0889)
		(layer "In4.Cu")
		(net "M_F_ECC<7>")
	)
	(segment
		(start 241.38255 -114.360706)
		(end 241.38255 -114.863626)
		(width 0.14224)
		(layer "In4.Cu")
		(net "M_F_ECC<7>")
	)
	(segment
		(start 247.469152 -102.23881)
		(end 247.469152 -102.346252)
		(width 0.0889)
		(layer "In4.Cu")
		(net "M_F_ECC<7>")
	)
	(segment
		(start 241.905282 -113.547906)
		(end 241.905282 -114.050826)
		(width 0.14224)
		(layer "In4.Cu")
		(net "M_F_ECC<7>")
	)
	(segment
		(start 247.284494 -89.470738)
		(end 247.290844 -89.481406)
		(width 0.0889)
		(layer "In4.Cu")
		(net "M_F_ECC<7>")
	)
	(segment
		(start 247.284494 -90.461338)
		(end 247.290844 -90.472006)
		(width 0.0889)
		(layer "In4.Cu")
		(net "M_F_ECC<7>")
	)
	(segment
		(start 247.284494 -85.508338)
		(end 247.290844 -85.519006)
		(width 0.0889)
		(layer "In4.Cu")
		(net "M_F_ECC<7>")
	)
	(segment
		(start 241.0206 -143.764)
		(end 240.977928 -143.806672)
		(width 0.14224)
		(layer "In4.Cu")
		(net "M_F_ECC<7>")
	)
	(segment
		(start 240.952528 -138.802872)
		(end 240.952528 -139.460478)
		(width 0.14224)
		(layer "In4.Cu")
		(net "M_F_ECC<7>")
	)
	(segment
		(start 240.977928 -143.806672)
		(end 240.977928 -144.169638)
		(width 0.14224)
		(layer "In4.Cu")
		(net "M_F_ECC<7>")
	)
	(segment
		(start 241.181128 -140.806678)
		(end 240.901728 -141.086078)
		(width 0.14224)
		(layer "In4.Cu")
		(net "M_F_ECC<7>")
	)
	(segment
		(start 247.279668 -86.490302)
		(end 247.284494 -86.498938)
		(width 0.0889)
		(layer "In4.Cu")
		(net "M_F_ECC<7>")
	)
	(segment
		(start 247.196864 -85.354414)
		(end 247.284494 -85.508338)
		(width 0.0889)
		(layer "In4.Cu")
		(net "M_F_ECC<7>")
	)
	(segment
		(start 247.279668 -90.452702)
		(end 247.284494 -90.461338)
		(width 0.0889)
		(layer "In4.Cu")
		(net "M_F_ECC<7>")
	)
	(segment
		(start 241.905282 -114.050826)
		(end 241.750342 -114.205766)
		(width 0.14224)
		(layer "In4.Cu")
		(net "M_F_ECC<7>")
	)
	(segment
		(start 247.284494 -95.414338)
		(end 247.290844 -95.425006)
		(width 0.0889)
		(layer "In4.Cu")
		(net "M_F_ECC<7>")
	)
	(segment
		(start 241.864896 -117.302026)
		(end 241.709956 -117.456966)
		(width 0.14224)
		(layer "In4.Cu")
		(net "M_F_ECC<7>")
	)
	(segment
		(start 240.952528 -146.210528)
		(end 241.0206 -146.2786)
		(width 0.14224)
		(layer "In4.Cu")
		(net "M_F_ECC<7>")
	)
	(segment
		(start 240.952528 -145.813018)
		(end 240.952528 -146.210528)
		(width 0.14224)
		(layer "In4.Cu")
		(net "M_F_ECC<7>")
	)
	(segment
		(start 241.750342 -119.082566)
		(end 240.657634 -119.082566)
		(width 0.14224)
		(layer "In4.Cu")
		(net "M_F_ECC<7>")
	)
	(segment
		(start 241.2746 -125.73)
		(end 241.2746 -126.5174)
		(width 0.14224)
		(layer "In4.Cu")
		(net "M_F_ECC<7>")
	)
	(segment
		(start 241.248184 -116.489226)
		(end 241.403124 -116.644166)
		(width 0.14224)
		(layer "In4.Cu")
		(net "M_F_ECC<7>")
	)
	(segment
		(start 240.657634 -119.082566)
		(end 239.7252 -120.015)
		(width 0.14224)
		(layer "In4.Cu")
		(net "M_F_ECC<7>")
	)
	(segment
		(start 241.2746 -126.5174)
		(end 240.952528 -126.839472)
		(width 0.14224)
		(layer "In4.Cu")
		(net "M_F_ECC<7>")
	)
	(segment
		(start 247.703848 -105.952544)
		(end 241.297968 -112.358424)
		(width 0.14224)
		(layer "In4.Cu")
		(net "M_F_ECC<7>")
	)
	(segment
		(start 246.965216 -101.734874)
		(end 247.469152 -102.23881)
		(width 0.0889)
		(layer "In4.Cu")
		(net "M_F_ECC<7>")
	)
	(segment
		(start 241.155728 -134.757668)
		(end 241.155728 -136.008872)
		(width 0.14224)
		(layer "In4.Cu")
		(net "M_F_ECC<7>")
	)
	(segment
		(start 241.750342 -115.831366)
		(end 241.403124 -115.831366)
		(width 0.14224)
		(layer "In4.Cu")
		(net "M_F_ECC<7>")
	)
	(segment
		(start 240.952528 -136.609328)
		(end 241.0206 -136.6774)
		(width 0.14224)
		(layer "In4.Cu")
		(net "M_F_ECC<7>")
	)
	(segment
		(start 241.905282 -118.927626)
		(end 241.750342 -119.082566)
		(width 0.14224)
		(layer "In4.Cu")
		(net "M_F_ECC<7>")
	)
	(segment
		(start 247.290844 -94.01302)
		(end 247.284494 -94.023688)
		(width 0.0889)
		(layer "In4.Cu")
		(net "M_F_ECC<7>")
	)
	(segment
		(start 241.403124 -115.831366)
		(end 241.248184 -115.986306)
		(width 0.14224)
		(layer "In4.Cu")
		(net "M_F_ECC<7>")
	)
	(segment
		(start 241.53749 -114.205766)
		(end 241.38255 -114.360706)
		(width 0.14224)
		(layer "In4.Cu")
		(net "M_F_ECC<7>")
	)
	(segment
		(start 241.181128 -130.087878)
		(end 241.181128 -131.205478)
		(width 0.14224)
		(layer "In4.Cu")
		(net "M_F_ECC<7>")
	)
	(segment
		(start 241.53114 -113.392966)
		(end 241.750342 -113.392966)
		(width 0.14224)
		(layer "In4.Cu")
		(net "M_F_ECC<7>")
	)
	(segment
		(start 240.941606 -149.191472)
		(end 240.599722 -149.533356)
		(width 0.14224)
		(layer "In4.Cu")
		(net "M_F_ECC<7>")
	)
	(segment
		(start 241.416586 -117.456966)
		(end 241.275108 -117.598444)
		(width 0.14224)
		(layer "In4.Cu")
		(net "M_F_ECC<7>")
	)
	(segment
		(start 240.952528 -123.594368)
		(end 240.952528 -125.407928)
		(width 0.14224)
		(layer "In4.Cu")
		(net "M_F_ECC<7>")
	)
	(segment
		(start 241.0206 -148.463)
		(end 240.952528 -148.531072)
		(width 0.14224)
		(layer "In4.Cu")
		(net "M_F_ECC<7>")
	)
	(segment
		(start 247.279668 -93.424502)
		(end 247.284494 -93.433138)
		(width 0.0889)
		(layer "In4.Cu")
		(net "M_F_ECC<7>")
	)
	(segment
		(start 240.952528 -139.460478)
		(end 241.181128 -139.689078)
		(width 0.14224)
		(layer "In4.Cu")
		(net "M_F_ECC<7>")
	)
	(segment
		(start 241.44351 -118.269766)
		(end 241.750342 -118.269766)
		(width 0.14224)
		(layer "In4.Cu")
		(net "M_F_ECC<7>")
	)
	(segment
		(start 247.408446 -97.791524)
		(end 247.219216 -97.980754)
		(width 0.0889)
		(layer "In4.Cu")
		(net "M_F_ECC<7>")
	)
	(segment
		(start 240.977928 -134.579868)
		(end 241.155728 -134.757668)
		(width 0.14224)
		(layer "In4.Cu")
		(net "M_F_ECC<7>")
	)
	(segment
		(start 247.408446 -96.62668)
		(end 247.408446 -97.791524)
		(width 0.0889)
		(layer "In4.Cu")
		(net "M_F_ECC<7>")
	)
	(segment
		(start 239.7252 -120.015)
		(end 239.7252 -122.36704)
		(width 0.14224)
		(layer "In4.Cu")
		(net "M_F_ECC<7>")
	)
	(segment
		(start 247.279668 -92.433902)
		(end 247.284494 -92.442538)
		(width 0.0889)
		(layer "In4.Cu")
		(net "M_F_ECC<7>")
	)
	(segment
		(start 247.284494 -88.480138)
		(end 247.290844 -88.490806)
		(width 0.0889)
		(layer "In4.Cu")
		(net "M_F_ECC<7>")
	)
	(segment
		(start 240.952528 -149.191472)
		(end 240.941606 -149.191472)
		(width 0.14224)
		(layer "In4.Cu")
		(net "M_F_ECC<7>")
	)
	(segment
		(start 246.965216 -100.927154)
		(end 246.965216 -101.734874)
		(width 0.0889)
		(layer "In4.Cu")
		(net "M_F_ECC<7>")
	)
	(segment
		(start 247.284494 -86.498938)
		(end 247.290844 -86.509606)
		(width 0.0889)
		(layer "In4.Cu")
		(net "M_F_ECC<7>")
	)
	(segment
		(start 240.977928 -144.169638)
		(end 241.121692 -144.313402)
		(width 0.14224)
		(layer "In4.Cu")
		(net "M_F_ECC<7>")
	)
	(segment
		(start 241.38255 -114.863626)
		(end 241.53749 -115.018566)
		(width 0.14224)
		(layer "In4.Cu")
		(net "M_F_ECC<7>")
	)
	(segment
		(start 241.297968 -113.159794)
		(end 241.53114 -113.392966)
		(width 0.14224)
		(layer "In4.Cu")
		(net "M_F_ECC<7>")
	)
	(segment
		(start 241.709956 -117.456966)
		(end 241.416586 -117.456966)
		(width 0.14224)
		(layer "In4.Cu")
		(net "M_F_ECC<7>")
	)
	(segment
		(start 241.275108 -117.598444)
		(end 241.275108 -118.101364)
		(width 0.14224)
		(layer "In4.Cu")
		(net "M_F_ECC<7>")
	)
	(segment
		(start 241.181128 -131.205478)
		(end 240.977928 -131.408678)
		(width 0.14224)
		(layer "In4.Cu")
		(net "M_F_ECC<7>")
	)
	(segment
		(start 247.279668 -91.443302)
		(end 247.284494 -91.451938)
		(width 0.0889)
		(layer "In4.Cu")
		(net "M_F_ECC<7>")
	)
	(segment
		(start 241.0206 -141.604746)
		(end 241.0206 -143.764)
		(width 0.14224)
		(layer "In4.Cu")
		(net "M_F_ECC<7>")
	)
	(segment
		(start 241.403124 -116.644166)
		(end 241.709956 -116.644166)
		(width 0.14224)
		(layer "In4.Cu")
		(net "M_F_ECC<7>")
	)
	(segment
		(start 247.703848 -102.580948)
		(end 247.703848 -105.952544)
		(width 0.14224)
		(layer "In4.Cu")
		(net "M_F_ECC<7>")
	)
	(segment
		(start 240.952528 -125.407928)
		(end 241.2746 -125.73)
		(width 0.14224)
		(layer "In4.Cu")
		(net "M_F_ECC<7>")
	)
	(segment
		(start 241.155728 -136.008872)
		(end 240.952528 -136.212072)
		(width 0.14224)
		(layer "In4.Cu")
		(net "M_F_ECC<7>")
	)
	(segment
		(start 247.219216 -100.673154)
		(end 246.965216 -100.927154)
		(width 0.0889)
		(layer "In4.Cu")
		(net "M_F_ECC<7>")
	)
	(segment
		(start 247.279668 -88.471502)
		(end 247.284494 -88.480138)
		(width 0.0889)
		(layer "In4.Cu")
		(net "M_F_ECC<7>")
	)
	(segment
		(start 241.181128 -139.689078)
		(end 241.181128 -140.806678)
		(width 0.14224)
		(layer "In4.Cu")
		(net "M_F_ECC<7>")
	)
	(segment
		(start 240.901728 -141.086078)
		(end 240.901728 -141.485874)
		(width 0.14224)
		(layer "In4.Cu")
		(net "M_F_ECC<7>")
	)
	(segment
		(start 240.901728 -141.485874)
		(end 241.0206 -141.604746)
		(width 0.14224)
		(layer "In4.Cu")
		(net "M_F_ECC<7>")
	)
	(arc
		(start 247.290844 -87.500206)
		(mid 247.363642 -87.790969)
		(end 247.284494 -88.080088)
		(width 0.0889)
		(layer "In4.Cu")
		(net "M_F_ECC<7>")
	)
	(arc
		(start 247.290844 -91.462606)
		(mid 247.363642 -91.753369)
		(end 247.284494 -92.042488)
		(width 0.0889)
		(layer "In4.Cu")
		(net "M_F_ECC<7>")
	)
	(arc
		(start 247.284494 -86.098888)
		(mid 247.231024 -86.293951)
		(end 247.279668 -86.490302)
		(width 0.0889)
		(layer "In4.Cu")
		(net "M_F_ECC<7>")
	)
	(arc
		(start 247.284494 -94.023688)
		(mid 247.230995 -94.223586)
		(end 247.284494 -94.423484)
		(width 0.0889)
		(layer "In4.Cu")
		(net "M_F_ECC<7>")
	)
	(arc
		(start 246.772684 -84.812886)
		(mid 247.004698 -85.068043)
		(end 247.196864 -85.354414)
		(width 0.0889)
		(layer "In4.Cu")
		(net "M_F_ECC<7>")
	)
	(arc
		(start 247.290844 -92.453206)
		(mid 247.363642 -92.743969)
		(end 247.284494 -93.033088)
		(width 0.0889)
		(layer "In4.Cu")
		(net "M_F_ECC<7>")
	)
	(arc
		(start 247.290844 -86.509606)
		(mid 247.363642 -86.800369)
		(end 247.284494 -87.089488)
		(width 0.0889)
		(layer "In4.Cu")
		(net "M_F_ECC<7>")
	)
	(arc
		(start 247.290844 -95.425006)
		(mid 247.363642 -95.715769)
		(end 247.284494 -96.004888)
		(width 0.0889)
		(layer "In4.Cu")
		(net "M_F_ECC<7>")
	)
	(arc
		(start 247.290844 -88.490806)
		(mid 247.363642 -88.781569)
		(end 247.284494 -89.070688)
		(width 0.0889)
		(layer "In4.Cu")
		(net "M_F_ECC<7>")
	)
	(arc
		(start 247.290844 -85.519006)
		(mid 247.363642 -85.809769)
		(end 247.284494 -86.098888)
		(width 0.0889)
		(layer "In4.Cu")
		(net "M_F_ECC<7>")
	)
	(arc
		(start 247.290844 -90.472006)
		(mid 247.363642 -90.762769)
		(end 247.284494 -91.051888)
		(width 0.0889)
		(layer "In4.Cu")
		(net "M_F_ECC<7>")
	)
	(arc
		(start 247.284494 -88.080088)
		(mid 247.231024 -88.275151)
		(end 247.279668 -88.471502)
		(width 0.0889)
		(layer "In4.Cu")
		(net "M_F_ECC<7>")
	)
	(arc
		(start 247.284494 -95.014288)
		(mid 247.231024 -95.209351)
		(end 247.279668 -95.405702)
		(width 0.0889)
		(layer "In4.Cu")
		(net "M_F_ECC<7>")
	)
	(arc
		(start 247.284494 -92.042488)
		(mid 247.231024 -92.237551)
		(end 247.279668 -92.433902)
		(width 0.0889)
		(layer "In4.Cu")
		(net "M_F_ECC<7>")
	)
	(arc
		(start 247.284494 -90.061288)
		(mid 247.231024 -90.256351)
		(end 247.279668 -90.452702)
		(width 0.0889)
		(layer "In4.Cu")
		(net "M_F_ECC<7>")
	)
	(arc
		(start 247.284494 -93.433138)
		(mid 247.363716 -93.722256)
		(end 247.290844 -94.01302)
		(width 0.0889)
		(layer "In4.Cu")
		(net "M_F_ECC<7>")
	)
	(arc
		(start 247.284494 -93.033088)
		(mid 247.231024 -93.228151)
		(end 247.279668 -93.424502)
		(width 0.0889)
		(layer "In4.Cu")
		(net "M_F_ECC<7>")
	)
	(arc
		(start 247.284494 -96.004888)
		(mid 247.231024 -96.199951)
		(end 247.279668 -96.396302)
		(width 0.0889)
		(layer "In4.Cu")
		(net "M_F_ECC<7>")
	)
	(arc
		(start 247.284494 -89.070688)
		(mid 247.231024 -89.265751)
		(end 247.279668 -89.462102)
		(width 0.0889)
		(layer "In4.Cu")
		(net "M_F_ECC<7>")
	)
	(arc
		(start 247.284494 -87.089488)
		(mid 247.231024 -87.284551)
		(end 247.279668 -87.480902)
		(width 0.0889)
		(layer "In4.Cu")
		(net "M_F_ECC<7>")
	)
	(arc
		(start 247.290844 -89.481406)
		(mid 247.363642 -89.772169)
		(end 247.284494 -90.061288)
		(width 0.0889)
		(layer "In4.Cu")
		(net "M_F_ECC<7>")
	)
	(arc
		(start 247.284494 -94.423484)
		(mid 247.363625 -94.718886)
		(end 247.284494 -95.014288)
		(width 0.0889)
		(layer "In4.Cu")
		(net "M_F_ECC<7>")
	)
	(arc
		(start 247.284494 -91.051888)
		(mid 247.231024 -91.246951)
		(end 247.279668 -91.443302)
		(width 0.0889)
		(layer "In4.Cu")
		(net "M_F_ECC<7>")
	)
	(segment
		(start 239.911128 -152.479248)
		(end 240.168176 -152.2222)
		(width 0.14224)
		(layer "In11.Cu")
		(net "M_F_ECC<7>")
	)
	(segment
		(start 240.193576 -150.435818)
		(end 240.149126 -150.391368)
		(width 0.14224)
		(layer "In11.Cu")
		(net "M_F_ECC<7>")
	)
	(segment
		(start 240.149126 -149.9616)
		(end 240.57737 -149.533356)
		(width 0.14224)
		(layer "In11.Cu")
		(net "M_F_ECC<7>")
	)
	(segment
		(start 240.57737 -149.533356)
		(end 240.599722 -149.533356)
		(width 0.14224)
		(layer "In11.Cu")
		(net "M_F_ECC<7>")
	)
	(segment
		(start 239.911128 -152.752552)
		(end 239.911128 -152.479248)
		(width 0.14224)
		(layer "In11.Cu")
		(net "M_F_ECC<7>")
	)
	(segment
		(start 240.199926 -153.364946)
		(end 240.199926 -153.04135)
		(width 0.14224)
		(layer "In11.Cu")
		(net "M_F_ECC<7>")
	)
	(segment
		(start 240.193576 -151.1046)
		(end 240.193576 -150.435818)
		(width 0.14224)
		(layer "In11.Cu")
		(net "M_F_ECC<7>")
	)
	(segment
		(start 239.911128 -151.387048)
		(end 240.193576 -151.1046)
		(width 0.14224)
		(layer "In11.Cu")
		(net "M_F_ECC<7>")
	)
	(segment
		(start 239.911128 -151.660352)
		(end 239.911128 -151.387048)
		(width 0.14224)
		(layer "In11.Cu")
		(net "M_F_ECC<7>")
	)
	(segment
		(start 239.749838 -153.542746)
		(end 240.022126 -153.542746)
		(width 0.14224)
		(layer "In11.Cu")
		(net "M_F_ECC<7>")
	)
	(segment
		(start 240.149126 -150.391368)
		(end 240.149126 -149.9616)
		(width 0.14224)
		(layer "In11.Cu")
		(net "M_F_ECC<7>")
	)
	(segment
		(start 240.168176 -151.9174)
		(end 239.911128 -151.660352)
		(width 0.14224)
		(layer "In11.Cu")
		(net "M_F_ECC<7>")
	)
	(segment
		(start 240.022126 -153.542746)
		(end 240.199926 -153.364946)
		(width 0.14224)
		(layer "In11.Cu")
		(net "M_F_ECC<7>")
	)
	(segment
		(start 240.199926 -153.04135)
		(end 239.911128 -152.752552)
		(width 0.14224)
		(layer "In11.Cu")
		(net "M_F_ECC<7>")
	)
	(segment
		(start 240.168176 -152.2222)
		(end 240.168176 -151.9174)
		(width 0.14224)
		(layer "In11.Cu")
		(net "M_F_ECC<7>")
	)
	(segment
		(start 240.732056 -155.45308)
		(end 240.599976 -155.321)
		(width 0.1651)
		(layer "F.Cu")
		(net "M_F_ECC<6>")
	)
	(segment
		(start 247.344184 -82.83194)
		(end 246.772684 -82.83194)
		(width 0.1651)
		(layer "F.Cu")
		(net "M_F_ECC<6>")
	)
	(segment
		(start 240.599976 -156.87294)
		(end 240.599976 -155.8036)
		(width 0.1651)
		(layer "F.Cu")
		(net "M_F_ECC<6>")
	)
	(segment
		(start 240.599976 -155.8036)
		(end 240.732056 -155.67152)
		(width 0.1651)
		(layer "F.Cu")
		(net "M_F_ECC<6>")
	)
	(segment
		(start 240.600484 -156.87294)
		(end 240.599976 -156.87294)
		(width 0.1651)
		(layer "F.Cu")
		(net "M_F_ECC<6>")
	)
	(segment
		(start 240.599976 -155.321)
		(end 240.599976 -155.118054)
		(width 0.1651)
		(layer "F.Cu")
		(net "M_F_ECC<6>")
	)
	(segment
		(start 240.599976 -155.118054)
		(end 240.599722 -155.1178)
		(width 0.1651)
		(layer "F.Cu")
		(net "M_F_ECC<6>")
	)
	(segment
		(start 240.732056 -155.67152)
		(end 240.732056 -155.45308)
		(width 0.1651)
		(layer "F.Cu")
		(net "M_F_ECC<6>")
	)
	(via
		(at 246.772684 -82.83194)
		(size 0.508)
		(drill 0.254)
		(layers "F.Cu" "B.Cu")
		(net "M_F_ECC<6>")
	)
	(via
		(at 239.749838 -150.814278)
		(size 0.508)
		(drill 0.254)
		(layers "F.Cu" "B.Cu")
		(net "M_F_ECC<6>")
	)
	(via
		(at 240.599722 -155.1178)
		(size 0.508)
		(drill 0.254)
		(layers "F.Cu" "B.Cu")
		(net "M_F_ECC<6>")
	)
	(segment
		(start 239.749838 -152.078182)
		(end 239.749838 -150.814278)
		(width 0.1651)
		(layer "B.Cu")
		(net "M_F_ECC<6>")
	)
	(segment
		(start 239.750346 -152.078436)
		(end 239.749838 -152.078182)
		(width 0.1651)
		(layer "B.Cu")
		(net "M_F_ECC<6>")
	)
	(segment
		(start 247.27916 -102.386384)
		(end 247.068848 -102.596696)
		(width 0.0889)
		(layer "In4.Cu")
		(net "M_F_ECC<6>")
	)
	(segment
		(start 247.119394 -88.575388)
		(end 247.12422 -88.584024)
		(width 0.0889)
		(layer "In4.Cu")
		(net "M_F_ECC<6>")
	)
	(segment
		(start 247.113044 -90.54592)
		(end 247.119394 -90.556588)
		(width 0.0889)
		(layer "In4.Cu")
		(net "M_F_ECC<6>")
	)
	(segment
		(start 247.218454 -97.712784)
		(end 247.029224 -97.902014)
		(width 0.0889)
		(layer "In4.Cu")
		(net "M_F_ECC<6>")
	)
	(segment
		(start 246.609616 -85.178392)
		(end 246.770144 -85.266022)
		(width 0.0889)
		(layer "In4.Cu")
		(net "M_F_ECC<6>")
	)
	(segment
		(start 247.27916 -102.31755)
		(end 247.27916 -102.386384)
		(width 0.0889)
		(layer "In4.Cu")
		(net "M_F_ECC<6>")
	)
	(segment
		(start 247.119394 -94.518988)
		(end 247.12422 -94.527624)
		(width 0.0889)
		(layer "In4.Cu")
		(net "M_F_ECC<6>")
	)
	(segment
		(start 239.994186 -145.534126)
		(end 240.291366 -145.831306)
		(width 0.14224)
		(layer "In4.Cu")
		(net "M_F_ECC<6>")
	)
	(segment
		(start 246.425974 -84.612988)
		(end 246.421148 -84.621624)
		(width 0.0889)
		(layer "In4.Cu")
		(net "M_F_ECC<6>")
	)
	(segment
		(start 246.775224 -101.813614)
		(end 247.27916 -102.31755)
		(width 0.0889)
		(layer "In4.Cu")
		(net "M_F_ECC<6>")
	)
	(segment
		(start 240.291366 -145.831306)
		(end 240.291366 -146.118834)
		(width 0.14224)
		(layer "In4.Cu")
		(net "M_F_ECC<6>")
	)
	(segment
		(start 247.068848 -102.596696)
		(end 247.068848 -105.6894)
		(width 0.14224)
		(layer "In4.Cu")
		(net "M_F_ECC<6>")
	)
	(segment
		(start 240.215928 -134.579868)
		(end 240.114328 -134.681468)
		(width 0.14224)
		(layer "In4.Cu")
		(net "M_F_ECC<6>")
	)
	(segment
		(start 240.678208 -118.167404)
		(end 239.0394 -119.806212)
		(width 0.14224)
		(layer "In4.Cu")
		(net "M_F_ECC<6>")
	)
	(segment
		(start 247.029224 -100.594414)
		(end 246.775224 -100.848414)
		(width 0.0889)
		(layer "In4.Cu")
		(net "M_F_ECC<6>")
	)
	(segment
		(start 240.227104 -129.949702)
		(end 240.114328 -130.062478)
		(width 0.14224)
		(layer "In4.Cu")
		(net "M_F_ECC<6>")
	)
	(segment
		(start 240.22685 -136.21385)
		(end 240.22685 -139.551156)
		(width 0.14224)
		(layer "In4.Cu")
		(net "M_F_ECC<6>")
	)
	(segment
		(start 240.266728 -143.746728)
		(end 240.266728 -144.118838)
		(width 0.14224)
		(layer "In4.Cu")
		(net "M_F_ECC<6>")
	)
	(segment
		(start 247.119394 -86.594188)
		(end 247.12422 -86.602824)
		(width 0.0889)
		(layer "In4.Cu")
		(net "M_F_ECC<6>")
	)
	(segment
		(start 246.425974 -83.622388)
		(end 246.421148 -83.631024)
		(width 0.0889)
		(layer "In4.Cu")
		(net "M_F_ECC<6>")
	)
	(segment
		(start 247.068086 -85.514688)
		(end 247.12422 -85.612224)
		(width 0.0889)
		(layer "In4.Cu")
		(net "M_F_ECC<6>")
	)
	(segment
		(start 240.1824 -125.5776)
		(end 240.1824 -127.3048)
		(width 0.14224)
		(layer "In4.Cu")
		(net "M_F_ECC<6>")
	)
	(segment
		(start 247.113044 -92.52712)
		(end 247.119394 -92.537788)
		(width 0.0889)
		(layer "In4.Cu")
		(net "M_F_ECC<6>")
	)
	(segment
		(start 246.442992 -83.593178)
		(end 246.425974 -83.622388)
		(width 0.0889)
		(layer "In4.Cu")
		(net "M_F_ECC<6>")
	)
	(segment
		(start 239.0394 -122.5296)
		(end 240.317528 -123.807728)
		(width 0.14224)
		(layer "In4.Cu")
		(net "M_F_ECC<6>")
	)
	(segment
		(start 246.770144 -85.266022)
		(end 247.068086 -85.514688)
		(width 0.0889)
		(layer "In4.Cu")
		(net "M_F_ECC<6>")
	)
	(segment
		(start 247.218454 -96.676718)
		(end 247.218454 -97.712784)
		(width 0.0889)
		(layer "In4.Cu")
		(net "M_F_ECC<6>")
	)
	(segment
		(start 247.113044 -91.53652)
		(end 247.119394 -91.547188)
		(width 0.0889)
		(layer "In4.Cu")
		(net "M_F_ECC<6>")
	)
	(segment
		(start 240.114328 -134.681468)
		(end 240.114328 -136.101328)
		(width 0.14224)
		(layer "In4.Cu")
		(net "M_F_ECC<6>")
	)
	(segment
		(start 240.266728 -141.5288)
		(end 240.1824 -141.613128)
		(width 0.14224)
		(layer "In4.Cu")
		(net "M_F_ECC<6>")
	)
	(segment
		(start 240.1824 -143.6624)
		(end 240.266728 -143.746728)
		(width 0.14224)
		(layer "In4.Cu")
		(net "M_F_ECC<6>")
	)
	(segment
		(start 247.029224 -97.902014)
		(end 247.029224 -100.594414)
		(width 0.0889)
		(layer "In4.Cu")
		(net "M_F_ECC<6>")
	)
	(segment
		(start 240.114328 -140.908278)
		(end 240.266728 -141.060678)
		(width 0.14224)
		(layer "In4.Cu")
		(net "M_F_ECC<6>")
	)
	(segment
		(start 239.6236 -150.68804)
		(end 239.749838 -150.814278)
		(width 0.14224)
		(layer "In4.Cu")
		(net "M_F_ECC<6>")
	)
	(segment
		(start 240.114328 -131.307078)
		(end 240.215928 -131.408678)
		(width 0.14224)
		(layer "In4.Cu")
		(net "M_F_ECC<6>")
	)
	(segment
		(start 247.119394 -89.565988)
		(end 247.12422 -89.574624)
		(width 0.0889)
		(layer "In4.Cu")
		(net "M_F_ECC<6>")
	)
	(segment
		(start 240.678208 -112.08004)
		(end 240.678208 -118.167404)
		(width 0.14224)
		(layer "In4.Cu")
		(net "M_F_ECC<6>")
	)
	(segment
		(start 240.215928 -131.408678)
		(end 240.215928 -134.579868)
		(width 0.14224)
		(layer "In4.Cu")
		(net "M_F_ECC<6>")
	)
	(segment
		(start 240.114328 -139.663678)
		(end 240.114328 -140.908278)
		(width 0.14224)
		(layer "In4.Cu")
		(net "M_F_ECC<6>")
	)
	(segment
		(start 240.317528 -123.807728)
		(end 240.317528 -125.442472)
		(width 0.14224)
		(layer "In4.Cu")
		(net "M_F_ECC<6>")
	)
	(segment
		(start 239.994186 -144.39138)
		(end 239.994186 -145.534126)
		(width 0.14224)
		(layer "In4.Cu")
		(net "M_F_ECC<6>")
	)
	(segment
		(start 247.119394 -91.547188)
		(end 247.12422 -91.555824)
		(width 0.0889)
		(layer "In4.Cu")
		(net "M_F_ECC<6>")
	)
	(segment
		(start 246.775224 -100.848414)
		(end 246.775224 -101.813614)
		(width 0.0889)
		(layer "In4.Cu")
		(net "M_F_ECC<6>")
	)
	(segment
		(start 247.113044 -95.49892)
		(end 247.119394 -95.509588)
		(width 0.0889)
		(layer "In4.Cu")
		(net "M_F_ECC<6>")
	)
	(segment
		(start 247.119394 -95.509588)
		(end 247.12422 -95.518224)
		(width 0.0889)
		(layer "In4.Cu")
		(net "M_F_ECC<6>")
	)
	(segment
		(start 240.1824 -141.613128)
		(end 240.1824 -143.6624)
		(width 0.14224)
		(layer "In4.Cu")
		(net "M_F_ECC<6>")
	)
	(segment
		(start 247.119394 -93.928438)
		(end 247.113044 -93.939106)
		(width 0.0889)
		(layer "In4.Cu")
		(net "M_F_ECC<6>")
	)
	(segment
		(start 247.113044 -86.58352)
		(end 247.119394 -86.594188)
		(width 0.0889)
		(layer "In4.Cu")
		(net "M_F_ECC<6>")
	)
	(segment
		(start 240.1824 -148.4376)
		(end 240.317528 -148.572728)
		(width 0.14224)
		(layer "In4.Cu")
		(net "M_F_ECC<6>")
	)
	(segment
		(start 247.119394 -87.584788)
		(end 247.12422 -87.593424)
		(width 0.0889)
		(layer "In4.Cu")
		(net "M_F_ECC<6>")
	)
	(segment
		(start 240.114328 -136.101328)
		(end 240.22685 -136.21385)
		(width 0.14224)
		(layer "In4.Cu")
		(net "M_F_ECC<6>")
	)
	(segment
		(start 240.114328 -130.062478)
		(end 240.114328 -131.307078)
		(width 0.14224)
		(layer "In4.Cu")
		(net "M_F_ECC<6>")
	)
	(segment
		(start 240.227104 -127.349504)
		(end 240.227104 -129.949702)
		(width 0.14224)
		(layer "In4.Cu")
		(net "M_F_ECC<6>")
	)
	(segment
		(start 247.119394 -92.537788)
		(end 247.12422 -92.546424)
		(width 0.0889)
		(layer "In4.Cu")
		(net "M_F_ECC<6>")
	)
	(segment
		(start 240.266728 -141.060678)
		(end 240.266728 -141.5288)
		(width 0.14224)
		(layer "In4.Cu")
		(net "M_F_ECC<6>")
	)
	(segment
		(start 240.291366 -146.118834)
		(end 240.1824 -146.2278)
		(width 0.14224)
		(layer "In4.Cu")
		(net "M_F_ECC<6>")
	)
	(segment
		(start 239.6236 -149.628606)
		(end 239.6236 -150.68804)
		(width 0.14224)
		(layer "In4.Cu")
		(net "M_F_ECC<6>")
	)
	(segment
		(start 240.1824 -146.2278)
		(end 240.1824 -148.4376)
		(width 0.14224)
		(layer "In4.Cu")
		(net "M_F_ECC<6>")
	)
	(segment
		(start 240.317528 -148.934678)
		(end 239.6236 -149.628606)
		(width 0.14224)
		(layer "In4.Cu")
		(net "M_F_ECC<6>")
	)
	(segment
		(start 247.113044 -87.57412)
		(end 247.119394 -87.584788)
		(width 0.0889)
		(layer "In4.Cu")
		(net "M_F_ECC<6>")
	)
	(segment
		(start 247.068848 -105.6894)
		(end 240.678208 -112.08004)
		(width 0.14224)
		(layer "In4.Cu")
		(net "M_F_ECC<6>")
	)
	(segment
		(start 247.113044 -89.55532)
		(end 247.119394 -89.565988)
		(width 0.0889)
		(layer "In4.Cu")
		(net "M_F_ECC<6>")
	)
	(segment
		(start 246.772684 -82.83194)
		(end 246.442992 -83.593178)
		(width 0.0889)
		(layer "In4.Cu")
		(net "M_F_ECC<6>")
	)
	(segment
		(start 240.1824 -127.3048)
		(end 240.227104 -127.349504)
		(width 0.14224)
		(layer "In4.Cu")
		(net "M_F_ECC<6>")
	)
	(segment
		(start 246.432324 -84.60232)
		(end 246.425974 -84.612988)
		(width 0.0889)
		(layer "In4.Cu")
		(net "M_F_ECC<6>")
	)
	(segment
		(start 240.266728 -144.118838)
		(end 239.994186 -144.39138)
		(width 0.14224)
		(layer "In4.Cu")
		(net "M_F_ECC<6>")
	)
	(segment
		(start 247.113044 -88.56472)
		(end 247.119394 -88.575388)
		(width 0.0889)
		(layer "In4.Cu")
		(net "M_F_ECC<6>")
	)
	(segment
		(start 240.317528 -148.572728)
		(end 240.317528 -148.934678)
		(width 0.14224)
		(layer "In4.Cu")
		(net "M_F_ECC<6>")
	)
	(segment
		(start 240.22685 -139.551156)
		(end 240.114328 -139.663678)
		(width 0.14224)
		(layer "In4.Cu")
		(net "M_F_ECC<6>")
	)
	(segment
		(start 247.119394 -90.556588)
		(end 247.12422 -90.565224)
		(width 0.0889)
		(layer "In4.Cu")
		(net "M_F_ECC<6>")
	)
	(segment
		(start 240.317528 -125.442472)
		(end 240.1824 -125.5776)
		(width 0.14224)
		(layer "In4.Cu")
		(net "M_F_ECC<6>")
	)
	(segment
		(start 247.113044 -96.48952)
		(end 247.218454 -96.676718)
		(width 0.0889)
		(layer "In4.Cu")
		(net "M_F_ECC<6>")
	)
	(segment
		(start 239.0394 -119.806212)
		(end 239.0394 -122.5296)
		(width 0.14224)
		(layer "In4.Cu")
		(net "M_F_ECC<6>")
	)
	(arc
		(start 247.119394 -90.956638)
		(mid 247.040172 -91.245756)
		(end 247.113044 -91.53652)
		(width 0.0889)
		(layer "In4.Cu")
		(net "M_F_ECC<6>")
	)
	(arc
		(start 247.12422 -91.555824)
		(mid 247.172975 -91.752176)
		(end 247.119394 -91.947238)
		(width 0.0889)
		(layer "In4.Cu")
		(net "M_F_ECC<6>")
	)
	(arc
		(start 247.12422 -94.527624)
		(mid 247.172975 -94.723976)
		(end 247.119394 -94.919038)
		(width 0.0889)
		(layer "In4.Cu")
		(net "M_F_ECC<6>")
	)
	(arc
		(start 246.425974 -84.022438)
		(mid 246.505196 -84.311556)
		(end 246.432324 -84.60232)
		(width 0.0889)
		(layer "In4.Cu")
		(net "M_F_ECC<6>")
	)
	(arc
		(start 247.119394 -87.984838)
		(mid 247.040172 -88.273956)
		(end 247.113044 -88.56472)
		(width 0.0889)
		(layer "In4.Cu")
		(net "M_F_ECC<6>")
	)
	(arc
		(start 247.119394 -92.937838)
		(mid 247.040263 -93.23324)
		(end 247.119394 -93.528642)
		(width 0.0889)
		(layer "In4.Cu")
		(net "M_F_ECC<6>")
	)
	(arc
		(start 247.12422 -88.584024)
		(mid 247.172975 -88.780376)
		(end 247.119394 -88.975438)
		(width 0.0889)
		(layer "In4.Cu")
		(net "M_F_ECC<6>")
	)
	(arc
		(start 247.119394 -89.966038)
		(mid 247.040172 -90.255156)
		(end 247.113044 -90.54592)
		(width 0.0889)
		(layer "In4.Cu")
		(net "M_F_ECC<6>")
	)
	(arc
		(start 247.12422 -90.565224)
		(mid 247.172975 -90.761576)
		(end 247.119394 -90.956638)
		(width 0.0889)
		(layer "In4.Cu")
		(net "M_F_ECC<6>")
	)
	(arc
		(start 247.12422 -92.546424)
		(mid 247.172975 -92.742776)
		(end 247.119394 -92.937838)
		(width 0.0889)
		(layer "In4.Cu")
		(net "M_F_ECC<6>")
	)
	(arc
		(start 247.12422 -95.518224)
		(mid 247.172975 -95.714576)
		(end 247.119394 -95.909638)
		(width 0.0889)
		(layer "In4.Cu")
		(net "M_F_ECC<6>")
	)
	(arc
		(start 247.12422 -85.612224)
		(mid 247.172975 -85.808576)
		(end 247.119394 -86.003638)
		(width 0.0889)
		(layer "In4.Cu")
		(net "M_F_ECC<6>")
	)
	(arc
		(start 247.12422 -89.574624)
		(mid 247.172975 -89.770976)
		(end 247.119394 -89.966038)
		(width 0.0889)
		(layer "In4.Cu")
		(net "M_F_ECC<6>")
	)
	(arc
		(start 247.119394 -93.528642)
		(mid 247.172893 -93.72854)
		(end 247.119394 -93.928438)
		(width 0.0889)
		(layer "In4.Cu")
		(net "M_F_ECC<6>")
	)
	(arc
		(start 247.119394 -86.003638)
		(mid 247.040172 -86.292756)
		(end 247.113044 -86.58352)
		(width 0.0889)
		(layer "In4.Cu")
		(net "M_F_ECC<6>")
	)
	(arc
		(start 247.119394 -88.975438)
		(mid 247.040172 -89.264556)
		(end 247.113044 -89.55532)
		(width 0.0889)
		(layer "In4.Cu")
		(net "M_F_ECC<6>")
	)
	(arc
		(start 246.421148 -84.621624)
		(mid 246.39362 -84.941217)
		(end 246.609616 -85.178392)
		(width 0.0889)
		(layer "In4.Cu")
		(net "M_F_ECC<6>")
	)
	(arc
		(start 247.119394 -91.947238)
		(mid 247.040172 -92.236356)
		(end 247.113044 -92.52712)
		(width 0.0889)
		(layer "In4.Cu")
		(net "M_F_ECC<6>")
	)
	(arc
		(start 247.119394 -94.919038)
		(mid 247.040172 -95.208156)
		(end 247.113044 -95.49892)
		(width 0.0889)
		(layer "In4.Cu")
		(net "M_F_ECC<6>")
	)
	(arc
		(start 246.421148 -83.631024)
		(mid 246.372393 -83.827376)
		(end 246.425974 -84.022438)
		(width 0.0889)
		(layer "In4.Cu")
		(net "M_F_ECC<6>")
	)
	(arc
		(start 247.119394 -95.909638)
		(mid 247.040172 -96.198756)
		(end 247.113044 -96.48952)
		(width 0.0889)
		(layer "In4.Cu")
		(net "M_F_ECC<6>")
	)
	(arc
		(start 247.113044 -93.939106)
		(mid 247.040246 -94.229869)
		(end 247.119394 -94.518988)
		(width 0.0889)
		(layer "In4.Cu")
		(net "M_F_ECC<6>")
	)
	(arc
		(start 247.12422 -87.593424)
		(mid 247.172975 -87.789776)
		(end 247.119394 -87.984838)
		(width 0.0889)
		(layer "In4.Cu")
		(net "M_F_ECC<6>")
	)
	(arc
		(start 247.12422 -86.602824)
		(mid 247.172975 -86.799176)
		(end 247.119394 -86.994238)
		(width 0.0889)
		(layer "In4.Cu")
		(net "M_F_ECC<6>")
	)
	(arc
		(start 247.119394 -86.994238)
		(mid 247.040172 -87.283356)
		(end 247.113044 -87.57412)
		(width 0.0889)
		(layer "In4.Cu")
		(net "M_F_ECC<6>")
	)
	(segment
		(start 239.316768 -151.247348)
		(end 239.749838 -150.814278)
		(width 0.14224)
		(layer "In11.Cu")
		(net "M_F_ECC<6>")
	)
	(segment
		(start 239.316768 -153.834846)
		(end 239.316768 -151.247348)
		(width 0.14224)
		(layer "In11.Cu")
		(net "M_F_ECC<6>")
	)
	(segment
		(start 240.599722 -155.1178)
		(end 239.316768 -153.834846)
		(width 0.14224)
		(layer "In11.Cu")
		(net "M_F_ECC<6>")
	)
	(segment
		(start 233.799888 -152.278842)
		(end 233.799888 -153.542746)
		(width 0.1651)
		(layer "F.Cu")
		(net "M_F_ECC<5>")
	)
	(segment
		(start 244.768624 -84.31784)
		(end 244.197124 -84.31784)
		(width 0.1651)
		(layer "F.Cu")
		(net "M_F_ECC<5>")
	)
	(segment
		(start 233.800396 -152.273)
		(end 233.799888 -152.278842)
		(width 0.1651)
		(layer "F.Cu")
		(net "M_F_ECC<5>")
	)
	(via
		(at 233.799888 -153.542746)
		(size 0.508)
		(drill 0.254)
		(layers "F.Cu" "B.Cu")
		(net "M_F_ECC<5>")
	)
	(via
		(at 234.573572 -149.533356)
		(size 0.508)
		(drill 0.254)
		(layers "F.Cu" "B.Cu")
		(net "M_F_ECC<5>")
	)
	(via
		(at 244.197124 -84.31784)
		(size 0.508)
		(drill 0.254)
		(layers "F.Cu" "B.Cu")
		(net "M_F_ECC<5>")
	)
	(segment
		(start 234.649772 -149.457156)
		(end 234.649772 -147.478496)
		(width 0.1651)
		(layer "B.Cu")
		(net "M_F_ECC<5>")
	)
	(segment
		(start 234.573572 -149.533356)
		(end 234.649772 -149.457156)
		(width 0.1651)
		(layer "B.Cu")
		(net "M_F_ECC<5>")
	)
	(segment
		(start 234.649772 -147.478496)
		(end 234.65028 -147.478496)
		(width 0.1651)
		(layer "B.Cu")
		(net "M_F_ECC<5>")
	)
	(segment
		(start 243.845588 -96.396302)
		(end 243.850414 -96.404938)
		(width 0.0889)
		(layer "In4.Cu")
		(net "M_F_ECC<5>")
	)
	(segment
		(start 234.958128 -145.607024)
		(end 234.958128 -146.235928)
		(width 0.14224)
		(layer "In4.Cu")
		(net "M_F_ECC<5>")
	)
	(segment
		(start 234.983528 -131.8514)
		(end 235.077 -131.944872)
		(width 0.14224)
		(layer "In4.Cu")
		(net "M_F_ECC<5>")
	)
	(segment
		(start 235.2294 -125.603)
		(end 235.0516 -125.7808)
		(width 0.14224)
		(layer "In4.Cu")
		(net "M_F_ECC<5>")
	)
	(segment
		(start 243.928646 -98.518472)
		(end 243.928646 -98.992436)
		(width 0.0889)
		(layer "In4.Cu")
		(net "M_F_ECC<5>")
	)
	(segment
		(start 234.983528 -143.781272)
		(end 234.983528 -144.271238)
		(width 0.14224)
		(layer "In4.Cu")
		(net "M_F_ECC<5>")
	)
	(segment
		(start 235.077 -148.4376)
		(end 234.958128 -148.556472)
		(width 0.14224)
		(layer "In4.Cu")
		(net "M_F_ECC<5>")
	)
	(segment
		(start 243.845588 -92.433902)
		(end 243.850414 -92.442538)
		(width 0.0889)
		(layer "In4.Cu")
		(net "M_F_ECC<5>")
	)
	(segment
		(start 234.958128 -139.41679)
		(end 235.047028 -139.50569)
		(width 0.14224)
		(layer "In4.Cu")
		(net "M_F_ECC<5>")
	)
	(segment
		(start 235.077 -146.3548)
		(end 235.077 -148.4376)
		(width 0.14224)
		(layer "In4.Cu")
		(net "M_F_ECC<5>")
	)
	(segment
		(start 234.983528 -144.271238)
		(end 235.110528 -144.398238)
		(width 0.14224)
		(layer "In4.Cu")
		(net "M_F_ECC<5>")
	)
	(segment
		(start 234.165394 -119.496586)
		(end 234.165394 -119.999506)
		(width 0.14224)
		(layer "In4.Cu")
		(net "M_F_ECC<5>")
	)
	(segment
		(start 235.1532 -119.186706)
		(end 234.99826 -119.341646)
		(width 0.14224)
		(layer "In4.Cu")
		(net "M_F_ECC<5>")
	)
	(segment
		(start 235.077 -141.546072)
		(end 235.077 -143.6878)
		(width 0.14224)
		(layer "In4.Cu")
		(net "M_F_ECC<5>")
	)
	(segment
		(start 234.994196 -128.632204)
		(end 234.994196 -129.930906)
		(width 0.14224)
		(layer "In4.Cu")
		(net "M_F_ECC<5>")
	)
	(segment
		(start 235.077 -143.6878)
		(end 234.983528 -143.781272)
		(width 0.14224)
		(layer "In4.Cu")
		(net "M_F_ECC<5>")
	)
	(segment
		(start 235.073952 -122.969528)
		(end 235.2294 -123.124976)
		(width 0.14224)
		(layer "In4.Cu")
		(net "M_F_ECC<5>")
	)
	(segment
		(start 235.0516 -128.5748)
		(end 234.994196 -128.632204)
		(width 0.14224)
		(layer "In4.Cu")
		(net "M_F_ECC<5>")
	)
	(segment
		(start 243.850414 -90.461338)
		(end 243.856764 -90.472006)
		(width 0.0889)
		(layer "In4.Cu")
		(net "M_F_ECC<5>")
	)
	(segment
		(start 234.320334 -120.154446)
		(end 234.99826 -120.154446)
		(width 0.14224)
		(layer "In4.Cu")
		(net "M_F_ECC<5>")
	)
	(segment
		(start 234.958128 -136.525)
		(end 235.077 -136.643872)
		(width 0.14224)
		(layer "In4.Cu")
		(net "M_F_ECC<5>")
	)
	(segment
		(start 235.0516 -125.7808)
		(end 235.0516 -128.5748)
		(width 0.14224)
		(layer "In4.Cu")
		(net "M_F_ECC<5>")
	)
	(segment
		(start 243.845588 -90.452702)
		(end 243.850414 -90.461338)
		(width 0.0889)
		(layer "In4.Cu")
		(net "M_F_ECC<5>")
	)
	(segment
		(start 234.95 -122.156728)
		(end 234.121198 -122.156728)
		(width 0.14224)
		(layer "In4.Cu")
		(net "M_F_ECC<5>")
	)
	(segment
		(start 243.850414 -89.470738)
		(end 243.856764 -89.481406)
		(width 0.0889)
		(layer "In4.Cu")
		(net "M_F_ECC<5>")
	)
	(segment
		(start 243.845588 -93.424502)
		(end 243.850414 -93.433138)
		(width 0.0889)
		(layer "In4.Cu")
		(net "M_F_ECC<5>")
	)
	(segment
		(start 235.047028 -129.983738)
		(end 235.047028 -131.370578)
		(width 0.14224)
		(layer "In4.Cu")
		(net "M_F_ECC<5>")
	)
	(segment
		(start 243.845588 -85.499702)
		(end 243.850414 -85.508338)
		(width 0.0889)
		(layer "In4.Cu")
		(net "M_F_ECC<5>")
	)
	(segment
		(start 235.1532 -112.0648)
		(end 235.1532 -119.186706)
		(width 0.14224)
		(layer "In4.Cu")
		(net "M_F_ECC<5>")
	)
	(segment
		(start 234.165394 -119.999506)
		(end 234.320334 -120.154446)
		(width 0.14224)
		(layer "In4.Cu")
		(net "M_F_ECC<5>")
	)
	(segment
		(start 243.850414 -97.395538)
		(end 243.856764 -97.406206)
		(width 0.0889)
		(layer "In4.Cu")
		(net "M_F_ECC<5>")
	)
	(segment
		(start 243.928646 -98.992436)
		(end 243.104162 -99.81692)
		(width 0.0889)
		(layer "In4.Cu")
		(net "M_F_ECC<5>")
	)
	(segment
		(start 243.845588 -95.405702)
		(end 243.850414 -95.414338)
		(width 0.0889)
		(layer "In4.Cu")
		(net "M_F_ECC<5>")
	)
	(segment
		(start 235.110528 -145.454624)
		(end 234.958128 -145.607024)
		(width 0.14224)
		(layer "In4.Cu")
		(net "M_F_ECC<5>")
	)
	(segment
		(start 234.994196 -129.930906)
		(end 235.047028 -129.983738)
		(width 0.14224)
		(layer "In4.Cu")
		(net "M_F_ECC<5>")
	)
	(segment
		(start 235.047028 -140.971778)
		(end 234.983528 -141.035278)
		(width 0.14224)
		(layer "In4.Cu")
		(net "M_F_ECC<5>")
	)
	(segment
		(start 243.104162 -100.470208)
		(end 242.748816 -100.825554)
		(width 0.0889)
		(layer "In4.Cu")
		(net "M_F_ECC<5>")
	)
	(segment
		(start 235.077 -136.643872)
		(end 235.077 -138.8364)
		(width 0.14224)
		(layer "In4.Cu")
		(net "M_F_ECC<5>")
	)
	(segment
		(start 234.320334 -119.341646)
		(end 234.165394 -119.496586)
		(width 0.14224)
		(layer "In4.Cu")
		(net "M_F_ECC<5>")
	)
	(segment
		(start 234.121198 -122.156728)
		(end 233.93146 -122.346466)
		(width 0.14224)
		(layer "In4.Cu")
		(net "M_F_ECC<5>")
	)
	(segment
		(start 243.845588 -98.377502)
		(end 243.856764 -98.397568)
		(width 0.0889)
		(layer "In4.Cu")
		(net "M_F_ECC<5>")
	)
	(segment
		(start 243.850414 -92.442538)
		(end 243.856764 -92.453206)
		(width 0.0889)
		(layer "In4.Cu")
		(net "M_F_ECC<5>")
	)
	(segment
		(start 235.1532 -120.309386)
		(end 235.1532 -121.953528)
		(width 0.14224)
		(layer "In4.Cu")
		(net "M_F_ECC<5>")
	)
	(segment
		(start 234.958128 -148.556472)
		(end 234.958128 -149.1488)
		(width 0.14224)
		(layer "In4.Cu")
		(net "M_F_ECC<5>")
	)
	(segment
		(start 243.850414 -95.414338)
		(end 243.856764 -95.425006)
		(width 0.0889)
		(layer "In4.Cu")
		(net "M_F_ECC<5>")
	)
	(segment
		(start 234.983528 -134.617968)
		(end 235.047028 -134.681468)
		(width 0.14224)
		(layer "In4.Cu")
		(net "M_F_ECC<5>")
	)
	(segment
		(start 234.99826 -120.154446)
		(end 235.1532 -120.309386)
		(width 0.14224)
		(layer "In4.Cu")
		(net "M_F_ECC<5>")
	)
	(segment
		(start 243.845588 -88.471502)
		(end 243.850414 -88.480138)
		(width 0.0889)
		(layer "In4.Cu")
		(net "M_F_ECC<5>")
	)
	(segment
		(start 233.93146 -122.752866)
		(end 234.148122 -122.969528)
		(width 0.14224)
		(layer "In4.Cu")
		(net "M_F_ECC<5>")
	)
	(segment
		(start 243.856764 -98.397568)
		(end 243.928646 -98.518472)
		(width 0.0889)
		(layer "In4.Cu")
		(net "M_F_ECC<5>")
	)
	(segment
		(start 243.856764 -94.01302)
		(end 243.850414 -94.023688)
		(width 0.0889)
		(layer "In4.Cu")
		(net "M_F_ECC<5>")
	)
	(segment
		(start 244.197124 -84.31784)
		(end 243.867178 -85.079586)
		(width 0.0889)
		(layer "In4.Cu")
		(net "M_F_ECC<5>")
	)
	(segment
		(start 235.110528 -144.398238)
		(end 235.110528 -145.454624)
		(width 0.14224)
		(layer "In4.Cu")
		(net "M_F_ECC<5>")
	)
	(segment
		(start 243.850414 -86.498938)
		(end 243.856764 -86.509606)
		(width 0.0889)
		(layer "In4.Cu")
		(net "M_F_ECC<5>")
	)
	(segment
		(start 235.077 -134.0104)
		(end 234.983528 -134.103872)
		(width 0.14224)
		(layer "In4.Cu")
		(net "M_F_ECC<5>")
	)
	(segment
		(start 234.983528 -141.035278)
		(end 234.983528 -141.4526)
		(width 0.14224)
		(layer "In4.Cu")
		(net "M_F_ECC<5>")
	)
	(segment
		(start 243.845588 -89.462102)
		(end 243.850414 -89.470738)
		(width 0.0889)
		(layer "In4.Cu")
		(net "M_F_ECC<5>")
	)
	(segment
		(start 243.850414 -96.404938)
		(end 243.856764 -96.415606)
		(width 0.0889)
		(layer "In4.Cu")
		(net "M_F_ECC<5>")
	)
	(segment
		(start 242.748816 -101.443282)
		(end 242.984782 -101.679248)
		(width 0.0889)
		(layer "In4.Cu")
		(net "M_F_ECC<5>")
	)
	(segment
		(start 235.077 -138.8364)
		(end 234.958128 -138.955272)
		(width 0.14224)
		(layer "In4.Cu")
		(net "M_F_ECC<5>")
	)
	(segment
		(start 243.845588 -86.490302)
		(end 243.850414 -86.498938)
		(width 0.0889)
		(layer "In4.Cu")
		(net "M_F_ECC<5>")
	)
	(segment
		(start 243.850414 -91.451938)
		(end 243.856764 -91.462606)
		(width 0.0889)
		(layer "In4.Cu")
		(net "M_F_ECC<5>")
	)
	(segment
		(start 235.2294 -123.124976)
		(end 235.2294 -125.603)
		(width 0.14224)
		(layer "In4.Cu")
		(net "M_F_ECC<5>")
	)
	(segment
		(start 234.958128 -149.1488)
		(end 234.573572 -149.533356)
		(width 0.14224)
		(layer "In4.Cu")
		(net "M_F_ECC<5>")
	)
	(segment
		(start 243.850414 -87.489538)
		(end 243.856764 -87.500206)
		(width 0.0889)
		(layer "In4.Cu")
		(net "M_F_ECC<5>")
	)
	(segment
		(start 235.047028 -134.681468)
		(end 235.047028 -135.938768)
		(width 0.14224)
		(layer "In4.Cu")
		(net "M_F_ECC<5>")
	)
	(segment
		(start 242.984782 -101.679248)
		(end 242.984782 -104.233218)
		(width 0.14224)
		(layer "In4.Cu")
		(net "M_F_ECC<5>")
	)
	(segment
		(start 235.047028 -135.938768)
		(end 234.958128 -136.027668)
		(width 0.14224)
		(layer "In4.Cu")
		(net "M_F_ECC<5>")
	)
	(segment
		(start 234.958128 -146.235928)
		(end 235.077 -146.3548)
		(width 0.14224)
		(layer "In4.Cu")
		(net "M_F_ECC<5>")
	)
	(segment
		(start 234.958128 -138.955272)
		(end 234.958128 -139.41679)
		(width 0.14224)
		(layer "In4.Cu")
		(net "M_F_ECC<5>")
	)
	(segment
		(start 234.99826 -119.341646)
		(end 234.320334 -119.341646)
		(width 0.14224)
		(layer "In4.Cu")
		(net "M_F_ECC<5>")
	)
	(segment
		(start 242.984782 -104.233218)
		(end 235.1532 -112.0648)
		(width 0.14224)
		(layer "In4.Cu")
		(net "M_F_ECC<5>")
	)
	(segment
		(start 234.983528 -131.434078)
		(end 234.983528 -131.8514)
		(width 0.14224)
		(layer "In4.Cu")
		(net "M_F_ECC<5>")
	)
	(segment
		(start 234.148122 -122.969528)
		(end 235.073952 -122.969528)
		(width 0.14224)
		(layer "In4.Cu")
		(net "M_F_ECC<5>")
	)
	(segment
		(start 233.93146 -122.346466)
		(end 233.93146 -122.752866)
		(width 0.14224)
		(layer "In4.Cu")
		(net "M_F_ECC<5>")
	)
	(segment
		(start 235.077 -131.944872)
		(end 235.077 -134.0104)
		(width 0.14224)
		(layer "In4.Cu")
		(net "M_F_ECC<5>")
	)
	(segment
		(start 243.845588 -91.443302)
		(end 243.850414 -91.451938)
		(width 0.0889)
		(layer "In4.Cu")
		(net "M_F_ECC<5>")
	)
	(segment
		(start 234.983528 -141.4526)
		(end 235.077 -141.546072)
		(width 0.14224)
		(layer "In4.Cu")
		(net "M_F_ECC<5>")
	)
	(segment
		(start 243.845588 -87.480902)
		(end 243.850414 -87.489538)
		(width 0.0889)
		(layer "In4.Cu")
		(net "M_F_ECC<5>")
	)
	(segment
		(start 235.047028 -131.370578)
		(end 234.983528 -131.434078)
		(width 0.14224)
		(layer "In4.Cu")
		(net "M_F_ECC<5>")
	)
	(segment
		(start 234.958128 -136.027668)
		(end 234.958128 -136.525)
		(width 0.14224)
		(layer "In4.Cu")
		(net "M_F_ECC<5>")
	)
	(segment
		(start 243.867178 -85.079586)
		(end 243.850414 -85.108288)
		(width 0.0889)
		(layer "In4.Cu")
		(net "M_F_ECC<5>")
	)
	(segment
		(start 243.850414 -85.508338)
		(end 243.856764 -85.519006)
		(width 0.0889)
		(layer "In4.Cu")
		(net "M_F_ECC<5>")
	)
	(segment
		(start 243.104162 -99.81692)
		(end 243.104162 -100.470208)
		(width 0.0889)
		(layer "In4.Cu")
		(net "M_F_ECC<5>")
	)
	(segment
		(start 235.1532 -121.953528)
		(end 234.95 -122.156728)
		(width 0.14224)
		(layer "In4.Cu")
		(net "M_F_ECC<5>")
	)
	(segment
		(start 243.850414 -88.480138)
		(end 243.856764 -88.490806)
		(width 0.0889)
		(layer "In4.Cu")
		(net "M_F_ECC<5>")
	)
	(segment
		(start 243.845588 -97.386902)
		(end 243.850414 -97.395538)
		(width 0.0889)
		(layer "In4.Cu")
		(net "M_F_ECC<5>")
	)
	(segment
		(start 234.983528 -134.103872)
		(end 234.983528 -134.617968)
		(width 0.14224)
		(layer "In4.Cu")
		(net "M_F_ECC<5>")
	)
	(segment
		(start 242.748816 -100.825554)
		(end 242.748816 -101.443282)
		(width 0.0889)
		(layer "In4.Cu")
		(net "M_F_ECC<5>")
	)
	(segment
		(start 235.047028 -139.50569)
		(end 235.047028 -140.971778)
		(width 0.14224)
		(layer "In4.Cu")
		(net "M_F_ECC<5>")
	)
	(arc
		(start 243.856764 -96.415606)
		(mid 243.929562 -96.706369)
		(end 243.850414 -96.995488)
		(width 0.0889)
		(layer "In4.Cu")
		(net "M_F_ECC<5>")
	)
	(arc
		(start 243.850414 -87.089488)
		(mid 243.796944 -87.284551)
		(end 243.845588 -87.480902)
		(width 0.0889)
		(layer "In4.Cu")
		(net "M_F_ECC<5>")
	)
	(arc
		(start 243.850414 -91.051888)
		(mid 243.796944 -91.246951)
		(end 243.845588 -91.443302)
		(width 0.0889)
		(layer "In4.Cu")
		(net "M_F_ECC<5>")
	)
	(arc
		(start 243.850414 -95.014288)
		(mid 243.796944 -95.209351)
		(end 243.845588 -95.405702)
		(width 0.0889)
		(layer "In4.Cu")
		(net "M_F_ECC<5>")
	)
	(arc
		(start 243.856764 -88.490806)
		(mid 243.929562 -88.781569)
		(end 243.850414 -89.070688)
		(width 0.0889)
		(layer "In4.Cu")
		(net "M_F_ECC<5>")
	)
	(arc
		(start 243.856764 -89.481406)
		(mid 243.929562 -89.772169)
		(end 243.850414 -90.061288)
		(width 0.0889)
		(layer "In4.Cu")
		(net "M_F_ECC<5>")
	)
	(arc
		(start 243.856764 -85.519006)
		(mid 243.929562 -85.809769)
		(end 243.850414 -86.098888)
		(width 0.0889)
		(layer "In4.Cu")
		(net "M_F_ECC<5>")
	)
	(arc
		(start 243.850414 -93.033088)
		(mid 243.796944 -93.228151)
		(end 243.845588 -93.424502)
		(width 0.0889)
		(layer "In4.Cu")
		(net "M_F_ECC<5>")
	)
	(arc
		(start 243.856764 -87.500206)
		(mid 243.929562 -87.790969)
		(end 243.850414 -88.080088)
		(width 0.0889)
		(layer "In4.Cu")
		(net "M_F_ECC<5>")
	)
	(arc
		(start 243.850414 -86.098888)
		(mid 243.796944 -86.293951)
		(end 243.845588 -86.490302)
		(width 0.0889)
		(layer "In4.Cu")
		(net "M_F_ECC<5>")
	)
	(arc
		(start 243.850414 -89.070688)
		(mid 243.796944 -89.265751)
		(end 243.845588 -89.462102)
		(width 0.0889)
		(layer "In4.Cu")
		(net "M_F_ECC<5>")
	)
	(arc
		(start 243.850414 -96.004888)
		(mid 243.796944 -96.199951)
		(end 243.845588 -96.396302)
		(width 0.0889)
		(layer "In4.Cu")
		(net "M_F_ECC<5>")
	)
	(arc
		(start 243.856764 -92.453206)
		(mid 243.929562 -92.743969)
		(end 243.850414 -93.033088)
		(width 0.0889)
		(layer "In4.Cu")
		(net "M_F_ECC<5>")
	)
	(arc
		(start 243.850414 -94.023688)
		(mid 243.796915 -94.223586)
		(end 243.850414 -94.423484)
		(width 0.0889)
		(layer "In4.Cu")
		(net "M_F_ECC<5>")
	)
	(arc
		(start 243.850414 -93.433138)
		(mid 243.929636 -93.722256)
		(end 243.856764 -94.01302)
		(width 0.0889)
		(layer "In4.Cu")
		(net "M_F_ECC<5>")
	)
	(arc
		(start 243.850414 -90.061288)
		(mid 243.796944 -90.256351)
		(end 243.845588 -90.452702)
		(width 0.0889)
		(layer "In4.Cu")
		(net "M_F_ECC<5>")
	)
	(arc
		(start 243.856764 -90.472006)
		(mid 243.929562 -90.762769)
		(end 243.850414 -91.051888)
		(width 0.0889)
		(layer "In4.Cu")
		(net "M_F_ECC<5>")
	)
	(arc
		(start 243.856764 -95.425006)
		(mid 243.929562 -95.715769)
		(end 243.850414 -96.004888)
		(width 0.0889)
		(layer "In4.Cu")
		(net "M_F_ECC<5>")
	)
	(arc
		(start 243.850414 -88.080088)
		(mid 243.796944 -88.275151)
		(end 243.845588 -88.471502)
		(width 0.0889)
		(layer "In4.Cu")
		(net "M_F_ECC<5>")
	)
	(arc
		(start 243.850414 -94.423484)
		(mid 243.929545 -94.718886)
		(end 243.850414 -95.014288)
		(width 0.0889)
		(layer "In4.Cu")
		(net "M_F_ECC<5>")
	)
	(arc
		(start 243.850414 -97.986088)
		(mid 243.796944 -98.181151)
		(end 243.845588 -98.377502)
		(width 0.0889)
		(layer "In4.Cu")
		(net "M_F_ECC<5>")
	)
	(arc
		(start 243.850414 -96.995488)
		(mid 243.796944 -97.190551)
		(end 243.845588 -97.386902)
		(width 0.0889)
		(layer "In4.Cu")
		(net "M_F_ECC<5>")
	)
	(arc
		(start 243.856764 -91.462606)
		(mid 243.929562 -91.753369)
		(end 243.850414 -92.042488)
		(width 0.0889)
		(layer "In4.Cu")
		(net "M_F_ECC<5>")
	)
	(arc
		(start 243.856764 -97.406206)
		(mid 243.929562 -97.696969)
		(end 243.850414 -97.986088)
		(width 0.0889)
		(layer "In4.Cu")
		(net "M_F_ECC<5>")
	)
	(arc
		(start 243.850414 -92.042488)
		(mid 243.796944 -92.237551)
		(end 243.845588 -92.433902)
		(width 0.0889)
		(layer "In4.Cu")
		(net "M_F_ECC<5>")
	)
	(arc
		(start 243.856764 -86.509606)
		(mid 243.929562 -86.800369)
		(end 243.850414 -87.089488)
		(width 0.0889)
		(layer "In4.Cu")
		(net "M_F_ECC<5>")
	)
	(arc
		(start 243.850414 -85.108288)
		(mid 243.796944 -85.303351)
		(end 243.845588 -85.499702)
		(width 0.0889)
		(layer "In4.Cu")
		(net "M_F_ECC<5>")
	)
	(segment
		(start 233.799888 -153.542746)
		(end 234.072176 -153.542746)
		(width 0.14224)
		(layer "In11.Cu")
		(net "M_F_ECC<5>")
	)
	(segment
		(start 234.122976 -149.9616)
		(end 234.55122 -149.533356)
		(width 0.14224)
		(layer "In11.Cu")
		(net "M_F_ECC<5>")
	)
	(segment
		(start 233.961178 -152.586944)
		(end 234.199176 -152.348946)
		(width 0.14224)
		(layer "In11.Cu")
		(net "M_F_ECC<5>")
	)
	(segment
		(start 233.961178 -151.418544)
		(end 234.249976 -151.129746)
		(width 0.14224)
		(layer "In11.Cu")
		(net "M_F_ECC<5>")
	)
	(segment
		(start 234.249976 -151.129746)
		(end 234.249976 -150.6474)
		(width 0.14224)
		(layer "In11.Cu")
		(net "M_F_ECC<5>")
	)
	(segment
		(start 234.199176 -152.348946)
		(end 234.199176 -151.993854)
		(width 0.14224)
		(layer "In11.Cu")
		(net "M_F_ECC<5>")
	)
	(segment
		(start 234.249976 -150.6474)
		(end 234.122976 -150.5204)
		(width 0.14224)
		(layer "In11.Cu")
		(net "M_F_ECC<5>")
	)
	(segment
		(start 233.961178 -152.898856)
		(end 233.961178 -152.586944)
		(width 0.14224)
		(layer "In11.Cu")
		(net "M_F_ECC<5>")
	)
	(segment
		(start 234.199176 -151.993854)
		(end 233.961178 -151.755856)
		(width 0.14224)
		(layer "In11.Cu")
		(net "M_F_ECC<5>")
	)
	(segment
		(start 234.072176 -153.542746)
		(end 234.224576 -153.390346)
		(width 0.14224)
		(layer "In11.Cu")
		(net "M_F_ECC<5>")
	)
	(segment
		(start 234.122976 -150.5204)
		(end 234.122976 -149.9616)
		(width 0.14224)
		(layer "In11.Cu")
		(net "M_F_ECC<5>")
	)
	(segment
		(start 234.224576 -153.390346)
		(end 234.224576 -153.162254)
		(width 0.14224)
		(layer "In11.Cu")
		(net "M_F_ECC<5>")
	)
	(segment
		(start 234.224576 -153.162254)
		(end 233.961178 -152.898856)
		(width 0.14224)
		(layer "In11.Cu")
		(net "M_F_ECC<5>")
	)
	(segment
		(start 234.55122 -149.533356)
		(end 234.573572 -149.533356)
		(width 0.14224)
		(layer "In11.Cu")
		(net "M_F_ECC<5>")
	)
	(segment
		(start 233.961178 -151.755856)
		(end 233.961178 -151.418544)
		(width 0.14224)
		(layer "In11.Cu")
		(net "M_F_ECC<5>")
	)
	(segment
		(start 244.768624 -83.32724)
		(end 244.197124 -83.32724)
		(width 0.1651)
		(layer "F.Cu")
		(net "M_F_ECC<4>")
	)
	(segment
		(start 234.649772 -156.87294)
		(end 234.649772 -155.547568)
		(width 0.1651)
		(layer "F.Cu")
		(net "M_F_ECC<4>")
	)
	(segment
		(start 234.65028 -156.87294)
		(end 234.649772 -156.87294)
		(width 0.1651)
		(layer "F.Cu")
		(net "M_F_ECC<4>")
	)
	(segment
		(start 234.649772 -155.547568)
		(end 234.551728 -155.0162)
		(width 0.1651)
		(layer "F.Cu")
		(net "M_F_ECC<4>")
	)
	(via
		(at 233.799888 -150.814278)
		(size 0.508)
		(drill 0.254)
		(layers "F.Cu" "B.Cu")
		(net "M_F_ECC<4>")
	)
	(via
		(at 234.551728 -155.0162)
		(size 0.508)
		(drill 0.254)
		(layers "F.Cu" "B.Cu")
		(net "M_F_ECC<4>")
	)
	(via
		(at 244.197124 -83.32724)
		(size 0.508)
		(drill 0.254)
		(layers "F.Cu" "B.Cu")
		(net "M_F_ECC<4>")
	)
	(segment
		(start 233.799888 -152.078182)
		(end 233.799888 -150.814278)
		(width 0.1651)
		(layer "B.Cu")
		(net "M_F_ECC<4>")
	)
	(segment
		(start 233.800396 -152.078436)
		(end 233.799888 -152.078182)
		(width 0.1651)
		(layer "B.Cu")
		(net "M_F_ECC<4>")
	)
	(segment
		(start 243.685314 -88.575388)
		(end 243.69014 -88.584024)
		(width 0.0889)
		(layer "In4.Cu")
		(net "M_F_ECC<4>")
	)
	(segment
		(start 234.323128 -136.205468)
		(end 234.323128 -139.333478)
		(width 0.14224)
		(layer "In4.Cu")
		(net "M_F_ECC<4>")
	)
	(segment
		(start 243.678964 -86.58352)
		(end 243.685314 -86.594188)
		(width 0.0889)
		(layer "In4.Cu")
		(net "M_F_ECC<4>")
	)
	(segment
		(start 243.678964 -87.57412)
		(end 243.685314 -87.584788)
		(width 0.0889)
		(layer "In4.Cu")
		(net "M_F_ECC<4>")
	)
	(segment
		(start 234.2896 -127.6604)
		(end 234.257596 -127.692404)
		(width 0.14224)
		(layer "In4.Cu")
		(net "M_F_ECC<4>")
	)
	(segment
		(start 242.91417 -99.73818)
		(end 242.91417 -100.391468)
		(width 0.0889)
		(layer "In4.Cu")
		(net "M_F_ECC<4>")
	)
	(segment
		(start 243.685314 -92.537788)
		(end 243.69014 -92.546424)
		(width 0.0889)
		(layer "In4.Cu")
		(net "M_F_ECC<4>")
	)
	(segment
		(start 242.558824 -100.746814)
		(end 242.558824 -101.432106)
		(width 0.0889)
		(layer "In4.Cu")
		(net "M_F_ECC<4>")
	)
	(segment
		(start 234.031536 -144.327118)
		(end 234.031536 -145.527776)
		(width 0.14224)
		(layer "In4.Cu")
		(net "M_F_ECC<4>")
	)
	(segment
		(start 242.558824 -101.432106)
		(end 242.349782 -101.641148)
		(width 0.0889)
		(layer "In4.Cu")
		(net "M_F_ECC<4>")
	)
	(segment
		(start 243.685314 -97.490788)
		(end 243.69014 -97.499424)
		(width 0.0889)
		(layer "In4.Cu")
		(net "M_F_ECC<4>")
	)
	(segment
		(start 243.678964 -95.49892)
		(end 243.685314 -95.509588)
		(width 0.0889)
		(layer "In4.Cu")
		(net "M_F_ECC<4>")
	)
	(segment
		(start 243.678964 -97.48012)
		(end 243.685314 -97.490788)
		(width 0.0889)
		(layer "In4.Cu")
		(net "M_F_ECC<4>")
	)
	(segment
		(start 233.851704 -120.604788)
		(end 234.054904 -120.807988)
		(width 0.14224)
		(layer "In4.Cu")
		(net "M_F_ECC<4>")
	)
	(segment
		(start 243.678964 -90.54592)
		(end 243.685314 -90.556588)
		(width 0.0889)
		(layer "In4.Cu")
		(net "M_F_ECC<4>")
	)
	(segment
		(start 242.349782 -103.928418)
		(end 234.4928 -111.7854)
		(width 0.14224)
		(layer "In4.Cu")
		(net "M_F_ECC<4>")
	)
	(segment
		(start 233.6546 -120.604788)
		(end 233.851704 -120.604788)
		(width 0.14224)
		(layer "In4.Cu")
		(net "M_F_ECC<4>")
	)
	(segment
		(start 234.285028 -148.960078)
		(end 233.799888 -149.445218)
		(width 0.14224)
		(layer "In4.Cu")
		(net "M_F_ECC<4>")
	)
	(segment
		(start 234.297728 -131.42087)
		(end 234.297728 -134.484872)
		(width 0.14224)
		(layer "In4.Cu")
		(net "M_F_ECC<4>")
	)
	(segment
		(start 243.678964 -88.56472)
		(end 243.685314 -88.575388)
		(width 0.0889)
		(layer "In4.Cu")
		(net "M_F_ECC<4>")
	)
	(segment
		(start 243.685314 -89.565988)
		(end 243.69014 -89.574624)
		(width 0.0889)
		(layer "In4.Cu")
		(net "M_F_ECC<4>")
	)
	(segment
		(start 243.678964 -92.52712)
		(end 243.685314 -92.537788)
		(width 0.0889)
		(layer "In4.Cu")
		(net "M_F_ECC<4>")
	)
	(segment
		(start 243.685314 -91.547188)
		(end 243.69014 -91.555824)
		(width 0.0889)
		(layer "In4.Cu")
		(net "M_F_ECC<4>")
	)
	(segment
		(start 243.685314 -94.518988)
		(end 243.69014 -94.527624)
		(width 0.0889)
		(layer "In4.Cu")
		(net "M_F_ECC<4>")
	)
	(segment
		(start 234.097576 -124.064522)
		(end 234.097576 -125.588776)
		(width 0.14224)
		(layer "In4.Cu")
		(net "M_F_ECC<4>")
	)
	(segment
		(start 242.91417 -100.391468)
		(end 242.558824 -100.746814)
		(width 0.0889)
		(layer "In4.Cu")
		(net "M_F_ECC<4>")
	)
	(segment
		(start 244.197124 -83.32724)
		(end 243.702078 -83.992974)
		(width 0.0889)
		(layer "In4.Cu")
		(net "M_F_ECC<4>")
	)
	(segment
		(start 233.799888 -149.445218)
		(end 233.799888 -150.814278)
		(width 0.14224)
		(layer "In4.Cu")
		(net "M_F_ECC<4>")
	)
	(segment
		(start 234.069128 -140.794486)
		(end 234.297728 -141.023086)
		(width 0.14224)
		(layer "In4.Cu")
		(net "M_F_ECC<4>")
	)
	(segment
		(start 243.702078 -83.992974)
		(end 243.685314 -84.022438)
		(width 0.0889)
		(layer "In4.Cu")
		(net "M_F_ECC<4>")
	)
	(segment
		(start 243.685314 -87.584788)
		(end 243.69014 -87.593424)
		(width 0.0889)
		(layer "In4.Cu")
		(net "M_F_ECC<4>")
	)
	(segment
		(start 243.678964 -91.53652)
		(end 243.685314 -91.547188)
		(width 0.0889)
		(layer "In4.Cu")
		(net "M_F_ECC<4>")
	)
	(segment
		(start 234.297728 -134.484872)
		(end 234.069128 -134.713472)
		(width 0.14224)
		(layer "In4.Cu")
		(net "M_F_ECC<4>")
	)
	(segment
		(start 234.2896 -125.7808)
		(end 234.2896 -127.6604)
		(width 0.14224)
		(layer "In4.Cu")
		(net "M_F_ECC<4>")
	)
	(segment
		(start 242.349782 -101.641148)
		(end 242.349782 -103.928418)
		(width 0.14224)
		(layer "In4.Cu")
		(net "M_F_ECC<4>")
	)
	(segment
		(start 234.069128 -131.19227)
		(end 234.297728 -131.42087)
		(width 0.14224)
		(layer "In4.Cu")
		(net "M_F_ECC<4>")
	)
	(segment
		(start 233.4514 -120.401588)
		(end 233.6546 -120.604788)
		(width 0.14224)
		(layer "In4.Cu")
		(net "M_F_ECC<4>")
	)
	(segment
		(start 233.4514 -123.418346)
		(end 234.097576 -124.064522)
		(width 0.14224)
		(layer "In4.Cu")
		(net "M_F_ECC<4>")
	)
	(segment
		(start 243.685314 -95.509588)
		(end 243.69014 -95.518224)
		(width 0.0889)
		(layer "In4.Cu")
		(net "M_F_ECC<4>")
	)
	(segment
		(start 243.678964 -85.59292)
		(end 243.685314 -85.603588)
		(width 0.0889)
		(layer "In4.Cu")
		(net "M_F_ECC<4>")
	)
	(segment
		(start 234.069128 -134.713472)
		(end 234.069128 -135.951468)
		(width 0.14224)
		(layer "In4.Cu")
		(net "M_F_ECC<4>")
	)
	(segment
		(start 243.678964 -98.47072)
		(end 243.738654 -98.57105)
		(width 0.0889)
		(layer "In4.Cu")
		(net "M_F_ECC<4>")
	)
	(segment
		(start 243.685314 -96.500188)
		(end 243.69014 -96.508824)
		(width 0.0889)
		(layer "In4.Cu")
		(net "M_F_ECC<4>")
	)
	(segment
		(start 234.4928 -111.7854)
		(end 234.4928 -118.317264)
		(width 0.14224)
		(layer "In4.Cu")
		(net "M_F_ECC<4>")
	)
	(segment
		(start 243.685314 -85.603588)
		(end 243.69014 -85.612224)
		(width 0.0889)
		(layer "In4.Cu")
		(net "M_F_ECC<4>")
	)
	(segment
		(start 234.257596 -127.692404)
		(end 234.257596 -129.80797)
		(width 0.14224)
		(layer "In4.Cu")
		(net "M_F_ECC<4>")
	)
	(segment
		(start 234.054904 -120.807988)
		(end 234.054904 -121.214388)
		(width 0.14224)
		(layer "In4.Cu")
		(net "M_F_ECC<4>")
	)
	(segment
		(start 233.6546 -121.417588)
		(end 233.4514 -121.620788)
		(width 0.14224)
		(layer "In4.Cu")
		(net "M_F_ECC<4>")
	)
	(segment
		(start 243.738654 -98.57105)
		(end 243.738654 -98.913696)
		(width 0.0889)
		(layer "In4.Cu")
		(net "M_F_ECC<4>")
	)
	(segment
		(start 233.851704 -121.417588)
		(end 233.6546 -121.417588)
		(width 0.14224)
		(layer "In4.Cu")
		(net "M_F_ECC<4>")
	)
	(segment
		(start 243.685314 -86.594188)
		(end 243.69014 -86.602824)
		(width 0.0889)
		(layer "In4.Cu")
		(net "M_F_ECC<4>")
	)
	(segment
		(start 234.285028 -145.781268)
		(end 234.285028 -148.960078)
		(width 0.14224)
		(layer "In4.Cu")
		(net "M_F_ECC<4>")
	)
	(segment
		(start 234.4928 -118.317264)
		(end 233.4514 -119.358664)
		(width 0.14224)
		(layer "In4.Cu")
		(net "M_F_ECC<4>")
	)
	(segment
		(start 234.054904 -121.214388)
		(end 233.851704 -121.417588)
		(width 0.14224)
		(layer "In4.Cu")
		(net "M_F_ECC<4>")
	)
	(segment
		(start 234.069128 -139.587478)
		(end 234.069128 -140.794486)
		(width 0.14224)
		(layer "In4.Cu")
		(net "M_F_ECC<4>")
	)
	(segment
		(start 243.678964 -96.48952)
		(end 243.685314 -96.500188)
		(width 0.0889)
		(layer "In4.Cu")
		(net "M_F_ECC<4>")
	)
	(segment
		(start 243.678964 -84.60232)
		(end 243.685314 -84.612988)
		(width 0.0889)
		(layer "In4.Cu")
		(net "M_F_ECC<4>")
	)
	(segment
		(start 234.031536 -145.527776)
		(end 234.285028 -145.781268)
		(width 0.14224)
		(layer "In4.Cu")
		(net "M_F_ECC<4>")
	)
	(segment
		(start 234.069128 -135.951468)
		(end 234.323128 -136.205468)
		(width 0.14224)
		(layer "In4.Cu")
		(net "M_F_ECC<4>")
	)
	(segment
		(start 234.297728 -144.060926)
		(end 234.031536 -144.327118)
		(width 0.14224)
		(layer "In4.Cu")
		(net "M_F_ECC<4>")
	)
	(segment
		(start 233.4514 -121.620788)
		(end 233.4514 -123.418346)
		(width 0.14224)
		(layer "In4.Cu")
		(net "M_F_ECC<4>")
	)
	(segment
		(start 243.685314 -93.928438)
		(end 243.678964 -93.939106)
		(width 0.0889)
		(layer "In4.Cu")
		(net "M_F_ECC<4>")
	)
	(segment
		(start 234.257596 -129.80797)
		(end 234.069128 -129.996438)
		(width 0.14224)
		(layer "In4.Cu")
		(net "M_F_ECC<4>")
	)
	(segment
		(start 243.685314 -90.556588)
		(end 243.69014 -90.565224)
		(width 0.0889)
		(layer "In4.Cu")
		(net "M_F_ECC<4>")
	)
	(segment
		(start 234.069128 -129.996438)
		(end 234.069128 -131.19227)
		(width 0.14224)
		(layer "In4.Cu")
		(net "M_F_ECC<4>")
	)
	(segment
		(start 234.323128 -139.333478)
		(end 234.069128 -139.587478)
		(width 0.14224)
		(layer "In4.Cu")
		(net "M_F_ECC<4>")
	)
	(segment
		(start 243.685314 -84.612988)
		(end 243.69014 -84.621624)
		(width 0.0889)
		(layer "In4.Cu")
		(net "M_F_ECC<4>")
	)
	(segment
		(start 243.738654 -98.913696)
		(end 242.91417 -99.73818)
		(width 0.0889)
		(layer "In4.Cu")
		(net "M_F_ECC<4>")
	)
	(segment
		(start 243.678964 -89.55532)
		(end 243.685314 -89.565988)
		(width 0.0889)
		(layer "In4.Cu")
		(net "M_F_ECC<4>")
	)
	(segment
		(start 234.097576 -125.588776)
		(end 234.2896 -125.7808)
		(width 0.14224)
		(layer "In4.Cu")
		(net "M_F_ECC<4>")
	)
	(segment
		(start 234.297728 -141.023086)
		(end 234.297728 -144.060926)
		(width 0.14224)
		(layer "In4.Cu")
		(net "M_F_ECC<4>")
	)
	(segment
		(start 233.4514 -119.358664)
		(end 233.4514 -120.401588)
		(width 0.14224)
		(layer "In4.Cu")
		(net "M_F_ECC<4>")
	)
	(arc
		(start 243.69014 -87.593424)
		(mid 243.738895 -87.789776)
		(end 243.685314 -87.984838)
		(width 0.0889)
		(layer "In4.Cu")
		(net "M_F_ECC<4>")
	)
	(arc
		(start 243.69014 -84.621624)
		(mid 243.738895 -84.817976)
		(end 243.685314 -85.013038)
		(width 0.0889)
		(layer "In4.Cu")
		(net "M_F_ECC<4>")
	)
	(arc
		(start 243.685314 -97.890838)
		(mid 243.606092 -98.179956)
		(end 243.678964 -98.47072)
		(width 0.0889)
		(layer "In4.Cu")
		(net "M_F_ECC<4>")
	)
	(arc
		(start 243.685314 -88.975438)
		(mid 243.606092 -89.264556)
		(end 243.678964 -89.55532)
		(width 0.0889)
		(layer "In4.Cu")
		(net "M_F_ECC<4>")
	)
	(arc
		(start 243.69014 -96.508824)
		(mid 243.738895 -96.705176)
		(end 243.685314 -96.900238)
		(width 0.0889)
		(layer "In4.Cu")
		(net "M_F_ECC<4>")
	)
	(arc
		(start 243.678964 -93.939106)
		(mid 243.606166 -94.229869)
		(end 243.685314 -94.518988)
		(width 0.0889)
		(layer "In4.Cu")
		(net "M_F_ECC<4>")
	)
	(arc
		(start 243.69014 -95.518224)
		(mid 243.738895 -95.714576)
		(end 243.685314 -95.909638)
		(width 0.0889)
		(layer "In4.Cu")
		(net "M_F_ECC<4>")
	)
	(arc
		(start 243.69014 -90.565224)
		(mid 243.738895 -90.761576)
		(end 243.685314 -90.956638)
		(width 0.0889)
		(layer "In4.Cu")
		(net "M_F_ECC<4>")
	)
	(arc
		(start 243.685314 -94.919038)
		(mid 243.606092 -95.208156)
		(end 243.678964 -95.49892)
		(width 0.0889)
		(layer "In4.Cu")
		(net "M_F_ECC<4>")
	)
	(arc
		(start 243.685314 -90.956638)
		(mid 243.606092 -91.245756)
		(end 243.678964 -91.53652)
		(width 0.0889)
		(layer "In4.Cu")
		(net "M_F_ECC<4>")
	)
	(arc
		(start 243.685314 -96.900238)
		(mid 243.606092 -97.189356)
		(end 243.678964 -97.48012)
		(width 0.0889)
		(layer "In4.Cu")
		(net "M_F_ECC<4>")
	)
	(arc
		(start 243.685314 -95.909638)
		(mid 243.606092 -96.198756)
		(end 243.678964 -96.48952)
		(width 0.0889)
		(layer "In4.Cu")
		(net "M_F_ECC<4>")
	)
	(arc
		(start 243.69014 -92.546424)
		(mid 243.738895 -92.742776)
		(end 243.685314 -92.937838)
		(width 0.0889)
		(layer "In4.Cu")
		(net "M_F_ECC<4>")
	)
	(arc
		(start 243.685314 -87.984838)
		(mid 243.606092 -88.273956)
		(end 243.678964 -88.56472)
		(width 0.0889)
		(layer "In4.Cu")
		(net "M_F_ECC<4>")
	)
	(arc
		(start 243.685314 -93.528642)
		(mid 243.738813 -93.72854)
		(end 243.685314 -93.928438)
		(width 0.0889)
		(layer "In4.Cu")
		(net "M_F_ECC<4>")
	)
	(arc
		(start 243.69014 -85.612224)
		(mid 243.738895 -85.808576)
		(end 243.685314 -86.003638)
		(width 0.0889)
		(layer "In4.Cu")
		(net "M_F_ECC<4>")
	)
	(arc
		(start 243.685314 -92.937838)
		(mid 243.606183 -93.23324)
		(end 243.685314 -93.528642)
		(width 0.0889)
		(layer "In4.Cu")
		(net "M_F_ECC<4>")
	)
	(arc
		(start 243.685314 -84.022438)
		(mid 243.606092 -84.311556)
		(end 243.678964 -84.60232)
		(width 0.0889)
		(layer "In4.Cu")
		(net "M_F_ECC<4>")
	)
	(arc
		(start 243.69014 -97.499424)
		(mid 243.738895 -97.695776)
		(end 243.685314 -97.890838)
		(width 0.0889)
		(layer "In4.Cu")
		(net "M_F_ECC<4>")
	)
	(arc
		(start 243.69014 -89.574624)
		(mid 243.738895 -89.770976)
		(end 243.685314 -89.966038)
		(width 0.0889)
		(layer "In4.Cu")
		(net "M_F_ECC<4>")
	)
	(arc
		(start 243.685314 -86.994238)
		(mid 243.606092 -87.283356)
		(end 243.678964 -87.57412)
		(width 0.0889)
		(layer "In4.Cu")
		(net "M_F_ECC<4>")
	)
	(arc
		(start 243.685314 -85.013038)
		(mid 243.606092 -85.302156)
		(end 243.678964 -85.59292)
		(width 0.0889)
		(layer "In4.Cu")
		(net "M_F_ECC<4>")
	)
	(arc
		(start 243.69014 -91.555824)
		(mid 243.738895 -91.752176)
		(end 243.685314 -91.947238)
		(width 0.0889)
		(layer "In4.Cu")
		(net "M_F_ECC<4>")
	)
	(arc
		(start 243.685314 -91.947238)
		(mid 243.606092 -92.236356)
		(end 243.678964 -92.52712)
		(width 0.0889)
		(layer "In4.Cu")
		(net "M_F_ECC<4>")
	)
	(arc
		(start 243.69014 -88.584024)
		(mid 243.738895 -88.780376)
		(end 243.685314 -88.975438)
		(width 0.0889)
		(layer "In4.Cu")
		(net "M_F_ECC<4>")
	)
	(arc
		(start 243.69014 -86.602824)
		(mid 243.738895 -86.799176)
		(end 243.685314 -86.994238)
		(width 0.0889)
		(layer "In4.Cu")
		(net "M_F_ECC<4>")
	)
	(arc
		(start 243.685314 -89.966038)
		(mid 243.606092 -90.255156)
		(end 243.678964 -90.54592)
		(width 0.0889)
		(layer "In4.Cu")
		(net "M_F_ECC<4>")
	)
	(arc
		(start 243.69014 -94.527624)
		(mid 243.738895 -94.723976)
		(end 243.685314 -94.919038)
		(width 0.0889)
		(layer "In4.Cu")
		(net "M_F_ECC<4>")
	)
	(arc
		(start 243.685314 -86.003638)
		(mid 243.606092 -86.292756)
		(end 243.678964 -86.58352)
		(width 0.0889)
		(layer "In4.Cu")
		(net "M_F_ECC<4>")
	)
	(segment
		(start 234.551728 -155.0162)
		(end 233.366818 -153.83129)
		(width 0.14224)
		(layer "In11.Cu")
		(net "M_F_ECC<4>")
	)
	(segment
		(start 233.366818 -151.247348)
		(end 233.799888 -150.814278)
		(width 0.14224)
		(layer "In11.Cu")
		(net "M_F_ECC<4>")
	)
	(segment
		(start 233.366818 -153.83129)
		(end 233.366818 -151.247348)
		(width 0.14224)
		(layer "In11.Cu")
		(net "M_F_ECC<4>")
	)
	(segment
		(start 241.44986 -152.278842)
		(end 241.44986 -153.542746)
		(width 0.1651)
		(layer "F.Cu")
		(net "M_F_ECC<3>")
	)
	(segment
		(start 248.202704 -84.31784)
		(end 247.631204 -84.31784)
		(width 0.1651)
		(layer "F.Cu")
		(net "M_F_ECC<3>")
	)
	(segment
		(start 241.450368 -152.273)
		(end 241.44986 -152.278842)
		(width 0.1651)
		(layer "F.Cu")
		(net "M_F_ECC<3>")
	)
	(via
		(at 241.44986 -153.542746)
		(size 0.508)
		(drill 0.254)
		(layers "F.Cu" "B.Cu")
		(net "M_F_ECC<3>")
	)
	(via
		(at 247.631204 -84.31784)
		(size 0.508)
		(drill 0.254)
		(layers "F.Cu" "B.Cu")
		(net "M_F_ECC<3>")
	)
	(via
		(at 242.299744 -149.533356)
		(size 0.508)
		(drill 0.254)
		(layers "F.Cu" "B.Cu")
		(net "M_F_ECC<3>")
	)
	(segment
		(start 242.300506 -147.478496)
		(end 242.299998 -147.478496)
		(width 0.1651)
		(layer "B.Cu")
		(net "M_F_ECC<3>")
	)
	(segment
		(start 242.299998 -148.227542)
		(end 242.299744 -148.227796)
		(width 0.1651)
		(layer "B.Cu")
		(net "M_F_ECC<3>")
	)
	(segment
		(start 242.299998 -147.478496)
		(end 242.299998 -148.227542)
		(width 0.1651)
		(layer "B.Cu")
		(net "M_F_ECC<3>")
	)
	(segment
		(start 242.299744 -148.227796)
		(end 242.299744 -149.533356)
		(width 0.1651)
		(layer "B.Cu")
		(net "M_F_ECC<3>")
	)
	(segment
		(start 243.053616 -121.182384)
		(end 242.83924 -121.39676)
		(width 0.14224)
		(layer "In4.Cu")
		(net "M_F_ECC<3>")
	)
	(segment
		(start 243.596668 -124.45238)
		(end 242.809268 -124.45238)
		(width 0.14224)
		(layer "In4.Cu")
		(net "M_F_ECC<3>")
	)
	(segment
		(start 249.050048 -103.103934)
		(end 249.050048 -106.402632)
		(width 0.14224)
		(layer "In4.Cu")
		(net "M_F_ECC<3>")
	)
	(segment
		(start 248.143014 -90.556588)
		(end 248.138188 -90.565224)
		(width 0.0889)
		(layer "In4.Cu")
		(net "M_F_ECC<3>")
	)
	(segment
		(start 242.451128 -128.805178)
		(end 242.654328 -129.008378)
		(width 0.14224)
		(layer "In4.Cu")
		(net "M_F_ECC<3>")
	)
	(segment
		(start 248.143014 -92.537788)
		(end 248.138188 -92.546424)
		(width 0.0889)
		(layer "In4.Cu")
		(net "M_F_ECC<3>")
	)
	(segment
		(start 242.667028 -141.009878)
		(end 242.667028 -141.574774)
		(width 0.14224)
		(layer "In4.Cu")
		(net "M_F_ECC<3>")
	)
	(segment
		(start 248.143014 -95.509588)
		(end 248.138188 -95.518224)
		(width 0.0889)
		(layer "In4.Cu")
		(net "M_F_ECC<3>")
	)
	(segment
		(start 242.7986 -136.0932)
		(end 242.654328 -136.237472)
		(width 0.14224)
		(layer "In4.Cu")
		(net "M_F_ECC<3>")
	)
	(segment
		(start 242.654328 -127.789178)
		(end 242.451128 -127.992378)
		(width 0.14224)
		(layer "In4.Cu")
		(net "M_F_ECC<3>")
	)
	(segment
		(start 248.149364 -90.54592)
		(end 248.143014 -90.556588)
		(width 0.0889)
		(layer "In4.Cu")
		(net "M_F_ECC<3>")
	)
	(segment
		(start 242.451128 -149.381972)
		(end 242.299744 -149.533356)
		(width 0.14224)
		(layer "In4.Cu")
		(net "M_F_ECC<3>")
	)
	(segment
		(start 242.806728 -140.870178)
		(end 242.667028 -141.009878)
		(width 0.14224)
		(layer "In4.Cu")
		(net "M_F_ECC<3>")
	)
	(segment
		(start 241.76609 -121.39676)
		(end 241.558318 -121.604532)
		(width 0.14224)
		(layer "In4.Cu")
		(net "M_F_ECC<3>")
	)
	(segment
		(start 242.7986 -136.745472)
		(end 242.7986 -138.811)
		(width 0.14224)
		(layer "In4.Cu")
		(net "M_F_ECC<3>")
	)
	(segment
		(start 248.819416 -97.081086)
		(end 248.819416 -102.873302)
		(width 0.0889)
		(layer "In4.Cu")
		(net "M_F_ECC<3>")
	)
	(segment
		(start 248.149364 -89.55532)
		(end 248.143014 -89.565988)
		(width 0.0889)
		(layer "In4.Cu")
		(net "M_F_ECC<3>")
	)
	(segment
		(start 248.143014 -85.603588)
		(end 248.138188 -85.612224)
		(width 0.0889)
		(layer "In4.Cu")
		(net "M_F_ECC<3>")
	)
	(segment
		(start 248.143014 -86.594188)
		(end 248.138188 -86.602824)
		(width 0.0889)
		(layer "In4.Cu")
		(net "M_F_ECC<3>")
	)
	(segment
		(start 248.143014 -95.909638)
		(end 248.14276 -95.910146)
		(width 0.0889)
		(layer "In4.Cu")
		(net "M_F_ECC<3>")
	)
	(segment
		(start 248.149364 -92.52712)
		(end 248.143014 -92.537788)
		(width 0.0889)
		(layer "In4.Cu")
		(net "M_F_ECC<3>")
	)
	(segment
		(start 243.751608 -124.29744)
		(end 243.596668 -124.45238)
		(width 0.14224)
		(layer "In4.Cu")
		(net "M_F_ECC<3>")
	)
	(segment
		(start 242.83924 -121.39676)
		(end 241.76609 -121.39676)
		(width 0.14224)
		(layer "In4.Cu")
		(net "M_F_ECC<3>")
	)
	(segment
		(start 249.050048 -106.402632)
		(end 243.053616 -112.399064)
		(width 0.14224)
		(layer "In4.Cu")
		(net "M_F_ECC<3>")
	)
	(segment
		(start 248.149364 -85.59292)
		(end 248.143014 -85.603588)
		(width 0.0889)
		(layer "In4.Cu")
		(net "M_F_ECC<3>")
	)
	(segment
		(start 242.785392 -131.290314)
		(end 242.667028 -131.408678)
		(width 0.14224)
		(layer "In4.Cu")
		(net "M_F_ECC<3>")
	)
	(segment
		(start 242.654328 -123.48464)
		(end 242.809268 -123.63958)
		(width 0.14224)
		(layer "In4.Cu")
		(net "M_F_ECC<3>")
	)
	(segment
		(start 248.143014 -89.565988)
		(end 248.138188 -89.574624)
		(width 0.0889)
		(layer "In4.Cu")
		(net "M_F_ECC<3>")
	)
	(segment
		(start 248.143014 -93.928438)
		(end 248.149364 -93.939106)
		(width 0.0889)
		(layer "In4.Cu")
		(net "M_F_ECC<3>")
	)
	(segment
		(start 242.654328 -139.562078)
		(end 242.806728 -139.714478)
		(width 0.14224)
		(layer "In4.Cu")
		(net "M_F_ECC<3>")
	)
	(segment
		(start 242.1382 -127.992378)
		(end 241.935 -128.195578)
		(width 0.14224)
		(layer "In4.Cu")
		(net "M_F_ECC<3>")
	)
	(segment
		(start 242.7986 -132.1562)
		(end 242.7986 -136.0932)
		(width 0.14224)
		(layer "In4.Cu")
		(net "M_F_ECC<3>")
	)
	(segment
		(start 248.149364 -95.49892)
		(end 248.143014 -95.509588)
		(width 0.0889)
		(layer "In4.Cu")
		(net "M_F_ECC<3>")
	)
	(segment
		(start 248.143014 -88.575388)
		(end 248.138188 -88.584024)
		(width 0.0889)
		(layer "In4.Cu")
		(net "M_F_ECC<3>")
	)
	(segment
		(start 241.935 -128.601978)
		(end 242.1382 -128.805178)
		(width 0.14224)
		(layer "In4.Cu")
		(net "M_F_ECC<3>")
	)
	(segment
		(start 242.1382 -128.805178)
		(end 242.451128 -128.805178)
		(width 0.14224)
		(layer "In4.Cu")
		(net "M_F_ECC<3>")
	)
	(segment
		(start 241.558318 -121.604532)
		(end 241.558318 -122.148092)
		(width 0.14224)
		(layer "In4.Cu")
		(net "M_F_ECC<3>")
	)
	(segment
		(start 242.654328 -138.955272)
		(end 242.654328 -139.562078)
		(width 0.14224)
		(layer "In4.Cu")
		(net "M_F_ECC<3>")
	)
	(segment
		(start 241.558318 -122.148092)
		(end 241.80165 -122.391424)
		(width 0.14224)
		(layer "In4.Cu")
		(net "M_F_ECC<3>")
	)
	(segment
		(start 242.654328 -122.615198)
		(end 242.654328 -123.48464)
		(width 0.14224)
		(layer "In4.Cu")
		(net "M_F_ECC<3>")
	)
	(segment
		(start 242.451128 -127.992378)
		(end 242.1382 -127.992378)
		(width 0.14224)
		(layer "In4.Cu")
		(net "M_F_ECC<3>")
	)
	(segment
		(start 242.667028 -131.408678)
		(end 242.667028 -132.024628)
		(width 0.14224)
		(layer "In4.Cu")
		(net "M_F_ECC<3>")
	)
	(segment
		(start 242.430554 -122.391424)
		(end 242.654328 -122.615198)
		(width 0.14224)
		(layer "In4.Cu")
		(net "M_F_ECC<3>")
	)
	(segment
		(start 242.7986 -138.811)
		(end 242.654328 -138.955272)
		(width 0.14224)
		(layer "In4.Cu")
		(net "M_F_ECC<3>")
	)
	(segment
		(start 242.654328 -129.960878)
		(end 242.785392 -130.091942)
		(width 0.14224)
		(layer "In4.Cu")
		(net "M_F_ECC<3>")
	)
	(segment
		(start 243.053616 -112.399064)
		(end 243.053616 -121.182384)
		(width 0.14224)
		(layer "In4.Cu")
		(net "M_F_ECC<3>")
	)
	(segment
		(start 243.0272 -126.8476)
		(end 242.654328 -127.220472)
		(width 0.14224)
		(layer "In4.Cu")
		(net "M_F_ECC<3>")
	)
	(segment
		(start 248.143014 -91.547188)
		(end 248.138188 -91.555824)
		(width 0.0889)
		(layer "In4.Cu")
		(net "M_F_ECC<3>")
	)
	(segment
		(start 242.451128 -146.016472)
		(end 242.451128 -149.381972)
		(width 0.14224)
		(layer "In4.Cu")
		(net "M_F_ECC<3>")
	)
	(segment
		(start 248.143014 -94.518988)
		(end 248.138188 -94.527624)
		(width 0.0889)
		(layer "In4.Cu")
		(net "M_F_ECC<3>")
	)
	(segment
		(start 242.809268 -124.45238)
		(end 242.654328 -124.60732)
		(width 0.14224)
		(layer "In4.Cu")
		(net "M_F_ECC<3>")
	)
	(segment
		(start 243.0272 -125.25248)
		(end 243.0272 -126.8476)
		(width 0.14224)
		(layer "In4.Cu")
		(net "M_F_ECC<3>")
	)
	(segment
		(start 242.654328 -127.220472)
		(end 242.654328 -127.789178)
		(width 0.14224)
		(layer "In4.Cu")
		(net "M_F_ECC<3>")
	)
	(segment
		(start 243.751608 -123.79452)
		(end 243.751608 -124.29744)
		(width 0.14224)
		(layer "In4.Cu")
		(net "M_F_ECC<3>")
	)
	(segment
		(start 243.596668 -123.63958)
		(end 243.751608 -123.79452)
		(width 0.14224)
		(layer "In4.Cu")
		(net "M_F_ECC<3>")
	)
	(segment
		(start 242.791996 -145.675604)
		(end 242.451128 -146.016472)
		(width 0.14224)
		(layer "In4.Cu")
		(net "M_F_ECC<3>")
	)
	(segment
		(start 247.658128 -84.321904)
		(end 248.048018 -84.84616)
		(width 0.0889)
		(layer "In4.Cu")
		(net "M_F_ECC<3>")
	)
	(segment
		(start 241.80165 -122.391424)
		(end 242.430554 -122.391424)
		(width 0.14224)
		(layer "In4.Cu")
		(net "M_F_ECC<3>")
	)
	(segment
		(start 248.149364 -91.53652)
		(end 248.143014 -91.547188)
		(width 0.0889)
		(layer "In4.Cu")
		(net "M_F_ECC<3>")
	)
	(segment
		(start 248.819416 -102.873302)
		(end 249.050048 -103.103934)
		(width 0.0889)
		(layer "In4.Cu")
		(net "M_F_ECC<3>")
	)
	(segment
		(start 242.654328 -129.008378)
		(end 242.654328 -129.960878)
		(width 0.14224)
		(layer "In4.Cu")
		(net "M_F_ECC<3>")
	)
	(segment
		(start 248.14276 -95.910146)
		(end 248.819416 -97.081086)
		(width 0.0889)
		(layer "In4.Cu")
		(net "M_F_ECC<3>")
	)
	(segment
		(start 242.667028 -141.574774)
		(end 242.791996 -141.699742)
		(width 0.14224)
		(layer "In4.Cu")
		(net "M_F_ECC<3>")
	)
	(segment
		(start 248.143014 -87.584788)
		(end 248.138188 -87.593424)
		(width 0.0889)
		(layer "In4.Cu")
		(net "M_F_ECC<3>")
	)
	(segment
		(start 248.149364 -88.56472)
		(end 248.143014 -88.575388)
		(width 0.0889)
		(layer "In4.Cu")
		(net "M_F_ECC<3>")
	)
	(segment
		(start 248.048018 -84.84616)
		(end 248.143014 -85.013038)
		(width 0.0889)
		(layer "In4.Cu")
		(net "M_F_ECC<3>")
	)
	(segment
		(start 242.654328 -136.237472)
		(end 242.654328 -136.6012)
		(width 0.14224)
		(layer "In4.Cu")
		(net "M_F_ECC<3>")
	)
	(segment
		(start 242.791996 -141.699742)
		(end 242.791996 -145.675604)
		(width 0.14224)
		(layer "In4.Cu")
		(net "M_F_ECC<3>")
	)
	(segment
		(start 242.654328 -136.6012)
		(end 242.7986 -136.745472)
		(width 0.14224)
		(layer "In4.Cu")
		(net "M_F_ECC<3>")
	)
	(segment
		(start 242.667028 -132.024628)
		(end 242.7986 -132.1562)
		(width 0.14224)
		(layer "In4.Cu")
		(net "M_F_ECC<3>")
	)
	(segment
		(start 242.809268 -123.63958)
		(end 243.596668 -123.63958)
		(width 0.14224)
		(layer "In4.Cu")
		(net "M_F_ECC<3>")
	)
	(segment
		(start 242.654328 -124.60732)
		(end 242.654328 -124.879608)
		(width 0.14224)
		(layer "In4.Cu")
		(net "M_F_ECC<3>")
	)
	(segment
		(start 241.935 -128.195578)
		(end 241.935 -128.601978)
		(width 0.14224)
		(layer "In4.Cu")
		(net "M_F_ECC<3>")
	)
	(segment
		(start 242.654328 -124.879608)
		(end 243.0272 -125.25248)
		(width 0.14224)
		(layer "In4.Cu")
		(net "M_F_ECC<3>")
	)
	(segment
		(start 247.631204 -84.31784)
		(end 247.658128 -84.321904)
		(width 0.0889)
		(layer "In4.Cu")
		(net "M_F_ECC<3>")
	)
	(segment
		(start 248.149364 -87.57412)
		(end 248.143014 -87.584788)
		(width 0.0889)
		(layer "In4.Cu")
		(net "M_F_ECC<3>")
	)
	(segment
		(start 242.806728 -139.714478)
		(end 242.806728 -140.870178)
		(width 0.14224)
		(layer "In4.Cu")
		(net "M_F_ECC<3>")
	)
	(segment
		(start 248.149364 -86.58352)
		(end 248.143014 -86.594188)
		(width 0.0889)
		(layer "In4.Cu")
		(net "M_F_ECC<3>")
	)
	(segment
		(start 242.785392 -130.091942)
		(end 242.785392 -131.290314)
		(width 0.14224)
		(layer "In4.Cu")
		(net "M_F_ECC<3>")
	)
	(arc
		(start 248.143014 -92.937838)
		(mid 248.222145 -93.23324)
		(end 248.143014 -93.528642)
		(width 0.0889)
		(layer "In4.Cu")
		(net "M_F_ECC<3>")
	)
	(arc
		(start 248.143014 -87.984838)
		(mid 248.222236 -88.273956)
		(end 248.149364 -88.56472)
		(width 0.0889)
		(layer "In4.Cu")
		(net "M_F_ECC<3>")
	)
	(arc
		(start 248.143014 -89.966038)
		(mid 248.222236 -90.255156)
		(end 248.149364 -90.54592)
		(width 0.0889)
		(layer "In4.Cu")
		(net "M_F_ECC<3>")
	)
	(arc
		(start 248.138188 -89.574624)
		(mid 248.089433 -89.770976)
		(end 248.143014 -89.966038)
		(width 0.0889)
		(layer "In4.Cu")
		(net "M_F_ECC<3>")
	)
	(arc
		(start 248.143014 -91.947238)
		(mid 248.222236 -92.236356)
		(end 248.149364 -92.52712)
		(width 0.0889)
		(layer "In4.Cu")
		(net "M_F_ECC<3>")
	)
	(arc
		(start 248.138188 -87.593424)
		(mid 248.089433 -87.789776)
		(end 248.143014 -87.984838)
		(width 0.0889)
		(layer "In4.Cu")
		(net "M_F_ECC<3>")
	)
	(arc
		(start 248.138188 -86.602824)
		(mid 248.089433 -86.799176)
		(end 248.143014 -86.994238)
		(width 0.0889)
		(layer "In4.Cu")
		(net "M_F_ECC<3>")
	)
	(arc
		(start 248.138188 -94.527624)
		(mid 248.089433 -94.723976)
		(end 248.143014 -94.919038)
		(width 0.0889)
		(layer "In4.Cu")
		(net "M_F_ECC<3>")
	)
	(arc
		(start 248.143014 -86.994238)
		(mid 248.222236 -87.283356)
		(end 248.149364 -87.57412)
		(width 0.0889)
		(layer "In4.Cu")
		(net "M_F_ECC<3>")
	)
	(arc
		(start 248.143014 -88.975438)
		(mid 248.222236 -89.264556)
		(end 248.149364 -89.55532)
		(width 0.0889)
		(layer "In4.Cu")
		(net "M_F_ECC<3>")
	)
	(arc
		(start 248.138188 -85.612224)
		(mid 248.089433 -85.808576)
		(end 248.143014 -86.003638)
		(width 0.0889)
		(layer "In4.Cu")
		(net "M_F_ECC<3>")
	)
	(arc
		(start 248.143014 -93.528642)
		(mid 248.089515 -93.72854)
		(end 248.143014 -93.928438)
		(width 0.0889)
		(layer "In4.Cu")
		(net "M_F_ECC<3>")
	)
	(arc
		(start 248.138188 -91.555824)
		(mid 248.089433 -91.752176)
		(end 248.143014 -91.947238)
		(width 0.0889)
		(layer "In4.Cu")
		(net "M_F_ECC<3>")
	)
	(arc
		(start 248.143014 -94.919038)
		(mid 248.222236 -95.208156)
		(end 248.149364 -95.49892)
		(width 0.0889)
		(layer "In4.Cu")
		(net "M_F_ECC<3>")
	)
	(arc
		(start 248.138188 -88.584024)
		(mid 248.089433 -88.780376)
		(end 248.143014 -88.975438)
		(width 0.0889)
		(layer "In4.Cu")
		(net "M_F_ECC<3>")
	)
	(arc
		(start 248.143014 -85.013038)
		(mid 248.222236 -85.302156)
		(end 248.149364 -85.59292)
		(width 0.0889)
		(layer "In4.Cu")
		(net "M_F_ECC<3>")
	)
	(arc
		(start 248.143014 -86.003638)
		(mid 248.222236 -86.292756)
		(end 248.149364 -86.58352)
		(width 0.0889)
		(layer "In4.Cu")
		(net "M_F_ECC<3>")
	)
	(arc
		(start 248.138188 -95.518224)
		(mid 248.089433 -95.714576)
		(end 248.143014 -95.909638)
		(width 0.0889)
		(layer "In4.Cu")
		(net "M_F_ECC<3>")
	)
	(arc
		(start 248.138188 -90.565224)
		(mid 248.089433 -90.761576)
		(end 248.143014 -90.956638)
		(width 0.0889)
		(layer "In4.Cu")
		(net "M_F_ECC<3>")
	)
	(arc
		(start 248.143014 -90.956638)
		(mid 248.222236 -91.245756)
		(end 248.149364 -91.53652)
		(width 0.0889)
		(layer "In4.Cu")
		(net "M_F_ECC<3>")
	)
	(arc
		(start 248.149364 -93.939106)
		(mid 248.222162 -94.229869)
		(end 248.143014 -94.518988)
		(width 0.0889)
		(layer "In4.Cu")
		(net "M_F_ECC<3>")
	)
	(arc
		(start 248.138188 -92.546424)
		(mid 248.089433 -92.742776)
		(end 248.143014 -92.937838)
		(width 0.0889)
		(layer "In4.Cu")
		(net "M_F_ECC<3>")
	)
	(segment
		(start 241.61115 -151.660352)
		(end 241.61115 -151.387048)
		(width 0.14224)
		(layer "In11.Cu")
		(net "M_F_ECC<3>")
	)
	(segment
		(start 241.868198 -151.9174)
		(end 241.61115 -151.660352)
		(width 0.14224)
		(layer "In11.Cu")
		(net "M_F_ECC<3>")
	)
	(segment
		(start 241.722148 -153.542746)
		(end 241.899948 -153.364946)
		(width 0.14224)
		(layer "In11.Cu")
		(net "M_F_ECC<3>")
	)
	(segment
		(start 241.893598 -150.435818)
		(end 241.849148 -150.391368)
		(width 0.14224)
		(layer "In11.Cu")
		(net "M_F_ECC<3>")
	)
	(segment
		(start 241.849148 -149.9616)
		(end 242.277392 -149.533356)
		(width 0.14224)
		(layer "In11.Cu")
		(net "M_F_ECC<3>")
	)
	(segment
		(start 241.899948 -153.04135)
		(end 241.61115 -152.752552)
		(width 0.14224)
		(layer "In11.Cu")
		(net "M_F_ECC<3>")
	)
	(segment
		(start 241.893598 -151.1046)
		(end 241.893598 -150.435818)
		(width 0.14224)
		(layer "In11.Cu")
		(net "M_F_ECC<3>")
	)
	(segment
		(start 241.849148 -150.391368)
		(end 241.849148 -149.9616)
		(width 0.14224)
		(layer "In11.Cu")
		(net "M_F_ECC<3>")
	)
	(segment
		(start 241.61115 -151.387048)
		(end 241.893598 -151.1046)
		(width 0.14224)
		(layer "In11.Cu")
		(net "M_F_ECC<3>")
	)
	(segment
		(start 241.61115 -152.752552)
		(end 241.61115 -152.479248)
		(width 0.14224)
		(layer "In11.Cu")
		(net "M_F_ECC<3>")
	)
	(segment
		(start 241.868198 -152.2222)
		(end 241.868198 -151.9174)
		(width 0.14224)
		(layer "In11.Cu")
		(net "M_F_ECC<3>")
	)
	(segment
		(start 241.61115 -152.479248)
		(end 241.868198 -152.2222)
		(width 0.14224)
		(layer "In11.Cu")
		(net "M_F_ECC<3>")
	)
	(segment
		(start 241.899948 -153.364946)
		(end 241.899948 -153.04135)
		(width 0.14224)
		(layer "In11.Cu")
		(net "M_F_ECC<3>")
	)
	(segment
		(start 242.277392 -149.533356)
		(end 242.299744 -149.533356)
		(width 0.14224)
		(layer "In11.Cu")
		(net "M_F_ECC<3>")
	)
	(segment
		(start 241.44986 -153.542746)
		(end 241.722148 -153.542746)
		(width 0.14224)
		(layer "In11.Cu")
		(net "M_F_ECC<3>")
	)
	(segment
		(start 248.202704 -83.32724)
		(end 247.631204 -83.32724)
		(width 0.1651)
		(layer "F.Cu")
		(net "M_F_ECC<2>")
	)
	(segment
		(start 242.299744 -155.395168)
		(end 242.299744 -155.1178)
		(width 0.1651)
		(layer "F.Cu")
		(net "M_F_ECC<2>")
	)
	(segment
		(start 242.299744 -155.881832)
		(end 242.431316 -155.75026)
		(width 0.1651)
		(layer "F.Cu")
		(net "M_F_ECC<2>")
	)
	(segment
		(start 242.299744 -156.87294)
		(end 242.299744 -155.881832)
		(width 0.1651)
		(layer "F.Cu")
		(net "M_F_ECC<2>")
	)
	(segment
		(start 242.431316 -155.75026)
		(end 242.431316 -155.52674)
		(width 0.1651)
		(layer "F.Cu")
		(net "M_F_ECC<2>")
	)
	(segment
		(start 242.300506 -156.87294)
		(end 242.299744 -156.87294)
		(width 0.1651)
		(layer "F.Cu")
		(net "M_F_ECC<2>")
	)
	(segment
		(start 242.431316 -155.52674)
		(end 242.299744 -155.395168)
		(width 0.1651)
		(layer "F.Cu")
		(net "M_F_ECC<2>")
	)
	(via
		(at 242.299744 -155.1178)
		(size 0.508)
		(drill 0.254)
		(layers "F.Cu" "B.Cu")
		(net "M_F_ECC<2>")
	)
	(via
		(at 241.44986 -150.814278)
		(size 0.508)
		(drill 0.254)
		(layers "F.Cu" "B.Cu")
		(net "M_F_ECC<2>")
	)
	(via
		(at 247.631204 -83.32724)
		(size 0.508)
		(drill 0.254)
		(layers "F.Cu" "B.Cu")
		(net "M_F_ECC<2>")
	)
	(segment
		(start 241.450368 -152.078436)
		(end 241.44986 -152.078182)
		(width 0.1651)
		(layer "B.Cu")
		(net "M_F_ECC<2>")
	)
	(segment
		(start 241.44986 -152.078182)
		(end 241.44986 -150.814278)
		(width 0.1651)
		(layer "B.Cu")
		(net "M_F_ECC<2>")
	)
	(segment
		(start 241.875564 -143.679164)
		(end 242.019328 -143.822928)
		(width 0.14224)
		(layer "In4.Cu")
		(net "M_F_ECC<2>")
	)
	(segment
		(start 241.790728 -136.126728)
		(end 241.943128 -136.279128)
		(width 0.14224)
		(layer "In4.Cu")
		(net "M_F_ECC<2>")
	)
	(segment
		(start 241.943128 -138.819128)
		(end 241.943128 -139.435078)
		(width 0.14224)
		(layer "In4.Cu")
		(net "M_F_ECC<2>")
	)
	(segment
		(start 241.739928 -145.578068)
		(end 241.968528 -145.806668)
		(width 0.14224)
		(layer "In4.Cu")
		(net "M_F_ECC<2>")
	)
	(segment
		(start 241.968528 -148.547328)
		(end 241.968528 -148.972778)
		(width 0.14224)
		(layer "In4.Cu")
		(net "M_F_ECC<2>")
	)
	(segment
		(start 240.853468 -120.841008)
		(end 240.853468 -122.57913)
		(width 0.14224)
		(layer "In4.Cu")
		(net "M_F_ECC<2>")
	)
	(segment
		(start 241.943128 -136.279128)
		(end 241.943128 -136.6266)
		(width 0.14224)
		(layer "In4.Cu")
		(net "M_F_ECC<2>")
	)
	(segment
		(start 242.0112 -123.736862)
		(end 242.0112 -125.349)
		(width 0.14224)
		(layer "In4.Cu")
		(net "M_F_ECC<2>")
	)
	(segment
		(start 248.629424 -97.132648)
		(end 248.629424 -102.889558)
		(width 0.0889)
		(layer "In4.Cu")
		(net "M_F_ECC<2>")
	)
	(segment
		(start 242.019328 -141.136878)
		(end 242.019328 -141.5034)
		(width 0.14224)
		(layer "In4.Cu")
		(net "M_F_ECC<2>")
	)
	(segment
		(start 241.780314 -129.996692)
		(end 241.780314 -131.275328)
		(width 0.14224)
		(layer "In4.Cu")
		(net "M_F_ECC<2>")
	)
	(segment
		(start 248.466864 -106.087672)
		(end 242.410488 -112.144048)
		(width 0.14224)
		(layer "In4.Cu")
		(net "M_F_ECC<2>")
	)
	(segment
		(start 240.853468 -122.57913)
		(end 242.0112 -123.736862)
		(width 0.14224)
		(layer "In4.Cu")
		(net "M_F_ECC<2>")
	)
	(segment
		(start 247.977914 -90.461338)
		(end 247.971564 -90.472006)
		(width 0.0889)
		(layer "In4.Cu")
		(net "M_F_ECC<2>")
	)
	(segment
		(start 242.410488 -112.144048)
		(end 242.410488 -119.283988)
		(width 0.14224)
		(layer "In4.Cu")
		(net "M_F_ECC<2>")
	)
	(segment
		(start 241.8842 -125.476)
		(end 241.8842 -127.0254)
		(width 0.14224)
		(layer "In4.Cu")
		(net "M_F_ECC<2>")
	)
	(segment
		(start 247.98274 -86.490302)
		(end 247.977914 -86.498938)
		(width 0.0889)
		(layer "In4.Cu")
		(net "M_F_ECC<2>")
	)
	(segment
		(start 247.971564 -94.01302)
		(end 247.977914 -94.023688)
		(width 0.0889)
		(layer "In4.Cu")
		(net "M_F_ECC<2>")
	)
	(segment
		(start 247.98274 -89.462102)
		(end 247.977914 -89.470738)
		(width 0.0889)
		(layer "In4.Cu")
		(net "M_F_ECC<2>")
	)
	(segment
		(start 241.943128 -129.833878)
		(end 241.780314 -129.996692)
		(width 0.14224)
		(layer "In4.Cu")
		(net "M_F_ECC<2>")
	)
	(segment
		(start 247.977914 -96.004888)
		(end 248.629424 -97.132648)
		(width 0.0889)
		(layer "In4.Cu")
		(net "M_F_ECC<2>")
	)
	(segment
		(start 241.8842 -138.7602)
		(end 241.943128 -138.819128)
		(width 0.14224)
		(layer "In4.Cu")
		(net "M_F_ECC<2>")
	)
	(segment
		(start 242.0112 -125.349)
		(end 241.8842 -125.476)
		(width 0.14224)
		(layer "In4.Cu")
		(net "M_F_ECC<2>")
	)
	(segment
		(start 247.977914 -87.489538)
		(end 247.971564 -87.500206)
		(width 0.0889)
		(layer "In4.Cu")
		(net "M_F_ECC<2>")
	)
	(segment
		(start 247.977914 -88.480138)
		(end 247.971564 -88.490806)
		(width 0.0889)
		(layer "In4.Cu")
		(net "M_F_ECC<2>")
	)
	(segment
		(start 247.977914 -91.451938)
		(end 247.971564 -91.462606)
		(width 0.0889)
		(layer "In4.Cu")
		(net "M_F_ECC<2>")
	)
	(segment
		(start 242.032028 -134.259828)
		(end 242.032028 -134.471664)
		(width 0.14224)
		(layer "In4.Cu")
		(net "M_F_ECC<2>")
	)
	(segment
		(start 241.8842 -148.463)
		(end 241.968528 -148.547328)
		(width 0.14224)
		(layer "In4.Cu")
		(net "M_F_ECC<2>")
	)
	(segment
		(start 241.943128 -129.395728)
		(end 241.943128 -129.833878)
		(width 0.14224)
		(layer "In4.Cu")
		(net "M_F_ECC<2>")
	)
	(segment
		(start 241.816128 -139.562078)
		(end 241.816128 -140.933678)
		(width 0.14224)
		(layer "In4.Cu")
		(net "M_F_ECC<2>")
	)
	(segment
		(start 242.019328 -144.093438)
		(end 241.739928 -144.372838)
		(width 0.14224)
		(layer "In4.Cu")
		(net "M_F_ECC<2>")
	)
	(segment
		(start 242.032028 -134.471664)
		(end 241.790728 -134.712964)
		(width 0.14224)
		(layer "In4.Cu")
		(net "M_F_ECC<2>")
	)
	(segment
		(start 241.3254 -150.689818)
		(end 241.44986 -150.814278)
		(width 0.14224)
		(layer "In4.Cu")
		(net "M_F_ECC<2>")
	)
	(segment
		(start 247.977914 -86.498938)
		(end 247.971564 -86.509606)
		(width 0.0889)
		(layer "In4.Cu")
		(net "M_F_ECC<2>")
	)
	(segment
		(start 248.629424 -102.889558)
		(end 248.466864 -103.052118)
		(width 0.0889)
		(layer "In4.Cu")
		(net "M_F_ECC<2>")
	)
	(segment
		(start 247.98274 -92.433902)
		(end 247.977914 -92.442538)
		(width 0.0889)
		(layer "In4.Cu")
		(net "M_F_ECC<2>")
	)
	(segment
		(start 247.98274 -91.443302)
		(end 247.977914 -91.451938)
		(width 0.0889)
		(layer "In4.Cu")
		(net "M_F_ECC<2>")
	)
	(segment
		(start 242.410488 -119.283988)
		(end 240.853468 -120.841008)
		(width 0.14224)
		(layer "In4.Cu")
		(net "M_F_ECC<2>")
	)
	(segment
		(start 242.032028 -131.8768)
		(end 241.8842 -132.024628)
		(width 0.14224)
		(layer "In4.Cu")
		(net "M_F_ECC<2>")
	)
	(segment
		(start 247.98274 -88.471502)
		(end 247.977914 -88.480138)
		(width 0.0889)
		(layer "In4.Cu")
		(net "M_F_ECC<2>")
	)
	(segment
		(start 247.977914 -85.508338)
		(end 247.971564 -85.519006)
		(width 0.0889)
		(layer "In4.Cu")
		(net "M_F_ECC<2>")
	)
	(segment
		(start 241.875564 -141.647164)
		(end 241.875564 -143.679164)
		(width 0.14224)
		(layer "In4.Cu")
		(net "M_F_ECC<2>")
	)
	(segment
		(start 241.8842 -132.024628)
		(end 241.8842 -134.112)
		(width 0.14224)
		(layer "In4.Cu")
		(net "M_F_ECC<2>")
	)
	(segment
		(start 247.936004 -85.035898)
		(end 247.977914 -85.108288)
		(width 0.0889)
		(layer "In4.Cu")
		(net "M_F_ECC<2>")
	)
	(segment
		(start 247.631204 -83.32724)
		(end 247.301258 -84.088986)
		(width 0.0889)
		(layer "In4.Cu")
		(net "M_F_ECC<2>")
	)
	(segment
		(start 241.968528 -148.972778)
		(end 241.3254 -149.615906)
		(width 0.14224)
		(layer "In4.Cu")
		(net "M_F_ECC<2>")
	)
	(segment
		(start 247.98274 -93.424502)
		(end 247.977914 -93.433138)
		(width 0.0889)
		(layer "In4.Cu")
		(net "M_F_ECC<2>")
	)
	(segment
		(start 241.943128 -136.6266)
		(end 241.8842 -136.685528)
		(width 0.14224)
		(layer "In4.Cu")
		(net "M_F_ECC<2>")
	)
	(segment
		(start 241.8842 -146.312128)
		(end 241.8842 -148.463)
		(width 0.14224)
		(layer "In4.Cu")
		(net "M_F_ECC<2>")
	)
	(segment
		(start 247.301258 -84.088986)
		(end 247.284494 -84.117688)
		(width 0.0889)
		(layer "In4.Cu")
		(net "M_F_ECC<2>")
	)
	(segment
		(start 241.8842 -134.112)
		(end 242.032028 -134.259828)
		(width 0.14224)
		(layer "In4.Cu")
		(net "M_F_ECC<2>")
	)
	(segment
		(start 242.019328 -141.5034)
		(end 241.875564 -141.647164)
		(width 0.14224)
		(layer "In4.Cu")
		(net "M_F_ECC<2>")
	)
	(segment
		(start 247.793256 -84.879942)
		(end 247.850914 -84.931758)
		(width 0.0889)
		(layer "In4.Cu")
		(net "M_F_ECC<2>")
	)
	(segment
		(start 247.98274 -95.405702)
		(end 247.977914 -95.414338)
		(width 0.0889)
		(layer "In4.Cu")
		(net "M_F_ECC<2>")
	)
	(segment
		(start 241.816128 -140.933678)
		(end 242.019328 -141.136878)
		(width 0.14224)
		(layer "In4.Cu")
		(net "M_F_ECC<2>")
	)
	(segment
		(start 247.98274 -85.499702)
		(end 247.977914 -85.508338)
		(width 0.0889)
		(layer "In4.Cu")
		(net "M_F_ECC<2>")
	)
	(segment
		(start 241.968528 -145.806668)
		(end 241.968528 -146.2278)
		(width 0.14224)
		(layer "In4.Cu")
		(net "M_F_ECC<2>")
	)
	(segment
		(start 241.3254 -149.615906)
		(end 241.3254 -150.689818)
		(width 0.14224)
		(layer "In4.Cu")
		(net "M_F_ECC<2>")
	)
	(segment
		(start 247.534176 -84.706206)
		(end 247.793256 -84.879942)
		(width 0.0889)
		(layer "In4.Cu")
		(net "M_F_ECC<2>")
	)
	(segment
		(start 241.4524 -128.905)
		(end 241.943128 -129.395728)
		(width 0.14224)
		(layer "In4.Cu")
		(net "M_F_ECC<2>")
	)
	(segment
		(start 242.019328 -143.822928)
		(end 242.019328 -144.093438)
		(width 0.14224)
		(layer "In4.Cu")
		(net "M_F_ECC<2>")
	)
	(segment
		(start 241.790728 -134.712964)
		(end 241.790728 -136.126728)
		(width 0.14224)
		(layer "In4.Cu")
		(net "M_F_ECC<2>")
	)
	(segment
		(start 247.98274 -90.452702)
		(end 247.977914 -90.461338)
		(width 0.0889)
		(layer "In4.Cu")
		(net "M_F_ECC<2>")
	)
	(segment
		(start 247.98274 -87.480902)
		(end 247.977914 -87.489538)
		(width 0.0889)
		(layer "In4.Cu")
		(net "M_F_ECC<2>")
	)
	(segment
		(start 248.466864 -103.052118)
		(end 248.466864 -106.087672)
		(width 0.14224)
		(layer "In4.Cu")
		(net "M_F_ECC<2>")
	)
	(segment
		(start 242.032028 -131.527042)
		(end 242.032028 -131.8768)
		(width 0.14224)
		(layer "In4.Cu")
		(net "M_F_ECC<2>")
	)
	(segment
		(start 241.943128 -139.435078)
		(end 241.816128 -139.562078)
		(width 0.14224)
		(layer "In4.Cu")
		(net "M_F_ECC<2>")
	)
	(segment
		(start 241.739928 -144.372838)
		(end 241.739928 -145.578068)
		(width 0.14224)
		(layer "In4.Cu")
		(net "M_F_ECC<2>")
	)
	(segment
		(start 241.8842 -127.0254)
		(end 241.4524 -127.4572)
		(width 0.14224)
		(layer "In4.Cu")
		(net "M_F_ECC<2>")
	)
	(segment
		(start 247.977914 -95.414338)
		(end 247.971564 -95.425006)
		(width 0.0889)
		(layer "In4.Cu")
		(net "M_F_ECC<2>")
	)
	(segment
		(start 247.977914 -89.470738)
		(end 247.971564 -89.481406)
		(width 0.0889)
		(layer "In4.Cu")
		(net "M_F_ECC<2>")
	)
	(segment
		(start 241.780314 -131.275328)
		(end 242.032028 -131.527042)
		(width 0.14224)
		(layer "In4.Cu")
		(net "M_F_ECC<2>")
	)
	(segment
		(start 247.850914 -84.931758)
		(end 247.936004 -85.035898)
		(width 0.0889)
		(layer "In4.Cu")
		(net "M_F_ECC<2>")
	)
	(segment
		(start 241.4524 -127.4572)
		(end 241.4524 -128.905)
		(width 0.14224)
		(layer "In4.Cu")
		(net "M_F_ECC<2>")
	)
	(segment
		(start 241.968528 -146.2278)
		(end 241.8842 -146.312128)
		(width 0.14224)
		(layer "In4.Cu")
		(net "M_F_ECC<2>")
	)
	(segment
		(start 247.977914 -92.442538)
		(end 247.971564 -92.453206)
		(width 0.0889)
		(layer "In4.Cu")
		(net "M_F_ECC<2>")
	)
	(segment
		(start 241.8842 -136.685528)
		(end 241.8842 -138.7602)
		(width 0.14224)
		(layer "In4.Cu")
		(net "M_F_ECC<2>")
	)
	(arc
		(start 247.971564 -89.481406)
		(mid 247.898766 -89.772169)
		(end 247.977914 -90.061288)
		(width 0.0889)
		(layer "In4.Cu")
		(net "M_F_ECC<2>")
	)
	(arc
		(start 247.971564 -92.453206)
		(mid 247.898766 -92.743969)
		(end 247.977914 -93.033088)
		(width 0.0889)
		(layer "In4.Cu")
		(net "M_F_ECC<2>")
	)
	(arc
		(start 247.977914 -85.108288)
		(mid 248.031384 -85.303351)
		(end 247.98274 -85.499702)
		(width 0.0889)
		(layer "In4.Cu")
		(net "M_F_ECC<2>")
	)
	(arc
		(start 247.977914 -93.033088)
		(mid 248.031384 -93.228151)
		(end 247.98274 -93.424502)
		(width 0.0889)
		(layer "In4.Cu")
		(net "M_F_ECC<2>")
	)
	(arc
		(start 247.977914 -87.089488)
		(mid 248.031384 -87.284551)
		(end 247.98274 -87.480902)
		(width 0.0889)
		(layer "In4.Cu")
		(net "M_F_ECC<2>")
	)
	(arc
		(start 247.977914 -89.070688)
		(mid 248.031384 -89.265751)
		(end 247.98274 -89.462102)
		(width 0.0889)
		(layer "In4.Cu")
		(net "M_F_ECC<2>")
	)
	(arc
		(start 247.971564 -87.500206)
		(mid 247.898766 -87.790969)
		(end 247.977914 -88.080088)
		(width 0.0889)
		(layer "In4.Cu")
		(net "M_F_ECC<2>")
	)
	(arc
		(start 247.284494 -84.117688)
		(mid 247.262659 -84.474184)
		(end 247.534176 -84.706206)
		(width 0.0889)
		(layer "In4.Cu")
		(net "M_F_ECC<2>")
	)
	(arc
		(start 247.977914 -90.061288)
		(mid 248.031384 -90.256351)
		(end 247.98274 -90.452702)
		(width 0.0889)
		(layer "In4.Cu")
		(net "M_F_ECC<2>")
	)
	(arc
		(start 247.971564 -85.519006)
		(mid 247.898766 -85.809769)
		(end 247.977914 -86.098888)
		(width 0.0889)
		(layer "In4.Cu")
		(net "M_F_ECC<2>")
	)
	(arc
		(start 247.971564 -91.462606)
		(mid 247.898766 -91.753369)
		(end 247.977914 -92.042488)
		(width 0.0889)
		(layer "In4.Cu")
		(net "M_F_ECC<2>")
	)
	(arc
		(start 247.977914 -94.423484)
		(mid 247.898783 -94.718886)
		(end 247.977914 -95.014288)
		(width 0.0889)
		(layer "In4.Cu")
		(net "M_F_ECC<2>")
	)
	(arc
		(start 247.977914 -94.023688)
		(mid 248.031413 -94.223586)
		(end 247.977914 -94.423484)
		(width 0.0889)
		(layer "In4.Cu")
		(net "M_F_ECC<2>")
	)
	(arc
		(start 247.971564 -88.490806)
		(mid 247.898766 -88.781569)
		(end 247.977914 -89.070688)
		(width 0.0889)
		(layer "In4.Cu")
		(net "M_F_ECC<2>")
	)
	(arc
		(start 247.971564 -95.425006)
		(mid 247.898766 -95.715769)
		(end 247.977914 -96.004888)
		(width 0.0889)
		(layer "In4.Cu")
		(net "M_F_ECC<2>")
	)
	(arc
		(start 247.977914 -95.014288)
		(mid 248.031384 -95.209351)
		(end 247.98274 -95.405702)
		(width 0.0889)
		(layer "In4.Cu")
		(net "M_F_ECC<2>")
	)
	(arc
		(start 247.971564 -86.509606)
		(mid 247.898766 -86.800369)
		(end 247.977914 -87.089488)
		(width 0.0889)
		(layer "In4.Cu")
		(net "M_F_ECC<2>")
	)
	(arc
		(start 247.977914 -91.051888)
		(mid 248.031384 -91.246951)
		(end 247.98274 -91.443302)
		(width 0.0889)
		(layer "In4.Cu")
		(net "M_F_ECC<2>")
	)
	(arc
		(start 247.977914 -86.098888)
		(mid 248.031384 -86.293951)
		(end 247.98274 -86.490302)
		(width 0.0889)
		(layer "In4.Cu")
		(net "M_F_ECC<2>")
	)
	(arc
		(start 247.977914 -93.433138)
		(mid 247.898692 -93.722256)
		(end 247.971564 -94.01302)
		(width 0.0889)
		(layer "In4.Cu")
		(net "M_F_ECC<2>")
	)
	(arc
		(start 247.977914 -88.080088)
		(mid 248.031384 -88.275151)
		(end 247.98274 -88.471502)
		(width 0.0889)
		(layer "In4.Cu")
		(net "M_F_ECC<2>")
	)
	(arc
		(start 247.977914 -92.042488)
		(mid 248.031384 -92.237551)
		(end 247.98274 -92.433902)
		(width 0.0889)
		(layer "In4.Cu")
		(net "M_F_ECC<2>")
	)
	(arc
		(start 247.971564 -90.472006)
		(mid 247.898766 -90.762769)
		(end 247.977914 -91.051888)
		(width 0.0889)
		(layer "In4.Cu")
		(net "M_F_ECC<2>")
	)
	(segment
		(start 242.299744 -155.1178)
		(end 241.01679 -153.834846)
		(width 0.14224)
		(layer "In11.Cu")
		(net "M_F_ECC<2>")
	)
	(segment
		(start 241.01679 -153.834846)
		(end 241.01679 -151.247348)
		(width 0.14224)
		(layer "In11.Cu")
		(net "M_F_ECC<2>")
	)
	(segment
		(start 241.01679 -151.247348)
		(end 241.44986 -150.814278)
		(width 0.14224)
		(layer "In11.Cu")
		(net "M_F_ECC<2>")
	)
	(segment
		(start 235.49991 -152.278842)
		(end 235.49991 -153.542746)
		(width 0.1651)
		(layer "F.Cu")
		(net "M_F_ECC<1>")
	)
	(segment
		(start 245.627144 -84.812886)
		(end 245.055644 -84.812886)
		(width 0.1651)
		(layer "F.Cu")
		(net "M_F_ECC<1>")
	)
	(segment
		(start 235.500418 -152.273)
		(end 235.49991 -152.278842)
		(width 0.1651)
		(layer "F.Cu")
		(net "M_F_ECC<1>")
	)
	(via
		(at 236.171994 -149.533356)
		(size 0.508)
		(drill 0.254)
		(layers "F.Cu" "B.Cu")
		(net "M_F_ECC<1>")
	)
	(via
		(at 235.49991 -153.542746)
		(size 0.508)
		(drill 0.254)
		(layers "F.Cu" "B.Cu")
		(net "M_F_ECC<1>")
	)
	(via
		(at 245.055644 -84.812886)
		(size 0.508)
		(drill 0.254)
		(layers "F.Cu" "B.Cu")
		(net "M_F_ECC<1>")
	)
	(segment
		(start 236.171994 -149.030182)
		(end 236.349794 -148.852382)
		(width 0.1651)
		(layer "B.Cu")
		(net "M_F_ECC<1>")
	)
	(segment
		(start 236.349794 -148.852382)
		(end 236.349794 -147.478496)
		(width 0.1651)
		(layer "B.Cu")
		(net "M_F_ECC<1>")
	)
	(segment
		(start 236.171994 -149.533356)
		(end 236.171994 -149.030182)
		(width 0.1651)
		(layer "B.Cu")
		(net "M_F_ECC<1>")
	)
	(segment
		(start 236.349794 -147.478496)
		(end 236.350302 -147.478496)
		(width 0.1651)
		(layer "B.Cu")
		(net "M_F_ECC<1>")
	)
	(segment
		(start 238.0488 -111.023654)
		(end 238.0488 -114.203988)
		(width 0.14224)
		(layer "In4.Cu")
		(net "M_F_ECC<1>")
	)
	(segment
		(start 236.4232 -123.6472)
		(end 236.659928 -123.883928)
		(width 0.14224)
		(layer "In4.Cu")
		(net "M_F_ECC<1>")
	)
	(segment
		(start 236.656118 -112.68964)
		(end 236.4232 -112.922558)
		(width 0.14224)
		(layer "In4.Cu")
		(net "M_F_ECC<1>")
	)
	(segment
		(start 236.659928 -141.351)
		(end 236.7788 -141.469872)
		(width 0.14224)
		(layer "In4.Cu")
		(net "M_F_ECC<1>")
	)
	(segment
		(start 244.715284 -95.49892)
		(end 244.708934 -95.509588)
		(width 0.0889)
		(layer "In4.Cu")
		(net "M_F_ECC<1>")
	)
	(segment
		(start 244.120416 -100.571554)
		(end 244.120416 -101.468682)
		(width 0.0889)
		(layer "In4.Cu")
		(net "M_F_ECC<1>")
	)
	(segment
		(start 236.7788 -136.694672)
		(end 236.7788 -138.7602)
		(width 0.14224)
		(layer "In4.Cu")
		(net "M_F_ECC<1>")
	)
	(segment
		(start 236.659928 -148.404072)
		(end 236.659928 -148.956522)
		(width 0.14224)
		(layer "In4.Cu")
		(net "M_F_ECC<1>")
	)
	(segment
		(start 236.7788 -141.469872)
		(end 236.7788 -142.9004)
		(width 0.14224)
		(layer "In4.Cu")
		(net "M_F_ECC<1>")
	)
	(segment
		(start 244.715284 -96.48952)
		(end 244.708934 -96.500188)
		(width 0.0889)
		(layer "In4.Cu")
		(net "M_F_ECC<1>")
	)
	(segment
		(start 236.7788 -148.2852)
		(end 236.659928 -148.404072)
		(width 0.14224)
		(layer "In4.Cu")
		(net "M_F_ECC<1>")
	)
	(segment
		(start 244.708934 -91.547188)
		(end 244.704108 -91.555824)
		(width 0.0889)
		(layer "In4.Cu")
		(net "M_F_ECC<1>")
	)
	(segment
		(start 244.330982 -104.741472)
		(end 238.0488 -111.023654)
		(width 0.14224)
		(layer "In4.Cu")
		(net "M_F_ECC<1>")
	)
	(segment
		(start 244.708934 -89.565988)
		(end 244.704108 -89.574624)
		(width 0.0889)
		(layer "In4.Cu")
		(net "M_F_ECC<1>")
	)
	(segment
		(start 244.120416 -101.468682)
		(end 244.330982 -101.679248)
		(width 0.0889)
		(layer "In4.Cu")
		(net "M_F_ECC<1>")
	)
	(segment
		(start 245.055644 -84.812886)
		(end 244.726206 -85.57387)
		(width 0.0889)
		(layer "In4.Cu")
		(net "M_F_ECC<1>")
	)
	(segment
		(start 236.7788 -134.0866)
		(end 236.659928 -134.205472)
		(width 0.14224)
		(layer "In4.Cu")
		(net "M_F_ECC<1>")
	)
	(segment
		(start 244.715284 -92.52712)
		(end 244.708934 -92.537788)
		(width 0.0889)
		(layer "In4.Cu")
		(net "M_F_ECC<1>")
	)
	(segment
		(start 238.0488 -114.203988)
		(end 237.815628 -114.43716)
		(width 0.14224)
		(layer "In4.Cu")
		(net "M_F_ECC<1>")
	)
	(segment
		(start 244.330982 -101.679248)
		(end 244.330982 -104.741472)
		(width 0.14224)
		(layer "In4.Cu")
		(net "M_F_ECC<1>")
	)
	(segment
		(start 244.715284 -90.54592)
		(end 244.708934 -90.556588)
		(width 0.0889)
		(layer "In4.Cu")
		(net "M_F_ECC<1>")
	)
	(segment
		(start 244.708934 -97.490788)
		(end 244.704108 -97.499424)
		(width 0.0889)
		(layer "In4.Cu")
		(net "M_F_ECC<1>")
	)
	(segment
		(start 244.708934 -88.575388)
		(end 244.704108 -88.584024)
		(width 0.0889)
		(layer "In4.Cu")
		(net "M_F_ECC<1>")
	)
	(segment
		(start 244.708934 -96.500188)
		(end 244.704108 -96.508824)
		(width 0.0889)
		(layer "In4.Cu")
		(net "M_F_ECC<1>")
	)
	(segment
		(start 236.659928 -138.879072)
		(end 236.659928 -141.351)
		(width 0.14224)
		(layer "In4.Cu")
		(net "M_F_ECC<1>")
	)
	(segment
		(start 237.815628 -114.43716)
		(end 237.409228 -114.43716)
		(width 0.14224)
		(layer "In4.Cu")
		(net "M_F_ECC<1>")
	)
	(segment
		(start 236.659928 -136.5758)
		(end 236.7788 -136.694672)
		(width 0.14224)
		(layer "In4.Cu")
		(net "M_F_ECC<1>")
	)
	(segment
		(start 236.7788 -142.9004)
		(end 236.659928 -143.019272)
		(width 0.14224)
		(layer "In4.Cu")
		(net "M_F_ECC<1>")
	)
	(segment
		(start 236.7788 -146.321272)
		(end 236.7788 -148.2852)
		(width 0.14224)
		(layer "In4.Cu")
		(net "M_F_ECC<1>")
	)
	(segment
		(start 244.544088 -100.147882)
		(end 244.120416 -100.571554)
		(width 0.0889)
		(layer "In4.Cu")
		(net "M_F_ECC<1>")
	)
	(segment
		(start 237.236 -112.863122)
		(end 237.062518 -112.68964)
		(width 0.14224)
		(layer "In4.Cu")
		(net "M_F_ECC<1>")
	)
	(segment
		(start 236.7788 -132.0546)
		(end 236.7788 -134.0866)
		(width 0.14224)
		(layer "In4.Cu")
		(net "M_F_ECC<1>")
	)
	(segment
		(start 237.236 -114.263932)
		(end 237.236 -112.863122)
		(width 0.14224)
		(layer "In4.Cu")
		(net "M_F_ECC<1>")
	)
	(segment
		(start 244.715284 -91.53652)
		(end 244.708934 -91.547188)
		(width 0.0889)
		(layer "In4.Cu")
		(net "M_F_ECC<1>")
	)
	(segment
		(start 236.4232 -112.922558)
		(end 236.4232 -123.6472)
		(width 0.14224)
		(layer "In4.Cu")
		(net "M_F_ECC<1>")
	)
	(segment
		(start 244.715284 -97.48012)
		(end 244.708934 -97.490788)
		(width 0.0889)
		(layer "In4.Cu")
		(net "M_F_ECC<1>")
	)
	(segment
		(start 236.659928 -148.956522)
		(end 236.171994 -149.444456)
		(width 0.14224)
		(layer "In4.Cu")
		(net "M_F_ECC<1>")
	)
	(segment
		(start 244.708934 -90.556588)
		(end 244.704108 -90.565224)
		(width 0.0889)
		(layer "In4.Cu")
		(net "M_F_ECC<1>")
	)
	(segment
		(start 237.062518 -112.68964)
		(end 236.656118 -112.68964)
		(width 0.14224)
		(layer "In4.Cu")
		(net "M_F_ECC<1>")
	)
	(segment
		(start 236.659928 -134.205472)
		(end 236.659928 -136.5758)
		(width 0.14224)
		(layer "In4.Cu")
		(net "M_F_ECC<1>")
	)
	(segment
		(start 236.7788 -138.7602)
		(end 236.659928 -138.879072)
		(width 0.14224)
		(layer "In4.Cu")
		(net "M_F_ECC<1>")
	)
	(segment
		(start 244.544088 -98.775266)
		(end 244.544088 -100.147882)
		(width 0.0889)
		(layer "In4.Cu")
		(net "M_F_ECC<1>")
	)
	(segment
		(start 244.715284 -86.58352)
		(end 244.708934 -86.594188)
		(width 0.0889)
		(layer "In4.Cu")
		(net "M_F_ECC<1>")
	)
	(segment
		(start 244.715284 -88.56472)
		(end 244.708934 -88.575388)
		(width 0.0889)
		(layer "In4.Cu")
		(net "M_F_ECC<1>")
	)
	(segment
		(start 236.659928 -131.935728)
		(end 236.7788 -132.0546)
		(width 0.14224)
		(layer "In4.Cu")
		(net "M_F_ECC<1>")
	)
	(segment
		(start 244.708934 -87.584788)
		(end 244.704108 -87.593424)
		(width 0.0889)
		(layer "In4.Cu")
		(net "M_F_ECC<1>")
	)
	(segment
		(start 244.708934 -93.928438)
		(end 244.715284 -93.939106)
		(width 0.0889)
		(layer "In4.Cu")
		(net "M_F_ECC<1>")
	)
	(segment
		(start 244.726206 -85.57387)
		(end 244.704108 -85.612224)
		(width 0.0889)
		(layer "In4.Cu")
		(net "M_F_ECC<1>")
	)
	(segment
		(start 244.708934 -95.509588)
		(end 244.704108 -95.518224)
		(width 0.0889)
		(layer "In4.Cu")
		(net "M_F_ECC<1>")
	)
	(segment
		(start 236.659928 -123.883928)
		(end 236.659928 -131.935728)
		(width 0.14224)
		(layer "In4.Cu")
		(net "M_F_ECC<1>")
	)
	(segment
		(start 236.171994 -149.444456)
		(end 236.171994 -149.533356)
		(width 0.14224)
		(layer "In4.Cu")
		(net "M_F_ECC<1>")
	)
	(segment
		(start 244.715284 -87.57412)
		(end 244.708934 -87.584788)
		(width 0.0889)
		(layer "In4.Cu")
		(net "M_F_ECC<1>")
	)
	(segment
		(start 244.715284 -98.47072)
		(end 244.544088 -98.775266)
		(width 0.0889)
		(layer "In4.Cu")
		(net "M_F_ECC<1>")
	)
	(segment
		(start 244.708934 -86.594188)
		(end 244.704108 -86.602824)
		(width 0.0889)
		(layer "In4.Cu")
		(net "M_F_ECC<1>")
	)
	(segment
		(start 244.708934 -92.537788)
		(end 244.704108 -92.546424)
		(width 0.0889)
		(layer "In4.Cu")
		(net "M_F_ECC<1>")
	)
	(segment
		(start 244.715284 -89.55532)
		(end 244.708934 -89.565988)
		(width 0.0889)
		(layer "In4.Cu")
		(net "M_F_ECC<1>")
	)
	(segment
		(start 236.659928 -146.2024)
		(end 236.7788 -146.321272)
		(width 0.14224)
		(layer "In4.Cu")
		(net "M_F_ECC<1>")
	)
	(segment
		(start 244.708934 -94.518988)
		(end 244.704108 -94.527624)
		(width 0.0889)
		(layer "In4.Cu")
		(net "M_F_ECC<1>")
	)
	(segment
		(start 237.409228 -114.43716)
		(end 237.236 -114.263932)
		(width 0.14224)
		(layer "In4.Cu")
		(net "M_F_ECC<1>")
	)
	(segment
		(start 236.659928 -143.019272)
		(end 236.659928 -146.2024)
		(width 0.14224)
		(layer "In4.Cu")
		(net "M_F_ECC<1>")
	)
	(arc
		(start 244.708934 -92.937838)
		(mid 244.788065 -93.23324)
		(end 244.708934 -93.528642)
		(width 0.0889)
		(layer "In4.Cu")
		(net "M_F_ECC<1>")
	)
	(arc
		(start 244.704108 -87.593424)
		(mid 244.655353 -87.789776)
		(end 244.708934 -87.984838)
		(width 0.0889)
		(layer "In4.Cu")
		(net "M_F_ECC<1>")
	)
	(arc
		(start 244.704108 -94.527624)
		(mid 244.655353 -94.723976)
		(end 244.708934 -94.919038)
		(width 0.0889)
		(layer "In4.Cu")
		(net "M_F_ECC<1>")
	)
	(arc
		(start 244.708934 -87.984838)
		(mid 244.788156 -88.273956)
		(end 244.715284 -88.56472)
		(width 0.0889)
		(layer "In4.Cu")
		(net "M_F_ECC<1>")
	)
	(arc
		(start 244.704108 -96.508824)
		(mid 244.655353 -96.705176)
		(end 244.708934 -96.900238)
		(width 0.0889)
		(layer "In4.Cu")
		(net "M_F_ECC<1>")
	)
	(arc
		(start 244.704108 -89.574624)
		(mid 244.655353 -89.770976)
		(end 244.708934 -89.966038)
		(width 0.0889)
		(layer "In4.Cu")
		(net "M_F_ECC<1>")
	)
	(arc
		(start 244.708934 -86.994238)
		(mid 244.788156 -87.283356)
		(end 244.715284 -87.57412)
		(width 0.0889)
		(layer "In4.Cu")
		(net "M_F_ECC<1>")
	)
	(arc
		(start 244.708934 -93.528642)
		(mid 244.655435 -93.72854)
		(end 244.708934 -93.928438)
		(width 0.0889)
		(layer "In4.Cu")
		(net "M_F_ECC<1>")
	)
	(arc
		(start 244.704108 -85.612224)
		(mid 244.655353 -85.808576)
		(end 244.708934 -86.003638)
		(width 0.0889)
		(layer "In4.Cu")
		(net "M_F_ECC<1>")
	)
	(arc
		(start 244.715284 -93.939106)
		(mid 244.788082 -94.229869)
		(end 244.708934 -94.518988)
		(width 0.0889)
		(layer "In4.Cu")
		(net "M_F_ECC<1>")
	)
	(arc
		(start 244.708934 -91.947238)
		(mid 244.788156 -92.236356)
		(end 244.715284 -92.52712)
		(width 0.0889)
		(layer "In4.Cu")
		(net "M_F_ECC<1>")
	)
	(arc
		(start 244.704108 -97.499424)
		(mid 244.655353 -97.695776)
		(end 244.708934 -97.890838)
		(width 0.0889)
		(layer "In4.Cu")
		(net "M_F_ECC<1>")
	)
	(arc
		(start 244.708934 -95.909638)
		(mid 244.788156 -96.198756)
		(end 244.715284 -96.48952)
		(width 0.0889)
		(layer "In4.Cu")
		(net "M_F_ECC<1>")
	)
	(arc
		(start 244.708934 -89.966038)
		(mid 244.788156 -90.255156)
		(end 244.715284 -90.54592)
		(width 0.0889)
		(layer "In4.Cu")
		(net "M_F_ECC<1>")
	)
	(arc
		(start 244.704108 -88.584024)
		(mid 244.655353 -88.780376)
		(end 244.708934 -88.975438)
		(width 0.0889)
		(layer "In4.Cu")
		(net "M_F_ECC<1>")
	)
	(arc
		(start 244.708934 -88.975438)
		(mid 244.788156 -89.264556)
		(end 244.715284 -89.55532)
		(width 0.0889)
		(layer "In4.Cu")
		(net "M_F_ECC<1>")
	)
	(arc
		(start 244.704108 -86.602824)
		(mid 244.655353 -86.799176)
		(end 244.708934 -86.994238)
		(width 0.0889)
		(layer "In4.Cu")
		(net "M_F_ECC<1>")
	)
	(arc
		(start 244.704108 -95.518224)
		(mid 244.655353 -95.714576)
		(end 244.708934 -95.909638)
		(width 0.0889)
		(layer "In4.Cu")
		(net "M_F_ECC<1>")
	)
	(arc
		(start 244.708934 -94.919038)
		(mid 244.788156 -95.208156)
		(end 244.715284 -95.49892)
		(width 0.0889)
		(layer "In4.Cu")
		(net "M_F_ECC<1>")
	)
	(arc
		(start 244.704108 -92.546424)
		(mid 244.655353 -92.742776)
		(end 244.708934 -92.937838)
		(width 0.0889)
		(layer "In4.Cu")
		(net "M_F_ECC<1>")
	)
	(arc
		(start 244.708934 -90.956638)
		(mid 244.788156 -91.245756)
		(end 244.715284 -91.53652)
		(width 0.0889)
		(layer "In4.Cu")
		(net "M_F_ECC<1>")
	)
	(arc
		(start 244.708934 -86.003638)
		(mid 244.788156 -86.292756)
		(end 244.715284 -86.58352)
		(width 0.0889)
		(layer "In4.Cu")
		(net "M_F_ECC<1>")
	)
	(arc
		(start 244.704108 -90.565224)
		(mid 244.655353 -90.761576)
		(end 244.708934 -90.956638)
		(width 0.0889)
		(layer "In4.Cu")
		(net "M_F_ECC<1>")
	)
	(arc
		(start 244.704108 -91.555824)
		(mid 244.655353 -91.752176)
		(end 244.708934 -91.947238)
		(width 0.0889)
		(layer "In4.Cu")
		(net "M_F_ECC<1>")
	)
	(arc
		(start 244.708934 -97.890838)
		(mid 244.788156 -98.179956)
		(end 244.715284 -98.47072)
		(width 0.0889)
		(layer "In4.Cu")
		(net "M_F_ECC<1>")
	)
	(arc
		(start 244.708934 -96.900238)
		(mid 244.788156 -97.189356)
		(end 244.715284 -97.48012)
		(width 0.0889)
		(layer "In4.Cu")
		(net "M_F_ECC<1>")
	)
	(segment
		(start 235.875576 -151.892)
		(end 235.6612 -151.677624)
		(width 0.14224)
		(layer "In11.Cu")
		(net "M_F_ECC<1>")
	)
	(segment
		(start 235.951776 -151.026368)
		(end 235.951776 -150.621746)
		(width 0.14224)
		(layer "In11.Cu")
		(net "M_F_ECC<1>")
	)
	(segment
		(start 235.900976 -153.0858)
		(end 235.6612 -152.846024)
		(width 0.14224)
		(layer "In11.Cu")
		(net "M_F_ECC<1>")
	)
	(segment
		(start 235.6612 -152.538176)
		(end 235.875576 -152.3238)
		(width 0.14224)
		(layer "In11.Cu")
		(net "M_F_ECC<1>")
	)
	(segment
		(start 235.74883 -153.542746)
		(end 235.900976 -153.3906)
		(width 0.14224)
		(layer "In11.Cu")
		(net "M_F_ECC<1>")
	)
	(segment
		(start 235.6612 -152.846024)
		(end 235.6612 -152.538176)
		(width 0.14224)
		(layer "In11.Cu")
		(net "M_F_ECC<1>")
	)
	(segment
		(start 235.721398 -150.391368)
		(end 235.721398 -149.983952)
		(width 0.14224)
		(layer "In11.Cu")
		(net "M_F_ECC<1>")
	)
	(segment
		(start 235.951776 -150.621746)
		(end 235.721398 -150.391368)
		(width 0.14224)
		(layer "In11.Cu")
		(net "M_F_ECC<1>")
	)
	(segment
		(start 235.6612 -151.677624)
		(end 235.6612 -151.316944)
		(width 0.14224)
		(layer "In11.Cu")
		(net "M_F_ECC<1>")
	)
	(segment
		(start 235.900976 -153.3906)
		(end 235.900976 -153.0858)
		(width 0.14224)
		(layer "In11.Cu")
		(net "M_F_ECC<1>")
	)
	(segment
		(start 235.721398 -149.983952)
		(end 236.171994 -149.533356)
		(width 0.14224)
		(layer "In11.Cu")
		(net "M_F_ECC<1>")
	)
	(segment
		(start 235.6612 -151.316944)
		(end 235.951776 -151.026368)
		(width 0.14224)
		(layer "In11.Cu")
		(net "M_F_ECC<1>")
	)
	(segment
		(start 235.49991 -153.542746)
		(end 235.74883 -153.542746)
		(width 0.14224)
		(layer "In11.Cu")
		(net "M_F_ECC<1>")
	)
	(segment
		(start 235.875576 -152.3238)
		(end 235.875576 -151.892)
		(width 0.14224)
		(layer "In11.Cu")
		(net "M_F_ECC<1>")
	)
	(segment
		(start 245.627144 -82.83194)
		(end 245.055644 -82.83194)
		(width 0.1651)
		(layer "F.Cu")
		(net "M_F_ECC<0>")
	)
	(segment
		(start 236.350302 -156.87294)
		(end 236.349794 -156.878782)
		(width 0.1651)
		(layer "F.Cu")
		(net "M_F_ECC<0>")
	)
	(segment
		(start 236.349794 -156.878782)
		(end 236.171994 -155.0162)
		(width 0.1651)
		(layer "F.Cu")
		(net "M_F_ECC<0>")
	)
	(via
		(at 245.055644 -82.83194)
		(size 0.508)
		(drill 0.254)
		(layers "F.Cu" "B.Cu")
		(net "M_F_ECC<0>")
	)
	(via
		(at 236.171994 -155.0162)
		(size 0.508)
		(drill 0.254)
		(layers "F.Cu" "B.Cu")
		(net "M_F_ECC<0>")
	)
	(via
		(at 235.49991 -150.814278)
		(size 0.508)
		(drill 0.254)
		(layers "F.Cu" "B.Cu")
		(net "M_F_ECC<0>")
	)
	(segment
		(start 235.500418 -152.078436)
		(end 235.49991 -152.078182)
		(width 0.1651)
		(layer "B.Cu")
		(net "M_F_ECC<0>")
	)
	(segment
		(start 235.49991 -152.078182)
		(end 235.49991 -150.814278)
		(width 0.1651)
		(layer "B.Cu")
		(net "M_F_ECC<0>")
	)
	(segment
		(start 244.543834 -91.451938)
		(end 244.537484 -91.462606)
		(width 0.0889)
		(layer "In4.Cu")
		(net "M_F_ECC<0>")
	)
	(segment
		(start 235.7882 -112.351312)
		(end 235.7882 -123.9266)
		(width 0.14224)
		(layer "In4.Cu")
		(net "M_F_ECC<0>")
	)
	(segment
		(start 236.94644 -112.14608)
		(end 236.685836 -112.14608)
		(width 0.14224)
		(layer "In4.Cu")
		(net "M_F_ECC<0>")
	)
	(segment
		(start 244.54866 -96.396302)
		(end 244.543834 -96.404938)
		(width 0.0889)
		(layer "In4.Cu")
		(net "M_F_ECC<0>")
	)
	(segment
		(start 236.19587 -111.943642)
		(end 235.7882 -112.351312)
		(width 0.14224)
		(layer "In4.Cu")
		(net "M_F_ECC<0>")
	)
	(segment
		(start 244.543834 -96.404938)
		(end 244.537484 -96.415606)
		(width 0.0889)
		(layer "In4.Cu")
		(net "M_F_ECC<0>")
	)
	(segment
		(start 235.956602 -134.496302)
		(end 235.682028 -134.770876)
		(width 0.14224)
		(layer "In4.Cu")
		(net "M_F_ECC<0>")
	)
	(segment
		(start 235.49991 -149.446996)
		(end 235.49991 -150.814278)
		(width 0.14224)
		(layer "In4.Cu")
		(net "M_F_ECC<0>")
	)
	(segment
		(start 235.986828 -145.842482)
		(end 235.986828 -148.960078)
		(width 0.14224)
		(layer "In4.Cu")
		(net "M_F_ECC<0>")
	)
	(segment
		(start 236.685836 -112.14608)
		(end 236.483398 -111.943642)
		(width 0.14224)
		(layer "In4.Cu")
		(net "M_F_ECC<0>")
	)
	(segment
		(start 235.970064 -125.708664)
		(end 235.970064 -129.774442)
		(width 0.14224)
		(layer "In4.Cu")
		(net "M_F_ECC<0>")
	)
	(segment
		(start 236.483398 -111.943642)
		(end 236.19587 -111.943642)
		(width 0.14224)
		(layer "In4.Cu")
		(net "M_F_ECC<0>")
	)
	(segment
		(start 244.543834 -88.480138)
		(end 244.537484 -88.490806)
		(width 0.0889)
		(layer "In4.Cu")
		(net "M_F_ECC<0>")
	)
	(segment
		(start 244.54866 -90.452702)
		(end 244.543834 -90.461338)
		(width 0.0889)
		(layer "In4.Cu")
		(net "M_F_ECC<0>")
	)
	(segment
		(start 245.055644 -82.83194)
		(end 244.560598 -83.497674)
		(width 0.0889)
		(layer "In4.Cu")
		(net "M_F_ECC<0>")
	)
	(segment
		(start 244.54866 -98.377502)
		(end 244.354096 -98.725736)
		(width 0.0889)
		(layer "In4.Cu")
		(net "M_F_ECC<0>")
	)
	(segment
		(start 244.543834 -92.442538)
		(end 244.537484 -92.453206)
		(width 0.0889)
		(layer "In4.Cu")
		(net "M_F_ECC<0>")
	)
	(segment
		(start 244.354096 -98.725736)
		(end 244.354096 -100.069142)
		(width 0.0889)
		(layer "In4.Cu")
		(net "M_F_ECC<0>")
	)
	(segment
		(start 244.54866 -92.433902)
		(end 244.543834 -92.442538)
		(width 0.0889)
		(layer "In4.Cu")
		(net "M_F_ECC<0>")
	)
	(segment
		(start 236.024928 -136.304528)
		(end 236.024928 -139.320778)
		(width 0.14224)
		(layer "In4.Cu")
		(net "M_F_ECC<0>")
	)
	(segment
		(start 244.54866 -85.499702)
		(end 244.543834 -85.508338)
		(width 0.0889)
		(layer "In4.Cu")
		(net "M_F_ECC<0>")
	)
	(segment
		(start 244.543834 -84.517738)
		(end 244.537484 -84.528406)
		(width 0.0889)
		(layer "In4.Cu")
		(net "M_F_ECC<0>")
	)
	(segment
		(start 243.695982 -104.44353)
		(end 237.0582 -111.081312)
		(width 0.14224)
		(layer "In4.Cu")
		(net "M_F_ECC<0>")
	)
	(segment
		(start 243.930424 -101.483414)
		(end 243.695982 -101.717856)
		(width 0.0889)
		(layer "In4.Cu")
		(net "M_F_ECC<0>")
	)
	(segment
		(start 244.543834 -85.508338)
		(end 244.537484 -85.519006)
		(width 0.0889)
		(layer "In4.Cu")
		(net "M_F_ECC<0>")
	)
	(segment
		(start 244.54866 -89.462102)
		(end 244.543834 -89.470738)
		(width 0.0889)
		(layer "In4.Cu")
		(net "M_F_ECC<0>")
	)
	(segment
		(start 235.682028 -140.743178)
		(end 235.974128 -141.035278)
		(width 0.14224)
		(layer "In4.Cu")
		(net "M_F_ECC<0>")
	)
	(segment
		(start 235.986828 -148.960078)
		(end 235.49991 -149.446996)
		(width 0.14224)
		(layer "In4.Cu")
		(net "M_F_ECC<0>")
	)
	(segment
		(start 235.970064 -129.774442)
		(end 235.682028 -130.062478)
		(width 0.14224)
		(layer "In4.Cu")
		(net "M_F_ECC<0>")
	)
	(segment
		(start 244.543834 -86.498938)
		(end 244.537484 -86.509606)
		(width 0.0889)
		(layer "In4.Cu")
		(net "M_F_ECC<0>")
	)
	(segment
		(start 235.956602 -131.416552)
		(end 235.956602 -134.496302)
		(width 0.14224)
		(layer "In4.Cu")
		(net "M_F_ECC<0>")
	)
	(segment
		(start 244.54866 -84.509102)
		(end 244.543834 -84.517738)
		(width 0.0889)
		(layer "In4.Cu")
		(net "M_F_ECC<0>")
	)
	(segment
		(start 244.543834 -95.414338)
		(end 244.537484 -95.425006)
		(width 0.0889)
		(layer "In4.Cu")
		(net "M_F_ECC<0>")
	)
	(segment
		(start 235.705396 -124.009404)
		(end 235.705396 -125.443996)
		(width 0.14224)
		(layer "In4.Cu")
		(net "M_F_ECC<0>")
	)
	(segment
		(start 244.543834 -89.470738)
		(end 244.537484 -89.481406)
		(width 0.0889)
		(layer "In4.Cu")
		(net "M_F_ECC<0>")
	)
	(segment
		(start 244.560598 -83.497674)
		(end 244.543834 -83.527138)
		(width 0.0889)
		(layer "In4.Cu")
		(net "M_F_ECC<0>")
	)
	(segment
		(start 235.682028 -134.770876)
		(end 235.682028 -135.961628)
		(width 0.14224)
		(layer "In4.Cu")
		(net "M_F_ECC<0>")
	)
	(segment
		(start 235.974128 -141.035278)
		(end 235.974128 -144.085818)
		(width 0.14224)
		(layer "In4.Cu")
		(net "M_F_ECC<0>")
	)
	(segment
		(start 244.54866 -93.424502)
		(end 244.543834 -93.433138)
		(width 0.0889)
		(layer "In4.Cu")
		(net "M_F_ECC<0>")
	)
	(segment
		(start 244.54866 -86.490302)
		(end 244.543834 -86.498938)
		(width 0.0889)
		(layer "In4.Cu")
		(net "M_F_ECC<0>")
	)
	(segment
		(start 244.54866 -87.480902)
		(end 244.543834 -87.489538)
		(width 0.0889)
		(layer "In4.Cu")
		(net "M_F_ECC<0>")
	)
	(segment
		(start 235.705396 -125.443996)
		(end 235.970064 -125.708664)
		(width 0.14224)
		(layer "In4.Cu")
		(net "M_F_ECC<0>")
	)
	(segment
		(start 235.974128 -144.085818)
		(end 235.694728 -144.365218)
		(width 0.14224)
		(layer "In4.Cu")
		(net "M_F_ECC<0>")
	)
	(segment
		(start 237.233714 -111.858806)
		(end 236.94644 -112.14608)
		(width 0.14224)
		(layer "In4.Cu")
		(net "M_F_ECC<0>")
	)
	(segment
		(start 243.695982 -101.717856)
		(end 243.695982 -104.44353)
		(width 0.14224)
		(layer "In4.Cu")
		(net "M_F_ECC<0>")
	)
	(segment
		(start 244.543834 -87.489538)
		(end 244.537484 -87.500206)
		(width 0.0889)
		(layer "In4.Cu")
		(net "M_F_ECC<0>")
	)
	(segment
		(start 237.0582 -111.36884)
		(end 237.233714 -111.544354)
		(width 0.14224)
		(layer "In4.Cu")
		(net "M_F_ECC<0>")
	)
	(segment
		(start 237.233714 -111.544354)
		(end 237.233714 -111.858806)
		(width 0.14224)
		(layer "In4.Cu")
		(net "M_F_ECC<0>")
	)
	(segment
		(start 235.694728 -144.365218)
		(end 235.694728 -145.550382)
		(width 0.14224)
		(layer "In4.Cu")
		(net "M_F_ECC<0>")
	)
	(segment
		(start 235.682028 -130.062478)
		(end 235.682028 -131.141978)
		(width 0.14224)
		(layer "In4.Cu")
		(net "M_F_ECC<0>")
	)
	(segment
		(start 244.54866 -91.443302)
		(end 244.543834 -91.451938)
		(width 0.0889)
		(layer "In4.Cu")
		(net "M_F_ECC<0>")
	)
	(segment
		(start 235.682028 -135.961628)
		(end 236.024928 -136.304528)
		(width 0.14224)
		(layer "In4.Cu")
		(net "M_F_ECC<0>")
	)
	(segment
		(start 244.54866 -97.386902)
		(end 244.543834 -97.395538)
		(width 0.0889)
		(layer "In4.Cu")
		(net "M_F_ECC<0>")
	)
	(segment
		(start 244.354096 -100.069142)
		(end 243.930424 -100.492814)
		(width 0.0889)
		(layer "In4.Cu")
		(net "M_F_ECC<0>")
	)
	(segment
		(start 244.543834 -90.461338)
		(end 244.537484 -90.472006)
		(width 0.0889)
		(layer "In4.Cu")
		(net "M_F_ECC<0>")
	)
	(segment
		(start 243.930424 -100.492814)
		(end 243.930424 -101.483414)
		(width 0.0889)
		(layer "In4.Cu")
		(net "M_F_ECC<0>")
	)
	(segment
		(start 236.024928 -139.320778)
		(end 235.682028 -139.663678)
		(width 0.14224)
		(layer "In4.Cu")
		(net "M_F_ECC<0>")
	)
	(segment
		(start 235.694728 -145.550382)
		(end 235.986828 -145.842482)
		(width 0.14224)
		(layer "In4.Cu")
		(net "M_F_ECC<0>")
	)
	(segment
		(start 244.54866 -95.405702)
		(end 244.543834 -95.414338)
		(width 0.0889)
		(layer "In4.Cu")
		(net "M_F_ECC<0>")
	)
	(segment
		(start 244.54866 -88.471502)
		(end 244.543834 -88.480138)
		(width 0.0889)
		(layer "In4.Cu")
		(net "M_F_ECC<0>")
	)
	(segment
		(start 244.543834 -83.527138)
		(end 244.537484 -83.537806)
		(width 0.0889)
		(layer "In4.Cu")
		(net "M_F_ECC<0>")
	)
	(segment
		(start 235.682028 -139.663678)
		(end 235.682028 -140.743178)
		(width 0.14224)
		(layer "In4.Cu")
		(net "M_F_ECC<0>")
	)
	(segment
		(start 244.537484 -94.01302)
		(end 244.543834 -94.023688)
		(width 0.0889)
		(layer "In4.Cu")
		(net "M_F_ECC<0>")
	)
	(segment
		(start 237.0582 -111.081312)
		(end 237.0582 -111.36884)
		(width 0.14224)
		(layer "In4.Cu")
		(net "M_F_ECC<0>")
	)
	(segment
		(start 244.543834 -97.395538)
		(end 244.537484 -97.406206)
		(width 0.0889)
		(layer "In4.Cu")
		(net "M_F_ECC<0>")
	)
	(segment
		(start 235.7882 -123.9266)
		(end 235.705396 -124.009404)
		(width 0.14224)
		(layer "In4.Cu")
		(net "M_F_ECC<0>")
	)
	(segment
		(start 235.682028 -131.141978)
		(end 235.956602 -131.416552)
		(width 0.14224)
		(layer "In4.Cu")
		(net "M_F_ECC<0>")
	)
	(arc
		(start 244.543834 -85.108288)
		(mid 244.597304 -85.303351)
		(end 244.54866 -85.499702)
		(width 0.0889)
		(layer "In4.Cu")
		(net "M_F_ECC<0>")
	)
	(arc
		(start 244.537484 -87.500206)
		(mid 244.464686 -87.790969)
		(end 244.543834 -88.080088)
		(width 0.0889)
		(layer "In4.Cu")
		(net "M_F_ECC<0>")
	)
	(arc
		(start 244.543834 -96.004888)
		(mid 244.597304 -96.199951)
		(end 244.54866 -96.396302)
		(width 0.0889)
		(layer "In4.Cu")
		(net "M_F_ECC<0>")
	)
	(arc
		(start 244.543834 -87.089488)
		(mid 244.597304 -87.284551)
		(end 244.54866 -87.480902)
		(width 0.0889)
		(layer "In4.Cu")
		(net "M_F_ECC<0>")
	)
	(arc
		(start 244.537484 -91.462606)
		(mid 244.464686 -91.753369)
		(end 244.543834 -92.042488)
		(width 0.0889)
		(layer "In4.Cu")
		(net "M_F_ECC<0>")
	)
	(arc
		(start 244.537484 -97.406206)
		(mid 244.464686 -97.696969)
		(end 244.543834 -97.986088)
		(width 0.0889)
		(layer "In4.Cu")
		(net "M_F_ECC<0>")
	)
	(arc
		(start 244.543834 -95.014288)
		(mid 244.597304 -95.209351)
		(end 244.54866 -95.405702)
		(width 0.0889)
		(layer "In4.Cu")
		(net "M_F_ECC<0>")
	)
	(arc
		(start 244.537484 -88.490806)
		(mid 244.464686 -88.781569)
		(end 244.543834 -89.070688)
		(width 0.0889)
		(layer "In4.Cu")
		(net "M_F_ECC<0>")
	)
	(arc
		(start 244.543834 -94.023688)
		(mid 244.597333 -94.223586)
		(end 244.543834 -94.423484)
		(width 0.0889)
		(layer "In4.Cu")
		(net "M_F_ECC<0>")
	)
	(arc
		(start 244.537484 -86.509606)
		(mid 244.464686 -86.800369)
		(end 244.543834 -87.089488)
		(width 0.0889)
		(layer "In4.Cu")
		(net "M_F_ECC<0>")
	)
	(arc
		(start 244.537484 -84.528406)
		(mid 244.464686 -84.819169)
		(end 244.543834 -85.108288)
		(width 0.0889)
		(layer "In4.Cu")
		(net "M_F_ECC<0>")
	)
	(arc
		(start 244.543834 -93.433138)
		(mid 244.464612 -93.722256)
		(end 244.537484 -94.01302)
		(width 0.0889)
		(layer "In4.Cu")
		(net "M_F_ECC<0>")
	)
	(arc
		(start 244.543834 -89.070688)
		(mid 244.597304 -89.265751)
		(end 244.54866 -89.462102)
		(width 0.0889)
		(layer "In4.Cu")
		(net "M_F_ECC<0>")
	)
	(arc
		(start 244.537484 -85.519006)
		(mid 244.464686 -85.809769)
		(end 244.543834 -86.098888)
		(width 0.0889)
		(layer "In4.Cu")
		(net "M_F_ECC<0>")
	)
	(arc
		(start 244.543834 -84.117688)
		(mid 244.597304 -84.312751)
		(end 244.54866 -84.509102)
		(width 0.0889)
		(layer "In4.Cu")
		(net "M_F_ECC<0>")
	)
	(arc
		(start 244.537484 -89.481406)
		(mid 244.464686 -89.772169)
		(end 244.543834 -90.061288)
		(width 0.0889)
		(layer "In4.Cu")
		(net "M_F_ECC<0>")
	)
	(arc
		(start 244.543834 -91.051888)
		(mid 244.597304 -91.246951)
		(end 244.54866 -91.443302)
		(width 0.0889)
		(layer "In4.Cu")
		(net "M_F_ECC<0>")
	)
	(arc
		(start 244.537484 -95.425006)
		(mid 244.464686 -95.715769)
		(end 244.543834 -96.004888)
		(width 0.0889)
		(layer "In4.Cu")
		(net "M_F_ECC<0>")
	)
	(arc
		(start 244.543834 -97.986088)
		(mid 244.597304 -98.181151)
		(end 244.54866 -98.377502)
		(width 0.0889)
		(layer "In4.Cu")
		(net "M_F_ECC<0>")
	)
	(arc
		(start 244.543834 -86.098888)
		(mid 244.597304 -86.293951)
		(end 244.54866 -86.490302)
		(width 0.0889)
		(layer "In4.Cu")
		(net "M_F_ECC<0>")
	)
	(arc
		(start 244.537484 -90.472006)
		(mid 244.464686 -90.762769)
		(end 244.543834 -91.051888)
		(width 0.0889)
		(layer "In4.Cu")
		(net "M_F_ECC<0>")
	)
	(arc
		(start 244.543834 -94.423484)
		(mid 244.464703 -94.718886)
		(end 244.543834 -95.014288)
		(width 0.0889)
		(layer "In4.Cu")
		(net "M_F_ECC<0>")
	)
	(arc
		(start 244.537484 -83.537806)
		(mid 244.464686 -83.828569)
		(end 244.543834 -84.117688)
		(width 0.0889)
		(layer "In4.Cu")
		(net "M_F_ECC<0>")
	)
	(arc
		(start 244.543834 -92.042488)
		(mid 244.597304 -92.237551)
		(end 244.54866 -92.433902)
		(width 0.0889)
		(layer "In4.Cu")
		(net "M_F_ECC<0>")
	)
	(arc
		(start 244.537484 -96.415606)
		(mid 244.464686 -96.706369)
		(end 244.543834 -96.995488)
		(width 0.0889)
		(layer "In4.Cu")
		(net "M_F_ECC<0>")
	)
	(arc
		(start 244.543834 -93.033088)
		(mid 244.597304 -93.228151)
		(end 244.54866 -93.424502)
		(width 0.0889)
		(layer "In4.Cu")
		(net "M_F_ECC<0>")
	)
	(arc
		(start 244.543834 -88.080088)
		(mid 244.597304 -88.275151)
		(end 244.54866 -88.471502)
		(width 0.0889)
		(layer "In4.Cu")
		(net "M_F_ECC<0>")
	)
	(arc
		(start 244.543834 -96.995488)
		(mid 244.597304 -97.190551)
		(end 244.54866 -97.386902)
		(width 0.0889)
		(layer "In4.Cu")
		(net "M_F_ECC<0>")
	)
	(arc
		(start 244.543834 -90.061288)
		(mid 244.597304 -90.256351)
		(end 244.54866 -90.452702)
		(width 0.0889)
		(layer "In4.Cu")
		(net "M_F_ECC<0>")
	)
	(arc
		(start 244.537484 -92.453206)
		(mid 244.464686 -92.743969)
		(end 244.543834 -93.033088)
		(width 0.0889)
		(layer "In4.Cu")
		(net "M_F_ECC<0>")
	)
	(segment
		(start 235.06684 -153.911046)
		(end 235.06684 -151.247348)
		(width 0.14224)
		(layer "In11.Cu")
		(net "M_F_ECC<0>")
	)
	(segment
		(start 236.171994 -155.0162)
		(end 235.06684 -153.911046)
		(width 0.14224)
		(layer "In11.Cu")
		(net "M_F_ECC<0>")
	)
	(segment
		(start 235.06684 -151.247348)
		(end 235.49991 -150.814278)
		(width 0.14224)
		(layer "In11.Cu")
		(net "M_F_ECC<0>")
	)
	(segment
		(start 199.279256 -153.515568)
		(end 199.279256 -154.333702)
		(width 0.1651)
		(layer "F.Cu")
		(net "M_F_DQS_DP<9>")
	)
	(segment
		(start 199.279256 -154.333702)
		(end 199.36079 -154.557984)
		(width 0.1651)
		(layer "F.Cu")
		(net "M_F_DQS_DP<9>")
	)
	(segment
		(start 243.051838 -87.28964)
		(end 242.480338 -87.28964)
		(width 0.1651)
		(layer "F.Cu")
		(net "M_F_DQS_DP<9>")
	)
	(segment
		(start 199.799956 -152.895554)
		(end 199.363838 -153.331672)
		(width 0.1651)
		(layer "F.Cu")
		(net "M_F_DQS_DP<9>")
	)
	(segment
		(start 199.36079 -154.557984)
		(end 199.742552 -154.939746)
		(width 0.1651)
		(layer "F.Cu")
		(net "M_F_DQS_DP<9>")
	)
	(segment
		(start 199.363838 -153.331672)
		(end 199.279256 -153.515568)
		(width 0.1651)
		(layer "F.Cu")
		(net "M_F_DQS_DP<9>")
	)
	(segment
		(start 199.800464 -152.273)
		(end 199.799956 -152.278842)
		(width 0.1651)
		(layer "F.Cu")
		(net "M_F_DQS_DP<9>")
	)
	(segment
		(start 199.799956 -152.278842)
		(end 199.799956 -152.895554)
		(width 0.1651)
		(layer "F.Cu")
		(net "M_F_DQS_DP<9>")
	)
	(via
		(at 242.480338 -87.28964)
		(size 0.508)
		(drill 0.254)
		(layers "F.Cu" "B.Cu")
		(net "M_F_DQS_DP<9>")
	)
	(via
		(at 199.742552 -149.4282)
		(size 0.508)
		(drill 0.254)
		(layers "F.Cu" "B.Cu")
		(net "M_F_DQS_DP<9>")
	)
	(via
		(at 199.742552 -154.939746)
		(size 0.508)
		(drill 0.254)
		(layers "F.Cu" "B.Cu")
		(net "M_F_DQS_DP<9>")
	)
	(segment
		(start 199.266556 -149.976332)
		(end 199.353932 -149.81682)
		(width 0.1651)
		(layer "B.Cu")
		(net "M_F_DQS_DP<9>")
	)
	(segment
		(start 199.266556 -150.871936)
		(end 199.266556 -149.976332)
		(width 0.1651)
		(layer "B.Cu")
		(net "M_F_DQS_DP<9>")
	)
	(segment
		(start 199.353932 -149.81682)
		(end 199.742552 -149.4282)
		(width 0.1651)
		(layer "B.Cu")
		(net "M_F_DQS_DP<9>")
	)
	(segment
		(start 199.343772 -151.00427)
		(end 199.266556 -150.871936)
		(width 0.1651)
		(layer "B.Cu")
		(net "M_F_DQS_DP<9>")
	)
	(segment
		(start 199.799956 -152.078182)
		(end 199.799956 -151.460454)
		(width 0.1651)
		(layer "B.Cu")
		(net "M_F_DQS_DP<9>")
	)
	(segment
		(start 199.799956 -151.460454)
		(end 199.343772 -151.00427)
		(width 0.1651)
		(layer "B.Cu")
		(net "M_F_DQS_DP<9>")
	)
	(segment
		(start 199.800464 -152.078436)
		(end 199.799956 -152.078182)
		(width 0.1651)
		(layer "B.Cu")
		(net "M_F_DQS_DP<9>")
	)
	(segment
		(start 240.784888 -85.70849)
		(end 240.752122 -85.70849)
		(width 0.0889)
		(layer "In11.Cu")
		(net "M_F_DQS_DP<9>")
	)
	(segment
		(start 241.639598 -86.203536)
		(end 241.606832 -86.203536)
		(width 0.0889)
		(layer "In11.Cu")
		(net "M_F_DQS_DP<9>")
	)
	(segment
		(start 205.34376 -108.24464)
		(end 201.50328 -112.08512)
		(width 0.14224)
		(layer "In11.Cu")
		(net "M_F_DQS_DP<9>")
	)
	(segment
		(start 230.5812 -88.335866)
		(end 230.559102 -88.335866)
		(width 0.0889)
		(layer "In11.Cu")
		(net "M_F_DQS_DP<9>")
	)
	(segment
		(start 235.623354 -86.69909)
		(end 235.590588 -86.69909)
		(width 0.0889)
		(layer "In11.Cu")
		(net "M_F_DQS_DP<9>")
	)
	(segment
		(start 199.6694 -149.4282)
		(end 199.2376 -149.86)
		(width 0.14224)
		(layer "In11.Cu")
		(net "M_F_DQS_DP<9>")
	)
	(segment
		(start 233.906314 -87.68969)
		(end 233.873548 -87.68969)
		(width 0.0889)
		(layer "In11.Cu")
		(net "M_F_DQS_DP<9>")
	)
	(segment
		(start 201.50328 -117.969792)
		(end 201.335132 -118.13794)
		(width 0.14224)
		(layer "In11.Cu")
		(net "M_F_DQS_DP<9>")
	)
	(segment
		(start 201.335132 -118.13794)
		(end 200.283826 -118.13794)
		(width 0.14224)
		(layer "In11.Cu")
		(net "M_F_DQS_DP<9>")
	)
	(segment
		(start 201.50328 -112.08512)
		(end 201.50328 -115.321842)
		(width 0.14224)
		(layer "In11.Cu")
		(net "M_F_DQS_DP<9>")
	)
	(segment
		(start 201.282554 -115.542568)
		(end 200.52792 -115.542568)
		(width 0.14224)
		(layer "In11.Cu")
		(net "M_F_DQS_DP<9>")
	)
	(segment
		(start 199.991726 -149.4282)
		(end 199.742552 -149.4282)
		(width 0.14224)
		(layer "In11.Cu")
		(net "M_F_DQS_DP<9>")
	)
	(segment
		(start 205.34376 -107.73664)
		(end 205.34376 -108.24464)
		(width 0.14224)
		(layer "In11.Cu")
		(net "M_F_DQS_DP<9>")
	)
	(segment
		(start 233.051604 -88.184736)
		(end 233.018838 -88.184736)
		(width 0.0889)
		(layer "In11.Cu")
		(net "M_F_DQS_DP<9>")
	)
	(segment
		(start 231.917494 -88.68029)
		(end 231.61244 -88.375236)
		(width 0.0889)
		(layer "In11.Cu")
		(net "M_F_DQS_DP<9>")
	)
	(segment
		(start 209.89544 -103.18496)
		(end 205.34376 -107.73664)
		(width 0.14224)
		(layer "In11.Cu")
		(net "M_F_DQS_DP<9>")
	)
	(segment
		(start 199.742552 -149.4282)
		(end 199.6694 -149.4282)
		(width 0.14224)
		(layer "In11.Cu")
		(net "M_F_DQS_DP<9>")
	)
	(segment
		(start 201.50328 -115.321842)
		(end 201.282554 -115.542568)
		(width 0.14224)
		(layer "In11.Cu")
		(net "M_F_DQS_DP<9>")
	)
	(segment
		(start 237.340394 -85.70849)
		(end 237.307628 -85.70849)
		(width 0.0889)
		(layer "In11.Cu")
		(net "M_F_DQS_DP<9>")
	)
	(segment
		(start 213.724998 -103.18496)
		(end 209.89544 -103.18496)
		(width 0.14224)
		(layer "In11.Cu")
		(net "M_F_DQS_DP<9>")
	)
	(segment
		(start 239.922558 -85.212936)
		(end 239.889792 -85.212936)
		(width 0.0889)
		(layer "In11.Cu")
		(net "M_F_DQS_DP<9>")
	)
	(segment
		(start 230.62057 -88.375236)
		(end 230.5812 -88.335866)
		(width 0.0889)
		(layer "In11.Cu")
		(net "M_F_DQS_DP<9>")
	)
	(segment
		(start 242.480338 -87.28964)
		(end 242.187222 -87.120476)
		(width 0.0889)
		(layer "In11.Cu")
		(net "M_F_DQS_DP<9>")
	)
	(segment
		(start 242.187222 -87.120476)
		(end 242.163346 -87.031068)
		(width 0.0889)
		(layer "In11.Cu")
		(net "M_F_DQS_DP<9>")
	)
	(segment
		(start 234.768644 -87.194136)
		(end 234.735878 -87.194136)
		(width 0.0889)
		(layer "In11.Cu")
		(net "M_F_DQS_DP<9>")
	)
	(segment
		(start 239.067848 -84.71789)
		(end 239.024668 -84.71789)
		(width 0.0889)
		(layer "In11.Cu")
		(net "M_F_DQS_DP<9>")
	)
	(segment
		(start 238.202724 -85.212936)
		(end 238.169958 -85.212936)
		(width 0.0889)
		(layer "In11.Cu")
		(net "M_F_DQS_DP<9>")
	)
	(segment
		(start 200.283826 -118.13794)
		(end 199.87768 -118.544086)
		(width 0.14224)
		(layer "In11.Cu")
		(net "M_F_DQS_DP<9>")
	)
	(segment
		(start 236.485684 -86.203536)
		(end 236.452918 -86.203536)
		(width 0.0889)
		(layer "In11.Cu")
		(net "M_F_DQS_DP<9>")
	)
	(segment
		(start 199.87768 -126.388368)
		(end 200.255632 -126.76632)
		(width 0.14224)
		(layer "In11.Cu")
		(net "M_F_DQS_DP<9>")
	)
	(segment
		(start 217.63736 -98.28022)
		(end 217.63736 -99.272598)
		(width 0.14224)
		(layer "In11.Cu")
		(net "M_F_DQS_DP<9>")
	)
	(segment
		(start 230.559102 -88.335866)
		(end 227.581714 -88.335866)
		(width 0.14224)
		(layer "In11.Cu")
		(net "M_F_DQS_DP<9>")
	)
	(segment
		(start 200.24344 -115.827048)
		(end 200.24344 -116.670328)
		(width 0.14224)
		(layer "In11.Cu")
		(net "M_F_DQS_DP<9>")
	)
	(segment
		(start 217.63736 -99.272598)
		(end 213.724998 -103.18496)
		(width 0.14224)
		(layer "In11.Cu")
		(net "M_F_DQS_DP<9>")
	)
	(segment
		(start 227.581714 -88.335866)
		(end 217.63736 -98.28022)
		(width 0.14224)
		(layer "In11.Cu")
		(net "M_F_DQS_DP<9>")
	)
	(segment
		(start 200.255632 -149.164294)
		(end 199.991726 -149.4282)
		(width 0.14224)
		(layer "In11.Cu")
		(net "M_F_DQS_DP<9>")
	)
	(segment
		(start 200.255632 -126.76632)
		(end 200.255632 -149.164294)
		(width 0.14224)
		(layer "In11.Cu")
		(net "M_F_DQS_DP<9>")
	)
	(segment
		(start 231.61244 -88.375236)
		(end 230.62057 -88.375236)
		(width 0.0889)
		(layer "In11.Cu")
		(net "M_F_DQS_DP<9>")
	)
	(segment
		(start 201.50328 -117.175534)
		(end 201.50328 -117.969792)
		(width 0.14224)
		(layer "In11.Cu")
		(net "M_F_DQS_DP<9>")
	)
	(segment
		(start 200.52792 -115.542568)
		(end 200.24344 -115.827048)
		(width 0.14224)
		(layer "In11.Cu")
		(net "M_F_DQS_DP<9>")
	)
	(segment
		(start 199.2376 -149.86)
		(end 199.2376 -154.434794)
		(width 0.14224)
		(layer "In11.Cu")
		(net "M_F_DQS_DP<9>")
	)
	(segment
		(start 201.282554 -116.954808)
		(end 201.50328 -117.175534)
		(width 0.14224)
		(layer "In11.Cu")
		(net "M_F_DQS_DP<9>")
	)
	(segment
		(start 232.189274 -88.68029)
		(end 231.917494 -88.68029)
		(width 0.0889)
		(layer "In11.Cu")
		(net "M_F_DQS_DP<9>")
	)
	(segment
		(start 200.52792 -116.954808)
		(end 201.282554 -116.954808)
		(width 0.14224)
		(layer "In11.Cu")
		(net "M_F_DQS_DP<9>")
	)
	(segment
		(start 199.2376 -154.434794)
		(end 199.742552 -154.939746)
		(width 0.14224)
		(layer "In11.Cu")
		(net "M_F_DQS_DP<9>")
	)
	(segment
		(start 200.24344 -116.670328)
		(end 200.52792 -116.954808)
		(width 0.14224)
		(layer "In11.Cu")
		(net "M_F_DQS_DP<9>")
	)
	(segment
		(start 199.87768 -118.544086)
		(end 199.87768 -126.388368)
		(width 0.14224)
		(layer "In11.Cu")
		(net "M_F_DQS_DP<9>")
	)
	(arc
		(start 234.735878 -87.194136)
		(mid 234.450454 -87.277603)
		(end 234.241848 -87.489538)
		(width 0.0889)
		(layer "In11.Cu")
		(net "M_F_DQS_DP<9>")
	)
	(arc
		(start 239.024668 -84.71789)
		(mid 238.741451 -84.802171)
		(end 238.534448 -85.013038)
		(width 0.0889)
		(layer "In11.Cu")
		(net "M_F_DQS_DP<9>")
	)
	(arc
		(start 233.873548 -87.68969)
		(mid 233.590331 -87.773971)
		(end 233.383328 -87.984838)
		(width 0.0889)
		(layer "In11.Cu")
		(net "M_F_DQS_DP<9>")
	)
	(arc
		(start 239.558068 -85.013038)
		(mid 239.351064 -84.802174)
		(end 239.067848 -84.71789)
		(width 0.0889)
		(layer "In11.Cu")
		(net "M_F_DQS_DP<9>")
	)
	(arc
		(start 236.817408 -86.003638)
		(mid 236.677329 -86.146374)
		(end 236.485684 -86.203536)
		(width 0.0889)
		(layer "In11.Cu")
		(net "M_F_DQS_DP<9>")
	)
	(arc
		(start 237.675928 -85.508338)
		(mid 237.534245 -85.652142)
		(end 237.340394 -85.70849)
		(width 0.0889)
		(layer "In11.Cu")
		(net "M_F_DQS_DP<9>")
	)
	(arc
		(start 232.524808 -88.480138)
		(mid 232.383125 -88.623942)
		(end 232.189274 -88.68029)
		(width 0.0889)
		(layer "In11.Cu")
		(net "M_F_DQS_DP<9>")
	)
	(arc
		(start 238.169958 -85.212936)
		(mid 237.884534 -85.296403)
		(end 237.675928 -85.508338)
		(width 0.0889)
		(layer "In11.Cu")
		(net "M_F_DQS_DP<9>")
	)
	(arc
		(start 235.100368 -86.994238)
		(mid 234.960289 -87.136974)
		(end 234.768644 -87.194136)
		(width 0.0889)
		(layer "In11.Cu")
		(net "M_F_DQS_DP<9>")
	)
	(arc
		(start 241.606832 -86.203536)
		(mid 241.41519 -86.14637)
		(end 241.275108 -86.003638)
		(width 0.0889)
		(layer "In11.Cu")
		(net "M_F_DQS_DP<9>")
	)
	(arc
		(start 238.534448 -85.013038)
		(mid 238.394369 -85.155774)
		(end 238.202724 -85.212936)
		(width 0.0889)
		(layer "In11.Cu")
		(net "M_F_DQS_DP<9>")
	)
	(arc
		(start 235.590588 -86.69909)
		(mid 235.307371 -86.783371)
		(end 235.100368 -86.994238)
		(width 0.0889)
		(layer "In11.Cu")
		(net "M_F_DQS_DP<9>")
	)
	(arc
		(start 233.018838 -88.184736)
		(mid 232.733414 -88.268203)
		(end 232.524808 -88.480138)
		(width 0.0889)
		(layer "In11.Cu")
		(net "M_F_DQS_DP<9>")
	)
	(arc
		(start 239.889792 -85.212936)
		(mid 239.69815 -85.15577)
		(end 239.558068 -85.013038)
		(width 0.0889)
		(layer "In11.Cu")
		(net "M_F_DQS_DP<9>")
	)
	(arc
		(start 236.452918 -86.203536)
		(mid 236.167494 -86.287003)
		(end 235.958888 -86.498938)
		(width 0.0889)
		(layer "In11.Cu")
		(net "M_F_DQS_DP<9>")
	)
	(arc
		(start 234.241848 -87.489538)
		(mid 234.100165 -87.633342)
		(end 233.906314 -87.68969)
		(width 0.0889)
		(layer "In11.Cu")
		(net "M_F_DQS_DP<9>")
	)
	(arc
		(start 241.275108 -86.003638)
		(mid 241.068104 -85.792774)
		(end 240.784888 -85.70849)
		(width 0.0889)
		(layer "In11.Cu")
		(net "M_F_DQS_DP<9>")
	)
	(arc
		(start 235.958888 -86.498938)
		(mid 235.817205 -86.642742)
		(end 235.623354 -86.69909)
		(width 0.0889)
		(layer "In11.Cu")
		(net "M_F_DQS_DP<9>")
	)
	(arc
		(start 242.163346 -87.031068)
		(mid 242.121367 -86.478108)
		(end 241.639598 -86.203536)
		(width 0.0889)
		(layer "In11.Cu")
		(net "M_F_DQS_DP<9>")
	)
	(arc
		(start 237.307628 -85.70849)
		(mid 237.024411 -85.792771)
		(end 236.817408 -86.003638)
		(width 0.0889)
		(layer "In11.Cu")
		(net "M_F_DQS_DP<9>")
	)
	(arc
		(start 233.383328 -87.984838)
		(mid 233.243249 -88.127574)
		(end 233.051604 -88.184736)
		(width 0.0889)
		(layer "In11.Cu")
		(net "M_F_DQS_DP<9>")
	)
	(arc
		(start 240.416588 -85.508338)
		(mid 240.20798 -85.296406)
		(end 239.922558 -85.212936)
		(width 0.0889)
		(layer "In11.Cu")
		(net "M_F_DQS_DP<9>")
	)
	(arc
		(start 240.752122 -85.70849)
		(mid 240.558272 -85.65214)
		(end 240.416588 -85.508338)
		(width 0.0889)
		(layer "In11.Cu")
		(net "M_F_DQS_DP<9>")
	)
	(segment
		(start 238.9378 -155.829)
		(end 238.899954 -155.866846)
		(width 0.1651)
		(layer "F.Cu")
		(net "M_F_DQS_DP<8>")
	)
	(segment
		(start 238.69396 -154.21356)
		(end 238.9378 -154.4574)
		(width 0.1651)
		(layer "F.Cu")
		(net "M_F_DQS_DP<8>")
	)
	(segment
		(start 238.9378 -154.4574)
		(end 238.9378 -155.829)
		(width 0.1651)
		(layer "F.Cu")
		(net "M_F_DQS_DP<8>")
	)
	(segment
		(start 238.899954 -156.87294)
		(end 238.900462 -156.87294)
		(width 0.1651)
		(layer "F.Cu")
		(net "M_F_DQS_DP<8>")
	)
	(segment
		(start 246.485664 -84.31784)
		(end 245.914164 -84.31784)
		(width 0.1651)
		(layer "F.Cu")
		(net "M_F_DQS_DP<8>")
	)
	(segment
		(start 238.437928 -154.21356)
		(end 238.69396 -154.21356)
		(width 0.1651)
		(layer "F.Cu")
		(net "M_F_DQS_DP<8>")
	)
	(segment
		(start 238.899954 -155.866846)
		(end 238.899954 -156.87294)
		(width 0.1651)
		(layer "F.Cu")
		(net "M_F_DQS_DP<8>")
	)
	(via
		(at 238.437928 -150.142956)
		(size 0.508)
		(drill 0.254)
		(layers "F.Cu" "B.Cu")
		(net "M_F_DQS_DP<8>")
	)
	(via
		(at 238.437928 -154.21356)
		(size 0.508)
		(drill 0.254)
		(layers "F.Cu" "B.Cu")
		(net "M_F_DQS_DP<8>")
	)
	(via
		(at 245.914164 -84.31784)
		(size 0.508)
		(drill 0.254)
		(layers "F.Cu" "B.Cu")
		(net "M_F_DQS_DP<8>")
	)
	(segment
		(start 238.9378 -149.8854)
		(end 238.9378 -148.6662)
		(width 0.1651)
		(layer "B.Cu")
		(net "M_F_DQS_DP<8>")
	)
	(segment
		(start 238.9378 -148.6662)
		(end 238.899954 -148.628354)
		(width 0.1651)
		(layer "B.Cu")
		(net "M_F_DQS_DP<8>")
	)
	(segment
		(start 238.899954 -147.478496)
		(end 238.900462 -147.478496)
		(width 0.1651)
		(layer "B.Cu")
		(net "M_F_DQS_DP<8>")
	)
	(segment
		(start 238.437928 -150.142956)
		(end 238.680244 -150.142956)
		(width 0.1651)
		(layer "B.Cu")
		(net "M_F_DQS_DP<8>")
	)
	(segment
		(start 238.899954 -148.628354)
		(end 238.899954 -147.478496)
		(width 0.1651)
		(layer "B.Cu")
		(net "M_F_DQS_DP<8>")
	)
	(segment
		(start 238.680244 -150.142956)
		(end 238.9378 -149.8854)
		(width 0.1651)
		(layer "B.Cu")
		(net "M_F_DQS_DP<8>")
	)
	(segment
		(start 246.432324 -96.48952)
		(end 246.421402 -96.507808)
		(width 0.0889)
		(layer "In4.Cu")
		(net "M_F_DQS_DP<8>")
	)
	(segment
		(start 246.432324 -89.55532)
		(end 246.425974 -89.565988)
		(width 0.0889)
		(layer "In4.Cu")
		(net "M_F_DQS_DP<8>")
	)
	(segment
		(start 246.421402 -96.507808)
		(end 246.420894 -96.50857)
		(width 0.0889)
		(layer "In4.Cu")
		(net "M_F_DQS_DP<8>")
	)
	(segment
		(start 246.310912 -85.361018)
		(end 246.310912 -85.7758)
		(width 0.0889)
		(layer "In4.Cu")
		(net "M_F_DQS_DP<8>")
	)
	(segment
		(start 246.425974 -95.509588)
		(end 246.421148 -95.518224)
		(width 0.0889)
		(layer "In4.Cu")
		(net "M_F_DQS_DP<8>")
	)
	(segment
		(start 246.425974 -87.584788)
		(end 246.421148 -87.593424)
		(width 0.0889)
		(layer "In4.Cu")
		(net "M_F_DQS_DP<8>")
	)
	(segment
		(start 246.432324 -95.49892)
		(end 246.425974 -95.509588)
		(width 0.0889)
		(layer "In4.Cu")
		(net "M_F_DQS_DP<8>")
	)
	(segment
		(start 239.220248 -149.360636)
		(end 238.437928 -150.142956)
		(width 0.14224)
		(layer "In4.Cu")
		(net "M_F_DQS_DP<8>")
	)
	(segment
		(start 240.057686 -115.57381)
		(end 239.666272 -115.965224)
		(width 0.14224)
		(layer "In4.Cu")
		(net "M_F_DQS_DP<8>")
	)
	(segment
		(start 238.37392 -122.785886)
		(end 239.220248 -123.632214)
		(width 0.14224)
		(layer "In4.Cu")
		(net "M_F_DQS_DP<8>")
	)
	(segment
		(start 238.78032 -116.617496)
		(end 239.001808 -116.838984)
		(width 0.14224)
		(layer "In4.Cu")
		(net "M_F_DQS_DP<8>")
	)
	(segment
		(start 246.301514 -102.635304)
		(end 246.301514 -103.87203)
		(width 0.0889)
		(layer "In4.Cu")
		(net "M_F_DQS_DP<8>")
	)
	(segment
		(start 246.425974 -94.518988)
		(end 246.421148 -94.527624)
		(width 0.0889)
		(layer "In4.Cu")
		(net "M_F_DQS_DP<8>")
	)
	(segment
		(start 246.425974 -93.928438)
		(end 246.432324 -93.939106)
		(width 0.0889)
		(layer "In4.Cu")
		(net "M_F_DQS_DP<8>")
	)
	(segment
		(start 246.432324 -87.57412)
		(end 246.425974 -87.584788)
		(width 0.0889)
		(layer "In4.Cu")
		(net "M_F_DQS_DP<8>")
	)
	(segment
		(start 246.340884 -103.933498)
		(end 246.340884 -105.476548)
		(width 0.14224)
		(layer "In4.Cu")
		(net "M_F_DQS_DP<8>")
	)
	(segment
		(start 246.432324 -90.54592)
		(end 246.425974 -90.556588)
		(width 0.0889)
		(layer "In4.Cu")
		(net "M_F_DQS_DP<8>")
	)
	(segment
		(start 246.425974 -89.565988)
		(end 246.421148 -89.574624)
		(width 0.0889)
		(layer "In4.Cu")
		(net "M_F_DQS_DP<8>")
	)
	(segment
		(start 239.001808 -116.838984)
		(end 239.551718 -116.838984)
		(width 0.14224)
		(layer "In4.Cu")
		(net "M_F_DQS_DP<8>")
	)
	(segment
		(start 246.508524 -97.04324)
		(end 246.508524 -100.454714)
		(width 0.0889)
		(layer "In4.Cu")
		(net "M_F_DQS_DP<8>")
	)
	(segment
		(start 246.432324 -88.56472)
		(end 246.425974 -88.575388)
		(width 0.0889)
		(layer "In4.Cu")
		(net "M_F_DQS_DP<8>")
	)
	(segment
		(start 246.508524 -100.454714)
		(end 246.085614 -100.877624)
		(width 0.0889)
		(layer "In4.Cu")
		(net "M_F_DQS_DP<8>")
	)
	(segment
		(start 246.340884 -105.476548)
		(end 240.057686 -111.759492)
		(width 0.14224)
		(layer "In4.Cu")
		(net "M_F_DQS_DP<8>")
	)
	(segment
		(start 238.646208 -118.30812)
		(end 238.37392 -118.580408)
		(width 0.14224)
		(layer "In4.Cu")
		(net "M_F_DQS_DP<8>")
	)
	(segment
		(start 246.425974 -91.547188)
		(end 246.421148 -91.555824)
		(width 0.0889)
		(layer "In4.Cu")
		(net "M_F_DQS_DP<8>")
	)
	(segment
		(start 246.425974 -90.556588)
		(end 246.421148 -90.565224)
		(width 0.0889)
		(layer "In4.Cu")
		(net "M_F_DQS_DP<8>")
	)
	(segment
		(start 239.551718 -118.30812)
		(end 238.646208 -118.30812)
		(width 0.14224)
		(layer "In4.Cu")
		(net "M_F_DQS_DP<8>")
	)
	(segment
		(start 246.432324 -86.58352)
		(end 246.425974 -86.594188)
		(width 0.0889)
		(layer "In4.Cu")
		(net "M_F_DQS_DP<8>")
	)
	(segment
		(start 239.666272 -115.965224)
		(end 239.001808 -115.965224)
		(width 0.14224)
		(layer "In4.Cu")
		(net "M_F_DQS_DP<8>")
	)
	(segment
		(start 246.085614 -102.261924)
		(end 246.301514 -102.635304)
		(width 0.0889)
		(layer "In4.Cu")
		(net "M_F_DQS_DP<8>")
	)
	(segment
		(start 239.551718 -116.838984)
		(end 239.836198 -117.123464)
		(width 0.14224)
		(layer "In4.Cu")
		(net "M_F_DQS_DP<8>")
	)
	(segment
		(start 246.425974 -88.575388)
		(end 246.421148 -88.584024)
		(width 0.0889)
		(layer "In4.Cu")
		(net "M_F_DQS_DP<8>")
	)
	(segment
		(start 246.432324 -91.53652)
		(end 246.425974 -91.547188)
		(width 0.0889)
		(layer "In4.Cu")
		(net "M_F_DQS_DP<8>")
	)
	(segment
		(start 246.420894 -96.50857)
		(end 246.421148 -96.508824)
		(width 0.0889)
		(layer "In4.Cu")
		(net "M_F_DQS_DP<8>")
	)
	(segment
		(start 239.836198 -117.123464)
		(end 239.836198 -118.02364)
		(width 0.14224)
		(layer "In4.Cu")
		(net "M_F_DQS_DP<8>")
	)
	(segment
		(start 238.37392 -118.580408)
		(end 238.37392 -122.785886)
		(width 0.14224)
		(layer "In4.Cu")
		(net "M_F_DQS_DP<8>")
	)
	(segment
		(start 239.001808 -115.965224)
		(end 238.78032 -116.186712)
		(width 0.14224)
		(layer "In4.Cu")
		(net "M_F_DQS_DP<8>")
	)
	(segment
		(start 246.340884 -103.9114)
		(end 246.340884 -103.933498)
		(width 0.0889)
		(layer "In4.Cu")
		(net "M_F_DQS_DP<8>")
	)
	(segment
		(start 239.836198 -118.02364)
		(end 239.551718 -118.30812)
		(width 0.14224)
		(layer "In4.Cu")
		(net "M_F_DQS_DP<8>")
	)
	(segment
		(start 246.425974 -86.594188)
		(end 246.421148 -86.602824)
		(width 0.0889)
		(layer "In4.Cu")
		(net "M_F_DQS_DP<8>")
	)
	(segment
		(start 246.301514 -103.87203)
		(end 246.340884 -103.9114)
		(width 0.0889)
		(layer "In4.Cu")
		(net "M_F_DQS_DP<8>")
	)
	(segment
		(start 240.057686 -111.759492)
		(end 240.057686 -115.57381)
		(width 0.14224)
		(layer "In4.Cu")
		(net "M_F_DQS_DP<8>")
	)
	(segment
		(start 239.220248 -123.632214)
		(end 239.220248 -149.360636)
		(width 0.14224)
		(layer "In4.Cu")
		(net "M_F_DQS_DP<8>")
	)
	(segment
		(start 246.085614 -100.877624)
		(end 246.085614 -102.261924)
		(width 0.0889)
		(layer "In4.Cu")
		(net "M_F_DQS_DP<8>")
	)
	(segment
		(start 246.425974 -96.900238)
		(end 246.508524 -97.04324)
		(width 0.0889)
		(layer "In4.Cu")
		(net "M_F_DQS_DP<8>")
	)
	(segment
		(start 238.78032 -116.186712)
		(end 238.78032 -116.617496)
		(width 0.14224)
		(layer "In4.Cu")
		(net "M_F_DQS_DP<8>")
	)
	(segment
		(start 246.425974 -92.537788)
		(end 246.421148 -92.546424)
		(width 0.0889)
		(layer "In4.Cu")
		(net "M_F_DQS_DP<8>")
	)
	(segment
		(start 246.432324 -92.52712)
		(end 246.425974 -92.537788)
		(width 0.0889)
		(layer "In4.Cu")
		(net "M_F_DQS_DP<8>")
	)
	(arc
		(start 246.425974 -95.909638)
		(mid 246.505196 -96.198756)
		(end 246.432324 -96.48952)
		(width 0.0889)
		(layer "In4.Cu")
		(net "M_F_DQS_DP<8>")
	)
	(arc
		(start 246.310912 -85.7758)
		(mid 246.365245 -85.891334)
		(end 246.425974 -86.003638)
		(width 0.0889)
		(layer "In4.Cu")
		(net "M_F_DQS_DP<8>")
	)
	(arc
		(start 246.425974 -87.984838)
		(mid 246.505196 -88.273956)
		(end 246.432324 -88.56472)
		(width 0.0889)
		(layer "In4.Cu")
		(net "M_F_DQS_DP<8>")
	)
	(arc
		(start 246.421148 -88.584024)
		(mid 246.372393 -88.780376)
		(end 246.425974 -88.975438)
		(width 0.0889)
		(layer "In4.Cu")
		(net "M_F_DQS_DP<8>")
	)
	(arc
		(start 246.425974 -90.956638)
		(mid 246.505196 -91.245756)
		(end 246.432324 -91.53652)
		(width 0.0889)
		(layer "In4.Cu")
		(net "M_F_DQS_DP<8>")
	)
	(arc
		(start 245.914164 -84.31784)
		(mid 246.065816 -84.723079)
		(end 246.260874 -85.109304)
		(width 0.0889)
		(layer "In4.Cu")
		(net "M_F_DQS_DP<8>")
	)
	(arc
		(start 246.432324 -93.939106)
		(mid 246.505122 -94.229869)
		(end 246.425974 -94.518988)
		(width 0.0889)
		(layer "In4.Cu")
		(net "M_F_DQS_DP<8>")
	)
	(arc
		(start 246.425974 -93.528642)
		(mid 246.372475 -93.72854)
		(end 246.425974 -93.928438)
		(width 0.0889)
		(layer "In4.Cu")
		(net "M_F_DQS_DP<8>")
	)
	(arc
		(start 246.425974 -88.975438)
		(mid 246.505196 -89.264556)
		(end 246.432324 -89.55532)
		(width 0.0889)
		(layer "In4.Cu")
		(net "M_F_DQS_DP<8>")
	)
	(arc
		(start 246.421148 -90.565224)
		(mid 246.372393 -90.761576)
		(end 246.425974 -90.956638)
		(width 0.0889)
		(layer "In4.Cu")
		(net "M_F_DQS_DP<8>")
	)
	(arc
		(start 246.425974 -89.966038)
		(mid 246.505196 -90.255156)
		(end 246.432324 -90.54592)
		(width 0.0889)
		(layer "In4.Cu")
		(net "M_F_DQS_DP<8>")
	)
	(arc
		(start 246.425974 -94.919038)
		(mid 246.505196 -95.208156)
		(end 246.432324 -95.49892)
		(width 0.0889)
		(layer "In4.Cu")
		(net "M_F_DQS_DP<8>")
	)
	(arc
		(start 246.421148 -87.593424)
		(mid 246.372393 -87.789776)
		(end 246.425974 -87.984838)
		(width 0.0889)
		(layer "In4.Cu")
		(net "M_F_DQS_DP<8>")
	)
	(arc
		(start 246.421148 -89.574624)
		(mid 246.372393 -89.770976)
		(end 246.425974 -89.966038)
		(width 0.0889)
		(layer "In4.Cu")
		(net "M_F_DQS_DP<8>")
	)
	(arc
		(start 246.421148 -95.518224)
		(mid 246.372393 -95.714576)
		(end 246.425974 -95.909638)
		(width 0.0889)
		(layer "In4.Cu")
		(net "M_F_DQS_DP<8>")
	)
	(arc
		(start 246.425974 -86.003638)
		(mid 246.505196 -86.292756)
		(end 246.432324 -86.58352)
		(width 0.0889)
		(layer "In4.Cu")
		(net "M_F_DQS_DP<8>")
	)
	(arc
		(start 246.421148 -86.602824)
		(mid 246.372393 -86.799176)
		(end 246.425974 -86.994238)
		(width 0.0889)
		(layer "In4.Cu")
		(net "M_F_DQS_DP<8>")
	)
	(arc
		(start 246.421148 -92.546424)
		(mid 246.372393 -92.742776)
		(end 246.425974 -92.937838)
		(width 0.0889)
		(layer "In4.Cu")
		(net "M_F_DQS_DP<8>")
	)
	(arc
		(start 246.425974 -91.947238)
		(mid 246.505196 -92.236356)
		(end 246.432324 -92.52712)
		(width 0.0889)
		(layer "In4.Cu")
		(net "M_F_DQS_DP<8>")
	)
	(arc
		(start 246.421148 -94.527624)
		(mid 246.372393 -94.723976)
		(end 246.425974 -94.919038)
		(width 0.0889)
		(layer "In4.Cu")
		(net "M_F_DQS_DP<8>")
	)
	(arc
		(start 246.421148 -96.508824)
		(mid 246.372393 -96.705176)
		(end 246.425974 -96.900238)
		(width 0.0889)
		(layer "In4.Cu")
		(net "M_F_DQS_DP<8>")
	)
	(arc
		(start 246.425974 -86.994238)
		(mid 246.505196 -87.283356)
		(end 246.432324 -87.57412)
		(width 0.0889)
		(layer "In4.Cu")
		(net "M_F_DQS_DP<8>")
	)
	(arc
		(start 246.260874 -85.109304)
		(mid 246.306587 -85.231041)
		(end 246.310912 -85.361018)
		(width 0.0889)
		(layer "In4.Cu")
		(net "M_F_DQS_DP<8>")
	)
	(arc
		(start 246.421148 -91.555824)
		(mid 246.372393 -91.752176)
		(end 246.425974 -91.947238)
		(width 0.0889)
		(layer "In4.Cu")
		(net "M_F_DQS_DP<8>")
	)
	(arc
		(start 246.425974 -92.937838)
		(mid 246.505105 -93.23324)
		(end 246.425974 -93.528642)
		(width 0.0889)
		(layer "In4.Cu")
		(net "M_F_DQS_DP<8>")
	)
	(segment
		(start 238.437928 -154.21356)
		(end 238.898176 -153.753312)
		(width 0.14224)
		(layer "In11.Cu")
		(net "M_F_DQS_DP<8>")
	)
	(segment
		(start 238.57966 -153.0604)
		(end 238.33328 -153.0604)
		(width 0.14224)
		(layer "In11.Cu")
		(net "M_F_DQS_DP<8>")
	)
	(segment
		(start 238.260636 -152.501092)
		(end 238.44885 -152.312878)
		(width 0.14224)
		(layer "In11.Cu")
		(net "M_F_DQS_DP<8>")
	)
	(segment
		(start 238.233712 -151.257)
		(end 238.618776 -151.257)
		(width 0.14224)
		(layer "In11.Cu")
		(net "M_F_DQS_DP<8>")
	)
	(segment
		(start 238.44885 -152.052274)
		(end 238.263176 -151.8666)
		(width 0.14224)
		(layer "In11.Cu")
		(net "M_F_DQS_DP<8>")
	)
	(segment
		(start 238.618776 -151.257)
		(end 238.872776 -151.003)
		(width 0.14224)
		(layer "In11.Cu")
		(net "M_F_DQS_DP<8>")
	)
	(segment
		(start 238.080804 -152.807924)
		(end 238.080804 -152.628092)
		(width 0.14224)
		(layer "In11.Cu")
		(net "M_F_DQS_DP<8>")
	)
	(segment
		(start 238.063278 -151.427434)
		(end 238.233712 -151.257)
		(width 0.14224)
		(layer "In11.Cu")
		(net "M_F_DQS_DP<8>")
	)
	(segment
		(start 238.080804 -152.628092)
		(end 238.207804 -152.501092)
		(width 0.14224)
		(layer "In11.Cu")
		(net "M_F_DQS_DP<8>")
	)
	(segment
		(start 238.898176 -153.378916)
		(end 238.57966 -153.0604)
		(width 0.14224)
		(layer "In11.Cu")
		(net "M_F_DQS_DP<8>")
	)
	(segment
		(start 238.44885 -152.312878)
		(end 238.44885 -152.052274)
		(width 0.14224)
		(layer "In11.Cu")
		(net "M_F_DQS_DP<8>")
	)
	(segment
		(start 238.063278 -151.751792)
		(end 238.063278 -151.427434)
		(width 0.14224)
		(layer "In11.Cu")
		(net "M_F_DQS_DP<8>")
	)
	(segment
		(start 238.898176 -153.753312)
		(end 238.898176 -153.378916)
		(width 0.14224)
		(layer "In11.Cu")
		(net "M_F_DQS_DP<8>")
	)
	(segment
		(start 238.872776 -151.003)
		(end 238.872776 -150.577804)
		(width 0.14224)
		(layer "In11.Cu")
		(net "M_F_DQS_DP<8>")
	)
	(segment
		(start 238.207804 -152.501092)
		(end 238.260636 -152.501092)
		(width 0.14224)
		(layer "In11.Cu")
		(net "M_F_DQS_DP<8>")
	)
	(segment
		(start 238.33328 -153.0604)
		(end 238.080804 -152.807924)
		(width 0.14224)
		(layer "In11.Cu")
		(net "M_F_DQS_DP<8>")
	)
	(segment
		(start 238.872776 -150.577804)
		(end 238.437928 -150.142956)
		(width 0.14224)
		(layer "In11.Cu")
		(net "M_F_DQS_DP<8>")
	)
	(segment
		(start 238.263176 -151.8666)
		(end 238.178086 -151.8666)
		(width 0.14224)
		(layer "In11.Cu")
		(net "M_F_DQS_DP<8>")
	)
	(segment
		(start 238.178086 -151.8666)
		(end 238.063278 -151.751792)
		(width 0.14224)
		(layer "In11.Cu")
		(net "M_F_DQS_DP<8>")
	)
	(segment
		(start 312.850022 -155.866846)
		(end 312.887868 -155.829)
		(width 0.1651)
		(layer "F.Cu")
		(net "M_F_DQS_DP<7>")
	)
	(segment
		(start 312.850276 -156.87294)
		(end 312.850022 -156.87294)
		(width 0.1651)
		(layer "F.Cu")
		(net "M_F_DQS_DP<7>")
	)
	(segment
		(start 312.644028 -154.21356)
		(end 312.387996 -154.21356)
		(width 0.1651)
		(layer "F.Cu")
		(net "M_F_DQS_DP<7>")
	)
	(segment
		(start 312.850022 -156.87294)
		(end 312.850022 -155.866846)
		(width 0.1651)
		(layer "F.Cu")
		(net "M_F_DQS_DP<7>")
	)
	(segment
		(start 283.212794 -91.565984)
		(end 283.784294 -91.565984)
		(width 0.1651)
		(layer "F.Cu")
		(net "M_F_DQS_DP<7>")
	)
	(segment
		(start 312.887868 -155.829)
		(end 312.887868 -154.4574)
		(width 0.1651)
		(layer "F.Cu")
		(net "M_F_DQS_DP<7>")
	)
	(segment
		(start 312.887868 -154.4574)
		(end 312.644028 -154.21356)
		(width 0.1651)
		(layer "F.Cu")
		(net "M_F_DQS_DP<7>")
	)
	(via
		(at 283.784294 -91.565984)
		(size 0.508)
		(drill 0.254)
		(layers "F.Cu" "B.Cu")
		(net "M_F_DQS_DP<7>")
	)
	(via
		(at 312.387996 -150.142956)
		(size 0.508)
		(drill 0.254)
		(layers "F.Cu" "B.Cu")
		(net "M_F_DQS_DP<7>")
	)
	(via
		(at 312.387996 -154.21356)
		(size 0.508)
		(drill 0.254)
		(layers "F.Cu" "B.Cu")
		(net "M_F_DQS_DP<7>")
	)
	(segment
		(start 312.630312 -150.142956)
		(end 312.887868 -149.8854)
		(width 0.1651)
		(layer "B.Cu")
		(net "M_F_DQS_DP<7>")
	)
	(segment
		(start 312.387996 -150.142956)
		(end 312.630312 -150.142956)
		(width 0.1651)
		(layer "B.Cu")
		(net "M_F_DQS_DP<7>")
	)
	(segment
		(start 312.887868 -148.6662)
		(end 312.850022 -148.628354)
		(width 0.1651)
		(layer "B.Cu")
		(net "M_F_DQS_DP<7>")
	)
	(segment
		(start 312.850022 -147.478496)
		(end 312.850276 -147.478496)
		(width 0.1651)
		(layer "B.Cu")
		(net "M_F_DQS_DP<7>")
	)
	(segment
		(start 312.887868 -149.8854)
		(end 312.887868 -148.6662)
		(width 0.1651)
		(layer "B.Cu")
		(net "M_F_DQS_DP<7>")
	)
	(segment
		(start 312.850022 -148.628354)
		(end 312.850022 -147.478496)
		(width 0.1651)
		(layer "B.Cu")
		(net "M_F_DQS_DP<7>")
	)
	(segment
		(start 312.210704 -152.501092)
		(end 312.150506 -152.501092)
		(width 0.14224)
		(layer "In11.Cu")
		(net "M_F_DQS_DP<7>")
	)
	(segment
		(start 299.914818 -111.167164)
		(end 301.15383 -111.167164)
		(width 0.14224)
		(layer "In11.Cu")
		(net "M_F_DQS_DP<7>")
	)
	(segment
		(start 293.018972 -105.221278)
		(end 293.42588 -105.628186)
		(width 0.14224)
		(layer "In11.Cu")
		(net "M_F_DQS_DP<7>")
	)
	(segment
		(start 312.568844 -151.257)
		(end 312.18378 -151.257)
		(width 0.14224)
		(layer "In11.Cu")
		(net "M_F_DQS_DP<7>")
	)
	(segment
		(start 289.442144 -100.1776)
		(end 289.44697 -100.186236)
		(width 0.0889)
		(layer "In11.Cu")
		(net "M_F_DQS_DP<7>")
	)
	(segment
		(start 289.44697 -99.195636)
		(end 289.45332 -99.206304)
		(width 0.0889)
		(layer "In11.Cu")
		(net "M_F_DQS_DP<7>")
	)
	(segment
		(start 293.42588 -105.628186)
		(end 293.42588 -106.517694)
		(width 0.14224)
		(layer "In11.Cu")
		(net "M_F_DQS_DP<7>")
	)
	(segment
		(start 299.580046 -111.501936)
		(end 299.914818 -111.167164)
		(width 0.14224)
		(layer "In11.Cu")
		(net "M_F_DQS_DP<7>")
	)
	(segment
		(start 287.200086 -94.937834)
		(end 287.23971 -94.937834)
		(width 0.0889)
		(layer "In11.Cu")
		(net "M_F_DQS_DP<7>")
	)
	(segment
		(start 301.15383 -111.167164)
		(end 313.170316 -123.18365)
		(width 0.14224)
		(layer "In11.Cu")
		(net "M_F_DQS_DP<7>")
	)
	(segment
		(start 312.013346 -152.864566)
		(end 312.20918 -153.0604)
		(width 0.14224)
		(layer "In11.Cu")
		(net "M_F_DQS_DP<7>")
	)
	(segment
		(start 312.013346 -151.751792)
		(end 312.128154 -151.8666)
		(width 0.14224)
		(layer "In11.Cu")
		(net "M_F_DQS_DP<7>")
	)
	(segment
		(start 289.442144 -97.2058)
		(end 289.44697 -97.214436)
		(width 0.0889)
		(layer "In11.Cu")
		(net "M_F_DQS_DP<7>")
	)
	(segment
		(start 312.013346 -151.427434)
		(end 312.013346 -151.751792)
		(width 0.14224)
		(layer "In11.Cu")
		(net "M_F_DQS_DP<7>")
	)
	(segment
		(start 286.347408 -94.442534)
		(end 286.37738 -94.442534)
		(width 0.0889)
		(layer "In11.Cu")
		(net "M_F_DQS_DP<7>")
	)
	(segment
		(start 289.45332 -100.766118)
		(end 289.44697 -100.776786)
		(width 0.0889)
		(layer "In11.Cu")
		(net "M_F_DQS_DP<7>")
	)
	(segment
		(start 312.20918 -153.0604)
		(end 312.594244 -153.0604)
		(width 0.14224)
		(layer "In11.Cu")
		(net "M_F_DQS_DP<7>")
	)
	(segment
		(start 289.782504 -102.367588)
		(end 289.81527 -102.367588)
		(width 0.0889)
		(layer "In11.Cu")
		(net "M_F_DQS_DP<7>")
	)
	(segment
		(start 312.128154 -151.8666)
		(end 312.213244 -151.8666)
		(width 0.14224)
		(layer "In11.Cu")
		(net "M_F_DQS_DP<7>")
	)
	(segment
		(start 291.96284 -105.42524)
		(end 292.241224 -105.42524)
		(width 0.14224)
		(layer "In11.Cu")
		(net "M_F_DQS_DP<7>")
	)
	(segment
		(start 290.637214 -102.862634)
		(end 290.741608 -102.862634)
		(width 0.0889)
		(layer "In11.Cu")
		(net "M_F_DQS_DP<7>")
	)
	(segment
		(start 312.150506 -152.501092)
		(end 312.013346 -152.638252)
		(width 0.14224)
		(layer "In11.Cu")
		(net "M_F_DQS_DP<7>")
	)
	(segment
		(start 290.994084 -104.456484)
		(end 291.96284 -105.42524)
		(width 0.14224)
		(layer "In11.Cu")
		(net "M_F_DQS_DP<7>")
	)
	(segment
		(start 312.391044 -152.0444)
		(end 312.391044 -152.320752)
		(width 0.14224)
		(layer "In11.Cu")
		(net "M_F_DQS_DP<7>")
	)
	(segment
		(start 292.445186 -105.221278)
		(end 293.018972 -105.221278)
		(width 0.14224)
		(layer "In11.Cu")
		(net "M_F_DQS_DP<7>")
	)
	(segment
		(start 312.594244 -153.0604)
		(end 312.848244 -153.3144)
		(width 0.14224)
		(layer "In11.Cu")
		(net "M_F_DQS_DP<7>")
	)
	(segment
		(start 294.815768 -106.69016)
		(end 298.917106 -110.791498)
		(width 0.14224)
		(layer "In11.Cu")
		(net "M_F_DQS_DP<7>")
	)
	(segment
		(start 289.442144 -99.187)
		(end 289.44697 -99.195636)
		(width 0.0889)
		(layer "In11.Cu")
		(net "M_F_DQS_DP<7>")
	)
	(segment
		(start 293.598346 -106.69016)
		(end 294.815768 -106.69016)
		(width 0.14224)
		(layer "In11.Cu")
		(net "M_F_DQS_DP<7>")
	)
	(segment
		(start 312.18378 -151.257)
		(end 312.013346 -151.427434)
		(width 0.14224)
		(layer "In11.Cu")
		(net "M_F_DQS_DP<7>")
	)
	(segment
		(start 298.917106 -110.791498)
		(end 298.917106 -112.055656)
		(width 0.14224)
		(layer "In11.Cu")
		(net "M_F_DQS_DP<7>")
	)
	(segment
		(start 299.580046 -112.041432)
		(end 299.580046 -111.501936)
		(width 0.14224)
		(layer "In11.Cu")
		(net "M_F_DQS_DP<7>")
	)
	(segment
		(start 312.848244 -153.753312)
		(end 312.387996 -154.21356)
		(width 0.14224)
		(layer "In11.Cu")
		(net "M_F_DQS_DP<7>")
	)
	(segment
		(start 312.213244 -151.8666)
		(end 312.391044 -152.0444)
		(width 0.14224)
		(layer "In11.Cu")
		(net "M_F_DQS_DP<7>")
	)
	(segment
		(start 312.822844 -151.003)
		(end 312.568844 -151.257)
		(width 0.14224)
		(layer "In11.Cu")
		(net "M_F_DQS_DP<7>")
	)
	(segment
		(start 293.42588 -106.517694)
		(end 293.598346 -106.69016)
		(width 0.14224)
		(layer "In11.Cu")
		(net "M_F_DQS_DP<7>")
	)
	(segment
		(start 312.391044 -152.320752)
		(end 312.210704 -152.501092)
		(width 0.14224)
		(layer "In11.Cu")
		(net "M_F_DQS_DP<7>")
	)
	(segment
		(start 313.170316 -123.18365)
		(end 313.170316 -149.360636)
		(width 0.14224)
		(layer "In11.Cu")
		(net "M_F_DQS_DP<7>")
	)
	(segment
		(start 284.631638 -93.452188)
		(end 284.664404 -93.452188)
		(width 0.0889)
		(layer "In11.Cu")
		(net "M_F_DQS_DP<7>")
	)
	(segment
		(start 299.064934 -112.203484)
		(end 299.417994 -112.203484)
		(width 0.14224)
		(layer "In11.Cu")
		(net "M_F_DQS_DP<7>")
	)
	(segment
		(start 290.994084 -104.237282)
		(end 290.994084 -104.456484)
		(width 0.14224)
		(layer "In11.Cu")
		(net "M_F_DQS_DP<7>")
	)
	(segment
		(start 288.920174 -95.928434)
		(end 288.95294 -95.928434)
		(width 0.0889)
		(layer "In11.Cu")
		(net "M_F_DQS_DP<7>")
	)
	(segment
		(start 285.486348 -93.947234)
		(end 285.514288 -93.947234)
		(width 0.0889)
		(layer "In11.Cu")
		(net "M_F_DQS_DP<7>")
	)
	(segment
		(start 312.822844 -150.577804)
		(end 312.822844 -151.003)
		(width 0.14224)
		(layer "In11.Cu")
		(net "M_F_DQS_DP<7>")
	)
	(segment
		(start 299.417994 -112.203484)
		(end 299.580046 -112.041432)
		(width 0.14224)
		(layer "In11.Cu")
		(net "M_F_DQS_DP<7>")
	)
	(segment
		(start 290.994084 -104.215184)
		(end 290.994084 -104.237282)
		(width 0.0889)
		(layer "In11.Cu")
		(net "M_F_DQS_DP<7>")
	)
	(segment
		(start 292.241224 -105.42524)
		(end 292.445186 -105.221278)
		(width 0.14224)
		(layer "In11.Cu")
		(net "M_F_DQS_DP<7>")
	)
	(segment
		(start 290.741608 -102.862634)
		(end 290.954714 -103.07574)
		(width 0.0889)
		(layer "In11.Cu")
		(net "M_F_DQS_DP<7>")
	)
	(segment
		(start 312.387996 -150.142956)
		(end 312.822844 -150.577804)
		(width 0.14224)
		(layer "In11.Cu")
		(net "M_F_DQS_DP<7>")
	)
	(segment
		(start 313.170316 -149.360636)
		(end 312.387996 -150.142956)
		(width 0.14224)
		(layer "In11.Cu")
		(net "M_F_DQS_DP<7>")
	)
	(segment
		(start 298.917106 -112.055656)
		(end 299.064934 -112.203484)
		(width 0.14224)
		(layer "In11.Cu")
		(net "M_F_DQS_DP<7>")
	)
	(segment
		(start 312.848244 -153.3144)
		(end 312.848244 -153.753312)
		(width 0.14224)
		(layer "In11.Cu")
		(net "M_F_DQS_DP<7>")
	)
	(segment
		(start 288.065464 -95.433134)
		(end 288.089594 -95.433134)
		(width 0.0889)
		(layer "In11.Cu")
		(net "M_F_DQS_DP<7>")
	)
	(segment
		(start 290.954714 -104.175814)
		(end 290.994084 -104.215184)
		(width 0.0889)
		(layer "In11.Cu")
		(net "M_F_DQS_DP<7>")
	)
	(segment
		(start 312.013346 -152.638252)
		(end 312.013346 -152.864566)
		(width 0.14224)
		(layer "In11.Cu")
		(net "M_F_DQS_DP<7>")
	)
	(segment
		(start 290.954714 -103.07574)
		(end 290.954714 -104.175814)
		(width 0.0889)
		(layer "In11.Cu")
		(net "M_F_DQS_DP<7>")
	)
	(arc
		(start 284.131004 -92.356686)
		(mid 284.172873 -92.419687)
		(end 284.222444 -92.476828)
		(width 0.0889)
		(layer "In11.Cu")
		(net "M_F_DQS_DP<7>")
	)
	(arc
		(start 289.44697 -99.786186)
		(mid 289.3935 -99.981249)
		(end 289.442144 -100.1776)
		(width 0.0889)
		(layer "In11.Cu")
		(net "M_F_DQS_DP<7>")
	)
	(arc
		(start 289.44697 -97.214436)
		(mid 289.526059 -97.510092)
		(end 289.44697 -97.805748)
		(width 0.0889)
		(layer "In11.Cu")
		(net "M_F_DQS_DP<7>")
	)
	(arc
		(start 289.44697 -98.795586)
		(mid 289.3935 -98.990649)
		(end 289.442144 -99.187)
		(width 0.0889)
		(layer "In11.Cu")
		(net "M_F_DQS_DP<7>")
	)
	(arc
		(start 286.87141 -94.737936)
		(mid 287.010154 -94.879969)
		(end 287.200086 -94.937834)
		(width 0.0889)
		(layer "In11.Cu")
		(net "M_F_DQS_DP<7>")
	)
	(arc
		(start 288.95294 -95.928434)
		(mid 289.451191 -96.231274)
		(end 289.44697 -96.814386)
		(width 0.0889)
		(layer "In11.Cu")
		(net "M_F_DQS_DP<7>")
	)
	(arc
		(start 289.44697 -100.776786)
		(mid 289.393471 -100.976684)
		(end 289.44697 -101.176582)
		(width 0.0889)
		(layer "In11.Cu")
		(net "M_F_DQS_DP<7>")
	)
	(arc
		(start 289.44697 -100.186236)
		(mid 289.526192 -100.475354)
		(end 289.45332 -100.766118)
		(width 0.0889)
		(layer "In11.Cu")
		(net "M_F_DQS_DP<7>")
	)
	(arc
		(start 285.154624 -93.747336)
		(mid 285.294703 -93.890072)
		(end 285.486348 -93.947234)
		(width 0.0889)
		(layer "In11.Cu")
		(net "M_F_DQS_DP<7>")
	)
	(arc
		(start 289.44697 -97.805748)
		(mid 289.393505 -98.005646)
		(end 289.44697 -98.205544)
		(width 0.0889)
		(layer "In11.Cu")
		(net "M_F_DQS_DP<7>")
	)
	(arc
		(start 284.296104 -92.851986)
		(mid 284.25085 -92.971208)
		(end 284.245304 -93.09862)
		(width 0.0889)
		(layer "In11.Cu")
		(net "M_F_DQS_DP<7>")
	)
	(arc
		(start 288.58845 -95.728536)
		(mid 288.728529 -95.871272)
		(end 288.920174 -95.928434)
		(width 0.0889)
		(layer "In11.Cu")
		(net "M_F_DQS_DP<7>")
	)
	(arc
		(start 287.23971 -94.937834)
		(mid 287.522927 -95.022115)
		(end 287.72993 -95.232982)
		(width 0.0889)
		(layer "In11.Cu")
		(net "M_F_DQS_DP<7>")
	)
	(arc
		(start 287.72993 -95.232982)
		(mid 287.871613 -95.376786)
		(end 288.065464 -95.433134)
		(width 0.0889)
		(layer "In11.Cu")
		(net "M_F_DQS_DP<7>")
	)
	(arc
		(start 286.013144 -94.242636)
		(mid 286.154301 -94.386021)
		(end 286.347408 -94.442534)
		(width 0.0889)
		(layer "In11.Cu")
		(net "M_F_DQS_DP<7>")
	)
	(arc
		(start 289.44697 -101.767386)
		(mid 289.444222 -102.162853)
		(end 289.782504 -102.367588)
		(width 0.0889)
		(layer "In11.Cu")
		(net "M_F_DQS_DP<7>")
	)
	(arc
		(start 289.44697 -96.814386)
		(mid 289.3935 -97.009449)
		(end 289.442144 -97.2058)
		(width 0.0889)
		(layer "In11.Cu")
		(net "M_F_DQS_DP<7>")
	)
	(arc
		(start 284.245304 -93.09862)
		(mid 284.372664 -93.347319)
		(end 284.631638 -93.452188)
		(width 0.0889)
		(layer "In11.Cu")
		(net "M_F_DQS_DP<7>")
	)
	(arc
		(start 283.784294 -91.565984)
		(mid 283.974903 -91.799074)
		(end 284.052518 -92.089986)
		(width 0.0889)
		(layer "In11.Cu")
		(net "M_F_DQS_DP<7>")
	)
	(arc
		(start 288.089594 -95.433134)
		(mid 288.377739 -95.515453)
		(end 288.58845 -95.728536)
		(width 0.0889)
		(layer "In11.Cu")
		(net "M_F_DQS_DP<7>")
	)
	(arc
		(start 289.81527 -102.367588)
		(mid 290.098487 -102.451869)
		(end 290.30549 -102.662736)
		(width 0.0889)
		(layer "In11.Cu")
		(net "M_F_DQS_DP<7>")
	)
	(arc
		(start 286.37738 -94.442534)
		(mid 286.662804 -94.526001)
		(end 286.87141 -94.737936)
		(width 0.0889)
		(layer "In11.Cu")
		(net "M_F_DQS_DP<7>")
	)
	(arc
		(start 289.44697 -101.176582)
		(mid 289.526101 -101.471984)
		(end 289.44697 -101.767386)
		(width 0.0889)
		(layer "In11.Cu")
		(net "M_F_DQS_DP<7>")
	)
	(arc
		(start 284.052518 -92.089986)
		(mid 284.075831 -92.228027)
		(end 284.131004 -92.356686)
		(width 0.0889)
		(layer "In11.Cu")
		(net "M_F_DQS_DP<7>")
	)
	(arc
		(start 289.45332 -99.206304)
		(mid 289.526118 -99.497067)
		(end 289.44697 -99.786186)
		(width 0.0889)
		(layer "In11.Cu")
		(net "M_F_DQS_DP<7>")
	)
	(arc
		(start 290.30549 -102.662736)
		(mid 290.445569 -102.805472)
		(end 290.637214 -102.862634)
		(width 0.0889)
		(layer "In11.Cu")
		(net "M_F_DQS_DP<7>")
	)
	(arc
		(start 285.514288 -93.947234)
		(mid 285.802433 -94.029553)
		(end 286.013144 -94.242636)
		(width 0.0889)
		(layer "In11.Cu")
		(net "M_F_DQS_DP<7>")
	)
	(arc
		(start 289.44697 -98.205544)
		(mid 289.525975 -98.500582)
		(end 289.44697 -98.795586)
		(width 0.0889)
		(layer "In11.Cu")
		(net "M_F_DQS_DP<7>")
	)
	(arc
		(start 284.222444 -92.476828)
		(mid 284.316405 -92.653177)
		(end 284.296104 -92.851986)
		(width 0.0889)
		(layer "In11.Cu")
		(net "M_F_DQS_DP<7>")
	)
	(arc
		(start 284.664404 -93.452188)
		(mid 284.947621 -93.536469)
		(end 285.154624 -93.747336)
		(width 0.0889)
		(layer "In11.Cu")
		(net "M_F_DQS_DP<7>")
	)
	(segment
		(start 303.500028 -156.87294)
		(end 303.500028 -155.866846)
		(width 0.1651)
		(layer "F.Cu")
		(net "M_F_DQS_DP<6>")
	)
	(segment
		(start 303.294034 -154.21356)
		(end 303.038002 -154.21356)
		(width 0.1651)
		(layer "F.Cu")
		(net "M_F_DQS_DP<6>")
	)
	(segment
		(start 278.061674 -91.565984)
		(end 278.633174 -91.565984)
		(width 0.1651)
		(layer "F.Cu")
		(net "M_F_DQS_DP<6>")
	)
	(segment
		(start 303.537874 -155.829)
		(end 303.537874 -154.4574)
		(width 0.1651)
		(layer "F.Cu")
		(net "M_F_DQS_DP<6>")
	)
	(segment
		(start 303.500282 -156.87294)
		(end 303.500028 -156.87294)
		(width 0.1651)
		(layer "F.Cu")
		(net "M_F_DQS_DP<6>")
	)
	(segment
		(start 303.537874 -154.4574)
		(end 303.294034 -154.21356)
		(width 0.1651)
		(layer "F.Cu")
		(net "M_F_DQS_DP<6>")
	)
	(segment
		(start 303.500028 -155.866846)
		(end 303.537874 -155.829)
		(width 0.1651)
		(layer "F.Cu")
		(net "M_F_DQS_DP<6>")
	)
	(via
		(at 303.038002 -150.142956)
		(size 0.508)
		(drill 0.254)
		(layers "F.Cu" "B.Cu")
		(net "M_F_DQS_DP<6>")
	)
	(via
		(at 278.633174 -91.565984)
		(size 0.508)
		(drill 0.254)
		(layers "F.Cu" "B.Cu")
		(net "M_F_DQS_DP<6>")
	)
	(via
		(at 303.038002 -154.21356)
		(size 0.508)
		(drill 0.254)
		(layers "F.Cu" "B.Cu")
		(net "M_F_DQS_DP<6>")
	)
	(segment
		(start 303.038002 -150.142956)
		(end 303.280318 -150.142956)
		(width 0.1651)
		(layer "B.Cu")
		(net "M_F_DQS_DP<6>")
	)
	(segment
		(start 303.280318 -150.142956)
		(end 303.537874 -149.8854)
		(width 0.1651)
		(layer "B.Cu")
		(net "M_F_DQS_DP<6>")
	)
	(segment
		(start 303.537874 -149.8854)
		(end 303.537874 -148.6662)
		(width 0.1651)
		(layer "B.Cu")
		(net "M_F_DQS_DP<6>")
	)
	(segment
		(start 303.500028 -147.478496)
		(end 303.500282 -147.478496)
		(width 0.1651)
		(layer "B.Cu")
		(net "M_F_DQS_DP<6>")
	)
	(segment
		(start 303.537874 -148.6662)
		(end 303.500028 -148.628354)
		(width 0.1651)
		(layer "B.Cu")
		(net "M_F_DQS_DP<6>")
	)
	(segment
		(start 303.500028 -148.628354)
		(end 303.500028 -147.478496)
		(width 0.1651)
		(layer "B.Cu")
		(net "M_F_DQS_DP<6>")
	)
	(segment
		(start 297.172126 -119.143272)
		(end 297.484546 -118.830852)
		(width 0.14224)
		(layer "In11.Cu")
		(net "M_F_DQS_DP<6>")
	)
	(segment
		(start 283.437584 -103.253286)
		(end 283.432758 -103.261922)
		(width 0.0889)
		(layer "In11.Cu")
		(net "M_F_DQS_DP<6>")
	)
	(segment
		(start 283.443934 -104.233218)
		(end 283.437584 -104.243886)
		(width 0.0889)
		(layer "In11.Cu")
		(net "M_F_DQS_DP<6>")
	)
	(segment
		(start 302.663352 -152.864566)
		(end 302.859186 -153.0604)
		(width 0.14224)
		(layer "In11.Cu")
		(net "M_F_DQS_DP<6>")
	)
	(segment
		(start 302.86071 -152.501092)
		(end 302.800512 -152.501092)
		(width 0.14224)
		(layer "In11.Cu")
		(net "M_F_DQS_DP<6>")
	)
	(segment
		(start 303.21885 -151.257)
		(end 302.833786 -151.257)
		(width 0.14224)
		(layer "In11.Cu")
		(net "M_F_DQS_DP<6>")
	)
	(segment
		(start 302.663352 -151.427434)
		(end 302.663352 -151.751792)
		(width 0.14224)
		(layer "In11.Cu")
		(net "M_F_DQS_DP<6>")
	)
	(segment
		(start 283.479494 -112.94999)
		(end 290.346892 -119.817388)
		(width 0.14224)
		(layer "In11.Cu")
		(net "M_F_DQS_DP<6>")
	)
	(segment
		(start 282.052268 -97.909634)
		(end 282.085034 -97.909634)
		(width 0.0889)
		(layer "In11.Cu")
		(net "M_F_DQS_DP<6>")
	)
	(segment
		(start 303.04105 -152.0444)
		(end 303.04105 -152.320752)
		(width 0.14224)
		(layer "In11.Cu")
		(net "M_F_DQS_DP<6>")
	)
	(segment
		(start 298.373546 -119.527828)
		(end 298.528486 -119.682768)
		(width 0.14224)
		(layer "In11.Cu")
		(net "M_F_DQS_DP<6>")
	)
	(segment
		(start 303.24425 -153.0604)
		(end 303.49825 -153.3144)
		(width 0.14224)
		(layer "In11.Cu")
		(net "M_F_DQS_DP<6>")
	)
	(segment
		(start 283.516324 -106.209592)
		(end 283.440124 -106.285792)
		(width 0.0889)
		(layer "In11.Cu")
		(net "M_F_DQS_DP<6>")
	)
	(segment
		(start 283.437584 -104.243886)
		(end 283.432758 -104.252522)
		(width 0.0889)
		(layer "In11.Cu")
		(net "M_F_DQS_DP<6>")
	)
	(segment
		(start 302.86325 -151.8666)
		(end 303.04105 -152.0444)
		(width 0.14224)
		(layer "In11.Cu")
		(net "M_F_DQS_DP<6>")
	)
	(segment
		(start 302.800512 -152.501092)
		(end 302.663352 -152.638252)
		(width 0.14224)
		(layer "In11.Cu")
		(net "M_F_DQS_DP<6>")
	)
	(segment
		(start 294.54221 -119.817388)
		(end 295.272968 -119.08663)
		(width 0.14224)
		(layer "In11.Cu")
		(net "M_F_DQS_DP<6>")
	)
	(segment
		(start 283.440124 -107.126532)
		(end 283.479494 -107.165902)
		(width 0.0889)
		(layer "In11.Cu")
		(net "M_F_DQS_DP<6>")
	)
	(segment
		(start 283.443934 -105.223818)
		(end 283.437584 -105.234486)
		(width 0.0889)
		(layer "In11.Cu")
		(net "M_F_DQS_DP<6>")
	)
	(segment
		(start 283.440124 -106.285792)
		(end 283.440124 -107.126532)
		(width 0.0889)
		(layer "In11.Cu")
		(net "M_F_DQS_DP<6>")
	)
	(segment
		(start 302.663352 -152.638252)
		(end 302.663352 -152.864566)
		(width 0.14224)
		(layer "In11.Cu")
		(net "M_F_DQS_DP<6>")
	)
	(segment
		(start 298.061126 -118.830852)
		(end 298.373546 -119.143272)
		(width 0.14224)
		(layer "In11.Cu")
		(net "M_F_DQS_DP<6>")
	)
	(segment
		(start 303.820322 -149.308566)
		(end 303.4284 -149.700488)
		(width 0.14224)
		(layer "In11.Cu")
		(net "M_F_DQS_DP<6>")
	)
	(segment
		(start 281.197558 -97.414588)
		(end 281.230324 -97.414588)
		(width 0.0889)
		(layer "In11.Cu")
		(net "M_F_DQS_DP<6>")
	)
	(segment
		(start 303.820322 -124.443998)
		(end 303.820322 -149.308566)
		(width 0.14224)
		(layer "In11.Cu")
		(net "M_F_DQS_DP<6>")
	)
	(segment
		(start 297.172126 -119.527828)
		(end 297.172126 -119.143272)
		(width 0.14224)
		(layer "In11.Cu")
		(net "M_F_DQS_DP<6>")
	)
	(segment
		(start 283.437584 -105.234486)
		(end 283.432758 -105.243122)
		(width 0.0889)
		(layer "In11.Cu")
		(net "M_F_DQS_DP<6>")
	)
	(segment
		(start 297.017186 -119.682768)
		(end 297.172126 -119.527828)
		(width 0.14224)
		(layer "In11.Cu")
		(net "M_F_DQS_DP<6>")
	)
	(segment
		(start 279.151334 -94.822518)
		(end 279.144984 -94.833186)
		(width 0.0889)
		(layer "In11.Cu")
		(net "M_F_DQS_DP<6>")
	)
	(segment
		(start 290.346892 -119.817388)
		(end 294.54221 -119.817388)
		(width 0.14224)
		(layer "In11.Cu")
		(net "M_F_DQS_DP<6>")
	)
	(segment
		(start 302.77816 -151.8666)
		(end 302.86325 -151.8666)
		(width 0.14224)
		(layer "In11.Cu")
		(net "M_F_DQS_DP<6>")
	)
	(segment
		(start 302.859186 -153.0604)
		(end 303.24425 -153.0604)
		(width 0.14224)
		(layer "In11.Cu")
		(net "M_F_DQS_DP<6>")
	)
	(segment
		(start 298.373546 -119.143272)
		(end 298.373546 -119.527828)
		(width 0.14224)
		(layer "In11.Cu")
		(net "M_F_DQS_DP<6>")
	)
	(segment
		(start 283.516324 -105.771188)
		(end 283.516324 -106.209592)
		(width 0.0889)
		(layer "In11.Cu")
		(net "M_F_DQS_DP<6>")
	)
	(segment
		(start 303.49825 -153.753312)
		(end 303.038002 -154.21356)
		(width 0.14224)
		(layer "In11.Cu")
		(net "M_F_DQS_DP<6>")
	)
	(segment
		(start 280.335228 -96.919034)
		(end 280.367994 -96.919034)
		(width 0.0889)
		(layer "In11.Cu")
		(net "M_F_DQS_DP<6>")
	)
	(segment
		(start 303.4284 -149.752558)
		(end 303.038002 -150.142956)
		(width 0.14224)
		(layer "In11.Cu")
		(net "M_F_DQS_DP<6>")
	)
	(segment
		(start 303.47285 -151.003)
		(end 303.21885 -151.257)
		(width 0.14224)
		(layer "In11.Cu")
		(net "M_F_DQS_DP<6>")
	)
	(segment
		(start 302.663352 -151.751792)
		(end 302.77816 -151.8666)
		(width 0.14224)
		(layer "In11.Cu")
		(net "M_F_DQS_DP<6>")
	)
	(segment
		(start 297.484546 -118.830852)
		(end 298.061126 -118.830852)
		(width 0.14224)
		(layer "In11.Cu")
		(net "M_F_DQS_DP<6>")
	)
	(segment
		(start 283.443934 -103.242618)
		(end 283.437584 -103.253286)
		(width 0.0889)
		(layer "In11.Cu")
		(net "M_F_DQS_DP<6>")
	)
	(segment
		(start 303.4284 -149.700488)
		(end 303.4284 -149.752558)
		(width 0.14224)
		(layer "In11.Cu")
		(net "M_F_DQS_DP<6>")
	)
	(segment
		(start 299.059092 -119.682768)
		(end 303.820322 -124.443998)
		(width 0.14224)
		(layer "In11.Cu")
		(net "M_F_DQS_DP<6>")
	)
	(segment
		(start 283.479494 -107.188)
		(end 283.479494 -112.94999)
		(width 0.14224)
		(layer "In11.Cu")
		(net "M_F_DQS_DP<6>")
	)
	(segment
		(start 283.437584 -105.634536)
		(end 283.516324 -105.771188)
		(width 0.0889)
		(layer "In11.Cu")
		(net "M_F_DQS_DP<6>")
	)
	(segment
		(start 295.95064 -119.08663)
		(end 296.546778 -119.682768)
		(width 0.14224)
		(layer "In11.Cu")
		(net "M_F_DQS_DP<6>")
	)
	(segment
		(start 279.145238 -93.25229)
		(end 279.144984 -93.252036)
		(width 0.0889)
		(layer "In11.Cu")
		(net "M_F_DQS_DP<6>")
	)
	(segment
		(start 279.151334 -93.831918)
		(end 279.144984 -93.842586)
		(width 0.0889)
		(layer "In11.Cu")
		(net "M_F_DQS_DP<6>")
	)
	(segment
		(start 302.833786 -151.257)
		(end 302.663352 -151.427434)
		(width 0.14224)
		(layer "In11.Cu")
		(net "M_F_DQS_DP<6>")
	)
	(segment
		(start 298.528486 -119.682768)
		(end 299.059092 -119.682768)
		(width 0.14224)
		(layer "In11.Cu")
		(net "M_F_DQS_DP<6>")
	)
	(segment
		(start 278.976582 -92.351352)
		(end 278.986488 -92.368624)
		(width 0.0889)
		(layer "In11.Cu")
		(net "M_F_DQS_DP<6>")
	)
	(segment
		(start 303.47285 -150.577804)
		(end 303.47285 -151.003)
		(width 0.14224)
		(layer "In11.Cu")
		(net "M_F_DQS_DP<6>")
	)
	(segment
		(start 303.038002 -150.142956)
		(end 303.47285 -150.577804)
		(width 0.14224)
		(layer "In11.Cu")
		(net "M_F_DQS_DP<6>")
	)
	(segment
		(start 279.480518 -96.423988)
		(end 279.513284 -96.423988)
		(width 0.0889)
		(layer "In11.Cu")
		(net "M_F_DQS_DP<6>")
	)
	(segment
		(start 296.546778 -119.682768)
		(end 297.017186 -119.682768)
		(width 0.14224)
		(layer "In11.Cu")
		(net "M_F_DQS_DP<6>")
	)
	(segment
		(start 283.437584 -99.690682)
		(end 283.443934 -99.70135)
		(width 0.0889)
		(layer "In11.Cu")
		(net "M_F_DQS_DP<6>")
	)
	(segment
		(start 283.479494 -107.165902)
		(end 283.479494 -107.188)
		(width 0.0889)
		(layer "In11.Cu")
		(net "M_F_DQS_DP<6>")
	)
	(segment
		(start 303.04105 -152.320752)
		(end 302.86071 -152.501092)
		(width 0.14224)
		(layer "In11.Cu")
		(net "M_F_DQS_DP<6>")
	)
	(segment
		(start 303.49825 -153.3144)
		(end 303.49825 -153.753312)
		(width 0.14224)
		(layer "In11.Cu")
		(net "M_F_DQS_DP<6>")
	)
	(segment
		(start 282.914598 -98.405188)
		(end 282.947364 -98.405188)
		(width 0.0889)
		(layer "In11.Cu")
		(net "M_F_DQS_DP<6>")
	)
	(segment
		(start 295.272968 -119.08663)
		(end 295.95064 -119.08663)
		(width 0.14224)
		(layer "In11.Cu")
		(net "M_F_DQS_DP<6>")
	)
	(segment
		(start 283.443934 -99.280218)
		(end 283.437584 -99.290886)
		(width 0.0889)
		(layer "In11.Cu")
		(net "M_F_DQS_DP<6>")
	)
	(arc
		(start 283.437584 -101.671628)
		(mid 283.440827 -101.677049)
		(end 283.443934 -101.68255)
		(width 0.0889)
		(layer "In11.Cu")
		(net "M_F_DQS_DP<6>")
	)
	(arc
		(start 283.432758 -103.261922)
		(mid 283.384003 -103.458274)
		(end 283.437584 -103.653336)
		(width 0.0889)
		(layer "In11.Cu")
		(net "M_F_DQS_DP<6>")
	)
	(arc
		(start 279.144984 -93.252036)
		(mid 279.224206 -93.541154)
		(end 279.151334 -93.831918)
		(width 0.0889)
		(layer "In11.Cu")
		(net "M_F_DQS_DP<6>")
	)
	(arc
		(start 280.003504 -96.719136)
		(mid 280.143583 -96.861872)
		(end 280.335228 -96.919034)
		(width 0.0889)
		(layer "In11.Cu")
		(net "M_F_DQS_DP<6>")
	)
	(arc
		(start 283.437584 -104.643936)
		(mid 283.516806 -104.933054)
		(end 283.443934 -105.223818)
		(width 0.0889)
		(layer "In11.Cu")
		(net "M_F_DQS_DP<6>")
	)
	(arc
		(start 283.437584 -101.271832)
		(mid 283.384085 -101.47173)
		(end 283.437584 -101.671628)
		(width 0.0889)
		(layer "In11.Cu")
		(net "M_F_DQS_DP<6>")
	)
	(arc
		(start 280.367994 -96.919034)
		(mid 280.653418 -97.002501)
		(end 280.862024 -97.214436)
		(width 0.0889)
		(layer "In11.Cu")
		(net "M_F_DQS_DP<6>")
	)
	(arc
		(start 283.437584 -102.262432)
		(mid 283.383958 -102.462584)
		(end 283.437584 -102.662736)
		(width 0.0889)
		(layer "In11.Cu")
		(net "M_F_DQS_DP<6>")
	)
	(arc
		(start 278.986488 -92.368624)
		(mid 279.02905 -92.496638)
		(end 279.02662 -92.631514)
		(width 0.0889)
		(layer "In11.Cu")
		(net "M_F_DQS_DP<6>")
	)
	(arc
		(start 283.437584 -99.290886)
		(mid 283.384085 -99.490784)
		(end 283.437584 -99.690682)
		(width 0.0889)
		(layer "In11.Cu")
		(net "M_F_DQS_DP<6>")
	)
	(arc
		(start 279.144984 -94.833186)
		(mid 279.091485 -95.033084)
		(end 279.144984 -95.232982)
		(width 0.0889)
		(layer "In11.Cu")
		(net "M_F_DQS_DP<6>")
	)
	(arc
		(start 283.432758 -104.252522)
		(mid 283.384003 -104.448874)
		(end 283.437584 -104.643936)
		(width 0.0889)
		(layer "In11.Cu")
		(net "M_F_DQS_DP<6>")
	)
	(arc
		(start 282.085034 -97.909634)
		(mid 282.370458 -97.993101)
		(end 282.579064 -98.205036)
		(width 0.0889)
		(layer "In11.Cu")
		(net "M_F_DQS_DP<6>")
	)
	(arc
		(start 281.720544 -97.709736)
		(mid 281.860623 -97.852472)
		(end 282.052268 -97.909634)
		(width 0.0889)
		(layer "In11.Cu")
		(net "M_F_DQS_DP<6>")
	)
	(arc
		(start 279.144984 -95.823786)
		(mid 279.142236 -96.219253)
		(end 279.480518 -96.423988)
		(width 0.0889)
		(layer "In11.Cu")
		(net "M_F_DQS_DP<6>")
	)
	(arc
		(start 283.443934 -101.68255)
		(mid 283.516732 -101.973313)
		(end 283.437584 -102.262432)
		(width 0.0889)
		(layer "In11.Cu")
		(net "M_F_DQS_DP<6>")
	)
	(arc
		(start 283.472382 -100.751386)
		(mid 283.515797 -101.015677)
		(end 283.437584 -101.271832)
		(width 0.0889)
		(layer "In11.Cu")
		(net "M_F_DQS_DP<6>")
	)
	(arc
		(start 279.144984 -95.232982)
		(mid 279.224115 -95.528384)
		(end 279.144984 -95.823786)
		(width 0.0889)
		(layer "In11.Cu")
		(net "M_F_DQS_DP<6>")
	)
	(arc
		(start 283.432758 -105.243122)
		(mid 283.384003 -105.439474)
		(end 283.437584 -105.634536)
		(width 0.0889)
		(layer "In11.Cu")
		(net "M_F_DQS_DP<6>")
	)
	(arc
		(start 283.437584 -100.281232)
		(mid 283.384085 -100.48113)
		(end 283.437584 -100.681028)
		(width 0.0889)
		(layer "In11.Cu")
		(net "M_F_DQS_DP<6>")
	)
	(arc
		(start 278.633174 -91.565984)
		(mid 278.783557 -91.96799)
		(end 278.976582 -92.351352)
		(width 0.0889)
		(layer "In11.Cu")
		(net "M_F_DQS_DP<6>")
	)
	(arc
		(start 279.513284 -96.423988)
		(mid 279.796501 -96.508269)
		(end 280.003504 -96.719136)
		(width 0.0889)
		(layer "In11.Cu")
		(net "M_F_DQS_DP<6>")
	)
	(arc
		(start 279.144984 -94.242636)
		(mid 279.224206 -94.531754)
		(end 279.151334 -94.822518)
		(width 0.0889)
		(layer "In11.Cu")
		(net "M_F_DQS_DP<6>")
	)
	(arc
		(start 279.02662 -92.631514)
		(mid 279.033463 -92.951935)
		(end 279.145238 -93.25229)
		(width 0.0889)
		(layer "In11.Cu")
		(net "M_F_DQS_DP<6>")
	)
	(arc
		(start 283.437584 -102.662736)
		(mid 283.516806 -102.951854)
		(end 283.443934 -103.242618)
		(width 0.0889)
		(layer "In11.Cu")
		(net "M_F_DQS_DP<6>")
	)
	(arc
		(start 283.443934 -99.70135)
		(mid 283.516732 -99.992113)
		(end 283.437584 -100.281232)
		(width 0.0889)
		(layer "In11.Cu")
		(net "M_F_DQS_DP<6>")
	)
	(arc
		(start 283.437584 -103.653336)
		(mid 283.516806 -103.942454)
		(end 283.443934 -104.233218)
		(width 0.0889)
		(layer "In11.Cu")
		(net "M_F_DQS_DP<6>")
	)
	(arc
		(start 279.144984 -93.842586)
		(mid 279.09129 -94.042628)
		(end 279.144984 -94.242636)
		(width 0.0889)
		(layer "In11.Cu")
		(net "M_F_DQS_DP<6>")
	)
	(arc
		(start 281.230324 -97.414588)
		(mid 281.513541 -97.498869)
		(end 281.720544 -97.709736)
		(width 0.0889)
		(layer "In11.Cu")
		(net "M_F_DQS_DP<6>")
	)
	(arc
		(start 282.947364 -98.405188)
		(mid 283.439754 -98.704121)
		(end 283.443934 -99.280218)
		(width 0.0889)
		(layer "In11.Cu")
		(net "M_F_DQS_DP<6>")
	)
	(arc
		(start 283.437584 -100.681028)
		(mid 283.45616 -100.715625)
		(end 283.472382 -100.751386)
		(width 0.0889)
		(layer "In11.Cu")
		(net "M_F_DQS_DP<6>")
	)
	(arc
		(start 282.579064 -98.205036)
		(mid 282.720747 -98.34884)
		(end 282.914598 -98.405188)
		(width 0.0889)
		(layer "In11.Cu")
		(net "M_F_DQS_DP<6>")
	)
	(arc
		(start 280.862024 -97.214436)
		(mid 281.003707 -97.35824)
		(end 281.197558 -97.414588)
		(width 0.0889)
		(layer "In11.Cu")
		(net "M_F_DQS_DP<6>")
	)
	(segment
		(start 294.150034 -155.866846)
		(end 294.18788 -155.829)
		(width 0.1651)
		(layer "F.Cu")
		(net "M_F_DQS_DP<5>")
	)
	(segment
		(start 294.18788 -155.829)
		(end 294.18788 -154.4574)
		(width 0.1651)
		(layer "F.Cu")
		(net "M_F_DQS_DP<5>")
	)
	(segment
		(start 294.150288 -156.87294)
		(end 294.150034 -156.87294)
		(width 0.1651)
		(layer "F.Cu")
		(net "M_F_DQS_DP<5>")
	)
	(segment
		(start 294.18788 -154.4574)
		(end 293.94404 -154.21356)
		(width 0.1651)
		(layer "F.Cu")
		(net "M_F_DQS_DP<5>")
	)
	(segment
		(start 280.637234 -95.033084)
		(end 281.208734 -95.033084)
		(width 0.1651)
		(layer "F.Cu")
		(net "M_F_DQS_DP<5>")
	)
	(segment
		(start 294.150034 -156.87294)
		(end 294.150034 -155.866846)
		(width 0.1651)
		(layer "F.Cu")
		(net "M_F_DQS_DP<5>")
	)
	(segment
		(start 293.94404 -154.21356)
		(end 293.688008 -154.21356)
		(width 0.1651)
		(layer "F.Cu")
		(net "M_F_DQS_DP<5>")
	)
	(via
		(at 281.208734 -95.033084)
		(size 0.508)
		(drill 0.254)
		(layers "F.Cu" "B.Cu")
		(net "M_F_DQS_DP<5>")
	)
	(via
		(at 293.688008 -154.21356)
		(size 0.508)
		(drill 0.254)
		(layers "F.Cu" "B.Cu")
		(net "M_F_DQS_DP<5>")
	)
	(via
		(at 293.688008 -150.142956)
		(size 0.508)
		(drill 0.254)
		(layers "F.Cu" "B.Cu")
		(net "M_F_DQS_DP<5>")
	)
	(segment
		(start 293.688008 -150.142956)
		(end 293.930324 -150.142956)
		(width 0.1651)
		(layer "B.Cu")
		(net "M_F_DQS_DP<5>")
	)
	(segment
		(start 294.150034 -148.628354)
		(end 294.150034 -147.478496)
		(width 0.1651)
		(layer "B.Cu")
		(net "M_F_DQS_DP<5>")
	)
	(segment
		(start 293.930324 -150.142956)
		(end 294.18788 -149.8854)
		(width 0.1651)
		(layer "B.Cu")
		(net "M_F_DQS_DP<5>")
	)
	(segment
		(start 294.18788 -149.8854)
		(end 294.18788 -148.6662)
		(width 0.1651)
		(layer "B.Cu")
		(net "M_F_DQS_DP<5>")
	)
	(segment
		(start 294.150034 -147.478496)
		(end 294.150288 -147.478496)
		(width 0.1651)
		(layer "B.Cu")
		(net "M_F_DQS_DP<5>")
	)
	(segment
		(start 294.18788 -148.6662)
		(end 294.150034 -148.628354)
		(width 0.1651)
		(layer "B.Cu")
		(net "M_F_DQS_DP<5>")
	)
	(segment
		(start 292.996874 -122.349768)
		(end 293.357808 -121.988834)
		(width 0.14224)
		(layer "In4.Cu")
		(net "M_F_DQS_DP<5>")
	)
	(segment
		(start 294.470328 -149.360636)
		(end 293.688008 -150.142956)
		(width 0.14224)
		(layer "In4.Cu")
		(net "M_F_DQS_DP<5>")
	)
	(segment
		(start 281.729434 -101.256846)
		(end 281.726894 -101.261164)
		(width 0.0889)
		(layer "In4.Cu")
		(net "M_F_DQS_DP<5>")
	)
	(segment
		(start 281.726894 -101.261164)
		(end 281.713686 -101.284278)
		(width 0.0889)
		(layer "In4.Cu")
		(net "M_F_DQS_DP<5>")
	)
	(segment
		(start 281.720544 -100.281486)
		(end 281.713686 -100.293678)
		(width 0.0889)
		(layer "In4.Cu")
		(net "M_F_DQS_DP<5>")
	)
	(segment
		(start 282.052268 -104.84358)
		(end 282.085034 -104.84358)
		(width 0.0889)
		(layer "In4.Cu")
		(net "M_F_DQS_DP<5>")
	)
	(segment
		(start 293.776908 -123.417838)
		(end 293.776908 -123.647708)
		(width 0.14224)
		(layer "In4.Cu")
		(net "M_F_DQS_DP<5>")
	)
	(segment
		(start 282.607258 -106.178858)
		(end 282.830524 -106.402124)
		(width 0.0889)
		(layer "In4.Cu")
		(net "M_F_DQS_DP<5>")
	)
	(segment
		(start 293.776908 -123.647708)
		(end 294.470328 -124.341128)
		(width 0.14224)
		(layer "In4.Cu")
		(net "M_F_DQS_DP<5>")
	)
	(segment
		(start 282.830524 -106.402124)
		(end 282.830524 -107.41533)
		(width 0.0889)
		(layer "In4.Cu")
		(net "M_F_DQS_DP<5>")
	)
	(segment
		(start 293.848282 -121.988834)
		(end 294.325802 -122.466354)
		(width 0.14224)
		(layer "In4.Cu")
		(net "M_F_DQS_DP<5>")
	)
	(segment
		(start 294.325802 -122.868944)
		(end 293.776908 -123.417838)
		(width 0.14224)
		(layer "In4.Cu")
		(net "M_F_DQS_DP<5>")
	)
	(segment
		(start 294.470328 -124.341128)
		(end 294.470328 -149.360636)
		(width 0.14224)
		(layer "In4.Cu")
		(net "M_F_DQS_DP<5>")
	)
	(segment
		(start 281.726894 -100.270818)
		(end 281.720544 -100.281486)
		(width 0.0889)
		(layer "In4.Cu")
		(net "M_F_DQS_DP<5>")
	)
	(segment
		(start 282.869894 -112.624362)
		(end 292.5953 -122.349768)
		(width 0.14224)
		(layer "In4.Cu")
		(net "M_F_DQS_DP<5>")
	)
	(segment
		(start 282.869894 -107.4547)
		(end 282.869894 -107.476798)
		(width 0.0889)
		(layer "In4.Cu")
		(net "M_F_DQS_DP<5>")
	)
	(segment
		(start 282.830524 -107.41533)
		(end 282.869894 -107.4547)
		(width 0.0889)
		(layer "In4.Cu")
		(net "M_F_DQS_DP<5>")
	)
	(segment
		(start 281.729434 -104.228646)
		(end 281.713686 -104.256078)
		(width 0.0889)
		(layer "In4.Cu")
		(net "M_F_DQS_DP<5>")
	)
	(segment
		(start 293.357808 -121.988834)
		(end 293.848282 -121.988834)
		(width 0.14224)
		(layer "In4.Cu")
		(net "M_F_DQS_DP<5>")
	)
	(segment
		(start 282.572206 -106.11739)
		(end 282.607258 -106.178858)
		(width 0.0889)
		(layer "In4.Cu")
		(net "M_F_DQS_DP<5>")
	)
	(segment
		(start 281.729434 -102.247446)
		(end 281.713686 -102.274878)
		(width 0.0889)
		(layer "In4.Cu")
		(net "M_F_DQS_DP<5>")
	)
	(segment
		(start 282.869894 -107.476798)
		(end 282.869894 -112.624362)
		(width 0.14224)
		(layer "In4.Cu")
		(net "M_F_DQS_DP<5>")
	)
	(segment
		(start 292.5953 -122.349768)
		(end 292.996874 -122.349768)
		(width 0.14224)
		(layer "In4.Cu")
		(net "M_F_DQS_DP<5>")
	)
	(segment
		(start 294.325802 -122.466354)
		(end 294.325802 -122.868944)
		(width 0.14224)
		(layer "In4.Cu")
		(net "M_F_DQS_DP<5>")
	)
	(arc
		(start 281.720544 -102.662482)
		(mid 281.799733 -102.949097)
		(end 281.729434 -103.238046)
		(width 0.0889)
		(layer "In4.Cu")
		(net "M_F_DQS_DP<5>")
	)
	(arc
		(start 281.555444 -95.824294)
		(mid 281.601157 -95.946031)
		(end 281.605482 -96.076008)
		(width 0.0889)
		(layer "In4.Cu")
		(net "M_F_DQS_DP<5>")
	)
	(arc
		(start 281.713686 -100.293678)
		(mid 281.66701 -100.488379)
		(end 281.720544 -100.681282)
		(width 0.0889)
		(layer "In4.Cu")
		(net "M_F_DQS_DP<5>")
	)
	(arc
		(start 281.720544 -96.71939)
		(mid 281.799675 -97.014792)
		(end 281.720544 -97.310194)
		(width 0.0889)
		(layer "In4.Cu")
		(net "M_F_DQS_DP<5>")
	)
	(arc
		(start 281.720544 -100.681282)
		(mid 281.799733 -100.967897)
		(end 281.729434 -101.256846)
		(width 0.0889)
		(layer "In4.Cu")
		(net "M_F_DQS_DP<5>")
	)
	(arc
		(start 281.729434 -103.238046)
		(mid 281.72175 -103.251871)
		(end 281.713686 -103.265478)
		(width 0.0889)
		(layer "In4.Cu")
		(net "M_F_DQS_DP<5>")
	)
	(arc
		(start 281.713686 -101.284278)
		(mid 281.66701 -101.478979)
		(end 281.720544 -101.671882)
		(width 0.0889)
		(layer "In4.Cu")
		(net "M_F_DQS_DP<5>")
	)
	(arc
		(start 281.720544 -97.70999)
		(mid 281.799675 -98.005392)
		(end 281.720544 -98.300794)
		(width 0.0889)
		(layer "In4.Cu")
		(net "M_F_DQS_DP<5>")
	)
	(arc
		(start 281.720544 -98.70059)
		(mid 281.799675 -98.995992)
		(end 281.720544 -99.291394)
		(width 0.0889)
		(layer "In4.Cu")
		(net "M_F_DQS_DP<5>")
	)
	(arc
		(start 282.085034 -104.84358)
		(mid 282.583555 -105.146464)
		(end 282.579064 -105.729786)
		(width 0.0889)
		(layer "In4.Cu")
		(net "M_F_DQS_DP<5>")
	)
	(arc
		(start 281.720544 -101.671882)
		(mid 281.799733 -101.958497)
		(end 281.729434 -102.247446)
		(width 0.0889)
		(layer "In4.Cu")
		(net "M_F_DQS_DP<5>")
	)
	(arc
		(start 281.720544 -99.291394)
		(mid 281.668957 -99.454293)
		(end 281.68981 -99.62388)
		(width 0.0889)
		(layer "In4.Cu")
		(net "M_F_DQS_DP<5>")
	)
	(arc
		(start 281.713686 -104.256078)
		(mid 281.720549 -104.643391)
		(end 282.052268 -104.84358)
		(width 0.0889)
		(layer "In4.Cu")
		(net "M_F_DQS_DP<5>")
	)
	(arc
		(start 281.720544 -97.310194)
		(mid 281.667045 -97.510092)
		(end 281.720544 -97.70999)
		(width 0.0889)
		(layer "In4.Cu")
		(net "M_F_DQS_DP<5>")
	)
	(arc
		(start 281.68981 -99.62388)
		(mid 281.703606 -99.658128)
		(end 281.720544 -99.690936)
		(width 0.0889)
		(layer "In4.Cu")
		(net "M_F_DQS_DP<5>")
	)
	(arc
		(start 281.720544 -98.300794)
		(mid 281.667045 -98.500692)
		(end 281.720544 -98.70059)
		(width 0.0889)
		(layer "In4.Cu")
		(net "M_F_DQS_DP<5>")
	)
	(arc
		(start 281.720544 -103.653082)
		(mid 281.799733 -103.939697)
		(end 281.729434 -104.228646)
		(width 0.0889)
		(layer "In4.Cu")
		(net "M_F_DQS_DP<5>")
	)
	(arc
		(start 281.713686 -103.265478)
		(mid 281.66701 -103.460179)
		(end 281.720544 -103.653082)
		(width 0.0889)
		(layer "In4.Cu")
		(net "M_F_DQS_DP<5>")
	)
	(arc
		(start 282.579064 -105.729786)
		(mid 282.525626 -105.922691)
		(end 282.572206 -106.11739)
		(width 0.0889)
		(layer "In4.Cu")
		(net "M_F_DQS_DP<5>")
	)
	(arc
		(start 281.713686 -102.274878)
		(mid 281.66701 -102.469579)
		(end 281.720544 -102.662482)
		(width 0.0889)
		(layer "In4.Cu")
		(net "M_F_DQS_DP<5>")
	)
	(arc
		(start 281.208734 -95.033084)
		(mid 281.360418 -95.438185)
		(end 281.555444 -95.824294)
		(width 0.0889)
		(layer "In4.Cu")
		(net "M_F_DQS_DP<5>")
	)
	(arc
		(start 281.720544 -99.690936)
		(mid 281.799766 -99.980054)
		(end 281.726894 -100.270818)
		(width 0.0889)
		(layer "In4.Cu")
		(net "M_F_DQS_DP<5>")
	)
	(arc
		(start 281.605482 -96.076008)
		(mid 281.61318 -96.406609)
		(end 281.720544 -96.71939)
		(width 0.0889)
		(layer "In4.Cu")
		(net "M_F_DQS_DP<5>")
	)
	(segment
		(start 293.691056 -152.320752)
		(end 293.510716 -152.501092)
		(width 0.14224)
		(layer "In11.Cu")
		(net "M_F_DQS_DP<5>")
	)
	(segment
		(start 293.691056 -152.0444)
		(end 293.691056 -152.320752)
		(width 0.14224)
		(layer "In11.Cu")
		(net "M_F_DQS_DP<5>")
	)
	(segment
		(start 293.510716 -152.501092)
		(end 293.450518 -152.501092)
		(width 0.14224)
		(layer "In11.Cu")
		(net "M_F_DQS_DP<5>")
	)
	(segment
		(start 293.483792 -151.257)
		(end 293.313358 -151.427434)
		(width 0.14224)
		(layer "In11.Cu")
		(net "M_F_DQS_DP<5>")
	)
	(segment
		(start 293.509192 -153.0604)
		(end 293.894256 -153.0604)
		(width 0.14224)
		(layer "In11.Cu")
		(net "M_F_DQS_DP<5>")
	)
	(segment
		(start 293.513256 -151.8666)
		(end 293.691056 -152.0444)
		(width 0.14224)
		(layer "In11.Cu")
		(net "M_F_DQS_DP<5>")
	)
	(segment
		(start 293.450518 -152.501092)
		(end 293.313358 -152.638252)
		(width 0.14224)
		(layer "In11.Cu")
		(net "M_F_DQS_DP<5>")
	)
	(segment
		(start 294.148256 -153.3144)
		(end 294.148256 -153.753312)
		(width 0.14224)
		(layer "In11.Cu")
		(net "M_F_DQS_DP<5>")
	)
	(segment
		(start 293.868856 -151.257)
		(end 293.483792 -151.257)
		(width 0.14224)
		(layer "In11.Cu")
		(net "M_F_DQS_DP<5>")
	)
	(segment
		(start 294.148256 -153.753312)
		(end 293.688008 -154.21356)
		(width 0.14224)
		(layer "In11.Cu")
		(net "M_F_DQS_DP<5>")
	)
	(segment
		(start 294.122856 -150.577804)
		(end 294.122856 -151.003)
		(width 0.14224)
		(layer "In11.Cu")
		(net "M_F_DQS_DP<5>")
	)
	(segment
		(start 293.428166 -151.8666)
		(end 293.513256 -151.8666)
		(width 0.14224)
		(layer "In11.Cu")
		(net "M_F_DQS_DP<5>")
	)
	(segment
		(start 293.894256 -153.0604)
		(end 294.148256 -153.3144)
		(width 0.14224)
		(layer "In11.Cu")
		(net "M_F_DQS_DP<5>")
	)
	(segment
		(start 293.313358 -151.427434)
		(end 293.313358 -151.751792)
		(width 0.14224)
		(layer "In11.Cu")
		(net "M_F_DQS_DP<5>")
	)
	(segment
		(start 293.313358 -152.864566)
		(end 293.509192 -153.0604)
		(width 0.14224)
		(layer "In11.Cu")
		(net "M_F_DQS_DP<5>")
	)
	(segment
		(start 294.122856 -151.003)
		(end 293.868856 -151.257)
		(width 0.14224)
		(layer "In11.Cu")
		(net "M_F_DQS_DP<5>")
	)
	(segment
		(start 293.313358 -152.638252)
		(end 293.313358 -152.864566)
		(width 0.14224)
		(layer "In11.Cu")
		(net "M_F_DQS_DP<5>")
	)
	(segment
		(start 293.688008 -150.142956)
		(end 294.122856 -150.577804)
		(width 0.14224)
		(layer "In11.Cu")
		(net "M_F_DQS_DP<5>")
	)
	(segment
		(start 293.313358 -151.751792)
		(end 293.428166 -151.8666)
		(width 0.14224)
		(layer "In11.Cu")
		(net "M_F_DQS_DP<5>")
	)
	(segment
		(start 284.799786 -156.87294)
		(end 284.799786 -155.866846)
		(width 0.1651)
		(layer "F.Cu")
		(net "M_F_DQS_DP<4>")
	)
	(segment
		(start 284.799786 -155.866846)
		(end 284.837632 -155.829)
		(width 0.1651)
		(layer "F.Cu")
		(net "M_F_DQS_DP<4>")
	)
	(segment
		(start 273.769328 -95.033084)
		(end 274.340828 -95.033084)
		(width 0.1651)
		(layer "F.Cu")
		(net "M_F_DQS_DP<4>")
	)
	(segment
		(start 284.593792 -154.21356)
		(end 284.33776 -154.21356)
		(width 0.1651)
		(layer "F.Cu")
		(net "M_F_DQS_DP<4>")
	)
	(segment
		(start 284.837632 -154.4574)
		(end 284.593792 -154.21356)
		(width 0.1651)
		(layer "F.Cu")
		(net "M_F_DQS_DP<4>")
	)
	(segment
		(start 284.837632 -155.829)
		(end 284.837632 -154.4574)
		(width 0.1651)
		(layer "F.Cu")
		(net "M_F_DQS_DP<4>")
	)
	(segment
		(start 284.800294 -156.87294)
		(end 284.799786 -156.87294)
		(width 0.1651)
		(layer "F.Cu")
		(net "M_F_DQS_DP<4>")
	)
	(via
		(at 284.33776 -154.21356)
		(size 0.508)
		(drill 0.254)
		(layers "F.Cu" "B.Cu")
		(net "M_F_DQS_DP<4>")
	)
	(via
		(at 274.340828 -95.033084)
		(size 0.508)
		(drill 0.254)
		(layers "F.Cu" "B.Cu")
		(net "M_F_DQS_DP<4>")
	)
	(via
		(at 284.33776 -150.142956)
		(size 0.508)
		(drill 0.254)
		(layers "F.Cu" "B.Cu")
		(net "M_F_DQS_DP<4>")
	)
	(segment
		(start 284.837632 -148.6662)
		(end 284.799786 -148.628354)
		(width 0.1651)
		(layer "B.Cu")
		(net "M_F_DQS_DP<4>")
	)
	(segment
		(start 284.33776 -150.142956)
		(end 284.580076 -150.142956)
		(width 0.1651)
		(layer "B.Cu")
		(net "M_F_DQS_DP<4>")
	)
	(segment
		(start 284.580076 -150.142956)
		(end 284.837632 -149.8854)
		(width 0.1651)
		(layer "B.Cu")
		(net "M_F_DQS_DP<4>")
	)
	(segment
		(start 284.799786 -147.478496)
		(end 284.800294 -147.478496)
		(width 0.1651)
		(layer "B.Cu")
		(net "M_F_DQS_DP<4>")
	)
	(segment
		(start 284.799786 -148.628354)
		(end 284.799786 -147.478496)
		(width 0.1651)
		(layer "B.Cu")
		(net "M_F_DQS_DP<4>")
	)
	(segment
		(start 284.837632 -149.8854)
		(end 284.837632 -148.6662)
		(width 0.1651)
		(layer "B.Cu")
		(net "M_F_DQS_DP<4>")
	)
	(segment
		(start 284.160722 -152.501092)
		(end 284.100524 -152.501092)
		(width 0.14224)
		(layer "In11.Cu")
		(net "M_F_DQS_DP<4>")
	)
	(segment
		(start 284.772862 -150.578058)
		(end 284.772862 -151.003)
		(width 0.14224)
		(layer "In11.Cu")
		(net "M_F_DQS_DP<4>")
	)
	(segment
		(start 275.78812 -100.745798)
		(end 275.78812 -104.732328)
		(width 0.0889)
		(layer "In11.Cu")
		(net "M_F_DQS_DP<4>")
	)
	(segment
		(start 282.866084 -123.937014)
		(end 283.117036 -124.187966)
		(width 0.14224)
		(layer "In11.Cu")
		(net "M_F_DQS_DP<4>")
	)
	(segment
		(start 282.299918 -122.595386)
		(end 282.742386 -122.595386)
		(width 0.14224)
		(layer "In11.Cu")
		(net "M_F_DQS_DP<4>")
	)
	(segment
		(start 283.619194 -123.914662)
		(end 284.061662 -123.914662)
		(width 0.14224)
		(layer "In11.Cu")
		(net "M_F_DQS_DP<4>")
	)
	(segment
		(start 284.133798 -151.257)
		(end 283.963364 -151.427434)
		(width 0.14224)
		(layer "In11.Cu")
		(net "M_F_DQS_DP<4>")
	)
	(segment
		(start 273.989292 -98.1964)
		(end 273.994118 -98.205036)
		(width 0.0889)
		(layer "In11.Cu")
		(net "M_F_DQS_DP<4>")
	)
	(segment
		(start 284.74797 -129.12217)
		(end 285.120334 -129.494534)
		(width 0.14224)
		(layer "In11.Cu")
		(net "M_F_DQS_DP<4>")
	)
	(segment
		(start 275.78812 -104.732328)
		(end 275.82749 -104.771698)
		(width 0.0889)
		(layer "In11.Cu")
		(net "M_F_DQS_DP<4>")
	)
	(segment
		(start 275.82749 -104.771698)
		(end 275.82749 -104.793796)
		(width 0.0889)
		(layer "In11.Cu")
		(net "M_F_DQS_DP<4>")
	)
	(segment
		(start 283.963364 -151.751792)
		(end 284.078172 -151.8666)
		(width 0.14224)
		(layer "In11.Cu")
		(net "M_F_DQS_DP<4>")
	)
	(segment
		(start 284.341062 -152.0444)
		(end 284.341062 -152.320752)
		(width 0.14224)
		(layer "In11.Cu")
		(net "M_F_DQS_DP<4>")
	)
	(segment
		(start 284.078172 -151.8666)
		(end 284.163262 -151.8666)
		(width 0.14224)
		(layer "In11.Cu")
		(net "M_F_DQS_DP<4>")
	)
	(segment
		(start 275.015706 -99.973384)
		(end 275.78812 -100.745798)
		(width 0.0889)
		(layer "In11.Cu")
		(net "M_F_DQS_DP<4>")
	)
	(segment
		(start 282.044394 -122.85091)
		(end 282.299918 -122.595386)
		(width 0.14224)
		(layer "In11.Cu")
		(net "M_F_DQS_DP<4>")
	)
	(segment
		(start 283.963364 -151.427434)
		(end 283.963364 -151.751792)
		(width 0.14224)
		(layer "In11.Cu")
		(net "M_F_DQS_DP<4>")
	)
	(segment
		(start 273.989292 -96.2152)
		(end 273.994118 -96.223836)
		(width 0.0889)
		(layer "In11.Cu")
		(net "M_F_DQS_DP<4>")
	)
	(segment
		(start 284.518862 -151.257)
		(end 284.133798 -151.257)
		(width 0.14224)
		(layer "In11.Cu")
		(net "M_F_DQS_DP<4>")
	)
	(segment
		(start 275.82749 -104.793796)
		(end 275.82749 -115.68049)
		(width 0.14224)
		(layer "In11.Cu")
		(net "M_F_DQS_DP<4>")
	)
	(segment
		(start 284.341062 -152.320752)
		(end 284.160722 -152.501092)
		(width 0.14224)
		(layer "In11.Cu")
		(net "M_F_DQS_DP<4>")
	)
	(segment
		(start 281.575002 -122.599958)
		(end 281.825954 -122.85091)
		(width 0.14224)
		(layer "In11.Cu")
		(net "M_F_DQS_DP<4>")
	)
	(segment
		(start 285.120334 -129.494534)
		(end 285.120334 -149.360636)
		(width 0.14224)
		(layer "In11.Cu")
		(net "M_F_DQS_DP<4>")
	)
	(segment
		(start 283.149802 -123.002802)
		(end 283.149802 -123.44527)
		(width 0.14224)
		(layer "In11.Cu")
		(net "M_F_DQS_DP<4>")
	)
	(segment
		(start 283.149802 -123.44527)
		(end 282.866084 -123.728988)
		(width 0.14224)
		(layer "In11.Cu")
		(net "M_F_DQS_DP<4>")
	)
	(segment
		(start 284.159198 -153.0604)
		(end 284.544262 -153.0604)
		(width 0.14224)
		(layer "In11.Cu")
		(net "M_F_DQS_DP<4>")
	)
	(segment
		(start 284.544262 -153.0604)
		(end 284.798262 -153.3144)
		(width 0.14224)
		(layer "In11.Cu")
		(net "M_F_DQS_DP<4>")
	)
	(segment
		(start 284.74797 -124.60097)
		(end 284.74797 -129.12217)
		(width 0.14224)
		(layer "In11.Cu")
		(net "M_F_DQS_DP<4>")
	)
	(segment
		(start 284.338014 -154.21356)
		(end 284.33776 -154.21356)
		(width 0.14224)
		(layer "In11.Cu")
		(net "M_F_DQS_DP<4>")
	)
	(segment
		(start 281.830526 -122.125994)
		(end 281.575002 -122.381518)
		(width 0.14224)
		(layer "In11.Cu")
		(net "M_F_DQS_DP<4>")
	)
	(segment
		(start 282.866084 -123.728988)
		(end 282.866084 -123.937014)
		(width 0.14224)
		(layer "In11.Cu")
		(net "M_F_DQS_DP<4>")
	)
	(segment
		(start 284.798262 -153.3144)
		(end 284.798262 -153.753312)
		(width 0.14224)
		(layer "In11.Cu")
		(net "M_F_DQS_DP<4>")
	)
	(segment
		(start 275.82749 -115.68049)
		(end 281.830526 -121.683526)
		(width 0.14224)
		(layer "In11.Cu")
		(net "M_F_DQS_DP<4>")
	)
	(segment
		(start 281.575002 -122.381518)
		(end 281.575002 -122.599958)
		(width 0.14224)
		(layer "In11.Cu")
		(net "M_F_DQS_DP<4>")
	)
	(segment
		(start 281.825954 -122.85091)
		(end 282.044394 -122.85091)
		(width 0.14224)
		(layer "In11.Cu")
		(net "M_F_DQS_DP<4>")
	)
	(segment
		(start 283.963364 -152.638252)
		(end 283.963364 -152.864566)
		(width 0.14224)
		(layer "In11.Cu")
		(net "M_F_DQS_DP<4>")
	)
	(segment
		(start 273.989292 -97.2058)
		(end 273.994118 -97.214436)
		(width 0.0889)
		(layer "In11.Cu")
		(net "M_F_DQS_DP<4>")
	)
	(segment
		(start 274.340828 -94.69501)
		(end 274.282916 -94.637098)
		(width 0.0889)
		(layer "In11.Cu")
		(net "M_F_DQS_DP<4>")
	)
	(segment
		(start 284.33776 -150.142956)
		(end 284.772862 -150.578058)
		(width 0.14224)
		(layer "In11.Cu")
		(net "M_F_DQS_DP<4>")
	)
	(segment
		(start 273.994118 -98.205036)
		(end 274.000468 -98.215704)
		(width 0.0889)
		(layer "In11.Cu")
		(net "M_F_DQS_DP<4>")
	)
	(segment
		(start 274.340828 -95.033084)
		(end 274.340828 -94.69501)
		(width 0.0889)
		(layer "In11.Cu")
		(net "M_F_DQS_DP<4>")
	)
	(segment
		(start 284.798262 -153.753312)
		(end 284.338014 -154.21356)
		(width 0.14224)
		(layer "In11.Cu")
		(net "M_F_DQS_DP<4>")
	)
	(segment
		(start 281.830526 -121.683526)
		(end 281.830526 -122.125994)
		(width 0.14224)
		(layer "In11.Cu")
		(net "M_F_DQS_DP<4>")
	)
	(segment
		(start 273.994118 -97.214436)
		(end 274.000468 -97.225104)
		(width 0.0889)
		(layer "In11.Cu")
		(net "M_F_DQS_DP<4>")
	)
	(segment
		(start 284.600904 -151.174704)
		(end 284.518862 -151.257)
		(width 0.14224)
		(layer "In11.Cu")
		(net "M_F_DQS_DP<4>")
	)
	(segment
		(start 284.772862 -151.003)
		(end 284.600904 -151.174704)
		(width 0.14224)
		(layer "In11.Cu")
		(net "M_F_DQS_DP<4>")
	)
	(segment
		(start 284.100524 -152.501092)
		(end 283.963364 -152.638252)
		(width 0.14224)
		(layer "In11.Cu")
		(net "M_F_DQS_DP<4>")
	)
	(segment
		(start 284.338014 -150.142956)
		(end 284.33776 -150.142956)
		(width 0.14224)
		(layer "In11.Cu")
		(net "M_F_DQS_DP<4>")
	)
	(segment
		(start 282.742386 -122.595386)
		(end 283.149802 -123.002802)
		(width 0.14224)
		(layer "In11.Cu")
		(net "M_F_DQS_DP<4>")
	)
	(segment
		(start 283.117036 -124.187966)
		(end 283.34589 -124.187966)
		(width 0.14224)
		(layer "In11.Cu")
		(net "M_F_DQS_DP<4>")
	)
	(segment
		(start 273.994118 -96.223836)
		(end 274.000468 -96.234504)
		(width 0.0889)
		(layer "In11.Cu")
		(net "M_F_DQS_DP<4>")
	)
	(segment
		(start 284.163262 -151.8666)
		(end 284.341062 -152.0444)
		(width 0.14224)
		(layer "In11.Cu")
		(net "M_F_DQS_DP<4>")
	)
	(segment
		(start 274.329652 -99.395788)
		(end 274.362418 -99.395788)
		(width 0.0889)
		(layer "In11.Cu")
		(net "M_F_DQS_DP<4>")
	)
	(segment
		(start 283.963364 -152.864566)
		(end 284.159198 -153.0604)
		(width 0.14224)
		(layer "In11.Cu")
		(net "M_F_DQS_DP<4>")
	)
	(segment
		(start 283.34589 -124.187966)
		(end 283.619194 -123.914662)
		(width 0.14224)
		(layer "In11.Cu")
		(net "M_F_DQS_DP<4>")
	)
	(segment
		(start 285.120334 -149.360636)
		(end 284.338014 -150.142956)
		(width 0.14224)
		(layer "In11.Cu")
		(net "M_F_DQS_DP<4>")
	)
	(segment
		(start 274.852638 -99.690936)
		(end 275.015706 -99.973384)
		(width 0.0889)
		(layer "In11.Cu")
		(net "M_F_DQS_DP<4>")
	)
	(segment
		(start 284.061662 -123.914662)
		(end 284.74797 -124.60097)
		(width 0.14224)
		(layer "In11.Cu")
		(net "M_F_DQS_DP<4>")
	)
	(arc
		(start 274.000468 -97.225104)
		(mid 274.073266 -97.515867)
		(end 273.994118 -97.804986)
		(width 0.0889)
		(layer "In11.Cu")
		(net "M_F_DQS_DP<4>")
	)
	(arc
		(start 274.000468 -98.215704)
		(mid 274.073266 -98.506467)
		(end 273.994118 -98.795586)
		(width 0.0889)
		(layer "In11.Cu")
		(net "M_F_DQS_DP<4>")
	)
	(arc
		(start 274.362418 -99.395788)
		(mid 274.645635 -99.480069)
		(end 274.852638 -99.690936)
		(width 0.0889)
		(layer "In11.Cu")
		(net "M_F_DQS_DP<4>")
	)
	(arc
		(start 274.097242 -94.715584)
		(mid 273.948368 -94.954881)
		(end 273.994118 -95.232982)
		(width 0.0889)
		(layer "In11.Cu")
		(net "M_F_DQS_DP<4>")
	)
	(arc
		(start 273.994118 -98.795586)
		(mid 273.99137 -99.191053)
		(end 274.329652 -99.395788)
		(width 0.0889)
		(layer "In11.Cu")
		(net "M_F_DQS_DP<4>")
	)
	(arc
		(start 274.282916 -94.637098)
		(mid 274.18505 -94.664449)
		(end 274.097242 -94.715584)
		(width 0.0889)
		(layer "In11.Cu")
		(net "M_F_DQS_DP<4>")
	)
	(arc
		(start 274.000468 -96.234504)
		(mid 274.073266 -96.525267)
		(end 273.994118 -96.814386)
		(width 0.0889)
		(layer "In11.Cu")
		(net "M_F_DQS_DP<4>")
	)
	(arc
		(start 273.994118 -97.804986)
		(mid 273.940648 -98.000049)
		(end 273.989292 -98.1964)
		(width 0.0889)
		(layer "In11.Cu")
		(net "M_F_DQS_DP<4>")
	)
	(arc
		(start 273.994118 -96.814386)
		(mid 273.940648 -97.009449)
		(end 273.989292 -97.2058)
		(width 0.0889)
		(layer "In11.Cu")
		(net "M_F_DQS_DP<4>")
	)
	(arc
		(start 273.994118 -95.823786)
		(mid 273.940648 -96.018849)
		(end 273.989292 -96.2152)
		(width 0.0889)
		(layer "In11.Cu")
		(net "M_F_DQS_DP<4>")
	)
	(arc
		(start 273.994118 -95.232982)
		(mid 274.073249 -95.528384)
		(end 273.994118 -95.823786)
		(width 0.0889)
		(layer "In11.Cu")
		(net "M_F_DQS_DP<4>")
	)
	(segment
		(start 250.778264 -86.794086)
		(end 250.206764 -86.794086)
		(width 0.1651)
		(layer "F.Cu")
		(net "M_F_DQS_DP<3>")
	)
	(segment
		(start 229.587806 -154.4574)
		(end 229.343966 -154.21356)
		(width 0.1651)
		(layer "F.Cu")
		(net "M_F_DQS_DP<3>")
	)
	(segment
		(start 229.550468 -156.87294)
		(end 229.54996 -156.87294)
		(width 0.1651)
		(layer "F.Cu")
		(net "M_F_DQS_DP<3>")
	)
	(segment
		(start 229.54996 -156.87294)
		(end 229.54996 -155.866846)
		(width 0.1651)
		(layer "F.Cu")
		(net "M_F_DQS_DP<3>")
	)
	(segment
		(start 229.343966 -154.21356)
		(end 229.087934 -154.21356)
		(width 0.1651)
		(layer "F.Cu")
		(net "M_F_DQS_DP<3>")
	)
	(segment
		(start 229.54996 -155.866846)
		(end 229.587806 -155.829)
		(width 0.1651)
		(layer "F.Cu")
		(net "M_F_DQS_DP<3>")
	)
	(segment
		(start 229.587806 -155.829)
		(end 229.587806 -154.4574)
		(width 0.1651)
		(layer "F.Cu")
		(net "M_F_DQS_DP<3>")
	)
	(via
		(at 250.206764 -86.794086)
		(size 0.508)
		(drill 0.254)
		(layers "F.Cu" "B.Cu")
		(net "M_F_DQS_DP<3>")
	)
	(via
		(at 229.087934 -150.142956)
		(size 0.508)
		(drill 0.254)
		(layers "F.Cu" "B.Cu")
		(net "M_F_DQS_DP<3>")
	)
	(via
		(at 229.087934 -154.21356)
		(size 0.508)
		(drill 0.254)
		(layers "F.Cu" "B.Cu")
		(net "M_F_DQS_DP<3>")
	)
	(segment
		(start 229.54996 -148.628354)
		(end 229.587806 -148.6662)
		(width 0.1651)
		(layer "B.Cu")
		(net "M_F_DQS_DP<3>")
	)
	(segment
		(start 229.587806 -148.6662)
		(end 229.587806 -149.8854)
		(width 0.1651)
		(layer "B.Cu")
		(net "M_F_DQS_DP<3>")
	)
	(segment
		(start 229.54996 -147.478496)
		(end 229.54996 -148.628354)
		(width 0.1651)
		(layer "B.Cu")
		(net "M_F_DQS_DP<3>")
	)
	(segment
		(start 229.33025 -150.142956)
		(end 229.087934 -150.142956)
		(width 0.1651)
		(layer "B.Cu")
		(net "M_F_DQS_DP<3>")
	)
	(segment
		(start 229.587806 -149.8854)
		(end 229.33025 -150.142956)
		(width 0.1651)
		(layer "B.Cu")
		(net "M_F_DQS_DP<3>")
	)
	(segment
		(start 229.550468 -147.478496)
		(end 229.54996 -147.478496)
		(width 0.1651)
		(layer "B.Cu")
		(net "M_F_DQS_DP<3>")
	)
	(segment
		(start 250.713748 -90.452702)
		(end 250.718574 -90.461338)
		(width 0.0889)
		(layer "In11.Cu")
		(net "M_F_DQS_DP<3>")
	)
	(segment
		(start 250.713748 -92.433902)
		(end 250.718574 -92.442538)
		(width 0.0889)
		(layer "In11.Cu")
		(net "M_F_DQS_DP<3>")
	)
	(segment
		(start 239.13719 -119.264684)
		(end 238.673894 -119.72798)
		(width 0.14224)
		(layer "In11.Cu")
		(net "M_F_DQS_DP<3>")
	)
	(segment
		(start 250.713748 -91.443302)
		(end 250.718574 -91.451938)
		(width 0.0889)
		(layer "In11.Cu")
		(net "M_F_DQS_DP<3>")
	)
	(segment
		(start 246.390922 -103.67264)
		(end 246.390922 -105.417366)
		(width 0.14224)
		(layer "In11.Cu")
		(net "M_F_DQS_DP<3>")
	)
	(segment
		(start 249.86615 -96.48952)
		(end 249.865134 -96.491044)
		(width 0.0889)
		(layer "In11.Cu")
		(net "M_F_DQS_DP<3>")
	)
	(segment
		(start 248.807224 -98.257614)
		(end 246.064024 -101.000814)
		(width 0.0889)
		(layer "In11.Cu")
		(net "M_F_DQS_DP<3>")
	)
	(segment
		(start 228.913182 -151.8666)
		(end 229.090982 -152.0444)
		(width 0.14224)
		(layer "In11.Cu")
		(net "M_F_DQS_DP<3>")
	)
	(segment
		(start 229.522782 -151.003)
		(end 229.268782 -151.257)
		(width 0.14224)
		(layer "In11.Cu")
		(net "M_F_DQS_DP<3>")
	)
	(segment
		(start 250.718574 -91.451938)
		(end 250.724924 -91.462606)
		(width 0.0889)
		(layer "In11.Cu")
		(net "M_F_DQS_DP<3>")
	)
	(segment
		(start 229.870254 -124.136912)
		(end 229.870254 -149.36089)
		(width 0.14224)
		(layer "In11.Cu")
		(net "M_F_DQS_DP<3>")
	)
	(segment
		(start 246.064024 -102.372414)
		(end 246.351552 -102.659942)
		(width 0.0889)
		(layer "In11.Cu")
		(net "M_F_DQS_DP<3>")
	)
	(segment
		(start 229.087934 -150.142956)
		(end 229.522782 -150.577804)
		(width 0.14224)
		(layer "In11.Cu")
		(net "M_F_DQS_DP<3>")
	)
	(segment
		(start 239.13719 -118.728236)
		(end 239.13719 -119.264684)
		(width 0.14224)
		(layer "In11.Cu")
		(net "M_F_DQS_DP<3>")
	)
	(segment
		(start 229.268782 -151.257)
		(end 228.883718 -151.257)
		(width 0.14224)
		(layer "In11.Cu")
		(net "M_F_DQS_DP<3>")
	)
	(segment
		(start 250.713748 -89.462102)
		(end 250.718574 -89.470738)
		(width 0.0889)
		(layer "In11.Cu")
		(net "M_F_DQS_DP<3>")
	)
	(segment
		(start 239.612424 -117.968522)
		(end 239.300512 -117.968522)
		(width 0.14224)
		(layer "In11.Cu")
		(net "M_F_DQS_DP<3>")
	)
	(segment
		(start 229.548182 -153.3144)
		(end 229.548182 -153.753312)
		(width 0.14224)
		(layer "In11.Cu")
		(net "M_F_DQS_DP<3>")
	)
	(segment
		(start 228.713284 -152.864566)
		(end 228.909118 -153.0604)
		(width 0.14224)
		(layer "In11.Cu")
		(net "M_F_DQS_DP<3>")
	)
	(segment
		(start 250.219718 -93.32849)
		(end 250.195588 -93.32849)
		(width 0.0889)
		(layer "In11.Cu")
		(net "M_F_DQS_DP<3>")
	)
	(segment
		(start 249.860054 -93.928438)
		(end 249.866404 -93.939106)
		(width 0.0889)
		(layer "In11.Cu")
		(net "M_F_DQS_DP<3>")
	)
	(segment
		(start 246.351552 -103.611172)
		(end 246.390922 -103.650542)
		(width 0.0889)
		(layer "In11.Cu")
		(net "M_F_DQS_DP<3>")
	)
	(segment
		(start 239.754664 -118.110762)
		(end 239.612424 -117.968522)
		(width 0.14224)
		(layer "In11.Cu")
		(net "M_F_DQS_DP<3>")
	)
	(segment
		(start 246.064024 -101.000814)
		(end 246.064024 -102.372414)
		(width 0.0889)
		(layer "In11.Cu")
		(net "M_F_DQS_DP<3>")
	)
	(segment
		(start 229.294182 -153.0604)
		(end 229.548182 -153.3144)
		(width 0.14224)
		(layer "In11.Cu")
		(net "M_F_DQS_DP<3>")
	)
	(segment
		(start 238.99495 -118.274084)
		(end 238.99495 -118.585996)
		(width 0.14224)
		(layer "In11.Cu")
		(net "M_F_DQS_DP<3>")
	)
	(segment
		(start 250.718574 -92.442538)
		(end 250.724924 -92.453206)
		(width 0.0889)
		(layer "In11.Cu")
		(net "M_F_DQS_DP<3>")
	)
	(segment
		(start 240.291112 -118.110762)
		(end 239.754664 -118.110762)
		(width 0.14224)
		(layer "In11.Cu")
		(net "M_F_DQS_DP<3>")
	)
	(segment
		(start 240.612168 -116.656866)
		(end 240.612168 -116.968778)
		(width 0.14224)
		(layer "In11.Cu")
		(net "M_F_DQS_DP<3>")
	)
	(segment
		(start 229.088188 -150.142956)
		(end 229.087934 -150.142956)
		(width 0.14224)
		(layer "In11.Cu")
		(net "M_F_DQS_DP<3>")
	)
	(segment
		(start 229.548182 -153.753312)
		(end 229.087934 -154.21356)
		(width 0.14224)
		(layer "In11.Cu")
		(net "M_F_DQS_DP<3>")
	)
	(segment
		(start 242.53952 -114.729514)
		(end 240.612168 -116.656866)
		(width 0.14224)
		(layer "In11.Cu")
		(net "M_F_DQS_DP<3>")
	)
	(segment
		(start 248.807224 -97.608644)
		(end 248.807224 -98.257614)
		(width 0.0889)
		(layer "In11.Cu")
		(net "M_F_DQS_DP<3>")
	)
	(segment
		(start 229.870254 -149.36089)
		(end 229.088188 -150.142956)
		(width 0.14224)
		(layer "In11.Cu")
		(net "M_F_DQS_DP<3>")
	)
	(segment
		(start 228.713284 -152.638252)
		(end 228.713284 -152.864566)
		(width 0.14224)
		(layer "In11.Cu")
		(net "M_F_DQS_DP<3>")
	)
	(segment
		(start 246.351552 -102.659942)
		(end 246.351552 -103.611172)
		(width 0.0889)
		(layer "In11.Cu")
		(net "M_F_DQS_DP<3>")
	)
	(segment
		(start 249.784362 -96.631506)
		(end 248.807224 -97.608644)
		(width 0.0889)
		(layer "In11.Cu")
		(net "M_F_DQS_DP<3>")
	)
	(segment
		(start 237.377732 -120.882156)
		(end 236.751368 -121.50852)
		(width 0.14224)
		(layer "In11.Cu")
		(net "M_F_DQS_DP<3>")
	)
	(segment
		(start 249.860054 -95.509588)
		(end 249.855228 -95.518224)
		(width 0.0889)
		(layer "In11.Cu")
		(net "M_F_DQS_DP<3>")
	)
	(segment
		(start 239.300512 -117.968522)
		(end 238.99495 -118.274084)
		(width 0.14224)
		(layer "In11.Cu")
		(net "M_F_DQS_DP<3>")
	)
	(segment
		(start 249.860054 -94.518988)
		(end 249.855228 -94.527624)
		(width 0.0889)
		(layer "In11.Cu")
		(net "M_F_DQS_DP<3>")
	)
	(segment
		(start 228.828092 -151.8666)
		(end 228.913182 -151.8666)
		(width 0.14224)
		(layer "In11.Cu")
		(net "M_F_DQS_DP<3>")
	)
	(segment
		(start 229.090982 -152.0444)
		(end 229.090982 -152.320752)
		(width 0.14224)
		(layer "In11.Cu")
		(net "M_F_DQS_DP<3>")
	)
	(segment
		(start 238.673894 -119.72798)
		(end 238.053626 -119.72798)
		(width 0.14224)
		(layer "In11.Cu")
		(net "M_F_DQS_DP<3>")
	)
	(segment
		(start 228.713284 -151.751792)
		(end 228.828092 -151.8666)
		(width 0.14224)
		(layer "In11.Cu")
		(net "M_F_DQS_DP<3>")
	)
	(segment
		(start 250.718574 -88.480392)
		(end 250.724924 -88.490806)
		(width 0.0889)
		(layer "In11.Cu")
		(net "M_F_DQS_DP<3>")
	)
	(segment
		(start 229.522782 -150.577804)
		(end 229.522782 -151.003)
		(width 0.14224)
		(layer "In11.Cu")
		(net "M_F_DQS_DP<3>")
	)
	(segment
		(start 228.909118 -153.0604)
		(end 229.294182 -153.0604)
		(width 0.14224)
		(layer "In11.Cu")
		(net "M_F_DQS_DP<3>")
	)
	(segment
		(start 229.090982 -152.320752)
		(end 228.910642 -152.501092)
		(width 0.14224)
		(layer "In11.Cu")
		(net "M_F_DQS_DP<3>")
	)
	(segment
		(start 238.053626 -119.72798)
		(end 237.377732 -120.403874)
		(width 0.14224)
		(layer "In11.Cu")
		(net "M_F_DQS_DP<3>")
	)
	(segment
		(start 228.850444 -152.501092)
		(end 228.713284 -152.638252)
		(width 0.14224)
		(layer "In11.Cu")
		(net "M_F_DQS_DP<3>")
	)
	(segment
		(start 228.883718 -151.257)
		(end 228.713284 -151.427434)
		(width 0.14224)
		(layer "In11.Cu")
		(net "M_F_DQS_DP<3>")
	)
	(segment
		(start 236.751368 -121.50852)
		(end 232.498646 -121.50852)
		(width 0.14224)
		(layer "In11.Cu")
		(net "M_F_DQS_DP<3>")
	)
	(segment
		(start 228.713284 -151.427434)
		(end 228.713284 -151.751792)
		(width 0.14224)
		(layer "In11.Cu")
		(net "M_F_DQS_DP<3>")
	)
	(segment
		(start 238.99495 -118.585996)
		(end 239.13719 -118.728236)
		(width 0.14224)
		(layer "In11.Cu")
		(net "M_F_DQS_DP<3>")
	)
	(segment
		(start 240.612168 -116.968778)
		(end 240.754408 -117.111018)
		(width 0.14224)
		(layer "In11.Cu")
		(net "M_F_DQS_DP<3>")
	)
	(segment
		(start 242.53952 -109.268768)
		(end 242.53952 -114.729514)
		(width 0.14224)
		(layer "In11.Cu")
		(net "M_F_DQS_DP<3>")
	)
	(segment
		(start 250.718574 -90.461338)
		(end 250.724924 -90.472006)
		(width 0.0889)
		(layer "In11.Cu")
		(net "M_F_DQS_DP<3>")
	)
	(segment
		(start 240.754408 -117.647466)
		(end 240.291112 -118.110762)
		(width 0.14224)
		(layer "In11.Cu")
		(net "M_F_DQS_DP<3>")
	)
	(segment
		(start 249.866404 -95.49892)
		(end 249.860054 -95.509588)
		(width 0.0889)
		(layer "In11.Cu")
		(net "M_F_DQS_DP<3>")
	)
	(segment
		(start 237.377732 -120.403874)
		(end 237.377732 -120.882156)
		(width 0.14224)
		(layer "In11.Cu")
		(net "M_F_DQS_DP<3>")
	)
	(segment
		(start 250.718574 -89.470738)
		(end 250.724924 -89.481406)
		(width 0.0889)
		(layer "In11.Cu")
		(net "M_F_DQS_DP<3>")
	)
	(segment
		(start 232.498646 -121.50852)
		(end 229.870254 -124.136912)
		(width 0.14224)
		(layer "In11.Cu")
		(net "M_F_DQS_DP<3>")
	)
	(segment
		(start 246.390922 -103.650542)
		(end 246.390922 -103.67264)
		(width 0.0889)
		(layer "In11.Cu")
		(net "M_F_DQS_DP<3>")
	)
	(segment
		(start 249.865134 -96.491044)
		(end 249.784362 -96.631506)
		(width 0.0889)
		(layer "In11.Cu")
		(net "M_F_DQS_DP<3>")
	)
	(segment
		(start 246.390922 -105.417366)
		(end 242.53952 -109.268768)
		(width 0.14224)
		(layer "In11.Cu")
		(net "M_F_DQS_DP<3>")
	)
	(segment
		(start 240.754408 -117.111018)
		(end 240.754408 -117.647466)
		(width 0.14224)
		(layer "In11.Cu")
		(net "M_F_DQS_DP<3>")
	)
	(segment
		(start 228.910642 -152.501092)
		(end 228.850444 -152.501092)
		(width 0.14224)
		(layer "In11.Cu")
		(net "M_F_DQS_DP<3>")
	)
	(arc
		(start 250.195588 -93.32849)
		(mid 249.857473 -93.533192)
		(end 249.860054 -93.928438)
		(width 0.0889)
		(layer "In11.Cu")
		(net "M_F_DQS_DP<3>")
	)
	(arc
		(start 250.724924 -88.490806)
		(mid 250.797722 -88.781569)
		(end 250.718574 -89.070688)
		(width 0.0889)
		(layer "In11.Cu")
		(net "M_F_DQS_DP<3>")
	)
	(arc
		(start 250.718574 -89.070688)
		(mid 250.665104 -89.265751)
		(end 250.713748 -89.462102)
		(width 0.0889)
		(layer "In11.Cu")
		(net "M_F_DQS_DP<3>")
	)
	(arc
		(start 250.718574 -90.061288)
		(mid 250.665104 -90.256351)
		(end 250.713748 -90.452702)
		(width 0.0889)
		(layer "In11.Cu")
		(net "M_F_DQS_DP<3>")
	)
	(arc
		(start 250.724924 -89.481406)
		(mid 250.797722 -89.772169)
		(end 250.718574 -90.061288)
		(width 0.0889)
		(layer "In11.Cu")
		(net "M_F_DQS_DP<3>")
	)
	(arc
		(start 249.855228 -94.527624)
		(mid 249.806473 -94.723976)
		(end 249.860054 -94.919038)
		(width 0.0889)
		(layer "In11.Cu")
		(net "M_F_DQS_DP<3>")
	)
	(arc
		(start 250.724924 -92.453206)
		(mid 250.718747 -93.033138)
		(end 250.219718 -93.32849)
		(width 0.0889)
		(layer "In11.Cu")
		(net "M_F_DQS_DP<3>")
	)
	(arc
		(start 249.860054 -95.909638)
		(mid 249.939152 -96.198786)
		(end 249.86615 -96.48952)
		(width 0.0889)
		(layer "In11.Cu")
		(net "M_F_DQS_DP<3>")
	)
	(arc
		(start 250.718574 -91.051888)
		(mid 250.665104 -91.246951)
		(end 250.713748 -91.443302)
		(width 0.0889)
		(layer "In11.Cu")
		(net "M_F_DQS_DP<3>")
	)
	(arc
		(start 250.724924 -91.462606)
		(mid 250.797722 -91.753369)
		(end 250.718574 -92.042488)
		(width 0.0889)
		(layer "In11.Cu")
		(net "M_F_DQS_DP<3>")
	)
	(arc
		(start 250.603512 -87.83701)
		(mid 250.61121 -88.167611)
		(end 250.718574 -88.480392)
		(width 0.0889)
		(layer "In11.Cu")
		(net "M_F_DQS_DP<3>")
	)
	(arc
		(start 250.553474 -87.585296)
		(mid 250.599187 -87.707033)
		(end 250.603512 -87.83701)
		(width 0.0889)
		(layer "In11.Cu")
		(net "M_F_DQS_DP<3>")
	)
	(arc
		(start 249.866404 -93.939106)
		(mid 249.939202 -94.229869)
		(end 249.860054 -94.518988)
		(width 0.0889)
		(layer "In11.Cu")
		(net "M_F_DQS_DP<3>")
	)
	(arc
		(start 249.860054 -94.919038)
		(mid 249.939276 -95.208156)
		(end 249.866404 -95.49892)
		(width 0.0889)
		(layer "In11.Cu")
		(net "M_F_DQS_DP<3>")
	)
	(arc
		(start 250.718574 -92.042488)
		(mid 250.665104 -92.237551)
		(end 250.713748 -92.433902)
		(width 0.0889)
		(layer "In11.Cu")
		(net "M_F_DQS_DP<3>")
	)
	(arc
		(start 250.206764 -86.794086)
		(mid 250.358448 -87.199187)
		(end 250.553474 -87.585296)
		(width 0.0889)
		(layer "In11.Cu")
		(net "M_F_DQS_DP<3>")
	)
	(arc
		(start 250.724924 -90.472006)
		(mid 250.797722 -90.762769)
		(end 250.718574 -91.051888)
		(width 0.0889)
		(layer "In11.Cu")
		(net "M_F_DQS_DP<3>")
	)
	(arc
		(start 249.855228 -95.518224)
		(mid 249.806473 -95.714576)
		(end 249.860054 -95.909638)
		(width 0.0889)
		(layer "In11.Cu")
		(net "M_F_DQS_DP<3>")
	)
	(segment
		(start 220.199966 -155.866846)
		(end 220.199966 -156.87294)
		(width 0.1651)
		(layer "F.Cu")
		(net "M_F_DQS_DP<2>")
	)
	(segment
		(start 220.199966 -156.87294)
		(end 220.200474 -156.87294)
		(width 0.1651)
		(layer "F.Cu")
		(net "M_F_DQS_DP<2>")
	)
	(segment
		(start 219.73794 -154.21356)
		(end 219.993972 -154.21356)
		(width 0.1651)
		(layer "F.Cu")
		(net "M_F_DQS_DP<2>")
	)
	(segment
		(start 220.237812 -155.829)
		(end 220.199966 -155.866846)
		(width 0.1651)
		(layer "F.Cu")
		(net "M_F_DQS_DP<2>")
	)
	(segment
		(start 219.993972 -154.21356)
		(end 220.237812 -154.4574)
		(width 0.1651)
		(layer "F.Cu")
		(net "M_F_DQS_DP<2>")
	)
	(segment
		(start 245.627144 -93.72854)
		(end 245.055644 -93.72854)
		(width 0.1651)
		(layer "F.Cu")
		(net "M_F_DQS_DP<2>")
	)
	(segment
		(start 220.237812 -154.4574)
		(end 220.237812 -155.829)
		(width 0.1651)
		(layer "F.Cu")
		(net "M_F_DQS_DP<2>")
	)
	(via
		(at 219.73794 -150.142956)
		(size 0.508)
		(drill 0.254)
		(layers "F.Cu" "B.Cu")
		(net "M_F_DQS_DP<2>")
	)
	(via
		(at 245.055644 -93.72854)
		(size 0.508)
		(drill 0.254)
		(layers "F.Cu" "B.Cu")
		(net "M_F_DQS_DP<2>")
	)
	(via
		(at 219.73794 -154.21356)
		(size 0.508)
		(drill 0.254)
		(layers "F.Cu" "B.Cu")
		(net "M_F_DQS_DP<2>")
	)
	(segment
		(start 219.980256 -150.142956)
		(end 219.73794 -150.142956)
		(width 0.1651)
		(layer "B.Cu")
		(net "M_F_DQS_DP<2>")
	)
	(segment
		(start 220.237812 -148.6662)
		(end 220.237812 -149.8854)
		(width 0.1651)
		(layer "B.Cu")
		(net "M_F_DQS_DP<2>")
	)
	(segment
		(start 220.237812 -149.8854)
		(end 219.980256 -150.142956)
		(width 0.1651)
		(layer "B.Cu")
		(net "M_F_DQS_DP<2>")
	)
	(segment
		(start 220.199966 -147.478496)
		(end 220.199966 -148.628354)
		(width 0.1651)
		(layer "B.Cu")
		(net "M_F_DQS_DP<2>")
	)
	(segment
		(start 220.200474 -147.478496)
		(end 220.199966 -147.478496)
		(width 0.1651)
		(layer "B.Cu")
		(net "M_F_DQS_DP<2>")
	)
	(segment
		(start 220.199966 -148.628354)
		(end 220.237812 -148.6662)
		(width 0.1651)
		(layer "B.Cu")
		(net "M_F_DQS_DP<2>")
	)
	(segment
		(start 241.643408 -96.300036)
		(end 241.610642 -96.300036)
		(width 0.0889)
		(layer "In11.Cu")
		(net "M_F_DQS_DP<2>")
	)
	(segment
		(start 228.495098 -113.71199)
		(end 228.153976 -114.053112)
		(width 0.14224)
		(layer "In11.Cu")
		(net "M_F_DQS_DP<2>")
	)
	(segment
		(start 236.977682 -99.368102)
		(end 236.982508 -99.376738)
		(width 0.0889)
		(layer "In11.Cu")
		(net "M_F_DQS_DP<2>")
	)
	(segment
		(start 222.279464 -120.180862)
		(end 221.685104 -120.775222)
		(width 0.14224)
		(layer "In11.Cu")
		(net "M_F_DQS_DP<2>")
	)
	(segment
		(start 219.36329 -152.638252)
		(end 219.36329 -152.864566)
		(width 0.14224)
		(layer "In11.Cu")
		(net "M_F_DQS_DP<2>")
	)
	(segment
		(start 223.643444 -118.563644)
		(end 223.302322 -118.904766)
		(width 0.14224)
		(layer "In11.Cu")
		(net "M_F_DQS_DP<2>")
	)
	(segment
		(start 234.993942 -104.94645)
		(end 234.978194 -104.962198)
		(width 0.0889)
		(layer "In11.Cu")
		(net "M_F_DQS_DP<2>")
	)
	(segment
		(start 240.781078 -96.79559)
		(end 240.748312 -96.79559)
		(width 0.0889)
		(layer "In11.Cu")
		(net "M_F_DQS_DP<2>")
	)
	(segment
		(start 234.993942 -104.890824)
		(end 234.993942 -104.94645)
		(width 0.0889)
		(layer "In11.Cu")
		(net "M_F_DQS_DP<2>")
	)
	(segment
		(start 223.302322 -118.904766)
		(end 223.302322 -119.520716)
		(width 0.14224)
		(layer "In11.Cu")
		(net "M_F_DQS_DP<2>")
	)
	(segment
		(start 238.209328 -98.281236)
		(end 238.176562 -98.281236)
		(width 0.0889)
		(layer "In11.Cu")
		(net "M_F_DQS_DP<2>")
	)
	(segment
		(start 244.342412 -94.59722)
		(end 244.253004 -94.63532)
		(width 0.0889)
		(layer "In11.Cu")
		(net "M_F_DQS_DP<2>")
	)
	(segment
		(start 224.420684 -118.563644)
		(end 223.643444 -118.563644)
		(width 0.14224)
		(layer "In11.Cu")
		(net "M_F_DQS_DP<2>")
	)
	(segment
		(start 219.740988 -152.0444)
		(end 219.740988 -152.320752)
		(width 0.14224)
		(layer "In11.Cu")
		(net "M_F_DQS_DP<2>")
	)
	(segment
		(start 242.99545 -95.503746)
		(end 242.992148 -95.509588)
		(width 0.0889)
		(layer "In11.Cu")
		(net "M_F_DQS_DP<2>")
	)
	(segment
		(start 219.563188 -151.8666)
		(end 219.740988 -152.0444)
		(width 0.14224)
		(layer "In11.Cu")
		(net "M_F_DQS_DP<2>")
	)
	(segment
		(start 219.559124 -153.0604)
		(end 219.944188 -153.0604)
		(width 0.14224)
		(layer "In11.Cu")
		(net "M_F_DQS_DP<2>")
	)
	(segment
		(start 234.315 -105.625138)
		(end 234.315 -108.247688)
		(width 0.14224)
		(layer "In11.Cu")
		(net "M_F_DQS_DP<2>")
	)
	(segment
		(start 233.702352 -108.860336)
		(end 233.539792 -108.860336)
		(width 0.14224)
		(layer "In11.Cu")
		(net "M_F_DQS_DP<2>")
	)
	(segment
		(start 231.729534 -110.477554)
		(end 231.388412 -110.818676)
		(width 0.14224)
		(layer "In11.Cu")
		(net "M_F_DQS_DP<2>")
	)
	(segment
		(start 219.918788 -151.257)
		(end 219.533724 -151.257)
		(width 0.14224)
		(layer "In11.Cu")
		(net "M_F_DQS_DP<2>")
	)
	(segment
		(start 239.926368 -97.290636)
		(end 239.893602 -97.290636)
		(width 0.0889)
		(layer "In11.Cu")
		(net "M_F_DQS_DP<2>")
	)
	(segment
		(start 229.771194 -113.213134)
		(end 229.272338 -113.71199)
		(width 0.14224)
		(layer "In11.Cu")
		(net "M_F_DQS_DP<2>")
	)
	(segment
		(start 236.982508 -100.957888)
		(end 236.982254 -100.958142)
		(width 0.0889)
		(layer "In11.Cu")
		(net "M_F_DQS_DP<2>")
	)
	(segment
		(start 233.00563 -109.394498)
		(end 233.00563 -109.978698)
		(width 0.14224)
		(layer "In11.Cu")
		(net "M_F_DQS_DP<2>")
	)
	(segment
		(start 236.988858 -99.95662)
		(end 236.982508 -99.967288)
		(width 0.0889)
		(layer "In11.Cu")
		(net "M_F_DQS_DP<2>")
	)
	(segment
		(start 224.91954 -117.287548)
		(end 224.91954 -118.064788)
		(width 0.14224)
		(layer "In11.Cu")
		(net "M_F_DQS_DP<2>")
	)
	(segment
		(start 220.536516 -149.348444)
		(end 220.133164 -149.751796)
		(width 0.14224)
		(layer "In11.Cu")
		(net "M_F_DQS_DP<2>")
	)
	(segment
		(start 244.042946 -94.680532)
		(end 243.850414 -95.014288)
		(width 0.0889)
		(layer "In11.Cu")
		(net "M_F_DQS_DP<2>")
	)
	(segment
		(start 219.50045 -152.501092)
		(end 219.36329 -152.638252)
		(width 0.14224)
		(layer "In11.Cu")
		(net "M_F_DQS_DP<2>")
	)
	(segment
		(start 237.064804 -101.500178)
		(end 237.064804 -102.819962)
		(width 0.0889)
		(layer "In11.Cu")
		(net "M_F_DQS_DP<2>")
	)
	(segment
		(start 219.36329 -152.864566)
		(end 219.559124 -153.0604)
		(width 0.14224)
		(layer "In11.Cu")
		(net "M_F_DQS_DP<2>")
	)
	(segment
		(start 226.037902 -116.946426)
		(end 225.260662 -116.946426)
		(width 0.14224)
		(layer "In11.Cu")
		(net "M_F_DQS_DP<2>")
	)
	(segment
		(start 230.889556 -112.094772)
		(end 230.112316 -112.094772)
		(width 0.14224)
		(layer "In11.Cu")
		(net "M_F_DQS_DP<2>")
	)
	(segment
		(start 243.360194 -95.309436)
		(end 243.338604 -95.309436)
		(width 0.0889)
		(layer "In11.Cu")
		(net "M_F_DQS_DP<2>")
	)
	(segment
		(start 219.533724 -151.257)
		(end 219.36329 -151.427434)
		(width 0.14224)
		(layer "In11.Cu")
		(net "M_F_DQS_DP<2>")
	)
	(segment
		(start 225.260662 -116.946426)
		(end 224.91954 -117.287548)
		(width 0.14224)
		(layer "In11.Cu")
		(net "M_F_DQS_DP<2>")
	)
	(segment
		(start 219.478098 -151.8666)
		(end 219.563188 -151.8666)
		(width 0.14224)
		(layer "In11.Cu")
		(net "M_F_DQS_DP<2>")
	)
	(segment
		(start 221.25432 -121.729246)
		(end 221.25432 -126.403608)
		(width 0.14224)
		(layer "In11.Cu")
		(net "M_F_DQS_DP<2>")
	)
	(segment
		(start 231.388412 -111.595916)
		(end 230.889556 -112.094772)
		(width 0.14224)
		(layer "In11.Cu")
		(net "M_F_DQS_DP<2>")
	)
	(segment
		(start 223.302322 -119.520716)
		(end 222.642176 -120.180862)
		(width 0.14224)
		(layer "In11.Cu")
		(net "M_F_DQS_DP<2>")
	)
	(segment
		(start 229.272338 -113.71199)
		(end 228.495098 -113.71199)
		(width 0.14224)
		(layer "In11.Cu")
		(net "M_F_DQS_DP<2>")
	)
	(segment
		(start 221.25432 -126.403608)
		(end 220.536516 -127.121412)
		(width 0.14224)
		(layer "In11.Cu")
		(net "M_F_DQS_DP<2>")
	)
	(segment
		(start 219.36329 -151.751792)
		(end 219.478098 -151.8666)
		(width 0.14224)
		(layer "In11.Cu")
		(net "M_F_DQS_DP<2>")
	)
	(segment
		(start 224.91954 -118.064788)
		(end 224.420684 -118.563644)
		(width 0.14224)
		(layer "In11.Cu")
		(net "M_F_DQS_DP<2>")
	)
	(segment
		(start 222.642176 -120.180862)
		(end 222.279464 -120.180862)
		(width 0.14224)
		(layer "In11.Cu")
		(net "M_F_DQS_DP<2>")
	)
	(segment
		(start 219.740988 -152.320752)
		(end 219.560648 -152.501092)
		(width 0.14224)
		(layer "In11.Cu")
		(net "M_F_DQS_DP<2>")
	)
	(segment
		(start 237.346998 -98.77679)
		(end 237.314232 -98.77679)
		(width 0.0889)
		(layer "In11.Cu")
		(net "M_F_DQS_DP<2>")
	)
	(segment
		(start 231.388412 -110.818676)
		(end 231.388412 -111.595916)
		(width 0.14224)
		(layer "In11.Cu")
		(net "M_F_DQS_DP<2>")
	)
	(segment
		(start 219.560648 -152.501092)
		(end 219.50045 -152.501092)
		(width 0.14224)
		(layer "In11.Cu")
		(net "M_F_DQS_DP<2>")
	)
	(segment
		(start 219.944188 -153.0604)
		(end 220.198188 -153.3144)
		(width 0.14224)
		(layer "In11.Cu")
		(net "M_F_DQS_DP<2>")
	)
	(segment
		(start 232.506774 -110.477554)
		(end 231.729534 -110.477554)
		(width 0.14224)
		(layer "In11.Cu")
		(net "M_F_DQS_DP<2>")
	)
	(segment
		(start 226.536758 -115.67033)
		(end 226.536758 -116.44757)
		(width 0.14224)
		(layer "In11.Cu")
		(net "M_F_DQS_DP<2>")
	)
	(segment
		(start 220.133164 -149.751796)
		(end 220.129354 -149.751796)
		(width 0.14224)
		(layer "In11.Cu")
		(net "M_F_DQS_DP<2>")
	)
	(segment
		(start 220.536516 -127.121412)
		(end 220.536516 -149.348444)
		(width 0.14224)
		(layer "In11.Cu")
		(net "M_F_DQS_DP<2>")
	)
	(segment
		(start 244.253004 -94.63532)
		(end 244.042946 -94.680532)
		(width 0.0889)
		(layer "In11.Cu")
		(net "M_F_DQS_DP<2>")
	)
	(segment
		(start 236.977428 -101.349048)
		(end 237.064804 -101.500178)
		(width 0.0889)
		(layer "In11.Cu")
		(net "M_F_DQS_DP<2>")
	)
	(segment
		(start 220.172788 -151.003)
		(end 219.918788 -151.257)
		(width 0.14224)
		(layer "In11.Cu")
		(net "M_F_DQS_DP<2>")
	)
	(segment
		(start 228.153976 -114.053112)
		(end 228.153976 -114.830352)
		(width 0.14224)
		(layer "In11.Cu")
		(net "M_F_DQS_DP<2>")
	)
	(segment
		(start 233.539792 -108.860336)
		(end 233.00563 -109.394498)
		(width 0.14224)
		(layer "In11.Cu")
		(net "M_F_DQS_DP<2>")
	)
	(segment
		(start 220.172788 -150.577804)
		(end 220.172788 -151.003)
		(width 0.14224)
		(layer "In11.Cu")
		(net "M_F_DQS_DP<2>")
	)
	(segment
		(start 221.685104 -121.298462)
		(end 221.25432 -121.729246)
		(width 0.14224)
		(layer "In11.Cu")
		(net "M_F_DQS_DP<2>")
	)
	(segment
		(start 220.198188 -153.3144)
		(end 220.198188 -153.753312)
		(width 0.14224)
		(layer "In11.Cu")
		(net "M_F_DQS_DP<2>")
	)
	(segment
		(start 219.738194 -150.142956)
		(end 219.73794 -150.142956)
		(width 0.14224)
		(layer "In11.Cu")
		(net "M_F_DQS_DP<2>")
	)
	(segment
		(start 220.198188 -153.753312)
		(end 219.73794 -154.21356)
		(width 0.14224)
		(layer "In11.Cu")
		(net "M_F_DQS_DP<2>")
	)
	(segment
		(start 229.771194 -112.435894)
		(end 229.771194 -113.213134)
		(width 0.14224)
		(layer "In11.Cu")
		(net "M_F_DQS_DP<2>")
	)
	(segment
		(start 219.73794 -150.142956)
		(end 220.172788 -150.577804)
		(width 0.14224)
		(layer "In11.Cu")
		(net "M_F_DQS_DP<2>")
	)
	(segment
		(start 227.65512 -115.329208)
		(end 226.87788 -115.329208)
		(width 0.14224)
		(layer "In11.Cu")
		(net "M_F_DQS_DP<2>")
	)
	(segment
		(start 221.685104 -120.775222)
		(end 221.685104 -121.298462)
		(width 0.14224)
		(layer "In11.Cu")
		(net "M_F_DQS_DP<2>")
	)
	(segment
		(start 230.112316 -112.094772)
		(end 229.771194 -112.435894)
		(width 0.14224)
		(layer "In11.Cu")
		(net "M_F_DQS_DP<2>")
	)
	(segment
		(start 242.498118 -95.80499)
		(end 242.465352 -95.80499)
		(width 0.0889)
		(layer "In11.Cu")
		(net "M_F_DQS_DP<2>")
	)
	(segment
		(start 237.064804 -102.819962)
		(end 234.993942 -104.890824)
		(width 0.0889)
		(layer "In11.Cu")
		(net "M_F_DQS_DP<2>")
	)
	(segment
		(start 219.36329 -151.427434)
		(end 219.36329 -151.751792)
		(width 0.14224)
		(layer "In11.Cu")
		(net "M_F_DQS_DP<2>")
	)
	(segment
		(start 234.978194 -104.962198)
		(end 234.315 -105.625138)
		(width 0.14224)
		(layer "In11.Cu")
		(net "M_F_DQS_DP<2>")
	)
	(segment
		(start 228.153976 -114.830352)
		(end 227.65512 -115.329208)
		(width 0.14224)
		(layer "In11.Cu")
		(net "M_F_DQS_DP<2>")
	)
	(segment
		(start 233.00563 -109.978698)
		(end 232.506774 -110.477554)
		(width 0.14224)
		(layer "In11.Cu")
		(net "M_F_DQS_DP<2>")
	)
	(segment
		(start 234.315 -108.247688)
		(end 233.702352 -108.860336)
		(width 0.14224)
		(layer "In11.Cu")
		(net "M_F_DQS_DP<2>")
	)
	(segment
		(start 239.064038 -97.78619)
		(end 239.031272 -97.78619)
		(width 0.0889)
		(layer "In11.Cu")
		(net "M_F_DQS_DP<2>")
	)
	(segment
		(start 226.536758 -116.44757)
		(end 226.037902 -116.946426)
		(width 0.14224)
		(layer "In11.Cu")
		(net "M_F_DQS_DP<2>")
	)
	(segment
		(start 226.87788 -115.329208)
		(end 226.536758 -115.67033)
		(width 0.14224)
		(layer "In11.Cu")
		(net "M_F_DQS_DP<2>")
	)
	(segment
		(start 220.129354 -149.751796)
		(end 219.738194 -150.142956)
		(width 0.14224)
		(layer "In11.Cu")
		(net "M_F_DQS_DP<2>")
	)
	(arc
		(start 236.982508 -99.967288)
		(mid 236.929009 -100.167186)
		(end 236.982508 -100.367084)
		(width 0.0889)
		(layer "In11.Cu")
		(net "M_F_DQS_DP<2>")
	)
	(arc
		(start 239.031272 -97.78619)
		(mid 238.83963 -97.843356)
		(end 238.699548 -97.986088)
		(width 0.0889)
		(layer "In11.Cu")
		(net "M_F_DQS_DP<2>")
	)
	(arc
		(start 242.992148 -95.509588)
		(mid 242.78354 -95.72152)
		(end 242.498118 -95.80499)
		(width 0.0889)
		(layer "In11.Cu")
		(net "M_F_DQS_DP<2>")
	)
	(arc
		(start 243.338604 -95.309436)
		(mid 243.141443 -95.361395)
		(end 242.99545 -95.503746)
		(width 0.0889)
		(layer "In11.Cu")
		(net "M_F_DQS_DP<2>")
	)
	(arc
		(start 241.610642 -96.300036)
		(mid 241.416792 -96.356386)
		(end 241.275108 -96.500188)
		(width 0.0889)
		(layer "In11.Cu")
		(net "M_F_DQS_DP<2>")
	)
	(arc
		(start 236.982508 -100.367084)
		(mid 237.061639 -100.662486)
		(end 236.982508 -100.957888)
		(width 0.0889)
		(layer "In11.Cu")
		(net "M_F_DQS_DP<2>")
	)
	(arc
		(start 237.841028 -98.481388)
		(mid 237.63242 -98.69332)
		(end 237.346998 -98.77679)
		(width 0.0889)
		(layer "In11.Cu")
		(net "M_F_DQS_DP<2>")
	)
	(arc
		(start 244.543834 -94.424246)
		(mid 244.457894 -94.527937)
		(end 244.342412 -94.59722)
		(width 0.0889)
		(layer "In11.Cu")
		(net "M_F_DQS_DP<2>")
	)
	(arc
		(start 242.133628 -96.004888)
		(mid 241.926624 -96.215752)
		(end 241.643408 -96.300036)
		(width 0.0889)
		(layer "In11.Cu")
		(net "M_F_DQS_DP<2>")
	)
	(arc
		(start 237.314232 -98.77679)
		(mid 236.981314 -98.978781)
		(end 236.977682 -99.368102)
		(width 0.0889)
		(layer "In11.Cu")
		(net "M_F_DQS_DP<2>")
	)
	(arc
		(start 241.275108 -96.500188)
		(mid 241.0665 -96.71212)
		(end 240.781078 -96.79559)
		(width 0.0889)
		(layer "In11.Cu")
		(net "M_F_DQS_DP<2>")
	)
	(arc
		(start 239.893602 -97.290636)
		(mid 239.699752 -97.346986)
		(end 239.558068 -97.490788)
		(width 0.0889)
		(layer "In11.Cu")
		(net "M_F_DQS_DP<2>")
	)
	(arc
		(start 240.748312 -96.79559)
		(mid 240.55667 -96.852756)
		(end 240.416588 -96.995488)
		(width 0.0889)
		(layer "In11.Cu")
		(net "M_F_DQS_DP<2>")
	)
	(arc
		(start 236.982254 -100.958142)
		(mid 236.928945 -101.152951)
		(end 236.977428 -101.349048)
		(width 0.0889)
		(layer "In11.Cu")
		(net "M_F_DQS_DP<2>")
	)
	(arc
		(start 243.850414 -95.014288)
		(mid 243.64341 -95.225152)
		(end 243.360194 -95.309436)
		(width 0.0889)
		(layer "In11.Cu")
		(net "M_F_DQS_DP<2>")
	)
	(arc
		(start 239.558068 -97.490788)
		(mid 239.34946 -97.70272)
		(end 239.064038 -97.78619)
		(width 0.0889)
		(layer "In11.Cu")
		(net "M_F_DQS_DP<2>")
	)
	(arc
		(start 245.055644 -93.72854)
		(mid 244.780366 -94.062141)
		(end 244.543834 -94.424246)
		(width 0.0889)
		(layer "In11.Cu")
		(net "M_F_DQS_DP<2>")
	)
	(arc
		(start 238.699548 -97.986088)
		(mid 238.492544 -98.196952)
		(end 238.209328 -98.281236)
		(width 0.0889)
		(layer "In11.Cu")
		(net "M_F_DQS_DP<2>")
	)
	(arc
		(start 242.465352 -95.80499)
		(mid 242.27371 -95.862156)
		(end 242.133628 -96.004888)
		(width 0.0889)
		(layer "In11.Cu")
		(net "M_F_DQS_DP<2>")
	)
	(arc
		(start 236.982508 -99.376738)
		(mid 237.06173 -99.665856)
		(end 236.988858 -99.95662)
		(width 0.0889)
		(layer "In11.Cu")
		(net "M_F_DQS_DP<2>")
	)
	(arc
		(start 240.416588 -96.995488)
		(mid 240.209584 -97.206352)
		(end 239.926368 -97.290636)
		(width 0.0889)
		(layer "In11.Cu")
		(net "M_F_DQS_DP<2>")
	)
	(arc
		(start 238.176562 -98.281236)
		(mid 237.982712 -98.337586)
		(end 237.841028 -98.481388)
		(width 0.0889)
		(layer "In11.Cu")
		(net "M_F_DQS_DP<2>")
	)
	(segment
		(start 210.849972 -156.87294)
		(end 210.849972 -155.866846)
		(width 0.1651)
		(layer "F.Cu")
		(net "M_F_DQS_DP<1>")
	)
	(segment
		(start 210.887818 -154.4574)
		(end 210.643978 -154.21356)
		(width 0.1651)
		(layer "F.Cu")
		(net "M_F_DQS_DP<1>")
	)
	(segment
		(start 241.334798 -91.25204)
		(end 240.763298 -91.25204)
		(width 0.1651)
		(layer "F.Cu")
		(net "M_F_DQS_DP<1>")
	)
	(segment
		(start 210.887818 -155.829)
		(end 210.887818 -154.4574)
		(width 0.1651)
		(layer "F.Cu")
		(net "M_F_DQS_DP<1>")
	)
	(segment
		(start 210.849972 -155.866846)
		(end 210.887818 -155.829)
		(width 0.1651)
		(layer "F.Cu")
		(net "M_F_DQS_DP<1>")
	)
	(segment
		(start 210.85048 -156.87294)
		(end 210.849972 -156.87294)
		(width 0.1651)
		(layer "F.Cu")
		(net "M_F_DQS_DP<1>")
	)
	(segment
		(start 210.643978 -154.21356)
		(end 210.387946 -154.21356)
		(width 0.1651)
		(layer "F.Cu")
		(net "M_F_DQS_DP<1>")
	)
	(via
		(at 210.387946 -150.142956)
		(size 0.508)
		(drill 0.254)
		(layers "F.Cu" "B.Cu")
		(net "M_F_DQS_DP<1>")
	)
	(via
		(at 210.387946 -154.21356)
		(size 0.508)
		(drill 0.254)
		(layers "F.Cu" "B.Cu")
		(net "M_F_DQS_DP<1>")
	)
	(via
		(at 240.763298 -91.25204)
		(size 0.508)
		(drill 0.254)
		(layers "F.Cu" "B.Cu")
		(net "M_F_DQS_DP<1>")
	)
	(segment
		(start 210.85048 -147.478496)
		(end 210.849972 -147.478496)
		(width 0.1651)
		(layer "B.Cu")
		(net "M_F_DQS_DP<1>")
	)
	(segment
		(start 210.887818 -148.6662)
		(end 210.887818 -149.8854)
		(width 0.1651)
		(layer "B.Cu")
		(net "M_F_DQS_DP<1>")
	)
	(segment
		(start 210.849972 -148.628354)
		(end 210.887818 -148.6662)
		(width 0.1651)
		(layer "B.Cu")
		(net "M_F_DQS_DP<1>")
	)
	(segment
		(start 210.849972 -147.478496)
		(end 210.849972 -148.628354)
		(width 0.1651)
		(layer "B.Cu")
		(net "M_F_DQS_DP<1>")
	)
	(segment
		(start 210.630262 -150.142956)
		(end 210.387946 -150.142956)
		(width 0.1651)
		(layer "B.Cu")
		(net "M_F_DQS_DP<1>")
	)
	(segment
		(start 210.887818 -149.8854)
		(end 210.630262 -150.142956)
		(width 0.1651)
		(layer "B.Cu")
		(net "M_F_DQS_DP<1>")
	)
	(segment
		(start 211.80552 -120.819418)
		(end 211.80552 -121.475246)
		(width 0.14224)
		(layer "In11.Cu")
		(net "M_F_DQS_DP<1>")
	)
	(segment
		(start 234.771692 -94.31909)
		(end 234.771438 -94.318836)
		(width 0.0889)
		(layer "In11.Cu")
		(net "M_F_DQS_DP<1>")
	)
	(segment
		(start 231.616504 -96.21393)
		(end 231.616504 -97.156016)
		(width 0.0889)
		(layer "In11.Cu")
		(net "M_F_DQS_DP<1>")
	)
	(segment
		(start 228.464872 -97.467928)
		(end 227.6856 -98.2472)
		(width 0.14224)
		(layer "In11.Cu")
		(net "M_F_DQS_DP<1>")
	)
	(segment
		(start 210.013296 -151.427434)
		(end 210.013296 -151.751792)
		(width 0.14224)
		(layer "In11.Cu")
		(net "M_F_DQS_DP<1>")
	)
	(segment
		(start 214.134192 -116.985796)
		(end 214.134192 -117.521228)
		(width 0.14224)
		(layer "In11.Cu")
		(net "M_F_DQS_DP<1>")
	)
	(segment
		(start 210.822794 -151.011128)
		(end 210.576922 -151.257)
		(width 0.14224)
		(layer "In11.Cu")
		(net "M_F_DQS_DP<1>")
	)
	(segment
		(start 229.16007 -97.46488)
		(end 229.00259 -97.467928)
		(width 0.14224)
		(layer "In11.Cu")
		(net "M_F_DQS_DP<1>")
	)
	(segment
		(start 213.713568 -115.640866)
		(end 213.407498 -115.946936)
		(width 0.14224)
		(layer "In11.Cu")
		(net "M_F_DQS_DP<1>")
	)
	(segment
		(start 211.04352 -122.07494)
		(end 211.04352 -122.505724)
		(width 0.14224)
		(layer "In11.Cu")
		(net "M_F_DQS_DP<1>")
	)
	(segment
		(start 211.170266 -129.045208)
		(end 211.170266 -149.36089)
		(width 0.14224)
		(layer "In11.Cu")
		(net "M_F_DQS_DP<1>")
	)
	(segment
		(start 211.265008 -119.567452)
		(end 211.06892 -119.76354)
		(width 0.14224)
		(layer "In11.Cu")
		(net "M_F_DQS_DP<1>")
	)
	(segment
		(start 211.80552 -119.189246)
		(end 211.427314 -119.567452)
		(width 0.14224)
		(layer "In11.Cu")
		(net "M_F_DQS_DP<1>")
	)
	(segment
		(start 210.013296 -152.864566)
		(end 210.20913 -153.0604)
		(width 0.14224)
		(layer "In11.Cu")
		(net "M_F_DQS_DP<1>")
	)
	(segment
		(start 210.390994 -152.320752)
		(end 210.210654 -152.501092)
		(width 0.14224)
		(layer "In11.Cu")
		(net "M_F_DQS_DP<1>")
	)
	(segment
		(start 214.134192 -117.521228)
		(end 213.670388 -117.985032)
		(width 0.14224)
		(layer "In11.Cu")
		(net "M_F_DQS_DP<1>")
	)
	(segment
		(start 210.848194 -153.753312)
		(end 210.387946 -154.21356)
		(width 0.14224)
		(layer "In11.Cu")
		(net "M_F_DQS_DP<1>")
	)
	(segment
		(start 210.210654 -152.501092)
		(end 210.150456 -152.501092)
		(width 0.14224)
		(layer "In11.Cu")
		(net "M_F_DQS_DP<1>")
	)
	(segment
		(start 210.387946 -150.142956)
		(end 210.822794 -150.577804)
		(width 0.14224)
		(layer "In11.Cu")
		(net "M_F_DQS_DP<1>")
	)
	(segment
		(start 210.150456 -152.501092)
		(end 210.013296 -152.638252)
		(width 0.14224)
		(layer "In11.Cu")
		(net "M_F_DQS_DP<1>")
	)
	(segment
		(start 215.287606 -116.367814)
		(end 214.751666 -116.367814)
		(width 0.14224)
		(layer "In11.Cu")
		(net "M_F_DQS_DP<1>")
	)
	(segment
		(start 213.134702 -117.985032)
		(end 212.542628 -117.392958)
		(width 0.14224)
		(layer "In11.Cu")
		(net "M_F_DQS_DP<1>")
	)
	(segment
		(start 215.024716 -114.329718)
		(end 215.024716 -114.64163)
		(width 0.14224)
		(layer "In11.Cu")
		(net "M_F_DQS_DP<1>")
	)
	(segment
		(start 231.616504 -97.156016)
		(end 231.35082 -97.4217)
		(width 0.0889)
		(layer "In11.Cu")
		(net "M_F_DQS_DP<1>")
	)
	(segment
		(start 211.80552 -121.475246)
		(end 211.427314 -121.853452)
		(width 0.14224)
		(layer "In11.Cu")
		(net "M_F_DQS_DP<1>")
	)
	(segment
		(start 215.75141 -115.368578)
		(end 215.75141 -115.90401)
		(width 0.14224)
		(layer "In11.Cu")
		(net "M_F_DQS_DP<1>")
	)
	(segment
		(start 210.390994 -152.0444)
		(end 210.390994 -152.320752)
		(width 0.14224)
		(layer "In11.Cu")
		(net "M_F_DQS_DP<1>")
	)
	(segment
		(start 232.599484 -95.222314)
		(end 231.616504 -96.21393)
		(width 0.0889)
		(layer "In11.Cu")
		(net "M_F_DQS_DP<1>")
	)
	(segment
		(start 210.213194 -151.8666)
		(end 210.390994 -152.0444)
		(width 0.14224)
		(layer "In11.Cu")
		(net "M_F_DQS_DP<1>")
	)
	(segment
		(start 233.452924 -95.222314)
		(end 232.599484 -95.222314)
		(width 0.0889)
		(layer "In11.Cu")
		(net "M_F_DQS_DP<1>")
	)
	(segment
		(start 211.265008 -120.441212)
		(end 211.427314 -120.441212)
		(width 0.14224)
		(layer "In11.Cu")
		(net "M_F_DQS_DP<1>")
	)
	(segment
		(start 211.427314 -122.727212)
		(end 211.80552 -123.105418)
		(width 0.14224)
		(layer "In11.Cu")
		(net "M_F_DQS_DP<1>")
	)
	(segment
		(start 215.75141 -115.90401)
		(end 215.287606 -116.367814)
		(width 0.14224)
		(layer "In11.Cu")
		(net "M_F_DQS_DP<1>")
	)
	(segment
		(start 235.633768 -93.82379)
		(end 235.594144 -93.82379)
		(width 0.0889)
		(layer "In11.Cu")
		(net "M_F_DQS_DP<1>")
	)
	(segment
		(start 234.356402 -94.318836)
		(end 233.452924 -95.222314)
		(width 0.0889)
		(layer "In11.Cu")
		(net "M_F_DQS_DP<1>")
	)
	(segment
		(start 212.542628 -117.392958)
		(end 212.09635 -117.392958)
		(width 0.14224)
		(layer "In11.Cu")
		(net "M_F_DQS_DP<1>")
	)
	(segment
		(start 227.6856 -98.2472)
		(end 227.6856 -101.668834)
		(width 0.14224)
		(layer "In11.Cu")
		(net "M_F_DQS_DP<1>")
	)
	(segment
		(start 210.848194 -153.3144)
		(end 210.848194 -153.753312)
		(width 0.14224)
		(layer "In11.Cu")
		(net "M_F_DQS_DP<1>")
	)
	(segment
		(start 214.024972 -115.640866)
		(end 213.713568 -115.640866)
		(width 0.14224)
		(layer "In11.Cu")
		(net "M_F_DQS_DP<1>")
	)
	(segment
		(start 211.427314 -119.567452)
		(end 211.265008 -119.567452)
		(width 0.14224)
		(layer "In11.Cu")
		(net "M_F_DQS_DP<1>")
	)
	(segment
		(start 237.346998 -92.83319)
		(end 237.314232 -92.83319)
		(width 0.0889)
		(layer "In11.Cu")
		(net "M_F_DQS_DP<1>")
	)
	(segment
		(start 213.407498 -115.946936)
		(end 213.407498 -116.258848)
		(width 0.14224)
		(layer "In11.Cu")
		(net "M_F_DQS_DP<1>")
	)
	(segment
		(start 211.06892 -119.76354)
		(end 211.06892 -120.245124)
		(width 0.14224)
		(layer "In11.Cu")
		(net "M_F_DQS_DP<1>")
	)
	(segment
		(start 236.483652 -93.32849)
		(end 236.459522 -93.32849)
		(width 0.0889)
		(layer "In11.Cu")
		(net "M_F_DQS_DP<1>")
	)
	(segment
		(start 210.18373 -151.257)
		(end 210.013296 -151.427434)
		(width 0.14224)
		(layer "In11.Cu")
		(net "M_F_DQS_DP<1>")
	)
	(segment
		(start 214.751666 -116.367814)
		(end 214.024972 -115.640866)
		(width 0.14224)
		(layer "In11.Cu")
		(net "M_F_DQS_DP<1>")
	)
	(segment
		(start 231.35082 -97.4217)
		(end 229.359206 -97.4217)
		(width 0.0889)
		(layer "In11.Cu")
		(net "M_F_DQS_DP<1>")
	)
	(segment
		(start 211.80552 -128.409954)
		(end 211.170266 -129.045208)
		(width 0.14224)
		(layer "In11.Cu")
		(net "M_F_DQS_DP<1>")
	)
	(segment
		(start 210.128104 -151.8666)
		(end 210.213194 -151.8666)
		(width 0.14224)
		(layer "In11.Cu")
		(net "M_F_DQS_DP<1>")
	)
	(segment
		(start 211.427314 -120.441212)
		(end 211.80552 -120.819418)
		(width 0.14224)
		(layer "In11.Cu")
		(net "M_F_DQS_DP<1>")
	)
	(segment
		(start 211.80552 -123.105418)
		(end 211.80552 -128.409954)
		(width 0.14224)
		(layer "In11.Cu")
		(net "M_F_DQS_DP<1>")
	)
	(segment
		(start 238.209328 -92.337636)
		(end 238.176562 -92.337636)
		(width 0.0889)
		(layer "In11.Cu")
		(net "M_F_DQS_DP<1>")
	)
	(segment
		(start 210.013296 -152.638252)
		(end 210.013296 -152.864566)
		(width 0.14224)
		(layer "In11.Cu")
		(net "M_F_DQS_DP<1>")
	)
	(segment
		(start 239.064038 -91.84259)
		(end 239.031272 -91.84259)
		(width 0.0889)
		(layer "In11.Cu")
		(net "M_F_DQS_DP<1>")
	)
	(segment
		(start 210.576922 -151.257)
		(end 210.18373 -151.257)
		(width 0.14224)
		(layer "In11.Cu")
		(net "M_F_DQS_DP<1>")
	)
	(segment
		(start 211.80552 -117.683788)
		(end 211.80552 -119.189246)
		(width 0.14224)
		(layer "In11.Cu")
		(net "M_F_DQS_DP<1>")
	)
	(segment
		(start 212.09635 -117.392958)
		(end 211.80552 -117.683788)
		(width 0.14224)
		(layer "In11.Cu")
		(net "M_F_DQS_DP<1>")
	)
	(segment
		(start 227.6856 -101.668834)
		(end 215.024716 -114.329718)
		(width 0.14224)
		(layer "In11.Cu")
		(net "M_F_DQS_DP<1>")
	)
	(segment
		(start 211.04352 -122.505724)
		(end 211.265008 -122.727212)
		(width 0.14224)
		(layer "In11.Cu")
		(net "M_F_DQS_DP<1>")
	)
	(segment
		(start 229.359206 -97.4217)
		(end 229.220522 -97.424494)
		(width 0.0889)
		(layer "In11.Cu")
		(net "M_F_DQS_DP<1>")
	)
	(segment
		(start 211.170266 -149.36089)
		(end 210.3882 -150.142956)
		(width 0.14224)
		(layer "In11.Cu")
		(net "M_F_DQS_DP<1>")
	)
	(segment
		(start 210.822794 -150.577804)
		(end 210.822794 -151.011128)
		(width 0.14224)
		(layer "In11.Cu")
		(net "M_F_DQS_DP<1>")
	)
	(segment
		(start 213.407498 -116.258848)
		(end 214.134192 -116.985796)
		(width 0.14224)
		(layer "In11.Cu")
		(net "M_F_DQS_DP<1>")
	)
	(segment
		(start 215.024716 -114.64163)
		(end 215.75141 -115.368578)
		(width 0.14224)
		(layer "In11.Cu")
		(net "M_F_DQS_DP<1>")
	)
	(segment
		(start 234.771438 -94.318836)
		(end 234.356402 -94.318836)
		(width 0.0889)
		(layer "In11.Cu")
		(net "M_F_DQS_DP<1>")
	)
	(segment
		(start 210.3882 -150.142956)
		(end 210.387946 -150.142956)
		(width 0.14224)
		(layer "In11.Cu")
		(net "M_F_DQS_DP<1>")
	)
	(segment
		(start 213.670388 -117.985032)
		(end 213.134702 -117.985032)
		(width 0.14224)
		(layer "In11.Cu")
		(net "M_F_DQS_DP<1>")
	)
	(segment
		(start 229.220522 -97.424494)
		(end 229.182168 -97.464626)
		(width 0.0889)
		(layer "In11.Cu")
		(net "M_F_DQS_DP<1>")
	)
	(segment
		(start 229.00259 -97.467928)
		(end 228.464872 -97.467928)
		(width 0.14224)
		(layer "In11.Cu")
		(net "M_F_DQS_DP<1>")
	)
	(segment
		(start 211.265008 -121.853452)
		(end 211.04352 -122.07494)
		(width 0.14224)
		(layer "In11.Cu")
		(net "M_F_DQS_DP<1>")
	)
	(segment
		(start 210.013296 -151.751792)
		(end 210.128104 -151.8666)
		(width 0.14224)
		(layer "In11.Cu")
		(net "M_F_DQS_DP<1>")
	)
	(segment
		(start 211.06892 -120.245124)
		(end 211.265008 -120.441212)
		(width 0.14224)
		(layer "In11.Cu")
		(net "M_F_DQS_DP<1>")
	)
	(segment
		(start 211.427314 -121.853452)
		(end 211.265008 -121.853452)
		(width 0.14224)
		(layer "In11.Cu")
		(net "M_F_DQS_DP<1>")
	)
	(segment
		(start 210.594194 -153.0604)
		(end 210.848194 -153.3144)
		(width 0.14224)
		(layer "In11.Cu")
		(net "M_F_DQS_DP<1>")
	)
	(segment
		(start 229.182168 -97.464626)
		(end 229.16007 -97.46488)
		(width 0.0889)
		(layer "In11.Cu")
		(net "M_F_DQS_DP<1>")
	)
	(segment
		(start 210.20913 -153.0604)
		(end 210.594194 -153.0604)
		(width 0.14224)
		(layer "In11.Cu")
		(net "M_F_DQS_DP<1>")
	)
	(segment
		(start 240.047526 -91.347036)
		(end 239.893602 -91.347036)
		(width 0.0889)
		(layer "In11.Cu")
		(net "M_F_DQS_DP<1>")
	)
	(segment
		(start 211.265008 -122.727212)
		(end 211.427314 -122.727212)
		(width 0.14224)
		(layer "In11.Cu")
		(net "M_F_DQS_DP<1>")
	)
	(segment
		(start 240.763298 -91.25204)
		(end 240.047526 -91.347036)
		(width 0.0889)
		(layer "In11.Cu")
		(net "M_F_DQS_DP<1>")
	)
	(arc
		(start 239.558068 -91.547188)
		(mid 239.34946 -91.75912)
		(end 239.064038 -91.84259)
		(width 0.0889)
		(layer "In11.Cu")
		(net "M_F_DQS_DP<1>")
	)
	(arc
		(start 236.459522 -93.32849)
		(mid 236.265672 -93.38484)
		(end 236.123988 -93.528642)
		(width 0.0889)
		(layer "In11.Cu")
		(net "M_F_DQS_DP<1>")
	)
	(arc
		(start 235.265468 -94.023688)
		(mid 235.056969 -94.235555)
		(end 234.771692 -94.31909)
		(width 0.0889)
		(layer "In11.Cu")
		(net "M_F_DQS_DP<1>")
	)
	(arc
		(start 237.841028 -92.537788)
		(mid 237.63242 -92.74972)
		(end 237.346998 -92.83319)
		(width 0.0889)
		(layer "In11.Cu")
		(net "M_F_DQS_DP<1>")
	)
	(arc
		(start 238.176562 -92.337636)
		(mid 237.982712 -92.393986)
		(end 237.841028 -92.537788)
		(width 0.0889)
		(layer "In11.Cu")
		(net "M_F_DQS_DP<1>")
	)
	(arc
		(start 239.031272 -91.84259)
		(mid 238.83963 -91.899756)
		(end 238.699548 -92.042488)
		(width 0.0889)
		(layer "In11.Cu")
		(net "M_F_DQS_DP<1>")
	)
	(arc
		(start 238.699548 -92.042488)
		(mid 238.492544 -92.253352)
		(end 238.209328 -92.337636)
		(width 0.0889)
		(layer "In11.Cu")
		(net "M_F_DQS_DP<1>")
	)
	(arc
		(start 239.893602 -91.347036)
		(mid 239.699752 -91.403386)
		(end 239.558068 -91.547188)
		(width 0.0889)
		(layer "In11.Cu")
		(net "M_F_DQS_DP<1>")
	)
	(arc
		(start 237.314232 -92.83319)
		(mid 237.12259 -92.890356)
		(end 236.982508 -93.033088)
		(width 0.0889)
		(layer "In11.Cu")
		(net "M_F_DQS_DP<1>")
	)
	(arc
		(start 236.123988 -93.528642)
		(mid 235.916984 -93.739506)
		(end 235.633768 -93.82379)
		(width 0.0889)
		(layer "In11.Cu")
		(net "M_F_DQS_DP<1>")
	)
	(arc
		(start 235.594144 -93.82379)
		(mid 235.404215 -93.88166)
		(end 235.265468 -94.023688)
		(width 0.0889)
		(layer "In11.Cu")
		(net "M_F_DQS_DP<1>")
	)
	(arc
		(start 236.982508 -93.033088)
		(mid 236.771795 -93.246167)
		(end 236.483652 -93.32849)
		(width 0.0889)
		(layer "In11.Cu")
		(net "M_F_DQS_DP<1>")
	)
	(segment
		(start 236.679232 -153.515568)
		(end 236.679232 -154.333702)
		(width 0.1651)
		(layer "F.Cu")
		(net "M_F_DQS_DP<17>")
	)
	(segment
		(start 237.199932 -152.895554)
		(end 236.763814 -153.331672)
		(width 0.1651)
		(layer "F.Cu")
		(net "M_F_DQS_DP<17>")
	)
	(segment
		(start 246.485664 -82.33664)
		(end 245.914164 -82.33664)
		(width 0.1651)
		(layer "F.Cu")
		(net "M_F_DQS_DP<17>")
	)
	(segment
		(start 236.760766 -154.557984)
		(end 237.142528 -154.939746)
		(width 0.1651)
		(layer "F.Cu")
		(net "M_F_DQS_DP<17>")
	)
	(segment
		(start 236.763814 -153.331672)
		(end 236.679232 -153.515568)
		(width 0.1651)
		(layer "F.Cu")
		(net "M_F_DQS_DP<17>")
	)
	(segment
		(start 237.20044 -152.273)
		(end 237.199932 -152.278842)
		(width 0.1651)
		(layer "F.Cu")
		(net "M_F_DQS_DP<17>")
	)
	(segment
		(start 237.199932 -152.278842)
		(end 237.199932 -152.895554)
		(width 0.1651)
		(layer "F.Cu")
		(net "M_F_DQS_DP<17>")
	)
	(segment
		(start 236.679232 -154.333702)
		(end 236.760766 -154.557984)
		(width 0.1651)
		(layer "F.Cu")
		(net "M_F_DQS_DP<17>")
	)
	(via
		(at 245.914164 -82.33664)
		(size 0.508)
		(drill 0.254)
		(layers "F.Cu" "B.Cu")
		(net "M_F_DQS_DP<17>")
	)
	(via
		(at 237.142528 -154.939746)
		(size 0.508)
		(drill 0.254)
		(layers "F.Cu" "B.Cu")
		(net "M_F_DQS_DP<17>")
	)
	(via
		(at 237.142528 -149.4282)
		(size 0.508)
		(drill 0.254)
		(layers "F.Cu" "B.Cu")
		(net "M_F_DQS_DP<17>")
	)
	(segment
		(start 237.199932 -152.078182)
		(end 237.199932 -151.460454)
		(width 0.1651)
		(layer "B.Cu")
		(net "M_F_DQS_DP<17>")
	)
	(segment
		(start 237.199932 -151.460454)
		(end 236.743748 -151.00427)
		(width 0.1651)
		(layer "B.Cu")
		(net "M_F_DQS_DP<17>")
	)
	(segment
		(start 237.20044 -152.078436)
		(end 237.199932 -152.078182)
		(width 0.1651)
		(layer "B.Cu")
		(net "M_F_DQS_DP<17>")
	)
	(segment
		(start 236.666532 -149.976332)
		(end 236.753908 -149.81682)
		(width 0.1651)
		(layer "B.Cu")
		(net "M_F_DQS_DP<17>")
	)
	(segment
		(start 236.743748 -151.00427)
		(end 236.666532 -150.871936)
		(width 0.1651)
		(layer "B.Cu")
		(net "M_F_DQS_DP<17>")
	)
	(segment
		(start 236.753908 -149.81682)
		(end 237.142528 -149.4282)
		(width 0.1651)
		(layer "B.Cu")
		(net "M_F_DQS_DP<17>")
	)
	(segment
		(start 236.666532 -150.871936)
		(end 236.666532 -149.976332)
		(width 0.1651)
		(layer "B.Cu")
		(net "M_F_DQS_DP<17>")
	)
	(segment
		(start 245.40718 -96.508824)
		(end 245.402354 -96.500188)
		(width 0.0889)
		(layer "In4.Cu")
		(net "M_F_DQS_DP<17>")
	)
	(segment
		(start 245.402354 -98.481388)
		(end 245.396004 -98.47072)
		(width 0.0889)
		(layer "In4.Cu")
		(net "M_F_DQS_DP<17>")
	)
	(segment
		(start 237.11408 -123.304046)
		(end 237.11408 -115.826286)
		(width 0.14224)
		(layer "In4.Cu")
		(net "M_F_DQS_DP<17>")
	)
	(segment
		(start 237.655608 -142.105888)
		(end 237.655608 -123.845574)
		(width 0.14224)
		(layer "In4.Cu")
		(net "M_F_DQS_DP<17>")
	)
	(segment
		(start 245.402354 -85.603588)
		(end 245.396004 -85.59292)
		(width 0.0889)
		(layer "In4.Cu")
		(net "M_F_DQS_DP<17>")
	)
	(segment
		(start 237.655608 -146.738594)
		(end 237.551976 -146.634962)
		(width 0.14224)
		(layer "In4.Cu")
		(net "M_F_DQS_DP<17>")
	)
	(segment
		(start 237.655608 -146.27733)
		(end 237.655608 -143.45031)
		(width 0.14224)
		(layer "In4.Cu")
		(net "M_F_DQS_DP<17>")
	)
	(segment
		(start 237.498128 -148.280882)
		(end 237.498128 -148.026882)
		(width 0.14224)
		(layer "In4.Cu")
		(net "M_F_DQS_DP<17>")
	)
	(segment
		(start 245.40718 -88.584024)
		(end 245.402354 -88.575388)
		(width 0.0889)
		(layer "In4.Cu")
		(net "M_F_DQS_DP<17>")
	)
	(segment
		(start 237.142528 -149.4282)
		(end 237.421928 -149.4282)
		(width 0.14224)
		(layer "In4.Cu")
		(net "M_F_DQS_DP<17>")
	)
	(segment
		(start 245.315994 -100.02139)
		(end 245.405402 -99.866196)
		(width 0.0889)
		(layer "In4.Cu")
		(net "M_F_DQS_DP<17>")
	)
	(segment
		(start 245.40718 -84.621624)
		(end 245.402354 -84.612988)
		(width 0.0889)
		(layer "In4.Cu")
		(net "M_F_DQS_DP<17>")
	)
	(segment
		(start 245.402354 -89.565988)
		(end 245.396004 -89.55532)
		(width 0.0889)
		(layer "In4.Cu")
		(net "M_F_DQS_DP<17>")
	)
	(segment
		(start 245.402354 -84.612988)
		(end 245.396004 -84.60232)
		(width 0.0889)
		(layer "In4.Cu")
		(net "M_F_DQS_DP<17>")
	)
	(segment
		(start 245.054882 -104.993694)
		(end 245.054882 -103.000048)
		(width 0.14224)
		(layer "In4.Cu")
		(net "M_F_DQS_DP<17>")
	)
	(segment
		(start 237.498128 -148.026882)
		(end 237.655608 -147.869402)
		(width 0.14224)
		(layer "In4.Cu")
		(net "M_F_DQS_DP<17>")
	)
	(segment
		(start 237.551976 -146.634962)
		(end 237.551976 -146.380962)
		(width 0.14224)
		(layer "In4.Cu")
		(net "M_F_DQS_DP<17>")
	)
	(segment
		(start 245.40718 -83.631024)
		(end 245.402354 -83.622388)
		(width 0.0889)
		(layer "In4.Cu")
		(net "M_F_DQS_DP<17>")
	)
	(segment
		(start 245.914164 -82.674714)
		(end 245.914164 -82.33664)
		(width 0.0889)
		(layer "In4.Cu")
		(net "M_F_DQS_DP<17>")
	)
	(segment
		(start 245.40718 -94.527624)
		(end 245.402354 -94.518988)
		(width 0.0889)
		(layer "In4.Cu")
		(net "M_F_DQS_DP<17>")
	)
	(segment
		(start 245.402354 -87.584788)
		(end 245.396004 -87.57412)
		(width 0.0889)
		(layer "In4.Cu")
		(net "M_F_DQS_DP<17>")
	)
	(segment
		(start 237.655608 -142.915386)
		(end 237.655608 -142.621)
		(width 0.14224)
		(layer "In4.Cu")
		(net "M_F_DQS_DP<17>")
	)
	(segment
		(start 237.11408 -115.826286)
		(end 238.73968 -114.200686)
		(width 0.14224)
		(layer "In4.Cu")
		(net "M_F_DQS_DP<17>")
	)
	(segment
		(start 237.655608 -147.869402)
		(end 237.655608 -147.615402)
		(width 0.14224)
		(layer "In4.Cu")
		(net "M_F_DQS_DP<17>")
	)
	(segment
		(start 245.40718 -98.490024)
		(end 245.402354 -98.481388)
		(width 0.0889)
		(layer "In4.Cu")
		(net "M_F_DQS_DP<17>")
	)
	(segment
		(start 237.655608 -123.845574)
		(end 237.11408 -123.304046)
		(width 0.14224)
		(layer "In4.Cu")
		(net "M_F_DQS_DP<17>")
	)
	(segment
		(start 237.515146 -143.309848)
		(end 237.515146 -143.055848)
		(width 0.14224)
		(layer "In4.Cu")
		(net "M_F_DQS_DP<17>")
	)
	(segment
		(start 238.73968 -114.200686)
		(end 238.73968 -111.308388)
		(width 0.14224)
		(layer "In4.Cu")
		(net "M_F_DQS_DP<17>")
	)
	(segment
		(start 245.402354 -86.594188)
		(end 245.396004 -86.58352)
		(width 0.0889)
		(layer "In4.Cu")
		(net "M_F_DQS_DP<17>")
	)
	(segment
		(start 237.525052 -142.490444)
		(end 237.525052 -142.236444)
		(width 0.14224)
		(layer "In4.Cu")
		(net "M_F_DQS_DP<17>")
	)
	(segment
		(start 245.40718 -87.593424)
		(end 245.402354 -87.584788)
		(width 0.0889)
		(layer "In4.Cu")
		(net "M_F_DQS_DP<17>")
	)
	(segment
		(start 237.655608 -143.45031)
		(end 237.515146 -143.309848)
		(width 0.14224)
		(layer "In4.Cu")
		(net "M_F_DQS_DP<17>")
	)
	(segment
		(start 237.655608 -147.615402)
		(end 237.498128 -147.457922)
		(width 0.14224)
		(layer "In4.Cu")
		(net "M_F_DQS_DP<17>")
	)
	(segment
		(start 237.421928 -149.4282)
		(end 237.655608 -149.19452)
		(width 0.14224)
		(layer "In4.Cu")
		(net "M_F_DQS_DP<17>")
	)
	(segment
		(start 237.551976 -146.380962)
		(end 237.655608 -146.27733)
		(width 0.14224)
		(layer "In4.Cu")
		(net "M_F_DQS_DP<17>")
	)
	(segment
		(start 238.73968 -111.308388)
		(end 238.740188 -111.308388)
		(width 0.14224)
		(layer "In4.Cu")
		(net "M_F_DQS_DP<17>")
	)
	(segment
		(start 245.402354 -91.547188)
		(end 245.396004 -91.53652)
		(width 0.0889)
		(layer "In4.Cu")
		(net "M_F_DQS_DP<17>")
	)
	(segment
		(start 245.40718 -90.565224)
		(end 245.402354 -90.556588)
		(width 0.0889)
		(layer "In4.Cu")
		(net "M_F_DQS_DP<17>")
	)
	(segment
		(start 237.655608 -149.19452)
		(end 237.655608 -148.438362)
		(width 0.14224)
		(layer "In4.Cu")
		(net "M_F_DQS_DP<17>")
	)
	(segment
		(start 245.054882 -103.000048)
		(end 245.094252 -102.960678)
		(width 0.0889)
		(layer "In4.Cu")
		(net "M_F_DQS_DP<17>")
	)
	(segment
		(start 245.40718 -95.518224)
		(end 245.402354 -95.509588)
		(width 0.0889)
		(layer "In4.Cu")
		(net "M_F_DQS_DP<17>")
	)
	(segment
		(start 237.655608 -148.438362)
		(end 237.498128 -148.280882)
		(width 0.14224)
		(layer "In4.Cu")
		(net "M_F_DQS_DP<17>")
	)
	(segment
		(start 245.402354 -97.490788)
		(end 245.396004 -97.48012)
		(width 0.0889)
		(layer "In4.Cu")
		(net "M_F_DQS_DP<17>")
	)
	(segment
		(start 245.40718 -91.555824)
		(end 245.402354 -91.547188)
		(width 0.0889)
		(layer "In4.Cu")
		(net "M_F_DQS_DP<17>")
	)
	(segment
		(start 237.655608 -142.621)
		(end 237.525052 -142.490444)
		(width 0.14224)
		(layer "In4.Cu")
		(net "M_F_DQS_DP<17>")
	)
	(segment
		(start 245.402354 -88.575388)
		(end 245.396004 -88.56472)
		(width 0.0889)
		(layer "In4.Cu")
		(net "M_F_DQS_DP<17>")
	)
	(segment
		(start 245.402354 -83.622388)
		(end 245.396004 -83.61172)
		(width 0.0889)
		(layer "In4.Cu")
		(net "M_F_DQS_DP<17>")
	)
	(segment
		(start 237.498128 -147.457922)
		(end 237.498128 -147.203922)
		(width 0.14224)
		(layer "In4.Cu")
		(net "M_F_DQS_DP<17>")
	)
	(segment
		(start 237.498128 -147.203922)
		(end 237.655608 -147.046442)
		(width 0.14224)
		(layer "In4.Cu")
		(net "M_F_DQS_DP<17>")
	)
	(segment
		(start 245.84914 -82.739738)
		(end 245.914164 -82.674714)
		(width 0.0889)
		(layer "In4.Cu")
		(net "M_F_DQS_DP<17>")
	)
	(segment
		(start 245.094252 -100.243132)
		(end 245.315994 -100.02139)
		(width 0.0889)
		(layer "In4.Cu")
		(net "M_F_DQS_DP<17>")
	)
	(segment
		(start 237.525052 -142.236444)
		(end 237.655608 -142.105888)
		(width 0.14224)
		(layer "In4.Cu")
		(net "M_F_DQS_DP<17>")
	)
	(segment
		(start 245.40718 -89.574624)
		(end 245.402354 -89.565988)
		(width 0.0889)
		(layer "In4.Cu")
		(net "M_F_DQS_DP<17>")
	)
	(segment
		(start 245.402354 -96.500188)
		(end 245.396004 -96.48952)
		(width 0.0889)
		(layer "In4.Cu")
		(net "M_F_DQS_DP<17>")
	)
	(segment
		(start 245.40718 -85.612224)
		(end 245.402354 -85.603588)
		(width 0.0889)
		(layer "In4.Cu")
		(net "M_F_DQS_DP<17>")
	)
	(segment
		(start 238.740188 -111.308388)
		(end 245.054882 -104.993694)
		(width 0.14224)
		(layer "In4.Cu")
		(net "M_F_DQS_DP<17>")
	)
	(segment
		(start 245.402354 -95.509588)
		(end 245.396004 -95.49892)
		(width 0.0889)
		(layer "In4.Cu")
		(net "M_F_DQS_DP<17>")
	)
	(segment
		(start 245.094252 -102.960678)
		(end 245.094252 -100.243132)
		(width 0.0889)
		(layer "In4.Cu")
		(net "M_F_DQS_DP<17>")
	)
	(segment
		(start 245.402354 -92.537788)
		(end 245.396004 -92.52712)
		(width 0.0889)
		(layer "In4.Cu")
		(net "M_F_DQS_DP<17>")
	)
	(segment
		(start 245.402354 -90.556588)
		(end 245.396004 -90.54592)
		(width 0.0889)
		(layer "In4.Cu")
		(net "M_F_DQS_DP<17>")
	)
	(segment
		(start 245.40718 -86.602824)
		(end 245.402354 -86.594188)
		(width 0.0889)
		(layer "In4.Cu")
		(net "M_F_DQS_DP<17>")
	)
	(segment
		(start 237.515146 -143.055848)
		(end 237.655608 -142.915386)
		(width 0.14224)
		(layer "In4.Cu")
		(net "M_F_DQS_DP<17>")
	)
	(segment
		(start 245.40718 -97.499424)
		(end 245.402354 -97.490788)
		(width 0.0889)
		(layer "In4.Cu")
		(net "M_F_DQS_DP<17>")
	)
	(segment
		(start 245.40718 -92.546424)
		(end 245.402354 -92.537788)
		(width 0.0889)
		(layer "In4.Cu")
		(net "M_F_DQS_DP<17>")
	)
	(segment
		(start 237.655608 -147.046442)
		(end 237.655608 -146.738594)
		(width 0.14224)
		(layer "In4.Cu")
		(net "M_F_DQS_DP<17>")
	)
	(segment
		(start 245.396004 -93.939106)
		(end 245.402354 -93.928438)
		(width 0.0889)
		(layer "In4.Cu")
		(net "M_F_DQS_DP<17>")
	)
	(arc
		(start 245.402354 -84.022438)
		(mid 245.455824 -83.827375)
		(end 245.40718 -83.631024)
		(width 0.0889)
		(layer "In4.Cu")
		(net "M_F_DQS_DP<17>")
	)
	(arc
		(start 245.396004 -91.53652)
		(mid 245.323206 -91.245757)
		(end 245.402354 -90.956638)
		(width 0.0889)
		(layer "In4.Cu")
		(net "M_F_DQS_DP<17>")
	)
	(arc
		(start 245.402354 -88.975438)
		(mid 245.455824 -88.780375)
		(end 245.40718 -88.584024)
		(width 0.0889)
		(layer "In4.Cu")
		(net "M_F_DQS_DP<17>")
	)
	(arc
		(start 245.402354 -95.909638)
		(mid 245.455824 -95.714575)
		(end 245.40718 -95.518224)
		(width 0.0889)
		(layer "In4.Cu")
		(net "M_F_DQS_DP<17>")
	)
	(arc
		(start 245.402354 -93.928438)
		(mid 245.455853 -93.72854)
		(end 245.402354 -93.528642)
		(width 0.0889)
		(layer "In4.Cu")
		(net "M_F_DQS_DP<17>")
	)
	(arc
		(start 245.402354 -86.003638)
		(mid 245.455824 -85.808575)
		(end 245.40718 -85.612224)
		(width 0.0889)
		(layer "In4.Cu")
		(net "M_F_DQS_DP<17>")
	)
	(arc
		(start 245.396004 -96.48952)
		(mid 245.323206 -96.198757)
		(end 245.402354 -95.909638)
		(width 0.0889)
		(layer "In4.Cu")
		(net "M_F_DQS_DP<17>")
	)
	(arc
		(start 245.402354 -96.900238)
		(mid 245.455824 -96.705175)
		(end 245.40718 -96.508824)
		(width 0.0889)
		(layer "In4.Cu")
		(net "M_F_DQS_DP<17>")
	)
	(arc
		(start 245.396004 -97.48012)
		(mid 245.323206 -97.189357)
		(end 245.402354 -96.900238)
		(width 0.0889)
		(layer "In4.Cu")
		(net "M_F_DQS_DP<17>")
	)
	(arc
		(start 245.402354 -93.528642)
		(mid 245.323223 -93.23324)
		(end 245.402354 -92.937838)
		(width 0.0889)
		(layer "In4.Cu")
		(net "M_F_DQS_DP<17>")
	)
	(arc
		(start 245.402354 -85.013038)
		(mid 245.455824 -84.817975)
		(end 245.40718 -84.621624)
		(width 0.0889)
		(layer "In4.Cu")
		(net "M_F_DQS_DP<17>")
	)
	(arc
		(start 245.402354 -86.994238)
		(mid 245.455824 -86.799175)
		(end 245.40718 -86.602824)
		(width 0.0889)
		(layer "In4.Cu")
		(net "M_F_DQS_DP<17>")
	)
	(arc
		(start 245.396004 -98.47072)
		(mid 245.323206 -98.179957)
		(end 245.402354 -97.890838)
		(width 0.0889)
		(layer "In4.Cu")
		(net "M_F_DQS_DP<17>")
	)
	(arc
		(start 245.402354 -97.890838)
		(mid 245.455824 -97.695775)
		(end 245.40718 -97.499424)
		(width 0.0889)
		(layer "In4.Cu")
		(net "M_F_DQS_DP<17>")
	)
	(arc
		(start 245.402354 -92.937838)
		(mid 245.455824 -92.742775)
		(end 245.40718 -92.546424)
		(width 0.0889)
		(layer "In4.Cu")
		(net "M_F_DQS_DP<17>")
	)
	(arc
		(start 245.396004 -95.49892)
		(mid 245.323206 -95.208157)
		(end 245.402354 -94.919038)
		(width 0.0889)
		(layer "In4.Cu")
		(net "M_F_DQS_DP<17>")
	)
	(arc
		(start 245.402354 -94.518988)
		(mid 245.323132 -94.22987)
		(end 245.396004 -93.939106)
		(width 0.0889)
		(layer "In4.Cu")
		(net "M_F_DQS_DP<17>")
	)
	(arc
		(start 245.402354 -91.947238)
		(mid 245.455824 -91.752175)
		(end 245.40718 -91.555824)
		(width 0.0889)
		(layer "In4.Cu")
		(net "M_F_DQS_DP<17>")
	)
	(arc
		(start 245.402354 -89.966038)
		(mid 245.455824 -89.770975)
		(end 245.40718 -89.574624)
		(width 0.0889)
		(layer "In4.Cu")
		(net "M_F_DQS_DP<17>")
	)
	(arc
		(start 245.405402 -99.866196)
		(mid 245.455741 -99.668814)
		(end 245.402354 -99.472242)
		(width 0.0889)
		(layer "In4.Cu")
		(net "M_F_DQS_DP<17>")
	)
	(arc
		(start 245.402354 -99.472242)
		(mid 245.323223 -99.17684)
		(end 245.402354 -98.881438)
		(width 0.0889)
		(layer "In4.Cu")
		(net "M_F_DQS_DP<17>")
	)
	(arc
		(start 245.402354 -94.919038)
		(mid 245.455824 -94.723975)
		(end 245.40718 -94.527624)
		(width 0.0889)
		(layer "In4.Cu")
		(net "M_F_DQS_DP<17>")
	)
	(arc
		(start 245.396004 -89.55532)
		(mid 245.323206 -89.264557)
		(end 245.402354 -88.975438)
		(width 0.0889)
		(layer "In4.Cu")
		(net "M_F_DQS_DP<17>")
	)
	(arc
		(start 245.396004 -90.54592)
		(mid 245.323206 -90.255157)
		(end 245.402354 -89.966038)
		(width 0.0889)
		(layer "In4.Cu")
		(net "M_F_DQS_DP<17>")
	)
	(arc
		(start 245.396004 -86.58352)
		(mid 245.323206 -86.292757)
		(end 245.402354 -86.003638)
		(width 0.0889)
		(layer "In4.Cu")
		(net "M_F_DQS_DP<17>")
	)
	(arc
		(start 245.396004 -87.57412)
		(mid 245.323206 -87.283357)
		(end 245.402354 -86.994238)
		(width 0.0889)
		(layer "In4.Cu")
		(net "M_F_DQS_DP<17>")
	)
	(arc
		(start 245.396004 -84.60232)
		(mid 245.323206 -84.311557)
		(end 245.402354 -84.022438)
		(width 0.0889)
		(layer "In4.Cu")
		(net "M_F_DQS_DP<17>")
	)
	(arc
		(start 245.396004 -83.61172)
		(mid 245.389639 -83.054674)
		(end 245.84914 -82.739738)
		(width 0.0889)
		(layer "In4.Cu")
		(net "M_F_DQS_DP<17>")
	)
	(arc
		(start 245.396004 -88.56472)
		(mid 245.323206 -88.273957)
		(end 245.402354 -87.984838)
		(width 0.0889)
		(layer "In4.Cu")
		(net "M_F_DQS_DP<17>")
	)
	(arc
		(start 245.402354 -90.956638)
		(mid 245.455824 -90.761575)
		(end 245.40718 -90.565224)
		(width 0.0889)
		(layer "In4.Cu")
		(net "M_F_DQS_DP<17>")
	)
	(arc
		(start 245.396004 -85.59292)
		(mid 245.323206 -85.302157)
		(end 245.402354 -85.013038)
		(width 0.0889)
		(layer "In4.Cu")
		(net "M_F_DQS_DP<17>")
	)
	(arc
		(start 245.396004 -92.52712)
		(mid 245.323206 -92.236357)
		(end 245.402354 -91.947238)
		(width 0.0889)
		(layer "In4.Cu")
		(net "M_F_DQS_DP<17>")
	)
	(arc
		(start 245.402354 -87.984838)
		(mid 245.455824 -87.789775)
		(end 245.40718 -87.593424)
		(width 0.0889)
		(layer "In4.Cu")
		(net "M_F_DQS_DP<17>")
	)
	(arc
		(start 245.402354 -98.881438)
		(mid 245.455824 -98.686375)
		(end 245.40718 -98.490024)
		(width 0.0889)
		(layer "In4.Cu")
		(net "M_F_DQS_DP<17>")
	)
	(segment
		(start 237.142528 -154.939746)
		(end 236.637576 -154.434794)
		(width 0.14224)
		(layer "In11.Cu")
		(net "M_F_DQS_DP<17>")
	)
	(segment
		(start 236.637576 -154.434794)
		(end 236.637576 -149.933152)
		(width 0.14224)
		(layer "In11.Cu")
		(net "M_F_DQS_DP<17>")
	)
	(segment
		(start 236.637576 -149.933152)
		(end 237.142528 -149.4282)
		(width 0.14224)
		(layer "In11.Cu")
		(net "M_F_DQS_DP<17>")
	)
	(segment
		(start 310.713882 -153.331672)
		(end 310.6293 -153.515568)
		(width 0.1651)
		(layer "F.Cu")
		(net "M_F_DQS_DP<16>")
	)
	(segment
		(start 310.6293 -154.333702)
		(end 310.710834 -154.557984)
		(width 0.1651)
		(layer "F.Cu")
		(net "M_F_DQS_DP<16>")
	)
	(segment
		(start 310.710834 -154.557984)
		(end 311.092596 -154.939746)
		(width 0.1651)
		(layer "F.Cu")
		(net "M_F_DQS_DP<16>")
	)
	(segment
		(start 311.15 -152.895554)
		(end 310.713882 -153.331672)
		(width 0.1651)
		(layer "F.Cu")
		(net "M_F_DQS_DP<16>")
	)
	(segment
		(start 311.150508 -152.273)
		(end 311.15 -152.278842)
		(width 0.1651)
		(layer "F.Cu")
		(net "M_F_DQS_DP<16>")
	)
	(segment
		(start 311.15 -152.278842)
		(end 311.15 -152.895554)
		(width 0.1651)
		(layer "F.Cu")
		(net "M_F_DQS_DP<16>")
	)
	(segment
		(start 283.212794 -89.584784)
		(end 283.784294 -89.584784)
		(width 0.1651)
		(layer "F.Cu")
		(net "M_F_DQS_DP<16>")
	)
	(segment
		(start 310.6293 -153.515568)
		(end 310.6293 -154.333702)
		(width 0.1651)
		(layer "F.Cu")
		(net "M_F_DQS_DP<16>")
	)
	(via
		(at 311.092596 -154.939746)
		(size 0.508)
		(drill 0.254)
		(layers "F.Cu" "B.Cu")
		(net "M_F_DQS_DP<16>")
	)
	(via
		(at 311.092596 -149.4282)
		(size 0.508)
		(drill 0.254)
		(layers "F.Cu" "B.Cu")
		(net "M_F_DQS_DP<16>")
	)
	(via
		(at 283.784294 -89.584784)
		(size 0.508)
		(drill 0.254)
		(layers "F.Cu" "B.Cu")
		(net "M_F_DQS_DP<16>")
	)
	(segment
		(start 310.693816 -151.00427)
		(end 310.6166 -150.871936)
		(width 0.1651)
		(layer "B.Cu")
		(net "M_F_DQS_DP<16>")
	)
	(segment
		(start 310.6166 -149.976332)
		(end 310.703976 -149.81682)
		(width 0.1651)
		(layer "B.Cu")
		(net "M_F_DQS_DP<16>")
	)
	(segment
		(start 310.6166 -150.871936)
		(end 310.6166 -149.976332)
		(width 0.1651)
		(layer "B.Cu")
		(net "M_F_DQS_DP<16>")
	)
	(segment
		(start 310.703976 -149.81682)
		(end 311.092596 -149.4282)
		(width 0.1651)
		(layer "B.Cu")
		(net "M_F_DQS_DP<16>")
	)
	(segment
		(start 311.15 -151.460454)
		(end 310.693816 -151.00427)
		(width 0.1651)
		(layer "B.Cu")
		(net "M_F_DQS_DP<16>")
	)
	(segment
		(start 311.15 -152.078182)
		(end 311.15 -151.460454)
		(width 0.1651)
		(layer "B.Cu")
		(net "M_F_DQS_DP<16>")
	)
	(segment
		(start 311.150508 -152.078436)
		(end 311.15 -152.078182)
		(width 0.1651)
		(layer "B.Cu")
		(net "M_F_DQS_DP<16>")
	)
	(segment
		(start 310.587644 -149.86)
		(end 310.587644 -154.434794)
		(width 0.14224)
		(layer "In11.Cu")
		(net "M_F_DQS_DP<16>")
	)
	(segment
		(start 288.42335 -97.214436)
		(end 288.417 -97.225104)
		(width 0.0889)
		(layer "In11.Cu")
		(net "M_F_DQS_DP<16>")
	)
	(segment
		(start 311.605676 -146.834606)
		(end 311.605676 -147.13839)
		(width 0.14224)
		(layer "In11.Cu")
		(net "M_F_DQS_DP<16>")
	)
	(segment
		(start 283.272484 -92.261436)
		(end 283.266134 -92.272104)
		(width 0.0889)
		(layer "In11.Cu")
		(net "M_F_DQS_DP<16>")
	)
	(segment
		(start 311.605676 -146.38655)
		(end 311.508648 -146.483578)
		(width 0.14224)
		(layer "In11.Cu")
		(net "M_F_DQS_DP<16>")
	)
	(segment
		(start 297.705018 -111.209582)
		(end 297.705018 -112.80394)
		(width 0.14224)
		(layer "In11.Cu")
		(net "M_F_DQS_DP<16>")
	)
	(segment
		(start 289.787584 -104.502712)
		(end 289.787584 -104.52481)
		(width 0.0889)
		(layer "In11.Cu")
		(net "M_F_DQS_DP<16>")
	)
	(segment
		(start 311.508648 -146.483578)
		(end 311.508648 -146.737578)
		(width 0.14224)
		(layer "In11.Cu")
		(net "M_F_DQS_DP<16>")
	)
	(segment
		(start 288.428176 -100.1776)
		(end 288.42335 -100.186236)
		(width 0.0889)
		(layer "In11.Cu")
		(net "M_F_DQS_DP<16>")
	)
	(segment
		(start 311.476644 -148.11883)
		(end 311.476644 -148.37283)
		(width 0.14224)
		(layer "In11.Cu")
		(net "M_F_DQS_DP<16>")
	)
	(segment
		(start 301.525432 -113.25352)
		(end 311.605676 -123.333764)
		(width 0.14224)
		(layer "In11.Cu")
		(net "M_F_DQS_DP<16>")
	)
	(segment
		(start 311.019444 -149.4282)
		(end 310.587644 -149.86)
		(width 0.14224)
		(layer "In11.Cu")
		(net "M_F_DQS_DP<16>")
	)
	(segment
		(start 289.787584 -104.52481)
		(end 289.787584 -104.900984)
		(width 0.14224)
		(layer "In11.Cu")
		(net "M_F_DQS_DP<16>")
	)
	(segment
		(start 288.428176 -102.1588)
		(end 288.42335 -102.167436)
		(width 0.0889)
		(layer "In11.Cu")
		(net "M_F_DQS_DP<16>")
	)
	(segment
		(start 287.19653 -96.118934)
		(end 287.229296 -96.118934)
		(width 0.0889)
		(layer "In11.Cu")
		(net "M_F_DQS_DP<16>")
	)
	(segment
		(start 297.705018 -112.80394)
		(end 298.154598 -113.25352)
		(width 0.14224)
		(layer "In11.Cu")
		(net "M_F_DQS_DP<16>")
	)
	(segment
		(start 311.605676 -123.333764)
		(end 311.605676 -146.38655)
		(width 0.14224)
		(layer "In11.Cu")
		(net "M_F_DQS_DP<16>")
	)
	(segment
		(start 283.784294 -89.584784)
		(end 283.784294 -89.922858)
		(width 0.0889)
		(layer "In11.Cu")
		(net "M_F_DQS_DP<16>")
	)
	(segment
		(start 288.428176 -97.2058)
		(end 288.42335 -97.214436)
		(width 0.0889)
		(layer "In11.Cu")
		(net "M_F_DQS_DP<16>")
	)
	(segment
		(start 311.605676 -147.989798)
		(end 311.476644 -148.11883)
		(width 0.14224)
		(layer "In11.Cu")
		(net "M_F_DQS_DP<16>")
	)
	(segment
		(start 289.826954 -104.463342)
		(end 289.787584 -104.502712)
		(width 0.0889)
		(layer "In11.Cu")
		(net "M_F_DQS_DP<16>")
	)
	(segment
		(start 288.42335 -98.205036)
		(end 288.417 -98.215704)
		(width 0.0889)
		(layer "In11.Cu")
		(net "M_F_DQS_DP<16>")
	)
	(segment
		(start 288.428176 -99.187)
		(end 288.42335 -99.195636)
		(width 0.0889)
		(layer "In11.Cu")
		(net "M_F_DQS_DP<16>")
	)
	(segment
		(start 283.272484 -91.270836)
		(end 283.266134 -91.281504)
		(width 0.0889)
		(layer "In11.Cu")
		(net "M_F_DQS_DP<16>")
	)
	(segment
		(start 311.605676 -149.19452)
		(end 311.371996 -149.4282)
		(width 0.14224)
		(layer "In11.Cu")
		(net "M_F_DQS_DP<16>")
	)
	(segment
		(start 292.61562 -107.72902)
		(end 294.224456 -107.72902)
		(width 0.14224)
		(layer "In11.Cu")
		(net "M_F_DQS_DP<16>")
	)
	(segment
		(start 283.784294 -89.922858)
		(end 283.719016 -89.988136)
		(width 0.0889)
		(layer "In11.Cu")
		(net "M_F_DQS_DP<16>")
	)
	(segment
		(start 288.42335 -99.195636)
		(end 288.417 -99.206304)
		(width 0.0889)
		(layer "In11.Cu")
		(net "M_F_DQS_DP<16>")
	)
	(segment
		(start 310.587644 -154.434794)
		(end 311.092596 -154.939746)
		(width 0.14224)
		(layer "In11.Cu")
		(net "M_F_DQS_DP<16>")
	)
	(segment
		(start 285.483554 -95.128588)
		(end 285.513526 -95.128588)
		(width 0.0889)
		(layer "In11.Cu")
		(net "M_F_DQS_DP<16>")
	)
	(segment
		(start 289.787584 -104.900984)
		(end 292.61562 -107.72902)
		(width 0.14224)
		(layer "In11.Cu")
		(net "M_F_DQS_DP<16>")
	)
	(segment
		(start 284.621224 -94.633288)
		(end 284.660848 -94.633288)
		(width 0.0889)
		(layer "In11.Cu")
		(net "M_F_DQS_DP<16>")
	)
	(segment
		(start 311.092596 -149.4282)
		(end 311.019444 -149.4282)
		(width 0.14224)
		(layer "In11.Cu")
		(net "M_F_DQS_DP<16>")
	)
	(segment
		(start 311.605676 -147.70735)
		(end 311.605676 -147.989798)
		(width 0.14224)
		(layer "In11.Cu")
		(net "M_F_DQS_DP<16>")
	)
	(segment
		(start 283.77134 -94.137988)
		(end 283.79547 -94.137988)
		(width 0.0889)
		(layer "In11.Cu")
		(net "M_F_DQS_DP<16>")
	)
	(segment
		(start 298.154598 -113.25352)
		(end 301.525432 -113.25352)
		(width 0.14224)
		(layer "In11.Cu")
		(net "M_F_DQS_DP<16>")
	)
	(segment
		(start 288.05886 -96.614488)
		(end 288.091626 -96.614488)
		(width 0.0889)
		(layer "In11.Cu")
		(net "M_F_DQS_DP<16>")
	)
	(segment
		(start 286.346646 -95.623888)
		(end 286.374586 -95.623888)
		(width 0.0889)
		(layer "In11.Cu")
		(net "M_F_DQS_DP<16>")
	)
	(segment
		(start 288.428176 -98.1964)
		(end 288.42335 -98.205036)
		(width 0.0889)
		(layer "In11.Cu")
		(net "M_F_DQS_DP<16>")
	)
	(segment
		(start 311.371996 -149.4282)
		(end 311.092596 -149.4282)
		(width 0.14224)
		(layer "In11.Cu")
		(net "M_F_DQS_DP<16>")
	)
	(segment
		(start 311.448196 -147.54987)
		(end 311.605676 -147.70735)
		(width 0.14224)
		(layer "In11.Cu")
		(net "M_F_DQS_DP<16>")
	)
	(segment
		(start 289.826954 -103.599742)
		(end 289.826954 -104.463342)
		(width 0.0889)
		(layer "In11.Cu")
		(net "M_F_DQS_DP<16>")
	)
	(segment
		(start 311.605676 -147.13839)
		(end 311.448196 -147.29587)
		(width 0.14224)
		(layer "In11.Cu")
		(net "M_F_DQS_DP<16>")
	)
	(segment
		(start 283.27731 -93.2434)
		(end 283.272484 -93.252036)
		(width 0.0889)
		(layer "In11.Cu")
		(net "M_F_DQS_DP<16>")
	)
	(segment
		(start 288.42335 -102.167436)
		(end 288.417 -102.178104)
		(width 0.0889)
		(layer "In11.Cu")
		(net "M_F_DQS_DP<16>")
	)
	(segment
		(start 294.224456 -107.72902)
		(end 297.705018 -111.209582)
		(width 0.14224)
		(layer "In11.Cu")
		(net "M_F_DQS_DP<16>")
	)
	(segment
		(start 311.448196 -147.29587)
		(end 311.448196 -147.54987)
		(width 0.14224)
		(layer "In11.Cu")
		(net "M_F_DQS_DP<16>")
	)
	(segment
		(start 311.508648 -146.737578)
		(end 311.605676 -146.834606)
		(width 0.14224)
		(layer "In11.Cu")
		(net "M_F_DQS_DP<16>")
	)
	(segment
		(start 283.27731 -92.2528)
		(end 283.272484 -92.261436)
		(width 0.0889)
		(layer "In11.Cu")
		(net "M_F_DQS_DP<16>")
	)
	(segment
		(start 283.27731 -91.2622)
		(end 283.272484 -91.270836)
		(width 0.0889)
		(layer "In11.Cu")
		(net "M_F_DQS_DP<16>")
	)
	(segment
		(start 311.476644 -148.37283)
		(end 311.605676 -148.501862)
		(width 0.14224)
		(layer "In11.Cu")
		(net "M_F_DQS_DP<16>")
	)
	(segment
		(start 311.605676 -148.501862)
		(end 311.605676 -149.19452)
		(width 0.14224)
		(layer "In11.Cu")
		(net "M_F_DQS_DP<16>")
	)
	(segment
		(start 289.7759 -103.548688)
		(end 289.826954 -103.599742)
		(width 0.0889)
		(layer "In11.Cu")
		(net "M_F_DQS_DP<16>")
	)
	(segment
		(start 283.272484 -93.252036)
		(end 283.266134 -93.262704)
		(width 0.0889)
		(layer "In11.Cu")
		(net "M_F_DQS_DP<16>")
	)
	(segment
		(start 288.91357 -103.053134)
		(end 288.946336 -103.053134)
		(width 0.0889)
		(layer "In11.Cu")
		(net "M_F_DQS_DP<16>")
	)
	(segment
		(start 288.42335 -101.176836)
		(end 288.417 -101.187504)
		(width 0.0889)
		(layer "In11.Cu")
		(net "M_F_DQS_DP<16>")
	)
	(arc
		(start 288.417 -101.187504)
		(mid 288.344202 -101.478267)
		(end 288.42335 -101.767386)
		(width 0.0889)
		(layer "In11.Cu")
		(net "M_F_DQS_DP<16>")
	)
	(arc
		(start 288.417 -97.225104)
		(mid 288.344202 -97.515867)
		(end 288.42335 -97.804986)
		(width 0.0889)
		(layer "In11.Cu")
		(net "M_F_DQS_DP<16>")
	)
	(arc
		(start 288.091626 -96.614488)
		(mid 288.424544 -96.816479)
		(end 288.428176 -97.2058)
		(width 0.0889)
		(layer "In11.Cu")
		(net "M_F_DQS_DP<16>")
	)
	(arc
		(start 288.417 -102.178104)
		(mid 288.421031 -102.754286)
		(end 288.91357 -103.053134)
		(width 0.0889)
		(layer "In11.Cu")
		(net "M_F_DQS_DP<16>")
	)
	(arc
		(start 285.513526 -95.128588)
		(mid 285.706629 -95.185107)
		(end 285.84779 -95.328486)
		(width 0.0889)
		(layer "In11.Cu")
		(net "M_F_DQS_DP<16>")
	)
	(arc
		(start 286.374586 -95.623888)
		(mid 286.566228 -95.681054)
		(end 286.70631 -95.823786)
		(width 0.0889)
		(layer "In11.Cu")
		(net "M_F_DQS_DP<16>")
	)
	(arc
		(start 288.946336 -103.053134)
		(mid 289.140186 -103.109484)
		(end 289.28187 -103.253286)
		(width 0.0889)
		(layer "In11.Cu")
		(net "M_F_DQS_DP<16>")
	)
	(arc
		(start 288.42335 -100.186236)
		(mid 288.344219 -100.481638)
		(end 288.42335 -100.77704)
		(width 0.0889)
		(layer "In11.Cu")
		(net "M_F_DQS_DP<16>")
	)
	(arc
		(start 289.28187 -103.253286)
		(mid 289.490478 -103.465218)
		(end 289.7759 -103.548688)
		(width 0.0889)
		(layer "In11.Cu")
		(net "M_F_DQS_DP<16>")
	)
	(arc
		(start 283.272484 -91.861386)
		(mid 283.325954 -92.056449)
		(end 283.27731 -92.2528)
		(width 0.0889)
		(layer "In11.Cu")
		(net "M_F_DQS_DP<16>")
	)
	(arc
		(start 288.417 -98.215704)
		(mid 288.344202 -98.506467)
		(end 288.42335 -98.795586)
		(width 0.0889)
		(layer "In11.Cu")
		(net "M_F_DQS_DP<16>")
	)
	(arc
		(start 288.417 -99.206304)
		(mid 288.344202 -99.497067)
		(end 288.42335 -99.786186)
		(width 0.0889)
		(layer "In11.Cu")
		(net "M_F_DQS_DP<16>")
	)
	(arc
		(start 288.42335 -99.786186)
		(mid 288.47682 -99.981249)
		(end 288.428176 -100.1776)
		(width 0.0889)
		(layer "In11.Cu")
		(net "M_F_DQS_DP<16>")
	)
	(arc
		(start 286.70631 -95.823786)
		(mid 286.913314 -96.03465)
		(end 287.19653 -96.118934)
		(width 0.0889)
		(layer "In11.Cu")
		(net "M_F_DQS_DP<16>")
	)
	(arc
		(start 287.229296 -96.118934)
		(mid 287.423146 -96.175284)
		(end 287.56483 -96.319086)
		(width 0.0889)
		(layer "In11.Cu")
		(net "M_F_DQS_DP<16>")
	)
	(arc
		(start 283.79547 -94.137988)
		(mid 283.98932 -94.194338)
		(end 284.131004 -94.33814)
		(width 0.0889)
		(layer "In11.Cu")
		(net "M_F_DQS_DP<16>")
	)
	(arc
		(start 283.266134 -92.272104)
		(mid 283.193336 -92.562867)
		(end 283.272484 -92.851986)
		(width 0.0889)
		(layer "In11.Cu")
		(net "M_F_DQS_DP<16>")
	)
	(arc
		(start 284.131004 -94.33814)
		(mid 284.338008 -94.549004)
		(end 284.621224 -94.633288)
		(width 0.0889)
		(layer "In11.Cu")
		(net "M_F_DQS_DP<16>")
	)
	(arc
		(start 288.42335 -98.795586)
		(mid 288.47682 -98.990649)
		(end 288.428176 -99.187)
		(width 0.0889)
		(layer "In11.Cu")
		(net "M_F_DQS_DP<16>")
	)
	(arc
		(start 283.266134 -91.281504)
		(mid 283.193336 -91.572267)
		(end 283.272484 -91.861386)
		(width 0.0889)
		(layer "In11.Cu")
		(net "M_F_DQS_DP<16>")
	)
	(arc
		(start 283.272484 -90.870786)
		(mid 283.325954 -91.065849)
		(end 283.27731 -91.2622)
		(width 0.0889)
		(layer "In11.Cu")
		(net "M_F_DQS_DP<16>")
	)
	(arc
		(start 283.266134 -93.262704)
		(mid 283.272311 -93.842636)
		(end 283.77134 -94.137988)
		(width 0.0889)
		(layer "In11.Cu")
		(net "M_F_DQS_DP<16>")
	)
	(arc
		(start 285.84779 -95.328486)
		(mid 286.058503 -95.541565)
		(end 286.346646 -95.623888)
		(width 0.0889)
		(layer "In11.Cu")
		(net "M_F_DQS_DP<16>")
	)
	(arc
		(start 284.660848 -94.633288)
		(mid 284.850777 -94.691158)
		(end 284.989524 -94.833186)
		(width 0.0889)
		(layer "In11.Cu")
		(net "M_F_DQS_DP<16>")
	)
	(arc
		(start 288.42335 -101.767386)
		(mid 288.47682 -101.962449)
		(end 288.428176 -102.1588)
		(width 0.0889)
		(layer "In11.Cu")
		(net "M_F_DQS_DP<16>")
	)
	(arc
		(start 283.719016 -89.988136)
		(mid 283.257047 -90.308678)
		(end 283.272484 -90.870786)
		(width 0.0889)
		(layer "In11.Cu")
		(net "M_F_DQS_DP<16>")
	)
	(arc
		(start 288.42335 -100.77704)
		(mid 288.476849 -100.976938)
		(end 288.42335 -101.176836)
		(width 0.0889)
		(layer "In11.Cu")
		(net "M_F_DQS_DP<16>")
	)
	(arc
		(start 287.56483 -96.319086)
		(mid 287.773438 -96.531018)
		(end 288.05886 -96.614488)
		(width 0.0889)
		(layer "In11.Cu")
		(net "M_F_DQS_DP<16>")
	)
	(arc
		(start 283.272484 -92.851986)
		(mid 283.325954 -93.047049)
		(end 283.27731 -93.2434)
		(width 0.0889)
		(layer "In11.Cu")
		(net "M_F_DQS_DP<16>")
	)
	(arc
		(start 284.989524 -94.833186)
		(mid 285.198132 -95.045118)
		(end 285.483554 -95.128588)
		(width 0.0889)
		(layer "In11.Cu")
		(net "M_F_DQS_DP<16>")
	)
	(arc
		(start 288.42335 -97.804986)
		(mid 288.47682 -98.000049)
		(end 288.428176 -98.1964)
		(width 0.0889)
		(layer "In11.Cu")
		(net "M_F_DQS_DP<16>")
	)
	(segment
		(start 301.279306 -154.333702)
		(end 301.36084 -154.557984)
		(width 0.1651)
		(layer "F.Cu")
		(net "M_F_DQS_DP<15>")
	)
	(segment
		(start 301.800514 -152.273)
		(end 301.800006 -152.278842)
		(width 0.1651)
		(layer "F.Cu")
		(net "M_F_DQS_DP<15>")
	)
	(segment
		(start 301.279306 -153.515568)
		(end 301.279306 -154.333702)
		(width 0.1651)
		(layer "F.Cu")
		(net "M_F_DQS_DP<15>")
	)
	(segment
		(start 301.36084 -154.557984)
		(end 301.742602 -154.939746)
		(width 0.1651)
		(layer "F.Cu")
		(net "M_F_DQS_DP<15>")
	)
	(segment
		(start 278.061674 -89.584784)
		(end 278.633174 -89.584784)
		(width 0.1651)
		(layer "F.Cu")
		(net "M_F_DQS_DP<15>")
	)
	(segment
		(start 301.363888 -153.331672)
		(end 301.279306 -153.515568)
		(width 0.1651)
		(layer "F.Cu")
		(net "M_F_DQS_DP<15>")
	)
	(segment
		(start 301.800006 -152.278842)
		(end 301.800006 -152.895554)
		(width 0.1651)
		(layer "F.Cu")
		(net "M_F_DQS_DP<15>")
	)
	(segment
		(start 301.800006 -152.895554)
		(end 301.363888 -153.331672)
		(width 0.1651)
		(layer "F.Cu")
		(net "M_F_DQS_DP<15>")
	)
	(via
		(at 301.742602 -154.939746)
		(size 0.508)
		(drill 0.254)
		(layers "F.Cu" "B.Cu")
		(net "M_F_DQS_DP<15>")
	)
	(via
		(at 301.742602 -149.4282)
		(size 0.508)
		(drill 0.254)
		(layers "F.Cu" "B.Cu")
		(net "M_F_DQS_DP<15>")
	)
	(via
		(at 278.633174 -89.584784)
		(size 0.508)
		(drill 0.254)
		(layers "F.Cu" "B.Cu")
		(net "M_F_DQS_DP<15>")
	)
	(segment
		(start 301.800514 -152.078436)
		(end 301.800006 -152.078182)
		(width 0.1651)
		(layer "B.Cu")
		(net "M_F_DQS_DP<15>")
	)
	(segment
		(start 301.800006 -152.078182)
		(end 301.800006 -151.460454)
		(width 0.1651)
		(layer "B.Cu")
		(net "M_F_DQS_DP<15>")
	)
	(segment
		(start 301.266606 -149.976332)
		(end 301.353982 -149.81682)
		(width 0.1651)
		(layer "B.Cu")
		(net "M_F_DQS_DP<15>")
	)
	(segment
		(start 301.353982 -149.81682)
		(end 301.742602 -149.4282)
		(width 0.1651)
		(layer "B.Cu")
		(net "M_F_DQS_DP<15>")
	)
	(segment
		(start 301.800006 -151.460454)
		(end 301.343822 -151.00427)
		(width 0.1651)
		(layer "B.Cu")
		(net "M_F_DQS_DP<15>")
	)
	(segment
		(start 301.266606 -150.871936)
		(end 301.266606 -149.976332)
		(width 0.1651)
		(layer "B.Cu")
		(net "M_F_DQS_DP<15>")
	)
	(segment
		(start 301.343822 -151.00427)
		(end 301.266606 -150.871936)
		(width 0.1651)
		(layer "B.Cu")
		(net "M_F_DQS_DP<15>")
	)
	(segment
		(start 282.045664 -99.090734)
		(end 282.07843 -99.090734)
		(width 0.0889)
		(layer "In11.Cu")
		(net "M_F_DQS_DP<15>")
	)
	(segment
		(start 282.405074 -104.228646)
		(end 282.420822 -104.256078)
		(width 0.0889)
		(layer "In11.Cu")
		(net "M_F_DQS_DP<15>")
	)
	(segment
		(start 278.12619 -94.234)
		(end 278.121364 -94.242636)
		(width 0.0889)
		(layer "In11.Cu")
		(net "M_F_DQS_DP<15>")
	)
	(segment
		(start 278.121364 -93.252036)
		(end 278.115014 -93.262704)
		(width 0.0889)
		(layer "In11.Cu")
		(net "M_F_DQS_DP<15>")
	)
	(segment
		(start 282.405074 -103.238046)
		(end 282.420822 -103.265478)
		(width 0.0889)
		(layer "In11.Cu")
		(net "M_F_DQS_DP<15>")
	)
	(segment
		(start 282.413964 -99.690682)
		(end 282.407614 -99.70135)
		(width 0.0889)
		(layer "In11.Cu")
		(net "M_F_DQS_DP<15>")
	)
	(segment
		(start 302.255682 -124.42444)
		(end 302.255682 -146.38274)
		(width 0.14224)
		(layer "In11.Cu")
		(net "M_F_DQS_DP<15>")
	)
	(segment
		(start 282.419806 -105.624122)
		(end 282.293822 -105.842308)
		(width 0.0889)
		(layer "In11.Cu")
		(net "M_F_DQS_DP<15>")
	)
	(segment
		(start 282.254452 -107.188)
		(end 282.254452 -113.242852)
		(width 0.14224)
		(layer "In11.Cu")
		(net "M_F_DQS_DP<15>")
	)
	(segment
		(start 278.121364 -92.261436)
		(end 278.115014 -92.272104)
		(width 0.0889)
		(layer "In11.Cu")
		(net "M_F_DQS_DP<15>")
	)
	(segment
		(start 282.405074 -105.219246)
		(end 282.406852 -105.221532)
		(width 0.0889)
		(layer "In11.Cu")
		(net "M_F_DQS_DP<15>")
	)
	(segment
		(start 301.23765 -154.434794)
		(end 301.742602 -154.939746)
		(width 0.14224)
		(layer "In11.Cu")
		(net "M_F_DQS_DP<15>")
	)
	(segment
		(start 280.328624 -98.100134)
		(end 280.36139 -98.100134)
		(width 0.0889)
		(layer "In11.Cu")
		(net "M_F_DQS_DP<15>")
	)
	(segment
		(start 298.691554 -120.860312)
		(end 302.255682 -124.42444)
		(width 0.14224)
		(layer "In11.Cu")
		(net "M_F_DQS_DP<15>")
	)
	(segment
		(start 282.293822 -107.126532)
		(end 282.254452 -107.165902)
		(width 0.0889)
		(layer "In11.Cu")
		(net "M_F_DQS_DP<15>")
	)
	(segment
		(start 301.66945 -149.4282)
		(end 301.23765 -149.86)
		(width 0.14224)
		(layer "In11.Cu")
		(net "M_F_DQS_DP<15>")
	)
	(segment
		(start 282.41879 -101.662992)
		(end 282.413964 -101.671628)
		(width 0.0889)
		(layer "In11.Cu")
		(net "M_F_DQS_DP<15>")
	)
	(segment
		(start 302.255682 -147.982432)
		(end 302.098202 -148.139912)
		(width 0.14224)
		(layer "In11.Cu")
		(net "M_F_DQS_DP<15>")
	)
	(segment
		(start 302.140874 -146.751548)
		(end 302.255682 -146.866356)
		(width 0.14224)
		(layer "In11.Cu")
		(net "M_F_DQS_DP<15>")
	)
	(segment
		(start 282.413964 -100.681028)
		(end 282.407614 -100.691696)
		(width 0.0889)
		(layer "In11.Cu")
		(net "M_F_DQS_DP<15>")
	)
	(segment
		(start 302.098202 -148.139912)
		(end 302.098202 -148.393912)
		(width 0.14224)
		(layer "In11.Cu")
		(net "M_F_DQS_DP<15>")
	)
	(segment
		(start 289.871912 -120.860312)
		(end 298.691554 -120.860312)
		(width 0.14224)
		(layer "In11.Cu")
		(net "M_F_DQS_DP<15>")
	)
	(segment
		(start 282.293822 -105.842308)
		(end 282.293822 -107.126532)
		(width 0.0889)
		(layer "In11.Cu")
		(net "M_F_DQS_DP<15>")
	)
	(segment
		(start 301.921926 -149.4282)
		(end 301.742602 -149.4282)
		(width 0.14224)
		(layer "In11.Cu")
		(net "M_F_DQS_DP<15>")
	)
	(segment
		(start 282.413964 -102.262432)
		(end 282.41879 -102.271068)
		(width 0.0889)
		(layer "In11.Cu")
		(net "M_F_DQS_DP<15>")
	)
	(segment
		(start 278.633174 -89.584784)
		(end 278.633174 -89.922858)
		(width 0.0889)
		(layer "In11.Cu")
		(net "M_F_DQS_DP<15>")
	)
	(segment
		(start 282.254452 -113.242852)
		(end 289.871912 -120.860312)
		(width 0.14224)
		(layer "In11.Cu")
		(net "M_F_DQS_DP<15>")
	)
	(segment
		(start 302.255682 -147.728432)
		(end 302.255682 -147.982432)
		(width 0.14224)
		(layer "In11.Cu")
		(net "M_F_DQS_DP<15>")
	)
	(segment
		(start 302.098202 -147.570952)
		(end 302.255682 -147.728432)
		(width 0.14224)
		(layer "In11.Cu")
		(net "M_F_DQS_DP<15>")
	)
	(segment
		(start 302.098202 -148.393912)
		(end 302.255682 -148.551392)
		(width 0.14224)
		(layer "In11.Cu")
		(net "M_F_DQS_DP<15>")
	)
	(segment
		(start 302.255682 -148.551392)
		(end 302.255682 -149.094444)
		(width 0.14224)
		(layer "In11.Cu")
		(net "M_F_DQS_DP<15>")
	)
	(segment
		(start 282.406852 -105.221532)
		(end 282.421076 -105.246678)
		(width 0.0889)
		(layer "In11.Cu")
		(net "M_F_DQS_DP<15>")
	)
	(segment
		(start 278.12619 -92.2528)
		(end 278.121364 -92.261436)
		(width 0.0889)
		(layer "In11.Cu")
		(net "M_F_DQS_DP<15>")
	)
	(segment
		(start 302.255682 -149.094444)
		(end 301.921926 -149.4282)
		(width 0.14224)
		(layer "In11.Cu")
		(net "M_F_DQS_DP<15>")
	)
	(segment
		(start 278.12619 -96.2152)
		(end 278.121364 -96.223836)
		(width 0.0889)
		(layer "In11.Cu")
		(net "M_F_DQS_DP<15>")
	)
	(segment
		(start 302.255682 -146.866356)
		(end 302.255682 -147.159472)
		(width 0.14224)
		(layer "In11.Cu")
		(net "M_F_DQS_DP<15>")
	)
	(segment
		(start 301.23765 -149.86)
		(end 301.23765 -154.434794)
		(width 0.14224)
		(layer "In11.Cu")
		(net "M_F_DQS_DP<15>")
	)
	(segment
		(start 278.121364 -96.223836)
		(end 278.115014 -96.234504)
		(width 0.0889)
		(layer "In11.Cu")
		(net "M_F_DQS_DP<15>")
	)
	(segment
		(start 278.121364 -91.270836)
		(end 278.115014 -91.281504)
		(width 0.0889)
		(layer "In11.Cu")
		(net "M_F_DQS_DP<15>")
	)
	(segment
		(start 301.742602 -149.4282)
		(end 301.66945 -149.4282)
		(width 0.14224)
		(layer "In11.Cu")
		(net "M_F_DQS_DP<15>")
	)
	(segment
		(start 278.12619 -93.2434)
		(end 278.121364 -93.252036)
		(width 0.0889)
		(layer "In11.Cu")
		(net "M_F_DQS_DP<15>")
	)
	(segment
		(start 302.098202 -147.316952)
		(end 302.098202 -147.570952)
		(width 0.14224)
		(layer "In11.Cu")
		(net "M_F_DQS_DP<15>")
	)
	(segment
		(start 278.115014 -94.822518)
		(end 278.121364 -94.833186)
		(width 0.0889)
		(layer "In11.Cu")
		(net "M_F_DQS_DP<15>")
	)
	(segment
		(start 278.611584 -97.109534)
		(end 278.64435 -97.109534)
		(width 0.0889)
		(layer "In11.Cu")
		(net "M_F_DQS_DP<15>")
	)
	(segment
		(start 278.12619 -91.2622)
		(end 278.121364 -91.270836)
		(width 0.0889)
		(layer "In11.Cu")
		(net "M_F_DQS_DP<15>")
	)
	(segment
		(start 281.190954 -98.595688)
		(end 281.22372 -98.595688)
		(width 0.0889)
		(layer "In11.Cu")
		(net "M_F_DQS_DP<15>")
	)
	(segment
		(start 279.473914 -97.605088)
		(end 279.50668 -97.605088)
		(width 0.0889)
		(layer "In11.Cu")
		(net "M_F_DQS_DP<15>")
	)
	(segment
		(start 302.255682 -147.159472)
		(end 302.098202 -147.316952)
		(width 0.14224)
		(layer "In11.Cu")
		(net "M_F_DQS_DP<15>")
	)
	(segment
		(start 302.255682 -146.38274)
		(end 302.140874 -146.497548)
		(width 0.14224)
		(layer "In11.Cu")
		(net "M_F_DQS_DP<15>")
	)
	(segment
		(start 278.633174 -89.922858)
		(end 278.567896 -89.988136)
		(width 0.0889)
		(layer "In11.Cu")
		(net "M_F_DQS_DP<15>")
	)
	(segment
		(start 302.140874 -146.497548)
		(end 302.140874 -146.751548)
		(width 0.14224)
		(layer "In11.Cu")
		(net "M_F_DQS_DP<15>")
	)
	(segment
		(start 282.254452 -107.165902)
		(end 282.254452 -107.188)
		(width 0.0889)
		(layer "In11.Cu")
		(net "M_F_DQS_DP<15>")
	)
	(arc
		(start 282.421076 -105.246678)
		(mid 282.467662 -105.435549)
		(end 282.419806 -105.624122)
		(width 0.0889)
		(layer "In11.Cu")
		(net "M_F_DQS_DP<15>")
	)
	(arc
		(start 278.115014 -91.281504)
		(mid 278.042216 -91.572267)
		(end 278.121364 -91.861386)
		(width 0.0889)
		(layer "In11.Cu")
		(net "M_F_DQS_DP<15>")
	)
	(arc
		(start 280.696924 -98.300286)
		(mid 280.905532 -98.512218)
		(end 281.190954 -98.595688)
		(width 0.0889)
		(layer "In11.Cu")
		(net "M_F_DQS_DP<15>")
	)
	(arc
		(start 278.115014 -96.234504)
		(mid 278.119045 -96.810686)
		(end 278.611584 -97.109534)
		(width 0.0889)
		(layer "In11.Cu")
		(net "M_F_DQS_DP<15>")
	)
	(arc
		(start 278.567896 -89.988136)
		(mid 278.105927 -90.308678)
		(end 278.121364 -90.870786)
		(width 0.0889)
		(layer "In11.Cu")
		(net "M_F_DQS_DP<15>")
	)
	(arc
		(start 279.50668 -97.605088)
		(mid 279.698322 -97.662254)
		(end 279.838404 -97.804986)
		(width 0.0889)
		(layer "In11.Cu")
		(net "M_F_DQS_DP<15>")
	)
	(arc
		(start 282.413964 -102.662482)
		(mid 282.334775 -102.949097)
		(end 282.405074 -103.238046)
		(width 0.0889)
		(layer "In11.Cu")
		(net "M_F_DQS_DP<15>")
	)
	(arc
		(start 282.420822 -103.265478)
		(mid 282.467498 -103.460179)
		(end 282.413964 -103.653082)
		(width 0.0889)
		(layer "In11.Cu")
		(net "M_F_DQS_DP<15>")
	)
	(arc
		(start 278.115014 -93.262704)
		(mid 278.042216 -93.553467)
		(end 278.121364 -93.842586)
		(width 0.0889)
		(layer "In11.Cu")
		(net "M_F_DQS_DP<15>")
	)
	(arc
		(start 278.979884 -97.309686)
		(mid 279.188492 -97.521618)
		(end 279.473914 -97.605088)
		(width 0.0889)
		(layer "In11.Cu")
		(net "M_F_DQS_DP<15>")
	)
	(arc
		(start 282.420822 -104.256078)
		(mid 282.467498 -104.450779)
		(end 282.413964 -104.643682)
		(width 0.0889)
		(layer "In11.Cu")
		(net "M_F_DQS_DP<15>")
	)
	(arc
		(start 281.22372 -98.595688)
		(mid 281.415362 -98.652854)
		(end 281.555444 -98.795586)
		(width 0.0889)
		(layer "In11.Cu")
		(net "M_F_DQS_DP<15>")
	)
	(arc
		(start 278.121364 -92.851986)
		(mid 278.174834 -93.047049)
		(end 278.12619 -93.2434)
		(width 0.0889)
		(layer "In11.Cu")
		(net "M_F_DQS_DP<15>")
	)
	(arc
		(start 278.121364 -94.833186)
		(mid 278.174863 -95.033084)
		(end 278.121364 -95.232982)
		(width 0.0889)
		(layer "In11.Cu")
		(net "M_F_DQS_DP<15>")
	)
	(arc
		(start 282.407614 -100.691696)
		(mid 282.334816 -100.982459)
		(end 282.413964 -101.271578)
		(width 0.0889)
		(layer "In11.Cu")
		(net "M_F_DQS_DP<15>")
	)
	(arc
		(start 278.121364 -94.242636)
		(mid 278.042142 -94.531754)
		(end 278.115014 -94.822518)
		(width 0.0889)
		(layer "In11.Cu")
		(net "M_F_DQS_DP<15>")
	)
	(arc
		(start 282.07843 -99.090734)
		(mid 282.416545 -99.295436)
		(end 282.413964 -99.690682)
		(width 0.0889)
		(layer "In11.Cu")
		(net "M_F_DQS_DP<15>")
	)
	(arc
		(start 282.413964 -103.653082)
		(mid 282.334775 -103.939697)
		(end 282.405074 -104.228646)
		(width 0.0889)
		(layer "In11.Cu")
		(net "M_F_DQS_DP<15>")
	)
	(arc
		(start 279.838404 -97.804986)
		(mid 280.045408 -98.01585)
		(end 280.328624 -98.100134)
		(width 0.0889)
		(layer "In11.Cu")
		(net "M_F_DQS_DP<15>")
	)
	(arc
		(start 278.121364 -91.861386)
		(mid 278.174834 -92.056449)
		(end 278.12619 -92.2528)
		(width 0.0889)
		(layer "In11.Cu")
		(net "M_F_DQS_DP<15>")
	)
	(arc
		(start 282.413964 -100.281232)
		(mid 282.467463 -100.48113)
		(end 282.413964 -100.681028)
		(width 0.0889)
		(layer "In11.Cu")
		(net "M_F_DQS_DP<15>")
	)
	(arc
		(start 278.115014 -92.272104)
		(mid 278.042216 -92.562867)
		(end 278.121364 -92.851986)
		(width 0.0889)
		(layer "In11.Cu")
		(net "M_F_DQS_DP<15>")
	)
	(arc
		(start 280.36139 -98.100134)
		(mid 280.55524 -98.156484)
		(end 280.696924 -98.300286)
		(width 0.0889)
		(layer "In11.Cu")
		(net "M_F_DQS_DP<15>")
	)
	(arc
		(start 278.121364 -93.842586)
		(mid 278.174834 -94.037649)
		(end 278.12619 -94.234)
		(width 0.0889)
		(layer "In11.Cu")
		(net "M_F_DQS_DP<15>")
	)
	(arc
		(start 278.64435 -97.109534)
		(mid 278.8382 -97.165884)
		(end 278.979884 -97.309686)
		(width 0.0889)
		(layer "In11.Cu")
		(net "M_F_DQS_DP<15>")
	)
	(arc
		(start 282.413964 -101.271578)
		(mid 282.467434 -101.466641)
		(end 282.41879 -101.662992)
		(width 0.0889)
		(layer "In11.Cu")
		(net "M_F_DQS_DP<15>")
	)
	(arc
		(start 281.555444 -98.795586)
		(mid 281.762448 -99.00645)
		(end 282.045664 -99.090734)
		(width 0.0889)
		(layer "In11.Cu")
		(net "M_F_DQS_DP<15>")
	)
	(arc
		(start 282.413964 -104.643682)
		(mid 282.334775 -104.930297)
		(end 282.405074 -105.219246)
		(width 0.0889)
		(layer "In11.Cu")
		(net "M_F_DQS_DP<15>")
	)
	(arc
		(start 282.41879 -102.271068)
		(mid 282.467545 -102.46742)
		(end 282.413964 -102.662482)
		(width 0.0889)
		(layer "In11.Cu")
		(net "M_F_DQS_DP<15>")
	)
	(arc
		(start 282.413964 -101.671628)
		(mid 282.334833 -101.96703)
		(end 282.413964 -102.262432)
		(width 0.0889)
		(layer "In11.Cu")
		(net "M_F_DQS_DP<15>")
	)
	(arc
		(start 278.121364 -90.870786)
		(mid 278.174834 -91.065849)
		(end 278.12619 -91.2622)
		(width 0.0889)
		(layer "In11.Cu")
		(net "M_F_DQS_DP<15>")
	)
	(arc
		(start 282.407614 -99.70135)
		(mid 282.334816 -99.992113)
		(end 282.413964 -100.281232)
		(width 0.0889)
		(layer "In11.Cu")
		(net "M_F_DQS_DP<15>")
	)
	(arc
		(start 278.121364 -95.232982)
		(mid 278.042233 -95.528384)
		(end 278.121364 -95.823786)
		(width 0.0889)
		(layer "In11.Cu")
		(net "M_F_DQS_DP<15>")
	)
	(arc
		(start 278.121364 -95.823786)
		(mid 278.174834 -96.018849)
		(end 278.12619 -96.2152)
		(width 0.0889)
		(layer "In11.Cu")
		(net "M_F_DQS_DP<15>")
	)
	(segment
		(start 292.013894 -153.331672)
		(end 291.929312 -153.515568)
		(width 0.1651)
		(layer "F.Cu")
		(net "M_F_DQS_DP<14>")
	)
	(segment
		(start 292.450012 -152.895554)
		(end 292.013894 -153.331672)
		(width 0.1651)
		(layer "F.Cu")
		(net "M_F_DQS_DP<14>")
	)
	(segment
		(start 291.929312 -153.515568)
		(end 291.929312 -154.333702)
		(width 0.1651)
		(layer "F.Cu")
		(net "M_F_DQS_DP<14>")
	)
	(segment
		(start 292.450012 -152.278842)
		(end 292.450012 -152.895554)
		(width 0.1651)
		(layer "F.Cu")
		(net "M_F_DQS_DP<14>")
	)
	(segment
		(start 280.637234 -93.052138)
		(end 281.208734 -93.052138)
		(width 0.1651)
		(layer "F.Cu")
		(net "M_F_DQS_DP<14>")
	)
	(segment
		(start 291.929312 -154.333702)
		(end 292.010846 -154.557984)
		(width 0.1651)
		(layer "F.Cu")
		(net "M_F_DQS_DP<14>")
	)
	(segment
		(start 292.010846 -154.557984)
		(end 292.392608 -154.939746)
		(width 0.1651)
		(layer "F.Cu")
		(net "M_F_DQS_DP<14>")
	)
	(segment
		(start 292.45052 -152.273)
		(end 292.450012 -152.278842)
		(width 0.1651)
		(layer "F.Cu")
		(net "M_F_DQS_DP<14>")
	)
	(via
		(at 292.392608 -149.4282)
		(size 0.508)
		(drill 0.254)
		(layers "F.Cu" "B.Cu")
		(net "M_F_DQS_DP<14>")
	)
	(via
		(at 281.208734 -93.052138)
		(size 0.508)
		(drill 0.254)
		(layers "F.Cu" "B.Cu")
		(net "M_F_DQS_DP<14>")
	)
	(via
		(at 292.392608 -154.939746)
		(size 0.508)
		(drill 0.254)
		(layers "F.Cu" "B.Cu")
		(net "M_F_DQS_DP<14>")
	)
	(segment
		(start 292.45052 -152.078436)
		(end 292.450012 -152.078182)
		(width 0.1651)
		(layer "B.Cu")
		(net "M_F_DQS_DP<14>")
	)
	(segment
		(start 291.916612 -150.871936)
		(end 291.916612 -149.976332)
		(width 0.1651)
		(layer "B.Cu")
		(net "M_F_DQS_DP<14>")
	)
	(segment
		(start 292.450012 -151.460454)
		(end 291.993828 -151.00427)
		(width 0.1651)
		(layer "B.Cu")
		(net "M_F_DQS_DP<14>")
	)
	(segment
		(start 291.916612 -149.976332)
		(end 292.003988 -149.81682)
		(width 0.1651)
		(layer "B.Cu")
		(net "M_F_DQS_DP<14>")
	)
	(segment
		(start 292.450012 -152.078182)
		(end 292.450012 -151.460454)
		(width 0.1651)
		(layer "B.Cu")
		(net "M_F_DQS_DP<14>")
	)
	(segment
		(start 292.003988 -149.81682)
		(end 292.392608 -149.4282)
		(width 0.1651)
		(layer "B.Cu")
		(net "M_F_DQS_DP<14>")
	)
	(segment
		(start 291.993828 -151.00427)
		(end 291.916612 -150.871936)
		(width 0.1651)
		(layer "B.Cu")
		(net "M_F_DQS_DP<14>")
	)
	(segment
		(start 280.696924 -96.319086)
		(end 280.70175 -96.327722)
		(width 0.0889)
		(layer "In4.Cu")
		(net "M_F_DQS_DP<14>")
	)
	(segment
		(start 292.815518 -146.381216)
		(end 292.815518 -146.635216)
		(width 0.14224)
		(layer "In4.Cu")
		(net "M_F_DQS_DP<14>")
	)
	(segment
		(start 280.696924 -100.281486)
		(end 280.70175 -100.290122)
		(width 0.0889)
		(layer "In4.Cu")
		(net "M_F_DQS_DP<14>")
	)
	(segment
		(start 280.690574 -102.252018)
		(end 280.696924 -102.262686)
		(width 0.0889)
		(layer "In4.Cu")
		(net "M_F_DQS_DP<14>")
	)
	(segment
		(start 292.748208 -148.020278)
		(end 292.748208 -148.274278)
		(width 0.14224)
		(layer "In4.Cu")
		(net "M_F_DQS_DP<14>")
	)
	(segment
		(start 281.660854 -107.286298)
		(end 281.660854 -112.968024)
		(width 0.14224)
		(layer "In4.Cu")
		(net "M_F_DQS_DP<14>")
	)
	(segment
		(start 292.79215 -147.451318)
		(end 292.905688 -147.564856)
		(width 0.14224)
		(layer "In4.Cu")
		(net "M_F_DQS_DP<14>")
	)
	(segment
		(start 280.690574 -96.308418)
		(end 280.696924 -96.319086)
		(width 0.0889)
		(layer "In4.Cu")
		(net "M_F_DQS_DP<14>")
	)
	(segment
		(start 280.690574 -103.242618)
		(end 280.696924 -103.253286)
		(width 0.0889)
		(layer "In4.Cu")
		(net "M_F_DQS_DP<14>")
	)
	(segment
		(start 280.690574 -98.289618)
		(end 280.696924 -98.300286)
		(width 0.0889)
		(layer "In4.Cu")
		(net "M_F_DQS_DP<14>")
	)
	(segment
		(start 292.815518 -146.635216)
		(end 292.905688 -146.725386)
		(width 0.14224)
		(layer "In4.Cu")
		(net "M_F_DQS_DP<14>")
	)
	(segment
		(start 280.696924 -103.253286)
		(end 280.70175 -103.261922)
		(width 0.0889)
		(layer "In4.Cu")
		(net "M_F_DQS_DP<14>")
	)
	(segment
		(start 292.79215 -147.197318)
		(end 292.79215 -147.451318)
		(width 0.14224)
		(layer "In4.Cu")
		(net "M_F_DQS_DP<14>")
	)
	(segment
		(start 280.696924 -95.328486)
		(end 280.70175 -95.337122)
		(width 0.0889)
		(layer "In4.Cu")
		(net "M_F_DQS_DP<14>")
	)
	(segment
		(start 281.190954 -105.529888)
		(end 281.229054 -105.529888)
		(width 0.0889)
		(layer "In4.Cu")
		(net "M_F_DQS_DP<14>")
	)
	(segment
		(start 292.905688 -124.212858)
		(end 292.905688 -146.291046)
		(width 0.14224)
		(layer "In4.Cu")
		(net "M_F_DQS_DP<14>")
	)
	(segment
		(start 280.696924 -98.300286)
		(end 280.70175 -98.308922)
		(width 0.0889)
		(layer "In4.Cu")
		(net "M_F_DQS_DP<14>")
	)
	(segment
		(start 281.609292 -105.929684)
		(end 281.609292 -106.556302)
		(width 0.0889)
		(layer "In4.Cu")
		(net "M_F_DQS_DP<14>")
	)
	(segment
		(start 280.696924 -104.243886)
		(end 280.70175 -104.252522)
		(width 0.0889)
		(layer "In4.Cu")
		(net "M_F_DQS_DP<14>")
	)
	(segment
		(start 281.660854 -112.968024)
		(end 292.905688 -124.212858)
		(width 0.14224)
		(layer "In4.Cu")
		(net "M_F_DQS_DP<14>")
	)
	(segment
		(start 280.696924 -101.272086)
		(end 280.70175 -101.280722)
		(width 0.0889)
		(layer "In4.Cu")
		(net "M_F_DQS_DP<14>")
	)
	(segment
		(start 280.690574 -104.233218)
		(end 280.696924 -104.243886)
		(width 0.0889)
		(layer "In4.Cu")
		(net "M_F_DQS_DP<14>")
	)
	(segment
		(start 292.748208 -148.274278)
		(end 292.905688 -148.431758)
		(width 0.14224)
		(layer "In4.Cu")
		(net "M_F_DQS_DP<14>")
	)
	(segment
		(start 280.690574 -101.261418)
		(end 280.696924 -101.272086)
		(width 0.0889)
		(layer "In4.Cu")
		(net "M_F_DQS_DP<14>")
	)
	(segment
		(start 281.700224 -107.22483)
		(end 281.660854 -107.2642)
		(width 0.0889)
		(layer "In4.Cu")
		(net "M_F_DQS_DP<14>")
	)
	(segment
		(start 292.905688 -149.19452)
		(end 292.672008 -149.4282)
		(width 0.14224)
		(layer "In4.Cu")
		(net "M_F_DQS_DP<14>")
	)
	(segment
		(start 281.609292 -106.556302)
		(end 281.700224 -106.647234)
		(width 0.0889)
		(layer "In4.Cu")
		(net "M_F_DQS_DP<14>")
	)
	(segment
		(start 292.905688 -148.431758)
		(end 292.905688 -149.19452)
		(width 0.14224)
		(layer "In4.Cu")
		(net "M_F_DQS_DP<14>")
	)
	(segment
		(start 292.905688 -147.564856)
		(end 292.905688 -147.862798)
		(width 0.14224)
		(layer "In4.Cu")
		(net "M_F_DQS_DP<14>")
	)
	(segment
		(start 280.690574 -100.270818)
		(end 280.696924 -100.281486)
		(width 0.0889)
		(layer "In4.Cu")
		(net "M_F_DQS_DP<14>")
	)
	(segment
		(start 280.696924 -102.262686)
		(end 280.70175 -102.271322)
		(width 0.0889)
		(layer "In4.Cu")
		(net "M_F_DQS_DP<14>")
	)
	(segment
		(start 281.208734 -93.390212)
		(end 281.14371 -93.455236)
		(width 0.0889)
		(layer "In4.Cu")
		(net "M_F_DQS_DP<14>")
	)
	(segment
		(start 280.690574 -99.280218)
		(end 280.696924 -99.290886)
		(width 0.0889)
		(layer "In4.Cu")
		(net "M_F_DQS_DP<14>")
	)
	(segment
		(start 281.208734 -93.052138)
		(end 281.208734 -93.390212)
		(width 0.0889)
		(layer "In4.Cu")
		(net "M_F_DQS_DP<14>")
	)
	(segment
		(start 281.660854 -107.2642)
		(end 281.660854 -107.286298)
		(width 0.0889)
		(layer "In4.Cu")
		(net "M_F_DQS_DP<14>")
	)
	(segment
		(start 280.690574 -97.299018)
		(end 280.696924 -97.309686)
		(width 0.0889)
		(layer "In4.Cu")
		(net "M_F_DQS_DP<14>")
	)
	(segment
		(start 292.905688 -146.291046)
		(end 292.815518 -146.381216)
		(width 0.14224)
		(layer "In4.Cu")
		(net "M_F_DQS_DP<14>")
	)
	(segment
		(start 280.696924 -94.737936)
		(end 280.690574 -94.748604)
		(width 0.0889)
		(layer "In4.Cu")
		(net "M_F_DQS_DP<14>")
	)
	(segment
		(start 280.696924 -99.290886)
		(end 280.70175 -99.299522)
		(width 0.0889)
		(layer "In4.Cu")
		(net "M_F_DQS_DP<14>")
	)
	(segment
		(start 292.672008 -149.4282)
		(end 292.392608 -149.4282)
		(width 0.14224)
		(layer "In4.Cu")
		(net "M_F_DQS_DP<14>")
	)
	(segment
		(start 280.696924 -97.309686)
		(end 280.70175 -97.318322)
		(width 0.0889)
		(layer "In4.Cu")
		(net "M_F_DQS_DP<14>")
	)
	(segment
		(start 292.905688 -147.08378)
		(end 292.79215 -147.197318)
		(width 0.14224)
		(layer "In4.Cu")
		(net "M_F_DQS_DP<14>")
	)
	(segment
		(start 292.905688 -146.725386)
		(end 292.905688 -147.08378)
		(width 0.14224)
		(layer "In4.Cu")
		(net "M_F_DQS_DP<14>")
	)
	(segment
		(start 281.700224 -106.647234)
		(end 281.700224 -107.22483)
		(width 0.0889)
		(layer "In4.Cu")
		(net "M_F_DQS_DP<14>")
	)
	(segment
		(start 292.905688 -147.862798)
		(end 292.748208 -148.020278)
		(width 0.14224)
		(layer "In4.Cu")
		(net "M_F_DQS_DP<14>")
	)
	(arc
		(start 280.70175 -104.252522)
		(mid 280.750505 -104.448874)
		(end 280.696924 -104.643936)
		(width 0.0889)
		(layer "In4.Cu")
		(net "M_F_DQS_DP<14>")
	)
	(arc
		(start 280.70175 -95.337122)
		(mid 280.750505 -95.533474)
		(end 280.696924 -95.728536)
		(width 0.0889)
		(layer "In4.Cu")
		(net "M_F_DQS_DP<14>")
	)
	(arc
		(start 280.696924 -103.653336)
		(mid 280.617702 -103.942454)
		(end 280.690574 -104.233218)
		(width 0.0889)
		(layer "In4.Cu")
		(net "M_F_DQS_DP<14>")
	)
	(arc
		(start 280.696924 -104.643936)
		(mid 280.692595 -105.227108)
		(end 281.190954 -105.529888)
		(width 0.0889)
		(layer "In4.Cu")
		(net "M_F_DQS_DP<14>")
	)
	(arc
		(start 280.696924 -96.719136)
		(mid 280.617702 -97.008254)
		(end 280.690574 -97.299018)
		(width 0.0889)
		(layer "In4.Cu")
		(net "M_F_DQS_DP<14>")
	)
	(arc
		(start 280.70175 -97.318322)
		(mid 280.750505 -97.514674)
		(end 280.696924 -97.709736)
		(width 0.0889)
		(layer "In4.Cu")
		(net "M_F_DQS_DP<14>")
	)
	(arc
		(start 280.70175 -100.290122)
		(mid 280.750505 -100.486474)
		(end 280.696924 -100.681536)
		(width 0.0889)
		(layer "In4.Cu")
		(net "M_F_DQS_DP<14>")
	)
	(arc
		(start 280.696924 -94.33814)
		(mid 280.750423 -94.538038)
		(end 280.696924 -94.737936)
		(width 0.0889)
		(layer "In4.Cu")
		(net "M_F_DQS_DP<14>")
	)
	(arc
		(start 280.70175 -102.271322)
		(mid 280.750505 -102.467674)
		(end 280.696924 -102.662736)
		(width 0.0889)
		(layer "In4.Cu")
		(net "M_F_DQS_DP<14>")
	)
	(arc
		(start 280.70175 -98.308922)
		(mid 280.750505 -98.505274)
		(end 280.696924 -98.700336)
		(width 0.0889)
		(layer "In4.Cu")
		(net "M_F_DQS_DP<14>")
	)
	(arc
		(start 280.696924 -99.690936)
		(mid 280.617702 -99.980054)
		(end 280.690574 -100.270818)
		(width 0.0889)
		(layer "In4.Cu")
		(net "M_F_DQS_DP<14>")
	)
	(arc
		(start 280.690574 -94.748604)
		(mid 280.617776 -95.039367)
		(end 280.696924 -95.328486)
		(width 0.0889)
		(layer "In4.Cu")
		(net "M_F_DQS_DP<14>")
	)
	(arc
		(start 281.14371 -93.455236)
		(mid 280.68135 -93.775806)
		(end 280.696924 -94.33814)
		(width 0.0889)
		(layer "In4.Cu")
		(net "M_F_DQS_DP<14>")
	)
	(arc
		(start 280.696924 -102.662736)
		(mid 280.617702 -102.951854)
		(end 280.690574 -103.242618)
		(width 0.0889)
		(layer "In4.Cu")
		(net "M_F_DQS_DP<14>")
	)
	(arc
		(start 280.696924 -100.681536)
		(mid 280.617702 -100.970654)
		(end 280.690574 -101.261418)
		(width 0.0889)
		(layer "In4.Cu")
		(net "M_F_DQS_DP<14>")
	)
	(arc
		(start 280.696924 -95.728536)
		(mid 280.617702 -96.017654)
		(end 280.690574 -96.308418)
		(width 0.0889)
		(layer "In4.Cu")
		(net "M_F_DQS_DP<14>")
	)
	(arc
		(start 280.70175 -96.327722)
		(mid 280.750505 -96.524074)
		(end 280.696924 -96.719136)
		(width 0.0889)
		(layer "In4.Cu")
		(net "M_F_DQS_DP<14>")
	)
	(arc
		(start 280.70175 -101.280722)
		(mid 280.750505 -101.477074)
		(end 280.696924 -101.672136)
		(width 0.0889)
		(layer "In4.Cu")
		(net "M_F_DQS_DP<14>")
	)
	(arc
		(start 281.229054 -105.529888)
		(mid 281.498985 -105.653881)
		(end 281.609292 -105.929684)
		(width 0.0889)
		(layer "In4.Cu")
		(net "M_F_DQS_DP<14>")
	)
	(arc
		(start 280.70175 -99.299522)
		(mid 280.750505 -99.495874)
		(end 280.696924 -99.690936)
		(width 0.0889)
		(layer "In4.Cu")
		(net "M_F_DQS_DP<14>")
	)
	(arc
		(start 280.696924 -97.709736)
		(mid 280.617702 -97.998854)
		(end 280.690574 -98.289618)
		(width 0.0889)
		(layer "In4.Cu")
		(net "M_F_DQS_DP<14>")
	)
	(arc
		(start 280.70175 -103.261922)
		(mid 280.750505 -103.458274)
		(end 280.696924 -103.653336)
		(width 0.0889)
		(layer "In4.Cu")
		(net "M_F_DQS_DP<14>")
	)
	(arc
		(start 280.696924 -98.700336)
		(mid 280.617702 -98.989454)
		(end 280.690574 -99.280218)
		(width 0.0889)
		(layer "In4.Cu")
		(net "M_F_DQS_DP<14>")
	)
	(arc
		(start 280.696924 -101.672136)
		(mid 280.617702 -101.961254)
		(end 280.690574 -102.252018)
		(width 0.0889)
		(layer "In4.Cu")
		(net "M_F_DQS_DP<14>")
	)
	(segment
		(start 291.887656 -154.434794)
		(end 292.392608 -154.939746)
		(width 0.14224)
		(layer "In11.Cu")
		(net "M_F_DQS_DP<14>")
	)
	(segment
		(start 292.319456 -149.4282)
		(end 291.887656 -149.86)
		(width 0.14224)
		(layer "In11.Cu")
		(net "M_F_DQS_DP<14>")
	)
	(segment
		(start 292.392608 -149.4282)
		(end 292.319456 -149.4282)
		(width 0.14224)
		(layer "In11.Cu")
		(net "M_F_DQS_DP<14>")
	)
	(segment
		(start 291.887656 -149.86)
		(end 291.887656 -154.434794)
		(width 0.14224)
		(layer "In11.Cu")
		(net "M_F_DQS_DP<14>")
	)
	(segment
		(start 283.099764 -152.895808)
		(end 282.663646 -153.331926)
		(width 0.1651)
		(layer "F.Cu")
		(net "M_F_DQS_DP<13>")
	)
	(segment
		(start 282.579064 -153.515568)
		(end 282.579064 -154.333702)
		(width 0.1651)
		(layer "F.Cu")
		(net "M_F_DQS_DP<13>")
	)
	(segment
		(start 283.099764 -152.278842)
		(end 283.099764 -152.895808)
		(width 0.1651)
		(layer "F.Cu")
		(net "M_F_DQS_DP<13>")
	)
	(segment
		(start 283.100272 -152.273)
		(end 283.099764 -152.278842)
		(width 0.1651)
		(layer "F.Cu")
		(net "M_F_DQS_DP<13>")
	)
	(segment
		(start 282.660598 -154.557984)
		(end 283.04236 -154.939746)
		(width 0.1651)
		(layer "F.Cu")
		(net "M_F_DQS_DP<13>")
	)
	(segment
		(start 273.769328 -92.061538)
		(end 274.340828 -92.061538)
		(width 0.1651)
		(layer "F.Cu")
		(net "M_F_DQS_DP<13>")
	)
	(segment
		(start 282.579064 -154.333702)
		(end 282.660598 -154.557984)
		(width 0.1651)
		(layer "F.Cu")
		(net "M_F_DQS_DP<13>")
	)
	(segment
		(start 282.663646 -153.331926)
		(end 282.579064 -153.515568)
		(width 0.1651)
		(layer "F.Cu")
		(net "M_F_DQS_DP<13>")
	)
	(via
		(at 283.04236 -154.939746)
		(size 0.508)
		(drill 0.254)
		(layers "F.Cu" "B.Cu")
		(net "M_F_DQS_DP<13>")
	)
	(via
		(at 274.340828 -92.061538)
		(size 0.508)
		(drill 0.254)
		(layers "F.Cu" "B.Cu")
		(net "M_F_DQS_DP<13>")
	)
	(via
		(at 283.04236 -149.4282)
		(size 0.508)
		(drill 0.254)
		(layers "F.Cu" "B.Cu")
		(net "M_F_DQS_DP<13>")
	)
	(segment
		(start 283.100272 -152.078436)
		(end 283.099764 -152.078182)
		(width 0.1651)
		(layer "B.Cu")
		(net "M_F_DQS_DP<13>")
	)
	(segment
		(start 282.566364 -149.976332)
		(end 282.65374 -149.81682)
		(width 0.1651)
		(layer "B.Cu")
		(net "M_F_DQS_DP<13>")
	)
	(segment
		(start 283.099764 -151.460454)
		(end 282.64358 -151.00427)
		(width 0.1651)
		(layer "B.Cu")
		(net "M_F_DQS_DP<13>")
	)
	(segment
		(start 283.099764 -152.078182)
		(end 283.099764 -151.460454)
		(width 0.1651)
		(layer "B.Cu")
		(net "M_F_DQS_DP<13>")
	)
	(segment
		(start 282.64358 -151.00427)
		(end 282.566364 -150.871936)
		(width 0.1651)
		(layer "B.Cu")
		(net "M_F_DQS_DP<13>")
	)
	(segment
		(start 282.566364 -150.871936)
		(end 282.566364 -149.976332)
		(width 0.1651)
		(layer "B.Cu")
		(net "M_F_DQS_DP<13>")
	)
	(segment
		(start 282.65374 -149.81682)
		(end 283.04236 -149.4282)
		(width 0.1651)
		(layer "B.Cu")
		(net "M_F_DQS_DP<13>")
	)
	(segment
		(start 274.64512 -101.22662)
		(end 274.64512 -104.732328)
		(width 0.0889)
		(layer "In11.Cu")
		(net "M_F_DQS_DP<13>")
	)
	(segment
		(start 283.148532 -125.94336)
		(end 283.351986 -126.434596)
		(width 0.14224)
		(layer "In11.Cu")
		(net "M_F_DQS_DP<13>")
	)
	(segment
		(start 280.149046 -122.94362)
		(end 283.148532 -125.94336)
		(width 0.14224)
		(layer "In11.Cu")
		(net "M_F_DQS_DP<13>")
	)
	(segment
		(start 283.398214 -148.342096)
		(end 283.555694 -148.499576)
		(width 0.14224)
		(layer "In11.Cu")
		(net "M_F_DQS_DP<13>")
	)
	(segment
		(start 283.555694 -147.930616)
		(end 283.398214 -148.088096)
		(width 0.14224)
		(layer "In11.Cu")
		(net "M_F_DQS_DP<13>")
	)
	(segment
		(start 280.149046 -121.737374)
		(end 280.149046 -122.94362)
		(width 0.14224)
		(layer "In11.Cu")
		(net "M_F_DQS_DP<13>")
	)
	(segment
		(start 283.398214 -147.265136)
		(end 283.398214 -147.519136)
		(width 0.14224)
		(layer "In11.Cu")
		(net "M_F_DQS_DP<13>")
	)
	(segment
		(start 283.04236 -149.4282)
		(end 282.969462 -149.4282)
		(width 0.14224)
		(layer "In11.Cu")
		(net "M_F_DQS_DP<13>")
	)
	(segment
		(start 283.398214 -147.519136)
		(end 283.555694 -147.676616)
		(width 0.14224)
		(layer "In11.Cu")
		(net "M_F_DQS_DP<13>")
	)
	(segment
		(start 283.555694 -147.107656)
		(end 283.398214 -147.265136)
		(width 0.14224)
		(layer "In11.Cu")
		(net "M_F_DQS_DP<13>")
	)
	(segment
		(start 283.430218 -146.442176)
		(end 283.430218 -146.696176)
		(width 0.14224)
		(layer "In11.Cu")
		(net "M_F_DQS_DP<13>")
	)
	(segment
		(start 272.975324 -98.1964)
		(end 272.970498 -98.205036)
		(width 0.0889)
		(layer "In11.Cu")
		(net "M_F_DQS_DP<13>")
	)
	(segment
		(start 273.829018 -93.347286)
		(end 273.833844 -93.355922)
		(width 0.0889)
		(layer "In11.Cu")
		(net "M_F_DQS_DP<13>")
	)
	(segment
		(start 272.970498 -96.223836)
		(end 272.964148 -96.234504)
		(width 0.0889)
		(layer "In11.Cu")
		(net "M_F_DQS_DP<13>")
	)
	(segment
		(start 272.975324 -97.2058)
		(end 272.970498 -97.214436)
		(width 0.0889)
		(layer "In11.Cu")
		(net "M_F_DQS_DP<13>")
	)
	(segment
		(start 272.964148 -94.822518)
		(end 272.970498 -94.833186)
		(width 0.0889)
		(layer "In11.Cu")
		(net "M_F_DQS_DP<13>")
	)
	(segment
		(start 273.469354 -100.081588)
		(end 273.487134 -100.081588)
		(width 0.0889)
		(layer "In11.Cu")
		(net "M_F_DQS_DP<13>")
	)
	(segment
		(start 273.822668 -93.336618)
		(end 273.829018 -93.347286)
		(width 0.0889)
		(layer "In11.Cu")
		(net "M_F_DQS_DP<13>")
	)
	(segment
		(start 283.555694 -148.964396)
		(end 283.09189 -149.4282)
		(width 0.14224)
		(layer "In11.Cu")
		(net "M_F_DQS_DP<13>")
	)
	(segment
		(start 283.555694 -143.702532)
		(end 283.555694 -146.3167)
		(width 0.14224)
		(layer "In11.Cu")
		(net "M_F_DQS_DP<13>")
	)
	(segment
		(start 283.555694 -146.3167)
		(end 283.430218 -146.442176)
		(width 0.14224)
		(layer "In11.Cu")
		(net "M_F_DQS_DP<13>")
	)
	(segment
		(start 272.970498 -98.205036)
		(end 272.964148 -98.215704)
		(width 0.0889)
		(layer "In11.Cu")
		(net "M_F_DQS_DP<13>")
	)
	(segment
		(start 274.340828 -92.399612)
		(end 274.275804 -92.464636)
		(width 0.0889)
		(layer "In11.Cu")
		(net "M_F_DQS_DP<13>")
	)
	(segment
		(start 272.970498 -99.195636)
		(end 272.964148 -99.206304)
		(width 0.0889)
		(layer "In11.Cu")
		(net "M_F_DQS_DP<13>")
	)
	(segment
		(start 283.09189 -149.4282)
		(end 283.04236 -149.4282)
		(width 0.14224)
		(layer "In11.Cu")
		(net "M_F_DQS_DP<13>")
	)
	(segment
		(start 273.829018 -100.28174)
		(end 274.004786 -100.586286)
		(width 0.0889)
		(layer "In11.Cu")
		(net "M_F_DQS_DP<13>")
	)
	(segment
		(start 274.60575 -104.793796)
		(end 274.60575 -116.194078)
		(width 0.14224)
		(layer "In11.Cu")
		(net "M_F_DQS_DP<13>")
	)
	(segment
		(start 283.430218 -146.696176)
		(end 283.555694 -146.821652)
		(width 0.14224)
		(layer "In11.Cu")
		(net "M_F_DQS_DP<13>")
	)
	(segment
		(start 282.911804 -149.485604)
		(end 282.537662 -149.86)
		(width 0.14224)
		(layer "In11.Cu")
		(net "M_F_DQS_DP<13>")
	)
	(segment
		(start 283.398214 -148.088096)
		(end 283.398214 -148.342096)
		(width 0.14224)
		(layer "In11.Cu")
		(net "M_F_DQS_DP<13>")
	)
	(segment
		(start 283.440886 -143.587724)
		(end 283.555694 -143.702532)
		(width 0.14224)
		(layer "In11.Cu")
		(net "M_F_DQS_DP<13>")
	)
	(segment
		(start 272.975324 -96.2152)
		(end 272.970498 -96.223836)
		(width 0.0889)
		(layer "In11.Cu")
		(net "M_F_DQS_DP<13>")
	)
	(segment
		(start 274.340828 -92.061538)
		(end 274.340828 -92.399612)
		(width 0.0889)
		(layer "In11.Cu")
		(net "M_F_DQS_DP<13>")
	)
	(segment
		(start 283.555694 -148.499576)
		(end 283.555694 -148.964396)
		(width 0.14224)
		(layer "In11.Cu")
		(net "M_F_DQS_DP<13>")
	)
	(segment
		(start 282.537662 -149.86)
		(end 282.537662 -154.435048)
		(width 0.14224)
		(layer "In11.Cu")
		(net "M_F_DQS_DP<13>")
	)
	(segment
		(start 274.60575 -116.194078)
		(end 280.149046 -121.737374)
		(width 0.14224)
		(layer "In11.Cu")
		(net "M_F_DQS_DP<13>")
	)
	(segment
		(start 282.969462 -149.4282)
		(end 282.911804 -149.485604)
		(width 0.14224)
		(layer "In11.Cu")
		(net "M_F_DQS_DP<13>")
	)
	(segment
		(start 273.497294 -93.947234)
		(end 273.469354 -93.947234)
		(width 0.0889)
		(layer "In11.Cu")
		(net "M_F_DQS_DP<13>")
	)
	(segment
		(start 274.60575 -104.771698)
		(end 274.60575 -104.793796)
		(width 0.0889)
		(layer "In11.Cu")
		(net "M_F_DQS_DP<13>")
	)
	(segment
		(start 283.351986 -126.434596)
		(end 283.4513 -126.674118)
		(width 0.14224)
		(layer "In11.Cu")
		(net "M_F_DQS_DP<13>")
	)
	(segment
		(start 272.975324 -99.187)
		(end 272.970498 -99.195636)
		(width 0.0889)
		(layer "In11.Cu")
		(net "M_F_DQS_DP<13>")
	)
	(segment
		(start 283.555694 -146.821652)
		(end 283.555694 -147.107656)
		(width 0.14224)
		(layer "In11.Cu")
		(net "M_F_DQS_DP<13>")
	)
	(segment
		(start 282.537662 -154.435048)
		(end 283.04236 -154.939746)
		(width 0.14224)
		(layer "In11.Cu")
		(net "M_F_DQS_DP<13>")
	)
	(segment
		(start 283.555694 -126.925832)
		(end 283.555694 -143.218916)
		(width 0.14224)
		(layer "In11.Cu")
		(net "M_F_DQS_DP<13>")
	)
	(segment
		(start 283.555694 -147.676616)
		(end 283.555694 -147.930616)
		(width 0.14224)
		(layer "In11.Cu")
		(net "M_F_DQS_DP<13>")
	)
	(segment
		(start 283.4513 -126.674118)
		(end 283.555694 -126.925832)
		(width 0.14224)
		(layer "In11.Cu")
		(net "M_F_DQS_DP<13>")
	)
	(segment
		(start 274.64512 -104.732328)
		(end 274.60575 -104.771698)
		(width 0.0889)
		(layer "In11.Cu")
		(net "M_F_DQS_DP<13>")
	)
	(segment
		(start 272.970498 -97.214436)
		(end 272.964148 -97.225104)
		(width 0.0889)
		(layer "In11.Cu")
		(net "M_F_DQS_DP<13>")
	)
	(segment
		(start 274.004786 -100.586286)
		(end 274.64512 -101.22662)
		(width 0.0889)
		(layer "In11.Cu")
		(net "M_F_DQS_DP<13>")
	)
	(segment
		(start 283.440886 -143.333724)
		(end 283.440886 -143.587724)
		(width 0.14224)
		(layer "In11.Cu")
		(net "M_F_DQS_DP<13>")
	)
	(segment
		(start 283.555694 -143.218916)
		(end 283.440886 -143.333724)
		(width 0.14224)
		(layer "In11.Cu")
		(net "M_F_DQS_DP<13>")
	)
	(arc
		(start 272.970498 -95.232982)
		(mid 272.891367 -95.528384)
		(end 272.970498 -95.823786)
		(width 0.0889)
		(layer "In11.Cu")
		(net "M_F_DQS_DP<13>")
	)
	(arc
		(start 272.964148 -97.225104)
		(mid 272.89135 -97.515867)
		(end 272.970498 -97.804986)
		(width 0.0889)
		(layer "In11.Cu")
		(net "M_F_DQS_DP<13>")
	)
	(arc
		(start 272.970498 -98.795586)
		(mid 273.023968 -98.990649)
		(end 272.975324 -99.187)
		(width 0.0889)
		(layer "In11.Cu")
		(net "M_F_DQS_DP<13>")
	)
	(arc
		(start 273.469354 -93.947234)
		(mid 272.970473 -94.242671)
		(end 272.964148 -94.822518)
		(width 0.0889)
		(layer "In11.Cu")
		(net "M_F_DQS_DP<13>")
	)
	(arc
		(start 272.964148 -98.215704)
		(mid 272.89135 -98.506467)
		(end 272.970498 -98.795586)
		(width 0.0889)
		(layer "In11.Cu")
		(net "M_F_DQS_DP<13>")
	)
	(arc
		(start 273.833844 -93.355922)
		(mid 273.830097 -93.745178)
		(end 273.497294 -93.947234)
		(width 0.0889)
		(layer "In11.Cu")
		(net "M_F_DQS_DP<13>")
	)
	(arc
		(start 272.970498 -95.823786)
		(mid 273.023968 -96.018849)
		(end 272.975324 -96.2152)
		(width 0.0889)
		(layer "In11.Cu")
		(net "M_F_DQS_DP<13>")
	)
	(arc
		(start 272.964148 -96.234504)
		(mid 272.89135 -96.525267)
		(end 272.970498 -96.814386)
		(width 0.0889)
		(layer "In11.Cu")
		(net "M_F_DQS_DP<13>")
	)
	(arc
		(start 272.970498 -97.804986)
		(mid 273.023968 -98.000049)
		(end 272.975324 -98.1964)
		(width 0.0889)
		(layer "In11.Cu")
		(net "M_F_DQS_DP<13>")
	)
	(arc
		(start 272.970498 -96.814386)
		(mid 273.023968 -97.009449)
		(end 272.975324 -97.2058)
		(width 0.0889)
		(layer "In11.Cu")
		(net "M_F_DQS_DP<13>")
	)
	(arc
		(start 273.487134 -100.081588)
		(mid 273.684569 -100.136411)
		(end 273.829018 -100.28174)
		(width 0.0889)
		(layer "In11.Cu")
		(net "M_F_DQS_DP<13>")
	)
	(arc
		(start 272.970498 -94.833186)
		(mid 273.023997 -95.033084)
		(end 272.970498 -95.232982)
		(width 0.0889)
		(layer "In11.Cu")
		(net "M_F_DQS_DP<13>")
	)
	(arc
		(start 274.275804 -92.464636)
		(mid 273.816327 -92.779585)
		(end 273.822668 -93.336618)
		(width 0.0889)
		(layer "In11.Cu")
		(net "M_F_DQS_DP<13>")
	)
	(arc
		(start 272.964148 -99.206304)
		(mid 272.970325 -99.786236)
		(end 273.469354 -100.081588)
		(width 0.0889)
		(layer "In11.Cu")
		(net "M_F_DQS_DP<13>")
	)
	(segment
		(start 227.849938 -152.895554)
		(end 227.41382 -153.331672)
		(width 0.1651)
		(layer "F.Cu")
		(net "M_F_DQS_DP<12>")
	)
	(segment
		(start 227.41382 -153.331672)
		(end 227.329238 -153.515568)
		(width 0.1651)
		(layer "F.Cu")
		(net "M_F_DQS_DP<12>")
	)
	(segment
		(start 250.778264 -84.812886)
		(end 250.206764 -84.812886)
		(width 0.1651)
		(layer "F.Cu")
		(net "M_F_DQS_DP<12>")
	)
	(segment
		(start 227.850446 -152.273)
		(end 227.849938 -152.278842)
		(width 0.1651)
		(layer "F.Cu")
		(net "M_F_DQS_DP<12>")
	)
	(segment
		(start 227.410772 -154.557984)
		(end 227.792534 -154.939746)
		(width 0.1651)
		(layer "F.Cu")
		(net "M_F_DQS_DP<12>")
	)
	(segment
		(start 227.849938 -152.278842)
		(end 227.849938 -152.895554)
		(width 0.1651)
		(layer "F.Cu")
		(net "M_F_DQS_DP<12>")
	)
	(segment
		(start 227.329238 -153.515568)
		(end 227.329238 -154.333702)
		(width 0.1651)
		(layer "F.Cu")
		(net "M_F_DQS_DP<12>")
	)
	(segment
		(start 227.329238 -154.333702)
		(end 227.410772 -154.557984)
		(width 0.1651)
		(layer "F.Cu")
		(net "M_F_DQS_DP<12>")
	)
	(via
		(at 227.792534 -154.939746)
		(size 0.508)
		(drill 0.254)
		(layers "F.Cu" "B.Cu")
		(net "M_F_DQS_DP<12>")
	)
	(via
		(at 227.792534 -149.4282)
		(size 0.508)
		(drill 0.254)
		(layers "F.Cu" "B.Cu")
		(net "M_F_DQS_DP<12>")
	)
	(via
		(at 250.206764 -84.812886)
		(size 0.508)
		(drill 0.254)
		(layers "F.Cu" "B.Cu")
		(net "M_F_DQS_DP<12>")
	)
	(segment
		(start 227.850446 -152.078436)
		(end 227.849938 -152.078182)
		(width 0.1651)
		(layer "B.Cu")
		(net "M_F_DQS_DP<12>")
	)
	(segment
		(start 227.403914 -149.81682)
		(end 227.792534 -149.4282)
		(width 0.1651)
		(layer "B.Cu")
		(net "M_F_DQS_DP<12>")
	)
	(segment
		(start 227.393754 -151.00427)
		(end 227.316538 -150.871936)
		(width 0.1651)
		(layer "B.Cu")
		(net "M_F_DQS_DP<12>")
	)
	(segment
		(start 227.316538 -149.976332)
		(end 227.403914 -149.81682)
		(width 0.1651)
		(layer "B.Cu")
		(net "M_F_DQS_DP<12>")
	)
	(segment
		(start 227.849938 -152.078182)
		(end 227.849938 -151.460454)
		(width 0.1651)
		(layer "B.Cu")
		(net "M_F_DQS_DP<12>")
	)
	(segment
		(start 227.316538 -150.871936)
		(end 227.316538 -149.976332)
		(width 0.1651)
		(layer "B.Cu")
		(net "M_F_DQS_DP<12>")
	)
	(segment
		(start 227.849938 -151.460454)
		(end 227.393754 -151.00427)
		(width 0.1651)
		(layer "B.Cu")
		(net "M_F_DQS_DP<12>")
	)
	(segment
		(start 228.0793 -149.4282)
		(end 227.792534 -149.4282)
		(width 0.14224)
		(layer "In11.Cu")
		(net "M_F_DQS_DP<12>")
	)
	(segment
		(start 245.047262 -103.196898)
		(end 245.047262 -105.008426)
		(width 0.14224)
		(layer "In11.Cu")
		(net "M_F_DQS_DP<12>")
	)
	(segment
		(start 241.30508 -108.7501)
		(end 241.30508 -114.200686)
		(width 0.14224)
		(layer "In11.Cu")
		(net "M_F_DQS_DP<12>")
	)
	(segment
		(start 246.582184 -99.085908)
		(end 246.091202 -99.57689)
		(width 0.0889)
		(layer "In11.Cu")
		(net "M_F_DQS_DP<12>")
	)
	(segment
		(start 245.047262 -103.1748)
		(end 245.047262 -103.196898)
		(width 0.0889)
		(layer "In11.Cu")
		(net "M_F_DQS_DP<12>")
	)
	(segment
		(start 228.819202 -123.384564)
		(end 228.305614 -124.624846)
		(width 0.14224)
		(layer "In11.Cu")
		(net "M_F_DQS_DP<12>")
	)
	(segment
		(start 249.694954 -90.461338)
		(end 249.688604 -90.472006)
		(width 0.0889)
		(layer "In11.Cu")
		(net "M_F_DQS_DP<12>")
	)
	(segment
		(start 248.5898 -96.336358)
		(end 246.582184 -98.343974)
		(width 0.0889)
		(layer "In11.Cu")
		(net "M_F_DQS_DP<12>")
	)
	(segment
		(start 228.183694 -148.194776)
		(end 228.183694 -148.448776)
		(width 0.14224)
		(layer "In11.Cu")
		(net "M_F_DQS_DP<12>")
	)
	(segment
		(start 249.69978 -90.452702)
		(end 249.694954 -90.461338)
		(width 0.0889)
		(layer "In11.Cu")
		(net "M_F_DQS_DP<12>")
	)
	(segment
		(start 250.206764 -85.15096)
		(end 250.141486 -85.216238)
		(width 0.0889)
		(layer "In11.Cu")
		(net "M_F_DQS_DP<12>")
	)
	(segment
		(start 245.086632 -103.13543)
		(end 245.047262 -103.1748)
		(width 0.0889)
		(layer "In11.Cu")
		(net "M_F_DQS_DP<12>")
	)
	(segment
		(start 250.206764 -84.812886)
		(end 250.206764 -85.15096)
		(width 0.0889)
		(layer "In11.Cu")
		(net "M_F_DQS_DP<12>")
	)
	(segment
		(start 245.344442 -99.97186)
		(end 245.086632 -100.439728)
		(width 0.0889)
		(layer "In11.Cu")
		(net "M_F_DQS_DP<12>")
	)
	(segment
		(start 235.231686 -120.27408)
		(end 231.929686 -120.27408)
		(width 0.14224)
		(layer "In11.Cu")
		(net "M_F_DQS_DP<12>")
	)
	(segment
		(start 228.305614 -124.624846)
		(end 228.305614 -146.569176)
		(width 0.14224)
		(layer "In11.Cu")
		(net "M_F_DQS_DP<12>")
	)
	(segment
		(start 245.473728 -99.748086)
		(end 245.472712 -99.749864)
		(width 0.0889)
		(layer "In11.Cu")
		(net "M_F_DQS_DP<12>")
	)
	(segment
		(start 227.287582 -149.86)
		(end 227.287582 -154.434794)
		(width 0.14224)
		(layer "In11.Cu")
		(net "M_F_DQS_DP<12>")
	)
	(segment
		(start 246.582184 -98.343974)
		(end 246.582184 -99.085908)
		(width 0.0889)
		(layer "In11.Cu")
		(net "M_F_DQS_DP<12>")
	)
	(segment
		(start 248.836434 -95.509588)
		(end 248.84126 -95.518224)
		(width 0.0889)
		(layer "In11.Cu")
		(net "M_F_DQS_DP<12>")
	)
	(segment
		(start 228.183694 -148.448776)
		(end 228.305614 -148.570696)
		(width 0.14224)
		(layer "In11.Cu")
		(net "M_F_DQS_DP<12>")
	)
	(segment
		(start 228.183694 -146.945096)
		(end 228.305614 -147.067016)
		(width 0.14224)
		(layer "In11.Cu")
		(net "M_F_DQS_DP<12>")
	)
	(segment
		(start 249.694954 -87.489538)
		(end 249.688604 -87.500206)
		(width 0.0889)
		(layer "In11.Cu")
		(net "M_F_DQS_DP<12>")
	)
	(segment
		(start 248.836434 -95.909638)
		(end 248.5898 -96.336358)
		(width 0.0889)
		(layer "In11.Cu")
		(net "M_F_DQS_DP<12>")
	)
	(segment
		(start 245.644924 -99.57689)
		(end 245.473728 -99.748086)
		(width 0.0889)
		(layer "In11.Cu")
		(net "M_F_DQS_DP<12>")
	)
	(segment
		(start 228.183694 -147.442936)
		(end 228.183694 -147.696936)
		(width 0.14224)
		(layer "In11.Cu")
		(net "M_F_DQS_DP<12>")
	)
	(segment
		(start 227.287582 -154.434794)
		(end 227.792534 -154.939746)
		(width 0.14224)
		(layer "In11.Cu")
		(net "M_F_DQS_DP<12>")
	)
	(segment
		(start 228.305614 -147.067016)
		(end 228.305614 -147.321016)
		(width 0.14224)
		(layer "In11.Cu")
		(net "M_F_DQS_DP<12>")
	)
	(segment
		(start 228.305614 -147.321016)
		(end 228.183694 -147.442936)
		(width 0.14224)
		(layer "In11.Cu")
		(net "M_F_DQS_DP<12>")
	)
	(segment
		(start 249.35942 -92.64269)
		(end 249.326654 -92.64269)
		(width 0.0889)
		(layer "In11.Cu")
		(net "M_F_DQS_DP<12>")
	)
	(segment
		(start 249.69978 -87.480902)
		(end 249.694954 -87.489538)
		(width 0.0889)
		(layer "In11.Cu")
		(net "M_F_DQS_DP<12>")
	)
	(segment
		(start 246.091202 -99.57689)
		(end 245.644924 -99.57689)
		(width 0.0889)
		(layer "In11.Cu")
		(net "M_F_DQS_DP<12>")
	)
	(segment
		(start 228.305614 -149.201886)
		(end 228.0793 -149.4282)
		(width 0.14224)
		(layer "In11.Cu")
		(net "M_F_DQS_DP<12>")
	)
	(segment
		(start 248.836434 -93.928438)
		(end 248.830084 -93.939106)
		(width 0.0889)
		(layer "In11.Cu")
		(net "M_F_DQS_DP<12>")
	)
	(segment
		(start 241.30508 -114.200686)
		(end 235.231686 -120.27408)
		(width 0.14224)
		(layer "In11.Cu")
		(net "M_F_DQS_DP<12>")
	)
	(segment
		(start 248.830084 -95.49892)
		(end 248.836434 -95.509588)
		(width 0.0889)
		(layer "In11.Cu")
		(net "M_F_DQS_DP<12>")
	)
	(segment
		(start 249.69978 -88.471502)
		(end 249.694954 -88.480138)
		(width 0.0889)
		(layer "In11.Cu")
		(net "M_F_DQS_DP<12>")
	)
	(segment
		(start 228.305614 -147.818856)
		(end 228.305614 -148.072856)
		(width 0.14224)
		(layer "In11.Cu")
		(net "M_F_DQS_DP<12>")
	)
	(segment
		(start 231.929686 -120.27408)
		(end 228.819202 -123.384564)
		(width 0.14224)
		(layer "In11.Cu")
		(net "M_F_DQS_DP<12>")
	)
	(segment
		(start 228.305614 -148.570696)
		(end 228.305614 -149.201886)
		(width 0.14224)
		(layer "In11.Cu")
		(net "M_F_DQS_DP<12>")
	)
	(segment
		(start 228.183694 -146.691096)
		(end 228.183694 -146.945096)
		(width 0.14224)
		(layer "In11.Cu")
		(net "M_F_DQS_DP<12>")
	)
	(segment
		(start 227.719382 -149.4282)
		(end 227.287582 -149.86)
		(width 0.14224)
		(layer "In11.Cu")
		(net "M_F_DQS_DP<12>")
	)
	(segment
		(start 249.694954 -88.480138)
		(end 249.688604 -88.490806)
		(width 0.0889)
		(layer "In11.Cu")
		(net "M_F_DQS_DP<12>")
	)
	(segment
		(start 245.047262 -105.008426)
		(end 241.305588 -108.7501)
		(width 0.14224)
		(layer "In11.Cu")
		(net "M_F_DQS_DP<12>")
	)
	(segment
		(start 249.69978 -86.490302)
		(end 249.694954 -86.498938)
		(width 0.0889)
		(layer "In11.Cu")
		(net "M_F_DQS_DP<12>")
	)
	(segment
		(start 227.792534 -149.4282)
		(end 227.719382 -149.4282)
		(width 0.14224)
		(layer "In11.Cu")
		(net "M_F_DQS_DP<12>")
	)
	(segment
		(start 249.694954 -89.470738)
		(end 249.688604 -89.481406)
		(width 0.0889)
		(layer "In11.Cu")
		(net "M_F_DQS_DP<12>")
	)
	(segment
		(start 228.183694 -147.696936)
		(end 228.305614 -147.818856)
		(width 0.14224)
		(layer "In11.Cu")
		(net "M_F_DQS_DP<12>")
	)
	(segment
		(start 241.305588 -108.7501)
		(end 241.30508 -108.7501)
		(width 0.14224)
		(layer "In11.Cu")
		(net "M_F_DQS_DP<12>")
	)
	(segment
		(start 228.305614 -146.569176)
		(end 228.183694 -146.691096)
		(width 0.14224)
		(layer "In11.Cu")
		(net "M_F_DQS_DP<12>")
	)
	(segment
		(start 249.694954 -86.498938)
		(end 249.688604 -86.509606)
		(width 0.0889)
		(layer "In11.Cu")
		(net "M_F_DQS_DP<12>")
	)
	(segment
		(start 245.086632 -100.439728)
		(end 245.086632 -103.13543)
		(width 0.0889)
		(layer "In11.Cu")
		(net "M_F_DQS_DP<12>")
	)
	(segment
		(start 228.305614 -148.072856)
		(end 228.183694 -148.194776)
		(width 0.14224)
		(layer "In11.Cu")
		(net "M_F_DQS_DP<12>")
	)
	(segment
		(start 245.472712 -99.749864)
		(end 245.344442 -99.97186)
		(width 0.0889)
		(layer "In11.Cu")
		(net "M_F_DQS_DP<12>")
	)
	(segment
		(start 249.694954 -91.451938)
		(end 249.688604 -91.462606)
		(width 0.0889)
		(layer "In11.Cu")
		(net "M_F_DQS_DP<12>")
	)
	(segment
		(start 249.69978 -91.443302)
		(end 249.694954 -91.451938)
		(width 0.0889)
		(layer "In11.Cu")
		(net "M_F_DQS_DP<12>")
	)
	(segment
		(start 248.836434 -94.518988)
		(end 248.84126 -94.527624)
		(width 0.0889)
		(layer "In11.Cu")
		(net "M_F_DQS_DP<12>")
	)
	(segment
		(start 249.69978 -89.462102)
		(end 249.694954 -89.470738)
		(width 0.0889)
		(layer "In11.Cu")
		(net "M_F_DQS_DP<12>")
	)
	(arc
		(start 248.84126 -95.518224)
		(mid 248.890015 -95.714576)
		(end 248.836434 -95.909638)
		(width 0.0889)
		(layer "In11.Cu")
		(net "M_F_DQS_DP<12>")
	)
	(arc
		(start 248.836434 -93.528642)
		(mid 248.889933 -93.72854)
		(end 248.836434 -93.928438)
		(width 0.0889)
		(layer "In11.Cu")
		(net "M_F_DQS_DP<12>")
	)
	(arc
		(start 248.84126 -94.527624)
		(mid 248.890015 -94.723976)
		(end 248.836434 -94.919038)
		(width 0.0889)
		(layer "In11.Cu")
		(net "M_F_DQS_DP<12>")
	)
	(arc
		(start 249.688604 -91.462606)
		(mid 249.615806 -91.753369)
		(end 249.694954 -92.042488)
		(width 0.0889)
		(layer "In11.Cu")
		(net "M_F_DQS_DP<12>")
	)
	(arc
		(start 249.694954 -88.080088)
		(mid 249.748424 -88.275151)
		(end 249.69978 -88.471502)
		(width 0.0889)
		(layer "In11.Cu")
		(net "M_F_DQS_DP<12>")
	)
	(arc
		(start 250.141486 -85.216238)
		(mid 249.679517 -85.53678)
		(end 249.694954 -86.098888)
		(width 0.0889)
		(layer "In11.Cu")
		(net "M_F_DQS_DP<12>")
	)
	(arc
		(start 249.688604 -90.472006)
		(mid 249.615806 -90.762769)
		(end 249.694954 -91.051888)
		(width 0.0889)
		(layer "In11.Cu")
		(net "M_F_DQS_DP<12>")
	)
	(arc
		(start 249.694954 -92.042488)
		(mid 249.697702 -92.437955)
		(end 249.35942 -92.64269)
		(width 0.0889)
		(layer "In11.Cu")
		(net "M_F_DQS_DP<12>")
	)
	(arc
		(start 249.694954 -90.061288)
		(mid 249.748424 -90.256351)
		(end 249.69978 -90.452702)
		(width 0.0889)
		(layer "In11.Cu")
		(net "M_F_DQS_DP<12>")
	)
	(arc
		(start 249.694954 -89.070688)
		(mid 249.748424 -89.265751)
		(end 249.69978 -89.462102)
		(width 0.0889)
		(layer "In11.Cu")
		(net "M_F_DQS_DP<12>")
	)
	(arc
		(start 248.836434 -94.919038)
		(mid 248.757212 -95.208156)
		(end 248.830084 -95.49892)
		(width 0.0889)
		(layer "In11.Cu")
		(net "M_F_DQS_DP<12>")
	)
	(arc
		(start 249.688604 -87.500206)
		(mid 249.615806 -87.790969)
		(end 249.694954 -88.080088)
		(width 0.0889)
		(layer "In11.Cu")
		(net "M_F_DQS_DP<12>")
	)
	(arc
		(start 249.688604 -86.509606)
		(mid 249.615806 -86.800369)
		(end 249.694954 -87.089488)
		(width 0.0889)
		(layer "In11.Cu")
		(net "M_F_DQS_DP<12>")
	)
	(arc
		(start 249.694954 -87.089488)
		(mid 249.748424 -87.284551)
		(end 249.69978 -87.480902)
		(width 0.0889)
		(layer "In11.Cu")
		(net "M_F_DQS_DP<12>")
	)
	(arc
		(start 248.830084 -93.939106)
		(mid 248.757286 -94.229869)
		(end 248.836434 -94.518988)
		(width 0.0889)
		(layer "In11.Cu")
		(net "M_F_DQS_DP<12>")
	)
	(arc
		(start 249.326654 -92.64269)
		(mid 248.831177 -92.947133)
		(end 248.836434 -93.528642)
		(width 0.0889)
		(layer "In11.Cu")
		(net "M_F_DQS_DP<12>")
	)
	(arc
		(start 249.694954 -91.051888)
		(mid 249.748424 -91.246951)
		(end 249.69978 -91.443302)
		(width 0.0889)
		(layer "In11.Cu")
		(net "M_F_DQS_DP<12>")
	)
	(arc
		(start 249.688604 -89.481406)
		(mid 249.615806 -89.772169)
		(end 249.694954 -90.061288)
		(width 0.0889)
		(layer "In11.Cu")
		(net "M_F_DQS_DP<12>")
	)
	(arc
		(start 249.694954 -86.098888)
		(mid 249.748424 -86.293951)
		(end 249.69978 -86.490302)
		(width 0.0889)
		(layer "In11.Cu")
		(net "M_F_DQS_DP<12>")
	)
	(arc
		(start 249.688604 -88.490806)
		(mid 249.615806 -88.781569)
		(end 249.694954 -89.070688)
		(width 0.0889)
		(layer "In11.Cu")
		(net "M_F_DQS_DP<12>")
	)
	(segment
		(start 218.499944 -152.278842)
		(end 218.499944 -152.895554)
		(width 0.1651)
		(layer "F.Cu")
		(net "M_F_DQS_DP<11>")
	)
	(segment
		(start 218.063826 -153.331672)
		(end 217.979244 -153.515568)
		(width 0.1651)
		(layer "F.Cu")
		(net "M_F_DQS_DP<11>")
	)
	(segment
		(start 247.344184 -92.737686)
		(end 246.772684 -92.737686)
		(width 0.1651)
		(layer "F.Cu")
		(net "M_F_DQS_DP<11>")
	)
	(segment
		(start 217.979244 -153.515568)
		(end 217.979244 -154.333702)
		(width 0.1651)
		(layer "F.Cu")
		(net "M_F_DQS_DP<11>")
	)
	(segment
		(start 218.500452 -152.273)
		(end 218.499944 -152.278842)
		(width 0.1651)
		(layer "F.Cu")
		(net "M_F_DQS_DP<11>")
	)
	(segment
		(start 217.979244 -154.333702)
		(end 218.060778 -154.557984)
		(width 0.1651)
		(layer "F.Cu")
		(net "M_F_DQS_DP<11>")
	)
	(segment
		(start 218.060778 -154.557984)
		(end 218.44254 -154.939746)
		(width 0.1651)
		(layer "F.Cu")
		(net "M_F_DQS_DP<11>")
	)
	(segment
		(start 218.499944 -152.895554)
		(end 218.063826 -153.331672)
		(width 0.1651)
		(layer "F.Cu")
		(net "M_F_DQS_DP<11>")
	)
	(via
		(at 246.772684 -92.737686)
		(size 0.508)
		(drill 0.254)
		(layers "F.Cu" "B.Cu")
		(net "M_F_DQS_DP<11>")
	)
	(via
		(at 218.44254 -154.939746)
		(size 0.508)
		(drill 0.254)
		(layers "F.Cu" "B.Cu")
		(net "M_F_DQS_DP<11>")
	)
	(via
		(at 218.44254 -149.4282)
		(size 0.508)
		(drill 0.254)
		(layers "F.Cu" "B.Cu")
		(net "M_F_DQS_DP<11>")
	)
	(segment
		(start 218.499944 -152.078182)
		(end 218.499944 -151.460454)
		(width 0.1651)
		(layer "B.Cu")
		(net "M_F_DQS_DP<11>")
	)
	(segment
		(start 217.966544 -150.871936)
		(end 217.966544 -149.976332)
		(width 0.1651)
		(layer "B.Cu")
		(net "M_F_DQS_DP<11>")
	)
	(segment
		(start 217.966544 -149.976332)
		(end 218.05392 -149.81682)
		(width 0.1651)
		(layer "B.Cu")
		(net "M_F_DQS_DP<11>")
	)
	(segment
		(start 218.04376 -151.00427)
		(end 217.966544 -150.871936)
		(width 0.1651)
		(layer "B.Cu")
		(net "M_F_DQS_DP<11>")
	)
	(segment
		(start 218.500452 -152.078436)
		(end 218.499944 -152.078182)
		(width 0.1651)
		(layer "B.Cu")
		(net "M_F_DQS_DP<11>")
	)
	(segment
		(start 218.499944 -151.460454)
		(end 218.04376 -151.00427)
		(width 0.1651)
		(layer "B.Cu")
		(net "M_F_DQS_DP<11>")
	)
	(segment
		(start 218.05392 -149.81682)
		(end 218.44254 -149.4282)
		(width 0.1651)
		(layer "B.Cu")
		(net "M_F_DQS_DP<11>")
	)
	(segment
		(start 245.07063 -93.137736)
		(end 245.04269 -93.137736)
		(width 0.0889)
		(layer "In11.Cu")
		(net "M_F_DQS_DP<11>")
	)
	(segment
		(start 235.871004 -101.510338)
		(end 235.871004 -102.324916)
		(width 0.0889)
		(layer "In11.Cu")
		(net "M_F_DQS_DP<11>")
	)
	(segment
		(start 242.480338 -94.623636)
		(end 242.467384 -94.623636)
		(width 0.0889)
		(layer "In11.Cu")
		(net "M_F_DQS_DP<11>")
	)
	(segment
		(start 242.826794 -94.423484)
		(end 242.823492 -94.429326)
		(width 0.0889)
		(layer "In11.Cu")
		(net "M_F_DQS_DP<11>")
	)
	(segment
		(start 245.935754 -92.64269)
		(end 245.892574 -92.64269)
		(width 0.0889)
		(layer "In11.Cu")
		(net "M_F_DQS_DP<11>")
	)
	(segment
		(start 234.308396 -103.831644)
		(end 233.045 -105.09504)
		(width 0.14224)
		(layer "In11.Cu")
		(net "M_F_DQS_DP<11>")
	)
	(segment
		(start 235.958888 -100.957888)
		(end 235.959142 -100.958142)
		(width 0.0889)
		(layer "In11.Cu")
		(net "M_F_DQS_DP<11>")
	)
	(segment
		(start 241.636804 -95.118936)
		(end 241.604038 -95.118936)
		(width 0.0889)
		(layer "In11.Cu")
		(net "M_F_DQS_DP<11>")
	)
	(segment
		(start 236.485684 -98.090736)
		(end 236.452918 -98.090736)
		(width 0.0889)
		(layer "In11.Cu")
		(net "M_F_DQS_DP<11>")
	)
	(segment
		(start 217.937588 -154.434794)
		(end 218.44254 -154.939746)
		(width 0.14224)
		(layer "In11.Cu")
		(net "M_F_DQS_DP<11>")
	)
	(segment
		(start 233.045 -105.09504)
		(end 233.045 -107.348528)
		(width 0.14224)
		(layer "In11.Cu")
		(net "M_F_DQS_DP<11>")
	)
	(segment
		(start 244.215158 -93.633036)
		(end 244.179344 -93.633036)
		(width 0.0889)
		(layer "In11.Cu")
		(net "M_F_DQS_DP<11>")
	)
	(segment
		(start 246.772684 -92.737686)
		(end 246.479568 -92.90685)
		(width 0.0889)
		(layer "In11.Cu")
		(net "M_F_DQS_DP<11>")
	)
	(segment
		(start 238.202724 -97.100136)
		(end 238.169958 -97.100136)
		(width 0.0889)
		(layer "In11.Cu")
		(net "M_F_DQS_DP<11>")
	)
	(segment
		(start 220.01988 -120.37314)
		(end 220.01988 -125.859286)
		(width 0.14224)
		(layer "In11.Cu")
		(net "M_F_DQS_DP<11>")
	)
	(segment
		(start 217.937588 -149.86)
		(end 217.937588 -154.434794)
		(width 0.14224)
		(layer "In11.Cu")
		(net "M_F_DQS_DP<11>")
	)
	(segment
		(start 220.020388 -120.37314)
		(end 220.01988 -120.37314)
		(width 0.14224)
		(layer "In11.Cu")
		(net "M_F_DQS_DP<11>")
	)
	(segment
		(start 235.871004 -102.324916)
		(end 234.380024 -103.815896)
		(width 0.0889)
		(layer "In11.Cu")
		(net "M_F_DQS_DP<11>")
	)
	(segment
		(start 218.729306 -149.4282)
		(end 218.44254 -149.4282)
		(width 0.14224)
		(layer "In11.Cu")
		(net "M_F_DQS_DP<11>")
	)
	(segment
		(start 239.919764 -96.109536)
		(end 239.886998 -96.109536)
		(width 0.0889)
		(layer "In11.Cu")
		(net "M_F_DQS_DP<11>")
	)
	(segment
		(start 233.045 -107.348528)
		(end 220.020388 -120.37314)
		(width 0.14224)
		(layer "In11.Cu")
		(net "M_F_DQS_DP<11>")
	)
	(segment
		(start 234.324144 -103.815896)
		(end 234.308396 -103.831644)
		(width 0.0889)
		(layer "In11.Cu")
		(net "M_F_DQS_DP<11>")
	)
	(segment
		(start 218.95562 -149.201886)
		(end 218.729306 -149.4282)
		(width 0.14224)
		(layer "In11.Cu")
		(net "M_F_DQS_DP<11>")
	)
	(segment
		(start 218.369388 -149.4282)
		(end 217.937588 -149.86)
		(width 0.14224)
		(layer "In11.Cu")
		(net "M_F_DQS_DP<11>")
	)
	(segment
		(start 237.340394 -97.59569)
		(end 237.307628 -97.59569)
		(width 0.0889)
		(layer "In11.Cu")
		(net "M_F_DQS_DP<11>")
	)
	(segment
		(start 218.44254 -149.4282)
		(end 218.369388 -149.4282)
		(width 0.14224)
		(layer "In11.Cu")
		(net "M_F_DQS_DP<11>")
	)
	(segment
		(start 218.95562 -126.923546)
		(end 218.95562 -149.201886)
		(width 0.14224)
		(layer "In11.Cu")
		(net "M_F_DQS_DP<11>")
	)
	(segment
		(start 235.963714 -99.368102)
		(end 235.958888 -99.376738)
		(width 0.0889)
		(layer "In11.Cu")
		(net "M_F_DQS_DP<11>")
	)
	(segment
		(start 246.479568 -92.90685)
		(end 246.39016 -92.88272)
		(width 0.0889)
		(layer "In11.Cu")
		(net "M_F_DQS_DP<11>")
	)
	(segment
		(start 240.774474 -95.61449)
		(end 240.741708 -95.61449)
		(width 0.0889)
		(layer "In11.Cu")
		(net "M_F_DQS_DP<11>")
	)
	(segment
		(start 220.01988 -125.859286)
		(end 218.95562 -126.923546)
		(width 0.14224)
		(layer "In11.Cu")
		(net "M_F_DQS_DP<11>")
	)
	(segment
		(start 239.057434 -96.60509)
		(end 239.024668 -96.60509)
		(width 0.0889)
		(layer "In11.Cu")
		(net "M_F_DQS_DP<11>")
	)
	(segment
		(start 234.380024 -103.815896)
		(end 234.324144 -103.815896)
		(width 0.0889)
		(layer "In11.Cu")
		(net "M_F_DQS_DP<11>")
	)
	(segment
		(start 235.952538 -99.95662)
		(end 235.958888 -99.967288)
		(width 0.0889)
		(layer "In11.Cu")
		(net "M_F_DQS_DP<11>")
	)
	(segment
		(start 235.963968 -101.349048)
		(end 235.871004 -101.510338)
		(width 0.0889)
		(layer "In11.Cu")
		(net "M_F_DQS_DP<11>")
	)
	(segment
		(start 243.356638 -94.128336)
		(end 243.317014 -94.128336)
		(width 0.0889)
		(layer "In11.Cu")
		(net "M_F_DQS_DP<11>")
	)
	(arc
		(start 245.892574 -92.64269)
		(mid 245.609357 -92.726971)
		(end 245.402354 -92.937838)
		(width 0.0889)
		(layer "In11.Cu")
		(net "M_F_DQS_DP<11>")
	)
	(arc
		(start 243.685314 -93.928438)
		(mid 243.54657 -94.070471)
		(end 243.356638 -94.128336)
		(width 0.0889)
		(layer "In11.Cu")
		(net "M_F_DQS_DP<11>")
	)
	(arc
		(start 239.392968 -96.404938)
		(mid 239.251285 -96.548742)
		(end 239.057434 -96.60509)
		(width 0.0889)
		(layer "In11.Cu")
		(net "M_F_DQS_DP<11>")
	)
	(arc
		(start 241.968528 -94.919038)
		(mid 241.828449 -95.061774)
		(end 241.636804 -95.118936)
		(width 0.0889)
		(layer "In11.Cu")
		(net "M_F_DQS_DP<11>")
	)
	(arc
		(start 235.958888 -100.367084)
		(mid 235.879757 -100.662486)
		(end 235.958888 -100.957888)
		(width 0.0889)
		(layer "In11.Cu")
		(net "M_F_DQS_DP<11>")
	)
	(arc
		(start 239.024668 -96.60509)
		(mid 238.741451 -96.689371)
		(end 238.534448 -96.900238)
		(width 0.0889)
		(layer "In11.Cu")
		(net "M_F_DQS_DP<11>")
	)
	(arc
		(start 243.317014 -94.128336)
		(mid 243.033797 -94.212617)
		(end 242.826794 -94.423484)
		(width 0.0889)
		(layer "In11.Cu")
		(net "M_F_DQS_DP<11>")
	)
	(arc
		(start 236.452918 -98.090736)
		(mid 235.954667 -98.393576)
		(end 235.958888 -98.976688)
		(width 0.0889)
		(layer "In11.Cu")
		(net "M_F_DQS_DP<11>")
	)
	(arc
		(start 244.179344 -93.633036)
		(mid 243.89392 -93.716503)
		(end 243.685314 -93.928438)
		(width 0.0889)
		(layer "In11.Cu")
		(net "M_F_DQS_DP<11>")
	)
	(arc
		(start 235.958888 -99.967288)
		(mid 236.012387 -100.167186)
		(end 235.958888 -100.367084)
		(width 0.0889)
		(layer "In11.Cu")
		(net "M_F_DQS_DP<11>")
	)
	(arc
		(start 238.169958 -97.100136)
		(mid 237.884534 -97.183603)
		(end 237.675928 -97.395538)
		(width 0.0889)
		(layer "In11.Cu")
		(net "M_F_DQS_DP<11>")
	)
	(arc
		(start 235.958888 -99.376738)
		(mid 235.879666 -99.665856)
		(end 235.952538 -99.95662)
		(width 0.0889)
		(layer "In11.Cu")
		(net "M_F_DQS_DP<11>")
	)
	(arc
		(start 235.959142 -100.958142)
		(mid 236.012451 -101.152951)
		(end 235.963968 -101.349048)
		(width 0.0889)
		(layer "In11.Cu")
		(net "M_F_DQS_DP<11>")
	)
	(arc
		(start 246.39016 -92.88272)
		(mid 246.190415 -92.710726)
		(end 245.935754 -92.64269)
		(width 0.0889)
		(layer "In11.Cu")
		(net "M_F_DQS_DP<11>")
	)
	(arc
		(start 242.467384 -94.623636)
		(mid 242.179239 -94.705955)
		(end 241.968528 -94.919038)
		(width 0.0889)
		(layer "In11.Cu")
		(net "M_F_DQS_DP<11>")
	)
	(arc
		(start 245.402354 -92.937838)
		(mid 245.262275 -93.080574)
		(end 245.07063 -93.137736)
		(width 0.0889)
		(layer "In11.Cu")
		(net "M_F_DQS_DP<11>")
	)
	(arc
		(start 241.110008 -95.414338)
		(mid 240.968325 -95.558142)
		(end 240.774474 -95.61449)
		(width 0.0889)
		(layer "In11.Cu")
		(net "M_F_DQS_DP<11>")
	)
	(arc
		(start 237.307628 -97.59569)
		(mid 237.024411 -97.679971)
		(end 236.817408 -97.890838)
		(width 0.0889)
		(layer "In11.Cu")
		(net "M_F_DQS_DP<11>")
	)
	(arc
		(start 240.741708 -95.61449)
		(mid 240.458491 -95.698771)
		(end 240.251488 -95.909638)
		(width 0.0889)
		(layer "In11.Cu")
		(net "M_F_DQS_DP<11>")
	)
	(arc
		(start 238.534448 -96.900238)
		(mid 238.394369 -97.042974)
		(end 238.202724 -97.100136)
		(width 0.0889)
		(layer "In11.Cu")
		(net "M_F_DQS_DP<11>")
	)
	(arc
		(start 240.251488 -95.909638)
		(mid 240.111409 -96.052374)
		(end 239.919764 -96.109536)
		(width 0.0889)
		(layer "In11.Cu")
		(net "M_F_DQS_DP<11>")
	)
	(arc
		(start 242.823492 -94.429326)
		(mid 242.677526 -94.571725)
		(end 242.480338 -94.623636)
		(width 0.0889)
		(layer "In11.Cu")
		(net "M_F_DQS_DP<11>")
	)
	(arc
		(start 239.886998 -96.109536)
		(mid 239.601574 -96.193003)
		(end 239.392968 -96.404938)
		(width 0.0889)
		(layer "In11.Cu")
		(net "M_F_DQS_DP<11>")
	)
	(arc
		(start 236.817408 -97.890838)
		(mid 236.677329 -98.033574)
		(end 236.485684 -98.090736)
		(width 0.0889)
		(layer "In11.Cu")
		(net "M_F_DQS_DP<11>")
	)
	(arc
		(start 241.604038 -95.118936)
		(mid 241.318614 -95.202403)
		(end 241.110008 -95.414338)
		(width 0.0889)
		(layer "In11.Cu")
		(net "M_F_DQS_DP<11>")
	)
	(arc
		(start 244.543834 -93.433138)
		(mid 244.40509 -93.575171)
		(end 244.215158 -93.633036)
		(width 0.0889)
		(layer "In11.Cu")
		(net "M_F_DQS_DP<11>")
	)
	(arc
		(start 235.958888 -98.976688)
		(mid 236.012358 -99.171751)
		(end 235.963714 -99.368102)
		(width 0.0889)
		(layer "In11.Cu")
		(net "M_F_DQS_DP<11>")
	)
	(arc
		(start 237.675928 -97.395538)
		(mid 237.534245 -97.539342)
		(end 237.340394 -97.59569)
		(width 0.0889)
		(layer "In11.Cu")
		(net "M_F_DQS_DP<11>")
	)
	(arc
		(start 245.04269 -93.137736)
		(mid 244.754545 -93.220055)
		(end 244.543834 -93.433138)
		(width 0.0889)
		(layer "In11.Cu")
		(net "M_F_DQS_DP<11>")
	)
	(segment
		(start 208.713832 -153.331672)
		(end 208.62925 -153.515568)
		(width 0.1651)
		(layer "F.Cu")
		(net "M_F_DQS_DP<10>")
	)
	(segment
		(start 208.710784 -154.557984)
		(end 209.092546 -154.939746)
		(width 0.1651)
		(layer "F.Cu")
		(net "M_F_DQS_DP<10>")
	)
	(segment
		(start 209.14995 -152.895554)
		(end 208.713832 -153.331672)
		(width 0.1651)
		(layer "F.Cu")
		(net "M_F_DQS_DP<10>")
	)
	(segment
		(start 209.150458 -152.273)
		(end 209.14995 -152.278842)
		(width 0.1651)
		(layer "F.Cu")
		(net "M_F_DQS_DP<10>")
	)
	(segment
		(start 208.62925 -154.333702)
		(end 208.710784 -154.557984)
		(width 0.1651)
		(layer "F.Cu")
		(net "M_F_DQS_DP<10>")
	)
	(segment
		(start 209.14995 -152.278842)
		(end 209.14995 -152.895554)
		(width 0.1651)
		(layer "F.Cu")
		(net "M_F_DQS_DP<10>")
	)
	(segment
		(start 208.62925 -153.515568)
		(end 208.62925 -154.333702)
		(width 0.1651)
		(layer "F.Cu")
		(net "M_F_DQS_DP<10>")
	)
	(segment
		(start 243.051838 -92.24264)
		(end 242.480338 -92.24264)
		(width 0.1651)
		(layer "F.Cu")
		(net "M_F_DQS_DP<10>")
	)
	(via
		(at 209.092546 -149.4282)
		(size 0.508)
		(drill 0.254)
		(layers "F.Cu" "B.Cu")
		(net "M_F_DQS_DP<10>")
	)
	(via
		(at 209.092546 -154.939746)
		(size 0.508)
		(drill 0.254)
		(layers "F.Cu" "B.Cu")
		(net "M_F_DQS_DP<10>")
	)
	(via
		(at 242.480338 -92.24264)
		(size 0.508)
		(drill 0.254)
		(layers "F.Cu" "B.Cu")
		(net "M_F_DQS_DP<10>")
	)
	(segment
		(start 208.61655 -149.976332)
		(end 208.703926 -149.81682)
		(width 0.1651)
		(layer "B.Cu")
		(net "M_F_DQS_DP<10>")
	)
	(segment
		(start 209.14995 -152.078182)
		(end 209.14995 -151.460454)
		(width 0.1651)
		(layer "B.Cu")
		(net "M_F_DQS_DP<10>")
	)
	(segment
		(start 209.14995 -151.460454)
		(end 208.693766 -151.00427)
		(width 0.1651)
		(layer "B.Cu")
		(net "M_F_DQS_DP<10>")
	)
	(segment
		(start 208.703926 -149.81682)
		(end 209.092546 -149.4282)
		(width 0.1651)
		(layer "B.Cu")
		(net "M_F_DQS_DP<10>")
	)
	(segment
		(start 208.61655 -150.871936)
		(end 208.61655 -149.976332)
		(width 0.1651)
		(layer "B.Cu")
		(net "M_F_DQS_DP<10>")
	)
	(segment
		(start 209.150458 -152.078436)
		(end 209.14995 -152.078182)
		(width 0.1651)
		(layer "B.Cu")
		(net "M_F_DQS_DP<10>")
	)
	(segment
		(start 208.693766 -151.00427)
		(end 208.61655 -150.871936)
		(width 0.1651)
		(layer "B.Cu")
		(net "M_F_DQS_DP<10>")
	)
	(segment
		(start 210.47075 -127.429514)
		(end 209.984594 -127.429514)
		(width 0.14224)
		(layer "In11.Cu")
		(net "M_F_DQS_DP<10>")
	)
	(segment
		(start 240.784888 -90.66149)
		(end 240.752122 -90.66149)
		(width 0.0889)
		(layer "In11.Cu")
		(net "M_F_DQS_DP<10>")
	)
	(segment
		(start 238.202724 -91.156536)
		(end 238.169958 -91.156536)
		(width 0.0889)
		(layer "In11.Cu")
		(net "M_F_DQS_DP<10>")
	)
	(segment
		(start 236.485684 -92.147136)
		(end 236.452918 -92.147136)
		(width 0.0889)
		(layer "In11.Cu")
		(net "M_F_DQS_DP<10>")
	)
	(segment
		(start 209.605626 -127.808482)
		(end 209.605626 -149.201886)
		(width 0.14224)
		(layer "In11.Cu")
		(net "M_F_DQS_DP<10>")
	)
	(segment
		(start 210.43646 -124.269754)
		(end 210.657948 -124.491242)
		(width 0.14224)
		(layer "In11.Cu")
		(net "M_F_DQS_DP<10>")
	)
	(segment
		(start 229.53472 -96.11741)
		(end 228.24059 -96.11741)
		(width 0.14224)
		(layer "In11.Cu")
		(net "M_F_DQS_DP<10>")
	)
	(segment
		(start 209.605626 -125.522482)
		(end 209.605626 -126.176786)
		(width 0.14224)
		(layer "In11.Cu")
		(net "M_F_DQS_DP<10>")
	)
	(segment
		(start 209.605626 -117.9957)
		(end 209.605626 -123.890786)
		(width 0.14224)
		(layer "In11.Cu")
		(net "M_F_DQS_DP<10>")
	)
	(segment
		(start 209.605626 -126.176786)
		(end 209.984594 -126.555754)
		(width 0.14224)
		(layer "In11.Cu")
		(net "M_F_DQS_DP<10>")
	)
	(segment
		(start 209.606134 -117.9957)
		(end 209.605626 -117.9957)
		(width 0.14224)
		(layer "In11.Cu")
		(net "M_F_DQS_DP<10>")
	)
	(segment
		(start 210.679284 -127.22098)
		(end 210.47075 -127.429514)
		(width 0.14224)
		(layer "In11.Cu")
		(net "M_F_DQS_DP<10>")
	)
	(segment
		(start 210.657948 -124.922788)
		(end 210.437222 -125.143514)
		(width 0.14224)
		(layer "In11.Cu")
		(net "M_F_DQS_DP<10>")
	)
	(segment
		(start 209.984594 -125.143514)
		(end 209.605626 -125.522482)
		(width 0.14224)
		(layer "In11.Cu")
		(net "M_F_DQS_DP<10>")
	)
	(segment
		(start 235.623354 -92.64269)
		(end 235.590588 -92.64269)
		(width 0.0889)
		(layer "In11.Cu")
		(net "M_F_DQS_DP<10>")
	)
	(segment
		(start 234.768644 -93.137736)
		(end 234.242102 -93.137736)
		(width 0.0889)
		(layer "In11.Cu")
		(net "M_F_DQS_DP<10>")
	)
	(segment
		(start 209.092546 -149.4282)
		(end 209.019394 -149.4282)
		(width 0.14224)
		(layer "In11.Cu")
		(net "M_F_DQS_DP<10>")
	)
	(segment
		(start 241.639598 -91.156536)
		(end 241.606832 -91.156536)
		(width 0.0889)
		(layer "In11.Cu")
		(net "M_F_DQS_DP<10>")
	)
	(segment
		(start 210.679284 -126.788672)
		(end 210.679284 -127.22098)
		(width 0.14224)
		(layer "In11.Cu")
		(net "M_F_DQS_DP<10>")
	)
	(segment
		(start 209.605626 -149.201886)
		(end 209.379312 -149.4282)
		(width 0.14224)
		(layer "In11.Cu")
		(net "M_F_DQS_DP<10>")
	)
	(segment
		(start 208.587594 -154.434794)
		(end 209.092546 -154.939746)
		(width 0.14224)
		(layer "In11.Cu")
		(net "M_F_DQS_DP<10>")
	)
	(segment
		(start 239.905794 -90.16619)
		(end 239.903762 -90.16619)
		(width 0.0889)
		(layer "In11.Cu")
		(net "M_F_DQS_DP<10>")
	)
	(segment
		(start 242.187222 -92.073476)
		(end 242.163346 -91.984068)
		(width 0.0889)
		(layer "In11.Cu")
		(net "M_F_DQS_DP<10>")
	)
	(segment
		(start 210.657948 -124.491242)
		(end 210.657948 -124.922788)
		(width 0.14224)
		(layer "In11.Cu")
		(net "M_F_DQS_DP<10>")
	)
	(segment
		(start 209.605626 -123.890786)
		(end 209.984594 -124.269754)
		(width 0.14224)
		(layer "In11.Cu")
		(net "M_F_DQS_DP<10>")
	)
	(segment
		(start 209.379312 -149.4282)
		(end 209.092546 -149.4282)
		(width 0.14224)
		(layer "In11.Cu")
		(net "M_F_DQS_DP<10>")
	)
	(segment
		(start 230.257858 -96.15678)
		(end 229.596188 -96.15678)
		(width 0.0889)
		(layer "In11.Cu")
		(net "M_F_DQS_DP<10>")
	)
	(segment
		(start 210.446366 -126.555754)
		(end 210.679284 -126.788672)
		(width 0.14224)
		(layer "In11.Cu")
		(net "M_F_DQS_DP<10>")
	)
	(segment
		(start 229.596188 -96.15678)
		(end 229.556818 -96.11741)
		(width 0.0889)
		(layer "In11.Cu")
		(net "M_F_DQS_DP<10>")
	)
	(segment
		(start 208.587594 -149.86)
		(end 208.587594 -154.434794)
		(width 0.14224)
		(layer "In11.Cu")
		(net "M_F_DQS_DP<10>")
	)
	(segment
		(start 226.40036 -101.201474)
		(end 209.606134 -117.9957)
		(width 0.14224)
		(layer "In11.Cu")
		(net "M_F_DQS_DP<10>")
	)
	(segment
		(start 229.556818 -96.11741)
		(end 229.53472 -96.11741)
		(width 0.0889)
		(layer "In11.Cu")
		(net "M_F_DQS_DP<10>")
	)
	(segment
		(start 209.019394 -149.4282)
		(end 208.587594 -149.86)
		(width 0.14224)
		(layer "In11.Cu")
		(net "M_F_DQS_DP<10>")
	)
	(segment
		(start 209.984594 -126.555754)
		(end 210.446366 -126.555754)
		(width 0.14224)
		(layer "In11.Cu")
		(net "M_F_DQS_DP<10>")
	)
	(segment
		(start 234.242102 -93.137736)
		(end 233.110024 -94.269814)
		(width 0.0889)
		(layer "In11.Cu")
		(net "M_F_DQS_DP<10>")
	)
	(segment
		(start 210.437222 -125.143514)
		(end 209.984594 -125.143514)
		(width 0.14224)
		(layer "In11.Cu")
		(net "M_F_DQS_DP<10>")
	)
	(segment
		(start 228.24059 -96.11741)
		(end 226.40036 -97.95764)
		(width 0.14224)
		(layer "In11.Cu")
		(net "M_F_DQS_DP<10>")
	)
	(segment
		(start 232.144824 -94.269814)
		(end 230.257858 -96.15678)
		(width 0.0889)
		(layer "In11.Cu")
		(net "M_F_DQS_DP<10>")
	)
	(segment
		(start 226.40036 -97.95764)
		(end 226.40036 -101.201474)
		(width 0.14224)
		(layer "In11.Cu")
		(net "M_F_DQS_DP<10>")
	)
	(segment
		(start 209.984594 -124.269754)
		(end 210.43646 -124.269754)
		(width 0.14224)
		(layer "In11.Cu")
		(net "M_F_DQS_DP<10>")
	)
	(segment
		(start 239.057434 -90.66149)
		(end 239.024668 -90.66149)
		(width 0.0889)
		(layer "In11.Cu")
		(net "M_F_DQS_DP<10>")
	)
	(segment
		(start 233.110024 -94.269814)
		(end 232.144824 -94.269814)
		(width 0.0889)
		(layer "In11.Cu")
		(net "M_F_DQS_DP<10>")
	)
	(segment
		(start 209.984594 -127.429514)
		(end 209.605626 -127.808482)
		(width 0.14224)
		(layer "In11.Cu")
		(net "M_F_DQS_DP<10>")
	)
	(segment
		(start 237.340394 -91.65209)
		(end 237.307628 -91.65209)
		(width 0.0889)
		(layer "In11.Cu")
		(net "M_F_DQS_DP<10>")
	)
	(segment
		(start 242.480338 -92.24264)
		(end 242.187222 -92.073476)
		(width 0.0889)
		(layer "In11.Cu")
		(net "M_F_DQS_DP<10>")
	)
	(arc
		(start 236.817408 -91.947238)
		(mid 236.677329 -92.089974)
		(end 236.485684 -92.147136)
		(width 0.0889)
		(layer "In11.Cu")
		(net "M_F_DQS_DP<10>")
	)
	(arc
		(start 237.307628 -91.65209)
		(mid 237.024411 -91.736371)
		(end 236.817408 -91.947238)
		(width 0.0889)
		(layer "In11.Cu")
		(net "M_F_DQS_DP<10>")
	)
	(arc
		(start 235.958888 -92.442538)
		(mid 235.817205 -92.586342)
		(end 235.623354 -92.64269)
		(width 0.0889)
		(layer "In11.Cu")
		(net "M_F_DQS_DP<10>")
	)
	(arc
		(start 241.275108 -90.956638)
		(mid 241.068104 -90.745774)
		(end 240.784888 -90.66149)
		(width 0.0889)
		(layer "In11.Cu")
		(net "M_F_DQS_DP<10>")
	)
	(arc
		(start 241.606832 -91.156536)
		(mid 241.41519 -91.09937)
		(end 241.275108 -90.956638)
		(width 0.0889)
		(layer "In11.Cu")
		(net "M_F_DQS_DP<10>")
	)
	(arc
		(start 235.590588 -92.64269)
		(mid 235.307371 -92.726971)
		(end 235.100368 -92.937838)
		(width 0.0889)
		(layer "In11.Cu")
		(net "M_F_DQS_DP<10>")
	)
	(arc
		(start 239.903762 -90.16619)
		(mid 239.608768 -90.245264)
		(end 239.392968 -90.461338)
		(width 0.0889)
		(layer "In11.Cu")
		(net "M_F_DQS_DP<10>")
	)
	(arc
		(start 242.163346 -91.984068)
		(mid 242.121367 -91.431108)
		(end 241.639598 -91.156536)
		(width 0.0889)
		(layer "In11.Cu")
		(net "M_F_DQS_DP<10>")
	)
	(arc
		(start 238.534448 -90.956638)
		(mid 238.394369 -91.099374)
		(end 238.202724 -91.156536)
		(width 0.0889)
		(layer "In11.Cu")
		(net "M_F_DQS_DP<10>")
	)
	(arc
		(start 235.100368 -92.937838)
		(mid 234.960289 -93.080574)
		(end 234.768644 -93.137736)
		(width 0.0889)
		(layer "In11.Cu")
		(net "M_F_DQS_DP<10>")
	)
	(arc
		(start 238.169958 -91.156536)
		(mid 237.884534 -91.240003)
		(end 237.675928 -91.451938)
		(width 0.0889)
		(layer "In11.Cu")
		(net "M_F_DQS_DP<10>")
	)
	(arc
		(start 237.675928 -91.451938)
		(mid 237.534245 -91.595742)
		(end 237.340394 -91.65209)
		(width 0.0889)
		(layer "In11.Cu")
		(net "M_F_DQS_DP<10>")
	)
	(arc
		(start 240.416588 -90.461338)
		(mid 240.200734 -90.245357)
		(end 239.905794 -90.16619)
		(width 0.0889)
		(layer "In11.Cu")
		(net "M_F_DQS_DP<10>")
	)
	(arc
		(start 239.024668 -90.66149)
		(mid 238.741451 -90.745771)
		(end 238.534448 -90.956638)
		(width 0.0889)
		(layer "In11.Cu")
		(net "M_F_DQS_DP<10>")
	)
	(arc
		(start 240.752122 -90.66149)
		(mid 240.558272 -90.60514)
		(end 240.416588 -90.461338)
		(width 0.0889)
		(layer "In11.Cu")
		(net "M_F_DQS_DP<10>")
	)
	(arc
		(start 239.392968 -90.461338)
		(mid 239.251285 -90.605142)
		(end 239.057434 -90.66149)
		(width 0.0889)
		(layer "In11.Cu")
		(net "M_F_DQS_DP<10>")
	)
	(arc
		(start 236.452918 -92.147136)
		(mid 236.167494 -92.230603)
		(end 235.958888 -92.442538)
		(width 0.0889)
		(layer "In11.Cu")
		(net "M_F_DQS_DP<10>")
	)
	(segment
		(start 201.537824 -154.4574)
		(end 201.293984 -154.21356)
		(width 0.1651)
		(layer "F.Cu")
		(net "M_F_DQS_DP<0>")
	)
	(segment
		(start 201.293984 -154.21356)
		(end 201.037952 -154.21356)
		(width 0.1651)
		(layer "F.Cu")
		(net "M_F_DQS_DP<0>")
	)
	(segment
		(start 201.537824 -155.829)
		(end 201.537824 -154.4574)
		(width 0.1651)
		(layer "F.Cu")
		(net "M_F_DQS_DP<0>")
	)
	(segment
		(start 201.499978 -156.87294)
		(end 201.499978 -155.866846)
		(width 0.1651)
		(layer "F.Cu")
		(net "M_F_DQS_DP<0>")
	)
	(segment
		(start 201.499978 -155.866846)
		(end 201.537824 -155.829)
		(width 0.1651)
		(layer "F.Cu")
		(net "M_F_DQS_DP<0>")
	)
	(segment
		(start 201.500486 -156.87294)
		(end 201.499978 -156.87294)
		(width 0.1651)
		(layer "F.Cu")
		(net "M_F_DQS_DP<0>")
	)
	(segment
		(start 241.334798 -86.29904)
		(end 240.763298 -86.29904)
		(width 0.1651)
		(layer "F.Cu")
		(net "M_F_DQS_DP<0>")
	)
	(via
		(at 201.037952 -154.21356)
		(size 0.508)
		(drill 0.254)
		(layers "F.Cu" "B.Cu")
		(net "M_F_DQS_DP<0>")
	)
	(via
		(at 201.037952 -150.142956)
		(size 0.508)
		(drill 0.254)
		(layers "F.Cu" "B.Cu")
		(net "M_F_DQS_DP<0>")
	)
	(via
		(at 240.763298 -86.29904)
		(size 0.508)
		(drill 0.254)
		(layers "F.Cu" "B.Cu")
		(net "M_F_DQS_DP<0>")
	)
	(segment
		(start 201.537824 -149.8854)
		(end 201.280268 -150.142956)
		(width 0.1651)
		(layer "B.Cu")
		(net "M_F_DQS_DP<0>")
	)
	(segment
		(start 201.537824 -148.6662)
		(end 201.537824 -149.8854)
		(width 0.1651)
		(layer "B.Cu")
		(net "M_F_DQS_DP<0>")
	)
	(segment
		(start 201.499978 -148.628354)
		(end 201.537824 -148.6662)
		(width 0.1651)
		(layer "B.Cu")
		(net "M_F_DQS_DP<0>")
	)
	(segment
		(start 201.280268 -150.142956)
		(end 201.037952 -150.142956)
		(width 0.1651)
		(layer "B.Cu")
		(net "M_F_DQS_DP<0>")
	)
	(segment
		(start 201.499978 -147.478496)
		(end 201.499978 -148.628354)
		(width 0.1651)
		(layer "B.Cu")
		(net "M_F_DQS_DP<0>")
	)
	(segment
		(start 201.500486 -147.478496)
		(end 201.499978 -147.478496)
		(width 0.1651)
		(layer "B.Cu")
		(net "M_F_DQS_DP<0>")
	)
	(segment
		(start 202.76312 -119.00408)
		(end 202.384914 -119.382286)
		(width 0.14224)
		(layer "In11.Cu")
		(net "M_F_DQS_DP<0>")
	)
	(segment
		(start 201.631804 -119.382286)
		(end 201.402696 -119.611394)
		(width 0.14224)
		(layer "In11.Cu")
		(net "M_F_DQS_DP<0>")
	)
	(segment
		(start 202.7174 -125.889512)
		(end 201.820272 -126.78664)
		(width 0.14224)
		(layer "In11.Cu")
		(net "M_F_DQS_DP<0>")
	)
	(segment
		(start 202.76312 -121.289318)
		(end 202.384152 -121.668286)
		(width 0.14224)
		(layer "In11.Cu")
		(net "M_F_DQS_DP<0>")
	)
	(segment
		(start 201.424032 -122.542046)
		(end 202.384152 -122.542046)
		(width 0.14224)
		(layer "In11.Cu")
		(net "M_F_DQS_DP<0>")
	)
	(segment
		(start 239.675162 -86.203282)
		(end 239.398048 -86.033356)
		(width 0.0889)
		(layer "In11.Cu")
		(net "M_F_DQS_DP<0>")
	)
	(segment
		(start 228.450902 -89.594944)
		(end 228.428804 -89.594944)
		(width 0.0889)
		(layer "In11.Cu")
		(net "M_F_DQS_DP<0>")
	)
	(segment
		(start 201.11212 -124.175774)
		(end 201.11212 -124.60732)
		(width 0.14224)
		(layer "In11.Cu")
		(net "M_F_DQS_DP<0>")
	)
	(segment
		(start 202.384152 -122.542046)
		(end 202.76312 -122.921014)
		(width 0.14224)
		(layer "In11.Cu")
		(net "M_F_DQS_DP<0>")
	)
	(segment
		(start 202.384914 -119.382286)
		(end 201.631804 -119.382286)
		(width 0.14224)
		(layer "In11.Cu")
		(net "M_F_DQS_DP<0>")
	)
	(segment
		(start 200.833736 -151.257)
		(end 200.663302 -151.427434)
		(width 0.14224)
		(layer "In11.Cu")
		(net "M_F_DQS_DP<0>")
	)
	(segment
		(start 228.490272 -89.555574)
		(end 228.450902 -89.594944)
		(width 0.0889)
		(layer "In11.Cu")
		(net "M_F_DQS_DP<0>")
	)
	(segment
		(start 210.1596 -104.3686)
		(end 206.375 -108.1532)
		(width 0.14224)
		(layer "In11.Cu")
		(net "M_F_DQS_DP<0>")
	)
	(segment
		(start 240.763298 -86.29904)
		(end 240.248694 -86.203282)
		(width 0.0889)
		(layer "In11.Cu")
		(net "M_F_DQS_DP<0>")
	)
	(segment
		(start 200.8632 -151.8666)
		(end 201.041 -152.0444)
		(width 0.14224)
		(layer "In11.Cu")
		(net "M_F_DQS_DP<0>")
	)
	(segment
		(start 218.78544 -98.63836)
		(end 218.78544 -99.880674)
		(width 0.14224)
		(layer "In11.Cu")
		(net "M_F_DQS_DP<0>")
	)
	(segment
		(start 234.775248 -88.375236)
		(end 234.742482 -88.375236)
		(width 0.0889)
		(layer "In11.Cu")
		(net "M_F_DQS_DP<0>")
	)
	(segment
		(start 200.86066 -152.501092)
		(end 200.800462 -152.501092)
		(width 0.14224)
		(layer "In11.Cu")
		(net "M_F_DQS_DP<0>")
	)
	(segment
		(start 200.663302 -152.864566)
		(end 200.859136 -153.0604)
		(width 0.14224)
		(layer "In11.Cu")
		(net "M_F_DQS_DP<0>")
	)
	(segment
		(start 201.820272 -126.78664)
		(end 201.820272 -149.36978)
		(width 0.14224)
		(layer "In11.Cu")
		(net "M_F_DQS_DP<0>")
	)
	(segment
		(start 201.041 -152.320752)
		(end 200.86066 -152.501092)
		(width 0.14224)
		(layer "In11.Cu")
		(net "M_F_DQS_DP<0>")
	)
	(segment
		(start 231.36352 -89.555574)
		(end 228.490272 -89.555574)
		(width 0.0889)
		(layer "In11.Cu")
		(net "M_F_DQS_DP<0>")
	)
	(segment
		(start 201.4728 -150.577804)
		(end 201.4728 -151.003)
		(width 0.14224)
		(layer "In11.Cu")
		(net "M_F_DQS_DP<0>")
	)
	(segment
		(start 201.61504 -120.256046)
		(end 202.384152 -120.256046)
		(width 0.14224)
		(layer "In11.Cu")
		(net "M_F_DQS_DP<0>")
	)
	(segment
		(start 232.191814 -89.86139)
		(end 231.669336 -89.86139)
		(width 0.0889)
		(layer "In11.Cu")
		(net "M_F_DQS_DP<0>")
	)
	(segment
		(start 202.76312 -120.635014)
		(end 202.76312 -121.289318)
		(width 0.14224)
		(layer "In11.Cu")
		(net "M_F_DQS_DP<0>")
	)
	(segment
		(start 202.384914 -123.954286)
		(end 201.333608 -123.954286)
		(width 0.14224)
		(layer "In11.Cu")
		(net "M_F_DQS_DP<0>")
	)
	(segment
		(start 231.669336 -89.86139)
		(end 231.36352 -89.555574)
		(width 0.0889)
		(layer "In11.Cu")
		(net "M_F_DQS_DP<0>")
	)
	(segment
		(start 201.333608 -123.954286)
		(end 201.11212 -124.175774)
		(width 0.14224)
		(layer "In11.Cu")
		(net "M_F_DQS_DP<0>")
	)
	(segment
		(start 201.11212 -124.60732)
		(end 201.332846 -124.828046)
		(width 0.14224)
		(layer "In11.Cu")
		(net "M_F_DQS_DP<0>")
	)
	(segment
		(start 201.4728 -151.003)
		(end 201.2188 -151.257)
		(width 0.14224)
		(layer "In11.Cu")
		(net "M_F_DQS_DP<0>")
	)
	(segment
		(start 201.402696 -120.043702)
		(end 201.61504 -120.256046)
		(width 0.14224)
		(layer "In11.Cu")
		(net "M_F_DQS_DP<0>")
	)
	(segment
		(start 202.76312 -122.921014)
		(end 202.76312 -123.57608)
		(width 0.14224)
		(layer "In11.Cu")
		(net "M_F_DQS_DP<0>")
	)
	(segment
		(start 201.424032 -121.668286)
		(end 201.203306 -121.889012)
		(width 0.14224)
		(layer "In11.Cu")
		(net "M_F_DQS_DP<0>")
	)
	(segment
		(start 228.428804 -89.594944)
		(end 227.828856 -89.594944)
		(width 0.14224)
		(layer "In11.Cu")
		(net "M_F_DQS_DP<0>")
	)
	(segment
		(start 200.663302 -151.427434)
		(end 200.663302 -151.751792)
		(width 0.14224)
		(layer "In11.Cu")
		(net "M_F_DQS_DP<0>")
	)
	(segment
		(start 227.828856 -89.594944)
		(end 218.78544 -98.63836)
		(width 0.14224)
		(layer "In11.Cu")
		(net "M_F_DQS_DP<0>")
	)
	(segment
		(start 218.78544 -99.880674)
		(end 214.297514 -104.3686)
		(width 0.14224)
		(layer "In11.Cu")
		(net "M_F_DQS_DP<0>")
	)
	(segment
		(start 200.859136 -153.0604)
		(end 201.22896 -153.0604)
		(width 0.14224)
		(layer "In11.Cu")
		(net "M_F_DQS_DP<0>")
	)
	(segment
		(start 236.492288 -87.384636)
		(end 236.459522 -87.384636)
		(width 0.0889)
		(layer "In11.Cu")
		(net "M_F_DQS_DP<0>")
	)
	(segment
		(start 201.203306 -122.32132)
		(end 201.424032 -122.542046)
		(width 0.14224)
		(layer "In11.Cu")
		(net "M_F_DQS_DP<0>")
	)
	(segment
		(start 201.037952 -150.142956)
		(end 201.4728 -150.577804)
		(width 0.14224)
		(layer "In11.Cu")
		(net "M_F_DQS_DP<0>")
	)
	(segment
		(start 202.384152 -120.256046)
		(end 202.76312 -120.635014)
		(width 0.14224)
		(layer "In11.Cu")
		(net "M_F_DQS_DP<0>")
	)
	(segment
		(start 202.7174 -125.207014)
		(end 202.7174 -125.889512)
		(width 0.14224)
		(layer "In11.Cu")
		(net "M_F_DQS_DP<0>")
	)
	(segment
		(start 233.912918 -88.87079)
		(end 233.880152 -88.87079)
		(width 0.0889)
		(layer "In11.Cu")
		(net "M_F_DQS_DP<0>")
	)
	(segment
		(start 235.629958 -87.88019)
		(end 235.597192 -87.88019)
		(width 0.0889)
		(layer "In11.Cu")
		(net "M_F_DQS_DP<0>")
	)
	(segment
		(start 200.663302 -151.751792)
		(end 200.77811 -151.8666)
		(width 0.14224)
		(layer "In11.Cu")
		(net "M_F_DQS_DP<0>")
	)
	(segment
		(start 201.332846 -124.828046)
		(end 202.338432 -124.828046)
		(width 0.14224)
		(layer "In11.Cu")
		(net "M_F_DQS_DP<0>")
	)
	(segment
		(start 206.375 -108.1532)
		(end 206.375 -108.6612)
		(width 0.14224)
		(layer "In11.Cu")
		(net "M_F_DQS_DP<0>")
	)
	(segment
		(start 202.76312 -112.27308)
		(end 202.76312 -119.00408)
		(width 0.14224)
		(layer "In11.Cu")
		(net "M_F_DQS_DP<0>")
	)
	(segment
		(start 201.2188 -151.257)
		(end 200.833736 -151.257)
		(width 0.14224)
		(layer "In11.Cu")
		(net "M_F_DQS_DP<0>")
	)
	(segment
		(start 202.76312 -123.57608)
		(end 202.384914 -123.954286)
		(width 0.14224)
		(layer "In11.Cu")
		(net "M_F_DQS_DP<0>")
	)
	(segment
		(start 201.4982 -153.32964)
		(end 201.4982 -153.753312)
		(width 0.14224)
		(layer "In11.Cu")
		(net "M_F_DQS_DP<0>")
	)
	(segment
		(start 201.22896 -153.0604)
		(end 201.4982 -153.32964)
		(width 0.14224)
		(layer "In11.Cu")
		(net "M_F_DQS_DP<0>")
	)
	(segment
		(start 233.058208 -89.365836)
		(end 233.025442 -89.365836)
		(width 0.0889)
		(layer "In11.Cu")
		(net "M_F_DQS_DP<0>")
	)
	(segment
		(start 201.041 -152.0444)
		(end 201.041 -152.320752)
		(width 0.14224)
		(layer "In11.Cu")
		(net "M_F_DQS_DP<0>")
	)
	(segment
		(start 200.663302 -152.638252)
		(end 200.663302 -152.864566)
		(width 0.14224)
		(layer "In11.Cu")
		(net "M_F_DQS_DP<0>")
	)
	(segment
		(start 201.203306 -121.889012)
		(end 201.203306 -122.32132)
		(width 0.14224)
		(layer "In11.Cu")
		(net "M_F_DQS_DP<0>")
	)
	(segment
		(start 202.338432 -124.828046)
		(end 202.7174 -125.207014)
		(width 0.14224)
		(layer "In11.Cu")
		(net "M_F_DQS_DP<0>")
	)
	(segment
		(start 201.047096 -150.142956)
		(end 201.037952 -150.142956)
		(width 0.14224)
		(layer "In11.Cu")
		(net "M_F_DQS_DP<0>")
	)
	(segment
		(start 200.800462 -152.501092)
		(end 200.663302 -152.638252)
		(width 0.14224)
		(layer "In11.Cu")
		(net "M_F_DQS_DP<0>")
	)
	(segment
		(start 239.061244 -85.89899)
		(end 239.031272 -85.89899)
		(width 0.0889)
		(layer "In11.Cu")
		(net "M_F_DQS_DP<0>")
	)
	(segment
		(start 206.375 -108.6612)
		(end 202.76312 -112.27308)
		(width 0.14224)
		(layer "In11.Cu")
		(net "M_F_DQS_DP<0>")
	)
	(segment
		(start 202.384152 -121.668286)
		(end 201.424032 -121.668286)
		(width 0.14224)
		(layer "In11.Cu")
		(net "M_F_DQS_DP<0>")
	)
	(segment
		(start 214.297514 -104.3686)
		(end 210.1596 -104.3686)
		(width 0.14224)
		(layer "In11.Cu")
		(net "M_F_DQS_DP<0>")
	)
	(segment
		(start 200.77811 -151.8666)
		(end 200.8632 -151.8666)
		(width 0.14224)
		(layer "In11.Cu")
		(net "M_F_DQS_DP<0>")
	)
	(segment
		(start 201.820272 -149.36978)
		(end 201.047096 -150.142956)
		(width 0.14224)
		(layer "In11.Cu")
		(net "M_F_DQS_DP<0>")
	)
	(segment
		(start 201.4982 -153.753312)
		(end 201.037952 -154.21356)
		(width 0.14224)
		(layer "In11.Cu")
		(net "M_F_DQS_DP<0>")
	)
	(segment
		(start 237.346998 -86.88959)
		(end 237.314232 -86.88959)
		(width 0.0889)
		(layer "In11.Cu")
		(net "M_F_DQS_DP<0>")
	)
	(segment
		(start 240.248694 -86.203282)
		(end 239.675162 -86.203282)
		(width 0.0889)
		(layer "In11.Cu")
		(net "M_F_DQS_DP<0>")
	)
	(segment
		(start 238.209328 -86.394036)
		(end 238.176562 -86.394036)
		(width 0.0889)
		(layer "In11.Cu")
		(net "M_F_DQS_DP<0>")
	)
	(segment
		(start 201.402696 -119.611394)
		(end 201.402696 -120.043702)
		(width 0.14224)
		(layer "In11.Cu")
		(net "M_F_DQS_DP<0>")
	)
	(arc
		(start 235.265468 -88.080088)
		(mid 235.058464 -88.290952)
		(end 234.775248 -88.375236)
		(width 0.0889)
		(layer "In11.Cu")
		(net "M_F_DQS_DP<0>")
	)
	(arc
		(start 239.031272 -85.89899)
		(mid 238.83963 -85.956156)
		(end 238.699548 -86.098888)
		(width 0.0889)
		(layer "In11.Cu")
		(net "M_F_DQS_DP<0>")
	)
	(arc
		(start 235.597192 -87.88019)
		(mid 235.40555 -87.937356)
		(end 235.265468 -88.080088)
		(width 0.0889)
		(layer "In11.Cu")
		(net "M_F_DQS_DP<0>")
	)
	(arc
		(start 237.841028 -86.594188)
		(mid 237.63242 -86.80612)
		(end 237.346998 -86.88959)
		(width 0.0889)
		(layer "In11.Cu")
		(net "M_F_DQS_DP<0>")
	)
	(arc
		(start 239.211104 -85.934296)
		(mid 239.164894 -85.91676)
		(end 239.11687 -85.905086)
		(width 0.0889)
		(layer "In11.Cu")
		(net "M_F_DQS_DP<0>")
	)
	(arc
		(start 234.406948 -88.575388)
		(mid 234.19834 -88.78732)
		(end 233.912918 -88.87079)
		(width 0.0889)
		(layer "In11.Cu")
		(net "M_F_DQS_DP<0>")
	)
	(arc
		(start 233.880152 -88.87079)
		(mid 233.68851 -88.927956)
		(end 233.548428 -89.070688)
		(width 0.0889)
		(layer "In11.Cu")
		(net "M_F_DQS_DP<0>")
	)
	(arc
		(start 232.689908 -89.565988)
		(mid 232.479555 -89.77896)
		(end 232.191814 -89.86139)
		(width 0.0889)
		(layer "In11.Cu")
		(net "M_F_DQS_DP<0>")
	)
	(arc
		(start 236.123988 -87.584788)
		(mid 235.91538 -87.79672)
		(end 235.629958 -87.88019)
		(width 0.0889)
		(layer "In11.Cu")
		(net "M_F_DQS_DP<0>")
	)
	(arc
		(start 233.025442 -89.365836)
		(mid 232.831592 -89.422186)
		(end 232.689908 -89.565988)
		(width 0.0889)
		(layer "In11.Cu")
		(net "M_F_DQS_DP<0>")
	)
	(arc
		(start 233.548428 -89.070688)
		(mid 233.341424 -89.281552)
		(end 233.058208 -89.365836)
		(width 0.0889)
		(layer "In11.Cu")
		(net "M_F_DQS_DP<0>")
	)
	(arc
		(start 238.176562 -86.394036)
		(mid 237.982712 -86.450386)
		(end 237.841028 -86.594188)
		(width 0.0889)
		(layer "In11.Cu")
		(net "M_F_DQS_DP<0>")
	)
	(arc
		(start 238.699548 -86.098888)
		(mid 238.492544 -86.309752)
		(end 238.209328 -86.394036)
		(width 0.0889)
		(layer "In11.Cu")
		(net "M_F_DQS_DP<0>")
	)
	(arc
		(start 239.398048 -86.033356)
		(mid 239.306138 -85.980879)
		(end 239.211104 -85.934296)
		(width 0.0889)
		(layer "In11.Cu")
		(net "M_F_DQS_DP<0>")
	)
	(arc
		(start 236.459522 -87.384636)
		(mid 236.265672 -87.440986)
		(end 236.123988 -87.584788)
		(width 0.0889)
		(layer "In11.Cu")
		(net "M_F_DQS_DP<0>")
	)
	(arc
		(start 239.11687 -85.905086)
		(mid 239.089164 -85.901061)
		(end 239.061244 -85.89899)
		(width 0.0889)
		(layer "In11.Cu")
		(net "M_F_DQS_DP<0>")
	)
	(arc
		(start 236.982508 -87.089488)
		(mid 236.775504 -87.300352)
		(end 236.492288 -87.384636)
		(width 0.0889)
		(layer "In11.Cu")
		(net "M_F_DQS_DP<0>")
	)
	(arc
		(start 234.742482 -88.375236)
		(mid 234.548632 -88.431586)
		(end 234.406948 -88.575388)
		(width 0.0889)
		(layer "In11.Cu")
		(net "M_F_DQS_DP<0>")
	)
	(arc
		(start 237.314232 -86.88959)
		(mid 237.12259 -86.946756)
		(end 236.982508 -87.089488)
		(width 0.0889)
		(layer "In11.Cu")
		(net "M_F_DQS_DP<0>")
	)
	(segment
		(start 199.957436 -154.45613)
		(end 199.768206 -154.2669)
		(width 0.1651)
		(layer "F.Cu")
		(net "M_F_DQS_DN<9>")
	)
	(segment
		(start 199.768206 -154.2669)
		(end 199.749156 -154.2669)
		(width 0.1651)
		(layer "F.Cu")
		(net "M_F_DQS_DN<9>")
	)
	(segment
		(start 200.231756 -153.7716)
		(end 200.417684 -153.957528)
		(width 0.1651)
		(layer "F.Cu")
		(net "M_F_DQS_DN<9>")
	)
	(segment
		(start 200.64984 -152.278842)
		(end 200.64984 -152.932384)
		(width 0.1651)
		(layer "F.Cu")
		(net "M_F_DQS_DN<9>")
	)
	(segment
		(start 200.165716 -154.45613)
		(end 199.957436 -154.45613)
		(width 0.1651)
		(layer "F.Cu")
		(net "M_F_DQS_DN<9>")
	)
	(segment
		(start 200.417684 -153.957528)
		(end 200.417684 -154.204162)
		(width 0.1651)
		(layer "F.Cu")
		(net "M_F_DQS_DN<9>")
	)
	(segment
		(start 200.650348 -152.273)
		(end 200.64984 -152.278842)
		(width 0.1651)
		(layer "F.Cu")
		(net "M_F_DQS_DN<9>")
	)
	(segment
		(start 200.64984 -152.932384)
		(end 200.231756 -153.350468)
		(width 0.1651)
		(layer "F.Cu")
		(net "M_F_DQS_DN<9>")
	)
	(segment
		(start 200.231756 -153.350468)
		(end 200.231756 -153.7716)
		(width 0.1651)
		(layer "F.Cu")
		(net "M_F_DQS_DN<9>")
	)
	(segment
		(start 242.193318 -86.794086)
		(end 241.621818 -86.794086)
		(width 0.1651)
		(layer "F.Cu")
		(net "M_F_DQS_DN<9>")
	)
	(segment
		(start 200.417684 -154.204162)
		(end 200.165716 -154.45613)
		(width 0.1651)
		(layer "F.Cu")
		(net "M_F_DQS_DN<9>")
	)
	(via
		(at 199.742552 -150.0886)
		(size 0.508)
		(drill 0.254)
		(layers "F.Cu" "B.Cu")
		(net "M_F_DQS_DN<9>")
	)
	(via
		(at 199.749156 -154.2669)
		(size 0.508)
		(drill 0.254)
		(layers "F.Cu" "B.Cu")
		(net "M_F_DQS_DN<9>")
	)
	(via
		(at 241.621818 -86.794086)
		(size 0.508)
		(drill 0.254)
		(layers "F.Cu" "B.Cu")
		(net "M_F_DQS_DN<9>")
	)
	(segment
		(start 199.937116 -149.894036)
		(end 199.742552 -150.0886)
		(width 0.1651)
		(layer "B.Cu")
		(net "M_F_DQS_DN<9>")
	)
	(segment
		(start 200.650348 -152.078436)
		(end 200.650094 -152.077928)
		(width 0.1651)
		(layer "B.Cu")
		(net "M_F_DQS_DN<9>")
	)
	(segment
		(start 200.384156 -150.114)
		(end 200.164192 -149.894036)
		(width 0.1651)
		(layer "B.Cu")
		(net "M_F_DQS_DN<9>")
	)
	(segment
		(start 200.650094 -152.077928)
		(end 200.650094 -151.421592)
		(width 0.1651)
		(layer "B.Cu")
		(net "M_F_DQS_DN<9>")
	)
	(segment
		(start 200.384156 -150.4442)
		(end 200.384156 -150.114)
		(width 0.1651)
		(layer "B.Cu")
		(net "M_F_DQS_DN<9>")
	)
	(segment
		(start 200.206356 -150.622)
		(end 200.384156 -150.4442)
		(width 0.1651)
		(layer "B.Cu")
		(net "M_F_DQS_DN<9>")
	)
	(segment
		(start 200.164192 -149.894036)
		(end 199.937116 -149.894036)
		(width 0.1651)
		(layer "B.Cu")
		(net "M_F_DQS_DN<9>")
	)
	(segment
		(start 200.206356 -150.977854)
		(end 200.206356 -150.622)
		(width 0.1651)
		(layer "B.Cu")
		(net "M_F_DQS_DN<9>")
	)
	(segment
		(start 200.650094 -151.421592)
		(end 200.206356 -150.977854)
		(width 0.1651)
		(layer "B.Cu")
		(net "M_F_DQS_DN<9>")
	)
	(segment
		(start 217.9066 -98.39198)
		(end 217.9066 -99.384358)
		(width 0.14224)
		(layer "In11.Cu")
		(net "M_F_DQS_DN<9>")
	)
	(segment
		(start 205.613 -108.3564)
		(end 201.77252 -112.19688)
		(width 0.14224)
		(layer "In11.Cu")
		(net "M_F_DQS_DN<9>")
	)
	(segment
		(start 199.6694 -153.162)
		(end 199.927972 -153.162)
		(width 0.14224)
		(layer "In11.Cu")
		(net "M_F_DQS_DN<9>")
	)
	(segment
		(start 201.77252 -117.063774)
		(end 201.77252 -118.082314)
		(width 0.14224)
		(layer "In11.Cu")
		(net "M_F_DQS_DN<9>")
	)
	(segment
		(start 201.394314 -116.685568)
		(end 201.77252 -117.063774)
		(width 0.14224)
		(layer "In11.Cu")
		(net "M_F_DQS_DN<9>")
	)
	(segment
		(start 235.629958 -86.88959)
		(end 235.597192 -86.88959)
		(width 0.0889)
		(layer "In11.Cu")
		(net "M_F_DQS_DN<9>")
	)
	(segment
		(start 200.14692 -118.656608)
		(end 200.14692 -126.275846)
		(width 0.14224)
		(layer "In11.Cu")
		(net "M_F_DQS_DN<9>")
	)
	(segment
		(start 240.778284 -85.89899)
		(end 240.745518 -85.89899)
		(width 0.0889)
		(layer "In11.Cu")
		(net "M_F_DQS_DN<9>")
	)
	(segment
		(start 200.524872 -149.319488)
		(end 199.75576 -150.0886)
		(width 0.14224)
		(layer "In11.Cu")
		(net "M_F_DQS_DN<9>")
	)
	(segment
		(start 200.524872 -147.10918)
		(end 200.682352 -147.26666)
		(width 0.14224)
		(layer "In11.Cu")
		(net "M_F_DQS_DN<9>")
	)
	(segment
		(start 227.693474 -88.605106)
		(end 217.9066 -98.39198)
		(width 0.14224)
		(layer "In11.Cu")
		(net "M_F_DQS_DN<9>")
	)
	(segment
		(start 200.51268 -116.558568)
		(end 200.63968 -116.685568)
		(width 0.14224)
		(layer "In11.Cu")
		(net "M_F_DQS_DN<9>")
	)
	(segment
		(start 237.346998 -85.89899)
		(end 237.314232 -85.89899)
		(width 0.0889)
		(layer "In11.Cu")
		(net "M_F_DQS_DN<9>")
	)
	(segment
		(start 199.6567 -151.2062)
		(end 199.50684 -151.35606)
		(width 0.14224)
		(layer "In11.Cu")
		(net "M_F_DQS_DN<9>")
	)
	(segment
		(start 233.912918 -87.88019)
		(end 233.880152 -87.88019)
		(width 0.0889)
		(layer "In11.Cu")
		(net "M_F_DQS_DN<9>")
	)
	(segment
		(start 199.63892 -151.83612)
		(end 199.79386 -151.83612)
		(width 0.14224)
		(layer "In11.Cu")
		(net "M_F_DQS_DN<9>")
	)
	(segment
		(start 200.682352 -148.34362)
		(end 200.524872 -148.5011)
		(width 0.14224)
		(layer "In11.Cu")
		(net "M_F_DQS_DN<9>")
	)
	(segment
		(start 200.682352 -147.52066)
		(end 200.524872 -147.67814)
		(width 0.14224)
		(layer "In11.Cu")
		(net "M_F_DQS_DN<9>")
	)
	(segment
		(start 199.742552 -150.0886)
		(end 200.1774 -150.523448)
		(width 0.14224)
		(layer "In11.Cu")
		(net "M_F_DQS_DN<9>")
	)
	(segment
		(start 200.682352 -148.08962)
		(end 200.682352 -148.34362)
		(width 0.14224)
		(layer "In11.Cu")
		(net "M_F_DQS_DN<9>")
	)
	(segment
		(start 199.50684 -151.70404)
		(end 199.63892 -151.83612)
		(width 0.14224)
		(layer "In11.Cu")
		(net "M_F_DQS_DN<9>")
	)
	(segment
		(start 236.492288 -86.394036)
		(end 236.459522 -86.394036)
		(width 0.0889)
		(layer "In11.Cu")
		(net "M_F_DQS_DN<9>")
	)
	(segment
		(start 231.533446 -88.565736)
		(end 230.62057 -88.565736)
		(width 0.0889)
		(layer "In11.Cu")
		(net "M_F_DQS_DN<9>")
	)
	(segment
		(start 200.14692 -126.275846)
		(end 200.524872 -126.653798)
		(width 0.14224)
		(layer "In11.Cu")
		(net "M_F_DQS_DN<9>")
	)
	(segment
		(start 201.77252 -118.082314)
		(end 201.447654 -118.40718)
		(width 0.14224)
		(layer "In11.Cu")
		(net "M_F_DQS_DN<9>")
	)
	(segment
		(start 200.1774 -150.523448)
		(end 200.1774 -150.9268)
		(width 0.14224)
		(layer "In11.Cu")
		(net "M_F_DQS_DN<9>")
	)
	(segment
		(start 200.1774 -150.9268)
		(end 199.898 -151.2062)
		(width 0.14224)
		(layer "In11.Cu")
		(net "M_F_DQS_DN<9>")
	)
	(segment
		(start 200.524872 -148.5011)
		(end 200.524872 -149.319488)
		(width 0.14224)
		(layer "In11.Cu")
		(net "M_F_DQS_DN<9>")
	)
	(segment
		(start 200.63968 -115.811808)
		(end 200.51268 -115.938808)
		(width 0.14224)
		(layer "In11.Cu")
		(net "M_F_DQS_DN<9>")
	)
	(segment
		(start 200.63968 -116.685568)
		(end 201.394314 -116.685568)
		(width 0.14224)
		(layer "In11.Cu")
		(net "M_F_DQS_DN<9>")
	)
	(segment
		(start 239.915954 -85.403436)
		(end 239.883188 -85.403436)
		(width 0.0889)
		(layer "In11.Cu")
		(net "M_F_DQS_DN<9>")
	)
	(segment
		(start 200.524872 -147.93214)
		(end 200.682352 -148.08962)
		(width 0.14224)
		(layer "In11.Cu")
		(net "M_F_DQS_DN<9>")
	)
	(segment
		(start 200.51268 -115.938808)
		(end 200.51268 -116.558568)
		(width 0.14224)
		(layer "In11.Cu")
		(net "M_F_DQS_DN<9>")
	)
	(segment
		(start 201.447654 -118.40718)
		(end 200.396348 -118.40718)
		(width 0.14224)
		(layer "In11.Cu")
		(net "M_F_DQS_DN<9>")
	)
	(segment
		(start 205.613 -107.8484)
		(end 205.613 -108.3564)
		(width 0.14224)
		(layer "In11.Cu")
		(net "M_F_DQS_DN<9>")
	)
	(segment
		(start 199.9488 -151.99106)
		(end 199.9488 -152.34412)
		(width 0.14224)
		(layer "In11.Cu")
		(net "M_F_DQS_DN<9>")
	)
	(segment
		(start 199.50684 -151.35606)
		(end 199.50684 -151.70404)
		(width 0.14224)
		(layer "In11.Cu")
		(net "M_F_DQS_DN<9>")
	)
	(segment
		(start 201.394314 -115.811808)
		(end 200.63968 -115.811808)
		(width 0.14224)
		(layer "In11.Cu")
		(net "M_F_DQS_DN<9>")
	)
	(segment
		(start 199.79386 -151.83612)
		(end 199.9488 -151.99106)
		(width 0.14224)
		(layer "In11.Cu")
		(net "M_F_DQS_DN<9>")
	)
	(segment
		(start 200.682352 -147.26666)
		(end 200.682352 -147.52066)
		(width 0.14224)
		(layer "In11.Cu")
		(net "M_F_DQS_DN<9>")
	)
	(segment
		(start 200.396348 -118.40718)
		(end 200.14692 -118.656608)
		(width 0.14224)
		(layer "In11.Cu")
		(net "M_F_DQS_DN<9>")
	)
	(segment
		(start 199.927972 -153.162)
		(end 200.182226 -153.416254)
		(width 0.14224)
		(layer "In11.Cu")
		(net "M_F_DQS_DN<9>")
	)
	(segment
		(start 213.836758 -103.4542)
		(end 210.0072 -103.4542)
		(width 0.14224)
		(layer "In11.Cu")
		(net "M_F_DQS_DN<9>")
	)
	(segment
		(start 201.77252 -115.433602)
		(end 201.394314 -115.811808)
		(width 0.14224)
		(layer "In11.Cu")
		(net "M_F_DQS_DN<9>")
	)
	(segment
		(start 199.9488 -152.34412)
		(end 199.79386 -152.49906)
		(width 0.14224)
		(layer "In11.Cu")
		(net "M_F_DQS_DN<9>")
	)
	(segment
		(start 199.64654 -152.49906)
		(end 199.50684 -152.63876)
		(width 0.14224)
		(layer "In11.Cu")
		(net "M_F_DQS_DN<9>")
	)
	(segment
		(start 199.50684 -152.63876)
		(end 199.50684 -152.99944)
		(width 0.14224)
		(layer "In11.Cu")
		(net "M_F_DQS_DN<9>")
	)
	(segment
		(start 200.524872 -147.67814)
		(end 200.524872 -147.93214)
		(width 0.14224)
		(layer "In11.Cu")
		(net "M_F_DQS_DN<9>")
	)
	(segment
		(start 239.061244 -84.90839)
		(end 239.031272 -84.90839)
		(width 0.0889)
		(layer "In11.Cu")
		(net "M_F_DQS_DN<9>")
	)
	(segment
		(start 231.8385 -88.87079)
		(end 231.533446 -88.565736)
		(width 0.0889)
		(layer "In11.Cu")
		(net "M_F_DQS_DN<9>")
	)
	(segment
		(start 241.914934 -86.96325)
		(end 241.993674 -86.941914)
		(width 0.0889)
		(layer "In11.Cu")
		(net "M_F_DQS_DN<9>")
	)
	(segment
		(start 241.621818 -86.794086)
		(end 241.914934 -86.96325)
		(width 0.0889)
		(layer "In11.Cu")
		(net "M_F_DQS_DN<9>")
	)
	(segment
		(start 230.5812 -88.605106)
		(end 230.559102 -88.605106)
		(width 0.0889)
		(layer "In11.Cu")
		(net "M_F_DQS_DN<9>")
	)
	(segment
		(start 210.0072 -103.4542)
		(end 205.613 -107.8484)
		(width 0.14224)
		(layer "In11.Cu")
		(net "M_F_DQS_DN<9>")
	)
	(segment
		(start 230.62057 -88.565736)
		(end 230.5812 -88.605106)
		(width 0.0889)
		(layer "In11.Cu")
		(net "M_F_DQS_DN<9>")
	)
	(segment
		(start 232.191814 -88.87079)
		(end 231.8385 -88.87079)
		(width 0.0889)
		(layer "In11.Cu")
		(net "M_F_DQS_DN<9>")
	)
	(segment
		(start 234.775248 -87.384636)
		(end 234.742482 -87.384636)
		(width 0.0889)
		(layer "In11.Cu")
		(net "M_F_DQS_DN<9>")
	)
	(segment
		(start 200.182226 -153.416254)
		(end 200.182226 -153.83383)
		(width 0.14224)
		(layer "In11.Cu")
		(net "M_F_DQS_DN<9>")
	)
	(segment
		(start 200.182226 -153.83383)
		(end 199.749156 -154.2669)
		(width 0.14224)
		(layer "In11.Cu")
		(net "M_F_DQS_DN<9>")
	)
	(segment
		(start 241.632994 -86.394036)
		(end 241.600228 -86.394036)
		(width 0.0889)
		(layer "In11.Cu")
		(net "M_F_DQS_DN<9>")
	)
	(segment
		(start 199.898 -151.2062)
		(end 199.6567 -151.2062)
		(width 0.14224)
		(layer "In11.Cu")
		(net "M_F_DQS_DN<9>")
	)
	(segment
		(start 217.9066 -99.384358)
		(end 213.836758 -103.4542)
		(width 0.14224)
		(layer "In11.Cu")
		(net "M_F_DQS_DN<9>")
	)
	(segment
		(start 238.209328 -85.403436)
		(end 238.176562 -85.403436)
		(width 0.0889)
		(layer "In11.Cu")
		(net "M_F_DQS_DN<9>")
	)
	(segment
		(start 230.559102 -88.605106)
		(end 227.693474 -88.605106)
		(width 0.14224)
		(layer "In11.Cu")
		(net "M_F_DQS_DN<9>")
	)
	(segment
		(start 233.058208 -88.375236)
		(end 233.025442 -88.375236)
		(width 0.0889)
		(layer "In11.Cu")
		(net "M_F_DQS_DN<9>")
	)
	(segment
		(start 199.79386 -152.49906)
		(end 199.64654 -152.49906)
		(width 0.14224)
		(layer "In11.Cu")
		(net "M_F_DQS_DN<9>")
	)
	(segment
		(start 199.50684 -152.99944)
		(end 199.6694 -153.162)
		(width 0.14224)
		(layer "In11.Cu")
		(net "M_F_DQS_DN<9>")
	)
	(segment
		(start 199.75576 -150.0886)
		(end 199.742552 -150.0886)
		(width 0.14224)
		(layer "In11.Cu")
		(net "M_F_DQS_DN<9>")
	)
	(segment
		(start 201.77252 -112.19688)
		(end 201.77252 -115.433602)
		(width 0.14224)
		(layer "In11.Cu")
		(net "M_F_DQS_DN<9>")
	)
	(segment
		(start 200.524872 -126.653798)
		(end 200.524872 -147.10918)
		(width 0.14224)
		(layer "In11.Cu")
		(net "M_F_DQS_DN<9>")
	)
	(arc
		(start 238.699548 -85.108288)
		(mid 238.492544 -85.319152)
		(end 238.209328 -85.403436)
		(width 0.0889)
		(layer "In11.Cu")
		(net "M_F_DQS_DN<9>")
	)
	(arc
		(start 239.031272 -84.90839)
		(mid 238.83963 -84.965556)
		(end 238.699548 -85.108288)
		(width 0.0889)
		(layer "In11.Cu")
		(net "M_F_DQS_DN<9>")
	)
	(arc
		(start 236.123988 -86.594188)
		(mid 235.91538 -86.80612)
		(end 235.629958 -86.88959)
		(width 0.0889)
		(layer "In11.Cu")
		(net "M_F_DQS_DN<9>")
	)
	(arc
		(start 236.982508 -86.098888)
		(mid 236.775504 -86.309752)
		(end 236.492288 -86.394036)
		(width 0.0889)
		(layer "In11.Cu")
		(net "M_F_DQS_DN<9>")
	)
	(arc
		(start 235.597192 -86.88959)
		(mid 235.40555 -86.946756)
		(end 235.265468 -87.089488)
		(width 0.0889)
		(layer "In11.Cu")
		(net "M_F_DQS_DN<9>")
	)
	(arc
		(start 239.392968 -85.108288)
		(mid 239.252889 -84.965552)
		(end 239.061244 -84.90839)
		(width 0.0889)
		(layer "In11.Cu")
		(net "M_F_DQS_DN<9>")
	)
	(arc
		(start 233.880152 -87.88019)
		(mid 233.68851 -87.937356)
		(end 233.548428 -88.080088)
		(width 0.0889)
		(layer "In11.Cu")
		(net "M_F_DQS_DN<9>")
	)
	(arc
		(start 234.406948 -87.584788)
		(mid 234.19834 -87.79672)
		(end 233.912918 -87.88019)
		(width 0.0889)
		(layer "In11.Cu")
		(net "M_F_DQS_DN<9>")
	)
	(arc
		(start 241.993674 -86.941914)
		(mid 241.956034 -86.573975)
		(end 241.632994 -86.394036)
		(width 0.0889)
		(layer "In11.Cu")
		(net "M_F_DQS_DN<9>")
	)
	(arc
		(start 238.176562 -85.403436)
		(mid 237.982712 -85.459786)
		(end 237.841028 -85.603588)
		(width 0.0889)
		(layer "In11.Cu")
		(net "M_F_DQS_DN<9>")
	)
	(arc
		(start 240.745518 -85.89899)
		(mid 240.460094 -85.815523)
		(end 240.251488 -85.603588)
		(width 0.0889)
		(layer "In11.Cu")
		(net "M_F_DQS_DN<9>")
	)
	(arc
		(start 241.600228 -86.394036)
		(mid 241.317011 -86.309755)
		(end 241.110008 -86.098888)
		(width 0.0889)
		(layer "In11.Cu")
		(net "M_F_DQS_DN<9>")
	)
	(arc
		(start 235.265468 -87.089488)
		(mid 235.058464 -87.300352)
		(end 234.775248 -87.384636)
		(width 0.0889)
		(layer "In11.Cu")
		(net "M_F_DQS_DN<9>")
	)
	(arc
		(start 239.883188 -85.403436)
		(mid 239.599971 -85.319155)
		(end 239.392968 -85.108288)
		(width 0.0889)
		(layer "In11.Cu")
		(net "M_F_DQS_DN<9>")
	)
	(arc
		(start 237.314232 -85.89899)
		(mid 237.12259 -85.956156)
		(end 236.982508 -86.098888)
		(width 0.0889)
		(layer "In11.Cu")
		(net "M_F_DQS_DN<9>")
	)
	(arc
		(start 233.548428 -88.080088)
		(mid 233.341424 -88.290952)
		(end 233.058208 -88.375236)
		(width 0.0889)
		(layer "In11.Cu")
		(net "M_F_DQS_DN<9>")
	)
	(arc
		(start 236.459522 -86.394036)
		(mid 236.265672 -86.450386)
		(end 236.123988 -86.594188)
		(width 0.0889)
		(layer "In11.Cu")
		(net "M_F_DQS_DN<9>")
	)
	(arc
		(start 232.689908 -88.575388)
		(mid 232.479555 -88.78836)
		(end 232.191814 -88.87079)
		(width 0.0889)
		(layer "In11.Cu")
		(net "M_F_DQS_DN<9>")
	)
	(arc
		(start 240.251488 -85.603588)
		(mid 240.109805 -85.459784)
		(end 239.915954 -85.403436)
		(width 0.0889)
		(layer "In11.Cu")
		(net "M_F_DQS_DN<9>")
	)
	(arc
		(start 233.025442 -88.375236)
		(mid 232.831592 -88.431586)
		(end 232.689908 -88.575388)
		(width 0.0889)
		(layer "In11.Cu")
		(net "M_F_DQS_DN<9>")
	)
	(arc
		(start 237.841028 -85.603588)
		(mid 237.63242 -85.81552)
		(end 237.346998 -85.89899)
		(width 0.0889)
		(layer "In11.Cu")
		(net "M_F_DQS_DN<9>")
	)
	(arc
		(start 234.742482 -87.384636)
		(mid 234.548632 -87.440986)
		(end 234.406948 -87.584788)
		(width 0.0889)
		(layer "In11.Cu")
		(net "M_F_DQS_DN<9>")
	)
	(arc
		(start 241.110008 -86.098888)
		(mid 240.969929 -85.956152)
		(end 240.778284 -85.89899)
		(width 0.0889)
		(layer "In11.Cu")
		(net "M_F_DQS_DN<9>")
	)
	(segment
		(start 238.049816 -156.87294)
		(end 238.049816 -155.80487)
		(width 0.1651)
		(layer "F.Cu")
		(net "M_F_DQS_DN<8>")
	)
	(segment
		(start 238.222282 -154.6606)
		(end 238.437928 -154.876246)
		(width 0.1651)
		(layer "F.Cu")
		(net "M_F_DQS_DN<8>")
	)
	(segment
		(start 246.485664 -85.30844)
		(end 245.914164 -85.30844)
		(width 0.1651)
		(layer "F.Cu")
		(net "M_F_DQS_DN<8>")
	)
	(segment
		(start 237.6678 -154.991054)
		(end 237.998254 -154.6606)
		(width 0.1651)
		(layer "F.Cu")
		(net "M_F_DQS_DN<8>")
	)
	(segment
		(start 237.998254 -154.6606)
		(end 238.222282 -154.6606)
		(width 0.1651)
		(layer "F.Cu")
		(net "M_F_DQS_DN<8>")
	)
	(segment
		(start 238.049816 -155.80487)
		(end 237.6678 -155.422854)
		(width 0.1651)
		(layer "F.Cu")
		(net "M_F_DQS_DN<8>")
	)
	(segment
		(start 237.6678 -155.422854)
		(end 237.6678 -154.991054)
		(width 0.1651)
		(layer "F.Cu")
		(net "M_F_DQS_DN<8>")
	)
	(segment
		(start 238.050324 -156.87294)
		(end 238.049816 -156.87294)
		(width 0.1651)
		(layer "F.Cu")
		(net "M_F_DQS_DN<8>")
	)
	(via
		(at 245.914164 -85.30844)
		(size 0.508)
		(drill 0.254)
		(layers "F.Cu" "B.Cu")
		(net "M_F_DQS_DN<8>")
	)
	(via
		(at 238.437928 -154.876246)
		(size 0.508)
		(drill 0.254)
		(layers "F.Cu" "B.Cu")
		(net "M_F_DQS_DN<8>")
	)
	(via
		(at 238.437928 -149.482556)
		(size 0.508)
		(drill 0.254)
		(layers "F.Cu" "B.Cu")
		(net "M_F_DQS_DN<8>")
	)
	(segment
		(start 238.212884 -149.7076)
		(end 238.437928 -149.482556)
		(width 0.1651)
		(layer "B.Cu")
		(net "M_F_DQS_DN<8>")
	)
	(segment
		(start 237.9218 -148.513546)
		(end 237.9218 -148.767546)
		(width 0.1651)
		(layer "B.Cu")
		(net "M_F_DQS_DN<8>")
	)
	(segment
		(start 238.049816 -147.478496)
		(end 238.049816 -148.38553)
		(width 0.1651)
		(layer "B.Cu")
		(net "M_F_DQS_DN<8>")
	)
	(segment
		(start 237.9218 -148.767546)
		(end 237.6678 -149.021546)
		(width 0.1651)
		(layer "B.Cu")
		(net "M_F_DQS_DN<8>")
	)
	(segment
		(start 237.6678 -149.021546)
		(end 237.6678 -149.352)
		(width 0.1651)
		(layer "B.Cu")
		(net "M_F_DQS_DN<8>")
	)
	(segment
		(start 238.0234 -149.7076)
		(end 238.212884 -149.7076)
		(width 0.1651)
		(layer "B.Cu")
		(net "M_F_DQS_DN<8>")
	)
	(segment
		(start 238.050324 -147.478496)
		(end 238.049816 -147.478496)
		(width 0.1651)
		(layer "B.Cu")
		(net "M_F_DQS_DN<8>")
	)
	(segment
		(start 237.6678 -149.352)
		(end 238.0234 -149.7076)
		(width 0.1651)
		(layer "B.Cu")
		(net "M_F_DQS_DN<8>")
	)
	(segment
		(start 238.049816 -148.38553)
		(end 237.9218 -148.513546)
		(width 0.1651)
		(layer "B.Cu")
		(net "M_F_DQS_DN<8>")
	)
	(segment
		(start 245.914164 -85.30844)
		(end 246.183404 -85.96884)
		(width 0.0889)
		(layer "In4.Cu")
		(net "M_F_DQS_DN<8>")
	)
	(segment
		(start 238.793528 -132.843524)
		(end 238.793528 -133.097524)
		(width 0.14224)
		(layer "In4.Cu")
		(net "M_F_DQS_DN<8>")
	)
	(segment
		(start 246.260874 -86.498938)
		(end 246.254524 -86.509606)
		(width 0.0889)
		(layer "In4.Cu")
		(net "M_F_DQS_DN<8>")
	)
	(segment
		(start 246.260874 -87.489538)
		(end 246.254524 -87.500206)
		(width 0.0889)
		(layer "In4.Cu")
		(net "M_F_DQS_DN<8>")
	)
	(segment
		(start 238.793528 -147.297902)
		(end 238.793528 -147.551902)
		(width 0.14224)
		(layer "In4.Cu")
		(net "M_F_DQS_DN<8>")
	)
	(segment
		(start 238.793528 -132.274564)
		(end 238.951008 -132.432044)
		(width 0.14224)
		(layer "In4.Cu")
		(net "M_F_DQS_DN<8>")
	)
	(segment
		(start 246.111014 -103.87203)
		(end 246.071644 -103.9114)
		(width 0.0889)
		(layer "In4.Cu")
		(net "M_F_DQS_DN<8>")
	)
	(segment
		(start 238.51108 -116.074952)
		(end 238.51108 -116.729256)
		(width 0.14224)
		(layer "In4.Cu")
		(net "M_F_DQS_DN<8>")
	)
	(segment
		(start 246.259604 -96.40697)
		(end 246.258588 -96.408494)
		(width 0.0889)
		(layer "In4.Cu")
		(net "M_F_DQS_DN<8>")
	)
	(segment
		(start 238.951008 -131.863084)
		(end 238.793528 -132.020564)
		(width 0.14224)
		(layer "In4.Cu")
		(net "M_F_DQS_DN<8>")
	)
	(segment
		(start 238.854234 -146.728942)
		(end 238.951008 -146.825716)
		(width 0.14224)
		(layer "In4.Cu")
		(net "M_F_DQS_DN<8>")
	)
	(segment
		(start 246.260874 -88.480138)
		(end 246.254524 -88.490806)
		(width 0.0889)
		(layer "In4.Cu")
		(net "M_F_DQS_DN<8>")
	)
	(segment
		(start 246.318024 -100.37572)
		(end 245.895114 -100.79863)
		(width 0.0889)
		(layer "In4.Cu")
		(net "M_F_DQS_DN<8>")
	)
	(segment
		(start 238.793528 -138.783822)
		(end 238.951008 -138.941302)
		(width 0.14224)
		(layer "In4.Cu")
		(net "M_F_DQS_DN<8>")
	)
	(segment
		(start 238.951008 -147.709382)
		(end 238.951008 -147.963382)
		(width 0.14224)
		(layer "In4.Cu")
		(net "M_F_DQS_DN<8>")
	)
	(segment
		(start 238.951008 -138.118342)
		(end 238.951008 -138.372342)
		(width 0.14224)
		(layer "In4.Cu")
		(net "M_F_DQS_DN<8>")
	)
	(segment
		(start 238.951008 -143.655796)
		(end 238.951008 -145.360136)
		(width 0.14224)
		(layer "In4.Cu")
		(net "M_F_DQS_DN<8>")
	)
	(segment
		(start 238.951008 -123.744736)
		(end 238.951008 -131.863084)
		(width 0.14224)
		(layer "In4.Cu")
		(net "M_F_DQS_DN<8>")
	)
	(segment
		(start 238.951008 -149.248876)
		(end 238.717328 -149.482556)
		(width 0.14224)
		(layer "In4.Cu")
		(net "M_F_DQS_DN<8>")
	)
	(segment
		(start 238.51108 -116.729256)
		(end 238.890048 -117.108224)
		(width 0.14224)
		(layer "In4.Cu")
		(net "M_F_DQS_DN<8>")
	)
	(segment
		(start 238.793528 -137.706862)
		(end 238.793528 -137.960862)
		(width 0.14224)
		(layer "In4.Cu")
		(net "M_F_DQS_DN<8>")
	)
	(segment
		(start 238.951008 -147.140422)
		(end 238.793528 -147.297902)
		(width 0.14224)
		(layer "In4.Cu")
		(net "M_F_DQS_DN<8>")
	)
	(segment
		(start 238.951008 -145.360136)
		(end 238.840518 -145.470626)
		(width 0.14224)
		(layer "In4.Cu")
		(net "M_F_DQS_DN<8>")
	)
	(segment
		(start 246.260874 -91.451938)
		(end 246.254524 -91.462606)
		(width 0.0889)
		(layer "In4.Cu")
		(net "M_F_DQS_DN<8>")
	)
	(segment
		(start 246.260874 -96.404938)
		(end 246.259604 -96.40697)
		(width 0.0889)
		(layer "In4.Cu")
		(net "M_F_DQS_DN<8>")
	)
	(segment
		(start 238.951008 -141.474698)
		(end 238.793528 -141.632178)
		(width 0.14224)
		(layer "In4.Cu")
		(net "M_F_DQS_DN<8>")
	)
	(segment
		(start 238.793528 -142.455138)
		(end 238.793528 -142.709138)
		(width 0.14224)
		(layer "In4.Cu")
		(net "M_F_DQS_DN<8>")
	)
	(segment
		(start 238.854234 -146.474942)
		(end 238.854234 -146.728942)
		(width 0.14224)
		(layer "In4.Cu")
		(net "M_F_DQS_DN<8>")
	)
	(segment
		(start 238.793528 -141.886178)
		(end 238.951008 -142.043658)
		(width 0.14224)
		(layer "In4.Cu")
		(net "M_F_DQS_DN<8>")
	)
	(segment
		(start 238.793528 -147.551902)
		(end 238.951008 -147.709382)
		(width 0.14224)
		(layer "In4.Cu")
		(net "M_F_DQS_DN<8>")
	)
	(segment
		(start 238.951008 -136.726422)
		(end 238.793528 -136.883902)
		(width 0.14224)
		(layer "In4.Cu")
		(net "M_F_DQS_DN<8>")
	)
	(segment
		(start 239.554512 -115.695984)
		(end 238.890048 -115.695984)
		(width 0.14224)
		(layer "In4.Cu")
		(net "M_F_DQS_DN<8>")
	)
	(segment
		(start 245.895114 -102.313232)
		(end 246.111014 -102.686612)
		(width 0.0889)
		(layer "In4.Cu")
		(net "M_F_DQS_DN<8>")
	)
	(segment
		(start 246.2657 -92.433902)
		(end 246.260874 -92.442538)
		(width 0.0889)
		(layer "In4.Cu")
		(net "M_F_DQS_DN<8>")
	)
	(segment
		(start 238.951008 -137.295382)
		(end 238.951008 -137.549382)
		(width 0.14224)
		(layer "In4.Cu")
		(net "M_F_DQS_DN<8>")
	)
	(segment
		(start 246.183404 -85.96884)
		(end 246.260874 -86.098888)
		(width 0.0889)
		(layer "In4.Cu")
		(net "M_F_DQS_DN<8>")
	)
	(segment
		(start 238.793528 -141.632178)
		(end 238.793528 -141.886178)
		(width 0.14224)
		(layer "In4.Cu")
		(net "M_F_DQS_DN<8>")
	)
	(segment
		(start 246.258588 -96.408494)
		(end 246.257318 -96.411034)
		(width 0.0889)
		(layer "In4.Cu")
		(net "M_F_DQS_DN<8>")
	)
	(segment
		(start 246.111014 -102.686612)
		(end 246.111014 -103.87203)
		(width 0.0889)
		(layer "In4.Cu")
		(net "M_F_DQS_DN<8>")
	)
	(segment
		(start 238.951008 -147.963382)
		(end 238.793528 -148.120862)
		(width 0.14224)
		(layer "In4.Cu")
		(net "M_F_DQS_DN<8>")
	)
	(segment
		(start 239.788446 -115.46205)
		(end 239.554512 -115.695984)
		(width 0.14224)
		(layer "In4.Cu")
		(net "M_F_DQS_DN<8>")
	)
	(segment
		(start 238.793528 -148.374862)
		(end 238.951008 -148.532342)
		(width 0.14224)
		(layer "In4.Cu")
		(net "M_F_DQS_DN<8>")
	)
	(segment
		(start 239.439958 -117.108224)
		(end 239.566958 -117.235224)
		(width 0.14224)
		(layer "In4.Cu")
		(net "M_F_DQS_DN<8>")
	)
	(segment
		(start 238.951008 -145.835116)
		(end 238.951008 -146.378168)
		(width 0.14224)
		(layer "In4.Cu")
		(net "M_F_DQS_DN<8>")
	)
	(segment
		(start 245.895114 -100.79863)
		(end 245.895114 -102.313232)
		(width 0.0889)
		(layer "In4.Cu")
		(net "M_F_DQS_DN<8>")
	)
	(segment
		(start 238.951008 -134.077964)
		(end 238.951008 -136.726422)
		(width 0.14224)
		(layer "In4.Cu")
		(net "M_F_DQS_DN<8>")
	)
	(segment
		(start 246.2657 -96.396302)
		(end 246.260874 -96.404938)
		(width 0.0889)
		(layer "In4.Cu")
		(net "M_F_DQS_DN<8>")
	)
	(segment
		(start 246.2657 -86.490302)
		(end 246.260874 -86.498938)
		(width 0.0889)
		(layer "In4.Cu")
		(net "M_F_DQS_DN<8>")
	)
	(segment
		(start 246.2657 -95.405702)
		(end 246.260874 -95.414338)
		(width 0.0889)
		(layer "In4.Cu")
		(net "M_F_DQS_DN<8>")
	)
	(segment
		(start 238.10468 -122.898408)
		(end 238.951008 -123.744736)
		(width 0.14224)
		(layer "In4.Cu")
		(net "M_F_DQS_DN<8>")
	)
	(segment
		(start 238.793528 -138.529822)
		(end 238.793528 -138.783822)
		(width 0.14224)
		(layer "In4.Cu")
		(net "M_F_DQS_DN<8>")
	)
	(segment
		(start 246.257318 -96.411034)
		(end 246.254524 -96.415606)
		(width 0.0889)
		(layer "In4.Cu")
		(net "M_F_DQS_DN<8>")
	)
	(segment
		(start 246.2657 -91.443302)
		(end 246.260874 -91.451938)
		(width 0.0889)
		(layer "In4.Cu")
		(net "M_F_DQS_DN<8>")
	)
	(segment
		(start 246.254524 -94.01302)
		(end 246.260874 -94.023688)
		(width 0.0889)
		(layer "In4.Cu")
		(net "M_F_DQS_DN<8>")
	)
	(segment
		(start 246.260874 -89.470738)
		(end 246.254524 -89.481406)
		(width 0.0889)
		(layer "In4.Cu")
		(net "M_F_DQS_DN<8>")
	)
	(segment
		(start 246.2657 -87.480902)
		(end 246.260874 -87.489538)
		(width 0.0889)
		(layer "In4.Cu")
		(net "M_F_DQS_DN<8>")
	)
	(segment
		(start 238.534448 -118.03888)
		(end 238.10468 -118.468648)
		(width 0.14224)
		(layer "In4.Cu")
		(net "M_F_DQS_DN<8>")
	)
	(segment
		(start 238.951008 -148.532342)
		(end 238.951008 -149.248876)
		(width 0.14224)
		(layer "In4.Cu")
		(net "M_F_DQS_DN<8>")
	)
	(segment
		(start 238.951008 -133.255004)
		(end 238.951008 -133.509004)
		(width 0.14224)
		(layer "In4.Cu")
		(net "M_F_DQS_DN<8>")
	)
	(segment
		(start 238.890048 -115.695984)
		(end 238.51108 -116.074952)
		(width 0.14224)
		(layer "In4.Cu")
		(net "M_F_DQS_DN<8>")
	)
	(segment
		(start 238.951008 -138.941302)
		(end 238.951008 -141.474698)
		(width 0.14224)
		(layer "In4.Cu")
		(net "M_F_DQS_DN<8>")
	)
	(segment
		(start 239.566958 -117.235224)
		(end 239.566958 -117.91188)
		(width 0.14224)
		(layer "In4.Cu")
		(net "M_F_DQS_DN<8>")
	)
	(segment
		(start 238.830612 -143.2814)
		(end 238.830612 -143.5354)
		(width 0.14224)
		(layer "In4.Cu")
		(net "M_F_DQS_DN<8>")
	)
	(segment
		(start 238.10468 -118.468648)
		(end 238.10468 -122.898408)
		(width 0.14224)
		(layer "In4.Cu")
		(net "M_F_DQS_DN<8>")
	)
	(segment
		(start 239.566958 -117.91188)
		(end 239.439958 -118.03888)
		(width 0.14224)
		(layer "In4.Cu")
		(net "M_F_DQS_DN<8>")
	)
	(segment
		(start 238.951008 -146.378168)
		(end 238.854234 -146.474942)
		(width 0.14224)
		(layer "In4.Cu")
		(net "M_F_DQS_DN<8>")
	)
	(segment
		(start 238.951008 -137.549382)
		(end 238.793528 -137.706862)
		(width 0.14224)
		(layer "In4.Cu")
		(net "M_F_DQS_DN<8>")
	)
	(segment
		(start 238.951008 -142.866618)
		(end 238.951008 -143.161004)
		(width 0.14224)
		(layer "In4.Cu")
		(net "M_F_DQS_DN<8>")
	)
	(segment
		(start 246.2657 -90.452702)
		(end 246.260874 -90.461338)
		(width 0.0889)
		(layer "In4.Cu")
		(net "M_F_DQS_DN<8>")
	)
	(segment
		(start 238.793528 -133.097524)
		(end 238.951008 -133.255004)
		(width 0.14224)
		(layer "In4.Cu")
		(net "M_F_DQS_DN<8>")
	)
	(segment
		(start 238.793528 -148.120862)
		(end 238.793528 -148.374862)
		(width 0.14224)
		(layer "In4.Cu")
		(net "M_F_DQS_DN<8>")
	)
	(segment
		(start 246.260874 -95.414338)
		(end 246.254524 -95.425006)
		(width 0.0889)
		(layer "In4.Cu")
		(net "M_F_DQS_DN<8>")
	)
	(segment
		(start 246.071644 -103.9114)
		(end 246.071644 -103.933498)
		(width 0.0889)
		(layer "In4.Cu")
		(net "M_F_DQS_DN<8>")
	)
	(segment
		(start 238.951008 -142.043658)
		(end 238.951008 -142.297658)
		(width 0.14224)
		(layer "In4.Cu")
		(net "M_F_DQS_DN<8>")
	)
	(segment
		(start 238.793528 -136.883902)
		(end 238.793528 -137.137902)
		(width 0.14224)
		(layer "In4.Cu")
		(net "M_F_DQS_DN<8>")
	)
	(segment
		(start 238.951008 -132.686044)
		(end 238.793528 -132.843524)
		(width 0.14224)
		(layer "In4.Cu")
		(net "M_F_DQS_DN<8>")
	)
	(segment
		(start 238.793528 -133.920484)
		(end 238.951008 -134.077964)
		(width 0.14224)
		(layer "In4.Cu")
		(net "M_F_DQS_DN<8>")
	)
	(segment
		(start 238.793528 -137.137902)
		(end 238.951008 -137.295382)
		(width 0.14224)
		(layer "In4.Cu")
		(net "M_F_DQS_DN<8>")
	)
	(segment
		(start 238.793528 -137.960862)
		(end 238.951008 -138.118342)
		(width 0.14224)
		(layer "In4.Cu")
		(net "M_F_DQS_DN<8>")
	)
	(segment
		(start 239.788446 -111.647732)
		(end 239.788446 -115.46205)
		(width 0.14224)
		(layer "In4.Cu")
		(net "M_F_DQS_DN<8>")
	)
	(segment
		(start 238.890048 -117.108224)
		(end 239.439958 -117.108224)
		(width 0.14224)
		(layer "In4.Cu")
		(net "M_F_DQS_DN<8>")
	)
	(segment
		(start 246.318024 -97.09531)
		(end 246.318024 -100.37572)
		(width 0.0889)
		(layer "In4.Cu")
		(net "M_F_DQS_DN<8>")
	)
	(segment
		(start 238.793528 -133.666484)
		(end 238.793528 -133.920484)
		(width 0.14224)
		(layer "In4.Cu")
		(net "M_F_DQS_DN<8>")
	)
	(segment
		(start 238.951008 -133.509004)
		(end 238.793528 -133.666484)
		(width 0.14224)
		(layer "In4.Cu")
		(net "M_F_DQS_DN<8>")
	)
	(segment
		(start 239.439958 -118.03888)
		(end 238.534448 -118.03888)
		(width 0.14224)
		(layer "In4.Cu")
		(net "M_F_DQS_DN<8>")
	)
	(segment
		(start 238.840518 -145.724626)
		(end 238.951008 -145.835116)
		(width 0.14224)
		(layer "In4.Cu")
		(net "M_F_DQS_DN<8>")
	)
	(segment
		(start 238.793528 -142.709138)
		(end 238.951008 -142.866618)
		(width 0.14224)
		(layer "In4.Cu")
		(net "M_F_DQS_DN<8>")
	)
	(segment
		(start 238.951008 -142.297658)
		(end 238.793528 -142.455138)
		(width 0.14224)
		(layer "In4.Cu")
		(net "M_F_DQS_DN<8>")
	)
	(segment
		(start 246.071644 -105.364788)
		(end 239.788446 -111.647732)
		(width 0.14224)
		(layer "In4.Cu")
		(net "M_F_DQS_DN<8>")
	)
	(segment
		(start 246.260874 -96.995488)
		(end 246.318024 -97.09531)
		(width 0.0889)
		(layer "In4.Cu")
		(net "M_F_DQS_DN<8>")
	)
	(segment
		(start 238.717328 -149.482556)
		(end 238.437928 -149.482556)
		(width 0.14224)
		(layer "In4.Cu")
		(net "M_F_DQS_DN<8>")
	)
	(segment
		(start 246.2657 -88.471502)
		(end 246.260874 -88.480138)
		(width 0.0889)
		(layer "In4.Cu")
		(net "M_F_DQS_DN<8>")
	)
	(segment
		(start 246.2657 -93.424502)
		(end 246.260874 -93.433138)
		(width 0.0889)
		(layer "In4.Cu")
		(net "M_F_DQS_DN<8>")
	)
	(segment
		(start 238.951008 -143.161004)
		(end 238.830612 -143.2814)
		(width 0.14224)
		(layer "In4.Cu")
		(net "M_F_DQS_DN<8>")
	)
	(segment
		(start 246.2657 -89.462102)
		(end 246.260874 -89.470738)
		(width 0.0889)
		(layer "In4.Cu")
		(net "M_F_DQS_DN<8>")
	)
	(segment
		(start 246.260874 -92.442538)
		(end 246.254524 -92.453206)
		(width 0.0889)
		(layer "In4.Cu")
		(net "M_F_DQS_DN<8>")
	)
	(segment
		(start 238.951008 -138.372342)
		(end 238.793528 -138.529822)
		(width 0.14224)
		(layer "In4.Cu")
		(net "M_F_DQS_DN<8>")
	)
	(segment
		(start 238.830612 -143.5354)
		(end 238.951008 -143.655796)
		(width 0.14224)
		(layer "In4.Cu")
		(net "M_F_DQS_DN<8>")
	)
	(segment
		(start 246.071644 -103.933498)
		(end 246.071644 -105.364788)
		(width 0.14224)
		(layer "In4.Cu")
		(net "M_F_DQS_DN<8>")
	)
	(segment
		(start 238.951008 -146.825716)
		(end 238.951008 -147.140422)
		(width 0.14224)
		(layer "In4.Cu")
		(net "M_F_DQS_DN<8>")
	)
	(segment
		(start 238.840518 -145.470626)
		(end 238.840518 -145.724626)
		(width 0.14224)
		(layer "In4.Cu")
		(net "M_F_DQS_DN<8>")
	)
	(segment
		(start 238.951008 -132.432044)
		(end 238.951008 -132.686044)
		(width 0.14224)
		(layer "In4.Cu")
		(net "M_F_DQS_DN<8>")
	)
	(segment
		(start 238.793528 -132.020564)
		(end 238.793528 -132.274564)
		(width 0.14224)
		(layer "In4.Cu")
		(net "M_F_DQS_DN<8>")
	)
	(segment
		(start 246.260874 -90.461338)
		(end 246.254524 -90.472006)
		(width 0.0889)
		(layer "In4.Cu")
		(net "M_F_DQS_DN<8>")
	)
	(arc
		(start 246.260874 -95.014288)
		(mid 246.314344 -95.209351)
		(end 246.2657 -95.405702)
		(width 0.0889)
		(layer "In4.Cu")
		(net "M_F_DQS_DN<8>")
	)
	(arc
		(start 246.254524 -90.472006)
		(mid 246.181726 -90.762769)
		(end 246.260874 -91.051888)
		(width 0.0889)
		(layer "In4.Cu")
		(net "M_F_DQS_DN<8>")
	)
	(arc
		(start 246.260874 -96.004888)
		(mid 246.314344 -96.199951)
		(end 246.2657 -96.396302)
		(width 0.0889)
		(layer "In4.Cu")
		(net "M_F_DQS_DN<8>")
	)
	(arc
		(start 246.254524 -91.462606)
		(mid 246.181726 -91.753369)
		(end 246.260874 -92.042488)
		(width 0.0889)
		(layer "In4.Cu")
		(net "M_F_DQS_DN<8>")
	)
	(arc
		(start 246.260874 -93.033088)
		(mid 246.314344 -93.228151)
		(end 246.2657 -93.424502)
		(width 0.0889)
		(layer "In4.Cu")
		(net "M_F_DQS_DN<8>")
	)
	(arc
		(start 246.260874 -94.423484)
		(mid 246.181743 -94.718886)
		(end 246.260874 -95.014288)
		(width 0.0889)
		(layer "In4.Cu")
		(net "M_F_DQS_DN<8>")
	)
	(arc
		(start 246.260874 -92.042488)
		(mid 246.314344 -92.237551)
		(end 246.2657 -92.433902)
		(width 0.0889)
		(layer "In4.Cu")
		(net "M_F_DQS_DN<8>")
	)
	(arc
		(start 246.260874 -89.070688)
		(mid 246.314344 -89.265751)
		(end 246.2657 -89.462102)
		(width 0.0889)
		(layer "In4.Cu")
		(net "M_F_DQS_DN<8>")
	)
	(arc
		(start 246.254524 -92.453206)
		(mid 246.181726 -92.743969)
		(end 246.260874 -93.033088)
		(width 0.0889)
		(layer "In4.Cu")
		(net "M_F_DQS_DN<8>")
	)
	(arc
		(start 246.254524 -86.509606)
		(mid 246.181726 -86.800369)
		(end 246.260874 -87.089488)
		(width 0.0889)
		(layer "In4.Cu")
		(net "M_F_DQS_DN<8>")
	)
	(arc
		(start 246.260874 -91.051888)
		(mid 246.314344 -91.246951)
		(end 246.2657 -91.443302)
		(width 0.0889)
		(layer "In4.Cu")
		(net "M_F_DQS_DN<8>")
	)
	(arc
		(start 246.260874 -94.023688)
		(mid 246.314373 -94.223586)
		(end 246.260874 -94.423484)
		(width 0.0889)
		(layer "In4.Cu")
		(net "M_F_DQS_DN<8>")
	)
	(arc
		(start 246.254524 -95.425006)
		(mid 246.181726 -95.715769)
		(end 246.260874 -96.004888)
		(width 0.0889)
		(layer "In4.Cu")
		(net "M_F_DQS_DN<8>")
	)
	(arc
		(start 246.254524 -89.481406)
		(mid 246.181726 -89.772169)
		(end 246.260874 -90.061288)
		(width 0.0889)
		(layer "In4.Cu")
		(net "M_F_DQS_DN<8>")
	)
	(arc
		(start 246.254524 -87.500206)
		(mid 246.181726 -87.790969)
		(end 246.260874 -88.080088)
		(width 0.0889)
		(layer "In4.Cu")
		(net "M_F_DQS_DN<8>")
	)
	(arc
		(start 246.260874 -93.433138)
		(mid 246.181652 -93.722256)
		(end 246.254524 -94.01302)
		(width 0.0889)
		(layer "In4.Cu")
		(net "M_F_DQS_DN<8>")
	)
	(arc
		(start 246.254524 -96.415606)
		(mid 246.181726 -96.706369)
		(end 246.260874 -96.995488)
		(width 0.0889)
		(layer "In4.Cu")
		(net "M_F_DQS_DN<8>")
	)
	(arc
		(start 246.260874 -88.080088)
		(mid 246.314344 -88.275151)
		(end 246.2657 -88.471502)
		(width 0.0889)
		(layer "In4.Cu")
		(net "M_F_DQS_DN<8>")
	)
	(arc
		(start 246.260874 -90.061288)
		(mid 246.314344 -90.256351)
		(end 246.2657 -90.452702)
		(width 0.0889)
		(layer "In4.Cu")
		(net "M_F_DQS_DN<8>")
	)
	(arc
		(start 246.260874 -87.089488)
		(mid 246.314344 -87.284551)
		(end 246.2657 -87.480902)
		(width 0.0889)
		(layer "In4.Cu")
		(net "M_F_DQS_DN<8>")
	)
	(arc
		(start 246.254524 -88.490806)
		(mid 246.181726 -88.781569)
		(end 246.260874 -89.070688)
		(width 0.0889)
		(layer "In4.Cu")
		(net "M_F_DQS_DN<8>")
	)
	(arc
		(start 246.260874 -86.098888)
		(mid 246.314344 -86.293951)
		(end 246.2657 -86.490302)
		(width 0.0889)
		(layer "In4.Cu")
		(net "M_F_DQS_DN<8>")
	)
	(segment
		(start 237.794038 -152.906476)
		(end 237.794038 -151.31542)
		(width 0.14224)
		(layer "In11.Cu")
		(net "M_F_DQS_DN<8>")
	)
	(segment
		(start 238.364776 -149.482556)
		(end 238.437928 -149.482556)
		(width 0.14224)
		(layer "In11.Cu")
		(net "M_F_DQS_DN<8>")
	)
	(segment
		(start 238.437928 -154.876246)
		(end 238.004858 -154.443176)
		(width 0.14224)
		(layer "In11.Cu")
		(net "M_F_DQS_DN<8>")
	)
	(segment
		(start 238.004858 -154.443176)
		(end 238.004858 -153.117296)
		(width 0.14224)
		(layer "In11.Cu")
		(net "M_F_DQS_DN<8>")
	)
	(segment
		(start 238.004858 -153.117296)
		(end 237.794038 -152.906476)
		(width 0.14224)
		(layer "In11.Cu")
		(net "M_F_DQS_DN<8>")
	)
	(segment
		(start 238.004858 -151.1046)
		(end 238.004858 -149.842474)
		(width 0.14224)
		(layer "In11.Cu")
		(net "M_F_DQS_DN<8>")
	)
	(segment
		(start 238.004858 -149.842474)
		(end 238.364776 -149.482556)
		(width 0.14224)
		(layer "In11.Cu")
		(net "M_F_DQS_DN<8>")
	)
	(segment
		(start 237.794038 -151.31542)
		(end 238.004858 -151.1046)
		(width 0.14224)
		(layer "In11.Cu")
		(net "M_F_DQS_DN<8>")
	)
	(segment
		(start 312.000392 -156.87294)
		(end 311.999884 -156.87294)
		(width 0.1651)
		(layer "F.Cu")
		(net "M_F_DQS_DN<7>")
	)
	(segment
		(start 311.617868 -154.991054)
		(end 311.948322 -154.6606)
		(width 0.1651)
		(layer "F.Cu")
		(net "M_F_DQS_DN<7>")
	)
	(segment
		(start 283.212794 -92.556584)
		(end 283.784294 -92.556584)
		(width 0.1651)
		(layer "F.Cu")
		(net "M_F_DQS_DN<7>")
	)
	(segment
		(start 311.999884 -156.87294)
		(end 311.999884 -155.80487)
		(width 0.1651)
		(layer "F.Cu")
		(net "M_F_DQS_DN<7>")
	)
	(segment
		(start 312.17235 -154.6606)
		(end 312.387996 -154.876246)
		(width 0.1651)
		(layer "F.Cu")
		(net "M_F_DQS_DN<7>")
	)
	(segment
		(start 311.617868 -155.422854)
		(end 311.617868 -154.991054)
		(width 0.1651)
		(layer "F.Cu")
		(net "M_F_DQS_DN<7>")
	)
	(segment
		(start 311.948322 -154.6606)
		(end 312.17235 -154.6606)
		(width 0.1651)
		(layer "F.Cu")
		(net "M_F_DQS_DN<7>")
	)
	(segment
		(start 311.999884 -155.80487)
		(end 311.617868 -155.422854)
		(width 0.1651)
		(layer "F.Cu")
		(net "M_F_DQS_DN<7>")
	)
	(via
		(at 312.387996 -149.482556)
		(size 0.508)
		(drill 0.254)
		(layers "F.Cu" "B.Cu")
		(net "M_F_DQS_DN<7>")
	)
	(via
		(at 312.387996 -154.876246)
		(size 0.508)
		(drill 0.254)
		(layers "F.Cu" "B.Cu")
		(net "M_F_DQS_DN<7>")
	)
	(via
		(at 283.784294 -92.556584)
		(size 0.508)
		(drill 0.254)
		(layers "F.Cu" "B.Cu")
		(net "M_F_DQS_DN<7>")
	)
	(segment
		(start 312.000392 -147.478496)
		(end 311.999884 -147.478496)
		(width 0.1651)
		(layer "B.Cu")
		(net "M_F_DQS_DN<7>")
	)
	(segment
		(start 312.162952 -149.7076)
		(end 312.387996 -149.482556)
		(width 0.1651)
		(layer "B.Cu")
		(net "M_F_DQS_DN<7>")
	)
	(segment
		(start 311.871868 -148.767546)
		(end 311.617868 -149.021546)
		(width 0.1651)
		(layer "B.Cu")
		(net "M_F_DQS_DN<7>")
	)
	(segment
		(start 311.999884 -147.478496)
		(end 311.999884 -148.38553)
		(width 0.1651)
		(layer "B.Cu")
		(net "M_F_DQS_DN<7>")
	)
	(segment
		(start 311.871868 -148.513546)
		(end 311.871868 -148.767546)
		(width 0.1651)
		(layer "B.Cu")
		(net "M_F_DQS_DN<7>")
	)
	(segment
		(start 311.617868 -149.352)
		(end 311.973468 -149.7076)
		(width 0.1651)
		(layer "B.Cu")
		(net "M_F_DQS_DN<7>")
	)
	(segment
		(start 311.973468 -149.7076)
		(end 312.162952 -149.7076)
		(width 0.1651)
		(layer "B.Cu")
		(net "M_F_DQS_DN<7>")
	)
	(segment
		(start 311.617868 -149.021546)
		(end 311.617868 -149.352)
		(width 0.1651)
		(layer "B.Cu")
		(net "M_F_DQS_DN<7>")
	)
	(segment
		(start 311.999884 -148.38553)
		(end 311.871868 -148.513546)
		(width 0.1651)
		(layer "B.Cu")
		(net "M_F_DQS_DN<7>")
	)
	(segment
		(start 289.27552 -99.280218)
		(end 289.28187 -99.290886)
		(width 0.0889)
		(layer "In11.Cu")
		(net "M_F_DQS_DN<7>")
	)
	(segment
		(start 289.28187 -100.681536)
		(end 289.27552 -100.692204)
		(width 0.0889)
		(layer "In11.Cu")
		(net "M_F_DQS_DN<7>")
	)
	(segment
		(start 290.630102 -103.053134)
		(end 290.662614 -103.053134)
		(width 0.0889)
		(layer "In11.Cu")
		(net "M_F_DQS_DN<7>")
	)
	(segment
		(start 311.954926 -154.443176)
		(end 312.387996 -154.876246)
		(width 0.14224)
		(layer "In11.Cu")
		(net "M_F_DQS_DN<7>")
	)
	(segment
		(start 312.743596 -137.73531)
		(end 312.743596 -137.98931)
		(width 0.14224)
		(layer "In11.Cu")
		(net "M_F_DQS_DN<7>")
	)
	(segment
		(start 299.849286 -111.613696)
		(end 300.026578 -111.436404)
		(width 0.14224)
		(layer "In11.Cu")
		(net "M_F_DQS_DN<7>")
	)
	(segment
		(start 288.91357 -96.118934)
		(end 288.946336 -96.118934)
		(width 0.0889)
		(layer "In11.Cu")
		(net "M_F_DQS_DN<7>")
	)
	(segment
		(start 312.901076 -133.200902)
		(end 312.901076 -133.454902)
		(width 0.14224)
		(layer "In11.Cu")
		(net "M_F_DQS_DN<7>")
	)
	(segment
		(start 289.28187 -99.290886)
		(end 289.286696 -99.299522)
		(width 0.0889)
		(layer "In11.Cu")
		(net "M_F_DQS_DN<7>")
	)
	(segment
		(start 292.352984 -105.69448)
		(end 292.556946 -105.490518)
		(width 0.14224)
		(layer "In11.Cu")
		(net "M_F_DQS_DN<7>")
	)
	(segment
		(start 312.901076 -138.40079)
		(end 312.743596 -138.55827)
		(width 0.14224)
		(layer "In11.Cu")
		(net "M_F_DQS_DN<7>")
	)
	(segment
		(start 312.743596 -138.81227)
		(end 312.901076 -138.96975)
		(width 0.14224)
		(layer "In11.Cu")
		(net "M_F_DQS_DN<7>")
	)
	(segment
		(start 311.744106 -152.97658)
		(end 311.954926 -153.1874)
		(width 0.14224)
		(layer "In11.Cu")
		(net "M_F_DQS_DN<7>")
	)
	(segment
		(start 299.849286 -112.153192)
		(end 299.849286 -111.613696)
		(width 0.14224)
		(layer "In11.Cu")
		(net "M_F_DQS_DN<7>")
	)
	(segment
		(start 312.901076 -146.369786)
		(end 312.743596 -146.527266)
		(width 0.14224)
		(layer "In11.Cu")
		(net "M_F_DQS_DN<7>")
	)
	(segment
		(start 312.901076 -142.89405)
		(end 312.901076 -143.14805)
		(width 0.14224)
		(layer "In11.Cu")
		(net "M_F_DQS_DN<7>")
	)
	(segment
		(start 312.901076 -128.750314)
		(end 312.743596 -128.907794)
		(width 0.14224)
		(layer "In11.Cu")
		(net "M_F_DQS_DN<7>")
	)
	(segment
		(start 312.901076 -148.584666)
		(end 312.901076 -149.248622)
		(width 0.14224)
		(layer "In11.Cu")
		(net "M_F_DQS_DN<7>")
	)
	(segment
		(start 312.743596 -129.161794)
		(end 312.901076 -129.319274)
		(width 0.14224)
		(layer "In11.Cu")
		(net "M_F_DQS_DN<7>")
	)
	(segment
		(start 311.954926 -149.842474)
		(end 311.954926 -151.1046)
		(width 0.14224)
		(layer "In11.Cu")
		(net "M_F_DQS_DN<7>")
	)
	(segment
		(start 298.953174 -112.472724)
		(end 299.529754 -112.472724)
		(width 0.14224)
		(layer "In11.Cu")
		(net "M_F_DQS_DN<7>")
	)
	(segment
		(start 299.529754 -112.472724)
		(end 299.849286 -112.153192)
		(width 0.14224)
		(layer "In11.Cu")
		(net "M_F_DQS_DN<7>")
	)
	(segment
		(start 289.27552 -97.299018)
		(end 289.28187 -97.309686)
		(width 0.0889)
		(layer "In11.Cu")
		(net "M_F_DQS_DN<7>")
	)
	(segment
		(start 312.901076 -146.938746)
		(end 312.901076 -147.192746)
		(width 0.14224)
		(layer "In11.Cu")
		(net "M_F_DQS_DN<7>")
	)
	(segment
		(start 300.026578 -111.436404)
		(end 301.04207 -111.436404)
		(width 0.14224)
		(layer "In11.Cu")
		(net "M_F_DQS_DN<7>")
	)
	(segment
		(start 312.743596 -146.527266)
		(end 312.743596 -146.781266)
		(width 0.14224)
		(layer "In11.Cu")
		(net "M_F_DQS_DN<7>")
	)
	(segment
		(start 312.387996 -149.482556)
		(end 312.314844 -149.482556)
		(width 0.14224)
		(layer "In11.Cu")
		(net "M_F_DQS_DN<7>")
	)
	(segment
		(start 287.20034 -95.128588)
		(end 287.236154 -95.128588)
		(width 0.0889)
		(layer "In11.Cu")
		(net "M_F_DQS_DN<7>")
	)
	(segment
		(start 312.901076 -142.32509)
		(end 312.743596 -142.48257)
		(width 0.14224)
		(layer "In11.Cu")
		(net "M_F_DQS_DN<7>")
	)
	(segment
		(start 284.625034 -93.642688)
		(end 284.6578 -93.642688)
		(width 0.0889)
		(layer "In11.Cu")
		(net "M_F_DQS_DN<7>")
	)
	(segment
		(start 298.647866 -110.903258)
		(end 298.647866 -112.167416)
		(width 0.14224)
		(layer "In11.Cu")
		(net "M_F_DQS_DN<7>")
	)
	(segment
		(start 291.85108 -105.69448)
		(end 292.352984 -105.69448)
		(width 0.14224)
		(layer "In11.Cu")
		(net "M_F_DQS_DN<7>")
	)
	(segment
		(start 312.743596 -132.220462)
		(end 312.901076 -132.377942)
		(width 0.14224)
		(layer "In11.Cu")
		(net "M_F_DQS_DN<7>")
	)
	(segment
		(start 290.764214 -104.175814)
		(end 290.724844 -104.215184)
		(width 0.0889)
		(layer "In11.Cu")
		(net "M_F_DQS_DN<7>")
	)
	(segment
		(start 293.15664 -105.739946)
		(end 293.15664 -106.629454)
		(width 0.14224)
		(layer "In11.Cu")
		(net "M_F_DQS_DN<7>")
	)
	(segment
		(start 311.744106 -151.31542)
		(end 311.744106 -152.97658)
		(width 0.14224)
		(layer "In11.Cu")
		(net "M_F_DQS_DN<7>")
	)
	(segment
		(start 312.901076 -131.808982)
		(end 312.743596 -131.966462)
		(width 0.14224)
		(layer "In11.Cu")
		(net "M_F_DQS_DN<7>")
	)
	(segment
		(start 312.901076 -134.023862)
		(end 312.901076 -136.75487)
		(width 0.14224)
		(layer "In11.Cu")
		(net "M_F_DQS_DN<7>")
	)
	(segment
		(start 312.901076 -141.50213)
		(end 312.743596 -141.65961)
		(width 0.14224)
		(layer "In11.Cu")
		(net "M_F_DQS_DN<7>")
	)
	(segment
		(start 312.314844 -149.482556)
		(end 311.954926 -149.842474)
		(width 0.14224)
		(layer "In11.Cu")
		(net "M_F_DQS_DN<7>")
	)
	(segment
		(start 312.743596 -133.612382)
		(end 312.743596 -133.866382)
		(width 0.14224)
		(layer "In11.Cu")
		(net "M_F_DQS_DN<7>")
	)
	(segment
		(start 312.743596 -137.98931)
		(end 312.901076 -138.14679)
		(width 0.14224)
		(layer "In11.Cu")
		(net "M_F_DQS_DN<7>")
	)
	(segment
		(start 312.901076 -147.192746)
		(end 312.743596 -147.350226)
		(width 0.14224)
		(layer "In11.Cu")
		(net "M_F_DQS_DN<7>")
	)
	(segment
		(start 285.48838 -94.137988)
		(end 285.501334 -94.137988)
		(width 0.0889)
		(layer "In11.Cu")
		(net "M_F_DQS_DN<7>")
	)
	(segment
		(start 312.743596 -148.427186)
		(end 312.901076 -148.584666)
		(width 0.14224)
		(layer "In11.Cu")
		(net "M_F_DQS_DN<7>")
	)
	(segment
		(start 312.743596 -132.789422)
		(end 312.743596 -133.043422)
		(width 0.14224)
		(layer "In11.Cu")
		(net "M_F_DQS_DN<7>")
	)
	(segment
		(start 312.901076 -143.71701)
		(end 312.901076 -146.369786)
		(width 0.14224)
		(layer "In11.Cu")
		(net "M_F_DQS_DN<7>")
	)
	(segment
		(start 290.662614 -103.053134)
		(end 290.764214 -103.154734)
		(width 0.0889)
		(layer "In11.Cu")
		(net "M_F_DQS_DN<7>")
	)
	(segment
		(start 290.724844 -104.237282)
		(end 290.724844 -104.568244)
		(width 0.14224)
		(layer "In11.Cu")
		(net "M_F_DQS_DN<7>")
	)
	(segment
		(start 312.743596 -128.907794)
		(end 312.743596 -129.161794)
		(width 0.14224)
		(layer "In11.Cu")
		(net "M_F_DQS_DN<7>")
	)
	(segment
		(start 312.901076 -142.07109)
		(end 312.901076 -142.32509)
		(width 0.14224)
		(layer "In11.Cu")
		(net "M_F_DQS_DN<7>")
	)
	(segment
		(start 312.901076 -133.454902)
		(end 312.743596 -133.612382)
		(width 0.14224)
		(layer "In11.Cu")
		(net "M_F_DQS_DN<7>")
	)
	(segment
		(start 312.743596 -147.350226)
		(end 312.743596 -147.604226)
		(width 0.14224)
		(layer "In11.Cu")
		(net "M_F_DQS_DN<7>")
	)
	(segment
		(start 312.901076 -129.319274)
		(end 312.901076 -131.808982)
		(width 0.14224)
		(layer "In11.Cu")
		(net "M_F_DQS_DN<7>")
	)
	(segment
		(start 312.743596 -136.91235)
		(end 312.743596 -137.16635)
		(width 0.14224)
		(layer "In11.Cu")
		(net "M_F_DQS_DN<7>")
	)
	(segment
		(start 290.724844 -104.568244)
		(end 291.85108 -105.69448)
		(width 0.14224)
		(layer "In11.Cu")
		(net "M_F_DQS_DN<7>")
	)
	(segment
		(start 312.743596 -143.55953)
		(end 312.901076 -143.71701)
		(width 0.14224)
		(layer "In11.Cu")
		(net "M_F_DQS_DN<7>")
	)
	(segment
		(start 312.743596 -141.91361)
		(end 312.901076 -142.07109)
		(width 0.14224)
		(layer "In11.Cu")
		(net "M_F_DQS_DN<7>")
	)
	(segment
		(start 312.743596 -142.48257)
		(end 312.743596 -142.73657)
		(width 0.14224)
		(layer "In11.Cu")
		(net "M_F_DQS_DN<7>")
	)
	(segment
		(start 312.743596 -142.73657)
		(end 312.901076 -142.89405)
		(width 0.14224)
		(layer "In11.Cu")
		(net "M_F_DQS_DN<7>")
	)
	(segment
		(start 285.844488 -94.332298)
		(end 285.84779 -94.33814)
		(width 0.0889)
		(layer "In11.Cu")
		(net "M_F_DQS_DN<7>")
	)
	(segment
		(start 290.724844 -104.215184)
		(end 290.724844 -104.237282)
		(width 0.0889)
		(layer "In11.Cu")
		(net "M_F_DQS_DN<7>")
	)
	(segment
		(start 292.907212 -105.490518)
		(end 293.15664 -105.739946)
		(width 0.14224)
		(layer "In11.Cu")
		(net "M_F_DQS_DN<7>")
	)
	(segment
		(start 286.33801 -94.633288)
		(end 286.377634 -94.633288)
		(width 0.0889)
		(layer "In11.Cu")
		(net "M_F_DQS_DN<7>")
	)
	(segment
		(start 312.743596 -148.173186)
		(end 312.743596 -148.427186)
		(width 0.14224)
		(layer "In11.Cu")
		(net "M_F_DQS_DN<7>")
	)
	(segment
		(start 312.901076 -123.29541)
		(end 312.901076 -128.750314)
		(width 0.14224)
		(layer "In11.Cu")
		(net "M_F_DQS_DN<7>")
	)
	(segment
		(start 312.743596 -146.781266)
		(end 312.901076 -146.938746)
		(width 0.14224)
		(layer "In11.Cu")
		(net "M_F_DQS_DN<7>")
	)
	(segment
		(start 289.28187 -101.272086)
		(end 289.286696 -101.280722)
		(width 0.0889)
		(layer "In11.Cu")
		(net "M_F_DQS_DN<7>")
	)
	(segment
		(start 312.901076 -148.015706)
		(end 312.743596 -148.173186)
		(width 0.14224)
		(layer "In11.Cu")
		(net "M_F_DQS_DN<7>")
	)
	(segment
		(start 312.901076 -138.96975)
		(end 312.901076 -141.50213)
		(width 0.14224)
		(layer "In11.Cu")
		(net "M_F_DQS_DN<7>")
	)
	(segment
		(start 312.743596 -138.55827)
		(end 312.743596 -138.81227)
		(width 0.14224)
		(layer "In11.Cu")
		(net "M_F_DQS_DN<7>")
	)
	(segment
		(start 312.667142 -149.482556)
		(end 312.387996 -149.482556)
		(width 0.14224)
		(layer "In11.Cu")
		(net "M_F_DQS_DN<7>")
	)
	(segment
		(start 312.743596 -131.966462)
		(end 312.743596 -132.220462)
		(width 0.14224)
		(layer "In11.Cu")
		(net "M_F_DQS_DN<7>")
	)
	(segment
		(start 298.647866 -112.167416)
		(end 298.953174 -112.472724)
		(width 0.14224)
		(layer "In11.Cu")
		(net "M_F_DQS_DN<7>")
	)
	(segment
		(start 293.486586 -106.9594)
		(end 294.704008 -106.9594)
		(width 0.14224)
		(layer "In11.Cu")
		(net "M_F_DQS_DN<7>")
	)
	(segment
		(start 312.743596 -147.604226)
		(end 312.901076 -147.761706)
		(width 0.14224)
		(layer "In11.Cu")
		(net "M_F_DQS_DN<7>")
	)
	(segment
		(start 312.743596 -141.65961)
		(end 312.743596 -141.91361)
		(width 0.14224)
		(layer "In11.Cu")
		(net "M_F_DQS_DN<7>")
	)
	(segment
		(start 293.15664 -106.629454)
		(end 293.486586 -106.9594)
		(width 0.14224)
		(layer "In11.Cu")
		(net "M_F_DQS_DN<7>")
	)
	(segment
		(start 312.743596 -137.16635)
		(end 312.901076 -137.32383)
		(width 0.14224)
		(layer "In11.Cu")
		(net "M_F_DQS_DN<7>")
	)
	(segment
		(start 312.743596 -133.043422)
		(end 312.901076 -133.200902)
		(width 0.14224)
		(layer "In11.Cu")
		(net "M_F_DQS_DN<7>")
	)
	(segment
		(start 312.901076 -143.14805)
		(end 312.743596 -143.30553)
		(width 0.14224)
		(layer "In11.Cu")
		(net "M_F_DQS_DN<7>")
	)
	(segment
		(start 292.556946 -105.490518)
		(end 292.907212 -105.490518)
		(width 0.14224)
		(layer "In11.Cu")
		(net "M_F_DQS_DN<7>")
	)
	(segment
		(start 311.954926 -151.1046)
		(end 311.744106 -151.31542)
		(width 0.14224)
		(layer "In11.Cu")
		(net "M_F_DQS_DN<7>")
	)
	(segment
		(start 312.743596 -133.866382)
		(end 312.901076 -134.023862)
		(width 0.14224)
		(layer "In11.Cu")
		(net "M_F_DQS_DN<7>")
	)
	(segment
		(start 312.901076 -137.57783)
		(end 312.743596 -137.73531)
		(width 0.14224)
		(layer "In11.Cu")
		(net "M_F_DQS_DN<7>")
	)
	(segment
		(start 301.04207 -111.436404)
		(end 312.901076 -123.29541)
		(width 0.14224)
		(layer "In11.Cu")
		(net "M_F_DQS_DN<7>")
	)
	(segment
		(start 312.743596 -143.30553)
		(end 312.743596 -143.55953)
		(width 0.14224)
		(layer "In11.Cu")
		(net "M_F_DQS_DN<7>")
	)
	(segment
		(start 312.901076 -147.761706)
		(end 312.901076 -148.015706)
		(width 0.14224)
		(layer "In11.Cu")
		(net "M_F_DQS_DN<7>")
	)
	(segment
		(start 312.901076 -132.377942)
		(end 312.901076 -132.631942)
		(width 0.14224)
		(layer "In11.Cu")
		(net "M_F_DQS_DN<7>")
	)
	(segment
		(start 312.901076 -138.14679)
		(end 312.901076 -138.40079)
		(width 0.14224)
		(layer "In11.Cu")
		(net "M_F_DQS_DN<7>")
	)
	(segment
		(start 312.901076 -149.248622)
		(end 312.667142 -149.482556)
		(width 0.14224)
		(layer "In11.Cu")
		(net "M_F_DQS_DN<7>")
	)
	(segment
		(start 312.901076 -132.631942)
		(end 312.743596 -132.789422)
		(width 0.14224)
		(layer "In11.Cu")
		(net "M_F_DQS_DN<7>")
	)
	(segment
		(start 288.063686 -95.623888)
		(end 288.091626 -95.623888)
		(width 0.0889)
		(layer "In11.Cu")
		(net "M_F_DQS_DN<7>")
	)
	(segment
		(start 311.954926 -153.1874)
		(end 311.954926 -154.443176)
		(width 0.14224)
		(layer "In11.Cu")
		(net "M_F_DQS_DN<7>")
	)
	(segment
		(start 289.7759 -102.558088)
		(end 289.808666 -102.558088)
		(width 0.0889)
		(layer "In11.Cu")
		(net "M_F_DQS_DN<7>")
	)
	(segment
		(start 312.901076 -136.75487)
		(end 312.743596 -136.91235)
		(width 0.14224)
		(layer "In11.Cu")
		(net "M_F_DQS_DN<7>")
	)
	(segment
		(start 294.704008 -106.9594)
		(end 298.647866 -110.903258)
		(width 0.14224)
		(layer "In11.Cu")
		(net "M_F_DQS_DN<7>")
	)
	(segment
		(start 312.901076 -137.32383)
		(end 312.901076 -137.57783)
		(width 0.14224)
		(layer "In11.Cu")
		(net "M_F_DQS_DN<7>")
	)
	(segment
		(start 290.764214 -103.154734)
		(end 290.764214 -104.175814)
		(width 0.0889)
		(layer "In11.Cu")
		(net "M_F_DQS_DN<7>")
	)
	(arc
		(start 289.27552 -100.692204)
		(mid 289.202722 -100.982967)
		(end 289.28187 -101.272086)
		(width 0.0889)
		(layer "In11.Cu")
		(net "M_F_DQS_DN<7>")
	)
	(arc
		(start 285.501334 -94.137988)
		(mid 285.698495 -94.189947)
		(end 285.844488 -94.332298)
		(width 0.0889)
		(layer "In11.Cu")
		(net "M_F_DQS_DN<7>")
	)
	(arc
		(start 285.84779 -94.33814)
		(mid 286.054794 -94.549004)
		(end 286.33801 -94.633288)
		(width 0.0889)
		(layer "In11.Cu")
		(net "M_F_DQS_DN<7>")
	)
	(arc
		(start 289.808666 -102.558088)
		(mid 290.000308 -102.615254)
		(end 290.14039 -102.757986)
		(width 0.0889)
		(layer "In11.Cu")
		(net "M_F_DQS_DN<7>")
	)
	(arc
		(start 283.784294 -92.556584)
		(mid 283.967263 -92.816063)
		(end 284.05582 -93.120972)
		(width 0.0889)
		(layer "In11.Cu")
		(net "M_F_DQS_DN<7>")
	)
	(arc
		(start 284.6578 -93.642688)
		(mid 284.849442 -93.699854)
		(end 284.989524 -93.842586)
		(width 0.0889)
		(layer "In11.Cu")
		(net "M_F_DQS_DN<7>")
	)
	(arc
		(start 289.28187 -100.28174)
		(mid 289.335369 -100.481638)
		(end 289.28187 -100.681536)
		(width 0.0889)
		(layer "In11.Cu")
		(net "M_F_DQS_DN<7>")
	)
	(arc
		(start 289.28187 -98.301048)
		(mid 289.335344 -98.500692)
		(end 289.28187 -98.700336)
		(width 0.0889)
		(layer "In11.Cu")
		(net "M_F_DQS_DN<7>")
	)
	(arc
		(start 288.091626 -95.623888)
		(mid 288.283268 -95.681054)
		(end 288.42335 -95.823786)
		(width 0.0889)
		(layer "In11.Cu")
		(net "M_F_DQS_DN<7>")
	)
	(arc
		(start 284.05582 -93.120972)
		(mid 284.243412 -93.487664)
		(end 284.625034 -93.642688)
		(width 0.0889)
		(layer "In11.Cu")
		(net "M_F_DQS_DN<7>")
	)
	(arc
		(start 289.28187 -98.700336)
		(mid 289.202648 -98.989454)
		(end 289.27552 -99.280218)
		(width 0.0889)
		(layer "In11.Cu")
		(net "M_F_DQS_DN<7>")
	)
	(arc
		(start 289.286696 -101.280722)
		(mid 289.335451 -101.477074)
		(end 289.28187 -101.672136)
		(width 0.0889)
		(layer "In11.Cu")
		(net "M_F_DQS_DN<7>")
	)
	(arc
		(start 288.42335 -95.823786)
		(mid 288.630354 -96.03465)
		(end 288.91357 -96.118934)
		(width 0.0889)
		(layer "In11.Cu")
		(net "M_F_DQS_DN<7>")
	)
	(arc
		(start 289.28187 -99.690936)
		(mid 289.202739 -99.986338)
		(end 289.28187 -100.28174)
		(width 0.0889)
		(layer "In11.Cu")
		(net "M_F_DQS_DN<7>")
	)
	(arc
		(start 286.70631 -94.833186)
		(mid 286.914918 -95.045118)
		(end 287.20034 -95.128588)
		(width 0.0889)
		(layer "In11.Cu")
		(net "M_F_DQS_DN<7>")
	)
	(arc
		(start 289.28187 -96.719136)
		(mid 289.202648 -97.008254)
		(end 289.27552 -97.299018)
		(width 0.0889)
		(layer "In11.Cu")
		(net "M_F_DQS_DN<7>")
	)
	(arc
		(start 288.946336 -96.118934)
		(mid 289.284505 -96.323732)
		(end 289.28187 -96.719136)
		(width 0.0889)
		(layer "In11.Cu")
		(net "M_F_DQS_DN<7>")
	)
	(arc
		(start 287.236154 -95.128588)
		(mid 287.426083 -95.186458)
		(end 287.56483 -95.328486)
		(width 0.0889)
		(layer "In11.Cu")
		(net "M_F_DQS_DN<7>")
	)
	(arc
		(start 284.989524 -93.842586)
		(mid 285.200237 -94.055665)
		(end 285.48838 -94.137988)
		(width 0.0889)
		(layer "In11.Cu")
		(net "M_F_DQS_DN<7>")
	)
	(arc
		(start 286.377634 -94.633288)
		(mid 286.567563 -94.691158)
		(end 286.70631 -94.833186)
		(width 0.0889)
		(layer "In11.Cu")
		(net "M_F_DQS_DN<7>")
	)
	(arc
		(start 290.14039 -102.757986)
		(mid 290.347177 -102.968719)
		(end 290.630102 -103.053134)
		(width 0.0889)
		(layer "In11.Cu")
		(net "M_F_DQS_DN<7>")
	)
	(arc
		(start 289.28187 -101.672136)
		(mid 289.277541 -102.255308)
		(end 289.7759 -102.558088)
		(width 0.0889)
		(layer "In11.Cu")
		(net "M_F_DQS_DN<7>")
	)
	(arc
		(start 287.56483 -95.328486)
		(mid 287.775543 -95.541565)
		(end 288.063686 -95.623888)
		(width 0.0889)
		(layer "In11.Cu")
		(net "M_F_DQS_DN<7>")
	)
	(arc
		(start 289.28187 -97.309686)
		(mid 289.335589 -97.509982)
		(end 289.28187 -97.710244)
		(width 0.0889)
		(layer "In11.Cu")
		(net "M_F_DQS_DN<7>")
	)
	(arc
		(start 289.286696 -99.299522)
		(mid 289.335451 -99.495874)
		(end 289.28187 -99.690936)
		(width 0.0889)
		(layer "In11.Cu")
		(net "M_F_DQS_DN<7>")
	)
	(arc
		(start 289.28187 -97.710244)
		(mid 289.202739 -98.005646)
		(end 289.28187 -98.301048)
		(width 0.0889)
		(layer "In11.Cu")
		(net "M_F_DQS_DN<7>")
	)
	(segment
		(start 302.822356 -154.6606)
		(end 303.038002 -154.876246)
		(width 0.1651)
		(layer "F.Cu")
		(net "M_F_DQS_DN<6>")
	)
	(segment
		(start 302.64989 -155.80487)
		(end 302.267874 -155.422854)
		(width 0.1651)
		(layer "F.Cu")
		(net "M_F_DQS_DN<6>")
	)
	(segment
		(start 302.267874 -155.422854)
		(end 302.267874 -154.991054)
		(width 0.1651)
		(layer "F.Cu")
		(net "M_F_DQS_DN<6>")
	)
	(segment
		(start 302.598328 -154.6606)
		(end 302.822356 -154.6606)
		(width 0.1651)
		(layer "F.Cu")
		(net "M_F_DQS_DN<6>")
	)
	(segment
		(start 302.267874 -154.991054)
		(end 302.598328 -154.6606)
		(width 0.1651)
		(layer "F.Cu")
		(net "M_F_DQS_DN<6>")
	)
	(segment
		(start 278.061674 -92.556584)
		(end 278.633174 -92.556584)
		(width 0.1651)
		(layer "F.Cu")
		(net "M_F_DQS_DN<6>")
	)
	(segment
		(start 302.650398 -156.87294)
		(end 302.64989 -156.87294)
		(width 0.1651)
		(layer "F.Cu")
		(net "M_F_DQS_DN<6>")
	)
	(segment
		(start 302.64989 -156.87294)
		(end 302.64989 -155.80487)
		(width 0.1651)
		(layer "F.Cu")
		(net "M_F_DQS_DN<6>")
	)
	(via
		(at 303.038002 -154.876246)
		(size 0.508)
		(drill 0.254)
		(layers "F.Cu" "B.Cu")
		(net "M_F_DQS_DN<6>")
	)
	(via
		(at 303.038002 -149.482556)
		(size 0.508)
		(drill 0.254)
		(layers "F.Cu" "B.Cu")
		(net "M_F_DQS_DN<6>")
	)
	(via
		(at 278.633174 -92.556584)
		(size 0.508)
		(drill 0.254)
		(layers "F.Cu" "B.Cu")
		(net "M_F_DQS_DN<6>")
	)
	(segment
		(start 302.812958 -149.7076)
		(end 303.038002 -149.482556)
		(width 0.1651)
		(layer "B.Cu")
		(net "M_F_DQS_DN<6>")
	)
	(segment
		(start 302.64989 -147.478496)
		(end 302.64989 -148.38553)
		(width 0.1651)
		(layer "B.Cu")
		(net "M_F_DQS_DN<6>")
	)
	(segment
		(start 302.64989 -148.38553)
		(end 302.521874 -148.513546)
		(width 0.1651)
		(layer "B.Cu")
		(net "M_F_DQS_DN<6>")
	)
	(segment
		(start 302.521874 -148.513546)
		(end 302.521874 -148.767546)
		(width 0.1651)
		(layer "B.Cu")
		(net "M_F_DQS_DN<6>")
	)
	(segment
		(start 302.623474 -149.7076)
		(end 302.812958 -149.7076)
		(width 0.1651)
		(layer "B.Cu")
		(net "M_F_DQS_DN<6>")
	)
	(segment
		(start 302.521874 -148.767546)
		(end 302.267874 -149.021546)
		(width 0.1651)
		(layer "B.Cu")
		(net "M_F_DQS_DN<6>")
	)
	(segment
		(start 302.650398 -147.478496)
		(end 302.64989 -147.478496)
		(width 0.1651)
		(layer "B.Cu")
		(net "M_F_DQS_DN<6>")
	)
	(segment
		(start 302.267874 -149.352)
		(end 302.623474 -149.7076)
		(width 0.1651)
		(layer "B.Cu")
		(net "M_F_DQS_DN<6>")
	)
	(segment
		(start 302.267874 -149.021546)
		(end 302.267874 -149.352)
		(width 0.1651)
		(layer "B.Cu")
		(net "M_F_DQS_DN<6>")
	)
	(segment
		(start 302.604932 -151.1046)
		(end 302.394112 -151.31542)
		(width 0.14224)
		(layer "In11.Cu")
		(net "M_F_DQS_DN<6>")
	)
	(segment
		(start 303.551082 -137.224516)
		(end 303.551082 -137.478516)
		(width 0.14224)
		(layer "In11.Cu")
		(net "M_F_DQS_DN<6>")
	)
	(segment
		(start 298.104306 -119.639588)
		(end 298.416726 -119.952008)
		(width 0.14224)
		(layer "In11.Cu")
		(net "M_F_DQS_DN<6>")
	)
	(segment
		(start 302.604932 -153.1874)
		(end 302.604932 -154.443176)
		(width 0.14224)
		(layer "In11.Cu")
		(net "M_F_DQS_DN<6>")
	)
	(segment
		(start 303.551082 -146.263614)
		(end 303.393602 -146.421094)
		(width 0.14224)
		(layer "In11.Cu")
		(net "M_F_DQS_DN<6>")
	)
	(segment
		(start 302.604932 -149.842474)
		(end 302.604932 -151.1046)
		(width 0.14224)
		(layer "In11.Cu")
		(net "M_F_DQS_DN<6>")
	)
	(segment
		(start 303.551082 -148.478494)
		(end 303.551082 -149.196044)
		(width 0.14224)
		(layer "In11.Cu")
		(net "M_F_DQS_DN<6>")
	)
	(segment
		(start 303.443132 -128.943354)
		(end 303.443132 -129.197354)
		(width 0.14224)
		(layer "In11.Cu")
		(net "M_F_DQS_DN<6>")
	)
	(segment
		(start 302.394112 -152.97658)
		(end 302.604932 -153.1874)
		(width 0.14224)
		(layer "In11.Cu")
		(net "M_F_DQS_DN<6>")
	)
	(segment
		(start 297.949366 -119.100092)
		(end 298.104306 -119.255032)
		(width 0.14224)
		(layer "In11.Cu")
		(net "M_F_DQS_DN<6>")
	)
	(segment
		(start 303.551082 -142.28953)
		(end 303.393602 -142.44701)
		(width 0.14224)
		(layer "In11.Cu")
		(net "M_F_DQS_DN<6>")
	)
	(segment
		(start 283.272484 -104.148636)
		(end 283.266134 -104.159304)
		(width 0.0889)
		(layer "In11.Cu")
		(net "M_F_DQS_DN<6>")
	)
	(segment
		(start 303.393602 -143.26997)
		(end 303.393602 -143.52397)
		(width 0.14224)
		(layer "In11.Cu")
		(net "M_F_DQS_DN<6>")
	)
	(segment
		(start 303.551082 -147.086574)
		(end 303.393602 -147.244054)
		(width 0.14224)
		(layer "In11.Cu")
		(net "M_F_DQS_DN<6>")
	)
	(segment
		(start 303.393602 -146.421094)
		(end 303.393602 -146.675094)
		(width 0.14224)
		(layer "In11.Cu")
		(net "M_F_DQS_DN<6>")
	)
	(segment
		(start 303.393602 -137.635996)
		(end 303.393602 -137.889996)
		(width 0.14224)
		(layer "In11.Cu")
		(net "M_F_DQS_DN<6>")
	)
	(segment
		(start 303.551082 -136.655556)
		(end 303.393602 -136.813036)
		(width 0.14224)
		(layer "In11.Cu")
		(net "M_F_DQS_DN<6>")
	)
	(segment
		(start 303.038002 -149.482556)
		(end 302.96485 -149.482556)
		(width 0.14224)
		(layer "In11.Cu")
		(net "M_F_DQS_DN<6>")
	)
	(segment
		(start 303.393602 -133.965696)
		(end 303.551082 -134.123176)
		(width 0.14224)
		(layer "In11.Cu")
		(net "M_F_DQS_DN<6>")
	)
	(segment
		(start 282.907994 -98.595688)
		(end 282.94076 -98.595688)
		(width 0.0889)
		(layer "In11.Cu")
		(net "M_F_DQS_DN<6>")
	)
	(segment
		(start 303.551082 -132.477256)
		(end 303.551082 -132.731256)
		(width 0.14224)
		(layer "In11.Cu")
		(net "M_F_DQS_DN<6>")
	)
	(segment
		(start 303.393602 -132.319776)
		(end 303.551082 -132.477256)
		(width 0.14224)
		(layer "In11.Cu")
		(net "M_F_DQS_DN<6>")
	)
	(segment
		(start 303.551082 -124.555758)
		(end 303.551082 -128.835404)
		(width 0.14224)
		(layer "In11.Cu")
		(net "M_F_DQS_DN<6>")
	)
	(segment
		(start 283.210254 -107.165902)
		(end 283.210254 -107.188)
		(width 0.0889)
		(layer "In11.Cu")
		(net "M_F_DQS_DN<6>")
	)
	(segment
		(start 298.947332 -119.952008)
		(end 303.551082 -124.555758)
		(width 0.14224)
		(layer "In11.Cu")
		(net "M_F_DQS_DN<6>")
	)
	(segment
		(start 303.393602 -147.244054)
		(end 303.393602 -147.498054)
		(width 0.14224)
		(layer "In11.Cu")
		(net "M_F_DQS_DN<6>")
	)
	(segment
		(start 279.473914 -96.614488)
		(end 279.50668 -96.614488)
		(width 0.0889)
		(layer "In11.Cu")
		(net "M_F_DQS_DN<6>")
	)
	(segment
		(start 283.272484 -105.729786)
		(end 283.325824 -105.822242)
		(width 0.0889)
		(layer "In11.Cu")
		(net "M_F_DQS_DN<6>")
	)
	(segment
		(start 280.328624 -97.109534)
		(end 280.36139 -97.109534)
		(width 0.0889)
		(layer "In11.Cu")
		(net "M_F_DQS_DN<6>")
	)
	(segment
		(start 303.551082 -147.655534)
		(end 303.551082 -147.909534)
		(width 0.14224)
		(layer "In11.Cu")
		(net "M_F_DQS_DN<6>")
	)
	(segment
		(start 303.393602 -133.711696)
		(end 303.393602 -133.965696)
		(width 0.14224)
		(layer "In11.Cu")
		(net "M_F_DQS_DN<6>")
	)
	(segment
		(start 303.551082 -138.301476)
		(end 303.393602 -138.458956)
		(width 0.14224)
		(layer "In11.Cu")
		(net "M_F_DQS_DN<6>")
	)
	(segment
		(start 295.384728 -119.35587)
		(end 295.83888 -119.35587)
		(width 0.14224)
		(layer "In11.Cu")
		(net "M_F_DQS_DN<6>")
	)
	(segment
		(start 303.551082 -133.554216)
		(end 303.393602 -133.711696)
		(width 0.14224)
		(layer "In11.Cu")
		(net "M_F_DQS_DN<6>")
	)
	(segment
		(start 303.551082 -137.478516)
		(end 303.393602 -137.635996)
		(width 0.14224)
		(layer "In11.Cu")
		(net "M_F_DQS_DN<6>")
	)
	(segment
		(start 303.393602 -143.52397)
		(end 303.551082 -143.68145)
		(width 0.14224)
		(layer "In11.Cu")
		(net "M_F_DQS_DN<6>")
	)
	(segment
		(start 302.96485 -149.482556)
		(end 302.604932 -149.842474)
		(width 0.14224)
		(layer "In11.Cu")
		(net "M_F_DQS_DN<6>")
	)
	(segment
		(start 281.190954 -97.605088)
		(end 281.22372 -97.605088)
		(width 0.0889)
		(layer "In11.Cu")
		(net "M_F_DQS_DN<6>")
	)
	(segment
		(start 278.979884 -95.328486)
		(end 278.98471 -95.337122)
		(width 0.0889)
		(layer "In11.Cu")
		(net "M_F_DQS_DN<6>")
	)
	(segment
		(start 303.393602 -142.44701)
		(end 303.393602 -142.70101)
		(width 0.14224)
		(layer "In11.Cu")
		(net "M_F_DQS_DN<6>")
	)
	(segment
		(start 303.393602 -137.889996)
		(end 303.551082 -138.047476)
		(width 0.14224)
		(layer "In11.Cu")
		(net "M_F_DQS_DN<6>")
	)
	(segment
		(start 303.551082 -128.835404)
		(end 303.443132 -128.943354)
		(width 0.14224)
		(layer "In11.Cu")
		(net "M_F_DQS_DN<6>")
	)
	(segment
		(start 283.210254 -107.188)
		(end 283.210254 -113.06175)
		(width 0.14224)
		(layer "In11.Cu")
		(net "M_F_DQS_DN<6>")
	)
	(segment
		(start 278.980138 -93.347794)
		(end 278.979884 -93.34754)
		(width 0.0889)
		(layer "In11.Cu")
		(net "M_F_DQS_DN<6>")
	)
	(segment
		(start 303.393602 -147.498054)
		(end 303.551082 -147.655534)
		(width 0.14224)
		(layer "In11.Cu")
		(net "M_F_DQS_DN<6>")
	)
	(segment
		(start 303.393602 -136.813036)
		(end 303.393602 -137.067036)
		(width 0.14224)
		(layer "In11.Cu")
		(net "M_F_DQS_DN<6>")
	)
	(segment
		(start 295.83888 -119.35587)
		(end 296.435018 -119.952008)
		(width 0.14224)
		(layer "In11.Cu")
		(net "M_F_DQS_DN<6>")
	)
	(segment
		(start 283.325824 -105.822242)
		(end 283.325824 -106.130598)
		(width 0.0889)
		(layer "In11.Cu")
		(net "M_F_DQS_DN<6>")
	)
	(segment
		(start 303.551082 -133.300216)
		(end 303.551082 -133.554216)
		(width 0.14224)
		(layer "In11.Cu")
		(net "M_F_DQS_DN<6>")
	)
	(segment
		(start 297.441366 -119.255032)
		(end 297.596306 -119.100092)
		(width 0.14224)
		(layer "In11.Cu")
		(net "M_F_DQS_DN<6>")
	)
	(segment
		(start 303.393602 -137.067036)
		(end 303.551082 -137.224516)
		(width 0.14224)
		(layer "In11.Cu")
		(net "M_F_DQS_DN<6>")
	)
	(segment
		(start 294.65397 -120.086628)
		(end 295.384728 -119.35587)
		(width 0.14224)
		(layer "In11.Cu")
		(net "M_F_DQS_DN<6>")
	)
	(segment
		(start 303.551082 -134.123176)
		(end 303.551082 -136.655556)
		(width 0.14224)
		(layer "In11.Cu")
		(net "M_F_DQS_DN<6>")
	)
	(segment
		(start 303.551082 -138.047476)
		(end 303.551082 -138.301476)
		(width 0.14224)
		(layer "In11.Cu")
		(net "M_F_DQS_DN<6>")
	)
	(segment
		(start 297.128946 -119.952008)
		(end 297.441366 -119.639588)
		(width 0.14224)
		(layer "In11.Cu")
		(net "M_F_DQS_DN<6>")
	)
	(segment
		(start 278.979884 -94.737936)
		(end 278.973534 -94.748604)
		(width 0.0889)
		(layer "In11.Cu")
		(net "M_F_DQS_DN<6>")
	)
	(segment
		(start 303.551082 -146.832574)
		(end 303.551082 -147.086574)
		(width 0.14224)
		(layer "In11.Cu")
		(net "M_F_DQS_DN<6>")
	)
	(segment
		(start 303.551082 -132.731256)
		(end 303.393602 -132.888736)
		(width 0.14224)
		(layer "In11.Cu")
		(net "M_F_DQS_DN<6>")
	)
	(segment
		(start 303.393602 -146.675094)
		(end 303.551082 -146.832574)
		(width 0.14224)
		(layer "In11.Cu")
		(net "M_F_DQS_DN<6>")
	)
	(segment
		(start 283.27731 -105.1306)
		(end 283.272484 -105.139236)
		(width 0.0889)
		(layer "In11.Cu")
		(net "M_F_DQS_DN<6>")
	)
	(segment
		(start 303.393602 -141.62405)
		(end 303.393602 -141.87805)
		(width 0.14224)
		(layer "In11.Cu")
		(net "M_F_DQS_DN<6>")
	)
	(segment
		(start 283.210254 -113.06175)
		(end 290.235132 -120.086628)
		(width 0.14224)
		(layer "In11.Cu")
		(net "M_F_DQS_DN<6>")
	)
	(segment
		(start 283.27731 -104.14)
		(end 283.272484 -104.148636)
		(width 0.0889)
		(layer "In11.Cu")
		(net "M_F_DQS_DN<6>")
	)
	(segment
		(start 303.393602 -138.458956)
		(end 303.393602 -138.712956)
		(width 0.14224)
		(layer "In11.Cu")
		(net "M_F_DQS_DN<6>")
	)
	(segment
		(start 303.551082 -141.46657)
		(end 303.393602 -141.62405)
		(width 0.14224)
		(layer "In11.Cu")
		(net "M_F_DQS_DN<6>")
	)
	(segment
		(start 303.551082 -138.870436)
		(end 303.551082 -141.46657)
		(width 0.14224)
		(layer "In11.Cu")
		(net "M_F_DQS_DN<6>")
	)
	(segment
		(start 298.416726 -119.952008)
		(end 298.947332 -119.952008)
		(width 0.14224)
		(layer "In11.Cu")
		(net "M_F_DQS_DN<6>")
	)
	(segment
		(start 302.604932 -154.443176)
		(end 303.038002 -154.876246)
		(width 0.14224)
		(layer "In11.Cu")
		(net "M_F_DQS_DN<6>")
	)
	(segment
		(start 302.394112 -151.31542)
		(end 302.394112 -152.97658)
		(width 0.14224)
		(layer "In11.Cu")
		(net "M_F_DQS_DN<6>")
	)
	(segment
		(start 303.393602 -133.142736)
		(end 303.551082 -133.300216)
		(width 0.14224)
		(layer "In11.Cu")
		(net "M_F_DQS_DN<6>")
	)
	(segment
		(start 303.393602 -142.70101)
		(end 303.551082 -142.85849)
		(width 0.14224)
		(layer "In11.Cu")
		(net "M_F_DQS_DN<6>")
	)
	(segment
		(start 283.325824 -106.130598)
		(end 283.249624 -106.206798)
		(width 0.0889)
		(layer "In11.Cu")
		(net "M_F_DQS_DN<6>")
	)
	(segment
		(start 303.393602 -132.065776)
		(end 303.393602 -132.319776)
		(width 0.14224)
		(layer "In11.Cu")
		(net "M_F_DQS_DN<6>")
	)
	(segment
		(start 283.272484 -103.158036)
		(end 283.266134 -103.168704)
		(width 0.0889)
		(layer "In11.Cu")
		(net "M_F_DQS_DN<6>")
	)
	(segment
		(start 283.27731 -99.187)
		(end 283.272484 -99.195636)
		(width 0.0889)
		(layer "In11.Cu")
		(net "M_F_DQS_DN<6>")
	)
	(segment
		(start 303.551082 -147.909534)
		(end 303.393602 -148.067014)
		(width 0.14224)
		(layer "In11.Cu")
		(net "M_F_DQS_DN<6>")
	)
	(segment
		(start 303.393602 -148.321014)
		(end 303.551082 -148.478494)
		(width 0.14224)
		(layer "In11.Cu")
		(net "M_F_DQS_DN<6>")
	)
	(segment
		(start 298.104306 -119.255032)
		(end 298.104306 -119.639588)
		(width 0.14224)
		(layer "In11.Cu")
		(net "M_F_DQS_DN<6>")
	)
	(segment
		(start 283.27731 -103.1494)
		(end 283.272484 -103.158036)
		(width 0.0889)
		(layer "In11.Cu")
		(net "M_F_DQS_DN<6>")
	)
	(segment
		(start 282.045664 -98.100134)
		(end 282.07843 -98.100134)
		(width 0.0889)
		(layer "In11.Cu")
		(net "M_F_DQS_DN<6>")
	)
	(segment
		(start 303.551082 -142.03553)
		(end 303.551082 -142.28953)
		(width 0.14224)
		(layer "In11.Cu")
		(net "M_F_DQS_DN<6>")
	)
	(segment
		(start 303.551082 -131.908296)
		(end 303.393602 -132.065776)
		(width 0.14224)
		(layer "In11.Cu")
		(net "M_F_DQS_DN<6>")
	)
	(segment
		(start 303.551082 -143.68145)
		(end 303.551082 -146.263614)
		(width 0.14224)
		(layer "In11.Cu")
		(net "M_F_DQS_DN<6>")
	)
	(segment
		(start 303.551082 -129.305304)
		(end 303.551082 -131.908296)
		(width 0.14224)
		(layer "In11.Cu")
		(net "M_F_DQS_DN<6>")
	)
	(segment
		(start 303.393602 -141.87805)
		(end 303.551082 -142.03553)
		(width 0.14224)
		(layer "In11.Cu")
		(net "M_F_DQS_DN<6>")
	)
	(segment
		(start 296.435018 -119.952008)
		(end 297.128946 -119.952008)
		(width 0.14224)
		(layer "In11.Cu")
		(net "M_F_DQS_DN<6>")
	)
	(segment
		(start 303.551082 -142.85849)
		(end 303.551082 -143.11249)
		(width 0.14224)
		(layer "In11.Cu")
		(net "M_F_DQS_DN<6>")
	)
	(segment
		(start 297.596306 -119.100092)
		(end 297.949366 -119.100092)
		(width 0.14224)
		(layer "In11.Cu")
		(net "M_F_DQS_DN<6>")
	)
	(segment
		(start 283.249624 -107.126532)
		(end 283.210254 -107.165902)
		(width 0.0889)
		(layer "In11.Cu")
		(net "M_F_DQS_DN<6>")
	)
	(segment
		(start 303.393602 -138.712956)
		(end 303.551082 -138.870436)
		(width 0.14224)
		(layer "In11.Cu")
		(net "M_F_DQS_DN<6>")
	)
	(segment
		(start 283.272484 -99.785932)
		(end 283.27731 -99.794568)
		(width 0.0889)
		(layer "In11.Cu")
		(net "M_F_DQS_DN<6>")
	)
	(segment
		(start 290.235132 -120.086628)
		(end 294.65397 -120.086628)
		(width 0.14224)
		(layer "In11.Cu")
		(net "M_F_DQS_DN<6>")
	)
	(segment
		(start 303.443132 -129.197354)
		(end 303.551082 -129.305304)
		(width 0.14224)
		(layer "In11.Cu")
		(net "M_F_DQS_DN<6>")
	)
	(segment
		(start 303.551082 -149.196044)
		(end 303.26457 -149.482556)
		(width 0.14224)
		(layer "In11.Cu")
		(net "M_F_DQS_DN<6>")
	)
	(segment
		(start 303.26457 -149.482556)
		(end 303.038002 -149.482556)
		(width 0.14224)
		(layer "In11.Cu")
		(net "M_F_DQS_DN<6>")
	)
	(segment
		(start 303.551082 -143.11249)
		(end 303.393602 -143.26997)
		(width 0.14224)
		(layer "In11.Cu")
		(net "M_F_DQS_DN<6>")
	)
	(segment
		(start 303.393602 -132.888736)
		(end 303.393602 -133.142736)
		(width 0.14224)
		(layer "In11.Cu")
		(net "M_F_DQS_DN<6>")
	)
	(segment
		(start 297.441366 -119.639588)
		(end 297.441366 -119.255032)
		(width 0.14224)
		(layer "In11.Cu")
		(net "M_F_DQS_DN<6>")
	)
	(segment
		(start 303.393602 -148.067014)
		(end 303.393602 -148.321014)
		(width 0.14224)
		(layer "In11.Cu")
		(net "M_F_DQS_DN<6>")
	)
	(segment
		(start 283.249624 -106.206798)
		(end 283.249624 -107.126532)
		(width 0.0889)
		(layer "In11.Cu")
		(net "M_F_DQS_DN<6>")
	)
	(segment
		(start 283.272484 -105.139236)
		(end 283.266134 -105.149904)
		(width 0.0889)
		(layer "In11.Cu")
		(net "M_F_DQS_DN<6>")
	)
	(arc
		(start 279.50668 -96.614488)
		(mid 279.698322 -96.671654)
		(end 279.838404 -96.814386)
		(width 0.0889)
		(layer "In11.Cu")
		(net "M_F_DQS_DN<6>")
	)
	(arc
		(start 278.979884 -94.33814)
		(mid 279.033383 -94.538038)
		(end 278.979884 -94.737936)
		(width 0.0889)
		(layer "In11.Cu")
		(net "M_F_DQS_DN<6>")
	)
	(arc
		(start 283.272484 -104.739186)
		(mid 283.325954 -104.934249)
		(end 283.27731 -105.1306)
		(width 0.0889)
		(layer "In11.Cu")
		(net "M_F_DQS_DN<6>")
	)
	(arc
		(start 278.979884 -93.34754)
		(mid 279.033383 -93.547438)
		(end 278.979884 -93.747336)
		(width 0.0889)
		(layer "In11.Cu")
		(net "M_F_DQS_DN<6>")
	)
	(arc
		(start 283.272484 -99.195636)
		(mid 283.193479 -99.490784)
		(end 283.272484 -99.785932)
		(width 0.0889)
		(layer "In11.Cu")
		(net "M_F_DQS_DN<6>")
	)
	(arc
		(start 282.07843 -98.100134)
		(mid 282.27228 -98.156484)
		(end 282.413964 -98.300286)
		(width 0.0889)
		(layer "In11.Cu")
		(net "M_F_DQS_DN<6>")
	)
	(arc
		(start 283.272484 -101.176582)
		(mid 283.193489 -101.465557)
		(end 283.266134 -101.75621)
		(width 0.0889)
		(layer "In11.Cu")
		(net "M_F_DQS_DN<6>")
	)
	(arc
		(start 282.94076 -98.595688)
		(mid 283.273678 -98.797679)
		(end 283.27731 -99.187)
		(width 0.0889)
		(layer "In11.Cu")
		(net "M_F_DQS_DN<6>")
	)
	(arc
		(start 278.979884 -93.747336)
		(mid 278.900821 -94.042738)
		(end 278.979884 -94.33814)
		(width 0.0889)
		(layer "In11.Cu")
		(net "M_F_DQS_DN<6>")
	)
	(arc
		(start 283.266134 -105.149904)
		(mid 283.193336 -105.440667)
		(end 283.272484 -105.729786)
		(width 0.0889)
		(layer "In11.Cu")
		(net "M_F_DQS_DN<6>")
	)
	(arc
		(start 280.696924 -97.309686)
		(mid 280.905532 -97.521618)
		(end 281.190954 -97.605088)
		(width 0.0889)
		(layer "In11.Cu")
		(net "M_F_DQS_DN<6>")
	)
	(arc
		(start 279.838404 -96.814386)
		(mid 280.045408 -97.02525)
		(end 280.328624 -97.109534)
		(width 0.0889)
		(layer "In11.Cu")
		(net "M_F_DQS_DN<6>")
	)
	(arc
		(start 278.98471 -95.337122)
		(mid 279.033465 -95.533474)
		(end 278.979884 -95.728536)
		(width 0.0889)
		(layer "In11.Cu")
		(net "M_F_DQS_DN<6>")
	)
	(arc
		(start 281.22372 -97.605088)
		(mid 281.415362 -97.662254)
		(end 281.555444 -97.804986)
		(width 0.0889)
		(layer "In11.Cu")
		(net "M_F_DQS_DN<6>")
	)
	(arc
		(start 283.27731 -101.775768)
		(mid 283.326065 -101.97212)
		(end 283.272484 -102.167182)
		(width 0.0889)
		(layer "In11.Cu")
		(net "M_F_DQS_DN<6>")
	)
	(arc
		(start 283.272484 -103.748586)
		(mid 283.325954 -103.943649)
		(end 283.27731 -104.14)
		(width 0.0889)
		(layer "In11.Cu")
		(net "M_F_DQS_DN<6>")
	)
	(arc
		(start 280.36139 -97.109534)
		(mid 280.55524 -97.165884)
		(end 280.696924 -97.309686)
		(width 0.0889)
		(layer "In11.Cu")
		(net "M_F_DQS_DN<6>")
	)
	(arc
		(start 283.266134 -100.76561)
		(mid 283.286743 -100.803355)
		(end 283.303218 -100.84308)
		(width 0.0889)
		(layer "In11.Cu")
		(net "M_F_DQS_DN<6>")
	)
	(arc
		(start 283.266134 -101.75621)
		(mid 283.271822 -101.765932)
		(end 283.27731 -101.775768)
		(width 0.0889)
		(layer "In11.Cu")
		(net "M_F_DQS_DN<6>")
	)
	(arc
		(start 283.303218 -100.84308)
		(mid 283.32439 -101.013195)
		(end 283.272484 -101.176582)
		(width 0.0889)
		(layer "In11.Cu")
		(net "M_F_DQS_DN<6>")
	)
	(arc
		(start 278.973534 -94.748604)
		(mid 278.900736 -95.039367)
		(end 278.979884 -95.328486)
		(width 0.0889)
		(layer "In11.Cu")
		(net "M_F_DQS_DN<6>")
	)
	(arc
		(start 283.272484 -102.167182)
		(mid 283.193353 -102.462584)
		(end 283.272484 -102.757986)
		(width 0.0889)
		(layer "In11.Cu")
		(net "M_F_DQS_DN<6>")
	)
	(arc
		(start 278.979884 -95.728536)
		(mid 278.975555 -96.311708)
		(end 279.473914 -96.614488)
		(width 0.0889)
		(layer "In11.Cu")
		(net "M_F_DQS_DN<6>")
	)
	(arc
		(start 283.266134 -103.168704)
		(mid 283.193336 -103.459467)
		(end 283.272484 -103.748586)
		(width 0.0889)
		(layer "In11.Cu")
		(net "M_F_DQS_DN<6>")
	)
	(arc
		(start 281.555444 -97.804986)
		(mid 281.762448 -98.01585)
		(end 282.045664 -98.100134)
		(width 0.0889)
		(layer "In11.Cu")
		(net "M_F_DQS_DN<6>")
	)
	(arc
		(start 282.413964 -98.300286)
		(mid 282.622572 -98.512218)
		(end 282.907994 -98.595688)
		(width 0.0889)
		(layer "In11.Cu")
		(net "M_F_DQS_DN<6>")
	)
	(arc
		(start 283.266134 -104.159304)
		(mid 283.193336 -104.450067)
		(end 283.272484 -104.739186)
		(width 0.0889)
		(layer "In11.Cu")
		(net "M_F_DQS_DN<6>")
	)
	(arc
		(start 283.27731 -99.794568)
		(mid 283.326065 -99.99092)
		(end 283.272484 -100.185982)
		(width 0.0889)
		(layer "In11.Cu")
		(net "M_F_DQS_DN<6>")
	)
	(arc
		(start 283.272484 -100.185982)
		(mid 283.193489 -100.474957)
		(end 283.266134 -100.76561)
		(width 0.0889)
		(layer "In11.Cu")
		(net "M_F_DQS_DN<6>")
	)
	(arc
		(start 283.272484 -102.757986)
		(mid 283.325954 -102.953049)
		(end 283.27731 -103.1494)
		(width 0.0889)
		(layer "In11.Cu")
		(net "M_F_DQS_DN<6>")
	)
	(arc
		(start 278.633174 -92.556584)
		(mid 278.78494 -92.961711)
		(end 278.980138 -93.347794)
		(width 0.0889)
		(layer "In11.Cu")
		(net "M_F_DQS_DN<6>")
	)
	(segment
		(start 293.248334 -154.6606)
		(end 293.472362 -154.6606)
		(width 0.1651)
		(layer "F.Cu")
		(net "M_F_DQS_DN<5>")
	)
	(segment
		(start 293.299896 -155.80487)
		(end 292.91788 -155.422854)
		(width 0.1651)
		(layer "F.Cu")
		(net "M_F_DQS_DN<5>")
	)
	(segment
		(start 292.91788 -155.422854)
		(end 292.91788 -154.991054)
		(width 0.1651)
		(layer "F.Cu")
		(net "M_F_DQS_DN<5>")
	)
	(segment
		(start 292.91788 -154.991054)
		(end 293.248334 -154.6606)
		(width 0.1651)
		(layer "F.Cu")
		(net "M_F_DQS_DN<5>")
	)
	(segment
		(start 293.299896 -156.87294)
		(end 293.299896 -155.80487)
		(width 0.1651)
		(layer "F.Cu")
		(net "M_F_DQS_DN<5>")
	)
	(segment
		(start 280.637234 -96.023938)
		(end 281.208734 -96.023938)
		(width 0.1651)
		(layer "F.Cu")
		(net "M_F_DQS_DN<5>")
	)
	(segment
		(start 293.300404 -156.87294)
		(end 293.299896 -156.87294)
		(width 0.1651)
		(layer "F.Cu")
		(net "M_F_DQS_DN<5>")
	)
	(segment
		(start 293.472362 -154.6606)
		(end 293.688008 -154.876246)
		(width 0.1651)
		(layer "F.Cu")
		(net "M_F_DQS_DN<5>")
	)
	(via
		(at 281.208734 -96.023938)
		(size 0.508)
		(drill 0.254)
		(layers "F.Cu" "B.Cu")
		(net "M_F_DQS_DN<5>")
	)
	(via
		(at 293.688008 -149.482556)
		(size 0.508)
		(drill 0.254)
		(layers "F.Cu" "B.Cu")
		(net "M_F_DQS_DN<5>")
	)
	(via
		(at 293.688008 -154.876246)
		(size 0.508)
		(drill 0.254)
		(layers "F.Cu" "B.Cu")
		(net "M_F_DQS_DN<5>")
	)
	(segment
		(start 293.27348 -149.7076)
		(end 293.462964 -149.7076)
		(width 0.1651)
		(layer "B.Cu")
		(net "M_F_DQS_DN<5>")
	)
	(segment
		(start 292.91788 -149.352)
		(end 293.27348 -149.7076)
		(width 0.1651)
		(layer "B.Cu")
		(net "M_F_DQS_DN<5>")
	)
	(segment
		(start 293.299896 -147.478496)
		(end 293.299896 -148.38553)
		(width 0.1651)
		(layer "B.Cu")
		(net "M_F_DQS_DN<5>")
	)
	(segment
		(start 293.17188 -148.767546)
		(end 292.91788 -149.021546)
		(width 0.1651)
		(layer "B.Cu")
		(net "M_F_DQS_DN<5>")
	)
	(segment
		(start 293.17188 -148.513546)
		(end 293.17188 -148.767546)
		(width 0.1651)
		(layer "B.Cu")
		(net "M_F_DQS_DN<5>")
	)
	(segment
		(start 293.300404 -147.478496)
		(end 293.299896 -147.478496)
		(width 0.1651)
		(layer "B.Cu")
		(net "M_F_DQS_DN<5>")
	)
	(segment
		(start 293.299896 -148.38553)
		(end 293.17188 -148.513546)
		(width 0.1651)
		(layer "B.Cu")
		(net "M_F_DQS_DN<5>")
	)
	(segment
		(start 292.91788 -149.021546)
		(end 292.91788 -149.352)
		(width 0.1651)
		(layer "B.Cu")
		(net "M_F_DQS_DN<5>")
	)
	(segment
		(start 293.462964 -149.7076)
		(end 293.688008 -149.482556)
		(width 0.1651)
		(layer "B.Cu")
		(net "M_F_DQS_DN<5>")
	)
	(segment
		(start 294.056562 -122.757184)
		(end 293.507668 -123.306078)
		(width 0.14224)
		(layer "In4.Cu")
		(net "M_F_DQS_DN<5>")
	)
	(segment
		(start 282.640024 -107.41533)
		(end 282.600654 -107.4547)
		(width 0.0889)
		(layer "In4.Cu")
		(net "M_F_DQS_DN<5>")
	)
	(segment
		(start 294.201088 -132.371592)
		(end 294.201088 -132.625592)
		(width 0.14224)
		(layer "In4.Cu")
		(net "M_F_DQS_DN<5>")
	)
	(segment
		(start 294.043608 -147.264374)
		(end 294.043608 -147.518374)
		(width 0.14224)
		(layer "In4.Cu")
		(net "M_F_DQS_DN<5>")
	)
	(segment
		(start 294.056562 -122.578114)
		(end 294.056562 -122.757184)
		(width 0.14224)
		(layer "In4.Cu")
		(net "M_F_DQS_DN<5>")
	)
	(segment
		(start 294.201088 -143.093694)
		(end 294.043608 -143.251174)
		(width 0.14224)
		(layer "In4.Cu")
		(net "M_F_DQS_DN<5>")
	)
	(segment
		(start 293.507668 -123.306078)
		(end 293.507668 -123.759468)
		(width 0.14224)
		(layer "In4.Cu")
		(net "M_F_DQS_DN<5>")
	)
	(segment
		(start 294.043608 -141.605254)
		(end 294.043608 -141.859254)
		(width 0.14224)
		(layer "In4.Cu")
		(net "M_F_DQS_DN<5>")
	)
	(segment
		(start 294.201088 -138.003788)
		(end 294.201088 -138.257788)
		(width 0.14224)
		(layer "In4.Cu")
		(net "M_F_DQS_DN<5>")
	)
	(segment
		(start 294.043608 -138.669268)
		(end 294.201088 -138.826748)
		(width 0.14224)
		(layer "In4.Cu")
		(net "M_F_DQS_DN<5>")
	)
	(segment
		(start 293.967408 -149.482556)
		(end 293.688008 -149.482556)
		(width 0.14224)
		(layer "In4.Cu")
		(net "M_F_DQS_DN<5>")
	)
	(segment
		(start 294.043608 -146.441414)
		(end 294.043608 -146.695414)
		(width 0.14224)
		(layer "In4.Cu")
		(net "M_F_DQS_DN<5>")
	)
	(segment
		(start 294.201088 -142.839694)
		(end 294.201088 -143.093694)
		(width 0.14224)
		(layer "In4.Cu")
		(net "M_F_DQS_DN<5>")
	)
	(segment
		(start 294.043608 -146.695414)
		(end 294.201088 -146.852894)
		(width 0.14224)
		(layer "In4.Cu")
		(net "M_F_DQS_DN<5>")
	)
	(segment
		(start 294.201088 -134.017512)
		(end 294.201088 -136.611868)
		(width 0.14224)
		(layer "In4.Cu")
		(net "M_F_DQS_DN<5>")
	)
	(segment
		(start 294.201088 -136.611868)
		(end 294.043608 -136.769348)
		(width 0.14224)
		(layer "In4.Cu")
		(net "M_F_DQS_DN<5>")
	)
	(segment
		(start 294.043608 -132.214112)
		(end 294.201088 -132.371592)
		(width 0.14224)
		(layer "In4.Cu")
		(net "M_F_DQS_DN<5>")
	)
	(segment
		(start 282.600654 -107.4547)
		(end 282.600654 -107.476798)
		(width 0.0889)
		(layer "In4.Cu")
		(net "M_F_DQS_DN<5>")
	)
	(segment
		(start 294.043608 -133.037072)
		(end 294.201088 -133.194552)
		(width 0.14224)
		(layer "In4.Cu")
		(net "M_F_DQS_DN<5>")
	)
	(segment
		(start 294.201088 -146.852894)
		(end 294.201088 -147.106894)
		(width 0.14224)
		(layer "In4.Cu")
		(net "M_F_DQS_DN<5>")
	)
	(segment
		(start 294.201088 -142.270734)
		(end 294.043608 -142.428214)
		(width 0.14224)
		(layer "In4.Cu")
		(net "M_F_DQS_DN<5>")
	)
	(segment
		(start 294.201088 -131.802632)
		(end 294.043608 -131.960112)
		(width 0.14224)
		(layer "In4.Cu")
		(net "M_F_DQS_DN<5>")
	)
	(segment
		(start 294.043608 -137.023348)
		(end 294.201088 -137.180828)
		(width 0.14224)
		(layer "In4.Cu")
		(net "M_F_DQS_DN<5>")
	)
	(segment
		(start 281.562302 -101.16439)
		(end 281.546554 -101.191822)
		(width 0.0889)
		(layer "In4.Cu")
		(net "M_F_DQS_DN<5>")
	)
	(segment
		(start 292.48354 -122.619008)
		(end 293.108634 -122.619008)
		(width 0.14224)
		(layer "In4.Cu")
		(net "M_F_DQS_DN<5>")
	)
	(segment
		(start 294.107616 -140.078968)
		(end 294.107616 -140.332968)
		(width 0.14224)
		(layer "In4.Cu")
		(net "M_F_DQS_DN<5>")
	)
	(segment
		(start 294.201088 -138.826748)
		(end 294.201088 -139.985496)
		(width 0.14224)
		(layer "In4.Cu")
		(net "M_F_DQS_DN<5>")
	)
	(segment
		(start 294.201088 -140.42644)
		(end 294.201088 -141.447774)
		(width 0.14224)
		(layer "In4.Cu")
		(net "M_F_DQS_DN<5>")
	)
	(segment
		(start 294.043608 -137.846308)
		(end 294.201088 -138.003788)
		(width 0.14224)
		(layer "In4.Cu")
		(net "M_F_DQS_DN<5>")
	)
	(segment
		(start 294.201088 -147.106894)
		(end 294.043608 -147.264374)
		(width 0.14224)
		(layer "In4.Cu")
		(net "M_F_DQS_DN<5>")
	)
	(segment
		(start 294.043608 -148.341334)
		(end 294.201088 -148.498814)
		(width 0.14224)
		(layer "In4.Cu")
		(net "M_F_DQS_DN<5>")
	)
	(segment
		(start 282.600654 -112.736122)
		(end 292.48354 -122.619008)
		(width 0.14224)
		(layer "In4.Cu")
		(net "M_F_DQS_DN<5>")
	)
	(segment
		(start 294.043608 -142.682214)
		(end 294.201088 -142.839694)
		(width 0.14224)
		(layer "In4.Cu")
		(net "M_F_DQS_DN<5>")
	)
	(segment
		(start 293.108634 -122.619008)
		(end 293.469568 -122.258074)
		(width 0.14224)
		(layer "In4.Cu")
		(net "M_F_DQS_DN<5>")
	)
	(segment
		(start 294.201088 -141.447774)
		(end 294.043608 -141.605254)
		(width 0.14224)
		(layer "In4.Cu")
		(net "M_F_DQS_DN<5>")
	)
	(segment
		(start 294.201088 -147.929854)
		(end 294.043608 -148.087334)
		(width 0.14224)
		(layer "In4.Cu")
		(net "M_F_DQS_DN<5>")
	)
	(segment
		(start 282.45435 -106.295444)
		(end 282.640024 -106.481118)
		(width 0.0889)
		(layer "In4.Cu")
		(net "M_F_DQS_DN<5>")
	)
	(segment
		(start 281.562302 -104.13619)
		(end 281.546554 -104.163622)
		(width 0.0889)
		(layer "In4.Cu")
		(net "M_F_DQS_DN<5>")
	)
	(segment
		(start 294.201088 -133.448552)
		(end 294.043608 -133.606032)
		(width 0.14224)
		(layer "In4.Cu")
		(net "M_F_DQS_DN<5>")
	)
	(segment
		(start 294.043608 -142.428214)
		(end 294.043608 -142.682214)
		(width 0.14224)
		(layer "In4.Cu")
		(net "M_F_DQS_DN<5>")
	)
	(segment
		(start 281.562302 -100.17379)
		(end 281.546554 -100.201222)
		(width 0.0889)
		(layer "In4.Cu")
		(net "M_F_DQS_DN<5>")
	)
	(segment
		(start 294.043608 -148.087334)
		(end 294.043608 -148.341334)
		(width 0.14224)
		(layer "In4.Cu")
		(net "M_F_DQS_DN<5>")
	)
	(segment
		(start 282.453842 -106.294428)
		(end 282.45435 -106.295444)
		(width 0.0889)
		(layer "In4.Cu")
		(net "M_F_DQS_DN<5>")
	)
	(segment
		(start 294.201088 -146.283934)
		(end 294.043608 -146.441414)
		(width 0.14224)
		(layer "In4.Cu")
		(net "M_F_DQS_DN<5>")
	)
	(segment
		(start 293.469568 -122.258074)
		(end 293.736522 -122.258074)
		(width 0.14224)
		(layer "In4.Cu")
		(net "M_F_DQS_DN<5>")
	)
	(segment
		(start 294.043608 -136.769348)
		(end 294.043608 -137.023348)
		(width 0.14224)
		(layer "In4.Cu")
		(net "M_F_DQS_DN<5>")
	)
	(segment
		(start 293.736522 -122.258074)
		(end 294.056562 -122.578114)
		(width 0.14224)
		(layer "In4.Cu")
		(net "M_F_DQS_DN<5>")
	)
	(segment
		(start 294.043608 -138.415268)
		(end 294.043608 -138.669268)
		(width 0.14224)
		(layer "In4.Cu")
		(net "M_F_DQS_DN<5>")
	)
	(segment
		(start 282.042362 -105.03408)
		(end 282.07208 -105.03408)
		(width 0.0889)
		(layer "In4.Cu")
		(net "M_F_DQS_DN<5>")
	)
	(segment
		(start 294.201088 -138.257788)
		(end 294.043608 -138.415268)
		(width 0.14224)
		(layer "In4.Cu")
		(net "M_F_DQS_DN<5>")
	)
	(segment
		(start 294.107616 -140.332968)
		(end 294.201088 -140.42644)
		(width 0.14224)
		(layer "In4.Cu")
		(net "M_F_DQS_DN<5>")
	)
	(segment
		(start 294.043608 -143.251174)
		(end 294.043608 -143.505174)
		(width 0.14224)
		(layer "In4.Cu")
		(net "M_F_DQS_DN<5>")
	)
	(segment
		(start 294.043608 -131.960112)
		(end 294.043608 -132.214112)
		(width 0.14224)
		(layer "In4.Cu")
		(net "M_F_DQS_DN<5>")
	)
	(segment
		(start 294.201088 -137.180828)
		(end 294.201088 -137.434828)
		(width 0.14224)
		(layer "In4.Cu")
		(net "M_F_DQS_DN<5>")
	)
	(segment
		(start 294.043608 -147.518374)
		(end 294.201088 -147.675854)
		(width 0.14224)
		(layer "In4.Cu")
		(net "M_F_DQS_DN<5>")
	)
	(segment
		(start 294.043608 -132.783072)
		(end 294.043608 -133.037072)
		(width 0.14224)
		(layer "In4.Cu")
		(net "M_F_DQS_DN<5>")
	)
	(segment
		(start 294.201088 -137.434828)
		(end 294.043608 -137.592308)
		(width 0.14224)
		(layer "In4.Cu")
		(net "M_F_DQS_DN<5>")
	)
	(segment
		(start 293.507668 -123.759468)
		(end 294.201088 -124.452888)
		(width 0.14224)
		(layer "In4.Cu")
		(net "M_F_DQS_DN<5>")
	)
	(segment
		(start 282.640024 -106.481118)
		(end 282.640024 -107.41533)
		(width 0.0889)
		(layer "In4.Cu")
		(net "M_F_DQS_DN<5>")
	)
	(segment
		(start 294.201088 -139.985496)
		(end 294.107616 -140.078968)
		(width 0.14224)
		(layer "In4.Cu")
		(net "M_F_DQS_DN<5>")
	)
	(segment
		(start 294.201088 -132.625592)
		(end 294.043608 -132.783072)
		(width 0.14224)
		(layer "In4.Cu")
		(net "M_F_DQS_DN<5>")
	)
	(segment
		(start 294.201088 -148.498814)
		(end 294.201088 -149.248876)
		(width 0.14224)
		(layer "In4.Cu")
		(net "M_F_DQS_DN<5>")
	)
	(segment
		(start 294.201088 -147.675854)
		(end 294.201088 -147.929854)
		(width 0.14224)
		(layer "In4.Cu")
		(net "M_F_DQS_DN<5>")
	)
	(segment
		(start 294.043608 -133.606032)
		(end 294.043608 -133.860032)
		(width 0.14224)
		(layer "In4.Cu")
		(net "M_F_DQS_DN<5>")
	)
	(segment
		(start 294.201088 -143.662654)
		(end 294.201088 -146.283934)
		(width 0.14224)
		(layer "In4.Cu")
		(net "M_F_DQS_DN<5>")
	)
	(segment
		(start 294.201088 -149.248876)
		(end 293.967408 -149.482556)
		(width 0.14224)
		(layer "In4.Cu")
		(net "M_F_DQS_DN<5>")
	)
	(segment
		(start 294.043608 -133.860032)
		(end 294.201088 -134.017512)
		(width 0.14224)
		(layer "In4.Cu")
		(net "M_F_DQS_DN<5>")
	)
	(segment
		(start 294.201088 -142.016734)
		(end 294.201088 -142.270734)
		(width 0.14224)
		(layer "In4.Cu")
		(net "M_F_DQS_DN<5>")
	)
	(segment
		(start 294.043608 -141.859254)
		(end 294.201088 -142.016734)
		(width 0.14224)
		(layer "In4.Cu")
		(net "M_F_DQS_DN<5>")
	)
	(segment
		(start 282.405328 -106.209592)
		(end 282.453842 -106.294428)
		(width 0.0889)
		(layer "In4.Cu")
		(net "M_F_DQS_DN<5>")
	)
	(segment
		(start 294.201088 -133.194552)
		(end 294.201088 -133.448552)
		(width 0.14224)
		(layer "In4.Cu")
		(net "M_F_DQS_DN<5>")
	)
	(segment
		(start 294.201088 -124.452888)
		(end 294.201088 -131.802632)
		(width 0.14224)
		(layer "In4.Cu")
		(net "M_F_DQS_DN<5>")
	)
	(segment
		(start 281.562302 -102.15499)
		(end 281.546554 -102.182422)
		(width 0.0889)
		(layer "In4.Cu")
		(net "M_F_DQS_DN<5>")
	)
	(segment
		(start 294.043608 -137.592308)
		(end 294.043608 -137.846308)
		(width 0.14224)
		(layer "In4.Cu")
		(net "M_F_DQS_DN<5>")
	)
	(segment
		(start 294.043608 -143.505174)
		(end 294.201088 -143.662654)
		(width 0.14224)
		(layer "In4.Cu")
		(net "M_F_DQS_DN<5>")
	)
	(segment
		(start 282.600654 -107.476798)
		(end 282.600654 -112.736122)
		(width 0.14224)
		(layer "In4.Cu")
		(net "M_F_DQS_DN<5>")
	)
	(arc
		(start 281.546554 -100.201222)
		(mid 281.476157 -100.490173)
		(end 281.555444 -100.776786)
		(width 0.0889)
		(layer "In4.Cu")
		(net "M_F_DQS_DN<5>")
	)
	(arc
		(start 281.555444 -102.757986)
		(mid 281.608882 -102.950891)
		(end 281.562302 -103.14559)
		(width 0.0889)
		(layer "In4.Cu")
		(net "M_F_DQS_DN<5>")
	)
	(arc
		(start 281.555444 -101.767386)
		(mid 281.608882 -101.960291)
		(end 281.562302 -102.15499)
		(width 0.0889)
		(layer "In4.Cu")
		(net "M_F_DQS_DN<5>")
	)
	(arc
		(start 282.07208 -105.03408)
		(mid 282.415148 -105.236303)
		(end 282.413964 -105.634536)
		(width 0.0889)
		(layer "In4.Cu")
		(net "M_F_DQS_DN<5>")
	)
	(arc
		(start 281.555444 -100.776786)
		(mid 281.608882 -100.969691)
		(end 281.562302 -101.16439)
		(width 0.0889)
		(layer "In4.Cu")
		(net "M_F_DQS_DN<5>")
	)
	(arc
		(start 281.555444 -96.814894)
		(mid 281.608943 -97.014792)
		(end 281.555444 -97.21469)
		(width 0.0889)
		(layer "In4.Cu")
		(net "M_F_DQS_DN<5>")
	)
	(arc
		(start 281.555444 -98.20529)
		(mid 281.476313 -98.500692)
		(end 281.555444 -98.796094)
		(width 0.0889)
		(layer "In4.Cu")
		(net "M_F_DQS_DN<5>")
	)
	(arc
		(start 281.555444 -97.21469)
		(mid 281.476313 -97.510092)
		(end 281.555444 -97.805494)
		(width 0.0889)
		(layer "In4.Cu")
		(net "M_F_DQS_DN<5>")
	)
	(arc
		(start 281.555444 -99.786186)
		(mid 281.608882 -99.979091)
		(end 281.562302 -100.17379)
		(width 0.0889)
		(layer "In4.Cu")
		(net "M_F_DQS_DN<5>")
	)
	(arc
		(start 281.555444 -103.748586)
		(mid 281.608882 -103.941491)
		(end 281.562302 -104.13619)
		(width 0.0889)
		(layer "In4.Cu")
		(net "M_F_DQS_DN<5>")
	)
	(arc
		(start 281.5209 -99.71659)
		(mid 281.536965 -99.751987)
		(end 281.555444 -99.786186)
		(width 0.0889)
		(layer "In4.Cu")
		(net "M_F_DQS_DN<5>")
	)
	(arc
		(start 281.555444 -97.805494)
		(mid 281.608943 -98.005392)
		(end 281.555444 -98.20529)
		(width 0.0889)
		(layer "In4.Cu")
		(net "M_F_DQS_DN<5>")
	)
	(arc
		(start 282.413964 -105.634536)
		(mid 282.334901 -105.920957)
		(end 282.405328 -106.209592)
		(width 0.0889)
		(layer "In4.Cu")
		(net "M_F_DQS_DN<5>")
	)
	(arc
		(start 281.546554 -104.163622)
		(mid 281.553559 -104.736095)
		(end 282.042362 -105.03408)
		(width 0.0889)
		(layer "In4.Cu")
		(net "M_F_DQS_DN<5>")
	)
	(arc
		(start 281.546554 -103.173022)
		(mid 281.476157 -103.461973)
		(end 281.555444 -103.748586)
		(width 0.0889)
		(layer "In4.Cu")
		(net "M_F_DQS_DN<5>")
	)
	(arc
		(start 281.555444 -98.796094)
		(mid 281.608943 -98.995992)
		(end 281.555444 -99.19589)
		(width 0.0889)
		(layer "In4.Cu")
		(net "M_F_DQS_DN<5>")
	)
	(arc
		(start 281.208734 -96.023938)
		(mid 281.360336 -96.428951)
		(end 281.555444 -96.814894)
		(width 0.0889)
		(layer "In4.Cu")
		(net "M_F_DQS_DN<5>")
	)
	(arc
		(start 281.555444 -99.19589)
		(mid 281.477505 -99.452216)
		(end 281.5209 -99.71659)
		(width 0.0889)
		(layer "In4.Cu")
		(net "M_F_DQS_DN<5>")
	)
	(arc
		(start 281.546554 -102.182422)
		(mid 281.476157 -102.471373)
		(end 281.555444 -102.757986)
		(width 0.0889)
		(layer "In4.Cu")
		(net "M_F_DQS_DN<5>")
	)
	(arc
		(start 281.562302 -103.14559)
		(mid 281.554654 -103.159436)
		(end 281.546554 -103.173022)
		(width 0.0889)
		(layer "In4.Cu")
		(net "M_F_DQS_DN<5>")
	)
	(arc
		(start 281.546554 -101.191822)
		(mid 281.476157 -101.480773)
		(end 281.555444 -101.767386)
		(width 0.0889)
		(layer "In4.Cu")
		(net "M_F_DQS_DN<5>")
	)
	(segment
		(start 293.254684 -151.104854)
		(end 293.044118 -151.31542)
		(width 0.14224)
		(layer "In11.Cu")
		(net "M_F_DQS_DN<5>")
	)
	(segment
		(start 293.614856 -149.482556)
		(end 293.254684 -149.842728)
		(width 0.14224)
		(layer "In11.Cu")
		(net "M_F_DQS_DN<5>")
	)
	(segment
		(start 293.254684 -154.442922)
		(end 293.688008 -154.876246)
		(width 0.14224)
		(layer "In11.Cu")
		(net "M_F_DQS_DN<5>")
	)
	(segment
		(start 293.254684 -153.187146)
		(end 293.254684 -154.442922)
		(width 0.14224)
		(layer "In11.Cu")
		(net "M_F_DQS_DN<5>")
	)
	(segment
		(start 293.254684 -149.842728)
		(end 293.254684 -151.104854)
		(width 0.14224)
		(layer "In11.Cu")
		(net "M_F_DQS_DN<5>")
	)
	(segment
		(start 293.688008 -149.482556)
		(end 293.614856 -149.482556)
		(width 0.14224)
		(layer "In11.Cu")
		(net "M_F_DQS_DN<5>")
	)
	(segment
		(start 293.044118 -152.97658)
		(end 293.254684 -153.187146)
		(width 0.14224)
		(layer "In11.Cu")
		(net "M_F_DQS_DN<5>")
	)
	(segment
		(start 293.044118 -151.31542)
		(end 293.044118 -152.97658)
		(width 0.14224)
		(layer "In11.Cu")
		(net "M_F_DQS_DN<5>")
	)
	(segment
		(start 283.95041 -156.87294)
		(end 283.949648 -156.87294)
		(width 0.1651)
		(layer "F.Cu")
		(net "M_F_DQS_DN<4>")
	)
	(segment
		(start 283.949648 -156.87294)
		(end 283.949648 -155.80487)
		(width 0.1651)
		(layer "F.Cu")
		(net "M_F_DQS_DN<4>")
	)
	(segment
		(start 273.769328 -94.042738)
		(end 274.340828 -94.042738)
		(width 0.1651)
		(layer "F.Cu")
		(net "M_F_DQS_DN<4>")
	)
	(segment
		(start 283.567632 -154.991054)
		(end 283.898086 -154.6606)
		(width 0.1651)
		(layer "F.Cu")
		(net "M_F_DQS_DN<4>")
	)
	(segment
		(start 283.898086 -154.6606)
		(end 284.122114 -154.6606)
		(width 0.1651)
		(layer "F.Cu")
		(net "M_F_DQS_DN<4>")
	)
	(segment
		(start 283.949648 -155.80487)
		(end 283.567632 -155.422854)
		(width 0.1651)
		(layer "F.Cu")
		(net "M_F_DQS_DN<4>")
	)
	(segment
		(start 284.122114 -154.6606)
		(end 284.33776 -154.876246)
		(width 0.1651)
		(layer "F.Cu")
		(net "M_F_DQS_DN<4>")
	)
	(segment
		(start 283.567632 -155.422854)
		(end 283.567632 -154.991054)
		(width 0.1651)
		(layer "F.Cu")
		(net "M_F_DQS_DN<4>")
	)
	(via
		(at 284.33776 -149.482556)
		(size 0.508)
		(drill 0.254)
		(layers "F.Cu" "B.Cu")
		(net "M_F_DQS_DN<4>")
	)
	(via
		(at 284.33776 -154.876246)
		(size 0.508)
		(drill 0.254)
		(layers "F.Cu" "B.Cu")
		(net "M_F_DQS_DN<4>")
	)
	(via
		(at 274.340828 -94.042738)
		(size 0.508)
		(drill 0.254)
		(layers "F.Cu" "B.Cu")
		(net "M_F_DQS_DN<4>")
	)
	(segment
		(start 283.923232 -149.7076)
		(end 283.567632 -149.352)
		(width 0.1651)
		(layer "B.Cu")
		(net "M_F_DQS_DN<4>")
	)
	(segment
		(start 283.821632 -148.767546)
		(end 283.821632 -148.513546)
		(width 0.1651)
		(layer "B.Cu")
		(net "M_F_DQS_DN<4>")
	)
	(segment
		(start 284.112716 -149.7076)
		(end 283.923232 -149.7076)
		(width 0.1651)
		(layer "B.Cu")
		(net "M_F_DQS_DN<4>")
	)
	(segment
		(start 284.33776 -149.482556)
		(end 284.112716 -149.7076)
		(width 0.1651)
		(layer "B.Cu")
		(net "M_F_DQS_DN<4>")
	)
	(segment
		(start 283.949902 -147.478496)
		(end 283.95041 -147.478496)
		(width 0.1651)
		(layer "B.Cu")
		(net "M_F_DQS_DN<4>")
	)
	(segment
		(start 283.567632 -149.352)
		(end 283.567632 -149.021546)
		(width 0.1651)
		(layer "B.Cu")
		(net "M_F_DQS_DN<4>")
	)
	(segment
		(start 283.821632 -148.513546)
		(end 283.949902 -148.385276)
		(width 0.1651)
		(layer "B.Cu")
		(net "M_F_DQS_DN<4>")
	)
	(segment
		(start 283.567632 -149.021546)
		(end 283.821632 -148.767546)
		(width 0.1651)
		(layer "B.Cu")
		(net "M_F_DQS_DN<4>")
	)
	(segment
		(start 283.949902 -148.385276)
		(end 283.949902 -147.478496)
		(width 0.1651)
		(layer "B.Cu")
		(net "M_F_DQS_DN<4>")
	)
	(segment
		(start 273.822668 -96.308418)
		(end 273.829018 -96.319086)
		(width 0.0889)
		(layer "In11.Cu")
		(net "M_F_DQS_DN<4>")
	)
	(segment
		(start 284.851094 -147.754594)
		(end 284.851094 -148.008594)
		(width 0.14224)
		(layer "In11.Cu")
		(net "M_F_DQS_DN<4>")
	)
	(segment
		(start 273.829018 -96.319086)
		(end 273.833844 -96.327722)
		(width 0.0889)
		(layer "In11.Cu")
		(net "M_F_DQS_DN<4>")
	)
	(segment
		(start 284.298644 -149.482556)
		(end 283.90469 -149.87651)
		(width 0.14224)
		(layer "In11.Cu")
		(net "M_F_DQS_DN<4>")
	)
	(segment
		(start 284.47873 -124.71273)
		(end 284.47873 -129.23393)
		(width 0.14224)
		(layer "In11.Cu")
		(net "M_F_DQS_DN<4>")
	)
	(segment
		(start 273.829018 -98.300286)
		(end 273.833844 -98.308922)
		(width 0.0889)
		(layer "In11.Cu")
		(net "M_F_DQS_DN<4>")
	)
	(segment
		(start 281.561286 -121.795286)
		(end 281.561286 -122.014234)
		(width 0.14224)
		(layer "In11.Cu")
		(net "M_F_DQS_DN<4>")
	)
	(segment
		(start 283.90469 -149.87651)
		(end 283.90469 -151.104854)
		(width 0.14224)
		(layer "In11.Cu")
		(net "M_F_DQS_DN<4>")
	)
	(segment
		(start 283.005276 -124.457206)
		(end 283.45765 -124.457206)
		(width 0.14224)
		(layer "In11.Cu")
		(net "M_F_DQS_DN<4>")
	)
	(segment
		(start 282.630626 -122.864626)
		(end 282.880562 -123.114562)
		(width 0.14224)
		(layer "In11.Cu")
		(net "M_F_DQS_DN<4>")
	)
	(segment
		(start 284.851094 -146.931634)
		(end 284.851094 -147.185634)
		(width 0.14224)
		(layer "In11.Cu")
		(net "M_F_DQS_DN<4>")
	)
	(segment
		(start 284.851094 -147.185634)
		(end 284.693614 -147.343114)
		(width 0.14224)
		(layer "In11.Cu")
		(net "M_F_DQS_DN<4>")
	)
	(segment
		(start 273.829018 -97.309686)
		(end 273.833844 -97.318322)
		(width 0.0889)
		(layer "In11.Cu")
		(net "M_F_DQS_DN<4>")
	)
	(segment
		(start 275.59762 -100.825046)
		(end 275.59762 -104.732328)
		(width 0.0889)
		(layer "In11.Cu")
		(net "M_F_DQS_DN<4>")
	)
	(segment
		(start 284.851094 -149.248876)
		(end 284.617414 -149.482556)
		(width 0.14224)
		(layer "In11.Cu")
		(net "M_F_DQS_DN<4>")
	)
	(segment
		(start 283.90469 -154.491944)
		(end 284.288992 -154.876246)
		(width 0.14224)
		(layer "In11.Cu")
		(net "M_F_DQS_DN<4>")
	)
	(segment
		(start 284.693614 -146.774154)
		(end 284.851094 -146.931634)
		(width 0.14224)
		(layer "In11.Cu")
		(net "M_F_DQS_DN<4>")
	)
	(segment
		(start 275.55825 -104.771698)
		(end 275.55825 -104.793796)
		(width 0.0889)
		(layer "In11.Cu")
		(net "M_F_DQS_DN<4>")
	)
	(segment
		(start 284.693614 -148.420074)
		(end 284.851094 -148.577554)
		(width 0.14224)
		(layer "In11.Cu")
		(net "M_F_DQS_DN<4>")
	)
	(segment
		(start 284.693614 -147.597114)
		(end 284.851094 -147.754594)
		(width 0.14224)
		(layer "In11.Cu")
		(net "M_F_DQS_DN<4>")
	)
	(segment
		(start 274.15617 -94.430088)
		(end 273.981164 -94.5642)
		(width 0.0889)
		(layer "In11.Cu")
		(net "M_F_DQS_DN<4>")
	)
	(segment
		(start 282.880562 -123.33351)
		(end 282.596844 -123.617228)
		(width 0.14224)
		(layer "In11.Cu")
		(net "M_F_DQS_DN<4>")
	)
	(segment
		(start 281.561286 -122.014234)
		(end 281.305762 -122.269758)
		(width 0.14224)
		(layer "In11.Cu")
		(net "M_F_DQS_DN<4>")
	)
	(segment
		(start 283.694124 -151.31542)
		(end 283.694124 -152.97658)
		(width 0.14224)
		(layer "In11.Cu")
		(net "M_F_DQS_DN<4>")
	)
	(segment
		(start 281.305762 -122.269758)
		(end 281.305762 -122.711718)
		(width 0.14224)
		(layer "In11.Cu")
		(net "M_F_DQS_DN<4>")
	)
	(segment
		(start 283.45765 -124.457206)
		(end 283.730954 -124.183902)
		(width 0.14224)
		(layer "In11.Cu")
		(net "M_F_DQS_DN<4>")
	)
	(segment
		(start 273.829018 -95.328486)
		(end 273.833844 -95.337122)
		(width 0.0889)
		(layer "In11.Cu")
		(net "M_F_DQS_DN<4>")
	)
	(segment
		(start 274.863306 -100.090732)
		(end 275.59762 -100.825046)
		(width 0.0889)
		(layer "In11.Cu")
		(net "M_F_DQS_DN<4>")
	)
	(segment
		(start 281.305762 -122.711718)
		(end 281.714194 -123.12015)
		(width 0.14224)
		(layer "In11.Cu")
		(net "M_F_DQS_DN<4>")
	)
	(segment
		(start 284.33776 -149.482556)
		(end 284.298644 -149.482556)
		(width 0.14224)
		(layer "In11.Cu")
		(net "M_F_DQS_DN<4>")
	)
	(segment
		(start 275.59762 -104.732328)
		(end 275.55825 -104.771698)
		(width 0.0889)
		(layer "In11.Cu")
		(net "M_F_DQS_DN<4>")
	)
	(segment
		(start 275.55825 -104.793796)
		(end 275.55825 -115.79225)
		(width 0.14224)
		(layer "In11.Cu")
		(net "M_F_DQS_DN<4>")
	)
	(segment
		(start 282.596844 -124.048774)
		(end 283.005276 -124.457206)
		(width 0.14224)
		(layer "In11.Cu")
		(net "M_F_DQS_DN<4>")
	)
	(segment
		(start 273.822668 -97.299018)
		(end 273.829018 -97.309686)
		(width 0.0889)
		(layer "In11.Cu")
		(net "M_F_DQS_DN<4>")
	)
	(segment
		(start 281.714194 -123.12015)
		(end 282.156154 -123.12015)
		(width 0.14224)
		(layer "In11.Cu")
		(net "M_F_DQS_DN<4>")
	)
	(segment
		(start 283.694124 -152.97658)
		(end 283.90469 -153.187146)
		(width 0.14224)
		(layer "In11.Cu")
		(net "M_F_DQS_DN<4>")
	)
	(segment
		(start 273.822668 -98.289618)
		(end 273.829018 -98.300286)
		(width 0.0889)
		(layer "In11.Cu")
		(net "M_F_DQS_DN<4>")
	)
	(segment
		(start 284.47873 -129.23393)
		(end 284.851094 -129.606294)
		(width 0.14224)
		(layer "In11.Cu")
		(net "M_F_DQS_DN<4>")
	)
	(segment
		(start 274.323048 -99.586288)
		(end 274.355814 -99.586288)
		(width 0.0889)
		(layer "In11.Cu")
		(net "M_F_DQS_DN<4>")
	)
	(segment
		(start 284.693614 -148.166074)
		(end 284.693614 -148.420074)
		(width 0.14224)
		(layer "In11.Cu")
		(net "M_F_DQS_DN<4>")
	)
	(segment
		(start 283.90469 -151.104854)
		(end 283.694124 -151.31542)
		(width 0.14224)
		(layer "In11.Cu")
		(net "M_F_DQS_DN<4>")
	)
	(segment
		(start 282.880562 -123.114562)
		(end 282.880562 -123.33351)
		(width 0.14224)
		(layer "In11.Cu")
		(net "M_F_DQS_DN<4>")
	)
	(segment
		(start 284.617414 -149.482556)
		(end 284.33776 -149.482556)
		(width 0.14224)
		(layer "In11.Cu")
		(net "M_F_DQS_DN<4>")
	)
	(segment
		(start 282.156154 -123.12015)
		(end 282.411678 -122.864626)
		(width 0.14224)
		(layer "In11.Cu")
		(net "M_F_DQS_DN<4>")
	)
	(segment
		(start 282.411678 -122.864626)
		(end 282.630626 -122.864626)
		(width 0.14224)
		(layer "In11.Cu")
		(net "M_F_DQS_DN<4>")
	)
	(segment
		(start 284.851094 -148.008594)
		(end 284.693614 -148.166074)
		(width 0.14224)
		(layer "In11.Cu")
		(net "M_F_DQS_DN<4>")
	)
	(segment
		(start 284.693614 -147.343114)
		(end 284.693614 -147.597114)
		(width 0.14224)
		(layer "In11.Cu")
		(net "M_F_DQS_DN<4>")
	)
	(segment
		(start 283.90469 -153.187146)
		(end 283.90469 -154.491944)
		(width 0.14224)
		(layer "In11.Cu")
		(net "M_F_DQS_DN<4>")
	)
	(segment
		(start 284.693614 -146.520154)
		(end 284.693614 -146.774154)
		(width 0.14224)
		(layer "In11.Cu")
		(net "M_F_DQS_DN<4>")
	)
	(segment
		(start 284.851094 -148.577554)
		(end 284.851094 -149.248876)
		(width 0.14224)
		(layer "In11.Cu")
		(net "M_F_DQS_DN<4>")
	)
	(segment
		(start 284.288992 -154.876246)
		(end 284.33776 -154.876246)
		(width 0.14224)
		(layer "In11.Cu")
		(net "M_F_DQS_DN<4>")
	)
	(segment
		(start 282.596844 -123.617228)
		(end 282.596844 -124.048774)
		(width 0.14224)
		(layer "In11.Cu")
		(net "M_F_DQS_DN<4>")
	)
	(segment
		(start 284.851094 -129.606294)
		(end 284.851094 -146.362674)
		(width 0.14224)
		(layer "In11.Cu")
		(net "M_F_DQS_DN<4>")
	)
	(segment
		(start 284.851094 -146.362674)
		(end 284.693614 -146.520154)
		(width 0.14224)
		(layer "In11.Cu")
		(net "M_F_DQS_DN<4>")
	)
	(segment
		(start 283.949902 -124.183902)
		(end 284.47873 -124.71273)
		(width 0.14224)
		(layer "In11.Cu")
		(net "M_F_DQS_DN<4>")
	)
	(segment
		(start 275.55825 -115.79225)
		(end 281.561286 -121.795286)
		(width 0.14224)
		(layer "In11.Cu")
		(net "M_F_DQS_DN<4>")
	)
	(segment
		(start 274.687538 -99.786186)
		(end 274.863306 -100.090732)
		(width 0.0889)
		(layer "In11.Cu")
		(net "M_F_DQS_DN<4>")
	)
	(segment
		(start 283.730954 -124.183902)
		(end 283.949902 -124.183902)
		(width 0.14224)
		(layer "In11.Cu")
		(net "M_F_DQS_DN<4>")
	)
	(arc
		(start 273.829018 -95.728536)
		(mid 273.749796 -96.017654)
		(end 273.822668 -96.308418)
		(width 0.0889)
		(layer "In11.Cu")
		(net "M_F_DQS_DN<4>")
	)
	(arc
		(start 274.355814 -99.586288)
		(mid 274.547456 -99.643454)
		(end 274.687538 -99.786186)
		(width 0.0889)
		(layer "In11.Cu")
		(net "M_F_DQS_DN<4>")
	)
	(arc
		(start 273.829018 -96.719136)
		(mid 273.749796 -97.008254)
		(end 273.822668 -97.299018)
		(width 0.0889)
		(layer "In11.Cu")
		(net "M_F_DQS_DN<4>")
	)
	(arc
		(start 273.833844 -98.308922)
		(mid 273.882599 -98.505274)
		(end 273.829018 -98.700336)
		(width 0.0889)
		(layer "In11.Cu")
		(net "M_F_DQS_DN<4>")
	)
	(arc
		(start 273.833844 -97.318322)
		(mid 273.882599 -97.514674)
		(end 273.829018 -97.709736)
		(width 0.0889)
		(layer "In11.Cu")
		(net "M_F_DQS_DN<4>")
	)
	(arc
		(start 273.981164 -94.5642)
		(mid 273.76126 -94.91771)
		(end 273.829018 -95.328486)
		(width 0.0889)
		(layer "In11.Cu")
		(net "M_F_DQS_DN<4>")
	)
	(arc
		(start 274.340828 -94.042738)
		(mid 274.292303 -94.257296)
		(end 274.15617 -94.430088)
		(width 0.0889)
		(layer "In11.Cu")
		(net "M_F_DQS_DN<4>")
	)
	(arc
		(start 273.833844 -95.337122)
		(mid 273.882599 -95.533474)
		(end 273.829018 -95.728536)
		(width 0.0889)
		(layer "In11.Cu")
		(net "M_F_DQS_DN<4>")
	)
	(arc
		(start 273.829018 -97.709736)
		(mid 273.749796 -97.998854)
		(end 273.822668 -98.289618)
		(width 0.0889)
		(layer "In11.Cu")
		(net "M_F_DQS_DN<4>")
	)
	(arc
		(start 273.829018 -98.700336)
		(mid 273.824689 -99.283508)
		(end 274.323048 -99.586288)
		(width 0.0889)
		(layer "In11.Cu")
		(net "M_F_DQS_DN<4>")
	)
	(arc
		(start 273.833844 -96.327722)
		(mid 273.882599 -96.524074)
		(end 273.829018 -96.719136)
		(width 0.0889)
		(layer "In11.Cu")
		(net "M_F_DQS_DN<4>")
	)
	(segment
		(start 228.317806 -155.422854)
		(end 228.317806 -154.991054)
		(width 0.1651)
		(layer "F.Cu")
		(net "M_F_DQS_DN<3>")
	)
	(segment
		(start 228.64826 -154.6606)
		(end 228.872288 -154.6606)
		(width 0.1651)
		(layer "F.Cu")
		(net "M_F_DQS_DN<3>")
	)
	(segment
		(start 228.699822 -155.80487)
		(end 228.317806 -155.422854)
		(width 0.1651)
		(layer "F.Cu")
		(net "M_F_DQS_DN<3>")
	)
	(segment
		(start 228.317806 -154.991054)
		(end 228.64826 -154.6606)
		(width 0.1651)
		(layer "F.Cu")
		(net "M_F_DQS_DN<3>")
	)
	(segment
		(start 228.70033 -156.87294)
		(end 228.699822 -156.87294)
		(width 0.1651)
		(layer "F.Cu")
		(net "M_F_DQS_DN<3>")
	)
	(segment
		(start 250.778264 -87.784686)
		(end 250.206764 -87.784686)
		(width 0.1651)
		(layer "F.Cu")
		(net "M_F_DQS_DN<3>")
	)
	(segment
		(start 228.699822 -156.87294)
		(end 228.699822 -155.80487)
		(width 0.1651)
		(layer "F.Cu")
		(net "M_F_DQS_DN<3>")
	)
	(segment
		(start 228.872288 -154.6606)
		(end 229.087934 -154.876246)
		(width 0.1651)
		(layer "F.Cu")
		(net "M_F_DQS_DN<3>")
	)
	(via
		(at 229.087934 -149.482556)
		(size 0.508)
		(drill 0.254)
		(layers "F.Cu" "B.Cu")
		(net "M_F_DQS_DN<3>")
	)
	(via
		(at 250.206764 -87.784686)
		(size 0.508)
		(drill 0.254)
		(layers "F.Cu" "B.Cu")
		(net "M_F_DQS_DN<3>")
	)
	(via
		(at 229.087934 -154.876246)
		(size 0.508)
		(drill 0.254)
		(layers "F.Cu" "B.Cu")
		(net "M_F_DQS_DN<3>")
	)
	(segment
		(start 228.571806 -148.767546)
		(end 228.571806 -148.513546)
		(width 0.1651)
		(layer "B.Cu")
		(net "M_F_DQS_DN<3>")
	)
	(segment
		(start 228.571806 -148.513546)
		(end 228.699822 -148.38553)
		(width 0.1651)
		(layer "B.Cu")
		(net "M_F_DQS_DN<3>")
	)
	(segment
		(start 229.087934 -149.482556)
		(end 228.86289 -149.7076)
		(width 0.1651)
		(layer "B.Cu")
		(net "M_F_DQS_DN<3>")
	)
	(segment
		(start 228.699822 -148.38553)
		(end 228.699822 -147.478496)
		(width 0.1651)
		(layer "B.Cu")
		(net "M_F_DQS_DN<3>")
	)
	(segment
		(start 228.86289 -149.7076)
		(end 228.673406 -149.7076)
		(width 0.1651)
		(layer "B.Cu")
		(net "M_F_DQS_DN<3>")
	)
	(segment
		(start 228.317806 -149.352)
		(end 228.317806 -149.021546)
		(width 0.1651)
		(layer "B.Cu")
		(net "M_F_DQS_DN<3>")
	)
	(segment
		(start 228.699822 -147.478496)
		(end 228.70033 -147.478496)
		(width 0.1651)
		(layer "B.Cu")
		(net "M_F_DQS_DN<3>")
	)
	(segment
		(start 228.673406 -149.7076)
		(end 228.317806 -149.352)
		(width 0.1651)
		(layer "B.Cu")
		(net "M_F_DQS_DN<3>")
	)
	(segment
		(start 228.317806 -149.021546)
		(end 228.571806 -148.767546)
		(width 0.1651)
		(layer "B.Cu")
		(net "M_F_DQS_DN<3>")
	)
	(segment
		(start 229.443534 -142.708122)
		(end 229.601014 -142.865602)
		(width 0.14224)
		(layer "In11.Cu")
		(net "M_F_DQS_DN<3>")
	)
	(segment
		(start 229.601014 -133.540246)
		(end 229.443534 -133.697726)
		(width 0.14224)
		(layer "In11.Cu")
		(net "M_F_DQS_DN<3>")
	)
	(segment
		(start 229.601014 -137.231628)
		(end 229.601014 -137.485628)
		(width 0.14224)
		(layer "In11.Cu")
		(net "M_F_DQS_DN<3>")
	)
	(segment
		(start 228.444044 -151.31542)
		(end 228.444044 -152.97658)
		(width 0.14224)
		(layer "In11.Cu")
		(net "M_F_DQS_DN<3>")
	)
	(segment
		(start 238.72571 -118.698518)
		(end 238.86795 -118.840758)
		(width 0.14224)
		(layer "In11.Cu")
		(net "M_F_DQS_DN<3>")
	)
	(segment
		(start 250.547124 -91.53652)
		(end 250.553474 -91.547188)
		(width 0.0889)
		(layer "In11.Cu")
		(net "M_F_DQS_DN<3>")
	)
	(segment
		(start 239.18799 -117.699282)
		(end 238.72571 -118.161562)
		(width 0.14224)
		(layer "In11.Cu")
		(net "M_F_DQS_DN<3>")
	)
	(segment
		(start 229.601014 -132.717286)
		(end 229.443534 -132.874766)
		(width 0.14224)
		(layer "In11.Cu")
		(net "M_F_DQS_DN<3>")
	)
	(segment
		(start 237.941866 -119.45874)
		(end 237.108492 -120.292114)
		(width 0.14224)
		(layer "In11.Cu")
		(net "M_F_DQS_DN<3>")
	)
	(segment
		(start 245.873524 -100.92182)
		(end 245.873524 -102.451408)
		(width 0.0889)
		(layer "In11.Cu")
		(net "M_F_DQS_DN<3>")
	)
	(segment
		(start 229.601014 -129.294636)
		(end 229.601014 -131.951222)
		(width 0.14224)
		(layer "In11.Cu")
		(net "M_F_DQS_DN<3>")
	)
	(segment
		(start 246.121682 -103.650542)
		(end 246.121682 -103.67264)
		(width 0.0889)
		(layer "In11.Cu")
		(net "M_F_DQS_DN<3>")
	)
	(segment
		(start 229.601014 -138.877548)
		(end 229.601014 -141.473682)
		(width 0.14224)
		(layer "In11.Cu")
		(net "M_F_DQS_DN<3>")
	)
	(segment
		(start 250.22175 -93.137736)
		(end 250.19381 -93.137736)
		(width 0.0889)
		(layer "In11.Cu")
		(net "M_F_DQS_DN<3>")
	)
	(segment
		(start 229.443534 -147.293584)
		(end 229.443534 -147.547584)
		(width 0.14224)
		(layer "In11.Cu")
		(net "M_F_DQS_DN<3>")
	)
	(segment
		(start 229.601014 -148.528024)
		(end 229.601014 -149.24913)
		(width 0.14224)
		(layer "In11.Cu")
		(net "M_F_DQS_DN<3>")
	)
	(segment
		(start 249.688604 -94.01302)
		(end 249.694954 -94.023688)
		(width 0.0889)
		(layer "In11.Cu")
		(net "M_F_DQS_DN<3>")
	)
	(segment
		(start 242.270788 -109.1565)
		(end 242.27028 -109.1565)
		(width 0.14224)
		(layer "In11.Cu")
		(net "M_F_DQS_DN<3>")
	)
	(segment
		(start 229.601014 -149.24913)
		(end 229.367588 -149.482556)
		(width 0.14224)
		(layer "In11.Cu")
		(net "M_F_DQS_DN<3>")
	)
	(segment
		(start 229.443534 -148.116544)
		(end 229.443534 -148.370544)
		(width 0.14224)
		(layer "In11.Cu")
		(net "M_F_DQS_DN<3>")
	)
	(segment
		(start 229.49662 -129.190242)
		(end 229.601014 -129.294636)
		(width 0.14224)
		(layer "In11.Cu")
		(net "M_F_DQS_DN<3>")
	)
	(segment
		(start 229.601014 -143.119602)
		(end 229.443534 -143.277082)
		(width 0.14224)
		(layer "In11.Cu")
		(net "M_F_DQS_DN<3>")
	)
	(segment
		(start 246.161052 -103.611172)
		(end 246.121682 -103.650542)
		(width 0.0889)
		(layer "In11.Cu")
		(net "M_F_DQS_DN<3>")
	)
	(segment
		(start 240.485168 -117.22354)
		(end 240.485168 -117.534944)
		(width 0.14224)
		(layer "In11.Cu")
		(net "M_F_DQS_DN<3>")
	)
	(segment
		(start 248.616724 -97.52965)
		(end 248.616724 -98.17862)
		(width 0.0889)
		(layer "In11.Cu")
		(net "M_F_DQS_DN<3>")
	)
	(segment
		(start 229.443534 -143.277082)
		(end 229.443534 -143.531082)
		(width 0.14224)
		(layer "In11.Cu")
		(net "M_F_DQS_DN<3>")
	)
	(segment
		(start 229.443534 -133.951726)
		(end 229.601014 -134.109206)
		(width 0.14224)
		(layer "In11.Cu")
		(net "M_F_DQS_DN<3>")
	)
	(segment
		(start 250.554998 -88.578436)
		(end 250.5583 -88.584024)
		(width 0.0889)
		(layer "In11.Cu")
		(net "M_F_DQS_DN<3>")
	)
	(segment
		(start 228.654864 -154.443176)
		(end 229.087934 -154.876246)
		(width 0.14224)
		(layer "In11.Cu")
		(net "M_F_DQS_DN<3>")
	)
	(segment
		(start 229.443534 -137.897108)
		(end 229.601014 -138.054588)
		(width 0.14224)
		(layer "In11.Cu")
		(net "M_F_DQS_DN<3>")
	)
	(segment
		(start 228.654864 -151.1046)
		(end 228.444044 -151.31542)
		(width 0.14224)
		(layer "In11.Cu")
		(net "M_F_DQS_DN<3>")
	)
	(segment
		(start 250.553474 -90.556588)
		(end 250.5583 -90.565224)
		(width 0.0889)
		(layer "In11.Cu")
		(net "M_F_DQS_DN<3>")
	)
	(segment
		(start 229.601014 -141.473682)
		(end 229.443534 -141.631162)
		(width 0.14224)
		(layer "In11.Cu")
		(net "M_F_DQS_DN<3>")
	)
	(segment
		(start 229.443534 -132.874766)
		(end 229.443534 -133.128766)
		(width 0.14224)
		(layer "In11.Cu")
		(net "M_F_DQS_DN<3>")
	)
	(segment
		(start 250.55449 -88.577674)
		(end 250.554998 -88.578436)
		(width 0.0889)
		(layer "In11.Cu")
		(net "M_F_DQS_DN<3>")
	)
	(segment
		(start 229.601014 -143.688562)
		(end 229.601014 -146.313144)
		(width 0.14224)
		(layer "In11.Cu")
		(net "M_F_DQS_DN<3>")
	)
	(segment
		(start 237.108492 -120.770396)
		(end 236.639608 -121.23928)
		(width 0.14224)
		(layer "In11.Cu")
		(net "M_F_DQS_DN<3>")
	)
	(segment
		(start 242.27028 -114.616992)
		(end 240.342928 -116.544344)
		(width 0.14224)
		(layer "In11.Cu")
		(net "M_F_DQS_DN<3>")
	)
	(segment
		(start 249.631708 -96.514666)
		(end 248.616724 -97.52965)
		(width 0.0889)
		(layer "In11.Cu")
		(net "M_F_DQS_DN<3>")
	)
	(segment
		(start 229.443534 -138.466068)
		(end 229.443534 -138.720068)
		(width 0.14224)
		(layer "In11.Cu")
		(net "M_F_DQS_DN<3>")
	)
	(segment
		(start 229.601014 -142.865602)
		(end 229.601014 -143.119602)
		(width 0.14224)
		(layer "In11.Cu")
		(net "M_F_DQS_DN<3>")
	)
	(segment
		(start 229.443534 -147.547584)
		(end 229.601014 -147.705064)
		(width 0.14224)
		(layer "In11.Cu")
		(net "M_F_DQS_DN<3>")
	)
	(segment
		(start 240.17859 -117.841522)
		(end 239.867186 -117.841522)
		(width 0.14224)
		(layer "In11.Cu")
		(net "M_F_DQS_DN<3>")
	)
	(segment
		(start 229.443534 -138.720068)
		(end 229.601014 -138.877548)
		(width 0.14224)
		(layer "In11.Cu")
		(net "M_F_DQS_DN<3>")
	)
	(segment
		(start 238.86795 -119.152924)
		(end 238.562134 -119.45874)
		(width 0.14224)
		(layer "In11.Cu")
		(net "M_F_DQS_DN<3>")
	)
	(segment
		(start 229.601014 -147.705064)
		(end 229.601014 -147.959064)
		(width 0.14224)
		(layer "In11.Cu")
		(net "M_F_DQS_DN<3>")
	)
	(segment
		(start 239.724946 -117.699282)
		(end 239.18799 -117.699282)
		(width 0.14224)
		(layer "In11.Cu")
		(net "M_F_DQS_DN<3>")
	)
	(segment
		(start 229.443534 -136.820148)
		(end 229.443534 -137.074148)
		(width 0.14224)
		(layer "In11.Cu")
		(net "M_F_DQS_DN<3>")
	)
	(segment
		(start 246.121682 -103.67264)
		(end 246.121682 -105.305606)
		(width 0.14224)
		(layer "In11.Cu")
		(net "M_F_DQS_DN<3>")
	)
	(segment
		(start 250.553474 -91.547188)
		(end 250.5583 -91.555824)
		(width 0.0889)
		(layer "In11.Cu")
		(net "M_F_DQS_DN<3>")
	)
	(segment
		(start 236.639608 -121.23928)
		(end 232.386886 -121.23928)
		(width 0.14224)
		(layer "In11.Cu")
		(net "M_F_DQS_DN<3>")
	)
	(segment
		(start 229.443534 -148.370544)
		(end 229.601014 -148.528024)
		(width 0.14224)
		(layer "In11.Cu")
		(net "M_F_DQS_DN<3>")
	)
	(segment
		(start 238.86795 -118.840758)
		(end 238.86795 -119.152924)
		(width 0.14224)
		(layer "In11.Cu")
		(net "M_F_DQS_DN<3>")
	)
	(segment
		(start 229.601014 -147.959064)
		(end 229.443534 -148.116544)
		(width 0.14224)
		(layer "In11.Cu")
		(net "M_F_DQS_DN<3>")
	)
	(segment
		(start 229.443534 -133.128766)
		(end 229.601014 -133.286246)
		(width 0.14224)
		(layer "In11.Cu")
		(net "M_F_DQS_DN<3>")
	)
	(segment
		(start 249.694954 -95.414338)
		(end 249.688604 -95.425006)
		(width 0.0889)
		(layer "In11.Cu")
		(net "M_F_DQS_DN<3>")
	)
	(segment
		(start 229.443534 -143.531082)
		(end 229.601014 -143.688562)
		(width 0.14224)
		(layer "In11.Cu")
		(net "M_F_DQS_DN<3>")
	)
	(segment
		(start 229.601014 -128.831848)
		(end 229.49662 -128.936242)
		(width 0.14224)
		(layer "In11.Cu")
		(net "M_F_DQS_DN<3>")
	)
	(segment
		(start 228.444044 -152.97658)
		(end 228.654864 -153.1874)
		(width 0.14224)
		(layer "In11.Cu")
		(net "M_F_DQS_DN<3>")
	)
	(segment
		(start 248.616724 -98.17862)
		(end 245.873524 -100.92182)
		(width 0.0889)
		(layer "In11.Cu")
		(net "M_F_DQS_DN<3>")
	)
	(segment
		(start 229.443534 -141.885162)
		(end 229.601014 -142.042642)
		(width 0.14224)
		(layer "In11.Cu")
		(net "M_F_DQS_DN<3>")
	)
	(segment
		(start 250.553474 -92.537788)
		(end 250.5583 -92.546424)
		(width 0.0889)
		(layer "In11.Cu")
		(net "M_F_DQS_DN<3>")
	)
	(segment
		(start 229.601014 -138.308588)
		(end 229.443534 -138.466068)
		(width 0.14224)
		(layer "In11.Cu")
		(net "M_F_DQS_DN<3>")
	)
	(segment
		(start 250.553474 -89.565988)
		(end 250.5583 -89.574624)
		(width 0.0889)
		(layer "In11.Cu")
		(net "M_F_DQS_DN<3>")
	)
	(segment
		(start 229.601014 -136.662668)
		(end 229.443534 -136.820148)
		(width 0.14224)
		(layer "In11.Cu")
		(net "M_F_DQS_DN<3>")
	)
	(segment
		(start 229.443534 -137.074148)
		(end 229.601014 -137.231628)
		(width 0.14224)
		(layer "In11.Cu")
		(net "M_F_DQS_DN<3>")
	)
	(segment
		(start 237.108492 -120.292114)
		(end 237.108492 -120.770396)
		(width 0.14224)
		(layer "In11.Cu")
		(net "M_F_DQS_DN<3>")
	)
	(segment
		(start 229.601014 -146.313144)
		(end 229.443534 -146.470624)
		(width 0.14224)
		(layer "In11.Cu")
		(net "M_F_DQS_DN<3>")
	)
	(segment
		(start 229.475538 -132.076698)
		(end 229.475538 -132.330698)
		(width 0.14224)
		(layer "In11.Cu")
		(net "M_F_DQS_DN<3>")
	)
	(segment
		(start 229.601014 -147.136104)
		(end 229.443534 -147.293584)
		(width 0.14224)
		(layer "In11.Cu")
		(net "M_F_DQS_DN<3>")
	)
	(segment
		(start 229.601014 -133.286246)
		(end 229.601014 -133.540246)
		(width 0.14224)
		(layer "In11.Cu")
		(net "M_F_DQS_DN<3>")
	)
	(segment
		(start 229.601014 -132.456174)
		(end 229.601014 -132.717286)
		(width 0.14224)
		(layer "In11.Cu")
		(net "M_F_DQS_DN<3>")
	)
	(segment
		(start 229.601014 -138.054588)
		(end 229.601014 -138.308588)
		(width 0.14224)
		(layer "In11.Cu")
		(net "M_F_DQS_DN<3>")
	)
	(segment
		(start 229.601014 -146.882104)
		(end 229.601014 -147.136104)
		(width 0.14224)
		(layer "In11.Cu")
		(net "M_F_DQS_DN<3>")
	)
	(segment
		(start 250.553474 -88.575896)
		(end 250.55449 -88.577674)
		(width 0.0889)
		(layer "In11.Cu")
		(net "M_F_DQS_DN<3>")
	)
	(segment
		(start 229.475538 -132.330698)
		(end 229.601014 -132.456174)
		(width 0.14224)
		(layer "In11.Cu")
		(net "M_F_DQS_DN<3>")
	)
	(segment
		(start 240.342928 -116.544344)
		(end 240.342928 -117.0813)
		(width 0.14224)
		(layer "In11.Cu")
		(net "M_F_DQS_DN<3>")
	)
	(segment
		(start 250.547124 -89.55532)
		(end 250.553474 -89.565988)
		(width 0.0889)
		(layer "In11.Cu")
		(net "M_F_DQS_DN<3>")
	)
	(segment
		(start 229.367588 -149.482556)
		(end 229.087934 -149.482556)
		(width 0.14224)
		(layer "In11.Cu")
		(net "M_F_DQS_DN<3>")
	)
	(segment
		(start 238.562134 -119.45874)
		(end 237.941866 -119.45874)
		(width 0.14224)
		(layer "In11.Cu")
		(net "M_F_DQS_DN<3>")
	)
	(segment
		(start 232.386886 -121.23928)
		(end 229.601014 -124.025152)
		(width 0.14224)
		(layer "In11.Cu")
		(net "M_F_DQS_DN<3>")
	)
	(segment
		(start 246.121682 -105.305606)
		(end 242.270788 -109.1565)
		(width 0.14224)
		(layer "In11.Cu")
		(net "M_F_DQS_DN<3>")
	)
	(segment
		(start 229.443534 -133.697726)
		(end 229.443534 -133.951726)
		(width 0.14224)
		(layer "In11.Cu")
		(net "M_F_DQS_DN<3>")
	)
	(segment
		(start 229.601014 -142.296642)
		(end 229.443534 -142.454122)
		(width 0.14224)
		(layer "In11.Cu")
		(net "M_F_DQS_DN<3>")
	)
	(segment
		(start 240.485168 -117.534944)
		(end 240.17859 -117.841522)
		(width 0.14224)
		(layer "In11.Cu")
		(net "M_F_DQS_DN<3>")
	)
	(segment
		(start 229.443534 -146.724624)
		(end 229.601014 -146.882104)
		(width 0.14224)
		(layer "In11.Cu")
		(net "M_F_DQS_DN<3>")
	)
	(segment
		(start 240.342928 -117.0813)
		(end 240.485168 -117.22354)
		(width 0.14224)
		(layer "In11.Cu")
		(net "M_F_DQS_DN<3>")
	)
	(segment
		(start 228.654864 -153.1874)
		(end 228.654864 -154.443176)
		(width 0.14224)
		(layer "In11.Cu")
		(net "M_F_DQS_DN<3>")
	)
	(segment
		(start 229.087934 -149.482556)
		(end 229.014782 -149.482556)
		(width 0.14224)
		(layer "In11.Cu")
		(net "M_F_DQS_DN<3>")
	)
	(segment
		(start 239.867186 -117.841522)
		(end 239.724946 -117.699282)
		(width 0.14224)
		(layer "In11.Cu")
		(net "M_F_DQS_DN<3>")
	)
	(segment
		(start 245.873524 -102.451408)
		(end 246.161052 -102.738936)
		(width 0.0889)
		(layer "In11.Cu")
		(net "M_F_DQS_DN<3>")
	)
	(segment
		(start 229.601014 -124.025152)
		(end 229.601014 -128.831848)
		(width 0.14224)
		(layer "In11.Cu")
		(net "M_F_DQS_DN<3>")
	)
	(segment
		(start 246.161052 -102.738936)
		(end 246.161052 -103.611172)
		(width 0.0889)
		(layer "In11.Cu")
		(net "M_F_DQS_DN<3>")
	)
	(segment
		(start 250.547124 -92.52712)
		(end 250.553474 -92.537788)
		(width 0.0889)
		(layer "In11.Cu")
		(net "M_F_DQS_DN<3>")
	)
	(segment
		(start 229.601014 -134.109206)
		(end 229.601014 -136.662668)
		(width 0.14224)
		(layer "In11.Cu")
		(net "M_F_DQS_DN<3>")
	)
	(segment
		(start 249.69978 -96.396302)
		(end 249.631708 -96.514666)
		(width 0.0889)
		(layer "In11.Cu")
		(net "M_F_DQS_DN<3>")
	)
	(segment
		(start 229.014782 -149.482556)
		(end 228.654864 -149.842474)
		(width 0.14224)
		(layer "In11.Cu")
		(net "M_F_DQS_DN<3>")
	)
	(segment
		(start 229.443534 -141.631162)
		(end 229.443534 -141.885162)
		(width 0.14224)
		(layer "In11.Cu")
		(net "M_F_DQS_DN<3>")
	)
	(segment
		(start 229.443534 -146.470624)
		(end 229.443534 -146.724624)
		(width 0.14224)
		(layer "In11.Cu")
		(net "M_F_DQS_DN<3>")
	)
	(segment
		(start 238.72571 -118.161562)
		(end 238.72571 -118.698518)
		(width 0.14224)
		(layer "In11.Cu")
		(net "M_F_DQS_DN<3>")
	)
	(segment
		(start 242.27028 -109.1565)
		(end 242.27028 -114.616992)
		(width 0.14224)
		(layer "In11.Cu")
		(net "M_F_DQS_DN<3>")
	)
	(segment
		(start 229.601014 -142.042642)
		(end 229.601014 -142.296642)
		(width 0.14224)
		(layer "In11.Cu")
		(net "M_F_DQS_DN<3>")
	)
	(segment
		(start 229.601014 -137.485628)
		(end 229.443534 -137.643108)
		(width 0.14224)
		(layer "In11.Cu")
		(net "M_F_DQS_DN<3>")
	)
	(segment
		(start 229.49662 -128.936242)
		(end 229.49662 -129.190242)
		(width 0.14224)
		(layer "In11.Cu")
		(net "M_F_DQS_DN<3>")
	)
	(segment
		(start 229.443534 -137.643108)
		(end 229.443534 -137.897108)
		(width 0.14224)
		(layer "In11.Cu")
		(net "M_F_DQS_DN<3>")
	)
	(segment
		(start 249.69978 -95.405702)
		(end 249.694954 -95.414338)
		(width 0.0889)
		(layer "In11.Cu")
		(net "M_F_DQS_DN<3>")
	)
	(segment
		(start 228.654864 -149.842474)
		(end 228.654864 -151.1046)
		(width 0.14224)
		(layer "In11.Cu")
		(net "M_F_DQS_DN<3>")
	)
	(segment
		(start 229.601014 -131.951222)
		(end 229.475538 -132.076698)
		(width 0.14224)
		(layer "In11.Cu")
		(net "M_F_DQS_DN<3>")
	)
	(segment
		(start 229.443534 -142.454122)
		(end 229.443534 -142.708122)
		(width 0.14224)
		(layer "In11.Cu")
		(net "M_F_DQS_DN<3>")
	)
	(segment
		(start 250.547124 -90.54592)
		(end 250.553474 -90.556588)
		(width 0.0889)
		(layer "In11.Cu")
		(net "M_F_DQS_DN<3>")
	)
	(arc
		(start 250.5583 -90.565224)
		(mid 250.607055 -90.761576)
		(end 250.553474 -90.956638)
		(width 0.0889)
		(layer "In11.Cu")
		(net "M_F_DQS_DN<3>")
	)
	(arc
		(start 250.5583 -91.555824)
		(mid 250.607055 -91.752176)
		(end 250.553474 -91.947238)
		(width 0.0889)
		(layer "In11.Cu")
		(net "M_F_DQS_DN<3>")
	)
	(arc
		(start 249.694954 -94.023688)
		(mid 249.748453 -94.223586)
		(end 249.694954 -94.423484)
		(width 0.0889)
		(layer "In11.Cu")
		(net "M_F_DQS_DN<3>")
	)
	(arc
		(start 249.688604 -95.425006)
		(mid 249.615806 -95.715769)
		(end 249.694954 -96.004888)
		(width 0.0889)
		(layer "In11.Cu")
		(net "M_F_DQS_DN<3>")
	)
	(arc
		(start 250.5583 -88.584024)
		(mid 250.607055 -88.780376)
		(end 250.553474 -88.975438)
		(width 0.0889)
		(layer "In11.Cu")
		(net "M_F_DQS_DN<3>")
	)
	(arc
		(start 250.553474 -91.947238)
		(mid 250.474252 -92.236356)
		(end 250.547124 -92.52712)
		(width 0.0889)
		(layer "In11.Cu")
		(net "M_F_DQS_DN<3>")
	)
	(arc
		(start 250.5583 -92.546424)
		(mid 250.554553 -92.93568)
		(end 250.22175 -93.137736)
		(width 0.0889)
		(layer "In11.Cu")
		(net "M_F_DQS_DN<3>")
	)
	(arc
		(start 249.694954 -96.004888)
		(mid 249.748424 -96.199951)
		(end 249.69978 -96.396302)
		(width 0.0889)
		(layer "In11.Cu")
		(net "M_F_DQS_DN<3>")
	)
	(arc
		(start 249.694954 -95.014288)
		(mid 249.748424 -95.209351)
		(end 249.69978 -95.405702)
		(width 0.0889)
		(layer "In11.Cu")
		(net "M_F_DQS_DN<3>")
	)
	(arc
		(start 250.5583 -89.574624)
		(mid 250.607055 -89.770976)
		(end 250.553474 -89.966038)
		(width 0.0889)
		(layer "In11.Cu")
		(net "M_F_DQS_DN<3>")
	)
	(arc
		(start 249.694954 -94.423484)
		(mid 249.615823 -94.718886)
		(end 249.694954 -95.014288)
		(width 0.0889)
		(layer "In11.Cu")
		(net "M_F_DQS_DN<3>")
	)
	(arc
		(start 250.19381 -93.137736)
		(mid 249.694929 -93.433173)
		(end 249.688604 -94.01302)
		(width 0.0889)
		(layer "In11.Cu")
		(net "M_F_DQS_DN<3>")
	)
	(arc
		(start 250.553474 -90.956638)
		(mid 250.474252 -91.245756)
		(end 250.547124 -91.53652)
		(width 0.0889)
		(layer "In11.Cu")
		(net "M_F_DQS_DN<3>")
	)
	(arc
		(start 250.206764 -87.784686)
		(mid 250.358343 -88.189833)
		(end 250.553474 -88.575896)
		(width 0.0889)
		(layer "In11.Cu")
		(net "M_F_DQS_DN<3>")
	)
	(arc
		(start 250.553474 -89.966038)
		(mid 250.474252 -90.255156)
		(end 250.547124 -90.54592)
		(width 0.0889)
		(layer "In11.Cu")
		(net "M_F_DQS_DN<3>")
	)
	(arc
		(start 250.553474 -88.975438)
		(mid 250.474252 -89.264556)
		(end 250.547124 -89.55532)
		(width 0.0889)
		(layer "In11.Cu")
		(net "M_F_DQS_DN<3>")
	)
	(segment
		(start 219.350336 -156.87294)
		(end 219.349828 -156.87294)
		(width 0.1651)
		(layer "F.Cu")
		(net "M_F_DQS_DN<2>")
	)
	(segment
		(start 218.967812 -155.422854)
		(end 218.967812 -154.991054)
		(width 0.1651)
		(layer "F.Cu")
		(net "M_F_DQS_DN<2>")
	)
	(segment
		(start 219.349828 -156.87294)
		(end 219.349828 -155.80487)
		(width 0.1651)
		(layer "F.Cu")
		(net "M_F_DQS_DN<2>")
	)
	(segment
		(start 219.349828 -155.80487)
		(end 218.967812 -155.422854)
		(width 0.1651)
		(layer "F.Cu")
		(net "M_F_DQS_DN<2>")
	)
	(segment
		(start 219.298266 -154.6606)
		(end 219.522294 -154.6606)
		(width 0.1651)
		(layer "F.Cu")
		(net "M_F_DQS_DN<2>")
	)
	(segment
		(start 218.967812 -154.991054)
		(end 219.298266 -154.6606)
		(width 0.1651)
		(layer "F.Cu")
		(net "M_F_DQS_DN<2>")
	)
	(segment
		(start 244.768624 -94.223586)
		(end 244.197124 -94.223586)
		(width 0.1651)
		(layer "F.Cu")
		(net "M_F_DQS_DN<2>")
	)
	(segment
		(start 219.522294 -154.6606)
		(end 219.73794 -154.876246)
		(width 0.1651)
		(layer "F.Cu")
		(net "M_F_DQS_DN<2>")
	)
	(via
		(at 244.197124 -94.223586)
		(size 0.508)
		(drill 0.254)
		(layers "F.Cu" "B.Cu")
		(net "M_F_DQS_DN<2>")
	)
	(via
		(at 219.73794 -149.482556)
		(size 0.508)
		(drill 0.254)
		(layers "F.Cu" "B.Cu")
		(net "M_F_DQS_DN<2>")
	)
	(via
		(at 219.73794 -154.876246)
		(size 0.508)
		(drill 0.254)
		(layers "F.Cu" "B.Cu")
		(net "M_F_DQS_DN<2>")
	)
	(segment
		(start 219.350336 -147.478496)
		(end 219.349828 -147.478496)
		(width 0.1651)
		(layer "B.Cu")
		(net "M_F_DQS_DN<2>")
	)
	(segment
		(start 219.221812 -148.767546)
		(end 218.967812 -149.021546)
		(width 0.1651)
		(layer "B.Cu")
		(net "M_F_DQS_DN<2>")
	)
	(segment
		(start 218.967812 -149.021546)
		(end 218.967812 -149.352)
		(width 0.1651)
		(layer "B.Cu")
		(net "M_F_DQS_DN<2>")
	)
	(segment
		(start 219.349828 -148.38553)
		(end 219.221812 -148.513546)
		(width 0.1651)
		(layer "B.Cu")
		(net "M_F_DQS_DN<2>")
	)
	(segment
		(start 219.323412 -149.7076)
		(end 219.512896 -149.7076)
		(width 0.1651)
		(layer "B.Cu")
		(net "M_F_DQS_DN<2>")
	)
	(segment
		(start 219.221812 -148.513546)
		(end 219.221812 -148.767546)
		(width 0.1651)
		(layer "B.Cu")
		(net "M_F_DQS_DN<2>")
	)
	(segment
		(start 218.967812 -149.352)
		(end 219.323412 -149.7076)
		(width 0.1651)
		(layer "B.Cu")
		(net "M_F_DQS_DN<2>")
	)
	(segment
		(start 219.512896 -149.7076)
		(end 219.73794 -149.482556)
		(width 0.1651)
		(layer "B.Cu")
		(net "M_F_DQS_DN<2>")
	)
	(segment
		(start 219.349828 -147.478496)
		(end 219.349828 -148.38553)
		(width 0.1651)
		(layer "B.Cu")
		(net "M_F_DQS_DN<2>")
	)
	(segment
		(start 220.109796 -136.855454)
		(end 220.109796 -137.109454)
		(width 0.14224)
		(layer "In11.Cu")
		(net "M_F_DQS_DN<2>")
	)
	(segment
		(start 220.267276 -137.266934)
		(end 220.267276 -137.520934)
		(width 0.14224)
		(layer "In11.Cu")
		(net "M_F_DQS_DN<2>")
	)
	(segment
		(start 220.109796 -142.672816)
		(end 220.267276 -142.830296)
		(width 0.14224)
		(layer "In11.Cu")
		(net "M_F_DQS_DN<2>")
	)
	(segment
		(start 220.98508 -121.617486)
		(end 220.98508 -126.291086)
		(width 0.14224)
		(layer "In11.Cu")
		(net "M_F_DQS_DN<2>")
	)
	(segment
		(start 226.267518 -116.335048)
		(end 225.92538 -116.677186)
		(width 0.14224)
		(layer "In11.Cu")
		(net "M_F_DQS_DN<2>")
	)
	(segment
		(start 234.787694 -104.771444)
		(end 234.04576 -105.513378)
		(width 0.14224)
		(layer "In11.Cu")
		(net "M_F_DQS_DN<2>")
	)
	(segment
		(start 220.109796 -137.109454)
		(end 220.267276 -137.266934)
		(width 0.14224)
		(layer "In11.Cu")
		(net "M_F_DQS_DN<2>")
	)
	(segment
		(start 220.267276 -137.520934)
		(end 220.109796 -137.678414)
		(width 0.14224)
		(layer "In11.Cu")
		(net "M_F_DQS_DN<2>")
	)
	(segment
		(start 220.109796 -146.667728)
		(end 220.267276 -146.825208)
		(width 0.14224)
		(layer "In11.Cu")
		(net "M_F_DQS_DN<2>")
	)
	(segment
		(start 229.501954 -113.100612)
		(end 229.159816 -113.44275)
		(width 0.14224)
		(layer "In11.Cu")
		(net "M_F_DQS_DN<2>")
	)
	(segment
		(start 230.777034 -111.825532)
		(end 229.999794 -111.825532)
		(width 0.14224)
		(layer "In11.Cu")
		(net "M_F_DQS_DN<2>")
	)
	(segment
		(start 220.267276 -142.830296)
		(end 220.267276 -143.084296)
		(width 0.14224)
		(layer "In11.Cu")
		(net "M_F_DQS_DN<2>")
	)
	(segment
		(start 228.382576 -113.44275)
		(end 227.884736 -113.94059)
		(width 0.14224)
		(layer "In11.Cu")
		(net "M_F_DQS_DN<2>")
	)
	(segment
		(start 221.415864 -120.663462)
		(end 221.415864 -121.186702)
		(width 0.14224)
		(layer "In11.Cu")
		(net "M_F_DQS_DN<2>")
	)
	(segment
		(start 231.119172 -111.483394)
		(end 230.777034 -111.825532)
		(width 0.14224)
		(layer "In11.Cu")
		(net "M_F_DQS_DN<2>")
	)
	(segment
		(start 220.267276 -148.471128)
		(end 220.267276 -149.19325)
		(width 0.14224)
		(layer "In11.Cu")
		(net "M_F_DQS_DN<2>")
	)
	(segment
		(start 222.530416 -119.911622)
		(end 222.167704 -119.911622)
		(width 0.14224)
		(layer "In11.Cu")
		(net "M_F_DQS_DN<2>")
	)
	(segment
		(start 224.308162 -118.294404)
		(end 223.531684 -118.294404)
		(width 0.14224)
		(layer "In11.Cu")
		(net "M_F_DQS_DN<2>")
	)
	(segment
		(start 220.267276 -133.20776)
		(end 220.267276 -133.547104)
		(width 0.14224)
		(layer "In11.Cu")
		(net "M_F_DQS_DN<2>")
	)
	(segment
		(start 239.919764 -97.100136)
		(end 239.886998 -97.100136)
		(width 0.0889)
		(layer "In11.Cu")
		(net "M_F_DQS_DN<2>")
	)
	(segment
		(start 227.542598 -115.059968)
		(end 226.765358 -115.059968)
		(width 0.14224)
		(layer "In11.Cu")
		(net "M_F_DQS_DN<2>")
	)
	(segment
		(start 227.884736 -113.94059)
		(end 227.884736 -114.71783)
		(width 0.14224)
		(layer "In11.Cu")
		(net "M_F_DQS_DN<2>")
	)
	(segment
		(start 220.109796 -141.595856)
		(end 220.109796 -141.849856)
		(width 0.14224)
		(layer "In11.Cu")
		(net "M_F_DQS_DN<2>")
	)
	(segment
		(start 233.428032 -108.591096)
		(end 232.73639 -109.282738)
		(width 0.14224)
		(layer "In11.Cu")
		(net "M_F_DQS_DN<2>")
	)
	(segment
		(start 234.04576 -105.513378)
		(end 234.04576 -108.135928)
		(width 0.14224)
		(layer "In11.Cu")
		(net "M_F_DQS_DN<2>")
	)
	(segment
		(start 219.73794 -149.482556)
		(end 219.664788 -149.482556)
		(width 0.14224)
		(layer "In11.Cu")
		(net "M_F_DQS_DN<2>")
	)
	(segment
		(start 220.267276 -143.653256)
		(end 220.267276 -146.256248)
		(width 0.14224)
		(layer "In11.Cu")
		(net "M_F_DQS_DN<2>")
	)
	(segment
		(start 219.09405 -152.97658)
		(end 219.30487 -153.1874)
		(width 0.14224)
		(layer "In11.Cu")
		(net "M_F_DQS_DN<2>")
	)
	(segment
		(start 236.874304 -101.557836)
		(end 236.874304 -102.740968)
		(width 0.0889)
		(layer "In11.Cu")
		(net "M_F_DQS_DN<2>")
	)
	(segment
		(start 234.04576 -108.135928)
		(end 233.590592 -108.591096)
		(width 0.14224)
		(layer "In11.Cu")
		(net "M_F_DQS_DN<2>")
	)
	(segment
		(start 239.057434 -97.59569)
		(end 239.024668 -97.59569)
		(width 0.0889)
		(layer "In11.Cu")
		(net "M_F_DQS_DN<2>")
	)
	(segment
		(start 220.109796 -147.490688)
		(end 220.267276 -147.648168)
		(width 0.14224)
		(layer "In11.Cu")
		(net "M_F_DQS_DN<2>")
	)
	(segment
		(start 220.109796 -137.678414)
		(end 220.109796 -137.932414)
		(width 0.14224)
		(layer "In11.Cu")
		(net "M_F_DQS_DN<2>")
	)
	(segment
		(start 220.109796 -148.313648)
		(end 220.267276 -148.471128)
		(width 0.14224)
		(layer "In11.Cu")
		(net "M_F_DQS_DN<2>")
	)
	(segment
		(start 220.98508 -126.291086)
		(end 220.267276 -127.00889)
		(width 0.14224)
		(layer "In11.Cu")
		(net "M_F_DQS_DN<2>")
	)
	(segment
		(start 220.109796 -133.05028)
		(end 220.267276 -133.20776)
		(width 0.14224)
		(layer "In11.Cu")
		(net "M_F_DQS_DN<2>")
	)
	(segment
		(start 237.340394 -98.58629)
		(end 237.307628 -98.58629)
		(width 0.0889)
		(layer "In11.Cu")
		(net "M_F_DQS_DN<2>")
	)
	(segment
		(start 220.109796 -142.418816)
		(end 220.109796 -142.672816)
		(width 0.14224)
		(layer "In11.Cu")
		(net "M_F_DQS_DN<2>")
	)
	(segment
		(start 244.197124 -94.223586)
		(end 243.901722 -94.543372)
		(width 0.0889)
		(layer "In11.Cu")
		(net "M_F_DQS_DN<2>")
	)
	(segment
		(start 220.267276 -142.261336)
		(end 220.109796 -142.418816)
		(width 0.14224)
		(layer "In11.Cu")
		(net "M_F_DQS_DN<2>")
	)
	(segment
		(start 220.109796 -146.413728)
		(end 220.109796 -146.667728)
		(width 0.14224)
		(layer "In11.Cu")
		(net "M_F_DQS_DN<2>")
	)
	(segment
		(start 223.531684 -118.294404)
		(end 223.033082 -118.793006)
		(width 0.14224)
		(layer "In11.Cu")
		(net "M_F_DQS_DN<2>")
	)
	(segment
		(start 219.30487 -153.1874)
		(end 219.30487 -154.443176)
		(width 0.14224)
		(layer "In11.Cu")
		(net "M_F_DQS_DN<2>")
	)
	(segment
		(start 243.901722 -94.543372)
		(end 243.685314 -94.919038)
		(width 0.0889)
		(layer "In11.Cu")
		(net "M_F_DQS_DN<2>")
	)
	(segment
		(start 232.73639 -109.282738)
		(end 232.73639 -109.866176)
		(width 0.14224)
		(layer "In11.Cu")
		(net "M_F_DQS_DN<2>")
	)
	(segment
		(start 220.267276 -143.084296)
		(end 220.109796 -143.241776)
		(width 0.14224)
		(layer "In11.Cu")
		(net "M_F_DQS_DN<2>")
	)
	(segment
		(start 236.817408 -100.462588)
		(end 236.822234 -100.471224)
		(width 0.0889)
		(layer "In11.Cu")
		(net "M_F_DQS_DN<2>")
	)
	(segment
		(start 224.6503 -117.175026)
		(end 224.6503 -117.952266)
		(width 0.14224)
		(layer "In11.Cu")
		(net "M_F_DQS_DN<2>")
	)
	(segment
		(start 234.803442 -104.755696)
		(end 234.787694 -104.771444)
		(width 0.0889)
		(layer "In11.Cu")
		(net "M_F_DQS_DN<2>")
	)
	(segment
		(start 220.267276 -147.902168)
		(end 220.109796 -148.059648)
		(width 0.14224)
		(layer "In11.Cu")
		(net "M_F_DQS_DN<2>")
	)
	(segment
		(start 220.267276 -146.256248)
		(end 220.109796 -146.413728)
		(width 0.14224)
		(layer "In11.Cu")
		(net "M_F_DQS_DN<2>")
	)
	(segment
		(start 220.267276 -138.912854)
		(end 220.267276 -141.438376)
		(width 0.14224)
		(layer "In11.Cu")
		(net "M_F_DQS_DN<2>")
	)
	(segment
		(start 220.267276 -127.00889)
		(end 220.267276 -132.6388)
		(width 0.14224)
		(layer "In11.Cu")
		(net "M_F_DQS_DN<2>")
	)
	(segment
		(start 220.267276 -141.438376)
		(end 220.109796 -141.595856)
		(width 0.14224)
		(layer "In11.Cu")
		(net "M_F_DQS_DN<2>")
	)
	(segment
		(start 220.109796 -132.79628)
		(end 220.109796 -133.05028)
		(width 0.14224)
		(layer "In11.Cu")
		(net "M_F_DQS_DN<2>")
	)
	(segment
		(start 232.394252 -110.208314)
		(end 231.617012 -110.208314)
		(width 0.14224)
		(layer "In11.Cu")
		(net "M_F_DQS_DN<2>")
	)
	(segment
		(start 224.6503 -117.952266)
		(end 224.308162 -118.294404)
		(width 0.14224)
		(layer "In11.Cu")
		(net "M_F_DQS_DN<2>")
	)
	(segment
		(start 220.109796 -137.932414)
		(end 220.267276 -138.089894)
		(width 0.14224)
		(layer "In11.Cu")
		(net "M_F_DQS_DN<2>")
	)
	(segment
		(start 225.14814 -116.677186)
		(end 224.6503 -117.175026)
		(width 0.14224)
		(layer "In11.Cu")
		(net "M_F_DQS_DN<2>")
	)
	(segment
		(start 231.119172 -110.706154)
		(end 231.119172 -111.483394)
		(width 0.14224)
		(layer "In11.Cu")
		(net "M_F_DQS_DN<2>")
	)
	(segment
		(start 220.109796 -148.059648)
		(end 220.109796 -148.313648)
		(width 0.14224)
		(layer "In11.Cu")
		(net "M_F_DQS_DN<2>")
	)
	(segment
		(start 220.109796 -138.755374)
		(end 220.267276 -138.912854)
		(width 0.14224)
		(layer "In11.Cu")
		(net "M_F_DQS_DN<2>")
	)
	(segment
		(start 219.09405 -151.31542)
		(end 219.09405 -152.97658)
		(width 0.14224)
		(layer "In11.Cu")
		(net "M_F_DQS_DN<2>")
	)
	(segment
		(start 220.267276 -133.547104)
		(end 220.109796 -133.704584)
		(width 0.14224)
		(layer "In11.Cu")
		(net "M_F_DQS_DN<2>")
	)
	(segment
		(start 219.30487 -151.1046)
		(end 219.09405 -151.31542)
		(width 0.14224)
		(layer "In11.Cu")
		(net "M_F_DQS_DN<2>")
	)
	(segment
		(start 219.30487 -154.443176)
		(end 219.73794 -154.876246)
		(width 0.14224)
		(layer "In11.Cu")
		(net "M_F_DQS_DN<2>")
	)
	(segment
		(start 220.267276 -138.343894)
		(end 220.109796 -138.501374)
		(width 0.14224)
		(layer "In11.Cu")
		(net "M_F_DQS_DN<2>")
	)
	(segment
		(start 231.617012 -110.208314)
		(end 231.119172 -110.706154)
		(width 0.14224)
		(layer "In11.Cu")
		(net "M_F_DQS_DN<2>")
	)
	(segment
		(start 225.92538 -116.677186)
		(end 225.14814 -116.677186)
		(width 0.14224)
		(layer "In11.Cu")
		(net "M_F_DQS_DN<2>")
	)
	(segment
		(start 220.109796 -133.704584)
		(end 220.109796 -133.958584)
		(width 0.14224)
		(layer "In11.Cu")
		(net "M_F_DQS_DN<2>")
	)
	(segment
		(start 242.826794 -95.414338)
		(end 242.823492 -95.42018)
		(width 0.0889)
		(layer "In11.Cu")
		(net "M_F_DQS_DN<2>")
	)
	(segment
		(start 227.884736 -114.71783)
		(end 227.542598 -115.059968)
		(width 0.14224)
		(layer "In11.Cu")
		(net "M_F_DQS_DN<2>")
	)
	(segment
		(start 221.415864 -121.186702)
		(end 220.98508 -121.617486)
		(width 0.14224)
		(layer "In11.Cu")
		(net "M_F_DQS_DN<2>")
	)
	(segment
		(start 220.109796 -133.958584)
		(end 220.267276 -134.116064)
		(width 0.14224)
		(layer "In11.Cu")
		(net "M_F_DQS_DN<2>")
	)
	(segment
		(start 233.590592 -108.591096)
		(end 233.428032 -108.591096)
		(width 0.14224)
		(layer "In11.Cu")
		(net "M_F_DQS_DN<2>")
	)
	(segment
		(start 243.35613 -95.118936)
		(end 243.320824 -95.118936)
		(width 0.0889)
		(layer "In11.Cu")
		(net "M_F_DQS_DN<2>")
	)
	(segment
		(start 220.109796 -138.501374)
		(end 220.109796 -138.755374)
		(width 0.14224)
		(layer "In11.Cu")
		(net "M_F_DQS_DN<2>")
	)
	(segment
		(start 220.267276 -138.089894)
		(end 220.267276 -138.343894)
		(width 0.14224)
		(layer "In11.Cu")
		(net "M_F_DQS_DN<2>")
	)
	(segment
		(start 219.664788 -149.482556)
		(end 219.30487 -149.842474)
		(width 0.14224)
		(layer "In11.Cu")
		(net "M_F_DQS_DN<2>")
	)
	(segment
		(start 229.159816 -113.44275)
		(end 228.382576 -113.44275)
		(width 0.14224)
		(layer "In11.Cu")
		(net "M_F_DQS_DN<2>")
	)
	(segment
		(start 222.167704 -119.911622)
		(end 221.415864 -120.663462)
		(width 0.14224)
		(layer "In11.Cu")
		(net "M_F_DQS_DN<2>")
	)
	(segment
		(start 241.636804 -96.109536)
		(end 241.604038 -96.109536)
		(width 0.0889)
		(layer "In11.Cu")
		(net "M_F_DQS_DN<2>")
	)
	(segment
		(start 226.765358 -115.059968)
		(end 226.267518 -115.557808)
		(width 0.14224)
		(layer "In11.Cu")
		(net "M_F_DQS_DN<2>")
	)
	(segment
		(start 234.859576 -104.755696)
		(end 234.803442 -104.755696)
		(width 0.0889)
		(layer "In11.Cu")
		(net "M_F_DQS_DN<2>")
	)
	(segment
		(start 236.874304 -102.740968)
		(end 234.859576 -104.755696)
		(width 0.0889)
		(layer "In11.Cu")
		(net "M_F_DQS_DN<2>")
	)
	(segment
		(start 238.202724 -98.090736)
		(end 238.169958 -98.090736)
		(width 0.0889)
		(layer "In11.Cu")
		(net "M_F_DQS_DN<2>")
	)
	(segment
		(start 220.267276 -147.079208)
		(end 220.109796 -147.236688)
		(width 0.14224)
		(layer "In11.Cu")
		(net "M_F_DQS_DN<2>")
	)
	(segment
		(start 220.109796 -143.495776)
		(end 220.267276 -143.653256)
		(width 0.14224)
		(layer "In11.Cu")
		(net "M_F_DQS_DN<2>")
	)
	(segment
		(start 220.109796 -143.241776)
		(end 220.109796 -143.495776)
		(width 0.14224)
		(layer "In11.Cu")
		(net "M_F_DQS_DN<2>")
	)
	(segment
		(start 229.501954 -112.323372)
		(end 229.501954 -113.100612)
		(width 0.14224)
		(layer "In11.Cu")
		(net "M_F_DQS_DN<2>")
	)
	(segment
		(start 220.267276 -146.825208)
		(end 220.267276 -147.079208)
		(width 0.14224)
		(layer "In11.Cu")
		(net "M_F_DQS_DN<2>")
	)
	(segment
		(start 236.817408 -99.872038)
		(end 236.811058 -99.882706)
		(width 0.0889)
		(layer "In11.Cu")
		(net "M_F_DQS_DN<2>")
	)
	(segment
		(start 232.73639 -109.866176)
		(end 232.394252 -110.208314)
		(width 0.14224)
		(layer "In11.Cu")
		(net "M_F_DQS_DN<2>")
	)
	(segment
		(start 219.30487 -149.842474)
		(end 219.30487 -151.1046)
		(width 0.14224)
		(layer "In11.Cu")
		(net "M_F_DQS_DN<2>")
	)
	(segment
		(start 220.267276 -147.648168)
		(end 220.267276 -147.902168)
		(width 0.14224)
		(layer "In11.Cu")
		(net "M_F_DQS_DN<2>")
	)
	(segment
		(start 242.480338 -95.61449)
		(end 242.458748 -95.61449)
		(width 0.0889)
		(layer "In11.Cu")
		(net "M_F_DQS_DN<2>")
	)
	(segment
		(start 220.267276 -136.697974)
		(end 220.109796 -136.855454)
		(width 0.14224)
		(layer "In11.Cu")
		(net "M_F_DQS_DN<2>")
	)
	(segment
		(start 220.267276 -142.007336)
		(end 220.267276 -142.261336)
		(width 0.14224)
		(layer "In11.Cu")
		(net "M_F_DQS_DN<2>")
	)
	(segment
		(start 229.999794 -111.825532)
		(end 229.501954 -112.323372)
		(width 0.14224)
		(layer "In11.Cu")
		(net "M_F_DQS_DN<2>")
	)
	(segment
		(start 236.811058 -101.44252)
		(end 236.874304 -101.557836)
		(width 0.0889)
		(layer "In11.Cu")
		(net "M_F_DQS_DN<2>")
	)
	(segment
		(start 220.267276 -134.116064)
		(end 220.267276 -136.697974)
		(width 0.14224)
		(layer "In11.Cu")
		(net "M_F_DQS_DN<2>")
	)
	(segment
		(start 220.109796 -141.849856)
		(end 220.267276 -142.007336)
		(width 0.14224)
		(layer "In11.Cu")
		(net "M_F_DQS_DN<2>")
	)
	(segment
		(start 240.774474 -96.60509)
		(end 240.741708 -96.60509)
		(width 0.0889)
		(layer "In11.Cu")
		(net "M_F_DQS_DN<2>")
	)
	(segment
		(start 220.267276 -149.19325)
		(end 219.97797 -149.482556)
		(width 0.14224)
		(layer "In11.Cu")
		(net "M_F_DQS_DN<2>")
	)
	(segment
		(start 223.033082 -119.408956)
		(end 222.530416 -119.911622)
		(width 0.14224)
		(layer "In11.Cu")
		(net "M_F_DQS_DN<2>")
	)
	(segment
		(start 219.97797 -149.482556)
		(end 219.73794 -149.482556)
		(width 0.14224)
		(layer "In11.Cu")
		(net "M_F_DQS_DN<2>")
	)
	(segment
		(start 223.033082 -118.793006)
		(end 223.033082 -119.408956)
		(width 0.14224)
		(layer "In11.Cu")
		(net "M_F_DQS_DN<2>")
	)
	(segment
		(start 220.109796 -147.236688)
		(end 220.109796 -147.490688)
		(width 0.14224)
		(layer "In11.Cu")
		(net "M_F_DQS_DN<2>")
	)
	(segment
		(start 236.817408 -100.862638)
		(end 236.817154 -100.862892)
		(width 0.0889)
		(layer "In11.Cu")
		(net "M_F_DQS_DN<2>")
	)
	(segment
		(start 226.267518 -115.557808)
		(end 226.267518 -116.335048)
		(width 0.14224)
		(layer "In11.Cu")
		(net "M_F_DQS_DN<2>")
	)
	(segment
		(start 220.267276 -132.6388)
		(end 220.109796 -132.79628)
		(width 0.14224)
		(layer "In11.Cu")
		(net "M_F_DQS_DN<2>")
	)
	(arc
		(start 236.822234 -100.471224)
		(mid 236.870989 -100.667576)
		(end 236.817408 -100.862638)
		(width 0.0889)
		(layer "In11.Cu")
		(net "M_F_DQS_DN<2>")
	)
	(arc
		(start 238.534448 -97.890838)
		(mid 238.394369 -98.033574)
		(end 238.202724 -98.090736)
		(width 0.0889)
		(layer "In11.Cu")
		(net "M_F_DQS_DN<2>")
	)
	(arc
		(start 241.604038 -96.109536)
		(mid 241.318614 -96.193003)
		(end 241.110008 -96.404938)
		(width 0.0889)
		(layer "In11.Cu")
		(net "M_F_DQS_DN<2>")
	)
	(arc
		(start 239.392968 -97.395538)
		(mid 239.251285 -97.539342)
		(end 239.057434 -97.59569)
		(width 0.0889)
		(layer "In11.Cu")
		(net "M_F_DQS_DN<2>")
	)
	(arc
		(start 243.685314 -94.919038)
		(mid 243.546321 -95.061118)
		(end 243.35613 -95.118936)
		(width 0.0889)
		(layer "In11.Cu")
		(net "M_F_DQS_DN<2>")
	)
	(arc
		(start 236.811058 -99.882706)
		(mid 236.73826 -100.173469)
		(end 236.817408 -100.462588)
		(width 0.0889)
		(layer "In11.Cu")
		(net "M_F_DQS_DN<2>")
	)
	(arc
		(start 242.823492 -95.42018)
		(mid 242.677526 -95.562579)
		(end 242.480338 -95.61449)
		(width 0.0889)
		(layer "In11.Cu")
		(net "M_F_DQS_DN<2>")
	)
	(arc
		(start 243.320824 -95.118936)
		(mid 243.0354 -95.202403)
		(end 242.826794 -95.414338)
		(width 0.0889)
		(layer "In11.Cu")
		(net "M_F_DQS_DN<2>")
	)
	(arc
		(start 241.110008 -96.404938)
		(mid 240.968325 -96.548742)
		(end 240.774474 -96.60509)
		(width 0.0889)
		(layer "In11.Cu")
		(net "M_F_DQS_DN<2>")
	)
	(arc
		(start 242.458748 -95.61449)
		(mid 242.175531 -95.698771)
		(end 241.968528 -95.909638)
		(width 0.0889)
		(layer "In11.Cu")
		(net "M_F_DQS_DN<2>")
	)
	(arc
		(start 237.675928 -98.386138)
		(mid 237.534245 -98.529942)
		(end 237.340394 -98.58629)
		(width 0.0889)
		(layer "In11.Cu")
		(net "M_F_DQS_DN<2>")
	)
	(arc
		(start 241.968528 -95.909638)
		(mid 241.828449 -96.052374)
		(end 241.636804 -96.109536)
		(width 0.0889)
		(layer "In11.Cu")
		(net "M_F_DQS_DN<2>")
	)
	(arc
		(start 239.024668 -97.59569)
		(mid 238.741451 -97.679971)
		(end 238.534448 -97.890838)
		(width 0.0889)
		(layer "In11.Cu")
		(net "M_F_DQS_DN<2>")
	)
	(arc
		(start 240.741708 -96.60509)
		(mid 240.458491 -96.689371)
		(end 240.251488 -96.900238)
		(width 0.0889)
		(layer "In11.Cu")
		(net "M_F_DQS_DN<2>")
	)
	(arc
		(start 236.817408 -99.472242)
		(mid 236.870907 -99.67214)
		(end 236.817408 -99.872038)
		(width 0.0889)
		(layer "In11.Cu")
		(net "M_F_DQS_DN<2>")
	)
	(arc
		(start 236.817154 -100.862892)
		(mid 236.738215 -101.151897)
		(end 236.811058 -101.44252)
		(width 0.0889)
		(layer "In11.Cu")
		(net "M_F_DQS_DN<2>")
	)
	(arc
		(start 237.307628 -98.58629)
		(mid 236.812151 -98.890733)
		(end 236.817408 -99.472242)
		(width 0.0889)
		(layer "In11.Cu")
		(net "M_F_DQS_DN<2>")
	)
	(arc
		(start 238.169958 -98.090736)
		(mid 237.884534 -98.174203)
		(end 237.675928 -98.386138)
		(width 0.0889)
		(layer "In11.Cu")
		(net "M_F_DQS_DN<2>")
	)
	(arc
		(start 239.886998 -97.100136)
		(mid 239.601574 -97.183603)
		(end 239.392968 -97.395538)
		(width 0.0889)
		(layer "In11.Cu")
		(net "M_F_DQS_DN<2>")
	)
	(arc
		(start 240.251488 -96.900238)
		(mid 240.111409 -97.042974)
		(end 239.919764 -97.100136)
		(width 0.0889)
		(layer "In11.Cu")
		(net "M_F_DQS_DN<2>")
	)
	(segment
		(start 209.999834 -156.87294)
		(end 209.999834 -155.80487)
		(width 0.1651)
		(layer "F.Cu")
		(net "M_F_DQS_DN<1>")
	)
	(segment
		(start 210.000342 -156.87294)
		(end 209.999834 -156.87294)
		(width 0.1651)
		(layer "F.Cu")
		(net "M_F_DQS_DN<1>")
	)
	(segment
		(start 240.476278 -90.756486)
		(end 239.904778 -90.756486)
		(width 0.1651)
		(layer "F.Cu")
		(net "M_F_DQS_DN<1>")
	)
	(segment
		(start 209.999834 -155.80487)
		(end 209.6008 -155.405836)
		(width 0.1651)
		(layer "F.Cu")
		(net "M_F_DQS_DN<1>")
	)
	(segment
		(start 209.6008 -155.405836)
		(end 209.6008 -155.008072)
		(width 0.1651)
		(layer "F.Cu")
		(net "M_F_DQS_DN<1>")
	)
	(segment
		(start 209.948272 -154.6606)
		(end 210.1723 -154.6606)
		(width 0.1651)
		(layer "F.Cu")
		(net "M_F_DQS_DN<1>")
	)
	(segment
		(start 210.1723 -154.6606)
		(end 210.387946 -154.876246)
		(width 0.1651)
		(layer "F.Cu")
		(net "M_F_DQS_DN<1>")
	)
	(segment
		(start 209.6008 -155.008072)
		(end 209.948272 -154.6606)
		(width 0.1651)
		(layer "F.Cu")
		(net "M_F_DQS_DN<1>")
	)
	(via
		(at 210.387946 -149.482556)
		(size 0.508)
		(drill 0.254)
		(layers "F.Cu" "B.Cu")
		(net "M_F_DQS_DN<1>")
	)
	(via
		(at 210.387946 -154.876246)
		(size 0.508)
		(drill 0.254)
		(layers "F.Cu" "B.Cu")
		(net "M_F_DQS_DN<1>")
	)
	(via
		(at 239.904778 -90.756486)
		(size 0.508)
		(drill 0.254)
		(layers "F.Cu" "B.Cu")
		(net "M_F_DQS_DN<1>")
	)
	(segment
		(start 209.617818 -149.352)
		(end 209.973418 -149.7076)
		(width 0.1651)
		(layer "B.Cu")
		(net "M_F_DQS_DN<1>")
	)
	(segment
		(start 210.000342 -147.478496)
		(end 209.999834 -147.478496)
		(width 0.1651)
		(layer "B.Cu")
		(net "M_F_DQS_DN<1>")
	)
	(segment
		(start 209.973418 -149.7076)
		(end 210.162902 -149.7076)
		(width 0.1651)
		(layer "B.Cu")
		(net "M_F_DQS_DN<1>")
	)
	(segment
		(start 209.871818 -148.513546)
		(end 209.871818 -148.767546)
		(width 0.1651)
		(layer "B.Cu")
		(net "M_F_DQS_DN<1>")
	)
	(segment
		(start 209.871818 -148.767546)
		(end 209.617818 -149.021546)
		(width 0.1651)
		(layer "B.Cu")
		(net "M_F_DQS_DN<1>")
	)
	(segment
		(start 209.617818 -149.021546)
		(end 209.617818 -149.352)
		(width 0.1651)
		(layer "B.Cu")
		(net "M_F_DQS_DN<1>")
	)
	(segment
		(start 210.162902 -149.7076)
		(end 210.387946 -149.482556)
		(width 0.1651)
		(layer "B.Cu")
		(net "M_F_DQS_DN<1>")
	)
	(segment
		(start 209.999834 -148.38553)
		(end 209.871818 -148.513546)
		(width 0.1651)
		(layer "B.Cu")
		(net "M_F_DQS_DN<1>")
	)
	(segment
		(start 209.999834 -147.478496)
		(end 209.999834 -148.38553)
		(width 0.1651)
		(layer "B.Cu")
		(net "M_F_DQS_DN<1>")
	)
	(segment
		(start 210.6676 -149.482556)
		(end 210.387946 -149.482556)
		(width 0.14224)
		(layer "In11.Cu")
		(net "M_F_DQS_DN<1>")
	)
	(segment
		(start 213.138258 -116.370354)
		(end 213.864952 -117.097302)
		(width 0.14224)
		(layer "In11.Cu")
		(net "M_F_DQS_DN<1>")
	)
	(segment
		(start 210.77428 -122.618246)
		(end 211.152486 -122.996452)
		(width 0.14224)
		(layer "In11.Cu")
		(net "M_F_DQS_DN<1>")
	)
	(segment
		(start 211.53628 -128.297432)
		(end 210.901026 -128.932686)
		(width 0.14224)
		(layer "In11.Cu")
		(net "M_F_DQS_DN<1>")
	)
	(segment
		(start 209.954876 -151.1046)
		(end 209.744056 -151.31542)
		(width 0.14224)
		(layer "In11.Cu")
		(net "M_F_DQS_DN<1>")
	)
	(segment
		(start 213.864952 -117.409468)
		(end 213.558628 -117.715792)
		(width 0.14224)
		(layer "In11.Cu")
		(net "M_F_DQS_DN<1>")
	)
	(segment
		(start 227.41636 -101.557074)
		(end 214.755984 -114.21745)
		(width 0.14224)
		(layer "In11.Cu")
		(net "M_F_DQS_DN<1>")
	)
	(segment
		(start 211.152486 -120.710452)
		(end 211.314792 -120.710452)
		(width 0.14224)
		(layer "In11.Cu")
		(net "M_F_DQS_DN<1>")
	)
	(segment
		(start 210.901026 -149.24913)
		(end 210.6676 -149.482556)
		(width 0.14224)
		(layer "In11.Cu")
		(net "M_F_DQS_DN<1>")
	)
	(segment
		(start 210.764882 -148.18614)
		(end 210.901026 -148.322284)
		(width 0.14224)
		(layer "In11.Cu")
		(net "M_F_DQS_DN<1>")
	)
	(segment
		(start 211.152486 -122.996452)
		(end 211.314792 -122.996452)
		(width 0.14224)
		(layer "In11.Cu")
		(net "M_F_DQS_DN<1>")
	)
	(segment
		(start 213.558628 -117.715792)
		(end 213.246462 -117.715792)
		(width 0.14224)
		(layer "In11.Cu")
		(net "M_F_DQS_DN<1>")
	)
	(segment
		(start 209.954876 -149.842474)
		(end 209.954876 -151.1046)
		(width 0.14224)
		(layer "In11.Cu")
		(net "M_F_DQS_DN<1>")
	)
	(segment
		(start 228.353112 -97.198688)
		(end 227.41636 -98.13544)
		(width 0.14224)
		(layer "In11.Cu")
		(net "M_F_DQS_DN<1>")
	)
	(segment
		(start 209.954876 -153.1874)
		(end 209.954876 -154.443176)
		(width 0.14224)
		(layer "In11.Cu")
		(net "M_F_DQS_DN<1>")
	)
	(segment
		(start 235.630212 -93.633036)
		(end 235.594398 -93.633036)
		(width 0.0889)
		(layer "In11.Cu")
		(net "M_F_DQS_DN<1>")
	)
	(segment
		(start 213.864952 -117.097302)
		(end 213.864952 -117.409468)
		(width 0.14224)
		(layer "In11.Cu")
		(net "M_F_DQS_DN<1>")
	)
	(segment
		(start 210.764628 -147.10918)
		(end 210.764628 -147.36318)
		(width 0.14224)
		(layer "In11.Cu")
		(net "M_F_DQS_DN<1>")
	)
	(segment
		(start 214.755476 -114.753136)
		(end 215.48217 -115.480084)
		(width 0.14224)
		(layer "In11.Cu")
		(net "M_F_DQS_DN<1>")
	)
	(segment
		(start 214.755984 -114.21745)
		(end 214.755476 -114.21745)
		(width 0.14224)
		(layer "In11.Cu")
		(net "M_F_DQS_DN<1>")
	)
	(segment
		(start 210.79968 -119.651018)
		(end 210.79968 -120.357646)
		(width 0.14224)
		(layer "In11.Cu")
		(net "M_F_DQS_DN<1>")
	)
	(segment
		(start 211.53628 -123.21794)
		(end 211.53628 -128.297432)
		(width 0.14224)
		(layer "In11.Cu")
		(net "M_F_DQS_DN<1>")
	)
	(segment
		(start 215.48217 -115.480084)
		(end 215.48217 -115.791488)
		(width 0.14224)
		(layer "In11.Cu")
		(net "M_F_DQS_DN<1>")
	)
	(segment
		(start 229.177088 -97.195386)
		(end 229.15499 -97.19564)
		(width 0.0889)
		(layer "In11.Cu")
		(net "M_F_DQS_DN<1>")
	)
	(segment
		(start 210.764882 -147.93214)
		(end 210.764882 -148.18614)
		(width 0.14224)
		(layer "In11.Cu")
		(net "M_F_DQS_DN<1>")
	)
	(segment
		(start 209.744056 -151.31542)
		(end 209.744056 -152.97658)
		(width 0.14224)
		(layer "In11.Cu")
		(net "M_F_DQS_DN<1>")
	)
	(segment
		(start 210.764628 -147.36318)
		(end 210.901026 -147.499578)
		(width 0.14224)
		(layer "In11.Cu")
		(net "M_F_DQS_DN<1>")
	)
	(segment
		(start 227.41636 -98.13544)
		(end 227.41636 -101.557074)
		(width 0.14224)
		(layer "In11.Cu")
		(net "M_F_DQS_DN<1>")
	)
	(segment
		(start 209.744056 -152.97658)
		(end 209.954876 -153.1874)
		(width 0.14224)
		(layer "In11.Cu")
		(net "M_F_DQS_DN<1>")
	)
	(segment
		(start 209.954876 -154.443176)
		(end 210.387946 -154.876246)
		(width 0.14224)
		(layer "In11.Cu")
		(net "M_F_DQS_DN<1>")
	)
	(segment
		(start 211.152486 -121.584212)
		(end 210.77428 -121.962418)
		(width 0.14224)
		(layer "In11.Cu")
		(net "M_F_DQS_DN<1>")
	)
	(segment
		(start 210.901026 -146.972782)
		(end 210.764628 -147.10918)
		(width 0.14224)
		(layer "In11.Cu")
		(net "M_F_DQS_DN<1>")
	)
	(segment
		(start 237.340394 -92.64269)
		(end 237.307628 -92.64269)
		(width 0.0889)
		(layer "In11.Cu")
		(net "M_F_DQS_DN<1>")
	)
	(segment
		(start 229.216966 -97.233994)
		(end 229.177088 -97.195386)
		(width 0.0889)
		(layer "In11.Cu")
		(net "M_F_DQS_DN<1>")
	)
	(segment
		(start 231.271826 -97.2312)
		(end 229.35565 -97.2312)
		(width 0.0889)
		(layer "In11.Cu")
		(net "M_F_DQS_DN<1>")
	)
	(segment
		(start 211.983828 -117.123718)
		(end 211.53628 -117.571266)
		(width 0.14224)
		(layer "In11.Cu")
		(net "M_F_DQS_DN<1>")
	)
	(segment
		(start 240.197894 -90.92565)
		(end 240.218976 -91.00439)
		(width 0.0889)
		(layer "In11.Cu")
		(net "M_F_DQS_DN<1>")
	)
	(segment
		(start 212.654388 -117.123718)
		(end 211.983828 -117.123718)
		(width 0.14224)
		(layer "In11.Cu")
		(net "M_F_DQS_DN<1>")
	)
	(segment
		(start 211.53628 -120.93194)
		(end 211.53628 -121.362724)
		(width 0.14224)
		(layer "In11.Cu")
		(net "M_F_DQS_DN<1>")
	)
	(segment
		(start 211.53628 -121.362724)
		(end 211.314792 -121.584212)
		(width 0.14224)
		(layer "In11.Cu")
		(net "M_F_DQS_DN<1>")
	)
	(segment
		(start 210.79968 -120.357646)
		(end 211.152486 -120.710452)
		(width 0.14224)
		(layer "In11.Cu")
		(net "M_F_DQS_DN<1>")
	)
	(segment
		(start 236.485684 -93.137736)
		(end 236.457744 -93.137736)
		(width 0.0889)
		(layer "In11.Cu")
		(net "M_F_DQS_DN<1>")
	)
	(segment
		(start 210.901026 -128.932686)
		(end 210.901026 -146.972782)
		(width 0.14224)
		(layer "In11.Cu")
		(net "M_F_DQS_DN<1>")
	)
	(segment
		(start 214.137494 -115.371626)
		(end 213.601046 -115.371626)
		(width 0.14224)
		(layer "In11.Cu")
		(net "M_F_DQS_DN<1>")
	)
	(segment
		(start 239.057434 -91.65209)
		(end 239.024668 -91.65209)
		(width 0.0889)
		(layer "In11.Cu")
		(net "M_F_DQS_DN<1>")
	)
	(segment
		(start 214.864188 -116.098574)
		(end 214.137494 -115.371626)
		(width 0.14224)
		(layer "In11.Cu")
		(net "M_F_DQS_DN<1>")
	)
	(segment
		(start 239.904778 -90.756486)
		(end 240.197894 -90.92565)
		(width 0.0889)
		(layer "In11.Cu")
		(net "M_F_DQS_DN<1>")
	)
	(segment
		(start 211.53628 -117.571266)
		(end 211.53628 -119.076724)
		(width 0.14224)
		(layer "In11.Cu")
		(net "M_F_DQS_DN<1>")
	)
	(segment
		(start 211.314792 -122.996452)
		(end 211.53628 -123.21794)
		(width 0.14224)
		(layer "In11.Cu")
		(net "M_F_DQS_DN<1>")
	)
	(segment
		(start 210.901026 -147.795996)
		(end 210.764882 -147.93214)
		(width 0.14224)
		(layer "In11.Cu")
		(net "M_F_DQS_DN<1>")
	)
	(segment
		(start 210.314794 -149.482556)
		(end 209.954876 -149.842474)
		(width 0.14224)
		(layer "In11.Cu")
		(net "M_F_DQS_DN<1>")
	)
	(segment
		(start 210.77428 -121.962418)
		(end 210.77428 -122.618246)
		(width 0.14224)
		(layer "In11.Cu")
		(net "M_F_DQS_DN<1>")
	)
	(segment
		(start 229.15499 -97.19564)
		(end 228.999796 -97.198688)
		(width 0.14224)
		(layer "In11.Cu")
		(net "M_F_DQS_DN<1>")
	)
	(segment
		(start 214.755476 -114.21745)
		(end 214.755476 -114.753136)
		(width 0.14224)
		(layer "In11.Cu")
		(net "M_F_DQS_DN<1>")
	)
	(segment
		(start 234.277408 -94.128336)
		(end 233.37393 -95.031814)
		(width 0.0889)
		(layer "In11.Cu")
		(net "M_F_DQS_DN<1>")
	)
	(segment
		(start 213.601046 -115.371626)
		(end 213.138258 -115.834414)
		(width 0.14224)
		(layer "In11.Cu")
		(net "M_F_DQS_DN<1>")
	)
	(segment
		(start 215.48217 -115.791488)
		(end 215.175084 -116.098574)
		(width 0.14224)
		(layer "In11.Cu")
		(net "M_F_DQS_DN<1>")
	)
	(segment
		(start 210.387946 -149.482556)
		(end 210.314794 -149.482556)
		(width 0.14224)
		(layer "In11.Cu")
		(net "M_F_DQS_DN<1>")
	)
	(segment
		(start 213.246462 -117.715792)
		(end 212.654388 -117.123718)
		(width 0.14224)
		(layer "In11.Cu")
		(net "M_F_DQS_DN<1>")
	)
	(segment
		(start 234.774232 -94.128336)
		(end 234.277408 -94.128336)
		(width 0.0889)
		(layer "In11.Cu")
		(net "M_F_DQS_DN<1>")
	)
	(segment
		(start 210.901026 -148.322284)
		(end 210.901026 -149.24913)
		(width 0.14224)
		(layer "In11.Cu")
		(net "M_F_DQS_DN<1>")
	)
	(segment
		(start 211.152486 -119.298212)
		(end 210.79968 -119.651018)
		(width 0.14224)
		(layer "In11.Cu")
		(net "M_F_DQS_DN<1>")
	)
	(segment
		(start 211.314792 -120.710452)
		(end 211.53628 -120.93194)
		(width 0.14224)
		(layer "In11.Cu")
		(net "M_F_DQS_DN<1>")
	)
	(segment
		(start 229.35565 -97.2312)
		(end 229.216966 -97.233994)
		(width 0.0889)
		(layer "In11.Cu")
		(net "M_F_DQS_DN<1>")
	)
	(segment
		(start 210.901026 -147.499578)
		(end 210.901026 -147.795996)
		(width 0.14224)
		(layer "In11.Cu")
		(net "M_F_DQS_DN<1>")
	)
	(segment
		(start 231.426004 -96.130364)
		(end 231.426004 -97.077022)
		(width 0.0889)
		(layer "In11.Cu")
		(net "M_F_DQS_DN<1>")
	)
	(segment
		(start 213.138258 -115.834414)
		(end 213.138258 -116.370354)
		(width 0.14224)
		(layer "In11.Cu")
		(net "M_F_DQS_DN<1>")
	)
	(segment
		(start 215.175084 -116.098574)
		(end 214.864188 -116.098574)
		(width 0.14224)
		(layer "In11.Cu")
		(net "M_F_DQS_DN<1>")
	)
	(segment
		(start 228.999796 -97.198688)
		(end 228.353112 -97.198688)
		(width 0.14224)
		(layer "In11.Cu")
		(net "M_F_DQS_DN<1>")
	)
	(segment
		(start 238.202724 -92.147136)
		(end 238.169958 -92.147136)
		(width 0.0889)
		(layer "In11.Cu")
		(net "M_F_DQS_DN<1>")
	)
	(segment
		(start 232.519728 -95.031814)
		(end 231.426004 -96.130364)
		(width 0.0889)
		(layer "In11.Cu")
		(net "M_F_DQS_DN<1>")
	)
	(segment
		(start 211.314792 -121.584212)
		(end 211.152486 -121.584212)
		(width 0.14224)
		(layer "In11.Cu")
		(net "M_F_DQS_DN<1>")
	)
	(segment
		(start 211.314792 -119.298212)
		(end 211.152486 -119.298212)
		(width 0.14224)
		(layer "In11.Cu")
		(net "M_F_DQS_DN<1>")
	)
	(segment
		(start 233.37393 -95.031814)
		(end 232.519728 -95.031814)
		(width 0.0889)
		(layer "In11.Cu")
		(net "M_F_DQS_DN<1>")
	)
	(segment
		(start 211.53628 -119.076724)
		(end 211.314792 -119.298212)
		(width 0.14224)
		(layer "In11.Cu")
		(net "M_F_DQS_DN<1>")
	)
	(segment
		(start 239.919764 -91.156536)
		(end 239.886998 -91.156536)
		(width 0.0889)
		(layer "In11.Cu")
		(net "M_F_DQS_DN<1>")
	)
	(segment
		(start 231.426004 -97.077022)
		(end 231.271826 -97.2312)
		(width 0.0889)
		(layer "In11.Cu")
		(net "M_F_DQS_DN<1>")
	)
	(arc
		(start 236.457744 -93.137736)
		(mid 236.169599 -93.220055)
		(end 235.958888 -93.433138)
		(width 0.0889)
		(layer "In11.Cu")
		(net "M_F_DQS_DN<1>")
	)
	(arc
		(start 235.958888 -93.433138)
		(mid 235.820144 -93.575171)
		(end 235.630212 -93.633036)
		(width 0.0889)
		(layer "In11.Cu")
		(net "M_F_DQS_DN<1>")
	)
	(arc
		(start 238.169958 -92.147136)
		(mid 237.884534 -92.230603)
		(end 237.675928 -92.442538)
		(width 0.0889)
		(layer "In11.Cu")
		(net "M_F_DQS_DN<1>")
	)
	(arc
		(start 239.886998 -91.156536)
		(mid 239.601574 -91.240003)
		(end 239.392968 -91.451938)
		(width 0.0889)
		(layer "In11.Cu")
		(net "M_F_DQS_DN<1>")
	)
	(arc
		(start 237.675928 -92.442538)
		(mid 237.534245 -92.586342)
		(end 237.340394 -92.64269)
		(width 0.0889)
		(layer "In11.Cu")
		(net "M_F_DQS_DN<1>")
	)
	(arc
		(start 236.817408 -92.937838)
		(mid 236.677329 -93.080574)
		(end 236.485684 -93.137736)
		(width 0.0889)
		(layer "In11.Cu")
		(net "M_F_DQS_DN<1>")
	)
	(arc
		(start 235.594398 -93.633036)
		(mid 235.308974 -93.716503)
		(end 235.100368 -93.928438)
		(width 0.0889)
		(layer "In11.Cu")
		(net "M_F_DQS_DN<1>")
	)
	(arc
		(start 235.100368 -93.928438)
		(mid 234.962707 -94.06981)
		(end 234.774232 -94.128336)
		(width 0.0889)
		(layer "In11.Cu")
		(net "M_F_DQS_DN<1>")
	)
	(arc
		(start 238.534448 -91.947238)
		(mid 238.394369 -92.089974)
		(end 238.202724 -92.147136)
		(width 0.0889)
		(layer "In11.Cu")
		(net "M_F_DQS_DN<1>")
	)
	(arc
		(start 239.392968 -91.451938)
		(mid 239.251285 -91.595742)
		(end 239.057434 -91.65209)
		(width 0.0889)
		(layer "In11.Cu")
		(net "M_F_DQS_DN<1>")
	)
	(arc
		(start 239.024668 -91.65209)
		(mid 238.741451 -91.736371)
		(end 238.534448 -91.947238)
		(width 0.0889)
		(layer "In11.Cu")
		(net "M_F_DQS_DN<1>")
	)
	(arc
		(start 237.307628 -92.64269)
		(mid 237.024411 -92.726971)
		(end 236.817408 -92.937838)
		(width 0.0889)
		(layer "In11.Cu")
		(net "M_F_DQS_DN<1>")
	)
	(arc
		(start 240.218976 -91.00439)
		(mid 240.086095 -91.113373)
		(end 239.919764 -91.156536)
		(width 0.0889)
		(layer "In11.Cu")
		(net "M_F_DQS_DN<1>")
	)
	(segment
		(start 238.049816 -152.932384)
		(end 237.631732 -153.350468)
		(width 0.1651)
		(layer "F.Cu")
		(net "M_F_DQS_DN<17>")
	)
	(segment
		(start 237.631732 -153.7716)
		(end 237.81766 -153.957528)
		(width 0.1651)
		(layer "F.Cu")
		(net "M_F_DQS_DN<17>")
	)
	(segment
		(start 237.357412 -154.45613)
		(end 237.168182 -154.2669)
		(width 0.1651)
		(layer "F.Cu")
		(net "M_F_DQS_DN<17>")
	)
	(segment
		(start 237.81766 -154.204162)
		(end 237.565692 -154.45613)
		(width 0.1651)
		(layer "F.Cu")
		(net "M_F_DQS_DN<17>")
	)
	(segment
		(start 238.049816 -152.278842)
		(end 238.049816 -152.932384)
		(width 0.1651)
		(layer "F.Cu")
		(net "M_F_DQS_DN<17>")
	)
	(segment
		(start 237.81766 -153.957528)
		(end 237.81766 -154.204162)
		(width 0.1651)
		(layer "F.Cu")
		(net "M_F_DQS_DN<17>")
	)
	(segment
		(start 246.485664 -83.32724)
		(end 245.914164 -83.32724)
		(width 0.1651)
		(layer "F.Cu")
		(net "M_F_DQS_DN<17>")
	)
	(segment
		(start 237.631732 -153.350468)
		(end 237.631732 -153.7716)
		(width 0.1651)
		(layer "F.Cu")
		(net "M_F_DQS_DN<17>")
	)
	(segment
		(start 237.565692 -154.45613)
		(end 237.357412 -154.45613)
		(width 0.1651)
		(layer "F.Cu")
		(net "M_F_DQS_DN<17>")
	)
	(segment
		(start 238.050324 -152.273)
		(end 238.049816 -152.278842)
		(width 0.1651)
		(layer "F.Cu")
		(net "M_F_DQS_DN<17>")
	)
	(segment
		(start 237.168182 -154.2669)
		(end 237.149132 -154.2669)
		(width 0.1651)
		(layer "F.Cu")
		(net "M_F_DQS_DN<17>")
	)
	(via
		(at 237.142528 -150.0886)
		(size 0.508)
		(drill 0.254)
		(layers "F.Cu" "B.Cu")
		(net "M_F_DQS_DN<17>")
	)
	(via
		(at 245.914164 -83.32724)
		(size 0.508)
		(drill 0.254)
		(layers "F.Cu" "B.Cu")
		(net "M_F_DQS_DN<17>")
	)
	(via
		(at 237.149132 -154.2669)
		(size 0.508)
		(drill 0.254)
		(layers "F.Cu" "B.Cu")
		(net "M_F_DQS_DN<17>")
	)
	(segment
		(start 238.05007 -151.421592)
		(end 237.606332 -150.977854)
		(width 0.1651)
		(layer "B.Cu")
		(net "M_F_DQS_DN<17>")
	)
	(segment
		(start 237.784132 -150.4442)
		(end 237.784132 -150.114)
		(width 0.1651)
		(layer "B.Cu")
		(net "M_F_DQS_DN<17>")
	)
	(segment
		(start 237.784132 -150.114)
		(end 237.564168 -149.894036)
		(width 0.1651)
		(layer "B.Cu")
		(net "M_F_DQS_DN<17>")
	)
	(segment
		(start 237.606332 -150.977854)
		(end 237.606332 -150.622)
		(width 0.1651)
		(layer "B.Cu")
		(net "M_F_DQS_DN<17>")
	)
	(segment
		(start 237.606332 -150.622)
		(end 237.784132 -150.4442)
		(width 0.1651)
		(layer "B.Cu")
		(net "M_F_DQS_DN<17>")
	)
	(segment
		(start 238.050324 -152.078436)
		(end 238.05007 -152.077928)
		(width 0.1651)
		(layer "B.Cu")
		(net "M_F_DQS_DN<17>")
	)
	(segment
		(start 237.337092 -149.894036)
		(end 237.142528 -150.0886)
		(width 0.1651)
		(layer "B.Cu")
		(net "M_F_DQS_DN<17>")
	)
	(segment
		(start 238.05007 -152.077928)
		(end 238.05007 -151.421592)
		(width 0.1651)
		(layer "B.Cu")
		(net "M_F_DQS_DN<17>")
	)
	(segment
		(start 237.564168 -149.894036)
		(end 237.337092 -149.894036)
		(width 0.1651)
		(layer "B.Cu")
		(net "M_F_DQS_DN<17>")
	)
	(segment
		(start 245.562628 -89.462102)
		(end 245.567454 -89.470738)
		(width 0.0889)
		(layer "In4.Cu")
		(net "M_F_DQS_DN<17>")
	)
	(segment
		(start 245.567454 -85.508338)
		(end 245.573804 -85.519006)
		(width 0.0889)
		(layer "In4.Cu")
		(net "M_F_DQS_DN<17>")
	)
	(segment
		(start 245.567454 -84.517738)
		(end 245.573804 -84.528406)
		(width 0.0889)
		(layer "In4.Cu")
		(net "M_F_DQS_DN<17>")
	)
	(segment
		(start 237.38332 -123.192286)
		(end 237.924848 -123.733814)
		(width 0.14224)
		(layer "In4.Cu")
		(net "M_F_DQS_DN<17>")
	)
	(segment
		(start 245.567454 -90.461338)
		(end 245.573804 -90.472006)
		(width 0.0889)
		(layer "In4.Cu")
		(net "M_F_DQS_DN<17>")
	)
	(segment
		(start 237.855506 -115.610132)
		(end 237.711996 -115.610132)
		(width 0.14224)
		(layer "In4.Cu")
		(net "M_F_DQS_DN<17>")
	)
	(segment
		(start 245.324122 -105.105454)
		(end 239.00892 -111.420656)
		(width 0.14224)
		(layer "In4.Cu")
		(net "M_F_DQS_DN<17>")
	)
	(segment
		(start 245.562628 -87.480902)
		(end 245.567454 -87.489538)
		(width 0.0889)
		(layer "In4.Cu")
		(net "M_F_DQS_DN<17>")
	)
	(segment
		(start 245.468648 -100.13823)
		(end 245.284752 -100.322126)
		(width 0.0889)
		(layer "In4.Cu")
		(net "M_F_DQS_DN<17>")
	)
	(segment
		(start 237.38332 -117.190012)
		(end 237.48492 -117.291612)
		(width 0.14224)
		(layer "In4.Cu")
		(net "M_F_DQS_DN<17>")
	)
	(segment
		(start 245.284752 -100.322126)
		(end 245.284752 -102.960678)
		(width 0.0889)
		(layer "In4.Cu")
		(net "M_F_DQS_DN<17>")
	)
	(segment
		(start 238.184436 -115.137692)
		(end 238.184436 -115.281202)
		(width 0.14224)
		(layer "In4.Cu")
		(net "M_F_DQS_DN<17>")
	)
	(segment
		(start 245.571264 -99.960176)
		(end 245.570756 -99.960938)
		(width 0.0889)
		(layer "In4.Cu")
		(net "M_F_DQS_DN<17>")
	)
	(segment
		(start 245.562628 -91.443302)
		(end 245.567454 -91.451938)
		(width 0.0889)
		(layer "In4.Cu")
		(net "M_F_DQS_DN<17>")
	)
	(segment
		(start 245.562628 -97.386902)
		(end 245.567454 -97.395538)
		(width 0.0889)
		(layer "In4.Cu")
		(net "M_F_DQS_DN<17>")
	)
	(segment
		(start 245.562628 -96.396302)
		(end 245.567454 -96.404938)
		(width 0.0889)
		(layer "In4.Cu")
		(net "M_F_DQS_DN<17>")
	)
	(segment
		(start 238.184436 -115.281202)
		(end 237.855506 -115.610132)
		(width 0.14224)
		(layer "In4.Cu")
		(net "M_F_DQS_DN<17>")
	)
	(segment
		(start 245.567454 -83.527138)
		(end 245.573804 -83.537806)
		(width 0.0889)
		(layer "In4.Cu")
		(net "M_F_DQS_DN<17>")
	)
	(segment
		(start 245.284752 -102.960678)
		(end 245.324122 -103.000048)
		(width 0.0889)
		(layer "In4.Cu")
		(net "M_F_DQS_DN<17>")
	)
	(segment
		(start 245.562628 -98.377502)
		(end 245.567454 -98.386138)
		(width 0.0889)
		(layer "In4.Cu")
		(net "M_F_DQS_DN<17>")
	)
	(segment
		(start 245.324122 -103.000048)
		(end 245.324122 -105.105454)
		(width 0.14224)
		(layer "In4.Cu")
		(net "M_F_DQS_DN<17>")
	)
	(segment
		(start 245.570756 -99.960938)
		(end 245.468648 -100.13823)
		(width 0.0889)
		(layer "In4.Cu")
		(net "M_F_DQS_DN<17>")
	)
	(segment
		(start 245.567454 -87.489538)
		(end 245.573804 -87.500206)
		(width 0.0889)
		(layer "In4.Cu")
		(net "M_F_DQS_DN<17>")
	)
	(segment
		(start 237.924848 -149.30628)
		(end 237.142528 -150.0886)
		(width 0.14224)
		(layer "In4.Cu")
		(net "M_F_DQS_DN<17>")
	)
	(segment
		(start 245.567454 -91.451938)
		(end 245.573804 -91.462606)
		(width 0.0889)
		(layer "In4.Cu")
		(net "M_F_DQS_DN<17>")
	)
	(segment
		(start 245.567454 -97.395538)
		(end 245.573804 -97.406206)
		(width 0.0889)
		(layer "In4.Cu")
		(net "M_F_DQS_DN<17>")
	)
	(segment
		(start 237.38332 -117.858032)
		(end 237.38332 -123.192286)
		(width 0.14224)
		(layer "In4.Cu")
		(net "M_F_DQS_DN<17>")
	)
	(segment
		(start 239.00892 -111.420656)
		(end 239.00892 -114.313208)
		(width 0.14224)
		(layer "In4.Cu")
		(net "M_F_DQS_DN<17>")
	)
	(segment
		(start 245.567454 -98.386138)
		(end 245.573804 -98.396806)
		(width 0.0889)
		(layer "In4.Cu")
		(net "M_F_DQS_DN<17>")
	)
	(segment
		(start 245.567454 -92.442538)
		(end 245.573804 -92.453206)
		(width 0.0889)
		(layer "In4.Cu")
		(net "M_F_DQS_DN<17>")
	)
	(segment
		(start 245.567454 -95.414338)
		(end 245.573804 -95.425006)
		(width 0.0889)
		(layer "In4.Cu")
		(net "M_F_DQS_DN<17>")
	)
	(segment
		(start 245.562628 -95.405702)
		(end 245.567454 -95.414338)
		(width 0.0889)
		(layer "In4.Cu")
		(net "M_F_DQS_DN<17>")
	)
	(segment
		(start 239.00892 -114.313208)
		(end 238.184436 -115.137692)
		(width 0.14224)
		(layer "In4.Cu")
		(net "M_F_DQS_DN<17>")
	)
	(segment
		(start 237.38332 -115.938808)
		(end 237.38332 -117.190012)
		(width 0.14224)
		(layer "In4.Cu")
		(net "M_F_DQS_DN<17>")
	)
	(segment
		(start 245.914164 -83.32724)
		(end 245.914164 -82.989166)
		(width 0.0889)
		(layer "In4.Cu")
		(net "M_F_DQS_DN<17>")
	)
	(segment
		(start 245.562628 -90.452702)
		(end 245.567454 -90.461338)
		(width 0.0889)
		(layer "In4.Cu")
		(net "M_F_DQS_DN<17>")
	)
	(segment
		(start 245.562628 -88.471502)
		(end 245.567454 -88.480138)
		(width 0.0889)
		(layer "In4.Cu")
		(net "M_F_DQS_DN<17>")
	)
	(segment
		(start 237.711996 -115.610132)
		(end 237.38332 -115.938808)
		(width 0.14224)
		(layer "In4.Cu")
		(net "M_F_DQS_DN<17>")
	)
	(segment
		(start 237.48492 -117.756432)
		(end 237.38332 -117.858032)
		(width 0.14224)
		(layer "In4.Cu")
		(net "M_F_DQS_DN<17>")
	)
	(segment
		(start 245.562628 -86.490302)
		(end 245.567454 -86.498938)
		(width 0.0889)
		(layer "In4.Cu")
		(net "M_F_DQS_DN<17>")
	)
	(segment
		(start 245.562628 -85.499702)
		(end 245.567454 -85.508338)
		(width 0.0889)
		(layer "In4.Cu")
		(net "M_F_DQS_DN<17>")
	)
	(segment
		(start 245.914164 -82.989166)
		(end 245.856252 -82.931254)
		(width 0.0889)
		(layer "In4.Cu")
		(net "M_F_DQS_DN<17>")
	)
	(segment
		(start 245.562628 -84.509102)
		(end 245.567454 -84.517738)
		(width 0.0889)
		(layer "In4.Cu")
		(net "M_F_DQS_DN<17>")
	)
	(segment
		(start 245.567454 -96.404938)
		(end 245.573804 -96.415606)
		(width 0.0889)
		(layer "In4.Cu")
		(net "M_F_DQS_DN<17>")
	)
	(segment
		(start 245.573804 -94.01302)
		(end 245.567454 -94.023688)
		(width 0.0889)
		(layer "In4.Cu")
		(net "M_F_DQS_DN<17>")
	)
	(segment
		(start 237.924848 -123.733814)
		(end 237.924848 -149.30628)
		(width 0.14224)
		(layer "In4.Cu")
		(net "M_F_DQS_DN<17>")
	)
	(segment
		(start 245.567454 -89.470738)
		(end 245.573804 -89.481406)
		(width 0.0889)
		(layer "In4.Cu")
		(net "M_F_DQS_DN<17>")
	)
	(segment
		(start 245.562628 -93.424502)
		(end 245.567454 -93.433138)
		(width 0.0889)
		(layer "In4.Cu")
		(net "M_F_DQS_DN<17>")
	)
	(segment
		(start 245.567454 -86.498938)
		(end 245.573804 -86.509606)
		(width 0.0889)
		(layer "In4.Cu")
		(net "M_F_DQS_DN<17>")
	)
	(segment
		(start 245.562628 -92.433902)
		(end 245.567454 -92.442538)
		(width 0.0889)
		(layer "In4.Cu")
		(net "M_F_DQS_DN<17>")
	)
	(segment
		(start 237.48492 -117.291612)
		(end 237.48492 -117.756432)
		(width 0.14224)
		(layer "In4.Cu")
		(net "M_F_DQS_DN<17>")
	)
	(segment
		(start 245.567454 -88.480138)
		(end 245.573804 -88.490806)
		(width 0.0889)
		(layer "In4.Cu")
		(net "M_F_DQS_DN<17>")
	)
	(arc
		(start 245.573804 -83.537806)
		(mid 245.646602 -83.828569)
		(end 245.567454 -84.117688)
		(width 0.0889)
		(layer "In4.Cu")
		(net "M_F_DQS_DN<17>")
	)
	(arc
		(start 245.573804 -97.406206)
		(mid 245.646602 -97.696969)
		(end 245.567454 -97.986088)
		(width 0.0889)
		(layer "In4.Cu")
		(net "M_F_DQS_DN<17>")
	)
	(arc
		(start 245.567454 -89.070688)
		(mid 245.513984 -89.265751)
		(end 245.562628 -89.462102)
		(width 0.0889)
		(layer "In4.Cu")
		(net "M_F_DQS_DN<17>")
	)
	(arc
		(start 245.567454 -87.089488)
		(mid 245.513984 -87.284551)
		(end 245.562628 -87.480902)
		(width 0.0889)
		(layer "In4.Cu")
		(net "M_F_DQS_DN<17>")
	)
	(arc
		(start 245.573804 -92.453206)
		(mid 245.646602 -92.743969)
		(end 245.567454 -93.033088)
		(width 0.0889)
		(layer "In4.Cu")
		(net "M_F_DQS_DN<17>")
	)
	(arc
		(start 245.567454 -98.976688)
		(mid 245.513828 -99.17684)
		(end 245.567454 -99.376992)
		(width 0.0889)
		(layer "In4.Cu")
		(net "M_F_DQS_DN<17>")
	)
	(arc
		(start 245.567454 -84.117688)
		(mid 245.513984 -84.312751)
		(end 245.562628 -84.509102)
		(width 0.0889)
		(layer "In4.Cu")
		(net "M_F_DQS_DN<17>")
	)
	(arc
		(start 245.573804 -96.415606)
		(mid 245.646602 -96.706369)
		(end 245.567454 -96.995488)
		(width 0.0889)
		(layer "In4.Cu")
		(net "M_F_DQS_DN<17>")
	)
	(arc
		(start 245.567454 -94.023688)
		(mid 245.513955 -94.223586)
		(end 245.567454 -94.423484)
		(width 0.0889)
		(layer "In4.Cu")
		(net "M_F_DQS_DN<17>")
	)
	(arc
		(start 245.573804 -90.472006)
		(mid 245.646602 -90.762769)
		(end 245.567454 -91.051888)
		(width 0.0889)
		(layer "In4.Cu")
		(net "M_F_DQS_DN<17>")
	)
	(arc
		(start 245.567454 -96.004888)
		(mid 245.513984 -96.199951)
		(end 245.562628 -96.396302)
		(width 0.0889)
		(layer "In4.Cu")
		(net "M_F_DQS_DN<17>")
	)
	(arc
		(start 245.573804 -95.425006)
		(mid 245.646602 -95.715769)
		(end 245.567454 -96.004888)
		(width 0.0889)
		(layer "In4.Cu")
		(net "M_F_DQS_DN<17>")
	)
	(arc
		(start 245.573804 -86.509606)
		(mid 245.646602 -86.800369)
		(end 245.567454 -87.089488)
		(width 0.0889)
		(layer "In4.Cu")
		(net "M_F_DQS_DN<17>")
	)
	(arc
		(start 245.567454 -92.042488)
		(mid 245.513984 -92.237551)
		(end 245.562628 -92.433902)
		(width 0.0889)
		(layer "In4.Cu")
		(net "M_F_DQS_DN<17>")
	)
	(arc
		(start 245.567454 -96.995488)
		(mid 245.513984 -97.190551)
		(end 245.562628 -97.386902)
		(width 0.0889)
		(layer "In4.Cu")
		(net "M_F_DQS_DN<17>")
	)
	(arc
		(start 245.573804 -91.462606)
		(mid 245.646602 -91.753369)
		(end 245.567454 -92.042488)
		(width 0.0889)
		(layer "In4.Cu")
		(net "M_F_DQS_DN<17>")
	)
	(arc
		(start 245.567454 -85.108288)
		(mid 245.513984 -85.303351)
		(end 245.562628 -85.499702)
		(width 0.0889)
		(layer "In4.Cu")
		(net "M_F_DQS_DN<17>")
	)
	(arc
		(start 245.567454 -97.986088)
		(mid 245.513984 -98.181151)
		(end 245.562628 -98.377502)
		(width 0.0889)
		(layer "In4.Cu")
		(net "M_F_DQS_DN<17>")
	)
	(arc
		(start 245.573804 -85.519006)
		(mid 245.646602 -85.809769)
		(end 245.567454 -86.098888)
		(width 0.0889)
		(layer "In4.Cu")
		(net "M_F_DQS_DN<17>")
	)
	(arc
		(start 245.567454 -86.098888)
		(mid 245.513984 -86.293951)
		(end 245.562628 -86.490302)
		(width 0.0889)
		(layer "In4.Cu")
		(net "M_F_DQS_DN<17>")
	)
	(arc
		(start 245.573804 -87.500206)
		(mid 245.646602 -87.790969)
		(end 245.567454 -88.080088)
		(width 0.0889)
		(layer "In4.Cu")
		(net "M_F_DQS_DN<17>")
	)
	(arc
		(start 245.567454 -95.014288)
		(mid 245.513984 -95.209351)
		(end 245.562628 -95.405702)
		(width 0.0889)
		(layer "In4.Cu")
		(net "M_F_DQS_DN<17>")
	)
	(arc
		(start 245.567454 -90.061288)
		(mid 245.513984 -90.256351)
		(end 245.562628 -90.452702)
		(width 0.0889)
		(layer "In4.Cu")
		(net "M_F_DQS_DN<17>")
	)
	(arc
		(start 245.567454 -99.376992)
		(mid 245.646319 -99.668074)
		(end 245.571264 -99.960176)
		(width 0.0889)
		(layer "In4.Cu")
		(net "M_F_DQS_DN<17>")
	)
	(arc
		(start 245.856252 -82.931254)
		(mid 245.554031 -83.152704)
		(end 245.567454 -83.527138)
		(width 0.0889)
		(layer "In4.Cu")
		(net "M_F_DQS_DN<17>")
	)
	(arc
		(start 245.573804 -84.528406)
		(mid 245.646602 -84.819169)
		(end 245.567454 -85.108288)
		(width 0.0889)
		(layer "In4.Cu")
		(net "M_F_DQS_DN<17>")
	)
	(arc
		(start 245.567454 -91.051888)
		(mid 245.513984 -91.246951)
		(end 245.562628 -91.443302)
		(width 0.0889)
		(layer "In4.Cu")
		(net "M_F_DQS_DN<17>")
	)
	(arc
		(start 245.573804 -98.396806)
		(mid 245.646602 -98.687569)
		(end 245.567454 -98.976688)
		(width 0.0889)
		(layer "In4.Cu")
		(net "M_F_DQS_DN<17>")
	)
	(arc
		(start 245.567454 -93.433138)
		(mid 245.646676 -93.722256)
		(end 245.573804 -94.01302)
		(width 0.0889)
		(layer "In4.Cu")
		(net "M_F_DQS_DN<17>")
	)
	(arc
		(start 245.567454 -88.080088)
		(mid 245.513984 -88.275151)
		(end 245.562628 -88.471502)
		(width 0.0889)
		(layer "In4.Cu")
		(net "M_F_DQS_DN<17>")
	)
	(arc
		(start 245.573804 -88.490806)
		(mid 245.646602 -88.781569)
		(end 245.567454 -89.070688)
		(width 0.0889)
		(layer "In4.Cu")
		(net "M_F_DQS_DN<17>")
	)
	(arc
		(start 245.567454 -93.033088)
		(mid 245.513984 -93.228151)
		(end 245.562628 -93.424502)
		(width 0.0889)
		(layer "In4.Cu")
		(net "M_F_DQS_DN<17>")
	)
	(arc
		(start 245.573804 -89.481406)
		(mid 245.646602 -89.772169)
		(end 245.567454 -90.061288)
		(width 0.0889)
		(layer "In4.Cu")
		(net "M_F_DQS_DN<17>")
	)
	(arc
		(start 245.567454 -94.423484)
		(mid 245.646585 -94.718886)
		(end 245.567454 -95.014288)
		(width 0.0889)
		(layer "In4.Cu")
		(net "M_F_DQS_DN<17>")
	)
	(segment
		(start 236.906816 -151.35606)
		(end 237.056676 -151.2062)
		(width 0.14224)
		(layer "In11.Cu")
		(net "M_F_DQS_DN<17>")
	)
	(segment
		(start 237.297976 -151.2062)
		(end 237.577376 -150.9268)
		(width 0.14224)
		(layer "In11.Cu")
		(net "M_F_DQS_DN<17>")
	)
	(segment
		(start 236.906816 -152.924764)
		(end 236.906816 -152.63876)
		(width 0.14224)
		(layer "In11.Cu")
		(net "M_F_DQS_DN<17>")
	)
	(segment
		(start 237.59287 -153.823162)
		(end 237.59287 -153.285698)
		(width 0.14224)
		(layer "In11.Cu")
		(net "M_F_DQS_DN<17>")
	)
	(segment
		(start 237.577376 -150.9268)
		(end 237.577376 -150.523448)
		(width 0.14224)
		(layer "In11.Cu")
		(net "M_F_DQS_DN<17>")
	)
	(segment
		(start 237.177072 -151.83612)
		(end 237.038896 -151.83612)
		(width 0.14224)
		(layer "In11.Cu")
		(net "M_F_DQS_DN<17>")
	)
	(segment
		(start 237.59287 -153.285698)
		(end 237.38967 -153.082498)
		(width 0.14224)
		(layer "In11.Cu")
		(net "M_F_DQS_DN<17>")
	)
	(segment
		(start 237.149132 -154.2669)
		(end 237.59287 -153.823162)
		(width 0.14224)
		(layer "In11.Cu")
		(net "M_F_DQS_DN<17>")
	)
	(segment
		(start 237.046516 -152.49906)
		(end 237.170468 -152.49906)
		(width 0.14224)
		(layer "In11.Cu")
		(net "M_F_DQS_DN<17>")
	)
	(segment
		(start 237.056676 -151.2062)
		(end 237.297976 -151.2062)
		(width 0.14224)
		(layer "In11.Cu")
		(net "M_F_DQS_DN<17>")
	)
	(segment
		(start 236.906816 -152.63876)
		(end 237.046516 -152.49906)
		(width 0.14224)
		(layer "In11.Cu")
		(net "M_F_DQS_DN<17>")
	)
	(segment
		(start 237.32871 -151.987758)
		(end 237.177072 -151.83612)
		(width 0.14224)
		(layer "In11.Cu")
		(net "M_F_DQS_DN<17>")
	)
	(segment
		(start 237.170468 -152.49906)
		(end 237.32871 -152.340818)
		(width 0.14224)
		(layer "In11.Cu")
		(net "M_F_DQS_DN<17>")
	)
	(segment
		(start 237.038896 -151.83612)
		(end 236.906816 -151.70404)
		(width 0.14224)
		(layer "In11.Cu")
		(net "M_F_DQS_DN<17>")
	)
	(segment
		(start 237.32871 -152.340818)
		(end 237.32871 -151.987758)
		(width 0.14224)
		(layer "In11.Cu")
		(net "M_F_DQS_DN<17>")
	)
	(segment
		(start 237.06455 -153.082498)
		(end 236.906816 -152.924764)
		(width 0.14224)
		(layer "In11.Cu")
		(net "M_F_DQS_DN<17>")
	)
	(segment
		(start 236.906816 -151.70404)
		(end 236.906816 -151.35606)
		(width 0.14224)
		(layer "In11.Cu")
		(net "M_F_DQS_DN<17>")
	)
	(segment
		(start 237.577376 -150.523448)
		(end 237.142528 -150.0886)
		(width 0.14224)
		(layer "In11.Cu")
		(net "M_F_DQS_DN<17>")
	)
	(segment
		(start 237.38967 -153.082498)
		(end 237.06455 -153.082498)
		(width 0.14224)
		(layer "In11.Cu")
		(net "M_F_DQS_DN<17>")
	)
	(segment
		(start 311.999884 -152.278842)
		(end 311.999884 -152.932384)
		(width 0.1651)
		(layer "F.Cu")
		(net "M_F_DQS_DN<16>")
	)
	(segment
		(start 311.5818 -153.7716)
		(end 311.767728 -153.957528)
		(width 0.1651)
		(layer "F.Cu")
		(net "M_F_DQS_DN<16>")
	)
	(segment
		(start 311.51576 -154.45613)
		(end 311.30748 -154.45613)
		(width 0.1651)
		(layer "F.Cu")
		(net "M_F_DQS_DN<16>")
	)
	(segment
		(start 311.11825 -154.2669)
		(end 311.0992 -154.2669)
		(width 0.1651)
		(layer "F.Cu")
		(net "M_F_DQS_DN<16>")
	)
	(segment
		(start 311.767728 -154.204162)
		(end 311.51576 -154.45613)
		(width 0.1651)
		(layer "F.Cu")
		(net "M_F_DQS_DN<16>")
	)
	(segment
		(start 311.5818 -153.350468)
		(end 311.5818 -153.7716)
		(width 0.1651)
		(layer "F.Cu")
		(net "M_F_DQS_DN<16>")
	)
	(segment
		(start 312.000392 -152.273)
		(end 311.999884 -152.278842)
		(width 0.1651)
		(layer "F.Cu")
		(net "M_F_DQS_DN<16>")
	)
	(segment
		(start 283.212794 -90.575384)
		(end 283.784294 -90.575384)
		(width 0.1651)
		(layer "F.Cu")
		(net "M_F_DQS_DN<16>")
	)
	(segment
		(start 311.30748 -154.45613)
		(end 311.11825 -154.2669)
		(width 0.1651)
		(layer "F.Cu")
		(net "M_F_DQS_DN<16>")
	)
	(segment
		(start 311.999884 -152.932384)
		(end 311.5818 -153.350468)
		(width 0.1651)
		(layer "F.Cu")
		(net "M_F_DQS_DN<16>")
	)
	(segment
		(start 311.767728 -153.957528)
		(end 311.767728 -154.204162)
		(width 0.1651)
		(layer "F.Cu")
		(net "M_F_DQS_DN<16>")
	)
	(via
		(at 283.784294 -90.575384)
		(size 0.508)
		(drill 0.254)
		(layers "F.Cu" "B.Cu")
		(net "M_F_DQS_DN<16>")
	)
	(via
		(at 311.0992 -154.2669)
		(size 0.508)
		(drill 0.254)
		(layers "F.Cu" "B.Cu")
		(net "M_F_DQS_DN<16>")
	)
	(via
		(at 311.092596 -150.0886)
		(size 0.508)
		(drill 0.254)
		(layers "F.Cu" "B.Cu")
		(net "M_F_DQS_DN<16>")
	)
	(segment
		(start 312.000392 -152.078436)
		(end 312.000392 -151.421846)
		(width 0.1651)
		(layer "B.Cu")
		(net "M_F_DQS_DN<16>")
	)
	(segment
		(start 312.000392 -151.421846)
		(end 311.5564 -150.977854)
		(width 0.1651)
		(layer "B.Cu")
		(net "M_F_DQS_DN<16>")
	)
	(segment
		(start 311.514236 -149.894036)
		(end 311.28716 -149.894036)
		(width 0.1651)
		(layer "B.Cu")
		(net "M_F_DQS_DN<16>")
	)
	(segment
		(start 311.5564 -150.977854)
		(end 311.5564 -150.622)
		(width 0.1651)
		(layer "B.Cu")
		(net "M_F_DQS_DN<16>")
	)
	(segment
		(start 311.5564 -150.622)
		(end 311.7342 -150.4442)
		(width 0.1651)
		(layer "B.Cu")
		(net "M_F_DQS_DN<16>")
	)
	(segment
		(start 311.28716 -149.894036)
		(end 311.092596 -150.0886)
		(width 0.1651)
		(layer "B.Cu")
		(net "M_F_DQS_DN<16>")
	)
	(segment
		(start 311.7342 -150.4442)
		(end 311.7342 -150.114)
		(width 0.1651)
		(layer "B.Cu")
		(net "M_F_DQS_DN<16>")
	)
	(segment
		(start 311.7342 -150.114)
		(end 311.514236 -149.894036)
		(width 0.1651)
		(layer "B.Cu")
		(net "M_F_DQS_DN<16>")
	)
	(segment
		(start 290.017454 -104.463342)
		(end 290.056824 -104.502712)
		(width 0.0889)
		(layer "In11.Cu")
		(net "M_F_DQS_DN<16>")
	)
	(segment
		(start 297.974258 -111.097822)
		(end 297.974258 -112.69218)
		(width 0.14224)
		(layer "In11.Cu")
		(net "M_F_DQS_DN<16>")
	)
	(segment
		(start 289.854894 -103.358188)
		(end 290.017454 -103.520748)
		(width 0.0889)
		(layer "In11.Cu")
		(net "M_F_DQS_DN<16>")
	)
	(segment
		(start 283.437584 -92.356686)
		(end 283.432758 -92.365322)
		(width 0.0889)
		(layer "In11.Cu")
		(net "M_F_DQS_DN<16>")
	)
	(segment
		(start 289.782504 -103.358188)
		(end 289.854894 -103.358188)
		(width 0.0889)
		(layer "In11.Cu")
		(net "M_F_DQS_DN<16>")
	)
	(segment
		(start 311.143904 -151.83612)
		(end 311.298844 -151.99106)
		(width 0.14224)
		(layer "In11.Cu")
		(net "M_F_DQS_DN<16>")
	)
	(segment
		(start 311.298844 -152.34412)
		(end 311.143904 -152.49906)
		(width 0.14224)
		(layer "In11.Cu")
		(net "M_F_DQS_DN<16>")
	)
	(segment
		(start 286.013144 -95.232982)
		(end 286.016446 -95.238824)
		(width 0.0889)
		(layer "In11.Cu")
		(net "M_F_DQS_DN<16>")
	)
	(segment
		(start 288.58845 -99.290886)
		(end 288.583624 -99.299522)
		(width 0.0889)
		(layer "In11.Cu")
		(net "M_F_DQS_DN<16>")
	)
	(segment
		(start 288.58845 -101.272086)
		(end 288.583624 -101.280722)
		(width 0.0889)
		(layer "In11.Cu")
		(net "M_F_DQS_DN<16>")
	)
	(segment
		(start 288.58845 -97.309686)
		(end 288.583624 -97.318322)
		(width 0.0889)
		(layer "In11.Cu")
		(net "M_F_DQS_DN<16>")
	)
	(segment
		(start 292.72738 -107.45978)
		(end 294.336216 -107.45978)
		(width 0.14224)
		(layer "In11.Cu")
		(net "M_F_DQS_DN<16>")
	)
	(segment
		(start 311.248044 -151.2062)
		(end 311.006744 -151.2062)
		(width 0.14224)
		(layer "In11.Cu")
		(net "M_F_DQS_DN<16>")
	)
	(segment
		(start 288.920174 -102.862634)
		(end 288.95294 -102.862634)
		(width 0.0889)
		(layer "In11.Cu")
		(net "M_F_DQS_DN<16>")
	)
	(segment
		(start 311.344564 -153.162)
		(end 311.53227 -153.349706)
		(width 0.14224)
		(layer "In11.Cu")
		(net "M_F_DQS_DN<16>")
	)
	(segment
		(start 298.266358 -112.98428)
		(end 301.637192 -112.98428)
		(width 0.14224)
		(layer "In11.Cu")
		(net "M_F_DQS_DN<16>")
	)
	(segment
		(start 311.874916 -149.30628)
		(end 311.092596 -150.0886)
		(width 0.14224)
		(layer "In11.Cu")
		(net "M_F_DQS_DN<16>")
	)
	(segment
		(start 283.443934 -93.336618)
		(end 283.437584 -93.347286)
		(width 0.0889)
		(layer "In11.Cu")
		(net "M_F_DQS_DN<16>")
	)
	(segment
		(start 283.437584 -91.366086)
		(end 283.432758 -91.374722)
		(width 0.0889)
		(layer "In11.Cu")
		(net "M_F_DQS_DN<16>")
	)
	(segment
		(start 311.019444 -153.162)
		(end 311.344564 -153.162)
		(width 0.14224)
		(layer "In11.Cu")
		(net "M_F_DQS_DN<16>")
	)
	(segment
		(start 311.527444 -150.523448)
		(end 311.527444 -150.9268)
		(width 0.14224)
		(layer "In11.Cu")
		(net "M_F_DQS_DN<16>")
	)
	(segment
		(start 290.056824 -104.789224)
		(end 292.72738 -107.45978)
		(width 0.14224)
		(layer "In11.Cu")
		(net "M_F_DQS_DN<16>")
	)
	(segment
		(start 288.5948 -97.299018)
		(end 288.58845 -97.309686)
		(width 0.0889)
		(layer "In11.Cu")
		(net "M_F_DQS_DN<16>")
	)
	(segment
		(start 284.62478 -94.442534)
		(end 284.660594 -94.442534)
		(width 0.0889)
		(layer "In11.Cu")
		(net "M_F_DQS_DN<16>")
	)
	(segment
		(start 311.298844 -151.99106)
		(end 311.298844 -152.34412)
		(width 0.14224)
		(layer "In11.Cu")
		(net "M_F_DQS_DN<16>")
	)
	(segment
		(start 294.336216 -107.45978)
		(end 297.974258 -111.097822)
		(width 0.14224)
		(layer "In11.Cu")
		(net "M_F_DQS_DN<16>")
	)
	(segment
		(start 283.769308 -93.947234)
		(end 283.797248 -93.947234)
		(width 0.0889)
		(layer "In11.Cu")
		(net "M_F_DQS_DN<16>")
	)
	(segment
		(start 286.3596 -95.433134)
		(end 286.372554 -95.433134)
		(width 0.0889)
		(layer "In11.Cu")
		(net "M_F_DQS_DN<16>")
	)
	(segment
		(start 311.53227 -153.349706)
		(end 311.53227 -153.83383)
		(width 0.14224)
		(layer "In11.Cu")
		(net "M_F_DQS_DN<16>")
	)
	(segment
		(start 288.5948 -98.289618)
		(end 288.58845 -98.300286)
		(width 0.0889)
		(layer "In11.Cu")
		(net "M_F_DQS_DN<16>")
	)
	(segment
		(start 283.784294 -90.575384)
		(end 283.784294 -90.23731)
		(width 0.0889)
		(layer "In11.Cu")
		(net "M_F_DQS_DN<16>")
	)
	(segment
		(start 288.065464 -96.423988)
		(end 288.09823 -96.423988)
		(width 0.0889)
		(layer "In11.Cu")
		(net "M_F_DQS_DN<16>")
	)
	(segment
		(start 311.874916 -123.222004)
		(end 311.874916 -149.30628)
		(width 0.14224)
		(layer "In11.Cu")
		(net "M_F_DQS_DN<16>")
	)
	(segment
		(start 283.443934 -92.346018)
		(end 283.437584 -92.356686)
		(width 0.0889)
		(layer "In11.Cu")
		(net "M_F_DQS_DN<16>")
	)
	(segment
		(start 290.056824 -104.52481)
		(end 290.056824 -104.789224)
		(width 0.14224)
		(layer "In11.Cu")
		(net "M_F_DQS_DN<16>")
	)
	(segment
		(start 310.856884 -151.70404)
		(end 310.988964 -151.83612)
		(width 0.14224)
		(layer "In11.Cu")
		(net "M_F_DQS_DN<16>")
	)
	(segment
		(start 288.5948 -102.252018)
		(end 288.58845 -102.262686)
		(width 0.0889)
		(layer "In11.Cu")
		(net "M_F_DQS_DN<16>")
	)
	(segment
		(start 283.784294 -90.23731)
		(end 283.726382 -90.179398)
		(width 0.0889)
		(layer "In11.Cu")
		(net "M_F_DQS_DN<16>")
	)
	(segment
		(start 311.006744 -151.2062)
		(end 310.856884 -151.35606)
		(width 0.14224)
		(layer "In11.Cu")
		(net "M_F_DQS_DN<16>")
	)
	(segment
		(start 283.437584 -93.347286)
		(end 283.432758 -93.355922)
		(width 0.0889)
		(layer "In11.Cu")
		(net "M_F_DQS_DN<16>")
	)
	(segment
		(start 310.988964 -151.83612)
		(end 311.143904 -151.83612)
		(width 0.14224)
		(layer "In11.Cu")
		(net "M_F_DQS_DN<16>")
	)
	(segment
		(start 310.856884 -152.63876)
		(end 310.856884 -152.99944)
		(width 0.14224)
		(layer "In11.Cu")
		(net "M_F_DQS_DN<16>")
	)
	(segment
		(start 301.637192 -112.98428)
		(end 311.874916 -123.222004)
		(width 0.14224)
		(layer "In11.Cu")
		(net "M_F_DQS_DN<16>")
	)
	(segment
		(start 311.53227 -153.83383)
		(end 311.0992 -154.2669)
		(width 0.14224)
		(layer "In11.Cu")
		(net "M_F_DQS_DN<16>")
	)
	(segment
		(start 310.856884 -152.99944)
		(end 311.019444 -153.162)
		(width 0.14224)
		(layer "In11.Cu")
		(net "M_F_DQS_DN<16>")
	)
	(segment
		(start 283.443934 -91.355418)
		(end 283.437584 -91.366086)
		(width 0.0889)
		(layer "In11.Cu")
		(net "M_F_DQS_DN<16>")
	)
	(segment
		(start 297.974258 -112.69218)
		(end 298.266358 -112.98428)
		(width 0.14224)
		(layer "In11.Cu")
		(net "M_F_DQS_DN<16>")
	)
	(segment
		(start 288.5948 -99.280218)
		(end 288.58845 -99.290886)
		(width 0.0889)
		(layer "In11.Cu")
		(net "M_F_DQS_DN<16>")
	)
	(segment
		(start 288.58845 -98.300286)
		(end 288.583624 -98.308922)
		(width 0.0889)
		(layer "In11.Cu")
		(net "M_F_DQS_DN<16>")
	)
	(segment
		(start 311.092596 -150.0886)
		(end 311.527444 -150.523448)
		(width 0.14224)
		(layer "In11.Cu")
		(net "M_F_DQS_DN<16>")
	)
	(segment
		(start 310.856884 -151.35606)
		(end 310.856884 -151.70404)
		(width 0.14224)
		(layer "In11.Cu")
		(net "M_F_DQS_DN<16>")
	)
	(segment
		(start 285.4833 -94.937834)
		(end 285.522924 -94.937834)
		(width 0.0889)
		(layer "In11.Cu")
		(net "M_F_DQS_DN<16>")
	)
	(segment
		(start 287.203134 -95.928434)
		(end 287.2359 -95.928434)
		(width 0.0889)
		(layer "In11.Cu")
		(net "M_F_DQS_DN<16>")
	)
	(segment
		(start 310.996584 -152.49906)
		(end 310.856884 -152.63876)
		(width 0.14224)
		(layer "In11.Cu")
		(net "M_F_DQS_DN<16>")
	)
	(segment
		(start 288.58845 -102.262686)
		(end 288.583624 -102.271322)
		(width 0.0889)
		(layer "In11.Cu")
		(net "M_F_DQS_DN<16>")
	)
	(segment
		(start 311.143904 -152.49906)
		(end 310.996584 -152.49906)
		(width 0.14224)
		(layer "In11.Cu")
		(net "M_F_DQS_DN<16>")
	)
	(segment
		(start 290.056824 -104.502712)
		(end 290.056824 -104.52481)
		(width 0.0889)
		(layer "In11.Cu")
		(net "M_F_DQS_DN<16>")
	)
	(segment
		(start 311.527444 -150.9268)
		(end 311.248044 -151.2062)
		(width 0.14224)
		(layer "In11.Cu")
		(net "M_F_DQS_DN<16>")
	)
	(segment
		(start 290.017454 -103.520748)
		(end 290.017454 -104.463342)
		(width 0.0889)
		(layer "In11.Cu")
		(net "M_F_DQS_DN<16>")
	)
	(segment
		(start 288.5948 -101.261418)
		(end 288.58845 -101.272086)
		(width 0.0889)
		(layer "In11.Cu")
		(net "M_F_DQS_DN<16>")
	)
	(arc
		(start 288.09823 -96.423988)
		(mid 288.59062 -96.722921)
		(end 288.5948 -97.299018)
		(width 0.0889)
		(layer "In11.Cu")
		(net "M_F_DQS_DN<16>")
	)
	(arc
		(start 287.72993 -96.223836)
		(mid 287.871613 -96.36764)
		(end 288.065464 -96.423988)
		(width 0.0889)
		(layer "In11.Cu")
		(net "M_F_DQS_DN<16>")
	)
	(arc
		(start 288.58845 -100.681536)
		(mid 288.667672 -100.970654)
		(end 288.5948 -101.261418)
		(width 0.0889)
		(layer "In11.Cu")
		(net "M_F_DQS_DN<16>")
	)
	(arc
		(start 287.2359 -95.928434)
		(mid 287.521324 -96.011901)
		(end 287.72993 -96.223836)
		(width 0.0889)
		(layer "In11.Cu")
		(net "M_F_DQS_DN<16>")
	)
	(arc
		(start 283.437584 -91.766136)
		(mid 283.516806 -92.055254)
		(end 283.443934 -92.346018)
		(width 0.0889)
		(layer "In11.Cu")
		(net "M_F_DQS_DN<16>")
	)
	(arc
		(start 286.87141 -95.728536)
		(mid 287.011489 -95.871272)
		(end 287.203134 -95.928434)
		(width 0.0889)
		(layer "In11.Cu")
		(net "M_F_DQS_DN<16>")
	)
	(arc
		(start 288.95294 -102.862634)
		(mid 289.238364 -102.946101)
		(end 289.44697 -103.158036)
		(width 0.0889)
		(layer "In11.Cu")
		(net "M_F_DQS_DN<16>")
	)
	(arc
		(start 288.583624 -101.280722)
		(mid 288.534869 -101.477074)
		(end 288.58845 -101.672136)
		(width 0.0889)
		(layer "In11.Cu")
		(net "M_F_DQS_DN<16>")
	)
	(arc
		(start 288.583624 -99.299522)
		(mid 288.534869 -99.495874)
		(end 288.58845 -99.690936)
		(width 0.0889)
		(layer "In11.Cu")
		(net "M_F_DQS_DN<16>")
	)
	(arc
		(start 288.583624 -98.308922)
		(mid 288.534869 -98.505274)
		(end 288.58845 -98.700336)
		(width 0.0889)
		(layer "In11.Cu")
		(net "M_F_DQS_DN<16>")
	)
	(arc
		(start 286.372554 -95.433134)
		(mid 286.660699 -95.515453)
		(end 286.87141 -95.728536)
		(width 0.0889)
		(layer "In11.Cu")
		(net "M_F_DQS_DN<16>")
	)
	(arc
		(start 288.58845 -98.700336)
		(mid 288.667672 -98.989454)
		(end 288.5948 -99.280218)
		(width 0.0889)
		(layer "In11.Cu")
		(net "M_F_DQS_DN<16>")
	)
	(arc
		(start 285.154624 -94.737936)
		(mid 285.293368 -94.879969)
		(end 285.4833 -94.937834)
		(width 0.0889)
		(layer "In11.Cu")
		(net "M_F_DQS_DN<16>")
	)
	(arc
		(start 283.437584 -92.756736)
		(mid 283.516806 -93.045854)
		(end 283.443934 -93.336618)
		(width 0.0889)
		(layer "In11.Cu")
		(net "M_F_DQS_DN<16>")
	)
	(arc
		(start 283.797248 -93.947234)
		(mid 284.085393 -94.029553)
		(end 284.296104 -94.242636)
		(width 0.0889)
		(layer "In11.Cu")
		(net "M_F_DQS_DN<16>")
	)
	(arc
		(start 283.437584 -90.775536)
		(mid 283.516806 -91.064654)
		(end 283.443934 -91.355418)
		(width 0.0889)
		(layer "In11.Cu")
		(net "M_F_DQS_DN<16>")
	)
	(arc
		(start 284.296104 -94.242636)
		(mid 284.434848 -94.384669)
		(end 284.62478 -94.442534)
		(width 0.0889)
		(layer "In11.Cu")
		(net "M_F_DQS_DN<16>")
	)
	(arc
		(start 284.660594 -94.442534)
		(mid 284.946018 -94.526001)
		(end 285.154624 -94.737936)
		(width 0.0889)
		(layer "In11.Cu")
		(net "M_F_DQS_DN<16>")
	)
	(arc
		(start 288.58845 -100.28174)
		(mid 288.534951 -100.481638)
		(end 288.58845 -100.681536)
		(width 0.0889)
		(layer "In11.Cu")
		(net "M_F_DQS_DN<16>")
	)
	(arc
		(start 288.583624 -97.318322)
		(mid 288.534869 -97.514674)
		(end 288.58845 -97.709736)
		(width 0.0889)
		(layer "In11.Cu")
		(net "M_F_DQS_DN<16>")
	)
	(arc
		(start 288.58845 -99.690936)
		(mid 288.667581 -99.986338)
		(end 288.58845 -100.28174)
		(width 0.0889)
		(layer "In11.Cu")
		(net "M_F_DQS_DN<16>")
	)
	(arc
		(start 288.58845 -97.709736)
		(mid 288.667672 -97.998854)
		(end 288.5948 -98.289618)
		(width 0.0889)
		(layer "In11.Cu")
		(net "M_F_DQS_DN<16>")
	)
	(arc
		(start 286.016446 -95.238824)
		(mid 286.162412 -95.381223)
		(end 286.3596 -95.433134)
		(width 0.0889)
		(layer "In11.Cu")
		(net "M_F_DQS_DN<16>")
	)
	(arc
		(start 288.583624 -102.271322)
		(mid 288.587371 -102.660578)
		(end 288.920174 -102.862634)
		(width 0.0889)
		(layer "In11.Cu")
		(net "M_F_DQS_DN<16>")
	)
	(arc
		(start 285.522924 -94.937834)
		(mid 285.806141 -95.022115)
		(end 286.013144 -95.232982)
		(width 0.0889)
		(layer "In11.Cu")
		(net "M_F_DQS_DN<16>")
	)
	(arc
		(start 289.44697 -103.158036)
		(mid 289.588653 -103.30184)
		(end 289.782504 -103.358188)
		(width 0.0889)
		(layer "In11.Cu")
		(net "M_F_DQS_DN<16>")
	)
	(arc
		(start 283.432758 -91.374722)
		(mid 283.384003 -91.571074)
		(end 283.437584 -91.766136)
		(width 0.0889)
		(layer "In11.Cu")
		(net "M_F_DQS_DN<16>")
	)
	(arc
		(start 288.58845 -101.672136)
		(mid 288.667672 -101.961254)
		(end 288.5948 -102.252018)
		(width 0.0889)
		(layer "In11.Cu")
		(net "M_F_DQS_DN<16>")
	)
	(arc
		(start 283.726382 -90.179398)
		(mid 283.424113 -90.400947)
		(end 283.437584 -90.775536)
		(width 0.0889)
		(layer "In11.Cu")
		(net "M_F_DQS_DN<16>")
	)
	(arc
		(start 283.432758 -93.355922)
		(mid 283.436505 -93.745178)
		(end 283.769308 -93.947234)
		(width 0.0889)
		(layer "In11.Cu")
		(net "M_F_DQS_DN<16>")
	)
	(arc
		(start 283.432758 -92.365322)
		(mid 283.384003 -92.561674)
		(end 283.437584 -92.756736)
		(width 0.0889)
		(layer "In11.Cu")
		(net "M_F_DQS_DN<16>")
	)
	(segment
		(start 302.650398 -152.273)
		(end 302.64989 -152.278842)
		(width 0.1651)
		(layer "F.Cu")
		(net "M_F_DQS_DN<15>")
	)
	(segment
		(start 301.768256 -154.2669)
		(end 301.749206 -154.2669)
		(width 0.1651)
		(layer "F.Cu")
		(net "M_F_DQS_DN<15>")
	)
	(segment
		(start 302.64989 -152.932384)
		(end 302.231806 -153.350468)
		(width 0.1651)
		(layer "F.Cu")
		(net "M_F_DQS_DN<15>")
	)
	(segment
		(start 302.64989 -152.278842)
		(end 302.64989 -152.932384)
		(width 0.1651)
		(layer "F.Cu")
		(net "M_F_DQS_DN<15>")
	)
	(segment
		(start 302.417734 -154.204162)
		(end 302.165766 -154.45613)
		(width 0.1651)
		(layer "F.Cu")
		(net "M_F_DQS_DN<15>")
	)
	(segment
		(start 302.231806 -153.7716)
		(end 302.417734 -153.957528)
		(width 0.1651)
		(layer "F.Cu")
		(net "M_F_DQS_DN<15>")
	)
	(segment
		(start 278.061674 -90.575384)
		(end 278.633174 -90.575384)
		(width 0.1651)
		(layer "F.Cu")
		(net "M_F_DQS_DN<15>")
	)
	(segment
		(start 302.165766 -154.45613)
		(end 301.957486 -154.45613)
		(width 0.1651)
		(layer "F.Cu")
		(net "M_F_DQS_DN<15>")
	)
	(segment
		(start 302.231806 -153.350468)
		(end 302.231806 -153.7716)
		(width 0.1651)
		(layer "F.Cu")
		(net "M_F_DQS_DN<15>")
	)
	(segment
		(start 301.957486 -154.45613)
		(end 301.768256 -154.2669)
		(width 0.1651)
		(layer "F.Cu")
		(net "M_F_DQS_DN<15>")
	)
	(segment
		(start 302.417734 -153.957528)
		(end 302.417734 -154.204162)
		(width 0.1651)
		(layer "F.Cu")
		(net "M_F_DQS_DN<15>")
	)
	(via
		(at 301.742602 -150.0886)
		(size 0.508)
		(drill 0.254)
		(layers "F.Cu" "B.Cu")
		(net "M_F_DQS_DN<15>")
	)
	(via
		(at 278.633174 -90.575384)
		(size 0.508)
		(drill 0.254)
		(layers "F.Cu" "B.Cu")
		(net "M_F_DQS_DN<15>")
	)
	(via
		(at 301.749206 -154.2669)
		(size 0.508)
		(drill 0.254)
		(layers "F.Cu" "B.Cu")
		(net "M_F_DQS_DN<15>")
	)
	(segment
		(start 302.384206 -150.4442)
		(end 302.384206 -150.114)
		(width 0.1651)
		(layer "B.Cu")
		(net "M_F_DQS_DN<15>")
	)
	(segment
		(start 302.384206 -150.114)
		(end 302.164242 -149.894036)
		(width 0.1651)
		(layer "B.Cu")
		(net "M_F_DQS_DN<15>")
	)
	(segment
		(start 302.164242 -149.894036)
		(end 301.937166 -149.894036)
		(width 0.1651)
		(layer "B.Cu")
		(net "M_F_DQS_DN<15>")
	)
	(segment
		(start 302.206406 -150.977854)
		(end 302.206406 -150.622)
		(width 0.1651)
		(layer "B.Cu")
		(net "M_F_DQS_DN<15>")
	)
	(segment
		(start 302.650398 -152.078436)
		(end 302.650144 -151.421592)
		(width 0.1651)
		(layer "B.Cu")
		(net "M_F_DQS_DN<15>")
	)
	(segment
		(start 302.650144 -151.421592)
		(end 302.206406 -150.977854)
		(width 0.1651)
		(layer "B.Cu")
		(net "M_F_DQS_DN<15>")
	)
	(segment
		(start 302.206406 -150.622)
		(end 302.384206 -150.4442)
		(width 0.1651)
		(layer "B.Cu")
		(net "M_F_DQS_DN<15>")
	)
	(segment
		(start 301.937166 -149.894036)
		(end 301.742602 -150.0886)
		(width 0.1651)
		(layer "B.Cu")
		(net "M_F_DQS_DN<15>")
	)
	(segment
		(start 282.572206 -103.14559)
		(end 282.587954 -103.173022)
		(width 0.0889)
		(layer "In11.Cu")
		(net "M_F_DQS_DN<15>")
	)
	(segment
		(start 282.484322 -107.126532)
		(end 282.523692 -107.165902)
		(width 0.0889)
		(layer "In11.Cu")
		(net "M_F_DQS_DN<15>")
	)
	(segment
		(start 279.480518 -97.414588)
		(end 279.513284 -97.414588)
		(width 0.0889)
		(layer "In11.Cu")
		(net "M_F_DQS_DN<15>")
	)
	(segment
		(start 278.286464 -92.356686)
		(end 278.281638 -92.365322)
		(width 0.0889)
		(layer "In11.Cu")
		(net "M_F_DQS_DN<15>")
	)
	(segment
		(start 302.17745 -150.9268)
		(end 301.89805 -151.2062)
		(width 0.14224)
		(layer "In11.Cu")
		(net "M_F_DQS_DN<15>")
	)
	(segment
		(start 278.292814 -96.308418)
		(end 278.286464 -96.319086)
		(width 0.0889)
		(layer "In11.Cu")
		(net "M_F_DQS_DN<15>")
	)
	(segment
		(start 278.286464 -93.347286)
		(end 278.281638 -93.355922)
		(width 0.0889)
		(layer "In11.Cu")
		(net "M_F_DQS_DN<15>")
	)
	(segment
		(start 278.286464 -96.319086)
		(end 278.281638 -96.327722)
		(width 0.0889)
		(layer "In11.Cu")
		(net "M_F_DQS_DN<15>")
	)
	(segment
		(start 302.1584 -149.573488)
		(end 302.1584 -149.672802)
		(width 0.14224)
		(layer "In11.Cu")
		(net "M_F_DQS_DN<15>")
	)
	(segment
		(start 289.983672 -120.591072)
		(end 298.803314 -120.591072)
		(width 0.14224)
		(layer "In11.Cu")
		(net "M_F_DQS_DN<15>")
	)
	(segment
		(start 281.197558 -98.405188)
		(end 281.230324 -98.405188)
		(width 0.0889)
		(layer "In11.Cu")
		(net "M_F_DQS_DN<15>")
	)
	(segment
		(start 301.94885 -151.99106)
		(end 301.94885 -152.34412)
		(width 0.14224)
		(layer "In11.Cu")
		(net "M_F_DQS_DN<15>")
	)
	(segment
		(start 278.286464 -94.737936)
		(end 278.292814 -94.748604)
		(width 0.0889)
		(layer "In11.Cu")
		(net "M_F_DQS_DN<15>")
	)
	(segment
		(start 301.50689 -151.35606)
		(end 301.50689 -151.70404)
		(width 0.14224)
		(layer "In11.Cu")
		(net "M_F_DQS_DN<15>")
	)
	(segment
		(start 301.89805 -151.2062)
		(end 301.65675 -151.2062)
		(width 0.14224)
		(layer "In11.Cu")
		(net "M_F_DQS_DN<15>")
	)
	(segment
		(start 282.484322 -105.893362)
		(end 282.484322 -107.126532)
		(width 0.0889)
		(layer "In11.Cu")
		(net "M_F_DQS_DN<15>")
	)
	(segment
		(start 282.052268 -98.900234)
		(end 282.085034 -98.900234)
		(width 0.0889)
		(layer "In11.Cu")
		(net "M_F_DQS_DN<15>")
	)
	(segment
		(start 282.572206 -105.12679)
		(end 282.587954 -105.154222)
		(width 0.0889)
		(layer "In11.Cu")
		(net "M_F_DQS_DN<15>")
	)
	(segment
		(start 301.79391 -152.49906)
		(end 301.64659 -152.49906)
		(width 0.14224)
		(layer "In11.Cu")
		(net "M_F_DQS_DN<15>")
	)
	(segment
		(start 278.286464 -91.366086)
		(end 278.281638 -91.374722)
		(width 0.0889)
		(layer "In11.Cu")
		(net "M_F_DQS_DN<15>")
	)
	(segment
		(start 302.524922 -149.206966)
		(end 302.1584 -149.573488)
		(width 0.14224)
		(layer "In11.Cu")
		(net "M_F_DQS_DN<15>")
	)
	(segment
		(start 278.292814 -93.336618)
		(end 278.286464 -93.347286)
		(width 0.0889)
		(layer "In11.Cu")
		(net "M_F_DQS_DN<15>")
	)
	(segment
		(start 280.335228 -97.909634)
		(end 280.367994 -97.909634)
		(width 0.0889)
		(layer "In11.Cu")
		(net "M_F_DQS_DN<15>")
	)
	(segment
		(start 282.523692 -107.188)
		(end 282.523692 -113.131092)
		(width 0.14224)
		(layer "In11.Cu")
		(net "M_F_DQS_DN<15>")
	)
	(segment
		(start 301.50689 -151.70404)
		(end 301.63897 -151.83612)
		(width 0.14224)
		(layer "In11.Cu")
		(net "M_F_DQS_DN<15>")
	)
	(segment
		(start 301.65675 -151.2062)
		(end 301.50689 -151.35606)
		(width 0.14224)
		(layer "In11.Cu")
		(net "M_F_DQS_DN<15>")
	)
	(segment
		(start 278.292814 -92.346018)
		(end 278.286464 -92.356686)
		(width 0.0889)
		(layer "In11.Cu")
		(net "M_F_DQS_DN<15>")
	)
	(segment
		(start 282.523692 -107.165902)
		(end 282.523692 -107.188)
		(width 0.0889)
		(layer "In11.Cu")
		(net "M_F_DQS_DN<15>")
	)
	(segment
		(start 301.66945 -153.162)
		(end 301.99457 -153.162)
		(width 0.14224)
		(layer "In11.Cu")
		(net "M_F_DQS_DN<15>")
	)
	(segment
		(start 302.524922 -124.31268)
		(end 302.524922 -149.206966)
		(width 0.14224)
		(layer "In11.Cu")
		(net "M_F_DQS_DN<15>")
	)
	(segment
		(start 302.17745 -150.523448)
		(end 302.17745 -150.9268)
		(width 0.14224)
		(layer "In11.Cu")
		(net "M_F_DQS_DN<15>")
	)
	(segment
		(start 301.94885 -152.34412)
		(end 301.79391 -152.49906)
		(width 0.14224)
		(layer "In11.Cu")
		(net "M_F_DQS_DN<15>")
	)
	(segment
		(start 301.79391 -151.83612)
		(end 301.94885 -151.99106)
		(width 0.14224)
		(layer "In11.Cu")
		(net "M_F_DQS_DN<15>")
	)
	(segment
		(start 302.1584 -149.672802)
		(end 301.742602 -150.0886)
		(width 0.14224)
		(layer "In11.Cu")
		(net "M_F_DQS_DN<15>")
	)
	(segment
		(start 298.803314 -120.591072)
		(end 302.524922 -124.31268)
		(width 0.14224)
		(layer "In11.Cu")
		(net "M_F_DQS_DN<15>")
	)
	(segment
		(start 278.633174 -90.575384)
		(end 278.633174 -90.23731)
		(width 0.0889)
		(layer "In11.Cu")
		(net "M_F_DQS_DN<15>")
	)
	(segment
		(start 301.742602 -150.0886)
		(end 302.17745 -150.523448)
		(width 0.14224)
		(layer "In11.Cu")
		(net "M_F_DQS_DN<15>")
	)
	(segment
		(start 282.579318 -105.729532)
		(end 282.579064 -105.729532)
		(width 0.0889)
		(layer "In11.Cu")
		(net "M_F_DQS_DN<15>")
	)
	(segment
		(start 278.618188 -96.919034)
		(end 278.650954 -96.919034)
		(width 0.0889)
		(layer "In11.Cu")
		(net "M_F_DQS_DN<15>")
	)
	(segment
		(start 278.292814 -91.355418)
		(end 278.286464 -91.366086)
		(width 0.0889)
		(layer "In11.Cu")
		(net "M_F_DQS_DN<15>")
	)
	(segment
		(start 282.523692 -113.131092)
		(end 289.983672 -120.591072)
		(width 0.14224)
		(layer "In11.Cu")
		(net "M_F_DQS_DN<15>")
	)
	(segment
		(start 301.99457 -153.162)
		(end 302.182276 -153.349706)
		(width 0.14224)
		(layer "In11.Cu")
		(net "M_F_DQS_DN<15>")
	)
	(segment
		(start 301.50689 -152.99944)
		(end 301.66945 -153.162)
		(width 0.14224)
		(layer "In11.Cu")
		(net "M_F_DQS_DN<15>")
	)
	(segment
		(start 282.572206 -104.13619)
		(end 282.587954 -104.163622)
		(width 0.0889)
		(layer "In11.Cu")
		(net "M_F_DQS_DN<15>")
	)
	(segment
		(start 278.286464 -95.328486)
		(end 278.281638 -95.337122)
		(width 0.0889)
		(layer "In11.Cu")
		(net "M_F_DQS_DN<15>")
	)
	(segment
		(start 302.182276 -153.349706)
		(end 302.182276 -153.83383)
		(width 0.14224)
		(layer "In11.Cu")
		(net "M_F_DQS_DN<15>")
	)
	(segment
		(start 278.633174 -90.23731)
		(end 278.575262 -90.179398)
		(width 0.0889)
		(layer "In11.Cu")
		(net "M_F_DQS_DN<15>")
	)
	(segment
		(start 282.579064 -100.776278)
		(end 282.574238 -100.784914)
		(width 0.0889)
		(layer "In11.Cu")
		(net "M_F_DQS_DN<15>")
	)
	(segment
		(start 302.182276 -153.83383)
		(end 301.749206 -154.2669)
		(width 0.14224)
		(layer "In11.Cu")
		(net "M_F_DQS_DN<15>")
	)
	(segment
		(start 301.64659 -152.49906)
		(end 301.50689 -152.63876)
		(width 0.14224)
		(layer "In11.Cu")
		(net "M_F_DQS_DN<15>")
	)
	(segment
		(start 282.579064 -102.166928)
		(end 282.585414 -102.177596)
		(width 0.0889)
		(layer "In11.Cu")
		(net "M_F_DQS_DN<15>")
	)
	(segment
		(start 301.50689 -152.63876)
		(end 301.50689 -152.99944)
		(width 0.14224)
		(layer "In11.Cu")
		(net "M_F_DQS_DN<15>")
	)
	(segment
		(start 301.63897 -151.83612)
		(end 301.79391 -151.83612)
		(width 0.14224)
		(layer "In11.Cu")
		(net "M_F_DQS_DN<15>")
	)
	(segment
		(start 282.579064 -105.729532)
		(end 282.484322 -105.893362)
		(width 0.0889)
		(layer "In11.Cu")
		(net "M_F_DQS_DN<15>")
	)
	(segment
		(start 282.585414 -100.76561)
		(end 282.579064 -100.776278)
		(width 0.0889)
		(layer "In11.Cu")
		(net "M_F_DQS_DN<15>")
	)
	(arc
		(start 282.579064 -99.785932)
		(mid 282.525565 -99.98583)
		(end 282.579064 -100.185728)
		(width 0.0889)
		(layer "In11.Cu")
		(net "M_F_DQS_DN<15>")
	)
	(arc
		(start 281.230324 -98.405188)
		(mid 281.513541 -98.489469)
		(end 281.720544 -98.700336)
		(width 0.0889)
		(layer "In11.Cu")
		(net "M_F_DQS_DN<15>")
	)
	(arc
		(start 282.574238 -100.784914)
		(mid 282.525483 -100.981266)
		(end 282.579064 -101.176328)
		(width 0.0889)
		(layer "In11.Cu")
		(net "M_F_DQS_DN<15>")
	)
	(arc
		(start 282.579064 -103.748586)
		(mid 282.525626 -103.941491)
		(end 282.572206 -104.13619)
		(width 0.0889)
		(layer "In11.Cu")
		(net "M_F_DQS_DN<15>")
	)
	(arc
		(start 278.281638 -92.365322)
		(mid 278.232883 -92.561674)
		(end 278.286464 -92.756736)
		(width 0.0889)
		(layer "In11.Cu")
		(net "M_F_DQS_DN<15>")
	)
	(arc
		(start 278.650954 -96.919034)
		(mid 278.936378 -97.002501)
		(end 279.144984 -97.214436)
		(width 0.0889)
		(layer "In11.Cu")
		(net "M_F_DQS_DN<15>")
	)
	(arc
		(start 280.367994 -97.909634)
		(mid 280.653418 -97.993101)
		(end 280.862024 -98.205036)
		(width 0.0889)
		(layer "In11.Cu")
		(net "M_F_DQS_DN<15>")
	)
	(arc
		(start 278.286464 -92.756736)
		(mid 278.365686 -93.045854)
		(end 278.292814 -93.336618)
		(width 0.0889)
		(layer "In11.Cu")
		(net "M_F_DQS_DN<15>")
	)
	(arc
		(start 278.281638 -96.327722)
		(mid 278.285385 -96.716978)
		(end 278.618188 -96.919034)
		(width 0.0889)
		(layer "In11.Cu")
		(net "M_F_DQS_DN<15>")
	)
	(arc
		(start 280.003504 -97.709736)
		(mid 280.143583 -97.852472)
		(end 280.335228 -97.909634)
		(width 0.0889)
		(layer "In11.Cu")
		(net "M_F_DQS_DN<15>")
	)
	(arc
		(start 281.720544 -98.700336)
		(mid 281.860623 -98.843072)
		(end 282.052268 -98.900234)
		(width 0.0889)
		(layer "In11.Cu")
		(net "M_F_DQS_DN<15>")
	)
	(arc
		(start 282.579064 -101.176328)
		(mid 282.658195 -101.47173)
		(end 282.579064 -101.767132)
		(width 0.0889)
		(layer "In11.Cu")
		(net "M_F_DQS_DN<15>")
	)
	(arc
		(start 279.513284 -97.414588)
		(mid 279.796501 -97.498869)
		(end 280.003504 -97.709736)
		(width 0.0889)
		(layer "In11.Cu")
		(net "M_F_DQS_DN<15>")
	)
	(arc
		(start 282.587954 -105.154222)
		(mid 282.658353 -105.442999)
		(end 282.579318 -105.729532)
		(width 0.0889)
		(layer "In11.Cu")
		(net "M_F_DQS_DN<15>")
	)
	(arc
		(start 278.286464 -91.766136)
		(mid 278.365686 -92.055254)
		(end 278.292814 -92.346018)
		(width 0.0889)
		(layer "In11.Cu")
		(net "M_F_DQS_DN<15>")
	)
	(arc
		(start 282.579064 -102.757986)
		(mid 282.525626 -102.950891)
		(end 282.572206 -103.14559)
		(width 0.0889)
		(layer "In11.Cu")
		(net "M_F_DQS_DN<15>")
	)
	(arc
		(start 282.085034 -98.900234)
		(mid 282.583232 -99.202978)
		(end 282.579064 -99.785932)
		(width 0.0889)
		(layer "In11.Cu")
		(net "M_F_DQS_DN<15>")
	)
	(arc
		(start 282.579064 -101.767132)
		(mid 282.525565 -101.96703)
		(end 282.579064 -102.166928)
		(width 0.0889)
		(layer "In11.Cu")
		(net "M_F_DQS_DN<15>")
	)
	(arc
		(start 278.281638 -95.337122)
		(mid 278.232883 -95.533474)
		(end 278.286464 -95.728536)
		(width 0.0889)
		(layer "In11.Cu")
		(net "M_F_DQS_DN<15>")
	)
	(arc
		(start 278.281638 -93.355922)
		(mid 278.232883 -93.552274)
		(end 278.286464 -93.747336)
		(width 0.0889)
		(layer "In11.Cu")
		(net "M_F_DQS_DN<15>")
	)
	(arc
		(start 279.144984 -97.214436)
		(mid 279.286667 -97.35824)
		(end 279.480518 -97.414588)
		(width 0.0889)
		(layer "In11.Cu")
		(net "M_F_DQS_DN<15>")
	)
	(arc
		(start 282.587954 -104.163622)
		(mid 282.658351 -104.452573)
		(end 282.579064 -104.739186)
		(width 0.0889)
		(layer "In11.Cu")
		(net "M_F_DQS_DN<15>")
	)
	(arc
		(start 278.286464 -93.747336)
		(mid 278.365595 -94.042738)
		(end 278.286464 -94.33814)
		(width 0.0889)
		(layer "In11.Cu")
		(net "M_F_DQS_DN<15>")
	)
	(arc
		(start 278.286464 -95.728536)
		(mid 278.365686 -96.017654)
		(end 278.292814 -96.308418)
		(width 0.0889)
		(layer "In11.Cu")
		(net "M_F_DQS_DN<15>")
	)
	(arc
		(start 282.579064 -100.185728)
		(mid 282.658286 -100.474846)
		(end 282.585414 -100.76561)
		(width 0.0889)
		(layer "In11.Cu")
		(net "M_F_DQS_DN<15>")
	)
	(arc
		(start 278.575262 -90.179398)
		(mid 278.272993 -90.400947)
		(end 278.286464 -90.775536)
		(width 0.0889)
		(layer "In11.Cu")
		(net "M_F_DQS_DN<15>")
	)
	(arc
		(start 282.585414 -102.177596)
		(mid 282.658334 -102.468613)
		(end 282.579064 -102.757986)
		(width 0.0889)
		(layer "In11.Cu")
		(net "M_F_DQS_DN<15>")
	)
	(arc
		(start 280.862024 -98.205036)
		(mid 281.003707 -98.34884)
		(end 281.197558 -98.405188)
		(width 0.0889)
		(layer "In11.Cu")
		(net "M_F_DQS_DN<15>")
	)
	(arc
		(start 282.587954 -103.173022)
		(mid 282.658351 -103.461973)
		(end 282.579064 -103.748586)
		(width 0.0889)
		(layer "In11.Cu")
		(net "M_F_DQS_DN<15>")
	)
	(arc
		(start 278.286464 -90.775536)
		(mid 278.365686 -91.064654)
		(end 278.292814 -91.355418)
		(width 0.0889)
		(layer "In11.Cu")
		(net "M_F_DQS_DN<15>")
	)
	(arc
		(start 282.579064 -104.739186)
		(mid 282.525626 -104.932091)
		(end 282.572206 -105.12679)
		(width 0.0889)
		(layer "In11.Cu")
		(net "M_F_DQS_DN<15>")
	)
	(arc
		(start 278.286464 -94.33814)
		(mid 278.232965 -94.538038)
		(end 278.286464 -94.737936)
		(width 0.0889)
		(layer "In11.Cu")
		(net "M_F_DQS_DN<15>")
	)
	(arc
		(start 278.281638 -91.374722)
		(mid 278.232883 -91.571074)
		(end 278.286464 -91.766136)
		(width 0.0889)
		(layer "In11.Cu")
		(net "M_F_DQS_DN<15>")
	)
	(arc
		(start 278.292814 -94.748604)
		(mid 278.365612 -95.039367)
		(end 278.286464 -95.328486)
		(width 0.0889)
		(layer "In11.Cu")
		(net "M_F_DQS_DN<15>")
	)
	(segment
		(start 292.815772 -154.45613)
		(end 292.607492 -154.45613)
		(width 0.1651)
		(layer "F.Cu")
		(net "M_F_DQS_DN<14>")
	)
	(segment
		(start 280.637234 -94.042738)
		(end 281.208734 -94.042738)
		(width 0.1651)
		(layer "F.Cu")
		(net "M_F_DQS_DN<14>")
	)
	(segment
		(start 293.299896 -152.278842)
		(end 293.299896 -152.932384)
		(width 0.1651)
		(layer "F.Cu")
		(net "M_F_DQS_DN<14>")
	)
	(segment
		(start 292.418262 -154.2669)
		(end 292.399212 -154.2669)
		(width 0.1651)
		(layer "F.Cu")
		(net "M_F_DQS_DN<14>")
	)
	(segment
		(start 293.299896 -152.932384)
		(end 292.881812 -153.350468)
		(width 0.1651)
		(layer "F.Cu")
		(net "M_F_DQS_DN<14>")
	)
	(segment
		(start 292.881812 -153.350468)
		(end 292.881812 -153.7716)
		(width 0.1651)
		(layer "F.Cu")
		(net "M_F_DQS_DN<14>")
	)
	(segment
		(start 293.300404 -152.273)
		(end 293.299896 -152.278842)
		(width 0.1651)
		(layer "F.Cu")
		(net "M_F_DQS_DN<14>")
	)
	(segment
		(start 293.06774 -154.204162)
		(end 292.815772 -154.45613)
		(width 0.1651)
		(layer "F.Cu")
		(net "M_F_DQS_DN<14>")
	)
	(segment
		(start 293.06774 -153.957528)
		(end 293.06774 -154.204162)
		(width 0.1651)
		(layer "F.Cu")
		(net "M_F_DQS_DN<14>")
	)
	(segment
		(start 292.607492 -154.45613)
		(end 292.418262 -154.2669)
		(width 0.1651)
		(layer "F.Cu")
		(net "M_F_DQS_DN<14>")
	)
	(segment
		(start 292.881812 -153.7716)
		(end 293.06774 -153.957528)
		(width 0.1651)
		(layer "F.Cu")
		(net "M_F_DQS_DN<14>")
	)
	(via
		(at 292.392608 -150.0886)
		(size 0.508)
		(drill 0.254)
		(layers "F.Cu" "B.Cu")
		(net "M_F_DQS_DN<14>")
	)
	(via
		(at 292.399212 -154.2669)
		(size 0.508)
		(drill 0.254)
		(layers "F.Cu" "B.Cu")
		(net "M_F_DQS_DN<14>")
	)
	(via
		(at 281.208734 -94.042738)
		(size 0.508)
		(drill 0.254)
		(layers "F.Cu" "B.Cu")
		(net "M_F_DQS_DN<14>")
	)
	(segment
		(start 293.034212 -150.114)
		(end 293.034212 -150.4442)
		(width 0.1651)
		(layer "B.Cu")
		(net "M_F_DQS_DN<14>")
	)
	(segment
		(start 292.856412 -150.977854)
		(end 293.30015 -151.421592)
		(width 0.1651)
		(layer "B.Cu")
		(net "M_F_DQS_DN<14>")
	)
	(segment
		(start 292.814248 -149.894036)
		(end 293.034212 -150.114)
		(width 0.1651)
		(layer "B.Cu")
		(net "M_F_DQS_DN<14>")
	)
	(segment
		(start 293.30015 -151.421592)
		(end 293.30015 -152.077928)
		(width 0.1651)
		(layer "B.Cu")
		(net "M_F_DQS_DN<14>")
	)
	(segment
		(start 292.392608 -150.0886)
		(end 292.587172 -149.894036)
		(width 0.1651)
		(layer "B.Cu")
		(net "M_F_DQS_DN<14>")
	)
	(segment
		(start 292.587172 -149.894036)
		(end 292.814248 -149.894036)
		(width 0.1651)
		(layer "B.Cu")
		(net "M_F_DQS_DN<14>")
	)
	(segment
		(start 293.034212 -150.4442)
		(end 292.856412 -150.622)
		(width 0.1651)
		(layer "B.Cu")
		(net "M_F_DQS_DN<14>")
	)
	(segment
		(start 293.30015 -152.077928)
		(end 293.300404 -152.078436)
		(width 0.1651)
		(layer "B.Cu")
		(net "M_F_DQS_DN<14>")
	)
	(segment
		(start 292.856412 -150.622)
		(end 292.856412 -150.977854)
		(width 0.1651)
		(layer "B.Cu")
		(net "M_F_DQS_DN<14>")
	)
	(segment
		(start 281.197558 -105.339388)
		(end 281.233626 -105.339388)
		(width 0.0889)
		(layer "In4.Cu")
		(net "M_F_DQS_DN<14>")
	)
	(segment
		(start 280.857198 -99.187)
		(end 280.862024 -99.195636)
		(width 0.0889)
		(layer "In4.Cu")
		(net "M_F_DQS_DN<14>")
	)
	(segment
		(start 280.857198 -103.1494)
		(end 280.862024 -103.158036)
		(width 0.0889)
		(layer "In4.Cu")
		(net "M_F_DQS_DN<14>")
	)
	(segment
		(start 280.857198 -94.234)
		(end 280.862024 -94.242636)
		(width 0.0889)
		(layer "In4.Cu")
		(net "M_F_DQS_DN<14>")
	)
	(segment
		(start 280.857198 -101.1682)
		(end 280.862024 -101.176836)
		(width 0.0889)
		(layer "In4.Cu")
		(net "M_F_DQS_DN<14>")
	)
	(segment
		(start 281.208734 -94.042738)
		(end 281.208734 -93.704664)
		(width 0.0889)
		(layer "In4.Cu")
		(net "M_F_DQS_DN<14>")
	)
	(segment
		(start 280.857198 -104.14)
		(end 280.862024 -104.148636)
		(width 0.0889)
		(layer "In4.Cu")
		(net "M_F_DQS_DN<14>")
	)
	(segment
		(start 281.930094 -107.286298)
		(end 281.930094 -112.856264)
		(width 0.14224)
		(layer "In4.Cu")
		(net "M_F_DQS_DN<14>")
	)
	(segment
		(start 281.799792 -106.477308)
		(end 281.890724 -106.56824)
		(width 0.0889)
		(layer "In4.Cu")
		(net "M_F_DQS_DN<14>")
	)
	(segment
		(start 280.862024 -103.158036)
		(end 280.868374 -103.168704)
		(width 0.0889)
		(layer "In4.Cu")
		(net "M_F_DQS_DN<14>")
	)
	(segment
		(start 280.857198 -102.1588)
		(end 280.862024 -102.167436)
		(width 0.0889)
		(layer "In4.Cu")
		(net "M_F_DQS_DN<14>")
	)
	(segment
		(start 280.862024 -101.176836)
		(end 280.868374 -101.187504)
		(width 0.0889)
		(layer "In4.Cu")
		(net "M_F_DQS_DN<14>")
	)
	(segment
		(start 280.857198 -97.2058)
		(end 280.862024 -97.214436)
		(width 0.0889)
		(layer "In4.Cu")
		(net "M_F_DQS_DN<14>")
	)
	(segment
		(start 281.930094 -107.2642)
		(end 281.930094 -107.286298)
		(width 0.0889)
		(layer "In4.Cu")
		(net "M_F_DQS_DN<14>")
	)
	(segment
		(start 280.862024 -100.186236)
		(end 280.868374 -100.196904)
		(width 0.0889)
		(layer "In4.Cu")
		(net "M_F_DQS_DN<14>")
	)
	(segment
		(start 280.862024 -102.167436)
		(end 280.868374 -102.178104)
		(width 0.0889)
		(layer "In4.Cu")
		(net "M_F_DQS_DN<14>")
	)
	(segment
		(start 280.857198 -100.1776)
		(end 280.862024 -100.186236)
		(width 0.0889)
		(layer "In4.Cu")
		(net "M_F_DQS_DN<14>")
	)
	(segment
		(start 280.857198 -96.2152)
		(end 280.862024 -96.223836)
		(width 0.0889)
		(layer "In4.Cu")
		(net "M_F_DQS_DN<14>")
	)
	(segment
		(start 280.857198 -98.1964)
		(end 280.862024 -98.205036)
		(width 0.0889)
		(layer "In4.Cu")
		(net "M_F_DQS_DN<14>")
	)
	(segment
		(start 280.862024 -97.214436)
		(end 280.868374 -97.225104)
		(width 0.0889)
		(layer "In4.Cu")
		(net "M_F_DQS_DN<14>")
	)
	(segment
		(start 280.868374 -94.822518)
		(end 280.862024 -94.833186)
		(width 0.0889)
		(layer "In4.Cu")
		(net "M_F_DQS_DN<14>")
	)
	(segment
		(start 281.208734 -93.704664)
		(end 281.150822 -93.646752)
		(width 0.0889)
		(layer "In4.Cu")
		(net "M_F_DQS_DN<14>")
	)
	(segment
		(start 293.174928 -124.101098)
		(end 293.174928 -149.30628)
		(width 0.14224)
		(layer "In4.Cu")
		(net "M_F_DQS_DN<14>")
	)
	(segment
		(start 281.799792 -105.929684)
		(end 281.799792 -106.477308)
		(width 0.0889)
		(layer "In4.Cu")
		(net "M_F_DQS_DN<14>")
	)
	(segment
		(start 280.862024 -96.223836)
		(end 280.868374 -96.234504)
		(width 0.0889)
		(layer "In4.Cu")
		(net "M_F_DQS_DN<14>")
	)
	(segment
		(start 281.930094 -112.856264)
		(end 293.174928 -124.101098)
		(width 0.14224)
		(layer "In4.Cu")
		(net "M_F_DQS_DN<14>")
	)
	(segment
		(start 281.890724 -106.56824)
		(end 281.890724 -107.22483)
		(width 0.0889)
		(layer "In4.Cu")
		(net "M_F_DQS_DN<14>")
	)
	(segment
		(start 280.862024 -99.195636)
		(end 280.868374 -99.206304)
		(width 0.0889)
		(layer "In4.Cu")
		(net "M_F_DQS_DN<14>")
	)
	(segment
		(start 280.862024 -98.205036)
		(end 280.868374 -98.215704)
		(width 0.0889)
		(layer "In4.Cu")
		(net "M_F_DQS_DN<14>")
	)
	(segment
		(start 281.890724 -107.22483)
		(end 281.930094 -107.2642)
		(width 0.0889)
		(layer "In4.Cu")
		(net "M_F_DQS_DN<14>")
	)
	(segment
		(start 280.862024 -104.148636)
		(end 280.868374 -104.159304)
		(width 0.0889)
		(layer "In4.Cu")
		(net "M_F_DQS_DN<14>")
	)
	(segment
		(start 293.174928 -149.30628)
		(end 292.392608 -150.0886)
		(width 0.14224)
		(layer "In4.Cu")
		(net "M_F_DQS_DN<14>")
	)
	(arc
		(start 280.862024 -103.748586)
		(mid 280.808554 -103.943649)
		(end 280.857198 -104.14)
		(width 0.0889)
		(layer "In4.Cu")
		(net "M_F_DQS_DN<14>")
	)
	(arc
		(start 280.862024 -102.757986)
		(mid 280.808554 -102.953049)
		(end 280.857198 -103.1494)
		(width 0.0889)
		(layer "In4.Cu")
		(net "M_F_DQS_DN<14>")
	)
	(arc
		(start 280.862024 -95.823786)
		(mid 280.808554 -96.018849)
		(end 280.857198 -96.2152)
		(width 0.0889)
		(layer "In4.Cu")
		(net "M_F_DQS_DN<14>")
	)
	(arc
		(start 280.868374 -98.215704)
		(mid 280.941172 -98.506467)
		(end 280.862024 -98.795586)
		(width 0.0889)
		(layer "In4.Cu")
		(net "M_F_DQS_DN<14>")
	)
	(arc
		(start 280.868374 -96.234504)
		(mid 280.941172 -96.525267)
		(end 280.862024 -96.814386)
		(width 0.0889)
		(layer "In4.Cu")
		(net "M_F_DQS_DN<14>")
	)
	(arc
		(start 280.868374 -104.159304)
		(mid 280.941172 -104.450067)
		(end 280.862024 -104.739186)
		(width 0.0889)
		(layer "In4.Cu")
		(net "M_F_DQS_DN<14>")
	)
	(arc
		(start 280.862024 -97.804986)
		(mid 280.808554 -98.000049)
		(end 280.857198 -98.1964)
		(width 0.0889)
		(layer "In4.Cu")
		(net "M_F_DQS_DN<14>")
	)
	(arc
		(start 280.862024 -100.776786)
		(mid 280.808554 -100.971849)
		(end 280.857198 -101.1682)
		(width 0.0889)
		(layer "In4.Cu")
		(net "M_F_DQS_DN<14>")
	)
	(arc
		(start 280.868374 -99.206304)
		(mid 280.941172 -99.497067)
		(end 280.862024 -99.786186)
		(width 0.0889)
		(layer "In4.Cu")
		(net "M_F_DQS_DN<14>")
	)
	(arc
		(start 280.862024 -99.786186)
		(mid 280.808554 -99.981249)
		(end 280.857198 -100.1776)
		(width 0.0889)
		(layer "In4.Cu")
		(net "M_F_DQS_DN<14>")
	)
	(arc
		(start 281.150822 -93.646752)
		(mid 280.850786 -93.863764)
		(end 280.857198 -94.234)
		(width 0.0889)
		(layer "In4.Cu")
		(net "M_F_DQS_DN<14>")
	)
	(arc
		(start 280.862024 -95.232982)
		(mid 280.941155 -95.528384)
		(end 280.862024 -95.823786)
		(width 0.0889)
		(layer "In4.Cu")
		(net "M_F_DQS_DN<14>")
	)
	(arc
		(start 280.862024 -101.767386)
		(mid 280.808554 -101.962449)
		(end 280.857198 -102.1588)
		(width 0.0889)
		(layer "In4.Cu")
		(net "M_F_DQS_DN<14>")
	)
	(arc
		(start 280.862024 -96.814386)
		(mid 280.808554 -97.009449)
		(end 280.857198 -97.2058)
		(width 0.0889)
		(layer "In4.Cu")
		(net "M_F_DQS_DN<14>")
	)
	(arc
		(start 280.868374 -100.196904)
		(mid 280.941172 -100.487667)
		(end 280.862024 -100.776786)
		(width 0.0889)
		(layer "In4.Cu")
		(net "M_F_DQS_DN<14>")
	)
	(arc
		(start 281.233626 -105.339388)
		(mid 281.635309 -105.520789)
		(end 281.799792 -105.929684)
		(width 0.0889)
		(layer "In4.Cu")
		(net "M_F_DQS_DN<14>")
	)
	(arc
		(start 280.868374 -101.187504)
		(mid 280.941172 -101.478267)
		(end 280.862024 -101.767386)
		(width 0.0889)
		(layer "In4.Cu")
		(net "M_F_DQS_DN<14>")
	)
	(arc
		(start 280.868374 -102.178104)
		(mid 280.941172 -102.468867)
		(end 280.862024 -102.757986)
		(width 0.0889)
		(layer "In4.Cu")
		(net "M_F_DQS_DN<14>")
	)
	(arc
		(start 280.868374 -103.168704)
		(mid 280.941172 -103.459467)
		(end 280.862024 -103.748586)
		(width 0.0889)
		(layer "In4.Cu")
		(net "M_F_DQS_DN<14>")
	)
	(arc
		(start 280.862024 -98.795586)
		(mid 280.808554 -98.990649)
		(end 280.857198 -99.187)
		(width 0.0889)
		(layer "In4.Cu")
		(net "M_F_DQS_DN<14>")
	)
	(arc
		(start 280.862024 -94.242636)
		(mid 280.941246 -94.531754)
		(end 280.868374 -94.822518)
		(width 0.0889)
		(layer "In4.Cu")
		(net "M_F_DQS_DN<14>")
	)
	(arc
		(start 280.862024 -104.739186)
		(mid 280.859276 -105.134653)
		(end 281.197558 -105.339388)
		(width 0.0889)
		(layer "In4.Cu")
		(net "M_F_DQS_DN<14>")
	)
	(arc
		(start 280.868374 -97.225104)
		(mid 280.941172 -97.515867)
		(end 280.862024 -97.804986)
		(width 0.0889)
		(layer "In4.Cu")
		(net "M_F_DQS_DN<14>")
	)
	(arc
		(start 280.862024 -94.833186)
		(mid 280.808525 -95.033084)
		(end 280.862024 -95.232982)
		(width 0.0889)
		(layer "In4.Cu")
		(net "M_F_DQS_DN<14>")
	)
	(segment
		(start 292.832282 -153.83383)
		(end 292.399212 -154.2669)
		(width 0.14224)
		(layer "In11.Cu")
		(net "M_F_DQS_DN<14>")
	)
	(segment
		(start 292.156896 -151.35606)
		(end 292.156896 -151.70404)
		(width 0.14224)
		(layer "In11.Cu")
		(net "M_F_DQS_DN<14>")
	)
	(segment
		(start 292.644576 -153.162)
		(end 292.832282 -153.349706)
		(width 0.14224)
		(layer "In11.Cu")
		(net "M_F_DQS_DN<14>")
	)
	(segment
		(start 292.156896 -152.99944)
		(end 292.319456 -153.162)
		(width 0.14224)
		(layer "In11.Cu")
		(net "M_F_DQS_DN<14>")
	)
	(segment
		(start 292.288976 -151.83612)
		(end 292.443916 -151.83612)
		(width 0.14224)
		(layer "In11.Cu")
		(net "M_F_DQS_DN<14>")
	)
	(segment
		(start 292.598856 -151.99106)
		(end 292.598856 -152.34412)
		(width 0.14224)
		(layer "In11.Cu")
		(net "M_F_DQS_DN<14>")
	)
	(segment
		(start 292.443916 -152.49906)
		(end 292.296596 -152.49906)
		(width 0.14224)
		(layer "In11.Cu")
		(net "M_F_DQS_DN<14>")
	)
	(segment
		(start 292.443916 -151.83612)
		(end 292.598856 -151.99106)
		(width 0.14224)
		(layer "In11.Cu")
		(net "M_F_DQS_DN<14>")
	)
	(segment
		(start 292.827456 -150.523448)
		(end 292.827456 -150.9268)
		(width 0.14224)
		(layer "In11.Cu")
		(net "M_F_DQS_DN<14>")
	)
	(segment
		(start 292.548056 -151.2062)
		(end 292.306756 -151.2062)
		(width 0.14224)
		(layer "In11.Cu")
		(net "M_F_DQS_DN<14>")
	)
	(segment
		(start 292.598856 -152.34412)
		(end 292.443916 -152.49906)
		(width 0.14224)
		(layer "In11.Cu")
		(net "M_F_DQS_DN<14>")
	)
	(segment
		(start 292.296596 -152.49906)
		(end 292.156896 -152.63876)
		(width 0.14224)
		(layer "In11.Cu")
		(net "M_F_DQS_DN<14>")
	)
	(segment
		(start 292.306756 -151.2062)
		(end 292.156896 -151.35606)
		(width 0.14224)
		(layer "In11.Cu")
		(net "M_F_DQS_DN<14>")
	)
	(segment
		(start 292.156896 -152.63876)
		(end 292.156896 -152.99944)
		(width 0.14224)
		(layer "In11.Cu")
		(net "M_F_DQS_DN<14>")
	)
	(segment
		(start 292.392608 -150.0886)
		(end 292.827456 -150.523448)
		(width 0.14224)
		(layer "In11.Cu")
		(net "M_F_DQS_DN<14>")
	)
	(segment
		(start 292.827456 -150.9268)
		(end 292.548056 -151.2062)
		(width 0.14224)
		(layer "In11.Cu")
		(net "M_F_DQS_DN<14>")
	)
	(segment
		(start 292.156896 -151.70404)
		(end 292.288976 -151.83612)
		(width 0.14224)
		(layer "In11.Cu")
		(net "M_F_DQS_DN<14>")
	)
	(segment
		(start 292.832282 -153.349706)
		(end 292.832282 -153.83383)
		(width 0.14224)
		(layer "In11.Cu")
		(net "M_F_DQS_DN<14>")
	)
	(segment
		(start 292.319456 -153.162)
		(end 292.644576 -153.162)
		(width 0.14224)
		(layer "In11.Cu")
		(net "M_F_DQS_DN<14>")
	)
	(segment
		(start 283.717492 -154.204162)
		(end 283.465524 -154.45613)
		(width 0.1651)
		(layer "F.Cu")
		(net "M_F_DQS_DN<13>")
	)
	(segment
		(start 283.531564 -153.350468)
		(end 283.531564 -153.7716)
		(width 0.1651)
		(layer "F.Cu")
		(net "M_F_DQS_DN<13>")
	)
	(segment
		(start 283.95041 -152.273)
		(end 283.949902 -152.278842)
		(width 0.1651)
		(layer "F.Cu")
		(net "M_F_DQS_DN<13>")
	)
	(segment
		(start 283.257244 -154.45613)
		(end 283.068014 -154.2669)
		(width 0.1651)
		(layer "F.Cu")
		(net "M_F_DQS_DN<13>")
	)
	(segment
		(start 283.949902 -152.278842)
		(end 283.949902 -152.93213)
		(width 0.1651)
		(layer "F.Cu")
		(net "M_F_DQS_DN<13>")
	)
	(segment
		(start 273.769328 -93.052138)
		(end 274.340828 -93.052138)
		(width 0.1651)
		(layer "F.Cu")
		(net "M_F_DQS_DN<13>")
	)
	(segment
		(start 283.531564 -153.7716)
		(end 283.717492 -153.957528)
		(width 0.1651)
		(layer "F.Cu")
		(net "M_F_DQS_DN<13>")
	)
	(segment
		(start 283.465524 -154.45613)
		(end 283.257244 -154.45613)
		(width 0.1651)
		(layer "F.Cu")
		(net "M_F_DQS_DN<13>")
	)
	(segment
		(start 283.068014 -154.2669)
		(end 283.048964 -154.2669)
		(width 0.1651)
		(layer "F.Cu")
		(net "M_F_DQS_DN<13>")
	)
	(segment
		(start 283.949902 -152.93213)
		(end 283.531564 -153.350468)
		(width 0.1651)
		(layer "F.Cu")
		(net "M_F_DQS_DN<13>")
	)
	(segment
		(start 283.717492 -153.957528)
		(end 283.717492 -154.204162)
		(width 0.1651)
		(layer "F.Cu")
		(net "M_F_DQS_DN<13>")
	)
	(via
		(at 274.340828 -93.052138)
		(size 0.508)
		(drill 0.254)
		(layers "F.Cu" "B.Cu")
		(net "M_F_DQS_DN<13>")
	)
	(via
		(at 283.04236 -150.0886)
		(size 0.508)
		(drill 0.254)
		(layers "F.Cu" "B.Cu")
		(net "M_F_DQS_DN<13>")
	)
	(via
		(at 283.048964 -154.2669)
		(size 0.508)
		(drill 0.254)
		(layers "F.Cu" "B.Cu")
		(net "M_F_DQS_DN<13>")
	)
	(segment
		(start 283.949902 -152.078182)
		(end 283.949902 -151.421592)
		(width 0.1651)
		(layer "B.Cu")
		(net "M_F_DQS_DN<13>")
	)
	(segment
		(start 283.683964 -150.4442)
		(end 283.683964 -150.114)
		(width 0.1651)
		(layer "B.Cu")
		(net "M_F_DQS_DN<13>")
	)
	(segment
		(start 283.683964 -150.114)
		(end 283.464 -149.894036)
		(width 0.1651)
		(layer "B.Cu")
		(net "M_F_DQS_DN<13>")
	)
	(segment
		(start 283.236924 -149.894036)
		(end 283.04236 -150.0886)
		(width 0.1651)
		(layer "B.Cu")
		(net "M_F_DQS_DN<13>")
	)
	(segment
		(start 283.949902 -151.421592)
		(end 283.506164 -150.977854)
		(width 0.1651)
		(layer "B.Cu")
		(net "M_F_DQS_DN<13>")
	)
	(segment
		(start 283.95041 -152.078436)
		(end 283.949902 -152.078182)
		(width 0.1651)
		(layer "B.Cu")
		(net "M_F_DQS_DN<13>")
	)
	(segment
		(start 283.464 -149.894036)
		(end 283.236924 -149.894036)
		(width 0.1651)
		(layer "B.Cu")
		(net "M_F_DQS_DN<13>")
	)
	(segment
		(start 283.506164 -150.622)
		(end 283.683964 -150.4442)
		(width 0.1651)
		(layer "B.Cu")
		(net "M_F_DQS_DN<13>")
	)
	(segment
		(start 283.506164 -150.977854)
		(end 283.506164 -150.622)
		(width 0.1651)
		(layer "B.Cu")
		(net "M_F_DQS_DN<13>")
	)
	(segment
		(start 283.824934 -149.07641)
		(end 283.550614 -149.35073)
		(width 0.14224)
		(layer "In11.Cu")
		(net "M_F_DQS_DN<13>")
	)
	(segment
		(start 283.093922 -151.83612)
		(end 282.938982 -151.83612)
		(width 0.14224)
		(layer "In11.Cu")
		(net "M_F_DQS_DN<13>")
	)
	(segment
		(start 283.198062 -151.2062)
		(end 283.477462 -150.9268)
		(width 0.14224)
		(layer "In11.Cu")
		(net "M_F_DQS_DN<13>")
	)
	(segment
		(start 282.969462 -153.162)
		(end 282.806902 -152.99944)
		(width 0.14224)
		(layer "In11.Cu")
		(net "M_F_DQS_DN<13>")
	)
	(segment
		(start 282.806902 -152.63876)
		(end 282.946602 -152.49906)
		(width 0.14224)
		(layer "In11.Cu")
		(net "M_F_DQS_DN<13>")
	)
	(segment
		(start 273.135598 -96.319086)
		(end 273.130772 -96.327722)
		(width 0.0889)
		(layer "In11.Cu")
		(net "M_F_DQS_DN<13>")
	)
	(segment
		(start 273.141948 -96.308418)
		(end 273.135598 -96.319086)
		(width 0.0889)
		(layer "In11.Cu")
		(net "M_F_DQS_DN<13>")
	)
	(segment
		(start 282.806902 -151.35606)
		(end 282.956762 -151.2062)
		(width 0.14224)
		(layer "In11.Cu")
		(net "M_F_DQS_DN<13>")
	)
	(segment
		(start 274.340828 -92.714064)
		(end 274.282916 -92.656152)
		(width 0.0889)
		(layer "In11.Cu")
		(net "M_F_DQS_DN<13>")
	)
	(segment
		(start 283.477462 -150.523448)
		(end 283.042614 -150.0886)
		(width 0.14224)
		(layer "In11.Cu")
		(net "M_F_DQS_DN<13>")
	)
	(segment
		(start 283.742892 -126.674118)
		(end 283.824934 -126.872238)
		(width 0.14224)
		(layer "In11.Cu")
		(net "M_F_DQS_DN<13>")
	)
	(segment
		(start 283.482288 -153.349706)
		(end 283.294582 -153.162)
		(width 0.14224)
		(layer "In11.Cu")
		(net "M_F_DQS_DN<13>")
	)
	(segment
		(start 283.042614 -150.0886)
		(end 283.04236 -150.0886)
		(width 0.14224)
		(layer "In11.Cu")
		(net "M_F_DQS_DN<13>")
	)
	(segment
		(start 273.477482 -99.891088)
		(end 273.495262 -99.891088)
		(width 0.0889)
		(layer "In11.Cu")
		(net "M_F_DQS_DN<13>")
	)
	(segment
		(start 273.135598 -95.328486)
		(end 273.130772 -95.337122)
		(width 0.0889)
		(layer "In11.Cu")
		(net "M_F_DQS_DN<13>")
	)
	(segment
		(start 273.994118 -100.18649)
		(end 274.157694 -100.469446)
		(width 0.0889)
		(layer "In11.Cu")
		(net "M_F_DQS_DN<13>")
	)
	(segment
		(start 283.482288 -153.833576)
		(end 283.482288 -153.349706)
		(width 0.14224)
		(layer "In11.Cu")
		(net "M_F_DQS_DN<13>")
	)
	(segment
		(start 283.294582 -153.162)
		(end 282.969462 -153.162)
		(width 0.14224)
		(layer "In11.Cu")
		(net "M_F_DQS_DN<13>")
	)
	(segment
		(start 283.824934 -126.872238)
		(end 283.824934 -149.07641)
		(width 0.14224)
		(layer "In11.Cu")
		(net "M_F_DQS_DN<13>")
	)
	(segment
		(start 283.550614 -149.35073)
		(end 283.550614 -149.617176)
		(width 0.14224)
		(layer "In11.Cu")
		(net "M_F_DQS_DN<13>")
	)
	(segment
		(start 274.87499 -104.771698)
		(end 274.87499 -104.793796)
		(width 0.0889)
		(layer "In11.Cu")
		(net "M_F_DQS_DN<13>")
	)
	(segment
		(start 283.093922 -152.49906)
		(end 283.248862 -152.34412)
		(width 0.14224)
		(layer "In11.Cu")
		(net "M_F_DQS_DN<13>")
	)
	(segment
		(start 282.806902 -151.70404)
		(end 282.806902 -151.35606)
		(width 0.14224)
		(layer "In11.Cu")
		(net "M_F_DQS_DN<13>")
	)
	(segment
		(start 274.340828 -93.052138)
		(end 274.340828 -92.714064)
		(width 0.0889)
		(layer "In11.Cu")
		(net "M_F_DQS_DN<13>")
	)
	(segment
		(start 273.135598 -97.309686)
		(end 273.130772 -97.318322)
		(width 0.0889)
		(layer "In11.Cu")
		(net "M_F_DQS_DN<13>")
	)
	(segment
		(start 273.495262 -94.137988)
		(end 273.471132 -94.137988)
		(width 0.0889)
		(layer "In11.Cu")
		(net "M_F_DQS_DN<13>")
	)
	(segment
		(start 282.938982 -151.83612)
		(end 282.806902 -151.70404)
		(width 0.14224)
		(layer "In11.Cu")
		(net "M_F_DQS_DN<13>")
	)
	(segment
		(start 273.135598 -94.737936)
		(end 273.141948 -94.748604)
		(width 0.0889)
		(layer "In11.Cu")
		(net "M_F_DQS_DN<13>")
	)
	(segment
		(start 280.418286 -122.83186)
		(end 283.377132 -125.790706)
		(width 0.14224)
		(layer "In11.Cu")
		(net "M_F_DQS_DN<13>")
	)
	(segment
		(start 273.135598 -99.290886)
		(end 273.130772 -99.299522)
		(width 0.0889)
		(layer "In11.Cu")
		(net "M_F_DQS_DN<13>")
	)
	(segment
		(start 283.248862 -151.99106)
		(end 283.093922 -151.83612)
		(width 0.14224)
		(layer "In11.Cu")
		(net "M_F_DQS_DN<13>")
	)
	(segment
		(start 274.83562 -101.147626)
		(end 274.83562 -104.732328)
		(width 0.0889)
		(layer "In11.Cu")
		(net "M_F_DQS_DN<13>")
	)
	(segment
		(start 283.550614 -149.617176)
		(end 283.07919 -150.0886)
		(width 0.14224)
		(layer "In11.Cu")
		(net "M_F_DQS_DN<13>")
	)
	(segment
		(start 273.141948 -97.299018)
		(end 273.135598 -97.309686)
		(width 0.0889)
		(layer "In11.Cu")
		(net "M_F_DQS_DN<13>")
	)
	(segment
		(start 283.07919 -150.0886)
		(end 283.042614 -150.0886)
		(width 0.14224)
		(layer "In11.Cu")
		(net "M_F_DQS_DN<13>")
	)
	(segment
		(start 274.83562 -104.732328)
		(end 274.87499 -104.771698)
		(width 0.0889)
		(layer "In11.Cu")
		(net "M_F_DQS_DN<13>")
	)
	(segment
		(start 283.377132 -125.790706)
		(end 283.742892 -126.674118)
		(width 0.14224)
		(layer "In11.Cu")
		(net "M_F_DQS_DN<13>")
	)
	(segment
		(start 283.048964 -154.2669)
		(end 283.482288 -153.833576)
		(width 0.14224)
		(layer "In11.Cu")
		(net "M_F_DQS_DN<13>")
	)
	(segment
		(start 273.989292 -93.2434)
		(end 273.994118 -93.252036)
		(width 0.0889)
		(layer "In11.Cu")
		(net "M_F_DQS_DN<13>")
	)
	(segment
		(start 282.946602 -152.49906)
		(end 283.093922 -152.49906)
		(width 0.14224)
		(layer "In11.Cu")
		(net "M_F_DQS_DN<13>")
	)
	(segment
		(start 273.141948 -99.280218)
		(end 273.135598 -99.290886)
		(width 0.0889)
		(layer "In11.Cu")
		(net "M_F_DQS_DN<13>")
	)
	(segment
		(start 274.157694 -100.469446)
		(end 274.83562 -101.147626)
		(width 0.0889)
		(layer "In11.Cu")
		(net "M_F_DQS_DN<13>")
	)
	(segment
		(start 283.248862 -152.34412)
		(end 283.248862 -151.99106)
		(width 0.14224)
		(layer "In11.Cu")
		(net "M_F_DQS_DN<13>")
	)
	(segment
		(start 282.956762 -151.2062)
		(end 283.198062 -151.2062)
		(width 0.14224)
		(layer "In11.Cu")
		(net "M_F_DQS_DN<13>")
	)
	(segment
		(start 283.477462 -150.9268)
		(end 283.477462 -150.523448)
		(width 0.14224)
		(layer "In11.Cu")
		(net "M_F_DQS_DN<13>")
	)
	(segment
		(start 274.87499 -104.793796)
		(end 274.87499 -116.082318)
		(width 0.14224)
		(layer "In11.Cu")
		(net "M_F_DQS_DN<13>")
	)
	(segment
		(start 273.135598 -98.300286)
		(end 273.130772 -98.308922)
		(width 0.0889)
		(layer "In11.Cu")
		(net "M_F_DQS_DN<13>")
	)
	(segment
		(start 273.994118 -93.252036)
		(end 274.000468 -93.262704)
		(width 0.0889)
		(layer "In11.Cu")
		(net "M_F_DQS_DN<13>")
	)
	(segment
		(start 274.87499 -116.082318)
		(end 280.418286 -121.625614)
		(width 0.14224)
		(layer "In11.Cu")
		(net "M_F_DQS_DN<13>")
	)
	(segment
		(start 273.141948 -98.289618)
		(end 273.135598 -98.300286)
		(width 0.0889)
		(layer "In11.Cu")
		(net "M_F_DQS_DN<13>")
	)
	(segment
		(start 282.806902 -152.99944)
		(end 282.806902 -152.63876)
		(width 0.14224)
		(layer "In11.Cu")
		(net "M_F_DQS_DN<13>")
	)
	(segment
		(start 280.418286 -121.625614)
		(end 280.418286 -122.83186)
		(width 0.14224)
		(layer "In11.Cu")
		(net "M_F_DQS_DN<13>")
	)
	(arc
		(start 273.471132 -94.137988)
		(mid 273.133017 -94.34269)
		(end 273.135598 -94.737936)
		(width 0.0889)
		(layer "In11.Cu")
		(net "M_F_DQS_DN<13>")
	)
	(arc
		(start 273.130772 -96.327722)
		(mid 273.082017 -96.524074)
		(end 273.135598 -96.719136)
		(width 0.0889)
		(layer "In11.Cu")
		(net "M_F_DQS_DN<13>")
	)
	(arc
		(start 273.135598 -97.709736)
		(mid 273.21482 -97.998854)
		(end 273.141948 -98.289618)
		(width 0.0889)
		(layer "In11.Cu")
		(net "M_F_DQS_DN<13>")
	)
	(arc
		(start 273.135598 -98.700336)
		(mid 273.21482 -98.989454)
		(end 273.141948 -99.280218)
		(width 0.0889)
		(layer "In11.Cu")
		(net "M_F_DQS_DN<13>")
	)
	(arc
		(start 273.135598 -95.728536)
		(mid 273.21482 -96.017654)
		(end 273.141948 -96.308418)
		(width 0.0889)
		(layer "In11.Cu")
		(net "M_F_DQS_DN<13>")
	)
	(arc
		(start 273.495262 -99.891088)
		(mid 273.783407 -99.973407)
		(end 273.994118 -100.18649)
		(width 0.0889)
		(layer "In11.Cu")
		(net "M_F_DQS_DN<13>")
	)
	(arc
		(start 273.130772 -97.318322)
		(mid 273.082017 -97.514674)
		(end 273.135598 -97.709736)
		(width 0.0889)
		(layer "In11.Cu")
		(net "M_F_DQS_DN<13>")
	)
	(arc
		(start 274.000468 -93.262704)
		(mid 273.994291 -93.842636)
		(end 273.495262 -94.137988)
		(width 0.0889)
		(layer "In11.Cu")
		(net "M_F_DQS_DN<13>")
	)
	(arc
		(start 273.130772 -99.299522)
		(mid 273.13706 -99.693177)
		(end 273.477482 -99.891088)
		(width 0.0889)
		(layer "In11.Cu")
		(net "M_F_DQS_DN<13>")
	)
	(arc
		(start 273.141948 -94.748604)
		(mid 273.214746 -95.039367)
		(end 273.135598 -95.328486)
		(width 0.0889)
		(layer "In11.Cu")
		(net "M_F_DQS_DN<13>")
	)
	(arc
		(start 274.282916 -92.656152)
		(mid 273.98288 -92.873164)
		(end 273.989292 -93.2434)
		(width 0.0889)
		(layer "In11.Cu")
		(net "M_F_DQS_DN<13>")
	)
	(arc
		(start 273.130772 -95.337122)
		(mid 273.082017 -95.533474)
		(end 273.135598 -95.728536)
		(width 0.0889)
		(layer "In11.Cu")
		(net "M_F_DQS_DN<13>")
	)
	(arc
		(start 273.135598 -96.719136)
		(mid 273.21482 -97.008254)
		(end 273.141948 -97.299018)
		(width 0.0889)
		(layer "In11.Cu")
		(net "M_F_DQS_DN<13>")
	)
	(arc
		(start 273.130772 -98.308922)
		(mid 273.082017 -98.505274)
		(end 273.135598 -98.700336)
		(width 0.0889)
		(layer "In11.Cu")
		(net "M_F_DQS_DN<13>")
	)
	(segment
		(start 228.007418 -154.45613)
		(end 227.818188 -154.2669)
		(width 0.1651)
		(layer "F.Cu")
		(net "M_F_DQS_DN<12>")
	)
	(segment
		(start 227.818188 -154.2669)
		(end 227.799138 -154.2669)
		(width 0.1651)
		(layer "F.Cu")
		(net "M_F_DQS_DN<12>")
	)
	(segment
		(start 228.699822 -152.932384)
		(end 228.281738 -153.350468)
		(width 0.1651)
		(layer "F.Cu")
		(net "M_F_DQS_DN<12>")
	)
	(segment
		(start 228.70033 -152.273)
		(end 228.699822 -152.278842)
		(width 0.1651)
		(layer "F.Cu")
		(net "M_F_DQS_DN<12>")
	)
	(segment
		(start 228.699822 -152.278842)
		(end 228.699822 -152.932384)
		(width 0.1651)
		(layer "F.Cu")
		(net "M_F_DQS_DN<12>")
	)
	(segment
		(start 228.467666 -154.204162)
		(end 228.215698 -154.45613)
		(width 0.1651)
		(layer "F.Cu")
		(net "M_F_DQS_DN<12>")
	)
	(segment
		(start 250.778264 -85.803486)
		(end 250.206764 -85.803486)
		(width 0.1651)
		(layer "F.Cu")
		(net "M_F_DQS_DN<12>")
	)
	(segment
		(start 228.281738 -153.7716)
		(end 228.467666 -153.957528)
		(width 0.1651)
		(layer "F.Cu")
		(net "M_F_DQS_DN<12>")
	)
	(segment
		(start 228.467666 -153.957528)
		(end 228.467666 -154.204162)
		(width 0.1651)
		(layer "F.Cu")
		(net "M_F_DQS_DN<12>")
	)
	(segment
		(start 228.281738 -153.350468)
		(end 228.281738 -153.7716)
		(width 0.1651)
		(layer "F.Cu")
		(net "M_F_DQS_DN<12>")
	)
	(segment
		(start 228.215698 -154.45613)
		(end 228.007418 -154.45613)
		(width 0.1651)
		(layer "F.Cu")
		(net "M_F_DQS_DN<12>")
	)
	(via
		(at 227.792534 -150.0886)
		(size 0.508)
		(drill 0.254)
		(layers "F.Cu" "B.Cu")
		(net "M_F_DQS_DN<12>")
	)
	(via
		(at 250.206764 -85.803486)
		(size 0.508)
		(drill 0.254)
		(layers "F.Cu" "B.Cu")
		(net "M_F_DQS_DN<12>")
	)
	(via
		(at 227.799138 -154.2669)
		(size 0.508)
		(drill 0.254)
		(layers "F.Cu" "B.Cu")
		(net "M_F_DQS_DN<12>")
	)
	(segment
		(start 228.70033 -152.078436)
		(end 228.700076 -152.077928)
		(width 0.1651)
		(layer "B.Cu")
		(net "M_F_DQS_DN<12>")
	)
	(segment
		(start 228.700076 -152.077928)
		(end 228.700076 -151.421592)
		(width 0.1651)
		(layer "B.Cu")
		(net "M_F_DQS_DN<12>")
	)
	(segment
		(start 228.434138 -150.4442)
		(end 228.434138 -150.114)
		(width 0.1651)
		(layer "B.Cu")
		(net "M_F_DQS_DN<12>")
	)
	(segment
		(start 227.987098 -149.894036)
		(end 227.792534 -150.0886)
		(width 0.1651)
		(layer "B.Cu")
		(net "M_F_DQS_DN<12>")
	)
	(segment
		(start 228.256338 -150.977854)
		(end 228.256338 -150.622)
		(width 0.1651)
		(layer "B.Cu")
		(net "M_F_DQS_DN<12>")
	)
	(segment
		(start 228.434138 -150.114)
		(end 228.214174 -149.894036)
		(width 0.1651)
		(layer "B.Cu")
		(net "M_F_DQS_DN<12>")
	)
	(segment
		(start 228.214174 -149.894036)
		(end 227.987098 -149.894036)
		(width 0.1651)
		(layer "B.Cu")
		(net "M_F_DQS_DN<12>")
	)
	(segment
		(start 228.700076 -151.421592)
		(end 228.256338 -150.977854)
		(width 0.1651)
		(layer "B.Cu")
		(net "M_F_DQS_DN<12>")
	)
	(segment
		(start 228.256338 -150.622)
		(end 228.434138 -150.4442)
		(width 0.1651)
		(layer "B.Cu")
		(net "M_F_DQS_DN<12>")
	)
	(segment
		(start 250.206764 -85.465412)
		(end 250.148852 -85.4075)
		(width 0.0889)
		(layer "In11.Cu")
		(net "M_F_DQS_DN<12>")
	)
	(segment
		(start 245.316502 -103.196898)
		(end 245.316502 -105.120186)
		(width 0.14224)
		(layer "In11.Cu")
		(net "M_F_DQS_DN<12>")
	)
	(segment
		(start 246.170196 -99.76739)
		(end 245.72468 -99.76739)
		(width 0.0889)
		(layer "In11.Cu")
		(net "M_F_DQS_DN<12>")
	)
	(segment
		(start 228.574854 -124.67844)
		(end 228.574854 -149.313646)
		(width 0.14224)
		(layer "In11.Cu")
		(net "M_F_DQS_DN<12>")
	)
	(segment
		(start 249.860054 -91.547188)
		(end 249.855228 -91.555824)
		(width 0.0889)
		(layer "In11.Cu")
		(net "M_F_DQS_DN<12>")
	)
	(segment
		(start 228.044502 -153.162)
		(end 228.232208 -153.349706)
		(width 0.14224)
		(layer "In11.Cu")
		(net "M_F_DQS_DN<12>")
	)
	(segment
		(start 227.556822 -151.70404)
		(end 227.688902 -151.83612)
		(width 0.14224)
		(layer "In11.Cu")
		(net "M_F_DQS_DN<12>")
	)
	(segment
		(start 249.007884 -94.01302)
		(end 249.001534 -94.023688)
		(width 0.0889)
		(layer "In11.Cu")
		(net "M_F_DQS_DN<12>")
	)
	(segment
		(start 228.227382 -150.523448)
		(end 228.227382 -150.9268)
		(width 0.14224)
		(layer "In11.Cu")
		(net "M_F_DQS_DN<12>")
	)
	(segment
		(start 249.866404 -86.58352)
		(end 249.860054 -86.594188)
		(width 0.0889)
		(layer "In11.Cu")
		(net "M_F_DQS_DN<12>")
	)
	(segment
		(start 249.001534 -95.414338)
		(end 249.007884 -95.425006)
		(width 0.0889)
		(layer "In11.Cu")
		(net "M_F_DQS_DN<12>")
	)
	(segment
		(start 249.00128 -96.005142)
		(end 248.7422 -96.453452)
		(width 0.0889)
		(layer "In11.Cu")
		(net "M_F_DQS_DN<12>")
	)
	(segment
		(start 227.998782 -151.99106)
		(end 227.998782 -152.34412)
		(width 0.14224)
		(layer "In11.Cu")
		(net "M_F_DQS_DN<12>")
	)
	(segment
		(start 249.866404 -89.55532)
		(end 249.860054 -89.565988)
		(width 0.0889)
		(layer "In11.Cu")
		(net "M_F_DQS_DN<12>")
	)
	(segment
		(start 227.706682 -151.2062)
		(end 227.556822 -151.35606)
		(width 0.14224)
		(layer "In11.Cu")
		(net "M_F_DQS_DN<12>")
	)
	(segment
		(start 249.860054 -86.594188)
		(end 249.855228 -86.602824)
		(width 0.0889)
		(layer "In11.Cu")
		(net "M_F_DQS_DN<12>")
	)
	(segment
		(start 227.792534 -150.0886)
		(end 228.227382 -150.523448)
		(width 0.14224)
		(layer "In11.Cu")
		(net "M_F_DQS_DN<12>")
	)
	(segment
		(start 248.996708 -95.405702)
		(end 249.001534 -95.414338)
		(width 0.0889)
		(layer "In11.Cu")
		(net "M_F_DQS_DN<12>")
	)
	(segment
		(start 249.860054 -90.556588)
		(end 249.855228 -90.565224)
		(width 0.0889)
		(layer "In11.Cu")
		(net "M_F_DQS_DN<12>")
	)
	(segment
		(start 227.688902 -151.83612)
		(end 227.843842 -151.83612)
		(width 0.14224)
		(layer "In11.Cu")
		(net "M_F_DQS_DN<12>")
	)
	(segment
		(start 241.57432 -108.862368)
		(end 241.57432 -114.313208)
		(width 0.14224)
		(layer "In11.Cu")
		(net "M_F_DQS_DN<12>")
	)
	(segment
		(start 227.696522 -152.49906)
		(end 227.556822 -152.63876)
		(width 0.14224)
		(layer "In11.Cu")
		(net "M_F_DQS_DN<12>")
	)
	(segment
		(start 248.996708 -93.424502)
		(end 249.001534 -93.433138)
		(width 0.0889)
		(layer "In11.Cu")
		(net "M_F_DQS_DN<12>")
	)
	(segment
		(start 249.860054 -89.565988)
		(end 249.855228 -89.574624)
		(width 0.0889)
		(layer "In11.Cu")
		(net "M_F_DQS_DN<12>")
	)
	(segment
		(start 232.041446 -120.54332)
		(end 229.047548 -123.537218)
		(width 0.14224)
		(layer "In11.Cu")
		(net "M_F_DQS_DN<12>")
	)
	(segment
		(start 227.7999 -150.0886)
		(end 227.792534 -150.0886)
		(width 0.14224)
		(layer "In11.Cu")
		(net "M_F_DQS_DN<12>")
	)
	(segment
		(start 228.227382 -150.9268)
		(end 227.947982 -151.2062)
		(width 0.14224)
		(layer "In11.Cu")
		(net "M_F_DQS_DN<12>")
	)
	(segment
		(start 227.556822 -151.35606)
		(end 227.556822 -151.70404)
		(width 0.14224)
		(layer "In11.Cu")
		(net "M_F_DQS_DN<12>")
	)
	(segment
		(start 241.57432 -114.313208)
		(end 235.344208 -120.54332)
		(width 0.14224)
		(layer "In11.Cu")
		(net "M_F_DQS_DN<12>")
	)
	(segment
		(start 245.316502 -103.1748)
		(end 245.316502 -103.196898)
		(width 0.0889)
		(layer "In11.Cu")
		(net "M_F_DQS_DN<12>")
	)
	(segment
		(start 228.574854 -149.313646)
		(end 227.7999 -150.0886)
		(width 0.14224)
		(layer "In11.Cu")
		(net "M_F_DQS_DN<12>")
	)
	(segment
		(start 249.001534 -96.004888)
		(end 249.00128 -96.005142)
		(width 0.0889)
		(layer "In11.Cu")
		(net "M_F_DQS_DN<12>")
	)
	(segment
		(start 235.344208 -120.54332)
		(end 232.041446 -120.54332)
		(width 0.14224)
		(layer "In11.Cu")
		(net "M_F_DQS_DN<12>")
	)
	(segment
		(start 227.719382 -153.162)
		(end 228.044502 -153.162)
		(width 0.14224)
		(layer "In11.Cu")
		(net "M_F_DQS_DN<12>")
	)
	(segment
		(start 227.843842 -151.83612)
		(end 227.998782 -151.99106)
		(width 0.14224)
		(layer "In11.Cu")
		(net "M_F_DQS_DN<12>")
	)
	(segment
		(start 250.206764 -85.803486)
		(end 250.206764 -85.465412)
		(width 0.0889)
		(layer "In11.Cu")
		(net "M_F_DQS_DN<12>")
	)
	(segment
		(start 249.366024 -92.83319)
		(end 249.333258 -92.83319)
		(width 0.0889)
		(layer "In11.Cu")
		(net "M_F_DQS_DN<12>")
	)
	(segment
		(start 249.860054 -87.584788)
		(end 249.855228 -87.593424)
		(width 0.0889)
		(layer "In11.Cu")
		(net "M_F_DQS_DN<12>")
	)
	(segment
		(start 227.556822 -152.63876)
		(end 227.556822 -152.99944)
		(width 0.14224)
		(layer "In11.Cu")
		(net "M_F_DQS_DN<12>")
	)
	(segment
		(start 249.866404 -90.54592)
		(end 249.860054 -90.556588)
		(width 0.0889)
		(layer "In11.Cu")
		(net "M_F_DQS_DN<12>")
	)
	(segment
		(start 227.998782 -152.34412)
		(end 227.843842 -152.49906)
		(width 0.14224)
		(layer "In11.Cu")
		(net "M_F_DQS_DN<12>")
	)
	(segment
		(start 249.866404 -87.57412)
		(end 249.860054 -87.584788)
		(width 0.0889)
		(layer "In11.Cu")
		(net "M_F_DQS_DN<12>")
	)
	(segment
		(start 227.556822 -152.99944)
		(end 227.719382 -153.162)
		(width 0.14224)
		(layer "In11.Cu")
		(net "M_F_DQS_DN<12>")
	)
	(segment
		(start 228.232208 -153.83383)
		(end 227.799138 -154.2669)
		(width 0.14224)
		(layer "In11.Cu")
		(net "M_F_DQS_DN<12>")
	)
	(segment
		(start 246.772684 -99.164902)
		(end 246.170196 -99.76739)
		(width 0.0889)
		(layer "In11.Cu")
		(net "M_F_DQS_DN<12>")
	)
	(segment
		(start 229.047548 -123.537218)
		(end 228.574854 -124.67844)
		(width 0.14224)
		(layer "In11.Cu")
		(net "M_F_DQS_DN<12>")
	)
	(segment
		(start 245.510304 -100.065586)
		(end 245.277132 -100.48875)
		(width 0.0889)
		(layer "In11.Cu")
		(net "M_F_DQS_DN<12>")
	)
	(segment
		(start 245.625112 -99.866958)
		(end 245.510304 -100.065586)
		(width 0.0889)
		(layer "In11.Cu")
		(net "M_F_DQS_DN<12>")
	)
	(segment
		(start 245.72468 -99.76739)
		(end 245.625112 -99.866958)
		(width 0.0889)
		(layer "In11.Cu")
		(net "M_F_DQS_DN<12>")
	)
	(segment
		(start 227.843842 -152.49906)
		(end 227.696522 -152.49906)
		(width 0.14224)
		(layer "In11.Cu")
		(net "M_F_DQS_DN<12>")
	)
	(segment
		(start 245.277132 -100.48875)
		(end 245.277132 -103.13543)
		(width 0.0889)
		(layer "In11.Cu")
		(net "M_F_DQS_DN<12>")
	)
	(segment
		(start 249.866404 -88.56472)
		(end 249.860054 -88.575388)
		(width 0.0889)
		(layer "In11.Cu")
		(net "M_F_DQS_DN<12>")
	)
	(segment
		(start 245.277132 -103.13543)
		(end 245.316502 -103.1748)
		(width 0.0889)
		(layer "In11.Cu")
		(net "M_F_DQS_DN<12>")
	)
	(segment
		(start 249.860054 -88.575388)
		(end 249.855228 -88.584024)
		(width 0.0889)
		(layer "In11.Cu")
		(net "M_F_DQS_DN<12>")
	)
	(segment
		(start 228.232208 -153.349706)
		(end 228.232208 -153.83383)
		(width 0.14224)
		(layer "In11.Cu")
		(net "M_F_DQS_DN<12>")
	)
	(segment
		(start 248.7422 -96.453452)
		(end 246.772684 -98.422968)
		(width 0.0889)
		(layer "In11.Cu")
		(net "M_F_DQS_DN<12>")
	)
	(segment
		(start 246.772684 -98.422968)
		(end 246.772684 -99.164902)
		(width 0.0889)
		(layer "In11.Cu")
		(net "M_F_DQS_DN<12>")
	)
	(segment
		(start 227.947982 -151.2062)
		(end 227.706682 -151.2062)
		(width 0.14224)
		(layer "In11.Cu")
		(net "M_F_DQS_DN<12>")
	)
	(segment
		(start 249.866404 -91.53652)
		(end 249.860054 -91.547188)
		(width 0.0889)
		(layer "In11.Cu")
		(net "M_F_DQS_DN<12>")
	)
	(segment
		(start 245.316502 -105.120186)
		(end 241.57432 -108.862368)
		(width 0.14224)
		(layer "In11.Cu")
		(net "M_F_DQS_DN<12>")
	)
	(arc
		(start 249.855228 -86.602824)
		(mid 249.806473 -86.799176)
		(end 249.860054 -86.994238)
		(width 0.0889)
		(layer "In11.Cu")
		(net "M_F_DQS_DN<12>")
	)
	(arc
		(start 250.148852 -85.4075)
		(mid 249.846583 -85.629049)
		(end 249.860054 -86.003638)
		(width 0.0889)
		(layer "In11.Cu")
		(net "M_F_DQS_DN<12>")
	)
	(arc
		(start 249.860054 -86.003638)
		(mid 249.939276 -86.292756)
		(end 249.866404 -86.58352)
		(width 0.0889)
		(layer "In11.Cu")
		(net "M_F_DQS_DN<12>")
	)
	(arc
		(start 249.860054 -90.956638)
		(mid 249.939276 -91.245756)
		(end 249.866404 -91.53652)
		(width 0.0889)
		(layer "In11.Cu")
		(net "M_F_DQS_DN<12>")
	)
	(arc
		(start 249.860054 -87.984838)
		(mid 249.939276 -88.273956)
		(end 249.866404 -88.56472)
		(width 0.0889)
		(layer "In11.Cu")
		(net "M_F_DQS_DN<12>")
	)
	(arc
		(start 249.860054 -86.994238)
		(mid 249.939276 -87.283356)
		(end 249.866404 -87.57412)
		(width 0.0889)
		(layer "In11.Cu")
		(net "M_F_DQS_DN<12>")
	)
	(arc
		(start 249.855228 -88.584024)
		(mid 249.806473 -88.780376)
		(end 249.860054 -88.975438)
		(width 0.0889)
		(layer "In11.Cu")
		(net "M_F_DQS_DN<12>")
	)
	(arc
		(start 249.860054 -91.947238)
		(mid 249.864383 -92.53041)
		(end 249.366024 -92.83319)
		(width 0.0889)
		(layer "In11.Cu")
		(net "M_F_DQS_DN<12>")
	)
	(arc
		(start 249.333258 -92.83319)
		(mid 249.00034 -93.035181)
		(end 248.996708 -93.424502)
		(width 0.0889)
		(layer "In11.Cu")
		(net "M_F_DQS_DN<12>")
	)
	(arc
		(start 249.860054 -88.975438)
		(mid 249.939276 -89.264556)
		(end 249.866404 -89.55532)
		(width 0.0889)
		(layer "In11.Cu")
		(net "M_F_DQS_DN<12>")
	)
	(arc
		(start 249.860054 -89.966038)
		(mid 249.939276 -90.255156)
		(end 249.866404 -90.54592)
		(width 0.0889)
		(layer "In11.Cu")
		(net "M_F_DQS_DN<12>")
	)
	(arc
		(start 249.001534 -94.023688)
		(mid 248.948035 -94.223586)
		(end 249.001534 -94.423484)
		(width 0.0889)
		(layer "In11.Cu")
		(net "M_F_DQS_DN<12>")
	)
	(arc
		(start 249.001534 -93.433138)
		(mid 249.080756 -93.722256)
		(end 249.007884 -94.01302)
		(width 0.0889)
		(layer "In11.Cu")
		(net "M_F_DQS_DN<12>")
	)
	(arc
		(start 249.855228 -89.574624)
		(mid 249.806473 -89.770976)
		(end 249.860054 -89.966038)
		(width 0.0889)
		(layer "In11.Cu")
		(net "M_F_DQS_DN<12>")
	)
	(arc
		(start 249.855228 -87.593424)
		(mid 249.806473 -87.789776)
		(end 249.860054 -87.984838)
		(width 0.0889)
		(layer "In11.Cu")
		(net "M_F_DQS_DN<12>")
	)
	(arc
		(start 249.001534 -94.423484)
		(mid 249.080665 -94.718886)
		(end 249.001534 -95.014288)
		(width 0.0889)
		(layer "In11.Cu")
		(net "M_F_DQS_DN<12>")
	)
	(arc
		(start 249.001534 -95.014288)
		(mid 248.948064 -95.209351)
		(end 248.996708 -95.405702)
		(width 0.0889)
		(layer "In11.Cu")
		(net "M_F_DQS_DN<12>")
	)
	(arc
		(start 249.855228 -90.565224)
		(mid 249.806473 -90.761576)
		(end 249.860054 -90.956638)
		(width 0.0889)
		(layer "In11.Cu")
		(net "M_F_DQS_DN<12>")
	)
	(arc
		(start 249.855228 -91.555824)
		(mid 249.806473 -91.752176)
		(end 249.860054 -91.947238)
		(width 0.0889)
		(layer "In11.Cu")
		(net "M_F_DQS_DN<12>")
	)
	(arc
		(start 249.007884 -95.425006)
		(mid 249.080682 -95.715769)
		(end 249.001534 -96.004888)
		(width 0.0889)
		(layer "In11.Cu")
		(net "M_F_DQS_DN<12>")
	)
	(segment
		(start 218.931744 -153.350468)
		(end 218.931744 -153.7716)
		(width 0.1651)
		(layer "F.Cu")
		(net "M_F_DQS_DN<11>")
	)
	(segment
		(start 219.117672 -153.957528)
		(end 219.117672 -154.204162)
		(width 0.1651)
		(layer "F.Cu")
		(net "M_F_DQS_DN<11>")
	)
	(segment
		(start 246.485664 -93.23324)
		(end 245.914164 -93.23324)
		(width 0.1651)
		(layer "F.Cu")
		(net "M_F_DQS_DN<11>")
	)
	(segment
		(start 218.468194 -154.2669)
		(end 218.449144 -154.2669)
		(width 0.1651)
		(layer "F.Cu")
		(net "M_F_DQS_DN<11>")
	)
	(segment
		(start 219.349828 -152.932384)
		(end 218.931744 -153.350468)
		(width 0.1651)
		(layer "F.Cu")
		(net "M_F_DQS_DN<11>")
	)
	(segment
		(start 218.657424 -154.45613)
		(end 218.468194 -154.2669)
		(width 0.1651)
		(layer "F.Cu")
		(net "M_F_DQS_DN<11>")
	)
	(segment
		(start 218.931744 -153.7716)
		(end 219.117672 -153.957528)
		(width 0.1651)
		(layer "F.Cu")
		(net "M_F_DQS_DN<11>")
	)
	(segment
		(start 218.865704 -154.45613)
		(end 218.657424 -154.45613)
		(width 0.1651)
		(layer "F.Cu")
		(net "M_F_DQS_DN<11>")
	)
	(segment
		(start 219.350336 -152.273)
		(end 219.349828 -152.278842)
		(width 0.1651)
		(layer "F.Cu")
		(net "M_F_DQS_DN<11>")
	)
	(segment
		(start 219.349828 -152.278842)
		(end 219.349828 -152.932384)
		(width 0.1651)
		(layer "F.Cu")
		(net "M_F_DQS_DN<11>")
	)
	(segment
		(start 219.117672 -154.204162)
		(end 218.865704 -154.45613)
		(width 0.1651)
		(layer "F.Cu")
		(net "M_F_DQS_DN<11>")
	)
	(via
		(at 245.914164 -93.23324)
		(size 0.508)
		(drill 0.254)
		(layers "F.Cu" "B.Cu")
		(net "M_F_DQS_DN<11>")
	)
	(via
		(at 218.44254 -150.0886)
		(size 0.508)
		(drill 0.254)
		(layers "F.Cu" "B.Cu")
		(net "M_F_DQS_DN<11>")
	)
	(via
		(at 218.449144 -154.2669)
		(size 0.508)
		(drill 0.254)
		(layers "F.Cu" "B.Cu")
		(net "M_F_DQS_DN<11>")
	)
	(segment
		(start 219.084144 -150.4442)
		(end 219.084144 -150.114)
		(width 0.1651)
		(layer "B.Cu")
		(net "M_F_DQS_DN<11>")
	)
	(segment
		(start 218.906344 -150.622)
		(end 219.084144 -150.4442)
		(width 0.1651)
		(layer "B.Cu")
		(net "M_F_DQS_DN<11>")
	)
	(segment
		(start 219.084144 -150.114)
		(end 218.86418 -149.894036)
		(width 0.1651)
		(layer "B.Cu")
		(net "M_F_DQS_DN<11>")
	)
	(segment
		(start 218.906344 -150.977854)
		(end 218.906344 -150.622)
		(width 0.1651)
		(layer "B.Cu")
		(net "M_F_DQS_DN<11>")
	)
	(segment
		(start 218.637104 -149.894036)
		(end 218.44254 -150.0886)
		(width 0.1651)
		(layer "B.Cu")
		(net "M_F_DQS_DN<11>")
	)
	(segment
		(start 219.350082 -152.077928)
		(end 219.350082 -151.421592)
		(width 0.1651)
		(layer "B.Cu")
		(net "M_F_DQS_DN<11>")
	)
	(segment
		(start 218.86418 -149.894036)
		(end 218.637104 -149.894036)
		(width 0.1651)
		(layer "B.Cu")
		(net "M_F_DQS_DN<11>")
	)
	(segment
		(start 219.350082 -151.421592)
		(end 218.906344 -150.977854)
		(width 0.1651)
		(layer "B.Cu")
		(net "M_F_DQS_DN<11>")
	)
	(segment
		(start 219.350336 -152.078436)
		(end 219.350082 -152.077928)
		(width 0.1651)
		(layer "B.Cu")
		(net "M_F_DQS_DN<11>")
	)
	(segment
		(start 239.064038 -96.79559)
		(end 239.031272 -96.79559)
		(width 0.0889)
		(layer "In11.Cu")
		(net "M_F_DQS_DN<11>")
	)
	(segment
		(start 233.31424 -105.2068)
		(end 233.31424 -107.460288)
		(width 0.14224)
		(layer "In11.Cu")
		(net "M_F_DQS_DN<11>")
	)
	(segment
		(start 218.449906 -150.0886)
		(end 218.44254 -150.0886)
		(width 0.14224)
		(layer "In11.Cu")
		(net "M_F_DQS_DN<11>")
	)
	(segment
		(start 218.597988 -151.2062)
		(end 218.356688 -151.2062)
		(width 0.14224)
		(layer "In11.Cu")
		(net "M_F_DQS_DN<11>")
	)
	(segment
		(start 218.694508 -153.162)
		(end 218.882214 -153.349706)
		(width 0.14224)
		(layer "In11.Cu")
		(net "M_F_DQS_DN<11>")
	)
	(segment
		(start 236.123988 -99.872038)
		(end 236.130338 -99.882706)
		(width 0.0889)
		(layer "In11.Cu")
		(net "M_F_DQS_DN<11>")
	)
	(segment
		(start 218.206828 -151.70404)
		(end 218.338908 -151.83612)
		(width 0.14224)
		(layer "In11.Cu")
		(net "M_F_DQS_DN<11>")
	)
	(segment
		(start 236.492288 -98.281236)
		(end 236.459522 -98.281236)
		(width 0.0889)
		(layer "In11.Cu")
		(net "M_F_DQS_DN<11>")
	)
	(segment
		(start 218.476068 -151.83612)
		(end 218.631008 -151.99106)
		(width 0.14224)
		(layer "In11.Cu")
		(net "M_F_DQS_DN<11>")
	)
	(segment
		(start 245.914164 -93.23324)
		(end 246.20728 -93.064076)
		(width 0.0889)
		(layer "In11.Cu")
		(net "M_F_DQS_DN<11>")
	)
	(segment
		(start 233.31424 -107.460288)
		(end 220.28912 -120.485408)
		(width 0.14224)
		(layer "In11.Cu")
		(net "M_F_DQS_DN<11>")
	)
	(segment
		(start 239.926368 -96.300036)
		(end 239.893602 -96.300036)
		(width 0.0889)
		(layer "In11.Cu")
		(net "M_F_DQS_DN<11>")
	)
	(segment
		(start 238.209328 -97.290636)
		(end 238.176562 -97.290636)
		(width 0.0889)
		(layer "In11.Cu")
		(net "M_F_DQS_DN<11>")
	)
	(segment
		(start 246.20728 -93.064076)
		(end 246.228362 -92.985336)
		(width 0.0889)
		(layer "In11.Cu")
		(net "M_F_DQS_DN<11>")
	)
	(segment
		(start 220.28912 -120.485408)
		(end 220.28912 -125.971808)
		(width 0.14224)
		(layer "In11.Cu")
		(net "M_F_DQS_DN<11>")
	)
	(segment
		(start 236.123988 -100.462588)
		(end 236.119162 -100.471224)
		(width 0.0889)
		(layer "In11.Cu")
		(net "M_F_DQS_DN<11>")
	)
	(segment
		(start 218.44254 -150.0886)
		(end 218.877388 -150.523448)
		(width 0.14224)
		(layer "In11.Cu")
		(net "M_F_DQS_DN<11>")
	)
	(segment
		(start 236.061504 -102.40391)
		(end 234.514644 -103.95077)
		(width 0.0889)
		(layer "In11.Cu")
		(net "M_F_DQS_DN<11>")
	)
	(segment
		(start 241.643408 -95.309436)
		(end 241.610642 -95.309436)
		(width 0.0889)
		(layer "In11.Cu")
		(net "M_F_DQS_DN<11>")
	)
	(segment
		(start 219.22486 -149.313646)
		(end 218.449906 -150.0886)
		(width 0.14224)
		(layer "In11.Cu")
		(net "M_F_DQS_DN<11>")
	)
	(segment
		(start 219.22486 -127.036068)
		(end 219.22486 -149.313646)
		(width 0.14224)
		(layer "In11.Cu")
		(net "M_F_DQS_DN<11>")
	)
	(segment
		(start 218.877388 -150.523448)
		(end 218.877388 -150.9268)
		(width 0.14224)
		(layer "In11.Cu")
		(net "M_F_DQS_DN<11>")
	)
	(segment
		(start 244.218714 -93.82379)
		(end 244.17909 -93.82379)
		(width 0.0889)
		(layer "In11.Cu")
		(net "M_F_DQS_DN<11>")
	)
	(segment
		(start 218.877388 -150.9268)
		(end 218.597988 -151.2062)
		(width 0.14224)
		(layer "In11.Cu")
		(net "M_F_DQS_DN<11>")
	)
	(segment
		(start 234.498896 -104.022144)
		(end 233.31424 -105.2068)
		(width 0.14224)
		(layer "In11.Cu")
		(net "M_F_DQS_DN<11>")
	)
	(segment
		(start 218.882214 -153.349706)
		(end 218.882214 -153.83383)
		(width 0.14224)
		(layer "In11.Cu")
		(net "M_F_DQS_DN<11>")
	)
	(segment
		(start 218.476068 -152.49906)
		(end 218.346528 -152.49906)
		(width 0.14224)
		(layer "In11.Cu")
		(net "M_F_DQS_DN<11>")
	)
	(segment
		(start 237.346998 -97.78619)
		(end 237.314232 -97.78619)
		(width 0.0889)
		(layer "In11.Cu")
		(net "M_F_DQS_DN<11>")
	)
	(segment
		(start 234.514644 -103.95077)
		(end 234.514644 -104.006396)
		(width 0.0889)
		(layer "In11.Cu")
		(net "M_F_DQS_DN<11>")
	)
	(segment
		(start 218.206828 -151.35606)
		(end 218.206828 -151.70404)
		(width 0.14224)
		(layer "In11.Cu")
		(net "M_F_DQS_DN<11>")
	)
	(segment
		(start 245.068598 -93.32849)
		(end 245.044468 -93.32849)
		(width 0.0889)
		(layer "In11.Cu")
		(net "M_F_DQS_DN<11>")
	)
	(segment
		(start 220.28912 -125.971808)
		(end 219.22486 -127.036068)
		(width 0.14224)
		(layer "In11.Cu")
		(net "M_F_DQS_DN<11>")
	)
	(segment
		(start 236.130338 -101.44252)
		(end 236.061504 -101.561392)
		(width 0.0889)
		(layer "In11.Cu")
		(net "M_F_DQS_DN<11>")
	)
	(segment
		(start 218.356688 -151.2062)
		(end 218.206828 -151.35606)
		(width 0.14224)
		(layer "In11.Cu")
		(net "M_F_DQS_DN<11>")
	)
	(segment
		(start 240.781078 -95.80499)
		(end 240.748312 -95.80499)
		(width 0.0889)
		(layer "In11.Cu")
		(net "M_F_DQS_DN<11>")
	)
	(segment
		(start 218.631008 -152.34412)
		(end 218.476068 -152.49906)
		(width 0.14224)
		(layer "In11.Cu")
		(net "M_F_DQS_DN<11>")
	)
	(segment
		(start 218.346528 -152.49906)
		(end 218.206828 -152.63876)
		(width 0.14224)
		(layer "In11.Cu")
		(net "M_F_DQS_DN<11>")
	)
	(segment
		(start 218.369388 -153.162)
		(end 218.694508 -153.162)
		(width 0.14224)
		(layer "In11.Cu")
		(net "M_F_DQS_DN<11>")
	)
	(segment
		(start 218.882214 -153.83383)
		(end 218.449144 -154.2669)
		(width 0.14224)
		(layer "In11.Cu")
		(net "M_F_DQS_DN<11>")
	)
	(segment
		(start 218.206828 -152.99944)
		(end 218.369388 -153.162)
		(width 0.14224)
		(layer "In11.Cu")
		(net "M_F_DQS_DN<11>")
	)
	(segment
		(start 218.338908 -151.83612)
		(end 218.476068 -151.83612)
		(width 0.14224)
		(layer "In11.Cu")
		(net "M_F_DQS_DN<11>")
	)
	(segment
		(start 218.206828 -152.63876)
		(end 218.206828 -152.99944)
		(width 0.14224)
		(layer "In11.Cu")
		(net "M_F_DQS_DN<11>")
	)
	(segment
		(start 245.92915 -92.83319)
		(end 245.899178 -92.83319)
		(width 0.0889)
		(layer "In11.Cu")
		(net "M_F_DQS_DN<11>")
	)
	(segment
		(start 236.061504 -101.561392)
		(end 236.061504 -102.40391)
		(width 0.0889)
		(layer "In11.Cu")
		(net "M_F_DQS_DN<11>")
	)
	(segment
		(start 242.493292 -94.81439)
		(end 242.465352 -94.81439)
		(width 0.0889)
		(layer "In11.Cu")
		(net "M_F_DQS_DN<11>")
	)
	(segment
		(start 243.356384 -94.31909)
		(end 243.326412 -94.31909)
		(width 0.0889)
		(layer "In11.Cu")
		(net "M_F_DQS_DN<11>")
	)
	(segment
		(start 218.631008 -151.99106)
		(end 218.631008 -152.34412)
		(width 0.14224)
		(layer "In11.Cu")
		(net "M_F_DQS_DN<11>")
	)
	(segment
		(start 234.514644 -104.006396)
		(end 234.498896 -104.022144)
		(width 0.0889)
		(layer "In11.Cu")
		(net "M_F_DQS_DN<11>")
	)
	(arc
		(start 236.119162 -100.471224)
		(mid 236.070407 -100.667576)
		(end 236.123988 -100.862638)
		(width 0.0889)
		(layer "In11.Cu")
		(net "M_F_DQS_DN<11>")
	)
	(arc
		(start 237.314232 -97.78619)
		(mid 237.12259 -97.843356)
		(end 236.982508 -97.986088)
		(width 0.0889)
		(layer "In11.Cu")
		(net "M_F_DQS_DN<11>")
	)
	(arc
		(start 244.708934 -93.528642)
		(mid 244.50193 -93.739506)
		(end 244.218714 -93.82379)
		(width 0.0889)
		(layer "In11.Cu")
		(net "M_F_DQS_DN<11>")
	)
	(arc
		(start 245.567454 -93.033088)
		(mid 245.356741 -93.246167)
		(end 245.068598 -93.32849)
		(width 0.0889)
		(layer "In11.Cu")
		(net "M_F_DQS_DN<11>")
	)
	(arc
		(start 241.275108 -95.509588)
		(mid 241.0665 -95.72152)
		(end 240.781078 -95.80499)
		(width 0.0889)
		(layer "In11.Cu")
		(net "M_F_DQS_DN<11>")
	)
	(arc
		(start 246.228362 -92.985336)
		(mid 246.095481 -92.876353)
		(end 245.92915 -92.83319)
		(width 0.0889)
		(layer "In11.Cu")
		(net "M_F_DQS_DN<11>")
	)
	(arc
		(start 236.123988 -100.862638)
		(mid 236.20321 -101.151756)
		(end 236.130338 -101.44252)
		(width 0.0889)
		(layer "In11.Cu")
		(net "M_F_DQS_DN<11>")
	)
	(arc
		(start 245.899178 -92.83319)
		(mid 245.707536 -92.890356)
		(end 245.567454 -93.033088)
		(width 0.0889)
		(layer "In11.Cu")
		(net "M_F_DQS_DN<11>")
	)
	(arc
		(start 236.982508 -97.986088)
		(mid 236.775504 -98.196952)
		(end 236.492288 -98.281236)
		(width 0.0889)
		(layer "In11.Cu")
		(net "M_F_DQS_DN<11>")
	)
	(arc
		(start 238.699548 -96.995488)
		(mid 238.492544 -97.206352)
		(end 238.209328 -97.290636)
		(width 0.0889)
		(layer "In11.Cu")
		(net "M_F_DQS_DN<11>")
	)
	(arc
		(start 239.558068 -96.500188)
		(mid 239.34946 -96.71212)
		(end 239.064038 -96.79559)
		(width 0.0889)
		(layer "In11.Cu")
		(net "M_F_DQS_DN<11>")
	)
	(arc
		(start 237.841028 -97.490788)
		(mid 237.63242 -97.70272)
		(end 237.346998 -97.78619)
		(width 0.0889)
		(layer "In11.Cu")
		(net "M_F_DQS_DN<11>")
	)
	(arc
		(start 236.130338 -99.882706)
		(mid 236.203136 -100.173469)
		(end 236.123988 -100.462588)
		(width 0.0889)
		(layer "In11.Cu")
		(net "M_F_DQS_DN<11>")
	)
	(arc
		(start 242.992148 -94.518988)
		(mid 242.781435 -94.732067)
		(end 242.493292 -94.81439)
		(width 0.0889)
		(layer "In11.Cu")
		(net "M_F_DQS_DN<11>")
	)
	(arc
		(start 239.893602 -96.300036)
		(mid 239.699752 -96.356386)
		(end 239.558068 -96.500188)
		(width 0.0889)
		(layer "In11.Cu")
		(net "M_F_DQS_DN<11>")
	)
	(arc
		(start 236.123988 -99.472242)
		(mid 236.070489 -99.67214)
		(end 236.123988 -99.872038)
		(width 0.0889)
		(layer "In11.Cu")
		(net "M_F_DQS_DN<11>")
	)
	(arc
		(start 242.133628 -95.014288)
		(mid 241.926624 -95.225152)
		(end 241.643408 -95.309436)
		(width 0.0889)
		(layer "In11.Cu")
		(net "M_F_DQS_DN<11>")
	)
	(arc
		(start 238.176562 -97.290636)
		(mid 237.982712 -97.346986)
		(end 237.841028 -97.490788)
		(width 0.0889)
		(layer "In11.Cu")
		(net "M_F_DQS_DN<11>")
	)
	(arc
		(start 240.416588 -96.004888)
		(mid 240.209584 -96.215752)
		(end 239.926368 -96.300036)
		(width 0.0889)
		(layer "In11.Cu")
		(net "M_F_DQS_DN<11>")
	)
	(arc
		(start 239.031272 -96.79559)
		(mid 238.83963 -96.852756)
		(end 238.699548 -96.995488)
		(width 0.0889)
		(layer "In11.Cu")
		(net "M_F_DQS_DN<11>")
	)
	(arc
		(start 243.850414 -94.023688)
		(mid 243.641806 -94.23562)
		(end 243.356384 -94.31909)
		(width 0.0889)
		(layer "In11.Cu")
		(net "M_F_DQS_DN<11>")
	)
	(arc
		(start 245.044468 -93.32849)
		(mid 244.850618 -93.38484)
		(end 244.708934 -93.528642)
		(width 0.0889)
		(layer "In11.Cu")
		(net "M_F_DQS_DN<11>")
	)
	(arc
		(start 236.459522 -98.281236)
		(mid 236.121353 -98.486034)
		(end 236.123988 -98.881438)
		(width 0.0889)
		(layer "In11.Cu")
		(net "M_F_DQS_DN<11>")
	)
	(arc
		(start 241.610642 -95.309436)
		(mid 241.416792 -95.365786)
		(end 241.275108 -95.509588)
		(width 0.0889)
		(layer "In11.Cu")
		(net "M_F_DQS_DN<11>")
	)
	(arc
		(start 240.748312 -95.80499)
		(mid 240.55667 -95.862156)
		(end 240.416588 -96.004888)
		(width 0.0889)
		(layer "In11.Cu")
		(net "M_F_DQS_DN<11>")
	)
	(arc
		(start 244.17909 -93.82379)
		(mid 243.989161 -93.88166)
		(end 243.850414 -94.023688)
		(width 0.0889)
		(layer "In11.Cu")
		(net "M_F_DQS_DN<11>")
	)
	(arc
		(start 243.326412 -94.31909)
		(mid 243.133309 -94.375609)
		(end 242.992148 -94.518988)
		(width 0.0889)
		(layer "In11.Cu")
		(net "M_F_DQS_DN<11>")
	)
	(arc
		(start 242.465352 -94.81439)
		(mid 242.27371 -94.871556)
		(end 242.133628 -95.014288)
		(width 0.0889)
		(layer "In11.Cu")
		(net "M_F_DQS_DN<11>")
	)
	(arc
		(start 236.123988 -98.881438)
		(mid 236.203119 -99.17684)
		(end 236.123988 -99.472242)
		(width 0.0889)
		(layer "In11.Cu")
		(net "M_F_DQS_DN<11>")
	)
	(segment
		(start 209.767678 -154.204162)
		(end 209.51571 -154.45613)
		(width 0.1651)
		(layer "F.Cu")
		(net "M_F_DQS_DN<10>")
	)
	(segment
		(start 209.999834 -152.932384)
		(end 209.58175 -153.350468)
		(width 0.1651)
		(layer "F.Cu")
		(net "M_F_DQS_DN<10>")
	)
	(segment
		(start 209.767678 -153.957528)
		(end 209.767678 -154.204162)
		(width 0.1651)
		(layer "F.Cu")
		(net "M_F_DQS_DN<10>")
	)
	(segment
		(start 209.30743 -154.45613)
		(end 209.1182 -154.2669)
		(width 0.1651)
		(layer "F.Cu")
		(net "M_F_DQS_DN<10>")
	)
	(segment
		(start 242.193318 -91.747086)
		(end 241.621818 -91.747086)
		(width 0.1651)
		(layer "F.Cu")
		(net "M_F_DQS_DN<10>")
	)
	(segment
		(start 209.58175 -153.350468)
		(end 209.58175 -153.7716)
		(width 0.1651)
		(layer "F.Cu")
		(net "M_F_DQS_DN<10>")
	)
	(segment
		(start 209.58175 -153.7716)
		(end 209.767678 -153.957528)
		(width 0.1651)
		(layer "F.Cu")
		(net "M_F_DQS_DN<10>")
	)
	(segment
		(start 209.1182 -154.2669)
		(end 209.09915 -154.2669)
		(width 0.1651)
		(layer "F.Cu")
		(net "M_F_DQS_DN<10>")
	)
	(segment
		(start 209.51571 -154.45613)
		(end 209.30743 -154.45613)
		(width 0.1651)
		(layer "F.Cu")
		(net "M_F_DQS_DN<10>")
	)
	(segment
		(start 210.000342 -152.273)
		(end 209.999834 -152.278842)
		(width 0.1651)
		(layer "F.Cu")
		(net "M_F_DQS_DN<10>")
	)
	(segment
		(start 209.999834 -152.278842)
		(end 209.999834 -152.932384)
		(width 0.1651)
		(layer "F.Cu")
		(net "M_F_DQS_DN<10>")
	)
	(via
		(at 209.09915 -154.2669)
		(size 0.508)
		(drill 0.254)
		(layers "F.Cu" "B.Cu")
		(net "M_F_DQS_DN<10>")
	)
	(via
		(at 241.621818 -91.747086)
		(size 0.508)
		(drill 0.254)
		(layers "F.Cu" "B.Cu")
		(net "M_F_DQS_DN<10>")
	)
	(via
		(at 209.092546 -150.0886)
		(size 0.508)
		(drill 0.254)
		(layers "F.Cu" "B.Cu")
		(net "M_F_DQS_DN<10>")
	)
	(segment
		(start 210.000088 -152.077928)
		(end 210.000088 -151.421592)
		(width 0.1651)
		(layer "B.Cu")
		(net "M_F_DQS_DN<10>")
	)
	(segment
		(start 209.55635 -150.977854)
		(end 209.55635 -150.622)
		(width 0.1651)
		(layer "B.Cu")
		(net "M_F_DQS_DN<10>")
	)
	(segment
		(start 209.73415 -150.4442)
		(end 209.73415 -150.114)
		(width 0.1651)
		(layer "B.Cu")
		(net "M_F_DQS_DN<10>")
	)
	(segment
		(start 210.000088 -151.421592)
		(end 209.55635 -150.977854)
		(width 0.1651)
		(layer "B.Cu")
		(net "M_F_DQS_DN<10>")
	)
	(segment
		(start 209.73415 -150.114)
		(end 209.514186 -149.894036)
		(width 0.1651)
		(layer "B.Cu")
		(net "M_F_DQS_DN<10>")
	)
	(segment
		(start 209.55635 -150.622)
		(end 209.73415 -150.4442)
		(width 0.1651)
		(layer "B.Cu")
		(net "M_F_DQS_DN<10>")
	)
	(segment
		(start 209.514186 -149.894036)
		(end 209.28711 -149.894036)
		(width 0.1651)
		(layer "B.Cu")
		(net "M_F_DQS_DN<10>")
	)
	(segment
		(start 210.000342 -152.078436)
		(end 210.000088 -152.077928)
		(width 0.1651)
		(layer "B.Cu")
		(net "M_F_DQS_DN<10>")
	)
	(segment
		(start 209.28711 -149.894036)
		(end 209.092546 -150.0886)
		(width 0.1651)
		(layer "B.Cu")
		(net "M_F_DQS_DN<10>")
	)
	(segment
		(start 209.298794 -151.99106)
		(end 209.298794 -152.34412)
		(width 0.14224)
		(layer "In11.Cu")
		(net "M_F_DQS_DN<10>")
	)
	(segment
		(start 209.099912 -150.0886)
		(end 209.092546 -150.0886)
		(width 0.14224)
		(layer "In11.Cu")
		(net "M_F_DQS_DN<10>")
	)
	(segment
		(start 229.556818 -96.38665)
		(end 229.53472 -96.38665)
		(width 0.0889)
		(layer "In11.Cu")
		(net "M_F_DQS_DN<10>")
	)
	(segment
		(start 233.189018 -94.460314)
		(end 232.223818 -94.460314)
		(width 0.0889)
		(layer "In11.Cu")
		(net "M_F_DQS_DN<10>")
	)
	(segment
		(start 229.596188 -96.34728)
		(end 229.556818 -96.38665)
		(width 0.0889)
		(layer "In11.Cu")
		(net "M_F_DQS_DN<10>")
	)
	(segment
		(start 209.344514 -153.162)
		(end 209.53222 -153.349706)
		(width 0.14224)
		(layer "In11.Cu")
		(net "M_F_DQS_DN<10>")
	)
	(segment
		(start 209.092546 -150.0886)
		(end 209.527394 -150.523448)
		(width 0.14224)
		(layer "In11.Cu")
		(net "M_F_DQS_DN<10>")
	)
	(segment
		(start 234.321096 -93.328236)
		(end 233.189018 -94.460314)
		(width 0.0889)
		(layer "In11.Cu")
		(net "M_F_DQS_DN<10>")
	)
	(segment
		(start 209.53222 -153.349706)
		(end 209.53222 -153.83383)
		(width 0.14224)
		(layer "In11.Cu")
		(net "M_F_DQS_DN<10>")
	)
	(segment
		(start 234.766612 -93.32849)
		(end 234.766358 -93.328236)
		(width 0.0889)
		(layer "In11.Cu")
		(net "M_F_DQS_DN<10>")
	)
	(segment
		(start 209.006694 -151.2062)
		(end 208.856834 -151.35606)
		(width 0.14224)
		(layer "In11.Cu")
		(net "M_F_DQS_DN<10>")
	)
	(segment
		(start 239.90554 -90.35669)
		(end 239.904016 -90.35669)
		(width 0.0889)
		(layer "In11.Cu")
		(net "M_F_DQS_DN<10>")
	)
	(segment
		(start 209.874866 -147.994624)
		(end 210.032346 -148.152104)
		(width 0.14224)
		(layer "In11.Cu")
		(net "M_F_DQS_DN<10>")
	)
	(segment
		(start 209.874866 -127.920242)
		(end 209.874866 -147.171664)
		(width 0.14224)
		(layer "In11.Cu")
		(net "M_F_DQS_DN<10>")
	)
	(segment
		(start 210.032346 -148.406104)
		(end 209.874866 -148.563584)
		(width 0.14224)
		(layer "In11.Cu")
		(net "M_F_DQS_DN<10>")
	)
	(segment
		(start 210.032346 -147.583144)
		(end 209.874866 -147.740624)
		(width 0.14224)
		(layer "In11.Cu")
		(net "M_F_DQS_DN<10>")
	)
	(segment
		(start 209.874866 -148.563584)
		(end 209.874866 -149.313646)
		(width 0.14224)
		(layer "In11.Cu")
		(net "M_F_DQS_DN<10>")
	)
	(segment
		(start 209.874866 -126.065026)
		(end 210.096354 -126.286514)
		(width 0.14224)
		(layer "In11.Cu")
		(net "M_F_DQS_DN<10>")
	)
	(segment
		(start 210.948524 -126.676912)
		(end 210.948524 -127.33274)
		(width 0.14224)
		(layer "In11.Cu")
		(net "M_F_DQS_DN<10>")
	)
	(segment
		(start 208.856834 -151.35606)
		(end 208.856834 -151.70404)
		(width 0.14224)
		(layer "In11.Cu")
		(net "M_F_DQS_DN<10>")
	)
	(segment
		(start 209.874866 -149.313646)
		(end 209.099912 -150.0886)
		(width 0.14224)
		(layer "In11.Cu")
		(net "M_F_DQS_DN<10>")
	)
	(segment
		(start 241.632994 -91.347036)
		(end 241.600228 -91.347036)
		(width 0.0889)
		(layer "In11.Cu")
		(net "M_F_DQS_DN<10>")
	)
	(segment
		(start 210.096354 -124.000514)
		(end 210.548982 -124.000514)
		(width 0.14224)
		(layer "In11.Cu")
		(net "M_F_DQS_DN<10>")
	)
	(segment
		(start 209.247994 -151.2062)
		(end 209.006694 -151.2062)
		(width 0.14224)
		(layer "In11.Cu")
		(net "M_F_DQS_DN<10>")
	)
	(segment
		(start 236.492288 -92.337636)
		(end 236.459522 -92.337636)
		(width 0.0889)
		(layer "In11.Cu")
		(net "M_F_DQS_DN<10>")
	)
	(segment
		(start 209.527394 -150.9268)
		(end 209.247994 -151.2062)
		(width 0.14224)
		(layer "In11.Cu")
		(net "M_F_DQS_DN<10>")
	)
	(segment
		(start 229.53472 -96.38665)
		(end 228.35235 -96.38665)
		(width 0.14224)
		(layer "In11.Cu")
		(net "M_F_DQS_DN<10>")
	)
	(segment
		(start 210.096354 -126.286514)
		(end 210.558126 -126.286514)
		(width 0.14224)
		(layer "In11.Cu")
		(net "M_F_DQS_DN<10>")
	)
	(segment
		(start 209.874866 -147.740624)
		(end 209.874866 -147.994624)
		(width 0.14224)
		(layer "In11.Cu")
		(net "M_F_DQS_DN<10>")
	)
	(segment
		(start 209.874866 -125.634242)
		(end 209.874866 -126.065026)
		(width 0.14224)
		(layer "In11.Cu")
		(net "M_F_DQS_DN<10>")
	)
	(segment
		(start 237.346998 -91.84259)
		(end 237.314232 -91.84259)
		(width 0.0889)
		(layer "In11.Cu")
		(net "M_F_DQS_DN<10>")
	)
	(segment
		(start 234.766358 -93.328236)
		(end 234.321096 -93.328236)
		(width 0.0889)
		(layer "In11.Cu")
		(net "M_F_DQS_DN<10>")
	)
	(segment
		(start 209.143854 -152.49906)
		(end 208.996534 -152.49906)
		(width 0.14224)
		(layer "In11.Cu")
		(net "M_F_DQS_DN<10>")
	)
	(segment
		(start 210.032346 -147.329144)
		(end 210.032346 -147.583144)
		(width 0.14224)
		(layer "In11.Cu")
		(net "M_F_DQS_DN<10>")
	)
	(segment
		(start 232.223818 -94.460314)
		(end 230.336852 -96.34728)
		(width 0.0889)
		(layer "In11.Cu")
		(net "M_F_DQS_DN<10>")
	)
	(segment
		(start 226.6696 -101.313234)
		(end 209.874866 -118.107968)
		(width 0.14224)
		(layer "In11.Cu")
		(net "M_F_DQS_DN<10>")
	)
	(segment
		(start 209.298794 -152.34412)
		(end 209.143854 -152.49906)
		(width 0.14224)
		(layer "In11.Cu")
		(net "M_F_DQS_DN<10>")
	)
	(segment
		(start 228.35235 -96.38665)
		(end 226.6696 -98.0694)
		(width 0.14224)
		(layer "In11.Cu")
		(net "M_F_DQS_DN<10>")
	)
	(segment
		(start 209.019394 -153.162)
		(end 209.344514 -153.162)
		(width 0.14224)
		(layer "In11.Cu")
		(net "M_F_DQS_DN<10>")
	)
	(segment
		(start 210.558126 -126.286514)
		(end 210.948524 -126.676912)
		(width 0.14224)
		(layer "In11.Cu")
		(net "M_F_DQS_DN<10>")
	)
	(segment
		(start 241.621818 -91.747086)
		(end 241.914934 -91.91625)
		(width 0.0889)
		(layer "In11.Cu")
		(net "M_F_DQS_DN<10>")
	)
	(segment
		(start 235.629958 -92.83319)
		(end 235.597192 -92.83319)
		(width 0.0889)
		(layer "In11.Cu")
		(net "M_F_DQS_DN<10>")
	)
	(segment
		(start 209.527394 -150.523448)
		(end 209.527394 -150.9268)
		(width 0.14224)
		(layer "In11.Cu")
		(net "M_F_DQS_DN<10>")
	)
	(segment
		(start 208.856834 -151.70404)
		(end 208.988914 -151.83612)
		(width 0.14224)
		(layer "In11.Cu")
		(net "M_F_DQS_DN<10>")
	)
	(segment
		(start 210.032346 -148.152104)
		(end 210.032346 -148.406104)
		(width 0.14224)
		(layer "In11.Cu")
		(net "M_F_DQS_DN<10>")
	)
	(segment
		(start 208.988914 -151.83612)
		(end 209.143854 -151.83612)
		(width 0.14224)
		(layer "In11.Cu")
		(net "M_F_DQS_DN<10>")
	)
	(segment
		(start 226.6696 -98.0694)
		(end 226.6696 -101.313234)
		(width 0.14224)
		(layer "In11.Cu")
		(net "M_F_DQS_DN<10>")
	)
	(segment
		(start 240.778284 -90.85199)
		(end 240.749582 -90.85199)
		(width 0.0889)
		(layer "In11.Cu")
		(net "M_F_DQS_DN<10>")
	)
	(segment
		(start 208.996534 -152.49906)
		(end 208.856834 -152.63876)
		(width 0.14224)
		(layer "In11.Cu")
		(net "M_F_DQS_DN<10>")
	)
	(segment
		(start 239.059974 -90.85199)
		(end 239.031272 -90.85199)
		(width 0.0889)
		(layer "In11.Cu")
		(net "M_F_DQS_DN<10>")
	)
	(segment
		(start 238.209328 -91.347036)
		(end 238.176562 -91.347036)
		(width 0.0889)
		(layer "In11.Cu")
		(net "M_F_DQS_DN<10>")
	)
	(segment
		(start 210.548982 -124.000514)
		(end 210.927188 -124.37872)
		(width 0.14224)
		(layer "In11.Cu")
		(net "M_F_DQS_DN<10>")
	)
	(segment
		(start 230.336852 -96.34728)
		(end 229.596188 -96.34728)
		(width 0.0889)
		(layer "In11.Cu")
		(net "M_F_DQS_DN<10>")
	)
	(segment
		(start 209.874866 -147.171664)
		(end 210.032346 -147.329144)
		(width 0.14224)
		(layer "In11.Cu")
		(net "M_F_DQS_DN<10>")
	)
	(segment
		(start 209.874866 -123.779026)
		(end 210.096354 -124.000514)
		(width 0.14224)
		(layer "In11.Cu")
		(net "M_F_DQS_DN<10>")
	)
	(segment
		(start 210.548982 -125.412754)
		(end 210.096354 -125.412754)
		(width 0.14224)
		(layer "In11.Cu")
		(net "M_F_DQS_DN<10>")
	)
	(segment
		(start 208.856834 -152.99944)
		(end 209.019394 -153.162)
		(width 0.14224)
		(layer "In11.Cu")
		(net "M_F_DQS_DN<10>")
	)
	(segment
		(start 210.58251 -127.698754)
		(end 210.096354 -127.698754)
		(width 0.14224)
		(layer "In11.Cu")
		(net "M_F_DQS_DN<10>")
	)
	(segment
		(start 210.927188 -125.034548)
		(end 210.548982 -125.412754)
		(width 0.14224)
		(layer "In11.Cu")
		(net "M_F_DQS_DN<10>")
	)
	(segment
		(start 210.096354 -125.412754)
		(end 209.874866 -125.634242)
		(width 0.14224)
		(layer "In11.Cu")
		(net "M_F_DQS_DN<10>")
	)
	(segment
		(start 210.948524 -127.33274)
		(end 210.58251 -127.698754)
		(width 0.14224)
		(layer "In11.Cu")
		(net "M_F_DQS_DN<10>")
	)
	(segment
		(start 209.143854 -151.83612)
		(end 209.298794 -151.99106)
		(width 0.14224)
		(layer "In11.Cu")
		(net "M_F_DQS_DN<10>")
	)
	(segment
		(start 210.927188 -124.37872)
		(end 210.927188 -125.034548)
		(width 0.14224)
		(layer "In11.Cu")
		(net "M_F_DQS_DN<10>")
	)
	(segment
		(start 208.856834 -152.63876)
		(end 208.856834 -152.99944)
		(width 0.14224)
		(layer "In11.Cu")
		(net "M_F_DQS_DN<10>")
	)
	(segment
		(start 209.874866 -118.107968)
		(end 209.874866 -123.779026)
		(width 0.14224)
		(layer "In11.Cu")
		(net "M_F_DQS_DN<10>")
	)
	(segment
		(start 209.53222 -153.83383)
		(end 209.09915 -154.2669)
		(width 0.14224)
		(layer "In11.Cu")
		(net "M_F_DQS_DN<10>")
	)
	(segment
		(start 210.096354 -127.698754)
		(end 209.874866 -127.920242)
		(width 0.14224)
		(layer "In11.Cu")
		(net "M_F_DQS_DN<10>")
	)
	(segment
		(start 241.914934 -91.91625)
		(end 241.993674 -91.894914)
		(width 0.0889)
		(layer "In11.Cu")
		(net "M_F_DQS_DN<10>")
	)
	(arc
		(start 236.982508 -92.042488)
		(mid 236.775504 -92.253352)
		(end 236.492288 -92.337636)
		(width 0.0889)
		(layer "In11.Cu")
		(net "M_F_DQS_DN<10>")
	)
	(arc
		(start 236.123988 -92.537788)
		(mid 235.91538 -92.74972)
		(end 235.629958 -92.83319)
		(width 0.0889)
		(layer "In11.Cu")
		(net "M_F_DQS_DN<10>")
	)
	(arc
		(start 238.699548 -91.051888)
		(mid 238.492544 -91.262752)
		(end 238.209328 -91.347036)
		(width 0.0889)
		(layer "In11.Cu")
		(net "M_F_DQS_DN<10>")
	)
	(arc
		(start 236.459522 -92.337636)
		(mid 236.265672 -92.393986)
		(end 236.123988 -92.537788)
		(width 0.0889)
		(layer "In11.Cu")
		(net "M_F_DQS_DN<10>")
	)
	(arc
		(start 237.841028 -91.547188)
		(mid 237.63242 -91.75912)
		(end 237.346998 -91.84259)
		(width 0.0889)
		(layer "In11.Cu")
		(net "M_F_DQS_DN<10>")
	)
	(arc
		(start 241.993674 -91.894914)
		(mid 241.956034 -91.526975)
		(end 241.632994 -91.347036)
		(width 0.0889)
		(layer "In11.Cu")
		(net "M_F_DQS_DN<10>")
	)
	(arc
		(start 239.558068 -90.556588)
		(mid 239.347715 -90.76956)
		(end 239.059974 -90.85199)
		(width 0.0889)
		(layer "In11.Cu")
		(net "M_F_DQS_DN<10>")
	)
	(arc
		(start 237.314232 -91.84259)
		(mid 237.12259 -91.899756)
		(end 236.982508 -92.042488)
		(width 0.0889)
		(layer "In11.Cu")
		(net "M_F_DQS_DN<10>")
	)
	(arc
		(start 238.176562 -91.347036)
		(mid 237.982712 -91.403386)
		(end 237.841028 -91.547188)
		(width 0.0889)
		(layer "In11.Cu")
		(net "M_F_DQS_DN<10>")
	)
	(arc
		(start 240.251488 -90.556588)
		(mid 240.105316 -90.410253)
		(end 239.90554 -90.35669)
		(width 0.0889)
		(layer "In11.Cu")
		(net "M_F_DQS_DN<10>")
	)
	(arc
		(start 235.597192 -92.83319)
		(mid 235.40555 -92.890356)
		(end 235.265468 -93.033088)
		(width 0.0889)
		(layer "In11.Cu")
		(net "M_F_DQS_DN<10>")
	)
	(arc
		(start 239.031272 -90.85199)
		(mid 238.83963 -90.909156)
		(end 238.699548 -91.051888)
		(width 0.0889)
		(layer "In11.Cu")
		(net "M_F_DQS_DN<10>")
	)
	(arc
		(start 235.265468 -93.033088)
		(mid 235.054755 -93.246167)
		(end 234.766612 -93.32849)
		(width 0.0889)
		(layer "In11.Cu")
		(net "M_F_DQS_DN<10>")
	)
	(arc
		(start 241.110008 -91.051888)
		(mid 240.969929 -90.909152)
		(end 240.778284 -90.85199)
		(width 0.0889)
		(layer "In11.Cu")
		(net "M_F_DQS_DN<10>")
	)
	(arc
		(start 241.600228 -91.347036)
		(mid 241.317011 -91.262755)
		(end 241.110008 -91.051888)
		(width 0.0889)
		(layer "In11.Cu")
		(net "M_F_DQS_DN<10>")
	)
	(arc
		(start 240.749582 -90.85199)
		(mid 240.461895 -90.769469)
		(end 240.251488 -90.556588)
		(width 0.0889)
		(layer "In11.Cu")
		(net "M_F_DQS_DN<10>")
	)
	(arc
		(start 239.904016 -90.35669)
		(mid 239.704243 -90.410259)
		(end 239.558068 -90.556588)
		(width 0.0889)
		(layer "In11.Cu")
		(net "M_F_DQS_DN<10>")
	)
	(segment
		(start 200.267824 -155.422854)
		(end 200.267824 -154.991054)
		(width 0.1651)
		(layer "F.Cu")
		(net "M_F_DQS_DN<0>")
	)
	(segment
		(start 200.267824 -154.991054)
		(end 200.598278 -154.6606)
		(width 0.1651)
		(layer "F.Cu")
		(net "M_F_DQS_DN<0>")
	)
	(segment
		(start 200.64984 -155.80487)
		(end 200.267824 -155.422854)
		(width 0.1651)
		(layer "F.Cu")
		(net "M_F_DQS_DN<0>")
	)
	(segment
		(start 200.822306 -154.6606)
		(end 201.037952 -154.876246)
		(width 0.1651)
		(layer "F.Cu")
		(net "M_F_DQS_DN<0>")
	)
	(segment
		(start 200.650348 -156.87294)
		(end 200.64984 -156.87294)
		(width 0.1651)
		(layer "F.Cu")
		(net "M_F_DQS_DN<0>")
	)
	(segment
		(start 200.64984 -156.87294)
		(end 200.64984 -155.80487)
		(width 0.1651)
		(layer "F.Cu")
		(net "M_F_DQS_DN<0>")
	)
	(segment
		(start 240.476278 -85.803486)
		(end 239.904778 -85.803486)
		(width 0.1651)
		(layer "F.Cu")
		(net "M_F_DQS_DN<0>")
	)
	(segment
		(start 200.598278 -154.6606)
		(end 200.822306 -154.6606)
		(width 0.1651)
		(layer "F.Cu")
		(net "M_F_DQS_DN<0>")
	)
	(via
		(at 239.904778 -85.803486)
		(size 0.508)
		(drill 0.254)
		(layers "F.Cu" "B.Cu")
		(net "M_F_DQS_DN<0>")
	)
	(via
		(at 201.037952 -154.876246)
		(size 0.508)
		(drill 0.254)
		(layers "F.Cu" "B.Cu")
		(net "M_F_DQS_DN<0>")
	)
	(via
		(at 201.037952 -149.482556)
		(size 0.508)
		(drill 0.254)
		(layers "F.Cu" "B.Cu")
		(net "M_F_DQS_DN<0>")
	)
	(segment
		(start 200.521824 -148.513546)
		(end 200.521824 -148.767546)
		(width 0.1651)
		(layer "B.Cu")
		(net "M_F_DQS_DN<0>")
	)
	(segment
		(start 200.267824 -149.352)
		(end 200.623424 -149.7076)
		(width 0.1651)
		(layer "B.Cu")
		(net "M_F_DQS_DN<0>")
	)
	(segment
		(start 200.521824 -148.767546)
		(end 200.267824 -149.021546)
		(width 0.1651)
		(layer "B.Cu")
		(net "M_F_DQS_DN<0>")
	)
	(segment
		(start 200.64984 -147.478496)
		(end 200.64984 -148.38553)
		(width 0.1651)
		(layer "B.Cu")
		(net "M_F_DQS_DN<0>")
	)
	(segment
		(start 200.623424 -149.7076)
		(end 200.812908 -149.7076)
		(width 0.1651)
		(layer "B.Cu")
		(net "M_F_DQS_DN<0>")
	)
	(segment
		(start 200.64984 -148.38553)
		(end 200.521824 -148.513546)
		(width 0.1651)
		(layer "B.Cu")
		(net "M_F_DQS_DN<0>")
	)
	(segment
		(start 200.650348 -147.478496)
		(end 200.64984 -147.478496)
		(width 0.1651)
		(layer "B.Cu")
		(net "M_F_DQS_DN<0>")
	)
	(segment
		(start 200.812908 -149.7076)
		(end 201.037952 -149.482556)
		(width 0.1651)
		(layer "B.Cu")
		(net "M_F_DQS_DN<0>")
	)
	(segment
		(start 200.267824 -149.021546)
		(end 200.267824 -149.352)
		(width 0.1651)
		(layer "B.Cu")
		(net "M_F_DQS_DN<0>")
	)
	(segment
		(start 201.551032 -148.040344)
		(end 201.393552 -148.197824)
		(width 0.14224)
		(layer "In11.Cu")
		(net "M_F_DQS_DN<0>")
	)
	(segment
		(start 235.623354 -87.68969)
		(end 235.590588 -87.68969)
		(width 0.0889)
		(layer "In11.Cu")
		(net "M_F_DQS_DN<0>")
	)
	(segment
		(start 201.393552 -148.451824)
		(end 201.551032 -148.609304)
		(width 0.14224)
		(layer "In11.Cu")
		(net "M_F_DQS_DN<0>")
	)
	(segment
		(start 201.422762 -137.638028)
		(end 201.422762 -137.892028)
		(width 0.14224)
		(layer "In11.Cu")
		(net "M_F_DQS_DN<0>")
	)
	(segment
		(start 201.551032 -142.336266)
		(end 201.393552 -142.493746)
		(width 0.14224)
		(layer "In11.Cu")
		(net "M_F_DQS_DN<0>")
	)
	(segment
		(start 201.551032 -138.303508)
		(end 201.393552 -138.460988)
		(width 0.14224)
		(layer "In11.Cu")
		(net "M_F_DQS_DN<0>")
	)
	(segment
		(start 206.10576 -108.04144)
		(end 206.10576 -108.54944)
		(width 0.14224)
		(layer "In11.Cu")
		(net "M_F_DQS_DN<0>")
	)
	(segment
		(start 200.84288 -124.063252)
		(end 200.84288 -124.71908)
		(width 0.14224)
		(layer "In11.Cu")
		(net "M_F_DQS_DN<0>")
	)
	(segment
		(start 202.49388 -123.463558)
		(end 202.272392 -123.685046)
		(width 0.14224)
		(layer "In11.Cu")
		(net "M_F_DQS_DN<0>")
	)
	(segment
		(start 200.604882 -149.842474)
		(end 200.604882 -151.1046)
		(width 0.14224)
		(layer "In11.Cu")
		(net "M_F_DQS_DN<0>")
	)
	(segment
		(start 201.393552 -146.805904)
		(end 201.551032 -146.963384)
		(width 0.14224)
		(layer "In11.Cu")
		(net "M_F_DQS_DN<0>")
	)
	(segment
		(start 214.185754 -104.09936)
		(end 210.04784 -104.09936)
		(width 0.14224)
		(layer "In11.Cu")
		(net "M_F_DQS_DN<0>")
	)
	(segment
		(start 201.551032 -149.214586)
		(end 201.283062 -149.482556)
		(width 0.14224)
		(layer "In11.Cu")
		(net "M_F_DQS_DN<0>")
	)
	(segment
		(start 238.202724 -86.203536)
		(end 238.169958 -86.203536)
		(width 0.0889)
		(layer "In11.Cu")
		(net "M_F_DQS_DN<0>")
	)
	(segment
		(start 228.450902 -89.325704)
		(end 228.428804 -89.325704)
		(width 0.0889)
		(layer "In11.Cu")
		(net "M_F_DQS_DN<0>")
	)
	(segment
		(start 201.422762 -137.892028)
		(end 201.551032 -138.020298)
		(width 0.14224)
		(layer "In11.Cu")
		(net "M_F_DQS_DN<0>")
	)
	(segment
		(start 202.49388 -121.177558)
		(end 202.272392 -121.399046)
		(width 0.14224)
		(layer "In11.Cu")
		(net "M_F_DQS_DN<0>")
	)
	(segment
		(start 200.604882 -151.1046)
		(end 200.394062 -151.31542)
		(width 0.14224)
		(layer "In11.Cu")
		(net "M_F_DQS_DN<0>")
	)
	(segment
		(start 201.551032 -142.905226)
		(end 201.551032 -143.159226)
		(width 0.14224)
		(layer "In11.Cu")
		(net "M_F_DQS_DN<0>")
	)
	(segment
		(start 227.717096 -89.325704)
		(end 218.5162 -98.5266)
		(width 0.14224)
		(layer "In11.Cu")
		(net "M_F_DQS_DN<0>")
	)
	(segment
		(start 201.50328 -120.525286)
		(end 202.272392 -120.525286)
		(width 0.14224)
		(layer "In11.Cu")
		(net "M_F_DQS_DN<0>")
	)
	(segment
		(start 228.490272 -89.365074)
		(end 228.450902 -89.325704)
		(width 0.0889)
		(layer "In11.Cu")
		(net "M_F_DQS_DN<0>")
	)
	(segment
		(start 202.272392 -123.685046)
		(end 201.221086 -123.685046)
		(width 0.14224)
		(layer "In11.Cu")
		(net "M_F_DQS_DN<0>")
	)
	(segment
		(start 201.221086 -123.685046)
		(end 200.84288 -124.063252)
		(width 0.14224)
		(layer "In11.Cu")
		(net "M_F_DQS_DN<0>")
	)
	(segment
		(start 202.44816 -125.318774)
		(end 202.44816 -125.777752)
		(width 0.14224)
		(layer "In11.Cu")
		(net "M_F_DQS_DN<0>")
	)
	(segment
		(start 201.551032 -147.217384)
		(end 201.393552 -147.374864)
		(width 0.14224)
		(layer "In11.Cu")
		(net "M_F_DQS_DN<0>")
	)
	(segment
		(start 239.904778 -85.803486)
		(end 239.150652 -85.71738)
		(width 0.0889)
		(layer "In11.Cu")
		(net "M_F_DQS_DN<0>")
	)
	(segment
		(start 201.283062 -149.482556)
		(end 201.037952 -149.482556)
		(width 0.14224)
		(layer "In11.Cu")
		(net "M_F_DQS_DN<0>")
	)
	(segment
		(start 201.551032 -143.159226)
		(end 201.393552 -143.316706)
		(width 0.14224)
		(layer "In11.Cu")
		(net "M_F_DQS_DN<0>")
	)
	(segment
		(start 200.84288 -124.71908)
		(end 201.221086 -125.097286)
		(width 0.14224)
		(layer "In11.Cu")
		(net "M_F_DQS_DN<0>")
	)
	(segment
		(start 206.10576 -108.54944)
		(end 202.49388 -112.16132)
		(width 0.14224)
		(layer "In11.Cu")
		(net "M_F_DQS_DN<0>")
	)
	(segment
		(start 202.273154 -119.113046)
		(end 201.520044 -119.113046)
		(width 0.14224)
		(layer "In11.Cu")
		(net "M_F_DQS_DN<0>")
	)
	(segment
		(start 202.226672 -125.097286)
		(end 202.44816 -125.318774)
		(width 0.14224)
		(layer "In11.Cu")
		(net "M_F_DQS_DN<0>")
	)
	(segment
		(start 231.74833 -89.67089)
		(end 231.442514 -89.365074)
		(width 0.0889)
		(layer "In11.Cu")
		(net "M_F_DQS_DN<0>")
	)
	(segment
		(start 200.934066 -122.43308)
		(end 201.312272 -122.811286)
		(width 0.14224)
		(layer "In11.Cu")
		(net "M_F_DQS_DN<0>")
	)
	(segment
		(start 201.551032 -141.513306)
		(end 201.393552 -141.670786)
		(width 0.14224)
		(layer "In11.Cu")
		(net "M_F_DQS_DN<0>")
	)
	(segment
		(start 201.393552 -148.197824)
		(end 201.393552 -148.451824)
		(width 0.14224)
		(layer "In11.Cu")
		(net "M_F_DQS_DN<0>")
	)
	(segment
		(start 201.43089 -137.069068)
		(end 201.551032 -137.18921)
		(width 0.14224)
		(layer "In11.Cu")
		(net "M_F_DQS_DN<0>")
	)
	(segment
		(start 202.49388 -123.032774)
		(end 202.49388 -123.463558)
		(width 0.14224)
		(layer "In11.Cu")
		(net "M_F_DQS_DN<0>")
	)
	(segment
		(start 234.768644 -88.184736)
		(end 234.735878 -88.184736)
		(width 0.0889)
		(layer "In11.Cu")
		(net "M_F_DQS_DN<0>")
	)
	(segment
		(start 200.394062 -151.31542)
		(end 200.394062 -152.97658)
		(width 0.14224)
		(layer "In11.Cu")
		(net "M_F_DQS_DN<0>")
	)
	(segment
		(start 200.394062 -152.97658)
		(end 200.604882 -153.1874)
		(width 0.14224)
		(layer "In11.Cu")
		(net "M_F_DQS_DN<0>")
	)
	(segment
		(start 237.340394 -86.69909)
		(end 237.307628 -86.69909)
		(width 0.0889)
		(layer "In11.Cu")
		(net "M_F_DQS_DN<0>")
	)
	(segment
		(start 201.393552 -146.551904)
		(end 201.393552 -146.805904)
		(width 0.14224)
		(layer "In11.Cu")
		(net "M_F_DQS_DN<0>")
	)
	(segment
		(start 202.272392 -120.525286)
		(end 202.49388 -120.746774)
		(width 0.14224)
		(layer "In11.Cu")
		(net "M_F_DQS_DN<0>")
	)
	(segment
		(start 200.934066 -121.777252)
		(end 200.934066 -122.43308)
		(width 0.14224)
		(layer "In11.Cu")
		(net "M_F_DQS_DN<0>")
	)
	(segment
		(start 201.037952 -149.482556)
		(end 200.9648 -149.482556)
		(width 0.14224)
		(layer "In11.Cu")
		(net "M_F_DQS_DN<0>")
	)
	(segment
		(start 201.520044 -119.113046)
		(end 201.133456 -119.499634)
		(width 0.14224)
		(layer "In11.Cu")
		(net "M_F_DQS_DN<0>")
	)
	(segment
		(start 201.551032 -146.394424)
		(end 201.393552 -146.551904)
		(width 0.14224)
		(layer "In11.Cu")
		(net "M_F_DQS_DN<0>")
	)
	(segment
		(start 201.312272 -121.399046)
		(end 200.934066 -121.777252)
		(width 0.14224)
		(layer "In11.Cu")
		(net "M_F_DQS_DN<0>")
	)
	(segment
		(start 201.551032 -148.609304)
		(end 201.551032 -149.214586)
		(width 0.14224)
		(layer "In11.Cu")
		(net "M_F_DQS_DN<0>")
	)
	(segment
		(start 201.393552 -143.570706)
		(end 201.551032 -143.728186)
		(width 0.14224)
		(layer "In11.Cu")
		(net "M_F_DQS_DN<0>")
	)
	(segment
		(start 201.551032 -126.67488)
		(end 201.551032 -136.694926)
		(width 0.14224)
		(layer "In11.Cu")
		(net "M_F_DQS_DN<0>")
	)
	(segment
		(start 201.551032 -143.728186)
		(end 201.551032 -146.394424)
		(width 0.14224)
		(layer "In11.Cu")
		(net "M_F_DQS_DN<0>")
	)
	(segment
		(start 201.551032 -136.694926)
		(end 201.43089 -136.815068)
		(width 0.14224)
		(layer "In11.Cu")
		(net "M_F_DQS_DN<0>")
	)
	(segment
		(start 201.221086 -125.097286)
		(end 202.226672 -125.097286)
		(width 0.14224)
		(layer "In11.Cu")
		(net "M_F_DQS_DN<0>")
	)
	(segment
		(start 239.067848 -85.70849)
		(end 239.024668 -85.70849)
		(width 0.0889)
		(layer "In11.Cu")
		(net "M_F_DQS_DN<0>")
	)
	(segment
		(start 201.393552 -138.714988)
		(end 201.551032 -138.872468)
		(width 0.14224)
		(layer "In11.Cu")
		(net "M_F_DQS_DN<0>")
	)
	(segment
		(start 202.49388 -112.16132)
		(end 202.49388 -118.89232)
		(width 0.14224)
		(layer "In11.Cu")
		(net "M_F_DQS_DN<0>")
	)
	(segment
		(start 202.49388 -120.746774)
		(end 202.49388 -121.177558)
		(width 0.14224)
		(layer "In11.Cu")
		(net "M_F_DQS_DN<0>")
	)
	(segment
		(start 201.393552 -138.460988)
		(end 201.393552 -138.714988)
		(width 0.14224)
		(layer "In11.Cu")
		(net "M_F_DQS_DN<0>")
	)
	(segment
		(start 201.551032 -147.786344)
		(end 201.551032 -148.040344)
		(width 0.14224)
		(layer "In11.Cu")
		(net "M_F_DQS_DN<0>")
	)
	(segment
		(start 201.393552 -147.374864)
		(end 201.393552 -147.628864)
		(width 0.14224)
		(layer "In11.Cu")
		(net "M_F_DQS_DN<0>")
	)
	(segment
		(start 201.551032 -138.020298)
		(end 201.551032 -138.303508)
		(width 0.14224)
		(layer "In11.Cu")
		(net "M_F_DQS_DN<0>")
	)
	(segment
		(start 201.43089 -136.815068)
		(end 201.43089 -137.069068)
		(width 0.14224)
		(layer "In11.Cu")
		(net "M_F_DQS_DN<0>")
	)
	(segment
		(start 201.393552 -141.924786)
		(end 201.551032 -142.082266)
		(width 0.14224)
		(layer "In11.Cu")
		(net "M_F_DQS_DN<0>")
	)
	(segment
		(start 218.5162 -99.768914)
		(end 214.185754 -104.09936)
		(width 0.14224)
		(layer "In11.Cu")
		(net "M_F_DQS_DN<0>")
	)
	(segment
		(start 201.393552 -141.670786)
		(end 201.393552 -141.924786)
		(width 0.14224)
		(layer "In11.Cu")
		(net "M_F_DQS_DN<0>")
	)
	(segment
		(start 200.604882 -154.443176)
		(end 201.037952 -154.876246)
		(width 0.14224)
		(layer "In11.Cu")
		(net "M_F_DQS_DN<0>")
	)
	(segment
		(start 201.551032 -138.872468)
		(end 201.551032 -141.513306)
		(width 0.14224)
		(layer "In11.Cu")
		(net "M_F_DQS_DN<0>")
	)
	(segment
		(start 201.133456 -120.155462)
		(end 201.50328 -120.525286)
		(width 0.14224)
		(layer "In11.Cu")
		(net "M_F_DQS_DN<0>")
	)
	(segment
		(start 232.189274 -89.67089)
		(end 231.74833 -89.67089)
		(width 0.0889)
		(layer "In11.Cu")
		(net "M_F_DQS_DN<0>")
	)
	(segment
		(start 200.604882 -153.1874)
		(end 200.604882 -154.443176)
		(width 0.14224)
		(layer "In11.Cu")
		(net "M_F_DQS_DN<0>")
	)
	(segment
		(start 202.272392 -122.811286)
		(end 202.49388 -123.032774)
		(width 0.14224)
		(layer "In11.Cu")
		(net "M_F_DQS_DN<0>")
	)
	(segment
		(start 202.272392 -121.399046)
		(end 201.312272 -121.399046)
		(width 0.14224)
		(layer "In11.Cu")
		(net "M_F_DQS_DN<0>")
	)
	(segment
		(start 201.551032 -146.963384)
		(end 201.551032 -147.217384)
		(width 0.14224)
		(layer "In11.Cu")
		(net "M_F_DQS_DN<0>")
	)
	(segment
		(start 201.551032 -137.18921)
		(end 201.551032 -137.509758)
		(width 0.14224)
		(layer "In11.Cu")
		(net "M_F_DQS_DN<0>")
	)
	(segment
		(start 201.393552 -147.628864)
		(end 201.551032 -147.786344)
		(width 0.14224)
		(layer "In11.Cu")
		(net "M_F_DQS_DN<0>")
	)
	(segment
		(start 201.312272 -122.811286)
		(end 202.272392 -122.811286)
		(width 0.14224)
		(layer "In11.Cu")
		(net "M_F_DQS_DN<0>")
	)
	(segment
		(start 210.04784 -104.09936)
		(end 206.10576 -108.04144)
		(width 0.14224)
		(layer "In11.Cu")
		(net "M_F_DQS_DN<0>")
	)
	(segment
		(start 201.393552 -142.493746)
		(end 201.393552 -142.747746)
		(width 0.14224)
		(layer "In11.Cu")
		(net "M_F_DQS_DN<0>")
	)
	(segment
		(start 233.906314 -88.68029)
		(end 233.873548 -88.68029)
		(width 0.0889)
		(layer "In11.Cu")
		(net "M_F_DQS_DN<0>")
	)
	(segment
		(start 201.393552 -142.747746)
		(end 201.551032 -142.905226)
		(width 0.14224)
		(layer "In11.Cu")
		(net "M_F_DQS_DN<0>")
	)
	(segment
		(start 233.051604 -89.175336)
		(end 233.018838 -89.175336)
		(width 0.0889)
		(layer "In11.Cu")
		(net "M_F_DQS_DN<0>")
	)
	(segment
		(start 218.5162 -98.5266)
		(end 218.5162 -99.768914)
		(width 0.14224)
		(layer "In11.Cu")
		(net "M_F_DQS_DN<0>")
	)
	(segment
		(start 228.428804 -89.325704)
		(end 227.717096 -89.325704)
		(width 0.14224)
		(layer "In11.Cu")
		(net "M_F_DQS_DN<0>")
	)
	(segment
		(start 200.9648 -149.482556)
		(end 200.604882 -149.842474)
		(width 0.14224)
		(layer "In11.Cu")
		(net "M_F_DQS_DN<0>")
	)
	(segment
		(start 201.393552 -143.316706)
		(end 201.393552 -143.570706)
		(width 0.14224)
		(layer "In11.Cu")
		(net "M_F_DQS_DN<0>")
	)
	(segment
		(start 201.551032 -142.082266)
		(end 201.551032 -142.336266)
		(width 0.14224)
		(layer "In11.Cu")
		(net "M_F_DQS_DN<0>")
	)
	(segment
		(start 231.442514 -89.365074)
		(end 228.490272 -89.365074)
		(width 0.0889)
		(layer "In11.Cu")
		(net "M_F_DQS_DN<0>")
	)
	(segment
		(start 201.133456 -119.499634)
		(end 201.133456 -120.155462)
		(width 0.14224)
		(layer "In11.Cu")
		(net "M_F_DQS_DN<0>")
	)
	(segment
		(start 201.551032 -137.509758)
		(end 201.422762 -137.638028)
		(width 0.14224)
		(layer "In11.Cu")
		(net "M_F_DQS_DN<0>")
	)
	(segment
		(start 202.44816 -125.777752)
		(end 201.551032 -126.67488)
		(width 0.14224)
		(layer "In11.Cu")
		(net "M_F_DQS_DN<0>")
	)
	(segment
		(start 236.485684 -87.194136)
		(end 236.452918 -87.194136)
		(width 0.0889)
		(layer "In11.Cu")
		(net "M_F_DQS_DN<0>")
	)
	(segment
		(start 202.49388 -118.89232)
		(end 202.273154 -119.113046)
		(width 0.14224)
		(layer "In11.Cu")
		(net "M_F_DQS_DN<0>")
	)
	(arc
		(start 238.534448 -86.003638)
		(mid 238.394369 -86.146374)
		(end 238.202724 -86.203536)
		(width 0.0889)
		(layer "In11.Cu")
		(net "M_F_DQS_DN<0>")
	)
	(arc
		(start 239.024668 -85.70849)
		(mid 238.741451 -85.792771)
		(end 238.534448 -86.003638)
		(width 0.0889)
		(layer "In11.Cu")
		(net "M_F_DQS_DN<0>")
	)
	(arc
		(start 233.383328 -88.975438)
		(mid 233.243249 -89.118174)
		(end 233.051604 -89.175336)
		(width 0.0889)
		(layer "In11.Cu")
		(net "M_F_DQS_DN<0>")
	)
	(arc
		(start 238.169958 -86.203536)
		(mid 237.884534 -86.287003)
		(end 237.675928 -86.498938)
		(width 0.0889)
		(layer "In11.Cu")
		(net "M_F_DQS_DN<0>")
	)
	(arc
		(start 235.590588 -87.68969)
		(mid 235.307371 -87.773971)
		(end 235.100368 -87.984838)
		(width 0.0889)
		(layer "In11.Cu")
		(net "M_F_DQS_DN<0>")
	)
	(arc
		(start 236.817408 -86.994238)
		(mid 236.677329 -87.136974)
		(end 236.485684 -87.194136)
		(width 0.0889)
		(layer "In11.Cu")
		(net "M_F_DQS_DN<0>")
	)
	(arc
		(start 235.100368 -87.984838)
		(mid 234.960289 -88.127574)
		(end 234.768644 -88.184736)
		(width 0.0889)
		(layer "In11.Cu")
		(net "M_F_DQS_DN<0>")
	)
	(arc
		(start 236.452918 -87.194136)
		(mid 236.167494 -87.277603)
		(end 235.958888 -87.489538)
		(width 0.0889)
		(layer "In11.Cu")
		(net "M_F_DQS_DN<0>")
	)
	(arc
		(start 233.018838 -89.175336)
		(mid 232.733414 -89.258803)
		(end 232.524808 -89.470738)
		(width 0.0889)
		(layer "In11.Cu")
		(net "M_F_DQS_DN<0>")
	)
	(arc
		(start 232.524808 -89.470738)
		(mid 232.383125 -89.614542)
		(end 232.189274 -89.67089)
		(width 0.0889)
		(layer "In11.Cu")
		(net "M_F_DQS_DN<0>")
	)
	(arc
		(start 237.307628 -86.69909)
		(mid 237.024411 -86.783371)
		(end 236.817408 -86.994238)
		(width 0.0889)
		(layer "In11.Cu")
		(net "M_F_DQS_DN<0>")
	)
	(arc
		(start 234.241848 -88.480138)
		(mid 234.100165 -88.623942)
		(end 233.906314 -88.68029)
		(width 0.0889)
		(layer "In11.Cu")
		(net "M_F_DQS_DN<0>")
	)
	(arc
		(start 237.675928 -86.498938)
		(mid 237.534245 -86.642742)
		(end 237.340394 -86.69909)
		(width 0.0889)
		(layer "In11.Cu")
		(net "M_F_DQS_DN<0>")
	)
	(arc
		(start 233.873548 -88.68029)
		(mid 233.590331 -88.764571)
		(end 233.383328 -88.975438)
		(width 0.0889)
		(layer "In11.Cu")
		(net "M_F_DQS_DN<0>")
	)
	(arc
		(start 234.735878 -88.184736)
		(mid 234.450454 -88.268203)
		(end 234.241848 -88.480138)
		(width 0.0889)
		(layer "In11.Cu")
		(net "M_F_DQS_DN<0>")
	)
	(arc
		(start 239.150652 -85.71738)
		(mid 239.109407 -85.71147)
		(end 239.067848 -85.70849)
		(width 0.0889)
		(layer "In11.Cu")
		(net "M_F_DQS_DN<0>")
	)
	(arc
		(start 235.958888 -87.489538)
		(mid 235.817205 -87.633342)
		(end 235.623354 -87.68969)
		(width 0.0889)
		(layer "In11.Cu")
		(net "M_F_DQS_DN<0>")
	)
	(segment
		(start 207.449928 -152.278842)
		(end 207.449928 -153.542746)
		(width 0.1651)
		(layer "F.Cu")
		(net "M_F_DQ<9>")
	)
	(segment
		(start 241.334798 -90.26144)
		(end 240.763298 -90.26144)
		(width 0.1651)
		(layer "F.Cu")
		(net "M_F_DQ<9>")
	)
	(segment
		(start 207.450436 -152.273)
		(end 207.449928 -152.278842)
		(width 0.1651)
		(layer "F.Cu")
		(net "M_F_DQ<9>")
	)
	(via
		(at 207.449928 -153.542746)
		(size 0.508)
		(drill 0.254)
		(layers "F.Cu" "B.Cu")
		(net "M_F_DQ<9>")
	)
	(via
		(at 240.763298 -90.26144)
		(size 0.508)
		(drill 0.254)
		(layers "F.Cu" "B.Cu")
		(net "M_F_DQ<9>")
	)
	(via
		(at 208.122012 -149.533356)
		(size 0.508)
		(drill 0.254)
		(layers "F.Cu" "B.Cu")
		(net "M_F_DQ<9>")
	)
	(segment
		(start 208.30032 -147.478496)
		(end 208.299812 -147.478496)
		(width 0.1651)
		(layer "B.Cu")
		(net "M_F_DQ<9>")
	)
	(segment
		(start 208.299812 -148.852382)
		(end 208.122012 -149.030182)
		(width 0.1651)
		(layer "B.Cu")
		(net "M_F_DQ<9>")
	)
	(segment
		(start 208.122012 -149.030182)
		(end 208.122012 -149.533356)
		(width 0.1651)
		(layer "B.Cu")
		(net "M_F_DQ<9>")
	)
	(segment
		(start 208.299812 -147.478496)
		(end 208.299812 -148.852382)
		(width 0.1651)
		(layer "B.Cu")
		(net "M_F_DQ<9>")
	)
	(segment
		(start 208.915 -119.903748)
		(end 208.7118 -120.106948)
		(width 0.14224)
		(layer "In11.Cu")
		(net "M_F_DQ<9>")
	)
	(segment
		(start 208.465928 -132.643626)
		(end 208.310988 -132.798566)
		(width 0.14224)
		(layer "In11.Cu")
		(net "M_F_DQ<9>")
	)
	(segment
		(start 208.447132 -127.653034)
		(end 208.292192 -127.807974)
		(width 0.14224)
		(layer "In11.Cu")
		(net "M_F_DQ<9>")
	)
	(segment
		(start 208.76006 -128.465834)
		(end 208.915 -128.620774)
		(width 0.14224)
		(layer "In11.Cu")
		(net "M_F_DQ<9>")
	)
	(segment
		(start 208.9404 -133.8834)
		(end 208.609946 -134.213854)
		(width 0.14224)
		(layer "In11.Cu")
		(net "M_F_DQ<9>")
	)
	(segment
		(start 208.609946 -141.3256)
		(end 208.7372 -141.452854)
		(width 0.14224)
		(layer "In11.Cu")
		(net "M_F_DQ<9>")
	)
	(segment
		(start 208.2292 -122.342148)
		(end 208.4324 -122.545348)
		(width 0.14224)
		(layer "In11.Cu")
		(net "M_F_DQ<9>")
	)
	(segment
		(start 208.26095 -123.953524)
		(end 208.478374 -124.170948)
		(width 0.14224)
		(layer "In11.Cu")
		(net "M_F_DQ<9>")
	)
	(segment
		(start 208.915 -118.278148)
		(end 208.7118 -118.481348)
		(width 0.14224)
		(layer "In11.Cu")
		(net "M_F_DQ<9>")
	)
	(segment
		(start 207.611218 -152.538176)
		(end 207.611218 -152.846024)
		(width 0.14224)
		(layer "In11.Cu")
		(net "M_F_DQ<9>")
	)
	(segment
		(start 208.2292 -121.935748)
		(end 208.2292 -122.342148)
		(width 0.14224)
		(layer "In11.Cu")
		(net "M_F_DQ<9>")
	)
	(segment
		(start 208.7118 -122.545348)
		(end 208.915 -122.748548)
		(width 0.14224)
		(layer "In11.Cu")
		(net "M_F_DQ<9>")
	)
	(segment
		(start 208.4578 -129.4892)
		(end 208.4578 -129.8194)
		(width 0.14224)
		(layer "In11.Cu")
		(net "M_F_DQ<9>")
	)
	(segment
		(start 208.292192 -127.807974)
		(end 208.292192 -128.310894)
		(width 0.14224)
		(layer "In11.Cu")
		(net "M_F_DQ<9>")
	)
	(segment
		(start 230.595424 -95.031814)
		(end 229.586282 -95.031814)
		(width 0.0889)
		(layer "In11.Cu")
		(net "M_F_DQ<9>")
	)
	(segment
		(start 208.122012 -149.533356)
		(end 208.09966 -149.533356)
		(width 0.14224)
		(layer "In11.Cu")
		(net "M_F_DQ<9>")
	)
	(segment
		(start 208.915 -121.529348)
		(end 208.7118 -121.732548)
		(width 0.14224)
		(layer "In11.Cu")
		(net "M_F_DQ<9>")
	)
	(segment
		(start 235.629958 -91.84259)
		(end 235.597192 -91.84259)
		(width 0.0889)
		(layer "In11.Cu")
		(net "M_F_DQ<9>")
	)
	(segment
		(start 208.609946 -131.7244)
		(end 208.9404 -132.054854)
		(width 0.14224)
		(layer "In11.Cu")
		(net "M_F_DQ<9>")
	)
	(segment
		(start 208.7118 -136.677654)
		(end 208.7118 -138.6078)
		(width 0.14224)
		(layer "In11.Cu")
		(net "M_F_DQ<9>")
	)
	(segment
		(start 207.698848 -153.542746)
		(end 207.449928 -153.542746)
		(width 0.14224)
		(layer "In11.Cu")
		(net "M_F_DQ<9>")
	)
	(segment
		(start 208.609946 -136.5758)
		(end 208.7118 -136.677654)
		(width 0.14224)
		(layer "In11.Cu")
		(net "M_F_DQ<9>")
	)
	(segment
		(start 207.901794 -151.026368)
		(end 207.611218 -151.316944)
		(width 0.14224)
		(layer "In11.Cu")
		(net "M_F_DQ<9>")
	)
	(segment
		(start 240.268252 -89.595452)
		(end 240.251488 -89.565988)
		(width 0.0889)
		(layer "In11.Cu")
		(net "M_F_DQ<9>")
	)
	(segment
		(start 208.7118 -118.481348)
		(end 208.449926 -118.481348)
		(width 0.14224)
		(layer "In11.Cu")
		(net "M_F_DQ<9>")
	)
	(segment
		(start 208.915 -128.620774)
		(end 208.915 -129.032)
		(width 0.14224)
		(layer "In11.Cu")
		(net "M_F_DQ<9>")
	)
	(segment
		(start 229.317296 -95.3008)
		(end 228.380036 -95.3008)
		(width 0.14224)
		(layer "In11.Cu")
		(net "M_F_DQ<9>")
	)
	(segment
		(start 225.7298 -100.930456)
		(end 208.915 -117.745256)
		(width 0.14224)
		(layer "In11.Cu")
		(net "M_F_DQ<9>")
	)
	(segment
		(start 208.7118 -120.106948)
		(end 208.471262 -120.106948)
		(width 0.14224)
		(layer "In11.Cu")
		(net "M_F_DQ<9>")
	)
	(segment
		(start 208.268062 -120.716548)
		(end 208.471262 -120.919748)
		(width 0.14224)
		(layer "In11.Cu")
		(net "M_F_DQ<9>")
	)
	(segment
		(start 208.292192 -128.310894)
		(end 208.447132 -128.465834)
		(width 0.14224)
		(layer "In11.Cu")
		(net "M_F_DQ<9>")
	)
	(segment
		(start 208.478374 -124.170948)
		(end 208.7118 -124.170948)
		(width 0.14224)
		(layer "In11.Cu")
		(net "M_F_DQ<9>")
	)
	(segment
		(start 208.26095 -123.547124)
		(end 208.26095 -123.953524)
		(width 0.14224)
		(layer "In11.Cu")
		(net "M_F_DQ<9>")
	)
	(segment
		(start 237.346998 -90.85199)
		(end 237.314232 -90.85199)
		(width 0.0889)
		(layer "In11.Cu")
		(net "M_F_DQ<9>")
	)
	(segment
		(start 208.7118 -119.294148)
		(end 208.915 -119.497348)
		(width 0.14224)
		(layer "In11.Cu")
		(net "M_F_DQ<9>")
	)
	(segment
		(start 208.7118 -120.919748)
		(end 208.915 -121.122948)
		(width 0.14224)
		(layer "In11.Cu")
		(net "M_F_DQ<9>")
	)
	(segment
		(start 208.471262 -120.106948)
		(end 208.268062 -120.310148)
		(width 0.14224)
		(layer "In11.Cu")
		(net "M_F_DQ<9>")
	)
	(segment
		(start 208.449926 -119.294148)
		(end 208.7118 -119.294148)
		(width 0.14224)
		(layer "In11.Cu")
		(net "M_F_DQ<9>")
	)
	(segment
		(start 208.76006 -127.653034)
		(end 208.447132 -127.653034)
		(width 0.14224)
		(layer "In11.Cu")
		(net "M_F_DQ<9>")
	)
	(segment
		(start 238.209328 -90.356436)
		(end 238.176562 -90.356436)
		(width 0.0889)
		(layer "In11.Cu")
		(net "M_F_DQ<9>")
	)
	(segment
		(start 233.491024 -93.152214)
		(end 232.475024 -93.152214)
		(width 0.0889)
		(layer "In11.Cu")
		(net "M_F_DQ<9>")
	)
	(segment
		(start 232.475024 -93.152214)
		(end 230.595424 -95.031814)
		(width 0.0889)
		(layer "In11.Cu")
		(net "M_F_DQ<9>")
	)
	(segment
		(start 208.915 -124.374148)
		(end 208.915 -127.498094)
		(width 0.14224)
		(layer "In11.Cu")
		(net "M_F_DQ<9>")
	)
	(segment
		(start 208.609946 -138.709654)
		(end 208.609946 -141.3256)
		(width 0.14224)
		(layer "In11.Cu")
		(net "M_F_DQ<9>")
	)
	(segment
		(start 208.09966 -149.533356)
		(end 207.671416 -149.9616)
		(width 0.14224)
		(layer "In11.Cu")
		(net "M_F_DQ<9>")
	)
	(segment
		(start 207.850994 -153.3906)
		(end 207.698848 -153.542746)
		(width 0.14224)
		(layer "In11.Cu")
		(net "M_F_DQ<9>")
	)
	(segment
		(start 208.78546 -133.456426)
		(end 208.9404 -133.611366)
		(width 0.14224)
		(layer "In11.Cu")
		(net "M_F_DQ<9>")
	)
	(segment
		(start 208.609946 -129.971546)
		(end 208.609946 -131.7244)
		(width 0.14224)
		(layer "In11.Cu")
		(net "M_F_DQ<9>")
	)
	(segment
		(start 208.449926 -118.481348)
		(end 208.246726 -118.684548)
		(width 0.14224)
		(layer "In11.Cu")
		(net "M_F_DQ<9>")
	)
	(segment
		(start 229.325424 -95.292672)
		(end 229.317296 -95.3008)
		(width 0.14224)
		(layer "In11.Cu")
		(net "M_F_DQ<9>")
	)
	(segment
		(start 208.4578 -129.8194)
		(end 208.609946 -129.971546)
		(width 0.14224)
		(layer "In11.Cu")
		(net "M_F_DQ<9>")
	)
	(segment
		(start 208.609946 -134.213854)
		(end 208.609946 -136.5758)
		(width 0.14224)
		(layer "In11.Cu")
		(net "M_F_DQ<9>")
	)
	(segment
		(start 208.4324 -121.732548)
		(end 208.2292 -121.935748)
		(width 0.14224)
		(layer "In11.Cu")
		(net "M_F_DQ<9>")
	)
	(segment
		(start 208.7118 -124.170948)
		(end 208.915 -124.374148)
		(width 0.14224)
		(layer "In11.Cu")
		(net "M_F_DQ<9>")
	)
	(segment
		(start 207.825594 -152.3238)
		(end 207.611218 -152.538176)
		(width 0.14224)
		(layer "In11.Cu")
		(net "M_F_DQ<9>")
	)
	(segment
		(start 208.246726 -119.090948)
		(end 208.449926 -119.294148)
		(width 0.14224)
		(layer "In11.Cu")
		(net "M_F_DQ<9>")
	)
	(segment
		(start 208.915 -117.745256)
		(end 208.915 -118.278148)
		(width 0.14224)
		(layer "In11.Cu")
		(net "M_F_DQ<9>")
	)
	(segment
		(start 234.775248 -92.337636)
		(end 234.305602 -92.337636)
		(width 0.0889)
		(layer "In11.Cu")
		(net "M_F_DQ<9>")
	)
	(segment
		(start 239.064038 -89.86139)
		(end 239.031272 -89.86139)
		(width 0.0889)
		(layer "In11.Cu")
		(net "M_F_DQ<9>")
	)
	(segment
		(start 208.9404 -132.054854)
		(end 208.9404 -132.488686)
		(width 0.14224)
		(layer "In11.Cu")
		(net "M_F_DQ<9>")
	)
	(segment
		(start 208.122012 -149.444456)
		(end 208.122012 -149.533356)
		(width 0.14224)
		(layer "In11.Cu")
		(net "M_F_DQ<9>")
	)
	(segment
		(start 207.611218 -151.677624)
		(end 207.825594 -151.892)
		(width 0.14224)
		(layer "In11.Cu")
		(net "M_F_DQ<9>")
	)
	(segment
		(start 208.310988 -132.798566)
		(end 208.310988 -133.301486)
		(width 0.14224)
		(layer "In11.Cu")
		(net "M_F_DQ<9>")
	)
	(segment
		(start 208.7372 -143.6624)
		(end 208.609946 -143.789654)
		(width 0.14224)
		(layer "In11.Cu")
		(net "M_F_DQ<9>")
	)
	(segment
		(start 207.611218 -152.846024)
		(end 207.850994 -153.0858)
		(width 0.14224)
		(layer "In11.Cu")
		(net "M_F_DQ<9>")
	)
	(segment
		(start 207.825594 -151.892)
		(end 207.825594 -152.3238)
		(width 0.14224)
		(layer "In11.Cu")
		(net "M_F_DQ<9>")
	)
	(segment
		(start 225.7298 -97.951036)
		(end 225.7298 -100.930456)
		(width 0.14224)
		(layer "In11.Cu")
		(net "M_F_DQ<9>")
	)
	(segment
		(start 236.492288 -91.347036)
		(end 236.459522 -91.347036)
		(width 0.0889)
		(layer "In11.Cu")
		(net "M_F_DQ<9>")
	)
	(segment
		(start 207.901794 -150.621746)
		(end 207.901794 -151.026368)
		(width 0.14224)
		(layer "In11.Cu")
		(net "M_F_DQ<9>")
	)
	(segment
		(start 208.78546 -132.643626)
		(end 208.465928 -132.643626)
		(width 0.14224)
		(layer "In11.Cu")
		(net "M_F_DQ<9>")
	)
	(segment
		(start 207.671416 -150.391368)
		(end 207.901794 -150.621746)
		(width 0.14224)
		(layer "In11.Cu")
		(net "M_F_DQ<9>")
	)
	(segment
		(start 208.268062 -120.310148)
		(end 208.268062 -120.716548)
		(width 0.14224)
		(layer "In11.Cu")
		(net "M_F_DQ<9>")
	)
	(segment
		(start 208.7372 -148.3868)
		(end 208.609946 -148.514054)
		(width 0.14224)
		(layer "In11.Cu")
		(net "M_F_DQ<9>")
	)
	(segment
		(start 208.609946 -148.956522)
		(end 208.122012 -149.444456)
		(width 0.14224)
		(layer "In11.Cu")
		(net "M_F_DQ<9>")
	)
	(segment
		(start 208.609946 -148.514054)
		(end 208.609946 -148.956522)
		(width 0.14224)
		(layer "In11.Cu")
		(net "M_F_DQ<9>")
	)
	(segment
		(start 208.9404 -132.488686)
		(end 208.78546 -132.643626)
		(width 0.14224)
		(layer "In11.Cu")
		(net "M_F_DQ<9>")
	)
	(segment
		(start 208.915 -127.498094)
		(end 208.76006 -127.653034)
		(width 0.14224)
		(layer "In11.Cu")
		(net "M_F_DQ<9>")
	)
	(segment
		(start 208.471262 -120.919748)
		(end 208.7118 -120.919748)
		(width 0.14224)
		(layer "In11.Cu")
		(net "M_F_DQ<9>")
	)
	(segment
		(start 208.9404 -133.611366)
		(end 208.9404 -133.8834)
		(width 0.14224)
		(layer "In11.Cu")
		(net "M_F_DQ<9>")
	)
	(segment
		(start 208.7118 -123.358148)
		(end 208.449926 -123.358148)
		(width 0.14224)
		(layer "In11.Cu")
		(net "M_F_DQ<9>")
	)
	(segment
		(start 208.447132 -128.465834)
		(end 208.76006 -128.465834)
		(width 0.14224)
		(layer "In11.Cu")
		(net "M_F_DQ<9>")
	)
	(segment
		(start 208.7372 -146.304254)
		(end 208.7372 -148.3868)
		(width 0.14224)
		(layer "In11.Cu")
		(net "M_F_DQ<9>")
	)
	(segment
		(start 208.7118 -138.6078)
		(end 208.609946 -138.709654)
		(width 0.14224)
		(layer "In11.Cu")
		(net "M_F_DQ<9>")
	)
	(segment
		(start 207.850994 -153.0858)
		(end 207.850994 -153.3906)
		(width 0.14224)
		(layer "In11.Cu")
		(net "M_F_DQ<9>")
	)
	(segment
		(start 208.7118 -121.732548)
		(end 208.4324 -121.732548)
		(width 0.14224)
		(layer "In11.Cu")
		(net "M_F_DQ<9>")
	)
	(segment
		(start 228.380036 -95.3008)
		(end 225.7298 -97.951036)
		(width 0.14224)
		(layer "In11.Cu")
		(net "M_F_DQ<9>")
	)
	(segment
		(start 208.465928 -133.456426)
		(end 208.78546 -133.456426)
		(width 0.14224)
		(layer "In11.Cu")
		(net "M_F_DQ<9>")
	)
	(segment
		(start 207.671416 -149.9616)
		(end 207.671416 -150.391368)
		(width 0.14224)
		(layer "In11.Cu")
		(net "M_F_DQ<9>")
	)
	(segment
		(start 208.609946 -143.789654)
		(end 208.609946 -146.177)
		(width 0.14224)
		(layer "In11.Cu")
		(net "M_F_DQ<9>")
	)
	(segment
		(start 208.7372 -141.452854)
		(end 208.7372 -143.6624)
		(width 0.14224)
		(layer "In11.Cu")
		(net "M_F_DQ<9>")
	)
	(segment
		(start 240.763298 -90.26144)
		(end 240.268252 -89.595452)
		(width 0.0889)
		(layer "In11.Cu")
		(net "M_F_DQ<9>")
	)
	(segment
		(start 208.915 -122.748548)
		(end 208.915 -123.154948)
		(width 0.14224)
		(layer "In11.Cu")
		(net "M_F_DQ<9>")
	)
	(segment
		(start 208.915 -123.154948)
		(end 208.7118 -123.358148)
		(width 0.14224)
		(layer "In11.Cu")
		(net "M_F_DQ<9>")
	)
	(segment
		(start 229.586282 -95.031814)
		(end 229.325424 -95.292672)
		(width 0.0889)
		(layer "In11.Cu")
		(net "M_F_DQ<9>")
	)
	(segment
		(start 207.611218 -151.316944)
		(end 207.611218 -151.677624)
		(width 0.14224)
		(layer "In11.Cu")
		(net "M_F_DQ<9>")
	)
	(segment
		(start 208.310988 -133.301486)
		(end 208.465928 -133.456426)
		(width 0.14224)
		(layer "In11.Cu")
		(net "M_F_DQ<9>")
	)
	(segment
		(start 234.305602 -92.337636)
		(end 233.491024 -93.152214)
		(width 0.0889)
		(layer "In11.Cu")
		(net "M_F_DQ<9>")
	)
	(segment
		(start 208.915 -119.497348)
		(end 208.915 -119.903748)
		(width 0.14224)
		(layer "In11.Cu")
		(net "M_F_DQ<9>")
	)
	(segment
		(start 208.609946 -146.177)
		(end 208.7372 -146.304254)
		(width 0.14224)
		(layer "In11.Cu")
		(net "M_F_DQ<9>")
	)
	(segment
		(start 208.246726 -118.684548)
		(end 208.246726 -119.090948)
		(width 0.14224)
		(layer "In11.Cu")
		(net "M_F_DQ<9>")
	)
	(segment
		(start 208.915 -129.032)
		(end 208.4578 -129.4892)
		(width 0.14224)
		(layer "In11.Cu")
		(net "M_F_DQ<9>")
	)
	(segment
		(start 208.4324 -122.545348)
		(end 208.7118 -122.545348)
		(width 0.14224)
		(layer "In11.Cu")
		(net "M_F_DQ<9>")
	)
	(segment
		(start 208.915 -121.122948)
		(end 208.915 -121.529348)
		(width 0.14224)
		(layer "In11.Cu")
		(net "M_F_DQ<9>")
	)
	(segment
		(start 208.449926 -123.358148)
		(end 208.26095 -123.547124)
		(width 0.14224)
		(layer "In11.Cu")
		(net "M_F_DQ<9>")
	)
	(arc
		(start 238.699548 -90.061288)
		(mid 238.492544 -90.272152)
		(end 238.209328 -90.356436)
		(width 0.0889)
		(layer "In11.Cu")
		(net "M_F_DQ<9>")
	)
	(arc
		(start 239.558068 -89.565988)
		(mid 239.34946 -89.77792)
		(end 239.064038 -89.86139)
		(width 0.0889)
		(layer "In11.Cu")
		(net "M_F_DQ<9>")
	)
	(arc
		(start 236.123988 -91.547188)
		(mid 235.91538 -91.75912)
		(end 235.629958 -91.84259)
		(width 0.0889)
		(layer "In11.Cu")
		(net "M_F_DQ<9>")
	)
	(arc
		(start 238.176562 -90.356436)
		(mid 237.982712 -90.412786)
		(end 237.841028 -90.556588)
		(width 0.0889)
		(layer "In11.Cu")
		(net "M_F_DQ<9>")
	)
	(arc
		(start 235.265468 -92.042488)
		(mid 235.058464 -92.253352)
		(end 234.775248 -92.337636)
		(width 0.0889)
		(layer "In11.Cu")
		(net "M_F_DQ<9>")
	)
	(arc
		(start 236.459522 -91.347036)
		(mid 236.265672 -91.403386)
		(end 236.123988 -91.547188)
		(width 0.0889)
		(layer "In11.Cu")
		(net "M_F_DQ<9>")
	)
	(arc
		(start 236.982508 -91.051888)
		(mid 236.775504 -91.262752)
		(end 236.492288 -91.347036)
		(width 0.0889)
		(layer "In11.Cu")
		(net "M_F_DQ<9>")
	)
	(arc
		(start 239.031272 -89.86139)
		(mid 238.83963 -89.918556)
		(end 238.699548 -90.061288)
		(width 0.0889)
		(layer "In11.Cu")
		(net "M_F_DQ<9>")
	)
	(arc
		(start 237.314232 -90.85199)
		(mid 237.12259 -90.909156)
		(end 236.982508 -91.051888)
		(width 0.0889)
		(layer "In11.Cu")
		(net "M_F_DQ<9>")
	)
	(arc
		(start 240.251488 -89.565988)
		(mid 239.904778 -89.365677)
		(end 239.558068 -89.565988)
		(width 0.0889)
		(layer "In11.Cu")
		(net "M_F_DQ<9>")
	)
	(arc
		(start 235.597192 -91.84259)
		(mid 235.40555 -91.899756)
		(end 235.265468 -92.042488)
		(width 0.0889)
		(layer "In11.Cu")
		(net "M_F_DQ<9>")
	)
	(arc
		(start 237.841028 -90.556588)
		(mid 237.63242 -90.76852)
		(end 237.346998 -90.85199)
		(width 0.0889)
		(layer "In11.Cu")
		(net "M_F_DQ<9>")
	)
	(segment
		(start 208.30032 -156.87294)
		(end 208.299812 -156.878782)
		(width 0.1651)
		(layer "F.Cu")
		(net "M_F_DQ<8>")
	)
	(segment
		(start 243.051838 -91.25204)
		(end 242.480338 -91.25204)
		(width 0.1651)
		(layer "F.Cu")
		(net "M_F_DQ<8>")
	)
	(segment
		(start 208.299812 -156.878782)
		(end 208.122012 -155.0162)
		(width 0.1651)
		(layer "F.Cu")
		(net "M_F_DQ<8>")
	)
	(via
		(at 242.480338 -91.25204)
		(size 0.508)
		(drill 0.254)
		(layers "F.Cu" "B.Cu")
		(net "M_F_DQ<8>")
	)
	(via
		(at 208.122012 -155.0162)
		(size 0.508)
		(drill 0.254)
		(layers "F.Cu" "B.Cu")
		(net "M_F_DQ<8>")
	)
	(via
		(at 207.449928 -150.814278)
		(size 0.508)
		(drill 0.254)
		(layers "F.Cu" "B.Cu")
		(net "M_F_DQ<8>")
	)
	(segment
		(start 207.450436 -152.078436)
		(end 207.449928 -152.078182)
		(width 0.1651)
		(layer "B.Cu")
		(net "M_F_DQ<8>")
	)
	(segment
		(start 207.449928 -152.078182)
		(end 207.449928 -150.814278)
		(width 0.1651)
		(layer "B.Cu")
		(net "M_F_DQ<8>")
	)
	(segment
		(start 207.085946 -150.450296)
		(end 207.085946 -149.810978)
		(width 0.14224)
		(layer "In11.Cu")
		(net "M_F_DQ<8>")
	)
	(segment
		(start 207.632046 -134.776718)
		(end 207.974946 -134.433818)
		(width 0.14224)
		(layer "In11.Cu")
		(net "M_F_DQ<8>")
	)
	(segment
		(start 236.452918 -91.156536)
		(end 236.485684 -91.156536)
		(width 0.0889)
		(layer "In11.Cu")
		(net "M_F_DQ<8>")
	)
	(segment
		(start 207.8736 -146.240246)
		(end 207.936846 -146.177)
		(width 0.14224)
		(layer "In11.Cu")
		(net "M_F_DQ<8>")
	)
	(segment
		(start 207.924146 -143.687546)
		(end 207.8736 -143.637)
		(width 0.14224)
		(layer "In11.Cu")
		(net "M_F_DQ<8>")
	)
	(segment
		(start 229.526592 -94.841822)
		(end 230.516684 -94.841822)
		(width 0.0889)
		(layer "In11.Cu")
		(net "M_F_DQ<8>")
	)
	(segment
		(start 207.974946 -138.810746)
		(end 207.8736 -138.7094)
		(width 0.14224)
		(layer "In11.Cu")
		(net "M_F_DQ<8>")
	)
	(segment
		(start 207.8736 -141.528546)
		(end 207.924146 -141.478)
		(width 0.14224)
		(layer "In11.Cu")
		(net "M_F_DQ<8>")
	)
	(segment
		(start 207.7466 -118.015512)
		(end 225.1456 -100.616512)
		(width 0.14224)
		(layer "In11.Cu")
		(net "M_F_DQ<8>")
	)
	(segment
		(start 233.412284 -92.962222)
		(end 234.171236 -92.20327)
		(width 0.0889)
		(layer "In11.Cu")
		(net "M_F_DQ<8>")
	)
	(segment
		(start 207.9498 -126.039372)
		(end 208.1276 -126.039372)
		(width 0.14224)
		(layer "In11.Cu")
		(net "M_F_DQ<8>")
	)
	(segment
		(start 207.899 -129.795524)
		(end 207.899 -129.2098)
		(width 0.14224)
		(layer "In11.Cu")
		(net "M_F_DQ<8>")
	)
	(segment
		(start 207.8736 -143.637)
		(end 207.8736 -141.528546)
		(width 0.14224)
		(layer "In11.Cu")
		(net "M_F_DQ<8>")
	)
	(segment
		(start 229.325424 -94.640654)
		(end 229.526592 -94.841822)
		(width 0.0889)
		(layer "In11.Cu")
		(net "M_F_DQ<8>")
	)
	(segment
		(start 228.337872 -94.6658)
		(end 229.300278 -94.6658)
		(width 0.14224)
		(layer "In11.Cu")
		(net "M_F_DQ<8>")
	)
	(segment
		(start 241.606832 -90.165936)
		(end 241.639598 -90.165936)
		(width 0.0889)
		(layer "In11.Cu")
		(net "M_F_DQ<8>")
	)
	(segment
		(start 242.133628 -90.461338)
		(end 242.1509 -90.491056)
		(width 0.0889)
		(layer "In11.Cu")
		(net "M_F_DQ<8>")
	)
	(segment
		(start 207.672178 -132.281168)
		(end 207.974946 -131.9784)
		(width 0.14224)
		(layer "In11.Cu")
		(net "M_F_DQ<8>")
	)
	(segment
		(start 207.632046 -135.9789)
		(end 207.632046 -134.776718)
		(width 0.14224)
		(layer "In11.Cu")
		(net "M_F_DQ<8>")
	)
	(segment
		(start 208.122012 -155.0162)
		(end 207.016858 -153.911046)
		(width 0.14224)
		(layer "In11.Cu")
		(net "M_F_DQ<8>")
	)
	(segment
		(start 207.9498 -125.226572)
		(end 207.7466 -125.023372)
		(width 0.14224)
		(layer "In11.Cu")
		(net "M_F_DQ<8>")
	)
	(segment
		(start 207.016858 -151.247348)
		(end 207.449928 -150.814278)
		(width 0.14224)
		(layer "In11.Cu")
		(net "M_F_DQ<8>")
	)
	(segment
		(start 242.1509 -90.491056)
		(end 242.480338 -91.25204)
		(width 0.0889)
		(layer "In11.Cu")
		(net "M_F_DQ<8>")
	)
	(segment
		(start 234.171236 -92.20327)
		(end 234.170982 -92.20327)
		(width 0.0889)
		(layer "In11.Cu")
		(net "M_F_DQ<8>")
	)
	(segment
		(start 207.8736 -148.4376)
		(end 207.8736 -146.240246)
		(width 0.14224)
		(layer "In11.Cu")
		(net "M_F_DQ<8>")
	)
	(segment
		(start 207.974946 -131.9784)
		(end 207.974946 -131.484878)
		(width 0.14224)
		(layer "In11.Cu")
		(net "M_F_DQ<8>")
	)
	(segment
		(start 207.7466 -129.0574)
		(end 207.7466 -126.242572)
		(width 0.14224)
		(layer "In11.Cu")
		(net "M_F_DQ<8>")
	)
	(segment
		(start 207.449928 -150.814278)
		(end 207.085946 -150.450296)
		(width 0.14224)
		(layer "In11.Cu")
		(net "M_F_DQ<8>")
	)
	(segment
		(start 207.936846 -146.177)
		(end 207.936846 -145.884646)
		(width 0.14224)
		(layer "In11.Cu")
		(net "M_F_DQ<8>")
	)
	(segment
		(start 234.226608 -92.147136)
		(end 234.768644 -92.147136)
		(width 0.0889)
		(layer "In11.Cu")
		(net "M_F_DQ<8>")
	)
	(segment
		(start 238.169958 -90.165936)
		(end 238.202724 -90.165936)
		(width 0.0889)
		(layer "In11.Cu")
		(net "M_F_DQ<8>")
	)
	(segment
		(start 207.924146 -141.035278)
		(end 207.632046 -140.743178)
		(width 0.14224)
		(layer "In11.Cu")
		(net "M_F_DQ<8>")
	)
	(segment
		(start 234.170982 -92.20327)
		(end 234.170982 -92.202762)
		(width 0.0889)
		(layer "In11.Cu")
		(net "M_F_DQ<8>")
	)
	(segment
		(start 207.085946 -149.810978)
		(end 207.936846 -148.960078)
		(width 0.14224)
		(layer "In11.Cu")
		(net "M_F_DQ<8>")
	)
	(segment
		(start 207.974946 -134.060946)
		(end 207.672178 -133.758178)
		(width 0.14224)
		(layer "In11.Cu")
		(net "M_F_DQ<8>")
	)
	(segment
		(start 207.632046 -130.062478)
		(end 207.899 -129.795524)
		(width 0.14224)
		(layer "In11.Cu")
		(net "M_F_DQ<8>")
	)
	(segment
		(start 207.974946 -134.433818)
		(end 207.974946 -134.060946)
		(width 0.14224)
		(layer "In11.Cu")
		(net "M_F_DQ<8>")
	)
	(segment
		(start 208.1276 -125.226572)
		(end 207.9498 -125.226572)
		(width 0.14224)
		(layer "In11.Cu")
		(net "M_F_DQ<8>")
	)
	(segment
		(start 207.974946 -139.320778)
		(end 207.974946 -138.810746)
		(width 0.14224)
		(layer "In11.Cu")
		(net "M_F_DQ<8>")
	)
	(segment
		(start 208.3308 -125.836172)
		(end 208.3308 -125.429772)
		(width 0.14224)
		(layer "In11.Cu")
		(net "M_F_DQ<8>")
	)
	(segment
		(start 207.974946 -131.484878)
		(end 207.632046 -131.141978)
		(width 0.14224)
		(layer "In11.Cu")
		(net "M_F_DQ<8>")
	)
	(segment
		(start 207.8736 -136.702546)
		(end 207.974946 -136.6012)
		(width 0.14224)
		(layer "In11.Cu")
		(net "M_F_DQ<8>")
	)
	(segment
		(start 207.924146 -141.478)
		(end 207.924146 -141.035278)
		(width 0.14224)
		(layer "In11.Cu")
		(net "M_F_DQ<8>")
	)
	(segment
		(start 207.936846 -145.884646)
		(end 207.644746 -145.592546)
		(width 0.14224)
		(layer "In11.Cu")
		(net "M_F_DQ<8>")
	)
	(segment
		(start 239.024668 -89.67089)
		(end 239.057434 -89.67089)
		(width 0.0889)
		(layer "In11.Cu")
		(net "M_F_DQ<8>")
	)
	(segment
		(start 207.7466 -125.023372)
		(end 207.7466 -118.015512)
		(width 0.14224)
		(layer "In11.Cu")
		(net "M_F_DQ<8>")
	)
	(segment
		(start 207.632046 -140.743178)
		(end 207.632046 -139.663678)
		(width 0.14224)
		(layer "In11.Cu")
		(net "M_F_DQ<8>")
	)
	(segment
		(start 207.924146 -144.085818)
		(end 207.924146 -143.687546)
		(width 0.14224)
		(layer "In11.Cu")
		(net "M_F_DQ<8>")
	)
	(segment
		(start 234.170982 -92.202762)
		(end 234.226608 -92.147136)
		(width 0.0889)
		(layer "In11.Cu")
		(net "M_F_DQ<8>")
	)
	(segment
		(start 207.936846 -148.500846)
		(end 207.8736 -148.4376)
		(width 0.14224)
		(layer "In11.Cu")
		(net "M_F_DQ<8>")
	)
	(segment
		(start 232.396284 -92.962222)
		(end 233.412284 -92.962222)
		(width 0.0889)
		(layer "In11.Cu")
		(net "M_F_DQ<8>")
	)
	(segment
		(start 207.974946 -136.3218)
		(end 207.632046 -135.9789)
		(width 0.14224)
		(layer "In11.Cu")
		(net "M_F_DQ<8>")
	)
	(segment
		(start 207.632046 -139.663678)
		(end 207.974946 -139.320778)
		(width 0.14224)
		(layer "In11.Cu")
		(net "M_F_DQ<8>")
	)
	(segment
		(start 207.899 -129.2098)
		(end 207.7466 -129.0574)
		(width 0.14224)
		(layer "In11.Cu")
		(net "M_F_DQ<8>")
	)
	(segment
		(start 207.7466 -126.242572)
		(end 207.9498 -126.039372)
		(width 0.14224)
		(layer "In11.Cu")
		(net "M_F_DQ<8>")
	)
	(segment
		(start 207.632046 -131.141978)
		(end 207.632046 -130.062478)
		(width 0.14224)
		(layer "In11.Cu")
		(net "M_F_DQ<8>")
	)
	(segment
		(start 207.644746 -144.365218)
		(end 207.924146 -144.085818)
		(width 0.14224)
		(layer "In11.Cu")
		(net "M_F_DQ<8>")
	)
	(segment
		(start 230.516684 -94.841822)
		(end 232.396284 -92.962222)
		(width 0.0889)
		(layer "In11.Cu")
		(net "M_F_DQ<8>")
	)
	(segment
		(start 208.1276 -126.039372)
		(end 208.3308 -125.836172)
		(width 0.14224)
		(layer "In11.Cu")
		(net "M_F_DQ<8>")
	)
	(segment
		(start 207.016858 -153.911046)
		(end 207.016858 -151.247348)
		(width 0.14224)
		(layer "In11.Cu")
		(net "M_F_DQ<8>")
	)
	(segment
		(start 207.974946 -136.6012)
		(end 207.974946 -136.3218)
		(width 0.14224)
		(layer "In11.Cu")
		(net "M_F_DQ<8>")
	)
	(segment
		(start 235.590588 -91.65209)
		(end 235.623354 -91.65209)
		(width 0.0889)
		(layer "In11.Cu")
		(net "M_F_DQ<8>")
	)
	(segment
		(start 207.8736 -138.7094)
		(end 207.8736 -136.702546)
		(width 0.14224)
		(layer "In11.Cu")
		(net "M_F_DQ<8>")
	)
	(segment
		(start 207.644746 -145.592546)
		(end 207.644746 -144.365218)
		(width 0.14224)
		(layer "In11.Cu")
		(net "M_F_DQ<8>")
	)
	(segment
		(start 225.1456 -97.858072)
		(end 228.337872 -94.6658)
		(width 0.14224)
		(layer "In11.Cu")
		(net "M_F_DQ<8>")
	)
	(segment
		(start 237.307628 -90.66149)
		(end 237.340394 -90.66149)
		(width 0.0889)
		(layer "In11.Cu")
		(net "M_F_DQ<8>")
	)
	(segment
		(start 207.672178 -133.758178)
		(end 207.672178 -132.281168)
		(width 0.14224)
		(layer "In11.Cu")
		(net "M_F_DQ<8>")
	)
	(segment
		(start 225.1456 -100.616512)
		(end 225.1456 -97.858072)
		(width 0.14224)
		(layer "In11.Cu")
		(net "M_F_DQ<8>")
	)
	(segment
		(start 239.886998 -89.175336)
		(end 239.922558 -89.175336)
		(width 0.0889)
		(layer "In11.Cu")
		(net "M_F_DQ<8>")
	)
	(segment
		(start 229.300278 -94.6658)
		(end 229.325424 -94.640654)
		(width 0.14224)
		(layer "In11.Cu")
		(net "M_F_DQ<8>")
	)
	(segment
		(start 240.752122 -89.67089)
		(end 240.784888 -89.67089)
		(width 0.0889)
		(layer "In11.Cu")
		(net "M_F_DQ<8>")
	)
	(segment
		(start 207.936846 -148.960078)
		(end 207.936846 -148.500846)
		(width 0.14224)
		(layer "In11.Cu")
		(net "M_F_DQ<8>")
	)
	(segment
		(start 208.3308 -125.429772)
		(end 208.1276 -125.226572)
		(width 0.14224)
		(layer "In11.Cu")
		(net "M_F_DQ<8>")
	)
	(arc
		(start 234.768644 -92.147136)
		(mid 234.960286 -92.08997)
		(end 235.100368 -91.947238)
		(width 0.0889)
		(layer "In11.Cu")
		(net "M_F_DQ<8>")
	)
	(arc
		(start 235.100368 -91.947238)
		(mid 235.307372 -91.736374)
		(end 235.590588 -91.65209)
		(width 0.0889)
		(layer "In11.Cu")
		(net "M_F_DQ<8>")
	)
	(arc
		(start 235.623354 -91.65209)
		(mid 235.817204 -91.59574)
		(end 235.958888 -91.451938)
		(width 0.0889)
		(layer "In11.Cu")
		(net "M_F_DQ<8>")
	)
	(arc
		(start 240.784888 -89.67089)
		(mid 241.068105 -89.755171)
		(end 241.275108 -89.966038)
		(width 0.0889)
		(layer "In11.Cu")
		(net "M_F_DQ<8>")
	)
	(arc
		(start 239.057434 -89.67089)
		(mid 239.251284 -89.61454)
		(end 239.392968 -89.470738)
		(width 0.0889)
		(layer "In11.Cu")
		(net "M_F_DQ<8>")
	)
	(arc
		(start 237.340394 -90.66149)
		(mid 237.534244 -90.60514)
		(end 237.675928 -90.461338)
		(width 0.0889)
		(layer "In11.Cu")
		(net "M_F_DQ<8>")
	)
	(arc
		(start 241.275108 -89.966038)
		(mid 241.415187 -90.108774)
		(end 241.606832 -90.165936)
		(width 0.0889)
		(layer "In11.Cu")
		(net "M_F_DQ<8>")
	)
	(arc
		(start 236.817408 -90.956638)
		(mid 237.024412 -90.745774)
		(end 237.307628 -90.66149)
		(width 0.0889)
		(layer "In11.Cu")
		(net "M_F_DQ<8>")
	)
	(arc
		(start 238.202724 -90.165936)
		(mid 238.394366 -90.10877)
		(end 238.534448 -89.966038)
		(width 0.0889)
		(layer "In11.Cu")
		(net "M_F_DQ<8>")
	)
	(arc
		(start 235.958888 -91.451938)
		(mid 236.167496 -91.240006)
		(end 236.452918 -91.156536)
		(width 0.0889)
		(layer "In11.Cu")
		(net "M_F_DQ<8>")
	)
	(arc
		(start 240.416588 -89.470738)
		(mid 240.558271 -89.614542)
		(end 240.752122 -89.67089)
		(width 0.0889)
		(layer "In11.Cu")
		(net "M_F_DQ<8>")
	)
	(arc
		(start 237.675928 -90.461338)
		(mid 237.884536 -90.249406)
		(end 238.169958 -90.165936)
		(width 0.0889)
		(layer "In11.Cu")
		(net "M_F_DQ<8>")
	)
	(arc
		(start 239.922558 -89.175336)
		(mid 240.207982 -89.258803)
		(end 240.416588 -89.470738)
		(width 0.0889)
		(layer "In11.Cu")
		(net "M_F_DQ<8>")
	)
	(arc
		(start 239.392968 -89.470738)
		(mid 239.601576 -89.258806)
		(end 239.886998 -89.175336)
		(width 0.0889)
		(layer "In11.Cu")
		(net "M_F_DQ<8>")
	)
	(arc
		(start 238.534448 -89.966038)
		(mid 238.741452 -89.755174)
		(end 239.024668 -89.67089)
		(width 0.0889)
		(layer "In11.Cu")
		(net "M_F_DQ<8>")
	)
	(arc
		(start 241.639598 -90.165936)
		(mid 241.925022 -90.249403)
		(end 242.133628 -90.461338)
		(width 0.0889)
		(layer "In11.Cu")
		(net "M_F_DQ<8>")
	)
	(arc
		(start 236.485684 -91.156536)
		(mid 236.677326 -91.09937)
		(end 236.817408 -90.956638)
		(width 0.0889)
		(layer "In11.Cu")
		(net "M_F_DQ<8>")
	)
	(segment
		(start 202.35037 -152.273)
		(end 202.349862 -152.278842)
		(width 0.1651)
		(layer "F.Cu")
		(net "M_F_DQ<7>")
	)
	(segment
		(start 240.476278 -86.794086)
		(end 239.904778 -86.794086)
		(width 0.1651)
		(layer "F.Cu")
		(net "M_F_DQ<7>")
	)
	(segment
		(start 202.349862 -152.278842)
		(end 202.349862 -153.542746)
		(width 0.1651)
		(layer "F.Cu")
		(net "M_F_DQ<7>")
	)
	(via
		(at 203.199746 -149.533356)
		(size 0.508)
		(drill 0.254)
		(layers "F.Cu" "B.Cu")
		(net "M_F_DQ<7>")
	)
	(via
		(at 202.349862 -153.542746)
		(size 0.508)
		(drill 0.254)
		(layers "F.Cu" "B.Cu")
		(net "M_F_DQ<7>")
	)
	(via
		(at 239.904778 -86.794086)
		(size 0.508)
		(drill 0.254)
		(layers "F.Cu" "B.Cu")
		(net "M_F_DQ<7>")
	)
	(segment
		(start 203.199746 -147.478496)
		(end 203.199746 -149.533356)
		(width 0.1651)
		(layer "B.Cu")
		(net "M_F_DQ<7>")
	)
	(segment
		(start 203.200508 -147.478496)
		(end 203.199746 -147.478496)
		(width 0.1651)
		(layer "B.Cu")
		(net "M_F_DQ<7>")
	)
	(segment
		(start 203.835 -134.836916)
		(end 203.835 -135.9408)
		(width 0.14224)
		(layer "In11.Cu")
		(net "M_F_DQ<7>")
	)
	(segment
		(start 203.454 -138.9126)
		(end 203.454 -139.361926)
		(width 0.14224)
		(layer "In11.Cu")
		(net "M_F_DQ<7>")
	)
	(segment
		(start 203.7842 -144.375886)
		(end 203.7842 -145.567146)
		(width 0.14224)
		(layer "In11.Cu")
		(net "M_F_DQ<7>")
	)
	(segment
		(start 207.46466 -110.968536)
		(end 207.205834 -111.227362)
		(width 0.14224)
		(layer "In11.Cu")
		(net "M_F_DQ<7>")
	)
	(segment
		(start 231.71404 -90.85199)
		(end 231.638856 -90.776806)
		(width 0.0889)
		(layer "In11.Cu")
		(net "M_F_DQ<7>")
	)
	(segment
		(start 203.8096 -139.717526)
		(end 203.8096 -140.690854)
		(width 0.14224)
		(layer "In11.Cu")
		(net "M_F_DQ<7>")
	)
	(segment
		(start 202.74915 -149.9616)
		(end 202.74915 -150.391368)
		(width 0.14224)
		(layer "In11.Cu")
		(net "M_F_DQ<7>")
	)
	(segment
		(start 203.865988 -127.623316)
		(end 203.711048 -127.778256)
		(width 0.14224)
		(layer "In11.Cu")
		(net "M_F_DQ<7>")
	)
	(segment
		(start 205.624684 -112.808512)
		(end 205.365858 -113.067338)
		(width 0.14224)
		(layer "In11.Cu")
		(net "M_F_DQ<7>")
	)
	(segment
		(start 202.7682 -151.9174)
		(end 202.7682 -152.2222)
		(width 0.14224)
		(layer "In11.Cu")
		(net "M_F_DQ<7>")
	)
	(segment
		(start 231.638856 -90.776806)
		(end 228.572314 -90.776806)
		(width 0.0889)
		(layer "In11.Cu")
		(net "M_F_DQ<7>")
	)
	(segment
		(start 236.492288 -88.375236)
		(end 236.459522 -88.375236)
		(width 0.0889)
		(layer "In11.Cu")
		(net "M_F_DQ<7>")
	)
	(segment
		(start 203.552552 -148.466048)
		(end 203.552552 -149.191472)
		(width 0.14224)
		(layer "In11.Cu")
		(net "M_F_DQ<7>")
	)
	(segment
		(start 203.199746 -149.533356)
		(end 203.177394 -149.533356)
		(width 0.14224)
		(layer "In11.Cu")
		(net "M_F_DQ<7>")
	)
	(segment
		(start 203.865988 -128.745996)
		(end 203.865988 -129.001012)
		(width 0.14224)
		(layer "In11.Cu")
		(net "M_F_DQ<7>")
	)
	(segment
		(start 203.905866 -112.728502)
		(end 204.704696 -113.527332)
		(width 0.14224)
		(layer "In11.Cu")
		(net "M_F_DQ<7>")
	)
	(segment
		(start 207.71485 -109.177582)
		(end 208.384648 -109.84738)
		(width 0.14224)
		(layer "In11.Cu")
		(net "M_F_DQ<7>")
	)
	(segment
		(start 204.825854 -111.607346)
		(end 204.825854 -111.808514)
		(width 0.14224)
		(layer "In11.Cu")
		(net "M_F_DQ<7>")
	)
	(segment
		(start 213.073996 -105.3592)
		(end 209.04581 -109.387386)
		(width 0.14224)
		(layer "In11.Cu")
		(net "M_F_DQ<7>")
	)
	(segment
		(start 207.46466 -110.767368)
		(end 207.46466 -110.968536)
		(width 0.14224)
		(layer "In11.Cu")
		(net "M_F_DQ<7>")
	)
	(segment
		(start 206.004668 -110.428532)
		(end 205.745842 -110.687358)
		(width 0.14224)
		(layer "In11.Cu")
		(net "M_F_DQ<7>")
	)
	(segment
		(start 205.08468 -111.34852)
		(end 204.825854 -111.607346)
		(width 0.14224)
		(layer "In11.Cu")
		(net "M_F_DQ<7>")
	)
	(segment
		(start 203.187554 -128.591056)
		(end 203.711048 -128.591056)
		(width 0.14224)
		(layer "In11.Cu")
		(net "M_F_DQ<7>")
	)
	(segment
		(start 203.032614 -127.933196)
		(end 203.032614 -128.436116)
		(width 0.14224)
		(layer "In11.Cu")
		(net "M_F_DQ<7>")
	)
	(segment
		(start 203.475082 -131.424172)
		(end 203.475082 -131.948682)
		(width 0.14224)
		(layer "In11.Cu")
		(net "M_F_DQ<7>")
	)
	(segment
		(start 228.357176 -90.991944)
		(end 228.26472 -91.0844)
		(width 0.14224)
		(layer "In11.Cu")
		(net "M_F_DQ<7>")
	)
	(segment
		(start 203.711048 -128.591056)
		(end 203.865988 -128.745996)
		(width 0.14224)
		(layer "In11.Cu")
		(net "M_F_DQ<7>")
	)
	(segment
		(start 228.572314 -90.776806)
		(end 228.357176 -90.991944)
		(width 0.0889)
		(layer "In11.Cu")
		(net "M_F_DQ<7>")
	)
	(segment
		(start 235.629958 -88.87079)
		(end 235.597192 -88.87079)
		(width 0.0889)
		(layer "In11.Cu")
		(net "M_F_DQ<7>")
	)
	(segment
		(start 207.71485 -108.99775)
		(end 207.71485 -109.177582)
		(width 0.14224)
		(layer "In11.Cu")
		(net "M_F_DQ<7>")
	)
	(segment
		(start 203.835 -130.141726)
		(end 203.835 -131.064254)
		(width 0.14224)
		(layer "In11.Cu")
		(net "M_F_DQ<7>")
	)
	(segment
		(start 203.4794 -136.7282)
		(end 203.6318 -136.8806)
		(width 0.14224)
		(layer "In11.Cu")
		(net "M_F_DQ<7>")
	)
	(segment
		(start 234.775248 -89.365836)
		(end 234.742482 -89.365836)
		(width 0.0889)
		(layer "In11.Cu")
		(net "M_F_DQ<7>")
	)
	(segment
		(start 237.346998 -87.88019)
		(end 237.314232 -87.88019)
		(width 0.0889)
		(layer "In11.Cu")
		(net "M_F_DQ<7>")
	)
	(segment
		(start 208.844642 -109.387386)
		(end 208.198212 -108.740956)
		(width 0.14224)
		(layer "In11.Cu")
		(net "M_F_DQ<7>")
	)
	(segment
		(start 239.21974 -86.88959)
		(end 239.031272 -86.88959)
		(width 0.0889)
		(layer "In11.Cu")
		(net "M_F_DQ<7>")
	)
	(segment
		(start 204.164692 -112.268508)
		(end 203.905866 -112.527334)
		(width 0.14224)
		(layer "In11.Cu")
		(net "M_F_DQ<7>")
	)
	(segment
		(start 203.449682 -141.42593)
		(end 203.6318 -141.608048)
		(width 0.14224)
		(layer "In11.Cu")
		(net "M_F_DQ<7>")
	)
	(segment
		(start 204.704696 -113.527332)
		(end 204.704696 -113.7285)
		(width 0.14224)
		(layer "In11.Cu")
		(net "M_F_DQ<7>")
	)
	(segment
		(start 233.912918 -89.86139)
		(end 233.880152 -89.86139)
		(width 0.0889)
		(layer "In11.Cu")
		(net "M_F_DQ<7>")
	)
	(segment
		(start 238.209328 -87.384636)
		(end 238.176562 -87.384636)
		(width 0.0889)
		(layer "In11.Cu")
		(net "M_F_DQ<7>")
	)
	(segment
		(start 203.507848 -144.099534)
		(end 203.7842 -144.375886)
		(width 0.14224)
		(layer "In11.Cu")
		(net "M_F_DQ<7>")
	)
	(segment
		(start 207.205834 -111.227362)
		(end 207.004666 -111.227362)
		(width 0.14224)
		(layer "In11.Cu")
		(net "M_F_DQ<7>")
	)
	(segment
		(start 203.835 -131.064254)
		(end 203.475082 -131.424172)
		(width 0.14224)
		(layer "In11.Cu")
		(net "M_F_DQ<7>")
	)
	(segment
		(start 220.1672 -98.679)
		(end 220.1672 -100.3554)
		(width 0.14224)
		(layer "In11.Cu")
		(net "M_F_DQ<7>")
	)
	(segment
		(start 203.032614 -128.436116)
		(end 203.187554 -128.591056)
		(width 0.14224)
		(layer "In11.Cu")
		(net "M_F_DQ<7>")
	)
	(segment
		(start 206.66583 -109.968538)
		(end 207.46466 -110.767368)
		(width 0.14224)
		(layer "In11.Cu")
		(net "M_F_DQ<7>")
	)
	(segment
		(start 205.285848 -111.34852)
		(end 205.08468 -111.34852)
		(width 0.14224)
		(layer "In11.Cu")
		(net "M_F_DQ<7>")
	)
	(segment
		(start 203.4286 -146.2278)
		(end 203.6318 -146.431)
		(width 0.14224)
		(layer "In11.Cu")
		(net "M_F_DQ<7>")
	)
	(segment
		(start 203.6318 -143.6878)
		(end 203.507848 -143.811752)
		(width 0.14224)
		(layer "In11.Cu")
		(net "M_F_DQ<7>")
	)
	(segment
		(start 206.544672 -111.687356)
		(end 206.544672 -111.888524)
		(width 0.14224)
		(layer "In11.Cu")
		(net "M_F_DQ<7>")
	)
	(segment
		(start 202.79995 -153.364946)
		(end 202.62215 -153.542746)
		(width 0.14224)
		(layer "In11.Cu")
		(net "M_F_DQ<7>")
	)
	(segment
		(start 206.205836 -110.428532)
		(end 206.004668 -110.428532)
		(width 0.14224)
		(layer "In11.Cu")
		(net "M_F_DQ<7>")
	)
	(segment
		(start 203.6318 -146.431)
		(end 203.6318 -148.3868)
		(width 0.14224)
		(layer "In11.Cu")
		(net "M_F_DQ<7>")
	)
	(segment
		(start 205.745842 -110.888526)
		(end 206.544672 -111.687356)
		(width 0.14224)
		(layer "In11.Cu")
		(net "M_F_DQ<7>")
	)
	(segment
		(start 204.825854 -111.808514)
		(end 205.624684 -112.607344)
		(width 0.14224)
		(layer "In11.Cu")
		(net "M_F_DQ<7>")
	)
	(segment
		(start 206.544672 -111.888524)
		(end 206.285846 -112.14735)
		(width 0.14224)
		(layer "In11.Cu")
		(net "M_F_DQ<7>")
	)
	(segment
		(start 215.1634 -105.3592)
		(end 213.073996 -105.3592)
		(width 0.14224)
		(layer "In11.Cu")
		(net "M_F_DQ<7>")
	)
	(segment
		(start 203.187554 -127.778256)
		(end 203.032614 -127.933196)
		(width 0.14224)
		(layer "In11.Cu")
		(net "M_F_DQ<7>")
	)
	(segment
		(start 227.7618 -91.0844)
		(end 220.1672 -98.679)
		(width 0.14224)
		(layer "In11.Cu")
		(net "M_F_DQ<7>")
	)
	(segment
		(start 207.971644 -108.740956)
		(end 207.71485 -108.99775)
		(width 0.14224)
		(layer "In11.Cu")
		(net "M_F_DQ<7>")
	)
	(segment
		(start 203.801218 -133.866382)
		(end 203.476606 -134.190994)
		(width 0.14224)
		(layer "In11.Cu")
		(net "M_F_DQ<7>")
	)
	(segment
		(start 202.511152 -152.752552)
		(end 202.79995 -153.04135)
		(width 0.14224)
		(layer "In11.Cu")
		(net "M_F_DQ<7>")
	)
	(segment
		(start 203.552552 -129.859278)
		(end 203.835 -130.141726)
		(width 0.14224)
		(layer "In11.Cu")
		(net "M_F_DQ<7>")
	)
	(segment
		(start 233.058208 -90.356436)
		(end 232.870248 -90.356436)
		(width 0.0889)
		(layer "In11.Cu")
		(net "M_F_DQ<7>")
	)
	(segment
		(start 203.6318 -136.8806)
		(end 203.6318 -138.7348)
		(width 0.14224)
		(layer "In11.Cu")
		(net "M_F_DQ<7>")
	)
	(segment
		(start 205.624684 -112.607344)
		(end 205.624684 -112.808512)
		(width 0.14224)
		(layer "In11.Cu")
		(net "M_F_DQ<7>")
	)
	(segment
		(start 203.454 -139.361926)
		(end 203.8096 -139.717526)
		(width 0.14224)
		(layer "In11.Cu")
		(net "M_F_DQ<7>")
	)
	(segment
		(start 239.904778 -86.794086)
		(end 239.37087 -86.872064)
		(width 0.0889)
		(layer "In11.Cu")
		(net "M_F_DQ<7>")
	)
	(segment
		(start 220.1672 -100.3554)
		(end 215.1634 -105.3592)
		(width 0.14224)
		(layer "In11.Cu")
		(net "M_F_DQ<7>")
	)
	(segment
		(start 205.365858 -113.067338)
		(end 205.16469 -113.067338)
		(width 0.14224)
		(layer "In11.Cu")
		(net "M_F_DQ<7>")
	)
	(segment
		(start 202.7936 -151.1046)
		(end 202.511152 -151.387048)
		(width 0.14224)
		(layer "In11.Cu")
		(net "M_F_DQ<7>")
	)
	(segment
		(start 203.8096 -140.690854)
		(end 203.449682 -141.050772)
		(width 0.14224)
		(layer "In11.Cu")
		(net "M_F_DQ<7>")
	)
	(segment
		(start 207.924654 -110.307374)
		(end 207.125824 -109.508544)
		(width 0.14224)
		(layer "In11.Cu")
		(net "M_F_DQ<7>")
	)
	(segment
		(start 208.384648 -110.048548)
		(end 208.125822 -110.307374)
		(width 0.14224)
		(layer "In11.Cu")
		(net "M_F_DQ<7>")
	)
	(segment
		(start 204.704696 -113.7285)
		(end 204.0636 -114.369596)
		(width 0.14224)
		(layer "In11.Cu")
		(net "M_F_DQ<7>")
	)
	(segment
		(start 202.7682 -152.2222)
		(end 202.511152 -152.479248)
		(width 0.14224)
		(layer "In11.Cu")
		(net "M_F_DQ<7>")
	)
	(segment
		(start 208.384648 -109.84738)
		(end 208.384648 -110.048548)
		(width 0.14224)
		(layer "In11.Cu")
		(net "M_F_DQ<7>")
	)
	(segment
		(start 203.54163 -149.191472)
		(end 203.199746 -149.533356)
		(width 0.14224)
		(layer "In11.Cu")
		(net "M_F_DQ<7>")
	)
	(segment
		(start 203.6318 -141.608048)
		(end 203.6318 -143.6878)
		(width 0.14224)
		(layer "In11.Cu")
		(net "M_F_DQ<7>")
	)
	(segment
		(start 208.198212 -108.740956)
		(end 207.971644 -108.740956)
		(width 0.14224)
		(layer "In11.Cu")
		(net "M_F_DQ<7>")
	)
	(segment
		(start 205.16469 -113.067338)
		(end 204.36586 -112.268508)
		(width 0.14224)
		(layer "In11.Cu")
		(net "M_F_DQ<7>")
	)
	(segment
		(start 209.04581 -109.387386)
		(end 208.844642 -109.387386)
		(width 0.14224)
		(layer "In11.Cu")
		(net "M_F_DQ<7>")
	)
	(segment
		(start 203.835 -135.9408)
		(end 203.4794 -136.2964)
		(width 0.14224)
		(layer "In11.Cu")
		(net "M_F_DQ<7>")
	)
	(segment
		(start 206.66583 -109.76737)
		(end 206.66583 -109.968538)
		(width 0.14224)
		(layer "In11.Cu")
		(net "M_F_DQ<7>")
	)
	(segment
		(start 239.37087 -86.872064)
		(end 239.21974 -86.88959)
		(width 0.0889)
		(layer "In11.Cu")
		(net "M_F_DQ<7>")
	)
	(segment
		(start 203.476606 -134.190994)
		(end 203.476606 -134.478522)
		(width 0.14224)
		(layer "In11.Cu")
		(net "M_F_DQ<7>")
	)
	(segment
		(start 202.62215 -153.542746)
		(end 202.349862 -153.542746)
		(width 0.14224)
		(layer "In11.Cu")
		(net "M_F_DQ<7>")
	)
	(segment
		(start 203.6318 -138.7348)
		(end 203.454 -138.9126)
		(width 0.14224)
		(layer "In11.Cu")
		(net "M_F_DQ<7>")
	)
	(segment
		(start 206.285846 -112.14735)
		(end 206.084678 -112.14735)
		(width 0.14224)
		(layer "In11.Cu")
		(net "M_F_DQ<7>")
	)
	(segment
		(start 203.4794 -136.2964)
		(end 203.4794 -136.7282)
		(width 0.14224)
		(layer "In11.Cu")
		(net "M_F_DQ<7>")
	)
	(segment
		(start 203.507848 -143.811752)
		(end 203.507848 -144.099534)
		(width 0.14224)
		(layer "In11.Cu")
		(net "M_F_DQ<7>")
	)
	(segment
		(start 203.177394 -149.533356)
		(end 202.74915 -149.9616)
		(width 0.14224)
		(layer "In11.Cu")
		(net "M_F_DQ<7>")
	)
	(segment
		(start 207.004666 -111.227362)
		(end 206.205836 -110.428532)
		(width 0.14224)
		(layer "In11.Cu")
		(net "M_F_DQ<7>")
	)
	(segment
		(start 203.905866 -112.527334)
		(end 203.905866 -112.728502)
		(width 0.14224)
		(layer "In11.Cu")
		(net "M_F_DQ<7>")
	)
	(segment
		(start 202.511152 -151.660352)
		(end 202.7682 -151.9174)
		(width 0.14224)
		(layer "In11.Cu")
		(net "M_F_DQ<7>")
	)
	(segment
		(start 207.125824 -109.508544)
		(end 206.924656 -109.508544)
		(width 0.14224)
		(layer "In11.Cu")
		(net "M_F_DQ<7>")
	)
	(segment
		(start 232.101898 -90.85199)
		(end 231.71404 -90.85199)
		(width 0.0889)
		(layer "In11.Cu")
		(net "M_F_DQ<7>")
	)
	(segment
		(start 203.865988 -126.867412)
		(end 203.865988 -127.623316)
		(width 0.14224)
		(layer "In11.Cu")
		(net "M_F_DQ<7>")
	)
	(segment
		(start 228.26472 -91.0844)
		(end 227.7618 -91.0844)
		(width 0.14224)
		(layer "In11.Cu")
		(net "M_F_DQ<7>")
	)
	(segment
		(start 203.449682 -141.050772)
		(end 203.449682 -141.42593)
		(width 0.14224)
		(layer "In11.Cu")
		(net "M_F_DQ<7>")
	)
	(segment
		(start 206.924656 -109.508544)
		(end 206.66583 -109.76737)
		(width 0.14224)
		(layer "In11.Cu")
		(net "M_F_DQ<7>")
	)
	(segment
		(start 202.511152 -151.387048)
		(end 202.511152 -151.660352)
		(width 0.14224)
		(layer "In11.Cu")
		(net "M_F_DQ<7>")
	)
	(segment
		(start 203.6318 -148.3868)
		(end 203.552552 -148.466048)
		(width 0.14224)
		(layer "In11.Cu")
		(net "M_F_DQ<7>")
	)
	(segment
		(start 203.552552 -149.191472)
		(end 203.54163 -149.191472)
		(width 0.14224)
		(layer "In11.Cu")
		(net "M_F_DQ<7>")
	)
	(segment
		(start 203.475082 -131.948682)
		(end 203.801218 -132.274818)
		(width 0.14224)
		(layer "In11.Cu")
		(net "M_F_DQ<7>")
	)
	(segment
		(start 204.0636 -114.369596)
		(end 204.0636 -126.6698)
		(width 0.14224)
		(layer "In11.Cu")
		(net "M_F_DQ<7>")
	)
	(segment
		(start 202.7936 -150.435818)
		(end 202.7936 -151.1046)
		(width 0.14224)
		(layer "In11.Cu")
		(net "M_F_DQ<7>")
	)
	(segment
		(start 203.711048 -127.778256)
		(end 203.187554 -127.778256)
		(width 0.14224)
		(layer "In11.Cu")
		(net "M_F_DQ<7>")
	)
	(segment
		(start 203.865988 -129.001012)
		(end 203.552552 -129.314448)
		(width 0.14224)
		(layer "In11.Cu")
		(net "M_F_DQ<7>")
	)
	(segment
		(start 204.0636 -126.6698)
		(end 203.865988 -126.867412)
		(width 0.14224)
		(layer "In11.Cu")
		(net "M_F_DQ<7>")
	)
	(segment
		(start 203.801218 -132.274818)
		(end 203.801218 -133.866382)
		(width 0.14224)
		(layer "In11.Cu")
		(net "M_F_DQ<7>")
	)
	(segment
		(start 203.7842 -145.567146)
		(end 203.4286 -145.922746)
		(width 0.14224)
		(layer "In11.Cu")
		(net "M_F_DQ<7>")
	)
	(segment
		(start 202.74915 -150.391368)
		(end 202.7936 -150.435818)
		(width 0.14224)
		(layer "In11.Cu")
		(net "M_F_DQ<7>")
	)
	(segment
		(start 203.552552 -129.314448)
		(end 203.552552 -129.859278)
		(width 0.14224)
		(layer "In11.Cu")
		(net "M_F_DQ<7>")
	)
	(segment
		(start 203.476606 -134.478522)
		(end 203.835 -134.836916)
		(width 0.14224)
		(layer "In11.Cu")
		(net "M_F_DQ<7>")
	)
	(segment
		(start 202.511152 -152.479248)
		(end 202.511152 -152.752552)
		(width 0.14224)
		(layer "In11.Cu")
		(net "M_F_DQ<7>")
	)
	(segment
		(start 208.125822 -110.307374)
		(end 207.924654 -110.307374)
		(width 0.14224)
		(layer "In11.Cu")
		(net "M_F_DQ<7>")
	)
	(segment
		(start 206.084678 -112.14735)
		(end 205.285848 -111.34852)
		(width 0.14224)
		(layer "In11.Cu")
		(net "M_F_DQ<7>")
	)
	(segment
		(start 204.36586 -112.268508)
		(end 204.164692 -112.268508)
		(width 0.14224)
		(layer "In11.Cu")
		(net "M_F_DQ<7>")
	)
	(segment
		(start 202.79995 -153.04135)
		(end 202.79995 -153.364946)
		(width 0.14224)
		(layer "In11.Cu")
		(net "M_F_DQ<7>")
	)
	(segment
		(start 205.745842 -110.687358)
		(end 205.745842 -110.888526)
		(width 0.14224)
		(layer "In11.Cu")
		(net "M_F_DQ<7>")
	)
	(segment
		(start 203.4286 -145.922746)
		(end 203.4286 -146.2278)
		(width 0.14224)
		(layer "In11.Cu")
		(net "M_F_DQ<7>")
	)
	(arc
		(start 234.406948 -89.565988)
		(mid 234.19834 -89.77792)
		(end 233.912918 -89.86139)
		(width 0.0889)
		(layer "In11.Cu")
		(net "M_F_DQ<7>")
	)
	(arc
		(start 238.699548 -87.089488)
		(mid 238.492544 -87.300352)
		(end 238.209328 -87.384636)
		(width 0.0889)
		(layer "In11.Cu")
		(net "M_F_DQ<7>")
	)
	(arc
		(start 233.880152 -89.86139)
		(mid 233.68851 -89.918556)
		(end 233.548428 -90.061288)
		(width 0.0889)
		(layer "In11.Cu")
		(net "M_F_DQ<7>")
	)
	(arc
		(start 236.123988 -88.575388)
		(mid 235.91538 -88.78732)
		(end 235.629958 -88.87079)
		(width 0.0889)
		(layer "In11.Cu")
		(net "M_F_DQ<7>")
	)
	(arc
		(start 234.742482 -89.365836)
		(mid 234.548632 -89.422186)
		(end 234.406948 -89.565988)
		(width 0.0889)
		(layer "In11.Cu")
		(net "M_F_DQ<7>")
	)
	(arc
		(start 236.982508 -88.080088)
		(mid 236.775504 -88.290952)
		(end 236.492288 -88.375236)
		(width 0.0889)
		(layer "In11.Cu")
		(net "M_F_DQ<7>")
	)
	(arc
		(start 232.870248 -90.356436)
		(mid 232.76696 -90.417364)
		(end 232.68432 -90.504264)
		(width 0.0889)
		(layer "In11.Cu")
		(net "M_F_DQ<7>")
	)
	(arc
		(start 237.314232 -87.88019)
		(mid 237.12259 -87.937356)
		(end 236.982508 -88.080088)
		(width 0.0889)
		(layer "In11.Cu")
		(net "M_F_DQ<7>")
	)
	(arc
		(start 233.548428 -90.061288)
		(mid 233.341424 -90.272152)
		(end 233.058208 -90.356436)
		(width 0.0889)
		(layer "In11.Cu")
		(net "M_F_DQ<7>")
	)
	(arc
		(start 238.176562 -87.384636)
		(mid 237.982712 -87.440986)
		(end 237.841028 -87.584788)
		(width 0.0889)
		(layer "In11.Cu")
		(net "M_F_DQ<7>")
	)
	(arc
		(start 237.841028 -87.584788)
		(mid 237.63242 -87.79672)
		(end 237.346998 -87.88019)
		(width 0.0889)
		(layer "In11.Cu")
		(net "M_F_DQ<7>")
	)
	(arc
		(start 232.68432 -90.504264)
		(mid 232.441056 -90.758429)
		(end 232.101898 -90.85199)
		(width 0.0889)
		(layer "In11.Cu")
		(net "M_F_DQ<7>")
	)
	(arc
		(start 235.597192 -88.87079)
		(mid 235.40555 -88.927956)
		(end 235.265468 -89.070688)
		(width 0.0889)
		(layer "In11.Cu")
		(net "M_F_DQ<7>")
	)
	(arc
		(start 236.459522 -88.375236)
		(mid 236.265672 -88.431586)
		(end 236.123988 -88.575388)
		(width 0.0889)
		(layer "In11.Cu")
		(net "M_F_DQ<7>")
	)
	(arc
		(start 235.265468 -89.070688)
		(mid 235.058464 -89.281552)
		(end 234.775248 -89.365836)
		(width 0.0889)
		(layer "In11.Cu")
		(net "M_F_DQ<7>")
	)
	(arc
		(start 239.031272 -86.88959)
		(mid 238.83963 -86.946756)
		(end 238.699548 -87.089488)
		(width 0.0889)
		(layer "In11.Cu")
		(net "M_F_DQ<7>")
	)
	(segment
		(start 203.2 -155.9052)
		(end 203.33208 -155.77312)
		(width 0.1651)
		(layer "F.Cu")
		(net "M_F_DQ<6>")
	)
	(segment
		(start 203.33208 -155.55468)
		(end 203.2 -155.4226)
		(width 0.1651)
		(layer "F.Cu")
		(net "M_F_DQ<6>")
	)
	(segment
		(start 203.200508 -156.87294)
		(end 203.2 -156.87294)
		(width 0.1651)
		(layer "F.Cu")
		(net "M_F_DQ<6>")
	)
	(segment
		(start 203.2 -156.87294)
		(end 203.2 -155.9052)
		(width 0.1651)
		(layer "F.Cu")
		(net "M_F_DQ<6>")
	)
	(segment
		(start 203.2 -155.118054)
		(end 203.199746 -155.1178)
		(width 0.1651)
		(layer "F.Cu")
		(net "M_F_DQ<6>")
	)
	(segment
		(start 203.33208 -155.77312)
		(end 203.33208 -155.55468)
		(width 0.1651)
		(layer "F.Cu")
		(net "M_F_DQ<6>")
	)
	(segment
		(start 242.193318 -87.784686)
		(end 241.621818 -87.784686)
		(width 0.1651)
		(layer "F.Cu")
		(net "M_F_DQ<6>")
	)
	(segment
		(start 203.2 -155.4226)
		(end 203.2 -155.118054)
		(width 0.1651)
		(layer "F.Cu")
		(net "M_F_DQ<6>")
	)
	(via
		(at 203.199746 -155.1178)
		(size 0.508)
		(drill 0.254)
		(layers "F.Cu" "B.Cu")
		(net "M_F_DQ<6>")
	)
	(via
		(at 202.349862 -150.814278)
		(size 0.508)
		(drill 0.254)
		(layers "F.Cu" "B.Cu")
		(net "M_F_DQ<6>")
	)
	(via
		(at 241.621818 -87.784686)
		(size 0.508)
		(drill 0.254)
		(layers "F.Cu" "B.Cu")
		(net "M_F_DQ<6>")
	)
	(segment
		(start 202.35037 -152.078436)
		(end 202.349862 -152.078182)
		(width 0.1651)
		(layer "B.Cu")
		(net "M_F_DQ<6>")
	)
	(segment
		(start 202.349862 -152.078182)
		(end 202.349862 -150.814278)
		(width 0.1651)
		(layer "B.Cu")
		(net "M_F_DQ<6>")
	)
	(segment
		(start 209.716116 -105.699052)
		(end 209.514948 -105.699052)
		(width 0.14224)
		(layer "In11.Cu")
		(net "M_F_DQ<6>")
	)
	(segment
		(start 206.8576 -108.3564)
		(end 206.8576 -108.8644)
		(width 0.14224)
		(layer "In11.Cu")
		(net "M_F_DQ<6>")
	)
	(segment
		(start 208.59496 -106.61904)
		(end 206.8576 -108.3564)
		(width 0.14224)
		(layer "In11.Cu")
		(net "M_F_DQ<6>")
	)
	(segment
		(start 202.917552 -145.857468)
		(end 202.917552 -146.177)
		(width 0.14224)
		(layer "In11.Cu")
		(net "M_F_DQ<6>")
	)
	(segment
		(start 202.917552 -146.177)
		(end 202.7682 -146.326352)
		(width 0.14224)
		(layer "In11.Cu")
		(net "M_F_DQ<6>")
	)
	(segment
		(start 236.452918 -88.184736)
		(end 236.485684 -88.184736)
		(width 0.0889)
		(layer "In11.Cu")
		(net "M_F_DQ<6>")
	)
	(segment
		(start 202.180952 -149.671278)
		(end 202.180952 -150.645368)
		(width 0.14224)
		(layer "In11.Cu")
		(net "M_F_DQ<6>")
	)
	(segment
		(start 202.7682 -132.026152)
		(end 202.7682 -134.0358)
		(width 0.14224)
		(layer "In11.Cu")
		(net "M_F_DQ<6>")
	)
	(segment
		(start 228.36251 -90.356944)
		(end 227.778056 -90.356944)
		(width 0.14224)
		(layer "In11.Cu")
		(net "M_F_DQ<6>")
	)
	(segment
		(start 202.349862 -150.814278)
		(end 201.916792 -151.247348)
		(width 0.14224)
		(layer "In11.Cu")
		(net "M_F_DQ<6>")
	)
	(segment
		(start 209.85226 -107.675172)
		(end 208.796128 -106.61904)
		(width 0.14224)
		(layer "In11.Cu")
		(net "M_F_DQ<6>")
	)
	(segment
		(start 202.7682 -148.3106)
		(end 202.9968 -148.5392)
		(width 0.14224)
		(layer "In11.Cu")
		(net "M_F_DQ<6>")
	)
	(segment
		(start 202.5142 -145.454116)
		(end 202.917552 -145.857468)
		(width 0.14224)
		(layer "In11.Cu")
		(net "M_F_DQ<6>")
	)
	(segment
		(start 210.312254 -107.215178)
		(end 210.312254 -107.416346)
		(width 0.14224)
		(layer "In11.Cu")
		(net "M_F_DQ<6>")
	)
	(segment
		(start 202.920346 -134.187946)
		(end 202.920346 -134.475474)
		(width 0.14224)
		(layer "In11.Cu")
		(net "M_F_DQ<6>")
	)
	(segment
		(start 202.9714 -129.4638)
		(end 202.9714 -129.692654)
		(width 0.14224)
		(layer "In11.Cu")
		(net "M_F_DQ<6>")
	)
	(segment
		(start 201.916792 -153.834846)
		(end 203.199746 -155.1178)
		(width 0.14224)
		(layer "In11.Cu")
		(net "M_F_DQ<6>")
	)
	(segment
		(start 219.4306 -100.193856)
		(end 214.773256 -104.8512)
		(width 0.14224)
		(layer "In11.Cu")
		(net "M_F_DQ<6>")
	)
	(segment
		(start 208.796128 -106.61904)
		(end 208.59496 -106.61904)
		(width 0.14224)
		(layer "In11.Cu")
		(net "M_F_DQ<6>")
	)
	(segment
		(start 202.6158 -139.76223)
		(end 202.6158 -140.690854)
		(width 0.14224)
		(layer "In11.Cu")
		(net "M_F_DQ<6>")
	)
	(segment
		(start 202.565 -130.099054)
		(end 202.565 -131.064254)
		(width 0.14224)
		(layer "In11.Cu")
		(net "M_F_DQ<6>")
	)
	(segment
		(start 237.307628 -87.68969)
		(end 237.340394 -87.68969)
		(width 0.0889)
		(layer "In11.Cu")
		(net "M_F_DQ<6>")
	)
	(segment
		(start 202.7682 -143.637)
		(end 202.914504 -143.783304)
		(width 0.14224)
		(layer "In11.Cu")
		(net "M_F_DQ<6>")
	)
	(segment
		(start 232.101898 -90.66149)
		(end 231.792272 -90.66149)
		(width 0.0889)
		(layer "In11.Cu")
		(net "M_F_DQ<6>")
	)
	(segment
		(start 232.833926 -90.165936)
		(end 233.051604 -90.165936)
		(width 0.0889)
		(layer "In11.Cu")
		(net "M_F_DQ<6>")
	)
	(segment
		(start 203.4286 -112.2934)
		(end 203.4286 -123.851416)
		(width 0.14224)
		(layer "In11.Cu")
		(net "M_F_DQ<6>")
	)
	(segment
		(start 201.916792 -151.247348)
		(end 201.916792 -153.834846)
		(width 0.14224)
		(layer "In11.Cu")
		(net "M_F_DQ<6>")
	)
	(segment
		(start 210.973416 -106.755184)
		(end 210.772248 -106.755184)
		(width 0.14224)
		(layer "In11.Cu")
		(net "M_F_DQ<6>")
	)
	(segment
		(start 203.4286 -126.3396)
		(end 202.5396 -127.2286)
		(width 0.14224)
		(layer "In11.Cu")
		(net "M_F_DQ<6>")
	)
	(segment
		(start 203.4286 -124.9426)
		(end 203.4286 -126.3396)
		(width 0.14224)
		(layer "In11.Cu")
		(net "M_F_DQ<6>")
	)
	(segment
		(start 228.59238 -90.586814)
		(end 228.36251 -90.356944)
		(width 0.0889)
		(layer "In11.Cu")
		(net "M_F_DQ<6>")
	)
	(segment
		(start 241.275108 -86.994238)
		(end 241.291872 -87.02294)
		(width 0.0889)
		(layer "In11.Cu")
		(net "M_F_DQ<6>")
	)
	(segment
		(start 202.7682 -141.576552)
		(end 202.7682 -143.637)
		(width 0.14224)
		(layer "In11.Cu")
		(net "M_F_DQ<6>")
	)
	(segment
		(start 241.291872 -87.02294)
		(end 241.621818 -87.784686)
		(width 0.0889)
		(layer "In11.Cu")
		(net "M_F_DQ<6>")
	)
	(segment
		(start 210.053428 -107.675172)
		(end 209.85226 -107.675172)
		(width 0.14224)
		(layer "In11.Cu")
		(net "M_F_DQ<6>")
	)
	(segment
		(start 202.7682 -138.7348)
		(end 202.917552 -138.884152)
		(width 0.14224)
		(layer "In11.Cu")
		(net "M_F_DQ<6>")
	)
	(segment
		(start 202.956922 -131.83743)
		(end 202.7682 -132.026152)
		(width 0.14224)
		(layer "In11.Cu")
		(net "M_F_DQ<6>")
	)
	(segment
		(start 239.024668 -86.69909)
		(end 239.198404 -86.69909)
		(width 0.0889)
		(layer "In11.Cu")
		(net "M_F_DQ<6>")
	)
	(segment
		(start 210.312254 -107.416346)
		(end 210.053428 -107.675172)
		(width 0.14224)
		(layer "In11.Cu")
		(net "M_F_DQ<6>")
	)
	(segment
		(start 209.256122 -105.957878)
		(end 209.256122 -106.159046)
		(width 0.14224)
		(layer "In11.Cu")
		(net "M_F_DQ<6>")
	)
	(segment
		(start 234.735878 -89.175336)
		(end 234.768644 -89.175336)
		(width 0.0889)
		(layer "In11.Cu")
		(net "M_F_DQ<6>")
	)
	(segment
		(start 206.8576 -108.8644)
		(end 203.4286 -112.2934)
		(width 0.14224)
		(layer "In11.Cu")
		(net "M_F_DQ<6>")
	)
	(segment
		(start 235.590588 -88.68029)
		(end 235.623354 -88.68029)
		(width 0.0889)
		(layer "In11.Cu")
		(net "M_F_DQ<6>")
	)
	(segment
		(start 210.3628 -104.8512)
		(end 210.17611 -105.03789)
		(width 0.14224)
		(layer "In11.Cu")
		(net "M_F_DQ<6>")
	)
	(segment
		(start 210.17611 -105.03789)
		(end 210.17611 -105.239058)
		(width 0.14224)
		(layer "In11.Cu")
		(net "M_F_DQ<6>")
	)
	(segment
		(start 202.917552 -139.460478)
		(end 202.6158 -139.76223)
		(width 0.14224)
		(layer "In11.Cu")
		(net "M_F_DQ<6>")
	)
	(segment
		(start 202.180952 -150.645368)
		(end 202.349862 -150.814278)
		(width 0.14224)
		(layer "In11.Cu")
		(net "M_F_DQ<6>")
	)
	(segment
		(start 202.914504 -144.071086)
		(end 202.5142 -144.47139)
		(width 0.14224)
		(layer "In11.Cu")
		(net "M_F_DQ<6>")
	)
	(segment
		(start 202.956922 -131.456176)
		(end 202.956922 -131.83743)
		(width 0.14224)
		(layer "In11.Cu")
		(net "M_F_DQ<6>")
	)
	(segment
		(start 202.7682 -136.9568)
		(end 202.7682 -138.7348)
		(width 0.14224)
		(layer "In11.Cu")
		(net "M_F_DQ<6>")
	)
	(segment
		(start 231.717596 -90.586814)
		(end 228.59238 -90.586814)
		(width 0.0889)
		(layer "In11.Cu")
		(net "M_F_DQ<6>")
	)
	(segment
		(start 202.5396 -129.032)
		(end 202.9714 -129.4638)
		(width 0.14224)
		(layer "In11.Cu")
		(net "M_F_DQ<6>")
	)
	(segment
		(start 211.232242 -106.496358)
		(end 210.973416 -106.755184)
		(width 0.14224)
		(layer "In11.Cu")
		(net "M_F_DQ<6>")
	)
	(segment
		(start 202.984354 -136.360154)
		(end 202.984354 -136.740646)
		(width 0.14224)
		(layer "In11.Cu")
		(net "M_F_DQ<6>")
	)
	(segment
		(start 202.5396 -127.2286)
		(end 202.5396 -129.032)
		(width 0.14224)
		(layer "In11.Cu")
		(net "M_F_DQ<6>")
	)
	(segment
		(start 202.6158 -140.690854)
		(end 202.931522 -141.006576)
		(width 0.14224)
		(layer "In11.Cu")
		(net "M_F_DQ<6>")
	)
	(segment
		(start 202.917552 -138.884152)
		(end 202.917552 -139.460478)
		(width 0.14224)
		(layer "In11.Cu")
		(net "M_F_DQ<6>")
	)
	(segment
		(start 202.931522 -141.006576)
		(end 202.931522 -141.41323)
		(width 0.14224)
		(layer "In11.Cu")
		(net "M_F_DQ<6>")
	)
	(segment
		(start 203.073 -124.207016)
		(end 203.073 -124.587)
		(width 0.14224)
		(layer "In11.Cu")
		(net "M_F_DQ<6>")
	)
	(segment
		(start 214.773256 -104.8512)
		(end 210.3628 -104.8512)
		(width 0.14224)
		(layer "In11.Cu")
		(net "M_F_DQ<6>")
	)
	(segment
		(start 202.5904 -134.80542)
		(end 202.5904 -135.9662)
		(width 0.14224)
		(layer "In11.Cu")
		(net "M_F_DQ<6>")
	)
	(segment
		(start 227.778056 -90.356944)
		(end 219.4306 -98.7044)
		(width 0.14224)
		(layer "In11.Cu")
		(net "M_F_DQ<6>")
	)
	(segment
		(start 203.073 -124.587)
		(end 203.4286 -124.9426)
		(width 0.14224)
		(layer "In11.Cu")
		(net "M_F_DQ<6>")
	)
	(segment
		(start 219.4306 -98.7044)
		(end 219.4306 -100.193856)
		(width 0.14224)
		(layer "In11.Cu")
		(net "M_F_DQ<6>")
	)
	(segment
		(start 202.9968 -148.5392)
		(end 202.9968 -148.85543)
		(width 0.14224)
		(layer "In11.Cu")
		(net "M_F_DQ<6>")
	)
	(segment
		(start 203.4286 -123.851416)
		(end 203.073 -124.207016)
		(width 0.14224)
		(layer "In11.Cu")
		(net "M_F_DQ<6>")
	)
	(segment
		(start 211.232242 -106.29519)
		(end 211.232242 -106.496358)
		(width 0.14224)
		(layer "In11.Cu")
		(net "M_F_DQ<6>")
	)
	(segment
		(start 202.565 -131.064254)
		(end 202.956922 -131.456176)
		(width 0.14224)
		(layer "In11.Cu")
		(net "M_F_DQ<6>")
	)
	(segment
		(start 202.9714 -129.692654)
		(end 202.565 -130.099054)
		(width 0.14224)
		(layer "In11.Cu")
		(net "M_F_DQ<6>")
	)
	(segment
		(start 202.920346 -134.475474)
		(end 202.5904 -134.80542)
		(width 0.14224)
		(layer "In11.Cu")
		(net "M_F_DQ<6>")
	)
	(segment
		(start 210.17611 -105.239058)
		(end 211.232242 -106.29519)
		(width 0.14224)
		(layer "In11.Cu")
		(net "M_F_DQ<6>")
	)
	(segment
		(start 209.514948 -105.699052)
		(end 209.256122 -105.957878)
		(width 0.14224)
		(layer "In11.Cu")
		(net "M_F_DQ<6>")
	)
	(segment
		(start 210.772248 -106.755184)
		(end 209.716116 -105.699052)
		(width 0.14224)
		(layer "In11.Cu")
		(net "M_F_DQ<6>")
	)
	(segment
		(start 231.792272 -90.66149)
		(end 231.717596 -90.586814)
		(width 0.0889)
		(layer "In11.Cu")
		(net "M_F_DQ<6>")
	)
	(segment
		(start 233.873548 -89.67089)
		(end 233.906314 -89.67089)
		(width 0.0889)
		(layer "In11.Cu")
		(net "M_F_DQ<6>")
	)
	(segment
		(start 202.9968 -148.85543)
		(end 202.180952 -149.671278)
		(width 0.14224)
		(layer "In11.Cu")
		(net "M_F_DQ<6>")
	)
	(segment
		(start 239.904016 -86.39429)
		(end 239.90554 -86.39429)
		(width 0.0889)
		(layer "In11.Cu")
		(net "M_F_DQ<6>")
	)
	(segment
		(start 238.169958 -87.194136)
		(end 238.202724 -87.194136)
		(width 0.0889)
		(layer "In11.Cu")
		(net "M_F_DQ<6>")
	)
	(segment
		(start 202.5904 -135.9662)
		(end 202.984354 -136.360154)
		(width 0.14224)
		(layer "In11.Cu")
		(net "M_F_DQ<6>")
	)
	(segment
		(start 202.7682 -134.0358)
		(end 202.920346 -134.187946)
		(width 0.14224)
		(layer "In11.Cu")
		(net "M_F_DQ<6>")
	)
	(segment
		(start 240.433098 -86.69909)
		(end 240.784888 -86.69909)
		(width 0.0889)
		(layer "In11.Cu")
		(net "M_F_DQ<6>")
	)
	(segment
		(start 239.198404 -86.69909)
		(end 239.665764 -86.473284)
		(width 0.0889)
		(layer "In11.Cu")
		(net "M_F_DQ<6>")
	)
	(segment
		(start 202.5142 -144.47139)
		(end 202.5142 -145.454116)
		(width 0.14224)
		(layer "In11.Cu")
		(net "M_F_DQ<6>")
	)
	(segment
		(start 202.931522 -141.41323)
		(end 202.7682 -141.576552)
		(width 0.14224)
		(layer "In11.Cu")
		(net "M_F_DQ<6>")
	)
	(segment
		(start 202.914504 -143.783304)
		(end 202.914504 -144.071086)
		(width 0.14224)
		(layer "In11.Cu")
		(net "M_F_DQ<6>")
	)
	(segment
		(start 209.256122 -106.159046)
		(end 210.312254 -107.215178)
		(width 0.14224)
		(layer "In11.Cu")
		(net "M_F_DQ<6>")
	)
	(segment
		(start 202.7682 -146.326352)
		(end 202.7682 -148.3106)
		(width 0.14224)
		(layer "In11.Cu")
		(net "M_F_DQ<6>")
	)
	(segment
		(start 202.984354 -136.740646)
		(end 202.7682 -136.9568)
		(width 0.14224)
		(layer "In11.Cu")
		(net "M_F_DQ<6>")
	)
	(arc
		(start 236.817408 -87.984838)
		(mid 237.024412 -87.773974)
		(end 237.307628 -87.68969)
		(width 0.0889)
		(layer "In11.Cu")
		(net "M_F_DQ<6>")
	)
	(arc
		(start 238.534448 -86.994238)
		(mid 238.741452 -86.783374)
		(end 239.024668 -86.69909)
		(width 0.0889)
		(layer "In11.Cu")
		(net "M_F_DQ<6>")
	)
	(arc
		(start 237.340394 -87.68969)
		(mid 237.534244 -87.63334)
		(end 237.675928 -87.489538)
		(width 0.0889)
		(layer "In11.Cu")
		(net "M_F_DQ<6>")
	)
	(arc
		(start 240.784888 -86.69909)
		(mid 241.068105 -86.783371)
		(end 241.275108 -86.994238)
		(width 0.0889)
		(layer "In11.Cu")
		(net "M_F_DQ<6>")
	)
	(arc
		(start 233.906314 -89.67089)
		(mid 234.100164 -89.61454)
		(end 234.241848 -89.470738)
		(width 0.0889)
		(layer "In11.Cu")
		(net "M_F_DQ<6>")
	)
	(arc
		(start 234.768644 -89.175336)
		(mid 234.960286 -89.11817)
		(end 235.100368 -88.975438)
		(width 0.0889)
		(layer "In11.Cu")
		(net "M_F_DQ<6>")
	)
	(arc
		(start 235.623354 -88.68029)
		(mid 235.817204 -88.62394)
		(end 235.958888 -88.480138)
		(width 0.0889)
		(layer "In11.Cu")
		(net "M_F_DQ<6>")
	)
	(arc
		(start 232.48493 -90.464132)
		(mid 232.317338 -90.609239)
		(end 232.101898 -90.66149)
		(width 0.0889)
		(layer "In11.Cu")
		(net "M_F_DQ<6>")
	)
	(arc
		(start 232.833926 -90.165936)
		(mid 232.631028 -90.281796)
		(end 232.48493 -90.464132)
		(width 0.0889)
		(layer "In11.Cu")
		(net "M_F_DQ<6>")
	)
	(arc
		(start 235.958888 -88.480138)
		(mid 236.167496 -88.268206)
		(end 236.452918 -88.184736)
		(width 0.0889)
		(layer "In11.Cu")
		(net "M_F_DQ<6>")
	)
	(arc
		(start 239.90554 -86.39429)
		(mid 240.105313 -86.447859)
		(end 240.251488 -86.594188)
		(width 0.0889)
		(layer "In11.Cu")
		(net "M_F_DQ<6>")
	)
	(arc
		(start 239.665764 -86.473284)
		(mid 239.778517 -86.414553)
		(end 239.904016 -86.39429)
		(width 0.0889)
		(layer "In11.Cu")
		(net "M_F_DQ<6>")
	)
	(arc
		(start 233.051604 -90.165936)
		(mid 233.243246 -90.10877)
		(end 233.383328 -89.966038)
		(width 0.0889)
		(layer "In11.Cu")
		(net "M_F_DQ<6>")
	)
	(arc
		(start 233.383328 -89.966038)
		(mid 233.590332 -89.755174)
		(end 233.873548 -89.67089)
		(width 0.0889)
		(layer "In11.Cu")
		(net "M_F_DQ<6>")
	)
	(arc
		(start 234.241848 -89.470738)
		(mid 234.450456 -89.258806)
		(end 234.735878 -89.175336)
		(width 0.0889)
		(layer "In11.Cu")
		(net "M_F_DQ<6>")
	)
	(arc
		(start 235.100368 -88.975438)
		(mid 235.307372 -88.764574)
		(end 235.590588 -88.68029)
		(width 0.0889)
		(layer "In11.Cu")
		(net "M_F_DQ<6>")
	)
	(arc
		(start 238.202724 -87.194136)
		(mid 238.394366 -87.13697)
		(end 238.534448 -86.994238)
		(width 0.0889)
		(layer "In11.Cu")
		(net "M_F_DQ<6>")
	)
	(arc
		(start 236.485684 -88.184736)
		(mid 236.677326 -88.12757)
		(end 236.817408 -87.984838)
		(width 0.0889)
		(layer "In11.Cu")
		(net "M_F_DQ<6>")
	)
	(arc
		(start 240.251488 -86.594188)
		(mid 240.32822 -86.671017)
		(end 240.433098 -86.69909)
		(width 0.0889)
		(layer "In11.Cu")
		(net "M_F_DQ<6>")
	)
	(arc
		(start 237.675928 -87.489538)
		(mid 237.884536 -87.277606)
		(end 238.169958 -87.194136)
		(width 0.0889)
		(layer "In11.Cu")
		(net "M_F_DQ<6>")
	)
	(segment
		(start 313.700414 -152.273)
		(end 313.699906 -152.278842)
		(width 0.1651)
		(layer "F.Cu")
		(net "M_F_DQ<63>")
	)
	(segment
		(start 284.071314 -92.061538)
		(end 284.642814 -92.061538)
		(width 0.1651)
		(layer "F.Cu")
		(net "M_F_DQ<63>")
	)
	(segment
		(start 313.699906 -152.278842)
		(end 313.699906 -153.542746)
		(width 0.1651)
		(layer "F.Cu")
		(net "M_F_DQ<63>")
	)
	(via
		(at 313.699906 -153.542746)
		(size 0.508)
		(drill 0.254)
		(layers "F.Cu" "B.Cu")
		(net "M_F_DQ<63>")
	)
	(via
		(at 314.54979 -149.533356)
		(size 0.508)
		(drill 0.254)
		(layers "F.Cu" "B.Cu")
		(net "M_F_DQ<63>")
	)
	(via
		(at 284.642814 -92.061538)
		(size 0.508)
		(drill 0.254)
		(layers "F.Cu" "B.Cu")
		(net "M_F_DQ<63>")
	)
	(segment
		(start 314.550298 -149.532848)
		(end 314.54979 -149.533356)
		(width 0.1651)
		(layer "B.Cu")
		(net "M_F_DQ<63>")
	)
	(segment
		(start 314.550298 -147.478496)
		(end 314.550298 -149.532848)
		(width 0.1651)
		(layer "B.Cu")
		(net "M_F_DQ<63>")
	)
	(segment
		(start 315.154564 -129.084832)
		(end 314.902596 -129.3368)
		(width 0.14224)
		(layer "In11.Cu")
		(net "M_F_DQ<63>")
	)
	(segment
		(start 290.637214 -101.872034)
		(end 290.67379 -101.872034)
		(width 0.0889)
		(layer "In11.Cu")
		(net "M_F_DQ<63>")
	)
	(segment
		(start 314.9854 -131.959604)
		(end 314.9854 -134.0358)
		(width 0.14224)
		(layer "In11.Cu")
		(net "M_F_DQ<63>")
	)
	(segment
		(start 314.149994 -153.04135)
		(end 314.149994 -153.364946)
		(width 0.14224)
		(layer "In11.Cu")
		(net "M_F_DQ<63>")
	)
	(segment
		(start 314.118244 -152.2222)
		(end 313.861196 -152.479248)
		(width 0.14224)
		(layer "In11.Cu")
		(net "M_F_DQ<63>")
	)
	(segment
		(start 291.407342 -102.353872)
		(end 291.407088 -102.353872)
		(width 0.0889)
		(layer "In11.Cu")
		(net "M_F_DQ<63>")
	)
	(segment
		(start 290.30549 -96.71939)
		(end 290.31184 -96.730058)
		(width 0.0889)
		(layer "In11.Cu")
		(net "M_F_DQ<63>")
	)
	(segment
		(start 314.485782 -126.998476)
		(end 315.148722 -126.998476)
		(width 0.14224)
		(layer "In11.Cu")
		(net "M_F_DQ<63>")
	)
	(segment
		(start 314.470796 -125.019054)
		(end 315.154564 -125.702822)
		(width 0.14224)
		(layer "In11.Cu")
		(net "M_F_DQ<63>")
	)
	(segment
		(start 315.154564 -126.030736)
		(end 314.999624 -126.185676)
		(width 0.14224)
		(layer "In11.Cu")
		(net "M_F_DQ<63>")
	)
	(segment
		(start 314.902596 -148.418804)
		(end 314.902596 -149.191472)
		(width 0.14224)
		(layer "In11.Cu")
		(net "M_F_DQ<63>")
	)
	(segment
		(start 315.07176 -145.659094)
		(end 314.902596 -145.828258)
		(width 0.14224)
		(layer "In11.Cu")
		(net "M_F_DQ<63>")
	)
	(segment
		(start 314.099194 -150.391368)
		(end 314.143644 -150.435818)
		(width 0.14224)
		(layer "In11.Cu")
		(net "M_F_DQ<63>")
	)
	(segment
		(start 314.143644 -151.1046)
		(end 313.861196 -151.387048)
		(width 0.14224)
		(layer "In11.Cu")
		(net "M_F_DQ<63>")
	)
	(segment
		(start 315.148722 -127.811276)
		(end 314.49264 -127.811276)
		(width 0.14224)
		(layer "In11.Cu")
		(net "M_F_DQ<63>")
	)
	(segment
		(start 314.902596 -145.828258)
		(end 314.902596 -146.177)
		(width 0.14224)
		(layer "In11.Cu")
		(net "M_F_DQ<63>")
	)
	(segment
		(start 291.495988 -102.367334)
		(end 291.570918 -102.370128)
		(width 0.0889)
		(layer "In11.Cu")
		(net "M_F_DQ<63>")
	)
	(segment
		(start 284.642814 -92.061538)
		(end 285.13786 -92.727272)
		(width 0.0889)
		(layer "In11.Cu")
		(net "M_F_DQ<63>")
	)
	(segment
		(start 314.927996 -134.579868)
		(end 315.105796 -134.757668)
		(width 0.14224)
		(layer "In11.Cu")
		(net "M_F_DQ<63>")
	)
	(segment
		(start 293.543228 -103.827072)
		(end 299.64888 -109.932724)
		(width 0.14224)
		(layer "In11.Cu")
		(net "M_F_DQ<63>")
	)
	(segment
		(start 314.49264 -127.811276)
		(end 314.351924 -127.951992)
		(width 0.14224)
		(layer "In11.Cu")
		(net "M_F_DQ<63>")
	)
	(segment
		(start 315.131196 -139.689078)
		(end 315.131196 -140.69695)
		(width 0.14224)
		(layer "In11.Cu")
		(net "M_F_DQ<63>")
	)
	(segment
		(start 315.148722 -126.998476)
		(end 315.303662 -127.153416)
		(width 0.14224)
		(layer "In11.Cu")
		(net "M_F_DQ<63>")
	)
	(segment
		(start 314.999624 -126.185676)
		(end 314.485782 -126.185676)
		(width 0.14224)
		(layer "In11.Cu")
		(net "M_F_DQ<63>")
	)
	(segment
		(start 315.131196 -140.69695)
		(end 314.8076 -141.020546)
		(width 0.14224)
		(layer "In11.Cu")
		(net "M_F_DQ<63>")
	)
	(segment
		(start 291.868606 -103.683816)
		(end 291.961062 -103.776272)
		(width 0.0889)
		(layer "In11.Cu")
		(net "M_F_DQ<63>")
	)
	(segment
		(start 315.105796 -134.757668)
		(end 315.105796 -135.972042)
		(width 0.14224)
		(layer "In11.Cu")
		(net "M_F_DQ<63>")
	)
	(segment
		(start 314.527438 -149.533356)
		(end 314.099194 -149.9616)
		(width 0.14224)
		(layer "In11.Cu")
		(net "M_F_DQ<63>")
	)
	(segment
		(start 314.9854 -146.259804)
		(end 314.9854 -148.336)
		(width 0.14224)
		(layer "In11.Cu")
		(net "M_F_DQ<63>")
	)
	(segment
		(start 314.8076 -141.020546)
		(end 314.8076 -141.535404)
		(width 0.14224)
		(layer "In11.Cu")
		(net "M_F_DQ<63>")
	)
	(segment
		(start 285.486348 -92.956634)
		(end 285.519114 -92.956634)
		(width 0.0889)
		(layer "In11.Cu")
		(net "M_F_DQ<63>")
	)
	(segment
		(start 292.286436 -103.776272)
		(end 292.337236 -103.827072)
		(width 0.14224)
		(layer "In11.Cu")
		(net "M_F_DQ<63>")
	)
	(segment
		(start 314.118244 -151.9174)
		(end 314.118244 -152.2222)
		(width 0.14224)
		(layer "In11.Cu")
		(net "M_F_DQ<63>")
	)
	(segment
		(start 315.07176 -144.313402)
		(end 315.07176 -145.659094)
		(width 0.14224)
		(layer "In11.Cu")
		(net "M_F_DQ<63>")
	)
	(segment
		(start 285.13786 -92.727272)
		(end 285.154624 -92.756736)
		(width 0.0889)
		(layer "In11.Cu")
		(net "M_F_DQ<63>")
	)
	(segment
		(start 313.861196 -152.479248)
		(end 313.861196 -152.752552)
		(width 0.14224)
		(layer "In11.Cu")
		(net "M_F_DQ<63>")
	)
	(segment
		(start 314.470796 -122.9233)
		(end 314.470796 -125.019054)
		(width 0.14224)
		(layer "In11.Cu")
		(net "M_F_DQ<63>")
	)
	(segment
		(start 290.30549 -98.300286)
		(end 290.300664 -98.308922)
		(width 0.0889)
		(layer "In11.Cu")
		(net "M_F_DQ<63>")
	)
	(segment
		(start 314.927996 -143.669004)
		(end 314.927996 -144.169638)
		(width 0.14224)
		(layer "In11.Cu")
		(net "M_F_DQ<63>")
	)
	(segment
		(start 314.351924 -127.951992)
		(end 314.351924 -128.454912)
		(width 0.14224)
		(layer "In11.Cu")
		(net "M_F_DQ<63>")
	)
	(segment
		(start 286.013144 -93.252036)
		(end 286.016446 -93.257878)
		(width 0.0889)
		(layer "In11.Cu")
		(net "M_F_DQ<63>")
	)
	(segment
		(start 314.902596 -149.191472)
		(end 314.891674 -149.191472)
		(width 0.14224)
		(layer "In11.Cu")
		(net "M_F_DQ<63>")
	)
	(segment
		(start 314.902596 -129.3368)
		(end 314.902596 -129.859278)
		(width 0.14224)
		(layer "In11.Cu")
		(net "M_F_DQ<63>")
	)
	(segment
		(start 299.64888 -109.932724)
		(end 301.48022 -109.932724)
		(width 0.14224)
		(layer "In11.Cu")
		(net "M_F_DQ<63>")
	)
	(segment
		(start 314.485782 -126.185676)
		(end 314.330842 -126.340616)
		(width 0.14224)
		(layer "In11.Cu")
		(net "M_F_DQ<63>")
	)
	(segment
		(start 291.868606 -102.667816)
		(end 291.868606 -103.683816)
		(width 0.0889)
		(layer "In11.Cu")
		(net "M_F_DQ<63>")
	)
	(segment
		(start 314.351924 -128.454912)
		(end 314.521088 -128.624076)
		(width 0.14224)
		(layer "In11.Cu")
		(net "M_F_DQ<63>")
	)
	(segment
		(start 290.300664 -96.710754)
		(end 290.30549 -96.71939)
		(width 0.0889)
		(layer "In11.Cu")
		(net "M_F_DQ<63>")
	)
	(segment
		(start 314.330842 -126.340616)
		(end 314.330842 -126.843536)
		(width 0.14224)
		(layer "In11.Cu")
		(net "M_F_DQ<63>")
	)
	(segment
		(start 314.8076 -141.535404)
		(end 314.9854 -141.713204)
		(width 0.14224)
		(layer "In11.Cu")
		(net "M_F_DQ<63>")
	)
	(segment
		(start 290.31184 -99.280218)
		(end 290.30549 -99.290886)
		(width 0.0889)
		(layer "In11.Cu")
		(net "M_F_DQ<63>")
	)
	(segment
		(start 292.337236 -103.827072)
		(end 293.543228 -103.827072)
		(width 0.14224)
		(layer "In11.Cu")
		(net "M_F_DQ<63>")
	)
	(segment
		(start 314.9854 -134.0358)
		(end 314.927996 -134.093204)
		(width 0.14224)
		(layer "In11.Cu")
		(net "M_F_DQ<63>")
	)
	(segment
		(start 314.902596 -129.859278)
		(end 315.131196 -130.087878)
		(width 0.14224)
		(layer "In11.Cu")
		(net "M_F_DQ<63>")
	)
	(segment
		(start 314.927996 -144.169638)
		(end 315.07176 -144.313402)
		(width 0.14224)
		(layer "In11.Cu")
		(net "M_F_DQ<63>")
	)
	(segment
		(start 291.961062 -103.776272)
		(end 292.286436 -103.776272)
		(width 0.0889)
		(layer "In11.Cu")
		(net "M_F_DQ<63>")
	)
	(segment
		(start 314.891674 -149.191472)
		(end 314.54979 -149.533356)
		(width 0.14224)
		(layer "In11.Cu")
		(net "M_F_DQ<63>")
	)
	(segment
		(start 286.3596 -93.452188)
		(end 286.38119 -93.452188)
		(width 0.0889)
		(layer "In11.Cu")
		(net "M_F_DQ<63>")
	)
	(segment
		(start 314.927996 -134.093204)
		(end 314.927996 -134.579868)
		(width 0.14224)
		(layer "In11.Cu")
		(net "M_F_DQ<63>")
	)
	(segment
		(start 315.154564 -128.779016)
		(end 315.154564 -129.084832)
		(width 0.14224)
		(layer "In11.Cu")
		(net "M_F_DQ<63>")
	)
	(segment
		(start 314.8076 -139.365482)
		(end 315.131196 -139.689078)
		(width 0.14224)
		(layer "In11.Cu")
		(net "M_F_DQ<63>")
	)
	(segment
		(start 314.9854 -138.7602)
		(end 314.8076 -138.938)
		(width 0.14224)
		(layer "In11.Cu")
		(net "M_F_DQ<63>")
	)
	(segment
		(start 314.902596 -146.177)
		(end 314.9854 -146.259804)
		(width 0.14224)
		(layer "In11.Cu")
		(net "M_F_DQ<63>")
	)
	(segment
		(start 315.154564 -125.702822)
		(end 315.154564 -126.030736)
		(width 0.14224)
		(layer "In11.Cu")
		(net "M_F_DQ<63>")
	)
	(segment
		(start 314.999624 -128.624076)
		(end 315.154564 -128.779016)
		(width 0.14224)
		(layer "In11.Cu")
		(net "M_F_DQ<63>")
	)
	(segment
		(start 291.570918 -102.370128)
		(end 291.868606 -102.667816)
		(width 0.0889)
		(layer "In11.Cu")
		(net "M_F_DQ<63>")
	)
	(segment
		(start 314.927996 -131.9022)
		(end 314.9854 -131.959604)
		(width 0.14224)
		(layer "In11.Cu")
		(net "M_F_DQ<63>")
	)
	(segment
		(start 314.330842 -126.843536)
		(end 314.485782 -126.998476)
		(width 0.14224)
		(layer "In11.Cu")
		(net "M_F_DQ<63>")
	)
	(segment
		(start 314.823094 -136.743694)
		(end 314.9854 -136.906)
		(width 0.14224)
		(layer "In11.Cu")
		(net "M_F_DQ<63>")
	)
	(segment
		(start 314.823094 -136.254744)
		(end 314.823094 -136.743694)
		(width 0.14224)
		(layer "In11.Cu")
		(net "M_F_DQ<63>")
	)
	(segment
		(start 314.9854 -143.6116)
		(end 314.927996 -143.669004)
		(width 0.14224)
		(layer "In11.Cu")
		(net "M_F_DQ<63>")
	)
	(segment
		(start 314.8076 -138.938)
		(end 314.8076 -139.365482)
		(width 0.14224)
		(layer "In11.Cu")
		(net "M_F_DQ<63>")
	)
	(segment
		(start 315.131196 -130.087878)
		(end 315.131196 -131.205478)
		(width 0.14224)
		(layer "In11.Cu")
		(net "M_F_DQ<63>")
	)
	(segment
		(start 314.54979 -149.533356)
		(end 314.527438 -149.533356)
		(width 0.14224)
		(layer "In11.Cu")
		(net "M_F_DQ<63>")
	)
	(segment
		(start 313.861196 -151.387048)
		(end 313.861196 -151.660352)
		(width 0.14224)
		(layer "In11.Cu")
		(net "M_F_DQ<63>")
	)
	(segment
		(start 314.521088 -128.624076)
		(end 314.999624 -128.624076)
		(width 0.14224)
		(layer "In11.Cu")
		(net "M_F_DQ<63>")
	)
	(segment
		(start 314.149994 -153.364946)
		(end 313.972194 -153.542746)
		(width 0.14224)
		(layer "In11.Cu")
		(net "M_F_DQ<63>")
	)
	(segment
		(start 314.9854 -148.336)
		(end 314.902596 -148.418804)
		(width 0.14224)
		(layer "In11.Cu")
		(net "M_F_DQ<63>")
	)
	(segment
		(start 314.9854 -136.906)
		(end 314.9854 -138.7602)
		(width 0.14224)
		(layer "In11.Cu")
		(net "M_F_DQ<63>")
	)
	(segment
		(start 315.105796 -135.972042)
		(end 314.823094 -136.254744)
		(width 0.14224)
		(layer "In11.Cu")
		(net "M_F_DQ<63>")
	)
	(segment
		(start 290.30549 -100.681536)
		(end 290.31184 -100.692204)
		(width 0.0889)
		(layer "In11.Cu")
		(net "M_F_DQ<63>")
	)
	(segment
		(start 315.303662 -127.153416)
		(end 315.303662 -127.656336)
		(width 0.14224)
		(layer "In11.Cu")
		(net "M_F_DQ<63>")
	)
	(segment
		(start 315.131196 -131.205478)
		(end 314.927996 -131.408678)
		(width 0.14224)
		(layer "In11.Cu")
		(net "M_F_DQ<63>")
	)
	(segment
		(start 288.917126 -94.937834)
		(end 288.95675 -94.937834)
		(width 0.0889)
		(layer "In11.Cu")
		(net "M_F_DQ<63>")
	)
	(segment
		(start 287.203134 -93.947234)
		(end 287.231074 -93.947234)
		(width 0.0889)
		(layer "In11.Cu")
		(net "M_F_DQ<63>")
	)
	(segment
		(start 315.303662 -127.656336)
		(end 315.148722 -127.811276)
		(width 0.14224)
		(layer "In11.Cu")
		(net "M_F_DQ<63>")
	)
	(segment
		(start 314.143644 -150.435818)
		(end 314.143644 -151.1046)
		(width 0.14224)
		(layer "In11.Cu")
		(net "M_F_DQ<63>")
	)
	(segment
		(start 313.972194 -153.542746)
		(end 313.699906 -153.542746)
		(width 0.14224)
		(layer "In11.Cu")
		(net "M_F_DQ<63>")
	)
	(segment
		(start 290.30549 -99.290886)
		(end 290.300664 -99.299522)
		(width 0.0889)
		(layer "In11.Cu")
		(net "M_F_DQ<63>")
	)
	(segment
		(start 313.861196 -151.660352)
		(end 314.118244 -151.9174)
		(width 0.14224)
		(layer "In11.Cu")
		(net "M_F_DQ<63>")
	)
	(segment
		(start 290.30549 -101.272086)
		(end 290.300664 -101.280722)
		(width 0.0889)
		(layer "In11.Cu")
		(net "M_F_DQ<63>")
	)
	(segment
		(start 301.48022 -109.932724)
		(end 314.470796 -122.9233)
		(width 0.14224)
		(layer "In11.Cu")
		(net "M_F_DQ<63>")
	)
	(segment
		(start 288.058606 -94.442534)
		(end 288.09442 -94.442534)
		(width 0.0889)
		(layer "In11.Cu")
		(net "M_F_DQ<63>")
	)
	(segment
		(start 313.861196 -152.752552)
		(end 314.149994 -153.04135)
		(width 0.14224)
		(layer "In11.Cu")
		(net "M_F_DQ<63>")
	)
	(segment
		(start 314.927996 -131.408678)
		(end 314.927996 -131.9022)
		(width 0.14224)
		(layer "In11.Cu")
		(net "M_F_DQ<63>")
	)
	(segment
		(start 314.9854 -141.713204)
		(end 314.9854 -143.6116)
		(width 0.14224)
		(layer "In11.Cu")
		(net "M_F_DQ<63>")
	)
	(segment
		(start 314.099194 -149.9616)
		(end 314.099194 -150.391368)
		(width 0.14224)
		(layer "In11.Cu")
		(net "M_F_DQ<63>")
	)
	(arc
		(start 287.72993 -94.242636)
		(mid 287.868674 -94.384669)
		(end 288.058606 -94.442534)
		(width 0.0889)
		(layer "In11.Cu")
		(net "M_F_DQ<63>")
	)
	(arc
		(start 286.87141 -93.747336)
		(mid 287.011489 -93.890072)
		(end 287.203134 -93.947234)
		(width 0.0889)
		(layer "In11.Cu")
		(net "M_F_DQ<63>")
	)
	(arc
		(start 290.300664 -99.299522)
		(mid 290.251909 -99.495874)
		(end 290.30549 -99.690936)
		(width 0.0889)
		(layer "In11.Cu")
		(net "M_F_DQ<63>")
	)
	(arc
		(start 286.016446 -93.257878)
		(mid 286.162412 -93.400277)
		(end 286.3596 -93.452188)
		(width 0.0889)
		(layer "In11.Cu")
		(net "M_F_DQ<63>")
	)
	(arc
		(start 291.407088 -102.353872)
		(mid 291.45116 -102.363093)
		(end 291.495988 -102.367334)
		(width 0.0889)
		(layer "In11.Cu")
		(net "M_F_DQ<63>")
	)
	(arc
		(start 290.300664 -101.280722)
		(mid 290.304411 -101.669978)
		(end 290.637214 -101.872034)
		(width 0.0889)
		(layer "In11.Cu")
		(net "M_F_DQ<63>")
	)
	(arc
		(start 288.58845 -94.737936)
		(mid 288.727194 -94.879969)
		(end 288.917126 -94.937834)
		(width 0.0889)
		(layer "In11.Cu")
		(net "M_F_DQ<63>")
	)
	(arc
		(start 288.09442 -94.442534)
		(mid 288.379844 -94.526001)
		(end 288.58845 -94.737936)
		(width 0.0889)
		(layer "In11.Cu")
		(net "M_F_DQ<63>")
	)
	(arc
		(start 289.44697 -95.232982)
		(mid 289.588653 -95.376786)
		(end 289.782504 -95.433134)
		(width 0.0889)
		(layer "In11.Cu")
		(net "M_F_DQ<63>")
	)
	(arc
		(start 290.31184 -96.730058)
		(mid 290.384604 -97.021075)
		(end 290.30549 -97.310448)
		(width 0.0889)
		(layer "In11.Cu")
		(net "M_F_DQ<63>")
	)
	(arc
		(start 290.30549 -99.690936)
		(mid 290.384621 -99.986338)
		(end 290.30549 -100.28174)
		(width 0.0889)
		(layer "In11.Cu")
		(net "M_F_DQ<63>")
	)
	(arc
		(start 290.30549 -96.31934)
		(mid 290.25202 -96.514403)
		(end 290.300664 -96.710754)
		(width 0.0889)
		(layer "In11.Cu")
		(net "M_F_DQ<63>")
	)
	(arc
		(start 289.81527 -95.433388)
		(mid 290.310747 -95.737831)
		(end 290.30549 -96.31934)
		(width 0.0889)
		(layer "In11.Cu")
		(net "M_F_DQ<63>")
	)
	(arc
		(start 290.67379 -101.872034)
		(mid 290.957007 -101.956315)
		(end 291.16401 -102.167182)
		(width 0.0889)
		(layer "In11.Cu")
		(net "M_F_DQ<63>")
	)
	(arc
		(start 290.30549 -100.28174)
		(mid 290.251991 -100.481638)
		(end 290.30549 -100.681536)
		(width 0.0889)
		(layer "In11.Cu")
		(net "M_F_DQ<63>")
	)
	(arc
		(start 290.30549 -97.710244)
		(mid 290.384495 -98.005282)
		(end 290.30549 -98.300286)
		(width 0.0889)
		(layer "In11.Cu")
		(net "M_F_DQ<63>")
	)
	(arc
		(start 290.30549 -98.700336)
		(mid 290.384712 -98.989454)
		(end 290.31184 -99.280218)
		(width 0.0889)
		(layer "In11.Cu")
		(net "M_F_DQ<63>")
	)
	(arc
		(start 286.38119 -93.452188)
		(mid 286.664407 -93.536469)
		(end 286.87141 -93.747336)
		(width 0.0889)
		(layer "In11.Cu")
		(net "M_F_DQ<63>")
	)
	(arc
		(start 285.519114 -92.956634)
		(mid 285.804538 -93.040101)
		(end 286.013144 -93.252036)
		(width 0.0889)
		(layer "In11.Cu")
		(net "M_F_DQ<63>")
	)
	(arc
		(start 288.95675 -94.937834)
		(mid 289.239967 -95.022115)
		(end 289.44697 -95.232982)
		(width 0.0889)
		(layer "In11.Cu")
		(net "M_F_DQ<63>")
	)
	(arc
		(start 290.300664 -98.308922)
		(mid 290.251909 -98.505274)
		(end 290.30549 -98.700336)
		(width 0.0889)
		(layer "In11.Cu")
		(net "M_F_DQ<63>")
	)
	(arc
		(start 291.16401 -102.167182)
		(mid 291.267074 -102.28478)
		(end 291.407342 -102.353872)
		(width 0.0889)
		(layer "In11.Cu")
		(net "M_F_DQ<63>")
	)
	(arc
		(start 285.154624 -92.756736)
		(mid 285.294703 -92.899472)
		(end 285.486348 -92.956634)
		(width 0.0889)
		(layer "In11.Cu")
		(net "M_F_DQ<63>")
	)
	(arc
		(start 289.782504 -95.433134)
		(mid 289.798889 -95.433026)
		(end 289.81527 -95.433388)
		(width 0.0889)
		(layer "In11.Cu")
		(net "M_F_DQ<63>")
	)
	(arc
		(start 290.30549 -97.310448)
		(mid 290.251991 -97.510346)
		(end 290.30549 -97.710244)
		(width 0.0889)
		(layer "In11.Cu")
		(net "M_F_DQ<63>")
	)
	(arc
		(start 287.231074 -93.947234)
		(mid 287.519219 -94.029553)
		(end 287.72993 -94.242636)
		(width 0.0889)
		(layer "In11.Cu")
		(net "M_F_DQ<63>")
	)
	(arc
		(start 290.31184 -100.692204)
		(mid 290.384638 -100.982967)
		(end 290.30549 -101.272086)
		(width 0.0889)
		(layer "In11.Cu")
		(net "M_F_DQ<63>")
	)
	(segment
		(start 314.682124 -155.55468)
		(end 314.682124 -155.77312)
		(width 0.1651)
		(layer "F.Cu")
		(net "M_F_DQ<62>")
	)
	(segment
		(start 314.550044 -155.4226)
		(end 314.682124 -155.55468)
		(width 0.1651)
		(layer "F.Cu")
		(net "M_F_DQ<62>")
	)
	(segment
		(start 314.550044 -155.9052)
		(end 314.550044 -156.87294)
		(width 0.1651)
		(layer "F.Cu")
		(net "M_F_DQ<62>")
	)
	(segment
		(start 314.550044 -155.118054)
		(end 314.550044 -155.4226)
		(width 0.1651)
		(layer "F.Cu")
		(net "M_F_DQ<62>")
	)
	(segment
		(start 314.550044 -156.87294)
		(end 314.550298 -156.87294)
		(width 0.1651)
		(layer "F.Cu")
		(net "M_F_DQ<62>")
	)
	(segment
		(start 284.071314 -90.080338)
		(end 284.642814 -90.080338)
		(width 0.1651)
		(layer "F.Cu")
		(net "M_F_DQ<62>")
	)
	(segment
		(start 314.54979 -155.1178)
		(end 314.550044 -155.118054)
		(width 0.1651)
		(layer "F.Cu")
		(net "M_F_DQ<62>")
	)
	(segment
		(start 314.682124 -155.77312)
		(end 314.550044 -155.9052)
		(width 0.1651)
		(layer "F.Cu")
		(net "M_F_DQ<62>")
	)
	(via
		(at 284.642814 -90.080338)
		(size 0.508)
		(drill 0.254)
		(layers "F.Cu" "B.Cu")
		(net "M_F_DQ<62>")
	)
	(via
		(at 313.699906 -150.814278)
		(size 0.508)
		(drill 0.254)
		(layers "F.Cu" "B.Cu")
		(net "M_F_DQ<62>")
	)
	(via
		(at 314.54979 -155.1178)
		(size 0.508)
		(drill 0.254)
		(layers "F.Cu" "B.Cu")
		(net "M_F_DQ<62>")
	)
	(segment
		(start 313.699906 -152.078182)
		(end 313.699906 -150.814278)
		(width 0.1651)
		(layer "B.Cu")
		(net "M_F_DQ<62>")
	)
	(segment
		(start 313.700414 -152.078436)
		(end 313.699906 -152.078182)
		(width 0.1651)
		(layer "B.Cu")
		(net "M_F_DQ<62>")
	)
	(segment
		(start 314.1218 -146.297396)
		(end 314.1218 -148.3106)
		(width 0.14224)
		(layer "In11.Cu")
		(net "M_F_DQ<62>")
	)
	(segment
		(start 313.266836 -153.834846)
		(end 314.54979 -155.1178)
		(width 0.14224)
		(layer "In11.Cu")
		(net "M_F_DQ<62>")
	)
	(segment
		(start 314.1218 -132.022596)
		(end 314.1218 -134.0358)
		(width 0.14224)
		(layer "In11.Cu")
		(net "M_F_DQ<62>")
	)
	(segment
		(start 314.1218 -143.6624)
		(end 314.253626 -143.794226)
		(width 0.14224)
		(layer "In11.Cu")
		(net "M_F_DQ<62>")
	)
	(segment
		(start 313.944254 -145.593054)
		(end 314.267596 -145.916396)
		(width 0.14224)
		(layer "In11.Cu")
		(net "M_F_DQ<62>")
	)
	(segment
		(start 313.9948 -140.741146)
		(end 314.304934 -141.05128)
		(width 0.14224)
		(layer "In11.Cu")
		(net "M_F_DQ<62>")
	)
	(segment
		(start 313.530996 -149.671278)
		(end 313.530996 -150.645368)
		(width 0.14224)
		(layer "In11.Cu")
		(net "M_F_DQ<62>")
	)
	(segment
		(start 314.304934 -141.339062)
		(end 314.1218 -141.522196)
		(width 0.14224)
		(layer "In11.Cu")
		(net "M_F_DQ<62>")
	)
	(segment
		(start 299.436536 -110.514384)
		(end 301.253144 -110.514384)
		(width 0.14224)
		(layer "In11.Cu")
		(net "M_F_DQ<62>")
	)
	(segment
		(start 314.165996 -131.9784)
		(end 314.1218 -132.022596)
		(width 0.14224)
		(layer "In11.Cu")
		(net "M_F_DQ<62>")
	)
	(segment
		(start 285.479744 -93.147134)
		(end 285.501334 -93.147134)
		(width 0.0889)
		(layer "In11.Cu")
		(net "M_F_DQ<62>")
	)
	(segment
		(start 314.304934 -141.05128)
		(end 314.304934 -141.339062)
		(width 0.14224)
		(layer "In11.Cu")
		(net "M_F_DQ<62>")
	)
	(segment
		(start 314.253626 -143.794226)
		(end 314.253626 -144.082008)
		(width 0.14224)
		(layer "In11.Cu")
		(net "M_F_DQ<62>")
	)
	(segment
		(start 284.312868 -90.842084)
		(end 284.296104 -90.870786)
		(width 0.0889)
		(layer "In11.Cu")
		(net "M_F_DQ<62>")
	)
	(segment
		(start 290.13404 -100.766118)
		(end 290.14039 -100.776786)
		(width 0.0889)
		(layer "In11.Cu")
		(net "M_F_DQ<62>")
	)
	(segment
		(start 314.064396 -130.062478)
		(end 314.064396 -131.307078)
		(width 0.14224)
		(layer "In11.Cu")
		(net "M_F_DQ<62>")
	)
	(segment
		(start 291.48913 -102.557834)
		(end 291.678106 -102.74681)
		(width 0.0889)
		(layer "In11.Cu")
		(net "M_F_DQ<62>")
	)
	(segment
		(start 313.699906 -150.814278)
		(end 313.266836 -151.247348)
		(width 0.14224)
		(layer "In11.Cu")
		(net "M_F_DQ<62>")
	)
	(segment
		(start 291.835586 -104.227122)
		(end 292.053264 -104.4448)
		(width 0.14224)
		(layer "In11.Cu")
		(net "M_F_DQ<62>")
	)
	(segment
		(start 290.14039 -99.195636)
		(end 290.13404 -99.206304)
		(width 0.0889)
		(layer "In11.Cu")
		(net "M_F_DQ<62>")
	)
	(segment
		(start 314.064396 -131.307078)
		(end 314.165996 -131.408678)
		(width 0.14224)
		(layer "In11.Cu")
		(net "M_F_DQ<62>")
	)
	(segment
		(start 290.145216 -99.187)
		(end 290.14039 -99.195636)
		(width 0.0889)
		(layer "In11.Cu")
		(net "M_F_DQ<62>")
	)
	(segment
		(start 290.63061 -102.062534)
		(end 290.663376 -102.062534)
		(width 0.0889)
		(layer "In11.Cu")
		(net "M_F_DQ<62>")
	)
	(segment
		(start 285.844488 -93.341444)
		(end 285.84779 -93.347286)
		(width 0.0889)
		(layer "In11.Cu")
		(net "M_F_DQ<62>")
	)
	(segment
		(start 313.530996 -150.645368)
		(end 313.699906 -150.814278)
		(width 0.14224)
		(layer "In11.Cu")
		(net "M_F_DQ<62>")
	)
	(segment
		(start 284.291278 -91.2622)
		(end 284.296104 -91.270836)
		(width 0.0889)
		(layer "In11.Cu")
		(net "M_F_DQ<62>")
	)
	(segment
		(start 314.1218 -136.8044)
		(end 314.1218 -138.7602)
		(width 0.14224)
		(layer "In11.Cu")
		(net "M_F_DQ<62>")
	)
	(segment
		(start 314.253626 -144.082008)
		(end 313.944254 -144.39138)
		(width 0.14224)
		(layer "In11.Cu")
		(net "M_F_DQ<62>")
	)
	(segment
		(start 290.13404 -96.803972)
		(end 290.14039 -96.81464)
		(width 0.0889)
		(layer "In11.Cu")
		(net "M_F_DQ<62>")
	)
	(segment
		(start 291.835586 -103.92029)
		(end 291.835586 -104.227122)
		(width 0.0889)
		(layer "In11.Cu")
		(net "M_F_DQ<62>")
	)
	(segment
		(start 314.267596 -129.859278)
		(end 314.064396 -130.062478)
		(width 0.14224)
		(layer "In11.Cu")
		(net "M_F_DQ<62>")
	)
	(segment
		(start 290.145216 -100.1776)
		(end 290.14039 -100.186236)
		(width 0.0889)
		(layer "In11.Cu")
		(net "M_F_DQ<62>")
	)
	(segment
		(start 313.827414 -129.017014)
		(end 314.267596 -129.457196)
		(width 0.14224)
		(layer "In11.Cu")
		(net "M_F_DQ<62>")
	)
	(segment
		(start 313.827414 -123.088654)
		(end 313.827414 -129.017014)
		(width 0.14224)
		(layer "In11.Cu")
		(net "M_F_DQ<62>")
	)
	(segment
		(start 314.362846 -148.839428)
		(end 313.530996 -149.671278)
		(width 0.14224)
		(layer "In11.Cu")
		(net "M_F_DQ<62>")
	)
	(segment
		(start 301.253144 -110.514384)
		(end 313.827414 -123.088654)
		(width 0.14224)
		(layer "In11.Cu")
		(net "M_F_DQ<62>")
	)
	(segment
		(start 286.34182 -93.642688)
		(end 286.374586 -93.642688)
		(width 0.0889)
		(layer "In11.Cu")
		(net "M_F_DQ<62>")
	)
	(segment
		(start 287.205166 -94.137988)
		(end 287.229296 -94.137988)
		(width 0.0889)
		(layer "In11.Cu")
		(net "M_F_DQ<62>")
	)
	(segment
		(start 313.944254 -144.39138)
		(end 313.944254 -145.593054)
		(width 0.14224)
		(layer "In11.Cu")
		(net "M_F_DQ<62>")
	)
	(segment
		(start 284.642814 -90.080338)
		(end 284.312868 -90.842084)
		(width 0.0889)
		(layer "In11.Cu")
		(net "M_F_DQ<62>")
	)
	(segment
		(start 314.267596 -138.905996)
		(end 314.267596 -139.460478)
		(width 0.14224)
		(layer "In11.Cu")
		(net "M_F_DQ<62>")
	)
	(segment
		(start 314.267596 -139.460478)
		(end 313.9948 -139.733274)
		(width 0.14224)
		(layer "In11.Cu")
		(net "M_F_DQ<62>")
	)
	(segment
		(start 288.05505 -94.633288)
		(end 288.094674 -94.633288)
		(width 0.0889)
		(layer "In11.Cu")
		(net "M_F_DQ<62>")
	)
	(segment
		(start 314.1218 -134.0358)
		(end 314.165996 -134.079996)
		(width 0.14224)
		(layer "In11.Cu")
		(net "M_F_DQ<62>")
	)
	(segment
		(start 314.165996 -134.579868)
		(end 314.064396 -134.681468)
		(width 0.14224)
		(layer "In11.Cu")
		(net "M_F_DQ<62>")
	)
	(segment
		(start 293.366952 -104.4448)
		(end 299.436536 -110.514384)
		(width 0.14224)
		(layer "In11.Cu")
		(net "M_F_DQ<62>")
	)
	(segment
		(start 314.1218 -141.522196)
		(end 314.1218 -143.6624)
		(width 0.14224)
		(layer "In11.Cu")
		(net "M_F_DQ<62>")
	)
	(segment
		(start 313.9948 -139.733274)
		(end 313.9948 -140.741146)
		(width 0.14224)
		(layer "In11.Cu")
		(net "M_F_DQ<62>")
	)
	(segment
		(start 314.267596 -129.457196)
		(end 314.267596 -129.859278)
		(width 0.14224)
		(layer "In11.Cu")
		(net "M_F_DQ<62>")
	)
	(segment
		(start 284.296104 -91.270836)
		(end 284.302454 -91.281504)
		(width 0.0889)
		(layer "In11.Cu")
		(net "M_F_DQ<62>")
	)
	(segment
		(start 314.165996 -134.079996)
		(end 314.165996 -134.579868)
		(width 0.14224)
		(layer "In11.Cu")
		(net "M_F_DQ<62>")
	)
	(segment
		(start 314.267596 -136.658604)
		(end 314.1218 -136.8044)
		(width 0.14224)
		(layer "In11.Cu")
		(net "M_F_DQ<62>")
	)
	(segment
		(start 314.165996 -131.408678)
		(end 314.165996 -131.9784)
		(width 0.14224)
		(layer "In11.Cu")
		(net "M_F_DQ<62>")
	)
	(segment
		(start 314.362846 -148.551646)
		(end 314.362846 -148.839428)
		(width 0.14224)
		(layer "In11.Cu")
		(net "M_F_DQ<62>")
	)
	(segment
		(start 314.1218 -138.7602)
		(end 314.267596 -138.905996)
		(width 0.14224)
		(layer "In11.Cu")
		(net "M_F_DQ<62>")
	)
	(segment
		(start 314.267596 -146.1516)
		(end 314.1218 -146.297396)
		(width 0.14224)
		(layer "In11.Cu")
		(net "M_F_DQ<62>")
	)
	(segment
		(start 314.267596 -145.916396)
		(end 314.267596 -146.1516)
		(width 0.14224)
		(layer "In11.Cu")
		(net "M_F_DQ<62>")
	)
	(segment
		(start 290.14039 -96.81464)
		(end 290.145216 -96.823276)
		(width 0.0889)
		(layer "In11.Cu")
		(net "M_F_DQ<62>")
	)
	(segment
		(start 291.678106 -103.76281)
		(end 291.835586 -103.92029)
		(width 0.0889)
		(layer "In11.Cu")
		(net "M_F_DQ<62>")
	)
	(segment
		(start 288.91738 -95.128588)
		(end 288.953194 -95.128588)
		(width 0.0889)
		(layer "In11.Cu")
		(net "M_F_DQ<62>")
	)
	(segment
		(start 314.1218 -148.3106)
		(end 314.362846 -148.551646)
		(width 0.14224)
		(layer "In11.Cu")
		(net "M_F_DQ<62>")
	)
	(segment
		(start 314.267596 -136.264396)
		(end 314.267596 -136.658604)
		(width 0.14224)
		(layer "In11.Cu")
		(net "M_F_DQ<62>")
	)
	(segment
		(start 314.064396 -134.681468)
		(end 314.064396 -136.061196)
		(width 0.14224)
		(layer "In11.Cu")
		(net "M_F_DQ<62>")
	)
	(segment
		(start 314.064396 -136.061196)
		(end 314.267596 -136.264396)
		(width 0.14224)
		(layer "In11.Cu")
		(net "M_F_DQ<62>")
	)
	(segment
		(start 291.678106 -102.74681)
		(end 291.678106 -103.76281)
		(width 0.0889)
		(layer "In11.Cu")
		(net "M_F_DQ<62>")
	)
	(segment
		(start 292.053264 -104.4448)
		(end 293.366952 -104.4448)
		(width 0.14224)
		(layer "In11.Cu")
		(net "M_F_DQ<62>")
	)
	(segment
		(start 313.266836 -151.247348)
		(end 313.266836 -153.834846)
		(width 0.14224)
		(layer "In11.Cu")
		(net "M_F_DQ<62>")
	)
	(arc
		(start 284.425136 -92.397326)
		(mid 284.536799 -92.488237)
		(end 284.626304 -92.601034)
		(width 0.0889)
		(layer "In11.Cu")
		(net "M_F_DQ<62>")
	)
	(arc
		(start 284.296104 -91.861386)
		(mid 284.253745 -92.155051)
		(end 284.425136 -92.397326)
		(width 0.0889)
		(layer "In11.Cu")
		(net "M_F_DQ<62>")
	)
	(arc
		(start 290.663376 -102.062534)
		(mid 290.857226 -102.118884)
		(end 290.99891 -102.262686)
		(width 0.0889)
		(layer "In11.Cu")
		(net "M_F_DQ<62>")
	)
	(arc
		(start 288.953194 -95.128588)
		(mid 289.143123 -95.186458)
		(end 289.28187 -95.328486)
		(width 0.0889)
		(layer "In11.Cu")
		(net "M_F_DQ<62>")
	)
	(arc
		(start 290.99891 -102.262686)
		(mid 291.205914 -102.47355)
		(end 291.48913 -102.557834)
		(width 0.0889)
		(layer "In11.Cu")
		(net "M_F_DQ<62>")
	)
	(arc
		(start 284.302454 -91.281504)
		(mid 284.375252 -91.572267)
		(end 284.296104 -91.861386)
		(width 0.0889)
		(layer "In11.Cu")
		(net "M_F_DQ<62>")
	)
	(arc
		(start 285.501334 -93.147134)
		(mid 285.698495 -93.199093)
		(end 285.844488 -93.341444)
		(width 0.0889)
		(layer "In11.Cu")
		(net "M_F_DQ<62>")
	)
	(arc
		(start 287.56483 -94.33814)
		(mid 287.771834 -94.549004)
		(end 288.05505 -94.633288)
		(width 0.0889)
		(layer "In11.Cu")
		(net "M_F_DQ<62>")
	)
	(arc
		(start 290.14039 -97.214944)
		(mid 290.061259 -97.510346)
		(end 290.14039 -97.805748)
		(width 0.0889)
		(layer "In11.Cu")
		(net "M_F_DQ<62>")
	)
	(arc
		(start 290.14039 -99.786186)
		(mid 290.19386 -99.981249)
		(end 290.145216 -100.1776)
		(width 0.0889)
		(layer "In11.Cu")
		(net "M_F_DQ<62>")
	)
	(arc
		(start 286.70631 -93.842586)
		(mid 286.917023 -94.055665)
		(end 287.205166 -94.137988)
		(width 0.0889)
		(layer "In11.Cu")
		(net "M_F_DQ<62>")
	)
	(arc
		(start 289.811714 -95.624142)
		(mid 290.144683 -95.83169)
		(end 290.14039 -96.22409)
		(width 0.0889)
		(layer "In11.Cu")
		(net "M_F_DQ<62>")
	)
	(arc
		(start 290.14039 -101.176582)
		(mid 290.135136 -101.75809)
		(end 290.63061 -102.062534)
		(width 0.0889)
		(layer "In11.Cu")
		(net "M_F_DQ<62>")
	)
	(arc
		(start 289.28187 -95.328486)
		(mid 289.490469 -95.540516)
		(end 289.7759 -95.624142)
		(width 0.0889)
		(layer "In11.Cu")
		(net "M_F_DQ<62>")
	)
	(arc
		(start 290.14039 -98.795586)
		(mid 290.19386 -98.990649)
		(end 290.145216 -99.187)
		(width 0.0889)
		(layer "In11.Cu")
		(net "M_F_DQ<62>")
	)
	(arc
		(start 290.14039 -100.776786)
		(mid 290.193889 -100.976684)
		(end 290.14039 -101.176582)
		(width 0.0889)
		(layer "In11.Cu")
		(net "M_F_DQ<62>")
	)
	(arc
		(start 284.989524 -92.851986)
		(mid 285.196528 -93.06285)
		(end 285.479744 -93.147134)
		(width 0.0889)
		(layer "In11.Cu")
		(net "M_F_DQ<62>")
	)
	(arc
		(start 286.374586 -93.642688)
		(mid 286.566228 -93.699854)
		(end 286.70631 -93.842586)
		(width 0.0889)
		(layer "In11.Cu")
		(net "M_F_DQ<62>")
	)
	(arc
		(start 290.14039 -100.186236)
		(mid 290.061168 -100.475354)
		(end 290.13404 -100.766118)
		(width 0.0889)
		(layer "In11.Cu")
		(net "M_F_DQ<62>")
	)
	(arc
		(start 288.094674 -94.633288)
		(mid 288.284603 -94.691158)
		(end 288.42335 -94.833186)
		(width 0.0889)
		(layer "In11.Cu")
		(net "M_F_DQ<62>")
	)
	(arc
		(start 290.14039 -96.22409)
		(mid 290.061168 -96.513208)
		(end 290.13404 -96.803972)
		(width 0.0889)
		(layer "In11.Cu")
		(net "M_F_DQ<62>")
	)
	(arc
		(start 290.13404 -99.206304)
		(mid 290.061242 -99.497067)
		(end 290.14039 -99.786186)
		(width 0.0889)
		(layer "In11.Cu")
		(net "M_F_DQ<62>")
	)
	(arc
		(start 284.626304 -92.601034)
		(mid 284.693747 -92.641516)
		(end 284.766512 -92.671392)
		(width 0.0889)
		(layer "In11.Cu")
		(net "M_F_DQ<62>")
	)
	(arc
		(start 290.145216 -96.823276)
		(mid 290.193969 -97.019738)
		(end 290.14039 -97.214944)
		(width 0.0889)
		(layer "In11.Cu")
		(net "M_F_DQ<62>")
	)
	(arc
		(start 284.766512 -92.671392)
		(mid 284.894755 -92.74102)
		(end 284.989524 -92.851986)
		(width 0.0889)
		(layer "In11.Cu")
		(net "M_F_DQ<62>")
	)
	(arc
		(start 290.13404 -98.215704)
		(mid 290.061242 -98.506467)
		(end 290.14039 -98.795586)
		(width 0.0889)
		(layer "In11.Cu")
		(net "M_F_DQ<62>")
	)
	(arc
		(start 290.14039 -97.805748)
		(mid 290.193816 -98.011599)
		(end 290.13404 -98.215704)
		(width 0.0889)
		(layer "In11.Cu")
		(net "M_F_DQ<62>")
	)
	(arc
		(start 284.296104 -90.870786)
		(mid 284.242634 -91.065849)
		(end 284.291278 -91.2622)
		(width 0.0889)
		(layer "In11.Cu")
		(net "M_F_DQ<62>")
	)
	(arc
		(start 288.42335 -94.833186)
		(mid 288.631958 -95.045118)
		(end 288.91738 -95.128588)
		(width 0.0889)
		(layer "In11.Cu")
		(net "M_F_DQ<62>")
	)
	(arc
		(start 289.7759 -95.624142)
		(mid 289.793807 -95.623733)
		(end 289.811714 -95.624142)
		(width 0.0889)
		(layer "In11.Cu")
		(net "M_F_DQ<62>")
	)
	(arc
		(start 287.229296 -94.137988)
		(mid 287.423146 -94.194338)
		(end 287.56483 -94.33814)
		(width 0.0889)
		(layer "In11.Cu")
		(net "M_F_DQ<62>")
	)
	(arc
		(start 285.84779 -93.347286)
		(mid 286.056398 -93.559218)
		(end 286.34182 -93.642688)
		(width 0.0889)
		(layer "In11.Cu")
		(net "M_F_DQ<62>")
	)
	(segment
		(start 307.749956 -152.278842)
		(end 307.749956 -153.542746)
		(width 0.1651)
		(layer "F.Cu")
		(net "M_F_DQ<61>")
	)
	(segment
		(start 307.750464 -152.273)
		(end 307.749956 -152.278842)
		(width 0.1651)
		(layer "F.Cu")
		(net "M_F_DQ<61>")
	)
	(segment
		(start 281.495754 -91.565984)
		(end 282.067254 -91.565984)
		(width 0.1651)
		(layer "F.Cu")
		(net "M_F_DQ<61>")
	)
	(via
		(at 282.067254 -91.565984)
		(size 0.508)
		(drill 0.254)
		(layers "F.Cu" "B.Cu")
		(net "M_F_DQ<61>")
	)
	(via
		(at 308.52364 -149.533356)
		(size 0.508)
		(drill 0.254)
		(layers "F.Cu" "B.Cu")
		(net "M_F_DQ<61>")
	)
	(via
		(at 307.749956 -153.542746)
		(size 0.508)
		(drill 0.254)
		(layers "F.Cu" "B.Cu")
		(net "M_F_DQ<61>")
	)
	(segment
		(start 308.59984 -147.478496)
		(end 308.59984 -149.425152)
		(width 0.1651)
		(layer "B.Cu")
		(net "M_F_DQ<61>")
	)
	(segment
		(start 308.52364 -149.501352)
		(end 308.52364 -149.533356)
		(width 0.1651)
		(layer "B.Cu")
		(net "M_F_DQ<61>")
	)
	(segment
		(start 308.600348 -147.478496)
		(end 308.59984 -147.478496)
		(width 0.1651)
		(layer "B.Cu")
		(net "M_F_DQ<61>")
	)
	(segment
		(start 308.59984 -149.425152)
		(end 308.52364 -149.501352)
		(width 0.1651)
		(layer "B.Cu")
		(net "M_F_DQ<61>")
	)
	(segment
		(start 287.9344 -109.002322)
		(end 288.08934 -109.157262)
		(width 0.14224)
		(layer "In11.Cu")
		(net "M_F_DQ<61>")
	)
	(segment
		(start 308.997096 -135.938768)
		(end 308.908196 -136.027668)
		(width 0.14224)
		(layer "In11.Cu")
		(net "M_F_DQ<61>")
	)
	(segment
		(start 309.0418 -138.7094)
		(end 308.908196 -138.843004)
		(width 0.14224)
		(layer "In11.Cu")
		(net "M_F_DQ<61>")
	)
	(segment
		(start 307.911246 -152.898856)
		(end 308.174644 -153.162254)
		(width 0.14224)
		(layer "In11.Cu")
		(net "M_F_DQ<61>")
	)
	(segment
		(start 308.933596 -141.478)
		(end 309.0164 -141.560804)
		(width 0.14224)
		(layer "In11.Cu")
		(net "M_F_DQ<61>")
	)
	(segment
		(start 288.622486 -109.312202)
		(end 288.622486 -109.665262)
		(width 0.14224)
		(layer "In11.Cu")
		(net "M_F_DQ<61>")
	)
	(segment
		(start 308.908196 -148.368004)
		(end 308.908196 -149.1488)
		(width 0.14224)
		(layer "In11.Cu")
		(net "M_F_DQ<61>")
	)
	(segment
		(start 308.908196 -149.1488)
		(end 308.52364 -149.533356)
		(width 0.14224)
		(layer "In11.Cu")
		(net "M_F_DQ<61>")
	)
	(segment
		(start 308.200044 -151.129746)
		(end 307.911246 -151.418544)
		(width 0.14224)
		(layer "In11.Cu")
		(net "M_F_DQ<61>")
	)
	(segment
		(start 309.0418 -136.658604)
		(end 309.0418 -138.7094)
		(width 0.14224)
		(layer "In11.Cu")
		(net "M_F_DQ<61>")
	)
	(segment
		(start 287.9344 -109.975142)
		(end 287.9344 -111.379)
		(width 0.14224)
		(layer "In11.Cu")
		(net "M_F_DQ<61>")
	)
	(segment
		(start 282.04922 -94.937834)
		(end 282.088844 -94.937834)
		(width 0.0889)
		(layer "In11.Cu")
		(net "M_F_DQ<61>")
	)
	(segment
		(start 287.72993 -104.739186)
		(end 287.651952 -104.874314)
		(width 0.0889)
		(layer "In11.Cu")
		(net "M_F_DQ<61>")
	)
	(segment
		(start 307.911246 -151.755856)
		(end 308.149244 -151.993854)
		(width 0.14224)
		(layer "In11.Cu")
		(net "M_F_DQ<61>")
	)
	(segment
		(start 308.908196 -136.027668)
		(end 308.908196 -136.525)
		(width 0.14224)
		(layer "In11.Cu")
		(net "M_F_DQ<61>")
	)
	(segment
		(start 286.3596 -97.414588)
		(end 286.38119 -97.414588)
		(width 0.0889)
		(layer "In11.Cu")
		(net "M_F_DQ<61>")
	)
	(segment
		(start 309.0418 -131.985004)
		(end 309.0418 -133.985)
		(width 0.14224)
		(layer "In11.Cu")
		(net "M_F_DQ<61>")
	)
	(segment
		(start 307.911246 -152.586944)
		(end 307.911246 -152.898856)
		(width 0.14224)
		(layer "In11.Cu")
		(net "M_F_DQ<61>")
	)
	(segment
		(start 300.23308 -114.8588)
		(end 309.070502 -123.696222)
		(width 0.14224)
		(layer "In11.Cu")
		(net "M_F_DQ<61>")
	)
	(segment
		(start 308.933596 -134.617968)
		(end 308.997096 -134.681468)
		(width 0.14224)
		(layer "In11.Cu")
		(net "M_F_DQ<61>")
	)
	(segment
		(start 287.651952 -104.874314)
		(end 287.651952 -105.110026)
		(width 0.0889)
		(layer "In11.Cu")
		(net "M_F_DQ<61>")
	)
	(segment
		(start 309.0418 -139.441682)
		(end 309.0418 -140.927074)
		(width 0.14224)
		(layer "In11.Cu")
		(net "M_F_DQ<61>")
	)
	(segment
		(start 286.87776 -102.252018)
		(end 286.87141 -102.262686)
		(width 0.0889)
		(layer "In11.Cu")
		(net "M_F_DQ<61>")
	)
	(segment
		(start 286.87141 -103.253286)
		(end 286.866584 -103.261922)
		(width 0.0889)
		(layer "In11.Cu")
		(net "M_F_DQ<61>")
	)
	(segment
		(start 287.651952 -105.110026)
		(end 287.9344 -105.392474)
		(width 0.0889)
		(layer "In11.Cu")
		(net "M_F_DQ<61>")
	)
	(segment
		(start 308.908196 -146.1008)
		(end 309.0164 -146.209004)
		(width 0.14224)
		(layer "In11.Cu")
		(net "M_F_DQ<61>")
	)
	(segment
		(start 309.0164 -148.2598)
		(end 308.908196 -148.368004)
		(width 0.14224)
		(layer "In11.Cu")
		(net "M_F_DQ<61>")
	)
	(segment
		(start 308.073044 -150.5204)
		(end 308.200044 -150.6474)
		(width 0.14224)
		(layer "In11.Cu")
		(net "M_F_DQ<61>")
	)
	(segment
		(start 284.631638 -96.423988)
		(end 284.664404 -96.423988)
		(width 0.0889)
		(layer "In11.Cu")
		(net "M_F_DQ<61>")
	)
	(segment
		(start 308.908196 -145.607024)
		(end 308.908196 -146.1008)
		(width 0.14224)
		(layer "In11.Cu")
		(net "M_F_DQ<61>")
	)
	(segment
		(start 308.933596 -143.745204)
		(end 308.933596 -144.271238)
		(width 0.14224)
		(layer "In11.Cu")
		(net "M_F_DQ<61>")
	)
	(segment
		(start 308.501288 -149.533356)
		(end 308.073044 -149.9616)
		(width 0.14224)
		(layer "In11.Cu")
		(net "M_F_DQ<61>")
	)
	(segment
		(start 308.908196 -139.308078)
		(end 309.0418 -139.441682)
		(width 0.14224)
		(layer "In11.Cu")
		(net "M_F_DQ<61>")
	)
	(segment
		(start 308.933596 -141.035278)
		(end 308.933596 -141.478)
		(width 0.14224)
		(layer "In11.Cu")
		(net "M_F_DQ<61>")
	)
	(segment
		(start 281.737816 -92.326968)
		(end 281.715718 -92.365322)
		(width 0.0889)
		(layer "In11.Cu")
		(net "M_F_DQ<61>")
	)
	(segment
		(start 286.87776 -99.280218)
		(end 286.87141 -99.290886)
		(width 0.0889)
		(layer "In11.Cu")
		(net "M_F_DQ<61>")
	)
	(segment
		(start 308.933596 -129.299208)
		(end 308.933596 -129.920238)
		(width 0.14224)
		(layer "In11.Cu")
		(net "M_F_DQ<61>")
	)
	(segment
		(start 308.933596 -131.8768)
		(end 309.0418 -131.985004)
		(width 0.14224)
		(layer "In11.Cu")
		(net "M_F_DQ<61>")
	)
	(segment
		(start 288.08934 -109.820202)
		(end 287.9344 -109.975142)
		(width 0.14224)
		(layer "In11.Cu")
		(net "M_F_DQ<61>")
	)
	(segment
		(start 309.0164 -131.351274)
		(end 308.933596 -131.434078)
		(width 0.14224)
		(layer "In11.Cu")
		(net "M_F_DQ<61>")
	)
	(segment
		(start 309.0164 -141.560804)
		(end 309.0164 -143.6624)
		(width 0.14224)
		(layer "In11.Cu")
		(net "M_F_DQ<61>")
	)
	(segment
		(start 286.87141 -101.272086)
		(end 286.866584 -101.280722)
		(width 0.0889)
		(layer "In11.Cu")
		(net "M_F_DQ<61>")
	)
	(segment
		(start 308.073044 -149.9616)
		(end 308.073044 -150.5204)
		(width 0.14224)
		(layer "In11.Cu")
		(net "M_F_DQ<61>")
	)
	(segment
		(start 308.933596 -131.434078)
		(end 308.933596 -131.8768)
		(width 0.14224)
		(layer "In11.Cu")
		(net "M_F_DQ<61>")
	)
	(segment
		(start 286.013144 -97.214436)
		(end 286.016446 -97.220278)
		(width 0.0889)
		(layer "In11.Cu")
		(net "M_F_DQ<61>")
	)
	(segment
		(start 309.060596 -145.454624)
		(end 308.908196 -145.607024)
		(width 0.14224)
		(layer "In11.Cu")
		(net "M_F_DQ<61>")
	)
	(segment
		(start 286.87776 -101.261418)
		(end 286.87141 -101.272086)
		(width 0.0889)
		(layer "In11.Cu")
		(net "M_F_DQ<61>")
	)
	(segment
		(start 308.908196 -136.525)
		(end 309.0418 -136.658604)
		(width 0.14224)
		(layer "In11.Cu")
		(net "M_F_DQ<61>")
	)
	(segment
		(start 281.726894 -93.336618)
		(end 281.720544 -93.347286)
		(width 0.0889)
		(layer "In11.Cu")
		(net "M_F_DQ<61>")
	)
	(segment
		(start 286.87776 -103.242618)
		(end 286.87141 -103.253286)
		(width 0.0889)
		(layer "In11.Cu")
		(net "M_F_DQ<61>")
	)
	(segment
		(start 308.52364 -149.533356)
		(end 308.501288 -149.533356)
		(width 0.14224)
		(layer "In11.Cu")
		(net "M_F_DQ<61>")
	)
	(segment
		(start 287.9344 -105.392474)
		(end 287.9344 -109.002322)
		(width 0.14224)
		(layer "In11.Cu")
		(net "M_F_DQ<61>")
	)
	(segment
		(start 307.911246 -151.418544)
		(end 307.911246 -151.755856)
		(width 0.14224)
		(layer "In11.Cu")
		(net "M_F_DQ<61>")
	)
	(segment
		(start 309.0418 -140.927074)
		(end 308.933596 -141.035278)
		(width 0.14224)
		(layer "In11.Cu")
		(net "M_F_DQ<61>")
	)
	(segment
		(start 308.174644 -153.162254)
		(end 308.174644 -153.390346)
		(width 0.14224)
		(layer "In11.Cu")
		(net "M_F_DQ<61>")
	)
	(segment
		(start 309.060596 -144.398238)
		(end 309.060596 -145.454624)
		(width 0.14224)
		(layer "In11.Cu")
		(net "M_F_DQ<61>")
	)
	(segment
		(start 288.467546 -109.157262)
		(end 288.622486 -109.312202)
		(width 0.14224)
		(layer "In11.Cu")
		(net "M_F_DQ<61>")
	)
	(segment
		(start 282.914598 -95.433134)
		(end 282.938728 -95.433134)
		(width 0.0889)
		(layer "In11.Cu")
		(net "M_F_DQ<61>")
	)
	(segment
		(start 308.200044 -150.6474)
		(end 308.200044 -151.129746)
		(width 0.14224)
		(layer "In11.Cu")
		(net "M_F_DQ<61>")
	)
	(segment
		(start 309.0164 -143.6624)
		(end 308.933596 -143.745204)
		(width 0.14224)
		(layer "In11.Cu")
		(net "M_F_DQ<61>")
	)
	(segment
		(start 287.203134 -103.853234)
		(end 287.2359 -103.853234)
		(width 0.0889)
		(layer "In11.Cu")
		(net "M_F_DQ<61>")
	)
	(segment
		(start 308.933596 -134.093204)
		(end 308.933596 -134.617968)
		(width 0.14224)
		(layer "In11.Cu")
		(net "M_F_DQ<61>")
	)
	(segment
		(start 308.149244 -152.348946)
		(end 307.911246 -152.586944)
		(width 0.14224)
		(layer "In11.Cu")
		(net "M_F_DQ<61>")
	)
	(segment
		(start 286.87141 -99.290886)
		(end 286.866584 -99.299522)
		(width 0.0889)
		(layer "In11.Cu")
		(net "M_F_DQ<61>")
	)
	(segment
		(start 283.769308 -95.928434)
		(end 283.802074 -95.928434)
		(width 0.0889)
		(layer "In11.Cu")
		(net "M_F_DQ<61>")
	)
	(segment
		(start 308.933596 -144.271238)
		(end 309.060596 -144.398238)
		(width 0.14224)
		(layer "In11.Cu")
		(net "M_F_DQ<61>")
	)
	(segment
		(start 308.908196 -138.843004)
		(end 308.908196 -139.308078)
		(width 0.14224)
		(layer "In11.Cu")
		(net "M_F_DQ<61>")
	)
	(segment
		(start 308.933596 -129.920238)
		(end 309.0164 -130.003042)
		(width 0.14224)
		(layer "In11.Cu")
		(net "M_F_DQ<61>")
	)
	(segment
		(start 288.622486 -109.665262)
		(end 288.467546 -109.820202)
		(width 0.14224)
		(layer "In11.Cu")
		(net "M_F_DQ<61>")
	)
	(segment
		(start 309.070502 -129.162302)
		(end 308.933596 -129.299208)
		(width 0.14224)
		(layer "In11.Cu")
		(net "M_F_DQ<61>")
	)
	(segment
		(start 308.022244 -153.542746)
		(end 307.749956 -153.542746)
		(width 0.14224)
		(layer "In11.Cu")
		(net "M_F_DQ<61>")
	)
	(segment
		(start 309.070502 -123.696222)
		(end 309.070502 -129.162302)
		(width 0.14224)
		(layer "In11.Cu")
		(net "M_F_DQ<61>")
	)
	(segment
		(start 309.0164 -130.003042)
		(end 309.0164 -131.351274)
		(width 0.14224)
		(layer "In11.Cu")
		(net "M_F_DQ<61>")
	)
	(segment
		(start 308.149244 -151.993854)
		(end 308.149244 -152.348946)
		(width 0.14224)
		(layer "In11.Cu")
		(net "M_F_DQ<61>")
	)
	(segment
		(start 291.4142 -114.8588)
		(end 300.23308 -114.8588)
		(width 0.14224)
		(layer "In11.Cu")
		(net "M_F_DQ<61>")
	)
	(segment
		(start 281.720544 -93.347286)
		(end 281.715718 -93.355922)
		(width 0.0889)
		(layer "In11.Cu")
		(net "M_F_DQ<61>")
	)
	(segment
		(start 282.067254 -91.565984)
		(end 281.737816 -92.326968)
		(width 0.0889)
		(layer "In11.Cu")
		(net "M_F_DQ<61>")
	)
	(segment
		(start 285.486348 -96.919034)
		(end 285.519114 -96.919034)
		(width 0.0889)
		(layer "In11.Cu")
		(net "M_F_DQ<61>")
	)
	(segment
		(start 288.467546 -109.820202)
		(end 288.08934 -109.820202)
		(width 0.14224)
		(layer "In11.Cu")
		(net "M_F_DQ<61>")
	)
	(segment
		(start 309.0418 -133.985)
		(end 308.933596 -134.093204)
		(width 0.14224)
		(layer "In11.Cu")
		(net "M_F_DQ<61>")
	)
	(segment
		(start 286.87141 -100.281486)
		(end 286.866584 -100.290122)
		(width 0.0889)
		(layer "In11.Cu")
		(net "M_F_DQ<61>")
	)
	(segment
		(start 286.87776 -100.270818)
		(end 286.87141 -100.281486)
		(width 0.0889)
		(layer "In11.Cu")
		(net "M_F_DQ<61>")
	)
	(segment
		(start 287.9344 -111.379)
		(end 291.4142 -114.8588)
		(width 0.14224)
		(layer "In11.Cu")
		(net "M_F_DQ<61>")
	)
	(segment
		(start 308.997096 -134.681468)
		(end 308.997096 -135.938768)
		(width 0.14224)
		(layer "In11.Cu")
		(net "M_F_DQ<61>")
	)
	(segment
		(start 286.87141 -102.262686)
		(end 286.866584 -102.271322)
		(width 0.0889)
		(layer "In11.Cu")
		(net "M_F_DQ<61>")
	)
	(segment
		(start 288.08934 -109.157262)
		(end 288.467546 -109.157262)
		(width 0.14224)
		(layer "In11.Cu")
		(net "M_F_DQ<61>")
	)
	(segment
		(start 309.0164 -146.209004)
		(end 309.0164 -148.2598)
		(width 0.14224)
		(layer "In11.Cu")
		(net "M_F_DQ<61>")
	)
	(segment
		(start 308.174644 -153.390346)
		(end 308.022244 -153.542746)
		(width 0.14224)
		(layer "In11.Cu")
		(net "M_F_DQ<61>")
	)
	(arc
		(start 282.579064 -95.232982)
		(mid 282.720747 -95.376786)
		(end 282.914598 -95.433134)
		(width 0.0889)
		(layer "In11.Cu")
		(net "M_F_DQ<61>")
	)
	(arc
		(start 281.720544 -94.33814)
		(mid 281.716299 -94.730385)
		(end 282.04922 -94.937834)
		(width 0.0889)
		(layer "In11.Cu")
		(net "M_F_DQ<61>")
	)
	(arc
		(start 286.38119 -97.414588)
		(mid 286.664382 -97.499253)
		(end 286.87141 -97.710244)
		(width 0.0889)
		(layer "In11.Cu")
		(net "M_F_DQ<61>")
	)
	(arc
		(start 281.720544 -93.747336)
		(mid 281.799675 -94.042738)
		(end 281.720544 -94.33814)
		(width 0.0889)
		(layer "In11.Cu")
		(net "M_F_DQ<61>")
	)
	(arc
		(start 286.87141 -100.681536)
		(mid 286.950632 -100.970654)
		(end 286.87776 -101.261418)
		(width 0.0889)
		(layer "In11.Cu")
		(net "M_F_DQ<61>")
	)
	(arc
		(start 286.866584 -101.280722)
		(mid 286.817829 -101.477074)
		(end 286.87141 -101.672136)
		(width 0.0889)
		(layer "In11.Cu")
		(net "M_F_DQ<61>")
	)
	(arc
		(start 286.87141 -101.672136)
		(mid 286.950632 -101.961254)
		(end 286.87776 -102.252018)
		(width 0.0889)
		(layer "In11.Cu")
		(net "M_F_DQ<61>")
	)
	(arc
		(start 286.87141 -99.690936)
		(mid 286.950632 -99.980054)
		(end 286.87776 -100.270818)
		(width 0.0889)
		(layer "In11.Cu")
		(net "M_F_DQ<61>")
	)
	(arc
		(start 286.87141 -98.301048)
		(mid 286.817911 -98.500946)
		(end 286.87141 -98.700844)
		(width 0.0889)
		(layer "In11.Cu")
		(net "M_F_DQ<61>")
	)
	(arc
		(start 287.2359 -103.853234)
		(mid 287.734151 -104.156074)
		(end 287.72993 -104.739186)
		(width 0.0889)
		(layer "In11.Cu")
		(net "M_F_DQ<61>")
	)
	(arc
		(start 286.87141 -98.700844)
		(mid 286.881049 -98.718113)
		(end 286.890206 -98.735642)
		(width 0.0889)
		(layer "In11.Cu")
		(net "M_F_DQ<61>")
	)
	(arc
		(start 286.866584 -100.290122)
		(mid 286.817829 -100.486474)
		(end 286.87141 -100.681536)
		(width 0.0889)
		(layer "In11.Cu")
		(net "M_F_DQ<61>")
	)
	(arc
		(start 281.720544 -92.756736)
		(mid 281.799766 -93.045854)
		(end 281.726894 -93.336618)
		(width 0.0889)
		(layer "In11.Cu")
		(net "M_F_DQ<61>")
	)
	(arc
		(start 281.715718 -92.365322)
		(mid 281.666963 -92.561674)
		(end 281.720544 -92.756736)
		(width 0.0889)
		(layer "In11.Cu")
		(net "M_F_DQ<61>")
	)
	(arc
		(start 286.866584 -103.261922)
		(mid 286.870331 -103.651178)
		(end 287.203134 -103.853234)
		(width 0.0889)
		(layer "In11.Cu")
		(net "M_F_DQ<61>")
	)
	(arc
		(start 286.87141 -102.662736)
		(mid 286.950632 -102.951854)
		(end 286.87776 -103.242618)
		(width 0.0889)
		(layer "In11.Cu")
		(net "M_F_DQ<61>")
	)
	(arc
		(start 286.866584 -102.271322)
		(mid 286.817829 -102.467674)
		(end 286.87141 -102.662736)
		(width 0.0889)
		(layer "In11.Cu")
		(net "M_F_DQ<61>")
	)
	(arc
		(start 282.088844 -94.937834)
		(mid 282.372061 -95.022115)
		(end 282.579064 -95.232982)
		(width 0.0889)
		(layer "In11.Cu")
		(net "M_F_DQ<61>")
	)
	(arc
		(start 286.87141 -97.710244)
		(mid 286.950541 -98.005646)
		(end 286.87141 -98.301048)
		(width 0.0889)
		(layer "In11.Cu")
		(net "M_F_DQ<61>")
	)
	(arc
		(start 284.664404 -96.423988)
		(mid 284.947621 -96.508269)
		(end 285.154624 -96.719136)
		(width 0.0889)
		(layer "In11.Cu")
		(net "M_F_DQ<61>")
	)
	(arc
		(start 281.715718 -93.355922)
		(mid 281.666963 -93.552274)
		(end 281.720544 -93.747336)
		(width 0.0889)
		(layer "In11.Cu")
		(net "M_F_DQ<61>")
	)
	(arc
		(start 282.938728 -95.433134)
		(mid 283.226873 -95.515453)
		(end 283.437584 -95.728536)
		(width 0.0889)
		(layer "In11.Cu")
		(net "M_F_DQ<61>")
	)
	(arc
		(start 285.519114 -96.919034)
		(mid 285.804538 -97.002501)
		(end 286.013144 -97.214436)
		(width 0.0889)
		(layer "In11.Cu")
		(net "M_F_DQ<61>")
	)
	(arc
		(start 286.866584 -99.299522)
		(mid 286.817829 -99.495874)
		(end 286.87141 -99.690936)
		(width 0.0889)
		(layer "In11.Cu")
		(net "M_F_DQ<61>")
	)
	(arc
		(start 285.154624 -96.719136)
		(mid 285.294703 -96.861872)
		(end 285.486348 -96.919034)
		(width 0.0889)
		(layer "In11.Cu")
		(net "M_F_DQ<61>")
	)
	(arc
		(start 286.890206 -98.735642)
		(mid 286.950484 -99.009455)
		(end 286.87776 -99.280218)
		(width 0.0889)
		(layer "In11.Cu")
		(net "M_F_DQ<61>")
	)
	(arc
		(start 286.016446 -97.220278)
		(mid 286.162412 -97.362677)
		(end 286.3596 -97.414588)
		(width 0.0889)
		(layer "In11.Cu")
		(net "M_F_DQ<61>")
	)
	(arc
		(start 284.296104 -96.223836)
		(mid 284.437787 -96.36764)
		(end 284.631638 -96.423988)
		(width 0.0889)
		(layer "In11.Cu")
		(net "M_F_DQ<61>")
	)
	(arc
		(start 283.437584 -95.728536)
		(mid 283.577663 -95.871272)
		(end 283.769308 -95.928434)
		(width 0.0889)
		(layer "In11.Cu")
		(net "M_F_DQ<61>")
	)
	(arc
		(start 283.802074 -95.928434)
		(mid 284.087498 -96.011901)
		(end 284.296104 -96.223836)
		(width 0.0889)
		(layer "In11.Cu")
		(net "M_F_DQ<61>")
	)
	(segment
		(start 308.501796 -155.0162)
		(end 308.59984 -155.547568)
		(width 0.1651)
		(layer "F.Cu")
		(net "M_F_DQ<60>")
	)
	(segment
		(start 308.59984 -156.87294)
		(end 308.600348 -156.87294)
		(width 0.1651)
		(layer "F.Cu")
		(net "M_F_DQ<60>")
	)
	(segment
		(start 308.59984 -155.547568)
		(end 308.59984 -156.87294)
		(width 0.1651)
		(layer "F.Cu")
		(net "M_F_DQ<60>")
	)
	(segment
		(start 281.495754 -90.575384)
		(end 282.067254 -90.575384)
		(width 0.1651)
		(layer "F.Cu")
		(net "M_F_DQ<60>")
	)
	(via
		(at 308.501796 -155.0162)
		(size 0.508)
		(drill 0.254)
		(layers "F.Cu" "B.Cu")
		(net "M_F_DQ<60>")
	)
	(via
		(at 307.749956 -150.814278)
		(size 0.508)
		(drill 0.254)
		(layers "F.Cu" "B.Cu")
		(net "M_F_DQ<60>")
	)
	(via
		(at 282.067254 -90.575384)
		(size 0.508)
		(drill 0.254)
		(layers "F.Cu" "B.Cu")
		(net "M_F_DQ<60>")
	)
	(segment
		(start 307.750464 -152.078436)
		(end 307.750464 -150.814786)
		(width 0.1651)
		(layer "B.Cu")
		(net "M_F_DQ<60>")
	)
	(segment
		(start 307.750464 -150.814786)
		(end 307.749956 -150.814278)
		(width 0.1651)
		(layer "B.Cu")
		(net "M_F_DQ<60>")
	)
	(segment
		(start 286.70631 -101.176836)
		(end 286.69996 -101.187504)
		(width 0.0889)
		(layer "In11.Cu")
		(net "M_F_DQ<60>")
	)
	(segment
		(start 281.555444 -91.270836)
		(end 281.549094 -91.281504)
		(width 0.0889)
		(layer "In11.Cu")
		(net "M_F_DQ<60>")
	)
	(segment
		(start 281.555444 -93.252036)
		(end 281.549094 -93.262704)
		(width 0.0889)
		(layer "In11.Cu")
		(net "M_F_DQ<60>")
	)
	(segment
		(start 308.18582 -139.420854)
		(end 308.10073 -139.505944)
		(width 0.14224)
		(layer "In11.Cu")
		(net "M_F_DQ<60>")
	)
	(segment
		(start 286.70631 -103.158036)
		(end 286.69996 -103.168704)
		(width 0.0889)
		(layer "In11.Cu")
		(net "M_F_DQ<60>")
	)
	(segment
		(start 308.207156 -123.712986)
		(end 308.207156 -129.808478)
		(width 0.14224)
		(layer "In11.Cu")
		(net "M_F_DQ<60>")
	)
	(segment
		(start 308.250844 -155.0162)
		(end 308.501796 -155.0162)
		(width 0.14224)
		(layer "In11.Cu")
		(net "M_F_DQ<60>")
	)
	(segment
		(start 307.749956 -150.814278)
		(end 307.316886 -151.247348)
		(width 0.14224)
		(layer "In11.Cu")
		(net "M_F_DQ<60>")
	)
	(segment
		(start 281.56027 -92.2528)
		(end 281.555444 -92.261436)
		(width 0.0889)
		(layer "In11.Cu")
		(net "M_F_DQ<60>")
	)
	(segment
		(start 287.4518 -105.065322)
		(end 287.212024 -105.305098)
		(width 0.0889)
		(layer "In11.Cu")
		(net "M_F_DQ<60>")
	)
	(segment
		(start 307.316886 -151.247348)
		(end 307.316886 -153.78049)
		(width 0.14224)
		(layer "In11.Cu")
		(net "M_F_DQ<60>")
	)
	(segment
		(start 308.10073 -139.505944)
		(end 308.10073 -140.862812)
		(width 0.14224)
		(layer "In11.Cu")
		(net "M_F_DQ<60>")
	)
	(segment
		(start 308.235096 -148.960078)
		(end 307.434996 -149.760178)
		(width 0.14224)
		(layer "In11.Cu")
		(net "M_F_DQ<60>")
	)
	(segment
		(start 282.049474 -95.128588)
		(end 282.085288 -95.128588)
		(width 0.0889)
		(layer "In11.Cu")
		(net "M_F_DQ<60>")
	)
	(segment
		(start 284.625034 -96.614488)
		(end 284.6578 -96.614488)
		(width 0.0889)
		(layer "In11.Cu")
		(net "M_F_DQ<60>")
	)
	(segment
		(start 287.4518 -104.756966)
		(end 287.4518 -105.065322)
		(width 0.0889)
		(layer "In11.Cu")
		(net "M_F_DQ<60>")
	)
	(segment
		(start 286.711136 -101.1682)
		(end 286.70631 -101.176836)
		(width 0.0889)
		(layer "In11.Cu")
		(net "M_F_DQ<60>")
	)
	(segment
		(start 308.058058 -135.99033)
		(end 308.18582 -136.118092)
		(width 0.14224)
		(layer "In11.Cu")
		(net "M_F_DQ<60>")
	)
	(segment
		(start 286.70631 -102.167436)
		(end 286.69996 -102.178104)
		(width 0.0889)
		(layer "In11.Cu")
		(net "M_F_DQ<60>")
	)
	(segment
		(start 308.207156 -134.514844)
		(end 308.058058 -134.663942)
		(width 0.14224)
		(layer "In11.Cu")
		(net "M_F_DQ<60>")
	)
	(segment
		(start 308.247796 -144.10055)
		(end 307.981604 -144.366742)
		(width 0.14224)
		(layer "In11.Cu")
		(net "M_F_DQ<60>")
	)
	(segment
		(start 307.981604 -144.366742)
		(end 307.981604 -145.527776)
		(width 0.14224)
		(layer "In11.Cu")
		(net "M_F_DQ<60>")
	)
	(segment
		(start 281.555444 -92.261436)
		(end 281.549094 -92.272104)
		(width 0.0889)
		(layer "In11.Cu")
		(net "M_F_DQ<60>")
	)
	(segment
		(start 308.107842 -131.268724)
		(end 308.207156 -131.368038)
		(width 0.14224)
		(layer "In11.Cu")
		(net "M_F_DQ<60>")
	)
	(segment
		(start 308.247796 -141.009878)
		(end 308.247796 -144.10055)
		(width 0.14224)
		(layer "In11.Cu")
		(net "M_F_DQ<60>")
	)
	(segment
		(start 308.107842 -129.907792)
		(end 308.107842 -131.268724)
		(width 0.14224)
		(layer "In11.Cu")
		(net "M_F_DQ<60>")
	)
	(segment
		(start 282.067254 -90.575384)
		(end 281.572208 -91.241372)
		(width 0.0889)
		(layer "In11.Cu")
		(net "M_F_DQ<60>")
	)
	(segment
		(start 286.34182 -97.605088)
		(end 286.374586 -97.605088)
		(width 0.0889)
		(layer "In11.Cu")
		(net "M_F_DQ<60>")
	)
	(segment
		(start 286.711136 -103.1494)
		(end 286.70631 -103.158036)
		(width 0.0889)
		(layer "In11.Cu")
		(net "M_F_DQ<60>")
	)
	(segment
		(start 308.235096 -145.781268)
		(end 308.235096 -148.960078)
		(width 0.14224)
		(layer "In11.Cu")
		(net "M_F_DQ<60>")
	)
	(segment
		(start 308.10073 -140.862812)
		(end 308.247796 -141.009878)
		(width 0.14224)
		(layer "In11.Cu")
		(net "M_F_DQ<60>")
	)
	(segment
		(start 286.70631 -100.186236)
		(end 286.69996 -100.196904)
		(width 0.0889)
		(layer "In11.Cu")
		(net "M_F_DQ<60>")
	)
	(segment
		(start 307.434996 -149.760178)
		(end 307.434996 -150.499318)
		(width 0.14224)
		(layer "In11.Cu")
		(net "M_F_DQ<60>")
	)
	(segment
		(start 291.1856 -115.4684)
		(end 299.96257 -115.4684)
		(width 0.14224)
		(layer "In11.Cu")
		(net "M_F_DQ<60>")
	)
	(segment
		(start 283.762704 -96.118934)
		(end 283.79547 -96.118934)
		(width 0.0889)
		(layer "In11.Cu")
		(net "M_F_DQ<60>")
	)
	(segment
		(start 308.207156 -131.368038)
		(end 308.207156 -134.514844)
		(width 0.14224)
		(layer "In11.Cu")
		(net "M_F_DQ<60>")
	)
	(segment
		(start 286.711136 -100.1776)
		(end 286.70631 -100.186236)
		(width 0.0889)
		(layer "In11.Cu")
		(net "M_F_DQ<60>")
	)
	(segment
		(start 282.91282 -95.623888)
		(end 282.94076 -95.623888)
		(width 0.0889)
		(layer "In11.Cu")
		(net "M_F_DQ<60>")
	)
	(segment
		(start 307.474874 -154.24023)
		(end 308.250844 -155.0162)
		(width 0.14224)
		(layer "In11.Cu")
		(net "M_F_DQ<60>")
	)
	(segment
		(start 286.711136 -102.1588)
		(end 286.70631 -102.167436)
		(width 0.0889)
		(layer "In11.Cu")
		(net "M_F_DQ<60>")
	)
	(segment
		(start 307.981604 -145.527776)
		(end 308.235096 -145.781268)
		(width 0.14224)
		(layer "In11.Cu")
		(net "M_F_DQ<60>")
	)
	(segment
		(start 285.844488 -97.303844)
		(end 285.84779 -97.309686)
		(width 0.0889)
		(layer "In11.Cu")
		(net "M_F_DQ<60>")
	)
	(segment
		(start 286.711136 -99.187)
		(end 286.70631 -99.195636)
		(width 0.0889)
		(layer "In11.Cu")
		(net "M_F_DQ<60>")
	)
	(segment
		(start 307.316886 -153.78049)
		(end 307.474874 -153.938478)
		(width 0.14224)
		(layer "In11.Cu")
		(net "M_F_DQ<60>")
	)
	(segment
		(start 307.474874 -153.938478)
		(end 307.474874 -154.24023)
		(width 0.14224)
		(layer "In11.Cu")
		(net "M_F_DQ<60>")
	)
	(segment
		(start 287.2232 -105.316274)
		(end 287.2232 -111.506)
		(width 0.14224)
		(layer "In11.Cu")
		(net "M_F_DQ<60>")
	)
	(segment
		(start 287.2232 -111.506)
		(end 291.1856 -115.4684)
		(width 0.14224)
		(layer "In11.Cu")
		(net "M_F_DQ<60>")
	)
	(segment
		(start 281.572208 -91.241372)
		(end 281.555444 -91.270836)
		(width 0.0889)
		(layer "In11.Cu")
		(net "M_F_DQ<60>")
	)
	(segment
		(start 287.212024 -105.305098)
		(end 287.2232 -105.316274)
		(width 0.14224)
		(layer "In11.Cu")
		(net "M_F_DQ<60>")
	)
	(segment
		(start 308.207156 -129.808478)
		(end 308.107842 -129.907792)
		(width 0.14224)
		(layer "In11.Cu")
		(net "M_F_DQ<60>")
	)
	(segment
		(start 286.70631 -99.195636)
		(end 286.69996 -99.206304)
		(width 0.0889)
		(layer "In11.Cu")
		(net "M_F_DQ<60>")
	)
	(segment
		(start 287.19653 -104.043734)
		(end 287.229296 -104.043734)
		(width 0.0889)
		(layer "In11.Cu")
		(net "M_F_DQ<60>")
	)
	(segment
		(start 287.56483 -104.643936)
		(end 287.4518 -104.756966)
		(width 0.0889)
		(layer "In11.Cu")
		(net "M_F_DQ<60>")
	)
	(segment
		(start 299.96257 -115.4684)
		(end 308.207156 -123.712986)
		(width 0.14224)
		(layer "In11.Cu")
		(net "M_F_DQ<60>")
	)
	(segment
		(start 281.56027 -94.234)
		(end 281.555444 -94.242636)
		(width 0.0889)
		(layer "In11.Cu")
		(net "M_F_DQ<60>")
	)
	(segment
		(start 308.18582 -136.118092)
		(end 308.18582 -139.420854)
		(width 0.14224)
		(layer "In11.Cu")
		(net "M_F_DQ<60>")
	)
	(segment
		(start 307.434996 -150.499318)
		(end 307.749956 -150.814278)
		(width 0.14224)
		(layer "In11.Cu")
		(net "M_F_DQ<60>")
	)
	(segment
		(start 281.56027 -93.2434)
		(end 281.555444 -93.252036)
		(width 0.0889)
		(layer "In11.Cu")
		(net "M_F_DQ<60>")
	)
	(segment
		(start 285.479744 -97.109534)
		(end 285.501334 -97.109534)
		(width 0.0889)
		(layer "In11.Cu")
		(net "M_F_DQ<60>")
	)
	(segment
		(start 308.058058 -134.663942)
		(end 308.058058 -135.99033)
		(width 0.14224)
		(layer "In11.Cu")
		(net "M_F_DQ<60>")
	)
	(arc
		(start 286.70631 -97.805748)
		(mid 286.759809 -98.005646)
		(end 286.70631 -98.205544)
		(width 0.0889)
		(layer "In11.Cu")
		(net "M_F_DQ<60>")
	)
	(arc
		(start 286.70631 -98.205544)
		(mid 286.627179 -98.500946)
		(end 286.70631 -98.796348)
		(width 0.0889)
		(layer "In11.Cu")
		(net "M_F_DQ<60>")
	)
	(arc
		(start 285.501334 -97.109534)
		(mid 285.698495 -97.161493)
		(end 285.844488 -97.303844)
		(width 0.0889)
		(layer "In11.Cu")
		(net "M_F_DQ<60>")
	)
	(arc
		(start 286.70631 -99.786186)
		(mid 286.75978 -99.981249)
		(end 286.711136 -100.1776)
		(width 0.0889)
		(layer "In11.Cu")
		(net "M_F_DQ<60>")
	)
	(arc
		(start 281.549094 -93.262704)
		(mid 281.476296 -93.553467)
		(end 281.555444 -93.842586)
		(width 0.0889)
		(layer "In11.Cu")
		(net "M_F_DQ<60>")
	)
	(arc
		(start 282.94076 -95.623888)
		(mid 283.132402 -95.681054)
		(end 283.272484 -95.823786)
		(width 0.0889)
		(layer "In11.Cu")
		(net "M_F_DQ<60>")
	)
	(arc
		(start 284.989524 -96.814386)
		(mid 285.196528 -97.02525)
		(end 285.479744 -97.109534)
		(width 0.0889)
		(layer "In11.Cu")
		(net "M_F_DQ<60>")
	)
	(arc
		(start 281.555444 -92.851986)
		(mid 281.608914 -93.047049)
		(end 281.56027 -93.2434)
		(width 0.0889)
		(layer "In11.Cu")
		(net "M_F_DQ<60>")
	)
	(arc
		(start 281.555444 -91.861386)
		(mid 281.608914 -92.056449)
		(end 281.56027 -92.2528)
		(width 0.0889)
		(layer "In11.Cu")
		(net "M_F_DQ<60>")
	)
	(arc
		(start 285.84779 -97.309686)
		(mid 286.056398 -97.521618)
		(end 286.34182 -97.605088)
		(width 0.0889)
		(layer "In11.Cu")
		(net "M_F_DQ<60>")
	)
	(arc
		(start 286.69996 -103.168704)
		(mid 286.703991 -103.744886)
		(end 287.19653 -104.043734)
		(width 0.0889)
		(layer "In11.Cu")
		(net "M_F_DQ<60>")
	)
	(arc
		(start 284.6578 -96.614488)
		(mid 284.849442 -96.671654)
		(end 284.989524 -96.814386)
		(width 0.0889)
		(layer "In11.Cu")
		(net "M_F_DQ<60>")
	)
	(arc
		(start 286.70631 -98.796348)
		(mid 286.720647 -98.822848)
		(end 286.732726 -98.85045)
		(width 0.0889)
		(layer "In11.Cu")
		(net "M_F_DQ<60>")
	)
	(arc
		(start 286.70631 -100.776786)
		(mid 286.75978 -100.971849)
		(end 286.711136 -101.1682)
		(width 0.0889)
		(layer "In11.Cu")
		(net "M_F_DQ<60>")
	)
	(arc
		(start 282.085288 -95.128588)
		(mid 282.275217 -95.186458)
		(end 282.413964 -95.328486)
		(width 0.0889)
		(layer "In11.Cu")
		(net "M_F_DQ<60>")
	)
	(arc
		(start 284.131004 -96.319086)
		(mid 284.339612 -96.531018)
		(end 284.625034 -96.614488)
		(width 0.0889)
		(layer "In11.Cu")
		(net "M_F_DQ<60>")
	)
	(arc
		(start 286.732726 -98.85045)
		(mid 286.759101 -99.02111)
		(end 286.711136 -99.187)
		(width 0.0889)
		(layer "In11.Cu")
		(net "M_F_DQ<60>")
	)
	(arc
		(start 283.79547 -96.118934)
		(mid 283.98932 -96.175284)
		(end 284.131004 -96.319086)
		(width 0.0889)
		(layer "In11.Cu")
		(net "M_F_DQ<60>")
	)
	(arc
		(start 286.69996 -100.196904)
		(mid 286.627162 -100.487667)
		(end 286.70631 -100.776786)
		(width 0.0889)
		(layer "In11.Cu")
		(net "M_F_DQ<60>")
	)
	(arc
		(start 286.70631 -101.767386)
		(mid 286.75978 -101.962449)
		(end 286.711136 -102.1588)
		(width 0.0889)
		(layer "In11.Cu")
		(net "M_F_DQ<60>")
	)
	(arc
		(start 281.555444 -94.242636)
		(mid 281.551115 -94.825808)
		(end 282.049474 -95.128588)
		(width 0.0889)
		(layer "In11.Cu")
		(net "M_F_DQ<60>")
	)
	(arc
		(start 282.413964 -95.328486)
		(mid 282.624677 -95.541565)
		(end 282.91282 -95.623888)
		(width 0.0889)
		(layer "In11.Cu")
		(net "M_F_DQ<60>")
	)
	(arc
		(start 286.374586 -97.605088)
		(mid 286.566245 -97.662761)
		(end 286.70631 -97.805748)
		(width 0.0889)
		(layer "In11.Cu")
		(net "M_F_DQ<60>")
	)
	(arc
		(start 286.69996 -99.206304)
		(mid 286.627162 -99.497067)
		(end 286.70631 -99.786186)
		(width 0.0889)
		(layer "In11.Cu")
		(net "M_F_DQ<60>")
	)
	(arc
		(start 281.555444 -93.842586)
		(mid 281.608914 -94.037649)
		(end 281.56027 -94.234)
		(width 0.0889)
		(layer "In11.Cu")
		(net "M_F_DQ<60>")
	)
	(arc
		(start 283.272484 -95.823786)
		(mid 283.479488 -96.03465)
		(end 283.762704 -96.118934)
		(width 0.0889)
		(layer "In11.Cu")
		(net "M_F_DQ<60>")
	)
	(arc
		(start 287.229296 -104.043734)
		(mid 287.567465 -104.248532)
		(end 287.56483 -104.643936)
		(width 0.0889)
		(layer "In11.Cu")
		(net "M_F_DQ<60>")
	)
	(arc
		(start 286.70631 -102.757986)
		(mid 286.75978 -102.953049)
		(end 286.711136 -103.1494)
		(width 0.0889)
		(layer "In11.Cu")
		(net "M_F_DQ<60>")
	)
	(arc
		(start 286.69996 -102.178104)
		(mid 286.627162 -102.468867)
		(end 286.70631 -102.757986)
		(width 0.0889)
		(layer "In11.Cu")
		(net "M_F_DQ<60>")
	)
	(arc
		(start 281.549094 -92.272104)
		(mid 281.476296 -92.562867)
		(end 281.555444 -92.851986)
		(width 0.0889)
		(layer "In11.Cu")
		(net "M_F_DQ<60>")
	)
	(arc
		(start 281.549094 -91.281504)
		(mid 281.476296 -91.572267)
		(end 281.555444 -91.861386)
		(width 0.0889)
		(layer "In11.Cu")
		(net "M_F_DQ<60>")
	)
	(arc
		(start 286.69996 -101.187504)
		(mid 286.627162 -101.478267)
		(end 286.70631 -101.767386)
		(width 0.0889)
		(layer "In11.Cu")
		(net "M_F_DQ<60>")
	)
	(segment
		(start 196.399912 -152.278842)
		(end 196.399912 -153.542746)
		(width 0.1651)
		(layer "F.Cu")
		(net "M_F_DQ<5>")
	)
	(segment
		(start 196.40042 -152.273)
		(end 196.399912 -152.278842)
		(width 0.1651)
		(layer "F.Cu")
		(net "M_F_DQ<5>")
	)
	(segment
		(start 242.193318 -84.812886)
		(end 241.621818 -84.812886)
		(width 0.1651)
		(layer "F.Cu")
		(net "M_F_DQ<5>")
	)
	(via
		(at 196.399912 -153.542746)
		(size 0.508)
		(drill 0.254)
		(layers "F.Cu" "B.Cu")
		(net "M_F_DQ<5>")
	)
	(via
		(at 241.621818 -84.812886)
		(size 0.508)
		(drill 0.254)
		(layers "F.Cu" "B.Cu")
		(net "M_F_DQ<5>")
	)
	(via
		(at 197.173596 -149.533356)
		(size 0.508)
		(drill 0.254)
		(layers "F.Cu" "B.Cu")
		(net "M_F_DQ<5>")
	)
	(segment
		(start 197.249796 -147.478496)
		(end 197.249796 -149.457156)
		(width 0.1651)
		(layer "B.Cu")
		(net "M_F_DQ<5>")
	)
	(segment
		(start 197.249796 -149.457156)
		(end 197.173596 -149.533356)
		(width 0.1651)
		(layer "B.Cu")
		(net "M_F_DQ<5>")
	)
	(segment
		(start 197.250304 -147.478496)
		(end 197.249796 -147.478496)
		(width 0.1651)
		(layer "B.Cu")
		(net "M_F_DQ<5>")
	)
	(segment
		(start 196.561202 -151.755856)
		(end 196.7992 -151.993854)
		(width 0.14224)
		(layer "In11.Cu")
		(net "M_F_DQ<5>")
	)
	(segment
		(start 199.885046 -111.645954)
		(end 199.373236 -111.645954)
		(width 0.14224)
		(layer "In11.Cu")
		(net "M_F_DQ<5>")
	)
	(segment
		(start 197.6882 -132.032248)
		(end 197.6882 -134.0358)
		(width 0.14224)
		(layer "In11.Cu")
		(net "M_F_DQ<5>")
	)
	(segment
		(start 197.6882 -146.230848)
		(end 197.6882 -148.336)
		(width 0.14224)
		(layer "In11.Cu")
		(net "M_F_DQ<5>")
	)
	(segment
		(start 203.8604 -107.6706)
		(end 199.885046 -111.645954)
		(width 0.14224)
		(layer "In11.Cu")
		(net "M_F_DQ<5>")
	)
	(segment
		(start 216.20099 -98.302064)
		(end 213.665054 -100.838)
		(width 0.14224)
		(layer "In11.Cu")
		(net "M_F_DQ<5>")
	)
	(segment
		(start 240.778284 -83.91779)
		(end 240.745518 -83.91779)
		(width 0.0889)
		(layer "In11.Cu")
		(net "M_F_DQ<5>")
	)
	(segment
		(start 231.511348 -86.565232)
		(end 231.511348 -86.269068)
		(width 0.0889)
		(layer "In11.Cu")
		(net "M_F_DQ<5>")
	)
	(segment
		(start 197.583552 -131.9276)
		(end 197.6882 -132.032248)
		(width 0.14224)
		(layer "In11.Cu")
		(net "M_F_DQ<5>")
	)
	(segment
		(start 197.583552 -141.035278)
		(end 197.583552 -141.5288)
		(width 0.14224)
		(layer "In11.Cu")
		(net "M_F_DQ<5>")
	)
	(segment
		(start 197.52183 -126.88697)
		(end 197.52183 -129.858516)
		(width 0.14224)
		(layer "In11.Cu")
		(net "M_F_DQ<5>")
	)
	(segment
		(start 239.922812 -83.42249)
		(end 239.883188 -83.42249)
		(width 0.0889)
		(layer "In11.Cu")
		(net "M_F_DQ<5>")
	)
	(segment
		(start 197.647052 -135.938768)
		(end 197.558152 -136.027668)
		(width 0.14224)
		(layer "In11.Cu")
		(net "M_F_DQ<5>")
	)
	(segment
		(start 196.8246 -153.390346)
		(end 196.6722 -153.542746)
		(width 0.14224)
		(layer "In11.Cu")
		(net "M_F_DQ<5>")
	)
	(segment
		(start 197.558152 -146.1008)
		(end 197.6882 -146.230848)
		(width 0.14224)
		(layer "In11.Cu")
		(net "M_F_DQ<5>")
	)
	(segment
		(start 197.583552 -134.617968)
		(end 197.647052 -134.681468)
		(width 0.14224)
		(layer "In11.Cu")
		(net "M_F_DQ<5>")
	)
	(segment
		(start 197.6882 -136.6774)
		(end 197.6882 -138.811)
		(width 0.14224)
		(layer "In11.Cu")
		(net "M_F_DQ<5>")
	)
	(segment
		(start 197.647052 -140.971778)
		(end 197.583552 -141.035278)
		(width 0.14224)
		(layer "In11.Cu")
		(net "M_F_DQ<5>")
	)
	(segment
		(start 234.775248 -85.403436)
		(end 234.742482 -85.403436)
		(width 0.0889)
		(layer "In11.Cu")
		(net "M_F_DQ<5>")
	)
	(segment
		(start 196.561202 -152.898856)
		(end 196.8246 -153.162254)
		(width 0.14224)
		(layer "In11.Cu")
		(net "M_F_DQ<5>")
	)
	(segment
		(start 241.126772 -84.147152)
		(end 241.110008 -84.117688)
		(width 0.0889)
		(layer "In11.Cu")
		(net "M_F_DQ<5>")
	)
	(segment
		(start 197.6882 -134.0358)
		(end 197.583552 -134.140448)
		(width 0.14224)
		(layer "In11.Cu")
		(net "M_F_DQ<5>")
	)
	(segment
		(start 197.710552 -144.398238)
		(end 197.710552 -145.454624)
		(width 0.14224)
		(layer "In11.Cu")
		(net "M_F_DQ<5>")
	)
	(segment
		(start 197.558152 -149.1488)
		(end 197.173596 -149.533356)
		(width 0.14224)
		(layer "In11.Cu")
		(net "M_F_DQ<5>")
	)
	(segment
		(start 204.384656 -105.419144)
		(end 203.8604 -106.684826)
		(width 0.14224)
		(layer "In11.Cu")
		(net "M_F_DQ<5>")
	)
	(segment
		(start 233.912918 -85.89899)
		(end 233.880152 -85.89899)
		(width 0.0889)
		(layer "In11.Cu")
		(net "M_F_DQ<5>")
	)
	(segment
		(start 196.7992 -152.348946)
		(end 196.561202 -152.586944)
		(width 0.14224)
		(layer "In11.Cu")
		(net "M_F_DQ<5>")
	)
	(segment
		(start 197.558152 -136.027668)
		(end 197.558152 -136.547352)
		(width 0.14224)
		(layer "In11.Cu")
		(net "M_F_DQ<5>")
	)
	(segment
		(start 206.0702 -102.87)
		(end 206.0702 -104.876854)
		(width 0.14224)
		(layer "In11.Cu")
		(net "M_F_DQ<5>")
	)
	(segment
		(start 233.058208 -86.394036)
		(end 233.025442 -86.394036)
		(width 0.0889)
		(layer "In11.Cu")
		(net "M_F_DQ<5>")
	)
	(segment
		(start 197.9422 -126.4666)
		(end 197.52183 -126.88697)
		(width 0.14224)
		(layer "In11.Cu")
		(net "M_F_DQ<5>")
	)
	(segment
		(start 213.665054 -100.838)
		(end 208.1022 -100.838)
		(width 0.14224)
		(layer "In11.Cu")
		(net "M_F_DQ<5>")
	)
	(segment
		(start 197.583552 -134.140448)
		(end 197.583552 -134.617968)
		(width 0.14224)
		(layer "In11.Cu")
		(net "M_F_DQ<5>")
	)
	(segment
		(start 231.835706 -86.88959)
		(end 231.511348 -86.565232)
		(width 0.0889)
		(layer "In11.Cu")
		(net "M_F_DQ<5>")
	)
	(segment
		(start 197.558152 -139.308078)
		(end 197.647052 -139.396978)
		(width 0.14224)
		(layer "In11.Cu")
		(net "M_F_DQ<5>")
	)
	(segment
		(start 196.561202 -152.586944)
		(end 196.561202 -152.898856)
		(width 0.14224)
		(layer "In11.Cu")
		(net "M_F_DQ<5>")
	)
	(segment
		(start 197.710552 -145.454624)
		(end 197.558152 -145.607024)
		(width 0.14224)
		(layer "In11.Cu")
		(net "M_F_DQ<5>")
	)
	(segment
		(start 232.195878 -86.88959)
		(end 231.835706 -86.88959)
		(width 0.0889)
		(layer "In11.Cu")
		(net "M_F_DQ<5>")
	)
	(segment
		(start 216.20099 -97.68459)
		(end 216.20099 -98.302064)
		(width 0.14224)
		(layer "In11.Cu")
		(net "M_F_DQ<5>")
	)
	(segment
		(start 196.85 -150.6474)
		(end 196.85 -151.129746)
		(width 0.14224)
		(layer "In11.Cu")
		(net "M_F_DQ<5>")
	)
	(segment
		(start 231.294686 -86.052406)
		(end 230.65105 -86.052406)
		(width 0.0889)
		(layer "In11.Cu")
		(net "M_F_DQ<5>")
	)
	(segment
		(start 197.151244 -149.533356)
		(end 196.723 -149.9616)
		(width 0.14224)
		(layer "In11.Cu")
		(net "M_F_DQ<5>")
	)
	(segment
		(start 197.583552 -131.434078)
		(end 197.583552 -131.9276)
		(width 0.14224)
		(layer "In11.Cu")
		(net "M_F_DQ<5>")
	)
	(segment
		(start 196.8246 -153.162254)
		(end 196.8246 -153.390346)
		(width 0.14224)
		(layer "In11.Cu")
		(net "M_F_DQ<5>")
	)
	(segment
		(start 197.52183 -129.858516)
		(end 197.647052 -129.983738)
		(width 0.14224)
		(layer "In11.Cu")
		(net "M_F_DQ<5>")
	)
	(segment
		(start 237.346998 -83.91779)
		(end 237.314232 -83.91779)
		(width 0.0889)
		(layer "In11.Cu")
		(net "M_F_DQ<5>")
	)
	(segment
		(start 238.209328 -83.42249)
		(end 238.169704 -83.42249)
		(width 0.0889)
		(layer "In11.Cu")
		(net "M_F_DQ<5>")
	)
	(segment
		(start 197.558152 -148.466048)
		(end 197.558152 -149.1488)
		(width 0.14224)
		(layer "In11.Cu")
		(net "M_F_DQ<5>")
	)
	(segment
		(start 203.8604 -106.684826)
		(end 203.8604 -107.6706)
		(width 0.14224)
		(layer "In11.Cu")
		(net "M_F_DQ<5>")
	)
	(segment
		(start 197.6882 -138.811)
		(end 197.558152 -138.941048)
		(width 0.14224)
		(layer "In11.Cu")
		(net "M_F_DQ<5>")
	)
	(segment
		(start 241.621818 -84.812886)
		(end 241.126772 -84.147152)
		(width 0.0889)
		(layer "In11.Cu")
		(net "M_F_DQ<5>")
	)
	(segment
		(start 206.0702 -104.876854)
		(end 205.867254 -105.0798)
		(width 0.14224)
		(layer "In11.Cu")
		(net "M_F_DQ<5>")
	)
	(segment
		(start 197.558152 -136.547352)
		(end 197.6882 -136.6774)
		(width 0.14224)
		(layer "In11.Cu")
		(net "M_F_DQ<5>")
	)
	(segment
		(start 196.723 -149.9616)
		(end 196.723 -150.5204)
		(width 0.14224)
		(layer "In11.Cu")
		(net "M_F_DQ<5>")
	)
	(segment
		(start 230.216456 -86.487)
		(end 227.39858 -86.487)
		(width 0.14224)
		(layer "In11.Cu")
		(net "M_F_DQ<5>")
	)
	(segment
		(start 230.65105 -86.052406)
		(end 230.216456 -86.487)
		(width 0.0889)
		(layer "In11.Cu")
		(net "M_F_DQ<5>")
	)
	(segment
		(start 205.867254 -105.0798)
		(end 204.724 -105.0798)
		(width 0.14224)
		(layer "In11.Cu")
		(net "M_F_DQ<5>")
	)
	(segment
		(start 199.373236 -111.645954)
		(end 197.9422 -113.07699)
		(width 0.14224)
		(layer "In11.Cu")
		(net "M_F_DQ<5>")
	)
	(segment
		(start 197.6882 -141.633448)
		(end 197.6882 -143.5608)
		(width 0.14224)
		(layer "In11.Cu")
		(net "M_F_DQ<5>")
	)
	(segment
		(start 197.558152 -145.607024)
		(end 197.558152 -146.1008)
		(width 0.14224)
		(layer "In11.Cu")
		(net "M_F_DQ<5>")
	)
	(segment
		(start 196.7992 -151.993854)
		(end 196.7992 -152.348946)
		(width 0.14224)
		(layer "In11.Cu")
		(net "M_F_DQ<5>")
	)
	(segment
		(start 204.724 -105.0798)
		(end 204.384656 -105.419144)
		(width 0.14224)
		(layer "In11.Cu")
		(net "M_F_DQ<5>")
	)
	(segment
		(start 196.6722 -153.542746)
		(end 196.399912 -153.542746)
		(width 0.14224)
		(layer "In11.Cu")
		(net "M_F_DQ<5>")
	)
	(segment
		(start 227.39858 -86.487)
		(end 216.20099 -97.68459)
		(width 0.14224)
		(layer "In11.Cu")
		(net "M_F_DQ<5>")
	)
	(segment
		(start 235.629958 -84.90839)
		(end 235.597192 -84.90839)
		(width 0.0889)
		(layer "In11.Cu")
		(net "M_F_DQ<5>")
	)
	(segment
		(start 196.723 -150.5204)
		(end 196.85 -150.6474)
		(width 0.14224)
		(layer "In11.Cu")
		(net "M_F_DQ<5>")
	)
	(segment
		(start 208.1022 -100.838)
		(end 206.0702 -102.87)
		(width 0.14224)
		(layer "In11.Cu")
		(net "M_F_DQ<5>")
	)
	(segment
		(start 197.647052 -129.983738)
		(end 197.647052 -131.370578)
		(width 0.14224)
		(layer "In11.Cu")
		(net "M_F_DQ<5>")
	)
	(segment
		(start 197.583552 -144.271238)
		(end 197.710552 -144.398238)
		(width 0.14224)
		(layer "In11.Cu")
		(net "M_F_DQ<5>")
	)
	(segment
		(start 197.9422 -113.07699)
		(end 197.9422 -126.4666)
		(width 0.14224)
		(layer "In11.Cu")
		(net "M_F_DQ<5>")
	)
	(segment
		(start 236.492288 -84.412836)
		(end 236.459522 -84.412836)
		(width 0.0889)
		(layer "In11.Cu")
		(net "M_F_DQ<5>")
	)
	(segment
		(start 197.583552 -141.5288)
		(end 197.6882 -141.633448)
		(width 0.14224)
		(layer "In11.Cu")
		(net "M_F_DQ<5>")
	)
	(segment
		(start 197.647052 -131.370578)
		(end 197.583552 -131.434078)
		(width 0.14224)
		(layer "In11.Cu")
		(net "M_F_DQ<5>")
	)
	(segment
		(start 197.173596 -149.533356)
		(end 197.151244 -149.533356)
		(width 0.14224)
		(layer "In11.Cu")
		(net "M_F_DQ<5>")
	)
	(segment
		(start 196.561202 -151.418544)
		(end 196.561202 -151.755856)
		(width 0.14224)
		(layer "In11.Cu")
		(net "M_F_DQ<5>")
	)
	(segment
		(start 196.85 -151.129746)
		(end 196.561202 -151.418544)
		(width 0.14224)
		(layer "In11.Cu")
		(net "M_F_DQ<5>")
	)
	(segment
		(start 197.558152 -138.941048)
		(end 197.558152 -139.308078)
		(width 0.14224)
		(layer "In11.Cu")
		(net "M_F_DQ<5>")
	)
	(segment
		(start 197.6882 -148.336)
		(end 197.558152 -148.466048)
		(width 0.14224)
		(layer "In11.Cu")
		(net "M_F_DQ<5>")
	)
	(segment
		(start 197.647052 -134.681468)
		(end 197.647052 -135.938768)
		(width 0.14224)
		(layer "In11.Cu")
		(net "M_F_DQ<5>")
	)
	(segment
		(start 197.6882 -143.5608)
		(end 197.583552 -143.665448)
		(width 0.14224)
		(layer "In11.Cu")
		(net "M_F_DQ<5>")
	)
	(segment
		(start 197.647052 -139.396978)
		(end 197.647052 -140.971778)
		(width 0.14224)
		(layer "In11.Cu")
		(net "M_F_DQ<5>")
	)
	(segment
		(start 197.583552 -143.665448)
		(end 197.583552 -144.271238)
		(width 0.14224)
		(layer "In11.Cu")
		(net "M_F_DQ<5>")
	)
	(segment
		(start 231.511348 -86.269068)
		(end 231.294686 -86.052406)
		(width 0.0889)
		(layer "In11.Cu")
		(net "M_F_DQ<5>")
	)
	(arc
		(start 236.982508 -84.117688)
		(mid 236.775504 -84.328552)
		(end 236.492288 -84.412836)
		(width 0.0889)
		(layer "In11.Cu")
		(net "M_F_DQ<5>")
	)
	(arc
		(start 238.699548 -83.127342)
		(mid 238.492544 -83.338206)
		(end 238.209328 -83.42249)
		(width 0.0889)
		(layer "In11.Cu")
		(net "M_F_DQ<5>")
	)
	(arc
		(start 234.406948 -85.603588)
		(mid 234.19834 -85.81552)
		(end 233.912918 -85.89899)
		(width 0.0889)
		(layer "In11.Cu")
		(net "M_F_DQ<5>")
	)
	(arc
		(start 232.689908 -86.594188)
		(mid 232.4813 -86.80612)
		(end 232.195878 -86.88959)
		(width 0.0889)
		(layer "In11.Cu")
		(net "M_F_DQ<5>")
	)
	(arc
		(start 233.548428 -86.098888)
		(mid 233.341424 -86.309752)
		(end 233.058208 -86.394036)
		(width 0.0889)
		(layer "In11.Cu")
		(net "M_F_DQ<5>")
	)
	(arc
		(start 233.880152 -85.89899)
		(mid 233.68851 -85.956156)
		(end 233.548428 -86.098888)
		(width 0.0889)
		(layer "In11.Cu")
		(net "M_F_DQ<5>")
	)
	(arc
		(start 236.459522 -84.412836)
		(mid 236.265672 -84.469186)
		(end 236.123988 -84.612988)
		(width 0.0889)
		(layer "In11.Cu")
		(net "M_F_DQ<5>")
	)
	(arc
		(start 241.110008 -84.117688)
		(mid 240.969929 -83.974952)
		(end 240.778284 -83.91779)
		(width 0.0889)
		(layer "In11.Cu")
		(net "M_F_DQ<5>")
	)
	(arc
		(start 235.597192 -84.90839)
		(mid 235.40555 -84.965556)
		(end 235.265468 -85.108288)
		(width 0.0889)
		(layer "In11.Cu")
		(net "M_F_DQ<5>")
	)
	(arc
		(start 240.251488 -83.622388)
		(mid 240.112744 -83.480355)
		(end 239.922812 -83.42249)
		(width 0.0889)
		(layer "In11.Cu")
		(net "M_F_DQ<5>")
	)
	(arc
		(start 239.392968 -83.127342)
		(mid 239.046258 -82.927031)
		(end 238.699548 -83.127342)
		(width 0.0889)
		(layer "In11.Cu")
		(net "M_F_DQ<5>")
	)
	(arc
		(start 240.745518 -83.91779)
		(mid 240.460094 -83.834323)
		(end 240.251488 -83.622388)
		(width 0.0889)
		(layer "In11.Cu")
		(net "M_F_DQ<5>")
	)
	(arc
		(start 233.025442 -86.394036)
		(mid 232.831592 -86.450386)
		(end 232.689908 -86.594188)
		(width 0.0889)
		(layer "In11.Cu")
		(net "M_F_DQ<5>")
	)
	(arc
		(start 236.123988 -84.612988)
		(mid 235.91538 -84.82492)
		(end 235.629958 -84.90839)
		(width 0.0889)
		(layer "In11.Cu")
		(net "M_F_DQ<5>")
	)
	(arc
		(start 237.841028 -83.622388)
		(mid 237.63242 -83.83432)
		(end 237.346998 -83.91779)
		(width 0.0889)
		(layer "In11.Cu")
		(net "M_F_DQ<5>")
	)
	(arc
		(start 235.265468 -85.108288)
		(mid 235.058464 -85.319152)
		(end 234.775248 -85.403436)
		(width 0.0889)
		(layer "In11.Cu")
		(net "M_F_DQ<5>")
	)
	(arc
		(start 239.883188 -83.42249)
		(mid 239.599971 -83.338209)
		(end 239.392968 -83.127342)
		(width 0.0889)
		(layer "In11.Cu")
		(net "M_F_DQ<5>")
	)
	(arc
		(start 238.169704 -83.42249)
		(mid 237.979775 -83.48036)
		(end 237.841028 -83.622388)
		(width 0.0889)
		(layer "In11.Cu")
		(net "M_F_DQ<5>")
	)
	(arc
		(start 234.742482 -85.403436)
		(mid 234.548632 -85.459786)
		(end 234.406948 -85.603588)
		(width 0.0889)
		(layer "In11.Cu")
		(net "M_F_DQ<5>")
	)
	(arc
		(start 237.314232 -83.91779)
		(mid 237.12259 -83.974956)
		(end 236.982508 -84.117688)
		(width 0.0889)
		(layer "In11.Cu")
		(net "M_F_DQ<5>")
	)
	(segment
		(start 315.400436 -152.273)
		(end 315.399928 -152.278842)
		(width 0.1651)
		(layer "F.Cu")
		(net "M_F_DQ<59>")
	)
	(segment
		(start 284.929834 -91.565984)
		(end 285.501334 -91.565984)
		(width 0.1651)
		(layer "F.Cu")
		(net "M_F_DQ<59>")
	)
	(segment
		(start 315.399928 -152.278842)
		(end 315.399928 -153.542746)
		(width 0.1651)
		(layer "F.Cu")
		(net "M_F_DQ<59>")
	)
	(via
		(at 315.399928 -153.542746)
		(size 0.508)
		(drill 0.254)
		(layers "F.Cu" "B.Cu")
		(net "M_F_DQ<59>")
	)
	(via
		(at 316.249812 -149.533356)
		(size 0.508)
		(drill 0.254)
		(layers "F.Cu" "B.Cu")
		(net "M_F_DQ<59>")
	)
	(via
		(at 285.501334 -91.565984)
		(size 0.508)
		(drill 0.254)
		(layers "F.Cu" "B.Cu")
		(net "M_F_DQ<59>")
	)
	(segment
		(start 316.25032 -147.478496)
		(end 316.249812 -147.478496)
		(width 0.1651)
		(layer "B.Cu")
		(net "M_F_DQ<59>")
	)
	(segment
		(start 316.249812 -147.478496)
		(end 316.249812 -149.533356)
		(width 0.1651)
		(layer "B.Cu")
		(net "M_F_DQ<59>")
	)
	(segment
		(start 315.843666 -150.435818)
		(end 315.843666 -151.1046)
		(width 0.14224)
		(layer "In11.Cu")
		(net "M_F_DQ<59>")
	)
	(segment
		(start 316.336934 -123.8758)
		(end 315.7728 -123.8758)
		(width 0.14224)
		(layer "In11.Cu")
		(net "M_F_DQ<59>")
	)
	(segment
		(start 287.203134 -92.956634)
		(end 287.2359 -92.956634)
		(width 0.0889)
		(layer "In11.Cu")
		(net "M_F_DQ<59>")
	)
	(segment
		(start 285.501334 -91.565984)
		(end 285.996888 -92.232734)
		(width 0.0889)
		(layer "In11.Cu")
		(net "M_F_DQ<59>")
	)
	(segment
		(start 316.438534 -129.202942)
		(end 316.604396 -129.368804)
		(width 0.14224)
		(layer "In11.Cu")
		(net "M_F_DQ<59>")
	)
	(segment
		(start 297.601132 -106.073956)
		(end 297.601132 -106.292904)
		(width 0.14224)
		(layer "In11.Cu")
		(net "M_F_DQ<59>")
	)
	(segment
		(start 315.850016 -153.04135)
		(end 315.850016 -153.364946)
		(width 0.14224)
		(layer "In11.Cu")
		(net "M_F_DQ<59>")
	)
	(segment
		(start 292.358064 -101.872288)
		(end 292.556184 -101.872288)
		(width 0.0889)
		(layer "In11.Cu")
		(net "M_F_DQ<59>")
	)
	(segment
		(start 315.561218 -152.479248)
		(end 315.561218 -152.752552)
		(width 0.14224)
		(layer "In11.Cu")
		(net "M_F_DQ<59>")
	)
	(segment
		(start 315.7728 -123.8758)
		(end 315.6458 -124.0028)
		(width 0.14224)
		(layer "In11.Cu")
		(net "M_F_DQ<59>")
	)
	(segment
		(start 285.996888 -92.232734)
		(end 286.016446 -92.267278)
		(width 0.0889)
		(layer "In11.Cu")
		(net "M_F_DQ<59>")
	)
	(segment
		(start 296.407332 -104.454452)
		(end 296.62628 -104.454452)
		(width 0.14224)
		(layer "In11.Cu")
		(net "M_F_DQ<59>")
	)
	(segment
		(start 316.617096 -131.408678)
		(end 316.617096 -134.573264)
		(width 0.14224)
		(layer "In11.Cu")
		(net "M_F_DQ<59>")
	)
	(segment
		(start 297.589448 -105.39222)
		(end 297.813984 -105.616756)
		(width 0.14224)
		(layer "In11.Cu")
		(net "M_F_DQ<59>")
	)
	(segment
		(start 297.813984 -105.861104)
		(end 297.601132 -106.073956)
		(width 0.14224)
		(layer "In11.Cu")
		(net "M_F_DQ<59>")
	)
	(segment
		(start 315.799216 -149.9616)
		(end 315.799216 -150.391368)
		(width 0.14224)
		(layer "In11.Cu")
		(net "M_F_DQ<59>")
	)
	(segment
		(start 293.217346 -102.845362)
		(end 294.15359 -102.845362)
		(width 0.14224)
		(layer "In11.Cu")
		(net "M_F_DQ<59>")
	)
	(segment
		(start 295.975532 -104.667304)
		(end 296.19448 -104.667304)
		(width 0.14224)
		(layer "In11.Cu")
		(net "M_F_DQ<59>")
	)
	(segment
		(start 292.791134 -102.107238)
		(end 292.791134 -102.762812)
		(width 0.0889)
		(layer "In11.Cu")
		(net "M_F_DQ<59>")
	)
	(segment
		(start 316.782196 -136.023604)
		(end 316.604396 -136.201404)
		(width 0.14224)
		(layer "In11.Cu")
		(net "M_F_DQ<59>")
	)
	(segment
		(start 296.876216 -104.923336)
		(end 296.663364 -105.136188)
		(width 0.14224)
		(layer "In11.Cu")
		(net "M_F_DQ<59>")
	)
	(segment
		(start 316.756796 -130.041142)
		(end 316.756796 -131.268978)
		(width 0.14224)
		(layer "In11.Cu")
		(net "M_F_DQ<59>")
	)
	(segment
		(start 316.832996 -145.599404)
		(end 316.578996 -145.853404)
		(width 0.14224)
		(layer "In11.Cu")
		(net "M_F_DQ<59>")
	)
	(segment
		(start 316.617096 -141.009878)
		(end 316.617096 -144.182338)
		(width 0.14224)
		(layer "In11.Cu")
		(net "M_F_DQ<59>")
	)
	(segment
		(start 288.065464 -93.452188)
		(end 288.09823 -93.452188)
		(width 0.0889)
		(layer "In11.Cu")
		(net "M_F_DQ<59>")
	)
	(segment
		(start 315.818266 -152.2222)
		(end 315.561218 -152.479248)
		(width 0.14224)
		(layer "In11.Cu")
		(net "M_F_DQ<59>")
	)
	(segment
		(start 297.601132 -106.292904)
		(end 300.133766 -108.825538)
		(width 0.14224)
		(layer "In11.Cu")
		(net "M_F_DQ<59>")
	)
	(segment
		(start 290.634166 -94.937834)
		(end 290.67379 -94.937834)
		(width 0.0889)
		(layer "In11.Cu")
		(net "M_F_DQ<59>")
	)
	(segment
		(start 316.249812 -149.533356)
		(end 316.22746 -149.533356)
		(width 0.14224)
		(layer "In11.Cu")
		(net "M_F_DQ<59>")
	)
	(segment
		(start 316.782196 -134.738364)
		(end 316.782196 -136.023604)
		(width 0.14224)
		(layer "In11.Cu")
		(net "M_F_DQ<59>")
	)
	(segment
		(start 291.159184 -100.1776)
		(end 291.16401 -100.186236)
		(width 0.0889)
		(layer "In11.Cu")
		(net "M_F_DQ<59>")
	)
	(segment
		(start 316.604396 -129.368804)
		(end 316.604396 -129.888742)
		(width 0.14224)
		(layer "In11.Cu")
		(net "M_F_DQ<59>")
	)
	(segment
		(start 291.17036 -100.766118)
		(end 291.16401 -100.776786)
		(width 0.0889)
		(layer "In11.Cu")
		(net "M_F_DQ<59>")
	)
	(segment
		(start 291.159184 -96.2152)
		(end 291.16401 -96.223836)
		(width 0.0889)
		(layer "In11.Cu")
		(net "M_F_DQ<59>")
	)
	(segment
		(start 316.31128 -124.6124)
		(end 316.438534 -124.739654)
		(width 0.14224)
		(layer "In11.Cu")
		(net "M_F_DQ<59>")
	)
	(segment
		(start 316.756796 -131.268978)
		(end 316.617096 -131.408678)
		(width 0.14224)
		(layer "In11.Cu")
		(net "M_F_DQ<59>")
	)
	(segment
		(start 315.818266 -151.9174)
		(end 315.818266 -152.2222)
		(width 0.14224)
		(layer "In11.Cu")
		(net "M_F_DQ<59>")
	)
	(segment
		(start 316.604396 -139.562078)
		(end 316.756796 -139.714478)
		(width 0.14224)
		(layer "In11.Cu")
		(net "M_F_DQ<59>")
	)
	(segment
		(start 291.499544 -101.376734)
		(end 291.5285 -101.376734)
		(width 0.0889)
		(layer "In11.Cu")
		(net "M_F_DQ<59>")
	)
	(segment
		(start 296.663364 -105.136188)
		(end 296.663364 -105.355136)
		(width 0.14224)
		(layer "In11.Cu")
		(net "M_F_DQ<59>")
	)
	(segment
		(start 316.604396 -129.888742)
		(end 316.756796 -130.041142)
		(width 0.14224)
		(layer "In11.Cu")
		(net "M_F_DQ<59>")
	)
	(segment
		(start 292.873684 -102.845362)
		(end 293.217346 -102.845362)
		(width 0.0889)
		(layer "In11.Cu")
		(net "M_F_DQ<59>")
	)
	(segment
		(start 289.775646 -94.442534)
		(end 289.81146 -94.442534)
		(width 0.0889)
		(layer "In11.Cu")
		(net "M_F_DQ<59>")
	)
	(segment
		(start 315.561218 -151.660352)
		(end 315.818266 -151.9174)
		(width 0.14224)
		(layer "In11.Cu")
		(net "M_F_DQ<59>")
	)
	(segment
		(start 297.813984 -105.616756)
		(end 297.813984 -105.861104)
		(width 0.14224)
		(layer "In11.Cu")
		(net "M_F_DQ<59>")
	)
	(segment
		(start 297.132248 -105.605072)
		(end 297.3451 -105.39222)
		(width 0.14224)
		(layer "In11.Cu")
		(net "M_F_DQ<59>")
	)
	(segment
		(start 316.438534 -123.386596)
		(end 316.438534 -123.7742)
		(width 0.14224)
		(layer "In11.Cu")
		(net "M_F_DQ<59>")
	)
	(segment
		(start 316.22746 -149.533356)
		(end 315.799216 -149.9616)
		(width 0.14224)
		(layer "In11.Cu")
		(net "M_F_DQ<59>")
	)
	(segment
		(start 316.578996 -149.21738)
		(end 316.249812 -149.546564)
		(width 0.14224)
		(layer "In11.Cu")
		(net "M_F_DQ<59>")
	)
	(segment
		(start 315.6458 -124.0028)
		(end 315.6458 -124.4092)
		(width 0.14224)
		(layer "In11.Cu")
		(net "M_F_DQ<59>")
	)
	(segment
		(start 316.617096 -144.182338)
		(end 316.832996 -144.398238)
		(width 0.14224)
		(layer "In11.Cu")
		(net "M_F_DQ<59>")
	)
	(segment
		(start 316.438534 -123.7742)
		(end 316.336934 -123.8758)
		(width 0.14224)
		(layer "In11.Cu")
		(net "M_F_DQ<59>")
	)
	(segment
		(start 315.799216 -150.391368)
		(end 315.843666 -150.435818)
		(width 0.14224)
		(layer "In11.Cu")
		(net "M_F_DQ<59>")
	)
	(segment
		(start 291.16401 -96.223836)
		(end 291.17036 -96.234504)
		(width 0.0889)
		(layer "In11.Cu")
		(net "M_F_DQ<59>")
	)
	(segment
		(start 292.791134 -102.762812)
		(end 292.873684 -102.845362)
		(width 0.0889)
		(layer "In11.Cu")
		(net "M_F_DQ<59>")
	)
	(segment
		(start 315.849 -124.6124)
		(end 316.31128 -124.6124)
		(width 0.14224)
		(layer "In11.Cu")
		(net "M_F_DQ<59>")
	)
	(segment
		(start 296.62628 -104.454452)
		(end 296.876216 -104.704388)
		(width 0.14224)
		(layer "In11.Cu")
		(net "M_F_DQ<59>")
	)
	(segment
		(start 316.756796 -140.870178)
		(end 316.617096 -141.009878)
		(width 0.14224)
		(layer "In11.Cu")
		(net "M_F_DQ<59>")
	)
	(segment
		(start 316.832996 -144.398238)
		(end 316.832996 -145.599404)
		(width 0.14224)
		(layer "In11.Cu")
		(net "M_F_DQ<59>")
	)
	(segment
		(start 296.663364 -105.355136)
		(end 296.9133 -105.605072)
		(width 0.14224)
		(layer "In11.Cu")
		(net "M_F_DQ<59>")
	)
	(segment
		(start 316.756796 -139.714478)
		(end 316.756796 -140.870178)
		(width 0.14224)
		(layer "In11.Cu")
		(net "M_F_DQ<59>")
	)
	(segment
		(start 301.877476 -108.825538)
		(end 316.438534 -123.386596)
		(width 0.14224)
		(layer "In11.Cu")
		(net "M_F_DQ<59>")
	)
	(segment
		(start 296.19448 -104.667304)
		(end 296.407332 -104.454452)
		(width 0.14224)
		(layer "In11.Cu")
		(net "M_F_DQ<59>")
	)
	(segment
		(start 286.3596 -92.461588)
		(end 286.38119 -92.461588)
		(width 0.0889)
		(layer "In11.Cu")
		(net "M_F_DQ<59>")
	)
	(segment
		(start 300.133766 -108.825538)
		(end 301.877476 -108.825538)
		(width 0.14224)
		(layer "In11.Cu")
		(net "M_F_DQ<59>")
	)
	(segment
		(start 315.561218 -152.752552)
		(end 315.850016 -153.04135)
		(width 0.14224)
		(layer "In11.Cu")
		(net "M_F_DQ<59>")
	)
	(segment
		(start 316.438534 -124.739654)
		(end 316.438534 -129.202942)
		(width 0.14224)
		(layer "In11.Cu")
		(net "M_F_DQ<59>")
	)
	(segment
		(start 316.604396 -136.201404)
		(end 316.604396 -139.562078)
		(width 0.14224)
		(layer "In11.Cu")
		(net "M_F_DQ<59>")
	)
	(segment
		(start 315.561218 -151.387048)
		(end 315.561218 -151.660352)
		(width 0.14224)
		(layer "In11.Cu")
		(net "M_F_DQ<59>")
	)
	(segment
		(start 291.16401 -99.195636)
		(end 291.17036 -99.206304)
		(width 0.0889)
		(layer "In11.Cu")
		(net "M_F_DQ<59>")
	)
	(segment
		(start 296.876216 -104.704388)
		(end 296.876216 -104.923336)
		(width 0.14224)
		(layer "In11.Cu")
		(net "M_F_DQ<59>")
	)
	(segment
		(start 315.850016 -153.364946)
		(end 315.672216 -153.542746)
		(width 0.14224)
		(layer "In11.Cu")
		(net "M_F_DQ<59>")
	)
	(segment
		(start 316.249812 -149.546564)
		(end 316.249812 -149.533356)
		(width 0.14224)
		(layer "In11.Cu")
		(net "M_F_DQ<59>")
	)
	(segment
		(start 296.9133 -105.605072)
		(end 297.132248 -105.605072)
		(width 0.14224)
		(layer "In11.Cu")
		(net "M_F_DQ<59>")
	)
	(segment
		(start 316.578996 -145.853404)
		(end 316.578996 -149.21738)
		(width 0.14224)
		(layer "In11.Cu")
		(net "M_F_DQ<59>")
	)
	(segment
		(start 316.617096 -134.573264)
		(end 316.782196 -134.738364)
		(width 0.14224)
		(layer "In11.Cu")
		(net "M_F_DQ<59>")
	)
	(segment
		(start 288.920174 -93.947234)
		(end 288.948114 -93.947234)
		(width 0.0889)
		(layer "In11.Cu")
		(net "M_F_DQ<59>")
	)
	(segment
		(start 315.843666 -151.1046)
		(end 315.561218 -151.387048)
		(width 0.14224)
		(layer "In11.Cu")
		(net "M_F_DQ<59>")
	)
	(segment
		(start 315.672216 -153.542746)
		(end 315.399928 -153.542746)
		(width 0.14224)
		(layer "In11.Cu")
		(net "M_F_DQ<59>")
	)
	(segment
		(start 297.3451 -105.39222)
		(end 297.589448 -105.39222)
		(width 0.14224)
		(layer "In11.Cu")
		(net "M_F_DQ<59>")
	)
	(segment
		(start 292.556184 -101.872288)
		(end 292.791134 -102.107238)
		(width 0.0889)
		(layer "In11.Cu")
		(net "M_F_DQ<59>")
	)
	(segment
		(start 294.15359 -102.845362)
		(end 295.975532 -104.667304)
		(width 0.14224)
		(layer "In11.Cu")
		(net "M_F_DQ<59>")
	)
	(segment
		(start 315.6458 -124.4092)
		(end 315.849 -124.6124)
		(width 0.14224)
		(layer "In11.Cu")
		(net "M_F_DQ<59>")
	)
	(arc
		(start 289.81146 -94.442534)
		(mid 290.096884 -94.526001)
		(end 290.30549 -94.737936)
		(width 0.0889)
		(layer "In11.Cu")
		(net "M_F_DQ<59>")
	)
	(arc
		(start 291.16401 -99.786186)
		(mid 291.11054 -99.981249)
		(end 291.159184 -100.1776)
		(width 0.0889)
		(layer "In11.Cu")
		(net "M_F_DQ<59>")
	)
	(arc
		(start 286.38119 -92.461588)
		(mid 286.664407 -92.545869)
		(end 286.87141 -92.756736)
		(width 0.0889)
		(layer "In11.Cu")
		(net "M_F_DQ<59>")
	)
	(arc
		(start 291.17036 -96.234504)
		(mid 291.243216 -96.525665)
		(end 291.16401 -96.815148)
		(width 0.0889)
		(layer "In11.Cu")
		(net "M_F_DQ<59>")
	)
	(arc
		(start 292.02253 -101.672136)
		(mid 292.164213 -101.81594)
		(end 292.358064 -101.872288)
		(width 0.0889)
		(layer "In11.Cu")
		(net "M_F_DQ<59>")
	)
	(arc
		(start 286.87141 -92.756736)
		(mid 287.011489 -92.899472)
		(end 287.203134 -92.956634)
		(width 0.0889)
		(layer "In11.Cu")
		(net "M_F_DQ<59>")
	)
	(arc
		(start 291.16401 -95.823786)
		(mid 291.11054 -96.018849)
		(end 291.159184 -96.2152)
		(width 0.0889)
		(layer "In11.Cu")
		(net "M_F_DQ<59>")
	)
	(arc
		(start 287.2359 -92.956634)
		(mid 287.521324 -93.040101)
		(end 287.72993 -93.252036)
		(width 0.0889)
		(layer "In11.Cu")
		(net "M_F_DQ<59>")
	)
	(arc
		(start 287.72993 -93.252036)
		(mid 287.871613 -93.39584)
		(end 288.065464 -93.452188)
		(width 0.0889)
		(layer "In11.Cu")
		(net "M_F_DQ<59>")
	)
	(arc
		(start 290.30549 -94.737936)
		(mid 290.444234 -94.879969)
		(end 290.634166 -94.937834)
		(width 0.0889)
		(layer "In11.Cu")
		(net "M_F_DQ<59>")
	)
	(arc
		(start 288.948114 -93.947234)
		(mid 289.236259 -94.029553)
		(end 289.44697 -94.242636)
		(width 0.0889)
		(layer "In11.Cu")
		(net "M_F_DQ<59>")
	)
	(arc
		(start 291.16401 -96.815148)
		(mid 291.110511 -97.015046)
		(end 291.16401 -97.214944)
		(width 0.0889)
		(layer "In11.Cu")
		(net "M_F_DQ<59>")
	)
	(arc
		(start 291.16401 -97.805748)
		(mid 291.110511 -98.005646)
		(end 291.16401 -98.205544)
		(width 0.0889)
		(layer "In11.Cu")
		(net "M_F_DQ<59>")
	)
	(arc
		(start 288.58845 -93.747336)
		(mid 288.728529 -93.890072)
		(end 288.920174 -93.947234)
		(width 0.0889)
		(layer "In11.Cu")
		(net "M_F_DQ<59>")
	)
	(arc
		(start 291.16401 -100.186236)
		(mid 291.243232 -100.475354)
		(end 291.17036 -100.766118)
		(width 0.0889)
		(layer "In11.Cu")
		(net "M_F_DQ<59>")
	)
	(arc
		(start 291.16401 -98.205544)
		(mid 291.243141 -98.500946)
		(end 291.16401 -98.796348)
		(width 0.0889)
		(layer "In11.Cu")
		(net "M_F_DQ<59>")
	)
	(arc
		(start 291.16401 -97.214944)
		(mid 291.243141 -97.510346)
		(end 291.16401 -97.805748)
		(width 0.0889)
		(layer "In11.Cu")
		(net "M_F_DQ<59>")
	)
	(arc
		(start 291.16401 -98.796348)
		(mid 291.110536 -98.995992)
		(end 291.16401 -99.195636)
		(width 0.0889)
		(layer "In11.Cu")
		(net "M_F_DQ<59>")
	)
	(arc
		(start 286.016446 -92.267278)
		(mid 286.162412 -92.409677)
		(end 286.3596 -92.461588)
		(width 0.0889)
		(layer "In11.Cu")
		(net "M_F_DQ<59>")
	)
	(arc
		(start 290.67379 -94.937834)
		(mid 291.169267 -95.242277)
		(end 291.16401 -95.823786)
		(width 0.0889)
		(layer "In11.Cu")
		(net "M_F_DQ<59>")
	)
	(arc
		(start 291.16401 -100.776786)
		(mid 291.161427 -101.172033)
		(end 291.499544 -101.376734)
		(width 0.0889)
		(layer "In11.Cu")
		(net "M_F_DQ<59>")
	)
	(arc
		(start 291.5285 -101.376734)
		(mid 291.813924 -101.460201)
		(end 292.02253 -101.672136)
		(width 0.0889)
		(layer "In11.Cu")
		(net "M_F_DQ<59>")
	)
	(arc
		(start 289.44697 -94.242636)
		(mid 289.585714 -94.384669)
		(end 289.775646 -94.442534)
		(width 0.0889)
		(layer "In11.Cu")
		(net "M_F_DQ<59>")
	)
	(arc
		(start 288.09823 -93.452188)
		(mid 288.381447 -93.536469)
		(end 288.58845 -93.747336)
		(width 0.0889)
		(layer "In11.Cu")
		(net "M_F_DQ<59>")
	)
	(arc
		(start 291.17036 -99.206304)
		(mid 291.243158 -99.497067)
		(end 291.16401 -99.786186)
		(width 0.0889)
		(layer "In11.Cu")
		(net "M_F_DQ<59>")
	)
	(segment
		(start 316.249812 -155.395168)
		(end 316.249812 -155.1178)
		(width 0.1651)
		(layer "F.Cu")
		(net "M_F_DQ<58>")
	)
	(segment
		(start 316.381384 -155.52674)
		(end 316.249812 -155.395168)
		(width 0.1651)
		(layer "F.Cu")
		(net "M_F_DQ<58>")
	)
	(segment
		(start 316.25032 -156.87294)
		(end 316.249812 -156.87294)
		(width 0.1651)
		(layer "F.Cu")
		(net "M_F_DQ<58>")
	)
	(segment
		(start 284.929834 -90.575384)
		(end 285.501334 -90.575384)
		(width 0.1651)
		(layer "F.Cu")
		(net "M_F_DQ<58>")
	)
	(segment
		(start 316.249812 -156.87294)
		(end 316.249812 -155.881832)
		(width 0.1651)
		(layer "F.Cu")
		(net "M_F_DQ<58>")
	)
	(segment
		(start 316.381384 -155.75026)
		(end 316.381384 -155.52674)
		(width 0.1651)
		(layer "F.Cu")
		(net "M_F_DQ<58>")
	)
	(segment
		(start 316.249812 -155.881832)
		(end 316.381384 -155.75026)
		(width 0.1651)
		(layer "F.Cu")
		(net "M_F_DQ<58>")
	)
	(via
		(at 285.501334 -90.575384)
		(size 0.508)
		(drill 0.254)
		(layers "F.Cu" "B.Cu")
		(net "M_F_DQ<58>")
	)
	(via
		(at 316.249812 -155.1178)
		(size 0.508)
		(drill 0.254)
		(layers "F.Cu" "B.Cu")
		(net "M_F_DQ<58>")
	)
	(via
		(at 315.399928 -150.814278)
		(size 0.508)
		(drill 0.254)
		(layers "F.Cu" "B.Cu")
		(net "M_F_DQ<58>")
	)
	(segment
		(start 315.399928 -152.078182)
		(end 315.399928 -150.814278)
		(width 0.1651)
		(layer "B.Cu")
		(net "M_F_DQ<58>")
	)
	(segment
		(start 315.400436 -152.078436)
		(end 315.399928 -152.078182)
		(width 0.1651)
		(layer "B.Cu")
		(net "M_F_DQ<58>")
	)
	(segment
		(start 293.86276 -103.3526)
		(end 299.903388 -109.393228)
		(width 0.14224)
		(layer "In11.Cu")
		(net "M_F_DQ<58>")
	)
	(segment
		(start 315.686694 -140.854176)
		(end 315.927486 -141.094968)
		(width 0.14224)
		(layer "In11.Cu")
		(net "M_F_DQ<58>")
	)
	(segment
		(start 315.927486 -144.135348)
		(end 315.657992 -144.404842)
		(width 0.14224)
		(layer "In11.Cu")
		(net "M_F_DQ<58>")
	)
	(segment
		(start 285.844488 -92.350844)
		(end 285.84779 -92.356686)
		(width 0.0889)
		(layer "In11.Cu")
		(net "M_F_DQ<58>")
	)
	(segment
		(start 289.77209 -94.633288)
		(end 289.811714 -94.633288)
		(width 0.0889)
		(layer "In11.Cu")
		(net "M_F_DQ<58>")
	)
	(segment
		(start 315.885068 -149.006306)
		(end 315.289184 -149.60219)
		(width 0.14224)
		(layer "In11.Cu")
		(net "M_F_DQ<58>")
	)
	(segment
		(start 286.34182 -92.652088)
		(end 286.374586 -92.652088)
		(width 0.0889)
		(layer "In11.Cu")
		(net "M_F_DQ<58>")
	)
	(segment
		(start 315.399928 -150.814278)
		(end 314.966858 -151.247348)
		(width 0.14224)
		(layer "In11.Cu")
		(net "M_F_DQ<58>")
	)
	(segment
		(start 314.966858 -151.247348)
		(end 314.966858 -153.834846)
		(width 0.14224)
		(layer "In11.Cu")
		(net "M_F_DQ<58>")
	)
	(segment
		(start 315.927486 -141.094968)
		(end 315.927486 -144.135348)
		(width 0.14224)
		(layer "In11.Cu")
		(net "M_F_DQ<58>")
	)
	(segment
		(start 285.501334 -90.575384)
		(end 285.006288 -91.241372)
		(width 0.0889)
		(layer "In11.Cu")
		(net "M_F_DQ<58>")
	)
	(segment
		(start 315.289184 -150.703534)
		(end 315.399928 -150.814278)
		(width 0.14224)
		(layer "In11.Cu")
		(net "M_F_DQ<58>")
	)
	(segment
		(start 290.99891 -100.681536)
		(end 290.99256 -100.692204)
		(width 0.0889)
		(layer "In11.Cu")
		(net "M_F_DQ<58>")
	)
	(segment
		(start 315.105796 -122.792236)
		(end 315.105796 -124.732796)
		(width 0.14224)
		(layer "In11.Cu")
		(net "M_F_DQ<58>")
	)
	(segment
		(start 290.63442 -95.128588)
		(end 290.670234 -95.128588)
		(width 0.0889)
		(layer "In11.Cu")
		(net "M_F_DQ<58>")
	)
	(segment
		(start 292.600634 -102.186232)
		(end 292.600634 -102.841806)
		(width 0.0889)
		(layer "In11.Cu")
		(net "M_F_DQ<58>")
	)
	(segment
		(start 314.966858 -153.834846)
		(end 316.249812 -155.1178)
		(width 0.14224)
		(layer "In11.Cu")
		(net "M_F_DQ<58>")
	)
	(segment
		(start 292.749986 -103.312722)
		(end 292.789864 -103.3526)
		(width 0.14224)
		(layer "In11.Cu")
		(net "M_F_DQ<58>")
	)
	(segment
		(start 315.94933 -136.227566)
		(end 315.94933 -139.378944)
		(width 0.14224)
		(layer "In11.Cu")
		(net "M_F_DQ<58>")
	)
	(segment
		(start 292.35146 -102.062788)
		(end 292.47719 -102.062788)
		(width 0.0889)
		(layer "In11.Cu")
		(net "M_F_DQ<58>")
	)
	(segment
		(start 292.749986 -102.991158)
		(end 292.749986 -103.312722)
		(width 0.0889)
		(layer "In11.Cu")
		(net "M_F_DQ<58>")
	)
	(segment
		(start 292.600634 -102.841806)
		(end 292.749986 -102.991158)
		(width 0.0889)
		(layer "In11.Cu")
		(net "M_F_DQ<58>")
	)
	(segment
		(start 315.893196 -129.833878)
		(end 315.6966 -130.030474)
		(width 0.14224)
		(layer "In11.Cu")
		(net "M_F_DQ<58>")
	)
	(segment
		(start 284.989524 -91.270836)
		(end 284.983174 -91.281504)
		(width 0.0889)
		(layer "In11.Cu")
		(net "M_F_DQ<58>")
	)
	(segment
		(start 292.789864 -103.3526)
		(end 293.86276 -103.3526)
		(width 0.14224)
		(layer "In11.Cu")
		(net "M_F_DQ<58>")
	)
	(segment
		(start 288.922206 -94.137988)
		(end 288.946336 -94.137988)
		(width 0.0889)
		(layer "In11.Cu")
		(net "M_F_DQ<58>")
	)
	(segment
		(start 315.657992 -145.546064)
		(end 315.885068 -145.77314)
		(width 0.14224)
		(layer "In11.Cu")
		(net "M_F_DQ<58>")
	)
	(segment
		(start 315.6585 -134.79526)
		(end 315.6585 -135.936736)
		(width 0.14224)
		(layer "In11.Cu")
		(net "M_F_DQ<58>")
	)
	(segment
		(start 315.686694 -139.64158)
		(end 315.686694 -140.854176)
		(width 0.14224)
		(layer "In11.Cu")
		(net "M_F_DQ<58>")
	)
	(segment
		(start 315.893196 -125.520196)
		(end 315.893196 -129.833878)
		(width 0.14224)
		(layer "In11.Cu")
		(net "M_F_DQ<58>")
	)
	(segment
		(start 301.706788 -109.393228)
		(end 315.105796 -122.792236)
		(width 0.14224)
		(layer "In11.Cu")
		(net "M_F_DQ<58>")
	)
	(segment
		(start 315.992002 -131.460748)
		(end 315.992002 -134.461758)
		(width 0.14224)
		(layer "In11.Cu")
		(net "M_F_DQ<58>")
	)
	(segment
		(start 315.105796 -124.732796)
		(end 315.893196 -125.520196)
		(width 0.14224)
		(layer "In11.Cu")
		(net "M_F_DQ<58>")
	)
	(segment
		(start 285.479744 -92.156534)
		(end 285.501334 -92.156534)
		(width 0.0889)
		(layer "In11.Cu")
		(net "M_F_DQ<58>")
	)
	(segment
		(start 292.47719 -102.062788)
		(end 292.600634 -102.186232)
		(width 0.0889)
		(layer "In11.Cu")
		(net "M_F_DQ<58>")
	)
	(segment
		(start 299.903388 -109.393228)
		(end 301.706788 -109.393228)
		(width 0.14224)
		(layer "In11.Cu")
		(net "M_F_DQ<58>")
	)
	(segment
		(start 285.006288 -91.241372)
		(end 284.989524 -91.270836)
		(width 0.0889)
		(layer "In11.Cu")
		(net "M_F_DQ<58>")
	)
	(segment
		(start 291.48913 -101.567234)
		(end 291.521896 -101.567234)
		(width 0.0889)
		(layer "In11.Cu")
		(net "M_F_DQ<58>")
	)
	(segment
		(start 315.94933 -139.378944)
		(end 315.686694 -139.64158)
		(width 0.14224)
		(layer "In11.Cu")
		(net "M_F_DQ<58>")
	)
	(segment
		(start 287.19653 -93.147134)
		(end 287.229296 -93.147134)
		(width 0.0889)
		(layer "In11.Cu")
		(net "M_F_DQ<58>")
	)
	(segment
		(start 315.6585 -135.936736)
		(end 315.94933 -136.227566)
		(width 0.14224)
		(layer "In11.Cu")
		(net "M_F_DQ<58>")
	)
	(segment
		(start 315.6966 -130.030474)
		(end 315.6966 -131.165346)
		(width 0.14224)
		(layer "In11.Cu")
		(net "M_F_DQ<58>")
	)
	(segment
		(start 315.885068 -145.77314)
		(end 315.885068 -149.006306)
		(width 0.14224)
		(layer "In11.Cu")
		(net "M_F_DQ<58>")
	)
	(segment
		(start 315.657992 -144.404842)
		(end 315.657992 -145.546064)
		(width 0.14224)
		(layer "In11.Cu")
		(net "M_F_DQ<58>")
	)
	(segment
		(start 315.992002 -134.461758)
		(end 315.6585 -134.79526)
		(width 0.14224)
		(layer "In11.Cu")
		(net "M_F_DQ<58>")
	)
	(segment
		(start 315.289184 -149.60219)
		(end 315.289184 -150.703534)
		(width 0.14224)
		(layer "In11.Cu")
		(net "M_F_DQ<58>")
	)
	(segment
		(start 288.05886 -93.642688)
		(end 288.091626 -93.642688)
		(width 0.0889)
		(layer "In11.Cu")
		(net "M_F_DQ<58>")
	)
	(segment
		(start 315.6966 -131.165346)
		(end 315.992002 -131.460748)
		(width 0.14224)
		(layer "In11.Cu")
		(net "M_F_DQ<58>")
	)
	(segment
		(start 290.99256 -96.308418)
		(end 290.99891 -96.319086)
		(width 0.0889)
		(layer "In11.Cu")
		(net "M_F_DQ<58>")
	)
	(arc
		(start 285.501334 -92.156534)
		(mid 285.698495 -92.208493)
		(end 285.844488 -92.350844)
		(width 0.0889)
		(layer "In11.Cu")
		(net "M_F_DQ<58>")
	)
	(arc
		(start 290.99891 -100.28174)
		(mid 291.052409 -100.481638)
		(end 290.99891 -100.681536)
		(width 0.0889)
		(layer "In11.Cu")
		(net "M_F_DQ<58>")
	)
	(arc
		(start 286.70631 -92.851986)
		(mid 286.913314 -93.06285)
		(end 287.19653 -93.147134)
		(width 0.0889)
		(layer "In11.Cu")
		(net "M_F_DQ<58>")
	)
	(arc
		(start 291.003736 -99.299522)
		(mid 291.052491 -99.495874)
		(end 290.99891 -99.690936)
		(width 0.0889)
		(layer "In11.Cu")
		(net "M_F_DQ<58>")
	)
	(arc
		(start 290.99891 -95.728536)
		(mid 290.919688 -96.017654)
		(end 290.99256 -96.308418)
		(width 0.0889)
		(layer "In11.Cu")
		(net "M_F_DQ<58>")
	)
	(arc
		(start 288.091626 -93.642688)
		(mid 288.283268 -93.699854)
		(end 288.42335 -93.842586)
		(width 0.0889)
		(layer "In11.Cu")
		(net "M_F_DQ<58>")
	)
	(arc
		(start 290.99891 -98.700844)
		(mid 290.919959 -99.000827)
		(end 291.003736 -99.299522)
		(width 0.0889)
		(layer "In11.Cu")
		(net "M_F_DQ<58>")
	)
	(arc
		(start 290.99891 -96.719644)
		(mid 290.919779 -97.015046)
		(end 290.99891 -97.310448)
		(width 0.0889)
		(layer "In11.Cu")
		(net "M_F_DQ<58>")
	)
	(arc
		(start 284.983174 -91.281504)
		(mid 284.987205 -91.857686)
		(end 285.479744 -92.156534)
		(width 0.0889)
		(layer "In11.Cu")
		(net "M_F_DQ<58>")
	)
	(arc
		(start 286.374586 -92.652088)
		(mid 286.566228 -92.709254)
		(end 286.70631 -92.851986)
		(width 0.0889)
		(layer "In11.Cu")
		(net "M_F_DQ<58>")
	)
	(arc
		(start 290.99891 -97.710244)
		(mid 290.919779 -98.005646)
		(end 290.99891 -98.301048)
		(width 0.0889)
		(layer "In11.Cu")
		(net "M_F_DQ<58>")
	)
	(arc
		(start 291.85743 -101.767386)
		(mid 292.066038 -101.979318)
		(end 292.35146 -102.062788)
		(width 0.0889)
		(layer "In11.Cu")
		(net "M_F_DQ<58>")
	)
	(arc
		(start 290.99891 -96.319086)
		(mid 291.052629 -96.519382)
		(end 290.99891 -96.719644)
		(width 0.0889)
		(layer "In11.Cu")
		(net "M_F_DQ<58>")
	)
	(arc
		(start 290.99256 -100.692204)
		(mid 290.996591 -101.268386)
		(end 291.48913 -101.567234)
		(width 0.0889)
		(layer "In11.Cu")
		(net "M_F_DQ<58>")
	)
	(arc
		(start 290.670234 -95.128588)
		(mid 291.003203 -95.336136)
		(end 290.99891 -95.728536)
		(width 0.0889)
		(layer "In11.Cu")
		(net "M_F_DQ<58>")
	)
	(arc
		(start 289.28187 -94.33814)
		(mid 289.488874 -94.549004)
		(end 289.77209 -94.633288)
		(width 0.0889)
		(layer "In11.Cu")
		(net "M_F_DQ<58>")
	)
	(arc
		(start 290.14039 -94.833186)
		(mid 290.348998 -95.045118)
		(end 290.63442 -95.128588)
		(width 0.0889)
		(layer "In11.Cu")
		(net "M_F_DQ<58>")
	)
	(arc
		(start 287.56483 -93.347286)
		(mid 287.773438 -93.559218)
		(end 288.05886 -93.642688)
		(width 0.0889)
		(layer "In11.Cu")
		(net "M_F_DQ<58>")
	)
	(arc
		(start 290.99891 -97.310448)
		(mid 291.052409 -97.510346)
		(end 290.99891 -97.710244)
		(width 0.0889)
		(layer "In11.Cu")
		(net "M_F_DQ<58>")
	)
	(arc
		(start 290.99891 -99.690936)
		(mid 290.919779 -99.986338)
		(end 290.99891 -100.28174)
		(width 0.0889)
		(layer "In11.Cu")
		(net "M_F_DQ<58>")
	)
	(arc
		(start 288.42335 -93.842586)
		(mid 288.634063 -94.055665)
		(end 288.922206 -94.137988)
		(width 0.0889)
		(layer "In11.Cu")
		(net "M_F_DQ<58>")
	)
	(arc
		(start 287.229296 -93.147134)
		(mid 287.423146 -93.203484)
		(end 287.56483 -93.347286)
		(width 0.0889)
		(layer "In11.Cu")
		(net "M_F_DQ<58>")
	)
	(arc
		(start 285.84779 -92.356686)
		(mid 286.056398 -92.568618)
		(end 286.34182 -92.652088)
		(width 0.0889)
		(layer "In11.Cu")
		(net "M_F_DQ<58>")
	)
	(arc
		(start 291.521896 -101.567234)
		(mid 291.715746 -101.623584)
		(end 291.85743 -101.767386)
		(width 0.0889)
		(layer "In11.Cu")
		(net "M_F_DQ<58>")
	)
	(arc
		(start 289.811714 -94.633288)
		(mid 290.001643 -94.691158)
		(end 290.14039 -94.833186)
		(width 0.0889)
		(layer "In11.Cu")
		(net "M_F_DQ<58>")
	)
	(arc
		(start 290.99891 -98.301048)
		(mid 291.052409 -98.500946)
		(end 290.99891 -98.700844)
		(width 0.0889)
		(layer "In11.Cu")
		(net "M_F_DQ<58>")
	)
	(arc
		(start 288.946336 -94.137988)
		(mid 289.140186 -94.194338)
		(end 289.28187 -94.33814)
		(width 0.0889)
		(layer "In11.Cu")
		(net "M_F_DQ<58>")
	)
	(segment
		(start 309.449978 -152.278842)
		(end 309.449978 -153.542746)
		(width 0.1651)
		(layer "F.Cu")
		(net "M_F_DQ<57>")
	)
	(segment
		(start 282.354274 -92.061538)
		(end 282.925774 -92.061538)
		(width 0.1651)
		(layer "F.Cu")
		(net "M_F_DQ<57>")
	)
	(segment
		(start 309.450486 -152.273)
		(end 309.449978 -152.278842)
		(width 0.1651)
		(layer "F.Cu")
		(net "M_F_DQ<57>")
	)
	(via
		(at 309.449978 -153.542746)
		(size 0.508)
		(drill 0.254)
		(layers "F.Cu" "B.Cu")
		(net "M_F_DQ<57>")
	)
	(via
		(at 310.122062 -149.533356)
		(size 0.508)
		(drill 0.254)
		(layers "F.Cu" "B.Cu")
		(net "M_F_DQ<57>")
	)
	(via
		(at 282.925774 -92.061538)
		(size 0.508)
		(drill 0.254)
		(layers "F.Cu" "B.Cu")
		(net "M_F_DQ<57>")
	)
	(segment
		(start 310.299862 -147.478496)
		(end 310.299862 -148.852382)
		(width 0.1651)
		(layer "B.Cu")
		(net "M_F_DQ<57>")
	)
	(segment
		(start 310.122062 -149.030182)
		(end 310.122062 -149.533356)
		(width 0.1651)
		(layer "B.Cu")
		(net "M_F_DQ<57>")
	)
	(segment
		(start 310.30037 -147.478496)
		(end 310.299862 -147.478496)
		(width 0.1651)
		(layer "B.Cu")
		(net "M_F_DQ<57>")
	)
	(segment
		(start 310.299862 -148.852382)
		(end 310.122062 -149.030182)
		(width 0.1651)
		(layer "B.Cu")
		(net "M_F_DQ<57>")
	)
	(segment
		(start 295.775126 -112.73663)
		(end 295.930066 -112.89157)
		(width 0.14224)
		(layer "In11.Cu")
		(net "M_F_DQ<57>")
	)
	(segment
		(start 289.117024 -105.240582)
		(end 292.084252 -108.20781)
		(width 0.14224)
		(layer "In11.Cu")
		(net "M_F_DQ<57>")
	)
	(segment
		(start 284.631638 -95.433134)
		(end 284.655768 -95.433134)
		(width 0.0889)
		(layer "In11.Cu")
		(net "M_F_DQ<57>")
	)
	(segment
		(start 282.579064 -93.252036)
		(end 282.585414 -93.262704)
		(width 0.0889)
		(layer "In11.Cu")
		(net "M_F_DQ<57>")
	)
	(segment
		(start 310.122062 -149.533356)
		(end 310.09971 -149.533356)
		(width 0.14224)
		(layer "In11.Cu")
		(net "M_F_DQ<57>")
	)
	(segment
		(start 286.3596 -96.423988)
		(end 286.38119 -96.423988)
		(width 0.0889)
		(layer "In11.Cu")
		(net "M_F_DQ<57>")
	)
	(segment
		(start 310.7182 -148.336)
		(end 310.609996 -148.444204)
		(width 0.14224)
		(layer "In11.Cu")
		(net "M_F_DQ<57>")
	)
	(segment
		(start 287.72993 -101.176836)
		(end 287.73628 -101.187504)
		(width 0.0889)
		(layer "In11.Cu")
		(net "M_F_DQ<57>")
	)
	(segment
		(start 310.609996 -127.120396)
		(end 310.7436 -127.254)
		(width 0.14224)
		(layer "In11.Cu")
		(net "M_F_DQ<57>")
	)
	(segment
		(start 285.486348 -95.928434)
		(end 285.519114 -95.928434)
		(width 0.0889)
		(layer "In11.Cu")
		(net "M_F_DQ<57>")
	)
	(segment
		(start 310.7182 -134.1374)
		(end 310.609996 -134.245604)
		(width 0.14224)
		(layer "In11.Cu")
		(net "M_F_DQ<57>")
	)
	(segment
		(start 296.283126 -112.89157)
		(end 296.438066 -112.73663)
		(width 0.14224)
		(layer "In11.Cu")
		(net "M_F_DQ<57>")
	)
	(segment
		(start 295.775126 -110.126526)
		(end 295.775126 -112.73663)
		(width 0.14224)
		(layer "In11.Cu")
		(net "M_F_DQ<57>")
	)
	(segment
		(start 309.851044 -153.3906)
		(end 309.698898 -153.542746)
		(width 0.14224)
		(layer "In11.Cu")
		(net "M_F_DQ<57>")
	)
	(segment
		(start 309.671466 -150.391368)
		(end 309.901844 -150.621746)
		(width 0.14224)
		(layer "In11.Cu")
		(net "M_F_DQ<57>")
	)
	(segment
		(start 288.441638 -103.483918)
		(end 288.905188 -103.947468)
		(width 0.0889)
		(layer "In11.Cu")
		(net "M_F_DQ<57>")
	)
	(segment
		(start 310.609996 -136.5758)
		(end 310.7436 -136.709404)
		(width 0.14224)
		(layer "In11.Cu")
		(net "M_F_DQ<57>")
	)
	(segment
		(start 282.595828 -92.823284)
		(end 282.579064 -92.851986)
		(width 0.0889)
		(layer "In11.Cu")
		(net "M_F_DQ<57>")
	)
	(segment
		(start 288.905188 -105.028746)
		(end 289.117024 -105.240582)
		(width 0.0889)
		(layer "In11.Cu")
		(net "M_F_DQ<57>")
	)
	(segment
		(start 309.611268 -152.846024)
		(end 309.851044 -153.0858)
		(width 0.14224)
		(layer "In11.Cu")
		(net "M_F_DQ<57>")
	)
	(segment
		(start 310.7436 -127.254)
		(end 310.7436 -129.2352)
		(width 0.14224)
		(layer "In11.Cu")
		(net "M_F_DQ<57>")
	)
	(segment
		(start 310.609996 -131.8514)
		(end 310.7182 -131.959604)
		(width 0.14224)
		(layer "In11.Cu")
		(net "M_F_DQ<57>")
	)
	(segment
		(start 310.7182 -141.478)
		(end 310.7182 -143.6624)
		(width 0.14224)
		(layer "In11.Cu")
		(net "M_F_DQ<57>")
	)
	(segment
		(start 309.611268 -151.316944)
		(end 309.611268 -151.677624)
		(width 0.14224)
		(layer "In11.Cu")
		(net "M_F_DQ<57>")
	)
	(segment
		(start 288.065464 -103.358188)
		(end 288.09823 -103.358188)
		(width 0.0889)
		(layer "In11.Cu")
		(net "M_F_DQ<57>")
	)
	(segment
		(start 301.096426 -113.75009)
		(end 310.609996 -123.26366)
		(width 0.14224)
		(layer "In11.Cu")
		(net "M_F_DQ<57>")
	)
	(segment
		(start 296.593006 -111.330486)
		(end 296.946066 -111.330486)
		(width 0.14224)
		(layer "In11.Cu")
		(net "M_F_DQ<57>")
	)
	(segment
		(start 296.438066 -112.73663)
		(end 296.438066 -111.485426)
		(width 0.14224)
		(layer "In11.Cu")
		(net "M_F_DQ<57>")
	)
	(segment
		(start 287.725104 -100.1776)
		(end 287.72993 -100.186236)
		(width 0.0889)
		(layer "In11.Cu")
		(net "M_F_DQ<57>")
	)
	(segment
		(start 282.925774 -92.061538)
		(end 282.595828 -92.823284)
		(width 0.0889)
		(layer "In11.Cu")
		(net "M_F_DQ<57>")
	)
	(segment
		(start 310.7436 -129.2352)
		(end 310.609996 -129.368804)
		(width 0.14224)
		(layer "In11.Cu")
		(net "M_F_DQ<57>")
	)
	(segment
		(start 295.930066 -112.89157)
		(end 296.283126 -112.89157)
		(width 0.14224)
		(layer "In11.Cu")
		(net "M_F_DQ<57>")
	)
	(segment
		(start 287.203134 -96.919034)
		(end 287.2359 -96.919034)
		(width 0.0889)
		(layer "In11.Cu")
		(net "M_F_DQ<57>")
	)
	(segment
		(start 310.609996 -148.444204)
		(end 310.609996 -148.956522)
		(width 0.14224)
		(layer "In11.Cu")
		(net "M_F_DQ<57>")
	)
	(segment
		(start 297.101006 -113.387124)
		(end 297.463972 -113.75009)
		(width 0.14224)
		(layer "In11.Cu")
		(net "M_F_DQ<57>")
	)
	(segment
		(start 310.609996 -123.26366)
		(end 310.609996 -127.120396)
		(width 0.14224)
		(layer "In11.Cu")
		(net "M_F_DQ<57>")
	)
	(segment
		(start 309.901844 -151.026368)
		(end 309.611268 -151.316944)
		(width 0.14224)
		(layer "In11.Cu")
		(net "M_F_DQ<57>")
	)
	(segment
		(start 296.438066 -111.485426)
		(end 296.593006 -111.330486)
		(width 0.14224)
		(layer "In11.Cu")
		(net "M_F_DQ<57>")
	)
	(segment
		(start 283.76626 -94.937834)
		(end 283.805884 -94.937834)
		(width 0.0889)
		(layer "In11.Cu")
		(net "M_F_DQ<57>")
	)
	(segment
		(start 297.101006 -111.485426)
		(end 297.101006 -113.387124)
		(width 0.14224)
		(layer "In11.Cu")
		(net "M_F_DQ<57>")
	)
	(segment
		(start 288.905188 -103.947468)
		(end 288.905188 -105.028746)
		(width 0.0889)
		(layer "In11.Cu")
		(net "M_F_DQ<57>")
	)
	(segment
		(start 310.609996 -146.177)
		(end 310.7182 -146.285204)
		(width 0.14224)
		(layer "In11.Cu")
		(net "M_F_DQ<57>")
	)
	(segment
		(start 286.013144 -96.223836)
		(end 286.016446 -96.229678)
		(width 0.0889)
		(layer "In11.Cu")
		(net "M_F_DQ<57>")
	)
	(segment
		(start 310.09971 -149.533356)
		(end 309.671466 -149.9616)
		(width 0.14224)
		(layer "In11.Cu")
		(net "M_F_DQ<57>")
	)
	(segment
		(start 309.611268 -151.677624)
		(end 309.825644 -151.892)
		(width 0.14224)
		(layer "In11.Cu")
		(net "M_F_DQ<57>")
	)
	(segment
		(start 310.122062 -149.444456)
		(end 310.122062 -149.533356)
		(width 0.14224)
		(layer "In11.Cu")
		(net "M_F_DQ<57>")
	)
	(segment
		(start 287.725104 -99.187)
		(end 287.72993 -99.195636)
		(width 0.0889)
		(layer "In11.Cu")
		(net "M_F_DQ<57>")
	)
	(segment
		(start 310.609996 -129.368804)
		(end 310.609996 -131.8514)
		(width 0.14224)
		(layer "In11.Cu")
		(net "M_F_DQ<57>")
	)
	(segment
		(start 310.7436 -136.709404)
		(end 310.7436 -138.7348)
		(width 0.14224)
		(layer "In11.Cu")
		(net "M_F_DQ<57>")
	)
	(segment
		(start 310.609996 -134.245604)
		(end 310.609996 -136.5758)
		(width 0.14224)
		(layer "In11.Cu")
		(net "M_F_DQ<57>")
	)
	(segment
		(start 287.725104 -102.1588)
		(end 287.72993 -102.167436)
		(width 0.0889)
		(layer "In11.Cu")
		(net "M_F_DQ<57>")
	)
	(segment
		(start 310.609996 -138.868404)
		(end 310.609996 -141.369796)
		(width 0.14224)
		(layer "In11.Cu")
		(net "M_F_DQ<57>")
	)
	(segment
		(start 309.671466 -149.9616)
		(end 309.671466 -150.391368)
		(width 0.14224)
		(layer "In11.Cu")
		(net "M_F_DQ<57>")
	)
	(segment
		(start 282.90774 -94.442534)
		(end 282.943554 -94.442534)
		(width 0.0889)
		(layer "In11.Cu")
		(net "M_F_DQ<57>")
	)
	(segment
		(start 309.825644 -151.892)
		(end 309.825644 -152.3238)
		(width 0.14224)
		(layer "In11.Cu")
		(net "M_F_DQ<57>")
	)
	(segment
		(start 293.85641 -108.20781)
		(end 295.775126 -110.126526)
		(width 0.14224)
		(layer "In11.Cu")
		(net "M_F_DQ<57>")
	)
	(segment
		(start 310.7182 -146.285204)
		(end 310.7182 -148.336)
		(width 0.14224)
		(layer "In11.Cu")
		(net "M_F_DQ<57>")
	)
	(segment
		(start 309.611268 -152.538176)
		(end 309.611268 -152.846024)
		(width 0.14224)
		(layer "In11.Cu")
		(net "M_F_DQ<57>")
	)
	(segment
		(start 309.901844 -150.621746)
		(end 309.901844 -151.026368)
		(width 0.14224)
		(layer "In11.Cu")
		(net "M_F_DQ<57>")
	)
	(segment
		(start 296.946066 -111.330486)
		(end 297.101006 -111.485426)
		(width 0.14224)
		(layer "In11.Cu")
		(net "M_F_DQ<57>")
	)
	(segment
		(start 282.574238 -93.2434)
		(end 282.579064 -93.252036)
		(width 0.0889)
		(layer "In11.Cu")
		(net "M_F_DQ<57>")
	)
	(segment
		(start 309.698898 -153.542746)
		(end 309.449978 -153.542746)
		(width 0.14224)
		(layer "In11.Cu")
		(net "M_F_DQ<57>")
	)
	(segment
		(start 310.7436 -138.7348)
		(end 310.609996 -138.868404)
		(width 0.14224)
		(layer "In11.Cu")
		(net "M_F_DQ<57>")
	)
	(segment
		(start 297.463972 -113.75009)
		(end 301.096426 -113.75009)
		(width 0.14224)
		(layer "In11.Cu")
		(net "M_F_DQ<57>")
	)
	(segment
		(start 287.72993 -102.167436)
		(end 287.73628 -102.178104)
		(width 0.0889)
		(layer "In11.Cu")
		(net "M_F_DQ<57>")
	)
	(segment
		(start 287.72993 -100.186236)
		(end 287.73628 -100.196904)
		(width 0.0889)
		(layer "In11.Cu")
		(net "M_F_DQ<57>")
	)
	(segment
		(start 287.725104 -101.1682)
		(end 287.72993 -101.176836)
		(width 0.0889)
		(layer "In11.Cu")
		(net "M_F_DQ<57>")
	)
	(segment
		(start 310.609996 -141.369796)
		(end 310.7182 -141.478)
		(width 0.14224)
		(layer "In11.Cu")
		(net "M_F_DQ<57>")
	)
	(segment
		(start 310.7182 -131.959604)
		(end 310.7182 -134.1374)
		(width 0.14224)
		(layer "In11.Cu")
		(net "M_F_DQ<57>")
	)
	(segment
		(start 310.609996 -148.956522)
		(end 310.122062 -149.444456)
		(width 0.14224)
		(layer "In11.Cu")
		(net "M_F_DQ<57>")
	)
	(segment
		(start 310.7182 -143.6624)
		(end 310.609996 -143.770604)
		(width 0.14224)
		(layer "In11.Cu")
		(net "M_F_DQ<57>")
	)
	(segment
		(start 287.72993 -99.195636)
		(end 287.73628 -99.206304)
		(width 0.0889)
		(layer "In11.Cu")
		(net "M_F_DQ<57>")
	)
	(segment
		(start 309.851044 -153.0858)
		(end 309.851044 -153.3906)
		(width 0.14224)
		(layer "In11.Cu")
		(net "M_F_DQ<57>")
	)
	(segment
		(start 309.825644 -152.3238)
		(end 309.611268 -152.538176)
		(width 0.14224)
		(layer "In11.Cu")
		(net "M_F_DQ<57>")
	)
	(segment
		(start 292.084252 -108.20781)
		(end 293.85641 -108.20781)
		(width 0.14224)
		(layer "In11.Cu")
		(net "M_F_DQ<57>")
	)
	(segment
		(start 310.609996 -143.770604)
		(end 310.609996 -146.177)
		(width 0.14224)
		(layer "In11.Cu")
		(net "M_F_DQ<57>")
	)
	(arc
		(start 287.72993 -98.205544)
		(mid 287.808935 -98.500582)
		(end 287.72993 -98.795586)
		(width 0.0889)
		(layer "In11.Cu")
		(net "M_F_DQ<57>")
	)
	(arc
		(start 287.72993 -102.757986)
		(mid 287.727182 -103.153453)
		(end 288.065464 -103.358188)
		(width 0.0889)
		(layer "In11.Cu")
		(net "M_F_DQ<57>")
	)
	(arc
		(start 286.38119 -96.423988)
		(mid 286.664407 -96.508269)
		(end 286.87141 -96.719136)
		(width 0.0889)
		(layer "In11.Cu")
		(net "M_F_DQ<57>")
	)
	(arc
		(start 288.09823 -103.358188)
		(mid 288.27989 -103.393846)
		(end 288.441638 -103.483918)
		(width 0.0889)
		(layer "In11.Cu")
		(net "M_F_DQ<57>")
	)
	(arc
		(start 282.579064 -92.851986)
		(mid 282.525594 -93.047049)
		(end 282.574238 -93.2434)
		(width 0.0889)
		(layer "In11.Cu")
		(net "M_F_DQ<57>")
	)
	(arc
		(start 287.72993 -97.804986)
		(mid 287.676279 -98.005282)
		(end 287.72993 -98.205544)
		(width 0.0889)
		(layer "In11.Cu")
		(net "M_F_DQ<57>")
	)
	(arc
		(start 287.2359 -96.919034)
		(mid 287.734151 -97.221874)
		(end 287.72993 -97.804986)
		(width 0.0889)
		(layer "In11.Cu")
		(net "M_F_DQ<57>")
	)
	(arc
		(start 283.805884 -94.937834)
		(mid 284.089101 -95.022115)
		(end 284.296104 -95.232982)
		(width 0.0889)
		(layer "In11.Cu")
		(net "M_F_DQ<57>")
	)
	(arc
		(start 287.73628 -101.187504)
		(mid 287.809078 -101.478267)
		(end 287.72993 -101.767386)
		(width 0.0889)
		(layer "In11.Cu")
		(net "M_F_DQ<57>")
	)
	(arc
		(start 287.72993 -101.767386)
		(mid 287.67646 -101.962449)
		(end 287.725104 -102.1588)
		(width 0.0889)
		(layer "In11.Cu")
		(net "M_F_DQ<57>")
	)
	(arc
		(start 284.296104 -95.232982)
		(mid 284.437787 -95.376786)
		(end 284.631638 -95.433134)
		(width 0.0889)
		(layer "In11.Cu")
		(net "M_F_DQ<57>")
	)
	(arc
		(start 285.154624 -95.728536)
		(mid 285.294703 -95.871272)
		(end 285.486348 -95.928434)
		(width 0.0889)
		(layer "In11.Cu")
		(net "M_F_DQ<57>")
	)
	(arc
		(start 283.437584 -94.737936)
		(mid 283.576328 -94.879969)
		(end 283.76626 -94.937834)
		(width 0.0889)
		(layer "In11.Cu")
		(net "M_F_DQ<57>")
	)
	(arc
		(start 284.655768 -95.433134)
		(mid 284.943913 -95.515453)
		(end 285.154624 -95.728536)
		(width 0.0889)
		(layer "In11.Cu")
		(net "M_F_DQ<57>")
	)
	(arc
		(start 287.73628 -102.178104)
		(mid 287.809078 -102.468867)
		(end 287.72993 -102.757986)
		(width 0.0889)
		(layer "In11.Cu")
		(net "M_F_DQ<57>")
	)
	(arc
		(start 287.73628 -100.196904)
		(mid 287.809078 -100.487667)
		(end 287.72993 -100.776786)
		(width 0.0889)
		(layer "In11.Cu")
		(net "M_F_DQ<57>")
	)
	(arc
		(start 286.016446 -96.229678)
		(mid 286.162412 -96.372077)
		(end 286.3596 -96.423988)
		(width 0.0889)
		(layer "In11.Cu")
		(net "M_F_DQ<57>")
	)
	(arc
		(start 287.72993 -99.786186)
		(mid 287.67646 -99.981249)
		(end 287.725104 -100.1776)
		(width 0.0889)
		(layer "In11.Cu")
		(net "M_F_DQ<57>")
	)
	(arc
		(start 287.72993 -100.776786)
		(mid 287.67646 -100.971849)
		(end 287.725104 -101.1682)
		(width 0.0889)
		(layer "In11.Cu")
		(net "M_F_DQ<57>")
	)
	(arc
		(start 282.585414 -93.262704)
		(mid 282.658212 -93.553467)
		(end 282.579064 -93.842586)
		(width 0.0889)
		(layer "In11.Cu")
		(net "M_F_DQ<57>")
	)
	(arc
		(start 286.87141 -96.719136)
		(mid 287.011489 -96.861872)
		(end 287.203134 -96.919034)
		(width 0.0889)
		(layer "In11.Cu")
		(net "M_F_DQ<57>")
	)
	(arc
		(start 287.73628 -99.206304)
		(mid 287.809078 -99.497067)
		(end 287.72993 -99.786186)
		(width 0.0889)
		(layer "In11.Cu")
		(net "M_F_DQ<57>")
	)
	(arc
		(start 282.579064 -93.842586)
		(mid 282.574654 -94.235049)
		(end 282.90774 -94.442534)
		(width 0.0889)
		(layer "In11.Cu")
		(net "M_F_DQ<57>")
	)
	(arc
		(start 287.72993 -98.795586)
		(mid 287.67646 -98.990649)
		(end 287.725104 -99.187)
		(width 0.0889)
		(layer "In11.Cu")
		(net "M_F_DQ<57>")
	)
	(arc
		(start 282.943554 -94.442534)
		(mid 283.228978 -94.526001)
		(end 283.437584 -94.737936)
		(width 0.0889)
		(layer "In11.Cu")
		(net "M_F_DQ<57>")
	)
	(arc
		(start 285.519114 -95.928434)
		(mid 285.804538 -96.011901)
		(end 286.013144 -96.223836)
		(width 0.0889)
		(layer "In11.Cu")
		(net "M_F_DQ<57>")
	)
	(segment
		(start 282.354274 -90.080338)
		(end 282.925774 -90.080338)
		(width 0.1651)
		(layer "F.Cu")
		(net "M_F_DQ<56>")
	)
	(segment
		(start 310.30037 -156.87294)
		(end 310.299862 -156.878782)
		(width 0.1651)
		(layer "F.Cu")
		(net "M_F_DQ<56>")
	)
	(segment
		(start 310.299862 -156.878782)
		(end 310.22036 -156.046932)
		(width 0.1651)
		(layer "F.Cu")
		(net "M_F_DQ<56>")
	)
	(segment
		(start 310.22036 -156.046932)
		(end 310.122062 -155.0162)
		(width 0.1651)
		(layer "F.Cu")
		(net "M_F_DQ<56>")
	)
	(via
		(at 309.449978 -150.814278)
		(size 0.508)
		(drill 0.254)
		(layers "F.Cu" "B.Cu")
		(net "M_F_DQ<56>")
	)
	(via
		(at 282.925774 -90.080338)
		(size 0.508)
		(drill 0.254)
		(layers "F.Cu" "B.Cu")
		(net "M_F_DQ<56>")
	)
	(via
		(at 310.122062 -155.0162)
		(size 0.508)
		(drill 0.254)
		(layers "F.Cu" "B.Cu")
		(net "M_F_DQ<56>")
	)
	(segment
		(start 309.450486 -152.078436)
		(end 309.449978 -152.078182)
		(width 0.1651)
		(layer "B.Cu")
		(net "M_F_DQ<56>")
	)
	(segment
		(start 309.449978 -152.078182)
		(end 309.449978 -150.814278)
		(width 0.1651)
		(layer "B.Cu")
		(net "M_F_DQ<56>")
	)
	(segment
		(start 309.903114 -139.39266)
		(end 309.632096 -139.663678)
		(width 0.14224)
		(layer "In11.Cu")
		(net "M_F_DQ<56>")
	)
	(segment
		(start 295.179242 -113.01222)
		(end 296.442384 -114.275362)
		(width 0.14224)
		(layer "In11.Cu")
		(net "M_F_DQ<56>")
	)
	(segment
		(start 282.413964 -91.366086)
		(end 282.41879 -91.374722)
		(width 0.0889)
		(layer "In11.Cu")
		(net "M_F_DQ<56>")
	)
	(segment
		(start 282.430728 -90.746072)
		(end 282.413964 -90.775536)
		(width 0.0889)
		(layer "In11.Cu")
		(net "M_F_DQ<56>")
	)
	(segment
		(start 309.661814 -134.747)
		(end 309.661814 -135.976614)
		(width 0.14224)
		(layer "In11.Cu")
		(net "M_F_DQ<56>")
	)
	(segment
		(start 295.179242 -110.443518)
		(end 295.179242 -113.01222)
		(width 0.14224)
		(layer "In11.Cu")
		(net "M_F_DQ<56>")
	)
	(segment
		(start 284.62986 -95.623888)
		(end 284.6578 -95.623888)
		(width 0.0889)
		(layer "In11.Cu")
		(net "M_F_DQ<56>")
	)
	(segment
		(start 287.56483 -99.290886)
		(end 287.569656 -99.299522)
		(width 0.0889)
		(layer "In11.Cu")
		(net "M_F_DQ<56>")
	)
	(segment
		(start 309.903114 -136.217914)
		(end 309.903114 -139.39266)
		(width 0.14224)
		(layer "In11.Cu")
		(net "M_F_DQ<56>")
	)
	(segment
		(start 282.413964 -93.347286)
		(end 282.41879 -93.355922)
		(width 0.0889)
		(layer "In11.Cu")
		(net "M_F_DQ<56>")
	)
	(segment
		(start 287.55848 -99.280218)
		(end 287.56483 -99.290886)
		(width 0.0889)
		(layer "In11.Cu")
		(net "M_F_DQ<56>")
	)
	(segment
		(start 288.05886 -103.548688)
		(end 288.091626 -103.548688)
		(width 0.0889)
		(layer "In11.Cu")
		(net "M_F_DQ<56>")
	)
	(segment
		(start 282.925774 -90.080338)
		(end 282.453842 -90.715084)
		(width 0.0889)
		(layer "In11.Cu")
		(net "M_F_DQ<56>")
	)
	(segment
		(start 309.896002 -144.114012)
		(end 309.676038 -144.333976)
		(width 0.14224)
		(layer "In11.Cu")
		(net "M_F_DQ<56>")
	)
	(segment
		(start 309.917338 -129.777236)
		(end 309.632096 -130.062478)
		(width 0.14224)
		(layer "In11.Cu")
		(net "M_F_DQ<56>")
	)
	(segment
		(start 309.903114 -145.81886)
		(end 309.903114 -148.99386)
		(width 0.14224)
		(layer "In11.Cu")
		(net "M_F_DQ<56>")
	)
	(segment
		(start 309.085996 -150.450296)
		(end 309.449978 -150.814278)
		(width 0.14224)
		(layer "In11.Cu")
		(net "M_F_DQ<56>")
	)
	(segment
		(start 288.482024 -105.50652)
		(end 291.662104 -108.6866)
		(width 0.14224)
		(layer "In11.Cu")
		(net "M_F_DQ<56>")
	)
	(segment
		(start 282.407614 -93.336618)
		(end 282.413964 -93.347286)
		(width 0.0889)
		(layer "In11.Cu")
		(net "M_F_DQ<56>")
	)
	(segment
		(start 309.661814 -135.976614)
		(end 309.903114 -136.217914)
		(width 0.14224)
		(layer "In11.Cu")
		(net "M_F_DQ<56>")
	)
	(segment
		(start 287.55848 -102.252018)
		(end 287.56483 -102.262686)
		(width 0.0889)
		(layer "In11.Cu")
		(net "M_F_DQ<56>")
	)
	(segment
		(start 282.407614 -91.355418)
		(end 282.413964 -91.366086)
		(width 0.0889)
		(layer "In11.Cu")
		(net "M_F_DQ<56>")
	)
	(segment
		(start 309.016908 -151.247348)
		(end 309.016908 -154.20721)
		(width 0.14224)
		(layer "In11.Cu")
		(net "M_F_DQ<56>")
	)
	(segment
		(start 287.56483 -102.262686)
		(end 287.569656 -102.271322)
		(width 0.0889)
		(layer "In11.Cu")
		(net "M_F_DQ<56>")
	)
	(segment
		(start 288.71291 -104.02443)
		(end 288.71291 -104.579928)
		(width 0.0889)
		(layer "In11.Cu")
		(net "M_F_DQ<56>")
	)
	(segment
		(start 309.88889 -131.398772)
		(end 309.88889 -134.519924)
		(width 0.14224)
		(layer "In11.Cu")
		(net "M_F_DQ<56>")
	)
	(segment
		(start 287.56483 -101.272086)
		(end 287.569656 -101.280722)
		(width 0.0889)
		(layer "In11.Cu")
		(net "M_F_DQ<56>")
	)
	(segment
		(start 309.016908 -154.20721)
		(end 309.825898 -155.0162)
		(width 0.14224)
		(layer "In11.Cu")
		(net "M_F_DQ<56>")
	)
	(segment
		(start 287.56483 -100.281486)
		(end 287.569656 -100.290122)
		(width 0.0889)
		(layer "In11.Cu")
		(net "M_F_DQ<56>")
	)
	(segment
		(start 309.903114 -148.99386)
		(end 309.085996 -149.810978)
		(width 0.14224)
		(layer "In11.Cu")
		(net "M_F_DQ<56>")
	)
	(segment
		(start 309.632096 -139.663678)
		(end 309.632096 -140.743178)
		(width 0.14224)
		(layer "In11.Cu")
		(net "M_F_DQ<56>")
	)
	(segment
		(start 300.657514 -114.275362)
		(end 309.917338 -123.535186)
		(width 0.14224)
		(layer "In11.Cu")
		(net "M_F_DQ<56>")
	)
	(segment
		(start 293.422324 -108.6866)
		(end 295.179242 -110.443518)
		(width 0.14224)
		(layer "In11.Cu")
		(net "M_F_DQ<56>")
	)
	(segment
		(start 288.71291 -104.579928)
		(end 288.482024 -104.810814)
		(width 0.0889)
		(layer "In11.Cu")
		(net "M_F_DQ<56>")
	)
	(segment
		(start 309.085996 -149.810978)
		(end 309.085996 -150.450296)
		(width 0.14224)
		(layer "In11.Cu")
		(net "M_F_DQ<56>")
	)
	(segment
		(start 282.413964 -92.356686)
		(end 282.41879 -92.365322)
		(width 0.0889)
		(layer "In11.Cu")
		(net "M_F_DQ<56>")
	)
	(segment
		(start 309.917338 -123.535186)
		(end 309.917338 -129.777236)
		(width 0.14224)
		(layer "In11.Cu")
		(net "M_F_DQ<56>")
	)
	(segment
		(start 309.676038 -144.333976)
		(end 309.676038 -145.591784)
		(width 0.14224)
		(layer "In11.Cu")
		(net "M_F_DQ<56>")
	)
	(segment
		(start 296.442384 -114.275362)
		(end 300.657514 -114.275362)
		(width 0.14224)
		(layer "In11.Cu")
		(net "M_F_DQ<56>")
	)
	(segment
		(start 309.632096 -130.062478)
		(end 309.632096 -131.141978)
		(width 0.14224)
		(layer "In11.Cu")
		(net "M_F_DQ<56>")
	)
	(segment
		(start 286.34182 -96.614488)
		(end 286.374586 -96.614488)
		(width 0.0889)
		(layer "In11.Cu")
		(net "M_F_DQ<56>")
	)
	(segment
		(start 309.676038 -145.591784)
		(end 309.903114 -145.81886)
		(width 0.14224)
		(layer "In11.Cu")
		(net "M_F_DQ<56>")
	)
	(segment
		(start 309.896002 -141.007084)
		(end 309.896002 -144.114012)
		(width 0.14224)
		(layer "In11.Cu")
		(net "M_F_DQ<56>")
	)
	(segment
		(start 288.349944 -103.661464)
		(end 288.71291 -104.02443)
		(width 0.0889)
		(layer "In11.Cu")
		(net "M_F_DQ<56>")
	)
	(segment
		(start 283.766514 -95.128588)
		(end 283.802328 -95.128588)
		(width 0.0889)
		(layer "In11.Cu")
		(net "M_F_DQ<56>")
	)
	(segment
		(start 309.825898 -155.0162)
		(end 310.122062 -155.0162)
		(width 0.14224)
		(layer "In11.Cu")
		(net "M_F_DQ<56>")
	)
	(segment
		(start 287.19653 -97.109534)
		(end 287.229296 -97.109534)
		(width 0.0889)
		(layer "In11.Cu")
		(net "M_F_DQ<56>")
	)
	(segment
		(start 287.55848 -101.261418)
		(end 287.56483 -101.272086)
		(width 0.0889)
		(layer "In11.Cu")
		(net "M_F_DQ<56>")
	)
	(segment
		(start 282.453842 -90.715084)
		(end 282.430728 -90.746072)
		(width 0.0889)
		(layer "In11.Cu")
		(net "M_F_DQ<56>")
	)
	(segment
		(start 282.904184 -94.633288)
		(end 282.943808 -94.633288)
		(width 0.0889)
		(layer "In11.Cu")
		(net "M_F_DQ<56>")
	)
	(segment
		(start 291.662104 -108.6866)
		(end 293.422324 -108.6866)
		(width 0.14224)
		(layer "In11.Cu")
		(net "M_F_DQ<56>")
	)
	(segment
		(start 285.479744 -96.118934)
		(end 285.501334 -96.118934)
		(width 0.0889)
		(layer "In11.Cu")
		(net "M_F_DQ<56>")
	)
	(segment
		(start 309.449978 -150.814278)
		(end 309.016908 -151.247348)
		(width 0.14224)
		(layer "In11.Cu")
		(net "M_F_DQ<56>")
	)
	(segment
		(start 288.482024 -104.810814)
		(end 288.482024 -105.50652)
		(width 0.14224)
		(layer "In11.Cu")
		(net "M_F_DQ<56>")
	)
	(segment
		(start 282.407614 -92.346018)
		(end 282.413964 -92.356686)
		(width 0.0889)
		(layer "In11.Cu")
		(net "M_F_DQ<56>")
	)
	(segment
		(start 287.55848 -100.270818)
		(end 287.56483 -100.281486)
		(width 0.0889)
		(layer "In11.Cu")
		(net "M_F_DQ<56>")
	)
	(segment
		(start 309.88889 -134.519924)
		(end 309.661814 -134.747)
		(width 0.14224)
		(layer "In11.Cu")
		(net "M_F_DQ<56>")
	)
	(segment
		(start 309.632096 -131.141978)
		(end 309.88889 -131.398772)
		(width 0.14224)
		(layer "In11.Cu")
		(net "M_F_DQ<56>")
	)
	(segment
		(start 285.844488 -96.313244)
		(end 285.84779 -96.319086)
		(width 0.0889)
		(layer "In11.Cu")
		(net "M_F_DQ<56>")
	)
	(segment
		(start 309.632096 -140.743178)
		(end 309.896002 -141.007084)
		(width 0.14224)
		(layer "In11.Cu")
		(net "M_F_DQ<56>")
	)
	(arc
		(start 287.56483 -99.690936)
		(mid 287.485608 -99.980054)
		(end 287.55848 -100.270818)
		(width 0.0889)
		(layer "In11.Cu")
		(net "M_F_DQ<56>")
	)
	(arc
		(start 287.569656 -99.299522)
		(mid 287.618411 -99.495874)
		(end 287.56483 -99.690936)
		(width 0.0889)
		(layer "In11.Cu")
		(net "M_F_DQ<56>")
	)
	(arc
		(start 288.091626 -103.548688)
		(mid 288.231452 -103.580637)
		(end 288.349944 -103.661464)
		(width 0.0889)
		(layer "In11.Cu")
		(net "M_F_DQ<56>")
	)
	(arc
		(start 283.272484 -94.833186)
		(mid 283.481092 -95.045118)
		(end 283.766514 -95.128588)
		(width 0.0889)
		(layer "In11.Cu")
		(net "M_F_DQ<56>")
	)
	(arc
		(start 284.131004 -95.328486)
		(mid 284.341717 -95.541565)
		(end 284.62986 -95.623888)
		(width 0.0889)
		(layer "In11.Cu")
		(net "M_F_DQ<56>")
	)
	(arc
		(start 285.501334 -96.118934)
		(mid 285.698495 -96.170893)
		(end 285.844488 -96.313244)
		(width 0.0889)
		(layer "In11.Cu")
		(net "M_F_DQ<56>")
	)
	(arc
		(start 287.56483 -101.672136)
		(mid 287.485608 -101.961254)
		(end 287.55848 -102.252018)
		(width 0.0889)
		(layer "In11.Cu")
		(net "M_F_DQ<56>")
	)
	(arc
		(start 282.41879 -92.365322)
		(mid 282.467545 -92.561674)
		(end 282.413964 -92.756736)
		(width 0.0889)
		(layer "In11.Cu")
		(net "M_F_DQ<56>")
	)
	(arc
		(start 282.943808 -94.633288)
		(mid 283.133737 -94.691158)
		(end 283.272484 -94.833186)
		(width 0.0889)
		(layer "In11.Cu")
		(net "M_F_DQ<56>")
	)
	(arc
		(start 287.229296 -97.109534)
		(mid 287.567465 -97.314332)
		(end 287.56483 -97.709736)
		(width 0.0889)
		(layer "In11.Cu")
		(net "M_F_DQ<56>")
	)
	(arc
		(start 284.989524 -95.823786)
		(mid 285.196528 -96.03465)
		(end 285.479744 -96.118934)
		(width 0.0889)
		(layer "In11.Cu")
		(net "M_F_DQ<56>")
	)
	(arc
		(start 282.413964 -90.775536)
		(mid 282.334742 -91.064654)
		(end 282.407614 -91.355418)
		(width 0.0889)
		(layer "In11.Cu")
		(net "M_F_DQ<56>")
	)
	(arc
		(start 287.56483 -100.681536)
		(mid 287.485608 -100.970654)
		(end 287.55848 -101.261418)
		(width 0.0889)
		(layer "In11.Cu")
		(net "M_F_DQ<56>")
	)
	(arc
		(start 287.56483 -97.709736)
		(mid 287.48564 -98.005392)
		(end 287.56483 -98.301048)
		(width 0.0889)
		(layer "In11.Cu")
		(net "M_F_DQ<56>")
	)
	(arc
		(start 286.374586 -96.614488)
		(mid 286.566228 -96.671654)
		(end 286.70631 -96.814386)
		(width 0.0889)
		(layer "In11.Cu")
		(net "M_F_DQ<56>")
	)
	(arc
		(start 285.84779 -96.319086)
		(mid 286.056398 -96.531018)
		(end 286.34182 -96.614488)
		(width 0.0889)
		(layer "In11.Cu")
		(net "M_F_DQ<56>")
	)
	(arc
		(start 286.70631 -96.814386)
		(mid 286.913314 -97.02525)
		(end 287.19653 -97.109534)
		(width 0.0889)
		(layer "In11.Cu")
		(net "M_F_DQ<56>")
	)
	(arc
		(start 284.6578 -95.623888)
		(mid 284.849442 -95.681054)
		(end 284.989524 -95.823786)
		(width 0.0889)
		(layer "In11.Cu")
		(net "M_F_DQ<56>")
	)
	(arc
		(start 287.56483 -102.662736)
		(mid 287.560501 -103.245908)
		(end 288.05886 -103.548688)
		(width 0.0889)
		(layer "In11.Cu")
		(net "M_F_DQ<56>")
	)
	(arc
		(start 282.41879 -93.355922)
		(mid 282.467545 -93.552274)
		(end 282.413964 -93.747336)
		(width 0.0889)
		(layer "In11.Cu")
		(net "M_F_DQ<56>")
	)
	(arc
		(start 282.413964 -93.747336)
		(mid 282.40871 -94.328844)
		(end 282.904184 -94.633288)
		(width 0.0889)
		(layer "In11.Cu")
		(net "M_F_DQ<56>")
	)
	(arc
		(start 282.413964 -91.766136)
		(mid 282.334742 -92.055254)
		(end 282.407614 -92.346018)
		(width 0.0889)
		(layer "In11.Cu")
		(net "M_F_DQ<56>")
	)
	(arc
		(start 287.569656 -102.271322)
		(mid 287.618411 -102.467674)
		(end 287.56483 -102.662736)
		(width 0.0889)
		(layer "In11.Cu")
		(net "M_F_DQ<56>")
	)
	(arc
		(start 287.56483 -98.700336)
		(mid 287.485608 -98.989454)
		(end 287.55848 -99.280218)
		(width 0.0889)
		(layer "In11.Cu")
		(net "M_F_DQ<56>")
	)
	(arc
		(start 282.413964 -92.756736)
		(mid 282.334742 -93.045854)
		(end 282.407614 -93.336618)
		(width 0.0889)
		(layer "In11.Cu")
		(net "M_F_DQ<56>")
	)
	(arc
		(start 287.569656 -100.290122)
		(mid 287.618411 -100.486474)
		(end 287.56483 -100.681536)
		(width 0.0889)
		(layer "In11.Cu")
		(net "M_F_DQ<56>")
	)
	(arc
		(start 282.41879 -91.374722)
		(mid 282.467545 -91.571074)
		(end 282.413964 -91.766136)
		(width 0.0889)
		(layer "In11.Cu")
		(net "M_F_DQ<56>")
	)
	(arc
		(start 283.802328 -95.128588)
		(mid 283.992257 -95.186458)
		(end 284.131004 -95.328486)
		(width 0.0889)
		(layer "In11.Cu")
		(net "M_F_DQ<56>")
	)
	(arc
		(start 287.569656 -101.280722)
		(mid 287.618411 -101.477074)
		(end 287.56483 -101.672136)
		(width 0.0889)
		(layer "In11.Cu")
		(net "M_F_DQ<56>")
	)
	(arc
		(start 287.56483 -98.301048)
		(mid 287.618304 -98.500692)
		(end 287.56483 -98.700336)
		(width 0.0889)
		(layer "In11.Cu")
		(net "M_F_DQ<56>")
	)
	(segment
		(start 304.349912 -152.278842)
		(end 304.349912 -153.542746)
		(width 0.1651)
		(layer "F.Cu")
		(net "M_F_DQ<55>")
	)
	(segment
		(start 278.920194 -92.061538)
		(end 279.491694 -92.061538)
		(width 0.1651)
		(layer "F.Cu")
		(net "M_F_DQ<55>")
	)
	(segment
		(start 304.35042 -152.273)
		(end 304.349912 -152.278842)
		(width 0.1651)
		(layer "F.Cu")
		(net "M_F_DQ<55>")
	)
	(via
		(at 304.349912 -153.542746)
		(size 0.508)
		(drill 0.254)
		(layers "F.Cu" "B.Cu")
		(net "M_F_DQ<55>")
	)
	(via
		(at 279.491694 -92.061538)
		(size 0.508)
		(drill 0.254)
		(layers "F.Cu" "B.Cu")
		(net "M_F_DQ<55>")
	)
	(via
		(at 305.199796 -149.533356)
		(size 0.508)
		(drill 0.254)
		(layers "F.Cu" "B.Cu")
		(net "M_F_DQ<55>")
	)
	(segment
		(start 305.200304 -147.478496)
		(end 305.199796 -147.478496)
		(width 0.1651)
		(layer "B.Cu")
		(net "M_F_DQ<55>")
	)
	(segment
		(start 305.199796 -147.478496)
		(end 305.199796 -149.533356)
		(width 0.1651)
		(layer "B.Cu")
		(net "M_F_DQ<55>")
	)
	(segment
		(start 305.755802 -134.757668)
		(end 305.755802 -136.077452)
		(width 0.14224)
		(layer "In11.Cu")
		(net "M_F_DQ<55>")
	)
	(segment
		(start 305.552602 -145.830798)
		(end 305.552602 -149.191472)
		(width 0.14224)
		(layer "In11.Cu")
		(net "M_F_DQ<55>")
	)
	(segment
		(start 293.72814 -117.94998)
		(end 293.72814 -118.299992)
		(width 0.14224)
		(layer "In11.Cu")
		(net "M_F_DQ<55>")
	)
	(segment
		(start 305.6382 -136.661398)
		(end 305.6382 -138.8364)
		(width 0.14224)
		(layer "In11.Cu")
		(net "M_F_DQ<55>")
	)
	(segment
		(start 305.199796 -149.533356)
		(end 305.177444 -149.533356)
		(width 0.14224)
		(layer "In11.Cu")
		(net "M_F_DQ<55>")
	)
	(segment
		(start 305.552602 -138.921998)
		(end 305.552602 -139.460478)
		(width 0.14224)
		(layer "In11.Cu")
		(net "M_F_DQ<55>")
	)
	(segment
		(start 304.76825 -152.2222)
		(end 304.511202 -152.479248)
		(width 0.14224)
		(layer "In11.Cu")
		(net "M_F_DQ<55>")
	)
	(segment
		(start 284.557724 -106.716576)
		(end 284.781498 -106.94035)
		(width 0.0889)
		(layer "In11.Cu")
		(net "M_F_DQ<55>")
	)
	(segment
		(start 305.54168 -149.191472)
		(end 305.199796 -149.533356)
		(width 0.14224)
		(layer "In11.Cu")
		(net "M_F_DQ<55>")
	)
	(segment
		(start 305.4858 -126.9746)
		(end 305.696366 -127.185166)
		(width 0.14224)
		(layer "In11.Cu")
		(net "M_F_DQ<55>")
	)
	(segment
		(start 304.511202 -152.479248)
		(end 304.511202 -152.752552)
		(width 0.14224)
		(layer "In11.Cu")
		(net "M_F_DQ<55>")
	)
	(segment
		(start 293.22014 -117.79504)
		(end 293.5732 -117.79504)
		(width 0.14224)
		(layer "In11.Cu")
		(net "M_F_DQ<55>")
	)
	(segment
		(start 284.296104 -102.167436)
		(end 284.302454 -102.178104)
		(width 0.0889)
		(layer "In11.Cu")
		(net "M_F_DQ<55>")
	)
	(segment
		(start 292.91026 -118.554246)
		(end 293.0652 -118.399306)
		(width 0.14224)
		(layer "In11.Cu")
		(net "M_F_DQ<55>")
	)
	(segment
		(start 305.578002 -131.408678)
		(end 305.578002 -131.9276)
		(width 0.14224)
		(layer "In11.Cu")
		(net "M_F_DQ<55>")
	)
	(segment
		(start 305.578002 -134.579868)
		(end 305.755802 -134.757668)
		(width 0.14224)
		(layer "In11.Cu")
		(net "M_F_DQ<55>")
	)
	(segment
		(start 284.291278 -102.1588)
		(end 284.296104 -102.167436)
		(width 0.0889)
		(layer "In11.Cu")
		(net "M_F_DQ<55>")
	)
	(segment
		(start 305.696366 -129.269236)
		(end 305.552602 -129.413)
		(width 0.14224)
		(layer "In11.Cu")
		(net "M_F_DQ<55>")
	)
	(segment
		(start 281.197558 -96.423988)
		(end 281.230324 -96.423988)
		(width 0.0889)
		(layer "In11.Cu")
		(net "M_F_DQ<55>")
	)
	(segment
		(start 284.781498 -112.163098)
		(end 290.41344 -117.79504)
		(width 0.14224)
		(layer "In11.Cu")
		(net "M_F_DQ<55>")
	)
	(segment
		(start 305.177444 -149.533356)
		(end 304.7492 -149.9616)
		(width 0.14224)
		(layer "In11.Cu")
		(net "M_F_DQ<55>")
	)
	(segment
		(start 280.003504 -95.328486)
		(end 279.998678 -95.337122)
		(width 0.0889)
		(layer "In11.Cu")
		(net "M_F_DQ<55>")
	)
	(segment
		(start 292.24732 -117.79504)
		(end 292.40226 -117.94998)
		(width 0.14224)
		(layer "In11.Cu")
		(net "M_F_DQ<55>")
	)
	(segment
		(start 280.003504 -93.347286)
		(end 279.998678 -93.355922)
		(width 0.0889)
		(layer "In11.Cu")
		(net "M_F_DQ<55>")
	)
	(segment
		(start 284.296104 -104.148636)
		(end 284.302454 -104.159304)
		(width 0.0889)
		(layer "In11.Cu")
		(net "M_F_DQ<55>")
	)
	(segment
		(start 305.552602 -129.859278)
		(end 305.781202 -130.087878)
		(width 0.14224)
		(layer "In11.Cu")
		(net "M_F_DQ<55>")
	)
	(segment
		(start 279.491694 -92.061538)
		(end 279.98674 -92.727272)
		(width 0.0889)
		(layer "In11.Cu")
		(net "M_F_DQ<55>")
	)
	(segment
		(start 305.501802 -141.5034)
		(end 305.6382 -141.639798)
		(width 0.14224)
		(layer "In11.Cu")
		(net "M_F_DQ<55>")
	)
	(segment
		(start 291.73932 -118.399306)
		(end 291.73932 -117.94998)
		(width 0.14224)
		(layer "In11.Cu")
		(net "M_F_DQ<55>")
	)
	(segment
		(start 304.511202 -151.387048)
		(end 304.511202 -151.660352)
		(width 0.14224)
		(layer "In11.Cu")
		(net "M_F_DQ<55>")
	)
	(segment
		(start 292.40226 -118.399306)
		(end 292.5572 -118.554246)
		(width 0.14224)
		(layer "In11.Cu")
		(net "M_F_DQ<55>")
	)
	(segment
		(start 305.552602 -136.5758)
		(end 305.6382 -136.661398)
		(width 0.14224)
		(layer "In11.Cu")
		(net "M_F_DQ<55>")
	)
	(segment
		(start 304.511202 -152.752552)
		(end 304.8 -153.04135)
		(width 0.14224)
		(layer "In11.Cu")
		(net "M_F_DQ<55>")
	)
	(segment
		(start 284.296104 -99.195636)
		(end 284.302454 -99.206304)
		(width 0.0889)
		(layer "In11.Cu")
		(net "M_F_DQ<55>")
	)
	(segment
		(start 304.79365 -150.435818)
		(end 304.79365 -151.1046)
		(width 0.14224)
		(layer "In11.Cu")
		(net "M_F_DQ<55>")
	)
	(segment
		(start 293.5732 -117.79504)
		(end 293.72814 -117.94998)
		(width 0.14224)
		(layer "In11.Cu")
		(net "M_F_DQ<55>")
	)
	(segment
		(start 284.24251 -105.929938)
		(end 284.24251 -106.143298)
		(width 0.0889)
		(layer "In11.Cu")
		(net "M_F_DQ<55>")
	)
	(segment
		(start 292.5572 -118.554246)
		(end 292.91026 -118.554246)
		(width 0.14224)
		(layer "In11.Cu")
		(net "M_F_DQ<55>")
	)
	(segment
		(start 284.296104 -103.158036)
		(end 284.302454 -103.168704)
		(width 0.0889)
		(layer "In11.Cu")
		(net "M_F_DQ<55>")
	)
	(segment
		(start 304.8 -153.04135)
		(end 304.8 -153.364946)
		(width 0.14224)
		(layer "In11.Cu")
		(net "M_F_DQ<55>")
	)
	(segment
		(start 305.6382 -141.639798)
		(end 305.6382 -143.6878)
		(width 0.14224)
		(layer "In11.Cu")
		(net "M_F_DQ<55>")
	)
	(segment
		(start 291.73932 -117.94998)
		(end 291.89426 -117.79504)
		(width 0.14224)
		(layer "In11.Cu")
		(net "M_F_DQ<55>")
	)
	(segment
		(start 291.89426 -117.79504)
		(end 292.24732 -117.79504)
		(width 0.14224)
		(layer "In11.Cu")
		(net "M_F_DQ<55>")
	)
	(segment
		(start 284.24251 -106.143298)
		(end 284.557724 -106.458512)
		(width 0.0889)
		(layer "In11.Cu")
		(net "M_F_DQ<55>")
	)
	(segment
		(start 291.58438 -118.554246)
		(end 291.73932 -118.399306)
		(width 0.14224)
		(layer "In11.Cu")
		(net "M_F_DQ<55>")
	)
	(segment
		(start 305.501802 -141.086078)
		(end 305.501802 -141.5034)
		(width 0.14224)
		(layer "In11.Cu")
		(net "M_F_DQ<55>")
	)
	(segment
		(start 284.296104 -100.186236)
		(end 284.302454 -100.196904)
		(width 0.0889)
		(layer "In11.Cu")
		(net "M_F_DQ<55>")
	)
	(segment
		(start 305.578002 -134.070598)
		(end 305.578002 -134.579868)
		(width 0.14224)
		(layer "In11.Cu")
		(net "M_F_DQ<55>")
	)
	(segment
		(start 294.243252 -118.462044)
		(end 294.39108 -118.314216)
		(width 0.14224)
		(layer "In11.Cu")
		(net "M_F_DQ<55>")
	)
	(segment
		(start 294.39108 -117.94998)
		(end 294.54602 -117.79504)
		(width 0.14224)
		(layer "In11.Cu")
		(net "M_F_DQ<55>")
	)
	(segment
		(start 305.781202 -140.806678)
		(end 305.501802 -141.086078)
		(width 0.14224)
		(layer "In11.Cu")
		(net "M_F_DQ<55>")
	)
	(segment
		(start 279.98674 -92.727272)
		(end 280.003504 -92.756736)
		(width 0.0889)
		(layer "In11.Cu")
		(net "M_F_DQ<55>")
	)
	(segment
		(start 280.003504 -94.737936)
		(end 280.009854 -94.748604)
		(width 0.0889)
		(layer "In11.Cu")
		(net "M_F_DQ<55>")
	)
	(segment
		(start 305.6382 -131.987798)
		(end 305.6382 -134.0104)
		(width 0.14224)
		(layer "In11.Cu")
		(net "M_F_DQ<55>")
	)
	(segment
		(start 305.781202 -131.205478)
		(end 305.578002 -131.408678)
		(width 0.14224)
		(layer "In11.Cu")
		(net "M_F_DQ<55>")
	)
	(segment
		(start 305.721766 -144.313402)
		(end 305.721766 -145.661634)
		(width 0.14224)
		(layer "In11.Cu")
		(net "M_F_DQ<55>")
	)
	(segment
		(start 291.07638 -117.94998)
		(end 291.07638 -118.399306)
		(width 0.14224)
		(layer "In11.Cu")
		(net "M_F_DQ<55>")
	)
	(segment
		(start 293.890192 -118.462044)
		(end 294.243252 -118.462044)
		(width 0.14224)
		(layer "In11.Cu")
		(net "M_F_DQ<55>")
	)
	(segment
		(start 305.696366 -127.185166)
		(end 305.696366 -129.269236)
		(width 0.14224)
		(layer "In11.Cu")
		(net "M_F_DQ<55>")
	)
	(segment
		(start 305.6382 -143.6878)
		(end 305.578002 -143.747998)
		(width 0.14224)
		(layer "In11.Cu")
		(net "M_F_DQ<55>")
	)
	(segment
		(start 305.552602 -149.191472)
		(end 305.54168 -149.191472)
		(width 0.14224)
		(layer "In11.Cu")
		(net "M_F_DQ<55>")
	)
	(segment
		(start 280.335228 -95.928434)
		(end 280.367994 -95.928434)
		(width 0.0889)
		(layer "In11.Cu")
		(net "M_F_DQ<55>")
	)
	(segment
		(start 305.552602 -139.460478)
		(end 305.781202 -139.689078)
		(width 0.14224)
		(layer "In11.Cu")
		(net "M_F_DQ<55>")
	)
	(segment
		(start 280.009854 -93.336618)
		(end 280.003504 -93.347286)
		(width 0.0889)
		(layer "In11.Cu")
		(net "M_F_DQ<55>")
	)
	(segment
		(start 290.92144 -117.79504)
		(end 291.07638 -117.94998)
		(width 0.14224)
		(layer "In11.Cu")
		(net "M_F_DQ<55>")
	)
	(segment
		(start 284.557724 -106.458512)
		(end 284.557724 -106.716576)
		(width 0.0889)
		(layer "In11.Cu")
		(net "M_F_DQ<55>")
	)
	(segment
		(start 304.333148 -123.528328)
		(end 304.687732 -123.528328)
		(width 0.14224)
		(layer "In11.Cu")
		(net "M_F_DQ<55>")
	)
	(segment
		(start 305.755802 -136.077452)
		(end 305.552602 -136.280652)
		(width 0.14224)
		(layer "In11.Cu")
		(net "M_F_DQ<55>")
	)
	(segment
		(start 304.7492 -150.391368)
		(end 304.79365 -150.435818)
		(width 0.14224)
		(layer "In11.Cu")
		(net "M_F_DQ<55>")
	)
	(segment
		(start 284.291278 -104.14)
		(end 284.296104 -104.148636)
		(width 0.0889)
		(layer "In11.Cu")
		(net "M_F_DQ<55>")
	)
	(segment
		(start 305.552602 -129.413)
		(end 305.552602 -129.859278)
		(width 0.14224)
		(layer "In11.Cu")
		(net "M_F_DQ<55>")
	)
	(segment
		(start 305.781202 -139.689078)
		(end 305.781202 -140.806678)
		(width 0.14224)
		(layer "In11.Cu")
		(net "M_F_DQ<55>")
	)
	(segment
		(start 304.511202 -151.660352)
		(end 304.76825 -151.9174)
		(width 0.14224)
		(layer "In11.Cu")
		(net "M_F_DQ<55>")
	)
	(segment
		(start 305.781202 -130.087878)
		(end 305.781202 -131.205478)
		(width 0.14224)
		(layer "In11.Cu")
		(net "M_F_DQ<55>")
	)
	(segment
		(start 282.052268 -96.919034)
		(end 282.085034 -96.919034)
		(width 0.0889)
		(layer "In11.Cu")
		(net "M_F_DQ<55>")
	)
	(segment
		(start 284.781498 -106.94035)
		(end 284.781498 -112.163098)
		(width 0.14224)
		(layer "In11.Cu")
		(net "M_F_DQ<55>")
	)
	(segment
		(start 304.687732 -123.528328)
		(end 305.4858 -124.326396)
		(width 0.14224)
		(layer "In11.Cu")
		(net "M_F_DQ<55>")
	)
	(segment
		(start 305.721766 -145.661634)
		(end 305.552602 -145.830798)
		(width 0.14224)
		(layer "In11.Cu")
		(net "M_F_DQ<55>")
	)
	(segment
		(start 293.0652 -118.399306)
		(end 293.0652 -117.94998)
		(width 0.14224)
		(layer "In11.Cu")
		(net "M_F_DQ<55>")
	)
	(segment
		(start 304.79365 -151.1046)
		(end 304.511202 -151.387048)
		(width 0.14224)
		(layer "In11.Cu")
		(net "M_F_DQ<55>")
	)
	(segment
		(start 282.914598 -97.414588)
		(end 282.947364 -97.414588)
		(width 0.0889)
		(layer "In11.Cu")
		(net "M_F_DQ<55>")
	)
	(segment
		(start 284.291278 -99.187)
		(end 284.296104 -99.195636)
		(width 0.0889)
		(layer "In11.Cu")
		(net "M_F_DQ<55>")
	)
	(segment
		(start 305.552602 -136.280652)
		(end 305.552602 -136.5758)
		(width 0.14224)
		(layer "In11.Cu")
		(net "M_F_DQ<55>")
	)
	(segment
		(start 305.4858 -124.326396)
		(end 305.4858 -126.9746)
		(width 0.14224)
		(layer "In11.Cu")
		(net "M_F_DQ<55>")
	)
	(segment
		(start 305.6382 -134.0104)
		(end 305.578002 -134.070598)
		(width 0.14224)
		(layer "In11.Cu")
		(net "M_F_DQ<55>")
	)
	(segment
		(start 305.578002 -143.747998)
		(end 305.578002 -144.169638)
		(width 0.14224)
		(layer "In11.Cu")
		(net "M_F_DQ<55>")
	)
	(segment
		(start 304.6222 -153.542746)
		(end 304.349912 -153.542746)
		(width 0.14224)
		(layer "In11.Cu")
		(net "M_F_DQ<55>")
	)
	(segment
		(start 284.296104 -101.176836)
		(end 284.302454 -101.187504)
		(width 0.0889)
		(layer "In11.Cu")
		(net "M_F_DQ<55>")
	)
	(segment
		(start 284.291278 -100.1776)
		(end 284.296104 -100.186236)
		(width 0.0889)
		(layer "In11.Cu")
		(net "M_F_DQ<55>")
	)
	(segment
		(start 305.578002 -144.169638)
		(end 305.721766 -144.313402)
		(width 0.14224)
		(layer "In11.Cu")
		(net "M_F_DQ<55>")
	)
	(segment
		(start 291.07638 -118.399306)
		(end 291.23132 -118.554246)
		(width 0.14224)
		(layer "In11.Cu")
		(net "M_F_DQ<55>")
	)
	(segment
		(start 293.0652 -117.94998)
		(end 293.22014 -117.79504)
		(width 0.14224)
		(layer "In11.Cu")
		(net "M_F_DQ<55>")
	)
	(segment
		(start 305.6382 -138.8364)
		(end 305.552602 -138.921998)
		(width 0.14224)
		(layer "In11.Cu")
		(net "M_F_DQ<55>")
	)
	(segment
		(start 304.8 -153.364946)
		(end 304.6222 -153.542746)
		(width 0.14224)
		(layer "In11.Cu")
		(net "M_F_DQ<55>")
	)
	(segment
		(start 284.291278 -101.1682)
		(end 284.296104 -101.176836)
		(width 0.0889)
		(layer "In11.Cu")
		(net "M_F_DQ<55>")
	)
	(segment
		(start 298.59986 -117.79504)
		(end 304.333148 -123.528328)
		(width 0.14224)
		(layer "In11.Cu")
		(net "M_F_DQ<55>")
	)
	(segment
		(start 284.291278 -103.1494)
		(end 284.296104 -103.158036)
		(width 0.0889)
		(layer "In11.Cu")
		(net "M_F_DQ<55>")
	)
	(segment
		(start 293.72814 -118.299992)
		(end 293.890192 -118.462044)
		(width 0.14224)
		(layer "In11.Cu")
		(net "M_F_DQ<55>")
	)
	(segment
		(start 305.578002 -131.9276)
		(end 305.6382 -131.987798)
		(width 0.14224)
		(layer "In11.Cu")
		(net "M_F_DQ<55>")
	)
	(segment
		(start 291.23132 -118.554246)
		(end 291.58438 -118.554246)
		(width 0.14224)
		(layer "In11.Cu")
		(net "M_F_DQ<55>")
	)
	(segment
		(start 294.54602 -117.79504)
		(end 298.59986 -117.79504)
		(width 0.14224)
		(layer "In11.Cu")
		(net "M_F_DQ<55>")
	)
	(segment
		(start 284.291278 -105.1306)
		(end 284.296104 -105.139236)
		(width 0.0889)
		(layer "In11.Cu")
		(net "M_F_DQ<55>")
	)
	(segment
		(start 284.296104 -105.139236)
		(end 284.302454 -105.149904)
		(width 0.0889)
		(layer "In11.Cu")
		(net "M_F_DQ<55>")
	)
	(segment
		(start 283.769308 -97.909634)
		(end 283.802074 -97.909634)
		(width 0.0889)
		(layer "In11.Cu")
		(net "M_F_DQ<55>")
	)
	(segment
		(start 292.40226 -117.94998)
		(end 292.40226 -118.399306)
		(width 0.14224)
		(layer "In11.Cu")
		(net "M_F_DQ<55>")
	)
	(segment
		(start 304.7492 -149.9616)
		(end 304.7492 -150.391368)
		(width 0.14224)
		(layer "In11.Cu")
		(net "M_F_DQ<55>")
	)
	(segment
		(start 294.39108 -118.314216)
		(end 294.39108 -117.94998)
		(width 0.14224)
		(layer "In11.Cu")
		(net "M_F_DQ<55>")
	)
	(segment
		(start 290.41344 -117.79504)
		(end 290.92144 -117.79504)
		(width 0.14224)
		(layer "In11.Cu")
		(net "M_F_DQ<55>")
	)
	(segment
		(start 304.76825 -151.9174)
		(end 304.76825 -152.2222)
		(width 0.14224)
		(layer "In11.Cu")
		(net "M_F_DQ<55>")
	)
	(arc
		(start 283.437584 -97.709736)
		(mid 283.577663 -97.852472)
		(end 283.769308 -97.909634)
		(width 0.0889)
		(layer "In11.Cu")
		(net "M_F_DQ<55>")
	)
	(arc
		(start 282.085034 -96.919034)
		(mid 282.370458 -97.002501)
		(end 282.579064 -97.214436)
		(width 0.0889)
		(layer "In11.Cu")
		(net "M_F_DQ<55>")
	)
	(arc
		(start 283.802074 -97.909634)
		(mid 284.300325 -98.212474)
		(end 284.296104 -98.795586)
		(width 0.0889)
		(layer "In11.Cu")
		(net "M_F_DQ<55>")
	)
	(arc
		(start 284.302454 -103.168704)
		(mid 284.375252 -103.459467)
		(end 284.296104 -103.748586)
		(width 0.0889)
		(layer "In11.Cu")
		(net "M_F_DQ<55>")
	)
	(arc
		(start 284.302454 -101.187504)
		(mid 284.375252 -101.478267)
		(end 284.296104 -101.767386)
		(width 0.0889)
		(layer "In11.Cu")
		(net "M_F_DQ<55>")
	)
	(arc
		(start 284.302454 -100.196904)
		(mid 284.375252 -100.487667)
		(end 284.296104 -100.776786)
		(width 0.0889)
		(layer "In11.Cu")
		(net "M_F_DQ<55>")
	)
	(arc
		(start 280.862024 -96.223836)
		(mid 281.003707 -96.36764)
		(end 281.197558 -96.423988)
		(width 0.0889)
		(layer "In11.Cu")
		(net "M_F_DQ<55>")
	)
	(arc
		(start 284.302454 -99.206304)
		(mid 284.375252 -99.497067)
		(end 284.296104 -99.786186)
		(width 0.0889)
		(layer "In11.Cu")
		(net "M_F_DQ<55>")
	)
	(arc
		(start 281.720544 -96.719136)
		(mid 281.860623 -96.861872)
		(end 282.052268 -96.919034)
		(width 0.0889)
		(layer "In11.Cu")
		(net "M_F_DQ<55>")
	)
	(arc
		(start 282.947364 -97.414588)
		(mid 283.230581 -97.498869)
		(end 283.437584 -97.709736)
		(width 0.0889)
		(layer "In11.Cu")
		(net "M_F_DQ<55>")
	)
	(arc
		(start 280.367994 -95.928434)
		(mid 280.653418 -96.011901)
		(end 280.862024 -96.223836)
		(width 0.0889)
		(layer "In11.Cu")
		(net "M_F_DQ<55>")
	)
	(arc
		(start 281.230324 -96.423988)
		(mid 281.513541 -96.508269)
		(end 281.720544 -96.719136)
		(width 0.0889)
		(layer "In11.Cu")
		(net "M_F_DQ<55>")
	)
	(arc
		(start 282.579064 -97.214436)
		(mid 282.720747 -97.35824)
		(end 282.914598 -97.414588)
		(width 0.0889)
		(layer "In11.Cu")
		(net "M_F_DQ<55>")
	)
	(arc
		(start 284.302454 -104.159304)
		(mid 284.375252 -104.450067)
		(end 284.296104 -104.739186)
		(width 0.0889)
		(layer "In11.Cu")
		(net "M_F_DQ<55>")
	)
	(arc
		(start 284.302454 -105.149904)
		(mid 284.375252 -105.440667)
		(end 284.296104 -105.729786)
		(width 0.0889)
		(layer "In11.Cu")
		(net "M_F_DQ<55>")
	)
	(arc
		(start 280.003504 -94.33814)
		(mid 279.950005 -94.538038)
		(end 280.003504 -94.737936)
		(width 0.0889)
		(layer "In11.Cu")
		(net "M_F_DQ<55>")
	)
	(arc
		(start 280.009854 -94.748604)
		(mid 280.082652 -95.039367)
		(end 280.003504 -95.328486)
		(width 0.0889)
		(layer "In11.Cu")
		(net "M_F_DQ<55>")
	)
	(arc
		(start 284.296104 -100.776786)
		(mid 284.242634 -100.971849)
		(end 284.291278 -101.1682)
		(width 0.0889)
		(layer "In11.Cu")
		(net "M_F_DQ<55>")
	)
	(arc
		(start 284.296104 -99.786186)
		(mid 284.242634 -99.981249)
		(end 284.291278 -100.1776)
		(width 0.0889)
		(layer "In11.Cu")
		(net "M_F_DQ<55>")
	)
	(arc
		(start 280.003504 -93.747336)
		(mid 280.082635 -94.042738)
		(end 280.003504 -94.33814)
		(width 0.0889)
		(layer "In11.Cu")
		(net "M_F_DQ<55>")
	)
	(arc
		(start 284.296104 -101.767386)
		(mid 284.242634 -101.962449)
		(end 284.291278 -102.1588)
		(width 0.0889)
		(layer "In11.Cu")
		(net "M_F_DQ<55>")
	)
	(arc
		(start 284.296104 -104.739186)
		(mid 284.242634 -104.934249)
		(end 284.291278 -105.1306)
		(width 0.0889)
		(layer "In11.Cu")
		(net "M_F_DQ<55>")
	)
	(arc
		(start 279.998678 -93.355922)
		(mid 279.949923 -93.552274)
		(end 280.003504 -93.747336)
		(width 0.0889)
		(layer "In11.Cu")
		(net "M_F_DQ<55>")
	)
	(arc
		(start 284.302454 -102.178104)
		(mid 284.375252 -102.468867)
		(end 284.296104 -102.757986)
		(width 0.0889)
		(layer "In11.Cu")
		(net "M_F_DQ<55>")
	)
	(arc
		(start 284.296104 -98.795586)
		(mid 284.242634 -98.990649)
		(end 284.291278 -99.187)
		(width 0.0889)
		(layer "In11.Cu")
		(net "M_F_DQ<55>")
	)
	(arc
		(start 284.296104 -103.748586)
		(mid 284.242634 -103.943649)
		(end 284.291278 -104.14)
		(width 0.0889)
		(layer "In11.Cu")
		(net "M_F_DQ<55>")
	)
	(arc
		(start 284.296104 -102.757986)
		(mid 284.242634 -102.953049)
		(end 284.291278 -103.1494)
		(width 0.0889)
		(layer "In11.Cu")
		(net "M_F_DQ<55>")
	)
	(arc
		(start 284.296104 -105.729786)
		(mid 284.256117 -105.826332)
		(end 284.24251 -105.929938)
		(width 0.0889)
		(layer "In11.Cu")
		(net "M_F_DQ<55>")
	)
	(arc
		(start 280.003504 -92.756736)
		(mid 280.082726 -93.045854)
		(end 280.009854 -93.336618)
		(width 0.0889)
		(layer "In11.Cu")
		(net "M_F_DQ<55>")
	)
	(arc
		(start 279.998678 -95.337122)
		(mid 280.002425 -95.726378)
		(end 280.335228 -95.928434)
		(width 0.0889)
		(layer "In11.Cu")
		(net "M_F_DQ<55>")
	)
	(segment
		(start 305.20005 -155.9052)
		(end 305.20005 -156.87294)
		(width 0.1651)
		(layer "F.Cu")
		(net "M_F_DQ<54>")
	)
	(segment
		(start 305.20005 -156.87294)
		(end 305.200304 -156.87294)
		(width 0.1651)
		(layer "F.Cu")
		(net "M_F_DQ<54>")
	)
	(segment
		(start 305.199796 -155.1178)
		(end 305.20005 -155.118054)
		(width 0.1651)
		(layer "F.Cu")
		(net "M_F_DQ<54>")
	)
	(segment
		(start 305.33213 -155.77312)
		(end 305.20005 -155.9052)
		(width 0.1651)
		(layer "F.Cu")
		(net "M_F_DQ<54>")
	)
	(segment
		(start 305.20005 -155.118054)
		(end 305.20005 -155.4226)
		(width 0.1651)
		(layer "F.Cu")
		(net "M_F_DQ<54>")
	)
	(segment
		(start 305.33213 -155.55468)
		(end 305.33213 -155.77312)
		(width 0.1651)
		(layer "F.Cu")
		(net "M_F_DQ<54>")
	)
	(segment
		(start 278.920194 -90.080338)
		(end 279.491694 -90.080338)
		(width 0.1651)
		(layer "F.Cu")
		(net "M_F_DQ<54>")
	)
	(segment
		(start 305.20005 -155.4226)
		(end 305.33213 -155.55468)
		(width 0.1651)
		(layer "F.Cu")
		(net "M_F_DQ<54>")
	)
	(via
		(at 305.199796 -155.1178)
		(size 0.508)
		(drill 0.254)
		(layers "F.Cu" "B.Cu")
		(net "M_F_DQ<54>")
	)
	(via
		(at 279.491694 -90.080338)
		(size 0.508)
		(drill 0.254)
		(layers "F.Cu" "B.Cu")
		(net "M_F_DQ<54>")
	)
	(via
		(at 304.349912 -150.814278)
		(size 0.508)
		(drill 0.254)
		(layers "F.Cu" "B.Cu")
		(net "M_F_DQ<54>")
	)
	(segment
		(start 304.35042 -152.078436)
		(end 304.349912 -152.078182)
		(width 0.1651)
		(layer "B.Cu")
		(net "M_F_DQ<54>")
	)
	(segment
		(start 304.349912 -152.078182)
		(end 304.349912 -150.814278)
		(width 0.1651)
		(layer "B.Cu")
		(net "M_F_DQ<54>")
	)
	(segment
		(start 284.051756 -106.222546)
		(end 284.367224 -106.538014)
		(width 0.0889)
		(layer "In11.Cu")
		(net "M_F_DQ<54>")
	)
	(segment
		(start 304.829718 -136.198864)
		(end 304.829718 -139.441682)
		(width 0.14224)
		(layer "In11.Cu")
		(net "M_F_DQ<54>")
	)
	(segment
		(start 294.469058 -119.058182)
		(end 295.178988 -118.348252)
		(width 0.14224)
		(layer "In11.Cu")
		(net "M_F_DQ<54>")
	)
	(segment
		(start 298.407582 -118.348252)
		(end 304.084228 -124.024898)
		(width 0.14224)
		(layer "In11.Cu")
		(net "M_F_DQ<54>")
	)
	(segment
		(start 304.816002 -134.579868)
		(end 304.714402 -134.681468)
		(width 0.14224)
		(layer "In11.Cu")
		(net "M_F_DQ<54>")
	)
	(segment
		(start 284.131004 -102.262686)
		(end 284.13583 -102.271322)
		(width 0.0889)
		(layer "In11.Cu")
		(net "M_F_DQ<54>")
	)
	(segment
		(start 279.832054 -94.822518)
		(end 279.838404 -94.833186)
		(width 0.0889)
		(layer "In11.Cu")
		(net "M_F_DQ<54>")
	)
	(segment
		(start 304.866802 -144.118838)
		(end 304.701956 -144.283684)
		(width 0.14224)
		(layer "In11.Cu")
		(net "M_F_DQ<54>")
	)
	(segment
		(start 290.812982 -119.058182)
		(end 294.469058 -119.058182)
		(width 0.14224)
		(layer "In11.Cu")
		(net "M_F_DQ<54>")
	)
	(segment
		(start 304.268886 -150.733252)
		(end 304.349912 -150.814278)
		(width 0.14224)
		(layer "In11.Cu")
		(net "M_F_DQ<54>")
	)
	(segment
		(start 303.916842 -151.247348)
		(end 303.916842 -153.834846)
		(width 0.14224)
		(layer "In11.Cu")
		(net "M_F_DQ<54>")
	)
	(segment
		(start 279.84323 -93.2434)
		(end 279.838404 -93.252036)
		(width 0.0889)
		(layer "In11.Cu")
		(net "M_F_DQ<54>")
	)
	(segment
		(start 304.3174 -124.024898)
		(end 304.4444 -124.151898)
		(width 0.14224)
		(layer "In11.Cu")
		(net "M_F_DQ<54>")
	)
	(segment
		(start 282.907994 -97.605088)
		(end 282.94076 -97.605088)
		(width 0.0889)
		(layer "In11.Cu")
		(net "M_F_DQ<54>")
	)
	(segment
		(start 284.367224 -106.719624)
		(end 284.146498 -106.94035)
		(width 0.0889)
		(layer "In11.Cu")
		(net "M_F_DQ<54>")
	)
	(segment
		(start 304.349912 -150.814278)
		(end 303.916842 -151.247348)
		(width 0.14224)
		(layer "In11.Cu")
		(net "M_F_DQ<54>")
	)
	(segment
		(start 284.131004 -101.272086)
		(end 284.13583 -101.280722)
		(width 0.0889)
		(layer "In11.Cu")
		(net "M_F_DQ<54>")
	)
	(segment
		(start 284.124654 -103.242618)
		(end 284.131004 -103.253286)
		(width 0.0889)
		(layer "In11.Cu")
		(net "M_F_DQ<54>")
	)
	(segment
		(start 284.131004 -103.253286)
		(end 284.13583 -103.261922)
		(width 0.0889)
		(layer "In11.Cu")
		(net "M_F_DQ<54>")
	)
	(segment
		(start 304.7492 -126.334012)
		(end 304.815494 -126.400306)
		(width 0.14224)
		(layer "In11.Cu")
		(net "M_F_DQ<54>")
	)
	(segment
		(start 279.838404 -93.252036)
		(end 279.832054 -93.262704)
		(width 0.0889)
		(layer "In11.Cu")
		(net "M_F_DQ<54>")
	)
	(segment
		(start 284.124654 -100.270818)
		(end 284.131004 -100.281486)
		(width 0.0889)
		(layer "In11.Cu")
		(net "M_F_DQ<54>")
	)
	(segment
		(start 279.140158 -91.2622)
		(end 279.144984 -91.270836)
		(width 0.0889)
		(layer "In11.Cu")
		(net "M_F_DQ<54>")
	)
	(segment
		(start 279.144984 -91.270836)
		(end 279.151334 -91.281504)
		(width 0.0889)
		(layer "In11.Cu")
		(net "M_F_DQ<54>")
	)
	(segment
		(start 304.714402 -131.307078)
		(end 304.816002 -131.408678)
		(width 0.14224)
		(layer "In11.Cu")
		(net "M_F_DQ<54>")
	)
	(segment
		(start 284.124654 -102.252018)
		(end 284.131004 -102.262686)
		(width 0.0889)
		(layer "In11.Cu")
		(net "M_F_DQ<54>")
	)
	(segment
		(start 284.124654 -101.261418)
		(end 284.131004 -101.272086)
		(width 0.0889)
		(layer "In11.Cu")
		(net "M_F_DQ<54>")
	)
	(segment
		(start 284.367224 -106.538014)
		(end 284.367224 -106.719624)
		(width 0.0889)
		(layer "In11.Cu")
		(net "M_F_DQ<54>")
	)
	(segment
		(start 304.701956 -145.641822)
		(end 304.829464 -145.76933)
		(width 0.14224)
		(layer "In11.Cu")
		(net "M_F_DQ<54>")
	)
	(segment
		(start 284.146498 -106.94035)
		(end 284.146498 -112.391698)
		(width 0.14224)
		(layer "In11.Cu")
		(net "M_F_DQ<54>")
	)
	(segment
		(start 284.131004 -104.243886)
		(end 284.13583 -104.252522)
		(width 0.0889)
		(layer "In11.Cu")
		(net "M_F_DQ<54>")
	)
	(segment
		(start 303.916842 -153.834846)
		(end 305.199796 -155.1178)
		(width 0.14224)
		(layer "In11.Cu")
		(net "M_F_DQ<54>")
	)
	(segment
		(start 304.829464 -149.022816)
		(end 304.268886 -149.583394)
		(width 0.14224)
		(layer "In11.Cu")
		(net "M_F_DQ<54>")
	)
	(segment
		(start 304.866802 -140.960602)
		(end 304.866802 -144.118838)
		(width 0.14224)
		(layer "In11.Cu")
		(net "M_F_DQ<54>")
	)
	(segment
		(start 279.491694 -90.080338)
		(end 279.161748 -90.842084)
		(width 0.0889)
		(layer "In11.Cu")
		(net "M_F_DQ<54>")
	)
	(segment
		(start 284.051756 -105.929938)
		(end 284.051756 -106.222546)
		(width 0.0889)
		(layer "In11.Cu")
		(net "M_F_DQ<54>")
	)
	(segment
		(start 282.045664 -97.109534)
		(end 282.07843 -97.109534)
		(width 0.0889)
		(layer "In11.Cu")
		(net "M_F_DQ<54>")
	)
	(segment
		(start 304.268886 -149.583394)
		(end 304.268886 -150.733252)
		(width 0.14224)
		(layer "In11.Cu")
		(net "M_F_DQ<54>")
	)
	(segment
		(start 284.146498 -112.391698)
		(end 290.812982 -119.058182)
		(width 0.14224)
		(layer "In11.Cu")
		(net "M_F_DQ<54>")
	)
	(segment
		(start 304.829718 -139.441682)
		(end 304.723292 -139.548108)
		(width 0.14224)
		(layer "In11.Cu")
		(net "M_F_DQ<54>")
	)
	(segment
		(start 284.124654 -104.233218)
		(end 284.131004 -104.243886)
		(width 0.0889)
		(layer "In11.Cu")
		(net "M_F_DQ<54>")
	)
	(segment
		(start 279.84323 -94.234)
		(end 279.838404 -94.242636)
		(width 0.0889)
		(layer "In11.Cu")
		(net "M_F_DQ<54>")
	)
	(segment
		(start 295.178988 -118.348252)
		(end 298.407582 -118.348252)
		(width 0.14224)
		(layer "In11.Cu")
		(net "M_F_DQ<54>")
	)
	(segment
		(start 304.815494 -126.400306)
		(end 304.815494 -129.961386)
		(width 0.14224)
		(layer "In11.Cu")
		(net "M_F_DQ<54>")
	)
	(segment
		(start 304.4444 -125.4506)
		(end 304.7492 -125.7554)
		(width 0.14224)
		(layer "In11.Cu")
		(net "M_F_DQ<54>")
	)
	(segment
		(start 304.714402 -130.062478)
		(end 304.714402 -131.307078)
		(width 0.14224)
		(layer "In11.Cu")
		(net "M_F_DQ<54>")
	)
	(segment
		(start 304.723292 -140.817092)
		(end 304.866802 -140.960602)
		(width 0.14224)
		(layer "In11.Cu")
		(net "M_F_DQ<54>")
	)
	(segment
		(start 304.815494 -129.961386)
		(end 304.714402 -130.062478)
		(width 0.14224)
		(layer "In11.Cu")
		(net "M_F_DQ<54>")
	)
	(segment
		(start 304.816002 -131.408678)
		(end 304.816002 -134.579868)
		(width 0.14224)
		(layer "In11.Cu")
		(net "M_F_DQ<54>")
	)
	(segment
		(start 304.4444 -124.151898)
		(end 304.4444 -125.4506)
		(width 0.14224)
		(layer "In11.Cu")
		(net "M_F_DQ<54>")
	)
	(segment
		(start 284.131004 -99.290886)
		(end 284.13583 -99.299522)
		(width 0.0889)
		(layer "In11.Cu")
		(net "M_F_DQ<54>")
	)
	(segment
		(start 279.161748 -90.842084)
		(end 279.144984 -90.870786)
		(width 0.0889)
		(layer "In11.Cu")
		(net "M_F_DQ<54>")
	)
	(segment
		(start 284.124654 -105.223818)
		(end 284.131004 -105.234486)
		(width 0.0889)
		(layer "In11.Cu")
		(net "M_F_DQ<54>")
	)
	(segment
		(start 304.714402 -136.083548)
		(end 304.829718 -136.198864)
		(width 0.14224)
		(layer "In11.Cu")
		(net "M_F_DQ<54>")
	)
	(segment
		(start 280.328624 -96.118934)
		(end 280.36139 -96.118934)
		(width 0.0889)
		(layer "In11.Cu")
		(net "M_F_DQ<54>")
	)
	(segment
		(start 304.723292 -139.548108)
		(end 304.723292 -140.817092)
		(width 0.14224)
		(layer "In11.Cu")
		(net "M_F_DQ<54>")
	)
	(segment
		(start 304.084228 -124.024898)
		(end 304.3174 -124.024898)
		(width 0.14224)
		(layer "In11.Cu")
		(net "M_F_DQ<54>")
	)
	(segment
		(start 284.131004 -105.234486)
		(end 284.13583 -105.243122)
		(width 0.0889)
		(layer "In11.Cu")
		(net "M_F_DQ<54>")
	)
	(segment
		(start 284.124654 -99.280218)
		(end 284.131004 -99.290886)
		(width 0.0889)
		(layer "In11.Cu")
		(net "M_F_DQ<54>")
	)
	(segment
		(start 284.131004 -100.281486)
		(end 284.13583 -100.290122)
		(width 0.0889)
		(layer "In11.Cu")
		(net "M_F_DQ<54>")
	)
	(segment
		(start 304.714402 -134.681468)
		(end 304.714402 -136.083548)
		(width 0.14224)
		(layer "In11.Cu")
		(net "M_F_DQ<54>")
	)
	(segment
		(start 304.829464 -145.76933)
		(end 304.829464 -149.022816)
		(width 0.14224)
		(layer "In11.Cu")
		(net "M_F_DQ<54>")
	)
	(segment
		(start 281.190954 -96.614488)
		(end 281.22372 -96.614488)
		(width 0.0889)
		(layer "In11.Cu")
		(net "M_F_DQ<54>")
	)
	(segment
		(start 283.762704 -98.100134)
		(end 283.79547 -98.100134)
		(width 0.0889)
		(layer "In11.Cu")
		(net "M_F_DQ<54>")
	)
	(segment
		(start 304.701956 -144.283684)
		(end 304.701956 -145.641822)
		(width 0.14224)
		(layer "In11.Cu")
		(net "M_F_DQ<54>")
	)
	(segment
		(start 304.7492 -125.7554)
		(end 304.7492 -126.334012)
		(width 0.14224)
		(layer "In11.Cu")
		(net "M_F_DQ<54>")
	)
	(arc
		(start 279.651968 -92.685362)
		(mid 279.870327 -92.922333)
		(end 279.84323 -93.2434)
		(width 0.0889)
		(layer "In11.Cu")
		(net "M_F_DQ<54>")
	)
	(arc
		(start 284.131004 -99.690936)
		(mid 284.051782 -99.980054)
		(end 284.124654 -100.270818)
		(width 0.0889)
		(layer "In11.Cu")
		(net "M_F_DQ<54>")
	)
	(arc
		(start 284.131004 -102.662736)
		(mid 284.051782 -102.951854)
		(end 284.124654 -103.242618)
		(width 0.0889)
		(layer "In11.Cu")
		(net "M_F_DQ<54>")
	)
	(arc
		(start 284.131004 -104.643936)
		(mid 284.051782 -104.933054)
		(end 284.124654 -105.223818)
		(width 0.0889)
		(layer "In11.Cu")
		(net "M_F_DQ<54>")
	)
	(arc
		(start 284.13583 -104.252522)
		(mid 284.184585 -104.448874)
		(end 284.131004 -104.643936)
		(width 0.0889)
		(layer "In11.Cu")
		(net "M_F_DQ<54>")
	)
	(arc
		(start 284.131004 -98.700336)
		(mid 284.051782 -98.989454)
		(end 284.124654 -99.280218)
		(width 0.0889)
		(layer "In11.Cu")
		(net "M_F_DQ<54>")
	)
	(arc
		(start 281.555444 -96.814386)
		(mid 281.762448 -97.02525)
		(end 282.045664 -97.109534)
		(width 0.0889)
		(layer "In11.Cu")
		(net "M_F_DQ<54>")
	)
	(arc
		(start 284.13583 -103.261922)
		(mid 284.184585 -103.458274)
		(end 284.131004 -103.653336)
		(width 0.0889)
		(layer "In11.Cu")
		(net "M_F_DQ<54>")
	)
	(arc
		(start 284.131004 -101.672136)
		(mid 284.051782 -101.961254)
		(end 284.124654 -102.252018)
		(width 0.0889)
		(layer "In11.Cu")
		(net "M_F_DQ<54>")
	)
	(arc
		(start 279.151334 -91.281504)
		(mid 279.224132 -91.572267)
		(end 279.144984 -91.861386)
		(width 0.0889)
		(layer "In11.Cu")
		(net "M_F_DQ<54>")
	)
	(arc
		(start 280.36139 -96.118934)
		(mid 280.55524 -96.175284)
		(end 280.696924 -96.319086)
		(width 0.0889)
		(layer "In11.Cu")
		(net "M_F_DQ<54>")
	)
	(arc
		(start 283.79547 -98.100134)
		(mid 284.133639 -98.304932)
		(end 284.131004 -98.700336)
		(width 0.0889)
		(layer "In11.Cu")
		(net "M_F_DQ<54>")
	)
	(arc
		(start 284.13583 -99.299522)
		(mid 284.184585 -99.495874)
		(end 284.131004 -99.690936)
		(width 0.0889)
		(layer "In11.Cu")
		(net "M_F_DQ<54>")
	)
	(arc
		(start 284.131004 -103.653336)
		(mid 284.051782 -103.942454)
		(end 284.124654 -104.233218)
		(width 0.0889)
		(layer "In11.Cu")
		(net "M_F_DQ<54>")
	)
	(arc
		(start 282.07843 -97.109534)
		(mid 282.27228 -97.165884)
		(end 282.413964 -97.309686)
		(width 0.0889)
		(layer "In11.Cu")
		(net "M_F_DQ<54>")
	)
	(arc
		(start 279.406604 -92.501974)
		(mid 279.518693 -92.607844)
		(end 279.651968 -92.685362)
		(width 0.0889)
		(layer "In11.Cu")
		(net "M_F_DQ<54>")
	)
	(arc
		(start 284.13583 -100.290122)
		(mid 284.184585 -100.486474)
		(end 284.131004 -100.681536)
		(width 0.0889)
		(layer "In11.Cu")
		(net "M_F_DQ<54>")
	)
	(arc
		(start 282.413964 -97.309686)
		(mid 282.622572 -97.521618)
		(end 282.907994 -97.605088)
		(width 0.0889)
		(layer "In11.Cu")
		(net "M_F_DQ<54>")
	)
	(arc
		(start 279.272492 -92.39631)
		(mid 279.341868 -92.446196)
		(end 279.406604 -92.501974)
		(width 0.0889)
		(layer "In11.Cu")
		(net "M_F_DQ<54>")
	)
	(arc
		(start 282.94076 -97.605088)
		(mid 283.132402 -97.662254)
		(end 283.272484 -97.804986)
		(width 0.0889)
		(layer "In11.Cu")
		(net "M_F_DQ<54>")
	)
	(arc
		(start 283.272484 -97.804986)
		(mid 283.479488 -98.01585)
		(end 283.762704 -98.100134)
		(width 0.0889)
		(layer "In11.Cu")
		(net "M_F_DQ<54>")
	)
	(arc
		(start 284.13583 -105.243122)
		(mid 284.184585 -105.439474)
		(end 284.131004 -105.634536)
		(width 0.0889)
		(layer "In11.Cu")
		(net "M_F_DQ<54>")
	)
	(arc
		(start 279.838404 -94.242636)
		(mid 279.759182 -94.531754)
		(end 279.832054 -94.822518)
		(width 0.0889)
		(layer "In11.Cu")
		(net "M_F_DQ<54>")
	)
	(arc
		(start 284.131004 -105.634536)
		(mid 284.071937 -105.777022)
		(end 284.051756 -105.929938)
		(width 0.0889)
		(layer "In11.Cu")
		(net "M_F_DQ<54>")
	)
	(arc
		(start 284.13583 -101.280722)
		(mid 284.184585 -101.477074)
		(end 284.131004 -101.672136)
		(width 0.0889)
		(layer "In11.Cu")
		(net "M_F_DQ<54>")
	)
	(arc
		(start 279.838404 -94.833186)
		(mid 279.891903 -95.033084)
		(end 279.838404 -95.232982)
		(width 0.0889)
		(layer "In11.Cu")
		(net "M_F_DQ<54>")
	)
	(arc
		(start 284.13583 -102.271322)
		(mid 284.184585 -102.467674)
		(end 284.131004 -102.662736)
		(width 0.0889)
		(layer "In11.Cu")
		(net "M_F_DQ<54>")
	)
	(arc
		(start 280.696924 -96.319086)
		(mid 280.905532 -96.531018)
		(end 281.190954 -96.614488)
		(width 0.0889)
		(layer "In11.Cu")
		(net "M_F_DQ<54>")
	)
	(arc
		(start 284.131004 -100.681536)
		(mid 284.051782 -100.970654)
		(end 284.124654 -101.261418)
		(width 0.0889)
		(layer "In11.Cu")
		(net "M_F_DQ<54>")
	)
	(arc
		(start 279.838404 -95.232982)
		(mid 279.83315 -95.81449)
		(end 280.328624 -96.118934)
		(width 0.0889)
		(layer "In11.Cu")
		(net "M_F_DQ<54>")
	)
	(arc
		(start 279.832054 -93.262704)
		(mid 279.759256 -93.553467)
		(end 279.838404 -93.842586)
		(width 0.0889)
		(layer "In11.Cu")
		(net "M_F_DQ<54>")
	)
	(arc
		(start 279.144984 -90.870786)
		(mid 279.091514 -91.065849)
		(end 279.140158 -91.2622)
		(width 0.0889)
		(layer "In11.Cu")
		(net "M_F_DQ<54>")
	)
	(arc
		(start 279.838404 -93.842586)
		(mid 279.891874 -94.037649)
		(end 279.84323 -94.234)
		(width 0.0889)
		(layer "In11.Cu")
		(net "M_F_DQ<54>")
	)
	(arc
		(start 279.144984 -91.861386)
		(mid 279.102411 -92.154161)
		(end 279.272492 -92.39631)
		(width 0.0889)
		(layer "In11.Cu")
		(net "M_F_DQ<54>")
	)
	(arc
		(start 281.22372 -96.614488)
		(mid 281.415362 -96.671654)
		(end 281.555444 -96.814386)
		(width 0.0889)
		(layer "In11.Cu")
		(net "M_F_DQ<54>")
	)
	(segment
		(start 276.344634 -91.565984)
		(end 276.916134 -91.565984)
		(width 0.1651)
		(layer "F.Cu")
		(net "M_F_DQ<53>")
	)
	(segment
		(start 298.40047 -152.273)
		(end 298.399962 -152.278842)
		(width 0.1651)
		(layer "F.Cu")
		(net "M_F_DQ<53>")
	)
	(segment
		(start 298.399962 -152.278842)
		(end 298.399962 -153.542746)
		(width 0.1651)
		(layer "F.Cu")
		(net "M_F_DQ<53>")
	)
	(via
		(at 276.916134 -91.565984)
		(size 0.508)
		(drill 0.254)
		(layers "F.Cu" "B.Cu")
		(net "M_F_DQ<53>")
	)
	(via
		(at 299.173646 -149.533356)
		(size 0.508)
		(drill 0.254)
		(layers "F.Cu" "B.Cu")
		(net "M_F_DQ<53>")
	)
	(via
		(at 298.399962 -153.542746)
		(size 0.508)
		(drill 0.254)
		(layers "F.Cu" "B.Cu")
		(net "M_F_DQ<53>")
	)
	(segment
		(start 299.249846 -147.478496)
		(end 299.249846 -149.457156)
		(width 0.1651)
		(layer "B.Cu")
		(net "M_F_DQ<53>")
	)
	(segment
		(start 299.250354 -147.478496)
		(end 299.249846 -147.478496)
		(width 0.1651)
		(layer "B.Cu")
		(net "M_F_DQ<53>")
	)
	(segment
		(start 299.249846 -149.457156)
		(end 299.173646 -149.533356)
		(width 0.1651)
		(layer "B.Cu")
		(net "M_F_DQ<53>")
	)
	(segment
		(start 299.0723 -123.883928)
		(end 299.6184 -124.430028)
		(width 0.14224)
		(layer "In11.Cu")
		(net "M_F_DQ<53>")
	)
	(segment
		(start 298.79925 -152.348946)
		(end 298.561252 -152.586944)
		(width 0.14224)
		(layer "In11.Cu")
		(net "M_F_DQ<53>")
	)
	(segment
		(start 299.583602 -131.752848)
		(end 299.941742 -132.110988)
		(width 0.14224)
		(layer "In11.Cu")
		(net "M_F_DQ<53>")
	)
	(segment
		(start 299.7962 -146.364198)
		(end 299.7962 -148.2852)
		(width 0.14224)
		(layer "In11.Cu")
		(net "M_F_DQ<53>")
	)
	(segment
		(start 280.857198 -103.1494)
		(end 280.862024 -103.158036)
		(width 0.0889)
		(layer "In11.Cu")
		(net "M_F_DQ<53>")
	)
	(segment
		(start 299.786802 -132.564378)
		(end 299.61459 -132.564378)
		(width 0.14224)
		(layer "In11.Cu")
		(net "M_F_DQ<53>")
	)
	(segment
		(start 299.710602 -144.398238)
		(end 299.710602 -145.454624)
		(width 0.14224)
		(layer "In11.Cu")
		(net "M_F_DQ<53>")
	)
	(segment
		(start 299.558202 -148.523198)
		(end 299.558202 -149.1488)
		(width 0.14224)
		(layer "In11.Cu")
		(net "M_F_DQ<53>")
	)
	(segment
		(start 299.583602 -129.371598)
		(end 299.583602 -129.920238)
		(width 0.14224)
		(layer "In11.Cu")
		(net "M_F_DQ<53>")
	)
	(segment
		(start 276.569424 -95.328486)
		(end 276.564598 -95.337122)
		(width 0.0889)
		(layer "In11.Cu")
		(net "M_F_DQ<53>")
	)
	(segment
		(start 299.61459 -133.377178)
		(end 299.786802 -133.377178)
		(width 0.14224)
		(layer "In11.Cu")
		(net "M_F_DQ<53>")
	)
	(segment
		(start 299.441108 -128.569212)
		(end 299.719492 -128.569212)
		(width 0.14224)
		(layer "In11.Cu")
		(net "M_F_DQ<53>")
	)
	(segment
		(start 299.710602 -145.454624)
		(end 299.558202 -145.607024)
		(width 0.14224)
		(layer "In11.Cu")
		(net "M_F_DQ<53>")
	)
	(segment
		(start 297.743372 -123.854718)
		(end 297.951906 -123.854718)
		(width 0.14224)
		(layer "In11.Cu")
		(net "M_F_DQ<53>")
	)
	(segment
		(start 297.951906 -123.854718)
		(end 298.486576 -123.320048)
		(width 0.14224)
		(layer "In11.Cu")
		(net "M_F_DQ<53>")
	)
	(segment
		(start 299.786802 -133.377178)
		(end 299.941742 -133.532118)
		(width 0.14224)
		(layer "In11.Cu")
		(net "M_F_DQ<53>")
	)
	(segment
		(start 280.018744 -113.967514)
		(end 289.55111 -123.49988)
		(width 0.14224)
		(layer "In11.Cu")
		(net "M_F_DQ<53>")
	)
	(segment
		(start 278.618188 -98.900234)
		(end 278.650954 -98.900234)
		(width 0.0889)
		(layer "In11.Cu")
		(net "M_F_DQ<53>")
	)
	(segment
		(start 299.61459 -132.564378)
		(end 299.45965 -132.719318)
		(width 0.14224)
		(layer "In11.Cu")
		(net "M_F_DQ<53>")
	)
	(segment
		(start 280.133298 -105.936542)
		(end 280.133298 -106.488738)
		(width 0.0889)
		(layer "In11.Cu")
		(net "M_F_DQ<53>")
	)
	(segment
		(start 299.941742 -132.409438)
		(end 299.786802 -132.564378)
		(width 0.14224)
		(layer "In11.Cu")
		(net "M_F_DQ<53>")
	)
	(segment
		(start 298.79925 -151.993854)
		(end 298.79925 -152.348946)
		(width 0.14224)
		(layer "In11.Cu")
		(net "M_F_DQ<53>")
	)
	(segment
		(start 299.90288 -129.05232)
		(end 299.583602 -129.371598)
		(width 0.14224)
		(layer "In11.Cu")
		(net "M_F_DQ<53>")
	)
	(segment
		(start 299.173646 -149.533356)
		(end 299.151294 -149.533356)
		(width 0.14224)
		(layer "In11.Cu")
		(net "M_F_DQ<53>")
	)
	(segment
		(start 299.647102 -139.396978)
		(end 299.647102 -140.971778)
		(width 0.14224)
		(layer "In11.Cu")
		(net "M_F_DQ<53>")
	)
	(segment
		(start 276.575774 -96.308418)
		(end 276.569424 -96.319086)
		(width 0.0889)
		(layer "In11.Cu")
		(net "M_F_DQ<53>")
	)
	(segment
		(start 298.561252 -151.755856)
		(end 298.79925 -151.993854)
		(width 0.14224)
		(layer "In11.Cu")
		(net "M_F_DQ<53>")
	)
	(segment
		(start 298.716446 -123.320048)
		(end 299.0723 -123.675902)
		(width 0.14224)
		(layer "In11.Cu")
		(net "M_F_DQ<53>")
	)
	(segment
		(start 299.583602 -131.434078)
		(end 299.583602 -131.752848)
		(width 0.14224)
		(layer "In11.Cu")
		(net "M_F_DQ<53>")
	)
	(segment
		(start 299.941742 -132.110988)
		(end 299.941742 -132.409438)
		(width 0.14224)
		(layer "In11.Cu")
		(net "M_F_DQ<53>")
	)
	(segment
		(start 299.6692 -143.7386)
		(end 299.583602 -143.824198)
		(width 0.14224)
		(layer "In11.Cu")
		(net "M_F_DQ<53>")
	)
	(segment
		(start 276.586696 -92.326968)
		(end 276.564598 -92.365322)
		(width 0.0889)
		(layer "In11.Cu")
		(net "M_F_DQ<53>")
	)
	(segment
		(start 299.941742 -133.843014)
		(end 299.583602 -134.201154)
		(width 0.14224)
		(layer "In11.Cu")
		(net "M_F_DQ<53>")
	)
	(segment
		(start 280.862024 -103.158036)
		(end 280.868374 -103.168704)
		(width 0.0889)
		(layer "In11.Cu")
		(net "M_F_DQ<53>")
	)
	(segment
		(start 298.561252 -151.418544)
		(end 298.561252 -151.755856)
		(width 0.14224)
		(layer "In11.Cu")
		(net "M_F_DQ<53>")
	)
	(segment
		(start 279.480518 -99.395788)
		(end 279.513284 -99.395788)
		(width 0.0889)
		(layer "In11.Cu")
		(net "M_F_DQ<53>")
	)
	(segment
		(start 280.3652 -107.1626)
		(end 280.018744 -107.509056)
		(width 0.14224)
		(layer "In11.Cu")
		(net "M_F_DQ<53>")
	)
	(segment
		(start 299.279056 -128.40716)
		(end 299.441108 -128.569212)
		(width 0.14224)
		(layer "In11.Cu")
		(net "M_F_DQ<53>")
	)
	(segment
		(start 299.7962 -148.2852)
		(end 299.558202 -148.523198)
		(width 0.14224)
		(layer "In11.Cu")
		(net "M_F_DQ<53>")
	)
	(segment
		(start 299.583602 -141.5034)
		(end 299.6692 -141.588998)
		(width 0.14224)
		(layer "In11.Cu")
		(net "M_F_DQ<53>")
	)
	(segment
		(start 299.6184 -125.5268)
		(end 299.279056 -125.866144)
		(width 0.14224)
		(layer "In11.Cu")
		(net "M_F_DQ<53>")
	)
	(segment
		(start 280.857198 -101.1682)
		(end 280.862024 -101.176836)
		(width 0.0889)
		(layer "In11.Cu")
		(net "M_F_DQ<53>")
	)
	(segment
		(start 299.6184 -124.430028)
		(end 299.6184 -125.5268)
		(width 0.14224)
		(layer "In11.Cu")
		(net "M_F_DQ<53>")
	)
	(segment
		(start 299.583602 -143.824198)
		(end 299.583602 -144.271238)
		(width 0.14224)
		(layer "In11.Cu")
		(net "M_F_DQ<53>")
	)
	(segment
		(start 280.857198 -104.14)
		(end 280.862024 -104.148636)
		(width 0.0889)
		(layer "In11.Cu")
		(net "M_F_DQ<53>")
	)
	(segment
		(start 299.6692 -141.588998)
		(end 299.6692 -143.7386)
		(width 0.14224)
		(layer "In11.Cu")
		(net "M_F_DQ<53>")
	)
	(segment
		(start 276.569424 -94.737936)
		(end 276.575774 -94.748604)
		(width 0.0889)
		(layer "In11.Cu")
		(net "M_F_DQ<53>")
	)
	(segment
		(start 299.719492 -128.569212)
		(end 299.90288 -128.7526)
		(width 0.14224)
		(layer "In11.Cu")
		(net "M_F_DQ<53>")
	)
	(segment
		(start 297.388534 -123.49988)
		(end 297.743372 -123.854718)
		(width 0.14224)
		(layer "In11.Cu")
		(net "M_F_DQ<53>")
	)
	(segment
		(start 298.82465 -153.390346)
		(end 298.67225 -153.542746)
		(width 0.14224)
		(layer "In11.Cu")
		(net "M_F_DQ<53>")
	)
	(segment
		(start 298.67225 -153.542746)
		(end 298.399962 -153.542746)
		(width 0.14224)
		(layer "In11.Cu")
		(net "M_F_DQ<53>")
	)
	(segment
		(start 280.80843 -104.939338)
		(end 280.80843 -105.26141)
		(width 0.0889)
		(layer "In11.Cu")
		(net "M_F_DQ<53>")
	)
	(segment
		(start 289.55111 -123.49988)
		(end 297.388534 -123.49988)
		(width 0.14224)
		(layer "In11.Cu")
		(net "M_F_DQ<53>")
	)
	(segment
		(start 299.583602 -134.617968)
		(end 299.647102 -134.681468)
		(width 0.14224)
		(layer "In11.Cu")
		(net "M_F_DQ<53>")
	)
	(segment
		(start 280.862024 -102.167436)
		(end 280.868374 -102.178104)
		(width 0.0889)
		(layer "In11.Cu")
		(net "M_F_DQ<53>")
	)
	(segment
		(start 299.90288 -128.7526)
		(end 299.90288 -129.05232)
		(width 0.14224)
		(layer "In11.Cu")
		(net "M_F_DQ<53>")
	)
	(segment
		(start 280.857198 -102.1588)
		(end 280.862024 -102.167436)
		(width 0.0889)
		(layer "In11.Cu")
		(net "M_F_DQ<53>")
	)
	(segment
		(start 299.45965 -133.222238)
		(end 299.61459 -133.377178)
		(width 0.14224)
		(layer "In11.Cu")
		(net "M_F_DQ<53>")
	)
	(segment
		(start 277.763478 -98.405188)
		(end 277.796244 -98.405188)
		(width 0.0889)
		(layer "In11.Cu")
		(net "M_F_DQ<53>")
	)
	(segment
		(start 276.916134 -91.565984)
		(end 276.586696 -92.326968)
		(width 0.0889)
		(layer "In11.Cu")
		(net "M_F_DQ<53>")
	)
	(segment
		(start 280.862024 -104.148636)
		(end 280.868374 -104.159304)
		(width 0.0889)
		(layer "In11.Cu")
		(net "M_F_DQ<53>")
	)
	(segment
		(start 298.561252 -152.586944)
		(end 298.561252 -152.898856)
		(width 0.14224)
		(layer "In11.Cu")
		(net "M_F_DQ<53>")
	)
	(segment
		(start 298.82465 -153.162254)
		(end 298.82465 -153.390346)
		(width 0.14224)
		(layer "In11.Cu")
		(net "M_F_DQ<53>")
	)
	(segment
		(start 299.558202 -136.027668)
		(end 299.558202 -139.308078)
		(width 0.14224)
		(layer "In11.Cu")
		(net "M_F_DQ<53>")
	)
	(segment
		(start 299.558202 -149.1488)
		(end 299.173646 -149.533356)
		(width 0.14224)
		(layer "In11.Cu")
		(net "M_F_DQ<53>")
	)
	(segment
		(start 299.647102 -135.938768)
		(end 299.558202 -136.027668)
		(width 0.14224)
		(layer "In11.Cu")
		(net "M_F_DQ<53>")
	)
	(segment
		(start 299.558202 -139.308078)
		(end 299.647102 -139.396978)
		(width 0.14224)
		(layer "In11.Cu")
		(net "M_F_DQ<53>")
	)
	(segment
		(start 299.647102 -134.681468)
		(end 299.647102 -135.938768)
		(width 0.14224)
		(layer "In11.Cu")
		(net "M_F_DQ<53>")
	)
	(segment
		(start 276.575774 -93.336618)
		(end 276.569424 -93.347286)
		(width 0.0889)
		(layer "In11.Cu")
		(net "M_F_DQ<53>")
	)
	(segment
		(start 280.80843 -105.26141)
		(end 280.133298 -105.936542)
		(width 0.0889)
		(layer "In11.Cu")
		(net "M_F_DQ<53>")
	)
	(segment
		(start 299.45965 -132.719318)
		(end 299.45965 -133.222238)
		(width 0.14224)
		(layer "In11.Cu")
		(net "M_F_DQ<53>")
	)
	(segment
		(start 299.151294 -149.533356)
		(end 298.72305 -149.9616)
		(width 0.14224)
		(layer "In11.Cu")
		(net "M_F_DQ<53>")
	)
	(segment
		(start 299.647102 -129.983738)
		(end 299.647102 -131.370578)
		(width 0.14224)
		(layer "In11.Cu")
		(net "M_F_DQ<53>")
	)
	(segment
		(start 280.335228 -99.890834)
		(end 280.367994 -99.890834)
		(width 0.0889)
		(layer "In11.Cu")
		(net "M_F_DQ<53>")
	)
	(segment
		(start 280.862024 -101.176836)
		(end 280.868374 -101.187504)
		(width 0.0889)
		(layer "In11.Cu")
		(net "M_F_DQ<53>")
	)
	(segment
		(start 298.72305 -149.9616)
		(end 298.72305 -150.5204)
		(width 0.14224)
		(layer "In11.Cu")
		(net "M_F_DQ<53>")
	)
	(segment
		(start 299.583602 -141.035278)
		(end 299.583602 -141.5034)
		(width 0.14224)
		(layer "In11.Cu")
		(net "M_F_DQ<53>")
	)
	(segment
		(start 280.133298 -106.488738)
		(end 280.3652 -106.72064)
		(width 0.0889)
		(layer "In11.Cu")
		(net "M_F_DQ<53>")
	)
	(segment
		(start 299.647102 -140.971778)
		(end 299.583602 -141.035278)
		(width 0.14224)
		(layer "In11.Cu")
		(net "M_F_DQ<53>")
	)
	(segment
		(start 299.583602 -134.201154)
		(end 299.583602 -134.617968)
		(width 0.14224)
		(layer "In11.Cu")
		(net "M_F_DQ<53>")
	)
	(segment
		(start 276.575774 -97.299018)
		(end 276.569424 -97.309686)
		(width 0.0889)
		(layer "In11.Cu")
		(net "M_F_DQ<53>")
	)
	(segment
		(start 276.569424 -96.319086)
		(end 276.564598 -96.327722)
		(width 0.0889)
		(layer "In11.Cu")
		(net "M_F_DQ<53>")
	)
	(segment
		(start 298.561252 -152.898856)
		(end 298.82465 -153.162254)
		(width 0.14224)
		(layer "In11.Cu")
		(net "M_F_DQ<53>")
	)
	(segment
		(start 299.0723 -123.675902)
		(end 299.0723 -123.883928)
		(width 0.14224)
		(layer "In11.Cu")
		(net "M_F_DQ<53>")
	)
	(segment
		(start 276.901148 -97.909634)
		(end 276.933914 -97.909634)
		(width 0.0889)
		(layer "In11.Cu")
		(net "M_F_DQ<53>")
	)
	(segment
		(start 299.583602 -144.271238)
		(end 299.710602 -144.398238)
		(width 0.14224)
		(layer "In11.Cu")
		(net "M_F_DQ<53>")
	)
	(segment
		(start 299.583602 -129.920238)
		(end 299.647102 -129.983738)
		(width 0.14224)
		(layer "In11.Cu")
		(net "M_F_DQ<53>")
	)
	(segment
		(start 299.558202 -145.607024)
		(end 299.558202 -146.1262)
		(width 0.14224)
		(layer "In11.Cu")
		(net "M_F_DQ<53>")
	)
	(segment
		(start 298.85005 -151.129746)
		(end 298.561252 -151.418544)
		(width 0.14224)
		(layer "In11.Cu")
		(net "M_F_DQ<53>")
	)
	(segment
		(start 280.3652 -106.72064)
		(end 280.3652 -107.1626)
		(width 0.14224)
		(layer "In11.Cu")
		(net "M_F_DQ<53>")
	)
	(segment
		(start 299.941742 -133.532118)
		(end 299.941742 -133.843014)
		(width 0.14224)
		(layer "In11.Cu")
		(net "M_F_DQ<53>")
	)
	(segment
		(start 276.569424 -97.309686)
		(end 276.564598 -97.318322)
		(width 0.0889)
		(layer "In11.Cu")
		(net "M_F_DQ<53>")
	)
	(segment
		(start 299.558202 -146.1262)
		(end 299.7962 -146.364198)
		(width 0.14224)
		(layer "In11.Cu")
		(net "M_F_DQ<53>")
	)
	(segment
		(start 298.85005 -150.6474)
		(end 298.85005 -151.129746)
		(width 0.14224)
		(layer "In11.Cu")
		(net "M_F_DQ<53>")
	)
	(segment
		(start 298.72305 -150.5204)
		(end 298.85005 -150.6474)
		(width 0.14224)
		(layer "In11.Cu")
		(net "M_F_DQ<53>")
	)
	(segment
		(start 280.018744 -107.509056)
		(end 280.018744 -113.967514)
		(width 0.14224)
		(layer "In11.Cu")
		(net "M_F_DQ<53>")
	)
	(segment
		(start 299.647102 -131.370578)
		(end 299.583602 -131.434078)
		(width 0.14224)
		(layer "In11.Cu")
		(net "M_F_DQ<53>")
	)
	(segment
		(start 299.279056 -125.866144)
		(end 299.279056 -128.40716)
		(width 0.14224)
		(layer "In11.Cu")
		(net "M_F_DQ<53>")
	)
	(segment
		(start 276.569424 -93.347286)
		(end 276.564598 -93.355922)
		(width 0.0889)
		(layer "In11.Cu")
		(net "M_F_DQ<53>")
	)
	(segment
		(start 298.486576 -123.320048)
		(end 298.716446 -123.320048)
		(width 0.14224)
		(layer "In11.Cu")
		(net "M_F_DQ<53>")
	)
	(arc
		(start 280.868374 -104.159304)
		(mid 280.941172 -104.450067)
		(end 280.862024 -104.739186)
		(width 0.0889)
		(layer "In11.Cu")
		(net "M_F_DQ<53>")
	)
	(arc
		(start 280.868374 -102.178104)
		(mid 280.941172 -102.468867)
		(end 280.862024 -102.757986)
		(width 0.0889)
		(layer "In11.Cu")
		(net "M_F_DQ<53>")
	)
	(arc
		(start 280.003504 -99.690936)
		(mid 280.143583 -99.833672)
		(end 280.335228 -99.890834)
		(width 0.0889)
		(layer "In11.Cu")
		(net "M_F_DQ<53>")
	)
	(arc
		(start 280.862024 -103.748586)
		(mid 280.808554 -103.943649)
		(end 280.857198 -104.14)
		(width 0.0889)
		(layer "In11.Cu")
		(net "M_F_DQ<53>")
	)
	(arc
		(start 276.564598 -97.318322)
		(mid 276.568345 -97.707578)
		(end 276.901148 -97.909634)
		(width 0.0889)
		(layer "In11.Cu")
		(net "M_F_DQ<53>")
	)
	(arc
		(start 280.862024 -101.767386)
		(mid 280.808554 -101.962449)
		(end 280.857198 -102.1588)
		(width 0.0889)
		(layer "In11.Cu")
		(net "M_F_DQ<53>")
	)
	(arc
		(start 280.862024 -104.739186)
		(mid 280.822037 -104.835732)
		(end 280.80843 -104.939338)
		(width 0.0889)
		(layer "In11.Cu")
		(net "M_F_DQ<53>")
	)
	(arc
		(start 277.796244 -98.405188)
		(mid 278.079461 -98.489469)
		(end 278.286464 -98.700336)
		(width 0.0889)
		(layer "In11.Cu")
		(net "M_F_DQ<53>")
	)
	(arc
		(start 276.575774 -94.748604)
		(mid 276.648572 -95.039367)
		(end 276.569424 -95.328486)
		(width 0.0889)
		(layer "In11.Cu")
		(net "M_F_DQ<53>")
	)
	(arc
		(start 276.564598 -92.365322)
		(mid 276.515843 -92.561674)
		(end 276.569424 -92.756736)
		(width 0.0889)
		(layer "In11.Cu")
		(net "M_F_DQ<53>")
	)
	(arc
		(start 277.427944 -98.205036)
		(mid 277.569627 -98.34884)
		(end 277.763478 -98.405188)
		(width 0.0889)
		(layer "In11.Cu")
		(net "M_F_DQ<53>")
	)
	(arc
		(start 279.513284 -99.395788)
		(mid 279.796501 -99.480069)
		(end 280.003504 -99.690936)
		(width 0.0889)
		(layer "In11.Cu")
		(net "M_F_DQ<53>")
	)
	(arc
		(start 280.868374 -103.168704)
		(mid 280.941172 -103.459467)
		(end 280.862024 -103.748586)
		(width 0.0889)
		(layer "In11.Cu")
		(net "M_F_DQ<53>")
	)
	(arc
		(start 276.933914 -97.909634)
		(mid 277.219338 -97.993101)
		(end 277.427944 -98.205036)
		(width 0.0889)
		(layer "In11.Cu")
		(net "M_F_DQ<53>")
	)
	(arc
		(start 280.862024 -102.757986)
		(mid 280.808554 -102.953049)
		(end 280.857198 -103.1494)
		(width 0.0889)
		(layer "In11.Cu")
		(net "M_F_DQ<53>")
	)
	(arc
		(start 276.564598 -93.355922)
		(mid 276.515843 -93.552274)
		(end 276.569424 -93.747336)
		(width 0.0889)
		(layer "In11.Cu")
		(net "M_F_DQ<53>")
	)
	(arc
		(start 280.868374 -101.187504)
		(mid 280.941172 -101.478267)
		(end 280.862024 -101.767386)
		(width 0.0889)
		(layer "In11.Cu")
		(net "M_F_DQ<53>")
	)
	(arc
		(start 276.569424 -94.33814)
		(mid 276.515925 -94.538038)
		(end 276.569424 -94.737936)
		(width 0.0889)
		(layer "In11.Cu")
		(net "M_F_DQ<53>")
	)
	(arc
		(start 276.569424 -92.756736)
		(mid 276.648646 -93.045854)
		(end 276.575774 -93.336618)
		(width 0.0889)
		(layer "In11.Cu")
		(net "M_F_DQ<53>")
	)
	(arc
		(start 279.144984 -99.195636)
		(mid 279.286667 -99.33944)
		(end 279.480518 -99.395788)
		(width 0.0889)
		(layer "In11.Cu")
		(net "M_F_DQ<53>")
	)
	(arc
		(start 276.569424 -93.747336)
		(mid 276.648555 -94.042738)
		(end 276.569424 -94.33814)
		(width 0.0889)
		(layer "In11.Cu")
		(net "M_F_DQ<53>")
	)
	(arc
		(start 278.650954 -98.900234)
		(mid 278.936378 -98.983701)
		(end 279.144984 -99.195636)
		(width 0.0889)
		(layer "In11.Cu")
		(net "M_F_DQ<53>")
	)
	(arc
		(start 276.569424 -96.719136)
		(mid 276.648646 -97.008254)
		(end 276.575774 -97.299018)
		(width 0.0889)
		(layer "In11.Cu")
		(net "M_F_DQ<53>")
	)
	(arc
		(start 276.569424 -95.728536)
		(mid 276.648646 -96.017654)
		(end 276.575774 -96.308418)
		(width 0.0889)
		(layer "In11.Cu")
		(net "M_F_DQ<53>")
	)
	(arc
		(start 280.862024 -100.776786)
		(mid 280.808554 -100.971849)
		(end 280.857198 -101.1682)
		(width 0.0889)
		(layer "In11.Cu")
		(net "M_F_DQ<53>")
	)
	(arc
		(start 276.564598 -96.327722)
		(mid 276.515843 -96.524074)
		(end 276.569424 -96.719136)
		(width 0.0889)
		(layer "In11.Cu")
		(net "M_F_DQ<53>")
	)
	(arc
		(start 278.286464 -98.700336)
		(mid 278.426543 -98.843072)
		(end 278.618188 -98.900234)
		(width 0.0889)
		(layer "In11.Cu")
		(net "M_F_DQ<53>")
	)
	(arc
		(start 276.564598 -95.337122)
		(mid 276.515843 -95.533474)
		(end 276.569424 -95.728536)
		(width 0.0889)
		(layer "In11.Cu")
		(net "M_F_DQ<53>")
	)
	(arc
		(start 280.367994 -99.890834)
		(mid 280.866245 -100.193674)
		(end 280.862024 -100.776786)
		(width 0.0889)
		(layer "In11.Cu")
		(net "M_F_DQ<53>")
	)
	(segment
		(start 276.344634 -90.575384)
		(end 276.916134 -90.575384)
		(width 0.1651)
		(layer "F.Cu")
		(net "M_F_DQ<52>")
	)
	(segment
		(start 299.250354 -156.87294)
		(end 299.249846 -156.87294)
		(width 0.1651)
		(layer "F.Cu")
		(net "M_F_DQ<52>")
	)
	(segment
		(start 299.249846 -156.87294)
		(end 299.249846 -155.547568)
		(width 0.1651)
		(layer "F.Cu")
		(net "M_F_DQ<52>")
	)
	(segment
		(start 299.249846 -155.547568)
		(end 299.151802 -155.0162)
		(width 0.1651)
		(layer "F.Cu")
		(net "M_F_DQ<52>")
	)
	(via
		(at 298.399962 -150.814278)
		(size 0.508)
		(drill 0.254)
		(layers "F.Cu" "B.Cu")
		(net "M_F_DQ<52>")
	)
	(via
		(at 299.151802 -155.0162)
		(size 0.508)
		(drill 0.254)
		(layers "F.Cu" "B.Cu")
		(net "M_F_DQ<52>")
	)
	(via
		(at 276.916134 -90.575384)
		(size 0.508)
		(drill 0.254)
		(layers "F.Cu" "B.Cu")
		(net "M_F_DQ<52>")
	)
	(segment
		(start 298.399962 -152.078182)
		(end 298.399962 -150.814278)
		(width 0.1651)
		(layer "B.Cu")
		(net "M_F_DQ<52>")
	)
	(segment
		(start 298.40047 -152.078436)
		(end 298.399962 -152.078182)
		(width 0.1651)
		(layer "B.Cu")
		(net "M_F_DQ<52>")
	)
	(segment
		(start 298.90085 -155.0162)
		(end 299.151802 -155.0162)
		(width 0.14224)
		(layer "In11.Cu")
		(net "M_F_DQ<52>")
	)
	(segment
		(start 298.885102 -148.993098)
		(end 298.6024 -149.2758)
		(width 0.14224)
		(layer "In11.Cu")
		(net "M_F_DQ<52>")
	)
	(segment
		(start 298.897802 -143.729202)
		(end 298.897802 -144.078198)
		(width 0.14224)
		(layer "In11.Cu")
		(net "M_F_DQ<52>")
	)
	(segment
		(start 298.5516 -140.663676)
		(end 299.043344 -141.15542)
		(width 0.14224)
		(layer "In11.Cu")
		(net "M_F_DQ<52>")
	)
	(segment
		(start 298.2976 -149.2758)
		(end 298.085002 -149.488398)
		(width 0.14224)
		(layer "In11.Cu")
		(net "M_F_DQ<52>")
	)
	(segment
		(start 276.404324 -96.223836)
		(end 276.397974 -96.234504)
		(width 0.0889)
		(layer "In11.Cu")
		(net "M_F_DQ<52>")
	)
	(segment
		(start 298.5516 -139.8016)
		(end 298.5516 -140.663676)
		(width 0.14224)
		(layer "In11.Cu")
		(net "M_F_DQ<52>")
	)
	(segment
		(start 298.897802 -134.477252)
		(end 298.669202 -134.705852)
		(width 0.14224)
		(layer "In11.Cu")
		(net "M_F_DQ<52>")
	)
	(segment
		(start 280.690574 -102.252018)
		(end 280.696924 -102.262686)
		(width 0.0889)
		(layer "In11.Cu")
		(net "M_F_DQ<52>")
	)
	(segment
		(start 298.890436 -136.172702)
		(end 298.890436 -139.462764)
		(width 0.14224)
		(layer "In11.Cu")
		(net "M_F_DQ<52>")
	)
	(segment
		(start 276.397974 -94.822518)
		(end 276.404324 -94.833186)
		(width 0.0889)
		(layer "In11.Cu")
		(net "M_F_DQ<52>")
	)
	(segment
		(start 289.181286 -124.0282)
		(end 297.231054 -124.0282)
		(width 0.14224)
		(layer "In11.Cu")
		(net "M_F_DQ<52>")
	)
	(segment
		(start 298.885102 -145.781268)
		(end 298.885102 -148.993098)
		(width 0.14224)
		(layer "In11.Cu")
		(net "M_F_DQ<52>")
	)
	(segment
		(start 276.40915 -96.2152)
		(end 276.404324 -96.223836)
		(width 0.0889)
		(layer "In11.Cu")
		(net "M_F_DQ<52>")
	)
	(segment
		(start 298.085002 -150.499318)
		(end 298.399962 -150.814278)
		(width 0.14224)
		(layer "In11.Cu")
		(net "M_F_DQ<52>")
	)
	(segment
		(start 280.617676 -105.182162)
		(end 279.942798 -105.85704)
		(width 0.0889)
		(layer "In11.Cu")
		(net "M_F_DQ<52>")
	)
	(segment
		(start 276.404324 -91.270836)
		(end 276.397974 -91.281504)
		(width 0.0889)
		(layer "In11.Cu")
		(net "M_F_DQ<52>")
	)
	(segment
		(start 298.890436 -139.462764)
		(end 298.5516 -139.8016)
		(width 0.14224)
		(layer "In11.Cu")
		(net "M_F_DQ<52>")
	)
	(segment
		(start 298.831 -141.655546)
		(end 298.831 -143.6624)
		(width 0.14224)
		(layer "In11.Cu")
		(net "M_F_DQ<52>")
	)
	(segment
		(start 298.897802 -129.767838)
		(end 298.669202 -129.996438)
		(width 0.14224)
		(layer "In11.Cu")
		(net "M_F_DQ<52>")
	)
	(segment
		(start 298.12488 -154.24023)
		(end 298.90085 -155.0162)
		(width 0.14224)
		(layer "In11.Cu")
		(net "M_F_DQ<52>")
	)
	(segment
		(start 279.383744 -106.955844)
		(end 279.383744 -114.230658)
		(width 0.14224)
		(layer "In11.Cu")
		(net "M_F_DQ<52>")
	)
	(segment
		(start 298.669202 -129.996438)
		(end 298.669202 -131.180078)
		(width 0.14224)
		(layer "In11.Cu")
		(net "M_F_DQ<52>")
	)
	(segment
		(start 298.691554 -129.181352)
		(end 298.897802 -129.3876)
		(width 0.14224)
		(layer "In11.Cu")
		(net "M_F_DQ<52>")
	)
	(segment
		(start 276.40915 -97.2058)
		(end 276.404324 -97.214436)
		(width 0.0889)
		(layer "In11.Cu")
		(net "M_F_DQ<52>")
	)
	(segment
		(start 298.669202 -131.180078)
		(end 298.897802 -131.408678)
		(width 0.14224)
		(layer "In11.Cu")
		(net "M_F_DQ<52>")
	)
	(segment
		(start 297.966892 -153.78049)
		(end 298.12488 -153.938478)
		(width 0.14224)
		(layer "In11.Cu")
		(net "M_F_DQ<52>")
	)
	(segment
		(start 297.231054 -124.0282)
		(end 297.7896 -124.586746)
		(width 0.14224)
		(layer "In11.Cu")
		(net "M_F_DQ<52>")
	)
	(segment
		(start 298.897802 -144.078198)
		(end 298.5516 -144.4244)
		(width 0.14224)
		(layer "In11.Cu")
		(net "M_F_DQ<52>")
	)
	(segment
		(start 299.043344 -141.15542)
		(end 299.043344 -141.443202)
		(width 0.14224)
		(layer "In11.Cu")
		(net "M_F_DQ<52>")
	)
	(segment
		(start 279.383744 -114.230658)
		(end 289.181286 -124.0282)
		(width 0.14224)
		(layer "In11.Cu")
		(net "M_F_DQ<52>")
	)
	(segment
		(start 280.690574 -103.242618)
		(end 280.696924 -103.253286)
		(width 0.0889)
		(layer "In11.Cu")
		(net "M_F_DQ<52>")
	)
	(segment
		(start 280.696924 -104.243886)
		(end 280.70175 -104.252522)
		(width 0.0889)
		(layer "In11.Cu")
		(net "M_F_DQ<52>")
	)
	(segment
		(start 298.691554 -127.774954)
		(end 298.691554 -129.181352)
		(width 0.14224)
		(layer "In11.Cu")
		(net "M_F_DQ<52>")
	)
	(segment
		(start 280.696924 -102.262686)
		(end 280.70175 -102.271322)
		(width 0.0889)
		(layer "In11.Cu")
		(net "M_F_DQ<52>")
	)
	(segment
		(start 277.756874 -98.595688)
		(end 277.78964 -98.595688)
		(width 0.0889)
		(layer "In11.Cu")
		(net "M_F_DQ<52>")
	)
	(segment
		(start 297.966892 -151.247348)
		(end 297.966892 -153.78049)
		(width 0.14224)
		(layer "In11.Cu")
		(net "M_F_DQ<52>")
	)
	(segment
		(start 298.897802 -131.408678)
		(end 298.897802 -134.477252)
		(width 0.14224)
		(layer "In11.Cu")
		(net "M_F_DQ<52>")
	)
	(segment
		(start 276.404324 -93.252036)
		(end 276.397974 -93.262704)
		(width 0.0889)
		(layer "In11.Cu")
		(net "M_F_DQ<52>")
	)
	(segment
		(start 298.12488 -153.938478)
		(end 298.12488 -154.24023)
		(width 0.14224)
		(layer "In11.Cu")
		(net "M_F_DQ<52>")
	)
	(segment
		(start 276.40915 -93.2434)
		(end 276.404324 -93.252036)
		(width 0.0889)
		(layer "In11.Cu")
		(net "M_F_DQ<52>")
	)
	(segment
		(start 279.942798 -106.39679)
		(end 279.674574 -106.665014)
		(width 0.0889)
		(layer "In11.Cu")
		(net "M_F_DQ<52>")
	)
	(segment
		(start 298.399962 -150.814278)
		(end 297.966892 -151.247348)
		(width 0.14224)
		(layer "In11.Cu")
		(net "M_F_DQ<52>")
	)
	(segment
		(start 298.6024 -149.2758)
		(end 298.2976 -149.2758)
		(width 0.14224)
		(layer "In11.Cu")
		(net "M_F_DQ<52>")
	)
	(segment
		(start 298.669202 -135.951468)
		(end 298.890436 -136.172702)
		(width 0.14224)
		(layer "In11.Cu")
		(net "M_F_DQ<52>")
	)
	(segment
		(start 298.669202 -134.705852)
		(end 298.669202 -135.951468)
		(width 0.14224)
		(layer "In11.Cu")
		(net "M_F_DQ<52>")
	)
	(segment
		(start 297.7896 -126.873)
		(end 298.691554 -127.774954)
		(width 0.14224)
		(layer "In11.Cu")
		(net "M_F_DQ<52>")
	)
	(segment
		(start 298.5516 -144.4244)
		(end 298.5516 -145.447766)
		(width 0.14224)
		(layer "In11.Cu")
		(net "M_F_DQ<52>")
	)
	(segment
		(start 276.404324 -92.261436)
		(end 276.397974 -92.272104)
		(width 0.0889)
		(layer "In11.Cu")
		(net "M_F_DQ<52>")
	)
	(segment
		(start 280.696924 -103.253286)
		(end 280.70175 -103.261922)
		(width 0.0889)
		(layer "In11.Cu")
		(net "M_F_DQ<52>")
	)
	(segment
		(start 297.7896 -124.586746)
		(end 297.7896 -126.873)
		(width 0.14224)
		(layer "In11.Cu")
		(net "M_F_DQ<52>")
	)
	(segment
		(start 276.40915 -94.234)
		(end 276.404324 -94.242636)
		(width 0.0889)
		(layer "In11.Cu")
		(net "M_F_DQ<52>")
	)
	(segment
		(start 278.611584 -99.090734)
		(end 278.64435 -99.090734)
		(width 0.0889)
		(layer "In11.Cu")
		(net "M_F_DQ<52>")
	)
	(segment
		(start 279.942798 -105.85704)
		(end 279.942798 -106.39679)
		(width 0.0889)
		(layer "In11.Cu")
		(net "M_F_DQ<52>")
	)
	(segment
		(start 276.40915 -92.2528)
		(end 276.404324 -92.261436)
		(width 0.0889)
		(layer "In11.Cu")
		(net "M_F_DQ<52>")
	)
	(segment
		(start 276.916134 -90.575384)
		(end 276.421088 -91.241372)
		(width 0.0889)
		(layer "In11.Cu")
		(net "M_F_DQ<52>")
	)
	(segment
		(start 280.617676 -104.939338)
		(end 280.617676 -105.182162)
		(width 0.0889)
		(layer "In11.Cu")
		(net "M_F_DQ<52>")
	)
	(segment
		(start 279.473914 -99.586288)
		(end 279.50668 -99.586288)
		(width 0.0889)
		(layer "In11.Cu")
		(net "M_F_DQ<52>")
	)
	(segment
		(start 280.690574 -104.233218)
		(end 280.696924 -104.243886)
		(width 0.0889)
		(layer "In11.Cu")
		(net "M_F_DQ<52>")
	)
	(segment
		(start 298.831 -143.6624)
		(end 298.897802 -143.729202)
		(width 0.14224)
		(layer "In11.Cu")
		(net "M_F_DQ<52>")
	)
	(segment
		(start 298.897802 -129.3876)
		(end 298.897802 -129.767838)
		(width 0.14224)
		(layer "In11.Cu")
		(net "M_F_DQ<52>")
	)
	(segment
		(start 276.404324 -97.214436)
		(end 276.397974 -97.225104)
		(width 0.0889)
		(layer "In11.Cu")
		(net "M_F_DQ<52>")
	)
	(segment
		(start 276.894544 -98.100134)
		(end 276.92731 -98.100134)
		(width 0.0889)
		(layer "In11.Cu")
		(net "M_F_DQ<52>")
	)
	(segment
		(start 280.696924 -101.272086)
		(end 280.70175 -101.280722)
		(width 0.0889)
		(layer "In11.Cu")
		(net "M_F_DQ<52>")
	)
	(segment
		(start 298.5516 -145.447766)
		(end 298.885102 -145.781268)
		(width 0.14224)
		(layer "In11.Cu")
		(net "M_F_DQ<52>")
	)
	(segment
		(start 299.043344 -141.443202)
		(end 298.831 -141.655546)
		(width 0.14224)
		(layer "In11.Cu")
		(net "M_F_DQ<52>")
	)
	(segment
		(start 280.328624 -100.081334)
		(end 280.36139 -100.081334)
		(width 0.0889)
		(layer "In11.Cu")
		(net "M_F_DQ<52>")
	)
	(segment
		(start 298.085002 -149.488398)
		(end 298.085002 -150.499318)
		(width 0.14224)
		(layer "In11.Cu")
		(net "M_F_DQ<52>")
	)
	(segment
		(start 280.690574 -101.261418)
		(end 280.696924 -101.272086)
		(width 0.0889)
		(layer "In11.Cu")
		(net "M_F_DQ<52>")
	)
	(segment
		(start 279.674574 -106.665014)
		(end 279.383744 -106.955844)
		(width 0.14224)
		(layer "In11.Cu")
		(net "M_F_DQ<52>")
	)
	(segment
		(start 276.421088 -91.241372)
		(end 276.404324 -91.270836)
		(width 0.0889)
		(layer "In11.Cu")
		(net "M_F_DQ<52>")
	)
	(arc
		(start 276.404324 -95.823786)
		(mid 276.457794 -96.018849)
		(end 276.40915 -96.2152)
		(width 0.0889)
		(layer "In11.Cu")
		(net "M_F_DQ<52>")
	)
	(arc
		(start 276.404324 -95.232982)
		(mid 276.325193 -95.528384)
		(end 276.404324 -95.823786)
		(width 0.0889)
		(layer "In11.Cu")
		(net "M_F_DQ<52>")
	)
	(arc
		(start 276.397974 -96.234504)
		(mid 276.325176 -96.525267)
		(end 276.404324 -96.814386)
		(width 0.0889)
		(layer "In11.Cu")
		(net "M_F_DQ<52>")
	)
	(arc
		(start 276.404324 -94.242636)
		(mid 276.325102 -94.531754)
		(end 276.397974 -94.822518)
		(width 0.0889)
		(layer "In11.Cu")
		(net "M_F_DQ<52>")
	)
	(arc
		(start 276.397974 -91.281504)
		(mid 276.325176 -91.572267)
		(end 276.404324 -91.861386)
		(width 0.0889)
		(layer "In11.Cu")
		(net "M_F_DQ<52>")
	)
	(arc
		(start 278.979884 -99.290886)
		(mid 279.188492 -99.502818)
		(end 279.473914 -99.586288)
		(width 0.0889)
		(layer "In11.Cu")
		(net "M_F_DQ<52>")
	)
	(arc
		(start 276.397974 -93.262704)
		(mid 276.325176 -93.553467)
		(end 276.404324 -93.842586)
		(width 0.0889)
		(layer "In11.Cu")
		(net "M_F_DQ<52>")
	)
	(arc
		(start 280.36139 -100.081334)
		(mid 280.699559 -100.286132)
		(end 280.696924 -100.681536)
		(width 0.0889)
		(layer "In11.Cu")
		(net "M_F_DQ<52>")
	)
	(arc
		(start 280.696924 -104.643936)
		(mid 280.637857 -104.786422)
		(end 280.617676 -104.939338)
		(width 0.0889)
		(layer "In11.Cu")
		(net "M_F_DQ<52>")
	)
	(arc
		(start 280.70175 -103.261922)
		(mid 280.750505 -103.458274)
		(end 280.696924 -103.653336)
		(width 0.0889)
		(layer "In11.Cu")
		(net "M_F_DQ<52>")
	)
	(arc
		(start 276.404324 -96.814386)
		(mid 276.457794 -97.009449)
		(end 276.40915 -97.2058)
		(width 0.0889)
		(layer "In11.Cu")
		(net "M_F_DQ<52>")
	)
	(arc
		(start 276.397974 -92.272104)
		(mid 276.325176 -92.562867)
		(end 276.404324 -92.851986)
		(width 0.0889)
		(layer "In11.Cu")
		(net "M_F_DQ<52>")
	)
	(arc
		(start 276.404324 -91.861386)
		(mid 276.457794 -92.056449)
		(end 276.40915 -92.2528)
		(width 0.0889)
		(layer "In11.Cu")
		(net "M_F_DQ<52>")
	)
	(arc
		(start 276.397974 -97.225104)
		(mid 276.402005 -97.801286)
		(end 276.894544 -98.100134)
		(width 0.0889)
		(layer "In11.Cu")
		(net "M_F_DQ<52>")
	)
	(arc
		(start 277.78964 -98.595688)
		(mid 277.981282 -98.652854)
		(end 278.121364 -98.795586)
		(width 0.0889)
		(layer "In11.Cu")
		(net "M_F_DQ<52>")
	)
	(arc
		(start 280.696924 -100.681536)
		(mid 280.617702 -100.970654)
		(end 280.690574 -101.261418)
		(width 0.0889)
		(layer "In11.Cu")
		(net "M_F_DQ<52>")
	)
	(arc
		(start 276.404324 -92.851986)
		(mid 276.457794 -93.047049)
		(end 276.40915 -93.2434)
		(width 0.0889)
		(layer "In11.Cu")
		(net "M_F_DQ<52>")
	)
	(arc
		(start 278.64435 -99.090734)
		(mid 278.8382 -99.147084)
		(end 278.979884 -99.290886)
		(width 0.0889)
		(layer "In11.Cu")
		(net "M_F_DQ<52>")
	)
	(arc
		(start 276.92731 -98.100134)
		(mid 277.12116 -98.156484)
		(end 277.262844 -98.300286)
		(width 0.0889)
		(layer "In11.Cu")
		(net "M_F_DQ<52>")
	)
	(arc
		(start 280.696924 -101.672136)
		(mid 280.617702 -101.961254)
		(end 280.690574 -102.252018)
		(width 0.0889)
		(layer "In11.Cu")
		(net "M_F_DQ<52>")
	)
	(arc
		(start 279.838404 -99.786186)
		(mid 280.045408 -99.99705)
		(end 280.328624 -100.081334)
		(width 0.0889)
		(layer "In11.Cu")
		(net "M_F_DQ<52>")
	)
	(arc
		(start 276.404324 -93.842586)
		(mid 276.457794 -94.037649)
		(end 276.40915 -94.234)
		(width 0.0889)
		(layer "In11.Cu")
		(net "M_F_DQ<52>")
	)
	(arc
		(start 280.70175 -104.252522)
		(mid 280.750505 -104.448874)
		(end 280.696924 -104.643936)
		(width 0.0889)
		(layer "In11.Cu")
		(net "M_F_DQ<52>")
	)
	(arc
		(start 279.50668 -99.586288)
		(mid 279.698322 -99.643454)
		(end 279.838404 -99.786186)
		(width 0.0889)
		(layer "In11.Cu")
		(net "M_F_DQ<52>")
	)
	(arc
		(start 276.404324 -94.833186)
		(mid 276.457823 -95.033084)
		(end 276.404324 -95.232982)
		(width 0.0889)
		(layer "In11.Cu")
		(net "M_F_DQ<52>")
	)
	(arc
		(start 280.70175 -101.280722)
		(mid 280.750505 -101.477074)
		(end 280.696924 -101.672136)
		(width 0.0889)
		(layer "In11.Cu")
		(net "M_F_DQ<52>")
	)
	(arc
		(start 280.70175 -102.271322)
		(mid 280.750505 -102.467674)
		(end 280.696924 -102.662736)
		(width 0.0889)
		(layer "In11.Cu")
		(net "M_F_DQ<52>")
	)
	(arc
		(start 278.121364 -98.795586)
		(mid 278.328368 -99.00645)
		(end 278.611584 -99.090734)
		(width 0.0889)
		(layer "In11.Cu")
		(net "M_F_DQ<52>")
	)
	(arc
		(start 280.696924 -102.662736)
		(mid 280.617702 -102.951854)
		(end 280.690574 -103.242618)
		(width 0.0889)
		(layer "In11.Cu")
		(net "M_F_DQ<52>")
	)
	(arc
		(start 280.696924 -103.653336)
		(mid 280.617702 -103.942454)
		(end 280.690574 -104.233218)
		(width 0.0889)
		(layer "In11.Cu")
		(net "M_F_DQ<52>")
	)
	(arc
		(start 277.262844 -98.300286)
		(mid 277.471452 -98.512218)
		(end 277.756874 -98.595688)
		(width 0.0889)
		(layer "In11.Cu")
		(net "M_F_DQ<52>")
	)
	(segment
		(start 306.050442 -152.273)
		(end 306.049934 -152.278842)
		(width 0.1651)
		(layer "F.Cu")
		(net "M_F_DQ<51>")
	)
	(segment
		(start 306.049934 -152.278842)
		(end 306.049934 -153.542746)
		(width 0.1651)
		(layer "F.Cu")
		(net "M_F_DQ<51>")
	)
	(segment
		(start 279.778714 -91.565984)
		(end 280.350214 -91.565984)
		(width 0.1651)
		(layer "F.Cu")
		(net "M_F_DQ<51>")
	)
	(via
		(at 280.350214 -91.565984)
		(size 0.508)
		(drill 0.254)
		(layers "F.Cu" "B.Cu")
		(net "M_F_DQ<51>")
	)
	(via
		(at 306.049934 -153.542746)
		(size 0.508)
		(drill 0.254)
		(layers "F.Cu" "B.Cu")
		(net "M_F_DQ<51>")
	)
	(via
		(at 306.899818 -149.533356)
		(size 0.508)
		(drill 0.254)
		(layers "F.Cu" "B.Cu")
		(net "M_F_DQ<51>")
	)
	(segment
		(start 306.900326 -147.478496)
		(end 306.899818 -147.478496)
		(width 0.1651)
		(layer "B.Cu")
		(net "M_F_DQ<51>")
	)
	(segment
		(start 306.899818 -147.478496)
		(end 306.899818 -149.533356)
		(width 0.1651)
		(layer "B.Cu")
		(net "M_F_DQ<51>")
	)
	(segment
		(start 304.378868 -121.985532)
		(end 304.596292 -121.768108)
		(width 0.14224)
		(layer "In11.Cu")
		(net "M_F_DQ<51>")
	)
	(segment
		(start 303.18964 -120.361456)
		(end 302.972216 -120.57888)
		(width 0.14224)
		(layer "In11.Cu")
		(net "M_F_DQ<51>")
	)
	(segment
		(start 280.84526 -92.231972)
		(end 280.862024 -92.261436)
		(width 0.0889)
		(layer "In11.Cu")
		(net "M_F_DQ<51>")
	)
	(segment
		(start 307.34 -143.6116)
		(end 307.267102 -143.684498)
		(width 0.14224)
		(layer "In11.Cu")
		(net "M_F_DQ<51>")
	)
	(segment
		(start 306.899818 -149.546564)
		(end 306.899818 -149.533356)
		(width 0.14224)
		(layer "In11.Cu")
		(net "M_F_DQ<51>")
	)
	(segment
		(start 307.4162 -124.369068)
		(end 307.4162 -126.2888)
		(width 0.14224)
		(layer "In11.Cu")
		(net "M_F_DQ<51>")
	)
	(segment
		(start 280.350214 -91.565984)
		(end 280.84526 -92.231972)
		(width 0.0889)
		(layer "In11.Cu")
		(net "M_F_DQ<51>")
	)
	(segment
		(start 285.154624 -98.300286)
		(end 285.149798 -98.308922)
		(width 0.0889)
		(layer "In11.Cu")
		(net "M_F_DQ<51>")
	)
	(segment
		(start 307.254402 -129.346198)
		(end 307.254402 -129.960878)
		(width 0.14224)
		(layer "In11.Cu")
		(net "M_F_DQ<51>")
	)
	(segment
		(start 307.406802 -131.268978)
		(end 307.267102 -131.408678)
		(width 0.14224)
		(layer "In11.Cu")
		(net "M_F_DQ<51>")
	)
	(segment
		(start 307.267102 -134.573264)
		(end 307.432202 -134.738364)
		(width 0.14224)
		(layer "In11.Cu")
		(net "M_F_DQ<51>")
	)
	(segment
		(start 307.483002 -144.398238)
		(end 307.483002 -145.551652)
		(width 0.14224)
		(layer "In11.Cu")
		(net "M_F_DQ<51>")
	)
	(segment
		(start 307.267102 -134.083298)
		(end 307.267102 -134.573264)
		(width 0.14224)
		(layer "In11.Cu")
		(net "M_F_DQ<51>")
	)
	(segment
		(start 303.909984 -121.516648)
		(end 303.909984 -121.735596)
		(width 0.14224)
		(layer "In11.Cu")
		(net "M_F_DQ<51>")
	)
	(segment
		(start 307.229002 -145.805652)
		(end 307.229002 -149.21738)
		(width 0.14224)
		(layer "In11.Cu")
		(net "M_F_DQ<51>")
	)
	(segment
		(start 306.449222 -150.391368)
		(end 306.493672 -150.435818)
		(width 0.14224)
		(layer "In11.Cu")
		(net "M_F_DQ<51>")
	)
	(segment
		(start 307.406802 -140.870178)
		(end 307.267102 -141.009878)
		(width 0.14224)
		(layer "In11.Cu")
		(net "M_F_DQ<51>")
	)
	(segment
		(start 303.4411 -121.047764)
		(end 303.658524 -120.83034)
		(width 0.14224)
		(layer "In11.Cu")
		(net "M_F_DQ<51>")
	)
	(segment
		(start 307.34 -141.550898)
		(end 307.34 -143.6116)
		(width 0.14224)
		(layer "In11.Cu")
		(net "M_F_DQ<51>")
	)
	(segment
		(start 307.267102 -131.9022)
		(end 307.34 -131.975098)
		(width 0.14224)
		(layer "In11.Cu")
		(net "M_F_DQ<51>")
	)
	(segment
		(start 285.160974 -102.252018)
		(end 285.154624 -102.262686)
		(width 0.0889)
		(layer "In11.Cu")
		(net "M_F_DQ<51>")
	)
	(segment
		(start 280.862024 -92.261436)
		(end 280.868374 -92.272104)
		(width 0.0889)
		(layer "In11.Cu")
		(net "M_F_DQ<51>")
	)
	(segment
		(start 306.211224 -152.752552)
		(end 306.500022 -153.04135)
		(width 0.14224)
		(layer "In11.Cu")
		(net "M_F_DQ<51>")
	)
	(segment
		(start 307.483002 -145.551652)
		(end 307.229002 -145.805652)
		(width 0.14224)
		(layer "In11.Cu")
		(net "M_F_DQ<51>")
	)
	(segment
		(start 302.939704 -119.892572)
		(end 303.18964 -120.142508)
		(width 0.14224)
		(layer "In11.Cu")
		(net "M_F_DQ<51>")
	)
	(segment
		(start 282.914598 -96.423988)
		(end 282.947364 -96.423988)
		(width 0.0889)
		(layer "In11.Cu")
		(net "M_F_DQ<51>")
	)
	(segment
		(start 285.154624 -102.262686)
		(end 285.149798 -102.271322)
		(width 0.0889)
		(layer "In11.Cu")
		(net "M_F_DQ<51>")
	)
	(segment
		(start 286.051498 -106.665014)
		(end 286.051498 -111.553498)
		(width 0.14224)
		(layer "In11.Cu")
		(net "M_F_DQ<51>")
	)
	(segment
		(start 306.468272 -152.2222)
		(end 306.211224 -152.479248)
		(width 0.14224)
		(layer "In11.Cu")
		(net "M_F_DQ<51>")
	)
	(segment
		(start 307.267102 -141.009878)
		(end 307.267102 -141.478)
		(width 0.14224)
		(layer "In11.Cu")
		(net "M_F_DQ<51>")
	)
	(segment
		(start 307.254402 -136.204452)
		(end 307.254402 -136.5504)
		(width 0.14224)
		(layer "In11.Cu")
		(net "M_F_DQ<51>")
	)
	(segment
		(start 303.222152 -121.047764)
		(end 303.4411 -121.047764)
		(width 0.14224)
		(layer "In11.Cu")
		(net "M_F_DQ<51>")
	)
	(segment
		(start 285.154624 -103.253286)
		(end 285.149798 -103.261922)
		(width 0.0889)
		(layer "In11.Cu")
		(net "M_F_DQ<51>")
	)
	(segment
		(start 304.127408 -121.080276)
		(end 304.127408 -121.299224)
		(width 0.14224)
		(layer "In11.Cu")
		(net "M_F_DQ<51>")
	)
	(segment
		(start 285.154624 -101.272086)
		(end 285.149798 -101.280722)
		(width 0.0889)
		(layer "In11.Cu")
		(net "M_F_DQ<51>")
	)
	(segment
		(start 307.267102 -144.182338)
		(end 307.483002 -144.398238)
		(width 0.14224)
		(layer "In11.Cu")
		(net "M_F_DQ<51>")
	)
	(segment
		(start 307.4162 -126.2888)
		(end 307.3146 -126.3904)
		(width 0.14224)
		(layer "In11.Cu")
		(net "M_F_DQ<51>")
	)
	(segment
		(start 307.229002 -149.21738)
		(end 306.899818 -149.546564)
		(width 0.14224)
		(layer "In11.Cu")
		(net "M_F_DQ<51>")
	)
	(segment
		(start 285.218378 -105.71734)
		(end 285.801816 -106.300778)
		(width 0.0889)
		(layer "In11.Cu")
		(net "M_F_DQ<51>")
	)
	(segment
		(start 302.034448 -119.86006)
		(end 302.284384 -120.109996)
		(width 0.14224)
		(layer "In11.Cu")
		(net "M_F_DQ<51>")
	)
	(segment
		(start 281.197558 -95.433134)
		(end 281.221688 -95.433134)
		(width 0.0889)
		(layer "In11.Cu")
		(net "M_F_DQ<51>")
	)
	(segment
		(start 285.154624 -99.290886)
		(end 285.149798 -99.299522)
		(width 0.0889)
		(layer "In11.Cu")
		(net "M_F_DQ<51>")
	)
	(segment
		(start 307.254402 -138.845798)
		(end 307.254402 -139.562078)
		(width 0.14224)
		(layer "In11.Cu")
		(net "M_F_DQ<51>")
	)
	(segment
		(start 307.34 -134.0104)
		(end 307.267102 -134.083298)
		(width 0.14224)
		(layer "In11.Cu")
		(net "M_F_DQ<51>")
	)
	(segment
		(start 307.34 -131.975098)
		(end 307.34 -134.0104)
		(width 0.14224)
		(layer "In11.Cu")
		(net "M_F_DQ<51>")
	)
	(segment
		(start 280.857198 -94.234)
		(end 280.862024 -94.242636)
		(width 0.0889)
		(layer "In11.Cu")
		(net "M_F_DQ<51>")
	)
	(segment
		(start 285.801816 -106.415332)
		(end 286.051498 -106.665014)
		(width 0.0889)
		(layer "In11.Cu")
		(net "M_F_DQ<51>")
	)
	(segment
		(start 302.034448 -119.641112)
		(end 302.034448 -119.86006)
		(width 0.14224)
		(layer "In11.Cu")
		(net "M_F_DQ<51>")
	)
	(segment
		(start 285.154624 -105.234486)
		(end 285.149798 -105.243122)
		(width 0.0889)
		(layer "In11.Cu")
		(net "M_F_DQ<51>")
	)
	(segment
		(start 306.493672 -150.435818)
		(end 306.493672 -151.1046)
		(width 0.14224)
		(layer "In11.Cu")
		(net "M_F_DQ<51>")
	)
	(segment
		(start 280.862024 -93.252036)
		(end 280.868374 -93.262704)
		(width 0.0889)
		(layer "In11.Cu")
		(net "M_F_DQ<51>")
	)
	(segment
		(start 307.432202 -136.026652)
		(end 307.254402 -136.204452)
		(width 0.14224)
		(layer "In11.Cu")
		(net "M_F_DQ<51>")
	)
	(segment
		(start 306.211224 -151.387048)
		(end 306.211224 -151.660352)
		(width 0.14224)
		(layer "In11.Cu")
		(net "M_F_DQ<51>")
	)
	(segment
		(start 302.251872 -119.20474)
		(end 302.251872 -119.423688)
		(width 0.14224)
		(layer "In11.Cu")
		(net "M_F_DQ<51>")
	)
	(segment
		(start 283.769308 -96.919034)
		(end 283.802074 -96.919034)
		(width 0.0889)
		(layer "In11.Cu")
		(net "M_F_DQ<51>")
	)
	(segment
		(start 285.160974 -104.233218)
		(end 285.154624 -104.243886)
		(width 0.0889)
		(layer "In11.Cu")
		(net "M_F_DQ<51>")
	)
	(segment
		(start 303.658524 -120.83034)
		(end 303.877472 -120.83034)
		(width 0.14224)
		(layer "In11.Cu")
		(net "M_F_DQ<51>")
	)
	(segment
		(start 304.127408 -121.299224)
		(end 303.909984 -121.516648)
		(width 0.14224)
		(layer "In11.Cu")
		(net "M_F_DQ<51>")
	)
	(segment
		(start 285.154624 -104.243886)
		(end 285.149798 -104.252522)
		(width 0.0889)
		(layer "In11.Cu")
		(net "M_F_DQ<51>")
	)
	(segment
		(start 307.267102 -143.684498)
		(end 307.267102 -144.182338)
		(width 0.14224)
		(layer "In11.Cu")
		(net "M_F_DQ<51>")
	)
	(segment
		(start 299.657008 -116.609876)
		(end 302.251872 -119.20474)
		(width 0.14224)
		(layer "In11.Cu")
		(net "M_F_DQ<51>")
	)
	(segment
		(start 280.857198 -93.2434)
		(end 280.862024 -93.252036)
		(width 0.0889)
		(layer "In11.Cu")
		(net "M_F_DQ<51>")
	)
	(segment
		(start 285.160974 -103.242618)
		(end 285.154624 -103.253286)
		(width 0.0889)
		(layer "In11.Cu")
		(net "M_F_DQ<51>")
	)
	(segment
		(start 304.596292 -121.768108)
		(end 304.81524 -121.768108)
		(width 0.14224)
		(layer "In11.Cu")
		(net "M_F_DQ<51>")
	)
	(segment
		(start 285.154624 -100.281486)
		(end 285.149798 -100.290122)
		(width 0.0889)
		(layer "In11.Cu")
		(net "M_F_DQ<51>")
	)
	(segment
		(start 303.18964 -120.142508)
		(end 303.18964 -120.361456)
		(width 0.14224)
		(layer "In11.Cu")
		(net "M_F_DQ<51>")
	)
	(segment
		(start 302.284384 -120.109996)
		(end 302.503332 -120.109996)
		(width 0.14224)
		(layer "In11.Cu")
		(net "M_F_DQ<51>")
	)
	(segment
		(start 307.254402 -129.960878)
		(end 307.406802 -130.113278)
		(width 0.14224)
		(layer "In11.Cu")
		(net "M_F_DQ<51>")
	)
	(segment
		(start 307.267102 -141.478)
		(end 307.34 -141.550898)
		(width 0.14224)
		(layer "In11.Cu")
		(net "M_F_DQ<51>")
	)
	(segment
		(start 284.631638 -97.414588)
		(end 284.664404 -97.414588)
		(width 0.0889)
		(layer "In11.Cu")
		(net "M_F_DQ<51>")
	)
	(segment
		(start 307.3146 -138.7856)
		(end 307.254402 -138.845798)
		(width 0.14224)
		(layer "In11.Cu")
		(net "M_F_DQ<51>")
	)
	(segment
		(start 306.449222 -149.9616)
		(end 306.449222 -150.391368)
		(width 0.14224)
		(layer "In11.Cu")
		(net "M_F_DQ<51>")
	)
	(segment
		(start 302.972216 -120.57888)
		(end 302.972216 -120.797828)
		(width 0.14224)
		(layer "In11.Cu")
		(net "M_F_DQ<51>")
	)
	(segment
		(start 304.15992 -121.985532)
		(end 304.378868 -121.985532)
		(width 0.14224)
		(layer "In11.Cu")
		(net "M_F_DQ<51>")
	)
	(segment
		(start 307.3146 -129.286)
		(end 307.254402 -129.346198)
		(width 0.14224)
		(layer "In11.Cu")
		(net "M_F_DQ<51>")
	)
	(segment
		(start 280.868374 -94.822518)
		(end 280.862024 -94.833186)
		(width 0.0889)
		(layer "In11.Cu")
		(net "M_F_DQ<51>")
	)
	(segment
		(start 303.877472 -120.83034)
		(end 304.127408 -121.080276)
		(width 0.14224)
		(layer "In11.Cu")
		(net "M_F_DQ<51>")
	)
	(segment
		(start 285.160974 -100.270818)
		(end 285.154624 -100.281486)
		(width 0.0889)
		(layer "In11.Cu")
		(net "M_F_DQ<51>")
	)
	(segment
		(start 306.877466 -149.533356)
		(end 306.449222 -149.9616)
		(width 0.14224)
		(layer "In11.Cu")
		(net "M_F_DQ<51>")
	)
	(segment
		(start 307.406802 -139.714478)
		(end 307.406802 -140.870178)
		(width 0.14224)
		(layer "In11.Cu")
		(net "M_F_DQ<51>")
	)
	(segment
		(start 306.211224 -152.479248)
		(end 306.211224 -152.752552)
		(width 0.14224)
		(layer "In11.Cu")
		(net "M_F_DQ<51>")
	)
	(segment
		(start 306.211224 -151.660352)
		(end 306.468272 -151.9174)
		(width 0.14224)
		(layer "In11.Cu")
		(net "M_F_DQ<51>")
	)
	(segment
		(start 302.720756 -119.892572)
		(end 302.939704 -119.892572)
		(width 0.14224)
		(layer "In11.Cu")
		(net "M_F_DQ<51>")
	)
	(segment
		(start 282.052268 -95.928434)
		(end 282.085034 -95.928434)
		(width 0.0889)
		(layer "In11.Cu")
		(net "M_F_DQ<51>")
	)
	(segment
		(start 307.267102 -131.408678)
		(end 307.267102 -131.9022)
		(width 0.14224)
		(layer "In11.Cu")
		(net "M_F_DQ<51>")
	)
	(segment
		(start 304.81524 -121.768108)
		(end 307.4162 -124.369068)
		(width 0.14224)
		(layer "In11.Cu")
		(net "M_F_DQ<51>")
	)
	(segment
		(start 302.251872 -119.423688)
		(end 302.034448 -119.641112)
		(width 0.14224)
		(layer "In11.Cu")
		(net "M_F_DQ<51>")
	)
	(segment
		(start 291.107876 -116.609876)
		(end 299.657008 -116.609876)
		(width 0.14224)
		(layer "In11.Cu")
		(net "M_F_DQ<51>")
	)
	(segment
		(start 306.500022 -153.364946)
		(end 306.322222 -153.542746)
		(width 0.14224)
		(layer "In11.Cu")
		(net "M_F_DQ<51>")
	)
	(segment
		(start 285.160974 -101.261418)
		(end 285.154624 -101.272086)
		(width 0.0889)
		(layer "In11.Cu")
		(net "M_F_DQ<51>")
	)
	(segment
		(start 306.899818 -149.533356)
		(end 306.877466 -149.533356)
		(width 0.14224)
		(layer "In11.Cu")
		(net "M_F_DQ<51>")
	)
	(segment
		(start 306.500022 -153.04135)
		(end 306.500022 -153.364946)
		(width 0.14224)
		(layer "In11.Cu")
		(net "M_F_DQ<51>")
	)
	(segment
		(start 307.3146 -136.610598)
		(end 307.3146 -138.7856)
		(width 0.14224)
		(layer "In11.Cu")
		(net "M_F_DQ<51>")
	)
	(segment
		(start 286.051498 -111.553498)
		(end 291.107876 -116.609876)
		(width 0.14224)
		(layer "In11.Cu")
		(net "M_F_DQ<51>")
	)
	(segment
		(start 307.254402 -136.5504)
		(end 307.3146 -136.610598)
		(width 0.14224)
		(layer "In11.Cu")
		(net "M_F_DQ<51>")
	)
	(segment
		(start 306.493672 -151.1046)
		(end 306.211224 -151.387048)
		(width 0.14224)
		(layer "In11.Cu")
		(net "M_F_DQ<51>")
	)
	(segment
		(start 285.160974 -105.223818)
		(end 285.154624 -105.234486)
		(width 0.0889)
		(layer "In11.Cu")
		(net "M_F_DQ<51>")
	)
	(segment
		(start 303.909984 -121.735596)
		(end 304.15992 -121.985532)
		(width 0.14224)
		(layer "In11.Cu")
		(net "M_F_DQ<51>")
	)
	(segment
		(start 306.322222 -153.542746)
		(end 306.049934 -153.542746)
		(width 0.14224)
		(layer "In11.Cu")
		(net "M_F_DQ<51>")
	)
	(segment
		(start 307.254402 -139.562078)
		(end 307.406802 -139.714478)
		(width 0.14224)
		(layer "In11.Cu")
		(net "M_F_DQ<51>")
	)
	(segment
		(start 306.468272 -151.9174)
		(end 306.468272 -152.2222)
		(width 0.14224)
		(layer "In11.Cu")
		(net "M_F_DQ<51>")
	)
	(segment
		(start 285.801816 -106.300778)
		(end 285.801816 -106.415332)
		(width 0.0889)
		(layer "In11.Cu")
		(net "M_F_DQ<51>")
	)
	(segment
		(start 307.432202 -134.738364)
		(end 307.432202 -136.026652)
		(width 0.14224)
		(layer "In11.Cu")
		(net "M_F_DQ<51>")
	)
	(segment
		(start 302.503332 -120.109996)
		(end 302.720756 -119.892572)
		(width 0.14224)
		(layer "In11.Cu")
		(net "M_F_DQ<51>")
	)
	(segment
		(start 285.160974 -98.289618)
		(end 285.154624 -98.300286)
		(width 0.0889)
		(layer "In11.Cu")
		(net "M_F_DQ<51>")
	)
	(segment
		(start 302.972216 -120.797828)
		(end 303.222152 -121.047764)
		(width 0.14224)
		(layer "In11.Cu")
		(net "M_F_DQ<51>")
	)
	(segment
		(start 307.3146 -126.3904)
		(end 307.3146 -129.286)
		(width 0.14224)
		(layer "In11.Cu")
		(net "M_F_DQ<51>")
	)
	(segment
		(start 285.160974 -99.280218)
		(end 285.154624 -99.290886)
		(width 0.0889)
		(layer "In11.Cu")
		(net "M_F_DQ<51>")
	)
	(segment
		(start 307.406802 -130.113278)
		(end 307.406802 -131.268978)
		(width 0.14224)
		(layer "In11.Cu")
		(net "M_F_DQ<51>")
	)
	(arc
		(start 284.664404 -97.414588)
		(mid 285.156794 -97.713521)
		(end 285.160974 -98.289618)
		(width 0.0889)
		(layer "In11.Cu")
		(net "M_F_DQ<51>")
	)
	(arc
		(start 282.579064 -96.223836)
		(mid 282.720747 -96.36764)
		(end 282.914598 -96.423988)
		(width 0.0889)
		(layer "In11.Cu")
		(net "M_F_DQ<51>")
	)
	(arc
		(start 285.154624 -100.681536)
		(mid 285.233846 -100.970654)
		(end 285.160974 -101.261418)
		(width 0.0889)
		(layer "In11.Cu")
		(net "M_F_DQ<51>")
	)
	(arc
		(start 285.149798 -102.271322)
		(mid 285.101043 -102.467674)
		(end 285.154624 -102.662736)
		(width 0.0889)
		(layer "In11.Cu")
		(net "M_F_DQ<51>")
	)
	(arc
		(start 285.149798 -98.308922)
		(mid 285.101043 -98.505274)
		(end 285.154624 -98.700336)
		(width 0.0889)
		(layer "In11.Cu")
		(net "M_F_DQ<51>")
	)
	(arc
		(start 280.868374 -93.262704)
		(mid 280.941172 -93.553467)
		(end 280.862024 -93.842586)
		(width 0.0889)
		(layer "In11.Cu")
		(net "M_F_DQ<51>")
	)
	(arc
		(start 285.154624 -102.662736)
		(mid 285.233846 -102.951854)
		(end 285.160974 -103.242618)
		(width 0.0889)
		(layer "In11.Cu")
		(net "M_F_DQ<51>")
	)
	(arc
		(start 285.154624 -104.643936)
		(mid 285.233846 -104.933054)
		(end 285.160974 -105.223818)
		(width 0.0889)
		(layer "In11.Cu")
		(net "M_F_DQ<51>")
	)
	(arc
		(start 285.154624 -101.672136)
		(mid 285.233846 -101.961254)
		(end 285.160974 -102.252018)
		(width 0.0889)
		(layer "In11.Cu")
		(net "M_F_DQ<51>")
	)
	(arc
		(start 280.862024 -93.842586)
		(mid 280.808554 -94.037649)
		(end 280.857198 -94.234)
		(width 0.0889)
		(layer "In11.Cu")
		(net "M_F_DQ<51>")
	)
	(arc
		(start 282.947364 -96.423988)
		(mid 283.230581 -96.508269)
		(end 283.437584 -96.719136)
		(width 0.0889)
		(layer "In11.Cu")
		(net "M_F_DQ<51>")
	)
	(arc
		(start 285.149798 -105.243122)
		(mid 285.105223 -105.491635)
		(end 285.218378 -105.71734)
		(width 0.0889)
		(layer "In11.Cu")
		(net "M_F_DQ<51>")
	)
	(arc
		(start 285.149798 -101.280722)
		(mid 285.101043 -101.477074)
		(end 285.154624 -101.672136)
		(width 0.0889)
		(layer "In11.Cu")
		(net "M_F_DQ<51>")
	)
	(arc
		(start 283.802074 -96.919034)
		(mid 284.087498 -97.002501)
		(end 284.296104 -97.214436)
		(width 0.0889)
		(layer "In11.Cu")
		(net "M_F_DQ<51>")
	)
	(arc
		(start 285.154624 -103.653336)
		(mid 285.233846 -103.942454)
		(end 285.160974 -104.233218)
		(width 0.0889)
		(layer "In11.Cu")
		(net "M_F_DQ<51>")
	)
	(arc
		(start 280.862024 -94.833186)
		(mid 280.859441 -95.228433)
		(end 281.197558 -95.433134)
		(width 0.0889)
		(layer "In11.Cu")
		(net "M_F_DQ<51>")
	)
	(arc
		(start 285.149798 -104.252522)
		(mid 285.101043 -104.448874)
		(end 285.154624 -104.643936)
		(width 0.0889)
		(layer "In11.Cu")
		(net "M_F_DQ<51>")
	)
	(arc
		(start 283.437584 -96.719136)
		(mid 283.577663 -96.861872)
		(end 283.769308 -96.919034)
		(width 0.0889)
		(layer "In11.Cu")
		(net "M_F_DQ<51>")
	)
	(arc
		(start 280.862024 -92.851986)
		(mid 280.808554 -93.047049)
		(end 280.857198 -93.2434)
		(width 0.0889)
		(layer "In11.Cu")
		(net "M_F_DQ<51>")
	)
	(arc
		(start 284.296104 -97.214436)
		(mid 284.437787 -97.35824)
		(end 284.631638 -97.414588)
		(width 0.0889)
		(layer "In11.Cu")
		(net "M_F_DQ<51>")
	)
	(arc
		(start 280.868374 -92.272104)
		(mid 280.941172 -92.562867)
		(end 280.862024 -92.851986)
		(width 0.0889)
		(layer "In11.Cu")
		(net "M_F_DQ<51>")
	)
	(arc
		(start 281.221688 -95.433134)
		(mid 281.509833 -95.515453)
		(end 281.720544 -95.728536)
		(width 0.0889)
		(layer "In11.Cu")
		(net "M_F_DQ<51>")
	)
	(arc
		(start 285.149798 -103.261922)
		(mid 285.101043 -103.458274)
		(end 285.154624 -103.653336)
		(width 0.0889)
		(layer "In11.Cu")
		(net "M_F_DQ<51>")
	)
	(arc
		(start 281.720544 -95.728536)
		(mid 281.860623 -95.871272)
		(end 282.052268 -95.928434)
		(width 0.0889)
		(layer "In11.Cu")
		(net "M_F_DQ<51>")
	)
	(arc
		(start 285.149798 -99.299522)
		(mid 285.101043 -99.495874)
		(end 285.154624 -99.690936)
		(width 0.0889)
		(layer "In11.Cu")
		(net "M_F_DQ<51>")
	)
	(arc
		(start 285.154624 -99.690936)
		(mid 285.233846 -99.980054)
		(end 285.160974 -100.270818)
		(width 0.0889)
		(layer "In11.Cu")
		(net "M_F_DQ<51>")
	)
	(arc
		(start 280.862024 -94.242636)
		(mid 280.941246 -94.531754)
		(end 280.868374 -94.822518)
		(width 0.0889)
		(layer "In11.Cu")
		(net "M_F_DQ<51>")
	)
	(arc
		(start 285.154624 -98.700336)
		(mid 285.233846 -98.989454)
		(end 285.160974 -99.280218)
		(width 0.0889)
		(layer "In11.Cu")
		(net "M_F_DQ<51>")
	)
	(arc
		(start 282.085034 -95.928434)
		(mid 282.370458 -96.011901)
		(end 282.579064 -96.223836)
		(width 0.0889)
		(layer "In11.Cu")
		(net "M_F_DQ<51>")
	)
	(arc
		(start 285.149798 -100.290122)
		(mid 285.101043 -100.486474)
		(end 285.154624 -100.681536)
		(width 0.0889)
		(layer "In11.Cu")
		(net "M_F_DQ<51>")
	)
	(segment
		(start 306.899818 -156.87294)
		(end 306.900326 -156.87294)
		(width 0.1651)
		(layer "F.Cu")
		(net "M_F_DQ<50>")
	)
	(segment
		(start 306.899818 -155.881832)
		(end 306.899818 -156.87294)
		(width 0.1651)
		(layer "F.Cu")
		(net "M_F_DQ<50>")
	)
	(segment
		(start 307.03139 -155.52674)
		(end 307.03139 -155.75026)
		(width 0.1651)
		(layer "F.Cu")
		(net "M_F_DQ<50>")
	)
	(segment
		(start 306.899818 -155.1178)
		(end 306.899818 -155.395168)
		(width 0.1651)
		(layer "F.Cu")
		(net "M_F_DQ<50>")
	)
	(segment
		(start 307.03139 -155.75026)
		(end 306.899818 -155.881832)
		(width 0.1651)
		(layer "F.Cu")
		(net "M_F_DQ<50>")
	)
	(segment
		(start 306.899818 -155.395168)
		(end 307.03139 -155.52674)
		(width 0.1651)
		(layer "F.Cu")
		(net "M_F_DQ<50>")
	)
	(segment
		(start 279.778714 -90.575384)
		(end 280.350214 -90.575384)
		(width 0.1651)
		(layer "F.Cu")
		(net "M_F_DQ<50>")
	)
	(via
		(at 280.350214 -90.575384)
		(size 0.508)
		(drill 0.254)
		(layers "F.Cu" "B.Cu")
		(net "M_F_DQ<50>")
	)
	(via
		(at 306.049934 -150.814278)
		(size 0.508)
		(drill 0.254)
		(layers "F.Cu" "B.Cu")
		(net "M_F_DQ<50>")
	)
	(via
		(at 306.899818 -155.1178)
		(size 0.508)
		(drill 0.254)
		(layers "F.Cu" "B.Cu")
		(net "M_F_DQ<50>")
	)
	(segment
		(start 306.049934 -152.078182)
		(end 306.049934 -150.814278)
		(width 0.1651)
		(layer "B.Cu")
		(net "M_F_DQ<50>")
	)
	(segment
		(start 306.050442 -152.078436)
		(end 306.049934 -152.078182)
		(width 0.1651)
		(layer "B.Cu")
		(net "M_F_DQ<50>")
	)
	(segment
		(start 306.340002 -144.372838)
		(end 306.340002 -145.578068)
		(width 0.14224)
		(layer "In11.Cu")
		(net "M_F_DQ<50>")
	)
	(segment
		(start 306.619402 -143.780002)
		(end 306.619402 -144.093438)
		(width 0.14224)
		(layer "In11.Cu")
		(net "M_F_DQ<50>")
	)
	(segment
		(start 306.390802 -136.058148)
		(end 306.6034 -136.270746)
		(width 0.14224)
		(layer "In11.Cu")
		(net "M_F_DQ<50>")
	)
	(segment
		(start 306.4764 -138.8618)
		(end 306.543202 -138.928602)
		(width 0.14224)
		(layer "In11.Cu")
		(net "M_F_DQ<50>")
	)
	(segment
		(start 306.475384 -143.635984)
		(end 306.619402 -143.780002)
		(width 0.14224)
		(layer "In11.Cu")
		(net "M_F_DQ<50>")
	)
	(segment
		(start 306.619402 -141.4526)
		(end 306.475384 -141.596618)
		(width 0.14224)
		(layer "In11.Cu")
		(net "M_F_DQ<50>")
	)
	(segment
		(start 284.99435 -104.14)
		(end 284.989524 -104.148636)
		(width 0.0889)
		(layer "In11.Cu")
		(net "M_F_DQ<50>")
	)
	(segment
		(start 283.762704 -97.109534)
		(end 283.79547 -97.109534)
		(width 0.0889)
		(layer "In11.Cu")
		(net "M_F_DQ<50>")
	)
	(segment
		(start 280.696924 -94.737936)
		(end 280.690574 -94.748604)
		(width 0.0889)
		(layer "In11.Cu")
		(net "M_F_DQ<50>")
	)
	(segment
		(start 306.049934 -150.814278)
		(end 305.616864 -151.247348)
		(width 0.14224)
		(layer "In11.Cu")
		(net "M_F_DQ<50>")
	)
	(segment
		(start 284.99435 -100.1776)
		(end 284.989524 -100.186236)
		(width 0.0889)
		(layer "In11.Cu")
		(net "M_F_DQ<50>")
	)
	(segment
		(start 306.6034 -136.270746)
		(end 306.6034 -136.566402)
		(width 0.14224)
		(layer "In11.Cu")
		(net "M_F_DQ<50>")
	)
	(segment
		(start 284.989524 -100.186236)
		(end 284.983174 -100.196904)
		(width 0.0889)
		(layer "In11.Cu")
		(net "M_F_DQ<50>")
	)
	(segment
		(start 306.705 -131.4958)
		(end 306.705 -131.829302)
		(width 0.14224)
		(layer "In11.Cu")
		(net "M_F_DQ<50>")
	)
	(segment
		(start 305.705002 -150.469346)
		(end 306.049934 -150.814278)
		(width 0.14224)
		(layer "In11.Cu")
		(net "M_F_DQ<50>")
	)
	(segment
		(start 305.616864 -153.834846)
		(end 306.899818 -155.1178)
		(width 0.14224)
		(layer "In11.Cu")
		(net "M_F_DQ<50>")
	)
	(segment
		(start 306.451 -124.923804)
		(end 306.451 -126.359412)
		(width 0.14224)
		(layer "In11.Cu")
		(net "M_F_DQ<50>")
	)
	(segment
		(start 306.543202 -138.928602)
		(end 306.543202 -139.435078)
		(width 0.14224)
		(layer "In11.Cu")
		(net "M_F_DQ<50>")
	)
	(segment
		(start 306.6034 -136.566402)
		(end 306.4764 -136.693402)
		(width 0.14224)
		(layer "In11.Cu")
		(net "M_F_DQ<50>")
	)
	(segment
		(start 284.989524 -104.148636)
		(end 284.983174 -104.159304)
		(width 0.0889)
		(layer "In11.Cu")
		(net "M_F_DQ<50>")
	)
	(segment
		(start 305.092354 -122.989086)
		(end 306.545996 -124.442728)
		(width 0.14224)
		(layer "In11.Cu")
		(net "M_F_DQ<50>")
	)
	(segment
		(start 298.649136 -117.163342)
		(end 304.47488 -122.989086)
		(width 0.14224)
		(layer "In11.Cu")
		(net "M_F_DQ<50>")
	)
	(segment
		(start 284.989524 -105.139236)
		(end 284.983174 -105.149904)
		(width 0.0889)
		(layer "In11.Cu")
		(net "M_F_DQ<50>")
	)
	(segment
		(start 306.416202 -140.933678)
		(end 306.619402 -141.136878)
		(width 0.14224)
		(layer "In11.Cu")
		(net "M_F_DQ<50>")
	)
	(segment
		(start 284.99435 -98.1964)
		(end 284.989524 -98.205036)
		(width 0.0889)
		(layer "In11.Cu")
		(net "M_F_DQ<50>")
	)
	(segment
		(start 306.390802 -134.712964)
		(end 306.390802 -136.058148)
		(width 0.14224)
		(layer "In11.Cu")
		(net "M_F_DQ<50>")
	)
	(segment
		(start 306.543202 -129.833878)
		(end 306.416202 -129.960878)
		(width 0.14224)
		(layer "In11.Cu")
		(net "M_F_DQ<50>")
	)
	(segment
		(start 284.989524 -99.195636)
		(end 284.983174 -99.206304)
		(width 0.0889)
		(layer "In11.Cu")
		(net "M_F_DQ<50>")
	)
	(segment
		(start 284.99435 -101.1682)
		(end 284.989524 -101.176836)
		(width 0.0889)
		(layer "In11.Cu")
		(net "M_F_DQ<50>")
	)
	(segment
		(start 284.989524 -103.158036)
		(end 284.983174 -103.168704)
		(width 0.0889)
		(layer "In11.Cu")
		(net "M_F_DQ<50>")
	)
	(segment
		(start 306.615592 -134.200392)
		(end 306.615592 -134.488174)
		(width 0.14224)
		(layer "In11.Cu")
		(net "M_F_DQ<50>")
	)
	(segment
		(start 306.543202 -127.085598)
		(end 306.3494 -127.2794)
		(width 0.14224)
		(layer "In11.Cu")
		(net "M_F_DQ<50>")
	)
	(segment
		(start 306.340002 -145.578068)
		(end 306.568602 -145.806668)
		(width 0.14224)
		(layer "In11.Cu")
		(net "M_F_DQ<50>")
	)
	(segment
		(start 280.350214 -90.575384)
		(end 279.94483 -91.120722)
		(width 0.0889)
		(layer "In11.Cu")
		(net "M_F_DQ<50>")
	)
	(segment
		(start 306.451 -126.359412)
		(end 306.543202 -126.451614)
		(width 0.14224)
		(layer "In11.Cu")
		(net "M_F_DQ<50>")
	)
	(segment
		(start 306.416202 -139.562078)
		(end 306.416202 -140.933678)
		(width 0.14224)
		(layer "In11.Cu")
		(net "M_F_DQ<50>")
	)
	(segment
		(start 282.907994 -96.614488)
		(end 282.94076 -96.614488)
		(width 0.0889)
		(layer "In11.Cu")
		(net "M_F_DQ<50>")
	)
	(segment
		(start 306.543202 -126.451614)
		(end 306.543202 -127.085598)
		(width 0.14224)
		(layer "In11.Cu")
		(net "M_F_DQ<50>")
	)
	(segment
		(start 306.545996 -124.828808)
		(end 306.451 -124.923804)
		(width 0.14224)
		(layer "In11.Cu")
		(net "M_F_DQ<50>")
	)
	(segment
		(start 284.625034 -97.605088)
		(end 284.6578 -97.605088)
		(width 0.0889)
		(layer "In11.Cu")
		(net "M_F_DQ<50>")
	)
	(segment
		(start 281.19578 -95.623888)
		(end 281.22372 -95.623888)
		(width 0.0889)
		(layer "In11.Cu")
		(net "M_F_DQ<50>")
	)
	(segment
		(start 285.611316 -106.379518)
		(end 285.611316 -106.470196)
		(width 0.0889)
		(layer "In11.Cu")
		(net "M_F_DQ<50>")
	)
	(segment
		(start 306.545996 -124.442728)
		(end 306.545996 -124.828808)
		(width 0.14224)
		(layer "In11.Cu")
		(net "M_F_DQ<50>")
	)
	(segment
		(start 284.99435 -103.1494)
		(end 284.989524 -103.158036)
		(width 0.0889)
		(layer "In11.Cu")
		(net "M_F_DQ<50>")
	)
	(segment
		(start 285.08325 -105.851452)
		(end 285.611316 -106.379518)
		(width 0.0889)
		(layer "In11.Cu")
		(net "M_F_DQ<50>")
	)
	(segment
		(start 306.475384 -141.596618)
		(end 306.475384 -143.635984)
		(width 0.14224)
		(layer "In11.Cu")
		(net "M_F_DQ<50>")
	)
	(segment
		(start 284.99435 -99.187)
		(end 284.989524 -99.195636)
		(width 0.0889)
		(layer "In11.Cu")
		(net "M_F_DQ<50>")
	)
	(segment
		(start 282.045664 -96.118934)
		(end 282.07843 -96.118934)
		(width 0.0889)
		(layer "In11.Cu")
		(net "M_F_DQ<50>")
	)
	(segment
		(start 284.989524 -98.205036)
		(end 284.983174 -98.215704)
		(width 0.0889)
		(layer "In11.Cu")
		(net "M_F_DQ<50>")
	)
	(segment
		(start 306.3494 -129.193798)
		(end 306.543202 -129.3876)
		(width 0.14224)
		(layer "In11.Cu")
		(net "M_F_DQ<50>")
	)
	(segment
		(start 306.568602 -145.806668)
		(end 306.568602 -148.972778)
		(width 0.14224)
		(layer "In11.Cu")
		(net "M_F_DQ<50>")
	)
	(segment
		(start 284.989524 -101.176836)
		(end 284.983174 -101.187504)
		(width 0.0889)
		(layer "In11.Cu")
		(net "M_F_DQ<50>")
	)
	(segment
		(start 306.543202 -139.435078)
		(end 306.416202 -139.562078)
		(width 0.14224)
		(layer "In11.Cu")
		(net "M_F_DQ<50>")
	)
	(segment
		(start 306.4764 -136.693402)
		(end 306.4764 -138.8618)
		(width 0.14224)
		(layer "In11.Cu")
		(net "M_F_DQ<50>")
	)
	(segment
		(start 306.4764 -134.0612)
		(end 306.615592 -134.200392)
		(width 0.14224)
		(layer "In11.Cu")
		(net "M_F_DQ<50>")
	)
	(segment
		(start 306.3494 -127.2794)
		(end 306.3494 -129.193798)
		(width 0.14224)
		(layer "In11.Cu")
		(net "M_F_DQ<50>")
	)
	(segment
		(start 280.690574 -93.336618)
		(end 280.696924 -93.347286)
		(width 0.0889)
		(layer "In11.Cu")
		(net "M_F_DQ<50>")
	)
	(segment
		(start 284.99435 -105.1306)
		(end 284.989524 -105.139236)
		(width 0.0889)
		(layer "In11.Cu")
		(net "M_F_DQ<50>")
	)
	(segment
		(start 306.568602 -148.972778)
		(end 305.705002 -149.836378)
		(width 0.14224)
		(layer "In11.Cu")
		(net "M_F_DQ<50>")
	)
	(segment
		(start 285.416498 -106.665014)
		(end 285.416498 -111.832898)
		(width 0.14224)
		(layer "In11.Cu")
		(net "M_F_DQ<50>")
	)
	(segment
		(start 280.696924 -93.347286)
		(end 280.70175 -93.355922)
		(width 0.0889)
		(layer "In11.Cu")
		(net "M_F_DQ<50>")
	)
	(segment
		(start 305.705002 -149.836378)
		(end 305.705002 -150.469346)
		(width 0.14224)
		(layer "In11.Cu")
		(net "M_F_DQ<50>")
	)
	(segment
		(start 306.705 -131.829302)
		(end 306.4764 -132.057902)
		(width 0.14224)
		(layer "In11.Cu")
		(net "M_F_DQ<50>")
	)
	(segment
		(start 306.615592 -134.488174)
		(end 306.390802 -134.712964)
		(width 0.14224)
		(layer "In11.Cu")
		(net "M_F_DQ<50>")
	)
	(segment
		(start 284.989524 -102.167436)
		(end 284.983174 -102.178104)
		(width 0.0889)
		(layer "In11.Cu")
		(net "M_F_DQ<50>")
	)
	(segment
		(start 285.416498 -111.832898)
		(end 290.746942 -117.163342)
		(width 0.14224)
		(layer "In11.Cu")
		(net "M_F_DQ<50>")
	)
	(segment
		(start 290.746942 -117.163342)
		(end 298.649136 -117.163342)
		(width 0.14224)
		(layer "In11.Cu")
		(net "M_F_DQ<50>")
	)
	(segment
		(start 306.619402 -144.093438)
		(end 306.340002 -144.372838)
		(width 0.14224)
		(layer "In11.Cu")
		(net "M_F_DQ<50>")
	)
	(segment
		(start 306.416202 -129.960878)
		(end 306.416202 -131.207002)
		(width 0.14224)
		(layer "In11.Cu")
		(net "M_F_DQ<50>")
	)
	(segment
		(start 284.99435 -102.1588)
		(end 284.989524 -102.167436)
		(width 0.0889)
		(layer "In11.Cu")
		(net "M_F_DQ<50>")
	)
	(segment
		(start 305.616864 -151.247348)
		(end 305.616864 -153.834846)
		(width 0.14224)
		(layer "In11.Cu")
		(net "M_F_DQ<50>")
	)
	(segment
		(start 306.543202 -129.3876)
		(end 306.543202 -129.833878)
		(width 0.14224)
		(layer "In11.Cu")
		(net "M_F_DQ<50>")
	)
	(segment
		(start 306.416202 -131.207002)
		(end 306.705 -131.4958)
		(width 0.14224)
		(layer "In11.Cu")
		(net "M_F_DQ<50>")
	)
	(segment
		(start 306.619402 -141.136878)
		(end 306.619402 -141.4526)
		(width 0.14224)
		(layer "In11.Cu")
		(net "M_F_DQ<50>")
	)
	(segment
		(start 306.4764 -132.057902)
		(end 306.4764 -134.0612)
		(width 0.14224)
		(layer "In11.Cu")
		(net "M_F_DQ<50>")
	)
	(segment
		(start 285.611316 -106.470196)
		(end 285.416498 -106.665014)
		(width 0.0889)
		(layer "In11.Cu")
		(net "M_F_DQ<50>")
	)
	(segment
		(start 304.47488 -122.989086)
		(end 305.092354 -122.989086)
		(width 0.14224)
		(layer "In11.Cu")
		(net "M_F_DQ<50>")
	)
	(arc
		(start 280.70175 -93.355922)
		(mid 280.750505 -93.552274)
		(end 280.696924 -93.747336)
		(width 0.0889)
		(layer "In11.Cu")
		(net "M_F_DQ<50>")
	)
	(arc
		(start 280.696924 -94.33814)
		(mid 280.750423 -94.538038)
		(end 280.696924 -94.737936)
		(width 0.0889)
		(layer "In11.Cu")
		(net "M_F_DQ<50>")
	)
	(arc
		(start 280.477468 -92.177108)
		(mid 280.724541 -92.414898)
		(end 280.696924 -92.756736)
		(width 0.0889)
		(layer "In11.Cu")
		(net "M_F_DQ<50>")
	)
	(arc
		(start 284.983174 -104.159304)
		(mid 284.910376 -104.450067)
		(end 284.989524 -104.739186)
		(width 0.0889)
		(layer "In11.Cu")
		(net "M_F_DQ<50>")
	)
	(arc
		(start 284.983174 -102.178104)
		(mid 284.910376 -102.468867)
		(end 284.989524 -102.757986)
		(width 0.0889)
		(layer "In11.Cu")
		(net "M_F_DQ<50>")
	)
	(arc
		(start 284.989524 -102.757986)
		(mid 285.042994 -102.953049)
		(end 284.99435 -103.1494)
		(width 0.0889)
		(layer "In11.Cu")
		(net "M_F_DQ<50>")
	)
	(arc
		(start 284.131004 -97.309686)
		(mid 284.339612 -97.521618)
		(end 284.625034 -97.605088)
		(width 0.0889)
		(layer "In11.Cu")
		(net "M_F_DQ<50>")
	)
	(arc
		(start 282.07843 -96.118934)
		(mid 282.27228 -96.175284)
		(end 282.413964 -96.319086)
		(width 0.0889)
		(layer "In11.Cu")
		(net "M_F_DQ<50>")
	)
	(arc
		(start 280.690574 -94.748604)
		(mid 280.696751 -95.328536)
		(end 281.19578 -95.623888)
		(width 0.0889)
		(layer "In11.Cu")
		(net "M_F_DQ<50>")
	)
	(arc
		(start 280.696924 -92.756736)
		(mid 280.617702 -93.045854)
		(end 280.690574 -93.336618)
		(width 0.0889)
		(layer "In11.Cu")
		(net "M_F_DQ<50>")
	)
	(arc
		(start 280.696924 -93.747336)
		(mid 280.617793 -94.042738)
		(end 280.696924 -94.33814)
		(width 0.0889)
		(layer "In11.Cu")
		(net "M_F_DQ<50>")
	)
	(arc
		(start 284.989524 -100.776786)
		(mid 285.042994 -100.971849)
		(end 284.99435 -101.1682)
		(width 0.0889)
		(layer "In11.Cu")
		(net "M_F_DQ<50>")
	)
	(arc
		(start 281.22372 -95.623888)
		(mid 281.415362 -95.681054)
		(end 281.555444 -95.823786)
		(width 0.0889)
		(layer "In11.Cu")
		(net "M_F_DQ<50>")
	)
	(arc
		(start 284.989524 -104.739186)
		(mid 285.042994 -104.934249)
		(end 284.99435 -105.1306)
		(width 0.0889)
		(layer "In11.Cu")
		(net "M_F_DQ<50>")
	)
	(arc
		(start 284.989524 -103.748586)
		(mid 285.042994 -103.943649)
		(end 284.99435 -104.14)
		(width 0.0889)
		(layer "In11.Cu")
		(net "M_F_DQ<50>")
	)
	(arc
		(start 284.983174 -103.168704)
		(mid 284.910376 -103.459467)
		(end 284.989524 -103.748586)
		(width 0.0889)
		(layer "In11.Cu")
		(net "M_F_DQ<50>")
	)
	(arc
		(start 282.413964 -96.319086)
		(mid 282.622572 -96.531018)
		(end 282.907994 -96.614488)
		(width 0.0889)
		(layer "In11.Cu")
		(net "M_F_DQ<50>")
	)
	(arc
		(start 283.79547 -97.109534)
		(mid 283.98932 -97.165884)
		(end 284.131004 -97.309686)
		(width 0.0889)
		(layer "In11.Cu")
		(net "M_F_DQ<50>")
	)
	(arc
		(start 281.555444 -95.823786)
		(mid 281.762448 -96.03465)
		(end 282.045664 -96.118934)
		(width 0.0889)
		(layer "In11.Cu")
		(net "M_F_DQ<50>")
	)
	(arc
		(start 284.983174 -105.149904)
		(mid 284.916327 -105.517332)
		(end 285.08325 -105.851452)
		(width 0.0889)
		(layer "In11.Cu")
		(net "M_F_DQ<50>")
	)
	(arc
		(start 284.6578 -97.605088)
		(mid 284.990718 -97.807079)
		(end 284.99435 -98.1964)
		(width 0.0889)
		(layer "In11.Cu")
		(net "M_F_DQ<50>")
	)
	(arc
		(start 284.983174 -99.206304)
		(mid 284.910376 -99.497067)
		(end 284.989524 -99.786186)
		(width 0.0889)
		(layer "In11.Cu")
		(net "M_F_DQ<50>")
	)
	(arc
		(start 283.272484 -96.814386)
		(mid 283.479488 -97.02525)
		(end 283.762704 -97.109534)
		(width 0.0889)
		(layer "In11.Cu")
		(net "M_F_DQ<50>")
	)
	(arc
		(start 284.983174 -98.215704)
		(mid 284.910376 -98.506467)
		(end 284.989524 -98.795586)
		(width 0.0889)
		(layer "In11.Cu")
		(net "M_F_DQ<50>")
	)
	(arc
		(start 282.94076 -96.614488)
		(mid 283.132402 -96.671654)
		(end 283.272484 -96.814386)
		(width 0.0889)
		(layer "In11.Cu")
		(net "M_F_DQ<50>")
	)
	(arc
		(start 284.983174 -100.196904)
		(mid 284.910376 -100.487667)
		(end 284.989524 -100.776786)
		(width 0.0889)
		(layer "In11.Cu")
		(net "M_F_DQ<50>")
	)
	(arc
		(start 284.989524 -98.795586)
		(mid 285.042994 -98.990649)
		(end 284.99435 -99.187)
		(width 0.0889)
		(layer "In11.Cu")
		(net "M_F_DQ<50>")
	)
	(arc
		(start 284.983174 -101.187504)
		(mid 284.910376 -101.478267)
		(end 284.989524 -101.767386)
		(width 0.0889)
		(layer "In11.Cu")
		(net "M_F_DQ<50>")
	)
	(arc
		(start 279.94483 -91.120722)
		(mid 279.882051 -91.363923)
		(end 279.914604 -91.612974)
		(width 0.0889)
		(layer "In11.Cu")
		(net "M_F_DQ<50>")
	)
	(arc
		(start 284.989524 -101.767386)
		(mid 285.042994 -101.962449)
		(end 284.99435 -102.1588)
		(width 0.0889)
		(layer "In11.Cu")
		(net "M_F_DQ<50>")
	)
	(arc
		(start 284.989524 -99.786186)
		(mid 285.042994 -99.981249)
		(end 284.99435 -100.1776)
		(width 0.0889)
		(layer "In11.Cu")
		(net "M_F_DQ<50>")
	)
	(arc
		(start 279.914604 -91.612974)
		(mid 280.129528 -91.961412)
		(end 280.477468 -92.177108)
		(width 0.0889)
		(layer "In11.Cu")
		(net "M_F_DQ<50>")
	)
	(segment
		(start 197.250304 -156.87294)
		(end 197.249796 -156.87294)
		(width 0.1651)
		(layer "F.Cu")
		(net "M_F_DQ<4>")
	)
	(segment
		(start 243.051838 -85.30844)
		(end 242.480338 -85.30844)
		(width 0.1651)
		(layer "F.Cu")
		(net "M_F_DQ<4>")
	)
	(segment
		(start 197.249796 -156.87294)
		(end 197.249796 -155.547568)
		(width 0.1651)
		(layer "F.Cu")
		(net "M_F_DQ<4>")
	)
	(segment
		(start 197.249796 -155.547568)
		(end 197.151752 -155.0162)
		(width 0.1651)
		(layer "F.Cu")
		(net "M_F_DQ<4>")
	)
	(via
		(at 196.399912 -150.814278)
		(size 0.508)
		(drill 0.254)
		(layers "F.Cu" "B.Cu")
		(net "M_F_DQ<4>")
	)
	(via
		(at 242.480338 -85.30844)
		(size 0.508)
		(drill 0.254)
		(layers "F.Cu" "B.Cu")
		(net "M_F_DQ<4>")
	)
	(via
		(at 197.151752 -155.0162)
		(size 0.508)
		(drill 0.254)
		(layers "F.Cu" "B.Cu")
		(net "M_F_DQ<4>")
	)
	(segment
		(start 196.40042 -152.078436)
		(end 196.399912 -152.078182)
		(width 0.1651)
		(layer "B.Cu")
		(net "M_F_DQ<4>")
	)
	(segment
		(start 196.399912 -152.078182)
		(end 196.399912 -150.814278)
		(width 0.1651)
		(layer "B.Cu")
		(net "M_F_DQ<4>")
	)
	(segment
		(start 197.3072 -125.827536)
		(end 196.956426 -126.674118)
		(width 0.14224)
		(layer "In11.Cu")
		(net "M_F_DQ<4>")
	)
	(segment
		(start 241.639598 -84.222336)
		(end 241.606832 -84.222336)
		(width 0.0889)
		(layer "In11.Cu")
		(net "M_F_DQ<4>")
	)
	(segment
		(start 196.8754 -126.869952)
		(end 196.8754 -129.721864)
		(width 0.14224)
		(layer "In11.Cu")
		(net "M_F_DQ<4>")
	)
	(segment
		(start 203.966572 -105.151428)
		(end 203.3016 -106.756708)
		(width 0.14224)
		(layer "In11.Cu")
		(net "M_F_DQ<4>")
	)
	(segment
		(start 196.669152 -135.855202)
		(end 196.8754 -136.353296)
		(width 0.14224)
		(layer "In11.Cu")
		(net "M_F_DQ<4>")
	)
	(segment
		(start 196.713094 -140.694918)
		(end 196.897752 -141.140688)
		(width 0.14224)
		(layer "In11.Cu")
		(net "M_F_DQ<4>")
	)
	(segment
		(start 233.051604 -86.203536)
		(end 233.018838 -86.203536)
		(width 0.0889)
		(layer "In11.Cu")
		(net "M_F_DQ<4>")
	)
	(segment
		(start 240.784888 -83.72729)
		(end 240.752122 -83.72729)
		(width 0.0889)
		(layer "In11.Cu")
		(net "M_F_DQ<4>")
	)
	(segment
		(start 196.8754 -136.353296)
		(end 196.8754 -139.38123)
		(width 0.14224)
		(layer "In11.Cu")
		(net "M_F_DQ<4>")
	)
	(segment
		(start 231.9147 -86.69909)
		(end 231.701848 -86.486238)
		(width 0.0889)
		(layer "In11.Cu")
		(net "M_F_DQ<4>")
	)
	(segment
		(start 235.623354 -84.71789)
		(end 235.590588 -84.71789)
		(width 0.0889)
		(layer "In11.Cu")
		(net "M_F_DQ<4>")
	)
	(segment
		(start 196.845428 -129.794)
		(end 196.803264 -129.8956)
		(width 0.14224)
		(layer "In11.Cu")
		(net "M_F_DQ<4>")
	)
	(segment
		(start 234.768644 -85.212936)
		(end 234.735878 -85.212936)
		(width 0.0889)
		(layer "In11.Cu")
		(net "M_F_DQ<4>")
	)
	(segment
		(start 196.688202 -145.51025)
		(end 196.832982 -145.859754)
		(width 0.14224)
		(layer "In11.Cu")
		(net "M_F_DQ<4>")
	)
	(segment
		(start 230.125524 -86.0044)
		(end 227.204016 -86.0044)
		(width 0.14224)
		(layer "In11.Cu")
		(net "M_F_DQ<4>")
	)
	(segment
		(start 196.281802 -149.681184)
		(end 196.281802 -150.696168)
		(width 0.14224)
		(layer "In11.Cu")
		(net "M_F_DQ<4>")
	)
	(segment
		(start 196.897752 -134.2771)
		(end 196.669152 -134.829296)
		(width 0.14224)
		(layer "In11.Cu")
		(net "M_F_DQ<4>")
	)
	(segment
		(start 207.924654 -100.3046)
		(end 205.5876 -102.641654)
		(width 0.14224)
		(layer "In11.Cu")
		(net "M_F_DQ<4>")
	)
	(segment
		(start 203.3016 -106.756708)
		(end 203.3016 -107.5182)
		(width 0.14224)
		(layer "In11.Cu")
		(net "M_F_DQ<4>")
	)
	(segment
		(start 196.669152 -131.085082)
		(end 196.897752 -131.637024)
		(width 0.14224)
		(layer "In11.Cu")
		(net "M_F_DQ<4>")
	)
	(segment
		(start 196.897752 -143.90624)
		(end 196.688202 -144.412208)
		(width 0.14224)
		(layer "In11.Cu")
		(net "M_F_DQ<4>")
	)
	(segment
		(start 196.655436 -149.30755)
		(end 196.281802 -149.681184)
		(width 0.14224)
		(layer "In11.Cu")
		(net "M_F_DQ<4>")
	)
	(segment
		(start 239.067848 -82.73669)
		(end 239.024668 -82.73669)
		(width 0.0889)
		(layer "In11.Cu")
		(net "M_F_DQ<4>")
	)
	(segment
		(start 195.966842 -153.83129)
		(end 197.151752 -155.0162)
		(width 0.14224)
		(layer "In11.Cu")
		(net "M_F_DQ<4>")
	)
	(segment
		(start 242.480338 -85.30844)
		(end 242.1509 -84.547456)
		(width 0.0889)
		(layer "In11.Cu")
		(net "M_F_DQ<4>")
	)
	(segment
		(start 237.340394 -83.72729)
		(end 237.307628 -83.72729)
		(width 0.0889)
		(layer "In11.Cu")
		(net "M_F_DQ<4>")
	)
	(segment
		(start 196.281802 -150.696168)
		(end 196.399912 -150.814278)
		(width 0.14224)
		(layer "In11.Cu")
		(net "M_F_DQ<4>")
	)
	(segment
		(start 196.688202 -144.412208)
		(end 196.688202 -145.51025)
		(width 0.14224)
		(layer "In11.Cu")
		(net "M_F_DQ<4>")
	)
	(segment
		(start 242.1509 -84.547456)
		(end 242.133628 -84.517738)
		(width 0.0889)
		(layer "In11.Cu")
		(net "M_F_DQ<4>")
	)
	(segment
		(start 196.669152 -134.829296)
		(end 196.669152 -135.855202)
		(width 0.14224)
		(layer "In11.Cu")
		(net "M_F_DQ<4>")
	)
	(segment
		(start 196.669152 -130.219958)
		(end 196.669152 -131.085082)
		(width 0.14224)
		(layer "In11.Cu")
		(net "M_F_DQ<4>")
	)
	(segment
		(start 196.803264 -129.8956)
		(end 196.669152 -130.219958)
		(width 0.14224)
		(layer "In11.Cu")
		(net "M_F_DQ<4>")
	)
	(segment
		(start 196.832982 -148.878798)
		(end 196.655436 -149.30755)
		(width 0.14224)
		(layer "In11.Cu")
		(net "M_F_DQ<4>")
	)
	(segment
		(start 205.5876 -102.641654)
		(end 204.95895 -104.15905)
		(width 0.14224)
		(layer "In11.Cu")
		(net "M_F_DQ<4>")
	)
	(segment
		(start 232.189274 -86.69909)
		(end 231.9147 -86.69909)
		(width 0.0889)
		(layer "In11.Cu")
		(net "M_F_DQ<4>")
	)
	(segment
		(start 196.897752 -141.140688)
		(end 196.897752 -143.90624)
		(width 0.14224)
		(layer "In11.Cu")
		(net "M_F_DQ<4>")
	)
	(segment
		(start 196.713094 -139.773152)
		(end 196.713094 -140.694918)
		(width 0.14224)
		(layer "In11.Cu")
		(net "M_F_DQ<4>")
	)
	(segment
		(start 203.3016 -107.5182)
		(end 199.771 -111.0488)
		(width 0.14224)
		(layer "In11.Cu")
		(net "M_F_DQ<4>")
	)
	(segment
		(start 195.966842 -151.247348)
		(end 195.966842 -153.83129)
		(width 0.14224)
		(layer "In11.Cu")
		(net "M_F_DQ<4>")
	)
	(segment
		(start 204.95895 -104.15905)
		(end 203.966572 -105.151428)
		(width 0.14224)
		(layer "In11.Cu")
		(net "M_F_DQ<4>")
	)
	(segment
		(start 196.399912 -150.814278)
		(end 195.966842 -151.247348)
		(width 0.14224)
		(layer "In11.Cu")
		(net "M_F_DQ<4>")
	)
	(segment
		(start 196.897752 -131.637024)
		(end 196.897752 -134.2771)
		(width 0.14224)
		(layer "In11.Cu")
		(net "M_F_DQ<4>")
	)
	(segment
		(start 233.906314 -85.70849)
		(end 233.873548 -85.70849)
		(width 0.0889)
		(layer "In11.Cu")
		(net "M_F_DQ<4>")
	)
	(segment
		(start 215.7222 -97.486216)
		(end 215.7222 -98.095054)
		(width 0.14224)
		(layer "In11.Cu")
		(net "M_F_DQ<4>")
	)
	(segment
		(start 196.8754 -139.38123)
		(end 196.713094 -139.773152)
		(width 0.14224)
		(layer "In11.Cu")
		(net "M_F_DQ<4>")
	)
	(segment
		(start 231.701848 -86.181438)
		(end 231.382316 -85.861906)
		(width 0.0889)
		(layer "In11.Cu")
		(net "M_F_DQ<4>")
	)
	(segment
		(start 196.956426 -126.674118)
		(end 196.8754 -126.869952)
		(width 0.14224)
		(layer "In11.Cu")
		(net "M_F_DQ<4>")
	)
	(segment
		(start 196.832982 -145.859754)
		(end 196.832982 -148.878798)
		(width 0.14224)
		(layer "In11.Cu")
		(net "M_F_DQ<4>")
	)
	(segment
		(start 199.771 -111.0488)
		(end 199.289162 -111.0488)
		(width 0.14224)
		(layer "In11.Cu")
		(net "M_F_DQ<4>")
	)
	(segment
		(start 230.268018 -85.861906)
		(end 230.125524 -86.0044)
		(width 0.0889)
		(layer "In11.Cu")
		(net "M_F_DQ<4>")
	)
	(segment
		(start 213.512654 -100.3046)
		(end 207.924654 -100.3046)
		(width 0.14224)
		(layer "In11.Cu")
		(net "M_F_DQ<4>")
	)
	(segment
		(start 238.205772 -83.231736)
		(end 238.169958 -83.231736)
		(width 0.0889)
		(layer "In11.Cu")
		(net "M_F_DQ<4>")
	)
	(segment
		(start 199.289162 -111.0488)
		(end 197.3072 -113.030762)
		(width 0.14224)
		(layer "In11.Cu")
		(net "M_F_DQ<4>")
	)
	(segment
		(start 215.7222 -98.095054)
		(end 213.512654 -100.3046)
		(width 0.14224)
		(layer "In11.Cu")
		(net "M_F_DQ<4>")
	)
	(segment
		(start 239.922558 -83.231736)
		(end 239.886744 -83.231736)
		(width 0.0889)
		(layer "In11.Cu")
		(net "M_F_DQ<4>")
	)
	(segment
		(start 236.485684 -84.222336)
		(end 236.452918 -84.222336)
		(width 0.0889)
		(layer "In11.Cu")
		(net "M_F_DQ<4>")
	)
	(segment
		(start 231.382316 -85.861906)
		(end 230.268018 -85.861906)
		(width 0.0889)
		(layer "In11.Cu")
		(net "M_F_DQ<4>")
	)
	(segment
		(start 227.204016 -86.0044)
		(end 215.7222 -97.486216)
		(width 0.14224)
		(layer "In11.Cu")
		(net "M_F_DQ<4>")
	)
	(segment
		(start 196.8754 -129.721864)
		(end 196.845428 -129.794)
		(width 0.14224)
		(layer "In11.Cu")
		(net "M_F_DQ<4>")
	)
	(segment
		(start 231.701848 -86.486238)
		(end 231.701848 -86.181438)
		(width 0.0889)
		(layer "In11.Cu")
		(net "M_F_DQ<4>")
	)
	(segment
		(start 197.3072 -113.030762)
		(end 197.3072 -125.827536)
		(width 0.14224)
		(layer "In11.Cu")
		(net "M_F_DQ<4>")
	)
	(arc
		(start 240.752122 -83.72729)
		(mid 240.558272 -83.67094)
		(end 240.416588 -83.527138)
		(width 0.0889)
		(layer "In11.Cu")
		(net "M_F_DQ<4>")
	)
	(arc
		(start 242.133628 -84.517738)
		(mid 241.92502 -84.305806)
		(end 241.639598 -84.222336)
		(width 0.0889)
		(layer "In11.Cu")
		(net "M_F_DQ<4>")
	)
	(arc
		(start 239.886744 -83.231736)
		(mid 239.696815 -83.173866)
		(end 239.558068 -83.031838)
		(width 0.0889)
		(layer "In11.Cu")
		(net "M_F_DQ<4>")
	)
	(arc
		(start 234.241848 -85.508338)
		(mid 234.100165 -85.652142)
		(end 233.906314 -85.70849)
		(width 0.0889)
		(layer "In11.Cu")
		(net "M_F_DQ<4>")
	)
	(arc
		(start 235.100368 -85.013038)
		(mid 234.960289 -85.155774)
		(end 234.768644 -85.212936)
		(width 0.0889)
		(layer "In11.Cu")
		(net "M_F_DQ<4>")
	)
	(arc
		(start 234.735878 -85.212936)
		(mid 234.450454 -85.296403)
		(end 234.241848 -85.508338)
		(width 0.0889)
		(layer "In11.Cu")
		(net "M_F_DQ<4>")
	)
	(arc
		(start 241.275108 -84.022438)
		(mid 241.068104 -83.811574)
		(end 240.784888 -83.72729)
		(width 0.0889)
		(layer "In11.Cu")
		(net "M_F_DQ<4>")
	)
	(arc
		(start 236.817408 -84.022438)
		(mid 236.677329 -84.165174)
		(end 236.485684 -84.222336)
		(width 0.0889)
		(layer "In11.Cu")
		(net "M_F_DQ<4>")
	)
	(arc
		(start 239.024668 -82.73669)
		(mid 238.741451 -82.820971)
		(end 238.534448 -83.031838)
		(width 0.0889)
		(layer "In11.Cu")
		(net "M_F_DQ<4>")
	)
	(arc
		(start 236.452918 -84.222336)
		(mid 236.167494 -84.305803)
		(end 235.958888 -84.517738)
		(width 0.0889)
		(layer "In11.Cu")
		(net "M_F_DQ<4>")
	)
	(arc
		(start 238.534448 -83.031838)
		(mid 238.395704 -83.173871)
		(end 238.205772 -83.231736)
		(width 0.0889)
		(layer "In11.Cu")
		(net "M_F_DQ<4>")
	)
	(arc
		(start 237.307628 -83.72729)
		(mid 237.024411 -83.811571)
		(end 236.817408 -84.022438)
		(width 0.0889)
		(layer "In11.Cu")
		(net "M_F_DQ<4>")
	)
	(arc
		(start 232.524808 -86.498938)
		(mid 232.383125 -86.642742)
		(end 232.189274 -86.69909)
		(width 0.0889)
		(layer "In11.Cu")
		(net "M_F_DQ<4>")
	)
	(arc
		(start 235.958888 -84.517738)
		(mid 235.817205 -84.661542)
		(end 235.623354 -84.71789)
		(width 0.0889)
		(layer "In11.Cu")
		(net "M_F_DQ<4>")
	)
	(arc
		(start 241.606832 -84.222336)
		(mid 241.41519 -84.16517)
		(end 241.275108 -84.022438)
		(width 0.0889)
		(layer "In11.Cu")
		(net "M_F_DQ<4>")
	)
	(arc
		(start 240.416588 -83.527138)
		(mid 240.20798 -83.315206)
		(end 239.922558 -83.231736)
		(width 0.0889)
		(layer "In11.Cu")
		(net "M_F_DQ<4>")
	)
	(arc
		(start 235.590588 -84.71789)
		(mid 235.307371 -84.802171)
		(end 235.100368 -85.013038)
		(width 0.0889)
		(layer "In11.Cu")
		(net "M_F_DQ<4>")
	)
	(arc
		(start 239.558068 -83.031838)
		(mid 239.351064 -82.820974)
		(end 239.067848 -82.73669)
		(width 0.0889)
		(layer "In11.Cu")
		(net "M_F_DQ<4>")
	)
	(arc
		(start 233.873548 -85.70849)
		(mid 233.590331 -85.792771)
		(end 233.383328 -86.003638)
		(width 0.0889)
		(layer "In11.Cu")
		(net "M_F_DQ<4>")
	)
	(arc
		(start 238.169958 -83.231736)
		(mid 237.884534 -83.315203)
		(end 237.675928 -83.527138)
		(width 0.0889)
		(layer "In11.Cu")
		(net "M_F_DQ<4>")
	)
	(arc
		(start 233.383328 -86.003638)
		(mid 233.243249 -86.146374)
		(end 233.051604 -86.203536)
		(width 0.0889)
		(layer "In11.Cu")
		(net "M_F_DQ<4>")
	)
	(arc
		(start 237.675928 -83.527138)
		(mid 237.534245 -83.670942)
		(end 237.340394 -83.72729)
		(width 0.0889)
		(layer "In11.Cu")
		(net "M_F_DQ<4>")
	)
	(arc
		(start 233.018838 -86.203536)
		(mid 232.733414 -86.287003)
		(end 232.524808 -86.498938)
		(width 0.0889)
		(layer "In11.Cu")
		(net "M_F_DQ<4>")
	)
	(segment
		(start 300.100492 -152.273)
		(end 300.099984 -152.278842)
		(width 0.1651)
		(layer "F.Cu")
		(net "M_F_DQ<49>")
	)
	(segment
		(start 277.203154 -92.061538)
		(end 277.774654 -92.061538)
		(width 0.1651)
		(layer "F.Cu")
		(net "M_F_DQ<49>")
	)
	(segment
		(start 300.099984 -152.278842)
		(end 300.099984 -153.542746)
		(width 0.1651)
		(layer "F.Cu")
		(net "M_F_DQ<49>")
	)
	(via
		(at 300.099984 -153.542746)
		(size 0.508)
		(drill 0.254)
		(layers "F.Cu" "B.Cu")
		(net "M_F_DQ<49>")
	)
	(via
		(at 277.774654 -92.061538)
		(size 0.508)
		(drill 0.254)
		(layers "F.Cu" "B.Cu")
		(net "M_F_DQ<49>")
	)
	(via
		(at 300.772068 -149.533356)
		(size 0.508)
		(drill 0.254)
		(layers "F.Cu" "B.Cu")
		(net "M_F_DQ<49>")
	)
	(segment
		(start 300.772068 -149.030182)
		(end 300.949868 -148.852382)
		(width 0.1651)
		(layer "B.Cu")
		(net "M_F_DQ<49>")
	)
	(segment
		(start 300.772068 -149.533356)
		(end 300.772068 -149.030182)
		(width 0.1651)
		(layer "B.Cu")
		(net "M_F_DQ<49>")
	)
	(segment
		(start 300.949868 -148.852382)
		(end 300.949868 -147.478496)
		(width 0.1651)
		(layer "B.Cu")
		(net "M_F_DQ<49>")
	)
	(segment
		(start 300.949868 -147.478496)
		(end 300.950376 -147.478496)
		(width 0.1651)
		(layer "B.Cu")
		(net "M_F_DQ<49>")
	)
	(segment
		(start 300.50105 -153.3906)
		(end 300.348904 -153.542746)
		(width 0.14224)
		(layer "In11.Cu")
		(net "M_F_DQ<49>")
	)
	(segment
		(start 292.893496 -121.533412)
		(end 293.048436 -121.378472)
		(width 0.14224)
		(layer "In11.Cu")
		(net "M_F_DQ<49>")
	)
	(segment
		(start 301.101506 -128.01854)
		(end 301.101506 -128.24206)
		(width 0.14224)
		(layer "In11.Cu")
		(net "M_F_DQ<49>")
	)
	(segment
		(start 297.22699 -121.37136)
		(end 298.210986 -121.37136)
		(width 0.14224)
		(layer "In11.Cu")
		(net "M_F_DQ<49>")
	)
	(segment
		(start 277.423118 -93.2434)
		(end 277.427944 -93.252036)
		(width 0.0889)
		(layer "In11.Cu")
		(net "M_F_DQ<49>")
	)
	(segment
		(start 301.256446 -127.8636)
		(end 301.101506 -128.01854)
		(width 0.14224)
		(layer "In11.Cu")
		(net "M_F_DQ<49>")
	)
	(segment
		(start 301.260002 -143.697198)
		(end 301.260002 -148.956522)
		(width 0.14224)
		(layer "In11.Cu")
		(net "M_F_DQ<49>")
	)
	(segment
		(start 300.261274 -152.538176)
		(end 300.261274 -152.846024)
		(width 0.14224)
		(layer "In11.Cu")
		(net "M_F_DQ<49>")
	)
	(segment
		(start 300.47565 -152.3238)
		(end 300.261274 -152.538176)
		(width 0.14224)
		(layer "In11.Cu")
		(net "M_F_DQ<49>")
	)
	(segment
		(start 297.07205 -121.840752)
		(end 297.07205 -121.5263)
		(width 0.14224)
		(layer "In11.Cu")
		(net "M_F_DQ<49>")
	)
	(segment
		(start 281.729434 -106.209846)
		(end 281.720544 -106.225086)
		(width 0.0889)
		(layer "In11.Cu")
		(net "M_F_DQ<49>")
	)
	(segment
		(start 294.727376 -121.378472)
		(end 294.882316 -121.533412)
		(width 0.14224)
		(layer "In11.Cu")
		(net "M_F_DQ<49>")
	)
	(segment
		(start 296.40911 -121.840752)
		(end 296.56405 -121.995692)
		(width 0.14224)
		(layer "In11.Cu")
		(net "M_F_DQ<49>")
	)
	(segment
		(start 279.480518 -98.405188)
		(end 279.513284 -98.405188)
		(width 0.0889)
		(layer "In11.Cu")
		(net "M_F_DQ<49>")
	)
	(segment
		(start 277.763478 -97.414588)
		(end 277.796244 -97.414588)
		(width 0.0889)
		(layer "In11.Cu")
		(net "M_F_DQ<49>")
	)
	(segment
		(start 281.720544 -105.234486)
		(end 281.713686 -105.246678)
		(width 0.0889)
		(layer "In11.Cu")
		(net "M_F_DQ<49>")
	)
	(segment
		(start 301.101506 -128.24206)
		(end 301.256446 -128.397)
		(width 0.14224)
		(layer "In11.Cu")
		(net "M_F_DQ<49>")
	)
	(segment
		(start 300.55185 -151.026368)
		(end 300.261274 -151.316944)
		(width 0.14224)
		(layer "In11.Cu")
		(net "M_F_DQ<49>")
	)
	(segment
		(start 277.427944 -93.252036)
		(end 277.434294 -93.262704)
		(width 0.0889)
		(layer "In11.Cu")
		(net "M_F_DQ<49>")
	)
	(segment
		(start 281.652726 -106.319828)
		(end 281.579574 -106.555286)
		(width 0.0889)
		(layer "In11.Cu")
		(net "M_F_DQ<49>")
	)
	(segment
		(start 300.50105 -153.0858)
		(end 300.50105 -153.3906)
		(width 0.14224)
		(layer "In11.Cu")
		(net "M_F_DQ<49>")
	)
	(segment
		(start 300.749716 -149.533356)
		(end 300.321472 -149.9616)
		(width 0.14224)
		(layer "In11.Cu")
		(net "M_F_DQ<49>")
	)
	(segment
		(start 294.882316 -121.840752)
		(end 295.037256 -121.995692)
		(width 0.14224)
		(layer "In11.Cu")
		(net "M_F_DQ<49>")
	)
	(segment
		(start 301.371 -136.686798)
		(end 301.371 -138.7094)
		(width 0.14224)
		(layer "In11.Cu")
		(net "M_F_DQ<49>")
	)
	(segment
		(start 277.423118 -94.234)
		(end 277.427944 -94.242636)
		(width 0.0889)
		(layer "In11.Cu")
		(net "M_F_DQ<49>")
	)
	(segment
		(start 277.423118 -96.2152)
		(end 277.427944 -96.223836)
		(width 0.0889)
		(layer "In11.Cu")
		(net "M_F_DQ<49>")
	)
	(segment
		(start 281.579574 -106.78287)
		(end 281.579574 -113.732056)
		(width 0.14224)
		(layer "In11.Cu")
		(net "M_F_DQ<49>")
	)
	(segment
		(start 294.882316 -121.533412)
		(end 294.882316 -121.840752)
		(width 0.14224)
		(layer "In11.Cu")
		(net "M_F_DQ<49>")
	)
	(segment
		(start 296.91711 -121.995692)
		(end 297.07205 -121.840752)
		(width 0.14224)
		(layer "In11.Cu")
		(net "M_F_DQ<49>")
	)
	(segment
		(start 301.371 -134.0612)
		(end 301.260002 -134.172198)
		(width 0.14224)
		(layer "In11.Cu")
		(net "M_F_DQ<49>")
	)
	(segment
		(start 300.261274 -152.846024)
		(end 300.50105 -153.0858)
		(width 0.14224)
		(layer "In11.Cu")
		(net "M_F_DQ<49>")
	)
	(segment
		(start 294.219376 -121.840752)
		(end 294.219376 -121.533412)
		(width 0.14224)
		(layer "In11.Cu")
		(net "M_F_DQ<49>")
	)
	(segment
		(start 301.260002 -129.346198)
		(end 301.260002 -131.740656)
		(width 0.14224)
		(layer "In11.Cu")
		(net "M_F_DQ<49>")
	)
	(segment
		(start 294.064436 -121.995692)
		(end 294.219376 -121.840752)
		(width 0.14224)
		(layer "In11.Cu")
		(net "M_F_DQ<49>")
	)
	(segment
		(start 301.260002 -136.5758)
		(end 301.371 -136.686798)
		(width 0.14224)
		(layer "In11.Cu")
		(net "M_F_DQ<49>")
	)
	(segment
		(start 296.25417 -121.37136)
		(end 296.40911 -121.5263)
		(width 0.14224)
		(layer "In11.Cu")
		(net "M_F_DQ<49>")
	)
	(segment
		(start 301.371 -138.7094)
		(end 301.260002 -138.820398)
		(width 0.14224)
		(layer "In11.Cu")
		(net "M_F_DQ<49>")
	)
	(segment
		(start 295.90111 -121.37136)
		(end 296.25417 -121.37136)
		(width 0.14224)
		(layer "In11.Cu")
		(net "M_F_DQ<49>")
	)
	(segment
		(start 301.260002 -134.172198)
		(end 301.260002 -136.5758)
		(width 0.14224)
		(layer "In11.Cu")
		(net "M_F_DQ<49>")
	)
	(segment
		(start 300.321472 -150.391368)
		(end 300.55185 -150.621746)
		(width 0.14224)
		(layer "In11.Cu")
		(net "M_F_DQ<49>")
	)
	(segment
		(start 293.556436 -121.840752)
		(end 293.711376 -121.995692)
		(width 0.14224)
		(layer "In11.Cu")
		(net "M_F_DQ<49>")
	)
	(segment
		(start 294.374316 -121.378472)
		(end 294.727376 -121.378472)
		(width 0.14224)
		(layer "In11.Cu")
		(net "M_F_DQ<49>")
	)
	(segment
		(start 300.321472 -149.9616)
		(end 300.321472 -150.391368)
		(width 0.14224)
		(layer "In11.Cu")
		(net "M_F_DQ<49>")
	)
	(segment
		(start 300.47565 -151.892)
		(end 300.47565 -152.3238)
		(width 0.14224)
		(layer "In11.Cu")
		(net "M_F_DQ<49>")
	)
	(segment
		(start 301.703994 -128.902206)
		(end 301.260002 -129.346198)
		(width 0.14224)
		(layer "In11.Cu")
		(net "M_F_DQ<49>")
	)
	(segment
		(start 281.729434 -101.256846)
		(end 281.726894 -101.261164)
		(width 0.0889)
		(layer "In11.Cu")
		(net "M_F_DQ<49>")
	)
	(segment
		(start 293.401496 -121.378472)
		(end 293.556436 -121.533412)
		(width 0.14224)
		(layer "In11.Cu")
		(net "M_F_DQ<49>")
	)
	(segment
		(start 289.84321 -121.995692)
		(end 292.738556 -121.995692)
		(width 0.14224)
		(layer "In11.Cu")
		(net "M_F_DQ<49>")
	)
	(segment
		(start 300.261274 -151.677624)
		(end 300.47565 -151.892)
		(width 0.14224)
		(layer "In11.Cu")
		(net "M_F_DQ<49>")
	)
	(segment
		(start 278.618188 -97.909634)
		(end 278.650954 -97.909634)
		(width 0.0889)
		(layer "In11.Cu")
		(net "M_F_DQ<49>")
	)
	(segment
		(start 297.07205 -121.5263)
		(end 297.22699 -121.37136)
		(width 0.14224)
		(layer "In11.Cu")
		(net "M_F_DQ<49>")
	)
	(segment
		(start 300.55185 -150.621746)
		(end 300.55185 -151.026368)
		(width 0.14224)
		(layer "In11.Cu")
		(net "M_F_DQ<49>")
	)
	(segment
		(start 292.738556 -121.995692)
		(end 292.893496 -121.840752)
		(width 0.14224)
		(layer "In11.Cu")
		(net "M_F_DQ<49>")
	)
	(segment
		(start 281.720544 -100.281486)
		(end 281.713686 -100.293678)
		(width 0.0889)
		(layer "In11.Cu")
		(net "M_F_DQ<49>")
	)
	(segment
		(start 277.434294 -94.822518)
		(end 277.427944 -94.833186)
		(width 0.0889)
		(layer "In11.Cu")
		(net "M_F_DQ<49>")
	)
	(segment
		(start 280.335228 -98.900234)
		(end 280.367994 -98.900234)
		(width 0.0889)
		(layer "In11.Cu")
		(net "M_F_DQ<49>")
	)
	(segment
		(start 301.703994 -127.333248)
		(end 301.703994 -127.70866)
		(width 0.14224)
		(layer "In11.Cu")
		(net "M_F_DQ<49>")
	)
	(segment
		(start 295.037256 -121.995692)
		(end 295.59123 -121.995692)
		(width 0.14224)
		(layer "In11.Cu")
		(net "M_F_DQ<49>")
	)
	(segment
		(start 277.427944 -96.223836)
		(end 277.434294 -96.234504)
		(width 0.0889)
		(layer "In11.Cu")
		(net "M_F_DQ<49>")
	)
	(segment
		(start 301.260002 -141.392656)
		(end 301.371 -141.503654)
		(width 0.14224)
		(layer "In11.Cu")
		(net "M_F_DQ<49>")
	)
	(segment
		(start 301.260002 -138.820398)
		(end 301.260002 -141.392656)
		(width 0.14224)
		(layer "In11.Cu")
		(net "M_F_DQ<49>")
	)
	(segment
		(start 296.56405 -121.995692)
		(end 296.91711 -121.995692)
		(width 0.14224)
		(layer "In11.Cu")
		(net "M_F_DQ<49>")
	)
	(segment
		(start 301.260002 -148.956522)
		(end 300.772068 -149.444456)
		(width 0.14224)
		(layer "In11.Cu")
		(net "M_F_DQ<49>")
	)
	(segment
		(start 294.219376 -121.533412)
		(end 294.374316 -121.378472)
		(width 0.14224)
		(layer "In11.Cu")
		(net "M_F_DQ<49>")
	)
	(segment
		(start 281.726894 -100.270818)
		(end 281.720544 -100.281486)
		(width 0.0889)
		(layer "In11.Cu")
		(net "M_F_DQ<49>")
	)
	(segment
		(start 293.048436 -121.378472)
		(end 293.401496 -121.378472)
		(width 0.14224)
		(layer "In11.Cu")
		(net "M_F_DQ<49>")
	)
	(segment
		(start 300.261274 -151.316944)
		(end 300.261274 -151.677624)
		(width 0.14224)
		(layer "In11.Cu")
		(net "M_F_DQ<49>")
	)
	(segment
		(start 301.371 -141.503654)
		(end 301.371 -143.5862)
		(width 0.14224)
		(layer "In11.Cu")
		(net "M_F_DQ<49>")
	)
	(segment
		(start 296.40911 -121.5263)
		(end 296.40911 -121.840752)
		(width 0.14224)
		(layer "In11.Cu")
		(net "M_F_DQ<49>")
	)
	(segment
		(start 301.549054 -127.8636)
		(end 301.256446 -127.8636)
		(width 0.14224)
		(layer "In11.Cu")
		(net "M_F_DQ<49>")
	)
	(segment
		(start 298.210986 -121.37136)
		(end 301.260002 -124.420376)
		(width 0.14224)
		(layer "In11.Cu")
		(net "M_F_DQ<49>")
	)
	(segment
		(start 300.348904 -153.542746)
		(end 300.099984 -153.542746)
		(width 0.14224)
		(layer "In11.Cu")
		(net "M_F_DQ<49>")
	)
	(segment
		(start 295.59123 -121.995692)
		(end 295.74617 -121.840752)
		(width 0.14224)
		(layer "In11.Cu")
		(net "M_F_DQ<49>")
	)
	(segment
		(start 301.703994 -128.55194)
		(end 301.703994 -128.902206)
		(width 0.14224)
		(layer "In11.Cu")
		(net "M_F_DQ<49>")
	)
	(segment
		(start 277.444708 -92.823284)
		(end 277.427944 -92.851986)
		(width 0.0889)
		(layer "In11.Cu")
		(net "M_F_DQ<49>")
	)
	(segment
		(start 281.579574 -113.732056)
		(end 289.84321 -121.995692)
		(width 0.14224)
		(layer "In11.Cu")
		(net "M_F_DQ<49>")
	)
	(segment
		(start 301.549054 -128.397)
		(end 301.703994 -128.55194)
		(width 0.14224)
		(layer "In11.Cu")
		(net "M_F_DQ<49>")
	)
	(segment
		(start 293.711376 -121.995692)
		(end 294.064436 -121.995692)
		(width 0.14224)
		(layer "In11.Cu")
		(net "M_F_DQ<49>")
	)
	(segment
		(start 300.772068 -149.444456)
		(end 300.772068 -149.533356)
		(width 0.14224)
		(layer "In11.Cu")
		(net "M_F_DQ<49>")
	)
	(segment
		(start 301.260002 -126.889256)
		(end 301.703994 -127.333248)
		(width 0.14224)
		(layer "In11.Cu")
		(net "M_F_DQ<49>")
	)
	(segment
		(start 301.256446 -128.397)
		(end 301.549054 -128.397)
		(width 0.14224)
		(layer "In11.Cu")
		(net "M_F_DQ<49>")
	)
	(segment
		(start 301.371 -131.851654)
		(end 301.371 -134.0612)
		(width 0.14224)
		(layer "In11.Cu")
		(net "M_F_DQ<49>")
	)
	(segment
		(start 301.703994 -127.70866)
		(end 301.549054 -127.8636)
		(width 0.14224)
		(layer "In11.Cu")
		(net "M_F_DQ<49>")
	)
	(segment
		(start 300.772068 -149.533356)
		(end 300.749716 -149.533356)
		(width 0.14224)
		(layer "In11.Cu")
		(net "M_F_DQ<49>")
	)
	(segment
		(start 277.774654 -92.061538)
		(end 277.444708 -92.823284)
		(width 0.0889)
		(layer "In11.Cu")
		(net "M_F_DQ<49>")
	)
	(segment
		(start 301.260002 -124.420376)
		(end 301.260002 -126.889256)
		(width 0.14224)
		(layer "In11.Cu")
		(net "M_F_DQ<49>")
	)
	(segment
		(start 281.729434 -103.238046)
		(end 281.713686 -103.265478)
		(width 0.0889)
		(layer "In11.Cu")
		(net "M_F_DQ<49>")
	)
	(segment
		(start 295.74617 -121.840752)
		(end 295.74617 -121.5263)
		(width 0.14224)
		(layer "In11.Cu")
		(net "M_F_DQ<49>")
	)
	(segment
		(start 301.260002 -131.740656)
		(end 301.371 -131.851654)
		(width 0.14224)
		(layer "In11.Cu")
		(net "M_F_DQ<49>")
	)
	(segment
		(start 301.371 -143.5862)
		(end 301.260002 -143.697198)
		(width 0.14224)
		(layer "In11.Cu")
		(net "M_F_DQ<49>")
	)
	(segment
		(start 281.579574 -106.555286)
		(end 281.579574 -106.78287)
		(width 0.0889)
		(layer "In11.Cu")
		(net "M_F_DQ<49>")
	)
	(segment
		(start 281.729434 -105.219246)
		(end 281.720544 -105.234486)
		(width 0.0889)
		(layer "In11.Cu")
		(net "M_F_DQ<49>")
	)
	(segment
		(start 281.729434 -104.228646)
		(end 281.713686 -104.256078)
		(width 0.0889)
		(layer "In11.Cu")
		(net "M_F_DQ<49>")
	)
	(segment
		(start 292.893496 -121.840752)
		(end 292.893496 -121.533412)
		(width 0.14224)
		(layer "In11.Cu")
		(net "M_F_DQ<49>")
	)
	(segment
		(start 281.197558 -99.395788)
		(end 281.230324 -99.395788)
		(width 0.0889)
		(layer "In11.Cu")
		(net "M_F_DQ<49>")
	)
	(segment
		(start 295.74617 -121.5263)
		(end 295.90111 -121.37136)
		(width 0.14224)
		(layer "In11.Cu")
		(net "M_F_DQ<49>")
	)
	(segment
		(start 293.556436 -121.533412)
		(end 293.556436 -121.840752)
		(width 0.14224)
		(layer "In11.Cu")
		(net "M_F_DQ<49>")
	)
	(segment
		(start 281.729434 -102.247446)
		(end 281.713686 -102.274878)
		(width 0.0889)
		(layer "In11.Cu")
		(net "M_F_DQ<49>")
	)
	(segment
		(start 281.726894 -101.261164)
		(end 281.713686 -101.284278)
		(width 0.0889)
		(layer "In11.Cu")
		(net "M_F_DQ<49>")
	)
	(arc
		(start 277.434294 -93.262704)
		(mid 277.507092 -93.553467)
		(end 277.427944 -93.842586)
		(width 0.0889)
		(layer "In11.Cu")
		(net "M_F_DQ<49>")
	)
	(arc
		(start 277.427944 -94.833186)
		(mid 277.374445 -95.033084)
		(end 277.427944 -95.232982)
		(width 0.0889)
		(layer "In11.Cu")
		(net "M_F_DQ<49>")
	)
	(arc
		(start 281.713686 -101.284278)
		(mid 281.66701 -101.478979)
		(end 281.720544 -101.671882)
		(width 0.0889)
		(layer "In11.Cu")
		(net "M_F_DQ<49>")
	)
	(arc
		(start 281.720544 -102.662482)
		(mid 281.799733 -102.949097)
		(end 281.729434 -103.238046)
		(width 0.0889)
		(layer "In11.Cu")
		(net "M_F_DQ<49>")
	)
	(arc
		(start 277.427944 -92.851986)
		(mid 277.374474 -93.047049)
		(end 277.423118 -93.2434)
		(width 0.0889)
		(layer "In11.Cu")
		(net "M_F_DQ<49>")
	)
	(arc
		(start 281.713686 -103.265478)
		(mid 281.66701 -103.460179)
		(end 281.720544 -103.653082)
		(width 0.0889)
		(layer "In11.Cu")
		(net "M_F_DQ<49>")
	)
	(arc
		(start 281.713686 -100.293678)
		(mid 281.66701 -100.488379)
		(end 281.720544 -100.681282)
		(width 0.0889)
		(layer "In11.Cu")
		(net "M_F_DQ<49>")
	)
	(arc
		(start 281.713686 -102.274878)
		(mid 281.66701 -102.469579)
		(end 281.720544 -102.662482)
		(width 0.0889)
		(layer "In11.Cu")
		(net "M_F_DQ<49>")
	)
	(arc
		(start 277.427944 -94.242636)
		(mid 277.507166 -94.531754)
		(end 277.434294 -94.822518)
		(width 0.0889)
		(layer "In11.Cu")
		(net "M_F_DQ<49>")
	)
	(arc
		(start 277.427944 -95.823786)
		(mid 277.374474 -96.018849)
		(end 277.423118 -96.2152)
		(width 0.0889)
		(layer "In11.Cu")
		(net "M_F_DQ<49>")
	)
	(arc
		(start 281.720544 -105.634282)
		(mid 281.799733 -105.920897)
		(end 281.729434 -106.209846)
		(width 0.0889)
		(layer "In11.Cu")
		(net "M_F_DQ<49>")
	)
	(arc
		(start 279.144984 -98.205036)
		(mid 279.286667 -98.34884)
		(end 279.480518 -98.405188)
		(width 0.0889)
		(layer "In11.Cu")
		(net "M_F_DQ<49>")
	)
	(arc
		(start 277.434294 -96.234504)
		(mid 277.507092 -96.525267)
		(end 277.427944 -96.814386)
		(width 0.0889)
		(layer "In11.Cu")
		(net "M_F_DQ<49>")
	)
	(arc
		(start 281.720544 -103.653082)
		(mid 281.799733 -103.939697)
		(end 281.729434 -104.228646)
		(width 0.0889)
		(layer "In11.Cu")
		(net "M_F_DQ<49>")
	)
	(arc
		(start 281.720544 -104.643682)
		(mid 281.799733 -104.930297)
		(end 281.729434 -105.219246)
		(width 0.0889)
		(layer "In11.Cu")
		(net "M_F_DQ<49>")
	)
	(arc
		(start 279.513284 -98.405188)
		(mid 279.796501 -98.489469)
		(end 280.003504 -98.700336)
		(width 0.0889)
		(layer "In11.Cu")
		(net "M_F_DQ<49>")
	)
	(arc
		(start 281.720544 -106.225086)
		(mid 281.688982 -106.274138)
		(end 281.652726 -106.319828)
		(width 0.0889)
		(layer "In11.Cu")
		(net "M_F_DQ<49>")
	)
	(arc
		(start 281.713686 -104.256078)
		(mid 281.66701 -104.450779)
		(end 281.720544 -104.643682)
		(width 0.0889)
		(layer "In11.Cu")
		(net "M_F_DQ<49>")
	)
	(arc
		(start 278.286464 -97.709736)
		(mid 278.426543 -97.852472)
		(end 278.618188 -97.909634)
		(width 0.0889)
		(layer "In11.Cu")
		(net "M_F_DQ<49>")
	)
	(arc
		(start 277.796244 -97.414588)
		(mid 278.079461 -97.498869)
		(end 278.286464 -97.709736)
		(width 0.0889)
		(layer "In11.Cu")
		(net "M_F_DQ<49>")
	)
	(arc
		(start 281.713686 -105.246678)
		(mid 281.66701 -105.441379)
		(end 281.720544 -105.634282)
		(width 0.0889)
		(layer "In11.Cu")
		(net "M_F_DQ<49>")
	)
	(arc
		(start 278.650954 -97.909634)
		(mid 278.936378 -97.993101)
		(end 279.144984 -98.205036)
		(width 0.0889)
		(layer "In11.Cu")
		(net "M_F_DQ<49>")
	)
	(arc
		(start 280.367994 -98.900234)
		(mid 280.653418 -98.983701)
		(end 280.862024 -99.195636)
		(width 0.0889)
		(layer "In11.Cu")
		(net "M_F_DQ<49>")
	)
	(arc
		(start 277.427944 -93.842586)
		(mid 277.374474 -94.037649)
		(end 277.423118 -94.234)
		(width 0.0889)
		(layer "In11.Cu")
		(net "M_F_DQ<49>")
	)
	(arc
		(start 281.230324 -99.395788)
		(mid 281.722714 -99.694721)
		(end 281.726894 -100.270818)
		(width 0.0889)
		(layer "In11.Cu")
		(net "M_F_DQ<49>")
	)
	(arc
		(start 281.720544 -100.681282)
		(mid 281.799733 -100.967897)
		(end 281.729434 -101.256846)
		(width 0.0889)
		(layer "In11.Cu")
		(net "M_F_DQ<49>")
	)
	(arc
		(start 280.003504 -98.700336)
		(mid 280.143583 -98.843072)
		(end 280.335228 -98.900234)
		(width 0.0889)
		(layer "In11.Cu")
		(net "M_F_DQ<49>")
	)
	(arc
		(start 277.427944 -96.814386)
		(mid 277.425196 -97.209853)
		(end 277.763478 -97.414588)
		(width 0.0889)
		(layer "In11.Cu")
		(net "M_F_DQ<49>")
	)
	(arc
		(start 280.862024 -99.195636)
		(mid 281.003707 -99.33944)
		(end 281.197558 -99.395788)
		(width 0.0889)
		(layer "In11.Cu")
		(net "M_F_DQ<49>")
	)
	(arc
		(start 277.427944 -95.232982)
		(mid 277.507075 -95.528384)
		(end 277.427944 -95.823786)
		(width 0.0889)
		(layer "In11.Cu")
		(net "M_F_DQ<49>")
	)
	(arc
		(start 281.720544 -101.671882)
		(mid 281.799733 -101.958497)
		(end 281.729434 -102.247446)
		(width 0.0889)
		(layer "In11.Cu")
		(net "M_F_DQ<49>")
	)
	(segment
		(start 300.949868 -156.878782)
		(end 300.870366 -156.046932)
		(width 0.1651)
		(layer "F.Cu")
		(net "M_F_DQ<48>")
	)
	(segment
		(start 300.950376 -156.87294)
		(end 300.949868 -156.878782)
		(width 0.1651)
		(layer "F.Cu")
		(net "M_F_DQ<48>")
	)
	(segment
		(start 300.870366 -156.046932)
		(end 300.772068 -155.0162)
		(width 0.1651)
		(layer "F.Cu")
		(net "M_F_DQ<48>")
	)
	(segment
		(start 277.203154 -90.080338)
		(end 277.774654 -90.080338)
		(width 0.1651)
		(layer "F.Cu")
		(net "M_F_DQ<48>")
	)
	(via
		(at 300.099984 -150.814278)
		(size 0.508)
		(drill 0.254)
		(layers "F.Cu" "B.Cu")
		(net "M_F_DQ<48>")
	)
	(via
		(at 277.774654 -90.080338)
		(size 0.508)
		(drill 0.254)
		(layers "F.Cu" "B.Cu")
		(net "M_F_DQ<48>")
	)
	(via
		(at 300.772068 -155.0162)
		(size 0.508)
		(drill 0.254)
		(layers "F.Cu" "B.Cu")
		(net "M_F_DQ<48>")
	)
	(segment
		(start 300.100492 -152.078436)
		(end 300.099984 -152.078182)
		(width 0.1651)
		(layer "B.Cu")
		(net "M_F_DQ<48>")
	)
	(segment
		(start 300.099984 -152.078182)
		(end 300.099984 -150.814278)
		(width 0.1651)
		(layer "B.Cu")
		(net "M_F_DQ<48>")
	)
	(segment
		(start 300.294802 -145.583402)
		(end 300.543468 -145.832068)
		(width 0.14224)
		(layer "In11.Cu")
		(net "M_F_DQ<48>")
	)
	(segment
		(start 300.099984 -150.814278)
		(end 299.666914 -151.247348)
		(width 0.14224)
		(layer "In11.Cu")
		(net "M_F_DQ<48>")
	)
	(segment
		(start 278.611584 -98.100134)
		(end 278.64435 -98.100134)
		(width 0.0889)
		(layer "In11.Cu")
		(net "M_F_DQ<48>")
	)
	(segment
		(start 300.316392 -130.028188)
		(end 300.316392 -131.176268)
		(width 0.14224)
		(layer "In11.Cu")
		(net "M_F_DQ<48>")
	)
	(segment
		(start 281.179524 -106.54792)
		(end 280.944574 -106.78287)
		(width 0.0889)
		(layer "In11.Cu")
		(net "M_F_DQ<48>")
	)
	(segment
		(start 300.550834 -126.374906)
		(end 300.550834 -129.793746)
		(width 0.14224)
		(layer "In11.Cu")
		(net "M_F_DQ<48>")
	)
	(segment
		(start 277.756874 -97.605088)
		(end 277.78964 -97.605088)
		(width 0.0889)
		(layer "In11.Cu")
		(net "M_F_DQ<48>")
	)
	(segment
		(start 277.256494 -92.346018)
		(end 277.262844 -92.356686)
		(width 0.0889)
		(layer "In11.Cu")
		(net "M_F_DQ<48>")
	)
	(segment
		(start 289.68319 -122.733816)
		(end 298.870878 -122.733816)
		(width 0.14224)
		(layer "In11.Cu")
		(net "M_F_DQ<48>")
	)
	(segment
		(start 277.262844 -95.328486)
		(end 277.26767 -95.337122)
		(width 0.0889)
		(layer "In11.Cu")
		(net "M_F_DQ<48>")
	)
	(segment
		(start 300.316646 -135.9789)
		(end 300.536356 -136.19861)
		(width 0.14224)
		(layer "In11.Cu")
		(net "M_F_DQ<48>")
	)
	(segment
		(start 277.262844 -91.366086)
		(end 277.26767 -91.374722)
		(width 0.0889)
		(layer "In11.Cu")
		(net "M_F_DQ<48>")
	)
	(segment
		(start 280.944574 -113.9952)
		(end 289.68319 -122.733816)
		(width 0.14224)
		(layer "In11.Cu")
		(net "M_F_DQ<48>")
	)
	(segment
		(start 281.562302 -102.15499)
		(end 281.546554 -102.182422)
		(width 0.0889)
		(layer "In11.Cu")
		(net "M_F_DQ<48>")
	)
	(segment
		(start 298.870878 -122.733816)
		(end 300.311566 -124.174504)
		(width 0.14224)
		(layer "In11.Cu")
		(net "M_F_DQ<48>")
	)
	(segment
		(start 300.550834 -129.793746)
		(end 300.316392 -130.028188)
		(width 0.14224)
		(layer "In11.Cu")
		(net "M_F_DQ<48>")
	)
	(segment
		(start 300.543722 -144.116298)
		(end 300.294802 -144.365218)
		(width 0.14224)
		(layer "In11.Cu")
		(net "M_F_DQ<48>")
	)
	(segment
		(start 300.316646 -134.742174)
		(end 300.316646 -135.9789)
		(width 0.14224)
		(layer "In11.Cu")
		(net "M_F_DQ<48>")
	)
	(segment
		(start 281.562302 -103.14559)
		(end 281.546554 -103.173022)
		(width 0.0889)
		(layer "In11.Cu")
		(net "M_F_DQ<48>")
	)
	(segment
		(start 277.262844 -93.347286)
		(end 277.26767 -93.355922)
		(width 0.0889)
		(layer "In11.Cu")
		(net "M_F_DQ<48>")
	)
	(segment
		(start 277.256494 -91.355418)
		(end 277.262844 -91.366086)
		(width 0.0889)
		(layer "In11.Cu")
		(net "M_F_DQ<48>")
	)
	(segment
		(start 299.666914 -151.247348)
		(end 299.666914 -154.20721)
		(width 0.14224)
		(layer "In11.Cu")
		(net "M_F_DQ<48>")
	)
	(segment
		(start 277.262844 -96.319086)
		(end 277.26767 -96.327722)
		(width 0.0889)
		(layer "In11.Cu")
		(net "M_F_DQ<48>")
	)
	(segment
		(start 300.316392 -131.176268)
		(end 300.625002 -131.484878)
		(width 0.14224)
		(layer "In11.Cu")
		(net "M_F_DQ<48>")
	)
	(segment
		(start 300.282102 -139.663678)
		(end 300.282102 -140.743178)
		(width 0.14224)
		(layer "In11.Cu")
		(net "M_F_DQ<48>")
	)
	(segment
		(start 299.666914 -154.20721)
		(end 300.475904 -155.0162)
		(width 0.14224)
		(layer "In11.Cu")
		(net "M_F_DQ<48>")
	)
	(segment
		(start 281.190954 -99.586288)
		(end 281.22372 -99.586288)
		(width 0.0889)
		(layer "In11.Cu")
		(net "M_F_DQ<48>")
	)
	(segment
		(start 281.562302 -101.16439)
		(end 281.546554 -101.191822)
		(width 0.0889)
		(layer "In11.Cu")
		(net "M_F_DQ<48>")
	)
	(segment
		(start 279.473914 -98.595688)
		(end 279.50668 -98.595688)
		(width 0.0889)
		(layer "In11.Cu")
		(net "M_F_DQ<48>")
	)
	(segment
		(start 300.625002 -131.484878)
		(end 300.625002 -134.433818)
		(width 0.14224)
		(layer "In11.Cu")
		(net "M_F_DQ<48>")
	)
	(segment
		(start 300.475904 -155.0162)
		(end 300.772068 -155.0162)
		(width 0.14224)
		(layer "In11.Cu")
		(net "M_F_DQ<48>")
	)
	(segment
		(start 300.282102 -140.743178)
		(end 300.543722 -141.004798)
		(width 0.14224)
		(layer "In11.Cu")
		(net "M_F_DQ<48>")
	)
	(segment
		(start 300.543468 -149.003512)
		(end 299.912024 -149.634956)
		(width 0.14224)
		(layer "In11.Cu")
		(net "M_F_DQ<48>")
	)
	(segment
		(start 300.311566 -124.174504)
		(end 300.311566 -126.135638)
		(width 0.14224)
		(layer "In11.Cu")
		(net "M_F_DQ<48>")
	)
	(segment
		(start 300.536356 -139.409424)
		(end 300.282102 -139.663678)
		(width 0.14224)
		(layer "In11.Cu")
		(net "M_F_DQ<48>")
	)
	(segment
		(start 277.774654 -90.080338)
		(end 277.279608 -90.746072)
		(width 0.0889)
		(layer "In11.Cu")
		(net "M_F_DQ<48>")
	)
	(segment
		(start 281.562302 -105.12679)
		(end 281.546554 -105.154222)
		(width 0.0889)
		(layer "In11.Cu")
		(net "M_F_DQ<48>")
	)
	(segment
		(start 300.543468 -145.832068)
		(end 300.543468 -149.003512)
		(width 0.14224)
		(layer "In11.Cu")
		(net "M_F_DQ<48>")
	)
	(segment
		(start 281.562302 -104.13619)
		(end 281.546554 -104.163622)
		(width 0.0889)
		(layer "In11.Cu")
		(net "M_F_DQ<48>")
	)
	(segment
		(start 281.562302 -100.17379)
		(end 281.546554 -100.201222)
		(width 0.0889)
		(layer "In11.Cu")
		(net "M_F_DQ<48>")
	)
	(segment
		(start 277.256494 -93.336618)
		(end 277.262844 -93.347286)
		(width 0.0889)
		(layer "In11.Cu")
		(net "M_F_DQ<48>")
	)
	(segment
		(start 277.256494 -96.308418)
		(end 277.262844 -96.319086)
		(width 0.0889)
		(layer "In11.Cu")
		(net "M_F_DQ<48>")
	)
	(segment
		(start 277.262844 -94.737936)
		(end 277.256494 -94.748604)
		(width 0.0889)
		(layer "In11.Cu")
		(net "M_F_DQ<48>")
	)
	(segment
		(start 277.279608 -90.746072)
		(end 277.262844 -90.775536)
		(width 0.0889)
		(layer "In11.Cu")
		(net "M_F_DQ<48>")
	)
	(segment
		(start 300.543722 -141.004798)
		(end 300.543722 -144.116298)
		(width 0.14224)
		(layer "In11.Cu")
		(net "M_F_DQ<48>")
	)
	(segment
		(start 300.311566 -126.135638)
		(end 300.550834 -126.374906)
		(width 0.14224)
		(layer "In11.Cu")
		(net "M_F_DQ<48>")
	)
	(segment
		(start 300.625002 -134.433818)
		(end 300.316646 -134.742174)
		(width 0.14224)
		(layer "In11.Cu")
		(net "M_F_DQ<48>")
	)
	(segment
		(start 280.328624 -99.090734)
		(end 280.36139 -99.090734)
		(width 0.0889)
		(layer "In11.Cu")
		(net "M_F_DQ<48>")
	)
	(segment
		(start 280.944574 -106.78287)
		(end 280.944574 -113.9952)
		(width 0.14224)
		(layer "In11.Cu")
		(net "M_F_DQ<48>")
	)
	(segment
		(start 300.536356 -136.19861)
		(end 300.536356 -139.409424)
		(width 0.14224)
		(layer "In11.Cu")
		(net "M_F_DQ<48>")
	)
	(segment
		(start 300.294802 -144.365218)
		(end 300.294802 -145.583402)
		(width 0.14224)
		(layer "In11.Cu")
		(net "M_F_DQ<48>")
	)
	(segment
		(start 299.912024 -149.634956)
		(end 299.912024 -150.626318)
		(width 0.14224)
		(layer "In11.Cu")
		(net "M_F_DQ<48>")
	)
	(segment
		(start 277.262844 -92.356686)
		(end 277.26767 -92.365322)
		(width 0.0889)
		(layer "In11.Cu")
		(net "M_F_DQ<48>")
	)
	(segment
		(start 281.429968 -106.26344)
		(end 281.179524 -106.54792)
		(width 0.0889)
		(layer "In11.Cu")
		(net "M_F_DQ<48>")
	)
	(segment
		(start 299.912024 -150.626318)
		(end 300.099984 -150.814278)
		(width 0.14224)
		(layer "In11.Cu")
		(net "M_F_DQ<48>")
	)
	(arc
		(start 277.256494 -94.748604)
		(mid 277.183696 -95.039367)
		(end 277.262844 -95.328486)
		(width 0.0889)
		(layer "In11.Cu")
		(net "M_F_DQ<48>")
	)
	(arc
		(start 279.838404 -98.795586)
		(mid 280.045408 -99.00645)
		(end 280.328624 -99.090734)
		(width 0.0889)
		(layer "In11.Cu")
		(net "M_F_DQ<48>")
	)
	(arc
		(start 277.26767 -91.374722)
		(mid 277.316425 -91.571074)
		(end 277.262844 -91.766136)
		(width 0.0889)
		(layer "In11.Cu")
		(net "M_F_DQ<48>")
	)
	(arc
		(start 277.262844 -91.766136)
		(mid 277.183622 -92.055254)
		(end 277.256494 -92.346018)
		(width 0.0889)
		(layer "In11.Cu")
		(net "M_F_DQ<48>")
	)
	(arc
		(start 281.22372 -99.586288)
		(mid 281.555564 -99.786405)
		(end 281.562302 -100.17379)
		(width 0.0889)
		(layer "In11.Cu")
		(net "M_F_DQ<48>")
	)
	(arc
		(start 280.36139 -99.090734)
		(mid 280.55524 -99.147084)
		(end 280.696924 -99.290886)
		(width 0.0889)
		(layer "In11.Cu")
		(net "M_F_DQ<48>")
	)
	(arc
		(start 278.64435 -98.100134)
		(mid 278.8382 -98.156484)
		(end 278.979884 -98.300286)
		(width 0.0889)
		(layer "In11.Cu")
		(net "M_F_DQ<48>")
	)
	(arc
		(start 278.121364 -97.804986)
		(mid 278.328368 -98.01585)
		(end 278.611584 -98.100134)
		(width 0.0889)
		(layer "In11.Cu")
		(net "M_F_DQ<48>")
	)
	(arc
		(start 277.26767 -92.365322)
		(mid 277.316425 -92.561674)
		(end 277.262844 -92.756736)
		(width 0.0889)
		(layer "In11.Cu")
		(net "M_F_DQ<48>")
	)
	(arc
		(start 281.546554 -104.163622)
		(mid 281.476157 -104.452573)
		(end 281.555444 -104.739186)
		(width 0.0889)
		(layer "In11.Cu")
		(net "M_F_DQ<48>")
	)
	(arc
		(start 281.555444 -100.776786)
		(mid 281.608882 -100.969691)
		(end 281.562302 -101.16439)
		(width 0.0889)
		(layer "In11.Cu")
		(net "M_F_DQ<48>")
	)
	(arc
		(start 277.262844 -95.728536)
		(mid 277.183622 -96.017654)
		(end 277.256494 -96.308418)
		(width 0.0889)
		(layer "In11.Cu")
		(net "M_F_DQ<48>")
	)
	(arc
		(start 277.262844 -93.747336)
		(mid 277.183713 -94.042738)
		(end 277.262844 -94.33814)
		(width 0.0889)
		(layer "In11.Cu")
		(net "M_F_DQ<48>")
	)
	(arc
		(start 281.546554 -100.201222)
		(mid 281.476157 -100.490173)
		(end 281.555444 -100.776786)
		(width 0.0889)
		(layer "In11.Cu")
		(net "M_F_DQ<48>")
	)
	(arc
		(start 277.262844 -90.775536)
		(mid 277.183622 -91.064654)
		(end 277.256494 -91.355418)
		(width 0.0889)
		(layer "In11.Cu")
		(net "M_F_DQ<48>")
	)
	(arc
		(start 278.979884 -98.300286)
		(mid 279.188492 -98.512218)
		(end 279.473914 -98.595688)
		(width 0.0889)
		(layer "In11.Cu")
		(net "M_F_DQ<48>")
	)
	(arc
		(start 277.262844 -94.33814)
		(mid 277.316343 -94.538038)
		(end 277.262844 -94.737936)
		(width 0.0889)
		(layer "In11.Cu")
		(net "M_F_DQ<48>")
	)
	(arc
		(start 281.555444 -105.729786)
		(mid 281.598458 -106.021503)
		(end 281.429968 -106.26344)
		(width 0.0889)
		(layer "In11.Cu")
		(net "M_F_DQ<48>")
	)
	(arc
		(start 279.50668 -98.595688)
		(mid 279.698322 -98.652854)
		(end 279.838404 -98.795586)
		(width 0.0889)
		(layer "In11.Cu")
		(net "M_F_DQ<48>")
	)
	(arc
		(start 280.696924 -99.290886)
		(mid 280.905532 -99.502818)
		(end 281.190954 -99.586288)
		(width 0.0889)
		(layer "In11.Cu")
		(net "M_F_DQ<48>")
	)
	(arc
		(start 281.555444 -102.757986)
		(mid 281.608882 -102.950891)
		(end 281.562302 -103.14559)
		(width 0.0889)
		(layer "In11.Cu")
		(net "M_F_DQ<48>")
	)
	(arc
		(start 277.26767 -95.337122)
		(mid 277.316425 -95.533474)
		(end 277.262844 -95.728536)
		(width 0.0889)
		(layer "In11.Cu")
		(net "M_F_DQ<48>")
	)
	(arc
		(start 281.555444 -103.748586)
		(mid 281.608882 -103.941491)
		(end 281.562302 -104.13619)
		(width 0.0889)
		(layer "In11.Cu")
		(net "M_F_DQ<48>")
	)
	(arc
		(start 277.262844 -92.756736)
		(mid 277.183622 -93.045854)
		(end 277.256494 -93.336618)
		(width 0.0889)
		(layer "In11.Cu")
		(net "M_F_DQ<48>")
	)
	(arc
		(start 277.262844 -96.719136)
		(mid 277.258515 -97.302308)
		(end 277.756874 -97.605088)
		(width 0.0889)
		(layer "In11.Cu")
		(net "M_F_DQ<48>")
	)
	(arc
		(start 281.555444 -101.767386)
		(mid 281.608882 -101.960291)
		(end 281.562302 -102.15499)
		(width 0.0889)
		(layer "In11.Cu")
		(net "M_F_DQ<48>")
	)
	(arc
		(start 281.546554 -102.182422)
		(mid 281.476157 -102.471373)
		(end 281.555444 -102.757986)
		(width 0.0889)
		(layer "In11.Cu")
		(net "M_F_DQ<48>")
	)
	(arc
		(start 281.555444 -104.739186)
		(mid 281.608882 -104.932091)
		(end 281.562302 -105.12679)
		(width 0.0889)
		(layer "In11.Cu")
		(net "M_F_DQ<48>")
	)
	(arc
		(start 281.546554 -103.173022)
		(mid 281.476157 -103.461973)
		(end 281.555444 -103.748586)
		(width 0.0889)
		(layer "In11.Cu")
		(net "M_F_DQ<48>")
	)
	(arc
		(start 281.546554 -101.191822)
		(mid 281.476157 -101.480773)
		(end 281.555444 -101.767386)
		(width 0.0889)
		(layer "In11.Cu")
		(net "M_F_DQ<48>")
	)
	(arc
		(start 277.26767 -93.355922)
		(mid 277.316425 -93.552274)
		(end 277.262844 -93.747336)
		(width 0.0889)
		(layer "In11.Cu")
		(net "M_F_DQ<48>")
	)
	(arc
		(start 281.546554 -105.154222)
		(mid 281.476157 -105.443173)
		(end 281.555444 -105.729786)
		(width 0.0889)
		(layer "In11.Cu")
		(net "M_F_DQ<48>")
	)
	(arc
		(start 277.78964 -97.605088)
		(mid 277.981282 -97.662254)
		(end 278.121364 -97.804986)
		(width 0.0889)
		(layer "In11.Cu")
		(net "M_F_DQ<48>")
	)
	(arc
		(start 277.26767 -96.327722)
		(mid 277.316425 -96.524074)
		(end 277.262844 -96.719136)
		(width 0.0889)
		(layer "In11.Cu")
		(net "M_F_DQ<48>")
	)
	(segment
		(start 295.000426 -152.273)
		(end 294.999918 -152.278842)
		(width 0.1651)
		(layer "F.Cu")
		(net "M_F_DQ<47>")
	)
	(segment
		(start 294.999918 -152.278842)
		(end 294.999918 -153.542746)
		(width 0.1651)
		(layer "F.Cu")
		(net "M_F_DQ<47>")
	)
	(segment
		(start 281.495754 -95.528384)
		(end 282.067254 -95.528384)
		(width 0.1651)
		(layer "F.Cu")
		(net "M_F_DQ<47>")
	)
	(via
		(at 282.067254 -95.528384)
		(size 0.508)
		(drill 0.254)
		(layers "F.Cu" "B.Cu")
		(net "M_F_DQ<47>")
	)
	(via
		(at 295.849802 -149.533356)
		(size 0.508)
		(drill 0.254)
		(layers "F.Cu" "B.Cu")
		(net "M_F_DQ<47>")
	)
	(via
		(at 294.999918 -153.542746)
		(size 0.508)
		(drill 0.254)
		(layers "F.Cu" "B.Cu")
		(net "M_F_DQ<47>")
	)
	(segment
		(start 295.849802 -147.478496)
		(end 295.849802 -149.533356)
		(width 0.1651)
		(layer "B.Cu")
		(net "M_F_DQ<47>")
	)
	(segment
		(start 295.85031 -147.478496)
		(end 295.849802 -147.478496)
		(width 0.1651)
		(layer "B.Cu")
		(net "M_F_DQ<47>")
	)
	(segment
		(start 282.579064 -100.776278)
		(end 282.574238 -100.784914)
		(width 0.0889)
		(layer "In4.Cu")
		(net "M_F_DQ<47>")
	)
	(segment
		(start 283.935424 -106.96956)
		(end 284.18536 -107.219496)
		(width 0.0889)
		(layer "In4.Cu")
		(net "M_F_DQ<47>")
	)
	(segment
		(start 296.151808 -141.086078)
		(end 296.151808 -141.516354)
		(width 0.14224)
		(layer "In4.Cu")
		(net "M_F_DQ<47>")
	)
	(segment
		(start 296.191686 -149.191472)
		(end 295.849802 -149.533356)
		(width 0.14224)
		(layer "In4.Cu")
		(net "M_F_DQ<47>")
	)
	(segment
		(start 296.291 -136.6774)
		(end 296.291 -138.6586)
		(width 0.14224)
		(layer "In4.Cu")
		(net "M_F_DQ<47>")
	)
	(segment
		(start 282.920948 -104.348788)
		(end 282.947364 -104.348788)
		(width 0.0889)
		(layer "In4.Cu")
		(net "M_F_DQ<47>")
	)
	(segment
		(start 282.5623 -96.194372)
		(end 282.579064 -96.223836)
		(width 0.0889)
		(layer "In4.Cu")
		(net "M_F_DQ<47>")
	)
	(segment
		(start 283.437584 -105.234486)
		(end 283.432758 -105.243122)
		(width 0.0889)
		(layer "In4.Cu")
		(net "M_F_DQ<47>")
	)
	(segment
		(start 290.629594 -118.88851)
		(end 290.848542 -118.88851)
		(width 0.14224)
		(layer "In4.Cu")
		(net "M_F_DQ<47>")
	)
	(segment
		(start 282.574238 -97.2058)
		(end 282.579064 -97.214436)
		(width 0.0889)
		(layer "In4.Cu")
		(net "M_F_DQ<47>")
	)
	(segment
		(start 296.291 -143.5862)
		(end 296.228008 -143.649192)
		(width 0.14224)
		(layer "In4.Cu")
		(net "M_F_DQ<47>")
	)
	(segment
		(start 290.848542 -118.88851)
		(end 291.066474 -118.670578)
		(width 0.14224)
		(layer "In4.Cu")
		(net "M_F_DQ<47>")
	)
	(segment
		(start 296.291 -138.6586)
		(end 296.202608 -138.746992)
		(width 0.14224)
		(layer "In4.Cu")
		(net "M_F_DQ<47>")
	)
	(segment
		(start 291.78631 -119.826278)
		(end 292.307518 -119.30507)
		(width 0.14224)
		(layer "In4.Cu")
		(net "M_F_DQ<47>")
	)
	(segment
		(start 296.202608 -136.589008)
		(end 296.291 -136.6774)
		(width 0.14224)
		(layer "In4.Cu")
		(net "M_F_DQ<47>")
	)
	(segment
		(start 292.255194 -120.51411)
		(end 292.54196 -120.800876)
		(width 0.14224)
		(layer "In4.Cu")
		(net "M_F_DQ<47>")
	)
	(segment
		(start 292.54196 -120.800876)
		(end 294.090852 -120.800876)
		(width 0.14224)
		(layer "In4.Cu")
		(net "M_F_DQ<47>")
	)
	(segment
		(start 292.776402 -119.773954)
		(end 292.255194 -120.295162)
		(width 0.14224)
		(layer "In4.Cu")
		(net "M_F_DQ<47>")
	)
	(segment
		(start 291.317426 -119.576342)
		(end 291.567362 -119.826278)
		(width 0.14224)
		(layer "In4.Cu")
		(net "M_F_DQ<47>")
	)
	(segment
		(start 296.431208 -131.205478)
		(end 296.228008 -131.408678)
		(width 0.14224)
		(layer "In4.Cu")
		(net "M_F_DQ<47>")
	)
	(segment
		(start 282.585414 -100.76561)
		(end 282.579064 -100.776278)
		(width 0.0889)
		(layer "In4.Cu")
		(net "M_F_DQ<47>")
	)
	(segment
		(start 291.317426 -119.357394)
		(end 291.317426 -119.576342)
		(width 0.14224)
		(layer "In4.Cu")
		(net "M_F_DQ<47>")
	)
	(segment
		(start 296.2656 -134.0612)
		(end 296.228008 -134.098792)
		(width 0.14224)
		(layer "In4.Cu")
		(net "M_F_DQ<47>")
	)
	(segment
		(start 296.202608 -136.232392)
		(end 296.202608 -136.589008)
		(width 0.14224)
		(layer "In4.Cu")
		(net "M_F_DQ<47>")
	)
	(segment
		(start 296.431208 -139.689078)
		(end 296.431208 -140.806678)
		(width 0.14224)
		(layer "In4.Cu")
		(net "M_F_DQ<47>")
	)
	(segment
		(start 292.307518 -119.30507)
		(end 292.48735 -119.30507)
		(width 0.14224)
		(layer "In4.Cu")
		(net "M_F_DQ<47>")
	)
	(segment
		(start 292.255194 -120.295162)
		(end 292.255194 -120.51411)
		(width 0.14224)
		(layer "In4.Cu")
		(net "M_F_DQ<47>")
	)
	(segment
		(start 296.151808 -141.516354)
		(end 296.291 -141.655546)
		(width 0.14224)
		(layer "In4.Cu")
		(net "M_F_DQ<47>")
	)
	(segment
		(start 296.371772 -144.313402)
		(end 296.371772 -145.664174)
		(width 0.14224)
		(layer "In4.Cu")
		(net "M_F_DQ<47>")
	)
	(segment
		(start 296.2656 -131.914392)
		(end 296.2656 -134.0612)
		(width 0.14224)
		(layer "In4.Cu")
		(net "M_F_DQ<47>")
	)
	(segment
		(start 283.516832 -105.929938)
		(end 283.516832 -106.380026)
		(width 0.0889)
		(layer "In4.Cu")
		(net "M_F_DQ<47>")
	)
	(segment
		(start 296.405808 -134.7089)
		(end 296.405808 -136.029192)
		(width 0.14224)
		(layer "In4.Cu")
		(net "M_F_DQ<47>")
	)
	(segment
		(start 291.535358 -119.139462)
		(end 291.317426 -119.357394)
		(width 0.14224)
		(layer "In4.Cu")
		(net "M_F_DQ<47>")
	)
	(segment
		(start 282.574238 -99.187)
		(end 282.579064 -99.195636)
		(width 0.0889)
		(layer "In4.Cu")
		(net "M_F_DQ<47>")
	)
	(segment
		(start 292.48735 -119.30507)
		(end 292.776402 -119.594122)
		(width 0.14224)
		(layer "In4.Cu")
		(net "M_F_DQ<47>")
	)
	(segment
		(start 296.228008 -143.649192)
		(end 296.228008 -144.169638)
		(width 0.14224)
		(layer "In4.Cu")
		(net "M_F_DQ<47>")
	)
	(segment
		(start 296.228008 -134.098792)
		(end 296.228008 -134.5311)
		(width 0.14224)
		(layer "In4.Cu")
		(net "M_F_DQ<47>")
	)
	(segment
		(start 296.228008 -131.8768)
		(end 296.2656 -131.914392)
		(width 0.14224)
		(layer "In4.Cu")
		(net "M_F_DQ<47>")
	)
	(segment
		(start 282.453842 -96.048576)
		(end 282.5623 -96.194372)
		(width 0.0889)
		(layer "In4.Cu")
		(net "M_F_DQ<47>")
	)
	(segment
		(start 295.444926 -123.522232)
		(end 296.202608 -124.279914)
		(width 0.14224)
		(layer "In4.Cu")
		(net "M_F_DQ<47>")
	)
	(segment
		(start 296.202608 -149.191472)
		(end 296.191686 -149.191472)
		(width 0.14224)
		(layer "In4.Cu")
		(net "M_F_DQ<47>")
	)
	(segment
		(start 296.202608 -139.460478)
		(end 296.431208 -139.689078)
		(width 0.14224)
		(layer "In4.Cu")
		(net "M_F_DQ<47>")
	)
	(segment
		(start 296.405808 -136.029192)
		(end 296.202608 -136.232392)
		(width 0.14224)
		(layer "In4.Cu")
		(net "M_F_DQ<47>")
	)
	(segment
		(start 291.246306 -118.670578)
		(end 291.535358 -118.95963)
		(width 0.14224)
		(layer "In4.Cu")
		(net "M_F_DQ<47>")
	)
	(segment
		(start 296.202608 -124.279914)
		(end 296.202608 -125.564392)
		(width 0.14224)
		(layer "In4.Cu")
		(net "M_F_DQ<47>")
	)
	(segment
		(start 296.228008 -144.169638)
		(end 296.371772 -144.313402)
		(width 0.14224)
		(layer "In4.Cu")
		(net "M_F_DQ<47>")
	)
	(segment
		(start 296.291 -141.655546)
		(end 296.291 -143.5862)
		(width 0.14224)
		(layer "In4.Cu")
		(net "M_F_DQ<47>")
	)
	(segment
		(start 284.18536 -112.444276)
		(end 290.629594 -118.88851)
		(width 0.14224)
		(layer "In4.Cu")
		(net "M_F_DQ<47>")
	)
	(segment
		(start 282.579064 -98.205036)
		(end 282.585414 -98.215704)
		(width 0.0889)
		(layer "In4.Cu")
		(net "M_F_DQ<47>")
	)
	(segment
		(start 296.228008 -134.5311)
		(end 296.405808 -134.7089)
		(width 0.14224)
		(layer "In4.Cu")
		(net "M_F_DQ<47>")
	)
	(segment
		(start 282.574238 -98.1964)
		(end 282.579064 -98.205036)
		(width 0.0889)
		(layer "In4.Cu")
		(net "M_F_DQ<47>")
	)
	(segment
		(start 291.535358 -118.95963)
		(end 291.535358 -119.139462)
		(width 0.14224)
		(layer "In4.Cu")
		(net "M_F_DQ<47>")
	)
	(segment
		(start 283.443934 -105.223818)
		(end 283.437584 -105.234486)
		(width 0.0889)
		(layer "In4.Cu")
		(net "M_F_DQ<47>")
	)
	(segment
		(start 282.067254 -95.528384)
		(end 282.453842 -96.048576)
		(width 0.0889)
		(layer "In4.Cu")
		(net "M_F_DQ<47>")
	)
	(segment
		(start 296.431208 -140.806678)
		(end 296.151808 -141.086078)
		(width 0.14224)
		(layer "In4.Cu")
		(net "M_F_DQ<47>")
	)
	(segment
		(start 296.202608 -125.564392)
		(end 295.9862 -125.7808)
		(width 0.14224)
		(layer "In4.Cu")
		(net "M_F_DQ<47>")
	)
	(segment
		(start 296.371772 -145.664174)
		(end 296.202608 -145.833338)
		(width 0.14224)
		(layer "In4.Cu")
		(net "M_F_DQ<47>")
	)
	(segment
		(start 296.202608 -138.746992)
		(end 296.202608 -139.460478)
		(width 0.14224)
		(layer "In4.Cu")
		(net "M_F_DQ<47>")
	)
	(segment
		(start 296.202608 -129.859278)
		(end 296.431208 -130.087878)
		(width 0.14224)
		(layer "In4.Cu")
		(net "M_F_DQ<47>")
	)
	(segment
		(start 291.567362 -119.826278)
		(end 291.78631 -119.826278)
		(width 0.14224)
		(layer "In4.Cu")
		(net "M_F_DQ<47>")
	)
	(segment
		(start 282.579064 -96.223836)
		(end 282.585414 -96.234504)
		(width 0.0889)
		(layer "In4.Cu")
		(net "M_F_DQ<47>")
	)
	(segment
		(start 282.579064 -97.214436)
		(end 282.585414 -97.225104)
		(width 0.0889)
		(layer "In4.Cu")
		(net "M_F_DQ<47>")
	)
	(segment
		(start 296.228008 -131.408678)
		(end 296.228008 -131.8768)
		(width 0.14224)
		(layer "In4.Cu")
		(net "M_F_DQ<47>")
	)
	(segment
		(start 295.9862 -125.7808)
		(end 295.9862 -127.889)
		(width 0.14224)
		(layer "In4.Cu")
		(net "M_F_DQ<47>")
	)
	(segment
		(start 296.202608 -128.105408)
		(end 296.202608 -129.859278)
		(width 0.14224)
		(layer "In4.Cu")
		(net "M_F_DQ<47>")
	)
	(segment
		(start 296.202608 -145.833338)
		(end 296.202608 -149.191472)
		(width 0.14224)
		(layer "In4.Cu")
		(net "M_F_DQ<47>")
	)
	(segment
		(start 295.9862 -127.889)
		(end 296.202608 -128.105408)
		(width 0.14224)
		(layer "In4.Cu")
		(net "M_F_DQ<47>")
	)
	(segment
		(start 282.572206 -103.14559)
		(end 282.587954 -103.173022)
		(width 0.0889)
		(layer "In4.Cu")
		(net "M_F_DQ<47>")
	)
	(segment
		(start 283.935424 -106.798618)
		(end 283.935424 -106.96956)
		(width 0.0889)
		(layer "In4.Cu")
		(net "M_F_DQ<47>")
	)
	(segment
		(start 292.776402 -119.594122)
		(end 292.776402 -119.773954)
		(width 0.14224)
		(layer "In4.Cu")
		(net "M_F_DQ<47>")
	)
	(segment
		(start 284.18536 -107.219496)
		(end 284.18536 -112.444276)
		(width 0.14224)
		(layer "In4.Cu")
		(net "M_F_DQ<47>")
	)
	(segment
		(start 282.579064 -99.195636)
		(end 282.585414 -99.206304)
		(width 0.0889)
		(layer "In4.Cu")
		(net "M_F_DQ<47>")
	)
	(segment
		(start 295.444926 -122.15495)
		(end 295.444926 -123.522232)
		(width 0.14224)
		(layer "In4.Cu")
		(net "M_F_DQ<47>")
	)
	(segment
		(start 291.066474 -118.670578)
		(end 291.246306 -118.670578)
		(width 0.14224)
		(layer "In4.Cu")
		(net "M_F_DQ<47>")
	)
	(segment
		(start 283.516832 -106.380026)
		(end 283.935424 -106.798618)
		(width 0.0889)
		(layer "In4.Cu")
		(net "M_F_DQ<47>")
	)
	(segment
		(start 296.431208 -130.087878)
		(end 296.431208 -131.205478)
		(width 0.14224)
		(layer "In4.Cu")
		(net "M_F_DQ<47>")
	)
	(segment
		(start 282.579064 -102.166928)
		(end 282.585414 -102.177596)
		(width 0.0889)
		(layer "In4.Cu")
		(net "M_F_DQ<47>")
	)
	(segment
		(start 294.090852 -120.800876)
		(end 295.444926 -122.15495)
		(width 0.14224)
		(layer "In4.Cu")
		(net "M_F_DQ<47>")
	)
	(arc
		(start 282.579064 -96.814386)
		(mid 282.525594 -97.009449)
		(end 282.574238 -97.2058)
		(width 0.0889)
		(layer "In4.Cu")
		(net "M_F_DQ<47>")
	)
	(arc
		(start 283.437584 -105.634536)
		(mid 283.496651 -105.777022)
		(end 283.516832 -105.929938)
		(width 0.0889)
		(layer "In4.Cu")
		(net "M_F_DQ<47>")
	)
	(arc
		(start 282.585414 -98.215704)
		(mid 282.658212 -98.506467)
		(end 282.579064 -98.795586)
		(width 0.0889)
		(layer "In4.Cu")
		(net "M_F_DQ<47>")
	)
	(arc
		(start 282.579064 -100.185728)
		(mid 282.658286 -100.474846)
		(end 282.585414 -100.76561)
		(width 0.0889)
		(layer "In4.Cu")
		(net "M_F_DQ<47>")
	)
	(arc
		(start 282.579064 -97.804986)
		(mid 282.525594 -98.000049)
		(end 282.574238 -98.1964)
		(width 0.0889)
		(layer "In4.Cu")
		(net "M_F_DQ<47>")
	)
	(arc
		(start 282.579064 -98.795586)
		(mid 282.525594 -98.990649)
		(end 282.574238 -99.187)
		(width 0.0889)
		(layer "In4.Cu")
		(net "M_F_DQ<47>")
	)
	(arc
		(start 282.585414 -96.234504)
		(mid 282.658212 -96.525267)
		(end 282.579064 -96.814386)
		(width 0.0889)
		(layer "In4.Cu")
		(net "M_F_DQ<47>")
	)
	(arc
		(start 282.947364 -104.348788)
		(mid 283.439754 -104.647721)
		(end 283.443934 -105.223818)
		(width 0.0889)
		(layer "In4.Cu")
		(net "M_F_DQ<47>")
	)
	(arc
		(start 282.585414 -102.177596)
		(mid 282.658334 -102.468613)
		(end 282.579064 -102.757986)
		(width 0.0889)
		(layer "In4.Cu")
		(net "M_F_DQ<47>")
	)
	(arc
		(start 283.432758 -105.243122)
		(mid 283.384003 -105.439474)
		(end 283.437584 -105.634536)
		(width 0.0889)
		(layer "In4.Cu")
		(net "M_F_DQ<47>")
	)
	(arc
		(start 282.579064 -101.767132)
		(mid 282.525565 -101.96703)
		(end 282.579064 -102.166928)
		(width 0.0889)
		(layer "In4.Cu")
		(net "M_F_DQ<47>")
	)
	(arc
		(start 282.574238 -100.1776)
		(mid 282.576577 -100.181708)
		(end 282.579064 -100.185728)
		(width 0.0889)
		(layer "In4.Cu")
		(net "M_F_DQ<47>")
	)
	(arc
		(start 282.574238 -100.784914)
		(mid 282.525483 -100.981266)
		(end 282.579064 -101.176328)
		(width 0.0889)
		(layer "In4.Cu")
		(net "M_F_DQ<47>")
	)
	(arc
		(start 282.579064 -103.748586)
		(mid 282.578042 -104.146599)
		(end 282.920948 -104.348788)
		(width 0.0889)
		(layer "In4.Cu")
		(net "M_F_DQ<47>")
	)
	(arc
		(start 282.579064 -99.786186)
		(mid 282.525594 -99.981249)
		(end 282.574238 -100.1776)
		(width 0.0889)
		(layer "In4.Cu")
		(net "M_F_DQ<47>")
	)
	(arc
		(start 282.585414 -99.206304)
		(mid 282.658212 -99.497067)
		(end 282.579064 -99.786186)
		(width 0.0889)
		(layer "In4.Cu")
		(net "M_F_DQ<47>")
	)
	(arc
		(start 282.579064 -102.757986)
		(mid 282.525626 -102.950891)
		(end 282.572206 -103.14559)
		(width 0.0889)
		(layer "In4.Cu")
		(net "M_F_DQ<47>")
	)
	(arc
		(start 282.579064 -101.176328)
		(mid 282.658195 -101.47173)
		(end 282.579064 -101.767132)
		(width 0.0889)
		(layer "In4.Cu")
		(net "M_F_DQ<47>")
	)
	(arc
		(start 282.585414 -97.225104)
		(mid 282.658212 -97.515867)
		(end 282.579064 -97.804986)
		(width 0.0889)
		(layer "In4.Cu")
		(net "M_F_DQ<47>")
	)
	(arc
		(start 282.587954 -103.173022)
		(mid 282.658351 -103.461973)
		(end 282.579064 -103.748586)
		(width 0.0889)
		(layer "In4.Cu")
		(net "M_F_DQ<47>")
	)
	(segment
		(start 295.161208 -152.752552)
		(end 295.161208 -152.479248)
		(width 0.14224)
		(layer "In11.Cu")
		(net "M_F_DQ<47>")
	)
	(segment
		(start 295.443656 -150.435818)
		(end 295.399206 -150.391368)
		(width 0.14224)
		(layer "In11.Cu")
		(net "M_F_DQ<47>")
	)
	(segment
		(start 295.399206 -149.9616)
		(end 295.82745 -149.533356)
		(width 0.14224)
		(layer "In11.Cu")
		(net "M_F_DQ<47>")
	)
	(segment
		(start 295.443656 -151.1046)
		(end 295.443656 -150.435818)
		(width 0.14224)
		(layer "In11.Cu")
		(net "M_F_DQ<47>")
	)
	(segment
		(start 295.161208 -151.660352)
		(end 295.161208 -151.387048)
		(width 0.14224)
		(layer "In11.Cu")
		(net "M_F_DQ<47>")
	)
	(segment
		(start 295.418256 -152.2222)
		(end 295.418256 -151.9174)
		(width 0.14224)
		(layer "In11.Cu")
		(net "M_F_DQ<47>")
	)
	(segment
		(start 295.399206 -150.391368)
		(end 295.399206 -149.9616)
		(width 0.14224)
		(layer "In11.Cu")
		(net "M_F_DQ<47>")
	)
	(segment
		(start 294.999918 -153.542746)
		(end 295.272206 -153.542746)
		(width 0.14224)
		(layer "In11.Cu")
		(net "M_F_DQ<47>")
	)
	(segment
		(start 295.82745 -149.533356)
		(end 295.849802 -149.533356)
		(width 0.14224)
		(layer "In11.Cu")
		(net "M_F_DQ<47>")
	)
	(segment
		(start 295.450006 -153.04135)
		(end 295.161208 -152.752552)
		(width 0.14224)
		(layer "In11.Cu")
		(net "M_F_DQ<47>")
	)
	(segment
		(start 295.450006 -153.364946)
		(end 295.450006 -153.04135)
		(width 0.14224)
		(layer "In11.Cu")
		(net "M_F_DQ<47>")
	)
	(segment
		(start 295.161208 -151.387048)
		(end 295.443656 -151.1046)
		(width 0.14224)
		(layer "In11.Cu")
		(net "M_F_DQ<47>")
	)
	(segment
		(start 295.272206 -153.542746)
		(end 295.450006 -153.364946)
		(width 0.14224)
		(layer "In11.Cu")
		(net "M_F_DQ<47>")
	)
	(segment
		(start 295.418256 -151.9174)
		(end 295.161208 -151.660352)
		(width 0.14224)
		(layer "In11.Cu")
		(net "M_F_DQ<47>")
	)
	(segment
		(start 295.161208 -152.479248)
		(end 295.418256 -152.2222)
		(width 0.14224)
		(layer "In11.Cu")
		(net "M_F_DQ<47>")
	)
	(segment
		(start 295.850056 -155.4226)
		(end 295.850056 -155.118054)
		(width 0.1651)
		(layer "F.Cu")
		(net "M_F_DQ<46>")
	)
	(segment
		(start 295.850056 -155.9052)
		(end 295.982136 -155.77312)
		(width 0.1651)
		(layer "F.Cu")
		(net "M_F_DQ<46>")
	)
	(segment
		(start 281.495754 -93.547184)
		(end 282.067254 -93.547184)
		(width 0.1651)
		(layer "F.Cu")
		(net "M_F_DQ<46>")
	)
	(segment
		(start 295.85031 -156.87294)
		(end 295.850056 -156.87294)
		(width 0.1651)
		(layer "F.Cu")
		(net "M_F_DQ<46>")
	)
	(segment
		(start 295.850056 -156.87294)
		(end 295.850056 -155.9052)
		(width 0.1651)
		(layer "F.Cu")
		(net "M_F_DQ<46>")
	)
	(segment
		(start 295.982136 -155.55468)
		(end 295.850056 -155.4226)
		(width 0.1651)
		(layer "F.Cu")
		(net "M_F_DQ<46>")
	)
	(segment
		(start 295.982136 -155.77312)
		(end 295.982136 -155.55468)
		(width 0.1651)
		(layer "F.Cu")
		(net "M_F_DQ<46>")
	)
	(segment
		(start 295.850056 -155.118054)
		(end 295.849802 -155.1178)
		(width 0.1651)
		(layer "F.Cu")
		(net "M_F_DQ<46>")
	)
	(via
		(at 295.849802 -155.1178)
		(size 0.508)
		(drill 0.254)
		(layers "F.Cu" "B.Cu")
		(net "M_F_DQ<46>")
	)
	(via
		(at 282.067254 -93.547184)
		(size 0.508)
		(drill 0.254)
		(layers "F.Cu" "B.Cu")
		(net "M_F_DQ<46>")
	)
	(via
		(at 294.999918 -150.814278)
		(size 0.508)
		(drill 0.254)
		(layers "F.Cu" "B.Cu")
		(net "M_F_DQ<46>")
	)
	(segment
		(start 294.999918 -152.078182)
		(end 294.999918 -150.814278)
		(width 0.1651)
		(layer "B.Cu")
		(net "M_F_DQ<46>")
	)
	(segment
		(start 295.000426 -152.078436)
		(end 294.999918 -152.078182)
		(width 0.1651)
		(layer "B.Cu")
		(net "M_F_DQ<46>")
	)
	(segment
		(start 295.516808 -143.751808)
		(end 295.516808 -144.118838)
		(width 0.14224)
		(layer "In4.Cu")
		(net "M_F_DQ<46>")
	)
	(segment
		(start 295.567608 -145.857468)
		(end 295.567608 -148.934678)
		(width 0.14224)
		(layer "In4.Cu")
		(net "M_F_DQ<46>")
	)
	(segment
		(start 295.364408 -140.908278)
		(end 295.516808 -141.060678)
		(width 0.14224)
		(layer "In4.Cu")
		(net "M_F_DQ<46>")
	)
	(segment
		(start 283.744924 -107.024932)
		(end 283.55036 -107.219496)
		(width 0.0889)
		(layer "In4.Cu")
		(net "M_F_DQ<46>")
	)
	(segment
		(start 282.413964 -99.290886)
		(end 282.41879 -99.299522)
		(width 0.0889)
		(layer "In4.Cu")
		(net "M_F_DQ<46>")
	)
	(segment
		(start 295.4274 -128.143)
		(end 295.567608 -128.283208)
		(width 0.14224)
		(layer "In4.Cu")
		(net "M_F_DQ<46>")
	)
	(segment
		(start 295.364408 -139.663678)
		(end 295.364408 -140.908278)
		(width 0.14224)
		(layer "In4.Cu")
		(net "M_F_DQ<46>")
	)
	(segment
		(start 295.42359 -138.93419)
		(end 295.567608 -139.078208)
		(width 0.14224)
		(layer "In4.Cu")
		(net "M_F_DQ<46>")
	)
	(segment
		(start 294.919654 -122.357134)
		(end 294.919654 -123.79833)
		(width 0.14224)
		(layer "In4.Cu")
		(net "M_F_DQ<46>")
	)
	(segment
		(start 295.0464 -125.3998)
		(end 295.4274 -125.7808)
		(width 0.14224)
		(layer "In4.Cu")
		(net "M_F_DQ<46>")
	)
	(segment
		(start 292.34003 -121.353326)
		(end 293.915846 -121.353326)
		(width 0.14224)
		(layer "In4.Cu")
		(net "M_F_DQ<46>")
	)
	(segment
		(start 281.720544 -94.737936)
		(end 281.726894 -94.748604)
		(width 0.0889)
		(layer "In4.Cu")
		(net "M_F_DQ<46>")
	)
	(segment
		(start 295.4274 -141.567408)
		(end 295.4274 -143.6624)
		(width 0.14224)
		(layer "In4.Cu")
		(net "M_F_DQ<46>")
	)
	(segment
		(start 282.405074 -103.238046)
		(end 282.420822 -103.265478)
		(width 0.0889)
		(layer "In4.Cu")
		(net "M_F_DQ<46>")
	)
	(segment
		(start 295.364408 -134.6327)
		(end 295.364408 -136.081008)
		(width 0.14224)
		(layer "In4.Cu")
		(net "M_F_DQ<46>")
	)
	(segment
		(start 283.55036 -112.563656)
		(end 292.34003 -121.353326)
		(width 0.14224)
		(layer "In4.Cu")
		(net "M_F_DQ<46>")
	)
	(segment
		(start 295.567608 -139.460478)
		(end 295.364408 -139.663678)
		(width 0.14224)
		(layer "In4.Cu")
		(net "M_F_DQ<46>")
	)
	(segment
		(start 282.907994 -104.539288)
		(end 282.94076 -104.539288)
		(width 0.0889)
		(layer "In4.Cu")
		(net "M_F_DQ<46>")
	)
	(segment
		(start 295.567608 -128.283208)
		(end 295.567608 -129.859278)
		(width 0.14224)
		(layer "In4.Cu")
		(net "M_F_DQ<46>")
	)
	(segment
		(start 282.41879 -101.662992)
		(end 282.413964 -101.671628)
		(width 0.0889)
		(layer "In4.Cu")
		(net "M_F_DQ<46>")
	)
	(segment
		(start 295.244266 -145.534126)
		(end 295.567608 -145.857468)
		(width 0.14224)
		(layer "In4.Cu")
		(net "M_F_DQ<46>")
	)
	(segment
		(start 295.364408 -136.081008)
		(end 295.567608 -136.284208)
		(width 0.14224)
		(layer "In4.Cu")
		(net "M_F_DQ<46>")
	)
	(segment
		(start 283.272484 -105.139236)
		(end 283.266134 -105.149904)
		(width 0.0889)
		(layer "In4.Cu")
		(net "M_F_DQ<46>")
	)
	(segment
		(start 295.4274 -125.7808)
		(end 295.4274 -128.143)
		(width 0.14224)
		(layer "In4.Cu")
		(net "M_F_DQ<46>")
	)
	(segment
		(start 281.737308 -94.309184)
		(end 281.720544 -94.33814)
		(width 0.0889)
		(layer "In4.Cu")
		(net "M_F_DQ<46>")
	)
	(segment
		(start 295.567608 -148.934678)
		(end 294.999918 -149.502368)
		(width 0.14224)
		(layer "In4.Cu")
		(net "M_F_DQ<46>")
	)
	(segment
		(start 295.466008 -131.408678)
		(end 295.466008 -131.9276)
		(width 0.14224)
		(layer "In4.Cu")
		(net "M_F_DQ<46>")
	)
	(segment
		(start 295.516808 -141.478)
		(end 295.4274 -141.567408)
		(width 0.14224)
		(layer "In4.Cu")
		(net "M_F_DQ<46>")
	)
	(segment
		(start 295.0464 -123.925076)
		(end 295.0464 -125.3998)
		(width 0.14224)
		(layer "In4.Cu")
		(net "M_F_DQ<46>")
	)
	(segment
		(start 283.326078 -106.462068)
		(end 283.744924 -106.880914)
		(width 0.0889)
		(layer "In4.Cu")
		(net "M_F_DQ<46>")
	)
	(segment
		(start 295.244266 -144.39138)
		(end 295.244266 -145.534126)
		(width 0.14224)
		(layer "In4.Cu")
		(net "M_F_DQ<46>")
	)
	(segment
		(start 283.326078 -105.929938)
		(end 283.326078 -106.462068)
		(width 0.0889)
		(layer "In4.Cu")
		(net "M_F_DQ<46>")
	)
	(segment
		(start 295.567608 -139.078208)
		(end 295.567608 -139.460478)
		(width 0.14224)
		(layer "In4.Cu")
		(net "M_F_DQ<46>")
	)
	(segment
		(start 295.567608 -136.525)
		(end 295.42359 -136.669018)
		(width 0.14224)
		(layer "In4.Cu")
		(net "M_F_DQ<46>")
	)
	(segment
		(start 295.466008 -134.099808)
		(end 295.466008 -134.5311)
		(width 0.14224)
		(layer "In4.Cu")
		(net "M_F_DQ<46>")
	)
	(segment
		(start 294.919654 -123.79833)
		(end 295.0464 -123.925076)
		(width 0.14224)
		(layer "In4.Cu")
		(net "M_F_DQ<46>")
	)
	(segment
		(start 295.466008 -131.9276)
		(end 295.4274 -131.966208)
		(width 0.14224)
		(layer "In4.Cu")
		(net "M_F_DQ<46>")
	)
	(segment
		(start 293.915846 -121.353326)
		(end 294.919654 -122.357134)
		(width 0.14224)
		(layer "In4.Cu")
		(net "M_F_DQ<46>")
	)
	(segment
		(start 295.364408 -131.307078)
		(end 295.466008 -131.408678)
		(width 0.14224)
		(layer "In4.Cu")
		(net "M_F_DQ<46>")
	)
	(segment
		(start 282.067254 -93.547184)
		(end 281.737308 -94.309184)
		(width 0.0889)
		(layer "In4.Cu")
		(net "M_F_DQ<46>")
	)
	(segment
		(start 295.42359 -136.669018)
		(end 295.42359 -138.93419)
		(width 0.14224)
		(layer "In4.Cu")
		(net "M_F_DQ<46>")
	)
	(segment
		(start 295.4274 -131.966208)
		(end 295.4274 -134.0612)
		(width 0.14224)
		(layer "In4.Cu")
		(net "M_F_DQ<46>")
	)
	(segment
		(start 282.413964 -102.262432)
		(end 282.41879 -102.271068)
		(width 0.0889)
		(layer "In4.Cu")
		(net "M_F_DQ<46>")
	)
	(segment
		(start 283.55036 -107.219496)
		(end 283.55036 -112.563656)
		(width 0.14224)
		(layer "In4.Cu")
		(net "M_F_DQ<46>")
	)
	(segment
		(start 295.567608 -129.859278)
		(end 295.364408 -130.062478)
		(width 0.14224)
		(layer "In4.Cu")
		(net "M_F_DQ<46>")
	)
	(segment
		(start 282.413964 -100.681028)
		(end 282.407614 -100.691696)
		(width 0.0889)
		(layer "In4.Cu")
		(net "M_F_DQ<46>")
	)
	(segment
		(start 295.4274 -134.0612)
		(end 295.466008 -134.099808)
		(width 0.14224)
		(layer "In4.Cu")
		(net "M_F_DQ<46>")
	)
	(segment
		(start 281.720544 -95.328486)
		(end 281.715718 -95.337122)
		(width 0.0889)
		(layer "In4.Cu")
		(net "M_F_DQ<46>")
	)
	(segment
		(start 283.27731 -105.1306)
		(end 283.272484 -105.139236)
		(width 0.0889)
		(layer "In4.Cu")
		(net "M_F_DQ<46>")
	)
	(segment
		(start 294.999918 -149.502368)
		(end 294.999918 -150.814278)
		(width 0.14224)
		(layer "In4.Cu")
		(net "M_F_DQ<46>")
	)
	(segment
		(start 295.364408 -130.062478)
		(end 295.364408 -131.307078)
		(width 0.14224)
		(layer "In4.Cu")
		(net "M_F_DQ<46>")
	)
	(segment
		(start 283.744924 -106.880914)
		(end 283.744924 -107.024932)
		(width 0.0889)
		(layer "In4.Cu")
		(net "M_F_DQ<46>")
	)
	(segment
		(start 295.466008 -134.5311)
		(end 295.364408 -134.6327)
		(width 0.14224)
		(layer "In4.Cu")
		(net "M_F_DQ<46>")
	)
	(segment
		(start 295.567608 -136.284208)
		(end 295.567608 -136.525)
		(width 0.14224)
		(layer "In4.Cu")
		(net "M_F_DQ<46>")
	)
	(segment
		(start 295.4274 -143.6624)
		(end 295.516808 -143.751808)
		(width 0.14224)
		(layer "In4.Cu")
		(net "M_F_DQ<46>")
	)
	(segment
		(start 295.516808 -141.060678)
		(end 295.516808 -141.478)
		(width 0.14224)
		(layer "In4.Cu")
		(net "M_F_DQ<46>")
	)
	(segment
		(start 295.516808 -144.118838)
		(end 295.244266 -144.39138)
		(width 0.14224)
		(layer "In4.Cu")
		(net "M_F_DQ<46>")
	)
	(arc
		(start 282.407614 -100.691696)
		(mid 282.334816 -100.982459)
		(end 282.413964 -101.271578)
		(width 0.0889)
		(layer "In4.Cu")
		(net "M_F_DQ<46>")
	)
	(arc
		(start 282.413964 -96.71939)
		(mid 282.334833 -97.014792)
		(end 282.413964 -97.310194)
		(width 0.0889)
		(layer "In4.Cu")
		(net "M_F_DQ<46>")
	)
	(arc
		(start 282.413964 -100.281232)
		(mid 282.467463 -100.48113)
		(end 282.413964 -100.681028)
		(width 0.0889)
		(layer "In4.Cu")
		(net "M_F_DQ<46>")
	)
	(arc
		(start 282.385262 -100.225098)
		(mid 282.398911 -100.253524)
		(end 282.413964 -100.281232)
		(width 0.0889)
		(layer "In4.Cu")
		(net "M_F_DQ<46>")
	)
	(arc
		(start 282.413964 -97.70999)
		(mid 282.334833 -98.005392)
		(end 282.413964 -98.300794)
		(width 0.0889)
		(layer "In4.Cu")
		(net "M_F_DQ<46>")
	)
	(arc
		(start 282.413964 -101.271578)
		(mid 282.467434 -101.466641)
		(end 282.41879 -101.662992)
		(width 0.0889)
		(layer "In4.Cu")
		(net "M_F_DQ<46>")
	)
	(arc
		(start 283.272484 -105.729786)
		(mid 283.312471 -105.826332)
		(end 283.326078 -105.929938)
		(width 0.0889)
		(layer "In4.Cu")
		(net "M_F_DQ<46>")
	)
	(arc
		(start 282.413964 -102.662482)
		(mid 282.334775 -102.949097)
		(end 282.405074 -103.238046)
		(width 0.0889)
		(layer "In4.Cu")
		(net "M_F_DQ<46>")
	)
	(arc
		(start 282.413964 -98.300794)
		(mid 282.467463 -98.500692)
		(end 282.413964 -98.70059)
		(width 0.0889)
		(layer "In4.Cu")
		(net "M_F_DQ<46>")
	)
	(arc
		(start 282.420822 -103.265478)
		(mid 282.467498 -103.460179)
		(end 282.413964 -103.653082)
		(width 0.0889)
		(layer "In4.Cu")
		(net "M_F_DQ<46>")
	)
	(arc
		(start 281.819604 -95.89262)
		(mid 281.862399 -95.979586)
		(end 281.933904 -96.04502)
		(width 0.0889)
		(layer "In4.Cu")
		(net "M_F_DQ<46>")
	)
	(arc
		(start 282.413964 -103.653082)
		(mid 282.409636 -104.236258)
		(end 282.907994 -104.539288)
		(width 0.0889)
		(layer "In4.Cu")
		(net "M_F_DQ<46>")
	)
	(arc
		(start 283.266134 -105.149904)
		(mid 283.193336 -105.440667)
		(end 283.272484 -105.729786)
		(width 0.0889)
		(layer "In4.Cu")
		(net "M_F_DQ<46>")
	)
	(arc
		(start 282.353004 -96.23552)
		(mid 282.385677 -96.275967)
		(end 282.413964 -96.319594)
		(width 0.0889)
		(layer "In4.Cu")
		(net "M_F_DQ<46>")
	)
	(arc
		(start 282.413964 -98.70059)
		(mid 282.334959 -98.995738)
		(end 282.413964 -99.290886)
		(width 0.0889)
		(layer "In4.Cu")
		(net "M_F_DQ<46>")
	)
	(arc
		(start 281.933904 -96.04502)
		(mid 281.988823 -96.070755)
		(end 282.048204 -96.08312)
		(width 0.0889)
		(layer "In4.Cu")
		(net "M_F_DQ<46>")
	)
	(arc
		(start 281.720544 -94.33814)
		(mid 281.667045 -94.538038)
		(end 281.720544 -94.737936)
		(width 0.0889)
		(layer "In4.Cu")
		(net "M_F_DQ<46>")
	)
	(arc
		(start 282.41879 -102.271068)
		(mid 282.467545 -102.46742)
		(end 282.413964 -102.662482)
		(width 0.0889)
		(layer "In4.Cu")
		(net "M_F_DQ<46>")
	)
	(arc
		(start 281.726894 -94.748604)
		(mid 281.799692 -95.039367)
		(end 281.720544 -95.328486)
		(width 0.0889)
		(layer "In4.Cu")
		(net "M_F_DQ<46>")
	)
	(arc
		(start 282.41879 -99.299522)
		(mid 282.467545 -99.495874)
		(end 282.413964 -99.690936)
		(width 0.0889)
		(layer "In4.Cu")
		(net "M_F_DQ<46>")
	)
	(arc
		(start 281.715718 -95.337122)
		(mid 281.666963 -95.533474)
		(end 281.720544 -95.728536)
		(width 0.0889)
		(layer "In4.Cu")
		(net "M_F_DQ<46>")
	)
	(arc
		(start 282.413964 -99.690936)
		(mid 282.335686 -99.954587)
		(end 282.385262 -100.225098)
		(width 0.0889)
		(layer "In4.Cu")
		(net "M_F_DQ<46>")
	)
	(arc
		(start 282.413964 -97.310194)
		(mid 282.467463 -97.510092)
		(end 282.413964 -97.70999)
		(width 0.0889)
		(layer "In4.Cu")
		(net "M_F_DQ<46>")
	)
	(arc
		(start 282.413964 -96.319594)
		(mid 282.467497 -96.519492)
		(end 282.413964 -96.71939)
		(width 0.0889)
		(layer "In4.Cu")
		(net "M_F_DQ<46>")
	)
	(arc
		(start 282.94076 -104.539288)
		(mid 283.273678 -104.741279)
		(end 283.27731 -105.1306)
		(width 0.0889)
		(layer "In4.Cu")
		(net "M_F_DQ<46>")
	)
	(arc
		(start 282.048204 -96.08312)
		(mid 282.215063 -96.130384)
		(end 282.353004 -96.23552)
		(width 0.0889)
		(layer "In4.Cu")
		(net "M_F_DQ<46>")
	)
	(arc
		(start 281.720544 -95.728536)
		(mid 281.769246 -95.811078)
		(end 281.819604 -95.89262)
		(width 0.0889)
		(layer "In4.Cu")
		(net "M_F_DQ<46>")
	)
	(arc
		(start 282.413964 -101.671628)
		(mid 282.334833 -101.96703)
		(end 282.413964 -102.262432)
		(width 0.0889)
		(layer "In4.Cu")
		(net "M_F_DQ<46>")
	)
	(segment
		(start 294.566848 -153.834846)
		(end 294.566848 -151.247348)
		(width 0.14224)
		(layer "In11.Cu")
		(net "M_F_DQ<46>")
	)
	(segment
		(start 294.566848 -151.247348)
		(end 294.999918 -150.814278)
		(width 0.14224)
		(layer "In11.Cu")
		(net "M_F_DQ<46>")
	)
	(segment
		(start 295.849802 -155.1178)
		(end 294.566848 -153.834846)
		(width 0.14224)
		(layer "In11.Cu")
		(net "M_F_DQ<46>")
	)
	(segment
		(start 289.050476 -152.273)
		(end 289.049968 -152.278842)
		(width 0.1651)
		(layer "F.Cu")
		(net "M_F_DQ<45>")
	)
	(segment
		(start 289.049968 -152.278842)
		(end 289.049968 -153.542746)
		(width 0.1651)
		(layer "F.Cu")
		(net "M_F_DQ<45>")
	)
	(segment
		(start 278.920194 -95.033084)
		(end 279.491694 -95.033084)
		(width 0.1651)
		(layer "F.Cu")
		(net "M_F_DQ<45>")
	)
	(via
		(at 279.491694 -95.033084)
		(size 0.508)
		(drill 0.254)
		(layers "F.Cu" "B.Cu")
		(net "M_F_DQ<45>")
	)
	(via
		(at 289.823652 -149.533356)
		(size 0.508)
		(drill 0.254)
		(layers "F.Cu" "B.Cu")
		(net "M_F_DQ<45>")
	)
	(via
		(at 289.049968 -153.542746)
		(size 0.508)
		(drill 0.254)
		(layers "F.Cu" "B.Cu")
		(net "M_F_DQ<45>")
	)
	(segment
		(start 289.899852 -149.457156)
		(end 289.823652 -149.533356)
		(width 0.1651)
		(layer "B.Cu")
		(net "M_F_DQ<45>")
	)
	(segment
		(start 289.899852 -147.478496)
		(end 289.899852 -149.457156)
		(width 0.1651)
		(layer "B.Cu")
		(net "M_F_DQ<45>")
	)
	(segment
		(start 289.90036 -147.478496)
		(end 289.899852 -147.478496)
		(width 0.1651)
		(layer "B.Cu")
		(net "M_F_DQ<45>")
	)
	(segment
		(start 290.322 -148.176996)
		(end 290.322 -148.4884)
		(width 0.14224)
		(layer "In4.Cu")
		(net "M_F_DQ<45>")
	)
	(segment
		(start 290.167568 -136.48436)
		(end 290.322 -136.638792)
		(width 0.14224)
		(layer "In4.Cu")
		(net "M_F_DQ<45>")
	)
	(segment
		(start 280.991564 -115.403376)
		(end 280.991564 -115.62207)
		(width 0.14224)
		(layer "In4.Cu")
		(net "M_F_DQ<45>")
	)
	(segment
		(start 282.181554 -116.088922)
		(end 281.929332 -116.341144)
		(width 0.14224)
		(layer "In4.Cu")
		(net "M_F_DQ<45>")
	)
	(segment
		(start 290.233608 -143.776192)
		(end 290.233608 -144.271238)
		(width 0.14224)
		(layer "In4.Cu")
		(net "M_F_DQ<45>")
	)
	(segment
		(start 290.208208 -145.607024)
		(end 290.208208 -146.1516)
		(width 0.14224)
		(layer "In4.Cu")
		(net "M_F_DQ<45>")
	)
	(segment
		(start 279.71496 -114.345466)
		(end 280.303732 -114.934238)
		(width 0.14224)
		(layer "In4.Cu")
		(net "M_F_DQ<45>")
	)
	(segment
		(start 279.140158 -104.14)
		(end 279.144984 -104.148636)
		(width 0.0889)
		(layer "In4.Cu")
		(net "M_F_DQ<45>")
	)
	(segment
		(start 279.491694 -95.033084)
		(end 279.207976 -95.666306)
		(width 0.0889)
		(layer "In4.Cu")
		(net "M_F_DQ<45>")
	)
	(segment
		(start 290.16706 -147.209256)
		(end 289.451288 -147.209256)
		(width 0.14224)
		(layer "In4.Cu")
		(net "M_F_DQ<45>")
	)
	(segment
		(start 280.52268 -114.934238)
		(end 280.774648 -114.68227)
		(width 0.14224)
		(layer "In4.Cu")
		(net "M_F_DQ<45>")
	)
	(segment
		(start 289.166808 -123.431808)
		(end 290.2712 -124.5362)
		(width 0.14224)
		(layer "In4.Cu")
		(net "M_F_DQ<45>")
	)
	(segment
		(start 279.140158 -100.1776)
		(end 279.144984 -100.186236)
		(width 0.0889)
		(layer "In4.Cu")
		(net "M_F_DQ<45>")
	)
	(segment
		(start 290.122356 -138.934444)
		(end 290.122356 -139.42441)
		(width 0.14224)
		(layer "In4.Cu")
		(net "M_F_DQ<45>")
	)
	(segment
		(start 279.144984 -100.186236)
		(end 279.151334 -100.196904)
		(width 0.0889)
		(layer "In4.Cu")
		(net "M_F_DQ<45>")
	)
	(segment
		(start 290.0934 -131.8768)
		(end 290.322 -132.1054)
		(width 0.14224)
		(layer "In4.Cu")
		(net "M_F_DQ<45>")
	)
	(segment
		(start 290.9824 -128.4732)
		(end 290.239196 -129.216404)
		(width 0.14224)
		(layer "In4.Cu")
		(net "M_F_DQ<45>")
	)
	(segment
		(start 290.2712 -124.5362)
		(end 290.2712 -125.603)
		(width 0.14224)
		(layer "In4.Cu")
		(net "M_F_DQ<45>")
	)
	(segment
		(start 279.140158 -101.1682)
		(end 279.144984 -101.176836)
		(width 0.0889)
		(layer "In4.Cu")
		(net "M_F_DQ<45>")
	)
	(segment
		(start 288.801302 -123.431808)
		(end 289.166808 -123.431808)
		(width 0.14224)
		(layer "In4.Cu")
		(net "M_F_DQ<45>")
	)
	(segment
		(start 281.460448 -115.872006)
		(end 281.712416 -115.620038)
		(width 0.14224)
		(layer "In4.Cu")
		(net "M_F_DQ<45>")
	)
	(segment
		(start 290.322 -136.0424)
		(end 290.167568 -136.196832)
		(width 0.14224)
		(layer "In4.Cu")
		(net "M_F_DQ<45>")
	)
	(segment
		(start 290.239196 -129.977896)
		(end 290.3982 -130.1369)
		(width 0.14224)
		(layer "In4.Cu")
		(net "M_F_DQ<45>")
	)
	(segment
		(start 281.2415 -115.872006)
		(end 281.460448 -115.872006)
		(width 0.14224)
		(layer "In4.Cu")
		(net "M_F_DQ<45>")
	)
	(segment
		(start 289.823652 -148.986748)
		(end 289.823652 -149.533356)
		(width 0.14224)
		(layer "In4.Cu")
		(net "M_F_DQ<45>")
	)
	(segment
		(start 281.929332 -116.559838)
		(end 288.801302 -123.431808)
		(width 0.14224)
		(layer "In4.Cu")
		(net "M_F_DQ<45>")
	)
	(segment
		(start 281.243786 -114.932206)
		(end 281.243786 -115.151154)
		(width 0.14224)
		(layer "In4.Cu")
		(net "M_F_DQ<45>")
	)
	(segment
		(start 279.09139 -105.996486)
		(end 279.477724 -106.38282)
		(width 0.0889)
		(layer "In4.Cu")
		(net "M_F_DQ<45>")
	)
	(segment
		(start 290.3982 -130.1369)
		(end 290.3982 -131.089654)
		(width 0.14224)
		(layer "In4.Cu")
		(net "M_F_DQ<45>")
	)
	(segment
		(start 290.1188 -126.752604)
		(end 290.9824 -127.616204)
		(width 0.14224)
		(layer "In4.Cu")
		(net "M_F_DQ<45>")
	)
	(segment
		(start 290.322 -138.7348)
		(end 290.122356 -138.934444)
		(width 0.14224)
		(layer "In4.Cu")
		(net "M_F_DQ<45>")
	)
	(segment
		(start 290.0934 -131.394454)
		(end 290.0934 -131.8768)
		(width 0.14224)
		(layer "In4.Cu")
		(net "M_F_DQ<45>")
	)
	(segment
		(start 290.1442 -134.5438)
		(end 290.322 -134.7216)
		(width 0.14224)
		(layer "In4.Cu")
		(net "M_F_DQ<45>")
	)
	(segment
		(start 279.144984 -105.139236)
		(end 279.151334 -105.149904)
		(width 0.0889)
		(layer "In4.Cu")
		(net "M_F_DQ<45>")
	)
	(segment
		(start 290.1696 -141.099286)
		(end 290.1696 -141.464792)
		(width 0.14224)
		(layer "In4.Cu")
		(net "M_F_DQ<45>")
	)
	(segment
		(start 290.167568 -136.196832)
		(end 290.167568 -136.48436)
		(width 0.14224)
		(layer "In4.Cu")
		(net "M_F_DQ<45>")
	)
	(segment
		(start 279.477724 -106.98226)
		(end 279.71496 -107.219496)
		(width 0.0889)
		(layer "In4.Cu")
		(net "M_F_DQ<45>")
	)
	(segment
		(start 289.451288 -147.209256)
		(end 289.296348 -147.364196)
		(width 0.14224)
		(layer "In4.Cu")
		(net "M_F_DQ<45>")
	)
	(segment
		(start 289.296348 -147.867116)
		(end 289.451288 -148.022056)
		(width 0.14224)
		(layer "In4.Cu")
		(net "M_F_DQ<45>")
	)
	(segment
		(start 279.144984 -103.158036)
		(end 279.151334 -103.168704)
		(width 0.0889)
		(layer "In4.Cu")
		(net "M_F_DQ<45>")
	)
	(segment
		(start 290.322 -132.1054)
		(end 290.322 -134.023608)
		(width 0.14224)
		(layer "In4.Cu")
		(net "M_F_DQ<45>")
	)
	(segment
		(start 279.09139 -105.929684)
		(end 279.09139 -105.996486)
		(width 0.0889)
		(layer "In4.Cu")
		(net "M_F_DQ<45>")
	)
	(segment
		(start 290.322 -146.265392)
		(end 290.322 -147.054316)
		(width 0.14224)
		(layer "In4.Cu")
		(net "M_F_DQ<45>")
	)
	(segment
		(start 290.122356 -139.42441)
		(end 290.4236 -139.725654)
		(width 0.14224)
		(layer "In4.Cu")
		(net "M_F_DQ<45>")
	)
	(segment
		(start 290.208208 -146.1516)
		(end 290.322 -146.265392)
		(width 0.14224)
		(layer "In4.Cu")
		(net "M_F_DQ<45>")
	)
	(segment
		(start 290.322 -141.617192)
		(end 290.322 -143.6878)
		(width 0.14224)
		(layer "In4.Cu")
		(net "M_F_DQ<45>")
	)
	(segment
		(start 279.144984 -102.167436)
		(end 279.151334 -102.178104)
		(width 0.0889)
		(layer "In4.Cu")
		(net "M_F_DQ<45>")
	)
	(segment
		(start 281.712416 -115.620038)
		(end 281.931618 -115.620038)
		(width 0.14224)
		(layer "In4.Cu")
		(net "M_F_DQ<45>")
	)
	(segment
		(start 290.233608 -144.271238)
		(end 290.360608 -144.398238)
		(width 0.14224)
		(layer "In4.Cu")
		(net "M_F_DQ<45>")
	)
	(segment
		(start 280.303732 -114.934238)
		(end 280.52268 -114.934238)
		(width 0.14224)
		(layer "In4.Cu")
		(net "M_F_DQ<45>")
	)
	(segment
		(start 279.71496 -107.219496)
		(end 279.71496 -114.345466)
		(width 0.14224)
		(layer "In4.Cu")
		(net "M_F_DQ<45>")
	)
	(segment
		(start 280.774648 -114.68227)
		(end 280.99385 -114.68227)
		(width 0.14224)
		(layer "In4.Cu")
		(net "M_F_DQ<45>")
	)
	(segment
		(start 290.2712 -125.603)
		(end 290.1188 -125.7554)
		(width 0.14224)
		(layer "In4.Cu")
		(net "M_F_DQ<45>")
	)
	(segment
		(start 289.451288 -148.022056)
		(end 290.16706 -148.022056)
		(width 0.14224)
		(layer "In4.Cu")
		(net "M_F_DQ<45>")
	)
	(segment
		(start 290.1442 -134.201408)
		(end 290.1442 -134.5438)
		(width 0.14224)
		(layer "In4.Cu")
		(net "M_F_DQ<45>")
	)
	(segment
		(start 279.144984 -104.148636)
		(end 279.151334 -104.159304)
		(width 0.0889)
		(layer "In4.Cu")
		(net "M_F_DQ<45>")
	)
	(segment
		(start 290.360608 -144.398238)
		(end 290.360608 -145.454624)
		(width 0.14224)
		(layer "In4.Cu")
		(net "M_F_DQ<45>")
	)
	(segment
		(start 290.322 -148.4884)
		(end 289.823652 -148.986748)
		(width 0.14224)
		(layer "In4.Cu")
		(net "M_F_DQ<45>")
	)
	(segment
		(start 279.140158 -105.1306)
		(end 279.144984 -105.139236)
		(width 0.0889)
		(layer "In4.Cu")
		(net "M_F_DQ<45>")
	)
	(segment
		(start 289.296348 -147.364196)
		(end 289.296348 -147.867116)
		(width 0.14224)
		(layer "In4.Cu")
		(net "M_F_DQ<45>")
	)
	(segment
		(start 290.1188 -125.7554)
		(end 290.1188 -126.752604)
		(width 0.14224)
		(layer "In4.Cu")
		(net "M_F_DQ<45>")
	)
	(segment
		(start 279.140158 -102.1588)
		(end 279.144984 -102.167436)
		(width 0.0889)
		(layer "In4.Cu")
		(net "M_F_DQ<45>")
	)
	(segment
		(start 290.322 -134.7216)
		(end 290.322 -136.0424)
		(width 0.14224)
		(layer "In4.Cu")
		(net "M_F_DQ<45>")
	)
	(segment
		(start 290.3982 -131.089654)
		(end 290.0934 -131.394454)
		(width 0.14224)
		(layer "In4.Cu")
		(net "M_F_DQ<45>")
	)
	(segment
		(start 290.9824 -127.616204)
		(end 290.9824 -128.4732)
		(width 0.14224)
		(layer "In4.Cu")
		(net "M_F_DQ<45>")
	)
	(segment
		(start 290.322 -147.054316)
		(end 290.16706 -147.209256)
		(width 0.14224)
		(layer "In4.Cu")
		(net "M_F_DQ<45>")
	)
	(segment
		(start 279.144984 -101.176836)
		(end 279.151334 -101.187504)
		(width 0.0889)
		(layer "In4.Cu")
		(net "M_F_DQ<45>")
	)
	(segment
		(start 290.322 -134.023608)
		(end 290.1442 -134.201408)
		(width 0.14224)
		(layer "In4.Cu")
		(net "M_F_DQ<45>")
	)
	(segment
		(start 290.4236 -139.725654)
		(end 290.4236 -140.845286)
		(width 0.14224)
		(layer "In4.Cu")
		(net "M_F_DQ<45>")
	)
	(segment
		(start 290.239196 -129.216404)
		(end 290.239196 -129.977896)
		(width 0.14224)
		(layer "In4.Cu")
		(net "M_F_DQ<45>")
	)
	(segment
		(start 290.1696 -141.464792)
		(end 290.322 -141.617192)
		(width 0.14224)
		(layer "In4.Cu")
		(net "M_F_DQ<45>")
	)
	(segment
		(start 279.140158 -103.1494)
		(end 279.144984 -103.158036)
		(width 0.0889)
		(layer "In4.Cu")
		(net "M_F_DQ<45>")
	)
	(segment
		(start 281.931618 -115.620038)
		(end 282.181554 -115.869974)
		(width 0.14224)
		(layer "In4.Cu")
		(net "M_F_DQ<45>")
	)
	(segment
		(start 290.4236 -140.845286)
		(end 290.1696 -141.099286)
		(width 0.14224)
		(layer "In4.Cu")
		(net "M_F_DQ<45>")
	)
	(segment
		(start 279.477724 -106.38282)
		(end 279.477724 -106.98226)
		(width 0.0889)
		(layer "In4.Cu")
		(net "M_F_DQ<45>")
	)
	(segment
		(start 290.16706 -148.022056)
		(end 290.322 -148.176996)
		(width 0.14224)
		(layer "In4.Cu")
		(net "M_F_DQ<45>")
	)
	(segment
		(start 280.991564 -115.62207)
		(end 281.2415 -115.872006)
		(width 0.14224)
		(layer "In4.Cu")
		(net "M_F_DQ<45>")
	)
	(segment
		(start 290.322 -136.638792)
		(end 290.322 -138.7348)
		(width 0.14224)
		(layer "In4.Cu")
		(net "M_F_DQ<45>")
	)
	(segment
		(start 281.929332 -116.341144)
		(end 281.929332 -116.559838)
		(width 0.14224)
		(layer "In4.Cu")
		(net "M_F_DQ<45>")
	)
	(segment
		(start 281.243786 -115.151154)
		(end 280.991564 -115.403376)
		(width 0.14224)
		(layer "In4.Cu")
		(net "M_F_DQ<45>")
	)
	(segment
		(start 290.322 -143.6878)
		(end 290.233608 -143.776192)
		(width 0.14224)
		(layer "In4.Cu")
		(net "M_F_DQ<45>")
	)
	(segment
		(start 290.360608 -145.454624)
		(end 290.208208 -145.607024)
		(width 0.14224)
		(layer "In4.Cu")
		(net "M_F_DQ<45>")
	)
	(segment
		(start 282.181554 -115.869974)
		(end 282.181554 -116.088922)
		(width 0.14224)
		(layer "In4.Cu")
		(net "M_F_DQ<45>")
	)
	(segment
		(start 280.99385 -114.68227)
		(end 281.243786 -114.932206)
		(width 0.14224)
		(layer "In4.Cu")
		(net "M_F_DQ<45>")
	)
	(arc
		(start 279.144984 -96.814894)
		(mid 279.091485 -97.014792)
		(end 279.144984 -97.21469)
		(width 0.0889)
		(layer "In4.Cu")
		(net "M_F_DQ<45>")
	)
	(arc
		(start 279.144984 -97.805494)
		(mid 279.091485 -98.005392)
		(end 279.144984 -98.20529)
		(width 0.0889)
		(layer "In4.Cu")
		(net "M_F_DQ<45>")
	)
	(arc
		(start 279.151334 -104.159304)
		(mid 279.224132 -104.450067)
		(end 279.144984 -104.739186)
		(width 0.0889)
		(layer "In4.Cu")
		(net "M_F_DQ<45>")
	)
	(arc
		(start 279.144984 -96.22409)
		(mid 279.224115 -96.519492)
		(end 279.144984 -96.814894)
		(width 0.0889)
		(layer "In4.Cu")
		(net "M_F_DQ<45>")
	)
	(arc
		(start 279.151334 -105.149904)
		(mid 279.224132 -105.440667)
		(end 279.144984 -105.729786)
		(width 0.0889)
		(layer "In4.Cu")
		(net "M_F_DQ<45>")
	)
	(arc
		(start 279.151334 -101.187504)
		(mid 279.224132 -101.478267)
		(end 279.144984 -101.767386)
		(width 0.0889)
		(layer "In4.Cu")
		(net "M_F_DQ<45>")
	)
	(arc
		(start 279.151334 -99.206304)
		(mid 279.224132 -99.497067)
		(end 279.144984 -99.786186)
		(width 0.0889)
		(layer "In4.Cu")
		(net "M_F_DQ<45>")
	)
	(arc
		(start 279.151334 -102.178104)
		(mid 279.224132 -102.468867)
		(end 279.144984 -102.757986)
		(width 0.0889)
		(layer "In4.Cu")
		(net "M_F_DQ<45>")
	)
	(arc
		(start 279.144984 -97.21469)
		(mid 279.224115 -97.510092)
		(end 279.144984 -97.805494)
		(width 0.0889)
		(layer "In4.Cu")
		(net "M_F_DQ<45>")
	)
	(arc
		(start 279.151334 -100.196904)
		(mid 279.224132 -100.487667)
		(end 279.144984 -100.776786)
		(width 0.0889)
		(layer "In4.Cu")
		(net "M_F_DQ<45>")
	)
	(arc
		(start 279.144984 -98.20529)
		(mid 279.224115 -98.500692)
		(end 279.144984 -98.796094)
		(width 0.0889)
		(layer "In4.Cu")
		(net "M_F_DQ<45>")
	)
	(arc
		(start 279.144984 -98.796094)
		(mid 279.091485 -98.995992)
		(end 279.144984 -99.19589)
		(width 0.0889)
		(layer "In4.Cu")
		(net "M_F_DQ<45>")
	)
	(arc
		(start 279.144984 -100.776786)
		(mid 279.091514 -100.971849)
		(end 279.140158 -101.1682)
		(width 0.0889)
		(layer "In4.Cu")
		(net "M_F_DQ<45>")
	)
	(arc
		(start 279.144984 -102.757986)
		(mid 279.091514 -102.953049)
		(end 279.140158 -103.1494)
		(width 0.0889)
		(layer "In4.Cu")
		(net "M_F_DQ<45>")
	)
	(arc
		(start 279.151334 -103.168704)
		(mid 279.224132 -103.459467)
		(end 279.144984 -103.748586)
		(width 0.0889)
		(layer "In4.Cu")
		(net "M_F_DQ<45>")
	)
	(arc
		(start 279.144984 -99.19589)
		(mid 279.148093 -99.201137)
		(end 279.151334 -99.206304)
		(width 0.0889)
		(layer "In4.Cu")
		(net "M_F_DQ<45>")
	)
	(arc
		(start 279.144984 -95.824294)
		(mid 279.091485 -96.024192)
		(end 279.144984 -96.22409)
		(width 0.0889)
		(layer "In4.Cu")
		(net "M_F_DQ<45>")
	)
	(arc
		(start 279.144984 -104.739186)
		(mid 279.091514 -104.934249)
		(end 279.140158 -105.1306)
		(width 0.0889)
		(layer "In4.Cu")
		(net "M_F_DQ<45>")
	)
	(arc
		(start 279.207976 -95.666306)
		(mid 279.182188 -95.747575)
		(end 279.144984 -95.824294)
		(width 0.0889)
		(layer "In4.Cu")
		(net "M_F_DQ<45>")
	)
	(arc
		(start 279.144984 -101.767386)
		(mid 279.091514 -101.962449)
		(end 279.140158 -102.1588)
		(width 0.0889)
		(layer "In4.Cu")
		(net "M_F_DQ<45>")
	)
	(arc
		(start 279.144984 -99.786186)
		(mid 279.091514 -99.981249)
		(end 279.140158 -100.1776)
		(width 0.0889)
		(layer "In4.Cu")
		(net "M_F_DQ<45>")
	)
	(arc
		(start 279.144984 -103.748586)
		(mid 279.091514 -103.943649)
		(end 279.140158 -104.14)
		(width 0.0889)
		(layer "In4.Cu")
		(net "M_F_DQ<45>")
	)
	(arc
		(start 279.144984 -105.729786)
		(mid 279.10503 -105.82621)
		(end 279.09139 -105.929684)
		(width 0.0889)
		(layer "In4.Cu")
		(net "M_F_DQ<45>")
	)
	(segment
		(start 289.500056 -150.6474)
		(end 289.373056 -150.5204)
		(width 0.14224)
		(layer "In11.Cu")
		(net "M_F_DQ<45>")
	)
	(segment
		(start 289.373056 -149.9616)
		(end 289.8013 -149.533356)
		(width 0.14224)
		(layer "In11.Cu")
		(net "M_F_DQ<45>")
	)
	(segment
		(start 289.211258 -152.898856)
		(end 289.211258 -152.586944)
		(width 0.14224)
		(layer "In11.Cu")
		(net "M_F_DQ<45>")
	)
	(segment
		(start 289.373056 -150.5204)
		(end 289.373056 -149.9616)
		(width 0.14224)
		(layer "In11.Cu")
		(net "M_F_DQ<45>")
	)
	(segment
		(start 289.474656 -153.162254)
		(end 289.211258 -152.898856)
		(width 0.14224)
		(layer "In11.Cu")
		(net "M_F_DQ<45>")
	)
	(segment
		(start 289.049968 -153.542746)
		(end 289.322256 -153.542746)
		(width 0.14224)
		(layer "In11.Cu")
		(net "M_F_DQ<45>")
	)
	(segment
		(start 289.211258 -151.418544)
		(end 289.500056 -151.129746)
		(width 0.14224)
		(layer "In11.Cu")
		(net "M_F_DQ<45>")
	)
	(segment
		(start 289.211258 -151.755856)
		(end 289.211258 -151.418544)
		(width 0.14224)
		(layer "In11.Cu")
		(net "M_F_DQ<45>")
	)
	(segment
		(start 289.449256 -152.348946)
		(end 289.449256 -151.993854)
		(width 0.14224)
		(layer "In11.Cu")
		(net "M_F_DQ<45>")
	)
	(segment
		(start 289.474656 -153.390346)
		(end 289.474656 -153.162254)
		(width 0.14224)
		(layer "In11.Cu")
		(net "M_F_DQ<45>")
	)
	(segment
		(start 289.500056 -151.129746)
		(end 289.500056 -150.6474)
		(width 0.14224)
		(layer "In11.Cu")
		(net "M_F_DQ<45>")
	)
	(segment
		(start 289.322256 -153.542746)
		(end 289.474656 -153.390346)
		(width 0.14224)
		(layer "In11.Cu")
		(net "M_F_DQ<45>")
	)
	(segment
		(start 289.8013 -149.533356)
		(end 289.823652 -149.533356)
		(width 0.14224)
		(layer "In11.Cu")
		(net "M_F_DQ<45>")
	)
	(segment
		(start 289.211258 -152.586944)
		(end 289.449256 -152.348946)
		(width 0.14224)
		(layer "In11.Cu")
		(net "M_F_DQ<45>")
	)
	(segment
		(start 289.449256 -151.993854)
		(end 289.211258 -151.755856)
		(width 0.14224)
		(layer "In11.Cu")
		(net "M_F_DQ<45>")
	)
	(segment
		(start 289.899852 -156.87294)
		(end 289.899852 -155.365196)
		(width 0.1651)
		(layer "F.Cu")
		(net "M_F_DQ<44>")
	)
	(segment
		(start 289.90036 -156.87294)
		(end 289.899852 -156.87294)
		(width 0.1651)
		(layer "F.Cu")
		(net "M_F_DQ<44>")
	)
	(segment
		(start 289.899852 -155.365196)
		(end 289.898328 -155.363672)
		(width 0.1651)
		(layer "F.Cu")
		(net "M_F_DQ<44>")
	)
	(segment
		(start 278.920194 -94.042738)
		(end 279.491694 -94.042738)
		(width 0.1651)
		(layer "F.Cu")
		(net "M_F_DQ<44>")
	)
	(via
		(at 289.049968 -150.814278)
		(size 0.508)
		(drill 0.254)
		(layers "F.Cu" "B.Cu")
		(net "M_F_DQ<44>")
	)
	(via
		(at 289.898328 -155.363672)
		(size 0.508)
		(drill 0.254)
		(layers "F.Cu" "B.Cu")
		(net "M_F_DQ<44>")
	)
	(via
		(at 279.491694 -94.042738)
		(size 0.508)
		(drill 0.254)
		(layers "F.Cu" "B.Cu")
		(net "M_F_DQ<44>")
	)
	(segment
		(start 289.050476 -152.078436)
		(end 289.049968 -152.078182)
		(width 0.1651)
		(layer "B.Cu")
		(net "M_F_DQ<44>")
	)
	(segment
		(start 289.049968 -152.078182)
		(end 289.049968 -150.814278)
		(width 0.1651)
		(layer "B.Cu")
		(net "M_F_DQ<44>")
	)
	(segment
		(start 289.547808 -127)
		(end 289.3314 -127.216408)
		(width 0.14224)
		(layer "In4.Cu")
		(net "M_F_DQ<44>")
	)
	(segment
		(start 289.9156 -128.421892)
		(end 289.7124 -128.625092)
		(width 0.14224)
		(layer "In4.Cu")
		(net "M_F_DQ<44>")
	)
	(segment
		(start 289.319208 -139.587478)
		(end 289.319208 -140.781278)
		(width 0.14224)
		(layer "In4.Cu")
		(net "M_F_DQ<44>")
	)
	(segment
		(start 279.491694 -94.042738)
		(end 279.092152 -94.597982)
		(width 0.0889)
		(layer "In4.Cu")
		(net "M_F_DQ<44>")
	)
	(segment
		(start 289.9156 -128.015492)
		(end 289.9156 -128.421892)
		(width 0.14224)
		(layer "In4.Cu")
		(net "M_F_DQ<44>")
	)
	(segment
		(start 289.319208 -135.951468)
		(end 289.573208 -136.205468)
		(width 0.14224)
		(layer "In4.Cu")
		(net "M_F_DQ<44>")
	)
	(segment
		(start 289.547808 -129.400808)
		(end 289.547808 -129.767838)
		(width 0.14224)
		(layer "In4.Cu")
		(net "M_F_DQ<44>")
	)
	(segment
		(start 278.979884 -103.253286)
		(end 278.98471 -103.261922)
		(width 0.0889)
		(layer "In4.Cu")
		(net "M_F_DQ<44>")
	)
	(segment
		(start 288.501582 -147.210526)
		(end 288.501582 -149.079966)
		(width 0.14224)
		(layer "In4.Cu")
		(net "M_F_DQ<44>")
	)
	(segment
		(start 289.547808 -134.125208)
		(end 289.547808 -134.479792)
		(width 0.14224)
		(layer "In4.Cu")
		(net "M_F_DQ<44>")
	)
	(segment
		(start 289.350196 -124.371608)
		(end 289.350196 -125.647196)
		(width 0.14224)
		(layer "In4.Cu")
		(net "M_F_DQ<44>")
	)
	(segment
		(start 289.3314 -128.828292)
		(end 289.3314 -129.1844)
		(width 0.14224)
		(layer "In4.Cu")
		(net "M_F_DQ<44>")
	)
	(segment
		(start 278.973534 -100.270818)
		(end 278.979884 -100.281486)
		(width 0.0889)
		(layer "In4.Cu")
		(net "M_F_DQ<44>")
	)
	(segment
		(start 279.287224 -106.461814)
		(end 279.287224 -107.012232)
		(width 0.0889)
		(layer "In4.Cu")
		(net "M_F_DQ<44>")
	)
	(segment
		(start 289.6362 -131.470654)
		(end 289.6362 -131.940808)
		(width 0.14224)
		(layer "In4.Cu")
		(net "M_F_DQ<44>")
	)
	(segment
		(start 289.4838 -136.665208)
		(end 289.4838 -138.9126)
		(width 0.14224)
		(layer "In4.Cu")
		(net "M_F_DQ<44>")
	)
	(segment
		(start 278.973534 -101.261418)
		(end 278.979884 -101.272086)
		(width 0.0889)
		(layer "In4.Cu")
		(net "M_F_DQ<44>")
	)
	(segment
		(start 278.979884 -104.243886)
		(end 278.98471 -104.252522)
		(width 0.0889)
		(layer "In4.Cu")
		(net "M_F_DQ<44>")
	)
	(segment
		(start 289.547808 -143.751808)
		(end 289.547808 -144.081246)
		(width 0.14224)
		(layer "In4.Cu")
		(net "M_F_DQ<44>")
	)
	(segment
		(start 278.979884 -105.234486)
		(end 278.98471 -105.243122)
		(width 0.0889)
		(layer "In4.Cu")
		(net "M_F_DQ<44>")
	)
	(segment
		(start 289.319208 -140.781278)
		(end 289.6362 -141.09827)
		(width 0.14224)
		(layer "In4.Cu")
		(net "M_F_DQ<44>")
	)
	(segment
		(start 289.573208 -136.5758)
		(end 289.4838 -136.665208)
		(width 0.14224)
		(layer "In4.Cu")
		(net "M_F_DQ<44>")
	)
	(segment
		(start 289.3314 -127.216408)
		(end 289.3314 -127.609092)
		(width 0.14224)
		(layer "In4.Cu")
		(net "M_F_DQ<44>")
	)
	(segment
		(start 289.547808 -129.767838)
		(end 289.319208 -129.996438)
		(width 0.14224)
		(layer "In4.Cu")
		(net "M_F_DQ<44>")
	)
	(segment
		(start 289.547808 -144.081246)
		(end 289.1282 -144.500854)
		(width 0.14224)
		(layer "In4.Cu")
		(net "M_F_DQ<44>")
	)
	(segment
		(start 289.045396 -124.066808)
		(end 289.350196 -124.371608)
		(width 0.14224)
		(layer "In4.Cu")
		(net "M_F_DQ<44>")
	)
	(segment
		(start 289.58921 -146.122898)
		(end 288.501582 -147.210526)
		(width 0.14224)
		(layer "In4.Cu")
		(net "M_F_DQ<44>")
	)
	(segment
		(start 279.07996 -107.219496)
		(end 279.07996 -114.460274)
		(width 0.14224)
		(layer "In4.Cu")
		(net "M_F_DQ<44>")
	)
	(segment
		(start 289.573208 -136.205468)
		(end 289.573208 -136.5758)
		(width 0.14224)
		(layer "In4.Cu")
		(net "M_F_DQ<44>")
	)
	(segment
		(start 289.4838 -143.6878)
		(end 289.547808 -143.751808)
		(width 0.14224)
		(layer "In4.Cu")
		(net "M_F_DQ<44>")
	)
	(segment
		(start 278.973534 -104.233218)
		(end 278.979884 -104.243886)
		(width 0.0889)
		(layer "In4.Cu")
		(net "M_F_DQ<44>")
	)
	(segment
		(start 289.573208 -139.002008)
		(end 289.573208 -139.333478)
		(width 0.14224)
		(layer "In4.Cu")
		(net "M_F_DQ<44>")
	)
	(segment
		(start 289.547808 -125.844808)
		(end 289.547808 -127)
		(width 0.14224)
		(layer "In4.Cu")
		(net "M_F_DQ<44>")
	)
	(segment
		(start 289.350196 -125.647196)
		(end 289.547808 -125.844808)
		(width 0.14224)
		(layer "In4.Cu")
		(net "M_F_DQ<44>")
	)
	(segment
		(start 289.319208 -131.153662)
		(end 289.6362 -131.470654)
		(width 0.14224)
		(layer "In4.Cu")
		(net "M_F_DQ<44>")
	)
	(segment
		(start 289.7124 -128.625092)
		(end 289.5346 -128.625092)
		(width 0.14224)
		(layer "In4.Cu")
		(net "M_F_DQ<44>")
	)
	(segment
		(start 279.07996 -114.460274)
		(end 288.686494 -124.066808)
		(width 0.14224)
		(layer "In4.Cu")
		(net "M_F_DQ<44>")
	)
	(segment
		(start 289.58921 -145.83537)
		(end 289.58921 -146.122898)
		(width 0.14224)
		(layer "In4.Cu")
		(net "M_F_DQ<44>")
	)
	(segment
		(start 278.973534 -102.252018)
		(end 278.979884 -102.262686)
		(width 0.0889)
		(layer "In4.Cu")
		(net "M_F_DQ<44>")
	)
	(segment
		(start 289.7124 -127.812292)
		(end 289.9156 -128.015492)
		(width 0.14224)
		(layer "In4.Cu")
		(net "M_F_DQ<44>")
	)
	(segment
		(start 278.90089 -105.929938)
		(end 278.90089 -106.07548)
		(width 0.0889)
		(layer "In4.Cu")
		(net "M_F_DQ<44>")
	)
	(segment
		(start 289.4838 -141.6812)
		(end 289.4838 -143.6878)
		(width 0.14224)
		(layer "In4.Cu")
		(net "M_F_DQ<44>")
	)
	(segment
		(start 289.547808 -134.479792)
		(end 289.319208 -134.708392)
		(width 0.14224)
		(layer "In4.Cu")
		(net "M_F_DQ<44>")
	)
	(segment
		(start 278.979884 -100.281486)
		(end 278.98471 -100.290122)
		(width 0.0889)
		(layer "In4.Cu")
		(net "M_F_DQ<44>")
	)
	(segment
		(start 289.5346 -127.812292)
		(end 289.7124 -127.812292)
		(width 0.14224)
		(layer "In4.Cu")
		(net "M_F_DQ<44>")
	)
	(segment
		(start 278.979884 -102.262686)
		(end 278.98471 -102.271322)
		(width 0.0889)
		(layer "In4.Cu")
		(net "M_F_DQ<44>")
	)
	(segment
		(start 279.287224 -107.012232)
		(end 279.07996 -107.219496)
		(width 0.0889)
		(layer "In4.Cu")
		(net "M_F_DQ<44>")
	)
	(segment
		(start 278.979884 -99.291394)
		(end 278.98471 -99.299522)
		(width 0.0889)
		(layer "In4.Cu")
		(net "M_F_DQ<44>")
	)
	(segment
		(start 289.049968 -149.628352)
		(end 289.049968 -150.814278)
		(width 0.14224)
		(layer "In4.Cu")
		(net "M_F_DQ<44>")
	)
	(segment
		(start 289.6362 -131.940808)
		(end 289.4838 -132.093208)
		(width 0.14224)
		(layer "In4.Cu")
		(net "M_F_DQ<44>")
	)
	(segment
		(start 289.3314 -127.609092)
		(end 289.5346 -127.812292)
		(width 0.14224)
		(layer "In4.Cu")
		(net "M_F_DQ<44>")
	)
	(segment
		(start 278.973534 -103.242618)
		(end 278.979884 -103.253286)
		(width 0.0889)
		(layer "In4.Cu")
		(net "M_F_DQ<44>")
	)
	(segment
		(start 289.4838 -132.093208)
		(end 289.4838 -134.0612)
		(width 0.14224)
		(layer "In4.Cu")
		(net "M_F_DQ<44>")
	)
	(segment
		(start 288.501582 -149.079966)
		(end 289.049968 -149.628352)
		(width 0.14224)
		(layer "In4.Cu")
		(net "M_F_DQ<44>")
	)
	(segment
		(start 288.686494 -124.066808)
		(end 289.045396 -124.066808)
		(width 0.14224)
		(layer "In4.Cu")
		(net "M_F_DQ<44>")
	)
	(segment
		(start 289.4838 -134.0612)
		(end 289.547808 -134.125208)
		(width 0.14224)
		(layer "In4.Cu")
		(net "M_F_DQ<44>")
	)
	(segment
		(start 289.5346 -128.625092)
		(end 289.3314 -128.828292)
		(width 0.14224)
		(layer "In4.Cu")
		(net "M_F_DQ<44>")
	)
	(segment
		(start 289.3314 -129.1844)
		(end 289.547808 -129.400808)
		(width 0.14224)
		(layer "In4.Cu")
		(net "M_F_DQ<44>")
	)
	(segment
		(start 278.90089 -106.07548)
		(end 279.287224 -106.461814)
		(width 0.0889)
		(layer "In4.Cu")
		(net "M_F_DQ<44>")
	)
	(segment
		(start 289.4838 -138.9126)
		(end 289.573208 -139.002008)
		(width 0.14224)
		(layer "In4.Cu")
		(net "M_F_DQ<44>")
	)
	(segment
		(start 278.979884 -101.272086)
		(end 278.98471 -101.280722)
		(width 0.0889)
		(layer "In4.Cu")
		(net "M_F_DQ<44>")
	)
	(segment
		(start 289.1282 -144.500854)
		(end 289.1282 -145.37436)
		(width 0.14224)
		(layer "In4.Cu")
		(net "M_F_DQ<44>")
	)
	(segment
		(start 278.973534 -105.223818)
		(end 278.979884 -105.234486)
		(width 0.0889)
		(layer "In4.Cu")
		(net "M_F_DQ<44>")
	)
	(segment
		(start 289.573208 -139.333478)
		(end 289.319208 -139.587478)
		(width 0.14224)
		(layer "In4.Cu")
		(net "M_F_DQ<44>")
	)
	(segment
		(start 289.6362 -141.5288)
		(end 289.4838 -141.6812)
		(width 0.14224)
		(layer "In4.Cu")
		(net "M_F_DQ<44>")
	)
	(segment
		(start 289.319208 -129.996438)
		(end 289.319208 -131.153662)
		(width 0.14224)
		(layer "In4.Cu")
		(net "M_F_DQ<44>")
	)
	(segment
		(start 289.1282 -145.37436)
		(end 289.58921 -145.83537)
		(width 0.14224)
		(layer "In4.Cu")
		(net "M_F_DQ<44>")
	)
	(segment
		(start 289.319208 -134.708392)
		(end 289.319208 -135.951468)
		(width 0.14224)
		(layer "In4.Cu")
		(net "M_F_DQ<44>")
	)
	(segment
		(start 289.6362 -141.09827)
		(end 289.6362 -141.5288)
		(width 0.14224)
		(layer "In4.Cu")
		(net "M_F_DQ<44>")
	)
	(arc
		(start 278.98471 -102.271322)
		(mid 279.033465 -102.467674)
		(end 278.979884 -102.662736)
		(width 0.0889)
		(layer "In4.Cu")
		(net "M_F_DQ<44>")
	)
	(arc
		(start 278.979884 -105.634536)
		(mid 278.920939 -105.777037)
		(end 278.90089 -105.929938)
		(width 0.0889)
		(layer "In4.Cu")
		(net "M_F_DQ<44>")
	)
	(arc
		(start 278.979884 -95.328994)
		(mid 279.033383 -95.528892)
		(end 278.979884 -95.72879)
		(width 0.0889)
		(layer "In4.Cu")
		(net "M_F_DQ<44>")
	)
	(arc
		(start 278.979884 -96.319594)
		(mid 279.033383 -96.519492)
		(end 278.979884 -96.71939)
		(width 0.0889)
		(layer "In4.Cu")
		(net "M_F_DQ<44>")
	)
	(arc
		(start 278.979884 -96.71939)
		(mid 278.900753 -97.014792)
		(end 278.979884 -97.310194)
		(width 0.0889)
		(layer "In4.Cu")
		(net "M_F_DQ<44>")
	)
	(arc
		(start 278.98471 -100.290122)
		(mid 279.033465 -100.486474)
		(end 278.979884 -100.681536)
		(width 0.0889)
		(layer "In4.Cu")
		(net "M_F_DQ<44>")
	)
	(arc
		(start 278.979884 -98.70059)
		(mid 278.900753 -98.995992)
		(end 278.979884 -99.291394)
		(width 0.0889)
		(layer "In4.Cu")
		(net "M_F_DQ<44>")
	)
	(arc
		(start 278.979884 -103.653336)
		(mid 278.900662 -103.942454)
		(end 278.973534 -104.233218)
		(width 0.0889)
		(layer "In4.Cu")
		(net "M_F_DQ<44>")
	)
	(arc
		(start 278.98471 -99.299522)
		(mid 279.033465 -99.495874)
		(end 278.979884 -99.690936)
		(width 0.0889)
		(layer "In4.Cu")
		(net "M_F_DQ<44>")
	)
	(arc
		(start 278.98471 -101.280722)
		(mid 279.033465 -101.477074)
		(end 278.979884 -101.672136)
		(width 0.0889)
		(layer "In4.Cu")
		(net "M_F_DQ<44>")
	)
	(arc
		(start 278.98471 -103.261922)
		(mid 279.033465 -103.458274)
		(end 278.979884 -103.653336)
		(width 0.0889)
		(layer "In4.Cu")
		(net "M_F_DQ<44>")
	)
	(arc
		(start 278.979884 -97.70999)
		(mid 278.900753 -98.005392)
		(end 278.979884 -98.300794)
		(width 0.0889)
		(layer "In4.Cu")
		(net "M_F_DQ<44>")
	)
	(arc
		(start 278.98471 -105.243122)
		(mid 279.033465 -105.439474)
		(end 278.979884 -105.634536)
		(width 0.0889)
		(layer "In4.Cu")
		(net "M_F_DQ<44>")
	)
	(arc
		(start 279.092152 -94.597982)
		(mid 278.907466 -94.943772)
		(end 278.979884 -95.328994)
		(width 0.0889)
		(layer "In4.Cu")
		(net "M_F_DQ<44>")
	)
	(arc
		(start 278.979884 -99.690936)
		(mid 278.900662 -99.980054)
		(end 278.973534 -100.270818)
		(width 0.0889)
		(layer "In4.Cu")
		(net "M_F_DQ<44>")
	)
	(arc
		(start 278.979884 -100.681536)
		(mid 278.900662 -100.970654)
		(end 278.973534 -101.261418)
		(width 0.0889)
		(layer "In4.Cu")
		(net "M_F_DQ<44>")
	)
	(arc
		(start 278.979884 -98.300794)
		(mid 279.033383 -98.500692)
		(end 278.979884 -98.70059)
		(width 0.0889)
		(layer "In4.Cu")
		(net "M_F_DQ<44>")
	)
	(arc
		(start 278.979884 -101.672136)
		(mid 278.900662 -101.961254)
		(end 278.973534 -102.252018)
		(width 0.0889)
		(layer "In4.Cu")
		(net "M_F_DQ<44>")
	)
	(arc
		(start 278.979884 -104.643936)
		(mid 278.900662 -104.933054)
		(end 278.973534 -105.223818)
		(width 0.0889)
		(layer "In4.Cu")
		(net "M_F_DQ<44>")
	)
	(arc
		(start 278.98471 -104.252522)
		(mid 279.033465 -104.448874)
		(end 278.979884 -104.643936)
		(width 0.0889)
		(layer "In4.Cu")
		(net "M_F_DQ<44>")
	)
	(arc
		(start 278.979884 -95.72879)
		(mid 278.900753 -96.024192)
		(end 278.979884 -96.319594)
		(width 0.0889)
		(layer "In4.Cu")
		(net "M_F_DQ<44>")
	)
	(arc
		(start 278.979884 -102.662736)
		(mid 278.900662 -102.951854)
		(end 278.973534 -103.242618)
		(width 0.0889)
		(layer "In4.Cu")
		(net "M_F_DQ<44>")
	)
	(arc
		(start 278.979884 -97.310194)
		(mid 279.033383 -97.510092)
		(end 278.979884 -97.70999)
		(width 0.0889)
		(layer "In4.Cu")
		(net "M_F_DQ<44>")
	)
	(segment
		(start 289.898328 -155.363672)
		(end 288.774886 -154.24023)
		(width 0.14224)
		(layer "In11.Cu")
		(net "M_F_DQ<44>")
	)
	(segment
		(start 288.616898 -151.247348)
		(end 289.049968 -150.814278)
		(width 0.14224)
		(layer "In11.Cu")
		(net "M_F_DQ<44>")
	)
	(segment
		(start 288.774886 -153.938478)
		(end 288.616898 -153.78049)
		(width 0.14224)
		(layer "In11.Cu")
		(net "M_F_DQ<44>")
	)
	(segment
		(start 288.616898 -153.78049)
		(end 288.616898 -151.247348)
		(width 0.14224)
		(layer "In11.Cu")
		(net "M_F_DQ<44>")
	)
	(segment
		(start 288.774886 -154.24023)
		(end 288.774886 -153.938478)
		(width 0.14224)
		(layer "In11.Cu")
		(net "M_F_DQ<44>")
	)
	(segment
		(start 282.354274 -95.033084)
		(end 282.925774 -95.033084)
		(width 0.1651)
		(layer "F.Cu")
		(net "M_F_DQ<43>")
	)
	(segment
		(start 296.69994 -152.278842)
		(end 296.69994 -153.542746)
		(width 0.1651)
		(layer "F.Cu")
		(net "M_F_DQ<43>")
	)
	(segment
		(start 296.700448 -152.273)
		(end 296.69994 -152.278842)
		(width 0.1651)
		(layer "F.Cu")
		(net "M_F_DQ<43>")
	)
	(via
		(at 297.549824 -149.533356)
		(size 0.508)
		(drill 0.254)
		(layers "F.Cu" "B.Cu")
		(net "M_F_DQ<43>")
	)
	(via
		(at 296.69994 -153.542746)
		(size 0.508)
		(drill 0.254)
		(layers "F.Cu" "B.Cu")
		(net "M_F_DQ<43>")
	)
	(via
		(at 282.925774 -95.033084)
		(size 0.508)
		(drill 0.254)
		(layers "F.Cu" "B.Cu")
		(net "M_F_DQ<43>")
	)
	(segment
		(start 297.549824 -147.478496)
		(end 297.549824 -149.533356)
		(width 0.1651)
		(layer "B.Cu")
		(net "M_F_DQ<43>")
	)
	(segment
		(start 297.550332 -147.478496)
		(end 297.549824 -147.478496)
		(width 0.1651)
		(layer "B.Cu")
		(net "M_F_DQ<43>")
	)
	(segment
		(start 284.296104 -104.148636)
		(end 284.302454 -104.159304)
		(width 0.0889)
		(layer "In4.Cu")
		(net "M_F_DQ<43>")
	)
	(segment
		(start 297.7896 -124.9934)
		(end 297.7896 -127.723392)
		(width 0.14224)
		(layer "In4.Cu")
		(net "M_F_DQ<43>")
	)
	(segment
		(start 297.7896 -141.137386)
		(end 297.7896 -144.05483)
		(width 0.14224)
		(layer "In4.Cu")
		(net "M_F_DQ<43>")
	)
	(segment
		(start 298.0182 -140.908786)
		(end 297.7896 -141.137386)
		(width 0.1016)
		(layer "In4.Cu")
		(net "M_F_DQ<43>")
	)
	(segment
		(start 298.133008 -145.604992)
		(end 297.879008 -145.858992)
		(width 0.14224)
		(layer "In4.Cu")
		(net "M_F_DQ<43>")
	)
	(segment
		(start 297.9674 -134.0612)
		(end 297.917108 -134.111492)
		(width 0.14224)
		(layer "In4.Cu")
		(net "M_F_DQ<43>")
	)
	(segment
		(start 296.4053 -121.02846)
		(end 296.25925 -121.17451)
		(width 0.14224)
		(layer "In4.Cu")
		(net "M_F_DQ<43>")
	)
	(segment
		(start 295.936416 -120.559576)
		(end 296.116248 -120.559576)
		(width 0.14224)
		(layer "In4.Cu")
		(net "M_F_DQ<43>")
	)
	(segment
		(start 297.39717 -122.83821)
		(end 297.633136 -122.83821)
		(width 0.14224)
		(layer "In4.Cu")
		(net "M_F_DQ<43>")
	)
	(segment
		(start 296.723816 -122.753628)
		(end 297.012868 -123.04268)
		(width 0.14224)
		(layer "In4.Cu")
		(net "M_F_DQ<43>")
	)
	(segment
		(start 297.943524 -123.148598)
		(end 297.943524 -124.839476)
		(width 0.14224)
		(layer "In4.Cu")
		(net "M_F_DQ<43>")
	)
	(segment
		(start 284.291278 -106.1212)
		(end 284.296104 -106.129836)
		(width 0.0889)
		(layer "In4.Cu")
		(net "M_F_DQ<43>")
	)
	(segment
		(start 285.4706 -112.193832)
		(end 290.878006 -117.601238)
		(width 0.14224)
		(layer "In4.Cu")
		(net "M_F_DQ<43>")
	)
	(segment
		(start 297.879008 -145.858992)
		(end 297.879008 -149.21738)
		(width 0.14224)
		(layer "In4.Cu")
		(net "M_F_DQ<43>")
	)
	(segment
		(start 297.904408 -129.960878)
		(end 298.056808 -130.113278)
		(width 0.14224)
		(layer "In4.Cu")
		(net "M_F_DQ<43>")
	)
	(segment
		(start 283.443934 -103.242618)
		(end 283.437584 -103.253286)
		(width 0.0889)
		(layer "In4.Cu")
		(net "M_F_DQ<43>")
	)
	(segment
		(start 284.296104 -105.139236)
		(end 284.302454 -105.149904)
		(width 0.0889)
		(layer "In4.Cu")
		(net "M_F_DQ<43>")
	)
	(segment
		(start 285.233364 -106.76128)
		(end 285.233364 -106.9975)
		(width 0.0889)
		(layer "In4.Cu")
		(net "M_F_DQ<43>")
	)
	(segment
		(start 298.133008 -144.398238)
		(end 298.133008 -145.604992)
		(width 0.14224)
		(layer "In4.Cu")
		(net "M_F_DQ<43>")
	)
	(segment
		(start 296.4053 -120.848628)
		(end 296.4053 -121.02846)
		(width 0.14224)
		(layer "In4.Cu")
		(net "M_F_DQ<43>")
	)
	(segment
		(start 297.917108 -134.111492)
		(end 297.917108 -134.520432)
		(width 0.14224)
		(layer "In4.Cu")
		(net "M_F_DQ<43>")
	)
	(segment
		(start 283.437584 -101.671882)
		(end 283.443934 -101.68255)
		(width 0.0889)
		(layer "In4.Cu")
		(net "M_F_DQ<43>")
	)
	(segment
		(start 297.879008 -149.21738)
		(end 297.549824 -149.546564)
		(width 0.14224)
		(layer "In4.Cu")
		(net "M_F_DQ<43>")
	)
	(segment
		(start 296.25925 -121.393458)
		(end 296.972228 -122.106436)
		(width 0.14224)
		(layer "In4.Cu")
		(net "M_F_DQ<43>")
	)
	(segment
		(start 297.904408 -136.525)
		(end 297.9674 -136.587992)
		(width 0.14224)
		(layer "In4.Cu")
		(net "M_F_DQ<43>")
	)
	(segment
		(start 292.46703 -117.601238)
		(end 295.571418 -120.705626)
		(width 0.14224)
		(layer "In4.Cu")
		(net "M_F_DQ<43>")
	)
	(segment
		(start 290.878006 -117.601238)
		(end 292.46703 -117.601238)
		(width 0.14224)
		(layer "In4.Cu")
		(net "M_F_DQ<43>")
	)
	(segment
		(start 298.0182 -139.67587)
		(end 298.0182 -140.908786)
		(width 0.1016)
		(layer "In4.Cu")
		(net "M_F_DQ<43>")
	)
	(segment
		(start 283.432758 -101.663246)
		(end 283.437584 -101.671882)
		(width 0.0889)
		(layer "In4.Cu")
		(net "M_F_DQ<43>")
	)
	(segment
		(start 297.904408 -138.924792)
		(end 297.904408 -139.562078)
		(width 0.14224)
		(layer "In4.Cu")
		(net "M_F_DQ<43>")
	)
	(segment
		(start 297.012868 -123.04268)
		(end 297.1927 -123.04268)
		(width 0.14224)
		(layer "In4.Cu")
		(net "M_F_DQ<43>")
	)
	(segment
		(start 285.4706 -107.234736)
		(end 285.4706 -112.193832)
		(width 0.14224)
		(layer "In4.Cu")
		(net "M_F_DQ<43>")
	)
	(segment
		(start 297.917108 -134.520432)
		(end 298.082208 -134.685532)
		(width 0.14224)
		(layer "In4.Cu")
		(net "M_F_DQ<43>")
	)
	(segment
		(start 296.723816 -122.573796)
		(end 296.723816 -122.753628)
		(width 0.14224)
		(layer "In4.Cu")
		(net "M_F_DQ<43>")
	)
	(segment
		(start 298.082208 -136.003792)
		(end 297.904408 -136.181592)
		(width 0.14224)
		(layer "In4.Cu")
		(net "M_F_DQ<43>")
	)
	(segment
		(start 295.571418 -120.705626)
		(end 295.790366 -120.705626)
		(width 0.14224)
		(layer "In4.Cu")
		(net "M_F_DQ<43>")
	)
	(segment
		(start 285.154624 -106.625136)
		(end 285.233364 -106.76128)
		(width 0.0889)
		(layer "In4.Cu")
		(net "M_F_DQ<43>")
	)
	(segment
		(start 283.430726 -100.668836)
		(end 283.446474 -100.696268)
		(width 0.0889)
		(layer "In4.Cu")
		(net "M_F_DQ<43>")
	)
	(segment
		(start 297.1927 -123.04268)
		(end 297.39717 -122.83821)
		(width 0.14224)
		(layer "In4.Cu")
		(net "M_F_DQ<43>")
	)
	(segment
		(start 285.45536 -107.219496)
		(end 285.4706 -107.234736)
		(width 0.14224)
		(layer "In4.Cu")
		(net "M_F_DQ<43>")
	)
	(segment
		(start 296.116248 -120.559576)
		(end 296.4053 -120.848628)
		(width 0.14224)
		(layer "In4.Cu")
		(net "M_F_DQ<43>")
	)
	(segment
		(start 297.9674 -138.8618)
		(end 297.904408 -138.924792)
		(width 0.14224)
		(layer "In4.Cu")
		(net "M_F_DQ<43>")
	)
	(segment
		(start 298.056808 -131.268978)
		(end 297.917108 -131.408678)
		(width 0.14224)
		(layer "In4.Cu")
		(net "M_F_DQ<43>")
	)
	(segment
		(start 297.904408 -139.562078)
		(end 298.0182 -139.67587)
		(width 0.1016)
		(layer "In4.Cu")
		(net "M_F_DQ<43>")
	)
	(segment
		(start 297.9674 -136.587992)
		(end 297.9674 -138.8618)
		(width 0.14224)
		(layer "In4.Cu")
		(net "M_F_DQ<43>")
	)
	(segment
		(start 283.437584 -103.253286)
		(end 283.432758 -103.261922)
		(width 0.0889)
		(layer "In4.Cu")
		(net "M_F_DQ<43>")
	)
	(segment
		(start 297.904408 -127.8382)
		(end 297.904408 -129.960878)
		(width 0.14224)
		(layer "In4.Cu")
		(net "M_F_DQ<43>")
	)
	(segment
		(start 297.904408 -136.181592)
		(end 297.904408 -136.525)
		(width 0.14224)
		(layer "In4.Cu")
		(net "M_F_DQ<43>")
	)
	(segment
		(start 297.943524 -124.839476)
		(end 297.7896 -124.9934)
		(width 0.14224)
		(layer "In4.Cu")
		(net "M_F_DQ<43>")
	)
	(segment
		(start 283.769308 -103.853234)
		(end 283.802074 -103.853234)
		(width 0.0889)
		(layer "In4.Cu")
		(net "M_F_DQ<43>")
	)
	(segment
		(start 296.972228 -122.106436)
		(end 296.972228 -122.325384)
		(width 0.14224)
		(layer "In4.Cu")
		(net "M_F_DQ<43>")
	)
	(segment
		(start 296.25925 -121.17451)
		(end 296.25925 -121.393458)
		(width 0.14224)
		(layer "In4.Cu")
		(net "M_F_DQ<43>")
	)
	(segment
		(start 284.291278 -105.1306)
		(end 284.296104 -105.139236)
		(width 0.0889)
		(layer "In4.Cu")
		(net "M_F_DQ<43>")
	)
	(segment
		(start 296.972228 -122.325384)
		(end 296.723816 -122.573796)
		(width 0.14224)
		(layer "In4.Cu")
		(net "M_F_DQ<43>")
	)
	(segment
		(start 297.7896 -144.05483)
		(end 298.133008 -144.398238)
		(width 0.14224)
		(layer "In4.Cu")
		(net "M_F_DQ<43>")
	)
	(segment
		(start 298.082208 -134.685532)
		(end 298.082208 -136.003792)
		(width 0.14224)
		(layer "In4.Cu")
		(net "M_F_DQ<43>")
	)
	(segment
		(start 297.7896 -127.723392)
		(end 297.904408 -127.8382)
		(width 0.14224)
		(layer "In4.Cu")
		(net "M_F_DQ<43>")
	)
	(segment
		(start 297.9674 -131.977892)
		(end 297.9674 -134.0612)
		(width 0.14224)
		(layer "In4.Cu")
		(net "M_F_DQ<43>")
	)
	(segment
		(start 297.917108 -131.9276)
		(end 297.9674 -131.977892)
		(width 0.14224)
		(layer "In4.Cu")
		(net "M_F_DQ<43>")
	)
	(segment
		(start 285.233364 -106.9975)
		(end 285.45536 -107.219496)
		(width 0.0889)
		(layer "In4.Cu")
		(net "M_F_DQ<43>")
	)
	(segment
		(start 297.917108 -131.408678)
		(end 297.917108 -131.9276)
		(width 0.14224)
		(layer "In4.Cu")
		(net "M_F_DQ<43>")
	)
	(segment
		(start 295.790366 -120.705626)
		(end 295.936416 -120.559576)
		(width 0.14224)
		(layer "In4.Cu")
		(net "M_F_DQ<43>")
	)
	(segment
		(start 298.056808 -130.113278)
		(end 298.056808 -131.268978)
		(width 0.14224)
		(layer "In4.Cu")
		(net "M_F_DQ<43>")
	)
	(segment
		(start 284.631638 -106.329988)
		(end 284.664404 -106.329988)
		(width 0.0889)
		(layer "In4.Cu")
		(net "M_F_DQ<43>")
	)
	(segment
		(start 297.633136 -122.83821)
		(end 297.943524 -123.148598)
		(width 0.14224)
		(layer "In4.Cu")
		(net "M_F_DQ<43>")
	)
	(segment
		(start 297.549824 -149.546564)
		(end 297.549824 -149.533356)
		(width 0.14224)
		(layer "In4.Cu")
		(net "M_F_DQ<43>")
	)
	(arc
		(start 283.437584 -97.310194)
		(mid 283.384085 -97.510092)
		(end 283.437584 -97.70999)
		(width 0.0889)
		(layer "In4.Cu")
		(net "M_F_DQ<43>")
	)
	(arc
		(start 284.296104 -105.729786)
		(mid 284.241422 -105.924848)
		(end 284.291278 -106.1212)
		(width 0.0889)
		(layer "In4.Cu")
		(net "M_F_DQ<43>")
	)
	(arc
		(start 283.437584 -99.291394)
		(mid 283.384085 -99.491292)
		(end 283.437584 -99.69119)
		(width 0.0889)
		(layer "In4.Cu")
		(net "M_F_DQ<43>")
	)
	(arc
		(start 283.437584 -96.71939)
		(mid 283.516715 -97.014792)
		(end 283.437584 -97.310194)
		(width 0.0889)
		(layer "In4.Cu")
		(net "M_F_DQ<43>")
	)
	(arc
		(start 284.664404 -106.329988)
		(mid 284.947621 -106.414269)
		(end 285.154624 -106.625136)
		(width 0.0889)
		(layer "In4.Cu")
		(net "M_F_DQ<43>")
	)
	(arc
		(start 283.437584 -98.300794)
		(mid 283.384085 -98.500692)
		(end 283.437584 -98.70059)
		(width 0.0889)
		(layer "In4.Cu")
		(net "M_F_DQ<43>")
	)
	(arc
		(start 283.443934 -99.70135)
		(mid 283.516732 -99.992113)
		(end 283.437584 -100.281232)
		(width 0.0889)
		(layer "In4.Cu")
		(net "M_F_DQ<43>")
	)
	(arc
		(start 283.802074 -103.853234)
		(mid 284.087498 -103.936701)
		(end 284.296104 -104.148636)
		(width 0.0889)
		(layer "In4.Cu")
		(net "M_F_DQ<43>")
	)
	(arc
		(start 282.925774 -95.033084)
		(mid 283.200966 -95.366748)
		(end 283.437584 -95.72879)
		(width 0.0889)
		(layer "In4.Cu")
		(net "M_F_DQ<43>")
	)
	(arc
		(start 284.302454 -104.159304)
		(mid 284.375252 -104.450067)
		(end 284.296104 -104.739186)
		(width 0.0889)
		(layer "In4.Cu")
		(net "M_F_DQ<43>")
	)
	(arc
		(start 284.296104 -104.739186)
		(mid 284.242634 -104.934249)
		(end 284.291278 -105.1306)
		(width 0.0889)
		(layer "In4.Cu")
		(net "M_F_DQ<43>")
	)
	(arc
		(start 283.437584 -97.70999)
		(mid 283.516715 -98.005392)
		(end 283.437584 -98.300794)
		(width 0.0889)
		(layer "In4.Cu")
		(net "M_F_DQ<43>")
	)
	(arc
		(start 284.302454 -105.149904)
		(mid 284.375252 -105.440667)
		(end 284.296104 -105.729786)
		(width 0.0889)
		(layer "In4.Cu")
		(net "M_F_DQ<43>")
	)
	(arc
		(start 283.437584 -99.69119)
		(mid 283.440669 -99.696326)
		(end 283.443934 -99.70135)
		(width 0.0889)
		(layer "In4.Cu")
		(net "M_F_DQ<43>")
	)
	(arc
		(start 283.437584 -100.281232)
		(mid 283.384146 -100.474137)
		(end 283.430726 -100.668836)
		(width 0.0889)
		(layer "In4.Cu")
		(net "M_F_DQ<43>")
	)
	(arc
		(start 283.437584 -98.70059)
		(mid 283.516715 -98.995992)
		(end 283.437584 -99.291394)
		(width 0.0889)
		(layer "In4.Cu")
		(net "M_F_DQ<43>")
	)
	(arc
		(start 283.437584 -102.262432)
		(mid 283.383958 -102.462584)
		(end 283.437584 -102.662736)
		(width 0.0889)
		(layer "In4.Cu")
		(net "M_F_DQ<43>")
	)
	(arc
		(start 283.437584 -95.72879)
		(mid 283.516715 -96.024192)
		(end 283.437584 -96.319594)
		(width 0.0889)
		(layer "In4.Cu")
		(net "M_F_DQ<43>")
	)
	(arc
		(start 284.296104 -106.129836)
		(mid 284.437787 -106.27364)
		(end 284.631638 -106.329988)
		(width 0.0889)
		(layer "In4.Cu")
		(net "M_F_DQ<43>")
	)
	(arc
		(start 283.443934 -101.68255)
		(mid 283.516732 -101.973313)
		(end 283.437584 -102.262432)
		(width 0.0889)
		(layer "In4.Cu")
		(net "M_F_DQ<43>")
	)
	(arc
		(start 283.437584 -102.662736)
		(mid 283.516806 -102.951854)
		(end 283.443934 -103.242618)
		(width 0.0889)
		(layer "In4.Cu")
		(net "M_F_DQ<43>")
	)
	(arc
		(start 283.446474 -100.696268)
		(mid 283.516871 -100.985219)
		(end 283.437584 -101.271832)
		(width 0.0889)
		(layer "In4.Cu")
		(net "M_F_DQ<43>")
	)
	(arc
		(start 283.437584 -101.271832)
		(mid 283.384114 -101.466895)
		(end 283.432758 -101.663246)
		(width 0.0889)
		(layer "In4.Cu")
		(net "M_F_DQ<43>")
	)
	(arc
		(start 283.432758 -103.261922)
		(mid 283.384003 -103.458274)
		(end 283.437584 -103.653336)
		(width 0.0889)
		(layer "In4.Cu")
		(net "M_F_DQ<43>")
	)
	(arc
		(start 283.437584 -96.319594)
		(mid 283.384085 -96.519492)
		(end 283.437584 -96.71939)
		(width 0.0889)
		(layer "In4.Cu")
		(net "M_F_DQ<43>")
	)
	(arc
		(start 283.437584 -103.653336)
		(mid 283.577663 -103.796072)
		(end 283.769308 -103.853234)
		(width 0.0889)
		(layer "In4.Cu")
		(net "M_F_DQ<43>")
	)
	(segment
		(start 296.972228 -153.542746)
		(end 297.150028 -153.364946)
		(width 0.14224)
		(layer "In11.Cu")
		(net "M_F_DQ<43>")
	)
	(segment
		(start 297.150028 -153.364946)
		(end 297.150028 -153.04135)
		(width 0.14224)
		(layer "In11.Cu")
		(net "M_F_DQ<43>")
	)
	(segment
		(start 297.150028 -153.04135)
		(end 296.86123 -152.752552)
		(width 0.14224)
		(layer "In11.Cu")
		(net "M_F_DQ<43>")
	)
	(segment
		(start 297.099228 -150.391368)
		(end 297.099228 -149.9616)
		(width 0.14224)
		(layer "In11.Cu")
		(net "M_F_DQ<43>")
	)
	(segment
		(start 297.143678 -150.435818)
		(end 297.099228 -150.391368)
		(width 0.14224)
		(layer "In11.Cu")
		(net "M_F_DQ<43>")
	)
	(segment
		(start 297.118278 -151.9174)
		(end 296.86123 -151.660352)
		(width 0.14224)
		(layer "In11.Cu")
		(net "M_F_DQ<43>")
	)
	(segment
		(start 297.527472 -149.533356)
		(end 297.549824 -149.533356)
		(width 0.14224)
		(layer "In11.Cu")
		(net "M_F_DQ<43>")
	)
	(segment
		(start 296.86123 -151.660352)
		(end 296.86123 -151.387048)
		(width 0.14224)
		(layer "In11.Cu")
		(net "M_F_DQ<43>")
	)
	(segment
		(start 296.86123 -152.479248)
		(end 297.118278 -152.2222)
		(width 0.14224)
		(layer "In11.Cu")
		(net "M_F_DQ<43>")
	)
	(segment
		(start 296.86123 -152.752552)
		(end 296.86123 -152.479248)
		(width 0.14224)
		(layer "In11.Cu")
		(net "M_F_DQ<43>")
	)
	(segment
		(start 296.69994 -153.542746)
		(end 296.972228 -153.542746)
		(width 0.14224)
		(layer "In11.Cu")
		(net "M_F_DQ<43>")
	)
	(segment
		(start 297.099228 -149.9616)
		(end 297.527472 -149.533356)
		(width 0.14224)
		(layer "In11.Cu")
		(net "M_F_DQ<43>")
	)
	(segment
		(start 297.118278 -152.2222)
		(end 297.118278 -151.9174)
		(width 0.14224)
		(layer "In11.Cu")
		(net "M_F_DQ<43>")
	)
	(segment
		(start 297.143678 -151.1046)
		(end 297.143678 -150.435818)
		(width 0.14224)
		(layer "In11.Cu")
		(net "M_F_DQ<43>")
	)
	(segment
		(start 296.86123 -151.387048)
		(end 297.143678 -151.1046)
		(width 0.14224)
		(layer "In11.Cu")
		(net "M_F_DQ<43>")
	)
	(segment
		(start 297.681396 -155.52674)
		(end 297.549824 -155.395168)
		(width 0.1651)
		(layer "F.Cu")
		(net "M_F_DQ<42>")
	)
	(segment
		(start 282.354274 -94.042738)
		(end 282.925774 -94.042738)
		(width 0.1651)
		(layer "F.Cu")
		(net "M_F_DQ<42>")
	)
	(segment
		(start 297.549824 -156.87294)
		(end 297.549824 -155.881832)
		(width 0.1651)
		(layer "F.Cu")
		(net "M_F_DQ<42>")
	)
	(segment
		(start 297.550332 -156.87294)
		(end 297.549824 -156.87294)
		(width 0.1651)
		(layer "F.Cu")
		(net "M_F_DQ<42>")
	)
	(segment
		(start 297.549824 -155.395168)
		(end 297.549824 -155.1178)
		(width 0.1651)
		(layer "F.Cu")
		(net "M_F_DQ<42>")
	)
	(segment
		(start 297.681396 -155.75026)
		(end 297.681396 -155.52674)
		(width 0.1651)
		(layer "F.Cu")
		(net "M_F_DQ<42>")
	)
	(segment
		(start 297.549824 -155.881832)
		(end 297.681396 -155.75026)
		(width 0.1651)
		(layer "F.Cu")
		(net "M_F_DQ<42>")
	)
	(via
		(at 282.925774 -94.042738)
		(size 0.508)
		(drill 0.254)
		(layers "F.Cu" "B.Cu")
		(net "M_F_DQ<42>")
	)
	(via
		(at 296.69994 -150.814278)
		(size 0.508)
		(drill 0.254)
		(layers "F.Cu" "B.Cu")
		(net "M_F_DQ<42>")
	)
	(via
		(at 297.549824 -155.1178)
		(size 0.508)
		(drill 0.254)
		(layers "F.Cu" "B.Cu")
		(net "M_F_DQ<42>")
	)
	(segment
		(start 296.700448 -152.078436)
		(end 296.69994 -152.078182)
		(width 0.1651)
		(layer "B.Cu")
		(net "M_F_DQ<42>")
	)
	(segment
		(start 296.69994 -152.078182)
		(end 296.69994 -150.814278)
		(width 0.1651)
		(layer "B.Cu")
		(net "M_F_DQ<42>")
	)
	(segment
		(start 284.989524 -106.720386)
		(end 285.042864 -106.813096)
		(width 0.0889)
		(layer "In4.Cu")
		(net "M_F_DQ<42>")
	)
	(segment
		(start 283.263594 -101.751892)
		(end 283.272484 -101.767132)
		(width 0.0889)
		(layer "In4.Cu")
		(net "M_F_DQ<42>")
	)
	(segment
		(start 297.1292 -134.0612)
		(end 297.282108 -134.214108)
		(width 0.14224)
		(layer "In4.Cu")
		(net "M_F_DQ<42>")
	)
	(segment
		(start 284.82036 -112.365536)
		(end 290.642294 -118.18747)
		(width 0.14224)
		(layer "In4.Cu")
		(net "M_F_DQ<42>")
	)
	(segment
		(start 284.625034 -106.520488)
		(end 284.6578 -106.520488)
		(width 0.0889)
		(layer "In4.Cu")
		(net "M_F_DQ<42>")
	)
	(segment
		(start 296.990008 -145.578068)
		(end 297.218608 -145.806668)
		(width 0.14224)
		(layer "In4.Cu")
		(net "M_F_DQ<42>")
	)
	(segment
		(start 297.218608 -145.806668)
		(end 297.218608 -148.972778)
		(width 0.14224)
		(layer "In4.Cu")
		(net "M_F_DQ<42>")
	)
	(segment
		(start 295.950132 -123.11126)
		(end 296.8498 -124.010928)
		(width 0.14224)
		(layer "In4.Cu")
		(net "M_F_DQ<42>")
	)
	(segment
		(start 290.642294 -118.18747)
		(end 292.25875 -118.18747)
		(width 0.14224)
		(layer "In4.Cu")
		(net "M_F_DQ<42>")
	)
	(segment
		(start 284.82036 -107.219496)
		(end 284.82036 -112.365536)
		(width 0.14224)
		(layer "In4.Cu")
		(net "M_F_DQ<42>")
	)
	(segment
		(start 296.990008 -144.372838)
		(end 296.990008 -145.578068)
		(width 0.14224)
		(layer "In4.Cu")
		(net "M_F_DQ<42>")
	)
	(segment
		(start 284.124654 -106.214418)
		(end 284.131004 -106.225086)
		(width 0.0889)
		(layer "In4.Cu")
		(net "M_F_DQ<42>")
	)
	(segment
		(start 292.25875 -118.18747)
		(end 295.950132 -121.878852)
		(width 0.14224)
		(layer "In4.Cu")
		(net "M_F_DQ<42>")
	)
	(segment
		(start 297.12539 -143.63319)
		(end 297.269408 -143.777208)
		(width 0.14224)
		(layer "In4.Cu")
		(net "M_F_DQ<42>")
	)
	(segment
		(start 297.066208 -140.933678)
		(end 297.269408 -141.136878)
		(width 0.14224)
		(layer "In4.Cu")
		(net "M_F_DQ<42>")
	)
	(segment
		(start 284.131004 -105.234486)
		(end 284.13583 -105.243122)
		(width 0.0889)
		(layer "In4.Cu")
		(net "M_F_DQ<42>")
	)
	(segment
		(start 295.950132 -121.878852)
		(end 295.950132 -123.11126)
		(width 0.14224)
		(layer "In4.Cu")
		(net "M_F_DQ<42>")
	)
	(segment
		(start 297.282108 -134.439152)
		(end 297.040808 -134.680452)
		(width 0.14224)
		(layer "In4.Cu")
		(net "M_F_DQ<42>")
	)
	(segment
		(start 296.8498 -124.010928)
		(end 296.8498 -125.6284)
		(width 0.14224)
		(layer "In4.Cu")
		(net "M_F_DQ<42>")
	)
	(segment
		(start 297.12539 -141.622018)
		(end 297.12539 -143.63319)
		(width 0.14224)
		(layer "In4.Cu")
		(net "M_F_DQ<42>")
	)
	(segment
		(start 282.925774 -94.042738)
		(end 282.560014 -94.871286)
		(width 0.0889)
		(layer "In4.Cu")
		(net "M_F_DQ<42>")
	)
	(segment
		(start 297.269408 -144.093438)
		(end 296.990008 -144.372838)
		(width 0.14224)
		(layer "In4.Cu")
		(net "M_F_DQ<42>")
	)
	(segment
		(start 297.269408 -141.478)
		(end 297.12539 -141.622018)
		(width 0.14224)
		(layer "In4.Cu")
		(net "M_F_DQ<42>")
	)
	(segment
		(start 297.066208 -131.332478)
		(end 297.2562 -131.52247)
		(width 0.14224)
		(layer "In4.Cu")
		(net "M_F_DQ<42>")
	)
	(segment
		(start 297.1292 -138.7856)
		(end 297.193208 -138.849608)
		(width 0.14224)
		(layer "In4.Cu")
		(net "M_F_DQ<42>")
	)
	(segment
		(start 285.042864 -106.813096)
		(end 285.042864 -106.996992)
		(width 0.0889)
		(layer "In4.Cu")
		(net "M_F_DQ<42>")
	)
	(segment
		(start 283.272484 -103.158036)
		(end 283.266134 -103.168704)
		(width 0.0889)
		(layer "In4.Cu")
		(net "M_F_DQ<42>")
	)
	(segment
		(start 297.218608 -148.972778)
		(end 296.69994 -149.491446)
		(width 0.14224)
		(layer "In4.Cu")
		(net "M_F_DQ<42>")
	)
	(segment
		(start 297.193208 -129.833878)
		(end 297.066208 -129.960878)
		(width 0.14224)
		(layer "In4.Cu")
		(net "M_F_DQ<42>")
	)
	(segment
		(start 297.269408 -141.136878)
		(end 297.269408 -141.478)
		(width 0.14224)
		(layer "In4.Cu")
		(net "M_F_DQ<42>")
	)
	(segment
		(start 297.269408 -143.777208)
		(end 297.269408 -144.093438)
		(width 0.14224)
		(layer "In4.Cu")
		(net "M_F_DQ<42>")
	)
	(segment
		(start 283.27731 -103.1494)
		(end 283.272484 -103.158036)
		(width 0.0889)
		(layer "In4.Cu")
		(net "M_F_DQ<42>")
	)
	(segment
		(start 297.193208 -136.284208)
		(end 297.193208 -136.5758)
		(width 0.14224)
		(layer "In4.Cu")
		(net "M_F_DQ<42>")
	)
	(segment
		(start 284.124654 -105.223818)
		(end 284.131004 -105.234486)
		(width 0.0889)
		(layer "In4.Cu")
		(net "M_F_DQ<42>")
	)
	(segment
		(start 297.040808 -136.131808)
		(end 297.193208 -136.284208)
		(width 0.14224)
		(layer "In4.Cu")
		(net "M_F_DQ<42>")
	)
	(segment
		(start 283.266134 -100.765864)
		(end 283.272484 -100.776532)
		(width 0.0889)
		(layer "In4.Cu")
		(net "M_F_DQ<42>")
	)
	(segment
		(start 297.193208 -136.5758)
		(end 297.1292 -136.639808)
		(width 0.14224)
		(layer "In4.Cu")
		(net "M_F_DQ<42>")
	)
	(segment
		(start 297.066208 -129.960878)
		(end 297.066208 -131.332478)
		(width 0.14224)
		(layer "In4.Cu")
		(net "M_F_DQ<42>")
	)
	(segment
		(start 297.0022 -125.7808)
		(end 297.0022 -126.257812)
		(width 0.14224)
		(layer "In4.Cu")
		(net "M_F_DQ<42>")
	)
	(segment
		(start 297.2562 -131.877308)
		(end 297.1292 -132.004308)
		(width 0.14224)
		(layer "In4.Cu")
		(net "M_F_DQ<42>")
	)
	(segment
		(start 285.042864 -106.996992)
		(end 284.82036 -107.219496)
		(width 0.0889)
		(layer "In4.Cu")
		(net "M_F_DQ<42>")
	)
	(segment
		(start 297.193208 -139.435078)
		(end 297.066208 -139.562078)
		(width 0.14224)
		(layer "In4.Cu")
		(net "M_F_DQ<42>")
	)
	(segment
		(start 296.8498 -125.6284)
		(end 297.0022 -125.7808)
		(width 0.14224)
		(layer "In4.Cu")
		(net "M_F_DQ<42>")
	)
	(segment
		(start 283.272484 -101.767132)
		(end 283.27731 -101.775768)
		(width 0.0889)
		(layer "In4.Cu")
		(net "M_F_DQ<42>")
	)
	(segment
		(start 296.69994 -149.491446)
		(end 296.69994 -150.814278)
		(width 0.14224)
		(layer "In4.Cu")
		(net "M_F_DQ<42>")
	)
	(segment
		(start 297.2562 -131.52247)
		(end 297.2562 -131.877308)
		(width 0.14224)
		(layer "In4.Cu")
		(net "M_F_DQ<42>")
	)
	(segment
		(start 297.193208 -126.44882)
		(end 297.193208 -129.833878)
		(width 0.14224)
		(layer "In4.Cu")
		(net "M_F_DQ<42>")
	)
	(segment
		(start 297.0022 -126.257812)
		(end 297.193208 -126.44882)
		(width 0.14224)
		(layer "In4.Cu")
		(net "M_F_DQ<42>")
	)
	(segment
		(start 284.131004 -104.243886)
		(end 284.13583 -104.252522)
		(width 0.0889)
		(layer "In4.Cu")
		(net "M_F_DQ<42>")
	)
	(segment
		(start 297.1292 -136.639808)
		(end 297.1292 -138.7856)
		(width 0.14224)
		(layer "In4.Cu")
		(net "M_F_DQ<42>")
	)
	(segment
		(start 283.272484 -100.776532)
		(end 283.279342 -100.788724)
		(width 0.0889)
		(layer "In4.Cu")
		(net "M_F_DQ<42>")
	)
	(segment
		(start 297.193208 -138.849608)
		(end 297.193208 -139.435078)
		(width 0.14224)
		(layer "In4.Cu")
		(net "M_F_DQ<42>")
	)
	(segment
		(start 297.1292 -132.004308)
		(end 297.1292 -134.0612)
		(width 0.14224)
		(layer "In4.Cu")
		(net "M_F_DQ<42>")
	)
	(segment
		(start 297.040808 -134.680452)
		(end 297.040808 -136.131808)
		(width 0.14224)
		(layer "In4.Cu")
		(net "M_F_DQ<42>")
	)
	(segment
		(start 283.762704 -104.043734)
		(end 283.79547 -104.043734)
		(width 0.0889)
		(layer "In4.Cu")
		(net "M_F_DQ<42>")
	)
	(segment
		(start 297.282108 -134.214108)
		(end 297.282108 -134.439152)
		(width 0.14224)
		(layer "In4.Cu")
		(net "M_F_DQ<42>")
	)
	(segment
		(start 297.066208 -139.562078)
		(end 297.066208 -140.933678)
		(width 0.14224)
		(layer "In4.Cu")
		(net "M_F_DQ<42>")
	)
	(arc
		(start 283.272484 -96.814894)
		(mid 283.325983 -97.014792)
		(end 283.272484 -97.21469)
		(width 0.0889)
		(layer "In4.Cu")
		(net "M_F_DQ<42>")
	)
	(arc
		(start 284.13583 -105.243122)
		(mid 284.184585 -105.439474)
		(end 284.131004 -105.634536)
		(width 0.0889)
		(layer "In4.Cu")
		(net "M_F_DQ<42>")
	)
	(arc
		(start 283.266134 -103.168704)
		(mid 283.193336 -103.459467)
		(end 283.272484 -103.748586)
		(width 0.0889)
		(layer "In4.Cu")
		(net "M_F_DQ<42>")
	)
	(arc
		(start 283.272484 -98.20529)
		(mid 283.193353 -98.500692)
		(end 283.272484 -98.796094)
		(width 0.0889)
		(layer "In4.Cu")
		(net "M_F_DQ<42>")
	)
	(arc
		(start 284.131004 -104.643936)
		(mid 284.051782 -104.933054)
		(end 284.124654 -105.223818)
		(width 0.0889)
		(layer "In4.Cu")
		(net "M_F_DQ<42>")
	)
	(arc
		(start 283.272484 -103.748586)
		(mid 283.479488 -103.95945)
		(end 283.762704 -104.043734)
		(width 0.0889)
		(layer "In4.Cu")
		(net "M_F_DQ<42>")
	)
	(arc
		(start 283.272484 -99.786694)
		(mid 283.274842 -99.790665)
		(end 283.27731 -99.794568)
		(width 0.0889)
		(layer "In4.Cu")
		(net "M_F_DQ<42>")
	)
	(arc
		(start 283.272484 -96.22409)
		(mid 283.193353 -96.519492)
		(end 283.272484 -96.814894)
		(width 0.0889)
		(layer "In4.Cu")
		(net "M_F_DQ<42>")
	)
	(arc
		(start 283.272484 -97.21469)
		(mid 283.193353 -97.510092)
		(end 283.272484 -97.805494)
		(width 0.0889)
		(layer "In4.Cu")
		(net "M_F_DQ<42>")
	)
	(arc
		(start 284.131004 -106.225086)
		(mid 284.339612 -106.437018)
		(end 284.625034 -106.520488)
		(width 0.0889)
		(layer "In4.Cu")
		(net "M_F_DQ<42>")
	)
	(arc
		(start 283.272484 -101.176328)
		(mid 283.193295 -101.462943)
		(end 283.263594 -101.751892)
		(width 0.0889)
		(layer "In4.Cu")
		(net "M_F_DQ<42>")
	)
	(arc
		(start 283.272484 -95.824294)
		(mid 283.325983 -96.024192)
		(end 283.272484 -96.22409)
		(width 0.0889)
		(layer "In4.Cu")
		(net "M_F_DQ<42>")
	)
	(arc
		(start 283.272484 -100.185982)
		(mid 283.193262 -100.4751)
		(end 283.266134 -100.765864)
		(width 0.0889)
		(layer "In4.Cu")
		(net "M_F_DQ<42>")
	)
	(arc
		(start 283.79547 -104.043734)
		(mid 283.98932 -104.100084)
		(end 284.131004 -104.243886)
		(width 0.0889)
		(layer "In4.Cu")
		(net "M_F_DQ<42>")
	)
	(arc
		(start 283.27731 -101.775768)
		(mid 283.326065 -101.97212)
		(end 283.272484 -102.167182)
		(width 0.0889)
		(layer "In4.Cu")
		(net "M_F_DQ<42>")
	)
	(arc
		(start 283.272484 -98.796094)
		(mid 283.325983 -98.995992)
		(end 283.272484 -99.19589)
		(width 0.0889)
		(layer "In4.Cu")
		(net "M_F_DQ<42>")
	)
	(arc
		(start 283.279342 -100.788724)
		(mid 283.326018 -100.983425)
		(end 283.272484 -101.176328)
		(width 0.0889)
		(layer "In4.Cu")
		(net "M_F_DQ<42>")
	)
	(arc
		(start 284.131004 -105.634536)
		(mid 284.046344 -105.923585)
		(end 284.124654 -106.214418)
		(width 0.0889)
		(layer "In4.Cu")
		(net "M_F_DQ<42>")
	)
	(arc
		(start 283.272484 -102.757986)
		(mid 283.325954 -102.953049)
		(end 283.27731 -103.1494)
		(width 0.0889)
		(layer "In4.Cu")
		(net "M_F_DQ<42>")
	)
	(arc
		(start 283.272484 -99.19589)
		(mid 283.193353 -99.491292)
		(end 283.272484 -99.786694)
		(width 0.0889)
		(layer "In4.Cu")
		(net "M_F_DQ<42>")
	)
	(arc
		(start 282.560014 -94.871286)
		(mid 282.555897 -95.186284)
		(end 282.780994 -95.406718)
		(width 0.0889)
		(layer "In4.Cu")
		(net "M_F_DQ<42>")
	)
	(arc
		(start 283.272484 -97.805494)
		(mid 283.325983 -98.005392)
		(end 283.272484 -98.20529)
		(width 0.0889)
		(layer "In4.Cu")
		(net "M_F_DQ<42>")
	)
	(arc
		(start 284.6578 -106.520488)
		(mid 284.849442 -106.577654)
		(end 284.989524 -106.720386)
		(width 0.0889)
		(layer "In4.Cu")
		(net "M_F_DQ<42>")
	)
	(arc
		(start 283.272484 -102.167182)
		(mid 283.193353 -102.462584)
		(end 283.272484 -102.757986)
		(width 0.0889)
		(layer "In4.Cu")
		(net "M_F_DQ<42>")
	)
	(arc
		(start 284.13583 -104.252522)
		(mid 284.184585 -104.448874)
		(end 284.131004 -104.643936)
		(width 0.0889)
		(layer "In4.Cu")
		(net "M_F_DQ<42>")
	)
	(arc
		(start 283.27731 -99.794568)
		(mid 283.326065 -99.99092)
		(end 283.272484 -100.185982)
		(width 0.0889)
		(layer "In4.Cu")
		(net "M_F_DQ<42>")
	)
	(arc
		(start 282.780994 -95.406718)
		(mid 283.061969 -95.574046)
		(end 283.272484 -95.824294)
		(width 0.0889)
		(layer "In4.Cu")
		(net "M_F_DQ<42>")
	)
	(segment
		(start 297.549824 -155.1178)
		(end 296.26687 -153.834846)
		(width 0.14224)
		(layer "In11.Cu")
		(net "M_F_DQ<42>")
	)
	(segment
		(start 296.26687 -151.247348)
		(end 296.69994 -150.814278)
		(width 0.14224)
		(layer "In11.Cu")
		(net "M_F_DQ<42>")
	)
	(segment
		(start 296.26687 -153.834846)
		(end 296.26687 -151.247348)
		(width 0.14224)
		(layer "In11.Cu")
		(net "M_F_DQ<42>")
	)
	(segment
		(start 290.750498 -152.273)
		(end 290.74999 -152.278842)
		(width 0.1651)
		(layer "F.Cu")
		(net "M_F_DQ<41>")
	)
	(segment
		(start 279.778714 -95.528384)
		(end 280.350214 -95.528384)
		(width 0.1651)
		(layer "F.Cu")
		(net "M_F_DQ<41>")
	)
	(segment
		(start 290.74999 -152.278842)
		(end 290.74999 -153.542746)
		(width 0.1651)
		(layer "F.Cu")
		(net "M_F_DQ<41>")
	)
	(via
		(at 290.74999 -153.542746)
		(size 0.508)
		(drill 0.254)
		(layers "F.Cu" "B.Cu")
		(net "M_F_DQ<41>")
	)
	(via
		(at 280.350214 -95.528384)
		(size 0.508)
		(drill 0.254)
		(layers "F.Cu" "B.Cu")
		(net "M_F_DQ<41>")
	)
	(via
		(at 291.422074 -149.533356)
		(size 0.508)
		(drill 0.254)
		(layers "F.Cu" "B.Cu")
		(net "M_F_DQ<41>")
	)
	(segment
		(start 291.599874 -148.852382)
		(end 291.422074 -149.030182)
		(width 0.1651)
		(layer "B.Cu")
		(net "M_F_DQ<41>")
	)
	(segment
		(start 291.599874 -147.478496)
		(end 291.599874 -148.852382)
		(width 0.1651)
		(layer "B.Cu")
		(net "M_F_DQ<41>")
	)
	(segment
		(start 291.422074 -149.030182)
		(end 291.422074 -149.533356)
		(width 0.1651)
		(layer "B.Cu")
		(net "M_F_DQ<41>")
	)
	(segment
		(start 291.600382 -147.478496)
		(end 291.599874 -147.478496)
		(width 0.1651)
		(layer "B.Cu")
		(net "M_F_DQ<41>")
	)
	(segment
		(start 280.009854 -100.270818)
		(end 280.003504 -100.281486)
		(width 0.0889)
		(layer "In4.Cu")
		(net "M_F_DQ<41>")
	)
	(segment
		(start 283.425646 -116.315236)
		(end 283.425646 -116.534184)
		(width 0.14224)
		(layer "In4.Cu")
		(net "M_F_DQ<41>")
	)
	(segment
		(start 280.862024 -107.09656)
		(end 280.98496 -107.219496)
		(width 0.0889)
		(layer "In4.Cu")
		(net "M_F_DQ<41>")
	)
	(segment
		(start 286.491426 -118.876064)
		(end 286.23895 -119.12854)
		(width 0.14224)
		(layer "In4.Cu")
		(net "M_F_DQ<41>")
	)
	(segment
		(start 287.176718 -120.066308)
		(end 287.176718 -120.285256)
		(width 0.14224)
		(layer "In4.Cu")
		(net "M_F_DQ<41>")
	)
	(segment
		(start 291.915596 -136.6266)
		(end 292.0238 -136.734804)
		(width 0.14224)
		(layer "In4.Cu")
		(net "M_F_DQ<41>")
	)
	(segment
		(start 287.429194 -119.813832)
		(end 287.176718 -120.066308)
		(width 0.14224)
		(layer "In4.Cu")
		(net "M_F_DQ<41>")
	)
	(segment
		(start 285.551118 -118.659656)
		(end 285.770066 -118.659656)
		(width 0.14224)
		(layer "In4.Cu")
		(net "M_F_DQ<41>")
	)
	(segment
		(start 283.425646 -116.534184)
		(end 283.675582 -116.78412)
		(width 0.14224)
		(layer "In4.Cu")
		(net "M_F_DQ<41>")
	)
	(segment
		(start 291.915596 -143.796004)
		(end 291.915596 -149.039834)
		(width 0.14224)
		(layer "In4.Cu")
		(net "M_F_DQ<41>")
	)
	(segment
		(start 284.363414 -117.253004)
		(end 284.363414 -117.471952)
		(width 0.14224)
		(layer "In4.Cu")
		(net "M_F_DQ<41>")
	)
	(segment
		(start 286.23895 -119.347488)
		(end 286.488886 -119.597424)
		(width 0.14224)
		(layer "In4.Cu")
		(net "M_F_DQ<41>")
	)
	(segment
		(start 280.009854 -103.242618)
		(end 280.003504 -103.253286)
		(width 0.0889)
		(layer "In4.Cu")
		(net "M_F_DQ<41>")
	)
	(segment
		(start 284.365954 -116.531644)
		(end 284.61589 -116.78158)
		(width 0.14224)
		(layer "In4.Cu")
		(net "M_F_DQ<41>")
	)
	(segment
		(start 285.084774 -117.469412)
		(end 285.303722 -117.469412)
		(width 0.14224)
		(layer "In4.Cu")
		(net "M_F_DQ<41>")
	)
	(segment
		(start 280.98496 -107.219496)
		(end 280.98496 -113.15065)
		(width 0.14224)
		(layer "In4.Cu")
		(net "M_F_DQ<41>")
	)
	(segment
		(start 291.915596 -131.793996)
		(end 292.0238 -131.9022)
		(width 0.14224)
		(layer "In4.Cu")
		(net "M_F_DQ<41>")
	)
	(segment
		(start 280.003504 -101.272086)
		(end 279.998678 -101.280722)
		(width 0.0889)
		(layer "In4.Cu")
		(net "M_F_DQ<41>")
	)
	(segment
		(start 291.915596 -134.118604)
		(end 291.915596 -136.6266)
		(width 0.14224)
		(layer "In4.Cu")
		(net "M_F_DQ<41>")
	)
	(segment
		(start 292.0238 -138.3792)
		(end 292.0238 -138.811)
		(width 0.14224)
		(layer "In4.Cu")
		(net "M_F_DQ<41>")
	)
	(segment
		(start 283.89453 -116.78412)
		(end 284.147006 -116.531644)
		(width 0.14224)
		(layer "In4.Cu")
		(net "M_F_DQ<41>")
	)
	(segment
		(start 291.915596 -138.919204)
		(end 291.915596 -141.420596)
		(width 0.14224)
		(layer "In4.Cu")
		(net "M_F_DQ<41>")
	)
	(segment
		(start 286.488886 -119.597424)
		(end 286.707834 -119.597424)
		(width 0.14224)
		(layer "In4.Cu")
		(net "M_F_DQ<41>")
	)
	(segment
		(start 280.98496 -113.15065)
		(end 283.678122 -115.843812)
		(width 0.14224)
		(layer "In4.Cu")
		(net "M_F_DQ<41>")
	)
	(segment
		(start 291.8206 -142.7988)
		(end 292.0238 -143.002)
		(width 0.14224)
		(layer "In4.Cu")
		(net "M_F_DQ<41>")
	)
	(segment
		(start 285.770066 -118.659656)
		(end 286.022542 -118.40718)
		(width 0.14224)
		(layer "In4.Cu")
		(net "M_F_DQ<41>")
	)
	(segment
		(start 291.8206 -142.1892)
		(end 291.8206 -142.7988)
		(width 0.14224)
		(layer "In4.Cu")
		(net "M_F_DQ<41>")
	)
	(segment
		(start 283.678122 -116.06276)
		(end 283.425646 -116.315236)
		(width 0.14224)
		(layer "In4.Cu")
		(net "M_F_DQ<41>")
	)
	(segment
		(start 283.675582 -116.78412)
		(end 283.89453 -116.78412)
		(width 0.14224)
		(layer "In4.Cu")
		(net "M_F_DQ<41>")
	)
	(segment
		(start 292.0238 -136.734804)
		(end 292.0238 -137.2616)
		(width 0.14224)
		(layer "In4.Cu")
		(net "M_F_DQ<41>")
	)
	(segment
		(start 280.003504 -104.243886)
		(end 279.998678 -104.252522)
		(width 0.0889)
		(layer "In4.Cu")
		(net "M_F_DQ<41>")
	)
	(segment
		(start 285.303722 -117.469412)
		(end 285.553658 -117.719348)
		(width 0.14224)
		(layer "In4.Cu")
		(net "M_F_DQ<41>")
	)
	(segment
		(start 285.553658 -117.719348)
		(end 285.553658 -117.938296)
		(width 0.14224)
		(layer "In4.Cu")
		(net "M_F_DQ<41>")
	)
	(segment
		(start 280.003504 -103.253286)
		(end 279.998678 -103.261922)
		(width 0.0889)
		(layer "In4.Cu")
		(net "M_F_DQ<41>")
	)
	(segment
		(start 280.003504 -105.234486)
		(end 279.998678 -105.243122)
		(width 0.0889)
		(layer "In4.Cu")
		(net "M_F_DQ<41>")
	)
	(segment
		(start 285.301182 -118.40972)
		(end 285.551118 -118.659656)
		(width 0.14224)
		(layer "In4.Cu")
		(net "M_F_DQ<41>")
	)
	(segment
		(start 287.429194 -119.594884)
		(end 287.429194 -119.813832)
		(width 0.14224)
		(layer "In4.Cu")
		(net "M_F_DQ<41>")
	)
	(segment
		(start 284.363414 -117.471952)
		(end 284.61335 -117.721888)
		(width 0.14224)
		(layer "In4.Cu")
		(net "M_F_DQ<41>")
	)
	(segment
		(start 291.915596 -129.368804)
		(end 291.915596 -131.793996)
		(width 0.14224)
		(layer "In4.Cu")
		(net "M_F_DQ<41>")
	)
	(segment
		(start 291.915596 -141.420596)
		(end 292.0238 -141.5288)
		(width 0.14224)
		(layer "In4.Cu")
		(net "M_F_DQ<41>")
	)
	(segment
		(start 287.179258 -119.344948)
		(end 287.429194 -119.594884)
		(width 0.14224)
		(layer "In4.Cu")
		(net "M_F_DQ<41>")
	)
	(segment
		(start 286.022542 -118.40718)
		(end 286.24149 -118.40718)
		(width 0.14224)
		(layer "In4.Cu")
		(net "M_F_DQ<41>")
	)
	(segment
		(start 291.8714 -126.9238)
		(end 292.240208 -127.292608)
		(width 0.14224)
		(layer "In4.Cu")
		(net "M_F_DQ<41>")
	)
	(segment
		(start 292.0238 -131.9022)
		(end 292.0238 -134.0104)
		(width 0.14224)
		(layer "In4.Cu")
		(net "M_F_DQ<41>")
	)
	(segment
		(start 284.61589 -117.000528)
		(end 284.363414 -117.253004)
		(width 0.14224)
		(layer "In4.Cu")
		(net "M_F_DQ<41>")
	)
	(segment
		(start 284.61589 -116.78158)
		(end 284.61589 -117.000528)
		(width 0.14224)
		(layer "In4.Cu")
		(net "M_F_DQ<41>")
	)
	(segment
		(start 280.003504 -102.262686)
		(end 279.998678 -102.271322)
		(width 0.0889)
		(layer "In4.Cu")
		(net "M_F_DQ<41>")
	)
	(segment
		(start 290.090098 -122.33656)
		(end 291.8714 -124.117862)
		(width 0.14224)
		(layer "In4.Cu")
		(net "M_F_DQ<41>")
	)
	(segment
		(start 291.915596 -149.039834)
		(end 291.422074 -149.533356)
		(width 0.14224)
		(layer "In4.Cu")
		(net "M_F_DQ<41>")
	)
	(segment
		(start 286.96031 -119.344948)
		(end 287.179258 -119.344948)
		(width 0.14224)
		(layer "In4.Cu")
		(net "M_F_DQ<41>")
	)
	(segment
		(start 291.6936 -137.5918)
		(end 291.6936 -138.049)
		(width 0.14224)
		(layer "In4.Cu")
		(net "M_F_DQ<41>")
	)
	(segment
		(start 292.0238 -143.002)
		(end 292.0238 -143.6878)
		(width 0.14224)
		(layer "In4.Cu")
		(net "M_F_DQ<41>")
	)
	(segment
		(start 291.6936 -138.049)
		(end 292.0238 -138.3792)
		(width 0.14224)
		(layer "In4.Cu")
		(net "M_F_DQ<41>")
	)
	(segment
		(start 280.350214 -95.528384)
		(end 280.066242 -96.16186)
		(width 0.0889)
		(layer "In4.Cu")
		(net "M_F_DQ<41>")
	)
	(segment
		(start 292.0238 -137.2616)
		(end 291.6936 -137.5918)
		(width 0.14224)
		(layer "In4.Cu")
		(net "M_F_DQ<41>")
	)
	(segment
		(start 284.61335 -117.721888)
		(end 284.832298 -117.721888)
		(width 0.14224)
		(layer "In4.Cu")
		(net "M_F_DQ<41>")
	)
	(segment
		(start 292.0238 -138.811)
		(end 291.915596 -138.919204)
		(width 0.14224)
		(layer "In4.Cu")
		(net "M_F_DQ<41>")
	)
	(segment
		(start 280.009854 -102.252018)
		(end 280.003504 -102.262686)
		(width 0.0889)
		(layer "In4.Cu")
		(net "M_F_DQ<41>")
	)
	(segment
		(start 292.0238 -143.6878)
		(end 291.915596 -143.796004)
		(width 0.14224)
		(layer "In4.Cu")
		(net "M_F_DQ<41>")
	)
	(segment
		(start 292.0238 -141.986)
		(end 291.8206 -142.1892)
		(width 0.14224)
		(layer "In4.Cu")
		(net "M_F_DQ<41>")
	)
	(segment
		(start 280.009854 -105.223818)
		(end 280.003504 -105.234486)
		(width 0.0889)
		(layer "In4.Cu")
		(net "M_F_DQ<41>")
	)
	(segment
		(start 287.176718 -120.285256)
		(end 289.228022 -122.33656)
		(width 0.14224)
		(layer "In4.Cu")
		(net "M_F_DQ<41>")
	)
	(segment
		(start 284.147006 -116.531644)
		(end 284.365954 -116.531644)
		(width 0.14224)
		(layer "In4.Cu")
		(net "M_F_DQ<41>")
	)
	(segment
		(start 289.228022 -122.33656)
		(end 290.090098 -122.33656)
		(width 0.14224)
		(layer "In4.Cu")
		(net "M_F_DQ<41>")
	)
	(segment
		(start 286.23895 -119.12854)
		(end 286.23895 -119.347488)
		(width 0.14224)
		(layer "In4.Cu")
		(net "M_F_DQ<41>")
	)
	(segment
		(start 286.707834 -119.597424)
		(end 286.96031 -119.344948)
		(width 0.14224)
		(layer "In4.Cu")
		(net "M_F_DQ<41>")
	)
	(segment
		(start 280.003504 -100.281486)
		(end 279.998678 -100.290122)
		(width 0.0889)
		(layer "In4.Cu")
		(net "M_F_DQ<41>")
	)
	(segment
		(start 280.009854 -104.233218)
		(end 280.003504 -104.243886)
		(width 0.0889)
		(layer "In4.Cu")
		(net "M_F_DQ<41>")
	)
	(segment
		(start 292.240208 -129.044192)
		(end 291.915596 -129.368804)
		(width 0.14224)
		(layer "In4.Cu")
		(net "M_F_DQ<41>")
	)
	(segment
		(start 292.240208 -127.292608)
		(end 292.240208 -129.044192)
		(width 0.14224)
		(layer "In4.Cu")
		(net "M_F_DQ<41>")
	)
	(segment
		(start 285.301182 -118.190772)
		(end 285.301182 -118.40972)
		(width 0.14224)
		(layer "In4.Cu")
		(net "M_F_DQ<41>")
	)
	(segment
		(start 280.009854 -101.261418)
		(end 280.003504 -101.272086)
		(width 0.0889)
		(layer "In4.Cu")
		(net "M_F_DQ<41>")
	)
	(segment
		(start 291.8714 -124.117862)
		(end 291.8714 -126.9238)
		(width 0.14224)
		(layer "In4.Cu")
		(net "M_F_DQ<41>")
	)
	(segment
		(start 292.0238 -141.5288)
		(end 292.0238 -141.986)
		(width 0.14224)
		(layer "In4.Cu")
		(net "M_F_DQ<41>")
	)
	(segment
		(start 285.553658 -117.938296)
		(end 285.301182 -118.190772)
		(width 0.14224)
		(layer "In4.Cu")
		(net "M_F_DQ<41>")
	)
	(segment
		(start 283.678122 -115.843812)
		(end 283.678122 -116.06276)
		(width 0.14224)
		(layer "In4.Cu")
		(net "M_F_DQ<41>")
	)
	(segment
		(start 292.0238 -134.0104)
		(end 291.915596 -134.118604)
		(width 0.14224)
		(layer "In4.Cu")
		(net "M_F_DQ<41>")
	)
	(segment
		(start 286.491426 -118.657116)
		(end 286.491426 -118.876064)
		(width 0.14224)
		(layer "In4.Cu")
		(net "M_F_DQ<41>")
	)
	(segment
		(start 280.862024 -106.720386)
		(end 280.862024 -107.09656)
		(width 0.0889)
		(layer "In4.Cu")
		(net "M_F_DQ<41>")
	)
	(segment
		(start 280.335228 -105.834434)
		(end 280.367994 -105.834434)
		(width 0.0889)
		(layer "In4.Cu")
		(net "M_F_DQ<41>")
	)
	(segment
		(start 286.24149 -118.40718)
		(end 286.491426 -118.657116)
		(width 0.14224)
		(layer "In4.Cu")
		(net "M_F_DQ<41>")
	)
	(segment
		(start 284.832298 -117.721888)
		(end 285.084774 -117.469412)
		(width 0.14224)
		(layer "In4.Cu")
		(net "M_F_DQ<41>")
	)
	(arc
		(start 279.998678 -103.261922)
		(mid 279.949923 -103.458274)
		(end 280.003504 -103.653336)
		(width 0.0889)
		(layer "In4.Cu")
		(net "M_F_DQ<41>")
	)
	(arc
		(start 279.998678 -105.243122)
		(mid 280.002425 -105.632378)
		(end 280.335228 -105.834434)
		(width 0.0889)
		(layer "In4.Cu")
		(net "M_F_DQ<41>")
	)
	(arc
		(start 280.003504 -101.672136)
		(mid 280.082726 -101.961254)
		(end 280.009854 -102.252018)
		(width 0.0889)
		(layer "In4.Cu")
		(net "M_F_DQ<41>")
	)
	(arc
		(start 280.003504 -103.653336)
		(mid 280.082726 -103.942454)
		(end 280.009854 -104.233218)
		(width 0.0889)
		(layer "In4.Cu")
		(net "M_F_DQ<41>")
	)
	(arc
		(start 280.367994 -105.834434)
		(mid 280.658815 -105.921021)
		(end 280.868374 -106.140504)
		(width 0.0889)
		(layer "In4.Cu")
		(net "M_F_DQ<41>")
	)
	(arc
		(start 280.003504 -102.662736)
		(mid 280.082726 -102.951854)
		(end 280.009854 -103.242618)
		(width 0.0889)
		(layer "In4.Cu")
		(net "M_F_DQ<41>")
	)
	(arc
		(start 280.003504 -104.643936)
		(mid 280.082726 -104.933054)
		(end 280.009854 -105.223818)
		(width 0.0889)
		(layer "In4.Cu")
		(net "M_F_DQ<41>")
	)
	(arc
		(start 280.003504 -96.319594)
		(mid 279.950005 -96.519492)
		(end 280.003504 -96.71939)
		(width 0.0889)
		(layer "In4.Cu")
		(net "M_F_DQ<41>")
	)
	(arc
		(start 280.003504 -97.70999)
		(mid 280.082635 -98.005392)
		(end 280.003504 -98.300794)
		(width 0.0889)
		(layer "In4.Cu")
		(net "M_F_DQ<41>")
	)
	(arc
		(start 280.868374 -106.140504)
		(mid 280.941172 -106.431267)
		(end 280.862024 -106.720386)
		(width 0.0889)
		(layer "In4.Cu")
		(net "M_F_DQ<41>")
	)
	(arc
		(start 280.003504 -99.291394)
		(mid 279.950005 -99.491292)
		(end 280.003504 -99.69119)
		(width 0.0889)
		(layer "In4.Cu")
		(net "M_F_DQ<41>")
	)
	(arc
		(start 280.003504 -100.681536)
		(mid 280.082726 -100.970654)
		(end 280.009854 -101.261418)
		(width 0.0889)
		(layer "In4.Cu")
		(net "M_F_DQ<41>")
	)
	(arc
		(start 280.066242 -96.16186)
		(mid 280.040581 -96.242999)
		(end 280.003504 -96.319594)
		(width 0.0889)
		(layer "In4.Cu")
		(net "M_F_DQ<41>")
	)
	(arc
		(start 280.003504 -98.70059)
		(mid 280.082635 -98.995992)
		(end 280.003504 -99.291394)
		(width 0.0889)
		(layer "In4.Cu")
		(net "M_F_DQ<41>")
	)
	(arc
		(start 279.998678 -102.271322)
		(mid 279.949923 -102.467674)
		(end 280.003504 -102.662736)
		(width 0.0889)
		(layer "In4.Cu")
		(net "M_F_DQ<41>")
	)
	(arc
		(start 279.998678 -104.252522)
		(mid 279.949923 -104.448874)
		(end 280.003504 -104.643936)
		(width 0.0889)
		(layer "In4.Cu")
		(net "M_F_DQ<41>")
	)
	(arc
		(start 279.998678 -100.290122)
		(mid 279.949923 -100.486474)
		(end 280.003504 -100.681536)
		(width 0.0889)
		(layer "In4.Cu")
		(net "M_F_DQ<41>")
	)
	(arc
		(start 280.003504 -99.69119)
		(mid 280.018999 -99.719758)
		(end 280.032968 -99.749102)
		(width 0.0889)
		(layer "In4.Cu")
		(net "M_F_DQ<41>")
	)
	(arc
		(start 280.003504 -98.300794)
		(mid 279.950005 -98.500692)
		(end 280.003504 -98.70059)
		(width 0.0889)
		(layer "In4.Cu")
		(net "M_F_DQ<41>")
	)
	(arc
		(start 280.003504 -96.71939)
		(mid 280.082635 -97.014792)
		(end 280.003504 -97.310194)
		(width 0.0889)
		(layer "In4.Cu")
		(net "M_F_DQ<41>")
	)
	(arc
		(start 280.003504 -97.310194)
		(mid 279.950005 -97.510092)
		(end 280.003504 -97.70999)
		(width 0.0889)
		(layer "In4.Cu")
		(net "M_F_DQ<41>")
	)
	(arc
		(start 279.998678 -101.280722)
		(mid 279.949923 -101.477074)
		(end 280.003504 -101.672136)
		(width 0.0889)
		(layer "In4.Cu")
		(net "M_F_DQ<41>")
	)
	(arc
		(start 280.032968 -99.749102)
		(mid 280.082202 -100.012664)
		(end 280.009854 -100.270818)
		(width 0.0889)
		(layer "In4.Cu")
		(net "M_F_DQ<41>")
	)
	(segment
		(start 291.399722 -149.533356)
		(end 291.422074 -149.533356)
		(width 0.14224)
		(layer "In11.Cu")
		(net "M_F_DQ<41>")
	)
	(segment
		(start 291.151056 -153.3906)
		(end 291.151056 -153.0858)
		(width 0.14224)
		(layer "In11.Cu")
		(net "M_F_DQ<41>")
	)
	(segment
		(start 290.91128 -151.316944)
		(end 291.201856 -151.026368)
		(width 0.14224)
		(layer "In11.Cu")
		(net "M_F_DQ<41>")
	)
	(segment
		(start 290.99891 -153.542746)
		(end 291.151056 -153.3906)
		(width 0.14224)
		(layer "In11.Cu")
		(net "M_F_DQ<41>")
	)
	(segment
		(start 290.74999 -153.542746)
		(end 290.99891 -153.542746)
		(width 0.14224)
		(layer "In11.Cu")
		(net "M_F_DQ<41>")
	)
	(segment
		(start 290.971478 -149.9616)
		(end 291.399722 -149.533356)
		(width 0.14224)
		(layer "In11.Cu")
		(net "M_F_DQ<41>")
	)
	(segment
		(start 290.971478 -150.391368)
		(end 290.971478 -149.9616)
		(width 0.14224)
		(layer "In11.Cu")
		(net "M_F_DQ<41>")
	)
	(segment
		(start 291.151056 -153.0858)
		(end 290.91128 -152.846024)
		(width 0.14224)
		(layer "In11.Cu")
		(net "M_F_DQ<41>")
	)
	(segment
		(start 291.125656 -151.892)
		(end 290.91128 -151.677624)
		(width 0.14224)
		(layer "In11.Cu")
		(net "M_F_DQ<41>")
	)
	(segment
		(start 291.201856 -151.026368)
		(end 291.201856 -150.621746)
		(width 0.14224)
		(layer "In11.Cu")
		(net "M_F_DQ<41>")
	)
	(segment
		(start 291.125656 -152.3238)
		(end 291.125656 -151.892)
		(width 0.14224)
		(layer "In11.Cu")
		(net "M_F_DQ<41>")
	)
	(segment
		(start 290.91128 -152.846024)
		(end 290.91128 -152.538176)
		(width 0.14224)
		(layer "In11.Cu")
		(net "M_F_DQ<41>")
	)
	(segment
		(start 290.91128 -151.677624)
		(end 290.91128 -151.316944)
		(width 0.14224)
		(layer "In11.Cu")
		(net "M_F_DQ<41>")
	)
	(segment
		(start 290.91128 -152.538176)
		(end 291.125656 -152.3238)
		(width 0.14224)
		(layer "In11.Cu")
		(net "M_F_DQ<41>")
	)
	(segment
		(start 291.201856 -150.621746)
		(end 290.971478 -150.391368)
		(width 0.14224)
		(layer "In11.Cu")
		(net "M_F_DQ<41>")
	)
	(segment
		(start 291.451284 -155.322778)
		(end 291.5158 -155.2448)
		(width 0.1651)
		(layer "F.Cu")
		(net "M_F_DQ<40>")
	)
	(segment
		(start 291.600382 -156.87294)
		(end 291.599874 -156.878782)
		(width 0.1651)
		(layer "F.Cu")
		(net "M_F_DQ<40>")
	)
	(segment
		(start 291.520372 -156.046932)
		(end 291.451284 -155.322778)
		(width 0.1651)
		(layer "F.Cu")
		(net "M_F_DQ<40>")
	)
	(segment
		(start 279.778714 -93.547184)
		(end 280.350214 -93.547184)
		(width 0.1651)
		(layer "F.Cu")
		(net "M_F_DQ<40>")
	)
	(segment
		(start 291.599874 -156.878782)
		(end 291.520372 -156.046932)
		(width 0.1651)
		(layer "F.Cu")
		(net "M_F_DQ<40>")
	)
	(via
		(at 280.350214 -93.547184)
		(size 0.508)
		(drill 0.254)
		(layers "F.Cu" "B.Cu")
		(net "M_F_DQ<40>")
	)
	(via
		(at 290.74999 -150.814278)
		(size 0.508)
		(drill 0.254)
		(layers "F.Cu" "B.Cu")
		(net "M_F_DQ<40>")
	)
	(via
		(at 291.5158 -155.2448)
		(size 0.508)
		(drill 0.254)
		(layers "F.Cu" "B.Cu")
		(net "M_F_DQ<40>")
	)
	(segment
		(start 290.74999 -152.078182)
		(end 290.74999 -150.814278)
		(width 0.1651)
		(layer "B.Cu")
		(net "M_F_DQ<40>")
	)
	(segment
		(start 290.750498 -152.078436)
		(end 290.74999 -152.078182)
		(width 0.1651)
		(layer "B.Cu")
		(net "M_F_DQ<40>")
	)
	(segment
		(start 280.621232 -106.948224)
		(end 280.3779 -107.191556)
		(width 0.0889)
		(layer "In4.Cu")
		(net "M_F_DQ<40>")
	)
	(segment
		(start 279.84323 -105.1306)
		(end 279.838404 -105.139236)
		(width 0.0889)
		(layer "In4.Cu")
		(net "M_F_DQ<40>")
	)
	(segment
		(start 291.275008 -134.428992)
		(end 290.932108 -134.771892)
		(width 0.14224)
		(layer "In4.Cu")
		(net "M_F_DQ<40>")
	)
	(segment
		(start 291.236908 -145.847562)
		(end 291.236908 -148.960078)
		(width 0.14224)
		(layer "In4.Cu")
		(net "M_F_DQ<40>")
	)
	(segment
		(start 291.275008 -134.176008)
		(end 291.275008 -134.428992)
		(width 0.14224)
		(layer "In4.Cu")
		(net "M_F_DQ<40>")
	)
	(segment
		(start 279.838404 -103.158036)
		(end 279.832054 -103.168704)
		(width 0.0889)
		(layer "In4.Cu")
		(net "M_F_DQ<40>")
	)
	(segment
		(start 291.1856 -143.7132)
		(end 291.224208 -143.751808)
		(width 0.14224)
		(layer "In4.Cu")
		(net "M_F_DQ<40>")
	)
	(segment
		(start 290.7792 -125.4506)
		(end 291.229796 -125.901196)
		(width 0.14224)
		(layer "In4.Cu")
		(net "M_F_DQ<40>")
	)
	(segment
		(start 291.275008 -131.484878)
		(end 291.275008 -131.9022)
		(width 0.14224)
		(layer "In4.Cu")
		(net "M_F_DQ<40>")
	)
	(segment
		(start 280.3779 -107.191556)
		(end 280.3779 -113.297462)
		(width 0.14224)
		(layer "In4.Cu")
		(net "M_F_DQ<40>")
	)
	(segment
		(start 279.84323 -101.1682)
		(end 279.838404 -101.176836)
		(width 0.0889)
		(layer "In4.Cu")
		(net "M_F_DQ<40>")
	)
	(segment
		(start 282.755086 -116.685314)
		(end 288.918142 -122.84837)
		(width 0.14224)
		(layer "In4.Cu")
		(net "M_F_DQ<40>")
	)
	(segment
		(start 290.932108 -135.941308)
		(end 291.275008 -136.284208)
		(width 0.14224)
		(layer "In4.Cu")
		(net "M_F_DQ<40>")
	)
	(segment
		(start 291.275008 -138.773408)
		(end 291.275008 -139.320778)
		(width 0.14224)
		(layer "In4.Cu")
		(net "M_F_DQ<40>")
	)
	(segment
		(start 279.84323 -100.1776)
		(end 279.838404 -100.186236)
		(width 0.0889)
		(layer "In4.Cu")
		(net "M_F_DQ<40>")
	)
	(segment
		(start 280.621232 -106.67746)
		(end 280.621232 -106.948224)
		(width 0.0889)
		(layer "In4.Cu")
		(net "M_F_DQ<40>")
	)
	(segment
		(start 291.229796 -126.90094)
		(end 291.592 -127.263144)
		(width 0.14224)
		(layer "In4.Cu")
		(net "M_F_DQ<40>")
	)
	(segment
		(start 279.838404 -102.167436)
		(end 279.832054 -102.178104)
		(width 0.0889)
		(layer "In4.Cu")
		(net "M_F_DQ<40>")
	)
	(segment
		(start 291.275008 -136.5758)
		(end 291.0078 -136.843008)
		(width 0.14224)
		(layer "In4.Cu")
		(net "M_F_DQ<40>")
	)
	(segment
		(start 279.84323 -102.1588)
		(end 279.838404 -102.167436)
		(width 0.0889)
		(layer "In4.Cu")
		(net "M_F_DQ<40>")
	)
	(segment
		(start 291.1094 -134.0104)
		(end 291.275008 -134.176008)
		(width 0.14224)
		(layer "In4.Cu")
		(net "M_F_DQ<40>")
	)
	(segment
		(start 279.969722 -95.005906)
		(end 279.838404 -95.23349)
		(width 0.0889)
		(layer "In4.Cu")
		(net "M_F_DQ<40>")
	)
	(segment
		(start 291.236908 -148.960078)
		(end 290.74999 -149.446996)
		(width 0.14224)
		(layer "In4.Cu")
		(net "M_F_DQ<40>")
	)
	(segment
		(start 291.229796 -129.76479)
		(end 290.932108 -130.062478)
		(width 0.14224)
		(layer "In4.Cu")
		(net "M_F_DQ<40>")
	)
	(segment
		(start 279.838404 -105.139236)
		(end 279.832054 -105.149904)
		(width 0.0889)
		(layer "In4.Cu")
		(net "M_F_DQ<40>")
	)
	(segment
		(start 291.2364 -141.04747)
		(end 291.2364 -141.542008)
		(width 0.14224)
		(layer "In4.Cu")
		(net "M_F_DQ<40>")
	)
	(segment
		(start 290.932108 -140.743178)
		(end 291.2364 -141.04747)
		(width 0.14224)
		(layer "In4.Cu")
		(net "M_F_DQ<40>")
	)
	(segment
		(start 291.1094 -132.067808)
		(end 291.1094 -134.0104)
		(width 0.14224)
		(layer "In4.Cu")
		(net "M_F_DQ<40>")
	)
	(segment
		(start 290.932108 -139.663678)
		(end 290.932108 -140.743178)
		(width 0.14224)
		(layer "In4.Cu")
		(net "M_F_DQ<40>")
	)
	(segment
		(start 291.1856 -141.592808)
		(end 291.1856 -143.7132)
		(width 0.14224)
		(layer "In4.Cu")
		(net "M_F_DQ<40>")
	)
	(segment
		(start 291.275008 -136.284208)
		(end 291.275008 -136.5758)
		(width 0.14224)
		(layer "In4.Cu")
		(net "M_F_DQ<40>")
	)
	(segment
		(start 291.0078 -136.843008)
		(end 291.0078 -138.5062)
		(width 0.14224)
		(layer "In4.Cu")
		(net "M_F_DQ<40>")
	)
	(segment
		(start 280.328624 -106.024934)
		(end 280.36139 -106.024934)
		(width 0.0889)
		(layer "In4.Cu")
		(net "M_F_DQ<40>")
	)
	(segment
		(start 279.84323 -104.14)
		(end 279.838404 -104.148636)
		(width 0.0889)
		(layer "In4.Cu")
		(net "M_F_DQ<40>")
	)
	(segment
		(start 279.838404 -101.176836)
		(end 279.832054 -101.187504)
		(width 0.0889)
		(layer "In4.Cu")
		(net "M_F_DQ<40>")
	)
	(segment
		(start 291.229796 -125.901196)
		(end 291.229796 -126.90094)
		(width 0.14224)
		(layer "In4.Cu")
		(net "M_F_DQ<40>")
	)
	(segment
		(start 291.275008 -139.320778)
		(end 290.932108 -139.663678)
		(width 0.14224)
		(layer "In4.Cu")
		(net "M_F_DQ<40>")
	)
	(segment
		(start 290.74999 -149.446996)
		(end 290.74999 -150.814278)
		(width 0.14224)
		(layer "In4.Cu")
		(net "M_F_DQ<40>")
	)
	(segment
		(start 289.268916 -122.84837)
		(end 290.7792 -124.358654)
		(width 0.14224)
		(layer "In4.Cu")
		(net "M_F_DQ<40>")
	)
	(segment
		(start 291.592 -128.8542)
		(end 291.229796 -129.216404)
		(width 0.14224)
		(layer "In4.Cu")
		(net "M_F_DQ<40>")
	)
	(segment
		(start 291.224208 -143.751808)
		(end 291.224208 -144.080738)
		(width 0.14224)
		(layer "In4.Cu")
		(net "M_F_DQ<40>")
	)
	(segment
		(start 290.932108 -130.062478)
		(end 290.932108 -131.141978)
		(width 0.14224)
		(layer "In4.Cu")
		(net "M_F_DQ<40>")
	)
	(segment
		(start 279.838404 -100.186236)
		(end 279.832054 -100.196904)
		(width 0.0889)
		(layer "In4.Cu")
		(net "M_F_DQ<40>")
	)
	(segment
		(start 291.592 -127.263144)
		(end 291.592 -128.8542)
		(width 0.14224)
		(layer "In4.Cu")
		(net "M_F_DQ<40>")
	)
	(segment
		(start 290.7792 -124.358654)
		(end 290.7792 -125.4506)
		(width 0.14224)
		(layer "In4.Cu")
		(net "M_F_DQ<40>")
	)
	(segment
		(start 291.229796 -129.216404)
		(end 291.229796 -129.76479)
		(width 0.14224)
		(layer "In4.Cu")
		(net "M_F_DQ<40>")
	)
	(segment
		(start 288.918142 -122.84837)
		(end 289.268916 -122.84837)
		(width 0.14224)
		(layer "In4.Cu")
		(net "M_F_DQ<40>")
	)
	(segment
		(start 290.932108 -134.771892)
		(end 290.932108 -135.941308)
		(width 0.14224)
		(layer "In4.Cu")
		(net "M_F_DQ<40>")
	)
	(segment
		(start 279.84323 -103.1494)
		(end 279.838404 -103.158036)
		(width 0.0889)
		(layer "In4.Cu")
		(net "M_F_DQ<40>")
	)
	(segment
		(start 291.224208 -144.080738)
		(end 290.944808 -144.360138)
		(width 0.14224)
		(layer "In4.Cu")
		(net "M_F_DQ<40>")
	)
	(segment
		(start 290.944808 -144.360138)
		(end 290.944808 -145.555462)
		(width 0.14224)
		(layer "In4.Cu")
		(net "M_F_DQ<40>")
	)
	(segment
		(start 280.061162 -94.200726)
		(end 280.350214 -93.547184)
		(width 0.0889)
		(layer "In4.Cu")
		(net "M_F_DQ<40>")
	)
	(segment
		(start 290.944808 -145.555462)
		(end 291.236908 -145.847562)
		(width 0.14224)
		(layer "In4.Cu")
		(net "M_F_DQ<40>")
	)
	(segment
		(start 291.2364 -141.542008)
		(end 291.1856 -141.592808)
		(width 0.14224)
		(layer "In4.Cu")
		(net "M_F_DQ<40>")
	)
	(segment
		(start 282.755086 -115.674648)
		(end 282.755086 -116.685314)
		(width 0.14224)
		(layer "In4.Cu")
		(net "M_F_DQ<40>")
	)
	(segment
		(start 291.275008 -131.9022)
		(end 291.1094 -132.067808)
		(width 0.14224)
		(layer "In4.Cu")
		(net "M_F_DQ<40>")
	)
	(segment
		(start 291.0078 -138.5062)
		(end 291.275008 -138.773408)
		(width 0.14224)
		(layer "In4.Cu")
		(net "M_F_DQ<40>")
	)
	(segment
		(start 290.932108 -131.141978)
		(end 291.275008 -131.484878)
		(width 0.14224)
		(layer "In4.Cu")
		(net "M_F_DQ<40>")
	)
	(segment
		(start 279.838404 -104.148636)
		(end 279.832054 -104.159304)
		(width 0.0889)
		(layer "In4.Cu")
		(net "M_F_DQ<40>")
	)
	(segment
		(start 280.3779 -113.297462)
		(end 282.755086 -115.674648)
		(width 0.14224)
		(layer "In4.Cu")
		(net "M_F_DQ<40>")
	)
	(arc
		(start 280.36139 -106.024934)
		(mid 280.706005 -106.265718)
		(end 280.621232 -106.67746)
		(width 0.0889)
		(layer "In4.Cu")
		(net "M_F_DQ<40>")
	)
	(arc
		(start 279.838404 -102.757986)
		(mid 279.891874 -102.953049)
		(end 279.84323 -103.1494)
		(width 0.0889)
		(layer "In4.Cu")
		(net "M_F_DQ<40>")
	)
	(arc
		(start 279.838404 -101.767386)
		(mid 279.891874 -101.962449)
		(end 279.84323 -102.1588)
		(width 0.0889)
		(layer "In4.Cu")
		(net "M_F_DQ<40>")
	)
	(arc
		(start 279.838404 -95.23349)
		(mid 279.759273 -95.528892)
		(end 279.838404 -95.824294)
		(width 0.0889)
		(layer "In4.Cu")
		(net "M_F_DQ<40>")
	)
	(arc
		(start 280.003504 -94.338394)
		(mid 280.036712 -94.271393)
		(end 280.061162 -94.200726)
		(width 0.0889)
		(layer "In4.Cu")
		(net "M_F_DQ<40>")
	)
	(arc
		(start 279.838404 -100.776786)
		(mid 279.891874 -100.971849)
		(end 279.84323 -101.1682)
		(width 0.0889)
		(layer "In4.Cu")
		(net "M_F_DQ<40>")
	)
	(arc
		(start 279.832054 -101.187504)
		(mid 279.759256 -101.478267)
		(end 279.838404 -101.767386)
		(width 0.0889)
		(layer "In4.Cu")
		(net "M_F_DQ<40>")
	)
	(arc
		(start 279.985216 -94.702376)
		(mid 279.950536 -94.518186)
		(end 280.003504 -94.338394)
		(width 0.0889)
		(layer "In4.Cu")
		(net "M_F_DQ<40>")
	)
	(arc
		(start 279.832054 -100.196904)
		(mid 279.759256 -100.487667)
		(end 279.838404 -100.776786)
		(width 0.0889)
		(layer "In4.Cu")
		(net "M_F_DQ<40>")
	)
	(arc
		(start 279.969722 -95.005906)
		(mid 280.014071 -94.856011)
		(end 279.985216 -94.702376)
		(width 0.0889)
		(layer "In4.Cu")
		(net "M_F_DQ<40>")
	)
	(arc
		(start 279.857708 -99.824286)
		(mid 279.891646 -100.00264)
		(end 279.84323 -100.1776)
		(width 0.0889)
		(layer "In4.Cu")
		(net "M_F_DQ<40>")
	)
	(arc
		(start 279.838404 -96.22409)
		(mid 279.759273 -96.519492)
		(end 279.838404 -96.814894)
		(width 0.0889)
		(layer "In4.Cu")
		(net "M_F_DQ<40>")
	)
	(arc
		(start 279.838404 -97.805494)
		(mid 279.891903 -98.005392)
		(end 279.838404 -98.20529)
		(width 0.0889)
		(layer "In4.Cu")
		(net "M_F_DQ<40>")
	)
	(arc
		(start 279.838404 -99.786694)
		(mid 279.848599 -99.805211)
		(end 279.857708 -99.824286)
		(width 0.0889)
		(layer "In4.Cu")
		(net "M_F_DQ<40>")
	)
	(arc
		(start 279.832054 -105.149904)
		(mid 279.836085 -105.726086)
		(end 280.328624 -106.024934)
		(width 0.0889)
		(layer "In4.Cu")
		(net "M_F_DQ<40>")
	)
	(arc
		(start 279.838404 -98.796094)
		(mid 279.891903 -98.995992)
		(end 279.838404 -99.19589)
		(width 0.0889)
		(layer "In4.Cu")
		(net "M_F_DQ<40>")
	)
	(arc
		(start 279.838404 -97.21469)
		(mid 279.759273 -97.510092)
		(end 279.838404 -97.805494)
		(width 0.0889)
		(layer "In4.Cu")
		(net "M_F_DQ<40>")
	)
	(arc
		(start 279.832054 -103.168704)
		(mid 279.759256 -103.459467)
		(end 279.838404 -103.748586)
		(width 0.0889)
		(layer "In4.Cu")
		(net "M_F_DQ<40>")
	)
	(arc
		(start 279.838404 -99.19589)
		(mid 279.759273 -99.491292)
		(end 279.838404 -99.786694)
		(width 0.0889)
		(layer "In4.Cu")
		(net "M_F_DQ<40>")
	)
	(arc
		(start 279.832054 -102.178104)
		(mid 279.759256 -102.468867)
		(end 279.838404 -102.757986)
		(width 0.0889)
		(layer "In4.Cu")
		(net "M_F_DQ<40>")
	)
	(arc
		(start 279.838404 -103.748586)
		(mid 279.891874 -103.943649)
		(end 279.84323 -104.14)
		(width 0.0889)
		(layer "In4.Cu")
		(net "M_F_DQ<40>")
	)
	(arc
		(start 279.832054 -104.159304)
		(mid 279.759256 -104.450067)
		(end 279.838404 -104.739186)
		(width 0.0889)
		(layer "In4.Cu")
		(net "M_F_DQ<40>")
	)
	(arc
		(start 279.838404 -95.824294)
		(mid 279.891903 -96.024192)
		(end 279.838404 -96.22409)
		(width 0.0889)
		(layer "In4.Cu")
		(net "M_F_DQ<40>")
	)
	(arc
		(start 279.838404 -98.20529)
		(mid 279.759273 -98.500692)
		(end 279.838404 -98.796094)
		(width 0.0889)
		(layer "In4.Cu")
		(net "M_F_DQ<40>")
	)
	(arc
		(start 279.838404 -104.739186)
		(mid 279.891874 -104.934249)
		(end 279.84323 -105.1306)
		(width 0.0889)
		(layer "In4.Cu")
		(net "M_F_DQ<40>")
	)
	(arc
		(start 279.838404 -96.814894)
		(mid 279.891903 -97.014792)
		(end 279.838404 -97.21469)
		(width 0.0889)
		(layer "In4.Cu")
		(net "M_F_DQ<40>")
	)
	(segment
		(start 290.31692 -154.04592)
		(end 290.31692 -151.247348)
		(width 0.14224)
		(layer "In11.Cu")
		(net "M_F_DQ<40>")
	)
	(segment
		(start 291.5158 -155.2448)
		(end 290.31692 -154.04592)
		(width 0.14224)
		(layer "In11.Cu")
		(net "M_F_DQ<40>")
	)
	(segment
		(start 290.31692 -151.247348)
		(end 290.74999 -150.814278)
		(width 0.14224)
		(layer "In11.Cu")
		(net "M_F_DQ<40>")
	)
	(segment
		(start 204.050392 -152.273)
		(end 204.049884 -152.278842)
		(width 0.1651)
		(layer "F.Cu")
		(net "M_F_DQ<3>")
	)
	(segment
		(start 204.049884 -152.278842)
		(end 204.049884 -153.542746)
		(width 0.1651)
		(layer "F.Cu")
		(net "M_F_DQ<3>")
	)
	(segment
		(start 240.476278 -87.784686)
		(end 239.904778 -87.784686)
		(width 0.1651)
		(layer "F.Cu")
		(net "M_F_DQ<3>")
	)
	(via
		(at 239.904778 -87.784686)
		(size 0.508)
		(drill 0.254)
		(layers "F.Cu" "B.Cu")
		(net "M_F_DQ<3>")
	)
	(via
		(at 204.899768 -149.533356)
		(size 0.508)
		(drill 0.254)
		(layers "F.Cu" "B.Cu")
		(net "M_F_DQ<3>")
	)
	(via
		(at 204.049884 -153.542746)
		(size 0.508)
		(drill 0.254)
		(layers "F.Cu" "B.Cu")
		(net "M_F_DQ<3>")
	)
	(segment
		(start 204.899768 -147.478496)
		(end 204.899768 -149.533356)
		(width 0.1651)
		(layer "B.Cu")
		(net "M_F_DQ<3>")
	)
	(segment
		(start 204.900276 -147.478496)
		(end 204.899768 -147.478496)
		(width 0.1651)
		(layer "B.Cu")
		(net "M_F_DQ<3>")
	)
	(segment
		(start 205.1812 -131.49453)
		(end 205.1812 -132.205984)
		(width 0.14224)
		(layer "In11.Cu")
		(net "M_F_DQ<3>")
	)
	(segment
		(start 205.3336 -120.607836)
		(end 205.3336 -121.116852)
		(width 0.14224)
		(layer "In11.Cu")
		(net "M_F_DQ<3>")
	)
	(segment
		(start 205.637384 -124.671836)
		(end 205.637384 -125.180852)
		(width 0.14224)
		(layer "In11.Cu")
		(net "M_F_DQ<3>")
	)
	(segment
		(start 228.098858 -92.296742)
		(end 221.5642 -98.8314)
		(width 0.14224)
		(layer "In11.Cu")
		(net "M_F_DQ<3>")
	)
	(segment
		(start 221.5642 -100.964746)
		(end 211.230464 -111.298482)
		(width 0.14224)
		(layer "In11.Cu")
		(net "M_F_DQ<3>")
	)
	(segment
		(start 205.3336 -117.195346)
		(end 205.3336 -117.865652)
		(width 0.14224)
		(layer "In11.Cu")
		(net "M_F_DQ<3>")
	)
	(segment
		(start 205.356206 -114.873532)
		(end 205.356206 -115.16106)
		(width 0.14224)
		(layer "In11.Cu")
		(net "M_F_DQ<3>")
	)
	(segment
		(start 205.3336 -119.491252)
		(end 205.637384 -119.795036)
		(width 0.14224)
		(layer "In11.Cu")
		(net "M_F_DQ<3>")
	)
	(segment
		(start 205.2066 -139.514326)
		(end 205.406752 -139.714478)
		(width 0.14224)
		(layer "In11.Cu")
		(net "M_F_DQ<3>")
	)
	(segment
		(start 204.899768 -149.546564)
		(end 204.899768 -149.533356)
		(width 0.14224)
		(layer "In11.Cu")
		(net "M_F_DQ<3>")
	)
	(segment
		(start 221.5642 -98.8314)
		(end 221.5642 -100.964746)
		(width 0.14224)
		(layer "In11.Cu")
		(net "M_F_DQ<3>")
	)
	(segment
		(start 205.3336 -124.368052)
		(end 205.637384 -124.671836)
		(width 0.14224)
		(layer "In11.Cu")
		(net "M_F_DQ<3>")
	)
	(segment
		(start 205.406752 -131.268978)
		(end 205.1812 -131.49453)
		(width 0.14224)
		(layer "In11.Cu")
		(net "M_F_DQ<3>")
	)
	(segment
		(start 228.53777 -92.057474)
		(end 228.298502 -92.296742)
		(width 0.0889)
		(layer "In11.Cu")
		(net "M_F_DQ<3>")
	)
	(segment
		(start 209.793332 -110.436406)
		(end 205.356206 -114.873532)
		(width 0.14224)
		(layer "In11.Cu")
		(net "M_F_DQ<3>")
	)
	(segment
		(start 209.83448 -111.544862)
		(end 210.122008 -111.544862)
		(width 0.14224)
		(layer "In11.Cu")
		(net "M_F_DQ<3>")
	)
	(segment
		(start 210.942936 -111.298482)
		(end 210.08086 -110.436406)
		(width 0.14224)
		(layer "In11.Cu")
		(net "M_F_DQ<3>")
	)
	(segment
		(start 205.637384 -126.797816)
		(end 205.080362 -127.354838)
		(width 0.14224)
		(layer "In11.Cu")
		(net "M_F_DQ<3>")
	)
	(segment
		(start 205.228952 -146.5072)
		(end 205.4606 -146.738848)
		(width 0.14224)
		(layer "In11.Cu")
		(net "M_F_DQ<3>")
	)
	(segment
		(start 233.058208 -91.347036)
		(end 232.777538 -91.347036)
		(width 0.0889)
		(layer "In11.Cu")
		(net "M_F_DQ<3>")
	)
	(segment
		(start 205.267052 -141.009878)
		(end 205.267052 -141.9352)
		(width 0.14224)
		(layer "In11.Cu")
		(net "M_F_DQ<3>")
	)
	(segment
		(start 205.3336 -122.742452)
		(end 205.637384 -123.046236)
		(width 0.14224)
		(layer "In11.Cu")
		(net "M_F_DQ<3>")
	)
	(segment
		(start 205.2066 -136.2964)
		(end 205.2066 -137.0584)
		(width 0.14224)
		(layer "In11.Cu")
		(net "M_F_DQ<3>")
	)
	(segment
		(start 234.775248 -90.356436)
		(end 234.742482 -90.356436)
		(width 0.0889)
		(layer "In11.Cu")
		(net "M_F_DQ<3>")
	)
	(segment
		(start 236.492288 -89.365836)
		(end 236.459522 -89.365836)
		(width 0.0889)
		(layer "In11.Cu")
		(net "M_F_DQ<3>")
	)
	(segment
		(start 232.777538 -91.347036)
		(end 232.504488 -91.620086)
		(width 0.0889)
		(layer "In11.Cu")
		(net "M_F_DQ<3>")
	)
	(segment
		(start 205.637384 -119.795036)
		(end 205.637384 -120.304052)
		(width 0.14224)
		(layer "In11.Cu")
		(net "M_F_DQ<3>")
	)
	(segment
		(start 205.267052 -144.182338)
		(end 205.482952 -144.398238)
		(width 0.14224)
		(layer "In11.Cu")
		(net "M_F_DQ<3>")
	)
	(segment
		(start 205.406752 -139.714478)
		(end 205.406752 -140.870178)
		(width 0.14224)
		(layer "In11.Cu")
		(net "M_F_DQ<3>")
	)
	(segment
		(start 205.1812 -132.205984)
		(end 205.4606 -132.485384)
		(width 0.14224)
		(layer "In11.Cu")
		(net "M_F_DQ<3>")
	)
	(segment
		(start 205.931008 -115.448334)
		(end 209.83448 -111.544862)
		(width 0.14224)
		(layer "In11.Cu")
		(net "M_F_DQ<3>")
	)
	(segment
		(start 205.64348 -115.448334)
		(end 205.931008 -115.448334)
		(width 0.14224)
		(layer "In11.Cu")
		(net "M_F_DQ<3>")
	)
	(segment
		(start 205.5622 -142.910052)
		(end 205.267052 -143.2052)
		(width 0.14224)
		(layer "In11.Cu")
		(net "M_F_DQ<3>")
	)
	(segment
		(start 205.5114 -137.3632)
		(end 205.5114 -137.9982)
		(width 0.14224)
		(layer "In11.Cu")
		(net "M_F_DQ<3>")
	)
	(segment
		(start 205.080362 -129.786888)
		(end 205.406752 -130.113278)
		(width 0.14224)
		(layer "In11.Cu")
		(net "M_F_DQ<3>")
	)
	(segment
		(start 210.409282 -111.832136)
		(end 210.409282 -112.119664)
		(width 0.14224)
		(layer "In11.Cu")
		(net "M_F_DQ<3>")
	)
	(segment
		(start 204.468222 -152.2222)
		(end 204.211174 -152.479248)
		(width 0.14224)
		(layer "In11.Cu")
		(net "M_F_DQ<3>")
	)
	(segment
		(start 205.3336 -118.982236)
		(end 205.3336 -119.491252)
		(width 0.14224)
		(layer "In11.Cu")
		(net "M_F_DQ<3>")
	)
	(segment
		(start 205.3336 -123.859036)
		(end 205.3336 -124.368052)
		(width 0.14224)
		(layer "In11.Cu")
		(net "M_F_DQ<3>")
	)
	(segment
		(start 231.746552 -91.620086)
		(end 231.309164 -92.057474)
		(width 0.0889)
		(layer "In11.Cu")
		(net "M_F_DQ<3>")
	)
	(segment
		(start 205.406752 -130.113278)
		(end 205.406752 -131.268978)
		(width 0.14224)
		(layer "In11.Cu")
		(net "M_F_DQ<3>")
	)
	(segment
		(start 211.230464 -111.298482)
		(end 210.942936 -111.298482)
		(width 0.14224)
		(layer "In11.Cu")
		(net "M_F_DQ<3>")
	)
	(segment
		(start 205.432152 -136.070848)
		(end 205.2066 -136.2964)
		(width 0.14224)
		(layer "In11.Cu")
		(net "M_F_DQ<3>")
	)
	(segment
		(start 205.637384 -121.420636)
		(end 205.637384 -121.929652)
		(width 0.14224)
		(layer "In11.Cu")
		(net "M_F_DQ<3>")
	)
	(segment
		(start 210.08086 -110.436406)
		(end 209.793332 -110.436406)
		(width 0.14224)
		(layer "In11.Cu")
		(net "M_F_DQ<3>")
	)
	(segment
		(start 205.3336 -125.993652)
		(end 205.637384 -126.297436)
		(width 0.14224)
		(layer "In11.Cu")
		(net "M_F_DQ<3>")
	)
	(segment
		(start 235.629958 -89.86139)
		(end 235.597192 -89.86139)
		(width 0.0889)
		(layer "In11.Cu")
		(net "M_F_DQ<3>")
	)
	(segment
		(start 204.449172 -149.9616)
		(end 204.449172 -150.391368)
		(width 0.14224)
		(layer "In11.Cu")
		(net "M_F_DQ<3>")
	)
	(segment
		(start 238.209328 -88.375236)
		(end 238.176562 -88.375236)
		(width 0.0889)
		(layer "In11.Cu")
		(net "M_F_DQ<3>")
	)
	(segment
		(start 205.637384 -126.297436)
		(end 205.637384 -126.797816)
		(width 0.14224)
		(layer "In11.Cu")
		(net "M_F_DQ<3>")
	)
	(segment
		(start 231.309164 -92.057474)
		(end 228.53777 -92.057474)
		(width 0.0889)
		(layer "In11.Cu")
		(net "M_F_DQ<3>")
	)
	(segment
		(start 204.493622 -151.1046)
		(end 204.211174 -151.387048)
		(width 0.14224)
		(layer "In11.Cu")
		(net "M_F_DQ<3>")
	)
	(segment
		(start 205.228952 -145.799048)
		(end 205.228952 -146.5072)
		(width 0.14224)
		(layer "In11.Cu")
		(net "M_F_DQ<3>")
	)
	(segment
		(start 239.082326 -87.88019)
		(end 239.031272 -87.88019)
		(width 0.0889)
		(layer "In11.Cu")
		(net "M_F_DQ<3>")
	)
	(segment
		(start 210.409282 -112.119664)
		(end 205.3336 -117.195346)
		(width 0.14224)
		(layer "In11.Cu")
		(net "M_F_DQ<3>")
	)
	(segment
		(start 205.3336 -117.865652)
		(end 205.637384 -118.169436)
		(width 0.14224)
		(layer "In11.Cu")
		(net "M_F_DQ<3>")
	)
	(segment
		(start 204.493622 -150.435818)
		(end 204.493622 -151.1046)
		(width 0.14224)
		(layer "In11.Cu")
		(net "M_F_DQ<3>")
	)
	(segment
		(start 205.2066 -138.303)
		(end 205.2066 -139.514326)
		(width 0.14224)
		(layer "In11.Cu")
		(net "M_F_DQ<3>")
	)
	(segment
		(start 204.899768 -149.533356)
		(end 204.877416 -149.533356)
		(width 0.14224)
		(layer "In11.Cu")
		(net "M_F_DQ<3>")
	)
	(segment
		(start 205.5622 -142.230348)
		(end 205.5622 -142.910052)
		(width 0.14224)
		(layer "In11.Cu")
		(net "M_F_DQ<3>")
	)
	(segment
		(start 205.637384 -121.929652)
		(end 205.3336 -122.233436)
		(width 0.14224)
		(layer "In11.Cu")
		(net "M_F_DQ<3>")
	)
	(segment
		(start 205.637384 -120.304052)
		(end 205.3336 -120.607836)
		(width 0.14224)
		(layer "In11.Cu")
		(net "M_F_DQ<3>")
	)
	(segment
		(start 205.4606 -147.697952)
		(end 205.228952 -147.9296)
		(width 0.14224)
		(layer "In11.Cu")
		(net "M_F_DQ<3>")
	)
	(segment
		(start 228.298502 -92.296742)
		(end 228.098858 -92.296742)
		(width 0.14224)
		(layer "In11.Cu")
		(net "M_F_DQ<3>")
	)
	(segment
		(start 205.4606 -146.738848)
		(end 205.4606 -147.697952)
		(width 0.14224)
		(layer "In11.Cu")
		(net "M_F_DQ<3>")
	)
	(segment
		(start 205.637384 -118.678452)
		(end 205.3336 -118.982236)
		(width 0.14224)
		(layer "In11.Cu")
		(net "M_F_DQ<3>")
	)
	(segment
		(start 205.267052 -143.2052)
		(end 205.267052 -144.182338)
		(width 0.14224)
		(layer "In11.Cu")
		(net "M_F_DQ<3>")
	)
	(segment
		(start 204.211174 -151.387048)
		(end 204.211174 -151.660352)
		(width 0.14224)
		(layer "In11.Cu")
		(net "M_F_DQ<3>")
	)
	(segment
		(start 210.122008 -111.544862)
		(end 210.409282 -111.832136)
		(width 0.14224)
		(layer "In11.Cu")
		(net "M_F_DQ<3>")
	)
	(segment
		(start 205.1812 -133.135624)
		(end 205.1812 -134.487412)
		(width 0.14224)
		(layer "In11.Cu")
		(net "M_F_DQ<3>")
	)
	(segment
		(start 204.877416 -149.533356)
		(end 204.449172 -149.9616)
		(width 0.14224)
		(layer "In11.Cu")
		(net "M_F_DQ<3>")
	)
	(segment
		(start 205.356206 -115.16106)
		(end 205.64348 -115.448334)
		(width 0.14224)
		(layer "In11.Cu")
		(net "M_F_DQ<3>")
	)
	(segment
		(start 205.228952 -149.21738)
		(end 204.899768 -149.546564)
		(width 0.14224)
		(layer "In11.Cu")
		(net "M_F_DQ<3>")
	)
	(segment
		(start 205.482952 -144.398238)
		(end 205.482952 -145.545048)
		(width 0.14224)
		(layer "In11.Cu")
		(net "M_F_DQ<3>")
	)
	(segment
		(start 205.482952 -145.545048)
		(end 205.228952 -145.799048)
		(width 0.14224)
		(layer "In11.Cu")
		(net "M_F_DQ<3>")
	)
	(segment
		(start 205.432152 -134.738364)
		(end 205.432152 -136.070848)
		(width 0.14224)
		(layer "In11.Cu")
		(net "M_F_DQ<3>")
	)
	(segment
		(start 205.406752 -140.870178)
		(end 205.267052 -141.009878)
		(width 0.14224)
		(layer "In11.Cu")
		(net "M_F_DQ<3>")
	)
	(segment
		(start 205.5114 -137.9982)
		(end 205.2066 -138.303)
		(width 0.14224)
		(layer "In11.Cu")
		(net "M_F_DQ<3>")
	)
	(segment
		(start 205.2066 -137.0584)
		(end 205.5114 -137.3632)
		(width 0.14224)
		(layer "In11.Cu")
		(net "M_F_DQ<3>")
	)
	(segment
		(start 232.504488 -91.620086)
		(end 231.746552 -91.620086)
		(width 0.0889)
		(layer "In11.Cu")
		(net "M_F_DQ<3>")
	)
	(segment
		(start 205.3336 -122.233436)
		(end 205.3336 -122.742452)
		(width 0.14224)
		(layer "In11.Cu")
		(net "M_F_DQ<3>")
	)
	(segment
		(start 205.1812 -134.487412)
		(end 205.432152 -134.738364)
		(width 0.14224)
		(layer "In11.Cu")
		(net "M_F_DQ<3>")
	)
	(segment
		(start 205.3336 -125.484636)
		(end 205.3336 -125.993652)
		(width 0.14224)
		(layer "In11.Cu")
		(net "M_F_DQ<3>")
	)
	(segment
		(start 204.211174 -152.752552)
		(end 204.499972 -153.04135)
		(width 0.14224)
		(layer "In11.Cu")
		(net "M_F_DQ<3>")
	)
	(segment
		(start 205.228952 -147.9296)
		(end 205.228952 -149.21738)
		(width 0.14224)
		(layer "In11.Cu")
		(net "M_F_DQ<3>")
	)
	(segment
		(start 204.499972 -153.04135)
		(end 204.499972 -153.364946)
		(width 0.14224)
		(layer "In11.Cu")
		(net "M_F_DQ<3>")
	)
	(segment
		(start 205.3336 -121.116852)
		(end 205.637384 -121.420636)
		(width 0.14224)
		(layer "In11.Cu")
		(net "M_F_DQ<3>")
	)
	(segment
		(start 204.211174 -152.479248)
		(end 204.211174 -152.752552)
		(width 0.14224)
		(layer "In11.Cu")
		(net "M_F_DQ<3>")
	)
	(segment
		(start 205.637384 -123.046236)
		(end 205.637384 -123.555252)
		(width 0.14224)
		(layer "In11.Cu")
		(net "M_F_DQ<3>")
	)
	(segment
		(start 204.322172 -153.542746)
		(end 204.049884 -153.542746)
		(width 0.14224)
		(layer "In11.Cu")
		(net "M_F_DQ<3>")
	)
	(segment
		(start 205.637384 -123.555252)
		(end 205.3336 -123.859036)
		(width 0.14224)
		(layer "In11.Cu")
		(net "M_F_DQ<3>")
	)
	(segment
		(start 205.267052 -141.9352)
		(end 205.5622 -142.230348)
		(width 0.14224)
		(layer "In11.Cu")
		(net "M_F_DQ<3>")
	)
	(segment
		(start 205.4606 -132.485384)
		(end 205.4606 -132.856224)
		(width 0.14224)
		(layer "In11.Cu")
		(net "M_F_DQ<3>")
	)
	(segment
		(start 205.4606 -132.856224)
		(end 205.1812 -133.135624)
		(width 0.14224)
		(layer "In11.Cu")
		(net "M_F_DQ<3>")
	)
	(segment
		(start 205.080362 -127.354838)
		(end 205.080362 -129.786888)
		(width 0.14224)
		(layer "In11.Cu")
		(net "M_F_DQ<3>")
	)
	(segment
		(start 204.449172 -150.391368)
		(end 204.493622 -150.435818)
		(width 0.14224)
		(layer "In11.Cu")
		(net "M_F_DQ<3>")
	)
	(segment
		(start 204.499972 -153.364946)
		(end 204.322172 -153.542746)
		(width 0.14224)
		(layer "In11.Cu")
		(net "M_F_DQ<3>")
	)
	(segment
		(start 237.346998 -88.87079)
		(end 237.314232 -88.87079)
		(width 0.0889)
		(layer "In11.Cu")
		(net "M_F_DQ<3>")
	)
	(segment
		(start 205.637384 -118.169436)
		(end 205.637384 -118.678452)
		(width 0.14224)
		(layer "In11.Cu")
		(net "M_F_DQ<3>")
	)
	(segment
		(start 239.904778 -87.784686)
		(end 239.082326 -87.88019)
		(width 0.0889)
		(layer "In11.Cu")
		(net "M_F_DQ<3>")
	)
	(segment
		(start 204.211174 -151.660352)
		(end 204.468222 -151.9174)
		(width 0.14224)
		(layer "In11.Cu")
		(net "M_F_DQ<3>")
	)
	(segment
		(start 205.637384 -125.180852)
		(end 205.3336 -125.484636)
		(width 0.14224)
		(layer "In11.Cu")
		(net "M_F_DQ<3>")
	)
	(segment
		(start 204.468222 -151.9174)
		(end 204.468222 -152.2222)
		(width 0.14224)
		(layer "In11.Cu")
		(net "M_F_DQ<3>")
	)
	(arc
		(start 234.406948 -90.556588)
		(mid 234.221082 -90.754204)
		(end 233.966512 -90.847926)
		(width 0.0889)
		(layer "In11.Cu")
		(net "M_F_DQ<3>")
	)
	(arc
		(start 238.176562 -88.375236)
		(mid 237.982712 -88.431586)
		(end 237.841028 -88.575388)
		(width 0.0889)
		(layer "In11.Cu")
		(net "M_F_DQ<3>")
	)
	(arc
		(start 239.031272 -87.88019)
		(mid 238.83963 -87.937356)
		(end 238.699548 -88.080088)
		(width 0.0889)
		(layer "In11.Cu")
		(net "M_F_DQ<3>")
	)
	(arc
		(start 236.459522 -89.365836)
		(mid 236.265672 -89.422186)
		(end 236.123988 -89.565988)
		(width 0.0889)
		(layer "In11.Cu")
		(net "M_F_DQ<3>")
	)
	(arc
		(start 235.597192 -89.86139)
		(mid 235.40555 -89.918556)
		(end 235.265468 -90.061288)
		(width 0.0889)
		(layer "In11.Cu")
		(net "M_F_DQ<3>")
	)
	(arc
		(start 237.314232 -88.87079)
		(mid 237.12259 -88.927956)
		(end 236.982508 -89.070688)
		(width 0.0889)
		(layer "In11.Cu")
		(net "M_F_DQ<3>")
	)
	(arc
		(start 233.548428 -91.051888)
		(mid 233.341424 -91.262752)
		(end 233.058208 -91.347036)
		(width 0.0889)
		(layer "In11.Cu")
		(net "M_F_DQ<3>")
	)
	(arc
		(start 235.265468 -90.061288)
		(mid 235.058464 -90.272152)
		(end 234.775248 -90.356436)
		(width 0.0889)
		(layer "In11.Cu")
		(net "M_F_DQ<3>")
	)
	(arc
		(start 236.982508 -89.070688)
		(mid 236.775504 -89.281552)
		(end 236.492288 -89.365836)
		(width 0.0889)
		(layer "In11.Cu")
		(net "M_F_DQ<3>")
	)
	(arc
		(start 236.123988 -89.565988)
		(mid 235.91538 -89.77792)
		(end 235.629958 -89.86139)
		(width 0.0889)
		(layer "In11.Cu")
		(net "M_F_DQ<3>")
	)
	(arc
		(start 233.966512 -90.847926)
		(mid 233.903002 -90.853692)
		(end 233.839258 -90.855546)
		(width 0.0889)
		(layer "In11.Cu")
		(net "M_F_DQ<3>")
	)
	(arc
		(start 234.742482 -90.356436)
		(mid 234.548632 -90.412786)
		(end 234.406948 -90.556588)
		(width 0.0889)
		(layer "In11.Cu")
		(net "M_F_DQ<3>")
	)
	(arc
		(start 238.699548 -88.080088)
		(mid 238.492544 -88.290952)
		(end 238.209328 -88.375236)
		(width 0.0889)
		(layer "In11.Cu")
		(net "M_F_DQ<3>")
	)
	(arc
		(start 237.841028 -88.575388)
		(mid 237.63242 -88.78732)
		(end 237.346998 -88.87079)
		(width 0.0889)
		(layer "In11.Cu")
		(net "M_F_DQ<3>")
	)
	(arc
		(start 233.839258 -90.855546)
		(mid 233.671015 -90.91993)
		(end 233.548428 -91.051888)
		(width 0.0889)
		(layer "In11.Cu")
		(net "M_F_DQ<3>")
	)
	(segment
		(start 285.650432 -152.273)
		(end 285.649924 -152.278842)
		(width 0.1651)
		(layer "F.Cu")
		(net "M_F_DQ<39>")
	)
	(segment
		(start 274.627848 -94.538038)
		(end 275.199348 -94.538038)
		(width 0.1651)
		(layer "F.Cu")
		(net "M_F_DQ<39>")
	)
	(segment
		(start 285.649924 -152.278842)
		(end 285.649924 -153.542746)
		(width 0.1651)
		(layer "F.Cu")
		(net "M_F_DQ<39>")
	)
	(via
		(at 286.499808 -149.533356)
		(size 0.508)
		(drill 0.254)
		(layers "F.Cu" "B.Cu")
		(net "M_F_DQ<39>")
	)
	(via
		(at 275.199348 -94.538038)
		(size 0.508)
		(drill 0.254)
		(layers "F.Cu" "B.Cu")
		(net "M_F_DQ<39>")
	)
	(via
		(at 285.649924 -153.542746)
		(size 0.508)
		(drill 0.254)
		(layers "F.Cu" "B.Cu")
		(net "M_F_DQ<39>")
	)
	(segment
		(start 286.499808 -149.533356)
		(end 286.499808 -147.478496)
		(width 0.1651)
		(layer "B.Cu")
		(net "M_F_DQ<39>")
	)
	(segment
		(start 286.499808 -147.478496)
		(end 286.500316 -147.478496)
		(width 0.1651)
		(layer "B.Cu")
		(net "M_F_DQ<39>")
	)
	(segment
		(start 277.0124 -115.109752)
		(end 286.517588 -124.61494)
		(width 0.14224)
		(layer "In11.Cu")
		(net "M_F_DQ<39>")
	)
	(segment
		(start 286.878014 -131.9022)
		(end 286.9184 -131.942586)
		(width 0.14224)
		(layer "In11.Cu")
		(net "M_F_DQ<39>")
	)
	(segment
		(start 277.2918 -103.36022)
		(end 277.2918 -105.3592)
		(width 0.14224)
		(layer "In11.Cu")
		(net "M_F_DQ<39>")
	)
	(segment
		(start 286.852614 -136.5758)
		(end 286.9184 -136.641586)
		(width 0.14224)
		(layer "In11.Cu")
		(net "M_F_DQ<39>")
	)
	(segment
		(start 287.021778 -144.313402)
		(end 287.021778 -145.641822)
		(width 0.14224)
		(layer "In11.Cu")
		(net "M_F_DQ<39>")
	)
	(segment
		(start 277.427944 -102.166928)
		(end 277.434294 -102.177596)
		(width 0.0889)
		(layer "In11.Cu")
		(net "M_F_DQ<39>")
	)
	(segment
		(start 286.388048 -125.178058)
		(end 286.180276 -125.178058)
		(width 0.14224)
		(layer "In11.Cu")
		(net "M_F_DQ<39>")
	)
	(segment
		(start 285.858204 -152.432004)
		(end 285.811214 -152.479248)
		(width 0.14224)
		(layer "In11.Cu")
		(net "M_F_DQ<39>")
	)
	(segment
		(start 286.878014 -131.408678)
		(end 286.878014 -131.9022)
		(width 0.14224)
		(layer "In11.Cu")
		(net "M_F_DQ<39>")
	)
	(segment
		(start 286.068262 -152.2222)
		(end 285.858204 -152.432004)
		(width 0.14224)
		(layer "In11.Cu")
		(net "M_F_DQ<39>")
	)
	(segment
		(start 286.517588 -125.048518)
		(end 286.388048 -125.178058)
		(width 0.14224)
		(layer "In11.Cu")
		(net "M_F_DQ<39>")
	)
	(segment
		(start 287.081214 -140.806678)
		(end 286.801814 -141.086078)
		(width 0.14224)
		(layer "In11.Cu")
		(net "M_F_DQ<39>")
	)
	(segment
		(start 286.9184 -134.0104)
		(end 286.878014 -134.050786)
		(width 0.14224)
		(layer "In11.Cu")
		(net "M_F_DQ<39>")
	)
	(segment
		(start 274.852638 -94.737936)
		(end 274.858988 -94.748604)
		(width 0.0889)
		(layer "In11.Cu")
		(net "M_F_DQ<39>")
	)
	(segment
		(start 275.199348 -94.538038)
		(end 274.861274 -94.538038)
		(width 0.0889)
		(layer "In11.Cu")
		(net "M_F_DQ<39>")
	)
	(segment
		(start 286.852614 -145.810986)
		(end 286.852614 -146.177)
		(width 0.14224)
		(layer "In11.Cu")
		(net "M_F_DQ<39>")
	)
	(segment
		(start 287.055814 -136.057132)
		(end 286.852614 -136.260332)
		(width 0.14224)
		(layer "In11.Cu")
		(net "M_F_DQ<39>")
	)
	(segment
		(start 287.021778 -145.641822)
		(end 286.852614 -145.810986)
		(width 0.14224)
		(layer "In11.Cu")
		(net "M_F_DQ<39>")
	)
	(segment
		(start 286.801814 -141.5288)
		(end 286.9184 -141.645386)
		(width 0.14224)
		(layer "In11.Cu")
		(net "M_F_DQ<39>")
	)
	(segment
		(start 274.858988 -98.289618)
		(end 274.852638 -98.300286)
		(width 0.0889)
		(layer "In11.Cu")
		(net "M_F_DQ<39>")
	)
	(segment
		(start 285.811214 -152.479248)
		(end 285.811214 -152.752552)
		(width 0.14224)
		(layer "In11.Cu")
		(net "M_F_DQ<39>")
	)
	(segment
		(start 286.049212 -149.9616)
		(end 286.049212 -150.391368)
		(width 0.14224)
		(layer "In11.Cu")
		(net "M_F_DQ<39>")
	)
	(segment
		(start 286.852614 -149.191472)
		(end 286.841692 -149.191472)
		(width 0.14224)
		(layer "In11.Cu")
		(net "M_F_DQ<39>")
	)
	(segment
		(start 286.100012 -153.04135)
		(end 286.100012 -153.364946)
		(width 0.14224)
		(layer "In11.Cu")
		(net "M_F_DQ<39>")
	)
	(segment
		(start 286.068262 -151.9174)
		(end 286.068262 -152.2222)
		(width 0.14224)
		(layer "In11.Cu")
		(net "M_F_DQ<39>")
	)
	(segment
		(start 286.801814 -141.086078)
		(end 286.801814 -141.5288)
		(width 0.14224)
		(layer "In11.Cu")
		(net "M_F_DQ<39>")
	)
	(segment
		(start 286.180276 -125.840998)
		(end 286.565848 -125.840998)
		(width 0.14224)
		(layer "In11.Cu")
		(net "M_F_DQ<39>")
	)
	(segment
		(start 286.852614 -148.477986)
		(end 286.852614 -149.191472)
		(width 0.14224)
		(layer "In11.Cu")
		(net "M_F_DQ<39>")
	)
	(segment
		(start 286.093662 -151.1046)
		(end 285.811214 -151.387048)
		(width 0.14224)
		(layer "In11.Cu")
		(net "M_F_DQ<39>")
	)
	(segment
		(start 276.89556 -99.89058)
		(end 276.937724 -99.89058)
		(width 0.0889)
		(layer "In11.Cu")
		(net "M_F_DQ<39>")
	)
	(segment
		(start 286.517588 -124.61494)
		(end 286.517588 -125.048518)
		(width 0.14224)
		(layer "In11.Cu")
		(net "M_F_DQ<39>")
	)
	(segment
		(start 286.025336 -128.509776)
		(end 286.852614 -129.337054)
		(width 0.14224)
		(layer "In11.Cu")
		(net "M_F_DQ<39>")
	)
	(segment
		(start 286.852614 -146.177)
		(end 286.9184 -146.242786)
		(width 0.14224)
		(layer "In11.Cu")
		(net "M_F_DQ<39>")
	)
	(segment
		(start 286.565848 -127.166878)
		(end 286.720788 -127.321818)
		(width 0.14224)
		(layer "In11.Cu")
		(net "M_F_DQ<39>")
	)
	(segment
		(start 277.427944 -102.757986)
		(end 277.368 -102.861364)
		(width 0.0889)
		(layer "In11.Cu")
		(net "M_F_DQ<39>")
	)
	(segment
		(start 286.565848 -126.503938)
		(end 286.180276 -126.503938)
		(width 0.14224)
		(layer "In11.Cu")
		(net "M_F_DQ<39>")
	)
	(segment
		(start 276.057614 -99.395788)
		(end 276.079204 -99.395788)
		(width 0.0889)
		(layer "In11.Cu")
		(net "M_F_DQ<39>")
	)
	(segment
		(start 285.922212 -153.542746)
		(end 285.649924 -153.542746)
		(width 0.14224)
		(layer "In11.Cu")
		(net "M_F_DQ<39>")
	)
	(segment
		(start 286.025336 -125.332998)
		(end 286.025336 -125.686058)
		(width 0.14224)
		(layer "In11.Cu")
		(net "M_F_DQ<39>")
	)
	(segment
		(start 286.100012 -153.364946)
		(end 285.922212 -153.542746)
		(width 0.14224)
		(layer "In11.Cu")
		(net "M_F_DQ<39>")
	)
	(segment
		(start 286.852614 -138.876786)
		(end 286.852614 -139.460478)
		(width 0.14224)
		(layer "In11.Cu")
		(net "M_F_DQ<39>")
	)
	(segment
		(start 286.852614 -136.260332)
		(end 286.852614 -136.5758)
		(width 0.14224)
		(layer "In11.Cu")
		(net "M_F_DQ<39>")
	)
	(segment
		(start 286.720788 -127.321818)
		(end 286.720788 -127.674878)
		(width 0.14224)
		(layer "In11.Cu")
		(net "M_F_DQ<39>")
	)
	(segment
		(start 285.811214 -151.387048)
		(end 285.811214 -151.660352)
		(width 0.14224)
		(layer "In11.Cu")
		(net "M_F_DQ<39>")
	)
	(segment
		(start 274.852638 -96.319086)
		(end 274.847812 -96.327722)
		(width 0.0889)
		(layer "In11.Cu")
		(net "M_F_DQ<39>")
	)
	(segment
		(start 274.858988 -96.308418)
		(end 274.852638 -96.319086)
		(width 0.0889)
		(layer "In11.Cu")
		(net "M_F_DQ<39>")
	)
	(segment
		(start 286.720788 -127.674878)
		(end 286.565848 -127.829818)
		(width 0.14224)
		(layer "In11.Cu")
		(net "M_F_DQ<39>")
	)
	(segment
		(start 286.9184 -143.6878)
		(end 286.878014 -143.728186)
		(width 0.14224)
		(layer "In11.Cu")
		(net "M_F_DQ<39>")
	)
	(segment
		(start 275.711158 -99.195636)
		(end 275.71446 -99.201478)
		(width 0.0889)
		(layer "In11.Cu")
		(net "M_F_DQ<39>")
	)
	(segment
		(start 286.9184 -141.645386)
		(end 286.9184 -143.6878)
		(width 0.14224)
		(layer "In11.Cu")
		(net "M_F_DQ<39>")
	)
	(segment
		(start 286.720788 -126.348998)
		(end 286.565848 -126.503938)
		(width 0.14224)
		(layer "In11.Cu")
		(net "M_F_DQ<39>")
	)
	(segment
		(start 277.0124 -105.6386)
		(end 277.0124 -115.109752)
		(width 0.14224)
		(layer "In11.Cu")
		(net "M_F_DQ<39>")
	)
	(segment
		(start 277.365206 -103.286814)
		(end 277.2918 -103.36022)
		(width 0.14224)
		(layer "In11.Cu")
		(net "M_F_DQ<39>")
	)
	(segment
		(start 286.878014 -134.579868)
		(end 287.055814 -134.757668)
		(width 0.14224)
		(layer "In11.Cu")
		(net "M_F_DQ<39>")
	)
	(segment
		(start 286.025336 -125.686058)
		(end 286.180276 -125.840998)
		(width 0.14224)
		(layer "In11.Cu")
		(net "M_F_DQ<39>")
	)
	(segment
		(start 286.9184 -146.242786)
		(end 286.9184 -148.4122)
		(width 0.14224)
		(layer "In11.Cu")
		(net "M_F_DQ<39>")
	)
	(segment
		(start 286.852614 -129.859278)
		(end 287.081214 -130.087878)
		(width 0.14224)
		(layer "In11.Cu")
		(net "M_F_DQ<39>")
	)
	(segment
		(start 286.565848 -125.840998)
		(end 286.720788 -125.995938)
		(width 0.14224)
		(layer "In11.Cu")
		(net "M_F_DQ<39>")
	)
	(segment
		(start 274.858988 -97.299018)
		(end 274.852638 -97.309686)
		(width 0.0889)
		(layer "In11.Cu")
		(net "M_F_DQ<39>")
	)
	(segment
		(start 286.878014 -134.050786)
		(end 286.878014 -134.579868)
		(width 0.14224)
		(layer "In11.Cu")
		(net "M_F_DQ<39>")
	)
	(segment
		(start 286.565848 -127.829818)
		(end 286.180276 -127.829818)
		(width 0.14224)
		(layer "In11.Cu")
		(net "M_F_DQ<39>")
	)
	(segment
		(start 277.365206 -102.864158)
		(end 277.365206 -103.286814)
		(width 0.0889)
		(layer "In11.Cu")
		(net "M_F_DQ<39>")
	)
	(segment
		(start 286.477456 -149.533356)
		(end 286.049212 -149.9616)
		(width 0.14224)
		(layer "In11.Cu")
		(net "M_F_DQ<39>")
	)
	(segment
		(start 286.9184 -148.4122)
		(end 286.852614 -148.477986)
		(width 0.14224)
		(layer "In11.Cu")
		(net "M_F_DQ<39>")
	)
	(segment
		(start 286.180276 -127.166878)
		(end 286.565848 -127.166878)
		(width 0.14224)
		(layer "In11.Cu")
		(net "M_F_DQ<39>")
	)
	(segment
		(start 274.852638 -97.309686)
		(end 274.847812 -97.318322)
		(width 0.0889)
		(layer "In11.Cu")
		(net "M_F_DQ<39>")
	)
	(segment
		(start 286.025336 -127.011938)
		(end 286.180276 -127.166878)
		(width 0.14224)
		(layer "In11.Cu")
		(net "M_F_DQ<39>")
	)
	(segment
		(start 286.852614 -139.460478)
		(end 287.081214 -139.689078)
		(width 0.14224)
		(layer "In11.Cu")
		(net "M_F_DQ<39>")
	)
	(segment
		(start 287.081214 -130.087878)
		(end 287.081214 -131.205478)
		(width 0.14224)
		(layer "In11.Cu")
		(net "M_F_DQ<39>")
	)
	(segment
		(start 274.861274 -94.538038)
		(end 274.803616 -94.595696)
		(width 0.0889)
		(layer "In11.Cu")
		(net "M_F_DQ<39>")
	)
	(segment
		(start 286.878014 -144.169638)
		(end 287.021778 -144.313402)
		(width 0.14224)
		(layer "In11.Cu")
		(net "M_F_DQ<39>")
	)
	(segment
		(start 286.852614 -129.337054)
		(end 286.852614 -129.859278)
		(width 0.14224)
		(layer "In11.Cu")
		(net "M_F_DQ<39>")
	)
	(segment
		(start 286.180276 -127.829818)
		(end 286.025336 -127.984758)
		(width 0.14224)
		(layer "In11.Cu")
		(net "M_F_DQ<39>")
	)
	(segment
		(start 286.180276 -126.503938)
		(end 286.025336 -126.658878)
		(width 0.14224)
		(layer "In11.Cu")
		(net "M_F_DQ<39>")
	)
	(segment
		(start 285.811214 -152.752552)
		(end 286.100012 -153.04135)
		(width 0.14224)
		(layer "In11.Cu")
		(net "M_F_DQ<39>")
	)
	(segment
		(start 286.499808 -149.533356)
		(end 286.477456 -149.533356)
		(width 0.14224)
		(layer "In11.Cu")
		(net "M_F_DQ<39>")
	)
	(segment
		(start 277.2918 -105.3592)
		(end 277.0124 -105.6386)
		(width 0.14224)
		(layer "In11.Cu")
		(net "M_F_DQ<39>")
	)
	(segment
		(start 277.427944 -100.776278)
		(end 277.423118 -100.784914)
		(width 0.0889)
		(layer "In11.Cu")
		(net "M_F_DQ<39>")
	)
	(segment
		(start 286.9184 -136.641586)
		(end 286.9184 -138.811)
		(width 0.14224)
		(layer "In11.Cu")
		(net "M_F_DQ<39>")
	)
	(segment
		(start 286.049212 -150.391368)
		(end 286.093662 -150.435818)
		(width 0.14224)
		(layer "In11.Cu")
		(net "M_F_DQ<39>")
	)
	(segment
		(start 286.878014 -143.728186)
		(end 286.878014 -144.169638)
		(width 0.14224)
		(layer "In11.Cu")
		(net "M_F_DQ<39>")
	)
	(segment
		(start 286.093662 -150.435818)
		(end 286.093662 -151.1046)
		(width 0.14224)
		(layer "In11.Cu")
		(net "M_F_DQ<39>")
	)
	(segment
		(start 286.9184 -131.942586)
		(end 286.9184 -134.0104)
		(width 0.14224)
		(layer "In11.Cu")
		(net "M_F_DQ<39>")
	)
	(segment
		(start 287.081214 -139.689078)
		(end 287.081214 -140.806678)
		(width 0.14224)
		(layer "In11.Cu")
		(net "M_F_DQ<39>")
	)
	(segment
		(start 287.055814 -134.757668)
		(end 287.055814 -136.057132)
		(width 0.14224)
		(layer "In11.Cu")
		(net "M_F_DQ<39>")
	)
	(segment
		(start 275.184362 -98.900234)
		(end 275.217128 -98.900234)
		(width 0.0889)
		(layer "In11.Cu")
		(net "M_F_DQ<39>")
	)
	(segment
		(start 277.434294 -100.76561)
		(end 277.427944 -100.776278)
		(width 0.0889)
		(layer "In11.Cu")
		(net "M_F_DQ<39>")
	)
	(segment
		(start 286.841692 -149.191472)
		(end 286.499808 -149.533356)
		(width 0.14224)
		(layer "In11.Cu")
		(net "M_F_DQ<39>")
	)
	(segment
		(start 287.081214 -131.205478)
		(end 286.878014 -131.408678)
		(width 0.14224)
		(layer "In11.Cu")
		(net "M_F_DQ<39>")
	)
	(segment
		(start 274.852638 -98.300286)
		(end 274.847812 -98.308922)
		(width 0.0889)
		(layer "In11.Cu")
		(net "M_F_DQ<39>")
	)
	(segment
		(start 286.180276 -125.178058)
		(end 286.025336 -125.332998)
		(width 0.14224)
		(layer "In11.Cu")
		(net "M_F_DQ<39>")
	)
	(segment
		(start 286.025336 -127.984758)
		(end 286.025336 -128.509776)
		(width 0.14224)
		(layer "In11.Cu")
		(net "M_F_DQ<39>")
	)
	(segment
		(start 286.025336 -126.658878)
		(end 286.025336 -127.011938)
		(width 0.14224)
		(layer "In11.Cu")
		(net "M_F_DQ<39>")
	)
	(segment
		(start 285.811214 -151.660352)
		(end 286.068262 -151.9174)
		(width 0.14224)
		(layer "In11.Cu")
		(net "M_F_DQ<39>")
	)
	(segment
		(start 277.368 -102.861364)
		(end 277.365206 -102.864158)
		(width 0.0889)
		(layer "In11.Cu")
		(net "M_F_DQ<39>")
	)
	(segment
		(start 286.720788 -125.995938)
		(end 286.720788 -126.348998)
		(width 0.14224)
		(layer "In11.Cu")
		(net "M_F_DQ<39>")
	)
	(segment
		(start 286.9184 -138.811)
		(end 286.852614 -138.876786)
		(width 0.14224)
		(layer "In11.Cu")
		(net "M_F_DQ<39>")
	)
	(arc
		(start 274.847812 -96.327722)
		(mid 274.799057 -96.524074)
		(end 274.852638 -96.719136)
		(width 0.0889)
		(layer "In11.Cu")
		(net "M_F_DQ<39>")
	)
	(arc
		(start 274.847812 -97.318322)
		(mid 274.799057 -97.514674)
		(end 274.852638 -97.709736)
		(width 0.0889)
		(layer "In11.Cu")
		(net "M_F_DQ<39>")
	)
	(arc
		(start 274.847812 -95.337122)
		(mid 274.799057 -95.533474)
		(end 274.852638 -95.728536)
		(width 0.0889)
		(layer "In11.Cu")
		(net "M_F_DQ<39>")
	)
	(arc
		(start 274.830286 -94.691708)
		(mid 274.840458 -94.715308)
		(end 274.852638 -94.737936)
		(width 0.0889)
		(layer "In11.Cu")
		(net "M_F_DQ<39>")
	)
	(arc
		(start 277.434294 -102.177596)
		(mid 277.507214 -102.468613)
		(end 277.427944 -102.757986)
		(width 0.0889)
		(layer "In11.Cu")
		(net "M_F_DQ<39>")
	)
	(arc
		(start 277.427944 -101.176328)
		(mid 277.507075 -101.47173)
		(end 277.427944 -101.767132)
		(width 0.0889)
		(layer "In11.Cu")
		(net "M_F_DQ<39>")
	)
	(arc
		(start 275.217128 -98.900234)
		(mid 275.502552 -98.983701)
		(end 275.711158 -99.195636)
		(width 0.0889)
		(layer "In11.Cu")
		(net "M_F_DQ<39>")
	)
	(arc
		(start 276.937724 -99.89058)
		(mid 277.430114 -100.189513)
		(end 277.434294 -100.76561)
		(width 0.0889)
		(layer "In11.Cu")
		(net "M_F_DQ<39>")
	)
	(arc
		(start 274.803616 -94.595696)
		(mid 274.813944 -94.644538)
		(end 274.830286 -94.691708)
		(width 0.0889)
		(layer "In11.Cu")
		(net "M_F_DQ<39>")
	)
	(arc
		(start 276.569424 -99.690936)
		(mid 276.707113 -99.83222)
		(end 276.89556 -99.89058)
		(width 0.0889)
		(layer "In11.Cu")
		(net "M_F_DQ<39>")
	)
	(arc
		(start 274.858988 -94.748604)
		(mid 274.931786 -95.039367)
		(end 274.852638 -95.328486)
		(width 0.0889)
		(layer "In11.Cu")
		(net "M_F_DQ<39>")
	)
	(arc
		(start 274.852638 -96.719136)
		(mid 274.93186 -97.008254)
		(end 274.858988 -97.299018)
		(width 0.0889)
		(layer "In11.Cu")
		(net "M_F_DQ<39>")
	)
	(arc
		(start 274.852638 -95.328486)
		(mid 274.850194 -95.332787)
		(end 274.847812 -95.337122)
		(width 0.0889)
		(layer "In11.Cu")
		(net "M_F_DQ<39>")
	)
	(arc
		(start 276.079204 -99.395788)
		(mid 276.362421 -99.480069)
		(end 276.569424 -99.690936)
		(width 0.0889)
		(layer "In11.Cu")
		(net "M_F_DQ<39>")
	)
	(arc
		(start 274.852638 -95.728536)
		(mid 274.93186 -96.017654)
		(end 274.858988 -96.308418)
		(width 0.0889)
		(layer "In11.Cu")
		(net "M_F_DQ<39>")
	)
	(arc
		(start 275.71446 -99.201478)
		(mid 275.860426 -99.343877)
		(end 276.057614 -99.395788)
		(width 0.0889)
		(layer "In11.Cu")
		(net "M_F_DQ<39>")
	)
	(arc
		(start 277.423118 -100.784914)
		(mid 277.374363 -100.981266)
		(end 277.427944 -101.176328)
		(width 0.0889)
		(layer "In11.Cu")
		(net "M_F_DQ<39>")
	)
	(arc
		(start 274.852638 -97.709736)
		(mid 274.93186 -97.998854)
		(end 274.858988 -98.289618)
		(width 0.0889)
		(layer "In11.Cu")
		(net "M_F_DQ<39>")
	)
	(arc
		(start 274.847812 -98.308922)
		(mid 274.851559 -98.698178)
		(end 275.184362 -98.900234)
		(width 0.0889)
		(layer "In11.Cu")
		(net "M_F_DQ<39>")
	)
	(arc
		(start 277.427944 -101.767132)
		(mid 277.374445 -101.96703)
		(end 277.427944 -102.166928)
		(width 0.0889)
		(layer "In11.Cu")
		(net "M_F_DQ<39>")
	)
	(segment
		(start 286.500062 -155.9052)
		(end 286.632142 -155.77312)
		(width 0.1651)
		(layer "F.Cu")
		(net "M_F_DQ<38>")
	)
	(segment
		(start 286.500062 -155.4226)
		(end 286.500062 -155.118054)
		(width 0.1651)
		(layer "F.Cu")
		(net "M_F_DQ<38>")
	)
	(segment
		(start 286.500316 -156.87294)
		(end 286.500062 -156.87294)
		(width 0.1651)
		(layer "F.Cu")
		(net "M_F_DQ<38>")
	)
	(segment
		(start 286.500062 -155.118054)
		(end 286.499808 -155.1178)
		(width 0.1651)
		(layer "F.Cu")
		(net "M_F_DQ<38>")
	)
	(segment
		(start 286.632142 -155.77312)
		(end 286.632142 -155.55468)
		(width 0.1651)
		(layer "F.Cu")
		(net "M_F_DQ<38>")
	)
	(segment
		(start 286.500062 -156.87294)
		(end 286.500062 -155.9052)
		(width 0.1651)
		(layer "F.Cu")
		(net "M_F_DQ<38>")
	)
	(segment
		(start 286.632142 -155.55468)
		(end 286.500062 -155.4226)
		(width 0.1651)
		(layer "F.Cu")
		(net "M_F_DQ<38>")
	)
	(segment
		(start 274.627848 -92.556584)
		(end 275.199348 -92.556584)
		(width 0.1651)
		(layer "F.Cu")
		(net "M_F_DQ<38>")
	)
	(via
		(at 286.499808 -155.1178)
		(size 0.508)
		(drill 0.254)
		(layers "F.Cu" "B.Cu")
		(net "M_F_DQ<38>")
	)
	(via
		(at 275.199348 -92.556584)
		(size 0.508)
		(drill 0.254)
		(layers "F.Cu" "B.Cu")
		(net "M_F_DQ<38>")
	)
	(via
		(at 285.649924 -150.814278)
		(size 0.508)
		(drill 0.254)
		(layers "F.Cu" "B.Cu")
		(net "M_F_DQ<38>")
	)
	(segment
		(start 285.650432 -152.078436)
		(end 285.649924 -152.078182)
		(width 0.1651)
		(layer "B.Cu")
		(net "M_F_DQ<38>")
	)
	(segment
		(start 285.649924 -152.078182)
		(end 285.649924 -150.814278)
		(width 0.1651)
		(layer "B.Cu")
		(net "M_F_DQ<38>")
	)
	(segment
		(start 286.116014 -134.579868)
		(end 286.014414 -134.681468)
		(width 0.14224)
		(layer "In11.Cu")
		(net "M_F_DQ<38>")
	)
	(segment
		(start 274.692364 -97.2058)
		(end 274.687538 -97.214436)
		(width 0.0889)
		(layer "In11.Cu")
		(net "M_F_DQ<38>")
	)
	(segment
		(start 286.014414 -139.663678)
		(end 286.014414 -140.908278)
		(width 0.14224)
		(layer "In11.Cu")
		(net "M_F_DQ<38>")
	)
	(segment
		(start 285.894272 -145.534126)
		(end 286.117792 -145.757646)
		(width 0.14224)
		(layer "In11.Cu")
		(net "M_F_DQ<38>")
	)
	(segment
		(start 274.704302 -93.222572)
		(end 274.687538 -93.252036)
		(width 0.0889)
		(layer "In11.Cu")
		(net "M_F_DQ<38>")
	)
	(segment
		(start 275.542502 -99.285044)
		(end 275.545804 -99.290886)
		(width 0.0889)
		(layer "In11.Cu")
		(net "M_F_DQ<38>")
	)
	(segment
		(start 286.103314 -129.973578)
		(end 286.014414 -130.062478)
		(width 0.14224)
		(layer "In11.Cu")
		(net "M_F_DQ<38>")
	)
	(segment
		(start 285.216854 -153.834846)
		(end 286.499808 -155.1178)
		(width 0.14224)
		(layer "In11.Cu")
		(net "M_F_DQ<38>")
	)
	(segment
		(start 286.117792 -145.757646)
		(end 286.117792 -149.0345)
		(width 0.14224)
		(layer "In11.Cu")
		(net "M_F_DQ<38>")
	)
	(segment
		(start 275.177758 -99.090734)
		(end 275.199348 -99.090734)
		(width 0.0889)
		(layer "In11.Cu")
		(net "M_F_DQ<38>")
	)
	(segment
		(start 274.687538 -98.205036)
		(end 274.681188 -98.215704)
		(width 0.0889)
		(layer "In11.Cu")
		(net "M_F_DQ<38>")
	)
	(segment
		(start 286.014414 -136.129268)
		(end 286.131762 -136.246616)
		(width 0.14224)
		(layer "In11.Cu")
		(net "M_F_DQ<38>")
	)
	(segment
		(start 286.131762 -139.54633)
		(end 286.014414 -139.663678)
		(width 0.14224)
		(layer "In11.Cu")
		(net "M_F_DQ<38>")
	)
	(segment
		(start 286.117792 -149.0345)
		(end 285.539942 -149.61235)
		(width 0.14224)
		(layer "In11.Cu")
		(net "M_F_DQ<38>")
	)
	(segment
		(start 285.894272 -144.39138)
		(end 285.894272 -145.534126)
		(width 0.14224)
		(layer "In11.Cu")
		(net "M_F_DQ<38>")
	)
	(segment
		(start 274.692364 -94.234)
		(end 274.687538 -94.242636)
		(width 0.0889)
		(layer "In11.Cu")
		(net "M_F_DQ<38>")
	)
	(segment
		(start 286.166814 -141.060678)
		(end 286.166814 -144.118838)
		(width 0.14224)
		(layer "In11.Cu")
		(net "M_F_DQ<38>")
	)
	(segment
		(start 274.687538 -97.214436)
		(end 274.681188 -97.225104)
		(width 0.0889)
		(layer "In11.Cu")
		(net "M_F_DQ<38>")
	)
	(segment
		(start 276.3774 -105.5116)
		(end 276.3774 -115.372896)
		(width 0.14224)
		(layer "In11.Cu")
		(net "M_F_DQ<38>")
	)
	(segment
		(start 286.116014 -131.408678)
		(end 286.116014 -134.579868)
		(width 0.14224)
		(layer "In11.Cu")
		(net "M_F_DQ<38>")
	)
	(segment
		(start 276.894544 -100.081334)
		(end 276.934168 -100.081334)
		(width 0.0889)
		(layer "In11.Cu")
		(net "M_F_DQ<38>")
	)
	(segment
		(start 285.216854 -151.247348)
		(end 285.216854 -153.834846)
		(width 0.14224)
		(layer "In11.Cu")
		(net "M_F_DQ<38>")
	)
	(segment
		(start 285.539942 -150.704296)
		(end 285.649924 -150.814278)
		(width 0.14224)
		(layer "In11.Cu")
		(net "M_F_DQ<38>")
	)
	(segment
		(start 276.039834 -99.586288)
		(end 276.0726 -99.586288)
		(width 0.0889)
		(layer "In11.Cu")
		(net "M_F_DQ<38>")
	)
	(segment
		(start 286.014414 -134.681468)
		(end 286.014414 -136.129268)
		(width 0.14224)
		(layer "In11.Cu")
		(net "M_F_DQ<38>")
	)
	(segment
		(start 285.539942 -149.61235)
		(end 285.539942 -150.704296)
		(width 0.14224)
		(layer "In11.Cu")
		(net "M_F_DQ<38>")
	)
	(segment
		(start 277.262844 -100.681028)
		(end 277.256494 -100.691696)
		(width 0.0889)
		(layer "In11.Cu")
		(net "M_F_DQ<38>")
	)
	(segment
		(start 286.014414 -140.908278)
		(end 286.166814 -141.060678)
		(width 0.14224)
		(layer "In11.Cu")
		(net "M_F_DQ<38>")
	)
	(segment
		(start 285.408116 -124.403612)
		(end 285.408116 -128.701292)
		(width 0.14224)
		(layer "In11.Cu")
		(net "M_F_DQ<38>")
	)
	(segment
		(start 286.131762 -136.246616)
		(end 286.131762 -139.54633)
		(width 0.14224)
		(layer "In11.Cu")
		(net "M_F_DQ<38>")
	)
	(segment
		(start 276.6568 -105.2322)
		(end 276.3774 -105.5116)
		(width 0.14224)
		(layer "In11.Cu")
		(net "M_F_DQ<38>")
	)
	(segment
		(start 277.095966 -102.931214)
		(end 276.740366 -103.286814)
		(width 0.0889)
		(layer "In11.Cu")
		(net "M_F_DQ<38>")
	)
	(segment
		(start 274.692364 -98.1964)
		(end 274.687538 -98.205036)
		(width 0.0889)
		(layer "In11.Cu")
		(net "M_F_DQ<38>")
	)
	(segment
		(start 275.199348 -92.556584)
		(end 274.704302 -93.222572)
		(width 0.0889)
		(layer "In11.Cu")
		(net "M_F_DQ<38>")
	)
	(segment
		(start 276.3774 -115.372896)
		(end 285.408116 -124.403612)
		(width 0.14224)
		(layer "In11.Cu")
		(net "M_F_DQ<38>")
	)
	(segment
		(start 285.408116 -128.701292)
		(end 286.103314 -129.39649)
		(width 0.14224)
		(layer "In11.Cu")
		(net "M_F_DQ<38>")
	)
	(segment
		(start 277.262844 -102.643432)
		(end 277.095966 -102.931214)
		(width 0.0889)
		(layer "In11.Cu")
		(net "M_F_DQ<38>")
	)
	(segment
		(start 285.649924 -150.814278)
		(end 285.216854 -151.247348)
		(width 0.14224)
		(layer "In11.Cu")
		(net "M_F_DQ<38>")
	)
	(segment
		(start 277.26767 -101.662992)
		(end 277.262844 -101.671628)
		(width 0.0889)
		(layer "In11.Cu")
		(net "M_F_DQ<38>")
	)
	(segment
		(start 274.687538 -96.223836)
		(end 274.681188 -96.234504)
		(width 0.0889)
		(layer "In11.Cu")
		(net "M_F_DQ<38>")
	)
	(segment
		(start 276.6568 -103.37038)
		(end 276.6568 -105.2322)
		(width 0.14224)
		(layer "In11.Cu")
		(net "M_F_DQ<38>")
	)
	(segment
		(start 276.740366 -103.286814)
		(end 276.6568 -103.37038)
		(width 0.14224)
		(layer "In11.Cu")
		(net "M_F_DQ<38>")
	)
	(segment
		(start 286.103314 -129.39649)
		(end 286.103314 -129.973578)
		(width 0.14224)
		(layer "In11.Cu")
		(net "M_F_DQ<38>")
	)
	(segment
		(start 286.014414 -130.062478)
		(end 286.014414 -131.307078)
		(width 0.14224)
		(layer "In11.Cu")
		(net "M_F_DQ<38>")
	)
	(segment
		(start 286.014414 -131.307078)
		(end 286.116014 -131.408678)
		(width 0.14224)
		(layer "In11.Cu")
		(net "M_F_DQ<38>")
	)
	(segment
		(start 277.262844 -102.262432)
		(end 277.26767 -102.271068)
		(width 0.0889)
		(layer "In11.Cu")
		(net "M_F_DQ<38>")
	)
	(segment
		(start 274.681188 -94.822518)
		(end 274.687538 -94.833186)
		(width 0.0889)
		(layer "In11.Cu")
		(net "M_F_DQ<38>")
	)
	(segment
		(start 274.692364 -96.2152)
		(end 274.687538 -96.223836)
		(width 0.0889)
		(layer "In11.Cu")
		(net "M_F_DQ<38>")
	)
	(segment
		(start 274.687538 -93.252036)
		(end 274.681188 -93.262704)
		(width 0.0889)
		(layer "In11.Cu")
		(net "M_F_DQ<38>")
	)
	(segment
		(start 286.166814 -144.118838)
		(end 285.894272 -144.39138)
		(width 0.14224)
		(layer "In11.Cu")
		(net "M_F_DQ<38>")
	)
	(arc
		(start 274.687538 -95.232982)
		(mid 274.608407 -95.528384)
		(end 274.687538 -95.823786)
		(width 0.0889)
		(layer "In11.Cu")
		(net "M_F_DQ<38>")
	)
	(arc
		(start 276.404324 -99.786186)
		(mid 276.611328 -99.99705)
		(end 276.894544 -100.081334)
		(width 0.0889)
		(layer "In11.Cu")
		(net "M_F_DQ<38>")
	)
	(arc
		(start 277.256494 -100.691696)
		(mid 277.183696 -100.982459)
		(end 277.262844 -101.271578)
		(width 0.0889)
		(layer "In11.Cu")
		(net "M_F_DQ<38>")
	)
	(arc
		(start 274.687538 -94.833186)
		(mid 274.741037 -95.033084)
		(end 274.687538 -95.232982)
		(width 0.0889)
		(layer "In11.Cu")
		(net "M_F_DQ<38>")
	)
	(arc
		(start 276.0726 -99.586288)
		(mid 276.264242 -99.643454)
		(end 276.404324 -99.786186)
		(width 0.0889)
		(layer "In11.Cu")
		(net "M_F_DQ<38>")
	)
	(arc
		(start 274.681188 -93.262704)
		(mid 274.60839 -93.553467)
		(end 274.687538 -93.842586)
		(width 0.0889)
		(layer "In11.Cu")
		(net "M_F_DQ<38>")
	)
	(arc
		(start 274.687538 -97.804986)
		(mid 274.741008 -98.000049)
		(end 274.692364 -98.1964)
		(width 0.0889)
		(layer "In11.Cu")
		(net "M_F_DQ<38>")
	)
	(arc
		(start 274.681188 -96.234504)
		(mid 274.60839 -96.525267)
		(end 274.687538 -96.814386)
		(width 0.0889)
		(layer "In11.Cu")
		(net "M_F_DQ<38>")
	)
	(arc
		(start 277.26767 -102.271068)
		(mid 277.313971 -102.457878)
		(end 277.262844 -102.643432)
		(width 0.0889)
		(layer "In11.Cu")
		(net "M_F_DQ<38>")
	)
	(arc
		(start 274.687538 -95.823786)
		(mid 274.741008 -96.018849)
		(end 274.692364 -96.2152)
		(width 0.0889)
		(layer "In11.Cu")
		(net "M_F_DQ<38>")
	)
	(arc
		(start 274.687538 -93.842586)
		(mid 274.741008 -94.037649)
		(end 274.692364 -94.234)
		(width 0.0889)
		(layer "In11.Cu")
		(net "M_F_DQ<38>")
	)
	(arc
		(start 275.545804 -99.290886)
		(mid 275.754412 -99.502818)
		(end 276.039834 -99.586288)
		(width 0.0889)
		(layer "In11.Cu")
		(net "M_F_DQ<38>")
	)
	(arc
		(start 275.199348 -99.090734)
		(mid 275.396509 -99.142693)
		(end 275.542502 -99.285044)
		(width 0.0889)
		(layer "In11.Cu")
		(net "M_F_DQ<38>")
	)
	(arc
		(start 277.262844 -101.671628)
		(mid 277.183713 -101.96703)
		(end 277.262844 -102.262432)
		(width 0.0889)
		(layer "In11.Cu")
		(net "M_F_DQ<38>")
	)
	(arc
		(start 274.681188 -98.215704)
		(mid 274.685219 -98.791886)
		(end 275.177758 -99.090734)
		(width 0.0889)
		(layer "In11.Cu")
		(net "M_F_DQ<38>")
	)
	(arc
		(start 277.262844 -101.271578)
		(mid 277.316314 -101.466641)
		(end 277.26767 -101.662992)
		(width 0.0889)
		(layer "In11.Cu")
		(net "M_F_DQ<38>")
	)
	(arc
		(start 276.934168 -100.081334)
		(mid 277.267084 -100.288786)
		(end 277.262844 -100.681028)
		(width 0.0889)
		(layer "In11.Cu")
		(net "M_F_DQ<38>")
	)
	(arc
		(start 274.681188 -97.225104)
		(mid 274.60839 -97.515867)
		(end 274.687538 -97.804986)
		(width 0.0889)
		(layer "In11.Cu")
		(net "M_F_DQ<38>")
	)
	(arc
		(start 274.687538 -94.242636)
		(mid 274.608316 -94.531754)
		(end 274.681188 -94.822518)
		(width 0.0889)
		(layer "In11.Cu")
		(net "M_F_DQ<38>")
	)
	(arc
		(start 274.687538 -96.814386)
		(mid 274.741008 -97.009449)
		(end 274.692364 -97.2058)
		(width 0.0889)
		(layer "In11.Cu")
		(net "M_F_DQ<38>")
	)
	(segment
		(start 272.052288 -93.052138)
		(end 272.623788 -93.052138)
		(width 0.1651)
		(layer "F.Cu")
		(net "M_F_DQ<37>")
	)
	(segment
		(start 279.700482 -152.273)
		(end 279.699974 -152.278842)
		(width 0.1651)
		(layer "F.Cu")
		(net "M_F_DQ<37>")
	)
	(segment
		(start 279.699974 -152.278842)
		(end 279.699974 -153.542746)
		(width 0.1651)
		(layer "F.Cu")
		(net "M_F_DQ<37>")
	)
	(via
		(at 272.623788 -93.052138)
		(size 0.508)
		(drill 0.254)
		(layers "F.Cu" "B.Cu")
		(net "M_F_DQ<37>")
	)
	(via
		(at 280.473658 -149.533356)
		(size 0.508)
		(drill 0.254)
		(layers "F.Cu" "B.Cu")
		(net "M_F_DQ<37>")
	)
	(via
		(at 279.699974 -153.542746)
		(size 0.508)
		(drill 0.254)
		(layers "F.Cu" "B.Cu")
		(net "M_F_DQ<37>")
	)
	(segment
		(start 280.549858 -147.478496)
		(end 280.549858 -149.457156)
		(width 0.1651)
		(layer "B.Cu")
		(net "M_F_DQ<37>")
	)
	(segment
		(start 280.550366 -147.478496)
		(end 280.549858 -147.478496)
		(width 0.1651)
		(layer "B.Cu")
		(net "M_F_DQ<37>")
	)
	(segment
		(start 280.549858 -149.457156)
		(end 280.473658 -149.533356)
		(width 0.1651)
		(layer "B.Cu")
		(net "M_F_DQ<37>")
	)
	(segment
		(start 271.424908 -99.280218)
		(end 271.418558 -99.290886)
		(width 0.0889)
		(layer "In11.Cu")
		(net "M_F_DQ<37>")
	)
	(segment
		(start 280.9748 -132.028946)
		(end 280.9748 -133.985)
		(width 0.14224)
		(layer "In11.Cu")
		(net "M_F_DQ<37>")
	)
	(segment
		(start 280.9748 -138.7348)
		(end 280.797 -138.9126)
		(width 0.14224)
		(layer "In11.Cu")
		(net "M_F_DQ<37>")
	)
	(segment
		(start 271.418558 -97.309686)
		(end 271.413732 -97.318322)
		(width 0.0889)
		(layer "In11.Cu")
		(net "M_F_DQ<37>")
	)
	(segment
		(start 280.023062 -149.9616)
		(end 280.023062 -150.5204)
		(width 0.14224)
		(layer "In11.Cu")
		(net "M_F_DQ<37>")
	)
	(segment
		(start 280.9748 -136.702546)
		(end 280.9748 -138.7348)
		(width 0.14224)
		(layer "In11.Cu")
		(net "M_F_DQ<37>")
	)
	(segment
		(start 274.73275 -120.10898)
		(end 274.73275 -120.327928)
		(width 0.14224)
		(layer "In11.Cu")
		(net "M_F_DQ<37>")
	)
	(segment
		(start 280.793444 -141.47419)
		(end 280.9748 -141.655546)
		(width 0.14224)
		(layer "In11.Cu")
		(net "M_F_DQ<37>")
	)
	(segment
		(start 280.9748 -146.268186)
		(end 280.9748 -148.463)
		(width 0.14224)
		(layer "In11.Cu")
		(net "M_F_DQ<37>")
	)
	(segment
		(start 274.982686 -120.577864)
		(end 275.201634 -120.577864)
		(width 0.14224)
		(layer "In11.Cu")
		(net "M_F_DQ<37>")
	)
	(segment
		(start 280.473658 -149.533356)
		(end 280.451306 -149.533356)
		(width 0.14224)
		(layer "In11.Cu")
		(net "M_F_DQ<37>")
	)
	(segment
		(start 271.418558 -99.290886)
		(end 271.413732 -99.299522)
		(width 0.0889)
		(layer "In11.Cu")
		(net "M_F_DQ<37>")
	)
	(segment
		(start 275.047456 -119.794274)
		(end 274.73275 -120.10898)
		(width 0.14224)
		(layer "In11.Cu")
		(net "M_F_DQ<37>")
	)
	(segment
		(start 281.010614 -145.454624)
		(end 280.858214 -145.607024)
		(width 0.14224)
		(layer "In11.Cu")
		(net "M_F_DQ<37>")
	)
	(segment
		(start 280.793444 -140.922756)
		(end 280.793444 -141.47419)
		(width 0.14224)
		(layer "In11.Cu")
		(net "M_F_DQ<37>")
	)
	(segment
		(start 280.9748 -148.463)
		(end 280.858214 -148.579586)
		(width 0.14224)
		(layer "In11.Cu")
		(net "M_F_DQ<37>")
	)
	(segment
		(start 280.883614 -143.728186)
		(end 280.883614 -144.271238)
		(width 0.14224)
		(layer "In11.Cu")
		(net "M_F_DQ<37>")
	)
	(segment
		(start 281.0256 -140.6906)
		(end 280.793444 -140.922756)
		(width 0.14224)
		(layer "In11.Cu")
		(net "M_F_DQ<37>")
	)
	(segment
		(start 280.150062 -150.6474)
		(end 280.150062 -151.129746)
		(width 0.14224)
		(layer "In11.Cu")
		(net "M_F_DQ<37>")
	)
	(segment
		(start 275.985224 -120.732042)
		(end 275.670518 -121.046748)
		(width 0.14224)
		(layer "In11.Cu")
		(net "M_F_DQ<37>")
	)
	(segment
		(start 272.223738 -101.14407)
		(end 272.223738 -103.864156)
		(width 0.0889)
		(layer "In11.Cu")
		(net "M_F_DQ<37>")
	)
	(segment
		(start 281.0256 -136.016746)
		(end 280.831544 -136.210802)
		(width 0.14224)
		(layer "In11.Cu")
		(net "M_F_DQ<37>")
	)
	(segment
		(start 280.883614 -144.271238)
		(end 281.010614 -144.398238)
		(width 0.14224)
		(layer "In11.Cu")
		(net "M_F_DQ<37>")
	)
	(segment
		(start 280.807414 -134.52856)
		(end 281.0256 -134.746746)
		(width 0.14224)
		(layer "In11.Cu")
		(net "M_F_DQ<37>")
	)
	(segment
		(start 271.418558 -94.737936)
		(end 271.424908 -94.748604)
		(width 0.0889)
		(layer "In11.Cu")
		(net "M_F_DQ<37>")
	)
	(segment
		(start 275.735288 -120.263158)
		(end 275.985224 -120.513094)
		(width 0.14224)
		(layer "In11.Cu")
		(net "M_F_DQ<37>")
	)
	(segment
		(start 280.858214 -148.579586)
		(end 280.858214 -149.1488)
		(width 0.14224)
		(layer "In11.Cu")
		(net "M_F_DQ<37>")
	)
	(segment
		(start 280.48712 -128.929892)
		(end 280.883614 -129.326386)
		(width 0.14224)
		(layer "In11.Cu")
		(net "M_F_DQ<37>")
	)
	(segment
		(start 271.786858 -93.147388)
		(end 271.754092 -93.147388)
		(width 0.0889)
		(layer "In11.Cu")
		(net "M_F_DQ<37>")
	)
	(segment
		(start 280.7716 -131.825746)
		(end 280.9748 -132.028946)
		(width 0.14224)
		(layer "In11.Cu")
		(net "M_F_DQ<37>")
	)
	(segment
		(start 272.66392 -104.304338)
		(end 272.604738 -104.36352)
		(width 0.14224)
		(layer "In11.Cu")
		(net "M_F_DQ<37>")
	)
	(segment
		(start 280.797 -139.4206)
		(end 281.0256 -139.6492)
		(width 0.14224)
		(layer "In11.Cu")
		(net "M_F_DQ<37>")
	)
	(segment
		(start 280.099262 -151.993854)
		(end 280.099262 -152.348946)
		(width 0.14224)
		(layer "In11.Cu")
		(net "M_F_DQ<37>")
	)
	(segment
		(start 271.424908 -96.308418)
		(end 271.418558 -96.319086)
		(width 0.0889)
		(layer "In11.Cu")
		(net "M_F_DQ<37>")
	)
	(segment
		(start 274.73275 -120.327928)
		(end 274.982686 -120.577864)
		(width 0.14224)
		(layer "In11.Cu")
		(net "M_F_DQ<37>")
	)
	(segment
		(start 280.150062 -151.129746)
		(end 279.861264 -151.418544)
		(width 0.14224)
		(layer "In11.Cu")
		(net "M_F_DQ<37>")
	)
	(segment
		(start 280.831544 -136.55929)
		(end 280.9748 -136.702546)
		(width 0.14224)
		(layer "In11.Cu")
		(net "M_F_DQ<37>")
	)
	(segment
		(start 271.424908 -98.289618)
		(end 271.418558 -98.300286)
		(width 0.0889)
		(layer "In11.Cu")
		(net "M_F_DQ<37>")
	)
	(segment
		(start 274.044918 -119.640096)
		(end 274.263866 -119.640096)
		(width 0.14224)
		(layer "In11.Cu")
		(net "M_F_DQ<37>")
	)
	(segment
		(start 279.972262 -153.542746)
		(end 279.699974 -153.542746)
		(width 0.14224)
		(layer "In11.Cu")
		(net "M_F_DQ<37>")
	)
	(segment
		(start 280.124662 -153.390346)
		(end 279.972262 -153.542746)
		(width 0.14224)
		(layer "In11.Cu")
		(net "M_F_DQ<37>")
	)
	(segment
		(start 275.51634 -120.263158)
		(end 275.735288 -120.263158)
		(width 0.14224)
		(layer "In11.Cu")
		(net "M_F_DQ<37>")
	)
	(segment
		(start 280.9748 -133.985)
		(end 280.807414 -134.152386)
		(width 0.14224)
		(layer "In11.Cu")
		(net "M_F_DQ<37>")
	)
	(segment
		(start 280.124662 -153.162254)
		(end 280.124662 -153.390346)
		(width 0.14224)
		(layer "In11.Cu")
		(net "M_F_DQ<37>")
	)
	(segment
		(start 280.451306 -149.533356)
		(end 280.023062 -149.9616)
		(width 0.14224)
		(layer "In11.Cu")
		(net "M_F_DQ<37>")
	)
	(segment
		(start 271.418558 -96.319086)
		(end 271.413732 -96.327722)
		(width 0.0889)
		(layer "In11.Cu")
		(net "M_F_DQ<37>")
	)
	(segment
		(start 280.48712 -126.082298)
		(end 280.48712 -128.929892)
		(width 0.14224)
		(layer "In11.Cu")
		(net "M_F_DQ<37>")
	)
	(segment
		(start 274.578572 -119.32539)
		(end 274.79752 -119.32539)
		(width 0.14224)
		(layer "In11.Cu")
		(net "M_F_DQ<37>")
	)
	(segment
		(start 271.497806 -100.418138)
		(end 272.223738 -101.14407)
		(width 0.0889)
		(layer "In11.Cu")
		(net "M_F_DQ<37>")
	)
	(segment
		(start 272.604738 -104.36352)
		(end 272.604738 -118.199916)
		(width 0.14224)
		(layer "In11.Cu")
		(net "M_F_DQ<37>")
	)
	(segment
		(start 272.604738 -118.199916)
		(end 274.044918 -119.640096)
		(width 0.14224)
		(layer "In11.Cu")
		(net "M_F_DQ<37>")
	)
	(segment
		(start 275.670518 -121.265696)
		(end 280.48712 -126.082298)
		(width 0.14224)
		(layer "In11.Cu")
		(net "M_F_DQ<37>")
	)
	(segment
		(start 281.010614 -144.398238)
		(end 281.010614 -145.454624)
		(width 0.14224)
		(layer "In11.Cu")
		(net "M_F_DQ<37>")
	)
	(segment
		(start 280.023062 -150.5204)
		(end 280.150062 -150.6474)
		(width 0.14224)
		(layer "In11.Cu")
		(net "M_F_DQ<37>")
	)
	(segment
		(start 280.797 -138.9126)
		(end 280.797 -139.4206)
		(width 0.14224)
		(layer "In11.Cu")
		(net "M_F_DQ<37>")
	)
	(segment
		(start 279.861264 -151.418544)
		(end 279.861264 -151.755856)
		(width 0.14224)
		(layer "In11.Cu")
		(net "M_F_DQ<37>")
	)
	(segment
		(start 275.201634 -120.577864)
		(end 275.51634 -120.263158)
		(width 0.14224)
		(layer "In11.Cu")
		(net "M_F_DQ<37>")
	)
	(segment
		(start 280.831544 -136.210802)
		(end 280.831544 -136.55929)
		(width 0.14224)
		(layer "In11.Cu")
		(net "M_F_DQ<37>")
	)
	(segment
		(start 279.861264 -151.755856)
		(end 280.099262 -151.993854)
		(width 0.14224)
		(layer "In11.Cu")
		(net "M_F_DQ<37>")
	)
	(segment
		(start 271.418558 -98.300286)
		(end 271.413732 -98.308922)
		(width 0.0889)
		(layer "In11.Cu")
		(net "M_F_DQ<37>")
	)
	(segment
		(start 280.9748 -143.637)
		(end 280.883614 -143.728186)
		(width 0.14224)
		(layer "In11.Cu")
		(net "M_F_DQ<37>")
	)
	(segment
		(start 275.985224 -120.513094)
		(end 275.985224 -120.732042)
		(width 0.14224)
		(layer "In11.Cu")
		(net "M_F_DQ<37>")
	)
	(segment
		(start 280.858214 -149.1488)
		(end 280.473658 -149.533356)
		(width 0.14224)
		(layer "In11.Cu")
		(net "M_F_DQ<37>")
	)
	(segment
		(start 280.858214 -145.607024)
		(end 280.858214 -146.1516)
		(width 0.14224)
		(layer "In11.Cu")
		(net "M_F_DQ<37>")
	)
	(segment
		(start 279.861264 -152.586944)
		(end 279.861264 -152.898856)
		(width 0.14224)
		(layer "In11.Cu")
		(net "M_F_DQ<37>")
	)
	(segment
		(start 280.883614 -129.920238)
		(end 281.1018 -130.138424)
		(width 0.14224)
		(layer "In11.Cu")
		(net "M_F_DQ<37>")
	)
	(segment
		(start 280.099262 -152.348946)
		(end 279.861264 -152.586944)
		(width 0.14224)
		(layer "In11.Cu")
		(net "M_F_DQ<37>")
	)
	(segment
		(start 280.807414 -134.152386)
		(end 280.807414 -134.52856)
		(width 0.14224)
		(layer "In11.Cu")
		(net "M_F_DQ<37>")
	)
	(segment
		(start 275.670518 -121.046748)
		(end 275.670518 -121.265696)
		(width 0.14224)
		(layer "In11.Cu")
		(net "M_F_DQ<37>")
	)
	(segment
		(start 281.0256 -139.6492)
		(end 281.0256 -140.6906)
		(width 0.14224)
		(layer "In11.Cu")
		(net "M_F_DQ<37>")
	)
	(segment
		(start 271.497806 -99.986338)
		(end 271.497806 -100.418138)
		(width 0.0889)
		(layer "In11.Cu")
		(net "M_F_DQ<37>")
	)
	(segment
		(start 281.0256 -134.746746)
		(end 281.0256 -136.016746)
		(width 0.14224)
		(layer "In11.Cu")
		(net "M_F_DQ<37>")
	)
	(segment
		(start 271.424908 -97.299018)
		(end 271.418558 -97.309686)
		(width 0.0889)
		(layer "In11.Cu")
		(net "M_F_DQ<37>")
	)
	(segment
		(start 274.79752 -119.32539)
		(end 275.047456 -119.575326)
		(width 0.14224)
		(layer "In11.Cu")
		(net "M_F_DQ<37>")
	)
	(segment
		(start 281.1018 -131.1148)
		(end 280.7716 -131.445)
		(width 0.14224)
		(layer "In11.Cu")
		(net "M_F_DQ<37>")
	)
	(segment
		(start 271.418558 -95.328486)
		(end 271.413732 -95.337122)
		(width 0.0889)
		(layer "In11.Cu")
		(net "M_F_DQ<37>")
	)
	(segment
		(start 280.883614 -129.326386)
		(end 280.883614 -129.920238)
		(width 0.14224)
		(layer "In11.Cu")
		(net "M_F_DQ<37>")
	)
	(segment
		(start 272.223738 -103.864156)
		(end 272.66392 -104.304338)
		(width 0.0889)
		(layer "In11.Cu")
		(net "M_F_DQ<37>")
	)
	(segment
		(start 275.047456 -119.575326)
		(end 275.047456 -119.794274)
		(width 0.14224)
		(layer "In11.Cu")
		(net "M_F_DQ<37>")
	)
	(segment
		(start 274.263866 -119.640096)
		(end 274.578572 -119.32539)
		(width 0.14224)
		(layer "In11.Cu")
		(net "M_F_DQ<37>")
	)
	(segment
		(start 281.1018 -130.138424)
		(end 281.1018 -131.1148)
		(width 0.14224)
		(layer "In11.Cu")
		(net "M_F_DQ<37>")
	)
	(segment
		(start 280.9748 -141.655546)
		(end 280.9748 -143.637)
		(width 0.14224)
		(layer "In11.Cu")
		(net "M_F_DQ<37>")
	)
	(segment
		(start 280.858214 -146.1516)
		(end 280.9748 -146.268186)
		(width 0.14224)
		(layer "In11.Cu")
		(net "M_F_DQ<37>")
	)
	(segment
		(start 280.7716 -131.445)
		(end 280.7716 -131.825746)
		(width 0.14224)
		(layer "In11.Cu")
		(net "M_F_DQ<37>")
	)
	(segment
		(start 279.861264 -152.898856)
		(end 280.124662 -153.162254)
		(width 0.14224)
		(layer "In11.Cu")
		(net "M_F_DQ<37>")
	)
	(arc
		(start 271.418558 -94.33814)
		(mid 271.365059 -94.538038)
		(end 271.418558 -94.737936)
		(width 0.0889)
		(layer "In11.Cu")
		(net "M_F_DQ<37>")
	)
	(arc
		(start 271.418558 -97.709736)
		(mid 271.49778 -97.998854)
		(end 271.424908 -98.289618)
		(width 0.0889)
		(layer "In11.Cu")
		(net "M_F_DQ<37>")
	)
	(arc
		(start 271.413732 -96.327722)
		(mid 271.364977 -96.524074)
		(end 271.418558 -96.719136)
		(width 0.0889)
		(layer "In11.Cu")
		(net "M_F_DQ<37>")
	)
	(arc
		(start 271.413732 -99.299522)
		(mid 271.364977 -99.495874)
		(end 271.418558 -99.690936)
		(width 0.0889)
		(layer "In11.Cu")
		(net "M_F_DQ<37>")
	)
	(arc
		(start 271.418558 -93.747336)
		(mid 271.497689 -94.042738)
		(end 271.418558 -94.33814)
		(width 0.0889)
		(layer "In11.Cu")
		(net "M_F_DQ<37>")
	)
	(arc
		(start 271.418558 -99.690936)
		(mid 271.477625 -99.833422)
		(end 271.497806 -99.986338)
		(width 0.0889)
		(layer "In11.Cu")
		(net "M_F_DQ<37>")
	)
	(arc
		(start 271.418558 -96.719136)
		(mid 271.49778 -97.008254)
		(end 271.424908 -97.299018)
		(width 0.0889)
		(layer "In11.Cu")
		(net "M_F_DQ<37>")
	)
	(arc
		(start 271.413732 -97.318322)
		(mid 271.364977 -97.514674)
		(end 271.418558 -97.709736)
		(width 0.0889)
		(layer "In11.Cu")
		(net "M_F_DQ<37>")
	)
	(arc
		(start 271.754092 -93.147388)
		(mid 271.415977 -93.35209)
		(end 271.418558 -93.747336)
		(width 0.0889)
		(layer "In11.Cu")
		(net "M_F_DQ<37>")
	)
	(arc
		(start 272.623788 -93.052138)
		(mid 272.208024 -93.123497)
		(end 271.786858 -93.147388)
		(width 0.0889)
		(layer "In11.Cu")
		(net "M_F_DQ<37>")
	)
	(arc
		(start 271.418558 -98.700336)
		(mid 271.49778 -98.989454)
		(end 271.424908 -99.280218)
		(width 0.0889)
		(layer "In11.Cu")
		(net "M_F_DQ<37>")
	)
	(arc
		(start 271.413732 -95.337122)
		(mid 271.364977 -95.533474)
		(end 271.418558 -95.728536)
		(width 0.0889)
		(layer "In11.Cu")
		(net "M_F_DQ<37>")
	)
	(arc
		(start 271.424908 -94.748604)
		(mid 271.497706 -95.039367)
		(end 271.418558 -95.328486)
		(width 0.0889)
		(layer "In11.Cu")
		(net "M_F_DQ<37>")
	)
	(arc
		(start 271.413732 -98.308922)
		(mid 271.364977 -98.505274)
		(end 271.418558 -98.700336)
		(width 0.0889)
		(layer "In11.Cu")
		(net "M_F_DQ<37>")
	)
	(arc
		(start 271.418558 -95.728536)
		(mid 271.49778 -96.017654)
		(end 271.424908 -96.308418)
		(width 0.0889)
		(layer "In11.Cu")
		(net "M_F_DQ<37>")
	)
	(segment
		(start 280.451814 -155.0162)
		(end 280.549858 -155.547568)
		(width 0.1651)
		(layer "F.Cu")
		(net "M_F_DQ<36>")
	)
	(segment
		(start 272.052288 -91.070938)
		(end 272.623788 -91.070938)
		(width 0.1016)
		(layer "F.Cu")
		(net "M_F_DQ<36>")
	)
	(segment
		(start 280.549858 -156.87294)
		(end 280.550366 -156.87294)
		(width 0.1651)
		(layer "F.Cu")
		(net "M_F_DQ<36>")
	)
	(segment
		(start 280.549858 -155.547568)
		(end 280.549858 -156.87294)
		(width 0.1651)
		(layer "F.Cu")
		(net "M_F_DQ<36>")
	)
	(via
		(at 272.623788 -91.070938)
		(size 0.508)
		(drill 0.254)
		(layers "F.Cu" "B.Cu")
		(net "M_F_DQ<36>")
	)
	(via
		(at 279.699974 -150.814278)
		(size 0.508)
		(drill 0.254)
		(layers "F.Cu" "B.Cu")
		(net "M_F_DQ<36>")
	)
	(via
		(at 280.451814 -155.0162)
		(size 0.508)
		(drill 0.254)
		(layers "F.Cu" "B.Cu")
		(net "M_F_DQ<36>")
	)
	(segment
		(start 279.699974 -152.078182)
		(end 279.699974 -150.814278)
		(width 0.1651)
		(layer "B.Cu")
		(net "M_F_DQ<36>")
	)
	(segment
		(start 279.700482 -152.078436)
		(end 279.699974 -152.078182)
		(width 0.1651)
		(layer "B.Cu")
		(net "M_F_DQ<36>")
	)
	(segment
		(start 271.253458 -97.214436)
		(end 271.247108 -97.225104)
		(width 0.0889)
		(layer "In11.Cu")
		(net "M_F_DQ<36>")
	)
	(segment
		(start 280.197814 -141.5542)
		(end 280.1112 -141.640814)
		(width 0.14224)
		(layer "In11.Cu")
		(net "M_F_DQ<36>")
	)
	(segment
		(start 280.1366 -136.713214)
		(end 280.1366 -138.811)
		(width 0.14224)
		(layer "In11.Cu")
		(net "M_F_DQ<36>")
	)
	(segment
		(start 280.197814 -129.767838)
		(end 279.969214 -129.996438)
		(width 0.14224)
		(layer "In11.Cu")
		(net "M_F_DQ<36>")
	)
	(segment
		(start 272.623788 -91.070938)
		(end 272.623788 -91.409012)
		(width 0.0889)
		(layer "In11.Cu")
		(net "M_F_DQ<36>")
	)
	(segment
		(start 279.266904 -151.247348)
		(end 279.266904 -153.78049)
		(width 0.14224)
		(layer "In11.Cu")
		(net "M_F_DQ<36>")
	)
	(segment
		(start 279.266904 -153.78049)
		(end 279.424892 -153.938478)
		(width 0.14224)
		(layer "In11.Cu")
		(net "M_F_DQ<36>")
	)
	(segment
		(start 280.223214 -138.897614)
		(end 280.223214 -139.333478)
		(width 0.14224)
		(layer "In11.Cu")
		(net "M_F_DQ<36>")
	)
	(segment
		(start 279.969214 -131.180078)
		(end 280.197814 -131.408678)
		(width 0.14224)
		(layer "In11.Cu")
		(net "M_F_DQ<36>")
	)
	(segment
		(start 280.197814 -141.009878)
		(end 280.197814 -141.5542)
		(width 0.14224)
		(layer "In11.Cu")
		(net "M_F_DQ<36>")
	)
	(segment
		(start 280.200862 -155.0162)
		(end 280.451814 -155.0162)
		(width 0.14224)
		(layer "In11.Cu")
		(net "M_F_DQ<36>")
	)
	(segment
		(start 280.197814 -134.456932)
		(end 279.969214 -134.685532)
		(width 0.14224)
		(layer "In11.Cu")
		(net "M_F_DQ<36>")
	)
	(segment
		(start 279.969214 -135.951468)
		(end 280.223214 -136.205468)
		(width 0.14224)
		(layer "In11.Cu")
		(net "M_F_DQ<36>")
	)
	(segment
		(start 279.801828 -128.940814)
		(end 280.197814 -129.3368)
		(width 0.14224)
		(layer "In11.Cu")
		(net "M_F_DQ<36>")
	)
	(segment
		(start 279.969214 -129.996438)
		(end 279.969214 -131.180078)
		(width 0.14224)
		(layer "In11.Cu")
		(net "M_F_DQ<36>")
	)
	(segment
		(start 279.969214 -140.781278)
		(end 280.197814 -141.009878)
		(width 0.14224)
		(layer "In11.Cu")
		(net "M_F_DQ<36>")
	)
	(segment
		(start 280.197814 -131.408678)
		(end 280.197814 -131.953)
		(width 0.14224)
		(layer "In11.Cu")
		(net "M_F_DQ<36>")
	)
	(segment
		(start 279.931622 -144.324578)
		(end 279.931622 -145.527776)
		(width 0.14224)
		(layer "In11.Cu")
		(net "M_F_DQ<36>")
	)
	(segment
		(start 279.4254 -150.539704)
		(end 279.699974 -150.814278)
		(width 0.14224)
		(layer "In11.Cu")
		(net "M_F_DQ<36>")
	)
	(segment
		(start 271.253458 -98.205036)
		(end 271.247108 -98.215704)
		(width 0.0889)
		(layer "In11.Cu")
		(net "M_F_DQ<36>")
	)
	(segment
		(start 280.197814 -144.058386)
		(end 279.931622 -144.324578)
		(width 0.14224)
		(layer "In11.Cu")
		(net "M_F_DQ<36>")
	)
	(segment
		(start 280.1366 -148.5392)
		(end 280.185114 -148.587714)
		(width 0.14224)
		(layer "In11.Cu")
		(net "M_F_DQ<36>")
	)
	(segment
		(start 280.1112 -143.6624)
		(end 280.197814 -143.749014)
		(width 0.14224)
		(layer "In11.Cu")
		(net "M_F_DQ<36>")
	)
	(segment
		(start 271.776444 -92.956888)
		(end 271.743678 -92.956888)
		(width 0.0889)
		(layer "In11.Cu")
		(net "M_F_DQ<36>")
	)
	(segment
		(start 271.307052 -99.986338)
		(end 271.307052 -100.496878)
		(width 0.0889)
		(layer "In11.Cu")
		(net "M_F_DQ<36>")
	)
	(segment
		(start 280.1366 -138.811)
		(end 280.223214 -138.897614)
		(width 0.14224)
		(layer "In11.Cu")
		(net "M_F_DQ<36>")
	)
	(segment
		(start 271.253458 -99.195636)
		(end 271.247108 -99.206304)
		(width 0.0889)
		(layer "In11.Cu")
		(net "M_F_DQ<36>")
	)
	(segment
		(start 280.1366 -132.014214)
		(end 280.1366 -134.0612)
		(width 0.14224)
		(layer "In11.Cu")
		(net "M_F_DQ<36>")
	)
	(segment
		(start 272.02892 -104.403652)
		(end 271.969738 -104.462834)
		(width 0.14224)
		(layer "In11.Cu")
		(net "M_F_DQ<36>")
	)
	(segment
		(start 279.931622 -145.527776)
		(end 280.185114 -145.781268)
		(width 0.14224)
		(layer "In11.Cu")
		(net "M_F_DQ<36>")
	)
	(segment
		(start 279.699974 -150.814278)
		(end 279.266904 -151.247348)
		(width 0.14224)
		(layer "In11.Cu")
		(net "M_F_DQ<36>")
	)
	(segment
		(start 279.801828 -126.231142)
		(end 279.801828 -128.940814)
		(width 0.14224)
		(layer "In11.Cu")
		(net "M_F_DQ<36>")
	)
	(segment
		(start 279.4254 -149.719792)
		(end 279.4254 -150.539704)
		(width 0.14224)
		(layer "In11.Cu")
		(net "M_F_DQ<36>")
	)
	(segment
		(start 280.185114 -145.781268)
		(end 280.185114 -146.177)
		(width 0.14224)
		(layer "In11.Cu")
		(net "M_F_DQ<36>")
	)
	(segment
		(start 271.969738 -118.399052)
		(end 279.801828 -126.231142)
		(width 0.14224)
		(layer "In11.Cu")
		(net "M_F_DQ<36>")
	)
	(segment
		(start 280.223214 -136.6266)
		(end 280.1366 -136.713214)
		(width 0.14224)
		(layer "In11.Cu")
		(net "M_F_DQ<36>")
	)
	(segment
		(start 280.1366 -146.225514)
		(end 280.1366 -148.5392)
		(width 0.14224)
		(layer "In11.Cu")
		(net "M_F_DQ<36>")
	)
	(segment
		(start 271.969738 -104.462834)
		(end 271.969738 -118.399052)
		(width 0.14224)
		(layer "In11.Cu")
		(net "M_F_DQ<36>")
	)
	(segment
		(start 280.1112 -141.640814)
		(end 280.1112 -143.6624)
		(width 0.14224)
		(layer "In11.Cu")
		(net "M_F_DQ<36>")
	)
	(segment
		(start 280.185114 -146.177)
		(end 280.1366 -146.225514)
		(width 0.14224)
		(layer "In11.Cu")
		(net "M_F_DQ<36>")
	)
	(segment
		(start 271.247108 -94.822518)
		(end 271.253458 -94.833186)
		(width 0.0889)
		(layer "In11.Cu")
		(net "M_F_DQ<36>")
	)
	(segment
		(start 280.197814 -129.3368)
		(end 280.197814 -129.767838)
		(width 0.14224)
		(layer "In11.Cu")
		(net "M_F_DQ<36>")
	)
	(segment
		(start 271.258284 -96.2152)
		(end 271.253458 -96.223836)
		(width 0.0889)
		(layer "In11.Cu")
		(net "M_F_DQ<36>")
	)
	(segment
		(start 272.02892 -101.218746)
		(end 272.02892 -104.403652)
		(width 0.0889)
		(layer "In11.Cu")
		(net "M_F_DQ<36>")
	)
	(segment
		(start 279.424892 -153.938478)
		(end 279.424892 -154.24023)
		(width 0.14224)
		(layer "In11.Cu")
		(net "M_F_DQ<36>")
	)
	(segment
		(start 280.223214 -139.333478)
		(end 279.969214 -139.587478)
		(width 0.14224)
		(layer "In11.Cu")
		(net "M_F_DQ<36>")
	)
	(segment
		(start 280.197814 -143.749014)
		(end 280.197814 -144.058386)
		(width 0.14224)
		(layer "In11.Cu")
		(net "M_F_DQ<36>")
	)
	(segment
		(start 280.223214 -136.205468)
		(end 280.223214 -136.6266)
		(width 0.14224)
		(layer "In11.Cu")
		(net "M_F_DQ<36>")
	)
	(segment
		(start 280.1366 -134.0612)
		(end 280.197814 -134.122414)
		(width 0.14224)
		(layer "In11.Cu")
		(net "M_F_DQ<36>")
	)
	(segment
		(start 271.258284 -98.1964)
		(end 271.253458 -98.205036)
		(width 0.0889)
		(layer "In11.Cu")
		(net "M_F_DQ<36>")
	)
	(segment
		(start 271.253458 -96.223836)
		(end 271.247108 -96.234504)
		(width 0.0889)
		(layer "In11.Cu")
		(net "M_F_DQ<36>")
	)
	(segment
		(start 271.258284 -99.187)
		(end 271.253458 -99.195636)
		(width 0.0889)
		(layer "In11.Cu")
		(net "M_F_DQ<36>")
	)
	(segment
		(start 272.623788 -91.409012)
		(end 272.558764 -91.474036)
		(width 0.0889)
		(layer "In11.Cu")
		(net "M_F_DQ<36>")
	)
	(segment
		(start 280.197814 -134.122414)
		(end 280.197814 -134.456932)
		(width 0.14224)
		(layer "In11.Cu")
		(net "M_F_DQ<36>")
	)
	(segment
		(start 279.969214 -139.587478)
		(end 279.969214 -140.781278)
		(width 0.14224)
		(layer "In11.Cu")
		(net "M_F_DQ<36>")
	)
	(segment
		(start 271.258284 -97.2058)
		(end 271.253458 -97.214436)
		(width 0.0889)
		(layer "In11.Cu")
		(net "M_F_DQ<36>")
	)
	(segment
		(start 280.185114 -148.587714)
		(end 280.185114 -148.960078)
		(width 0.14224)
		(layer "In11.Cu")
		(net "M_F_DQ<36>")
	)
	(segment
		(start 271.307052 -100.496878)
		(end 272.02892 -101.218746)
		(width 0.0889)
		(layer "In11.Cu")
		(net "M_F_DQ<36>")
	)
	(segment
		(start 280.197814 -131.953)
		(end 280.1366 -132.014214)
		(width 0.14224)
		(layer "In11.Cu")
		(net "M_F_DQ<36>")
	)
	(segment
		(start 279.424892 -154.24023)
		(end 280.200862 -155.0162)
		(width 0.14224)
		(layer "In11.Cu")
		(net "M_F_DQ<36>")
	)
	(segment
		(start 279.969214 -134.685532)
		(end 279.969214 -135.951468)
		(width 0.14224)
		(layer "In11.Cu")
		(net "M_F_DQ<36>")
	)
	(segment
		(start 280.185114 -148.960078)
		(end 279.4254 -149.719792)
		(width 0.14224)
		(layer "In11.Cu")
		(net "M_F_DQ<36>")
	)
	(arc
		(start 271.253458 -99.786186)
		(mid 271.293434 -99.882731)
		(end 271.307052 -99.986338)
		(width 0.0889)
		(layer "In11.Cu")
		(net "M_F_DQ<36>")
	)
	(arc
		(start 271.247108 -98.215704)
		(mid 271.17431 -98.506467)
		(end 271.253458 -98.795586)
		(width 0.0889)
		(layer "In11.Cu")
		(net "M_F_DQ<36>")
	)
	(arc
		(start 271.253458 -98.795586)
		(mid 271.306928 -98.990649)
		(end 271.258284 -99.187)
		(width 0.0889)
		(layer "In11.Cu")
		(net "M_F_DQ<36>")
	)
	(arc
		(start 271.743678 -92.956888)
		(mid 271.248201 -93.261331)
		(end 271.253458 -93.84284)
		(width 0.0889)
		(layer "In11.Cu")
		(net "M_F_DQ<36>")
	)
	(arc
		(start 271.247108 -97.225104)
		(mid 271.17431 -97.515867)
		(end 271.253458 -97.804986)
		(width 0.0889)
		(layer "In11.Cu")
		(net "M_F_DQ<36>")
	)
	(arc
		(start 271.253458 -93.84284)
		(mid 271.306957 -94.042738)
		(end 271.253458 -94.242636)
		(width 0.0889)
		(layer "In11.Cu")
		(net "M_F_DQ<36>")
	)
	(arc
		(start 271.253458 -97.804986)
		(mid 271.306928 -98.000049)
		(end 271.258284 -98.1964)
		(width 0.0889)
		(layer "In11.Cu")
		(net "M_F_DQ<36>")
	)
	(arc
		(start 271.253458 -95.232982)
		(mid 271.174327 -95.528384)
		(end 271.253458 -95.823786)
		(width 0.0889)
		(layer "In11.Cu")
		(net "M_F_DQ<36>")
	)
	(arc
		(start 271.253458 -94.833186)
		(mid 271.306957 -95.033084)
		(end 271.253458 -95.232982)
		(width 0.0889)
		(layer "In11.Cu")
		(net "M_F_DQ<36>")
	)
	(arc
		(start 271.253458 -95.823786)
		(mid 271.306928 -96.018849)
		(end 271.258284 -96.2152)
		(width 0.0889)
		(layer "In11.Cu")
		(net "M_F_DQ<36>")
	)
	(arc
		(start 271.247108 -96.234504)
		(mid 271.17431 -96.525267)
		(end 271.253458 -96.814386)
		(width 0.0889)
		(layer "In11.Cu")
		(net "M_F_DQ<36>")
	)
	(arc
		(start 272.558764 -91.474036)
		(mid 272.096404 -91.794606)
		(end 272.111978 -92.35694)
		(width 0.0889)
		(layer "In11.Cu")
		(net "M_F_DQ<36>")
	)
	(arc
		(start 272.111978 -92.35694)
		(mid 272.114561 -92.752187)
		(end 271.776444 -92.956888)
		(width 0.0889)
		(layer "In11.Cu")
		(net "M_F_DQ<36>")
	)
	(arc
		(start 271.253458 -94.242636)
		(mid 271.174236 -94.531754)
		(end 271.247108 -94.822518)
		(width 0.0889)
		(layer "In11.Cu")
		(net "M_F_DQ<36>")
	)
	(arc
		(start 271.247108 -99.206304)
		(mid 271.17431 -99.497067)
		(end 271.253458 -99.786186)
		(width 0.0889)
		(layer "In11.Cu")
		(net "M_F_DQ<36>")
	)
	(arc
		(start 271.253458 -96.814386)
		(mid 271.306928 -97.009449)
		(end 271.258284 -97.2058)
		(width 0.0889)
		(layer "In11.Cu")
		(net "M_F_DQ<36>")
	)
	(segment
		(start 287.350454 -152.273)
		(end 287.349946 -152.278842)
		(width 0.1651)
		(layer "F.Cu")
		(net "M_F_DQ<35>")
	)
	(segment
		(start 287.349946 -152.278842)
		(end 287.349946 -153.542746)
		(width 0.1651)
		(layer "F.Cu")
		(net "M_F_DQ<35>")
	)
	(segment
		(start 275.486114 -94.042738)
		(end 276.057614 -94.042738)
		(width 0.1651)
		(layer "F.Cu")
		(net "M_F_DQ<35>")
	)
	(via
		(at 287.349946 -153.542746)
		(size 0.508)
		(drill 0.254)
		(layers "F.Cu" "B.Cu")
		(net "M_F_DQ<35>")
	)
	(via
		(at 288.19983 -149.533356)
		(size 0.508)
		(drill 0.254)
		(layers "F.Cu" "B.Cu")
		(net "M_F_DQ<35>")
	)
	(via
		(at 276.057614 -94.042738)
		(size 0.508)
		(drill 0.254)
		(layers "F.Cu" "B.Cu")
		(net "M_F_DQ<35>")
	)
	(segment
		(start 288.200338 -147.478496)
		(end 288.19983 -147.478496)
		(width 0.1651)
		(layer "B.Cu")
		(net "M_F_DQ<35>")
	)
	(segment
		(start 288.19983 -147.478496)
		(end 288.19983 -149.533356)
		(width 0.1651)
		(layer "B.Cu")
		(net "M_F_DQ<35>")
	)
	(segment
		(start 287.749234 -149.9616)
		(end 287.749234 -150.391368)
		(width 0.14224)
		(layer "In11.Cu")
		(net "M_F_DQ<35>")
	)
	(segment
		(start 279.146 -105.156)
		(end 278.367744 -105.934256)
		(width 0.14224)
		(layer "In11.Cu")
		(net "M_F_DQ<35>")
	)
	(segment
		(start 276.057614 -93.704664)
		(end 275.999956 -93.647006)
		(width 0.0889)
		(layer "In11.Cu")
		(net "M_F_DQ<35>")
	)
	(segment
		(start 288.19983 -149.546564)
		(end 288.19983 -149.533356)
		(width 0.14224)
		(layer "In11.Cu")
		(net "M_F_DQ<35>")
	)
	(segment
		(start 288.261552 -128.347724)
		(end 288.416492 -128.502664)
		(width 0.14224)
		(layer "In11.Cu")
		(net "M_F_DQ<35>")
	)
	(segment
		(start 278.367744 -114.735356)
		(end 288.416492 -124.784104)
		(width 0.14224)
		(layer "In11.Cu")
		(net "M_F_DQ<35>")
	)
	(segment
		(start 278.286464 -101.271578)
		(end 278.281638 -101.280214)
		(width 0.0889)
		(layer "In11.Cu")
		(net "M_F_DQ<35>")
	)
	(segment
		(start 276.901148 -98.900234)
		(end 276.933914 -98.900234)
		(width 0.0889)
		(layer "In11.Cu")
		(net "M_F_DQ<35>")
	)
	(segment
		(start 288.416492 -129.666492)
		(end 288.8234 -130.0734)
		(width 0.14224)
		(layer "In11.Cu")
		(net "M_F_DQ<35>")
	)
	(segment
		(start 288.4678 -136.626346)
		(end 288.6202 -136.778746)
		(width 0.14224)
		(layer "In11.Cu")
		(net "M_F_DQ<35>")
	)
	(segment
		(start 288.567114 -131.953)
		(end 288.6202 -132.006086)
		(width 0.14224)
		(layer "In11.Cu")
		(net "M_F_DQ<35>")
	)
	(segment
		(start 288.567114 -134.088886)
		(end 288.567114 -134.573264)
		(width 0.14224)
		(layer "In11.Cu")
		(net "M_F_DQ<35>")
	)
	(segment
		(start 288.6202 -134.0358)
		(end 288.567114 -134.088886)
		(width 0.14224)
		(layer "In11.Cu")
		(net "M_F_DQ<35>")
	)
	(segment
		(start 287.749234 -150.391368)
		(end 287.793684 -150.435818)
		(width 0.14224)
		(layer "In11.Cu")
		(net "M_F_DQ<35>")
	)
	(segment
		(start 288.416492 -127.529844)
		(end 288.261552 -127.684784)
		(width 0.14224)
		(layer "In11.Cu")
		(net "M_F_DQ<35>")
	)
	(segment
		(start 288.6202 -146.217386)
		(end 288.6202 -148.4122)
		(width 0.14224)
		(layer "In11.Cu")
		(net "M_F_DQ<35>")
	)
	(segment
		(start 288.529014 -149.21738)
		(end 288.19983 -149.546564)
		(width 0.14224)
		(layer "In11.Cu")
		(net "M_F_DQ<35>")
	)
	(segment
		(start 288.567114 -134.573264)
		(end 288.732214 -134.738364)
		(width 0.14224)
		(layer "In11.Cu")
		(net "M_F_DQ<35>")
	)
	(segment
		(start 288.19983 -149.533356)
		(end 288.177478 -149.533356)
		(width 0.14224)
		(layer "In11.Cu")
		(net "M_F_DQ<35>")
	)
	(segment
		(start 275.717508 -94.822518)
		(end 275.711158 -94.833186)
		(width 0.0889)
		(layer "In11.Cu")
		(net "M_F_DQ<35>")
	)
	(segment
		(start 288.567114 -140.921486)
		(end 288.567114 -144.182338)
		(width 0.14224)
		(layer "In11.Cu")
		(net "M_F_DQ<35>")
	)
	(segment
		(start 288.6202 -132.006086)
		(end 288.6202 -134.0358)
		(width 0.14224)
		(layer "In11.Cu")
		(net "M_F_DQ<35>")
	)
	(segment
		(start 287.777936 -127.839724)
		(end 287.777936 -128.192784)
		(width 0.14224)
		(layer "In11.Cu")
		(net "M_F_DQ<35>")
	)
	(segment
		(start 278.292814 -102.25151)
		(end 278.277828 -102.277164)
		(width 0.0889)
		(layer "In11.Cu")
		(net "M_F_DQ<35>")
	)
	(segment
		(start 288.732214 -134.738364)
		(end 288.732214 -136.006332)
		(width 0.14224)
		(layer "In11.Cu")
		(net "M_F_DQ<35>")
	)
	(segment
		(start 279.146 -103.34244)
		(end 279.146 -105.156)
		(width 0.14224)
		(layer "In11.Cu")
		(net "M_F_DQ<35>")
	)
	(segment
		(start 288.177478 -149.533356)
		(end 287.749234 -149.9616)
		(width 0.14224)
		(layer "In11.Cu")
		(net "M_F_DQ<35>")
	)
	(segment
		(start 279.052274 -103.248714)
		(end 279.146 -103.34244)
		(width 0.14224)
		(layer "In11.Cu")
		(net "M_F_DQ<35>")
	)
	(segment
		(start 278.367744 -105.934256)
		(end 278.367744 -114.735356)
		(width 0.14224)
		(layer "In11.Cu")
		(net "M_F_DQ<35>")
	)
	(segment
		(start 288.783014 -144.398238)
		(end 288.783014 -145.556732)
		(width 0.14224)
		(layer "In11.Cu")
		(net "M_F_DQ<35>")
	)
	(segment
		(start 288.567114 -131.408678)
		(end 288.567114 -131.953)
		(width 0.14224)
		(layer "In11.Cu")
		(net "M_F_DQ<35>")
	)
	(segment
		(start 288.8234 -131.152392)
		(end 288.567114 -131.408678)
		(width 0.14224)
		(layer "In11.Cu")
		(net "M_F_DQ<35>")
	)
	(segment
		(start 277.75662 -99.395534)
		(end 277.799546 -99.395534)
		(width 0.0889)
		(layer "In11.Cu")
		(net "M_F_DQ<35>")
	)
	(segment
		(start 288.529014 -148.503386)
		(end 288.529014 -149.21738)
		(width 0.14224)
		(layer "In11.Cu")
		(net "M_F_DQ<35>")
	)
	(segment
		(start 288.554414 -138.851386)
		(end 288.554414 -139.608814)
		(width 0.14224)
		(layer "In11.Cu")
		(net "M_F_DQ<35>")
	)
	(segment
		(start 278.286464 -102.662228)
		(end 278.469852 -102.979474)
		(width 0.0889)
		(layer "In11.Cu")
		(net "M_F_DQ<35>")
	)
	(segment
		(start 288.554414 -139.608814)
		(end 288.60623 -139.66063)
		(width 0.1016)
		(layer "In11.Cu")
		(net "M_F_DQ<35>")
	)
	(segment
		(start 288.6202 -138.7856)
		(end 288.554414 -138.851386)
		(width 0.14224)
		(layer "In11.Cu")
		(net "M_F_DQ<35>")
	)
	(segment
		(start 288.261552 -127.684784)
		(end 287.932876 -127.684784)
		(width 0.14224)
		(layer "In11.Cu")
		(net "M_F_DQ<35>")
	)
	(segment
		(start 276.057614 -94.042738)
		(end 276.057614 -93.704664)
		(width 0.0889)
		(layer "In11.Cu")
		(net "M_F_DQ<35>")
	)
	(segment
		(start 287.800034 -153.04135)
		(end 287.800034 -153.364946)
		(width 0.14224)
		(layer "In11.Cu")
		(net "M_F_DQ<35>")
	)
	(segment
		(start 287.932876 -127.684784)
		(end 287.777936 -127.839724)
		(width 0.14224)
		(layer "In11.Cu")
		(net "M_F_DQ<35>")
	)
	(segment
		(start 288.529014 -146.1262)
		(end 288.6202 -146.217386)
		(width 0.14224)
		(layer "In11.Cu")
		(net "M_F_DQ<35>")
	)
	(segment
		(start 287.511236 -152.752552)
		(end 287.800034 -153.04135)
		(width 0.14224)
		(layer "In11.Cu")
		(net "M_F_DQ<35>")
	)
	(segment
		(start 288.8234 -130.0734)
		(end 288.8234 -131.152392)
		(width 0.14224)
		(layer "In11.Cu")
		(net "M_F_DQ<35>")
	)
	(segment
		(start 287.511236 -151.660352)
		(end 287.768284 -151.9174)
		(width 0.14224)
		(layer "In11.Cu")
		(net "M_F_DQ<35>")
	)
	(segment
		(start 287.622234 -153.542746)
		(end 287.349946 -153.542746)
		(width 0.14224)
		(layer "In11.Cu")
		(net "M_F_DQ<35>")
	)
	(segment
		(start 288.4678 -136.270746)
		(end 288.4678 -136.626346)
		(width 0.14224)
		(layer "In11.Cu")
		(net "M_F_DQ<35>")
	)
	(segment
		(start 288.416492 -128.502664)
		(end 288.416492 -129.666492)
		(width 0.14224)
		(layer "In11.Cu")
		(net "M_F_DQ<35>")
	)
	(segment
		(start 276.057614 -98.405188)
		(end 276.079204 -98.405188)
		(width 0.0889)
		(layer "In11.Cu")
		(net "M_F_DQ<35>")
	)
	(segment
		(start 288.60623 -140.88237)
		(end 288.567114 -140.921486)
		(width 0.1016)
		(layer "In11.Cu")
		(net "M_F_DQ<35>")
	)
	(segment
		(start 287.768284 -151.9174)
		(end 287.768284 -152.2222)
		(width 0.14224)
		(layer "In11.Cu")
		(net "M_F_DQ<35>")
	)
	(segment
		(start 288.6202 -136.778746)
		(end 288.6202 -138.7856)
		(width 0.14224)
		(layer "In11.Cu")
		(net "M_F_DQ<35>")
	)
	(segment
		(start 275.711158 -96.223836)
		(end 275.720048 -96.239076)
		(width 0.0889)
		(layer "In11.Cu")
		(net "M_F_DQ<35>")
	)
	(segment
		(start 287.932876 -128.347724)
		(end 288.261552 -128.347724)
		(width 0.14224)
		(layer "In11.Cu")
		(net "M_F_DQ<35>")
	)
	(segment
		(start 278.469852 -102.979474)
		(end 278.542242 -103.051864)
		(width 0.0889)
		(layer "In11.Cu")
		(net "M_F_DQ<35>")
	)
	(segment
		(start 287.800034 -153.364946)
		(end 287.622234 -153.542746)
		(width 0.14224)
		(layer "In11.Cu")
		(net "M_F_DQ<35>")
	)
	(segment
		(start 275.711158 -95.232982)
		(end 275.717508 -95.24365)
		(width 0.0889)
		(layer "In11.Cu")
		(net "M_F_DQ<35>")
	)
	(segment
		(start 287.793684 -151.1046)
		(end 287.511236 -151.387048)
		(width 0.14224)
		(layer "In11.Cu")
		(net "M_F_DQ<35>")
	)
	(segment
		(start 288.529014 -145.810732)
		(end 288.529014 -146.1262)
		(width 0.14224)
		(layer "In11.Cu")
		(net "M_F_DQ<35>")
	)
	(segment
		(start 278.542242 -103.051864)
		(end 278.855424 -103.051864)
		(width 0.0889)
		(layer "In11.Cu")
		(net "M_F_DQ<35>")
	)
	(segment
		(start 278.855424 -103.051864)
		(end 279.052274 -103.248714)
		(width 0.0889)
		(layer "In11.Cu")
		(net "M_F_DQ<35>")
	)
	(segment
		(start 288.416492 -124.784104)
		(end 288.416492 -127.529844)
		(width 0.14224)
		(layer "In11.Cu")
		(net "M_F_DQ<35>")
	)
	(segment
		(start 288.732214 -136.006332)
		(end 288.4678 -136.270746)
		(width 0.14224)
		(layer "In11.Cu")
		(net "M_F_DQ<35>")
	)
	(segment
		(start 278.286464 -100.681028)
		(end 278.292814 -100.691696)
		(width 0.0889)
		(layer "In11.Cu")
		(net "M_F_DQ<35>")
	)
	(segment
		(start 275.711158 -97.214436)
		(end 275.720048 -97.229676)
		(width 0.0889)
		(layer "In11.Cu")
		(net "M_F_DQ<35>")
	)
	(segment
		(start 288.60623 -139.66063)
		(end 288.60623 -140.88237)
		(width 0.1016)
		(layer "In11.Cu")
		(net "M_F_DQ<35>")
	)
	(segment
		(start 287.777936 -128.192784)
		(end 287.932876 -128.347724)
		(width 0.14224)
		(layer "In11.Cu")
		(net "M_F_DQ<35>")
	)
	(segment
		(start 288.6202 -148.4122)
		(end 288.529014 -148.503386)
		(width 0.14224)
		(layer "In11.Cu")
		(net "M_F_DQ<35>")
	)
	(segment
		(start 287.511236 -151.387048)
		(end 287.511236 -151.660352)
		(width 0.14224)
		(layer "In11.Cu")
		(net "M_F_DQ<35>")
	)
	(segment
		(start 287.768284 -152.2222)
		(end 287.511236 -152.479248)
		(width 0.14224)
		(layer "In11.Cu")
		(net "M_F_DQ<35>")
	)
	(segment
		(start 288.783014 -145.556732)
		(end 288.529014 -145.810732)
		(width 0.14224)
		(layer "In11.Cu")
		(net "M_F_DQ<35>")
	)
	(segment
		(start 287.793684 -150.435818)
		(end 287.793684 -151.1046)
		(width 0.14224)
		(layer "In11.Cu")
		(net "M_F_DQ<35>")
	)
	(segment
		(start 287.511236 -152.479248)
		(end 287.511236 -152.752552)
		(width 0.14224)
		(layer "In11.Cu")
		(net "M_F_DQ<35>")
	)
	(segment
		(start 288.567114 -144.182338)
		(end 288.783014 -144.398238)
		(width 0.14224)
		(layer "In11.Cu")
		(net "M_F_DQ<35>")
	)
	(arc
		(start 275.999956 -93.647006)
		(mid 275.697759 -93.868288)
		(end 275.711158 -94.242636)
		(width 0.0889)
		(layer "In11.Cu")
		(net "M_F_DQ<35>")
	)
	(arc
		(start 275.711158 -97.80524)
		(mid 275.711241 -98.205181)
		(end 276.057614 -98.405188)
		(width 0.0889)
		(layer "In11.Cu")
		(net "M_F_DQ<35>")
	)
	(arc
		(start 275.711158 -96.81464)
		(mid 275.657625 -97.014538)
		(end 275.711158 -97.214436)
		(width 0.0889)
		(layer "In11.Cu")
		(net "M_F_DQ<35>")
	)
	(arc
		(start 277.799546 -99.395534)
		(mid 278.292411 -99.701231)
		(end 278.286464 -100.281232)
		(width 0.0889)
		(layer "In11.Cu")
		(net "M_F_DQ<35>")
	)
	(arc
		(start 275.711158 -94.833186)
		(mid 275.657625 -95.033084)
		(end 275.711158 -95.232982)
		(width 0.0889)
		(layer "In11.Cu")
		(net "M_F_DQ<35>")
	)
	(arc
		(start 276.569424 -98.700336)
		(mid 276.709503 -98.843072)
		(end 276.901148 -98.900234)
		(width 0.0889)
		(layer "In11.Cu")
		(net "M_F_DQ<35>")
	)
	(arc
		(start 276.933914 -98.900234)
		(mid 277.219338 -98.983701)
		(end 277.427944 -99.195636)
		(width 0.0889)
		(layer "In11.Cu")
		(net "M_F_DQ<35>")
	)
	(arc
		(start 278.277828 -102.277164)
		(mid 278.232813 -102.470802)
		(end 278.286464 -102.662228)
		(width 0.0889)
		(layer "In11.Cu")
		(net "M_F_DQ<35>")
	)
	(arc
		(start 275.717508 -95.24365)
		(mid 275.790428 -95.534667)
		(end 275.711158 -95.82404)
		(width 0.0889)
		(layer "In11.Cu")
		(net "M_F_DQ<35>")
	)
	(arc
		(start 278.286464 -100.281232)
		(mid 278.232965 -100.48113)
		(end 278.286464 -100.681028)
		(width 0.0889)
		(layer "In11.Cu")
		(net "M_F_DQ<35>")
	)
	(arc
		(start 276.079204 -98.405188)
		(mid 276.362421 -98.489469)
		(end 276.569424 -98.700336)
		(width 0.0889)
		(layer "In11.Cu")
		(net "M_F_DQ<35>")
	)
	(arc
		(start 275.711158 -94.242636)
		(mid 275.790312 -94.531754)
		(end 275.717508 -94.822518)
		(width 0.0889)
		(layer "In11.Cu")
		(net "M_F_DQ<35>")
	)
	(arc
		(start 275.720048 -97.229676)
		(mid 275.790445 -97.518627)
		(end 275.711158 -97.80524)
		(width 0.0889)
		(layer "In11.Cu")
		(net "M_F_DQ<35>")
	)
	(arc
		(start 275.720048 -96.239076)
		(mid 275.790445 -96.528027)
		(end 275.711158 -96.81464)
		(width 0.0889)
		(layer "In11.Cu")
		(net "M_F_DQ<35>")
	)
	(arc
		(start 278.286464 -101.671628)
		(mid 278.365686 -101.960746)
		(end 278.292814 -102.25151)
		(width 0.0889)
		(layer "In11.Cu")
		(net "M_F_DQ<35>")
	)
	(arc
		(start 275.711158 -95.82404)
		(mid 275.657625 -96.023938)
		(end 275.711158 -96.223836)
		(width 0.0889)
		(layer "In11.Cu")
		(net "M_F_DQ<35>")
	)
	(arc
		(start 277.427944 -99.195636)
		(mid 277.566688 -99.337669)
		(end 277.75662 -99.395534)
		(width 0.0889)
		(layer "In11.Cu")
		(net "M_F_DQ<35>")
	)
	(arc
		(start 278.292814 -100.691696)
		(mid 278.365612 -100.982459)
		(end 278.286464 -101.271578)
		(width 0.0889)
		(layer "In11.Cu")
		(net "M_F_DQ<35>")
	)
	(arc
		(start 278.281638 -101.280214)
		(mid 278.232883 -101.476566)
		(end 278.286464 -101.671628)
		(width 0.0889)
		(layer "In11.Cu")
		(net "M_F_DQ<35>")
	)
	(segment
		(start 288.331402 -155.75026)
		(end 288.19983 -155.881832)
		(width 0.1651)
		(layer "F.Cu")
		(net "M_F_DQ<34>")
	)
	(segment
		(start 288.331402 -155.52674)
		(end 288.331402 -155.75026)
		(width 0.1651)
		(layer "F.Cu")
		(net "M_F_DQ<34>")
	)
	(segment
		(start 288.19983 -155.395168)
		(end 288.331402 -155.52674)
		(width 0.1651)
		(layer "F.Cu")
		(net "M_F_DQ<34>")
	)
	(segment
		(start 275.486114 -93.052138)
		(end 276.057614 -93.052138)
		(width 0.1651)
		(layer "F.Cu")
		(net "M_F_DQ<34>")
	)
	(segment
		(start 288.19983 -155.881832)
		(end 288.19983 -156.87294)
		(width 0.1651)
		(layer "F.Cu")
		(net "M_F_DQ<34>")
	)
	(segment
		(start 288.19983 -155.1178)
		(end 288.19983 -155.395168)
		(width 0.1651)
		(layer "F.Cu")
		(net "M_F_DQ<34>")
	)
	(segment
		(start 288.19983 -156.87294)
		(end 288.200338 -156.87294)
		(width 0.1651)
		(layer "F.Cu")
		(net "M_F_DQ<34>")
	)
	(via
		(at 288.19983 -155.1178)
		(size 0.508)
		(drill 0.254)
		(layers "F.Cu" "B.Cu")
		(net "M_F_DQ<34>")
	)
	(via
		(at 287.349946 -150.814278)
		(size 0.508)
		(drill 0.254)
		(layers "F.Cu" "B.Cu")
		(net "M_F_DQ<34>")
	)
	(via
		(at 276.057614 -93.052138)
		(size 0.508)
		(drill 0.254)
		(layers "F.Cu" "B.Cu")
		(net "M_F_DQ<34>")
	)
	(segment
		(start 287.350454 -152.078436)
		(end 287.349946 -152.078182)
		(width 0.1651)
		(layer "B.Cu")
		(net "M_F_DQ<34>")
	)
	(segment
		(start 287.349946 -152.078182)
		(end 287.349946 -150.814278)
		(width 0.1651)
		(layer "B.Cu")
		(net "M_F_DQ<34>")
	)
	(segment
		(start 277.6474 -114.916204)
		(end 287.281112 -124.549916)
		(width 0.14224)
		(layer "In11.Cu")
		(net "M_F_DQ<34>")
	)
	(segment
		(start 275.536914 -97.294446)
		(end 275.545804 -97.309686)
		(width 0.0889)
		(layer "In11.Cu")
		(net "M_F_DQ<34>")
	)
	(segment
		(start 276.039834 -98.595688)
		(end 276.0726 -98.595688)
		(width 0.0889)
		(layer "In11.Cu")
		(net "M_F_DQ<34>")
	)
	(segment
		(start 278.201374 -102.895908)
		(end 278.201374 -103.1748)
		(width 0.0889)
		(layer "In11.Cu")
		(net "M_F_DQ<34>")
	)
	(segment
		(start 287.82772 -139.47648)
		(end 287.655 -139.6492)
		(width 0.14224)
		(layer "In11.Cu")
		(net "M_F_DQ<34>")
	)
	(segment
		(start 287.884616 -148.956776)
		(end 287.238694 -149.602698)
		(width 0.14224)
		(layer "In11.Cu")
		(net "M_F_DQ<34>")
	)
	(segment
		(start 287.838388 -143.667988)
		(end 287.838388 -144.174464)
		(width 0.14224)
		(layer "In11.Cu")
		(net "M_F_DQ<34>")
	)
	(segment
		(start 287.655 -140.7414)
		(end 287.870392 -140.956792)
		(width 0.14224)
		(layer "In11.Cu")
		(net "M_F_DQ<34>")
	)
	(segment
		(start 276.894544 -99.090734)
		(end 276.92731 -99.090734)
		(width 0.0889)
		(layer "In11.Cu")
		(net "M_F_DQ<34>")
	)
	(segment
		(start 287.808416 -131.319016)
		(end 287.808416 -134.595362)
		(width 0.14224)
		(layer "In11.Cu")
		(net "M_F_DQ<34>")
	)
	(segment
		(start 287.281112 -128.810258)
		(end 287.81883 -129.347976)
		(width 0.14224)
		(layer "In11.Cu")
		(net "M_F_DQ<34>")
	)
	(segment
		(start 278.000206 -103.375968)
		(end 277.9776 -103.398574)
		(width 0.14224)
		(layer "In11.Cu")
		(net "M_F_DQ<34>")
	)
	(segment
		(start 287.5788 -134.824978)
		(end 287.5788 -135.915654)
		(width 0.14224)
		(layer "In11.Cu")
		(net "M_F_DQ<34>")
	)
	(segment
		(start 287.238694 -150.703026)
		(end 287.349946 -150.814278)
		(width 0.14224)
		(layer "In11.Cu")
		(net "M_F_DQ<34>")
	)
	(segment
		(start 278.115014 -100.76561)
		(end 278.121364 -100.776278)
		(width 0.0889)
		(layer "In11.Cu")
		(net "M_F_DQ<34>")
	)
	(segment
		(start 287.870392 -141.527022)
		(end 287.77565 -141.621764)
		(width 0.14224)
		(layer "In11.Cu")
		(net "M_F_DQ<34>")
	)
	(segment
		(start 287.655 -139.6492)
		(end 287.655 -140.7414)
		(width 0.14224)
		(layer "In11.Cu")
		(net "M_F_DQ<34>")
	)
	(segment
		(start 278.128222 -102.154482)
		(end 278.110696 -102.185216)
		(width 0.0889)
		(layer "In11.Cu")
		(net "M_F_DQ<34>")
	)
	(segment
		(start 287.5788 -135.915654)
		(end 287.82772 -136.164574)
		(width 0.14224)
		(layer "In11.Cu")
		(net "M_F_DQ<34>")
	)
	(segment
		(start 277.749762 -99.586034)
		(end 277.792688 -99.586034)
		(width 0.0889)
		(layer "In11.Cu")
		(net "M_F_DQ<34>")
	)
	(segment
		(start 287.77565 -141.621764)
		(end 287.77565 -143.60525)
		(width 0.14224)
		(layer "In11.Cu")
		(net "M_F_DQ<34>")
	)
	(segment
		(start 287.808416 -134.595362)
		(end 287.5788 -134.824978)
		(width 0.14224)
		(layer "In11.Cu")
		(net "M_F_DQ<34>")
	)
	(segment
		(start 287.238694 -149.602698)
		(end 287.238694 -150.703026)
		(width 0.14224)
		(layer "In11.Cu")
		(net "M_F_DQ<34>")
	)
	(segment
		(start 287.281112 -124.549916)
		(end 287.281112 -128.810258)
		(width 0.14224)
		(layer "In11.Cu")
		(net "M_F_DQ<34>")
	)
	(segment
		(start 287.6042 -145.61439)
		(end 287.884616 -145.894806)
		(width 0.14224)
		(layer "In11.Cu")
		(net "M_F_DQ<34>")
	)
	(segment
		(start 277.6474 -105.8926)
		(end 277.6474 -114.916204)
		(width 0.14224)
		(layer "In11.Cu")
		(net "M_F_DQ<34>")
	)
	(segment
		(start 275.539454 -94.327472)
		(end 275.545804 -94.33814)
		(width 0.0889)
		(layer "In11.Cu")
		(net "M_F_DQ<34>")
	)
	(segment
		(start 278.121364 -102.757732)
		(end 278.201374 -102.895908)
		(width 0.0889)
		(layer "In11.Cu")
		(net "M_F_DQ<34>")
	)
	(segment
		(start 277.9776 -103.398574)
		(end 277.9776 -105.5624)
		(width 0.14224)
		(layer "In11.Cu")
		(net "M_F_DQ<34>")
	)
	(segment
		(start 287.349946 -150.814278)
		(end 286.916876 -151.247348)
		(width 0.14224)
		(layer "In11.Cu")
		(net "M_F_DQ<34>")
	)
	(segment
		(start 277.9776 -105.5624)
		(end 277.6474 -105.8926)
		(width 0.14224)
		(layer "In11.Cu")
		(net "M_F_DQ<34>")
	)
	(segment
		(start 276.057614 -93.052138)
		(end 276.057614 -93.390212)
		(width 0.0889)
		(layer "In11.Cu")
		(net "M_F_DQ<34>")
	)
	(segment
		(start 287.870392 -140.956792)
		(end 287.870392 -141.527022)
		(width 0.14224)
		(layer "In11.Cu")
		(net "M_F_DQ<34>")
	)
	(segment
		(start 287.723072 -131.233672)
		(end 287.808416 -131.319016)
		(width 0.14224)
		(layer "In11.Cu")
		(net "M_F_DQ<34>")
	)
	(segment
		(start 286.916876 -153.834846)
		(end 288.19983 -155.1178)
		(width 0.14224)
		(layer "In11.Cu")
		(net "M_F_DQ<34>")
	)
	(segment
		(start 287.6042 -144.408652)
		(end 287.6042 -145.61439)
		(width 0.14224)
		(layer "In11.Cu")
		(net "M_F_DQ<34>")
	)
	(segment
		(start 286.916876 -151.247348)
		(end 286.916876 -153.834846)
		(width 0.14224)
		(layer "In11.Cu")
		(net "M_F_DQ<34>")
	)
	(segment
		(start 278.201374 -103.1748)
		(end 278.000206 -103.375968)
		(width 0.0889)
		(layer "In11.Cu")
		(net "M_F_DQ<34>")
	)
	(segment
		(start 276.057614 -93.390212)
		(end 275.99259 -93.455236)
		(width 0.0889)
		(layer "In11.Cu")
		(net "M_F_DQ<34>")
	)
	(segment
		(start 287.77565 -143.60525)
		(end 287.838388 -143.667988)
		(width 0.14224)
		(layer "In11.Cu")
		(net "M_F_DQ<34>")
	)
	(segment
		(start 287.884616 -145.894806)
		(end 287.884616 -148.956776)
		(width 0.14224)
		(layer "In11.Cu")
		(net "M_F_DQ<34>")
	)
	(segment
		(start 287.723072 -129.95402)
		(end 287.723072 -131.233672)
		(width 0.14224)
		(layer "In11.Cu")
		(net "M_F_DQ<34>")
	)
	(segment
		(start 287.838388 -144.174464)
		(end 287.6042 -144.408652)
		(width 0.14224)
		(layer "In11.Cu")
		(net "M_F_DQ<34>")
	)
	(segment
		(start 287.82772 -136.164574)
		(end 287.82772 -139.47648)
		(width 0.14224)
		(layer "In11.Cu")
		(net "M_F_DQ<34>")
	)
	(segment
		(start 275.536914 -96.303846)
		(end 275.545804 -96.319086)
		(width 0.0889)
		(layer "In11.Cu")
		(net "M_F_DQ<34>")
	)
	(segment
		(start 275.545804 -94.737936)
		(end 275.539454 -94.748604)
		(width 0.0889)
		(layer "In11.Cu")
		(net "M_F_DQ<34>")
	)
	(segment
		(start 287.81883 -129.347976)
		(end 287.81883 -129.858262)
		(width 0.14224)
		(layer "In11.Cu")
		(net "M_F_DQ<34>")
	)
	(segment
		(start 287.81883 -129.858262)
		(end 287.723072 -129.95402)
		(width 0.14224)
		(layer "In11.Cu")
		(net "M_F_DQ<34>")
	)
	(arc
		(start 276.92731 -99.090734)
		(mid 277.12116 -99.147084)
		(end 277.262844 -99.290886)
		(width 0.0889)
		(layer "In11.Cu")
		(net "M_F_DQ<34>")
	)
	(arc
		(start 277.262844 -99.290886)
		(mid 277.468403 -99.500983)
		(end 277.749762 -99.586034)
		(width 0.0889)
		(layer "In11.Cu")
		(net "M_F_DQ<34>")
	)
	(arc
		(start 275.545804 -95.728282)
		(mid 275.466615 -96.014897)
		(end 275.536914 -96.303846)
		(width 0.0889)
		(layer "In11.Cu")
		(net "M_F_DQ<34>")
	)
	(arc
		(start 278.121364 -101.176074)
		(mid 278.042233 -101.471476)
		(end 278.121364 -101.766878)
		(width 0.0889)
		(layer "In11.Cu")
		(net "M_F_DQ<34>")
	)
	(arc
		(start 277.792688 -99.586034)
		(mid 278.125604 -99.793486)
		(end 278.121364 -100.185728)
		(width 0.0889)
		(layer "In11.Cu")
		(net "M_F_DQ<34>")
	)
	(arc
		(start 276.404324 -98.795586)
		(mid 276.611328 -99.00645)
		(end 276.894544 -99.090734)
		(width 0.0889)
		(layer "In11.Cu")
		(net "M_F_DQ<34>")
	)
	(arc
		(start 275.545804 -96.319086)
		(mid 275.599337 -96.518984)
		(end 275.545804 -96.718882)
		(width 0.0889)
		(layer "In11.Cu")
		(net "M_F_DQ<34>")
	)
	(arc
		(start 278.121364 -100.776278)
		(mid 278.174863 -100.976176)
		(end 278.121364 -101.176074)
		(width 0.0889)
		(layer "In11.Cu")
		(net "M_F_DQ<34>")
	)
	(arc
		(start 275.545804 -96.718882)
		(mid 275.466615 -97.005497)
		(end 275.536914 -97.294446)
		(width 0.0889)
		(layer "In11.Cu")
		(net "M_F_DQ<34>")
	)
	(arc
		(start 275.99259 -93.455236)
		(mid 275.533062 -93.770284)
		(end 275.539454 -94.327472)
		(width 0.0889)
		(layer "In11.Cu")
		(net "M_F_DQ<34>")
	)
	(arc
		(start 275.545804 -94.33814)
		(mid 275.599337 -94.538038)
		(end 275.545804 -94.737936)
		(width 0.0889)
		(layer "In11.Cu")
		(net "M_F_DQ<34>")
	)
	(arc
		(start 275.545804 -95.328486)
		(mid 275.599337 -95.528384)
		(end 275.545804 -95.728282)
		(width 0.0889)
		(layer "In11.Cu")
		(net "M_F_DQ<34>")
	)
	(arc
		(start 275.539454 -94.748604)
		(mid 275.466656 -95.039367)
		(end 275.545804 -95.328486)
		(width 0.0889)
		(layer "In11.Cu")
		(net "M_F_DQ<34>")
	)
	(arc
		(start 278.121364 -100.185728)
		(mid 278.042142 -100.474846)
		(end 278.115014 -100.76561)
		(width 0.0889)
		(layer "In11.Cu")
		(net "M_F_DQ<34>")
	)
	(arc
		(start 278.110696 -102.185216)
		(mid 278.042097 -102.47285)
		(end 278.121364 -102.757732)
		(width 0.0889)
		(layer "In11.Cu")
		(net "M_F_DQ<34>")
	)
	(arc
		(start 276.0726 -98.595688)
		(mid 276.264242 -98.652854)
		(end 276.404324 -98.795586)
		(width 0.0889)
		(layer "In11.Cu")
		(net "M_F_DQ<34>")
	)
	(arc
		(start 275.545804 -97.309686)
		(mid 275.599337 -97.509584)
		(end 275.545804 -97.709482)
		(width 0.0889)
		(layer "In11.Cu")
		(net "M_F_DQ<34>")
	)
	(arc
		(start 275.545804 -97.709482)
		(mid 275.541476 -98.292658)
		(end 276.039834 -98.595688)
		(width 0.0889)
		(layer "In11.Cu")
		(net "M_F_DQ<34>")
	)
	(arc
		(start 278.121364 -101.766878)
		(mid 278.174802 -101.959783)
		(end 278.128222 -102.154482)
		(width 0.0889)
		(layer "In11.Cu")
		(net "M_F_DQ<34>")
	)
	(segment
		(start 281.400504 -152.273)
		(end 281.399996 -152.278842)
		(width 0.1651)
		(layer "F.Cu")
		(net "M_F_DQ<33>")
	)
	(segment
		(start 272.052288 -94.042738)
		(end 272.623788 -94.042738)
		(width 0.1651)
		(layer "F.Cu")
		(net "M_F_DQ<33>")
	)
	(segment
		(start 281.399996 -152.278842)
		(end 281.399996 -153.542746)
		(width 0.1651)
		(layer "F.Cu")
		(net "M_F_DQ<33>")
	)
	(via
		(at 282.07208 -149.533356)
		(size 0.508)
		(drill 0.254)
		(layers "F.Cu" "B.Cu")
		(net "M_F_DQ<33>")
	)
	(via
		(at 272.623788 -94.042738)
		(size 0.508)
		(drill 0.254)
		(layers "F.Cu" "B.Cu")
		(net "M_F_DQ<33>")
	)
	(via
		(at 281.399996 -153.542746)
		(size 0.508)
		(drill 0.254)
		(layers "F.Cu" "B.Cu")
		(net "M_F_DQ<33>")
	)
	(segment
		(start 282.24988 -148.852382)
		(end 282.07208 -149.030182)
		(width 0.1651)
		(layer "B.Cu")
		(net "M_F_DQ<33>")
	)
	(segment
		(start 282.24988 -147.478496)
		(end 282.24988 -148.852382)
		(width 0.1651)
		(layer "B.Cu")
		(net "M_F_DQ<33>")
	)
	(segment
		(start 282.250388 -147.478496)
		(end 282.24988 -147.478496)
		(width 0.1651)
		(layer "B.Cu")
		(net "M_F_DQ<33>")
	)
	(segment
		(start 282.07208 -149.030182)
		(end 282.07208 -149.533356)
		(width 0.1651)
		(layer "B.Cu")
		(net "M_F_DQ<33>")
	)
	(segment
		(start 272.277078 -98.205036)
		(end 272.283428 -98.215704)
		(width 0.0889)
		(layer "In11.Cu")
		(net "M_F_DQ<33>")
	)
	(segment
		(start 273.711416 -104.27335)
		(end 273.711416 -104.738678)
		(width 0.0889)
		(layer "In11.Cu")
		(net "M_F_DQ<33>")
	)
	(segment
		(start 277.751032 -121.625868)
		(end 278.000968 -121.875804)
		(width 0.14224)
		(layer "In11.Cu")
		(net "M_F_DQ<33>")
	)
	(segment
		(start 281.561286 -151.677624)
		(end 281.775662 -151.892)
		(width 0.14224)
		(layer "In11.Cu")
		(net "M_F_DQ<33>")
	)
	(segment
		(start 278.65324 -121.442226)
		(end 278.872188 -121.442226)
		(width 0.14224)
		(layer "In11.Cu")
		(net "M_F_DQ<33>")
	)
	(segment
		(start 282.8544 -127.541274)
		(end 282.69946 -127.696214)
		(width 0.14224)
		(layer "In11.Cu")
		(net "M_F_DQ<33>")
	)
	(segment
		(start 282.560014 -134.253986)
		(end 282.560014 -136.5758)
		(width 0.14224)
		(layer "In11.Cu")
		(net "M_F_DQ<33>")
	)
	(segment
		(start 281.851862 -150.621746)
		(end 281.851862 -151.026368)
		(width 0.14224)
		(layer "In11.Cu")
		(net "M_F_DQ<33>")
	)
	(segment
		(start 282.560014 -129.377186)
		(end 282.560014 -131.7244)
		(width 0.14224)
		(layer "In11.Cu")
		(net "M_F_DQ<33>")
	)
	(segment
		(start 272.277078 -97.214436)
		(end 272.283428 -97.225104)
		(width 0.0889)
		(layer "In11.Cu")
		(net "M_F_DQ<33>")
	)
	(segment
		(start 281.561286 -151.316944)
		(end 281.561286 -151.677624)
		(width 0.14224)
		(layer "In11.Cu")
		(net "M_F_DQ<33>")
	)
	(segment
		(start 282.8544 -128.663954)
		(end 282.8544 -129.0828)
		(width 0.14224)
		(layer "In11.Cu")
		(net "M_F_DQ<33>")
	)
	(segment
		(start 273.215354 -103.777288)
		(end 273.711416 -104.27335)
		(width 0.0889)
		(layer "In11.Cu")
		(net "M_F_DQ<33>")
	)
	(segment
		(start 272.623788 -100.386388)
		(end 272.641568 -100.386134)
		(width 0.0889)
		(layer "In11.Cu")
		(net "M_F_DQ<33>")
	)
	(segment
		(start 282.6766 -146.293586)
		(end 282.6766 -148.4122)
		(width 0.14224)
		(layer "In11.Cu")
		(net "M_F_DQ<33>")
	)
	(segment
		(start 282.69946 -127.696214)
		(end 282.069032 -127.696214)
		(width 0.14224)
		(layer "In11.Cu")
		(net "M_F_DQ<33>")
	)
	(segment
		(start 282.560014 -136.5758)
		(end 282.6766 -136.692386)
		(width 0.14224)
		(layer "In11.Cu")
		(net "M_F_DQ<33>")
	)
	(segment
		(start 281.801062 -153.0858)
		(end 281.801062 -153.3906)
		(width 0.14224)
		(layer "In11.Cu")
		(net "M_F_DQ<33>")
	)
	(segment
		(start 282.560014 -131.7244)
		(end 282.6766 -131.840986)
		(width 0.14224)
		(layer "In11.Cu")
		(net "M_F_DQ<33>")
	)
	(segment
		(start 282.07208 -149.533356)
		(end 282.049728 -149.533356)
		(width 0.14224)
		(layer "In11.Cu")
		(net "M_F_DQ<33>")
	)
	(segment
		(start 279.425908 -123.377198)
		(end 282.004262 -125.955552)
		(width 0.14224)
		(layer "In11.Cu")
		(net "M_F_DQ<33>")
	)
	(segment
		(start 282.8544 -129.0828)
		(end 282.560014 -129.377186)
		(width 0.14224)
		(layer "In11.Cu")
		(net "M_F_DQ<33>")
	)
	(segment
		(start 281.561286 -152.538176)
		(end 281.561286 -152.846024)
		(width 0.14224)
		(layer "In11.Cu")
		(net "M_F_DQ<33>")
	)
	(segment
		(start 278.184356 -120.973342)
		(end 277.751032 -121.40692)
		(width 0.14224)
		(layer "In11.Cu")
		(net "M_F_DQ<33>")
	)
	(segment
		(start 282.6766 -141.477746)
		(end 282.6766 -143.5862)
		(width 0.14224)
		(layer "In11.Cu")
		(net "M_F_DQ<33>")
	)
	(segment
		(start 282.560014 -146.177)
		(end 282.6766 -146.293586)
		(width 0.14224)
		(layer "In11.Cu")
		(net "M_F_DQ<33>")
	)
	(segment
		(start 273.893788 -116.463826)
		(end 278.184356 -120.754394)
		(width 0.14224)
		(layer "In11.Cu")
		(net "M_F_DQ<33>")
	)
	(segment
		(start 282.004262 -126.135384)
		(end 281.914092 -126.225554)
		(width 0.14224)
		(layer "In11.Cu")
		(net "M_F_DQ<33>")
	)
	(segment
		(start 282.069032 -128.509014)
		(end 282.69946 -128.509014)
		(width 0.14224)
		(layer "In11.Cu")
		(net "M_F_DQ<33>")
	)
	(segment
		(start 272.277078 -96.223836)
		(end 272.283428 -96.234504)
		(width 0.0889)
		(layer "In11.Cu")
		(net "M_F_DQ<33>")
	)
	(segment
		(start 281.775662 -151.892)
		(end 281.775662 -152.3238)
		(width 0.14224)
		(layer "In11.Cu")
		(net "M_F_DQ<33>")
	)
	(segment
		(start 282.560014 -141.36116)
		(end 282.6766 -141.477746)
		(width 0.14224)
		(layer "In11.Cu")
		(net "M_F_DQ<33>")
	)
	(segment
		(start 282.560014 -148.956522)
		(end 282.07208 -149.444456)
		(width 0.14224)
		(layer "In11.Cu")
		(net "M_F_DQ<33>")
	)
	(segment
		(start 282.6766 -143.5862)
		(end 282.560014 -143.702786)
		(width 0.14224)
		(layer "In11.Cu")
		(net "M_F_DQ<33>")
	)
	(segment
		(start 272.277078 -99.195636)
		(end 272.283428 -99.206304)
		(width 0.0889)
		(layer "In11.Cu")
		(net "M_F_DQ<33>")
	)
	(segment
		(start 282.069032 -126.883414)
		(end 282.69946 -126.883414)
		(width 0.14224)
		(layer "In11.Cu")
		(net "M_F_DQ<33>")
	)
	(segment
		(start 282.8544 -127.038354)
		(end 282.8544 -127.541274)
		(width 0.14224)
		(layer "In11.Cu")
		(net "M_F_DQ<33>")
	)
	(segment
		(start 272.283428 -94.822518)
		(end 272.277078 -94.833186)
		(width 0.0889)
		(layer "In11.Cu")
		(net "M_F_DQ<33>")
	)
	(segment
		(start 282.07208 -149.444456)
		(end 282.07208 -149.533356)
		(width 0.14224)
		(layer "In11.Cu")
		(net "M_F_DQ<33>")
	)
	(segment
		(start 281.914092 -126.728474)
		(end 282.069032 -126.883414)
		(width 0.14224)
		(layer "In11.Cu")
		(net "M_F_DQ<33>")
	)
	(segment
		(start 272.623788 -94.042738)
		(end 272.330672 -93.873828)
		(width 0.0889)
		(layer "In11.Cu")
		(net "M_F_DQ<33>")
	)
	(segment
		(start 281.648916 -153.542746)
		(end 281.399996 -153.542746)
		(width 0.14224)
		(layer "In11.Cu")
		(net "M_F_DQ<33>")
	)
	(segment
		(start 278.184356 -120.754394)
		(end 278.184356 -120.973342)
		(width 0.14224)
		(layer "In11.Cu")
		(net "M_F_DQ<33>")
	)
	(segment
		(start 273.711416 -104.738678)
		(end 273.93392 -104.961182)
		(width 0.0889)
		(layer "In11.Cu")
		(net "M_F_DQ<33>")
	)
	(segment
		(start 282.6766 -131.840986)
		(end 282.6766 -134.1374)
		(width 0.14224)
		(layer "In11.Cu")
		(net "M_F_DQ<33>")
	)
	(segment
		(start 282.69946 -126.883414)
		(end 282.8544 -127.038354)
		(width 0.14224)
		(layer "In11.Cu")
		(net "M_F_DQ<33>")
	)
	(segment
		(start 272.330672 -93.873828)
		(end 272.251932 -93.895164)
		(width 0.0889)
		(layer "In11.Cu")
		(net "M_F_DQ<33>")
	)
	(segment
		(start 281.621484 -149.9616)
		(end 281.621484 -150.391368)
		(width 0.14224)
		(layer "In11.Cu")
		(net "M_F_DQ<33>")
	)
	(segment
		(start 281.851862 -151.026368)
		(end 281.561286 -151.316944)
		(width 0.14224)
		(layer "In11.Cu")
		(net "M_F_DQ<33>")
	)
	(segment
		(start 272.272252 -99.187)
		(end 272.277078 -99.195636)
		(width 0.0889)
		(layer "In11.Cu")
		(net "M_F_DQ<33>")
	)
	(segment
		(start 273.215354 -100.977192)
		(end 273.215354 -103.777288)
		(width 0.0889)
		(layer "In11.Cu")
		(net "M_F_DQ<33>")
	)
	(segment
		(start 282.69946 -128.509014)
		(end 282.8544 -128.663954)
		(width 0.14224)
		(layer "In11.Cu")
		(net "M_F_DQ<33>")
	)
	(segment
		(start 272.272252 -96.2152)
		(end 272.277078 -96.223836)
		(width 0.0889)
		(layer "In11.Cu")
		(net "M_F_DQ<33>")
	)
	(segment
		(start 279.425908 -121.995946)
		(end 279.425908 -123.377198)
		(width 0.14224)
		(layer "In11.Cu")
		(net "M_F_DQ<33>")
	)
	(segment
		(start 282.6766 -134.1374)
		(end 282.560014 -134.253986)
		(width 0.14224)
		(layer "In11.Cu")
		(net "M_F_DQ<33>")
	)
	(segment
		(start 281.914092 -128.354074)
		(end 282.069032 -128.509014)
		(width 0.14224)
		(layer "In11.Cu")
		(net "M_F_DQ<33>")
	)
	(segment
		(start 278.000968 -121.875804)
		(end 278.219916 -121.875804)
		(width 0.14224)
		(layer "In11.Cu")
		(net "M_F_DQ<33>")
	)
	(segment
		(start 272.612612 -100.386388)
		(end 272.623788 -100.386388)
		(width 0.0889)
		(layer "In11.Cu")
		(net "M_F_DQ<33>")
	)
	(segment
		(start 281.775662 -152.3238)
		(end 281.561286 -152.538176)
		(width 0.14224)
		(layer "In11.Cu")
		(net "M_F_DQ<33>")
	)
	(segment
		(start 282.560014 -138.800586)
		(end 282.560014 -141.36116)
		(width 0.14224)
		(layer "In11.Cu")
		(net "M_F_DQ<33>")
	)
	(segment
		(start 282.6766 -136.692386)
		(end 282.6766 -138.684)
		(width 0.14224)
		(layer "In11.Cu")
		(net "M_F_DQ<33>")
	)
	(segment
		(start 278.219916 -121.875804)
		(end 278.65324 -121.442226)
		(width 0.14224)
		(layer "In11.Cu")
		(net "M_F_DQ<33>")
	)
	(segment
		(start 273.893788 -105.001314)
		(end 273.893788 -116.463826)
		(width 0.14224)
		(layer "In11.Cu")
		(net "M_F_DQ<33>")
	)
	(segment
		(start 282.560014 -148.528786)
		(end 282.560014 -148.956522)
		(width 0.14224)
		(layer "In11.Cu")
		(net "M_F_DQ<33>")
	)
	(segment
		(start 282.6766 -148.4122)
		(end 282.560014 -148.528786)
		(width 0.14224)
		(layer "In11.Cu")
		(net "M_F_DQ<33>")
	)
	(segment
		(start 282.560014 -143.702786)
		(end 282.560014 -146.177)
		(width 0.14224)
		(layer "In11.Cu")
		(net "M_F_DQ<33>")
	)
	(segment
		(start 282.6766 -138.684)
		(end 282.560014 -138.800586)
		(width 0.14224)
		(layer "In11.Cu")
		(net "M_F_DQ<33>")
	)
	(segment
		(start 272.272252 -97.2058)
		(end 272.277078 -97.214436)
		(width 0.0889)
		(layer "In11.Cu")
		(net "M_F_DQ<33>")
	)
	(segment
		(start 281.914092 -127.851154)
		(end 281.914092 -128.354074)
		(width 0.14224)
		(layer "In11.Cu")
		(net "M_F_DQ<33>")
	)
	(segment
		(start 282.069032 -127.696214)
		(end 281.914092 -127.851154)
		(width 0.14224)
		(layer "In11.Cu")
		(net "M_F_DQ<33>")
	)
	(segment
		(start 277.751032 -121.40692)
		(end 277.751032 -121.625868)
		(width 0.14224)
		(layer "In11.Cu")
		(net "M_F_DQ<33>")
	)
	(segment
		(start 281.914092 -126.225554)
		(end 281.914092 -126.728474)
		(width 0.14224)
		(layer "In11.Cu")
		(net "M_F_DQ<33>")
	)
	(segment
		(start 282.049728 -149.533356)
		(end 281.621484 -149.9616)
		(width 0.14224)
		(layer "In11.Cu")
		(net "M_F_DQ<33>")
	)
	(segment
		(start 281.801062 -153.3906)
		(end 281.648916 -153.542746)
		(width 0.14224)
		(layer "In11.Cu")
		(net "M_F_DQ<33>")
	)
	(segment
		(start 281.621484 -150.391368)
		(end 281.851862 -150.621746)
		(width 0.14224)
		(layer "In11.Cu")
		(net "M_F_DQ<33>")
	)
	(segment
		(start 282.004262 -125.955552)
		(end 282.004262 -126.135384)
		(width 0.14224)
		(layer "In11.Cu")
		(net "M_F_DQ<33>")
	)
	(segment
		(start 281.561286 -152.846024)
		(end 281.801062 -153.0858)
		(width 0.14224)
		(layer "In11.Cu")
		(net "M_F_DQ<33>")
	)
	(segment
		(start 278.872188 -121.442226)
		(end 279.425908 -121.995946)
		(width 0.14224)
		(layer "In11.Cu")
		(net "M_F_DQ<33>")
	)
	(segment
		(start 272.272252 -98.1964)
		(end 272.277078 -98.205036)
		(width 0.0889)
		(layer "In11.Cu")
		(net "M_F_DQ<33>")
	)
	(segment
		(start 273.93392 -104.961182)
		(end 273.893788 -105.001314)
		(width 0.14224)
		(layer "In11.Cu")
		(net "M_F_DQ<33>")
	)
	(arc
		(start 272.283428 -97.225104)
		(mid 272.356226 -97.515867)
		(end 272.277078 -97.804986)
		(width 0.0889)
		(layer "In11.Cu")
		(net "M_F_DQ<33>")
	)
	(arc
		(start 272.283428 -96.234504)
		(mid 272.356226 -96.525267)
		(end 272.277078 -96.814386)
		(width 0.0889)
		(layer "In11.Cu")
		(net "M_F_DQ<33>")
	)
	(arc
		(start 272.277078 -97.804986)
		(mid 272.223608 -98.000049)
		(end 272.272252 -98.1964)
		(width 0.0889)
		(layer "In11.Cu")
		(net "M_F_DQ<33>")
	)
	(arc
		(start 272.277078 -94.242636)
		(mid 272.3563 -94.531754)
		(end 272.283428 -94.822518)
		(width 0.0889)
		(layer "In11.Cu")
		(net "M_F_DQ<33>")
	)
	(arc
		(start 272.283428 -99.206304)
		(mid 272.356226 -99.497067)
		(end 272.277078 -99.786186)
		(width 0.0889)
		(layer "In11.Cu")
		(net "M_F_DQ<33>")
	)
	(arc
		(start 272.277078 -94.833186)
		(mid 272.223579 -95.033084)
		(end 272.277078 -95.232982)
		(width 0.0889)
		(layer "In11.Cu")
		(net "M_F_DQ<33>")
	)
	(arc
		(start 272.277078 -96.814386)
		(mid 272.223608 -97.009449)
		(end 272.272252 -97.2058)
		(width 0.0889)
		(layer "In11.Cu")
		(net "M_F_DQ<33>")
	)
	(arc
		(start 272.277078 -95.823786)
		(mid 272.223608 -96.018849)
		(end 272.272252 -96.2152)
		(width 0.0889)
		(layer "In11.Cu")
		(net "M_F_DQ<33>")
	)
	(arc
		(start 272.283428 -98.215704)
		(mid 272.356226 -98.506467)
		(end 272.277078 -98.795586)
		(width 0.0889)
		(layer "In11.Cu")
		(net "M_F_DQ<33>")
	)
	(arc
		(start 272.277078 -98.795586)
		(mid 272.223608 -98.990649)
		(end 272.272252 -99.187)
		(width 0.0889)
		(layer "In11.Cu")
		(net "M_F_DQ<33>")
	)
	(arc
		(start 272.641568 -100.386134)
		(mid 273.048318 -100.56531)
		(end 273.215354 -100.977192)
		(width 0.0889)
		(layer "In11.Cu")
		(net "M_F_DQ<33>")
	)
	(arc
		(start 272.251932 -93.895164)
		(mid 272.224663 -94.071793)
		(end 272.277078 -94.242636)
		(width 0.0889)
		(layer "In11.Cu")
		(net "M_F_DQ<33>")
	)
	(arc
		(start 272.277078 -95.232982)
		(mid 272.356209 -95.528384)
		(end 272.277078 -95.823786)
		(width 0.0889)
		(layer "In11.Cu")
		(net "M_F_DQ<33>")
	)
	(arc
		(start 272.277078 -99.786186)
		(mid 272.27433 -100.181653)
		(end 272.612612 -100.386388)
		(width 0.0889)
		(layer "In11.Cu")
		(net "M_F_DQ<33>")
	)
	(segment
		(start 272.910808 -92.556584)
		(end 273.482308 -92.556584)
		(width 0.1651)
		(layer "F.Cu")
		(net "M_F_DQ<32>")
	)
	(segment
		(start 282.250388 -156.87294)
		(end 282.24988 -156.878782)
		(width 0.1651)
		(layer "F.Cu")
		(net "M_F_DQ<32>")
	)
	(segment
		(start 282.24988 -156.878782)
		(end 282.07208 -155.0162)
		(width 0.1651)
		(layer "F.Cu")
		(net "M_F_DQ<32>")
	)
	(via
		(at 282.07208 -155.0162)
		(size 0.508)
		(drill 0.254)
		(layers "F.Cu" "B.Cu")
		(net "M_F_DQ<32>")
	)
	(via
		(at 273.482308 -92.556584)
		(size 0.508)
		(drill 0.254)
		(layers "F.Cu" "B.Cu")
		(net "M_F_DQ<32>")
	)
	(via
		(at 281.399996 -150.814278)
		(size 0.508)
		(drill 0.254)
		(layers "F.Cu" "B.Cu")
		(net "M_F_DQ<32>")
	)
	(segment
		(start 281.399996 -152.078182)
		(end 281.399996 -150.814278)
		(width 0.1651)
		(layer "B.Cu")
		(net "M_F_DQ<32>")
	)
	(segment
		(start 281.400504 -152.078436)
		(end 281.399996 -152.078182)
		(width 0.1651)
		(layer "B.Cu")
		(net "M_F_DQ<32>")
	)
	(segment
		(start 272.111978 -98.300286)
		(end 272.116804 -98.308922)
		(width 0.0889)
		(layer "In11.Cu")
		(net "M_F_DQ<32>")
	)
	(segment
		(start 281.925014 -136.71804)
		(end 281.8384 -136.804654)
		(width 0.14224)
		(layer "In11.Cu")
		(net "M_F_DQ<32>")
	)
	(segment
		(start 281.219148 -125.847602)
		(end 281.219148 -128.692148)
		(width 0.14224)
		(layer "In11.Cu")
		(net "M_F_DQ<32>")
	)
	(segment
		(start 280.966926 -154.20721)
		(end 281.775916 -155.0162)
		(width 0.14224)
		(layer "In11.Cu")
		(net "M_F_DQ<32>")
	)
	(segment
		(start 281.594814 -145.577814)
		(end 281.886914 -145.869914)
		(width 0.14224)
		(layer "In11.Cu")
		(net "M_F_DQ<32>")
	)
	(segment
		(start 281.925014 -131.484878)
		(end 281.925014 -131.8514)
		(width 0.14224)
		(layer "In11.Cu")
		(net "M_F_DQ<32>")
	)
	(segment
		(start 273.482308 -92.556584)
		(end 272.987262 -93.222572)
		(width 0.0889)
		(layer "In11.Cu")
		(net "M_F_DQ<32>")
	)
	(segment
		(start 273.239738 -105.020364)
		(end 273.239738 -116.717826)
		(width 0.14224)
		(layer "In11.Cu")
		(net "M_F_DQ<32>")
	)
	(segment
		(start 281.582114 -140.743178)
		(end 281.874214 -141.035278)
		(width 0.14224)
		(layer "In11.Cu")
		(net "M_F_DQ<32>")
	)
	(segment
		(start 281.925014 -139.320778)
		(end 281.582114 -139.663678)
		(width 0.14224)
		(layer "In11.Cu")
		(net "M_F_DQ<32>")
	)
	(segment
		(start 281.925014 -129.398014)
		(end 281.925014 -129.719578)
		(width 0.14224)
		(layer "In11.Cu")
		(net "M_F_DQ<32>")
	)
	(segment
		(start 281.813 -141.615414)
		(end 281.813 -143.7132)
		(width 0.14224)
		(layer "In11.Cu")
		(net "M_F_DQ<32>")
	)
	(segment
		(start 281.886914 -146.2024)
		(end 281.813 -146.276314)
		(width 0.14224)
		(layer "In11.Cu")
		(net "M_F_DQ<32>")
	)
	(segment
		(start 272.105628 -98.289618)
		(end 272.111978 -98.300286)
		(width 0.0889)
		(layer "In11.Cu")
		(net "M_F_DQ<32>")
	)
	(segment
		(start 281.925014 -134.173214)
		(end 281.925014 -134.431532)
		(width 0.14224)
		(layer "In11.Cu")
		(net "M_F_DQ<32>")
	)
	(segment
		(start 281.399996 -150.814278)
		(end 280.966926 -151.247348)
		(width 0.14224)
		(layer "In11.Cu")
		(net "M_F_DQ<32>")
	)
	(segment
		(start 281.036014 -150.450296)
		(end 281.399996 -150.814278)
		(width 0.14224)
		(layer "In11.Cu")
		(net "M_F_DQ<32>")
	)
	(segment
		(start 281.582114 -135.96366)
		(end 281.925014 -136.30656)
		(width 0.14224)
		(layer "In11.Cu")
		(net "M_F_DQ<32>")
	)
	(segment
		(start 272.111978 -95.328486)
		(end 272.116804 -95.337122)
		(width 0.0889)
		(layer "In11.Cu")
		(net "M_F_DQ<32>")
	)
	(segment
		(start 276.999192 -121.627646)
		(end 281.219148 -125.847602)
		(width 0.14224)
		(layer "In11.Cu")
		(net "M_F_DQ<32>")
	)
	(segment
		(start 281.8384 -136.804654)
		(end 281.8384 -138.8872)
		(width 0.14224)
		(layer "In11.Cu")
		(net "M_F_DQ<32>")
	)
	(segment
		(start 281.036014 -149.810978)
		(end 281.036014 -150.450296)
		(width 0.14224)
		(layer "In11.Cu")
		(net "M_F_DQ<32>")
	)
	(segment
		(start 281.874214 -144.083786)
		(end 281.594814 -144.363186)
		(width 0.14224)
		(layer "In11.Cu")
		(net "M_F_DQ<32>")
	)
	(segment
		(start 281.886914 -148.960078)
		(end 281.036014 -149.810978)
		(width 0.14224)
		(layer "In11.Cu")
		(net "M_F_DQ<32>")
	)
	(segment
		(start 272.620486 -100.577396)
		(end 272.624042 -100.577142)
		(width 0.0889)
		(layer "In11.Cu")
		(net "M_F_DQ<32>")
	)
	(segment
		(start 273.024092 -100.977192)
		(end 273.024092 -103.856282)
		(width 0.0889)
		(layer "In11.Cu")
		(net "M_F_DQ<32>")
	)
	(segment
		(start 281.8384 -134.0866)
		(end 281.925014 -134.173214)
		(width 0.14224)
		(layer "In11.Cu")
		(net "M_F_DQ<32>")
	)
	(segment
		(start 272.624042 -100.577142)
		(end 272.631154 -100.577142)
		(width 0.0889)
		(layer "In11.Cu")
		(net "M_F_DQ<32>")
	)
	(segment
		(start 281.874214 -141.5542)
		(end 281.813 -141.615414)
		(width 0.14224)
		(layer "In11.Cu")
		(net "M_F_DQ<32>")
	)
	(segment
		(start 273.024092 -103.856282)
		(end 273.521424 -104.353614)
		(width 0.0889)
		(layer "In11.Cu")
		(net "M_F_DQ<32>")
	)
	(segment
		(start 281.8384 -131.938014)
		(end 281.8384 -134.0866)
		(width 0.14224)
		(layer "In11.Cu")
		(net "M_F_DQ<32>")
	)
	(segment
		(start 281.813 -148.4884)
		(end 281.886914 -148.562314)
		(width 0.14224)
		(layer "In11.Cu")
		(net "M_F_DQ<32>")
	)
	(segment
		(start 272.105628 -99.280218)
		(end 272.111978 -99.290886)
		(width 0.0889)
		(layer "In11.Cu")
		(net "M_F_DQ<32>")
	)
	(segment
		(start 272.111978 -99.290886)
		(end 272.116804 -99.299522)
		(width 0.0889)
		(layer "In11.Cu")
		(net "M_F_DQ<32>")
	)
	(segment
		(start 272.105628 -96.308418)
		(end 272.111978 -96.319086)
		(width 0.0889)
		(layer "In11.Cu")
		(net "M_F_DQ<32>")
	)
	(segment
		(start 281.925014 -136.30656)
		(end 281.925014 -136.71804)
		(width 0.14224)
		(layer "In11.Cu")
		(net "M_F_DQ<32>")
	)
	(segment
		(start 281.582114 -139.663678)
		(end 281.582114 -140.743178)
		(width 0.14224)
		(layer "In11.Cu")
		(net "M_F_DQ<32>")
	)
	(segment
		(start 281.594814 -144.363186)
		(end 281.594814 -145.577814)
		(width 0.14224)
		(layer "In11.Cu")
		(net "M_F_DQ<32>")
	)
	(segment
		(start 272.105628 -97.299018)
		(end 272.111978 -97.309686)
		(width 0.0889)
		(layer "In11.Cu")
		(net "M_F_DQ<32>")
	)
	(segment
		(start 281.775916 -155.0162)
		(end 282.07208 -155.0162)
		(width 0.14224)
		(layer "In11.Cu")
		(net "M_F_DQ<32>")
	)
	(segment
		(start 272.111978 -94.737936)
		(end 272.105628 -94.748604)
		(width 0.0889)
		(layer "In11.Cu")
		(net "M_F_DQ<32>")
	)
	(segment
		(start 281.813 -143.7132)
		(end 281.874214 -143.774414)
		(width 0.14224)
		(layer "In11.Cu")
		(net "M_F_DQ<32>")
	)
	(segment
		(start 273.521424 -104.353614)
		(end 273.521424 -104.738678)
		(width 0.0889)
		(layer "In11.Cu")
		(net "M_F_DQ<32>")
	)
	(segment
		(start 281.813 -146.276314)
		(end 281.813 -148.4884)
		(width 0.14224)
		(layer "In11.Cu")
		(net "M_F_DQ<32>")
	)
	(segment
		(start 281.925014 -131.8514)
		(end 281.8384 -131.938014)
		(width 0.14224)
		(layer "In11.Cu")
		(net "M_F_DQ<32>")
	)
	(segment
		(start 276.999192 -120.47728)
		(end 276.999192 -121.627646)
		(width 0.14224)
		(layer "In11.Cu")
		(net "M_F_DQ<32>")
	)
	(segment
		(start 281.925014 -134.431532)
		(end 281.582114 -134.774432)
		(width 0.14224)
		(layer "In11.Cu")
		(net "M_F_DQ<32>")
	)
	(segment
		(start 272.987262 -93.222572)
		(end 272.970498 -93.252036)
		(width 0.0889)
		(layer "In11.Cu")
		(net "M_F_DQ<32>")
	)
	(segment
		(start 281.874214 -143.774414)
		(end 281.874214 -144.083786)
		(width 0.14224)
		(layer "In11.Cu")
		(net "M_F_DQ<32>")
	)
	(segment
		(start 281.886914 -148.562314)
		(end 281.886914 -148.960078)
		(width 0.14224)
		(layer "In11.Cu")
		(net "M_F_DQ<32>")
	)
	(segment
		(start 281.219148 -128.692148)
		(end 281.925014 -129.398014)
		(width 0.14224)
		(layer "In11.Cu")
		(net "M_F_DQ<32>")
	)
	(segment
		(start 281.925014 -129.719578)
		(end 281.582114 -130.062478)
		(width 0.14224)
		(layer "In11.Cu")
		(net "M_F_DQ<32>")
	)
	(segment
		(start 281.886914 -145.869914)
		(end 281.886914 -146.2024)
		(width 0.14224)
		(layer "In11.Cu")
		(net "M_F_DQ<32>")
	)
	(segment
		(start 281.582114 -131.141978)
		(end 281.925014 -131.484878)
		(width 0.14224)
		(layer "In11.Cu")
		(net "M_F_DQ<32>")
	)
	(segment
		(start 273.29892 -104.961182)
		(end 273.239738 -105.020364)
		(width 0.14224)
		(layer "In11.Cu")
		(net "M_F_DQ<32>")
	)
	(segment
		(start 272.634964 -93.452188)
		(end 272.623788 -93.452188)
		(width 0.0889)
		(layer "In11.Cu")
		(net "M_F_DQ<32>")
	)
	(segment
		(start 280.966926 -151.247348)
		(end 280.966926 -154.20721)
		(width 0.14224)
		(layer "In11.Cu")
		(net "M_F_DQ<32>")
	)
	(segment
		(start 272.111978 -97.309686)
		(end 272.116804 -97.318322)
		(width 0.0889)
		(layer "In11.Cu")
		(net "M_F_DQ<32>")
	)
	(segment
		(start 281.874214 -141.035278)
		(end 281.874214 -141.5542)
		(width 0.14224)
		(layer "In11.Cu")
		(net "M_F_DQ<32>")
	)
	(segment
		(start 273.521424 -104.738678)
		(end 273.29892 -104.961182)
		(width 0.0889)
		(layer "In11.Cu")
		(net "M_F_DQ<32>")
	)
	(segment
		(start 273.239738 -116.717826)
		(end 276.999192 -120.47728)
		(width 0.14224)
		(layer "In11.Cu")
		(net "M_F_DQ<32>")
	)
	(segment
		(start 281.582114 -130.062478)
		(end 281.582114 -131.141978)
		(width 0.14224)
		(layer "In11.Cu")
		(net "M_F_DQ<32>")
	)
	(segment
		(start 281.8384 -138.8872)
		(end 281.925014 -138.973814)
		(width 0.14224)
		(layer "In11.Cu")
		(net "M_F_DQ<32>")
	)
	(segment
		(start 281.582114 -134.774432)
		(end 281.582114 -135.96366)
		(width 0.14224)
		(layer "In11.Cu")
		(net "M_F_DQ<32>")
	)
	(segment
		(start 281.925014 -138.973814)
		(end 281.925014 -139.320778)
		(width 0.14224)
		(layer "In11.Cu")
		(net "M_F_DQ<32>")
	)
	(segment
		(start 272.111978 -96.319086)
		(end 272.116804 -96.327722)
		(width 0.0889)
		(layer "In11.Cu")
		(net "M_F_DQ<32>")
	)
	(arc
		(start 272.116804 -97.318322)
		(mid 272.165559 -97.514674)
		(end 272.111978 -97.709736)
		(width 0.0889)
		(layer "In11.Cu")
		(net "M_F_DQ<32>")
	)
	(arc
		(start 272.111978 -98.700336)
		(mid 272.032756 -98.989454)
		(end 272.105628 -99.280218)
		(width 0.0889)
		(layer "In11.Cu")
		(net "M_F_DQ<32>")
	)
	(arc
		(start 272.105628 -94.748604)
		(mid 272.03283 -95.039367)
		(end 272.111978 -95.328486)
		(width 0.0889)
		(layer "In11.Cu")
		(net "M_F_DQ<32>")
	)
	(arc
		(start 272.116804 -98.308922)
		(mid 272.165559 -98.505274)
		(end 272.111978 -98.700336)
		(width 0.0889)
		(layer "In11.Cu")
		(net "M_F_DQ<32>")
	)
	(arc
		(start 272.111978 -96.719136)
		(mid 272.032756 -97.008254)
		(end 272.105628 -97.299018)
		(width 0.0889)
		(layer "In11.Cu")
		(net "M_F_DQ<32>")
	)
	(arc
		(start 272.631154 -100.577142)
		(mid 272.909468 -100.696795)
		(end 273.024092 -100.977192)
		(width 0.0889)
		(layer "In11.Cu")
		(net "M_F_DQ<32>")
	)
	(arc
		(start 272.08226 -93.805756)
		(mid 272.0337 -94.075481)
		(end 272.111978 -94.33814)
		(width 0.0889)
		(layer "In11.Cu")
		(net "M_F_DQ<32>")
	)
	(arc
		(start 272.116804 -95.337122)
		(mid 272.165559 -95.533474)
		(end 272.111978 -95.728536)
		(width 0.0889)
		(layer "In11.Cu")
		(net "M_F_DQ<32>")
	)
	(arc
		(start 272.111978 -95.728536)
		(mid 272.032756 -96.017654)
		(end 272.105628 -96.308418)
		(width 0.0889)
		(layer "In11.Cu")
		(net "M_F_DQ<32>")
	)
	(arc
		(start 272.970498 -93.252036)
		(mid 272.828815 -93.39584)
		(end 272.634964 -93.452188)
		(width 0.0889)
		(layer "In11.Cu")
		(net "M_F_DQ<32>")
	)
	(arc
		(start 272.116804 -96.327722)
		(mid 272.165559 -96.524074)
		(end 272.111978 -96.719136)
		(width 0.0889)
		(layer "In11.Cu")
		(net "M_F_DQ<32>")
	)
	(arc
		(start 272.623788 -93.452188)
		(mid 272.30028 -93.548165)
		(end 272.08226 -93.805756)
		(width 0.0889)
		(layer "In11.Cu")
		(net "M_F_DQ<32>")
	)
	(arc
		(start 272.111978 -94.33814)
		(mid 272.165477 -94.538038)
		(end 272.111978 -94.737936)
		(width 0.0889)
		(layer "In11.Cu")
		(net "M_F_DQ<32>")
	)
	(arc
		(start 272.111978 -99.690936)
		(mid 272.111214 -100.280412)
		(end 272.620486 -100.577396)
		(width 0.0889)
		(layer "In11.Cu")
		(net "M_F_DQ<32>")
	)
	(arc
		(start 272.116804 -99.299522)
		(mid 272.165559 -99.495874)
		(end 272.111978 -99.690936)
		(width 0.0889)
		(layer "In11.Cu")
		(net "M_F_DQ<32>")
	)
	(arc
		(start 272.111978 -97.709736)
		(mid 272.032756 -97.998854)
		(end 272.105628 -98.289618)
		(width 0.0889)
		(layer "In11.Cu")
		(net "M_F_DQ<32>")
	)
	(segment
		(start 230.400352 -152.273)
		(end 230.399844 -152.278842)
		(width 0.1651)
		(layer "F.Cu")
		(net "M_F_DQ<31>")
	)
	(segment
		(start 230.399844 -152.278842)
		(end 230.399844 -153.542746)
		(width 0.1651)
		(layer "F.Cu")
		(net "M_F_DQ<31>")
	)
	(segment
		(start 251.636784 -87.28964)
		(end 251.065284 -87.28964)
		(width 0.1651)
		(layer "F.Cu")
		(net "M_F_DQ<31>")
	)
	(via
		(at 230.399844 -153.542746)
		(size 0.508)
		(drill 0.254)
		(layers "F.Cu" "B.Cu")
		(net "M_F_DQ<31>")
	)
	(via
		(at 231.249728 -149.533356)
		(size 0.508)
		(drill 0.254)
		(layers "F.Cu" "B.Cu")
		(net "M_F_DQ<31>")
	)
	(via
		(at 251.065284 -87.28964)
		(size 0.508)
		(drill 0.254)
		(layers "F.Cu" "B.Cu")
		(net "M_F_DQ<31>")
	)
	(segment
		(start 231.25049 -147.478496)
		(end 231.25049 -149.532594)
		(width 0.1651)
		(layer "B.Cu")
		(net "M_F_DQ<31>")
	)
	(segment
		(start 231.25049 -149.532594)
		(end 231.249728 -149.533356)
		(width 0.1651)
		(layer "B.Cu")
		(net "M_F_DQ<31>")
	)
	(segment
		(start 230.561134 -152.479248)
		(end 230.561134 -152.752552)
		(width 0.14224)
		(layer "In11.Cu")
		(net "M_F_DQ<31>")
	)
	(segment
		(start 250.139454 -97.290636)
		(end 250.1392 -97.29089)
		(width 0.0889)
		(layer "In11.Cu")
		(net "M_F_DQ<31>")
	)
	(segment
		(start 231.831134 -131.205478)
		(end 231.627934 -131.408678)
		(width 0.14224)
		(layer "In11.Cu")
		(net "M_F_DQ<31>")
	)
	(segment
		(start 231.771698 -144.313402)
		(end 231.771698 -145.646902)
		(width 0.14224)
		(layer "In11.Cu")
		(net "M_F_DQ<31>")
	)
	(segment
		(start 231.602534 -138.856466)
		(end 231.602534 -139.460478)
		(width 0.14224)
		(layer "In11.Cu")
		(net "M_F_DQ<31>")
	)
	(segment
		(start 251.577094 -89.565988)
		(end 251.572268 -89.574624)
		(width 0.0889)
		(layer "In11.Cu")
		(net "M_F_DQ<31>")
	)
	(segment
		(start 251.065284 -87.28964)
		(end 251.56033 -87.955374)
		(width 0.0889)
		(layer "In11.Cu")
		(net "M_F_DQ<31>")
	)
	(segment
		(start 240.946686 -119.326914)
		(end 240.946686 -119.545862)
		(width 0.14224)
		(layer "In11.Cu")
		(net "M_F_DQ<31>")
	)
	(segment
		(start 243.733066 -116.667534)
		(end 243.445792 -116.954808)
		(width 0.14224)
		(layer "In11.Cu")
		(net "M_F_DQ<31>")
	)
	(segment
		(start 239.797082 -120.695466)
		(end 239.931956 -120.83034)
		(width 0.14224)
		(layer "In11.Cu")
		(net "M_F_DQ<31>")
	)
	(segment
		(start 231.627934 -134.081266)
		(end 231.627934 -134.579868)
		(width 0.14224)
		(layer "In11.Cu")
		(net "M_F_DQ<31>")
	)
	(segment
		(start 241.87531 -119.105934)
		(end 241.656362 -119.105934)
		(width 0.14224)
		(layer "In11.Cu")
		(net "M_F_DQ<31>")
	)
	(segment
		(start 241.08156 -119.680736)
		(end 241.08156 -119.899684)
		(width 0.14224)
		(layer "In11.Cu")
		(net "M_F_DQ<31>")
	)
	(segment
		(start 241.08156 -119.899684)
		(end 240.725706 -120.255538)
		(width 0.14224)
		(layer "In11.Cu")
		(net "M_F_DQ<31>")
	)
	(segment
		(start 233.172254 -122.809)
		(end 231.746298 -124.234956)
		(width 0.14224)
		(layer "In11.Cu")
		(net "M_F_DQ<31>")
	)
	(segment
		(start 231.602534 -139.460478)
		(end 231.831134 -139.689078)
		(width 0.14224)
		(layer "In11.Cu")
		(net "M_F_DQ<31>")
	)
	(segment
		(start 230.818182 -152.2222)
		(end 230.561134 -152.479248)
		(width 0.14224)
		(layer "In11.Cu")
		(net "M_F_DQ<31>")
	)
	(segment
		(start 239.931956 -121.049288)
		(end 239.576102 -121.405142)
		(width 0.14224)
		(layer "In11.Cu")
		(net "M_F_DQ<31>")
	)
	(segment
		(start 243.9162 -115.3414)
		(end 243.449094 -115.808506)
		(width 0.14224)
		(layer "In11.Cu")
		(net "M_F_DQ<31>")
	)
	(segment
		(start 249.806968 -98.62947)
		(end 248.019824 -100.416614)
		(width 0.0889)
		(layer "In11.Cu")
		(net "M_F_DQ<31>")
	)
	(segment
		(start 231.627934 -134.579868)
		(end 231.805734 -134.757668)
		(width 0.14224)
		(layer "In11.Cu")
		(net "M_F_DQ<31>")
	)
	(segment
		(start 239.931956 -120.83034)
		(end 239.931956 -121.049288)
		(width 0.14224)
		(layer "In11.Cu")
		(net "M_F_DQ<31>")
	)
	(segment
		(start 247.772682 -103.167688)
		(end 247.772682 -105.896918)
		(width 0.14224)
		(layer "In11.Cu")
		(net "M_F_DQ<31>")
	)
	(segment
		(start 231.831134 -140.806678)
		(end 231.551734 -141.086078)
		(width 0.14224)
		(layer "In11.Cu")
		(net "M_F_DQ<31>")
	)
	(segment
		(start 231.805734 -136.011412)
		(end 231.602534 -136.214612)
		(width 0.14224)
		(layer "In11.Cu")
		(net "M_F_DQ<31>")
	)
	(segment
		(start 249.806968 -97.524824)
		(end 249.806968 -98.62947)
		(width 0.0889)
		(layer "In11.Cu")
		(net "M_F_DQ<31>")
	)
	(segment
		(start 239.003332 -121.270268)
		(end 238.647478 -121.626122)
		(width 0.14224)
		(layer "In11.Cu")
		(net "M_F_DQ<31>")
	)
	(segment
		(start 231.6734 -146.273266)
		(end 231.6734 -148.463)
		(width 0.14224)
		(layer "In11.Cu")
		(net "M_F_DQ<31>")
	)
	(segment
		(start 231.6734 -148.463)
		(end 231.602534 -148.533866)
		(width 0.14224)
		(layer "In11.Cu")
		(net "M_F_DQ<31>")
	)
	(segment
		(start 251.086874 -93.82379)
		(end 251.04725 -93.82379)
		(width 0.0889)
		(layer "In11.Cu")
		(net "M_F_DQ<31>")
	)
	(segment
		(start 231.602534 -149.191472)
		(end 231.591612 -149.191472)
		(width 0.14224)
		(layer "In11.Cu")
		(net "M_F_DQ<31>")
	)
	(segment
		(start 250.040902 -97.29089)
		(end 249.806968 -97.524824)
		(width 0.0889)
		(layer "In11.Cu")
		(net "M_F_DQ<31>")
	)
	(segment
		(start 251.583444 -91.53652)
		(end 251.577094 -91.547188)
		(width 0.0889)
		(layer "In11.Cu")
		(net "M_F_DQ<31>")
	)
	(segment
		(start 231.627934 -144.169638)
		(end 231.771698 -144.313402)
		(width 0.14224)
		(layer "In11.Cu")
		(net "M_F_DQ<31>")
	)
	(segment
		(start 231.602534 -145.816066)
		(end 231.602534 -146.2024)
		(width 0.14224)
		(layer "In11.Cu")
		(net "M_F_DQ<31>")
	)
	(segment
		(start 230.561134 -152.752552)
		(end 230.849932 -153.04135)
		(width 0.14224)
		(layer "In11.Cu")
		(net "M_F_DQ<31>")
	)
	(segment
		(start 231.602534 -136.5758)
		(end 231.6734 -136.646666)
		(width 0.14224)
		(layer "In11.Cu")
		(net "M_F_DQ<31>")
	)
	(segment
		(start 250.713748 -95.405702)
		(end 250.718574 -95.414338)
		(width 0.0889)
		(layer "In11.Cu")
		(net "M_F_DQ<31>")
	)
	(segment
		(start 231.602534 -148.533866)
		(end 231.602534 -149.191472)
		(width 0.14224)
		(layer "In11.Cu")
		(net "M_F_DQ<31>")
	)
	(segment
		(start 231.602534 -146.2024)
		(end 231.6734 -146.273266)
		(width 0.14224)
		(layer "In11.Cu")
		(net "M_F_DQ<31>")
	)
	(segment
		(start 240.371884 -120.120664)
		(end 240.152936 -120.120664)
		(width 0.14224)
		(layer "In11.Cu")
		(net "M_F_DQ<31>")
	)
	(segment
		(start 231.551734 -141.5796)
		(end 231.6734 -141.701266)
		(width 0.14224)
		(layer "In11.Cu")
		(net "M_F_DQ<31>")
	)
	(segment
		(start 243.9162 -109.7534)
		(end 243.9162 -115.3414)
		(width 0.14224)
		(layer "In11.Cu")
		(net "M_F_DQ<31>")
	)
	(segment
		(start 251.583444 -90.54592)
		(end 251.577094 -90.556588)
		(width 0.0889)
		(layer "In11.Cu")
		(net "M_F_DQ<31>")
	)
	(segment
		(start 247.772682 -105.896918)
		(end 243.9162 -109.7534)
		(width 0.14224)
		(layer "In11.Cu")
		(net "M_F_DQ<31>")
	)
	(segment
		(start 251.577094 -92.537788)
		(end 251.572268 -92.546424)
		(width 0.0889)
		(layer "In11.Cu")
		(net "M_F_DQ<31>")
	)
	(segment
		(start 231.6734 -138.7856)
		(end 231.602534 -138.856466)
		(width 0.14224)
		(layer "In11.Cu")
		(net "M_F_DQ<31>")
	)
	(segment
		(start 242.231164 -118.531132)
		(end 242.231164 -118.75008)
		(width 0.14224)
		(layer "In11.Cu")
		(net "M_F_DQ<31>")
	)
	(segment
		(start 242.09629 -118.17731)
		(end 242.09629 -118.396258)
		(width 0.14224)
		(layer "In11.Cu")
		(net "M_F_DQ<31>")
	)
	(segment
		(start 241.30254 -118.97106)
		(end 240.946686 -119.326914)
		(width 0.14224)
		(layer "In11.Cu")
		(net "M_F_DQ<31>")
	)
	(segment
		(start 230.799132 -149.9616)
		(end 230.799132 -150.391368)
		(width 0.14224)
		(layer "In11.Cu")
		(net "M_F_DQ<31>")
	)
	(segment
		(start 241.521488 -118.97106)
		(end 241.30254 -118.97106)
		(width 0.14224)
		(layer "In11.Cu")
		(net "M_F_DQ<31>")
	)
	(segment
		(start 243.449094 -116.096034)
		(end 243.733066 -116.380006)
		(width 0.14224)
		(layer "In11.Cu")
		(net "M_F_DQ<31>")
	)
	(segment
		(start 242.231164 -118.75008)
		(end 241.87531 -119.105934)
		(width 0.14224)
		(layer "In11.Cu")
		(net "M_F_DQ<31>")
	)
	(segment
		(start 238.20755 -122.554746)
		(end 238.072676 -122.419872)
		(width 0.14224)
		(layer "In11.Cu")
		(net "M_F_DQ<31>")
	)
	(segment
		(start 231.591612 -149.191472)
		(end 231.249728 -149.533356)
		(width 0.14224)
		(layer "In11.Cu")
		(net "M_F_DQ<31>")
	)
	(segment
		(start 238.782352 -121.979944)
		(end 238.782352 -122.198892)
		(width 0.14224)
		(layer "In11.Cu")
		(net "M_F_DQ<31>")
	)
	(segment
		(start 250.713748 -96.396302)
		(end 250.718574 -96.404938)
		(width 0.0889)
		(layer "In11.Cu")
		(net "M_F_DQ<31>")
	)
	(segment
		(start 231.602534 -136.214612)
		(end 231.602534 -136.5758)
		(width 0.14224)
		(layer "In11.Cu")
		(net "M_F_DQ<31>")
	)
	(segment
		(start 251.583444 -89.55532)
		(end 251.577094 -89.565988)
		(width 0.0889)
		(layer "In11.Cu")
		(net "M_F_DQ<31>")
	)
	(segment
		(start 230.843582 -151.1046)
		(end 230.561134 -151.387048)
		(width 0.14224)
		(layer "In11.Cu")
		(net "M_F_DQ<31>")
	)
	(segment
		(start 240.506758 -120.255538)
		(end 240.371884 -120.120664)
		(width 0.14224)
		(layer "In11.Cu")
		(net "M_F_DQ<31>")
	)
	(segment
		(start 251.577094 -88.575388)
		(end 251.572268 -88.584024)
		(width 0.0889)
		(layer "In11.Cu")
		(net "M_F_DQ<31>")
	)
	(segment
		(start 239.357154 -121.405142)
		(end 239.22228 -121.270268)
		(width 0.14224)
		(layer "In11.Cu")
		(net "M_F_DQ<31>")
	)
	(segment
		(start 251.577094 -90.556588)
		(end 251.572268 -90.565224)
		(width 0.0889)
		(layer "In11.Cu")
		(net "M_F_DQ<31>")
	)
	(segment
		(start 251.56033 -87.955374)
		(end 251.577094 -87.984838)
		(width 0.0889)
		(layer "In11.Cu")
		(net "M_F_DQ<31>")
	)
	(segment
		(start 238.647478 -121.84507)
		(end 238.782352 -121.979944)
		(width 0.14224)
		(layer "In11.Cu")
		(net "M_F_DQ<31>")
	)
	(segment
		(start 250.1392 -97.29089)
		(end 250.040902 -97.29089)
		(width 0.0889)
		(layer "In11.Cu")
		(net "M_F_DQ<31>")
	)
	(segment
		(start 243.449094 -115.808506)
		(end 243.449094 -116.096034)
		(width 0.14224)
		(layer "In11.Cu")
		(net "M_F_DQ<31>")
	)
	(segment
		(start 251.577094 -91.547188)
		(end 251.572268 -91.555824)
		(width 0.0889)
		(layer "In11.Cu")
		(net "M_F_DQ<31>")
	)
	(segment
		(start 250.228354 -97.290636)
		(end 250.139454 -97.290636)
		(width 0.0889)
		(layer "In11.Cu")
		(net "M_F_DQ<31>")
	)
	(segment
		(start 239.797082 -120.476518)
		(end 239.797082 -120.695466)
		(width 0.14224)
		(layer "In11.Cu")
		(net "M_F_DQ<31>")
	)
	(segment
		(start 238.072676 -122.419872)
		(end 237.853728 -122.419872)
		(width 0.14224)
		(layer "In11.Cu")
		(net "M_F_DQ<31>")
	)
	(segment
		(start 231.771698 -145.646902)
		(end 231.602534 -145.816066)
		(width 0.14224)
		(layer "In11.Cu")
		(net "M_F_DQ<31>")
	)
	(segment
		(start 231.831134 -139.689078)
		(end 231.831134 -140.806678)
		(width 0.14224)
		(layer "In11.Cu")
		(net "M_F_DQ<31>")
	)
	(segment
		(start 250.718574 -95.414338)
		(end 250.724924 -95.425006)
		(width 0.0889)
		(layer "In11.Cu")
		(net "M_F_DQ<31>")
	)
	(segment
		(start 238.426498 -122.554746)
		(end 238.20755 -122.554746)
		(width 0.14224)
		(layer "In11.Cu")
		(net "M_F_DQ<31>")
	)
	(segment
		(start 250.718574 -96.404938)
		(end 250.724924 -96.415606)
		(width 0.0889)
		(layer "In11.Cu")
		(net "M_F_DQ<31>")
	)
	(segment
		(start 231.746298 -124.234956)
		(end 231.746298 -125.555502)
		(width 0.14224)
		(layer "In11.Cu")
		(net "M_F_DQ<31>")
	)
	(segment
		(start 240.725706 -120.255538)
		(end 240.506758 -120.255538)
		(width 0.14224)
		(layer "In11.Cu")
		(net "M_F_DQ<31>")
	)
	(segment
		(start 241.656362 -119.105934)
		(end 241.521488 -118.97106)
		(width 0.14224)
		(layer "In11.Cu")
		(net "M_F_DQ<31>")
	)
	(segment
		(start 238.782352 -122.198892)
		(end 238.426498 -122.554746)
		(width 0.14224)
		(layer "In11.Cu")
		(net "M_F_DQ<31>")
	)
	(segment
		(start 230.849932 -153.04135)
		(end 230.849932 -153.364946)
		(width 0.14224)
		(layer "In11.Cu")
		(net "M_F_DQ<31>")
	)
	(segment
		(start 230.849932 -153.364946)
		(end 230.672132 -153.542746)
		(width 0.14224)
		(layer "In11.Cu")
		(net "M_F_DQ<31>")
	)
	(segment
		(start 231.6734 -134.0358)
		(end 231.627934 -134.081266)
		(width 0.14224)
		(layer "In11.Cu")
		(net "M_F_DQ<31>")
	)
	(segment
		(start 237.4646 -122.809)
		(end 233.172254 -122.809)
		(width 0.14224)
		(layer "In11.Cu")
		(net "M_F_DQ<31>")
	)
	(segment
		(start 240.152936 -120.120664)
		(end 239.797082 -120.476518)
		(width 0.14224)
		(layer "In11.Cu")
		(net "M_F_DQ<31>")
	)
	(segment
		(start 247.562624 -102.474014)
		(end 247.562624 -102.95763)
		(width 0.0889)
		(layer "In11.Cu")
		(net "M_F_DQ<31>")
	)
	(segment
		(start 247.562624 -102.95763)
		(end 247.772682 -103.167688)
		(width 0.0889)
		(layer "In11.Cu")
		(net "M_F_DQ<31>")
	)
	(segment
		(start 242.2906 -117.983)
		(end 242.09629 -118.17731)
		(width 0.14224)
		(layer "In11.Cu")
		(net "M_F_DQ<31>")
	)
	(segment
		(start 248.019824 -100.416614)
		(end 248.019824 -102.016814)
		(width 0.0889)
		(layer "In11.Cu")
		(net "M_F_DQ<31>")
	)
	(segment
		(start 231.602534 -125.699266)
		(end 231.602534 -129.859278)
		(width 0.14224)
		(layer "In11.Cu")
		(net "M_F_DQ<31>")
	)
	(segment
		(start 231.227376 -149.533356)
		(end 230.799132 -149.9616)
		(width 0.14224)
		(layer "In11.Cu")
		(net "M_F_DQ<31>")
	)
	(segment
		(start 243.733066 -116.380006)
		(end 243.733066 -116.667534)
		(width 0.14224)
		(layer "In11.Cu")
		(net "M_F_DQ<31>")
	)
	(segment
		(start 242.2906 -116.967)
		(end 242.2906 -117.983)
		(width 0.14224)
		(layer "In11.Cu")
		(net "M_F_DQ<31>")
	)
	(segment
		(start 231.551734 -141.086078)
		(end 231.551734 -141.5796)
		(width 0.14224)
		(layer "In11.Cu")
		(net "M_F_DQ<31>")
	)
	(segment
		(start 231.602534 -129.859278)
		(end 231.831134 -130.087878)
		(width 0.14224)
		(layer "In11.Cu")
		(net "M_F_DQ<31>")
	)
	(segment
		(start 231.6734 -136.646666)
		(end 231.6734 -138.7856)
		(width 0.14224)
		(layer "In11.Cu")
		(net "M_F_DQ<31>")
	)
	(segment
		(start 231.831134 -130.087878)
		(end 231.831134 -131.205478)
		(width 0.14224)
		(layer "In11.Cu")
		(net "M_F_DQ<31>")
	)
	(segment
		(start 239.22228 -121.270268)
		(end 239.003332 -121.270268)
		(width 0.14224)
		(layer "In11.Cu")
		(net "M_F_DQ<31>")
	)
	(segment
		(start 243.158264 -116.954808)
		(end 242.874292 -116.670836)
		(width 0.14224)
		(layer "In11.Cu")
		(net "M_F_DQ<31>")
	)
	(segment
		(start 231.627934 -131.9022)
		(end 231.6734 -131.947666)
		(width 0.14224)
		(layer "In11.Cu")
		(net "M_F_DQ<31>")
	)
	(segment
		(start 248.019824 -102.016814)
		(end 247.562624 -102.474014)
		(width 0.0889)
		(layer "In11.Cu")
		(net "M_F_DQ<31>")
	)
	(segment
		(start 230.672132 -153.542746)
		(end 230.399844 -153.542746)
		(width 0.14224)
		(layer "In11.Cu")
		(net "M_F_DQ<31>")
	)
	(segment
		(start 231.6734 -141.701266)
		(end 231.6734 -143.7132)
		(width 0.14224)
		(layer "In11.Cu")
		(net "M_F_DQ<31>")
	)
	(segment
		(start 231.249728 -149.533356)
		(end 231.227376 -149.533356)
		(width 0.14224)
		(layer "In11.Cu")
		(net "M_F_DQ<31>")
	)
	(segment
		(start 231.6734 -143.7132)
		(end 231.627934 -143.758666)
		(width 0.14224)
		(layer "In11.Cu")
		(net "M_F_DQ<31>")
	)
	(segment
		(start 237.853728 -122.419872)
		(end 237.4646 -122.809)
		(width 0.14224)
		(layer "In11.Cu")
		(net "M_F_DQ<31>")
	)
	(segment
		(start 242.09629 -118.396258)
		(end 242.231164 -118.531132)
		(width 0.14224)
		(layer "In11.Cu")
		(net "M_F_DQ<31>")
	)
	(segment
		(start 240.946686 -119.545862)
		(end 241.08156 -119.680736)
		(width 0.14224)
		(layer "In11.Cu")
		(net "M_F_DQ<31>")
	)
	(segment
		(start 231.627934 -143.758666)
		(end 231.627934 -144.169638)
		(width 0.14224)
		(layer "In11.Cu")
		(net "M_F_DQ<31>")
	)
	(segment
		(start 251.583444 -92.52712)
		(end 251.577094 -92.537788)
		(width 0.0889)
		(layer "In11.Cu")
		(net "M_F_DQ<31>")
	)
	(segment
		(start 230.843582 -150.435818)
		(end 230.843582 -151.1046)
		(width 0.14224)
		(layer "In11.Cu")
		(net "M_F_DQ<31>")
	)
	(segment
		(start 230.561134 -151.660352)
		(end 230.818182 -151.9174)
		(width 0.14224)
		(layer "In11.Cu")
		(net "M_F_DQ<31>")
	)
	(segment
		(start 231.6734 -131.947666)
		(end 231.6734 -134.0358)
		(width 0.14224)
		(layer "In11.Cu")
		(net "M_F_DQ<31>")
	)
	(segment
		(start 242.874292 -116.670836)
		(end 242.586764 -116.670836)
		(width 0.14224)
		(layer "In11.Cu")
		(net "M_F_DQ<31>")
	)
	(segment
		(start 242.586764 -116.670836)
		(end 242.2906 -116.967)
		(width 0.14224)
		(layer "In11.Cu")
		(net "M_F_DQ<31>")
	)
	(segment
		(start 239.576102 -121.405142)
		(end 239.357154 -121.405142)
		(width 0.14224)
		(layer "In11.Cu")
		(net "M_F_DQ<31>")
	)
	(segment
		(start 238.647478 -121.626122)
		(end 238.647478 -121.84507)
		(width 0.14224)
		(layer "In11.Cu")
		(net "M_F_DQ<31>")
	)
	(segment
		(start 230.818182 -151.9174)
		(end 230.818182 -152.2222)
		(width 0.14224)
		(layer "In11.Cu")
		(net "M_F_DQ<31>")
	)
	(segment
		(start 230.561134 -151.387048)
		(end 230.561134 -151.660352)
		(width 0.14224)
		(layer "In11.Cu")
		(net "M_F_DQ<31>")
	)
	(segment
		(start 251.583444 -88.56472)
		(end 251.577094 -88.575388)
		(width 0.0889)
		(layer "In11.Cu")
		(net "M_F_DQ<31>")
	)
	(segment
		(start 230.799132 -150.391368)
		(end 230.843582 -150.435818)
		(width 0.14224)
		(layer "In11.Cu")
		(net "M_F_DQ<31>")
	)
	(segment
		(start 231.627934 -131.408678)
		(end 231.627934 -131.9022)
		(width 0.14224)
		(layer "In11.Cu")
		(net "M_F_DQ<31>")
	)
	(segment
		(start 231.746298 -125.555502)
		(end 231.602534 -125.699266)
		(width 0.14224)
		(layer "In11.Cu")
		(net "M_F_DQ<31>")
	)
	(segment
		(start 243.445792 -116.954808)
		(end 243.158264 -116.954808)
		(width 0.14224)
		(layer "In11.Cu")
		(net "M_F_DQ<31>")
	)
	(segment
		(start 231.805734 -134.757668)
		(end 231.805734 -136.011412)
		(width 0.14224)
		(layer "In11.Cu")
		(net "M_F_DQ<31>")
	)
	(arc
		(start 250.718574 -96.004888)
		(mid 250.665104 -96.199951)
		(end 250.713748 -96.396302)
		(width 0.0889)
		(layer "In11.Cu")
		(net "M_F_DQ<31>")
	)
	(arc
		(start 251.572268 -92.546424)
		(mid 251.523513 -92.742776)
		(end 251.577094 -92.937838)
		(width 0.0889)
		(layer "In11.Cu")
		(net "M_F_DQ<31>")
	)
	(arc
		(start 251.577094 -91.947238)
		(mid 251.656316 -92.236356)
		(end 251.583444 -92.52712)
		(width 0.0889)
		(layer "In11.Cu")
		(net "M_F_DQ<31>")
	)
	(arc
		(start 250.718574 -94.423484)
		(mid 250.797705 -94.718886)
		(end 250.718574 -95.014288)
		(width 0.0889)
		(layer "In11.Cu")
		(net "M_F_DQ<31>")
	)
	(arc
		(start 251.577094 -87.984838)
		(mid 251.656316 -88.273956)
		(end 251.583444 -88.56472)
		(width 0.0889)
		(layer "In11.Cu")
		(net "M_F_DQ<31>")
	)
	(arc
		(start 251.572268 -91.555824)
		(mid 251.523513 -91.752176)
		(end 251.577094 -91.947238)
		(width 0.0889)
		(layer "In11.Cu")
		(net "M_F_DQ<31>")
	)
	(arc
		(start 251.577094 -92.937838)
		(mid 251.582348 -93.519346)
		(end 251.086874 -93.82379)
		(width 0.0889)
		(layer "In11.Cu")
		(net "M_F_DQ<31>")
	)
	(arc
		(start 251.04725 -93.82379)
		(mid 250.714334 -94.031242)
		(end 250.718574 -94.423484)
		(width 0.0889)
		(layer "In11.Cu")
		(net "M_F_DQ<31>")
	)
	(arc
		(start 250.724924 -96.415606)
		(mid 250.720893 -96.991788)
		(end 250.228354 -97.290636)
		(width 0.0889)
		(layer "In11.Cu")
		(net "M_F_DQ<31>")
	)
	(arc
		(start 250.724924 -95.425006)
		(mid 250.797722 -95.715769)
		(end 250.718574 -96.004888)
		(width 0.0889)
		(layer "In11.Cu")
		(net "M_F_DQ<31>")
	)
	(arc
		(start 251.577094 -88.975438)
		(mid 251.656316 -89.264556)
		(end 251.583444 -89.55532)
		(width 0.0889)
		(layer "In11.Cu")
		(net "M_F_DQ<31>")
	)
	(arc
		(start 250.718574 -95.014288)
		(mid 250.665104 -95.209351)
		(end 250.713748 -95.405702)
		(width 0.0889)
		(layer "In11.Cu")
		(net "M_F_DQ<31>")
	)
	(arc
		(start 251.572268 -88.584024)
		(mid 251.523513 -88.780376)
		(end 251.577094 -88.975438)
		(width 0.0889)
		(layer "In11.Cu")
		(net "M_F_DQ<31>")
	)
	(arc
		(start 251.572268 -90.565224)
		(mid 251.523513 -90.761576)
		(end 251.577094 -90.956638)
		(width 0.0889)
		(layer "In11.Cu")
		(net "M_F_DQ<31>")
	)
	(arc
		(start 251.577094 -90.956638)
		(mid 251.656316 -91.245756)
		(end 251.583444 -91.53652)
		(width 0.0889)
		(layer "In11.Cu")
		(net "M_F_DQ<31>")
	)
	(arc
		(start 251.572268 -89.574624)
		(mid 251.523513 -89.770976)
		(end 251.577094 -89.966038)
		(width 0.0889)
		(layer "In11.Cu")
		(net "M_F_DQ<31>")
	)
	(arc
		(start 251.577094 -89.966038)
		(mid 251.656316 -90.255156)
		(end 251.583444 -90.54592)
		(width 0.0889)
		(layer "In11.Cu")
		(net "M_F_DQ<31>")
	)
	(segment
		(start 251.636784 -85.30844)
		(end 251.065284 -85.30844)
		(width 0.1651)
		(layer "F.Cu")
		(net "M_F_DQ<30>")
	)
	(segment
		(start 231.25049 -156.87294)
		(end 231.249982 -156.87294)
		(width 0.1651)
		(layer "F.Cu")
		(net "M_F_DQ<30>")
	)
	(segment
		(start 231.382062 -155.77312)
		(end 231.382062 -155.55468)
		(width 0.1651)
		(layer "F.Cu")
		(net "M_F_DQ<30>")
	)
	(segment
		(start 231.249982 -155.118054)
		(end 231.249728 -155.1178)
		(width 0.1651)
		(layer "F.Cu")
		(net "M_F_DQ<30>")
	)
	(segment
		(start 231.249982 -156.87294)
		(end 231.249982 -155.9052)
		(width 0.1651)
		(layer "F.Cu")
		(net "M_F_DQ<30>")
	)
	(segment
		(start 231.382062 -155.55468)
		(end 231.249982 -155.4226)
		(width 0.1651)
		(layer "F.Cu")
		(net "M_F_DQ<30>")
	)
	(segment
		(start 231.249982 -155.9052)
		(end 231.382062 -155.77312)
		(width 0.1651)
		(layer "F.Cu")
		(net "M_F_DQ<30>")
	)
	(segment
		(start 231.249982 -155.4226)
		(end 231.249982 -155.118054)
		(width 0.1651)
		(layer "F.Cu")
		(net "M_F_DQ<30>")
	)
	(via
		(at 230.399844 -150.814278)
		(size 0.508)
		(drill 0.254)
		(layers "F.Cu" "B.Cu")
		(net "M_F_DQ<30>")
	)
	(via
		(at 251.065284 -85.30844)
		(size 0.508)
		(drill 0.254)
		(layers "F.Cu" "B.Cu")
		(net "M_F_DQ<30>")
	)
	(via
		(at 231.249728 -155.1178)
		(size 0.508)
		(drill 0.254)
		(layers "F.Cu" "B.Cu")
		(net "M_F_DQ<30>")
	)
	(segment
		(start 230.400352 -152.078436)
		(end 230.399844 -152.078182)
		(width 0.1651)
		(layer "B.Cu")
		(net "M_F_DQ<30>")
	)
	(segment
		(start 230.399844 -152.078182)
		(end 230.399844 -150.814278)
		(width 0.1651)
		(layer "B.Cu")
		(net "M_F_DQ<30>")
	)
	(segment
		(start 250.553474 -94.518988)
		(end 250.5583 -94.527624)
		(width 0.0889)
		(layer "In11.Cu")
		(net "M_F_DQ<30>")
	)
	(segment
		(start 232.8164 -122.174)
		(end 230.8098 -124.1806)
		(width 0.14224)
		(layer "In11.Cu")
		(net "M_F_DQ<30>")
	)
	(segment
		(start 230.764334 -139.663678)
		(end 230.764334 -140.908278)
		(width 0.14224)
		(layer "In11.Cu")
		(net "M_F_DQ<30>")
	)
	(segment
		(start 250.735338 -86.070186)
		(end 250.718574 -86.098888)
		(width 0.0889)
		(layer "In11.Cu")
		(net "M_F_DQ<30>")
	)
	(segment
		(start 230.967534 -136.276588)
		(end 230.967534 -136.69772)
		(width 0.14224)
		(layer "In11.Cu")
		(net "M_F_DQ<30>")
	)
	(segment
		(start 250.22175 -97.100136)
		(end 250.13285 -97.100136)
		(width 0.0889)
		(layer "In11.Cu")
		(net "M_F_DQ<30>")
	)
	(segment
		(start 251.411994 -90.461338)
		(end 251.405644 -90.472006)
		(width 0.0889)
		(layer "In11.Cu")
		(net "M_F_DQ<30>")
	)
	(segment
		(start 251.411994 -92.442538)
		(end 251.405644 -92.453206)
		(width 0.0889)
		(layer "In11.Cu")
		(net "M_F_DQ<30>")
	)
	(segment
		(start 230.967534 -146.177)
		(end 230.8352 -146.309334)
		(width 0.14224)
		(layer "In11.Cu")
		(net "M_F_DQ<30>")
	)
	(segment
		(start 230.8352 -134.0104)
		(end 230.865934 -134.041134)
		(width 0.14224)
		(layer "In11.Cu")
		(net "M_F_DQ<30>")
	)
	(segment
		(start 249.616976 -97.446084)
		(end 249.616976 -98.55073)
		(width 0.0889)
		(layer "In11.Cu")
		(net "M_F_DQ<30>")
	)
	(segment
		(start 230.8098 -124.1806)
		(end 230.8098 -125.6284)
		(width 0.14224)
		(layer "In11.Cu")
		(net "M_F_DQ<30>")
	)
	(segment
		(start 230.8352 -131.932934)
		(end 230.8352 -134.0104)
		(width 0.14224)
		(layer "In11.Cu")
		(net "M_F_DQ<30>")
	)
	(segment
		(start 250.718574 -86.498938)
		(end 250.724924 -86.509606)
		(width 0.0889)
		(layer "In11.Cu")
		(net "M_F_DQ<30>")
	)
	(segment
		(start 230.916734 -144.118838)
		(end 230.644192 -144.39138)
		(width 0.14224)
		(layer "In11.Cu")
		(net "M_F_DQ<30>")
	)
	(segment
		(start 230.865934 -134.041134)
		(end 230.865934 -134.579868)
		(width 0.14224)
		(layer "In11.Cu")
		(net "M_F_DQ<30>")
	)
	(segment
		(start 230.823516 -138.672316)
		(end 230.967534 -138.816334)
		(width 0.14224)
		(layer "In11.Cu")
		(net "M_F_DQ<30>")
	)
	(segment
		(start 241.6048 -116.6876)
		(end 241.6048 -117.7544)
		(width 0.14224)
		(layer "In11.Cu")
		(net "M_F_DQ<30>")
	)
	(segment
		(start 230.967534 -129.859278)
		(end 230.764334 -130.062478)
		(width 0.14224)
		(layer "In11.Cu")
		(net "M_F_DQ<30>")
	)
	(segment
		(start 243.2558 -109.4994)
		(end 243.2558 -115.0366)
		(width 0.14224)
		(layer "In11.Cu")
		(net "M_F_DQ<30>")
	)
	(segment
		(start 250.547124 -96.48952)
		(end 250.553474 -96.500188)
		(width 0.0889)
		(layer "In11.Cu")
		(net "M_F_DQ<30>")
	)
	(segment
		(start 250.713748 -86.490302)
		(end 250.718574 -86.498938)
		(width 0.0889)
		(layer "In11.Cu")
		(net "M_F_DQ<30>")
	)
	(segment
		(start 249.616976 -98.55073)
		(end 247.829832 -100.337874)
		(width 0.0889)
		(layer "In11.Cu")
		(net "M_F_DQ<30>")
	)
	(segment
		(start 230.967534 -136.69772)
		(end 230.823516 -136.841738)
		(width 0.14224)
		(layer "In11.Cu")
		(net "M_F_DQ<30>")
	)
	(segment
		(start 230.967534 -125.786134)
		(end 230.967534 -129.859278)
		(width 0.14224)
		(layer "In11.Cu")
		(net "M_F_DQ<30>")
	)
	(segment
		(start 251.065284 -85.30844)
		(end 250.735338 -86.070186)
		(width 0.0889)
		(layer "In11.Cu")
		(net "M_F_DQ<30>")
	)
	(segment
		(start 230.8352 -146.309334)
		(end 230.8352 -148.4376)
		(width 0.14224)
		(layer "In11.Cu")
		(net "M_F_DQ<30>")
	)
	(segment
		(start 241.6048 -117.7544)
		(end 237.1852 -122.174)
		(width 0.14224)
		(layer "In11.Cu")
		(net "M_F_DQ<30>")
	)
	(segment
		(start 230.916734 -141.5796)
		(end 230.8352 -141.661134)
		(width 0.14224)
		(layer "In11.Cu")
		(net "M_F_DQ<30>")
	)
	(segment
		(start 251.065284 -87.88019)
		(end 251.08027 -87.88019)
		(width 0.0889)
		(layer "In11.Cu")
		(net "M_F_DQ<30>")
	)
	(segment
		(start 251.41682 -89.462102)
		(end 251.411994 -89.470738)
		(width 0.0889)
		(layer "In11.Cu")
		(net "M_F_DQ<30>")
	)
	(segment
		(start 237.1852 -122.174)
		(end 232.8164 -122.174)
		(width 0.14224)
		(layer "In11.Cu")
		(net "M_F_DQ<30>")
	)
	(segment
		(start 247.359424 -102.397814)
		(end 247.359424 -102.945946)
		(width 0.0889)
		(layer "In11.Cu")
		(net "M_F_DQ<30>")
	)
	(segment
		(start 230.8352 -148.4376)
		(end 230.967534 -148.569934)
		(width 0.14224)
		(layer "In11.Cu")
		(net "M_F_DQ<30>")
	)
	(segment
		(start 251.41682 -91.443302)
		(end 251.411994 -91.451938)
		(width 0.0889)
		(layer "In11.Cu")
		(net "M_F_DQ<30>")
	)
	(segment
		(start 250.06046 -97.100898)
		(end 249.962162 -97.100898)
		(width 0.0889)
		(layer "In11.Cu")
		(net "M_F_DQ<30>")
	)
	(segment
		(start 230.967534 -145.857468)
		(end 230.967534 -146.177)
		(width 0.14224)
		(layer "In11.Cu")
		(net "M_F_DQ<30>")
	)
	(segment
		(start 247.829832 -101.927406)
		(end 247.359424 -102.397814)
		(width 0.0889)
		(layer "In11.Cu")
		(net "M_F_DQ<30>")
	)
	(segment
		(start 230.865934 -134.579868)
		(end 230.764334 -134.681468)
		(width 0.14224)
		(layer "In11.Cu")
		(net "M_F_DQ<30>")
	)
	(segment
		(start 229.966774 -151.247348)
		(end 229.966774 -153.834846)
		(width 0.14224)
		(layer "In11.Cu")
		(net "M_F_DQ<30>")
	)
	(segment
		(start 250.713748 -87.480902)
		(end 250.883166 -87.775034)
		(width 0.0889)
		(layer "In11.Cu")
		(net "M_F_DQ<30>")
	)
	(segment
		(start 251.411994 -91.451938)
		(end 251.405644 -91.462606)
		(width 0.0889)
		(layer "In11.Cu")
		(net "M_F_DQ<30>")
	)
	(segment
		(start 230.2256 -149.6822)
		(end 230.2256 -150.640034)
		(width 0.14224)
		(layer "In11.Cu")
		(net "M_F_DQ<30>")
	)
	(segment
		(start 229.966774 -153.834846)
		(end 231.249728 -155.1178)
		(width 0.14224)
		(layer "In11.Cu")
		(net "M_F_DQ<30>")
	)
	(segment
		(start 230.644192 -145.534126)
		(end 230.967534 -145.857468)
		(width 0.14224)
		(layer "In11.Cu")
		(net "M_F_DQ<30>")
	)
	(segment
		(start 230.8352 -143.7132)
		(end 230.916734 -143.794734)
		(width 0.14224)
		(layer "In11.Cu")
		(net "M_F_DQ<30>")
	)
	(segment
		(start 250.060714 -97.100644)
		(end 250.06046 -97.100898)
		(width 0.0889)
		(layer "In11.Cu")
		(net "M_F_DQ<30>")
	)
	(segment
		(start 247.137682 -105.617518)
		(end 243.2558 -109.4994)
		(width 0.14224)
		(layer "In11.Cu")
		(net "M_F_DQ<30>")
	)
	(segment
		(start 251.083318 -93.633036)
		(end 251.047504 -93.633036)
		(width 0.0889)
		(layer "In11.Cu")
		(net "M_F_DQ<30>")
	)
	(segment
		(start 230.8352 -141.661134)
		(end 230.8352 -143.7132)
		(width 0.14224)
		(layer "In11.Cu")
		(net "M_F_DQ<30>")
	)
	(segment
		(start 243.2558 -115.0366)
		(end 241.6048 -116.6876)
		(width 0.14224)
		(layer "In11.Cu")
		(net "M_F_DQ<30>")
	)
	(segment
		(start 251.41682 -88.471502)
		(end 251.411994 -88.480138)
		(width 0.0889)
		(layer "In11.Cu")
		(net "M_F_DQ<30>")
	)
	(segment
		(start 230.764334 -140.908278)
		(end 230.916734 -141.060678)
		(width 0.14224)
		(layer "In11.Cu")
		(net "M_F_DQ<30>")
	)
	(segment
		(start 249.962162 -97.100898)
		(end 249.616976 -97.446084)
		(width 0.0889)
		(layer "In11.Cu")
		(net "M_F_DQ<30>")
	)
	(segment
		(start 230.2256 -150.640034)
		(end 230.399844 -150.814278)
		(width 0.14224)
		(layer "In11.Cu")
		(net "M_F_DQ<30>")
	)
	(segment
		(start 251.41682 -90.452702)
		(end 251.411994 -90.461338)
		(width 0.0889)
		(layer "In11.Cu")
		(net "M_F_DQ<30>")
	)
	(segment
		(start 230.967534 -148.569934)
		(end 230.967534 -148.940266)
		(width 0.14224)
		(layer "In11.Cu")
		(net "M_F_DQ<30>")
	)
	(segment
		(start 230.967534 -148.940266)
		(end 230.2256 -149.6822)
		(width 0.14224)
		(layer "In11.Cu")
		(net "M_F_DQ<30>")
	)
	(segment
		(start 250.13285 -97.100136)
		(end 250.132342 -97.100644)
		(width 0.0889)
		(layer "In11.Cu")
		(net "M_F_DQ<30>")
	)
	(segment
		(start 230.916734 -143.794734)
		(end 230.916734 -144.118838)
		(width 0.14224)
		(layer "In11.Cu")
		(net "M_F_DQ<30>")
	)
	(segment
		(start 251.41682 -92.433902)
		(end 251.411994 -92.442538)
		(width 0.0889)
		(layer "In11.Cu")
		(net "M_F_DQ<30>")
	)
	(segment
		(start 230.644192 -144.39138)
		(end 230.644192 -145.534126)
		(width 0.14224)
		(layer "In11.Cu")
		(net "M_F_DQ<30>")
	)
	(segment
		(start 230.967534 -138.816334)
		(end 230.967534 -139.460478)
		(width 0.14224)
		(layer "In11.Cu")
		(net "M_F_DQ<30>")
	)
	(segment
		(start 250.553474 -95.509588)
		(end 250.5583 -95.518224)
		(width 0.0889)
		(layer "In11.Cu")
		(net "M_F_DQ<30>")
	)
	(segment
		(start 230.764334 -130.062478)
		(end 230.764334 -131.307078)
		(width 0.14224)
		(layer "In11.Cu")
		(net "M_F_DQ<30>")
	)
	(segment
		(start 250.547124 -95.49892)
		(end 250.553474 -95.509588)
		(width 0.0889)
		(layer "In11.Cu")
		(net "M_F_DQ<30>")
	)
	(segment
		(start 251.411994 -89.470738)
		(end 251.405644 -89.481406)
		(width 0.0889)
		(layer "In11.Cu")
		(net "M_F_DQ<30>")
	)
	(segment
		(start 251.411994 -88.480138)
		(end 251.405644 -88.490806)
		(width 0.0889)
		(layer "In11.Cu")
		(net "M_F_DQ<30>")
	)
	(segment
		(start 250.553474 -96.500188)
		(end 250.5583 -96.508824)
		(width 0.0889)
		(layer "In11.Cu")
		(net "M_F_DQ<30>")
	)
	(segment
		(start 230.8098 -125.6284)
		(end 230.967534 -125.786134)
		(width 0.14224)
		(layer "In11.Cu")
		(net "M_F_DQ<30>")
	)
	(segment
		(start 230.865934 -131.9022)
		(end 230.8352 -131.932934)
		(width 0.14224)
		(layer "In11.Cu")
		(net "M_F_DQ<30>")
	)
	(segment
		(start 230.764334 -131.307078)
		(end 230.865934 -131.408678)
		(width 0.14224)
		(layer "In11.Cu")
		(net "M_F_DQ<30>")
	)
	(segment
		(start 230.764334 -134.681468)
		(end 230.764334 -136.073388)
		(width 0.14224)
		(layer "In11.Cu")
		(net "M_F_DQ<30>")
	)
	(segment
		(start 230.865934 -131.408678)
		(end 230.865934 -131.9022)
		(width 0.14224)
		(layer "In11.Cu")
		(net "M_F_DQ<30>")
	)
	(segment
		(start 230.764334 -136.073388)
		(end 230.967534 -136.276588)
		(width 0.14224)
		(layer "In11.Cu")
		(net "M_F_DQ<30>")
	)
	(segment
		(start 247.829832 -100.337874)
		(end 247.829832 -101.927406)
		(width 0.0889)
		(layer "In11.Cu")
		(net "M_F_DQ<30>")
	)
	(segment
		(start 230.823516 -136.841738)
		(end 230.823516 -138.672316)
		(width 0.14224)
		(layer "In11.Cu")
		(net "M_F_DQ<30>")
	)
	(segment
		(start 230.399844 -150.814278)
		(end 229.966774 -151.247348)
		(width 0.14224)
		(layer "In11.Cu")
		(net "M_F_DQ<30>")
	)
	(segment
		(start 230.967534 -139.460478)
		(end 230.764334 -139.663678)
		(width 0.14224)
		(layer "In11.Cu")
		(net "M_F_DQ<30>")
	)
	(segment
		(start 247.359424 -102.945946)
		(end 247.137682 -103.167688)
		(width 0.0889)
		(layer "In11.Cu")
		(net "M_F_DQ<30>")
	)
	(segment
		(start 230.916734 -141.060678)
		(end 230.916734 -141.5796)
		(width 0.14224)
		(layer "In11.Cu")
		(net "M_F_DQ<30>")
	)
	(segment
		(start 247.137682 -103.167688)
		(end 247.137682 -105.617518)
		(width 0.14224)
		(layer "In11.Cu")
		(net "M_F_DQ<30>")
	)
	(segment
		(start 250.132342 -97.100644)
		(end 250.060714 -97.100644)
		(width 0.0889)
		(layer "In11.Cu")
		(net "M_F_DQ<30>")
	)
	(arc
		(start 250.718574 -86.098888)
		(mid 250.665104 -86.293951)
		(end 250.713748 -86.490302)
		(width 0.0889)
		(layer "In11.Cu")
		(net "M_F_DQ<30>")
	)
	(arc
		(start 251.405644 -88.490806)
		(mid 251.332846 -88.781569)
		(end 251.411994 -89.070688)
		(width 0.0889)
		(layer "In11.Cu")
		(net "M_F_DQ<30>")
	)
	(arc
		(start 250.553474 -94.919038)
		(mid 250.474252 -95.208156)
		(end 250.547124 -95.49892)
		(width 0.0889)
		(layer "In11.Cu")
		(net "M_F_DQ<30>")
	)
	(arc
		(start 251.405644 -89.481406)
		(mid 251.332846 -89.772169)
		(end 251.411994 -90.061288)
		(width 0.0889)
		(layer "In11.Cu")
		(net "M_F_DQ<30>")
	)
	(arc
		(start 250.724924 -86.509606)
		(mid 250.797722 -86.800369)
		(end 250.718574 -87.089488)
		(width 0.0889)
		(layer "In11.Cu")
		(net "M_F_DQ<30>")
	)
	(arc
		(start 251.411994 -91.051888)
		(mid 251.465464 -91.246951)
		(end 251.41682 -91.443302)
		(width 0.0889)
		(layer "In11.Cu")
		(net "M_F_DQ<30>")
	)
	(arc
		(start 250.553474 -95.909638)
		(mid 250.474252 -96.198756)
		(end 250.547124 -96.48952)
		(width 0.0889)
		(layer "In11.Cu")
		(net "M_F_DQ<30>")
	)
	(arc
		(start 250.718574 -87.089488)
		(mid 250.665104 -87.284551)
		(end 250.713748 -87.480902)
		(width 0.0889)
		(layer "In11.Cu")
		(net "M_F_DQ<30>")
	)
	(arc
		(start 251.405644 -92.453206)
		(mid 251.332846 -92.743969)
		(end 251.411994 -93.033088)
		(width 0.0889)
		(layer "In11.Cu")
		(net "M_F_DQ<30>")
	)
	(arc
		(start 251.405644 -91.462606)
		(mid 251.332846 -91.753369)
		(end 251.411994 -92.042488)
		(width 0.0889)
		(layer "In11.Cu")
		(net "M_F_DQ<30>")
	)
	(arc
		(start 251.411994 -93.033088)
		(mid 251.416404 -93.425551)
		(end 251.083318 -93.633036)
		(width 0.0889)
		(layer "In11.Cu")
		(net "M_F_DQ<30>")
	)
	(arc
		(start 251.411994 -89.070688)
		(mid 251.465464 -89.265751)
		(end 251.41682 -89.462102)
		(width 0.0889)
		(layer "In11.Cu")
		(net "M_F_DQ<30>")
	)
	(arc
		(start 250.5583 -94.527624)
		(mid 250.607055 -94.723976)
		(end 250.553474 -94.919038)
		(width 0.0889)
		(layer "In11.Cu")
		(net "M_F_DQ<30>")
	)
	(arc
		(start 251.411994 -92.042488)
		(mid 251.465464 -92.237551)
		(end 251.41682 -92.433902)
		(width 0.0889)
		(layer "In11.Cu")
		(net "M_F_DQ<30>")
	)
	(arc
		(start 250.883166 -87.775034)
		(mid 250.960139 -87.852003)
		(end 251.065284 -87.88019)
		(width 0.0889)
		(layer "In11.Cu")
		(net "M_F_DQ<30>")
	)
	(arc
		(start 250.5583 -96.508824)
		(mid 250.554553 -96.89808)
		(end 250.22175 -97.100136)
		(width 0.0889)
		(layer "In11.Cu")
		(net "M_F_DQ<30>")
	)
	(arc
		(start 250.5583 -95.518224)
		(mid 250.607055 -95.714576)
		(end 250.553474 -95.909638)
		(width 0.0889)
		(layer "In11.Cu")
		(net "M_F_DQ<30>")
	)
	(arc
		(start 251.047504 -93.633036)
		(mid 250.549253 -93.935876)
		(end 250.553474 -94.518988)
		(width 0.0889)
		(layer "In11.Cu")
		(net "M_F_DQ<30>")
	)
	(arc
		(start 251.405644 -90.472006)
		(mid 251.332846 -90.762769)
		(end 251.411994 -91.051888)
		(width 0.0889)
		(layer "In11.Cu")
		(net "M_F_DQ<30>")
	)
	(arc
		(start 251.08027 -87.88019)
		(mid 251.413188 -88.082181)
		(end 251.41682 -88.471502)
		(width 0.0889)
		(layer "In11.Cu")
		(net "M_F_DQ<30>")
	)
	(arc
		(start 251.411994 -90.061288)
		(mid 251.465464 -90.256351)
		(end 251.41682 -90.452702)
		(width 0.0889)
		(layer "In11.Cu")
		(net "M_F_DQ<30>")
	)
	(segment
		(start 241.334798 -88.28024)
		(end 240.763298 -88.28024)
		(width 0.1651)
		(layer "F.Cu")
		(net "M_F_DQ<2>")
	)
	(segment
		(start 204.899768 -155.395168)
		(end 204.899768 -155.1178)
		(width 0.1651)
		(layer "F.Cu")
		(net "M_F_DQ<2>")
	)
	(segment
		(start 205.03134 -155.75026)
		(end 205.03134 -155.52674)
		(width 0.1651)
		(layer "F.Cu")
		(net "M_F_DQ<2>")
	)
	(segment
		(start 205.03134 -155.52674)
		(end 204.899768 -155.395168)
		(width 0.1651)
		(layer "F.Cu")
		(net "M_F_DQ<2>")
	)
	(segment
		(start 204.899768 -155.881832)
		(end 205.03134 -155.75026)
		(width 0.1651)
		(layer "F.Cu")
		(net "M_F_DQ<2>")
	)
	(segment
		(start 204.900276 -156.87294)
		(end 204.899768 -156.87294)
		(width 0.1651)
		(layer "F.Cu")
		(net "M_F_DQ<2>")
	)
	(segment
		(start 204.899768 -156.87294)
		(end 204.899768 -155.881832)
		(width 0.1651)
		(layer "F.Cu")
		(net "M_F_DQ<2>")
	)
	(via
		(at 204.899768 -155.1178)
		(size 0.508)
		(drill 0.254)
		(layers "F.Cu" "B.Cu")
		(net "M_F_DQ<2>")
	)
	(via
		(at 240.763298 -88.28024)
		(size 0.508)
		(drill 0.254)
		(layers "F.Cu" "B.Cu")
		(net "M_F_DQ<2>")
	)
	(via
		(at 204.049884 -150.814278)
		(size 0.508)
		(drill 0.254)
		(layers "F.Cu" "B.Cu")
		(net "M_F_DQ<2>")
	)
	(segment
		(start 204.050392 -152.078436)
		(end 204.049884 -152.078182)
		(width 0.1651)
		(layer "B.Cu")
		(net "M_F_DQ<2>")
	)
	(segment
		(start 204.049884 -152.078182)
		(end 204.049884 -150.814278)
		(width 0.1651)
		(layer "B.Cu")
		(net "M_F_DQ<2>")
	)
	(segment
		(start 204.049884 -150.814278)
		(end 203.616814 -151.247348)
		(width 0.14224)
		(layer "In11.Cu")
		(net "M_F_DQ<2>")
	)
	(segment
		(start 204.6478 -136.652)
		(end 204.47 -136.8298)
		(width 0.14224)
		(layer "In11.Cu")
		(net "M_F_DQ<2>")
	)
	(segment
		(start 209.808826 -109.522768)
		(end 204.6986 -114.632994)
		(width 0.14224)
		(layer "In11.Cu")
		(net "M_F_DQ<2>")
	)
	(segment
		(start 204.4065 -127.0381)
		(end 204.4065 -129.1463)
		(width 0.14224)
		(layer "In11.Cu")
		(net "M_F_DQ<2>")
	)
	(segment
		(start 204.568552 -148.972778)
		(end 203.704952 -149.836378)
		(width 0.14224)
		(layer "In11.Cu")
		(net "M_F_DQ<2>")
	)
	(segment
		(start 234.768644 -90.165936)
		(end 234.735878 -90.165936)
		(width 0.0889)
		(layer "In11.Cu")
		(net "M_F_DQ<2>")
	)
	(segment
		(start 204.416152 -131.188206)
		(end 204.6986 -131.470654)
		(width 0.14224)
		(layer "In11.Cu")
		(net "M_F_DQ<2>")
	)
	(segment
		(start 204.6224 -146.4056)
		(end 204.4192 -146.6088)
		(width 0.14224)
		(layer "In11.Cu")
		(net "M_F_DQ<2>")
	)
	(segment
		(start 214.62111 -106.722164)
		(end 214.62111 -107.009692)
		(width 0.14224)
		(layer "In11.Cu")
		(net "M_F_DQ<2>")
	)
	(segment
		(start 204.6986 -115.4176)
		(end 205.252574 -115.971574)
		(width 0.14224)
		(layer "In11.Cu")
		(net "M_F_DQ<2>")
	)
	(segment
		(start 203.616814 -153.834846)
		(end 204.899768 -155.1178)
		(width 0.14224)
		(layer "In11.Cu")
		(net "M_F_DQ<2>")
	)
	(segment
		(start 213.489794 -105.8418)
		(end 210.569556 -108.762038)
		(width 0.14224)
		(layer "In11.Cu")
		(net "M_F_DQ<2>")
	)
	(segment
		(start 204.416152 -129.960878)
		(end 204.416152 -131.188206)
		(width 0.14224)
		(layer "In11.Cu")
		(net "M_F_DQ<2>")
	)
	(segment
		(start 240.43386 -87.519256)
		(end 240.416588 -87.489538)
		(width 0.0889)
		(layer "In11.Cu")
		(net "M_F_DQ<2>")
	)
	(segment
		(start 211.195158 -109.28604)
		(end 214.046308 -106.43489)
		(width 0.14224)
		(layer "In11.Cu")
		(net "M_F_DQ<2>")
	)
	(segment
		(start 204.416152 -139.703302)
		(end 204.416152 -140.814806)
		(width 0.14224)
		(layer "In11.Cu")
		(net "M_F_DQ<2>")
	)
	(segment
		(start 203.704952 -149.836378)
		(end 203.704952 -150.469346)
		(width 0.14224)
		(layer "In11.Cu")
		(net "M_F_DQ<2>")
	)
	(segment
		(start 204.6732 -143.637)
		(end 204.6732 -144.03959)
		(width 0.14224)
		(layer "In11.Cu")
		(net "M_F_DQ<2>")
	)
	(segment
		(start 228.404166 -91.657424)
		(end 228.39299 -91.6686)
		(width 0.14224)
		(layer "In11.Cu")
		(net "M_F_DQ<2>")
	)
	(segment
		(start 215.788748 -105.8418)
		(end 213.489794 -105.8418)
		(width 0.14224)
		(layer "In11.Cu")
		(net "M_F_DQ<2>")
	)
	(segment
		(start 232.425748 -91.430094)
		(end 231.667812 -91.430094)
		(width 0.0889)
		(layer "In11.Cu")
		(net "M_F_DQ<2>")
	)
	(segment
		(start 228.39299 -91.6686)
		(end 227.9396 -91.6686)
		(width 0.14224)
		(layer "In11.Cu")
		(net "M_F_DQ<2>")
	)
	(segment
		(start 204.339952 -144.372838)
		(end 204.339952 -145.578068)
		(width 0.14224)
		(layer "In11.Cu")
		(net "M_F_DQ<2>")
	)
	(segment
		(start 204.4192 -146.6088)
		(end 204.4192 -148.336)
		(width 0.14224)
		(layer "In11.Cu")
		(net "M_F_DQ<2>")
	)
	(segment
		(start 233.051604 -91.156536)
		(end 232.699306 -91.156536)
		(width 0.0889)
		(layer "In11.Cu")
		(net "M_F_DQ<2>")
	)
	(segment
		(start 231.230424 -91.867482)
		(end 228.614224 -91.867482)
		(width 0.0889)
		(layer "In11.Cu")
		(net "M_F_DQ<2>")
	)
	(segment
		(start 204.6732 -144.03959)
		(end 204.339952 -144.372838)
		(width 0.14224)
		(layer "In11.Cu")
		(net "M_F_DQ<2>")
	)
	(segment
		(start 228.614224 -91.867482)
		(end 228.404166 -91.657424)
		(width 0.0889)
		(layer "In11.Cu")
		(net "M_F_DQ<2>")
	)
	(segment
		(start 204.390752 -134.712964)
		(end 204.390752 -136.064752)
		(width 0.14224)
		(layer "In11.Cu")
		(net "M_F_DQ<2>")
	)
	(segment
		(start 204.6986 -134.405116)
		(end 204.390752 -134.712964)
		(width 0.14224)
		(layer "In11.Cu")
		(net "M_F_DQ<2>")
	)
	(segment
		(start 240.763298 -88.28024)
		(end 240.43386 -87.519256)
		(width 0.0889)
		(layer "In11.Cu")
		(net "M_F_DQ<2>")
	)
	(segment
		(start 235.623354 -89.67089)
		(end 235.590588 -89.67089)
		(width 0.0889)
		(layer "In11.Cu")
		(net "M_F_DQ<2>")
	)
	(segment
		(start 204.47 -138.8618)
		(end 204.6478 -139.0396)
		(width 0.14224)
		(layer "In11.Cu")
		(net "M_F_DQ<2>")
	)
	(segment
		(start 204.6478 -139.0396)
		(end 204.6478 -139.471654)
		(width 0.14224)
		(layer "In11.Cu")
		(net "M_F_DQ<2>")
	)
	(segment
		(start 203.704952 -150.469346)
		(end 204.049884 -150.814278)
		(width 0.14224)
		(layer "In11.Cu")
		(net "M_F_DQ<2>")
	)
	(segment
		(start 204.416152 -140.814806)
		(end 204.6732 -141.071854)
		(width 0.14224)
		(layer "In11.Cu")
		(net "M_F_DQ<2>")
	)
	(segment
		(start 210.569556 -108.762038)
		(end 210.569556 -108.998766)
		(width 0.14224)
		(layer "In11.Cu")
		(net "M_F_DQ<2>")
	)
	(segment
		(start 237.340394 -88.68029)
		(end 237.307628 -88.68029)
		(width 0.0889)
		(layer "In11.Cu")
		(net "M_F_DQ<2>")
	)
	(segment
		(start 214.62111 -107.009692)
		(end 211.245958 -110.384844)
		(width 0.14224)
		(layer "In11.Cu")
		(net "M_F_DQ<2>")
	)
	(segment
		(start 204.543152 -129.833878)
		(end 204.416152 -129.960878)
		(width 0.14224)
		(layer "In11.Cu")
		(net "M_F_DQ<2>")
	)
	(segment
		(start 211.245958 -110.384844)
		(end 210.93303 -110.384844)
		(width 0.14224)
		(layer "In11.Cu")
		(net "M_F_DQ<2>")
	)
	(segment
		(start 210.93303 -110.384844)
		(end 210.070954 -109.522768)
		(width 0.14224)
		(layer "In11.Cu")
		(net "M_F_DQ<2>")
	)
	(segment
		(start 205.252574 -115.971574)
		(end 205.252574 -116.378228)
		(width 0.14224)
		(layer "In11.Cu")
		(net "M_F_DQ<2>")
	)
	(segment
		(start 227.9396 -91.6686)
		(end 220.9038 -98.7044)
		(width 0.14224)
		(layer "In11.Cu")
		(net "M_F_DQ<2>")
	)
	(segment
		(start 210.569556 -108.998766)
		(end 210.85683 -109.28604)
		(width 0.14224)
		(layer "In11.Cu")
		(net "M_F_DQ<2>")
	)
	(segment
		(start 204.47 -141.652752)
		(end 204.47 -143.4338)
		(width 0.14224)
		(layer "In11.Cu")
		(net "M_F_DQ<2>")
	)
	(segment
		(start 204.6478 -136.3218)
		(end 204.6478 -136.652)
		(width 0.14224)
		(layer "In11.Cu")
		(net "M_F_DQ<2>")
	)
	(segment
		(start 204.390752 -136.064752)
		(end 204.6478 -136.3218)
		(width 0.14224)
		(layer "In11.Cu")
		(net "M_F_DQ<2>")
	)
	(segment
		(start 204.568552 -148.485352)
		(end 204.568552 -148.972778)
		(width 0.14224)
		(layer "In11.Cu")
		(net "M_F_DQ<2>")
	)
	(segment
		(start 204.6224 -145.860516)
		(end 204.6224 -146.4056)
		(width 0.14224)
		(layer "In11.Cu")
		(net "M_F_DQ<2>")
	)
	(segment
		(start 210.070954 -109.522768)
		(end 209.808826 -109.522768)
		(width 0.14224)
		(layer "In11.Cu")
		(net "M_F_DQ<2>")
	)
	(segment
		(start 204.6478 -139.471654)
		(end 204.416152 -139.703302)
		(width 0.14224)
		(layer "In11.Cu")
		(net "M_F_DQ<2>")
	)
	(segment
		(start 204.47 -136.8298)
		(end 204.47 -138.8618)
		(width 0.14224)
		(layer "In11.Cu")
		(net "M_F_DQ<2>")
	)
	(segment
		(start 232.699306 -91.156536)
		(end 232.425748 -91.430094)
		(width 0.0889)
		(layer "In11.Cu")
		(net "M_F_DQ<2>")
	)
	(segment
		(start 214.046308 -106.43489)
		(end 214.333836 -106.43489)
		(width 0.14224)
		(layer "In11.Cu")
		(net "M_F_DQ<2>")
	)
	(segment
		(start 204.6986 -131.470654)
		(end 204.6986 -134.405116)
		(width 0.14224)
		(layer "In11.Cu")
		(net "M_F_DQ<2>")
	)
	(segment
		(start 239.922558 -87.194136)
		(end 239.886998 -87.194136)
		(width 0.0889)
		(layer "In11.Cu")
		(net "M_F_DQ<2>")
	)
	(segment
		(start 220.9038 -100.726748)
		(end 215.788748 -105.8418)
		(width 0.14224)
		(layer "In11.Cu")
		(net "M_F_DQ<2>")
	)
	(segment
		(start 203.616814 -151.247348)
		(end 203.616814 -153.834846)
		(width 0.14224)
		(layer "In11.Cu")
		(net "M_F_DQ<2>")
	)
	(segment
		(start 204.4065 -129.1463)
		(end 204.543152 -129.282952)
		(width 0.14224)
		(layer "In11.Cu")
		(net "M_F_DQ<2>")
	)
	(segment
		(start 220.9038 -98.7044)
		(end 220.9038 -100.726748)
		(width 0.14224)
		(layer "In11.Cu")
		(net "M_F_DQ<2>")
	)
	(segment
		(start 204.6986 -116.932202)
		(end 204.6986 -126.746)
		(width 0.14224)
		(layer "In11.Cu")
		(net "M_F_DQ<2>")
	)
	(segment
		(start 238.202724 -88.184736)
		(end 238.169958 -88.184736)
		(width 0.0889)
		(layer "In11.Cu")
		(net "M_F_DQ<2>")
	)
	(segment
		(start 210.85683 -109.28604)
		(end 211.195158 -109.28604)
		(width 0.14224)
		(layer "In11.Cu")
		(net "M_F_DQ<2>")
	)
	(segment
		(start 205.252574 -116.378228)
		(end 204.6986 -116.932202)
		(width 0.14224)
		(layer "In11.Cu")
		(net "M_F_DQ<2>")
	)
	(segment
		(start 204.543152 -129.282952)
		(end 204.543152 -129.833878)
		(width 0.14224)
		(layer "In11.Cu")
		(net "M_F_DQ<2>")
	)
	(segment
		(start 204.6986 -126.746)
		(end 204.4065 -127.0381)
		(width 0.14224)
		(layer "In11.Cu")
		(net "M_F_DQ<2>")
	)
	(segment
		(start 231.667812 -91.430094)
		(end 231.230424 -91.867482)
		(width 0.0889)
		(layer "In11.Cu")
		(net "M_F_DQ<2>")
	)
	(segment
		(start 236.485684 -89.175336)
		(end 236.452918 -89.175336)
		(width 0.0889)
		(layer "In11.Cu")
		(net "M_F_DQ<2>")
	)
	(segment
		(start 204.6986 -114.632994)
		(end 204.6986 -115.4176)
		(width 0.14224)
		(layer "In11.Cu")
		(net "M_F_DQ<2>")
	)
	(segment
		(start 204.47 -143.4338)
		(end 204.6732 -143.637)
		(width 0.14224)
		(layer "In11.Cu")
		(net "M_F_DQ<2>")
	)
	(segment
		(start 204.6732 -141.449552)
		(end 204.47 -141.652752)
		(width 0.14224)
		(layer "In11.Cu")
		(net "M_F_DQ<2>")
	)
	(segment
		(start 239.057434 -87.68969)
		(end 239.024668 -87.68969)
		(width 0.0889)
		(layer "In11.Cu")
		(net "M_F_DQ<2>")
	)
	(segment
		(start 204.339952 -145.578068)
		(end 204.6224 -145.860516)
		(width 0.14224)
		(layer "In11.Cu")
		(net "M_F_DQ<2>")
	)
	(segment
		(start 204.4192 -148.336)
		(end 204.568552 -148.485352)
		(width 0.14224)
		(layer "In11.Cu")
		(net "M_F_DQ<2>")
	)
	(segment
		(start 214.333836 -106.43489)
		(end 214.62111 -106.722164)
		(width 0.14224)
		(layer "In11.Cu")
		(net "M_F_DQ<2>")
	)
	(segment
		(start 204.6732 -141.071854)
		(end 204.6732 -141.449552)
		(width 0.14224)
		(layer "In11.Cu")
		(net "M_F_DQ<2>")
	)
	(arc
		(start 237.675928 -88.480138)
		(mid 237.534245 -88.623942)
		(end 237.340394 -88.68029)
		(width 0.0889)
		(layer "In11.Cu")
		(net "M_F_DQ<2>")
	)
	(arc
		(start 237.307628 -88.68029)
		(mid 237.024411 -88.764571)
		(end 236.817408 -88.975438)
		(width 0.0889)
		(layer "In11.Cu")
		(net "M_F_DQ<2>")
	)
	(arc
		(start 233.850434 -90.66276)
		(mid 233.580523 -90.751912)
		(end 233.383328 -90.956638)
		(width 0.0889)
		(layer "In11.Cu")
		(net "M_F_DQ<2>")
	)
	(arc
		(start 236.817408 -88.975438)
		(mid 236.677329 -89.118174)
		(end 236.485684 -89.175336)
		(width 0.0889)
		(layer "In11.Cu")
		(net "M_F_DQ<2>")
	)
	(arc
		(start 238.169958 -88.184736)
		(mid 237.884534 -88.268203)
		(end 237.675928 -88.480138)
		(width 0.0889)
		(layer "In11.Cu")
		(net "M_F_DQ<2>")
	)
	(arc
		(start 234.735878 -90.165936)
		(mid 234.450454 -90.249403)
		(end 234.241848 -90.461338)
		(width 0.0889)
		(layer "In11.Cu")
		(net "M_F_DQ<2>")
	)
	(arc
		(start 234.241848 -90.461338)
		(mid 234.114097 -90.596439)
		(end 233.93908 -90.659204)
		(width 0.0889)
		(layer "In11.Cu")
		(net "M_F_DQ<2>")
	)
	(arc
		(start 240.416588 -87.489538)
		(mid 240.20798 -87.277606)
		(end 239.922558 -87.194136)
		(width 0.0889)
		(layer "In11.Cu")
		(net "M_F_DQ<2>")
	)
	(arc
		(start 235.590588 -89.67089)
		(mid 235.307371 -89.755171)
		(end 235.100368 -89.966038)
		(width 0.0889)
		(layer "In11.Cu")
		(net "M_F_DQ<2>")
	)
	(arc
		(start 239.886998 -87.194136)
		(mid 239.601574 -87.277603)
		(end 239.392968 -87.489538)
		(width 0.0889)
		(layer "In11.Cu")
		(net "M_F_DQ<2>")
	)
	(arc
		(start 235.958888 -89.470738)
		(mid 235.817205 -89.614542)
		(end 235.623354 -89.67089)
		(width 0.0889)
		(layer "In11.Cu")
		(net "M_F_DQ<2>")
	)
	(arc
		(start 233.93908 -90.659204)
		(mid 233.894819 -90.662525)
		(end 233.850434 -90.66276)
		(width 0.0889)
		(layer "In11.Cu")
		(net "M_F_DQ<2>")
	)
	(arc
		(start 239.024668 -87.68969)
		(mid 238.741451 -87.773971)
		(end 238.534448 -87.984838)
		(width 0.0889)
		(layer "In11.Cu")
		(net "M_F_DQ<2>")
	)
	(arc
		(start 239.392968 -87.489538)
		(mid 239.251285 -87.633342)
		(end 239.057434 -87.68969)
		(width 0.0889)
		(layer "In11.Cu")
		(net "M_F_DQ<2>")
	)
	(arc
		(start 236.452918 -89.175336)
		(mid 236.167494 -89.258803)
		(end 235.958888 -89.470738)
		(width 0.0889)
		(layer "In11.Cu")
		(net "M_F_DQ<2>")
	)
	(arc
		(start 238.534448 -87.984838)
		(mid 238.394369 -88.127574)
		(end 238.202724 -88.184736)
		(width 0.0889)
		(layer "In11.Cu")
		(net "M_F_DQ<2>")
	)
	(arc
		(start 233.383328 -90.956638)
		(mid 233.243249 -91.099374)
		(end 233.051604 -91.156536)
		(width 0.0889)
		(layer "In11.Cu")
		(net "M_F_DQ<2>")
	)
	(arc
		(start 235.100368 -89.966038)
		(mid 234.960289 -90.108774)
		(end 234.768644 -90.165936)
		(width 0.0889)
		(layer "In11.Cu")
		(net "M_F_DQ<2>")
	)
	(segment
		(start 224.449894 -152.278842)
		(end 224.449894 -153.542746)
		(width 0.1651)
		(layer "F.Cu")
		(net "M_F_DQ<29>")
	)
	(segment
		(start 249.061224 -86.794086)
		(end 248.489724 -86.794086)
		(width 0.1651)
		(layer "F.Cu")
		(net "M_F_DQ<29>")
	)
	(segment
		(start 224.450402 -152.273)
		(end 224.449894 -152.278842)
		(width 0.1651)
		(layer "F.Cu")
		(net "M_F_DQ<29>")
	)
	(via
		(at 225.223578 -149.533356)
		(size 0.508)
		(drill 0.254)
		(layers "F.Cu" "B.Cu")
		(net "M_F_DQ<29>")
	)
	(via
		(at 248.489724 -86.794086)
		(size 0.508)
		(drill 0.254)
		(layers "F.Cu" "B.Cu")
		(net "M_F_DQ<29>")
	)
	(via
		(at 224.449894 -153.542746)
		(size 0.508)
		(drill 0.254)
		(layers "F.Cu" "B.Cu")
		(net "M_F_DQ<29>")
	)
	(segment
		(start 225.300286 -147.478496)
		(end 225.299778 -147.478496)
		(width 0.1651)
		(layer "B.Cu")
		(net "M_F_DQ<29>")
	)
	(segment
		(start 225.299778 -147.478496)
		(end 225.299778 -149.457156)
		(width 0.1651)
		(layer "B.Cu")
		(net "M_F_DQ<29>")
	)
	(segment
		(start 225.299778 -149.457156)
		(end 225.223578 -149.533356)
		(width 0.1651)
		(layer "B.Cu")
		(net "M_F_DQ<29>")
	)
	(segment
		(start 225.3234 -127.583946)
		(end 225.8314 -128.091946)
		(width 0.14224)
		(layer "In11.Cu")
		(net "M_F_DQ<29>")
	)
	(segment
		(start 248.143014 -88.575388)
		(end 248.138188 -88.584024)
		(width 0.0889)
		(layer "In11.Cu")
		(net "M_F_DQ<29>")
	)
	(segment
		(start 226.744022 -122.41911)
		(end 226.829366 -122.504454)
		(width 0.14224)
		(layer "In11.Cu")
		(net "M_F_DQ<29>")
	)
	(segment
		(start 225.633534 -134.157466)
		(end 225.633534 -134.617968)
		(width 0.14224)
		(layer "In11.Cu")
		(net "M_F_DQ<29>")
	)
	(segment
		(start 228.77272 -120.780048)
		(end 228.553772 -120.780048)
		(width 0.14224)
		(layer "In11.Cu")
		(net "M_F_DQ<29>")
	)
	(segment
		(start 225.8314 -128.091946)
		(end 225.8314 -129.159)
		(width 0.14224)
		(layer "In11.Cu")
		(net "M_F_DQ<29>")
	)
	(segment
		(start 226.473512 -123.079256)
		(end 226.254564 -123.079256)
		(width 0.14224)
		(layer "In11.Cu")
		(net "M_F_DQ<29>")
	)
	(segment
		(start 226.744022 -122.200162)
		(end 226.744022 -122.41911)
		(width 0.14224)
		(layer "In11.Cu")
		(net "M_F_DQ<29>")
	)
	(segment
		(start 243.231416 -100.673154)
		(end 242.723416 -101.181154)
		(width 0.0889)
		(layer "In11.Cu")
		(net "M_F_DQ<29>")
	)
	(segment
		(start 224.611184 -151.755856)
		(end 224.849182 -151.993854)
		(width 0.14224)
		(layer "In11.Cu")
		(net "M_F_DQ<29>")
	)
	(segment
		(start 248.160286 -87.55507)
		(end 248.138188 -87.593424)
		(width 0.0889)
		(layer "In11.Cu")
		(net "M_F_DQ<29>")
	)
	(segment
		(start 225.697034 -135.938768)
		(end 225.552 -136.083802)
		(width 0.14224)
		(layer "In11.Cu")
		(net "M_F_DQ<29>")
	)
	(segment
		(start 225.552 -129.838704)
		(end 225.697034 -129.983738)
		(width 0.14224)
		(layer "In11.Cu")
		(net "M_F_DQ<29>")
	)
	(segment
		(start 228.468428 -120.694704)
		(end 228.24948 -120.694704)
		(width 0.14224)
		(layer "In11.Cu")
		(net "M_F_DQ<29>")
	)
	(segment
		(start 239.2934 -112.776)
		(end 234.244134 -117.825266)
		(width 0.14224)
		(layer "In11.Cu")
		(net "M_F_DQ<29>")
	)
	(segment
		(start 226.829366 -122.504454)
		(end 226.829366 -122.723402)
		(width 0.14224)
		(layer "In11.Cu")
		(net "M_F_DQ<29>")
	)
	(segment
		(start 247.648984 -91.84259)
		(end 247.616218 -91.84259)
		(width 0.0889)
		(layer "In11.Cu")
		(net "M_F_DQ<29>")
	)
	(segment
		(start 242.723416 -102.362762)
		(end 242.946682 -102.586028)
		(width 0.0889)
		(layer "In11.Cu")
		(net "M_F_DQ<29>")
	)
	(segment
		(start 230.278178 -119.055642)
		(end 230.278178 -119.27459)
		(width 0.14224)
		(layer "In11.Cu")
		(net "M_F_DQ<29>")
	)
	(segment
		(start 230.548688 -118.395496)
		(end 230.192834 -118.75135)
		(width 0.14224)
		(layer "In11.Cu")
		(net "M_F_DQ<29>")
	)
	(segment
		(start 225.4504 -143.5862)
		(end 225.4504 -144.0688)
		(width 0.14224)
		(layer "In11.Cu")
		(net "M_F_DQ<29>")
	)
	(segment
		(start 224.899982 -151.129746)
		(end 224.611184 -151.418544)
		(width 0.14224)
		(layer "In11.Cu")
		(net "M_F_DQ<29>")
	)
	(segment
		(start 229.128574 -120.424194)
		(end 228.77272 -120.780048)
		(width 0.14224)
		(layer "In11.Cu")
		(net "M_F_DQ<29>")
	)
	(segment
		(start 225.6028 -125.5268)
		(end 225.3234 -125.8062)
		(width 0.14224)
		(layer "In11.Cu")
		(net "M_F_DQ<29>")
	)
	(segment
		(start 225.7298 -141.731746)
		(end 225.7298 -143.3068)
		(width 0.14224)
		(layer "In11.Cu")
		(net "M_F_DQ<29>")
	)
	(segment
		(start 243.974366 -98.60788)
		(end 243.974366 -99.142804)
		(width 0.0889)
		(layer "In11.Cu")
		(net "M_F_DQ<29>")
	)
	(segment
		(start 225.697034 -139.667234)
		(end 225.697034 -140.971778)
		(width 0.14224)
		(layer "In11.Cu")
		(net "M_F_DQ<29>")
	)
	(segment
		(start 229.04323 -119.900954)
		(end 229.04323 -120.119902)
		(width 0.14224)
		(layer "In11.Cu")
		(net "M_F_DQ<29>")
	)
	(segment
		(start 247.279668 -93.424502)
		(end 247.284494 -93.433138)
		(width 0.0889)
		(layer "In11.Cu")
		(net "M_F_DQ<29>")
	)
	(segment
		(start 225.7298 -146.354546)
		(end 225.7298 -148.3106)
		(width 0.14224)
		(layer "In11.Cu")
		(net "M_F_DQ<29>")
	)
	(segment
		(start 224.849182 -152.348946)
		(end 224.611184 -152.586944)
		(width 0.14224)
		(layer "In11.Cu")
		(net "M_F_DQ<29>")
	)
	(segment
		(start 225.950272 -122.993912)
		(end 225.6028 -123.341384)
		(width 0.14224)
		(layer "In11.Cu")
		(net "M_F_DQ<29>")
	)
	(segment
		(start 230.767636 -118.395496)
		(end 230.548688 -118.395496)
		(width 0.14224)
		(layer "In11.Cu")
		(net "M_F_DQ<29>")
	)
	(segment
		(start 248.149364 -89.55532)
		(end 248.143014 -89.565988)
		(width 0.0889)
		(layer "In11.Cu")
		(net "M_F_DQ<29>")
	)
	(segment
		(start 227.97897 -121.35485)
		(end 227.97897 -121.573798)
		(width 0.14224)
		(layer "In11.Cu")
		(net "M_F_DQ<29>")
	)
	(segment
		(start 242.723416 -101.181154)
		(end 242.723416 -102.362762)
		(width 0.0889)
		(layer "In11.Cu")
		(net "M_F_DQ<29>")
	)
	(segment
		(start 246.794274 -95.309436)
		(end 246.761508 -95.309436)
		(width 0.0889)
		(layer "In11.Cu")
		(net "M_F_DQ<29>")
	)
	(segment
		(start 229.922324 -119.630444)
		(end 229.703376 -119.630444)
		(width 0.14224)
		(layer "In11.Cu")
		(net "M_F_DQ<29>")
	)
	(segment
		(start 225.608134 -149.1488)
		(end 225.223578 -149.533356)
		(width 0.14224)
		(layer "In11.Cu")
		(net "M_F_DQ<29>")
	)
	(segment
		(start 225.697034 -129.983738)
		(end 225.697034 -131.223766)
		(width 0.14224)
		(layer "In11.Cu")
		(net "M_F_DQ<29>")
	)
	(segment
		(start 225.552 -136.083802)
		(end 225.552 -136.443466)
		(width 0.14224)
		(layer "In11.Cu")
		(net "M_F_DQ<29>")
	)
	(segment
		(start 243.974366 -99.142804)
		(end 243.231416 -99.885754)
		(width 0.0889)
		(layer "In11.Cu")
		(net "M_F_DQ<29>")
	)
	(segment
		(start 225.697034 -134.681468)
		(end 225.697034 -135.938768)
		(width 0.14224)
		(layer "In11.Cu")
		(net "M_F_DQ<29>")
	)
	(segment
		(start 227.318824 -121.844308)
		(end 227.099876 -121.844308)
		(width 0.14224)
		(layer "In11.Cu")
		(net "M_F_DQ<29>")
	)
	(segment
		(start 224.611184 -151.418544)
		(end 224.611184 -151.755856)
		(width 0.14224)
		(layer "In11.Cu")
		(net "M_F_DQ<29>")
	)
	(segment
		(start 227.099876 -121.844308)
		(end 226.744022 -122.200162)
		(width 0.14224)
		(layer "In11.Cu")
		(net "M_F_DQ<29>")
	)
	(segment
		(start 224.722182 -153.542746)
		(end 224.449894 -153.542746)
		(width 0.14224)
		(layer "In11.Cu")
		(net "M_F_DQ<29>")
	)
	(segment
		(start 230.192834 -118.970298)
		(end 230.278178 -119.055642)
		(width 0.14224)
		(layer "In11.Cu")
		(net "M_F_DQ<29>")
	)
	(segment
		(start 225.543364 -131.89331)
		(end 225.7298 -132.079746)
		(width 0.14224)
		(layer "In11.Cu")
		(net "M_F_DQ<29>")
	)
	(segment
		(start 247.279668 -92.433902)
		(end 247.284494 -92.442538)
		(width 0.0889)
		(layer "In11.Cu")
		(net "M_F_DQ<29>")
	)
	(segment
		(start 248.143014 -90.556588)
		(end 248.138188 -90.565224)
		(width 0.0889)
		(layer "In11.Cu")
		(net "M_F_DQ<29>")
	)
	(segment
		(start 225.7298 -134.0612)
		(end 225.633534 -134.157466)
		(width 0.14224)
		(layer "In11.Cu")
		(net "M_F_DQ<29>")
	)
	(segment
		(start 225.4758 -138.9634)
		(end 225.4758 -139.446)
		(width 0.14224)
		(layer "In11.Cu")
		(net "M_F_DQ<29>")
	)
	(segment
		(start 225.760534 -144.378934)
		(end 225.760534 -145.56232)
		(width 0.14224)
		(layer "In11.Cu")
		(net "M_F_DQ<29>")
	)
	(segment
		(start 224.874582 -153.162254)
		(end 224.874582 -153.390346)
		(width 0.14224)
		(layer "In11.Cu")
		(net "M_F_DQ<29>")
	)
	(segment
		(start 229.618032 -119.5451)
		(end 229.399084 -119.5451)
		(width 0.14224)
		(layer "In11.Cu")
		(net "M_F_DQ<29>")
	)
	(segment
		(start 225.552 -129.4384)
		(end 225.552 -129.838704)
		(width 0.14224)
		(layer "In11.Cu")
		(net "M_F_DQ<29>")
	)
	(segment
		(start 248.489724 -86.794086)
		(end 248.160286 -87.55507)
		(width 0.0889)
		(layer "In11.Cu")
		(net "M_F_DQ<29>")
	)
	(segment
		(start 228.24948 -120.694704)
		(end 227.893626 -121.050558)
		(width 0.14224)
		(layer "In11.Cu")
		(net "M_F_DQ<29>")
	)
	(segment
		(start 230.85298 -118.48084)
		(end 230.767636 -118.395496)
		(width 0.14224)
		(layer "In11.Cu")
		(net "M_F_DQ<29>")
	)
	(segment
		(start 225.543364 -131.377436)
		(end 225.543364 -131.89331)
		(width 0.14224)
		(layer "In11.Cu")
		(net "M_F_DQ<29>")
	)
	(segment
		(start 225.7298 -148.3106)
		(end 225.608134 -148.432266)
		(width 0.14224)
		(layer "In11.Cu")
		(net "M_F_DQ<29>")
	)
	(segment
		(start 225.5266 -146.151346)
		(end 225.7298 -146.354546)
		(width 0.14224)
		(layer "In11.Cu")
		(net "M_F_DQ<29>")
	)
	(segment
		(start 225.223578 -149.533356)
		(end 225.201226 -149.533356)
		(width 0.14224)
		(layer "In11.Cu")
		(net "M_F_DQ<29>")
	)
	(segment
		(start 225.608134 -148.432266)
		(end 225.608134 -149.1488)
		(width 0.14224)
		(layer "In11.Cu")
		(net "M_F_DQ<29>")
	)
	(segment
		(start 225.4758 -139.446)
		(end 225.697034 -139.667234)
		(width 0.14224)
		(layer "In11.Cu")
		(net "M_F_DQ<29>")
	)
	(segment
		(start 229.128574 -120.205246)
		(end 229.128574 -120.424194)
		(width 0.14224)
		(layer "In11.Cu")
		(net "M_F_DQ<29>")
	)
	(segment
		(start 227.893626 -121.050558)
		(end 227.893626 -121.269506)
		(width 0.14224)
		(layer "In11.Cu")
		(net "M_F_DQ<29>")
	)
	(segment
		(start 227.623116 -121.929652)
		(end 227.404168 -121.929652)
		(width 0.14224)
		(layer "In11.Cu")
		(net "M_F_DQ<29>")
	)
	(segment
		(start 228.553772 -120.780048)
		(end 228.468428 -120.694704)
		(width 0.14224)
		(layer "In11.Cu")
		(net "M_F_DQ<29>")
	)
	(segment
		(start 248.149364 -90.54592)
		(end 248.143014 -90.556588)
		(width 0.0889)
		(layer "In11.Cu")
		(net "M_F_DQ<29>")
	)
	(segment
		(start 224.611184 -152.898856)
		(end 224.874582 -153.162254)
		(width 0.14224)
		(layer "In11.Cu")
		(net "M_F_DQ<29>")
	)
	(segment
		(start 245.931944 -96.79559)
		(end 245.899178 -96.79559)
		(width 0.0889)
		(layer "In11.Cu")
		(net "M_F_DQ<29>")
	)
	(segment
		(start 224.611184 -152.586944)
		(end 224.611184 -152.898856)
		(width 0.14224)
		(layer "In11.Cu")
		(net "M_F_DQ<29>")
	)
	(segment
		(start 243.845588 -98.377502)
		(end 243.974366 -98.60788)
		(width 0.0889)
		(layer "In11.Cu")
		(net "M_F_DQ<29>")
	)
	(segment
		(start 229.04323 -120.119902)
		(end 229.128574 -120.205246)
		(width 0.14224)
		(layer "In11.Cu")
		(net "M_F_DQ<29>")
	)
	(segment
		(start 247.284494 -92.442538)
		(end 247.290844 -92.453206)
		(width 0.0889)
		(layer "In11.Cu")
		(net "M_F_DQ<29>")
	)
	(segment
		(start 226.829366 -122.723402)
		(end 226.473512 -123.079256)
		(width 0.14224)
		(layer "In11.Cu")
		(net "M_F_DQ<29>")
	)
	(segment
		(start 225.5266 -141.528546)
		(end 225.7298 -141.731746)
		(width 0.14224)
		(layer "In11.Cu")
		(net "M_F_DQ<29>")
	)
	(segment
		(start 248.143014 -89.565988)
		(end 248.138188 -89.574624)
		(width 0.0889)
		(layer "In11.Cu")
		(net "M_F_DQ<29>")
	)
	(segment
		(start 227.97897 -121.573798)
		(end 227.623116 -121.929652)
		(width 0.14224)
		(layer "In11.Cu")
		(net "M_F_DQ<29>")
	)
	(segment
		(start 225.7298 -136.621266)
		(end 225.7298 -138.7094)
		(width 0.14224)
		(layer "In11.Cu")
		(net "M_F_DQ<29>")
	)
	(segment
		(start 225.5266 -145.796254)
		(end 225.5266 -146.151346)
		(width 0.14224)
		(layer "In11.Cu")
		(net "M_F_DQ<29>")
	)
	(segment
		(start 227.404168 -121.929652)
		(end 227.318824 -121.844308)
		(width 0.14224)
		(layer "In11.Cu")
		(net "M_F_DQ<29>")
	)
	(segment
		(start 229.703376 -119.630444)
		(end 229.618032 -119.5451)
		(width 0.14224)
		(layer "In11.Cu")
		(net "M_F_DQ<29>")
	)
	(segment
		(start 225.552 -136.443466)
		(end 225.7298 -136.621266)
		(width 0.14224)
		(layer "In11.Cu")
		(net "M_F_DQ<29>")
	)
	(segment
		(start 227.893626 -121.269506)
		(end 227.97897 -121.35485)
		(width 0.14224)
		(layer "In11.Cu")
		(net "M_F_DQ<29>")
	)
	(segment
		(start 229.399084 -119.5451)
		(end 229.04323 -119.900954)
		(width 0.14224)
		(layer "In11.Cu")
		(net "M_F_DQ<29>")
	)
	(segment
		(start 225.7298 -143.3068)
		(end 225.4504 -143.5862)
		(width 0.14224)
		(layer "In11.Cu")
		(net "M_F_DQ<29>")
	)
	(segment
		(start 224.772982 -150.5204)
		(end 224.899982 -150.6474)
		(width 0.14224)
		(layer "In11.Cu")
		(net "M_F_DQ<29>")
	)
	(segment
		(start 225.7298 -132.079746)
		(end 225.7298 -134.0612)
		(width 0.14224)
		(layer "In11.Cu")
		(net "M_F_DQ<29>")
	)
	(segment
		(start 225.6028 -123.341384)
		(end 225.6028 -125.5268)
		(width 0.14224)
		(layer "In11.Cu")
		(net "M_F_DQ<29>")
	)
	(segment
		(start 225.201226 -149.533356)
		(end 224.772982 -149.9616)
		(width 0.14224)
		(layer "In11.Cu")
		(net "M_F_DQ<29>")
	)
	(segment
		(start 224.899982 -150.6474)
		(end 224.899982 -151.129746)
		(width 0.14224)
		(layer "In11.Cu")
		(net "M_F_DQ<29>")
	)
	(segment
		(start 224.772982 -149.9616)
		(end 224.772982 -150.5204)
		(width 0.14224)
		(layer "In11.Cu")
		(net "M_F_DQ<29>")
	)
	(segment
		(start 247.290844 -94.01302)
		(end 247.284494 -94.023688)
		(width 0.0889)
		(layer "In11.Cu")
		(net "M_F_DQ<29>")
	)
	(segment
		(start 225.697034 -131.223766)
		(end 225.543364 -131.377436)
		(width 0.14224)
		(layer "In11.Cu")
		(net "M_F_DQ<29>")
	)
	(segment
		(start 225.5266 -141.142212)
		(end 225.5266 -141.528546)
		(width 0.14224)
		(layer "In11.Cu")
		(net "M_F_DQ<29>")
	)
	(segment
		(start 226.254564 -123.079256)
		(end 226.16922 -122.993912)
		(width 0.14224)
		(layer "In11.Cu")
		(net "M_F_DQ<29>")
	)
	(segment
		(start 226.16922 -122.993912)
		(end 225.950272 -122.993912)
		(width 0.14224)
		(layer "In11.Cu")
		(net "M_F_DQ<29>")
	)
	(segment
		(start 230.278178 -119.27459)
		(end 229.922324 -119.630444)
		(width 0.14224)
		(layer "In11.Cu")
		(net "M_F_DQ<29>")
	)
	(segment
		(start 231.727502 -117.825266)
		(end 231.071928 -118.48084)
		(width 0.14224)
		(layer "In11.Cu")
		(net "M_F_DQ<29>")
	)
	(segment
		(start 225.760534 -145.56232)
		(end 225.5266 -145.796254)
		(width 0.14224)
		(layer "In11.Cu")
		(net "M_F_DQ<29>")
	)
	(segment
		(start 230.192834 -118.75135)
		(end 230.192834 -118.970298)
		(width 0.14224)
		(layer "In11.Cu")
		(net "M_F_DQ<29>")
	)
	(segment
		(start 242.946682 -102.586028)
		(end 242.946682 -104.296718)
		(width 0.14224)
		(layer "In11.Cu")
		(net "M_F_DQ<29>")
	)
	(segment
		(start 239.2934 -107.95)
		(end 239.2934 -112.776)
		(width 0.14224)
		(layer "In11.Cu")
		(net "M_F_DQ<29>")
	)
	(segment
		(start 225.3234 -125.8062)
		(end 225.3234 -127.583946)
		(width 0.14224)
		(layer "In11.Cu")
		(net "M_F_DQ<29>")
	)
	(segment
		(start 225.7298 -138.7094)
		(end 225.4758 -138.9634)
		(width 0.14224)
		(layer "In11.Cu")
		(net "M_F_DQ<29>")
	)
	(segment
		(start 231.071928 -118.48084)
		(end 230.85298 -118.48084)
		(width 0.14224)
		(layer "In11.Cu")
		(net "M_F_DQ<29>")
	)
	(segment
		(start 248.149364 -88.56472)
		(end 248.143014 -88.575388)
		(width 0.0889)
		(layer "In11.Cu")
		(net "M_F_DQ<29>")
	)
	(segment
		(start 243.231416 -99.885754)
		(end 243.231416 -100.673154)
		(width 0.0889)
		(layer "In11.Cu")
		(net "M_F_DQ<29>")
	)
	(segment
		(start 225.8314 -129.159)
		(end 225.552 -129.4384)
		(width 0.14224)
		(layer "In11.Cu")
		(net "M_F_DQ<29>")
	)
	(segment
		(start 242.946682 -104.296718)
		(end 239.2934 -107.95)
		(width 0.14224)
		(layer "In11.Cu")
		(net "M_F_DQ<29>")
	)
	(segment
		(start 245.077234 -97.290636)
		(end 245.044468 -97.290636)
		(width 0.0889)
		(layer "In11.Cu")
		(net "M_F_DQ<29>")
	)
	(segment
		(start 224.849182 -151.993854)
		(end 224.849182 -152.348946)
		(width 0.14224)
		(layer "In11.Cu")
		(net "M_F_DQ<29>")
	)
	(segment
		(start 224.874582 -153.390346)
		(end 224.722182 -153.542746)
		(width 0.14224)
		(layer "In11.Cu")
		(net "M_F_DQ<29>")
	)
	(segment
		(start 234.244134 -117.825266)
		(end 231.727502 -117.825266)
		(width 0.14224)
		(layer "In11.Cu")
		(net "M_F_DQ<29>")
	)
	(segment
		(start 244.214904 -97.78619)
		(end 244.182138 -97.78619)
		(width 0.0889)
		(layer "In11.Cu")
		(net "M_F_DQ<29>")
	)
	(segment
		(start 225.697034 -140.971778)
		(end 225.5266 -141.142212)
		(width 0.14224)
		(layer "In11.Cu")
		(net "M_F_DQ<29>")
	)
	(segment
		(start 225.633534 -134.617968)
		(end 225.697034 -134.681468)
		(width 0.14224)
		(layer "In11.Cu")
		(net "M_F_DQ<29>")
	)
	(segment
		(start 225.4504 -144.0688)
		(end 225.760534 -144.378934)
		(width 0.14224)
		(layer "In11.Cu")
		(net "M_F_DQ<29>")
	)
	(arc
		(start 247.616218 -91.84259)
		(mid 247.2833 -92.044581)
		(end 247.279668 -92.433902)
		(width 0.0889)
		(layer "In11.Cu")
		(net "M_F_DQ<29>")
	)
	(arc
		(start 248.143014 -88.975438)
		(mid 248.222236 -89.264556)
		(end 248.149364 -89.55532)
		(width 0.0889)
		(layer "In11.Cu")
		(net "M_F_DQ<29>")
	)
	(arc
		(start 246.761508 -95.309436)
		(mid 246.423339 -95.514234)
		(end 246.425974 -95.909638)
		(width 0.0889)
		(layer "In11.Cu")
		(net "M_F_DQ<29>")
	)
	(arc
		(start 246.425974 -95.909638)
		(mid 246.430303 -96.49281)
		(end 245.931944 -96.79559)
		(width 0.0889)
		(layer "In11.Cu")
		(net "M_F_DQ<29>")
	)
	(arc
		(start 247.284494 -94.423484)
		(mid 247.289748 -95.004992)
		(end 246.794274 -95.309436)
		(width 0.0889)
		(layer "In11.Cu")
		(net "M_F_DQ<29>")
	)
	(arc
		(start 248.143014 -90.956638)
		(mid 248.147343 -91.53981)
		(end 247.648984 -91.84259)
		(width 0.0889)
		(layer "In11.Cu")
		(net "M_F_DQ<29>")
	)
	(arc
		(start 248.138188 -89.574624)
		(mid 248.089433 -89.770976)
		(end 248.143014 -89.966038)
		(width 0.0889)
		(layer "In11.Cu")
		(net "M_F_DQ<29>")
	)
	(arc
		(start 247.284494 -93.433138)
		(mid 247.363716 -93.722256)
		(end 247.290844 -94.01302)
		(width 0.0889)
		(layer "In11.Cu")
		(net "M_F_DQ<29>")
	)
	(arc
		(start 244.708934 -97.490788)
		(mid 244.500326 -97.70272)
		(end 244.214904 -97.78619)
		(width 0.0889)
		(layer "In11.Cu")
		(net "M_F_DQ<29>")
	)
	(arc
		(start 248.143014 -87.984838)
		(mid 248.222236 -88.273956)
		(end 248.149364 -88.56472)
		(width 0.0889)
		(layer "In11.Cu")
		(net "M_F_DQ<29>")
	)
	(arc
		(start 247.284494 -94.023688)
		(mid 247.230995 -94.223586)
		(end 247.284494 -94.423484)
		(width 0.0889)
		(layer "In11.Cu")
		(net "M_F_DQ<29>")
	)
	(arc
		(start 248.138188 -88.584024)
		(mid 248.089433 -88.780376)
		(end 248.143014 -88.975438)
		(width 0.0889)
		(layer "In11.Cu")
		(net "M_F_DQ<29>")
	)
	(arc
		(start 245.567454 -96.995488)
		(mid 245.36045 -97.206352)
		(end 245.077234 -97.290636)
		(width 0.0889)
		(layer "In11.Cu")
		(net "M_F_DQ<29>")
	)
	(arc
		(start 248.143014 -89.966038)
		(mid 248.222236 -90.255156)
		(end 248.149364 -90.54592)
		(width 0.0889)
		(layer "In11.Cu")
		(net "M_F_DQ<29>")
	)
	(arc
		(start 245.044468 -97.290636)
		(mid 244.850618 -97.346986)
		(end 244.708934 -97.490788)
		(width 0.0889)
		(layer "In11.Cu")
		(net "M_F_DQ<29>")
	)
	(arc
		(start 248.138188 -87.593424)
		(mid 248.089433 -87.789776)
		(end 248.143014 -87.984838)
		(width 0.0889)
		(layer "In11.Cu")
		(net "M_F_DQ<29>")
	)
	(arc
		(start 244.182138 -97.78619)
		(mid 243.84922 -97.988181)
		(end 243.845588 -98.377502)
		(width 0.0889)
		(layer "In11.Cu")
		(net "M_F_DQ<29>")
	)
	(arc
		(start 247.290844 -92.453206)
		(mid 247.363642 -92.743969)
		(end 247.284494 -93.033088)
		(width 0.0889)
		(layer "In11.Cu")
		(net "M_F_DQ<29>")
	)
	(arc
		(start 245.899178 -96.79559)
		(mid 245.707536 -96.852756)
		(end 245.567454 -96.995488)
		(width 0.0889)
		(layer "In11.Cu")
		(net "M_F_DQ<29>")
	)
	(arc
		(start 247.284494 -93.033088)
		(mid 247.231024 -93.228151)
		(end 247.279668 -93.424502)
		(width 0.0889)
		(layer "In11.Cu")
		(net "M_F_DQ<29>")
	)
	(arc
		(start 248.138188 -90.565224)
		(mid 248.089433 -90.761576)
		(end 248.143014 -90.956638)
		(width 0.0889)
		(layer "In11.Cu")
		(net "M_F_DQ<29>")
	)
	(segment
		(start 225.299778 -156.87294)
		(end 225.300286 -156.87294)
		(width 0.1651)
		(layer "F.Cu")
		(net "M_F_DQ<28>")
	)
	(segment
		(start 249.061224 -85.803486)
		(end 248.489724 -85.803486)
		(width 0.0889)
		(layer "F.Cu")
		(net "M_F_DQ<28>")
	)
	(segment
		(start 225.299778 -155.547568)
		(end 225.299778 -156.87294)
		(width 0.1651)
		(layer "F.Cu")
		(net "M_F_DQ<28>")
	)
	(segment
		(start 225.201734 -155.0162)
		(end 225.299778 -155.547568)
		(width 0.1651)
		(layer "F.Cu")
		(net "M_F_DQ<28>")
	)
	(via
		(at 224.449894 -150.814278)
		(size 0.508)
		(drill 0.254)
		(layers "F.Cu" "B.Cu")
		(net "M_F_DQ<28>")
	)
	(via
		(at 248.489724 -85.803486)
		(size 0.508)
		(drill 0.254)
		(layers "F.Cu" "B.Cu")
		(net "M_F_DQ<28>")
	)
	(via
		(at 225.201734 -155.0162)
		(size 0.508)
		(drill 0.254)
		(layers "F.Cu" "B.Cu")
		(net "M_F_DQ<28>")
	)
	(segment
		(start 224.450402 -152.078436)
		(end 224.449894 -152.078182)
		(width 0.1651)
		(layer "B.Cu")
		(net "M_F_DQ<28>")
	)
	(segment
		(start 224.449894 -152.078182)
		(end 224.449894 -150.814278)
		(width 0.1651)
		(layer "B.Cu")
		(net "M_F_DQ<28>")
	)
	(segment
		(start 247.98274 -87.480902)
		(end 247.977914 -87.489538)
		(width 0.0889)
		(layer "In11.Cu")
		(net "M_F_DQ<28>")
	)
	(segment
		(start 224.681542 -145.527776)
		(end 224.935034 -145.781268)
		(width 0.14224)
		(layer "In11.Cu")
		(net "M_F_DQ<28>")
	)
	(segment
		(start 246.78767 -95.118936)
		(end 246.754904 -95.118936)
		(width 0.0889)
		(layer "In11.Cu")
		(net "M_F_DQ<28>")
	)
	(segment
		(start 238.6584 -107.6706)
		(end 238.6584 -112.4966)
		(width 0.14224)
		(layer "In11.Cu")
		(net "M_F_DQ<28>")
	)
	(segment
		(start 242.311682 -102.586028)
		(end 242.311682 -104.017318)
		(width 0.14224)
		(layer "In11.Cu")
		(net "M_F_DQ<28>")
	)
	(segment
		(start 224.732596 -127.552196)
		(end 224.79 -127.6096)
		(width 0.14224)
		(layer "In11.Cu")
		(net "M_F_DQ<28>")
	)
	(segment
		(start 247.977914 -86.498938)
		(end 247.971564 -86.509606)
		(width 0.0889)
		(layer "In11.Cu")
		(net "M_F_DQ<28>")
	)
	(segment
		(start 242.533424 -101.102414)
		(end 242.533424 -102.364286)
		(width 0.0889)
		(layer "In11.Cu")
		(net "M_F_DQ<28>")
	)
	(segment
		(start 224.8662 -134.0866)
		(end 225.014282 -134.234682)
		(width 0.14224)
		(layer "In11.Cu")
		(net "M_F_DQ<28>")
	)
	(segment
		(start 224.719134 -129.996438)
		(end 224.719134 -131.180078)
		(width 0.14224)
		(layer "In11.Cu")
		(net "M_F_DQ<28>")
	)
	(segment
		(start 224.79 -129.1844)
		(end 224.9932 -129.3876)
		(width 0.14224)
		(layer "In11.Cu")
		(net "M_F_DQ<28>")
	)
	(segment
		(start 247.977914 -89.470738)
		(end 247.971564 -89.481406)
		(width 0.0889)
		(layer "In11.Cu")
		(net "M_F_DQ<28>")
	)
	(segment
		(start 247.119394 -94.518988)
		(end 247.12422 -94.527624)
		(width 0.0889)
		(layer "In11.Cu")
		(net "M_F_DQ<28>")
	)
	(segment
		(start 224.9932 -129.722372)
		(end 224.719134 -129.996438)
		(width 0.14224)
		(layer "In11.Cu")
		(net "M_F_DQ<28>")
	)
	(segment
		(start 224.8662 -148.3106)
		(end 224.935034 -148.379434)
		(width 0.14224)
		(layer "In11.Cu")
		(net "M_F_DQ<28>")
	)
	(segment
		(start 224.986596 -123.2789)
		(end 224.986596 -124.060204)
		(width 0.14224)
		(layer "In11.Cu")
		(net "M_F_DQ<28>")
	)
	(segment
		(start 224.935034 -148.960078)
		(end 224.134934 -149.760178)
		(width 0.14224)
		(layer "In11.Cu")
		(net "M_F_DQ<28>")
	)
	(segment
		(start 225.014282 -134.234682)
		(end 225.014282 -134.420864)
		(width 0.14224)
		(layer "In11.Cu")
		(net "M_F_DQ<28>")
	)
	(segment
		(start 224.8662 -131.983734)
		(end 224.8662 -134.0866)
		(width 0.14224)
		(layer "In11.Cu")
		(net "M_F_DQ<28>")
	)
	(segment
		(start 224.719134 -134.716012)
		(end 224.719134 -135.951468)
		(width 0.14224)
		(layer "In11.Cu")
		(net "M_F_DQ<28>")
	)
	(segment
		(start 247.119394 -92.537788)
		(end 247.12422 -92.546424)
		(width 0.0889)
		(layer "In11.Cu")
		(net "M_F_DQ<28>")
	)
	(segment
		(start 224.947734 -144.063466)
		(end 224.681542 -144.329658)
		(width 0.14224)
		(layer "In11.Cu")
		(net "M_F_DQ<28>")
	)
	(segment
		(start 224.9932 -129.3876)
		(end 224.9932 -129.722372)
		(width 0.14224)
		(layer "In11.Cu")
		(net "M_F_DQ<28>")
	)
	(segment
		(start 230.959406 -117.30609)
		(end 224.986596 -123.2789)
		(width 0.14224)
		(layer "In11.Cu")
		(net "M_F_DQ<28>")
	)
	(segment
		(start 224.719134 -139.587478)
		(end 224.719134 -140.772134)
		(width 0.14224)
		(layer "In11.Cu")
		(net "M_F_DQ<28>")
	)
	(segment
		(start 225.063304 -141.116304)
		(end 225.063304 -141.50975)
		(width 0.14224)
		(layer "In11.Cu")
		(net "M_F_DQ<28>")
	)
	(segment
		(start 224.79 -127.6096)
		(end 224.79 -129.1844)
		(width 0.14224)
		(layer "In11.Cu")
		(net "M_F_DQ<28>")
	)
	(segment
		(start 224.935034 -145.781268)
		(end 224.935034 -146.234912)
		(width 0.14224)
		(layer "In11.Cu")
		(net "M_F_DQ<28>")
	)
	(segment
		(start 224.8662 -146.303746)
		(end 224.8662 -148.3106)
		(width 0.14224)
		(layer "In11.Cu")
		(net "M_F_DQ<28>")
	)
	(segment
		(start 224.8662 -143.6116)
		(end 224.947734 -143.693134)
		(width 0.14224)
		(layer "In11.Cu")
		(net "M_F_DQ<28>")
	)
	(segment
		(start 224.681542 -144.329658)
		(end 224.681542 -145.527776)
		(width 0.14224)
		(layer "In11.Cu")
		(net "M_F_DQ<28>")
	)
	(segment
		(start 248.489724 -85.803486)
		(end 247.994678 -86.469474)
		(width 0.0889)
		(layer "In11.Cu")
		(net "M_F_DQ<28>")
	)
	(segment
		(start 224.947734 -131.408678)
		(end 224.947734 -131.9022)
		(width 0.14224)
		(layer "In11.Cu")
		(net "M_F_DQ<28>")
	)
	(segment
		(start 224.986596 -124.060204)
		(end 224.732596 -124.314204)
		(width 0.14224)
		(layer "In11.Cu")
		(net "M_F_DQ<28>")
	)
	(segment
		(start 243.041424 -99.807014)
		(end 243.041424 -100.594414)
		(width 0.0889)
		(layer "In11.Cu")
		(net "M_F_DQ<28>")
	)
	(segment
		(start 224.449894 -150.814278)
		(end 224.016824 -151.247348)
		(width 0.14224)
		(layer "In11.Cu")
		(net "M_F_DQ<28>")
	)
	(segment
		(start 224.016824 -153.83129)
		(end 225.201734 -155.0162)
		(width 0.14224)
		(layer "In11.Cu")
		(net "M_F_DQ<28>")
	)
	(segment
		(start 243.784374 -98.657918)
		(end 243.784374 -99.064064)
		(width 0.0889)
		(layer "In11.Cu")
		(net "M_F_DQ<28>")
	)
	(segment
		(start 247.119394 -93.928438)
		(end 247.113044 -93.939106)
		(width 0.0889)
		(layer "In11.Cu")
		(net "M_F_DQ<28>")
	)
	(segment
		(start 247.113044 -92.52712)
		(end 247.119394 -92.537788)
		(width 0.0889)
		(layer "In11.Cu")
		(net "M_F_DQ<28>")
	)
	(segment
		(start 224.8662 -136.708134)
		(end 224.8662 -138.8364)
		(width 0.14224)
		(layer "In11.Cu")
		(net "M_F_DQ<28>")
	)
	(segment
		(start 224.719134 -140.772134)
		(end 225.063304 -141.116304)
		(width 0.14224)
		(layer "In11.Cu")
		(net "M_F_DQ<28>")
	)
	(segment
		(start 244.2083 -97.59569)
		(end 244.175534 -97.59569)
		(width 0.0889)
		(layer "In11.Cu")
		(net "M_F_DQ<28>")
	)
	(segment
		(start 247.98274 -89.462102)
		(end 247.977914 -89.470738)
		(width 0.0889)
		(layer "In11.Cu")
		(net "M_F_DQ<28>")
	)
	(segment
		(start 224.134934 -149.760178)
		(end 224.134934 -150.499318)
		(width 0.14224)
		(layer "In11.Cu")
		(net "M_F_DQ<28>")
	)
	(segment
		(start 243.784374 -99.064064)
		(end 243.041424 -99.807014)
		(width 0.0889)
		(layer "In11.Cu")
		(net "M_F_DQ<28>")
	)
	(segment
		(start 224.732596 -124.314204)
		(end 224.732596 -127.552196)
		(width 0.14224)
		(layer "In11.Cu")
		(net "M_F_DQ<28>")
	)
	(segment
		(start 224.947734 -143.693134)
		(end 224.947734 -144.063466)
		(width 0.14224)
		(layer "In11.Cu")
		(net "M_F_DQ<28>")
	)
	(segment
		(start 243.041424 -100.594414)
		(end 242.533424 -101.102414)
		(width 0.0889)
		(layer "In11.Cu")
		(net "M_F_DQ<28>")
	)
	(segment
		(start 224.973134 -136.6012)
		(end 224.8662 -136.708134)
		(width 0.14224)
		(layer "In11.Cu")
		(net "M_F_DQ<28>")
	)
	(segment
		(start 224.719134 -131.180078)
		(end 224.947734 -131.408678)
		(width 0.14224)
		(layer "In11.Cu")
		(net "M_F_DQ<28>")
	)
	(segment
		(start 247.977914 -88.480138)
		(end 247.971564 -88.490806)
		(width 0.0889)
		(layer "In11.Cu")
		(net "M_F_DQ<28>")
	)
	(segment
		(start 243.678964 -98.47072)
		(end 243.784374 -98.657918)
		(width 0.0889)
		(layer "In11.Cu")
		(net "M_F_DQ<28>")
	)
	(segment
		(start 247.977914 -90.461338)
		(end 247.971564 -90.472006)
		(width 0.0889)
		(layer "In11.Cu")
		(net "M_F_DQ<28>")
	)
	(segment
		(start 224.973134 -138.943334)
		(end 224.973134 -139.333478)
		(width 0.14224)
		(layer "In11.Cu")
		(net "M_F_DQ<28>")
	)
	(segment
		(start 247.98274 -88.471502)
		(end 247.977914 -88.480138)
		(width 0.0889)
		(layer "In11.Cu")
		(net "M_F_DQ<28>")
	)
	(segment
		(start 247.98274 -90.452702)
		(end 247.977914 -90.461338)
		(width 0.0889)
		(layer "In11.Cu")
		(net "M_F_DQ<28>")
	)
	(segment
		(start 238.6584 -112.4966)
		(end 233.84891 -117.30609)
		(width 0.14224)
		(layer "In11.Cu")
		(net "M_F_DQ<28>")
	)
	(segment
		(start 242.311682 -104.017318)
		(end 238.6584 -107.6706)
		(width 0.14224)
		(layer "In11.Cu")
		(net "M_F_DQ<28>")
	)
	(segment
		(start 225.063304 -141.50975)
		(end 224.8662 -141.706854)
		(width 0.14224)
		(layer "In11.Cu")
		(net "M_F_DQ<28>")
	)
	(segment
		(start 224.935034 -148.379434)
		(end 224.935034 -148.960078)
		(width 0.14224)
		(layer "In11.Cu")
		(net "M_F_DQ<28>")
	)
	(segment
		(start 224.935034 -146.234912)
		(end 224.8662 -146.303746)
		(width 0.14224)
		(layer "In11.Cu")
		(net "M_F_DQ<28>")
	)
	(segment
		(start 225.014282 -134.420864)
		(end 224.719134 -134.716012)
		(width 0.14224)
		(layer "In11.Cu")
		(net "M_F_DQ<28>")
	)
	(segment
		(start 224.719134 -135.951468)
		(end 224.973134 -136.205468)
		(width 0.14224)
		(layer "In11.Cu")
		(net "M_F_DQ<28>")
	)
	(segment
		(start 233.84891 -117.30609)
		(end 230.959406 -117.30609)
		(width 0.14224)
		(layer "In11.Cu")
		(net "M_F_DQ<28>")
	)
	(segment
		(start 247.977914 -87.489538)
		(end 247.971564 -87.500206)
		(width 0.0889)
		(layer "In11.Cu")
		(net "M_F_DQ<28>")
	)
	(segment
		(start 224.973134 -136.205468)
		(end 224.973134 -136.6012)
		(width 0.14224)
		(layer "In11.Cu")
		(net "M_F_DQ<28>")
	)
	(segment
		(start 224.947734 -131.9022)
		(end 224.8662 -131.983734)
		(width 0.14224)
		(layer "In11.Cu")
		(net "M_F_DQ<28>")
	)
	(segment
		(start 247.994678 -86.469474)
		(end 247.977914 -86.498938)
		(width 0.0889)
		(layer "In11.Cu")
		(net "M_F_DQ<28>")
	)
	(segment
		(start 224.8662 -138.8364)
		(end 224.973134 -138.943334)
		(width 0.14224)
		(layer "In11.Cu")
		(net "M_F_DQ<28>")
	)
	(segment
		(start 242.533424 -102.364286)
		(end 242.311682 -102.586028)
		(width 0.0889)
		(layer "In11.Cu")
		(net "M_F_DQ<28>")
	)
	(segment
		(start 224.134934 -150.499318)
		(end 224.449894 -150.814278)
		(width 0.14224)
		(layer "In11.Cu")
		(net "M_F_DQ<28>")
	)
	(segment
		(start 224.016824 -151.247348)
		(end 224.016824 -153.83129)
		(width 0.14224)
		(layer "In11.Cu")
		(net "M_F_DQ<28>")
	)
	(segment
		(start 224.8662 -141.706854)
		(end 224.8662 -143.6116)
		(width 0.14224)
		(layer "In11.Cu")
		(net "M_F_DQ<28>")
	)
	(segment
		(start 247.64238 -91.65209)
		(end 247.609614 -91.65209)
		(width 0.0889)
		(layer "In11.Cu")
		(net "M_F_DQ<28>")
	)
	(segment
		(start 224.973134 -139.333478)
		(end 224.719134 -139.587478)
		(width 0.14224)
		(layer "In11.Cu")
		(net "M_F_DQ<28>")
	)
	(segment
		(start 245.92534 -96.60509)
		(end 245.892574 -96.60509)
		(width 0.0889)
		(layer "In11.Cu")
		(net "M_F_DQ<28>")
	)
	(segment
		(start 245.07063 -97.100136)
		(end 245.037864 -97.100136)
		(width 0.0889)
		(layer "In11.Cu")
		(net "M_F_DQ<28>")
	)
	(arc
		(start 247.977914 -90.061288)
		(mid 248.031384 -90.256351)
		(end 247.98274 -90.452702)
		(width 0.0889)
		(layer "In11.Cu")
		(net "M_F_DQ<28>")
	)
	(arc
		(start 247.971564 -88.490806)
		(mid 247.898766 -88.781569)
		(end 247.977914 -89.070688)
		(width 0.0889)
		(layer "In11.Cu")
		(net "M_F_DQ<28>")
	)
	(arc
		(start 246.260874 -96.004888)
		(mid 246.263622 -96.400355)
		(end 245.92534 -96.60509)
		(width 0.0889)
		(layer "In11.Cu")
		(net "M_F_DQ<28>")
	)
	(arc
		(start 247.113044 -93.939106)
		(mid 247.040246 -94.229869)
		(end 247.119394 -94.518988)
		(width 0.0889)
		(layer "In11.Cu")
		(net "M_F_DQ<28>")
	)
	(arc
		(start 247.971564 -90.472006)
		(mid 247.898766 -90.762769)
		(end 247.977914 -91.051888)
		(width 0.0889)
		(layer "In11.Cu")
		(net "M_F_DQ<28>")
	)
	(arc
		(start 247.971564 -86.509606)
		(mid 247.898766 -86.800369)
		(end 247.977914 -87.089488)
		(width 0.0889)
		(layer "In11.Cu")
		(net "M_F_DQ<28>")
	)
	(arc
		(start 247.977914 -89.070688)
		(mid 248.031384 -89.265751)
		(end 247.98274 -89.462102)
		(width 0.0889)
		(layer "In11.Cu")
		(net "M_F_DQ<28>")
	)
	(arc
		(start 247.609614 -91.65209)
		(mid 247.117224 -91.951023)
		(end 247.113044 -92.52712)
		(width 0.0889)
		(layer "In11.Cu")
		(net "M_F_DQ<28>")
	)
	(arc
		(start 247.977914 -91.051888)
		(mid 247.980662 -91.447355)
		(end 247.64238 -91.65209)
		(width 0.0889)
		(layer "In11.Cu")
		(net "M_F_DQ<28>")
	)
	(arc
		(start 247.12422 -92.546424)
		(mid 247.172975 -92.742776)
		(end 247.119394 -92.937838)
		(width 0.0889)
		(layer "In11.Cu")
		(net "M_F_DQ<28>")
	)
	(arc
		(start 245.402354 -96.900238)
		(mid 245.262275 -97.042974)
		(end 245.07063 -97.100136)
		(width 0.0889)
		(layer "In11.Cu")
		(net "M_F_DQ<28>")
	)
	(arc
		(start 246.754904 -95.118936)
		(mid 246.256653 -95.421776)
		(end 246.260874 -96.004888)
		(width 0.0889)
		(layer "In11.Cu")
		(net "M_F_DQ<28>")
	)
	(arc
		(start 247.971564 -87.500206)
		(mid 247.898766 -87.790969)
		(end 247.977914 -88.080088)
		(width 0.0889)
		(layer "In11.Cu")
		(net "M_F_DQ<28>")
	)
	(arc
		(start 245.892574 -96.60509)
		(mid 245.609357 -96.689371)
		(end 245.402354 -96.900238)
		(width 0.0889)
		(layer "In11.Cu")
		(net "M_F_DQ<28>")
	)
	(arc
		(start 247.119394 -92.937838)
		(mid 247.040263 -93.23324)
		(end 247.119394 -93.528642)
		(width 0.0889)
		(layer "In11.Cu")
		(net "M_F_DQ<28>")
	)
	(arc
		(start 247.977914 -88.080088)
		(mid 248.031384 -88.275151)
		(end 247.98274 -88.471502)
		(width 0.0889)
		(layer "In11.Cu")
		(net "M_F_DQ<28>")
	)
	(arc
		(start 247.971564 -89.481406)
		(mid 247.898766 -89.772169)
		(end 247.977914 -90.061288)
		(width 0.0889)
		(layer "In11.Cu")
		(net "M_F_DQ<28>")
	)
	(arc
		(start 244.175534 -97.59569)
		(mid 243.683144 -97.894623)
		(end 243.678964 -98.47072)
		(width 0.0889)
		(layer "In11.Cu")
		(net "M_F_DQ<28>")
	)
	(arc
		(start 247.12422 -94.527624)
		(mid 247.120473 -94.91688)
		(end 246.78767 -95.118936)
		(width 0.0889)
		(layer "In11.Cu")
		(net "M_F_DQ<28>")
	)
	(arc
		(start 244.543834 -97.395538)
		(mid 244.402151 -97.539342)
		(end 244.2083 -97.59569)
		(width 0.0889)
		(layer "In11.Cu")
		(net "M_F_DQ<28>")
	)
	(arc
		(start 247.119394 -93.528642)
		(mid 247.172893 -93.72854)
		(end 247.119394 -93.928438)
		(width 0.0889)
		(layer "In11.Cu")
		(net "M_F_DQ<28>")
	)
	(arc
		(start 247.977914 -87.089488)
		(mid 248.031384 -87.284551)
		(end 247.98274 -87.480902)
		(width 0.0889)
		(layer "In11.Cu")
		(net "M_F_DQ<28>")
	)
	(arc
		(start 245.037864 -97.100136)
		(mid 244.75244 -97.183603)
		(end 244.543834 -97.395538)
		(width 0.0889)
		(layer "In11.Cu")
		(net "M_F_DQ<28>")
	)
	(segment
		(start 252.495304 -86.794086)
		(end 251.923804 -86.794086)
		(width 0.1651)
		(layer "F.Cu")
		(net "M_F_DQ<27>")
	)
	(segment
		(start 232.100374 -152.273)
		(end 232.099866 -152.278842)
		(width 0.1651)
		(layer "F.Cu")
		(net "M_F_DQ<27>")
	)
	(segment
		(start 232.099866 -152.278842)
		(end 232.099866 -153.542746)
		(width 0.1651)
		(layer "F.Cu")
		(net "M_F_DQ<27>")
	)
	(via
		(at 232.94975 -149.533356)
		(size 0.508)
		(drill 0.254)
		(layers "F.Cu" "B.Cu")
		(net "M_F_DQ<27>")
	)
	(via
		(at 251.923804 -86.794086)
		(size 0.508)
		(drill 0.254)
		(layers "F.Cu" "B.Cu")
		(net "M_F_DQ<27>")
	)
	(via
		(at 232.099866 -153.542746)
		(size 0.508)
		(drill 0.254)
		(layers "F.Cu" "B.Cu")
		(net "M_F_DQ<27>")
	)
	(segment
		(start 232.94975 -147.478496)
		(end 232.94975 -149.533356)
		(width 0.1651)
		(layer "B.Cu")
		(net "M_F_DQ<27>")
	)
	(segment
		(start 232.950512 -147.478496)
		(end 232.94975 -147.478496)
		(width 0.1651)
		(layer "B.Cu")
		(net "M_F_DQ<27>")
	)
	(segment
		(start 243.3828 -119.492776)
		(end 243.243862 -119.353584)
		(width 0.14224)
		(layer "In11.Cu")
		(net "M_F_DQ<27>")
	)
	(segment
		(start 243.818664 -118.778782)
		(end 244.018562 -118.978934)
		(width 0.14224)
		(layer "In11.Cu")
		(net "M_F_DQ<27>")
	)
	(segment
		(start 232.549954 -153.04135)
		(end 232.549954 -153.364946)
		(width 0.14224)
		(layer "In11.Cu")
		(net "M_F_DQ<27>")
	)
	(segment
		(start 233.392472 -139.584938)
		(end 233.392472 -141.021562)
		(width 0.1016)
		(layer "In11.Cu")
		(net "M_F_DQ<27>")
	)
	(segment
		(start 233.3752 -146.222466)
		(end 233.3752 -148.2598)
		(width 0.14224)
		(layer "In11.Cu")
		(net "M_F_DQ<27>")
	)
	(segment
		(start 233.304334 -129.960878)
		(end 233.456734 -130.113278)
		(width 0.14224)
		(layer "In11.Cu")
		(net "M_F_DQ<27>")
	)
	(segment
		(start 233.456734 -131.268978)
		(end 233.317034 -131.408678)
		(width 0.14224)
		(layer "In11.Cu")
		(net "M_F_DQ<27>")
	)
	(segment
		(start 232.499154 -150.391368)
		(end 232.543604 -150.435818)
		(width 0.14224)
		(layer "In11.Cu")
		(net "M_F_DQ<27>")
	)
	(segment
		(start 252.435614 -87.489538)
		(end 252.441964 -87.500206)
		(width 0.0889)
		(layer "In11.Cu")
		(net "M_F_DQ<27>")
	)
	(segment
		(start 252.41885 -87.460074)
		(end 252.435614 -87.489538)
		(width 0.0889)
		(layer "In11.Cu")
		(net "M_F_DQ<27>")
	)
	(segment
		(start 241.879374 -121.438416)
		(end 241.879374 -121.65711)
		(width 0.14224)
		(layer "In11.Cu")
		(net "M_F_DQ<27>")
	)
	(segment
		(start 242.98275 -120.242584)
		(end 242.98275 -120.461278)
		(width 0.14224)
		(layer "In11.Cu")
		(net "M_F_DQ<27>")
	)
	(segment
		(start 233.482134 -136.036812)
		(end 233.304334 -136.214612)
		(width 0.14224)
		(layer "In11.Cu")
		(net "M_F_DQ<27>")
	)
	(segment
		(start 232.261156 -152.752552)
		(end 232.549954 -153.04135)
		(width 0.14224)
		(layer "In11.Cu")
		(net "M_F_DQ<27>")
	)
	(segment
		(start 241.304318 -122.012964)
		(end 240.944654 -121.652792)
		(width 0.14224)
		(layer "In11.Cu")
		(net "M_F_DQ<27>")
	)
	(segment
		(start 239.576102 -122.802396)
		(end 238.274098 -124.1044)
		(width 0.14224)
		(layer "In11.Cu")
		(net "M_F_DQ<27>")
	)
	(segment
		(start 239.79505 -122.802396)
		(end 239.576102 -122.802396)
		(width 0.14224)
		(layer "In11.Cu")
		(net "M_F_DQ<27>")
	)
	(segment
		(start 240.725706 -121.652792)
		(end 240.369852 -122.008646)
		(width 0.14224)
		(layer "In11.Cu")
		(net "M_F_DQ<27>")
	)
	(segment
		(start 245.1862 -110.3122)
		(end 245.1862 -117.192298)
		(width 0.14224)
		(layer "In11.Cu")
		(net "M_F_DQ<27>")
	)
	(segment
		(start 251.923804 -86.794086)
		(end 252.41885 -87.460074)
		(width 0.0889)
		(layer "In11.Cu")
		(net "M_F_DQ<27>")
	)
	(segment
		(start 233.3752 -136.621266)
		(end 233.3752 -138.7348)
		(width 0.14224)
		(layer "In11.Cu")
		(net "M_F_DQ<27>")
	)
	(segment
		(start 249.137424 -103.086154)
		(end 249.137424 -106.360976)
		(width 0.14224)
		(layer "In11.Cu")
		(net "M_F_DQ<27>")
	)
	(segment
		(start 242.66906 -119.928386)
		(end 242.98275 -120.242584)
		(width 0.14224)
		(layer "In11.Cu")
		(net "M_F_DQ<27>")
	)
	(segment
		(start 234.1372 -124.587)
		(end 234.1372 -124.968)
		(width 0.14224)
		(layer "In11.Cu")
		(net "M_F_DQ<27>")
	)
	(segment
		(start 232.518204 -152.2222)
		(end 232.261156 -152.479248)
		(width 0.14224)
		(layer "In11.Cu")
		(net "M_F_DQ<27>")
	)
	(segment
		(start 233.3752 -134.0866)
		(end 233.317034 -134.144766)
		(width 0.14224)
		(layer "In11.Cu")
		(net "M_F_DQ<27>")
	)
	(segment
		(start 243.44376 -119.553736)
		(end 243.3828 -119.492776)
		(width 0.14224)
		(layer "In11.Cu")
		(net "M_F_DQ<27>")
	)
	(segment
		(start 250.936506 -98.600768)
		(end 248.895616 -100.641658)
		(width 0.0889)
		(layer "In11.Cu")
		(net "M_F_DQ<27>")
	)
	(segment
		(start 248.895616 -102.844346)
		(end 249.137424 -103.086154)
		(width 0.0889)
		(layer "In11.Cu")
		(net "M_F_DQ<27>")
	)
	(segment
		(start 233.392472 -141.021562)
		(end 233.317034 -141.097)
		(width 0.1016)
		(layer "In11.Cu")
		(net "M_F_DQ<27>")
	)
	(segment
		(start 244.018562 -118.978934)
		(end 244.018562 -119.197882)
		(width 0.14224)
		(layer "In11.Cu")
		(net "M_F_DQ<27>")
	)
	(segment
		(start 232.261156 -152.479248)
		(end 232.261156 -152.752552)
		(width 0.14224)
		(layer "In11.Cu")
		(net "M_F_DQ<27>")
	)
	(segment
		(start 242.98275 -120.461278)
		(end 242.626896 -120.817132)
		(width 0.14224)
		(layer "In11.Cu")
		(net "M_F_DQ<27>")
	)
	(segment
		(start 251.941584 -94.31909)
		(end 251.90577 -94.31909)
		(width 0.0889)
		(layer "In11.Cu")
		(net "M_F_DQ<27>")
	)
	(segment
		(start 233.304334 -136.5504)
		(end 233.3752 -136.621266)
		(width 0.14224)
		(layer "In11.Cu")
		(net "M_F_DQ<27>")
	)
	(segment
		(start 241.519456 -121.07799)
		(end 241.879374 -121.438416)
		(width 0.14224)
		(layer "In11.Cu")
		(net "M_F_DQ<27>")
	)
	(segment
		(start 232.543604 -151.1046)
		(end 232.261156 -151.387048)
		(width 0.14224)
		(layer "In11.Cu")
		(net "M_F_DQ<27>")
	)
	(segment
		(start 232.543604 -150.435818)
		(end 232.543604 -151.1046)
		(width 0.14224)
		(layer "In11.Cu")
		(net "M_F_DQ<27>")
	)
	(segment
		(start 240.736882 -122.595132)
		(end 240.736882 -122.813826)
		(width 0.14224)
		(layer "In11.Cu")
		(net "M_F_DQ<27>")
	)
	(segment
		(start 244.018562 -119.197882)
		(end 243.662708 -119.553736)
		(width 0.14224)
		(layer "In11.Cu")
		(net "M_F_DQ<27>")
	)
	(segment
		(start 240.161826 -123.16968)
		(end 239.79505 -122.802396)
		(width 0.14224)
		(layer "In11.Cu")
		(net "M_F_DQ<27>")
	)
	(segment
		(start 233.278934 -146.1262)
		(end 233.3752 -146.222466)
		(width 0.14224)
		(layer "In11.Cu")
		(net "M_F_DQ<27>")
	)
	(segment
		(start 240.944654 -121.652792)
		(end 240.725706 -121.652792)
		(width 0.14224)
		(layer "In11.Cu")
		(net "M_F_DQ<27>")
	)
	(segment
		(start 252.430788 -91.443302)
		(end 252.435614 -91.451938)
		(width 0.0889)
		(layer "In11.Cu")
		(net "M_F_DQ<27>")
	)
	(segment
		(start 233.317034 -134.573264)
		(end 233.482134 -134.738364)
		(width 0.14224)
		(layer "In11.Cu")
		(net "M_F_DQ<27>")
	)
	(segment
		(start 233.304334 -139.4968)
		(end 233.392472 -139.584938)
		(width 0.1016)
		(layer "In11.Cu")
		(net "M_F_DQ<27>")
	)
	(segment
		(start 232.518204 -151.9174)
		(end 232.518204 -152.2222)
		(width 0.14224)
		(layer "In11.Cu")
		(net "M_F_DQ<27>")
	)
	(segment
		(start 251.577094 -96.500188)
		(end 251.572268 -96.508824)
		(width 0.0889)
		(layer "In11.Cu")
		(net "M_F_DQ<27>")
	)
	(segment
		(start 233.426 -125.6792)
		(end 233.426 -126.219204)
		(width 0.14224)
		(layer "In11.Cu")
		(net "M_F_DQ<27>")
	)
	(segment
		(start 233.278934 -149.21738)
		(end 232.94975 -149.546564)
		(width 0.14224)
		(layer "In11.Cu")
		(net "M_F_DQ<27>")
	)
	(segment
		(start 233.317034 -134.144766)
		(end 233.317034 -134.573264)
		(width 0.14224)
		(layer "In11.Cu")
		(net "M_F_DQ<27>")
	)
	(segment
		(start 240.369852 -122.008646)
		(end 240.369852 -122.227594)
		(width 0.14224)
		(layer "In11.Cu")
		(net "M_F_DQ<27>")
	)
	(segment
		(start 232.499154 -149.9616)
		(end 232.499154 -150.391368)
		(width 0.14224)
		(layer "In11.Cu")
		(net "M_F_DQ<27>")
	)
	(segment
		(start 233.532934 -144.398238)
		(end 233.532934 -145.587212)
		(width 0.14224)
		(layer "In11.Cu")
		(net "M_F_DQ<27>")
	)
	(segment
		(start 233.304334 -136.214612)
		(end 233.304334 -136.5504)
		(width 0.14224)
		(layer "In11.Cu")
		(net "M_F_DQ<27>")
	)
	(segment
		(start 233.278934 -148.356066)
		(end 233.278934 -149.21738)
		(width 0.14224)
		(layer "In11.Cu")
		(net "M_F_DQ<27>")
	)
	(segment
		(start 248.895616 -100.641658)
		(end 248.895616 -102.844346)
		(width 0.0889)
		(layer "In11.Cu")
		(net "M_F_DQ<27>")
	)
	(segment
		(start 252.430788 -88.471502)
		(end 252.435614 -88.480138)
		(width 0.0889)
		(layer "In11.Cu")
		(net "M_F_DQ<27>")
	)
	(segment
		(start 242.626896 -120.817132)
		(end 242.407694 -120.817132)
		(width 0.14224)
		(layer "In11.Cu")
		(net "M_F_DQ<27>")
	)
	(segment
		(start 252.435614 -91.451938)
		(end 252.441964 -91.462606)
		(width 0.0889)
		(layer "In11.Cu")
		(net "M_F_DQ<27>")
	)
	(segment
		(start 233.317034 -144.182338)
		(end 233.532934 -144.398238)
		(width 0.14224)
		(layer "In11.Cu")
		(net "M_F_DQ<27>")
	)
	(segment
		(start 233.482134 -134.738364)
		(end 233.482134 -136.036812)
		(width 0.14224)
		(layer "In11.Cu")
		(net "M_F_DQ<27>")
	)
	(segment
		(start 233.3752 -131.909566)
		(end 233.3752 -134.0866)
		(width 0.14224)
		(layer "In11.Cu")
		(net "M_F_DQ<27>")
	)
	(segment
		(start 249.137424 -106.360976)
		(end 245.1862 -110.3122)
		(width 0.14224)
		(layer "In11.Cu")
		(net "M_F_DQ<27>")
	)
	(segment
		(start 233.317034 -131.8514)
		(end 233.3752 -131.909566)
		(width 0.14224)
		(layer "In11.Cu")
		(net "M_F_DQ<27>")
	)
	(segment
		(start 251.583444 -95.49892)
		(end 251.577094 -95.509588)
		(width 0.0889)
		(layer "In11.Cu")
		(net "M_F_DQ<27>")
	)
	(segment
		(start 233.3752 -148.2598)
		(end 233.278934 -148.356066)
		(width 0.14224)
		(layer "In11.Cu")
		(net "M_F_DQ<27>")
	)
	(segment
		(start 233.317034 -141.097)
		(end 233.317034 -144.182338)
		(width 0.14224)
		(layer "In11.Cu")
		(net "M_F_DQ<27>")
	)
	(segment
		(start 243.024914 -119.353584)
		(end 242.66906 -119.709438)
		(width 0.14224)
		(layer "In11.Cu")
		(net "M_F_DQ<27>")
	)
	(segment
		(start 241.519456 -120.859042)
		(end 241.519456 -121.07799)
		(width 0.14224)
		(layer "In11.Cu")
		(net "M_F_DQ<27>")
	)
	(segment
		(start 233.278934 -145.841212)
		(end 233.278934 -146.1262)
		(width 0.14224)
		(layer "In11.Cu")
		(net "M_F_DQ<27>")
	)
	(segment
		(start 233.456734 -130.113278)
		(end 233.456734 -131.268978)
		(width 0.14224)
		(layer "In11.Cu")
		(net "M_F_DQ<27>")
	)
	(segment
		(start 242.407694 -120.817132)
		(end 242.094258 -120.503188)
		(width 0.14224)
		(layer "In11.Cu")
		(net "M_F_DQ<27>")
	)
	(segment
		(start 232.261156 -151.660352)
		(end 232.518204 -151.9174)
		(width 0.14224)
		(layer "In11.Cu")
		(net "M_F_DQ<27>")
	)
	(segment
		(start 243.243862 -119.353584)
		(end 243.024914 -119.353584)
		(width 0.14224)
		(layer "In11.Cu")
		(net "M_F_DQ<27>")
	)
	(segment
		(start 242.66906 -119.709438)
		(end 242.66906 -119.928386)
		(width 0.14224)
		(layer "In11.Cu")
		(net "M_F_DQ<27>")
	)
	(segment
		(start 233.317034 -131.408678)
		(end 233.317034 -131.8514)
		(width 0.14224)
		(layer "In11.Cu")
		(net "M_F_DQ<27>")
	)
	(segment
		(start 251.583444 -97.48012)
		(end 250.936506 -98.600768)
		(width 0.0889)
		(layer "In11.Cu")
		(net "M_F_DQ<27>")
	)
	(segment
		(start 241.879374 -121.65711)
		(end 241.52352 -122.012964)
		(width 0.14224)
		(layer "In11.Cu")
		(net "M_F_DQ<27>")
	)
	(segment
		(start 252.430788 -89.462102)
		(end 252.435614 -89.470738)
		(width 0.0889)
		(layer "In11.Cu")
		(net "M_F_DQ<27>")
	)
	(segment
		(start 233.304334 -126.34087)
		(end 233.304334 -129.960878)
		(width 0.14224)
		(layer "In11.Cu")
		(net "M_F_DQ<27>")
	)
	(segment
		(start 242.094258 -120.503188)
		(end 241.87531 -120.503188)
		(width 0.14224)
		(layer "In11.Cu")
		(net "M_F_DQ<27>")
	)
	(segment
		(start 240.369852 -122.227594)
		(end 240.736882 -122.595132)
		(width 0.14224)
		(layer "In11.Cu")
		(net "M_F_DQ<27>")
	)
	(segment
		(start 232.94975 -149.546564)
		(end 232.94975 -149.533356)
		(width 0.14224)
		(layer "In11.Cu")
		(net "M_F_DQ<27>")
	)
	(segment
		(start 243.662708 -119.553736)
		(end 243.44376 -119.553736)
		(width 0.14224)
		(layer "In11.Cu")
		(net "M_F_DQ<27>")
	)
	(segment
		(start 240.381028 -123.16968)
		(end 240.161826 -123.16968)
		(width 0.14224)
		(layer "In11.Cu")
		(net "M_F_DQ<27>")
	)
	(segment
		(start 251.583444 -96.48952)
		(end 251.577094 -96.500188)
		(width 0.0889)
		(layer "In11.Cu")
		(net "M_F_DQ<27>")
	)
	(segment
		(start 251.577094 -95.509588)
		(end 251.572268 -95.518224)
		(width 0.0889)
		(layer "In11.Cu")
		(net "M_F_DQ<27>")
	)
	(segment
		(start 252.430788 -90.452702)
		(end 252.435614 -90.461338)
		(width 0.0889)
		(layer "In11.Cu")
		(net "M_F_DQ<27>")
	)
	(segment
		(start 241.87531 -120.503188)
		(end 241.519456 -120.859042)
		(width 0.14224)
		(layer "In11.Cu")
		(net "M_F_DQ<27>")
	)
	(segment
		(start 232.927398 -149.533356)
		(end 232.499154 -149.9616)
		(width 0.14224)
		(layer "In11.Cu")
		(net "M_F_DQ<27>")
	)
	(segment
		(start 233.304334 -138.805666)
		(end 233.304334 -139.4968)
		(width 0.14224)
		(layer "In11.Cu")
		(net "M_F_DQ<27>")
	)
	(segment
		(start 234.6198 -124.1044)
		(end 234.1372 -124.587)
		(width 0.14224)
		(layer "In11.Cu")
		(net "M_F_DQ<27>")
	)
	(segment
		(start 252.435614 -90.461338)
		(end 252.441964 -90.472006)
		(width 0.0889)
		(layer "In11.Cu")
		(net "M_F_DQ<27>")
	)
	(segment
		(start 234.1372 -124.968)
		(end 233.426 -125.6792)
		(width 0.14224)
		(layer "In11.Cu")
		(net "M_F_DQ<27>")
	)
	(segment
		(start 241.52352 -122.012964)
		(end 241.304318 -122.012964)
		(width 0.14224)
		(layer "In11.Cu")
		(net "M_F_DQ<27>")
	)
	(segment
		(start 238.274098 -124.1044)
		(end 234.6198 -124.1044)
		(width 0.14224)
		(layer "In11.Cu")
		(net "M_F_DQ<27>")
	)
	(segment
		(start 243.818664 -118.559834)
		(end 243.818664 -118.778782)
		(width 0.14224)
		(layer "In11.Cu")
		(net "M_F_DQ<27>")
	)
	(segment
		(start 232.261156 -151.387048)
		(end 232.261156 -151.660352)
		(width 0.14224)
		(layer "In11.Cu")
		(net "M_F_DQ<27>")
	)
	(segment
		(start 232.549954 -153.364946)
		(end 232.372154 -153.542746)
		(width 0.14224)
		(layer "In11.Cu")
		(net "M_F_DQ<27>")
	)
	(segment
		(start 245.1862 -117.192298)
		(end 243.818664 -118.559834)
		(width 0.14224)
		(layer "In11.Cu")
		(net "M_F_DQ<27>")
	)
	(segment
		(start 252.430788 -92.433902)
		(end 252.435614 -92.442538)
		(width 0.0889)
		(layer "In11.Cu")
		(net "M_F_DQ<27>")
	)
	(segment
		(start 233.532934 -145.587212)
		(end 233.278934 -145.841212)
		(width 0.14224)
		(layer "In11.Cu")
		(net "M_F_DQ<27>")
	)
	(segment
		(start 252.435614 -89.470738)
		(end 252.441964 -89.481406)
		(width 0.0889)
		(layer "In11.Cu")
		(net "M_F_DQ<27>")
	)
	(segment
		(start 252.430788 -93.424502)
		(end 252.435614 -93.433138)
		(width 0.0889)
		(layer "In11.Cu")
		(net "M_F_DQ<27>")
	)
	(segment
		(start 233.3752 -138.7348)
		(end 233.304334 -138.805666)
		(width 0.14224)
		(layer "In11.Cu")
		(net "M_F_DQ<27>")
	)
	(segment
		(start 240.736882 -122.813826)
		(end 240.381028 -123.16968)
		(width 0.14224)
		(layer "In11.Cu")
		(net "M_F_DQ<27>")
	)
	(segment
		(start 232.94975 -149.533356)
		(end 232.927398 -149.533356)
		(width 0.14224)
		(layer "In11.Cu")
		(net "M_F_DQ<27>")
	)
	(segment
		(start 252.435614 -92.442538)
		(end 252.441964 -92.453206)
		(width 0.0889)
		(layer "In11.Cu")
		(net "M_F_DQ<27>")
	)
	(segment
		(start 232.372154 -153.542746)
		(end 232.099866 -153.542746)
		(width 0.14224)
		(layer "In11.Cu")
		(net "M_F_DQ<27>")
	)
	(segment
		(start 252.435614 -88.480138)
		(end 252.441964 -88.490806)
		(width 0.0889)
		(layer "In11.Cu")
		(net "M_F_DQ<27>")
	)
	(segment
		(start 233.426 -126.219204)
		(end 233.304334 -126.34087)
		(width 0.14224)
		(layer "In11.Cu")
		(net "M_F_DQ<27>")
	)
	(arc
		(start 252.435614 -90.061288)
		(mid 252.382144 -90.256351)
		(end 252.430788 -90.452702)
		(width 0.0889)
		(layer "In11.Cu")
		(net "M_F_DQ<27>")
	)
	(arc
		(start 251.572268 -96.508824)
		(mid 251.523513 -96.705176)
		(end 251.577094 -96.900238)
		(width 0.0889)
		(layer "In11.Cu")
		(net "M_F_DQ<27>")
	)
	(arc
		(start 252.435614 -93.033088)
		(mid 252.382144 -93.228151)
		(end 252.430788 -93.424502)
		(width 0.0889)
		(layer "In11.Cu")
		(net "M_F_DQ<27>")
	)
	(arc
		(start 252.435614 -89.070688)
		(mid 252.382144 -89.265751)
		(end 252.430788 -89.462102)
		(width 0.0889)
		(layer "In11.Cu")
		(net "M_F_DQ<27>")
	)
	(arc
		(start 251.577094 -94.919038)
		(mid 251.656316 -95.208156)
		(end 251.583444 -95.49892)
		(width 0.0889)
		(layer "In11.Cu")
		(net "M_F_DQ<27>")
	)
	(arc
		(start 251.572268 -95.518224)
		(mid 251.523513 -95.714576)
		(end 251.577094 -95.909638)
		(width 0.0889)
		(layer "In11.Cu")
		(net "M_F_DQ<27>")
	)
	(arc
		(start 252.441964 -92.453206)
		(mid 252.514762 -92.743969)
		(end 252.435614 -93.033088)
		(width 0.0889)
		(layer "In11.Cu")
		(net "M_F_DQ<27>")
	)
	(arc
		(start 252.441964 -89.481406)
		(mid 252.514762 -89.772169)
		(end 252.435614 -90.061288)
		(width 0.0889)
		(layer "In11.Cu")
		(net "M_F_DQ<27>")
	)
	(arc
		(start 251.577094 -95.909638)
		(mid 251.656316 -96.198756)
		(end 251.583444 -96.48952)
		(width 0.0889)
		(layer "In11.Cu")
		(net "M_F_DQ<27>")
	)
	(arc
		(start 252.435614 -88.080088)
		(mid 252.382144 -88.275151)
		(end 252.430788 -88.471502)
		(width 0.0889)
		(layer "In11.Cu")
		(net "M_F_DQ<27>")
	)
	(arc
		(start 251.577094 -96.900238)
		(mid 251.656316 -97.189356)
		(end 251.583444 -97.48012)
		(width 0.0889)
		(layer "In11.Cu")
		(net "M_F_DQ<27>")
	)
	(arc
		(start 252.435614 -92.042488)
		(mid 252.382144 -92.237551)
		(end 252.430788 -92.433902)
		(width 0.0889)
		(layer "In11.Cu")
		(net "M_F_DQ<27>")
	)
	(arc
		(start 252.441964 -87.500206)
		(mid 252.514762 -87.790969)
		(end 252.435614 -88.080088)
		(width 0.0889)
		(layer "In11.Cu")
		(net "M_F_DQ<27>")
	)
	(arc
		(start 252.435614 -93.433138)
		(mid 252.439943 -94.01631)
		(end 251.941584 -94.31909)
		(width 0.0889)
		(layer "In11.Cu")
		(net "M_F_DQ<27>")
	)
	(arc
		(start 252.441964 -88.490806)
		(mid 252.514762 -88.781569)
		(end 252.435614 -89.070688)
		(width 0.0889)
		(layer "In11.Cu")
		(net "M_F_DQ<27>")
	)
	(arc
		(start 252.441964 -91.462606)
		(mid 252.514762 -91.753369)
		(end 252.435614 -92.042488)
		(width 0.0889)
		(layer "In11.Cu")
		(net "M_F_DQ<27>")
	)
	(arc
		(start 252.435614 -91.051888)
		(mid 252.382144 -91.246951)
		(end 252.430788 -91.443302)
		(width 0.0889)
		(layer "In11.Cu")
		(net "M_F_DQ<27>")
	)
	(arc
		(start 252.441964 -90.472006)
		(mid 252.514762 -90.762769)
		(end 252.435614 -91.051888)
		(width 0.0889)
		(layer "In11.Cu")
		(net "M_F_DQ<27>")
	)
	(arc
		(start 251.90577 -94.31909)
		(mid 251.572801 -94.526638)
		(end 251.577094 -94.919038)
		(width 0.0889)
		(layer "In11.Cu")
		(net "M_F_DQ<27>")
	)
	(segment
		(start 233.081322 -155.52674)
		(end 233.081322 -155.75026)
		(width 0.1651)
		(layer "F.Cu")
		(net "M_F_DQ<26>")
	)
	(segment
		(start 232.94975 -155.395168)
		(end 233.081322 -155.52674)
		(width 0.1651)
		(layer "F.Cu")
		(net "M_F_DQ<26>")
	)
	(segment
		(start 232.94975 -156.87294)
		(end 232.950512 -156.87294)
		(width 0.1651)
		(layer "F.Cu")
		(net "M_F_DQ<26>")
	)
	(segment
		(start 233.081322 -155.75026)
		(end 232.94975 -155.881832)
		(width 0.1651)
		(layer "F.Cu")
		(net "M_F_DQ<26>")
	)
	(segment
		(start 252.495304 -85.803486)
		(end 251.923804 -85.803486)
		(width 0.1651)
		(layer "F.Cu")
		(net "M_F_DQ<26>")
	)
	(segment
		(start 232.94975 -155.881832)
		(end 232.94975 -156.87294)
		(width 0.1651)
		(layer "F.Cu")
		(net "M_F_DQ<26>")
	)
	(segment
		(start 232.94975 -155.1178)
		(end 232.94975 -155.395168)
		(width 0.1651)
		(layer "F.Cu")
		(net "M_F_DQ<26>")
	)
	(via
		(at 251.923804 -85.803486)
		(size 0.508)
		(drill 0.254)
		(layers "F.Cu" "B.Cu")
		(net "M_F_DQ<26>")
	)
	(via
		(at 232.099866 -150.814278)
		(size 0.508)
		(drill 0.254)
		(layers "F.Cu" "B.Cu")
		(net "M_F_DQ<26>")
	)
	(via
		(at 232.94975 -155.1178)
		(size 0.508)
		(drill 0.254)
		(layers "F.Cu" "B.Cu")
		(net "M_F_DQ<26>")
	)
	(segment
		(start 232.099866 -152.078182)
		(end 232.099866 -150.814278)
		(width 0.1651)
		(layer "B.Cu")
		(net "M_F_DQ<26>")
	)
	(segment
		(start 232.100374 -152.078436)
		(end 232.099866 -152.078182)
		(width 0.1651)
		(layer "B.Cu")
		(net "M_F_DQ<26>")
	)
	(segment
		(start 232.466134 -129.960878)
		(end 232.466134 -131.332478)
		(width 0.14224)
		(layer "In11.Cu")
		(net "M_F_DQ<26>")
	)
	(segment
		(start 232.618534 -145.806668)
		(end 232.618534 -146.177)
		(width 0.14224)
		(layer "In11.Cu")
		(net "M_F_DQ<26>")
	)
	(segment
		(start 232.099866 -150.814278)
		(end 231.666796 -151.247348)
		(width 0.14224)
		(layer "In11.Cu")
		(net "M_F_DQ<26>")
	)
	(segment
		(start 244.5512 -117.148356)
		(end 238.255556 -123.444)
		(width 0.14224)
		(layer "In11.Cu")
		(net "M_F_DQ<26>")
	)
	(segment
		(start 231.754934 -149.836378)
		(end 231.754934 -150.469346)
		(width 0.14224)
		(layer "In11.Cu")
		(net "M_F_DQ<26>")
	)
	(segment
		(start 232.440734 -134.712964)
		(end 232.440734 -136.098788)
		(width 0.14224)
		(layer "In11.Cu")
		(net "M_F_DQ<26>")
	)
	(segment
		(start 232.537 -141.584934)
		(end 232.537 -143.6878)
		(width 0.14224)
		(layer "In11.Cu")
		(net "M_F_DQ<26>")
	)
	(segment
		(start 232.440734 -136.098788)
		(end 232.593134 -136.251188)
		(width 0.14224)
		(layer "In11.Cu")
		(net "M_F_DQ<26>")
	)
	(segment
		(start 252.270514 -88.575388)
		(end 252.27534 -88.584024)
		(width 0.0889)
		(layer "In11.Cu")
		(net "M_F_DQ<26>")
	)
	(segment
		(start 231.666796 -153.834846)
		(end 232.94975 -155.1178)
		(width 0.14224)
		(layer "In11.Cu")
		(net "M_F_DQ<26>")
	)
	(segment
		(start 248.705624 -102.844346)
		(end 248.502424 -103.047546)
		(width 0.0889)
		(layer "In11.Cu")
		(net "M_F_DQ<26>")
	)
	(segment
		(start 251.41682 -97.386902)
		(end 250.78436 -98.484182)
		(width 0.0889)
		(layer "In11.Cu")
		(net "M_F_DQ<26>")
	)
	(segment
		(start 232.593134 -138.841734)
		(end 232.593134 -139.435078)
		(width 0.14224)
		(layer "In11.Cu")
		(net "M_F_DQ<26>")
	)
	(segment
		(start 232.670858 -134.48284)
		(end 232.440734 -134.712964)
		(width 0.14224)
		(layer "In11.Cu")
		(net "M_F_DQ<26>")
	)
	(segment
		(start 232.682034 -131.8514)
		(end 232.537 -131.996434)
		(width 0.14224)
		(layer "In11.Cu")
		(net "M_F_DQ<26>")
	)
	(segment
		(start 252.264164 -88.56472)
		(end 252.270514 -88.575388)
		(width 0.0889)
		(layer "In11.Cu")
		(net "M_F_DQ<26>")
	)
	(segment
		(start 232.618534 -148.972778)
		(end 231.754934 -149.836378)
		(width 0.14224)
		(layer "In11.Cu")
		(net "M_F_DQ<26>")
	)
	(segment
		(start 232.466134 -140.933678)
		(end 232.669334 -141.136878)
		(width 0.14224)
		(layer "In11.Cu")
		(net "M_F_DQ<26>")
	)
	(segment
		(start 251.941838 -94.128336)
		(end 251.902214 -94.128336)
		(width 0.0889)
		(layer "In11.Cu")
		(net "M_F_DQ<26>")
	)
	(segment
		(start 232.593134 -136.251188)
		(end 232.593134 -136.6012)
		(width 0.14224)
		(layer "In11.Cu")
		(net "M_F_DQ<26>")
	)
	(segment
		(start 252.264164 -90.54592)
		(end 252.270514 -90.556588)
		(width 0.0889)
		(layer "In11.Cu")
		(net "M_F_DQ<26>")
	)
	(segment
		(start 248.705624 -100.562918)
		(end 248.705624 -102.844346)
		(width 0.0889)
		(layer "In11.Cu")
		(net "M_F_DQ<26>")
	)
	(segment
		(start 232.682034 -131.548378)
		(end 232.682034 -131.8514)
		(width 0.14224)
		(layer "In11.Cu")
		(net "M_F_DQ<26>")
	)
	(segment
		(start 252.270514 -90.556588)
		(end 252.27534 -90.565224)
		(width 0.0889)
		(layer "In11.Cu")
		(net "M_F_DQ<26>")
	)
	(segment
		(start 232.537 -134.0612)
		(end 232.670858 -134.195058)
		(width 0.14224)
		(layer "In11.Cu")
		(net "M_F_DQ<26>")
	)
	(segment
		(start 251.594366 -86.56447)
		(end 251.572268 -86.602824)
		(width 0.0889)
		(layer "In11.Cu")
		(net "M_F_DQ<26>")
	)
	(segment
		(start 232.5116 -136.682734)
		(end 232.5116 -138.7602)
		(width 0.14224)
		(layer "In11.Cu")
		(net "M_F_DQ<26>")
	)
	(segment
		(start 232.670858 -134.195058)
		(end 232.670858 -134.48284)
		(width 0.14224)
		(layer "In11.Cu")
		(net "M_F_DQ<26>")
	)
	(segment
		(start 232.669334 -143.820134)
		(end 232.669334 -144.093438)
		(width 0.14224)
		(layer "In11.Cu")
		(net "M_F_DQ<26>")
	)
	(segment
		(start 232.5116 -146.283934)
		(end 232.5116 -148.4376)
		(width 0.14224)
		(layer "In11.Cu")
		(net "M_F_DQ<26>")
	)
	(segment
		(start 233.502454 -123.444)
		(end 232.537 -124.409454)
		(width 0.14224)
		(layer "In11.Cu")
		(net "M_F_DQ<26>")
	)
	(segment
		(start 232.537 -124.409454)
		(end 232.537 -125.7554)
		(width 0.14224)
		(layer "In11.Cu")
		(net "M_F_DQ<26>")
	)
	(segment
		(start 252.270514 -89.565988)
		(end 252.27534 -89.574624)
		(width 0.0889)
		(layer "In11.Cu")
		(net "M_F_DQ<26>")
	)
	(segment
		(start 232.5116 -148.4376)
		(end 232.618534 -148.544534)
		(width 0.14224)
		(layer "In11.Cu")
		(net "M_F_DQ<26>")
	)
	(segment
		(start 232.537 -125.7554)
		(end 232.593134 -125.811534)
		(width 0.14224)
		(layer "In11.Cu")
		(net "M_F_DQ<26>")
	)
	(segment
		(start 232.593134 -136.6012)
		(end 232.5116 -136.682734)
		(width 0.14224)
		(layer "In11.Cu")
		(net "M_F_DQ<26>")
	)
	(segment
		(start 231.754934 -150.469346)
		(end 232.099866 -150.814278)
		(width 0.14224)
		(layer "In11.Cu")
		(net "M_F_DQ<26>")
	)
	(segment
		(start 251.411994 -96.404938)
		(end 251.405644 -96.415606)
		(width 0.0889)
		(layer "In11.Cu")
		(net "M_F_DQ<26>")
	)
	(segment
		(start 232.389934 -144.372838)
		(end 232.389934 -145.578068)
		(width 0.14224)
		(layer "In11.Cu")
		(net "M_F_DQ<26>")
	)
	(segment
		(start 251.411994 -95.414338)
		(end 251.405644 -95.425006)
		(width 0.0889)
		(layer "In11.Cu")
		(net "M_F_DQ<26>")
	)
	(segment
		(start 232.593134 -139.435078)
		(end 232.466134 -139.562078)
		(width 0.14224)
		(layer "In11.Cu")
		(net "M_F_DQ<26>")
	)
	(segment
		(start 252.270514 -91.547188)
		(end 252.27534 -91.555824)
		(width 0.0889)
		(layer "In11.Cu")
		(net "M_F_DQ<26>")
	)
	(segment
		(start 248.502424 -106.081576)
		(end 244.5512 -110.0328)
		(width 0.14224)
		(layer "In11.Cu")
		(net "M_F_DQ<26>")
	)
	(segment
		(start 232.618534 -148.544534)
		(end 232.618534 -148.972778)
		(width 0.14224)
		(layer "In11.Cu")
		(net "M_F_DQ<26>")
	)
	(segment
		(start 232.669334 -141.4526)
		(end 232.537 -141.584934)
		(width 0.14224)
		(layer "In11.Cu")
		(net "M_F_DQ<26>")
	)
	(segment
		(start 232.466134 -131.332478)
		(end 232.682034 -131.548378)
		(width 0.14224)
		(layer "In11.Cu")
		(net "M_F_DQ<26>")
	)
	(segment
		(start 252.270514 -92.537788)
		(end 252.27534 -92.546424)
		(width 0.0889)
		(layer "In11.Cu")
		(net "M_F_DQ<26>")
	)
	(segment
		(start 251.577094 -86.994238)
		(end 251.741686 -87.27948)
		(width 0.0889)
		(layer "In11.Cu")
		(net "M_F_DQ<26>")
	)
	(segment
		(start 250.78436 -98.484182)
		(end 248.705624 -100.562918)
		(width 0.0889)
		(layer "In11.Cu")
		(net "M_F_DQ<26>")
	)
	(segment
		(start 232.618534 -146.177)
		(end 232.5116 -146.283934)
		(width 0.14224)
		(layer "In11.Cu")
		(net "M_F_DQ<26>")
	)
	(segment
		(start 251.923804 -85.803486)
		(end 251.594366 -86.56447)
		(width 0.0889)
		(layer "In11.Cu")
		(net "M_F_DQ<26>")
	)
	(segment
		(start 232.389934 -145.578068)
		(end 232.618534 -145.806668)
		(width 0.14224)
		(layer "In11.Cu")
		(net "M_F_DQ<26>")
	)
	(segment
		(start 238.255556 -123.444)
		(end 233.502454 -123.444)
		(width 0.14224)
		(layer "In11.Cu")
		(net "M_F_DQ<26>")
	)
	(segment
		(start 232.537 -143.6878)
		(end 232.669334 -143.820134)
		(width 0.14224)
		(layer "In11.Cu")
		(net "M_F_DQ<26>")
	)
	(segment
		(start 232.593134 -125.811534)
		(end 232.593134 -129.833878)
		(width 0.14224)
		(layer "In11.Cu")
		(net "M_F_DQ<26>")
	)
	(segment
		(start 248.502424 -103.047546)
		(end 248.502424 -106.081576)
		(width 0.14224)
		(layer "In11.Cu")
		(net "M_F_DQ<26>")
	)
	(segment
		(start 231.666796 -151.247348)
		(end 231.666796 -153.834846)
		(width 0.14224)
		(layer "In11.Cu")
		(net "M_F_DQ<26>")
	)
	(segment
		(start 252.264164 -89.55532)
		(end 252.270514 -89.565988)
		(width 0.0889)
		(layer "In11.Cu")
		(net "M_F_DQ<26>")
	)
	(segment
		(start 232.669334 -144.093438)
		(end 232.389934 -144.372838)
		(width 0.14224)
		(layer "In11.Cu")
		(net "M_F_DQ<26>")
	)
	(segment
		(start 252.264164 -92.52712)
		(end 252.270514 -92.537788)
		(width 0.0889)
		(layer "In11.Cu")
		(net "M_F_DQ<26>")
	)
	(segment
		(start 232.466134 -139.562078)
		(end 232.466134 -140.933678)
		(width 0.14224)
		(layer "In11.Cu")
		(net "M_F_DQ<26>")
	)
	(segment
		(start 251.923804 -87.384636)
		(end 251.93498 -87.384636)
		(width 0.0889)
		(layer "In11.Cu")
		(net "M_F_DQ<26>")
	)
	(segment
		(start 251.41682 -95.405702)
		(end 251.411994 -95.414338)
		(width 0.0889)
		(layer "In11.Cu")
		(net "M_F_DQ<26>")
	)
	(segment
		(start 232.537 -131.996434)
		(end 232.537 -134.0612)
		(width 0.14224)
		(layer "In11.Cu")
		(net "M_F_DQ<26>")
	)
	(segment
		(start 252.264164 -91.53652)
		(end 252.270514 -91.547188)
		(width 0.0889)
		(layer "In11.Cu")
		(net "M_F_DQ<26>")
	)
	(segment
		(start 232.593134 -129.833878)
		(end 232.466134 -129.960878)
		(width 0.14224)
		(layer "In11.Cu")
		(net "M_F_DQ<26>")
	)
	(segment
		(start 232.5116 -138.7602)
		(end 232.593134 -138.841734)
		(width 0.14224)
		(layer "In11.Cu")
		(net "M_F_DQ<26>")
	)
	(segment
		(start 244.5512 -110.0328)
		(end 244.5512 -117.148356)
		(width 0.14224)
		(layer "In11.Cu")
		(net "M_F_DQ<26>")
	)
	(segment
		(start 251.41682 -96.396302)
		(end 251.411994 -96.404938)
		(width 0.0889)
		(layer "In11.Cu")
		(net "M_F_DQ<26>")
	)
	(segment
		(start 232.669334 -141.136878)
		(end 232.669334 -141.4526)
		(width 0.14224)
		(layer "In11.Cu")
		(net "M_F_DQ<26>")
	)
	(arc
		(start 252.27534 -91.555824)
		(mid 252.324095 -91.752176)
		(end 252.270514 -91.947238)
		(width 0.0889)
		(layer "In11.Cu")
		(net "M_F_DQ<26>")
	)
	(arc
		(start 252.270514 -93.528642)
		(mid 252.274759 -93.920887)
		(end 251.941838 -94.128336)
		(width 0.0889)
		(layer "In11.Cu")
		(net "M_F_DQ<26>")
	)
	(arc
		(start 251.405644 -96.415606)
		(mid 251.332846 -96.706369)
		(end 251.411994 -96.995488)
		(width 0.0889)
		(layer "In11.Cu")
		(net "M_F_DQ<26>")
	)
	(arc
		(start 252.270514 -91.947238)
		(mid 252.191292 -92.236356)
		(end 252.264164 -92.52712)
		(width 0.0889)
		(layer "In11.Cu")
		(net "M_F_DQ<26>")
	)
	(arc
		(start 251.902214 -94.128336)
		(mid 251.406737 -94.432779)
		(end 251.411994 -95.014288)
		(width 0.0889)
		(layer "In11.Cu")
		(net "M_F_DQ<26>")
	)
	(arc
		(start 252.270514 -87.984838)
		(mid 252.191292 -88.273956)
		(end 252.264164 -88.56472)
		(width 0.0889)
		(layer "In11.Cu")
		(net "M_F_DQ<26>")
	)
	(arc
		(start 252.270514 -92.937838)
		(mid 252.191383 -93.23324)
		(end 252.270514 -93.528642)
		(width 0.0889)
		(layer "In11.Cu")
		(net "M_F_DQ<26>")
	)
	(arc
		(start 251.572268 -86.602824)
		(mid 251.523513 -86.799176)
		(end 251.577094 -86.994238)
		(width 0.0889)
		(layer "In11.Cu")
		(net "M_F_DQ<26>")
	)
	(arc
		(start 252.270514 -90.956638)
		(mid 252.191292 -91.245756)
		(end 252.264164 -91.53652)
		(width 0.0889)
		(layer "In11.Cu")
		(net "M_F_DQ<26>")
	)
	(arc
		(start 252.27534 -88.584024)
		(mid 252.324095 -88.780376)
		(end 252.270514 -88.975438)
		(width 0.0889)
		(layer "In11.Cu")
		(net "M_F_DQ<26>")
	)
	(arc
		(start 252.27534 -90.565224)
		(mid 252.324095 -90.761576)
		(end 252.270514 -90.956638)
		(width 0.0889)
		(layer "In11.Cu")
		(net "M_F_DQ<26>")
	)
	(arc
		(start 252.27534 -92.546424)
		(mid 252.324095 -92.742776)
		(end 252.270514 -92.937838)
		(width 0.0889)
		(layer "In11.Cu")
		(net "M_F_DQ<26>")
	)
	(arc
		(start 251.411994 -96.004888)
		(mid 251.465464 -96.199951)
		(end 251.41682 -96.396302)
		(width 0.0889)
		(layer "In11.Cu")
		(net "M_F_DQ<26>")
	)
	(arc
		(start 251.405644 -95.425006)
		(mid 251.332846 -95.715769)
		(end 251.411994 -96.004888)
		(width 0.0889)
		(layer "In11.Cu")
		(net "M_F_DQ<26>")
	)
	(arc
		(start 252.270514 -89.966038)
		(mid 252.191292 -90.255156)
		(end 252.264164 -90.54592)
		(width 0.0889)
		(layer "In11.Cu")
		(net "M_F_DQ<26>")
	)
	(arc
		(start 252.270514 -88.975438)
		(mid 252.191292 -89.264556)
		(end 252.264164 -89.55532)
		(width 0.0889)
		(layer "In11.Cu")
		(net "M_F_DQ<26>")
	)
	(arc
		(start 251.411994 -95.014288)
		(mid 251.465464 -95.209351)
		(end 251.41682 -95.405702)
		(width 0.0889)
		(layer "In11.Cu")
		(net "M_F_DQ<26>")
	)
	(arc
		(start 252.27534 -89.574624)
		(mid 252.324095 -89.770976)
		(end 252.270514 -89.966038)
		(width 0.0889)
		(layer "In11.Cu")
		(net "M_F_DQ<26>")
	)
	(arc
		(start 251.741686 -87.27948)
		(mid 251.818659 -87.356449)
		(end 251.923804 -87.384636)
		(width 0.0889)
		(layer "In11.Cu")
		(net "M_F_DQ<26>")
	)
	(arc
		(start 251.411994 -96.995488)
		(mid 251.465464 -97.190551)
		(end 251.41682 -97.386902)
		(width 0.0889)
		(layer "In11.Cu")
		(net "M_F_DQ<26>")
	)
	(arc
		(start 251.93498 -87.384636)
		(mid 252.273149 -87.589434)
		(end 252.270514 -87.984838)
		(width 0.0889)
		(layer "In11.Cu")
		(net "M_F_DQ<26>")
	)
	(segment
		(start 226.150424 -152.273)
		(end 226.149916 -152.278842)
		(width 0.1651)
		(layer "F.Cu")
		(net "M_F_DQ<25>")
	)
	(segment
		(start 249.919744 -87.28964)
		(end 249.348244 -87.28964)
		(width 0.1651)
		(layer "F.Cu")
		(net "M_F_DQ<25>")
	)
	(segment
		(start 226.149916 -152.278842)
		(end 226.149916 -153.542746)
		(width 0.1651)
		(layer "F.Cu")
		(net "M_F_DQ<25>")
	)
	(via
		(at 226.149916 -153.542746)
		(size 0.508)
		(drill 0.254)
		(layers "F.Cu" "B.Cu")
		(net "M_F_DQ<25>")
	)
	(via
		(at 249.348244 -87.28964)
		(size 0.508)
		(drill 0.254)
		(layers "F.Cu" "B.Cu")
		(net "M_F_DQ<25>")
	)
	(via
		(at 226.822 -149.533356)
		(size 0.508)
		(drill 0.254)
		(layers "F.Cu" "B.Cu")
		(net "M_F_DQ<25>")
	)
	(segment
		(start 226.9998 -147.478496)
		(end 226.9998 -148.852382)
		(width 0.1651)
		(layer "B.Cu")
		(net "M_F_DQ<25>")
	)
	(segment
		(start 226.9998 -148.852382)
		(end 226.822 -149.030182)
		(width 0.1651)
		(layer "B.Cu")
		(net "M_F_DQ<25>")
	)
	(segment
		(start 227.000308 -147.478496)
		(end 226.9998 -147.478496)
		(width 0.1651)
		(layer "B.Cu")
		(net "M_F_DQ<25>")
	)
	(segment
		(start 226.822 -149.030182)
		(end 226.822 -149.533356)
		(width 0.1651)
		(layer "B.Cu")
		(net "M_F_DQ<25>")
	)
	(segment
		(start 234.484672 -119.048022)
		(end 234.329732 -118.893082)
		(width 0.14224)
		(layer "In11.Cu")
		(net "M_F_DQ<25>")
	)
	(segment
		(start 231.6734 -119.507)
		(end 227.309934 -123.870466)
		(width 0.14224)
		(layer "In11.Cu")
		(net "M_F_DQ<25>")
	)
	(segment
		(start 236.439202 -117.771926)
		(end 236.469174 -117.801898)
		(width 0.14224)
		(layer "In11.Cu")
		(net "M_F_DQ<25>")
	)
	(segment
		(start 233.826812 -118.893082)
		(end 233.671872 -119.048022)
		(width 0.14224)
		(layer "In11.Cu")
		(net "M_F_DQ<25>")
	)
	(segment
		(start 233.516932 -119.666512)
		(end 233.014012 -119.666512)
		(width 0.14224)
		(layer "In11.Cu")
		(net "M_F_DQ<25>")
	)
	(segment
		(start 238.73841 -115.472718)
		(end 238.768382 -115.50269)
		(width 0.14224)
		(layer "In11.Cu")
		(net "M_F_DQ<25>")
	)
	(segment
		(start 234.639612 -119.507)
		(end 234.484672 -119.35206)
		(width 0.14224)
		(layer "In11.Cu")
		(net "M_F_DQ<25>")
	)
	(segment
		(start 226.311206 -152.846024)
		(end 226.550982 -153.0858)
		(width 0.14224)
		(layer "In11.Cu")
		(net "M_F_DQ<25>")
	)
	(segment
		(start 238.163608 -116.04752)
		(end 237.87608 -116.04752)
		(width 0.14224)
		(layer "In11.Cu")
		(net "M_F_DQ<25>")
	)
	(segment
		(start 232.046272 -119.048022)
		(end 232.046272 -119.35206)
		(width 0.14224)
		(layer "In11.Cu")
		(net "M_F_DQ<25>")
	)
	(segment
		(start 227.309934 -148.956522)
		(end 226.822 -149.444456)
		(width 0.14224)
		(layer "In11.Cu")
		(net "M_F_DQ<25>")
	)
	(segment
		(start 227.4316 -136.697466)
		(end 227.4316 -138.7602)
		(width 0.14224)
		(layer "In11.Cu")
		(net "M_F_DQ<25>")
	)
	(segment
		(start 236.1819 -118.3767)
		(end 235.894372 -118.3767)
		(width 0.14224)
		(layer "In11.Cu")
		(net "M_F_DQ<25>")
	)
	(segment
		(start 247.279668 -96.396302)
		(end 247.284494 -96.404938)
		(width 0.0889)
		(layer "In11.Cu")
		(net "M_F_DQ<25>")
	)
	(segment
		(start 227.4316 -134.2136)
		(end 227.309934 -134.335266)
		(width 0.14224)
		(layer "In11.Cu")
		(net "M_F_DQ<25>")
	)
	(segment
		(start 248.143014 -94.518988)
		(end 248.138188 -94.527624)
		(width 0.0889)
		(layer "In11.Cu")
		(net "M_F_DQ<25>")
	)
	(segment
		(start 236.439202 -117.484398)
		(end 236.439202 -117.771926)
		(width 0.14224)
		(layer "In11.Cu")
		(net "M_F_DQ<25>")
	)
	(segment
		(start 227.4316 -131.820666)
		(end 227.4316 -134.2136)
		(width 0.14224)
		(layer "In11.Cu")
		(net "M_F_DQ<25>")
	)
	(segment
		(start 227.309934 -143.784066)
		(end 227.309934 -146.20748)
		(width 0.14224)
		(layer "In11.Cu")
		(net "M_F_DQ<25>")
	)
	(segment
		(start 244.044216 -100.292154)
		(end 244.044216 -102.475538)
		(width 0.0889)
		(layer "In11.Cu")
		(net "M_F_DQ<25>")
	)
	(segment
		(start 226.525582 -151.892)
		(end 226.525582 -152.3238)
		(width 0.14224)
		(layer "In11.Cu")
		(net "M_F_DQ<25>")
	)
	(segment
		(start 232.859072 -119.511572)
		(end 232.859072 -119.048022)
		(width 0.14224)
		(layer "In11.Cu")
		(net "M_F_DQ<25>")
	)
	(segment
		(start 226.550982 -153.0858)
		(end 226.550982 -153.3906)
		(width 0.14224)
		(layer "In11.Cu")
		(net "M_F_DQ<25>")
	)
	(segment
		(start 226.371404 -150.391368)
		(end 226.601782 -150.621746)
		(width 0.14224)
		(layer "In11.Cu")
		(net "M_F_DQ<25>")
	)
	(segment
		(start 245.931944 -97.78619)
		(end 245.899178 -97.78619)
		(width 0.0889)
		(layer "In11.Cu")
		(net "M_F_DQ<25>")
	)
	(segment
		(start 236.469174 -117.801898)
		(end 236.469174 -118.089426)
		(width 0.14224)
		(layer "In11.Cu")
		(net "M_F_DQ<25>")
	)
	(segment
		(start 226.398836 -153.542746)
		(end 226.149916 -153.542746)
		(width 0.14224)
		(layer "In11.Cu")
		(net "M_F_DQ<25>")
	)
	(segment
		(start 249.348244 -87.28964)
		(end 249.041666 -87.996522)
		(width 0.0889)
		(layer "In11.Cu")
		(net "M_F_DQ<25>")
	)
	(segment
		(start 226.799648 -149.533356)
		(end 226.371404 -149.9616)
		(width 0.14224)
		(layer "In11.Cu")
		(net "M_F_DQ<25>")
	)
	(segment
		(start 248.143014 -93.928438)
		(end 248.149364 -93.939106)
		(width 0.0889)
		(layer "In11.Cu")
		(net "M_F_DQ<25>")
	)
	(segment
		(start 246.794274 -97.290636)
		(end 246.772684 -97.290636)
		(width 0.0889)
		(layer "In11.Cu")
		(net "M_F_DQ<25>")
	)
	(segment
		(start 240.5888 -108.4834)
		(end 240.5888 -113.9698)
		(width 0.14224)
		(layer "In11.Cu")
		(net "M_F_DQ<25>")
	)
	(segment
		(start 226.601782 -151.026368)
		(end 226.311206 -151.316944)
		(width 0.14224)
		(layer "In11.Cu")
		(net "M_F_DQ<25>")
	)
	(segment
		(start 238.19358 -116.077492)
		(end 238.163608 -116.04752)
		(width 0.14224)
		(layer "In11.Cu")
		(net "M_F_DQ<25>")
	)
	(segment
		(start 227.309934 -141.351)
		(end 227.4316 -141.472666)
		(width 0.14224)
		(layer "In11.Cu")
		(net "M_F_DQ<25>")
	)
	(segment
		(start 227.4316 -138.7602)
		(end 227.309934 -138.881866)
		(width 0.14224)
		(layer "In11.Cu")
		(net "M_F_DQ<25>")
	)
	(segment
		(start 239.630712 -114.927888)
		(end 239.343184 -114.927888)
		(width 0.14224)
		(layer "In11.Cu")
		(net "M_F_DQ<25>")
	)
	(segment
		(start 227.4316 -148.3614)
		(end 227.309934 -148.483066)
		(width 0.14224)
		(layer "In11.Cu")
		(net "M_F_DQ<25>")
	)
	(segment
		(start 227.309934 -148.483066)
		(end 227.309934 -148.956522)
		(width 0.14224)
		(layer "In11.Cu")
		(net "M_F_DQ<25>")
	)
	(segment
		(start 238.768382 -115.790218)
		(end 238.481108 -116.077492)
		(width 0.14224)
		(layer "In11.Cu")
		(net "M_F_DQ<25>")
	)
	(segment
		(start 238.768382 -115.50269)
		(end 238.768382 -115.790218)
		(width 0.14224)
		(layer "In11.Cu")
		(net "M_F_DQ<25>")
	)
	(segment
		(start 226.822 -149.533356)
		(end 226.799648 -149.533356)
		(width 0.14224)
		(layer "In11.Cu")
		(net "M_F_DQ<25>")
	)
	(segment
		(start 227.309934 -131.699)
		(end 227.4316 -131.820666)
		(width 0.14224)
		(layer "In11.Cu")
		(net "M_F_DQ<25>")
	)
	(segment
		(start 226.601782 -150.621746)
		(end 226.601782 -151.026368)
		(width 0.14224)
		(layer "In11.Cu")
		(net "M_F_DQ<25>")
	)
	(segment
		(start 240.5888 -113.9698)
		(end 239.630712 -114.927888)
		(width 0.14224)
		(layer "In11.Cu")
		(net "M_F_DQ<25>")
	)
	(segment
		(start 232.859072 -119.048022)
		(end 232.704132 -118.893082)
		(width 0.14224)
		(layer "In11.Cu")
		(net "M_F_DQ<25>")
	)
	(segment
		(start 227.309934 -146.20748)
		(end 227.4316 -146.329146)
		(width 0.14224)
		(layer "In11.Cu")
		(net "M_F_DQ<25>")
	)
	(segment
		(start 238.73841 -115.18519)
		(end 238.73841 -115.472718)
		(width 0.14224)
		(layer "In11.Cu")
		(net "M_F_DQ<25>")
	)
	(segment
		(start 233.014012 -119.666512)
		(end 232.859072 -119.511572)
		(width 0.14224)
		(layer "In11.Cu")
		(net "M_F_DQ<25>")
	)
	(segment
		(start 226.311206 -152.538176)
		(end 226.311206 -152.846024)
		(width 0.14224)
		(layer "In11.Cu")
		(net "M_F_DQ<25>")
	)
	(segment
		(start 226.822 -149.444456)
		(end 226.822 -149.533356)
		(width 0.14224)
		(layer "In11.Cu")
		(net "M_F_DQ<25>")
	)
	(segment
		(start 226.311206 -151.677624)
		(end 226.525582 -151.892)
		(width 0.14224)
		(layer "In11.Cu")
		(net "M_F_DQ<25>")
	)
	(segment
		(start 226.525582 -152.3238)
		(end 226.311206 -152.538176)
		(width 0.14224)
		(layer "In11.Cu")
		(net "M_F_DQ<25>")
	)
	(segment
		(start 237.014004 -117.197124)
		(end 236.726476 -117.197124)
		(width 0.14224)
		(layer "In11.Cu")
		(net "M_F_DQ<25>")
	)
	(segment
		(start 239.343184 -114.927888)
		(end 239.313212 -114.897916)
		(width 0.14224)
		(layer "In11.Cu")
		(net "M_F_DQ<25>")
	)
	(segment
		(start 226.371404 -149.9616)
		(end 226.371404 -150.391368)
		(width 0.14224)
		(layer "In11.Cu")
		(net "M_F_DQ<25>")
	)
	(segment
		(start 227.4316 -146.329146)
		(end 227.4316 -148.3614)
		(width 0.14224)
		(layer "In11.Cu")
		(net "M_F_DQ<25>")
	)
	(segment
		(start 235.31957 -118.951502)
		(end 235.31957 -119.23903)
		(width 0.14224)
		(layer "In11.Cu")
		(net "M_F_DQ<25>")
	)
	(segment
		(start 231.891332 -119.507)
		(end 231.6734 -119.507)
		(width 0.14224)
		(layer "In11.Cu")
		(net "M_F_DQ<25>")
	)
	(segment
		(start 235.894372 -118.3767)
		(end 235.8644 -118.346728)
		(width 0.14224)
		(layer "In11.Cu")
		(net "M_F_DQ<25>")
	)
	(segment
		(start 239.025684 -114.897916)
		(end 238.73841 -115.18519)
		(width 0.14224)
		(layer "In11.Cu")
		(net "M_F_DQ<25>")
	)
	(segment
		(start 238.481108 -116.077492)
		(end 238.19358 -116.077492)
		(width 0.14224)
		(layer "In11.Cu")
		(net "M_F_DQ<25>")
	)
	(segment
		(start 239.313212 -114.897916)
		(end 239.025684 -114.897916)
		(width 0.14224)
		(layer "In11.Cu")
		(net "M_F_DQ<25>")
	)
	(segment
		(start 227.309934 -138.881866)
		(end 227.309934 -141.351)
		(width 0.14224)
		(layer "In11.Cu")
		(net "M_F_DQ<25>")
	)
	(segment
		(start 244.292882 -102.724204)
		(end 244.292882 -104.779318)
		(width 0.14224)
		(layer "In11.Cu")
		(net "M_F_DQ<25>")
	)
	(segment
		(start 234.484672 -119.35206)
		(end 234.484672 -119.048022)
		(width 0.14224)
		(layer "In11.Cu")
		(net "M_F_DQ<25>")
	)
	(segment
		(start 235.8644 -118.346728)
		(end 235.576872 -118.346728)
		(width 0.14224)
		(layer "In11.Cu")
		(net "M_F_DQ<25>")
	)
	(segment
		(start 244.655086 -98.677222)
		(end 244.655086 -99.681284)
		(width 0.0889)
		(layer "In11.Cu")
		(net "M_F_DQ<25>")
	)
	(segment
		(start 237.618778 -116.652294)
		(end 237.618778 -116.939822)
		(width 0.14224)
		(layer "In11.Cu")
		(net "M_F_DQ<25>")
	)
	(segment
		(start 248.490232 -92.337636)
		(end 248.489978 -92.337636)
		(width 0.0889)
		(layer "In11.Cu")
		(net "M_F_DQ<25>")
	)
	(segment
		(start 233.671872 -119.048022)
		(end 233.671872 -119.511572)
		(width 0.14224)
		(layer "In11.Cu")
		(net "M_F_DQ<25>")
	)
	(segment
		(start 235.289598 -118.92153)
		(end 235.31957 -118.951502)
		(width 0.14224)
		(layer "In11.Cu")
		(net "M_F_DQ<25>")
	)
	(segment
		(start 247.648984 -95.80499)
		(end 247.616218 -95.80499)
		(width 0.0889)
		(layer "In11.Cu")
		(net "M_F_DQ<25>")
	)
	(segment
		(start 237.331504 -117.227096)
		(end 237.043976 -117.227096)
		(width 0.14224)
		(layer "In11.Cu")
		(net "M_F_DQ<25>")
	)
	(segment
		(start 227.4316 -141.472666)
		(end 227.4316 -143.6624)
		(width 0.14224)
		(layer "In11.Cu")
		(net "M_F_DQ<25>")
	)
	(segment
		(start 227.309934 -134.335266)
		(end 227.309934 -136.5758)
		(width 0.14224)
		(layer "In11.Cu")
		(net "M_F_DQ<25>")
	)
	(segment
		(start 235.289598 -118.634002)
		(end 235.289598 -118.92153)
		(width 0.14224)
		(layer "In11.Cu")
		(net "M_F_DQ<25>")
	)
	(segment
		(start 247.284494 -96.404938)
		(end 247.290844 -96.415606)
		(width 0.0889)
		(layer "In11.Cu")
		(net "M_F_DQ<25>")
	)
	(segment
		(start 237.87608 -116.04752)
		(end 237.588806 -116.334794)
		(width 0.14224)
		(layer "In11.Cu")
		(net "M_F_DQ<25>")
	)
	(segment
		(start 236.726476 -117.197124)
		(end 236.439202 -117.484398)
		(width 0.14224)
		(layer "In11.Cu")
		(net "M_F_DQ<25>")
	)
	(segment
		(start 244.655086 -99.681284)
		(end 244.044216 -100.292154)
		(width 0.0889)
		(layer "In11.Cu")
		(net "M_F_DQ<25>")
	)
	(segment
		(start 244.292882 -104.779318)
		(end 240.5888 -108.4834)
		(width 0.14224)
		(layer "In11.Cu")
		(net "M_F_DQ<25>")
	)
	(segment
		(start 234.329732 -118.893082)
		(end 233.826812 -118.893082)
		(width 0.14224)
		(layer "In11.Cu")
		(net "M_F_DQ<25>")
	)
	(segment
		(start 237.588806 -116.334794)
		(end 237.588806 -116.622322)
		(width 0.14224)
		(layer "In11.Cu")
		(net "M_F_DQ<25>")
	)
	(segment
		(start 244.044216 -102.475538)
		(end 244.292882 -102.724204)
		(width 0.0889)
		(layer "In11.Cu")
		(net "M_F_DQ<25>")
	)
	(segment
		(start 232.046272 -119.35206)
		(end 231.891332 -119.507)
		(width 0.14224)
		(layer "In11.Cu")
		(net "M_F_DQ<25>")
	)
	(segment
		(start 237.043976 -117.227096)
		(end 237.014004 -117.197124)
		(width 0.14224)
		(layer "In11.Cu")
		(net "M_F_DQ<25>")
	)
	(segment
		(start 235.0516 -119.507)
		(end 234.639612 -119.507)
		(width 0.14224)
		(layer "In11.Cu")
		(net "M_F_DQ<25>")
	)
	(segment
		(start 245.077234 -98.281236)
		(end 245.041166 -98.281236)
		(width 0.0889)
		(layer "In11.Cu")
		(net "M_F_DQ<25>")
	)
	(segment
		(start 237.588806 -116.622322)
		(end 237.618778 -116.652294)
		(width 0.14224)
		(layer "In11.Cu")
		(net "M_F_DQ<25>")
	)
	(segment
		(start 227.4316 -143.6624)
		(end 227.309934 -143.784066)
		(width 0.14224)
		(layer "In11.Cu")
		(net "M_F_DQ<25>")
	)
	(segment
		(start 227.309934 -136.5758)
		(end 227.4316 -136.697466)
		(width 0.14224)
		(layer "In11.Cu")
		(net "M_F_DQ<25>")
	)
	(segment
		(start 226.550982 -153.3906)
		(end 226.398836 -153.542746)
		(width 0.14224)
		(layer "In11.Cu")
		(net "M_F_DQ<25>")
	)
	(segment
		(start 227.309934 -123.870466)
		(end 227.309934 -131.699)
		(width 0.14224)
		(layer "In11.Cu")
		(net "M_F_DQ<25>")
	)
	(segment
		(start 226.311206 -151.316944)
		(end 226.311206 -151.677624)
		(width 0.14224)
		(layer "In11.Cu")
		(net "M_F_DQ<25>")
	)
	(segment
		(start 235.31957 -119.23903)
		(end 235.0516 -119.507)
		(width 0.14224)
		(layer "In11.Cu")
		(net "M_F_DQ<25>")
	)
	(segment
		(start 232.201212 -118.893082)
		(end 232.046272 -119.048022)
		(width 0.14224)
		(layer "In11.Cu")
		(net "M_F_DQ<25>")
	)
	(segment
		(start 237.618778 -116.939822)
		(end 237.331504 -117.227096)
		(width 0.14224)
		(layer "In11.Cu")
		(net "M_F_DQ<25>")
	)
	(segment
		(start 236.469174 -118.089426)
		(end 236.1819 -118.3767)
		(width 0.14224)
		(layer "In11.Cu")
		(net "M_F_DQ<25>")
	)
	(segment
		(start 235.576872 -118.346728)
		(end 235.289598 -118.634002)
		(width 0.14224)
		(layer "In11.Cu")
		(net "M_F_DQ<25>")
	)
	(segment
		(start 233.671872 -119.511572)
		(end 233.516932 -119.666512)
		(width 0.14224)
		(layer "In11.Cu")
		(net "M_F_DQ<25>")
	)
	(segment
		(start 232.704132 -118.893082)
		(end 232.201212 -118.893082)
		(width 0.14224)
		(layer "In11.Cu")
		(net "M_F_DQ<25>")
	)
	(arc
		(start 246.772684 -97.290636)
		(mid 246.572524 -97.344271)
		(end 246.425974 -97.490788)
		(width 0.0889)
		(layer "In11.Cu")
		(net "M_F_DQ<25>")
	)
	(arc
		(start 249.001534 -88.480392)
		(mid 249.080665 -88.775794)
		(end 249.001534 -89.071196)
		(width 0.0889)
		(layer "In11.Cu")
		(net "M_F_DQ<25>")
	)
	(arc
		(start 245.041166 -98.281236)
		(mid 244.768831 -98.401913)
		(end 244.655086 -98.677222)
		(width 0.0889)
		(layer "In11.Cu")
		(net "M_F_DQ<25>")
	)
	(arc
		(start 249.001534 -89.470992)
		(mid 249.080665 -89.766394)
		(end 249.001534 -90.061796)
		(width 0.0889)
		(layer "In11.Cu")
		(net "M_F_DQ<25>")
	)
	(arc
		(start 248.489978 -92.337636)
		(mid 248.143176 -92.537757)
		(end 248.143014 -92.938092)
		(width 0.0889)
		(layer "In11.Cu")
		(net "M_F_DQ<25>")
	)
	(arc
		(start 248.143014 -92.938092)
		(mid 248.222111 -93.233384)
		(end 248.143014 -93.528642)
		(width 0.0889)
		(layer "In11.Cu")
		(net "M_F_DQ<25>")
	)
	(arc
		(start 247.290844 -96.415606)
		(mid 247.286813 -96.991788)
		(end 246.794274 -97.290636)
		(width 0.0889)
		(layer "In11.Cu")
		(net "M_F_DQ<25>")
	)
	(arc
		(start 248.149364 -93.939106)
		(mid 248.222162 -94.229869)
		(end 248.143014 -94.518988)
		(width 0.0889)
		(layer "In11.Cu")
		(net "M_F_DQ<25>")
	)
	(arc
		(start 245.899178 -97.78619)
		(mid 245.707536 -97.843356)
		(end 245.567454 -97.986088)
		(width 0.0889)
		(layer "In11.Cu")
		(net "M_F_DQ<25>")
	)
	(arc
		(start 248.138188 -94.527624)
		(mid 248.089433 -94.723976)
		(end 248.143014 -94.919038)
		(width 0.0889)
		(layer "In11.Cu")
		(net "M_F_DQ<25>")
	)
	(arc
		(start 248.143014 -93.528642)
		(mid 248.089515 -93.72854)
		(end 248.143014 -93.928438)
		(width 0.0889)
		(layer "In11.Cu")
		(net "M_F_DQ<25>")
	)
	(arc
		(start 245.567454 -97.986088)
		(mid 245.36045 -98.196952)
		(end 245.077234 -98.281236)
		(width 0.0889)
		(layer "In11.Cu")
		(net "M_F_DQ<25>")
	)
	(arc
		(start 249.001534 -91.452192)
		(mid 249.0015 -92.042547)
		(end 248.490232 -92.337636)
		(width 0.0889)
		(layer "In11.Cu")
		(net "M_F_DQ<25>")
	)
	(arc
		(start 249.001534 -89.071196)
		(mid 248.948035 -89.271094)
		(end 249.001534 -89.470992)
		(width 0.0889)
		(layer "In11.Cu")
		(net "M_F_DQ<25>")
	)
	(arc
		(start 248.143014 -94.919038)
		(mid 248.147343 -95.50221)
		(end 247.648984 -95.80499)
		(width 0.0889)
		(layer "In11.Cu")
		(net "M_F_DQ<25>")
	)
	(arc
		(start 249.001534 -91.052396)
		(mid 248.948035 -91.252294)
		(end 249.001534 -91.452192)
		(width 0.0889)
		(layer "In11.Cu")
		(net "M_F_DQ<25>")
	)
	(arc
		(start 249.001534 -90.461592)
		(mid 249.080665 -90.756994)
		(end 249.001534 -91.052396)
		(width 0.0889)
		(layer "In11.Cu")
		(net "M_F_DQ<25>")
	)
	(arc
		(start 249.041666 -87.996522)
		(mid 249.023252 -88.039347)
		(end 249.001534 -88.080596)
		(width 0.0889)
		(layer "In11.Cu")
		(net "M_F_DQ<25>")
	)
	(arc
		(start 249.001534 -88.080596)
		(mid 248.948035 -88.280494)
		(end 249.001534 -88.480392)
		(width 0.0889)
		(layer "In11.Cu")
		(net "M_F_DQ<25>")
	)
	(arc
		(start 249.001534 -90.061796)
		(mid 248.948035 -90.261694)
		(end 249.001534 -90.461592)
		(width 0.0889)
		(layer "In11.Cu")
		(net "M_F_DQ<25>")
	)
	(arc
		(start 247.616218 -95.80499)
		(mid 247.2833 -96.006981)
		(end 247.279668 -96.396302)
		(width 0.0889)
		(layer "In11.Cu")
		(net "M_F_DQ<25>")
	)
	(arc
		(start 246.425974 -97.490788)
		(mid 246.217366 -97.70272)
		(end 245.931944 -97.78619)
		(width 0.0889)
		(layer "In11.Cu")
		(net "M_F_DQ<25>")
	)
	(segment
		(start 227.000308 -156.87294)
		(end 226.9998 -156.878782)
		(width 0.1651)
		(layer "F.Cu")
		(net "M_F_DQ<24>")
	)
	(segment
		(start 226.9998 -156.878782)
		(end 226.822 -155.0162)
		(width 0.1651)
		(layer "F.Cu")
		(net "M_F_DQ<24>")
	)
	(segment
		(start 249.919744 -85.30844)
		(end 249.348244 -85.30844)
		(width 0.1651)
		(layer "F.Cu")
		(net "M_F_DQ<24>")
	)
	(via
		(at 249.348244 -85.30844)
		(size 0.508)
		(drill 0.254)
		(layers "F.Cu" "B.Cu")
		(net "M_F_DQ<24>")
	)
	(via
		(at 226.149916 -150.814278)
		(size 0.508)
		(drill 0.254)
		(layers "F.Cu" "B.Cu")
		(net "M_F_DQ<24>")
	)
	(via
		(at 226.822 -155.0162)
		(size 0.508)
		(drill 0.254)
		(layers "F.Cu" "B.Cu")
		(net "M_F_DQ<24>")
	)
	(segment
		(start 226.149916 -152.078182)
		(end 226.149916 -150.814278)
		(width 0.1651)
		(layer "B.Cu")
		(net "M_F_DQ<24>")
	)
	(segment
		(start 226.150424 -152.078436)
		(end 226.149916 -152.078182)
		(width 0.1651)
		(layer "B.Cu")
		(net "M_F_DQ<24>")
	)
	(segment
		(start 226.628706 -131.454906)
		(end 226.628706 -134.480046)
		(width 0.14224)
		(layer "In11.Cu")
		(net "M_F_DQ<24>")
	)
	(segment
		(start 226.624134 -144.085818)
		(end 226.344734 -144.365218)
		(width 0.14224)
		(layer "In11.Cu")
		(net "M_F_DQ<24>")
	)
	(segment
		(start 226.149916 -150.814278)
		(end 225.716846 -151.247348)
		(width 0.14224)
		(layer "In11.Cu")
		(net "M_F_DQ<24>")
	)
	(segment
		(start 248.490232 -92.147136)
		(end 248.489724 -92.147136)
		(width 0.0889)
		(layer "In11.Cu")
		(net "M_F_DQ<24>")
	)
	(segment
		(start 225.887026 -150.551388)
		(end 226.149916 -150.814278)
		(width 0.14224)
		(layer "In11.Cu")
		(net "M_F_DQ<24>")
	)
	(segment
		(start 226.617784 -139.377928)
		(end 226.332034 -139.663678)
		(width 0.14224)
		(layer "In11.Cu")
		(net "M_F_DQ<24>")
	)
	(segment
		(start 226.344734 -145.572734)
		(end 226.610926 -145.838926)
		(width 0.14224)
		(layer "In11.Cu")
		(net "M_F_DQ<24>")
	)
	(segment
		(start 247.113044 -96.48952)
		(end 247.119394 -96.500188)
		(width 0.0889)
		(layer "In11.Cu")
		(net "M_F_DQ<24>")
	)
	(segment
		(start 243.854224 -102.527862)
		(end 243.657882 -102.724204)
		(width 0.0889)
		(layer "In11.Cu")
		(net "M_F_DQ<24>")
	)
	(segment
		(start 226.628706 -134.480046)
		(end 226.332034 -134.776718)
		(width 0.14224)
		(layer "In11.Cu")
		(net "M_F_DQ<24>")
	)
	(segment
		(start 234.629706 -118.354094)
		(end 231.91216 -118.354094)
		(width 0.14224)
		(layer "In11.Cu")
		(net "M_F_DQ<24>")
	)
	(segment
		(start 243.657882 -104.499918)
		(end 239.9284 -108.2294)
		(width 0.14224)
		(layer "In11.Cu")
		(net "M_F_DQ<24>")
	)
	(segment
		(start 226.2886 -129.0066)
		(end 226.596702 -129.314702)
		(width 0.14224)
		(layer "In11.Cu")
		(net "M_F_DQ<24>")
	)
	(segment
		(start 226.617784 -136.24433)
		(end 226.617784 -139.377928)
		(width 0.14224)
		(layer "In11.Cu")
		(net "M_F_DQ<24>")
	)
	(segment
		(start 239.9284 -108.2294)
		(end 239.9284 -113.0554)
		(width 0.14224)
		(layer "In11.Cu")
		(net "M_F_DQ<24>")
	)
	(segment
		(start 226.610926 -146.253708)
		(end 226.568 -146.296634)
		(width 0.14224)
		(layer "In11.Cu")
		(net "M_F_DQ<24>")
	)
	(segment
		(start 226.2886 -124.511054)
		(end 226.2886 -129.0066)
		(width 0.14224)
		(layer "In11.Cu")
		(net "M_F_DQ<24>")
	)
	(segment
		(start 225.716846 -151.247348)
		(end 225.716846 -153.911046)
		(width 0.14224)
		(layer "In11.Cu")
		(net "M_F_DQ<24>")
	)
	(segment
		(start 226.332034 -130.080766)
		(end 226.332034 -131.158234)
		(width 0.14224)
		(layer "In11.Cu")
		(net "M_F_DQ<24>")
	)
	(segment
		(start 226.332034 -140.743178)
		(end 226.624134 -141.035278)
		(width 0.14224)
		(layer "In11.Cu")
		(net "M_F_DQ<24>")
	)
	(segment
		(start 244.464586 -99.603052)
		(end 243.854224 -100.213414)
		(width 0.0889)
		(layer "In11.Cu")
		(net "M_F_DQ<24>")
	)
	(segment
		(start 226.596702 -129.314702)
		(end 226.596702 -129.816098)
		(width 0.14224)
		(layer "In11.Cu")
		(net "M_F_DQ<24>")
	)
	(segment
		(start 243.854224 -100.213414)
		(end 243.854224 -102.527862)
		(width 0.0889)
		(layer "In11.Cu")
		(net "M_F_DQ<24>")
	)
	(segment
		(start 226.596702 -129.816098)
		(end 226.332034 -130.080766)
		(width 0.14224)
		(layer "In11.Cu")
		(net "M_F_DQ<24>")
	)
	(segment
		(start 226.624134 -141.035278)
		(end 226.624134 -144.085818)
		(width 0.14224)
		(layer "In11.Cu")
		(net "M_F_DQ<24>")
	)
	(segment
		(start 225.716846 -153.911046)
		(end 226.822 -155.0162)
		(width 0.14224)
		(layer "In11.Cu")
		(net "M_F_DQ<24>")
	)
	(segment
		(start 231.91216 -118.354094)
		(end 226.674934 -123.59132)
		(width 0.14224)
		(layer "In11.Cu")
		(net "M_F_DQ<24>")
	)
	(segment
		(start 226.674934 -123.59132)
		(end 226.674934 -124.12472)
		(width 0.14224)
		(layer "In11.Cu")
		(net "M_F_DQ<24>")
	)
	(segment
		(start 246.78767 -97.100136)
		(end 246.772684 -97.100136)
		(width 0.0889)
		(layer "In11.Cu")
		(net "M_F_DQ<24>")
	)
	(segment
		(start 245.92534 -97.59569)
		(end 245.892574 -97.59569)
		(width 0.0889)
		(layer "In11.Cu")
		(net "M_F_DQ<24>")
	)
	(segment
		(start 247.64238 -95.61449)
		(end 247.609614 -95.61449)
		(width 0.0889)
		(layer "In11.Cu")
		(net "M_F_DQ<24>")
	)
	(segment
		(start 226.344734 -144.365218)
		(end 226.344734 -145.572734)
		(width 0.14224)
		(layer "In11.Cu")
		(net "M_F_DQ<24>")
	)
	(segment
		(start 244.464586 -98.676206)
		(end 244.464586 -99.603052)
		(width 0.0889)
		(layer "In11.Cu")
		(net "M_F_DQ<24>")
	)
	(segment
		(start 226.332034 -135.95858)
		(end 226.617784 -136.24433)
		(width 0.14224)
		(layer "In11.Cu")
		(net "M_F_DQ<24>")
	)
	(segment
		(start 226.332034 -139.663678)
		(end 226.332034 -140.743178)
		(width 0.14224)
		(layer "In11.Cu")
		(net "M_F_DQ<24>")
	)
	(segment
		(start 226.332034 -134.776718)
		(end 226.332034 -135.95858)
		(width 0.14224)
		(layer "In11.Cu")
		(net "M_F_DQ<24>")
	)
	(segment
		(start 226.674934 -124.12472)
		(end 226.2886 -124.511054)
		(width 0.14224)
		(layer "In11.Cu")
		(net "M_F_DQ<24>")
	)
	(segment
		(start 226.332034 -131.158234)
		(end 226.628706 -131.454906)
		(width 0.14224)
		(layer "In11.Cu")
		(net "M_F_DQ<24>")
	)
	(segment
		(start 247.119394 -96.500188)
		(end 247.12422 -96.508824)
		(width 0.0889)
		(layer "In11.Cu")
		(net "M_F_DQ<24>")
	)
	(segment
		(start 247.971564 -94.01302)
		(end 247.977914 -94.023688)
		(width 0.0889)
		(layer "In11.Cu")
		(net "M_F_DQ<24>")
	)
	(segment
		(start 226.568 -146.296634)
		(end 226.568 -149.028912)
		(width 0.14224)
		(layer "In11.Cu")
		(net "M_F_DQ<24>")
	)
	(segment
		(start 226.610926 -145.838926)
		(end 226.610926 -146.253708)
		(width 0.14224)
		(layer "In11.Cu")
		(net "M_F_DQ<24>")
	)
	(segment
		(start 245.07063 -98.090736)
		(end 245.037864 -98.090736)
		(width 0.0889)
		(layer "In11.Cu")
		(net "M_F_DQ<24>")
	)
	(segment
		(start 243.657882 -102.724204)
		(end 243.657882 -104.499918)
		(width 0.14224)
		(layer "In11.Cu")
		(net "M_F_DQ<24>")
	)
	(segment
		(start 226.568 -149.028912)
		(end 225.887026 -149.709886)
		(width 0.14224)
		(layer "In11.Cu")
		(net "M_F_DQ<24>")
	)
	(segment
		(start 225.887026 -149.709886)
		(end 225.887026 -150.551388)
		(width 0.14224)
		(layer "In11.Cu")
		(net "M_F_DQ<24>")
	)
	(segment
		(start 249.348244 -85.30844)
		(end 249.001534 -86.099396)
		(width 0.0889)
		(layer "In11.Cu")
		(net "M_F_DQ<24>")
	)
	(segment
		(start 248.967752 -86.766908)
		(end 248.836434 -86.994492)
		(width 0.0889)
		(layer "In11.Cu")
		(net "M_F_DQ<24>")
	)
	(segment
		(start 239.9284 -113.0554)
		(end 234.629706 -118.354094)
		(width 0.14224)
		(layer "In11.Cu")
		(net "M_F_DQ<24>")
	)
	(arc
		(start 248.836434 -89.966292)
		(mid 248.757303 -90.261694)
		(end 248.836434 -90.557096)
		(width 0.0889)
		(layer "In11.Cu")
		(net "M_F_DQ<24>")
	)
	(arc
		(start 247.977914 -93.033596)
		(mid 248.031481 -93.233384)
		(end 247.977914 -93.433138)
		(width 0.0889)
		(layer "In11.Cu")
		(net "M_F_DQ<24>")
	)
	(arc
		(start 248.836434 -88.975692)
		(mid 248.757303 -89.271094)
		(end 248.836434 -89.566496)
		(width 0.0889)
		(layer "In11.Cu")
		(net "M_F_DQ<24>")
	)
	(arc
		(start 245.402354 -97.890838)
		(mid 245.262275 -98.033574)
		(end 245.07063 -98.090736)
		(width 0.0889)
		(layer "In11.Cu")
		(net "M_F_DQ<24>")
	)
	(arc
		(start 247.977914 -93.433138)
		(mid 247.898692 -93.722256)
		(end 247.971564 -94.01302)
		(width 0.0889)
		(layer "In11.Cu")
		(net "M_F_DQ<24>")
	)
	(arc
		(start 248.836434 -90.956892)
		(mid 248.757303 -91.252294)
		(end 248.836434 -91.547696)
		(width 0.0889)
		(layer "In11.Cu")
		(net "M_F_DQ<24>")
	)
	(arc
		(start 248.836434 -90.557096)
		(mid 248.889933 -90.756994)
		(end 248.836434 -90.956892)
		(width 0.0889)
		(layer "In11.Cu")
		(net "M_F_DQ<24>")
	)
	(arc
		(start 249.001534 -86.099396)
		(mid 248.948541 -86.279187)
		(end 248.983246 -86.463378)
		(width 0.0889)
		(layer "In11.Cu")
		(net "M_F_DQ<24>")
	)
	(arc
		(start 248.983246 -86.463378)
		(mid 249.012111 -86.617013)
		(end 248.967752 -86.766908)
		(width 0.0889)
		(layer "In11.Cu")
		(net "M_F_DQ<24>")
	)
	(arc
		(start 247.12422 -96.508824)
		(mid 247.120473 -96.89808)
		(end 246.78767 -97.100136)
		(width 0.0889)
		(layer "In11.Cu")
		(net "M_F_DQ<24>")
	)
	(arc
		(start 247.977914 -94.423484)
		(mid 247.898783 -94.718886)
		(end 247.977914 -95.014288)
		(width 0.0889)
		(layer "In11.Cu")
		(net "M_F_DQ<24>")
	)
	(arc
		(start 248.836434 -88.575896)
		(mid 248.889933 -88.775794)
		(end 248.836434 -88.975692)
		(width 0.0889)
		(layer "In11.Cu")
		(net "M_F_DQ<24>")
	)
	(arc
		(start 247.977914 -95.014288)
		(mid 247.980662 -95.409755)
		(end 247.64238 -95.61449)
		(width 0.0889)
		(layer "In11.Cu")
		(net "M_F_DQ<24>")
	)
	(arc
		(start 245.892574 -97.59569)
		(mid 245.609357 -97.679971)
		(end 245.402354 -97.890838)
		(width 0.0889)
		(layer "In11.Cu")
		(net "M_F_DQ<24>")
	)
	(arc
		(start 248.836434 -87.585296)
		(mid 248.889933 -87.785194)
		(end 248.836434 -87.985092)
		(width 0.0889)
		(layer "In11.Cu")
		(net "M_F_DQ<24>")
	)
	(arc
		(start 248.836434 -87.985092)
		(mid 248.757303 -88.280494)
		(end 248.836434 -88.575896)
		(width 0.0889)
		(layer "In11.Cu")
		(net "M_F_DQ<24>")
	)
	(arc
		(start 248.836434 -86.994492)
		(mid 248.757303 -87.289894)
		(end 248.836434 -87.585296)
		(width 0.0889)
		(layer "In11.Cu")
		(net "M_F_DQ<24>")
	)
	(arc
		(start 246.772684 -97.100136)
		(mid 246.477216 -97.179288)
		(end 246.260874 -97.395538)
		(width 0.0889)
		(layer "In11.Cu")
		(net "M_F_DQ<24>")
	)
	(arc
		(start 248.836434 -89.566496)
		(mid 248.889933 -89.766394)
		(end 248.836434 -89.966292)
		(width 0.0889)
		(layer "In11.Cu")
		(net "M_F_DQ<24>")
	)
	(arc
		(start 248.489724 -92.147136)
		(mid 247.977873 -92.442631)
		(end 247.977914 -93.033596)
		(width 0.0889)
		(layer "In11.Cu")
		(net "M_F_DQ<24>")
	)
	(arc
		(start 246.260874 -97.395538)
		(mid 246.119191 -97.539342)
		(end 245.92534 -97.59569)
		(width 0.0889)
		(layer "In11.Cu")
		(net "M_F_DQ<24>")
	)
	(arc
		(start 247.609614 -95.61449)
		(mid 247.117224 -95.913423)
		(end 247.113044 -96.48952)
		(width 0.0889)
		(layer "In11.Cu")
		(net "M_F_DQ<24>")
	)
	(arc
		(start 245.037864 -98.090736)
		(mid 244.633315 -98.268014)
		(end 244.464586 -98.676206)
		(width 0.0889)
		(layer "In11.Cu")
		(net "M_F_DQ<24>")
	)
	(arc
		(start 247.977914 -94.023688)
		(mid 248.031413 -94.223586)
		(end 247.977914 -94.423484)
		(width 0.0889)
		(layer "In11.Cu")
		(net "M_F_DQ<24>")
	)
	(arc
		(start 248.836434 -91.547696)
		(mid 248.836281 -91.947249)
		(end 248.490232 -92.147136)
		(width 0.0889)
		(layer "In11.Cu")
		(net "M_F_DQ<24>")
	)
	(segment
		(start 221.04985 -152.278842)
		(end 221.04985 -153.542746)
		(width 0.1651)
		(layer "F.Cu")
		(net "M_F_DQ<23>")
	)
	(segment
		(start 221.050358 -152.273)
		(end 221.04985 -152.278842)
		(width 0.1651)
		(layer "F.Cu")
		(net "M_F_DQ<23>")
	)
	(segment
		(start 245.627144 -94.718886)
		(end 245.055644 -94.718886)
		(width 0.1651)
		(layer "F.Cu")
		(net "M_F_DQ<23>")
	)
	(via
		(at 221.04985 -153.542746)
		(size 0.508)
		(drill 0.254)
		(layers "F.Cu" "B.Cu")
		(net "M_F_DQ<23>")
	)
	(via
		(at 221.899734 -149.533356)
		(size 0.508)
		(drill 0.254)
		(layers "F.Cu" "B.Cu")
		(net "M_F_DQ<23>")
	)
	(via
		(at 245.055644 -94.718886)
		(size 0.508)
		(drill 0.254)
		(layers "F.Cu" "B.Cu")
		(net "M_F_DQ<23>")
	)
	(segment
		(start 221.900496 -147.478496)
		(end 221.899734 -147.478496)
		(width 0.1651)
		(layer "B.Cu")
		(net "M_F_DQ<23>")
	)
	(segment
		(start 221.899734 -147.478496)
		(end 221.899734 -149.533356)
		(width 0.1651)
		(layer "B.Cu")
		(net "M_F_DQ<23>")
	)
	(segment
		(start 234.253278 -111.67745)
		(end 234.35945 -111.783622)
		(width 0.14224)
		(layer "In11.Cu")
		(net "M_F_DQ<23>")
	)
	(segment
		(start 237.419896 -104.726486)
		(end 236.3216 -105.824782)
		(width 0.14224)
		(layer "In11.Cu")
		(net "M_F_DQ<23>")
	)
	(segment
		(start 234.35945 -112.07115)
		(end 234.013502 -112.417098)
		(width 0.14224)
		(layer "In11.Cu")
		(net "M_F_DQ<23>")
	)
	(segment
		(start 235.22178 -111.20882)
		(end 234.934252 -111.20882)
		(width 0.14224)
		(layer "In11.Cu")
		(net "M_F_DQ<23>")
	)
	(segment
		(start 238.787432 -103.097076)
		(end 237.419896 -104.464612)
		(width 0.0889)
		(layer "In11.Cu")
		(net "M_F_DQ<23>")
	)
	(segment
		(start 242.498118 -96.79559)
		(end 242.465352 -96.79559)
		(width 0.0889)
		(layer "In11.Cu")
		(net "M_F_DQ<23>")
	)
	(segment
		(start 222.1738 -136.8044)
		(end 222.3516 -136.9822)
		(width 0.14224)
		(layer "In11.Cu")
		(net "M_F_DQ<23>")
	)
	(segment
		(start 222.42526 -127.689864)
		(end 222.000318 -127.689864)
		(width 0.14224)
		(layer "In11.Cu")
		(net "M_F_DQ<23>")
	)
	(segment
		(start 221.322138 -153.542746)
		(end 221.04985 -153.542746)
		(width 0.14224)
		(layer "In11.Cu")
		(net "M_F_DQ<23>")
	)
	(segment
		(start 222.3516 -136.9822)
		(end 222.3516 -137.3124)
		(width 0.14224)
		(layer "In11.Cu")
		(net "M_F_DQ<23>")
	)
	(segment
		(start 222.5802 -128.9812)
		(end 222.1992 -129.3622)
		(width 0.14224)
		(layer "In11.Cu")
		(net "M_F_DQ<23>")
	)
	(segment
		(start 233.725974 -112.417098)
		(end 233.238802 -111.929926)
		(width 0.14224)
		(layer "In11.Cu")
		(net "M_F_DQ<23>")
	)
	(segment
		(start 238.787432 -101.491796)
		(end 238.787432 -103.097076)
		(width 0.0889)
		(layer "In11.Cu")
		(net "M_F_DQ<23>")
	)
	(segment
		(start 221.845378 -128.347724)
		(end 222.000318 -128.502664)
		(width 0.14224)
		(layer "In11.Cu")
		(net "M_F_DQ<23>")
	)
	(segment
		(start 234.82808 -111.102648)
		(end 234.540552 -111.102648)
		(width 0.14224)
		(layer "In11.Cu")
		(net "M_F_DQ<23>")
	)
	(segment
		(start 222.3262 -143.637)
		(end 222.178118 -143.785082)
		(width 0.14224)
		(layer "In11.Cu")
		(net "M_F_DQ<23>")
	)
	(segment
		(start 242.99545 -96.494346)
		(end 242.992148 -96.500188)
		(width 0.0889)
		(layer "In11.Cu")
		(net "M_F_DQ<23>")
	)
	(segment
		(start 221.468188 -152.2222)
		(end 221.21114 -152.479248)
		(width 0.14224)
		(layer "In11.Cu")
		(net "M_F_DQ<23>")
	)
	(segment
		(start 221.499938 -153.04135)
		(end 221.499938 -153.364946)
		(width 0.14224)
		(layer "In11.Cu")
		(net "M_F_DQ<23>")
	)
	(segment
		(start 243.360194 -96.300036)
		(end 243.338604 -96.300036)
		(width 0.0889)
		(layer "In11.Cu")
		(net "M_F_DQ<23>")
	)
	(segment
		(start 222.085154 -132.76453)
		(end 222.085154 -133.26745)
		(width 0.14224)
		(layer "In11.Cu")
		(net "M_F_DQ<23>")
	)
	(segment
		(start 232.664 -112.2172)
		(end 232.664 -112.504728)
		(width 0.14224)
		(layer "In11.Cu")
		(net "M_F_DQ<23>")
	)
	(segment
		(start 233.238802 -111.929926)
		(end 232.951274 -111.929926)
		(width 0.14224)
		(layer "In11.Cu")
		(net "M_F_DQ<23>")
	)
	(segment
		(start 234.253278 -111.389922)
		(end 234.253278 -111.67745)
		(width 0.14224)
		(layer "In11.Cu")
		(net "M_F_DQ<23>")
	)
	(segment
		(start 222.415354 -132.60959)
		(end 222.240094 -132.60959)
		(width 0.14224)
		(layer "In11.Cu")
		(net "M_F_DQ<23>")
	)
	(segment
		(start 221.877382 -149.533356)
		(end 221.449138 -149.9616)
		(width 0.14224)
		(layer "In11.Cu")
		(net "M_F_DQ<23>")
	)
	(segment
		(start 221.21114 -152.479248)
		(end 221.21114 -152.752552)
		(width 0.14224)
		(layer "In11.Cu")
		(net "M_F_DQ<23>")
	)
	(segment
		(start 222.504 -140.690346)
		(end 222.123 -141.071346)
		(width 0.14224)
		(layer "In11.Cu")
		(net "M_F_DQ<23>")
	)
	(segment
		(start 222.570294 -133.891274)
		(end 222.1738 -134.287768)
		(width 0.14224)
		(layer "In11.Cu")
		(net "M_F_DQ<23>")
	)
	(segment
		(start 222.415354 -133.42239)
		(end 222.570294 -133.57733)
		(width 0.14224)
		(layer "In11.Cu")
		(net "M_F_DQ<23>")
	)
	(segment
		(start 222.3516 -138.684)
		(end 222.1992 -138.8364)
		(width 0.14224)
		(layer "In11.Cu")
		(net "M_F_DQ<23>")
	)
	(segment
		(start 222.098616 -137.973816)
		(end 222.3516 -138.2268)
		(width 0.14224)
		(layer "In11.Cu")
		(net "M_F_DQ<23>")
	)
	(segment
		(start 222.570294 -132.45465)
		(end 222.415354 -132.60959)
		(width 0.14224)
		(layer "In11.Cu")
		(net "M_F_DQ<23>")
	)
	(segment
		(start 222.240094 -132.60959)
		(end 222.085154 -132.76453)
		(width 0.14224)
		(layer "In11.Cu")
		(net "M_F_DQ<23>")
	)
	(segment
		(start 222.123 -141.45006)
		(end 222.3262 -141.65326)
		(width 0.14224)
		(layer "In11.Cu")
		(net "M_F_DQ<23>")
	)
	(segment
		(start 222.4532 -130.059938)
		(end 222.4532 -131.114546)
		(width 0.14224)
		(layer "In11.Cu")
		(net "M_F_DQ<23>")
	)
	(segment
		(start 222.3262 -146.8628)
		(end 222.0214 -147.1676)
		(width 0.14224)
		(layer "In11.Cu")
		(net "M_F_DQ<23>")
	)
	(segment
		(start 222.1738 -134.475728)
		(end 222.45574 -134.757668)
		(width 0.14224)
		(layer "In11.Cu")
		(net "M_F_DQ<23>")
	)
	(segment
		(start 222.570294 -132.128006)
		(end 222.570294 -132.45465)
		(width 0.14224)
		(layer "In11.Cu")
		(net "M_F_DQ<23>")
	)
	(segment
		(start 222.1992 -138.8364)
		(end 222.1992 -139.407138)
		(width 0.14224)
		(layer "In11.Cu")
		(net "M_F_DQ<23>")
	)
	(segment
		(start 222.5802 -122.3518)
		(end 222.5802 -127.534924)
		(width 0.14224)
		(layer "In11.Cu")
		(net "M_F_DQ<23>")
	)
	(segment
		(start 232.114598 -113.10493)
		(end 231.82707 -113.10493)
		(width 0.14224)
		(layer "In11.Cu")
		(net "M_F_DQ<23>")
	)
	(segment
		(start 222.0214 -142.6972)
		(end 222.3262 -143.002)
		(width 0.14224)
		(layer "In11.Cu")
		(net "M_F_DQ<23>")
	)
	(segment
		(start 237.419896 -104.464612)
		(end 237.419896 -104.726486)
		(width 0.0889)
		(layer "In11.Cu")
		(net "M_F_DQ<23>")
	)
	(segment
		(start 222.000318 -128.502664)
		(end 222.42526 -128.502664)
		(width 0.14224)
		(layer "In11.Cu")
		(net "M_F_DQ<23>")
	)
	(segment
		(start 222.570294 -133.57733)
		(end 222.570294 -133.891274)
		(width 0.14224)
		(layer "In11.Cu")
		(net "M_F_DQ<23>")
	)
	(segment
		(start 222.3262 -143.002)
		(end 222.3262 -143.637)
		(width 0.14224)
		(layer "In11.Cu")
		(net "M_F_DQ<23>")
	)
	(segment
		(start 221.449138 -149.9616)
		(end 221.449138 -150.391368)
		(width 0.14224)
		(layer "In11.Cu")
		(net "M_F_DQ<23>")
	)
	(segment
		(start 239.064038 -98.77679)
		(end 239.031272 -98.77679)
		(width 0.0889)
		(layer "In11.Cu")
		(net "M_F_DQ<23>")
	)
	(segment
		(start 221.499938 -153.364946)
		(end 221.322138 -153.542746)
		(width 0.14224)
		(layer "In11.Cu")
		(net "M_F_DQ<23>")
	)
	(segment
		(start 222.140018 -145.906236)
		(end 222.140018 -146.270218)
		(width 0.14224)
		(layer "In11.Cu")
		(net "M_F_DQ<23>")
	)
	(segment
		(start 232.57637 -113.566702)
		(end 232.114598 -113.10493)
		(width 0.14224)
		(layer "In11.Cu")
		(net "M_F_DQ<23>")
	)
	(segment
		(start 238.705898 -99.95662)
		(end 238.699548 -99.967288)
		(width 0.0889)
		(layer "In11.Cu")
		(net "M_F_DQ<23>")
	)
	(segment
		(start 222.000318 -127.689864)
		(end 221.845378 -127.844804)
		(width 0.14224)
		(layer "In11.Cu")
		(net "M_F_DQ<23>")
	)
	(segment
		(start 222.098616 -137.565384)
		(end 222.098616 -137.973816)
		(width 0.14224)
		(layer "In11.Cu")
		(net "M_F_DQ<23>")
	)
	(segment
		(start 232.951274 -111.929926)
		(end 232.664 -112.2172)
		(width 0.14224)
		(layer "In11.Cu")
		(net "M_F_DQ<23>")
	)
	(segment
		(start 222.1992 -139.407138)
		(end 222.504 -139.711938)
		(width 0.14224)
		(layer "In11.Cu")
		(net "M_F_DQ<23>")
	)
	(segment
		(start 222.45574 -134.757668)
		(end 222.45574 -136.01446)
		(width 0.14224)
		(layer "In11.Cu")
		(net "M_F_DQ<23>")
	)
	(segment
		(start 234.35945 -111.783622)
		(end 234.35945 -112.07115)
		(width 0.14224)
		(layer "In11.Cu")
		(net "M_F_DQ<23>")
	)
	(segment
		(start 238.694722 -99.368102)
		(end 238.699548 -99.376738)
		(width 0.0889)
		(layer "In11.Cu")
		(net "M_F_DQ<23>")
	)
	(segment
		(start 222.178118 -143.785082)
		(end 222.178118 -144.072864)
		(width 0.14224)
		(layer "In11.Cu")
		(net "M_F_DQ<23>")
	)
	(segment
		(start 221.21114 -151.387048)
		(end 221.21114 -151.660352)
		(width 0.14224)
		(layer "In11.Cu")
		(net "M_F_DQ<23>")
	)
	(segment
		(start 244.726206 -95.47987)
		(end 244.708934 -95.509588)
		(width 0.0889)
		(layer "In11.Cu")
		(net "M_F_DQ<23>")
	)
	(segment
		(start 245.055644 -94.718886)
		(end 244.726206 -95.47987)
		(width 0.0889)
		(layer "In11.Cu")
		(net "M_F_DQ<23>")
	)
	(segment
		(start 222.123 -131.444746)
		(end 222.123 -131.680712)
		(width 0.14224)
		(layer "In11.Cu")
		(net "M_F_DQ<23>")
	)
	(segment
		(start 222.3262 -141.65326)
		(end 222.3262 -142.0876)
		(width 0.14224)
		(layer "In11.Cu")
		(net "M_F_DQ<23>")
	)
	(segment
		(start 222.1992 -129.805938)
		(end 222.4532 -130.059938)
		(width 0.14224)
		(layer "In11.Cu")
		(net "M_F_DQ<23>")
	)
	(segment
		(start 222.140018 -146.270218)
		(end 222.3262 -146.4564)
		(width 0.14224)
		(layer "In11.Cu")
		(net "M_F_DQ<23>")
	)
	(segment
		(start 236.3216 -110.109)
		(end 235.22178 -111.20882)
		(width 0.14224)
		(layer "In11.Cu")
		(net "M_F_DQ<23>")
	)
	(segment
		(start 222.1484 -148.717)
		(end 222.1484 -149.28469)
		(width 0.14224)
		(layer "In11.Cu")
		(net "M_F_DQ<23>")
	)
	(segment
		(start 222.504 -144.398746)
		(end 222.504 -145.542254)
		(width 0.14224)
		(layer "In11.Cu")
		(net "M_F_DQ<23>")
	)
	(segment
		(start 222.178118 -144.072864)
		(end 222.504 -144.398746)
		(width 0.14224)
		(layer "In11.Cu")
		(net "M_F_DQ<23>")
	)
	(segment
		(start 222.1738 -136.2964)
		(end 222.1738 -136.8044)
		(width 0.14224)
		(layer "In11.Cu")
		(net "M_F_DQ<23>")
	)
	(segment
		(start 222.504 -139.711938)
		(end 222.504 -140.690346)
		(width 0.14224)
		(layer "In11.Cu")
		(net "M_F_DQ<23>")
	)
	(segment
		(start 222.1738 -134.287768)
		(end 222.1738 -134.475728)
		(width 0.14224)
		(layer "In11.Cu")
		(net "M_F_DQ<23>")
	)
	(segment
		(start 221.899734 -149.533356)
		(end 221.877382 -149.533356)
		(width 0.14224)
		(layer "In11.Cu")
		(net "M_F_DQ<23>")
	)
	(segment
		(start 221.21114 -151.660352)
		(end 221.468188 -151.9174)
		(width 0.14224)
		(layer "In11.Cu")
		(net "M_F_DQ<23>")
	)
	(segment
		(start 238.700564 -101.359716)
		(end 238.787432 -101.491796)
		(width 0.0889)
		(layer "In11.Cu")
		(net "M_F_DQ<23>")
	)
	(segment
		(start 222.42526 -128.502664)
		(end 222.5802 -128.657604)
		(width 0.14224)
		(layer "In11.Cu")
		(net "M_F_DQ<23>")
	)
	(segment
		(start 221.493588 -151.1046)
		(end 221.21114 -151.387048)
		(width 0.14224)
		(layer "In11.Cu")
		(net "M_F_DQ<23>")
	)
	(segment
		(start 222.3516 -137.3124)
		(end 222.098616 -137.565384)
		(width 0.14224)
		(layer "In11.Cu")
		(net "M_F_DQ<23>")
	)
	(segment
		(start 222.123 -141.071346)
		(end 222.123 -141.45006)
		(width 0.14224)
		(layer "In11.Cu")
		(net "M_F_DQ<23>")
	)
	(segment
		(start 240.781078 -97.78619)
		(end 240.748312 -97.78619)
		(width 0.0889)
		(layer "In11.Cu")
		(net "M_F_DQ<23>")
	)
	(segment
		(start 221.493588 -150.435818)
		(end 221.493588 -151.1046)
		(width 0.14224)
		(layer "In11.Cu")
		(net "M_F_DQ<23>")
	)
	(segment
		(start 233.151172 -113.279428)
		(end 232.863898 -113.566702)
		(width 0.14224)
		(layer "In11.Cu")
		(net "M_F_DQ<23>")
	)
	(segment
		(start 221.449138 -150.391368)
		(end 221.493588 -150.435818)
		(width 0.14224)
		(layer "In11.Cu")
		(net "M_F_DQ<23>")
	)
	(segment
		(start 222.5802 -128.657604)
		(end 222.5802 -128.9812)
		(width 0.14224)
		(layer "In11.Cu")
		(net "M_F_DQ<23>")
	)
	(segment
		(start 222.123 -131.680712)
		(end 222.570294 -132.128006)
		(width 0.14224)
		(layer "In11.Cu")
		(net "M_F_DQ<23>")
	)
	(segment
		(start 221.468188 -151.9174)
		(end 221.468188 -152.2222)
		(width 0.14224)
		(layer "In11.Cu")
		(net "M_F_DQ<23>")
	)
	(segment
		(start 232.863898 -113.566702)
		(end 232.57637 -113.566702)
		(width 0.14224)
		(layer "In11.Cu")
		(net "M_F_DQ<23>")
	)
	(segment
		(start 241.643408 -97.290636)
		(end 241.610642 -97.290636)
		(width 0.0889)
		(layer "In11.Cu")
		(net "M_F_DQ<23>")
	)
	(segment
		(start 221.21114 -152.752552)
		(end 221.499938 -153.04135)
		(width 0.14224)
		(layer "In11.Cu")
		(net "M_F_DQ<23>")
	)
	(segment
		(start 234.013502 -112.417098)
		(end 233.725974 -112.417098)
		(width 0.14224)
		(layer "In11.Cu")
		(net "M_F_DQ<23>")
	)
	(segment
		(start 222.4532 -131.114546)
		(end 222.123 -131.444746)
		(width 0.14224)
		(layer "In11.Cu")
		(net "M_F_DQ<23>")
	)
	(segment
		(start 238.694722 -101.349302)
		(end 238.700564 -101.359716)
		(width 0.0889)
		(layer "In11.Cu")
		(net "M_F_DQ<23>")
	)
	(segment
		(start 222.3262 -148.5392)
		(end 222.1484 -148.717)
		(width 0.14224)
		(layer "In11.Cu")
		(net "M_F_DQ<23>")
	)
	(segment
		(start 222.5802 -127.534924)
		(end 222.42526 -127.689864)
		(width 0.14224)
		(layer "In11.Cu")
		(net "M_F_DQ<23>")
	)
	(segment
		(start 233.151172 -112.9919)
		(end 233.151172 -113.279428)
		(width 0.14224)
		(layer "In11.Cu")
		(net "M_F_DQ<23>")
	)
	(segment
		(start 222.0214 -147.5486)
		(end 222.3262 -147.8534)
		(width 0.14224)
		(layer "In11.Cu")
		(net "M_F_DQ<23>")
	)
	(segment
		(start 236.3216 -105.824782)
		(end 236.3216 -110.109)
		(width 0.14224)
		(layer "In11.Cu")
		(net "M_F_DQ<23>")
	)
	(segment
		(start 231.82707 -113.10493)
		(end 222.5802 -122.3518)
		(width 0.14224)
		(layer "In11.Cu")
		(net "M_F_DQ<23>")
	)
	(segment
		(start 222.1992 -129.3622)
		(end 222.1992 -129.805938)
		(width 0.14224)
		(layer "In11.Cu")
		(net "M_F_DQ<23>")
	)
	(segment
		(start 222.3262 -147.8534)
		(end 222.3262 -148.5392)
		(width 0.14224)
		(layer "In11.Cu")
		(net "M_F_DQ<23>")
	)
	(segment
		(start 232.664 -112.504728)
		(end 233.151172 -112.9919)
		(width 0.14224)
		(layer "In11.Cu")
		(net "M_F_DQ<23>")
	)
	(segment
		(start 244.214904 -95.80499)
		(end 244.182138 -95.80499)
		(width 0.0889)
		(layer "In11.Cu")
		(net "M_F_DQ<23>")
	)
	(segment
		(start 234.934252 -111.20882)
		(end 234.82808 -111.102648)
		(width 0.14224)
		(layer "In11.Cu")
		(net "M_F_DQ<23>")
	)
	(segment
		(start 222.3516 -138.2268)
		(end 222.3516 -138.684)
		(width 0.14224)
		(layer "In11.Cu")
		(net "M_F_DQ<23>")
	)
	(segment
		(start 222.45574 -136.01446)
		(end 222.1738 -136.2964)
		(width 0.14224)
		(layer "In11.Cu")
		(net "M_F_DQ<23>")
	)
	(segment
		(start 222.0214 -147.1676)
		(end 222.0214 -147.5486)
		(width 0.14224)
		(layer "In11.Cu")
		(net "M_F_DQ<23>")
	)
	(segment
		(start 222.085154 -133.26745)
		(end 222.240094 -133.42239)
		(width 0.14224)
		(layer "In11.Cu")
		(net "M_F_DQ<23>")
	)
	(segment
		(start 222.3262 -146.4564)
		(end 222.3262 -146.8628)
		(width 0.14224)
		(layer "In11.Cu")
		(net "M_F_DQ<23>")
	)
	(segment
		(start 222.1484 -149.28469)
		(end 221.899734 -149.533356)
		(width 0.14224)
		(layer "In11.Cu")
		(net "M_F_DQ<23>")
	)
	(segment
		(start 222.504 -145.542254)
		(end 222.140018 -145.906236)
		(width 0.14224)
		(layer "In11.Cu")
		(net "M_F_DQ<23>")
	)
	(segment
		(start 222.0214 -142.3924)
		(end 222.0214 -142.6972)
		(width 0.14224)
		(layer "In11.Cu")
		(net "M_F_DQ<23>")
	)
	(segment
		(start 222.3262 -142.0876)
		(end 222.0214 -142.3924)
		(width 0.14224)
		(layer "In11.Cu")
		(net "M_F_DQ<23>")
	)
	(segment
		(start 234.540552 -111.102648)
		(end 234.253278 -111.389922)
		(width 0.14224)
		(layer "In11.Cu")
		(net "M_F_DQ<23>")
	)
	(segment
		(start 222.240094 -133.42239)
		(end 222.415354 -133.42239)
		(width 0.14224)
		(layer "In11.Cu")
		(net "M_F_DQ<23>")
	)
	(segment
		(start 239.926368 -98.281236)
		(end 239.893602 -98.281236)
		(width 0.0889)
		(layer "In11.Cu")
		(net "M_F_DQ<23>")
	)
	(segment
		(start 221.845378 -127.844804)
		(end 221.845378 -128.347724)
		(width 0.14224)
		(layer "In11.Cu")
		(net "M_F_DQ<23>")
	)
	(arc
		(start 242.133628 -96.995488)
		(mid 241.926624 -97.206352)
		(end 241.643408 -97.290636)
		(width 0.0889)
		(layer "In11.Cu")
		(net "M_F_DQ<23>")
	)
	(arc
		(start 242.992148 -96.500188)
		(mid 242.78354 -96.71212)
		(end 242.498118 -96.79559)
		(width 0.0889)
		(layer "In11.Cu")
		(net "M_F_DQ<23>")
	)
	(arc
		(start 238.699548 -99.376738)
		(mid 238.77877 -99.665856)
		(end 238.705898 -99.95662)
		(width 0.0889)
		(layer "In11.Cu")
		(net "M_F_DQ<23>")
	)
	(arc
		(start 240.416588 -97.986088)
		(mid 240.209584 -98.196952)
		(end 239.926368 -98.281236)
		(width 0.0889)
		(layer "In11.Cu")
		(net "M_F_DQ<23>")
	)
	(arc
		(start 242.465352 -96.79559)
		(mid 242.27371 -96.852756)
		(end 242.133628 -96.995488)
		(width 0.0889)
		(layer "In11.Cu")
		(net "M_F_DQ<23>")
	)
	(arc
		(start 239.893602 -98.281236)
		(mid 239.699752 -98.337586)
		(end 239.558068 -98.481388)
		(width 0.0889)
		(layer "In11.Cu")
		(net "M_F_DQ<23>")
	)
	(arc
		(start 243.850414 -96.004888)
		(mid 243.64341 -96.215752)
		(end 243.360194 -96.300036)
		(width 0.0889)
		(layer "In11.Cu")
		(net "M_F_DQ<23>")
	)
	(arc
		(start 240.748312 -97.78619)
		(mid 240.55667 -97.843356)
		(end 240.416588 -97.986088)
		(width 0.0889)
		(layer "In11.Cu")
		(net "M_F_DQ<23>")
	)
	(arc
		(start 241.275108 -97.490788)
		(mid 241.0665 -97.70272)
		(end 240.781078 -97.78619)
		(width 0.0889)
		(layer "In11.Cu")
		(net "M_F_DQ<23>")
	)
	(arc
		(start 238.699548 -100.957888)
		(mid 238.646078 -101.152951)
		(end 238.694722 -101.349302)
		(width 0.0889)
		(layer "In11.Cu")
		(net "M_F_DQ<23>")
	)
	(arc
		(start 244.708934 -95.509588)
		(mid 244.500326 -95.72152)
		(end 244.214904 -95.80499)
		(width 0.0889)
		(layer "In11.Cu")
		(net "M_F_DQ<23>")
	)
	(arc
		(start 239.031272 -98.77679)
		(mid 238.698354 -98.978781)
		(end 238.694722 -99.368102)
		(width 0.0889)
		(layer "In11.Cu")
		(net "M_F_DQ<23>")
	)
	(arc
		(start 239.558068 -98.481388)
		(mid 239.34946 -98.69332)
		(end 239.064038 -98.77679)
		(width 0.0889)
		(layer "In11.Cu")
		(net "M_F_DQ<23>")
	)
	(arc
		(start 238.699548 -99.967288)
		(mid 238.646049 -100.167186)
		(end 238.699548 -100.367084)
		(width 0.0889)
		(layer "In11.Cu")
		(net "M_F_DQ<23>")
	)
	(arc
		(start 244.182138 -95.80499)
		(mid 243.990496 -95.862156)
		(end 243.850414 -96.004888)
		(width 0.0889)
		(layer "In11.Cu")
		(net "M_F_DQ<23>")
	)
	(arc
		(start 238.699548 -100.367084)
		(mid 238.778679 -100.662486)
		(end 238.699548 -100.957888)
		(width 0.0889)
		(layer "In11.Cu")
		(net "M_F_DQ<23>")
	)
	(arc
		(start 243.338604 -96.300036)
		(mid 243.141443 -96.351995)
		(end 242.99545 -96.494346)
		(width 0.0889)
		(layer "In11.Cu")
		(net "M_F_DQ<23>")
	)
	(arc
		(start 241.610642 -97.290636)
		(mid 241.416792 -97.346986)
		(end 241.275108 -97.490788)
		(width 0.0889)
		(layer "In11.Cu")
		(net "M_F_DQ<23>")
	)
	(segment
		(start 221.899988 -155.4226)
		(end 222.032068 -155.55468)
		(width 0.1651)
		(layer "F.Cu")
		(net "M_F_DQ<22>")
	)
	(segment
		(start 247.344184 -93.72854)
		(end 246.772684 -93.72854)
		(width 0.1651)
		(layer "F.Cu")
		(net "M_F_DQ<22>")
	)
	(segment
		(start 221.899988 -155.118054)
		(end 221.899988 -155.4226)
		(width 0.1651)
		(layer "F.Cu")
		(net "M_F_DQ<22>")
	)
	(segment
		(start 221.899988 -156.87294)
		(end 221.900496 -156.87294)
		(width 0.1651)
		(layer "F.Cu")
		(net "M_F_DQ<22>")
	)
	(segment
		(start 222.032068 -155.77312)
		(end 221.899988 -155.9052)
		(width 0.1651)
		(layer "F.Cu")
		(net "M_F_DQ<22>")
	)
	(segment
		(start 221.899734 -155.1178)
		(end 221.899988 -155.118054)
		(width 0.1651)
		(layer "F.Cu")
		(net "M_F_DQ<22>")
	)
	(segment
		(start 221.899988 -155.9052)
		(end 221.899988 -156.87294)
		(width 0.1651)
		(layer "F.Cu")
		(net "M_F_DQ<22>")
	)
	(segment
		(start 222.032068 -155.55468)
		(end 222.032068 -155.77312)
		(width 0.1651)
		(layer "F.Cu")
		(net "M_F_DQ<22>")
	)
	(via
		(at 221.04985 -150.815294)
		(size 0.508)
		(drill 0.254)
		(layers "F.Cu" "B.Cu")
		(net "M_F_DQ<22>")
	)
	(via
		(at 246.772684 -93.72854)
		(size 0.508)
		(drill 0.254)
		(layers "F.Cu" "B.Cu")
		(net "M_F_DQ<22>")
	)
	(via
		(at 221.899734 -155.1178)
		(size 0.508)
		(drill 0.254)
		(layers "F.Cu" "B.Cu")
		(net "M_F_DQ<22>")
	)
	(segment
		(start 221.04985 -152.078182)
		(end 221.04985 -150.815294)
		(width 0.1651)
		(layer "B.Cu")
		(net "M_F_DQ<22>")
	)
	(segment
		(start 221.050358 -152.078436)
		(end 221.04985 -152.078182)
		(width 0.1651)
		(layer "B.Cu")
		(net "M_F_DQ<22>")
	)
	(segment
		(start 221.488 -141.53134)
		(end 221.488 -143.3068)
		(width 0.14224)
		(layer "In11.Cu")
		(net "M_F_DQ<22>")
	)
	(segment
		(start 221.606872 -145.8468)
		(end 221.606872 -146.134328)
		(width 0.14224)
		(layer "In11.Cu")
		(net "M_F_DQ<22>")
	)
	(segment
		(start 221.04985 -150.814278)
		(end 221.04985 -150.815294)
		(width 0.14224)
		(layer "In11.Cu")
		(net "M_F_DQ<22>")
	)
	(segment
		(start 235.380022 -110.034578)
		(end 235.092494 -110.034578)
		(width 0.14224)
		(layer "In11.Cu")
		(net "M_F_DQ<22>")
	)
	(segment
		(start 221.615 -141.071346)
		(end 221.615 -141.40434)
		(width 0.14224)
		(layer "In11.Cu")
		(net "M_F_DQ<22>")
	)
	(segment
		(start 236.907324 -104.340914)
		(end 235.6866 -105.561638)
		(width 0.14224)
		(layer "In11.Cu")
		(net "M_F_DQ<22>")
	)
	(segment
		(start 221.9198 -122.047)
		(end 221.9198 -126.8222)
		(width 0.14224)
		(layer "In11.Cu")
		(net "M_F_DQ<22>")
	)
	(segment
		(start 221.41434 -134.681468)
		(end 221.41434 -136.07034)
		(width 0.14224)
		(layer "In11.Cu")
		(net "M_F_DQ<22>")
	)
	(segment
		(start 245.073424 -94.31909)
		(end 245.03761 -94.31909)
		(width 0.0889)
		(layer "In11.Cu")
		(net "M_F_DQ<22>")
	)
	(segment
		(start 237.274862 -104.340914)
		(end 236.907324 -104.340914)
		(width 0.0889)
		(layer "In11.Cu")
		(net "M_F_DQ<22>")
	)
	(segment
		(start 221.615 -141.40434)
		(end 221.488 -141.53134)
		(width 0.14224)
		(layer "In11.Cu")
		(net "M_F_DQ<22>")
	)
	(segment
		(start 220.88094 -150.645368)
		(end 221.04985 -150.814278)
		(width 0.14224)
		(layer "In11.Cu")
		(net "M_F_DQ<22>")
	)
	(segment
		(start 221.4118 -136.906)
		(end 221.4118 -138.811)
		(width 0.14224)
		(layer "In11.Cu")
		(net "M_F_DQ<22>")
	)
	(segment
		(start 235.6866 -105.561638)
		(end 235.6866 -108.2802)
		(width 0.14224)
		(layer "In11.Cu")
		(net "M_F_DQ<22>")
	)
	(segment
		(start 221.6404 -143.4592)
		(end 221.6404 -144.045178)
		(width 0.14224)
		(layer "In11.Cu")
		(net "M_F_DQ<22>")
	)
	(segment
		(start 239.919764 -98.090736)
		(end 239.886998 -98.090736)
		(width 0.0889)
		(layer "In11.Cu")
		(net "M_F_DQ<22>")
	)
	(segment
		(start 221.361 -146.3802)
		(end 221.361 -148.336)
		(width 0.14224)
		(layer "In11.Cu")
		(net "M_F_DQ<22>")
	)
	(segment
		(start 241.636804 -97.100136)
		(end 241.604038 -97.100136)
		(width 0.0889)
		(layer "In11.Cu")
		(net "M_F_DQ<22>")
	)
	(segment
		(start 221.9198 -126.8222)
		(end 221.268036 -127.473964)
		(width 0.14224)
		(layer "In11.Cu")
		(net "M_F_DQ<22>")
	)
	(segment
		(start 240.774474 -97.59569)
		(end 240.741708 -97.59569)
		(width 0.0889)
		(layer "In11.Cu")
		(net "M_F_DQ<22>")
	)
	(segment
		(start 221.899734 -155.1178)
		(end 220.61678 -153.834846)
		(width 0.14224)
		(layer "In11.Cu")
		(net "M_F_DQ<22>")
	)
	(segment
		(start 244.708934 -94.518988)
		(end 244.543834 -94.805246)
		(width 0.0889)
		(layer "In11.Cu")
		(net "M_F_DQ<22>")
	)
	(segment
		(start 221.61754 -139.460478)
		(end 221.2848 -139.793218)
		(width 0.14224)
		(layer "In11.Cu")
		(net "M_F_DQ<22>")
	)
	(segment
		(start 221.2848 -139.793218)
		(end 221.2848 -140.741146)
		(width 0.14224)
		(layer "In11.Cu")
		(net "M_F_DQ<22>")
	)
	(segment
		(start 235.6866 -108.2802)
		(end 235.230924 -108.735876)
		(width 0.14224)
		(layer "In11.Cu")
		(net "M_F_DQ<22>")
	)
	(segment
		(start 242.480338 -96.60509)
		(end 242.458748 -96.60509)
		(width 0.0889)
		(layer "In11.Cu")
		(net "M_F_DQ<22>")
	)
	(segment
		(start 238.534448 -100.462588)
		(end 238.539274 -100.471224)
		(width 0.0889)
		(layer "In11.Cu")
		(net "M_F_DQ<22>")
	)
	(segment
		(start 235.092494 -110.034578)
		(end 234.579922 -109.522006)
		(width 0.14224)
		(layer "In11.Cu")
		(net "M_F_DQ<22>")
	)
	(segment
		(start 221.268036 -127.473964)
		(end 221.268036 -129.066036)
		(width 0.14224)
		(layer "In11.Cu")
		(net "M_F_DQ<22>")
	)
	(segment
		(start 235.230924 -108.735876)
		(end 235.230924 -109.023404)
		(width 0.14224)
		(layer "In11.Cu")
		(net "M_F_DQ<22>")
	)
	(segment
		(start 221.62897 -129.847848)
		(end 221.3102 -130.166618)
		(width 0.14224)
		(layer "In11.Cu")
		(net "M_F_DQ<22>")
	)
	(segment
		(start 221.294198 -144.39138)
		(end 221.294198 -145.534126)
		(width 0.14224)
		(layer "In11.Cu")
		(net "M_F_DQ<22>")
	)
	(segment
		(start 221.3102 -130.166618)
		(end 221.3102 -131.202938)
		(width 0.14224)
		(layer "In11.Cu")
		(net "M_F_DQ<22>")
	)
	(segment
		(start 238.534448 -99.872038)
		(end 238.528098 -99.882706)
		(width 0.0889)
		(layer "In11.Cu")
		(net "M_F_DQ<22>")
	)
	(segment
		(start 221.361 -148.336)
		(end 221.61754 -148.59254)
		(width 0.14224)
		(layer "In11.Cu")
		(net "M_F_DQ<22>")
	)
	(segment
		(start 234.003088 -109.811312)
		(end 234.003088 -110.09884)
		(width 0.14224)
		(layer "In11.Cu")
		(net "M_F_DQ<22>")
	)
	(segment
		(start 235.230924 -109.023404)
		(end 235.667296 -109.459776)
		(width 0.14224)
		(layer "In11.Cu")
		(net "M_F_DQ<22>")
	)
	(segment
		(start 238.59744 -103.018336)
		(end 237.274862 -104.340914)
		(width 0.0889)
		(layer "In11.Cu")
		(net "M_F_DQ<22>")
	)
	(segment
		(start 220.61678 -153.834846)
		(end 220.61678 -151.247348)
		(width 0.14224)
		(layer "In11.Cu")
		(net "M_F_DQ<22>")
	)
	(segment
		(start 238.534448 -101.453188)
		(end 238.59744 -101.548946)
		(width 0.0889)
		(layer "In11.Cu")
		(net "M_F_DQ<22>")
	)
	(segment
		(start 221.6658 -136.3218)
		(end 221.6658 -136.652)
		(width 0.14224)
		(layer "In11.Cu")
		(net "M_F_DQ<22>")
	)
	(segment
		(start 221.4118 -138.811)
		(end 221.61754 -139.01674)
		(width 0.14224)
		(layer "In11.Cu")
		(net "M_F_DQ<22>")
	)
	(segment
		(start 233.585258 -110.830614)
		(end 233.504486 -110.749842)
		(width 0.14224)
		(layer "In11.Cu")
		(net "M_F_DQ<22>")
	)
	(segment
		(start 238.59744 -101.548946)
		(end 238.59744 -103.018336)
		(width 0.0889)
		(layer "In11.Cu")
		(net "M_F_DQ<22>")
	)
	(segment
		(start 221.51594 -134.579868)
		(end 221.41434 -134.681468)
		(width 0.14224)
		(layer "In11.Cu")
		(net "M_F_DQ<22>")
	)
	(segment
		(start 221.488 -143.3068)
		(end 221.6404 -143.4592)
		(width 0.14224)
		(layer "In11.Cu")
		(net "M_F_DQ<22>")
	)
	(segment
		(start 246.772684 -93.72854)
		(end 245.95074 -93.82379)
		(width 0.0889)
		(layer "In11.Cu")
		(net "M_F_DQ<22>")
	)
	(segment
		(start 244.2083 -95.61449)
		(end 244.175534 -95.61449)
		(width 0.0889)
		(layer "In11.Cu")
		(net "M_F_DQ<22>")
	)
	(segment
		(start 220.61678 -151.247348)
		(end 221.04985 -150.814278)
		(width 0.14224)
		(layer "In11.Cu")
		(net "M_F_DQ<22>")
	)
	(segment
		(start 234.16006 -110.54334)
		(end 233.872786 -110.830614)
		(width 0.14224)
		(layer "In11.Cu")
		(net "M_F_DQ<22>")
	)
	(segment
		(start 221.41434 -136.07034)
		(end 221.6658 -136.3218)
		(width 0.14224)
		(layer "In11.Cu")
		(net "M_F_DQ<22>")
	)
	(segment
		(start 221.268036 -129.066036)
		(end 221.62897 -129.42697)
		(width 0.14224)
		(layer "In11.Cu")
		(net "M_F_DQ<22>")
	)
	(segment
		(start 221.61754 -148.934678)
		(end 220.88094 -149.671278)
		(width 0.14224)
		(layer "In11.Cu")
		(net "M_F_DQ<22>")
	)
	(segment
		(start 221.62897 -129.42697)
		(end 221.62897 -129.847848)
		(width 0.14224)
		(layer "In11.Cu")
		(net "M_F_DQ<22>")
	)
	(segment
		(start 242.826794 -96.404938)
		(end 242.823492 -96.41078)
		(width 0.0889)
		(layer "In11.Cu")
		(net "M_F_DQ<22>")
	)
	(segment
		(start 243.35359 -96.109536)
		(end 243.320824 -96.109536)
		(width 0.0889)
		(layer "In11.Cu")
		(net "M_F_DQ<22>")
	)
	(segment
		(start 221.2848 -140.741146)
		(end 221.615 -141.071346)
		(width 0.14224)
		(layer "In11.Cu")
		(net "M_F_DQ<22>")
	)
	(segment
		(start 235.667296 -109.747304)
		(end 235.380022 -110.034578)
		(width 0.14224)
		(layer "In11.Cu")
		(net "M_F_DQ<22>")
	)
	(segment
		(start 221.61754 -148.59254)
		(end 221.61754 -148.934678)
		(width 0.14224)
		(layer "In11.Cu")
		(net "M_F_DQ<22>")
	)
	(segment
		(start 233.504486 -110.749842)
		(end 233.216958 -110.749842)
		(width 0.14224)
		(layer "In11.Cu")
		(net "M_F_DQ<22>")
	)
	(segment
		(start 235.667296 -109.459776)
		(end 235.667296 -109.747304)
		(width 0.14224)
		(layer "In11.Cu")
		(net "M_F_DQ<22>")
	)
	(segment
		(start 238.528098 -101.44252)
		(end 238.534448 -101.453188)
		(width 0.0889)
		(layer "In11.Cu")
		(net "M_F_DQ<22>")
	)
	(segment
		(start 234.292394 -109.522006)
		(end 234.003088 -109.811312)
		(width 0.14224)
		(layer "In11.Cu")
		(net "M_F_DQ<22>")
	)
	(segment
		(start 233.872786 -110.830614)
		(end 233.585258 -110.830614)
		(width 0.14224)
		(layer "In11.Cu")
		(net "M_F_DQ<22>")
	)
	(segment
		(start 221.3102 -131.202938)
		(end 221.51594 -131.408678)
		(width 0.14224)
		(layer "In11.Cu")
		(net "M_F_DQ<22>")
	)
	(segment
		(start 234.579922 -109.522006)
		(end 234.292394 -109.522006)
		(width 0.14224)
		(layer "In11.Cu")
		(net "M_F_DQ<22>")
	)
	(segment
		(start 221.61754 -139.01674)
		(end 221.61754 -139.460478)
		(width 0.14224)
		(layer "In11.Cu")
		(net "M_F_DQ<22>")
	)
	(segment
		(start 221.6404 -144.045178)
		(end 221.294198 -144.39138)
		(width 0.14224)
		(layer "In11.Cu")
		(net "M_F_DQ<22>")
	)
	(segment
		(start 239.057434 -98.58629)
		(end 239.024668 -98.58629)
		(width 0.0889)
		(layer "In11.Cu")
		(net "M_F_DQ<22>")
	)
	(segment
		(start 221.606872 -146.134328)
		(end 221.361 -146.3802)
		(width 0.14224)
		(layer "In11.Cu")
		(net "M_F_DQ<22>")
	)
	(segment
		(start 220.88094 -149.671278)
		(end 220.88094 -150.645368)
		(width 0.14224)
		(layer "In11.Cu")
		(net "M_F_DQ<22>")
	)
	(segment
		(start 221.294198 -145.534126)
		(end 221.606872 -145.8468)
		(width 0.14224)
		(layer "In11.Cu")
		(net "M_F_DQ<22>")
	)
	(segment
		(start 233.216958 -110.749842)
		(end 221.9198 -122.047)
		(width 0.14224)
		(layer "In11.Cu")
		(net "M_F_DQ<22>")
	)
	(segment
		(start 221.51594 -131.408678)
		(end 221.51594 -134.579868)
		(width 0.14224)
		(layer "In11.Cu")
		(net "M_F_DQ<22>")
	)
	(segment
		(start 234.003088 -110.09884)
		(end 234.16006 -110.255812)
		(width 0.14224)
		(layer "In11.Cu")
		(net "M_F_DQ<22>")
	)
	(segment
		(start 221.6658 -136.652)
		(end 221.4118 -136.906)
		(width 0.14224)
		(layer "In11.Cu")
		(net "M_F_DQ<22>")
	)
	(segment
		(start 234.16006 -110.255812)
		(end 234.16006 -110.54334)
		(width 0.14224)
		(layer "In11.Cu")
		(net "M_F_DQ<22>")
	)
	(segment
		(start 245.95074 -93.82379)
		(end 245.89613 -93.82379)
		(width 0.0889)
		(layer "In11.Cu")
		(net "M_F_DQ<22>")
	)
	(arc
		(start 238.534448 -100.862638)
		(mid 238.455226 -101.151756)
		(end 238.528098 -101.44252)
		(width 0.0889)
		(layer "In11.Cu")
		(net "M_F_DQ<22>")
	)
	(arc
		(start 238.528098 -99.882706)
		(mid 238.4553 -100.173469)
		(end 238.534448 -100.462588)
		(width 0.0889)
		(layer "In11.Cu")
		(net "M_F_DQ<22>")
	)
	(arc
		(start 241.968528 -96.900238)
		(mid 241.828449 -97.042974)
		(end 241.636804 -97.100136)
		(width 0.0889)
		(layer "In11.Cu")
		(net "M_F_DQ<22>")
	)
	(arc
		(start 243.685314 -95.909638)
		(mid 243.545235 -96.052374)
		(end 243.35359 -96.109536)
		(width 0.0889)
		(layer "In11.Cu")
		(net "M_F_DQ<22>")
	)
	(arc
		(start 242.823492 -96.41078)
		(mid 242.677526 -96.553179)
		(end 242.480338 -96.60509)
		(width 0.0889)
		(layer "In11.Cu")
		(net "M_F_DQ<22>")
	)
	(arc
		(start 238.539274 -100.471224)
		(mid 238.588029 -100.667576)
		(end 238.534448 -100.862638)
		(width 0.0889)
		(layer "In11.Cu")
		(net "M_F_DQ<22>")
	)
	(arc
		(start 239.886998 -98.090736)
		(mid 239.601574 -98.174203)
		(end 239.392968 -98.386138)
		(width 0.0889)
		(layer "In11.Cu")
		(net "M_F_DQ<22>")
	)
	(arc
		(start 244.175534 -95.61449)
		(mid 243.892317 -95.698771)
		(end 243.685314 -95.909638)
		(width 0.0889)
		(layer "In11.Cu")
		(net "M_F_DQ<22>")
	)
	(arc
		(start 244.543834 -95.014288)
		(mid 244.546582 -95.409755)
		(end 244.2083 -95.61449)
		(width 0.0889)
		(layer "In11.Cu")
		(net "M_F_DQ<22>")
	)
	(arc
		(start 242.458748 -96.60509)
		(mid 242.175531 -96.689371)
		(end 241.968528 -96.900238)
		(width 0.0889)
		(layer "In11.Cu")
		(net "M_F_DQ<22>")
	)
	(arc
		(start 239.024668 -98.58629)
		(mid 238.529191 -98.890733)
		(end 238.534448 -99.472242)
		(width 0.0889)
		(layer "In11.Cu")
		(net "M_F_DQ<22>")
	)
	(arc
		(start 241.604038 -97.100136)
		(mid 241.318614 -97.183603)
		(end 241.110008 -97.395538)
		(width 0.0889)
		(layer "In11.Cu")
		(net "M_F_DQ<22>")
	)
	(arc
		(start 240.251488 -97.890838)
		(mid 240.111409 -98.033574)
		(end 239.919764 -98.090736)
		(width 0.0889)
		(layer "In11.Cu")
		(net "M_F_DQ<22>")
	)
	(arc
		(start 239.392968 -98.386138)
		(mid 239.251285 -98.529942)
		(end 239.057434 -98.58629)
		(width 0.0889)
		(layer "In11.Cu")
		(net "M_F_DQ<22>")
	)
	(arc
		(start 244.543834 -94.805246)
		(mid 244.515773 -94.909784)
		(end 244.543834 -95.014288)
		(width 0.0889)
		(layer "In11.Cu")
		(net "M_F_DQ<22>")
	)
	(arc
		(start 241.110008 -97.395538)
		(mid 240.968325 -97.539342)
		(end 240.774474 -97.59569)
		(width 0.0889)
		(layer "In11.Cu")
		(net "M_F_DQ<22>")
	)
	(arc
		(start 240.741708 -97.59569)
		(mid 240.458491 -97.679971)
		(end 240.251488 -97.890838)
		(width 0.0889)
		(layer "In11.Cu")
		(net "M_F_DQ<22>")
	)
	(arc
		(start 245.567454 -94.023688)
		(mid 245.358846 -94.23562)
		(end 245.073424 -94.31909)
		(width 0.0889)
		(layer "In11.Cu")
		(net "M_F_DQ<22>")
	)
	(arc
		(start 245.03761 -94.31909)
		(mid 244.847681 -94.37696)
		(end 244.708934 -94.518988)
		(width 0.0889)
		(layer "In11.Cu")
		(net "M_F_DQ<22>")
	)
	(arc
		(start 245.89613 -93.82379)
		(mid 245.706201 -93.88166)
		(end 245.567454 -94.023688)
		(width 0.0889)
		(layer "In11.Cu")
		(net "M_F_DQ<22>")
	)
	(arc
		(start 243.320824 -96.109536)
		(mid 243.0354 -96.193003)
		(end 242.826794 -96.404938)
		(width 0.0889)
		(layer "In11.Cu")
		(net "M_F_DQ<22>")
	)
	(arc
		(start 238.534448 -99.472242)
		(mid 238.587947 -99.67214)
		(end 238.534448 -99.872038)
		(width 0.0889)
		(layer "In11.Cu")
		(net "M_F_DQ<22>")
	)
	(segment
		(start 215.0999 -152.278842)
		(end 215.0999 -153.542746)
		(width 0.1651)
		(layer "F.Cu")
		(net "M_F_DQ<21>")
	)
	(segment
		(start 244.768624 -92.24264)
		(end 244.197124 -92.24264)
		(width 0.1651)
		(layer "F.Cu")
		(net "M_F_DQ<21>")
	)
	(segment
		(start 215.100408 -152.273)
		(end 215.0999 -152.278842)
		(width 0.1651)
		(layer "F.Cu")
		(net "M_F_DQ<21>")
	)
	(via
		(at 215.0999 -153.542746)
		(size 0.508)
		(drill 0.254)
		(layers "F.Cu" "B.Cu")
		(net "M_F_DQ<21>")
	)
	(via
		(at 215.873584 -149.533356)
		(size 0.508)
		(drill 0.254)
		(layers "F.Cu" "B.Cu")
		(net "M_F_DQ<21>")
	)
	(via
		(at 244.197124 -92.24264)
		(size 0.508)
		(drill 0.254)
		(layers "F.Cu" "B.Cu")
		(net "M_F_DQ<21>")
	)
	(segment
		(start 215.949784 -147.478496)
		(end 215.950292 -147.478496)
		(width 0.1651)
		(layer "B.Cu")
		(net "M_F_DQ<21>")
	)
	(segment
		(start 215.873584 -149.533356)
		(end 215.949784 -149.457156)
		(width 0.1651)
		(layer "B.Cu")
		(net "M_F_DQ<21>")
	)
	(segment
		(start 215.949784 -149.457156)
		(end 215.949784 -147.478496)
		(width 0.1651)
		(layer "B.Cu")
		(net "M_F_DQ<21>")
	)
	(segment
		(start 216.165684 -136.180576)
		(end 216.165684 -136.648952)
		(width 0.14224)
		(layer "In11.Cu")
		(net "M_F_DQ<21>")
	)
	(segment
		(start 216.28354 -134.617968)
		(end 216.406984 -134.741412)
		(width 0.14224)
		(layer "In11.Cu")
		(net "M_F_DQ<21>")
	)
	(segment
		(start 216.5604 -146.558)
		(end 216.5604 -146.9644)
		(width 0.14224)
		(layer "In11.Cu")
		(net "M_F_DQ<21>")
	)
	(segment
		(start 233.348784 -101.261164)
		(end 233.267504 -101.384608)
		(width 0.0889)
		(layer "In11.Cu")
		(net "M_F_DQ<21>")
	)
	(segment
		(start 215.549988 -151.129746)
		(end 215.26119 -151.418544)
		(width 0.14224)
		(layer "In11.Cu")
		(net "M_F_DQ<21>")
	)
	(segment
		(start 215.499188 -152.348946)
		(end 215.26119 -152.586944)
		(width 0.14224)
		(layer "In11.Cu")
		(net "M_F_DQ<21>")
	)
	(segment
		(start 216.8652 -126.1618)
		(end 216.8652 -127.3556)
		(width 0.14224)
		(layer "In11.Cu")
		(net "M_F_DQ<21>")
	)
	(segment
		(start 215.873584 -149.533356)
		(end 215.851232 -149.533356)
		(width 0.14224)
		(layer "In11.Cu")
		(net "M_F_DQ<21>")
	)
	(segment
		(start 215.499188 -151.993854)
		(end 215.499188 -152.348946)
		(width 0.14224)
		(layer "In11.Cu")
		(net "M_F_DQ<21>")
	)
	(segment
		(start 216.22258 -143.681196)
		(end 216.22258 -144.210278)
		(width 0.14224)
		(layer "In11.Cu")
		(net "M_F_DQ<21>")
	)
	(segment
		(start 215.26119 -152.586944)
		(end 215.26119 -152.898856)
		(width 0.14224)
		(layer "In11.Cu")
		(net "M_F_DQ<21>")
	)
	(segment
		(start 215.26119 -151.755856)
		(end 215.499188 -151.993854)
		(width 0.14224)
		(layer "In11.Cu")
		(net "M_F_DQ<21>")
	)
	(segment
		(start 216.215468 -132.107432)
		(end 216.520522 -132.412486)
		(width 0.14224)
		(layer "In11.Cu")
		(net "M_F_DQ<21>")
	)
	(segment
		(start 216.25814 -149.29866)
		(end 216.023444 -149.533356)
		(width 0.14224)
		(layer "In11.Cu")
		(net "M_F_DQ<21>")
	)
	(segment
		(start 216.215468 -141.020038)
		(end 216.215468 -141.409928)
		(width 0.14224)
		(layer "In11.Cu")
		(net "M_F_DQ<21>")
	)
	(segment
		(start 215.851232 -149.533356)
		(end 215.422988 -149.9616)
		(width 0.14224)
		(layer "In11.Cu")
		(net "M_F_DQ<21>")
	)
	(segment
		(start 232.939336 -102.07498)
		(end 231.57053 -103.443786)
		(width 0.14224)
		(layer "In11.Cu")
		(net "M_F_DQ<21>")
	)
	(segment
		(start 215.422988 -150.5204)
		(end 215.549988 -150.6474)
		(width 0.14224)
		(layer "In11.Cu")
		(net "M_F_DQ<21>")
	)
	(segment
		(start 235.629958 -96.79559)
		(end 235.597192 -96.79559)
		(width 0.0889)
		(layer "In11.Cu")
		(net "M_F_DQ<21>")
	)
	(segment
		(start 215.524588 -153.162254)
		(end 215.524588 -153.390346)
		(width 0.14224)
		(layer "In11.Cu")
		(net "M_F_DQ<21>")
	)
	(segment
		(start 216.484962 -138.530838)
		(end 216.22258 -138.79322)
		(width 0.14224)
		(layer "In11.Cu")
		(net "M_F_DQ<21>")
	)
	(segment
		(start 216.41054 -144.398238)
		(end 216.41054 -145.579084)
		(width 0.14224)
		(layer "In11.Cu")
		(net "M_F_DQ<21>")
	)
	(segment
		(start 216.194132 -145.795492)
		(end 216.194132 -146.191732)
		(width 0.14224)
		(layer "In11.Cu")
		(net "M_F_DQ<21>")
	)
	(segment
		(start 216.165684 -136.648952)
		(end 216.484962 -136.96823)
		(width 0.14224)
		(layer "In11.Cu")
		(net "M_F_DQ<21>")
	)
	(segment
		(start 215.422988 -149.9616)
		(end 215.422988 -150.5204)
		(width 0.14224)
		(layer "In11.Cu")
		(net "M_F_DQ<21>")
	)
	(segment
		(start 216.406984 -134.741412)
		(end 216.406984 -135.939276)
		(width 0.14224)
		(layer "In11.Cu")
		(net "M_F_DQ<21>")
	)
	(segment
		(start 236.492288 -96.300036)
		(end 236.459522 -96.300036)
		(width 0.0889)
		(layer "In11.Cu")
		(net "M_F_DQ<21>")
	)
	(segment
		(start 215.26119 -152.898856)
		(end 215.524588 -153.162254)
		(width 0.14224)
		(layer "In11.Cu")
		(net "M_F_DQ<21>")
	)
	(segment
		(start 216.484962 -136.96823)
		(end 216.484962 -138.530838)
		(width 0.14224)
		(layer "In11.Cu")
		(net "M_F_DQ<21>")
	)
	(segment
		(start 239.922558 -94.31909)
		(end 239.886744 -94.31909)
		(width 0.0889)
		(layer "In11.Cu")
		(net "M_F_DQ<21>")
	)
	(segment
		(start 232.939336 -101.712776)
		(end 232.939336 -102.07498)
		(width 0.0889)
		(layer "In11.Cu")
		(net "M_F_DQ<21>")
	)
	(segment
		(start 216.25814 -129.894838)
		(end 216.449656 -130.086354)
		(width 0.14224)
		(layer "In11.Cu")
		(net "M_F_DQ<21>")
	)
	(segment
		(start 216.2302 -147.6248)
		(end 216.5604 -147.955)
		(width 0.14224)
		(layer "In11.Cu")
		(net "M_F_DQ<21>")
	)
	(segment
		(start 234.406948 -99.872038)
		(end 234.413298 -99.882706)
		(width 0.0889)
		(layer "In11.Cu")
		(net "M_F_DQ<21>")
	)
	(segment
		(start 243.375688 -92.337636)
		(end 243.338604 -92.337636)
		(width 0.0889)
		(layer "In11.Cu")
		(net "M_F_DQ<21>")
	)
	(segment
		(start 216.28354 -134.047484)
		(end 216.28354 -134.617968)
		(width 0.14224)
		(layer "In11.Cu")
		(net "M_F_DQ<21>")
	)
	(segment
		(start 244.197124 -92.24264)
		(end 243.3828 -92.336874)
		(width 0.0889)
		(layer "In11.Cu")
		(net "M_F_DQ<21>")
	)
	(segment
		(start 241.634772 -93.32849)
		(end 241.610642 -93.32849)
		(width 0.0889)
		(layer "In11.Cu")
		(net "M_F_DQ<21>")
	)
	(segment
		(start 233.908092 -100.75799)
		(end 233.880152 -100.75799)
		(width 0.0889)
		(layer "In11.Cu")
		(net "M_F_DQ<21>")
	)
	(segment
		(start 216.25814 -129.413)
		(end 216.25814 -129.894838)
		(width 0.14224)
		(layer "In11.Cu")
		(net "M_F_DQ<21>")
	)
	(segment
		(start 216.215468 -131.50215)
		(end 216.215468 -132.107432)
		(width 0.14224)
		(layer "In11.Cu")
		(net "M_F_DQ<21>")
	)
	(segment
		(start 216.449656 -130.086354)
		(end 216.449656 -131.267962)
		(width 0.14224)
		(layer "In11.Cu")
		(net "M_F_DQ<21>")
	)
	(segment
		(start 233.542078 -100.967032)
		(end 233.348784 -101.261164)
		(width 0.0889)
		(layer "In11.Cu")
		(net "M_F_DQ<21>")
	)
	(segment
		(start 239.059212 -94.81439)
		(end 239.031272 -94.81439)
		(width 0.0889)
		(layer "In11.Cu")
		(net "M_F_DQ<21>")
	)
	(segment
		(start 231.57053 -103.443786)
		(end 231.57053 -106.084878)
		(width 0.14224)
		(layer "In11.Cu")
		(net "M_F_DQ<21>")
	)
	(segment
		(start 216.22258 -144.210278)
		(end 216.41054 -144.398238)
		(width 0.14224)
		(layer "In11.Cu")
		(net "M_F_DQ<21>")
	)
	(segment
		(start 216.215468 -141.409928)
		(end 216.3826 -141.57706)
		(width 0.14224)
		(layer "In11.Cu")
		(net "M_F_DQ<21>")
	)
	(segment
		(start 234.766612 -97.29089)
		(end 234.742482 -97.29089)
		(width 0.0889)
		(layer "In11.Cu")
		(net "M_F_DQ<21>")
	)
	(segment
		(start 216.5604 -146.9644)
		(end 216.2302 -147.2946)
		(width 0.14224)
		(layer "In11.Cu")
		(net "M_F_DQ<21>")
	)
	(segment
		(start 215.524588 -153.390346)
		(end 215.372188 -153.542746)
		(width 0.14224)
		(layer "In11.Cu")
		(net "M_F_DQ<21>")
	)
	(segment
		(start 216.8652 -127.3556)
		(end 216.5604 -127.6604)
		(width 0.14224)
		(layer "In11.Cu")
		(net "M_F_DQ<21>")
	)
	(segment
		(start 216.22258 -138.79322)
		(end 216.22258 -139.272518)
		(width 0.14224)
		(layer "In11.Cu")
		(net "M_F_DQ<21>")
	)
	(segment
		(start 242.498118 -92.83319)
		(end 242.465352 -92.83319)
		(width 0.0889)
		(layer "In11.Cu")
		(net "M_F_DQ<21>")
	)
	(segment
		(start 216.442544 -140.792962)
		(end 216.215468 -141.020038)
		(width 0.14224)
		(layer "In11.Cu")
		(net "M_F_DQ<21>")
	)
	(segment
		(start 216.3826 -141.57706)
		(end 216.3826 -143.521176)
		(width 0.14224)
		(layer "In11.Cu")
		(net "M_F_DQ<21>")
	)
	(segment
		(start 215.26119 -151.418544)
		(end 215.26119 -151.755856)
		(width 0.14224)
		(layer "In11.Cu")
		(net "M_F_DQ<21>")
	)
	(segment
		(start 216.5604 -148.2344)
		(end 216.25814 -148.53666)
		(width 0.14224)
		(layer "In11.Cu")
		(net "M_F_DQ<21>")
	)
	(segment
		(start 216.5604 -129.11074)
		(end 216.25814 -129.413)
		(width 0.14224)
		(layer "In11.Cu")
		(net "M_F_DQ<21>")
	)
	(segment
		(start 216.22258 -139.272518)
		(end 216.442544 -139.492482)
		(width 0.14224)
		(layer "In11.Cu")
		(net "M_F_DQ<21>")
	)
	(segment
		(start 231.57053 -106.084878)
		(end 217.805 -119.850408)
		(width 0.14224)
		(layer "In11.Cu")
		(net "M_F_DQ<21>")
	)
	(segment
		(start 237.346998 -95.80499)
		(end 237.314232 -95.80499)
		(width 0.0889)
		(layer "In11.Cu")
		(net "M_F_DQ<21>")
	)
	(segment
		(start 216.520522 -133.810502)
		(end 216.28354 -134.047484)
		(width 0.14224)
		(layer "In11.Cu")
		(net "M_F_DQ<21>")
	)
	(segment
		(start 216.3826 -143.521176)
		(end 216.22258 -143.681196)
		(width 0.14224)
		(layer "In11.Cu")
		(net "M_F_DQ<21>")
	)
	(segment
		(start 217.805 -125.222)
		(end 216.8652 -126.1618)
		(width 0.14224)
		(layer "In11.Cu")
		(net "M_F_DQ<21>")
	)
	(segment
		(start 216.41054 -145.579084)
		(end 216.194132 -145.795492)
		(width 0.14224)
		(layer "In11.Cu")
		(net "M_F_DQ<21>")
	)
	(segment
		(start 216.2302 -147.2946)
		(end 216.2302 -147.6248)
		(width 0.14224)
		(layer "In11.Cu")
		(net "M_F_DQ<21>")
	)
	(segment
		(start 216.023444 -149.533356)
		(end 215.873584 -149.533356)
		(width 0.14224)
		(layer "In11.Cu")
		(net "M_F_DQ<21>")
	)
	(segment
		(start 216.520522 -132.412486)
		(end 216.520522 -133.810502)
		(width 0.14224)
		(layer "In11.Cu")
		(net "M_F_DQ<21>")
	)
	(segment
		(start 216.5604 -127.6604)
		(end 216.5604 -129.11074)
		(width 0.14224)
		(layer "In11.Cu")
		(net "M_F_DQ<21>")
	)
	(segment
		(start 242.99545 -92.531946)
		(end 242.992148 -92.537788)
		(width 0.0889)
		(layer "In11.Cu")
		(net "M_F_DQ<21>")
	)
	(segment
		(start 238.209328 -95.309436)
		(end 238.176562 -95.309436)
		(width 0.0889)
		(layer "In11.Cu")
		(net "M_F_DQ<21>")
	)
	(segment
		(start 216.442544 -139.492482)
		(end 216.442544 -140.792962)
		(width 0.14224)
		(layer "In11.Cu")
		(net "M_F_DQ<21>")
	)
	(segment
		(start 216.406984 -135.939276)
		(end 216.165684 -136.180576)
		(width 0.14224)
		(layer "In11.Cu")
		(net "M_F_DQ<21>")
	)
	(segment
		(start 233.267504 -101.384608)
		(end 232.939336 -101.712776)
		(width 0.0889)
		(layer "In11.Cu")
		(net "M_F_DQ<21>")
	)
	(segment
		(start 215.372188 -153.542746)
		(end 215.0999 -153.542746)
		(width 0.14224)
		(layer "In11.Cu")
		(net "M_F_DQ<21>")
	)
	(segment
		(start 216.194132 -146.191732)
		(end 216.5604 -146.558)
		(width 0.14224)
		(layer "In11.Cu")
		(net "M_F_DQ<21>")
	)
	(segment
		(start 216.5604 -147.955)
		(end 216.5604 -148.2344)
		(width 0.14224)
		(layer "In11.Cu")
		(net "M_F_DQ<21>")
	)
	(segment
		(start 217.805 -119.850408)
		(end 217.805 -125.222)
		(width 0.14224)
		(layer "In11.Cu")
		(net "M_F_DQ<21>")
	)
	(segment
		(start 215.549988 -150.6474)
		(end 215.549988 -151.129746)
		(width 0.14224)
		(layer "In11.Cu")
		(net "M_F_DQ<21>")
	)
	(segment
		(start 216.449656 -131.267962)
		(end 216.215468 -131.50215)
		(width 0.14224)
		(layer "In11.Cu")
		(net "M_F_DQ<21>")
	)
	(segment
		(start 243.3828 -92.336874)
		(end 243.375688 -92.337636)
		(width 0.0889)
		(layer "In11.Cu")
		(net "M_F_DQ<21>")
	)
	(segment
		(start 216.25814 -148.53666)
		(end 216.25814 -149.29866)
		(width 0.14224)
		(layer "In11.Cu")
		(net "M_F_DQ<21>")
	)
	(segment
		(start 233.548428 -100.957888)
		(end 233.542078 -100.967032)
		(width 0.0889)
		(layer "In11.Cu")
		(net "M_F_DQ<21>")
	)
	(segment
		(start 240.784888 -93.82379)
		(end 240.745264 -93.82379)
		(width 0.0889)
		(layer "In11.Cu")
		(net "M_F_DQ<21>")
	)
	(arc
		(start 236.982508 -96.004888)
		(mid 236.775504 -96.215752)
		(end 236.492288 -96.300036)
		(width 0.0889)
		(layer "In11.Cu")
		(net "M_F_DQ<21>")
	)
	(arc
		(start 234.406948 -98.481642)
		(mid 234.353449 -98.68154)
		(end 234.406948 -98.881438)
		(width 0.0889)
		(layer "In11.Cu")
		(net "M_F_DQ<21>")
	)
	(arc
		(start 237.841028 -95.509588)
		(mid 237.63242 -95.72152)
		(end 237.346998 -95.80499)
		(width 0.0889)
		(layer "In11.Cu")
		(net "M_F_DQ<21>")
	)
	(arc
		(start 241.275108 -93.528642)
		(mid 241.068104 -93.739506)
		(end 240.784888 -93.82379)
		(width 0.0889)
		(layer "In11.Cu")
		(net "M_F_DQ<21>")
	)
	(arc
		(start 234.406948 -99.472242)
		(mid 234.353449 -99.67214)
		(end 234.406948 -99.872038)
		(width 0.0889)
		(layer "In11.Cu")
		(net "M_F_DQ<21>")
	)
	(arc
		(start 234.406948 -98.881438)
		(mid 234.486079 -99.17684)
		(end 234.406948 -99.472242)
		(width 0.0889)
		(layer "In11.Cu")
		(net "M_F_DQ<21>")
	)
	(arc
		(start 236.123988 -96.500188)
		(mid 235.91538 -96.71212)
		(end 235.629958 -96.79559)
		(width 0.0889)
		(layer "In11.Cu")
		(net "M_F_DQ<21>")
	)
	(arc
		(start 240.416588 -94.023688)
		(mid 240.20798 -94.23562)
		(end 239.922558 -94.31909)
		(width 0.0889)
		(layer "In11.Cu")
		(net "M_F_DQ<21>")
	)
	(arc
		(start 242.133628 -93.033088)
		(mid 241.922915 -93.246167)
		(end 241.634772 -93.32849)
		(width 0.0889)
		(layer "In11.Cu")
		(net "M_F_DQ<21>")
	)
	(arc
		(start 238.699548 -95.014288)
		(mid 238.492544 -95.225152)
		(end 238.209328 -95.309436)
		(width 0.0889)
		(layer "In11.Cu")
		(net "M_F_DQ<21>")
	)
	(arc
		(start 242.992148 -92.537788)
		(mid 242.78354 -92.74972)
		(end 242.498118 -92.83319)
		(width 0.0889)
		(layer "In11.Cu")
		(net "M_F_DQ<21>")
	)
	(arc
		(start 239.558068 -94.518988)
		(mid 239.347355 -94.732067)
		(end 239.059212 -94.81439)
		(width 0.0889)
		(layer "In11.Cu")
		(net "M_F_DQ<21>")
	)
	(arc
		(start 235.265468 -96.995488)
		(mid 235.054755 -97.208567)
		(end 234.766612 -97.29089)
		(width 0.0889)
		(layer "In11.Cu")
		(net "M_F_DQ<21>")
	)
	(arc
		(start 243.338604 -92.337636)
		(mid 243.141443 -92.389595)
		(end 242.99545 -92.531946)
		(width 0.0889)
		(layer "In11.Cu")
		(net "M_F_DQ<21>")
	)
	(arc
		(start 239.886744 -94.31909)
		(mid 239.696815 -94.37696)
		(end 239.558068 -94.518988)
		(width 0.0889)
		(layer "In11.Cu")
		(net "M_F_DQ<21>")
	)
	(arc
		(start 234.406948 -97.890838)
		(mid 234.486079 -98.18624)
		(end 234.406948 -98.481642)
		(width 0.0889)
		(layer "In11.Cu")
		(net "M_F_DQ<21>")
	)
	(arc
		(start 242.465352 -92.83319)
		(mid 242.27371 -92.890356)
		(end 242.133628 -93.033088)
		(width 0.0889)
		(layer "In11.Cu")
		(net "M_F_DQ<21>")
	)
	(arc
		(start 236.459522 -96.300036)
		(mid 236.265672 -96.356386)
		(end 236.123988 -96.500188)
		(width 0.0889)
		(layer "In11.Cu")
		(net "M_F_DQ<21>")
	)
	(arc
		(start 235.597192 -96.79559)
		(mid 235.40555 -96.852756)
		(end 235.265468 -96.995488)
		(width 0.0889)
		(layer "In11.Cu")
		(net "M_F_DQ<21>")
	)
	(arc
		(start 234.742482 -97.29089)
		(mid 234.404367 -97.495592)
		(end 234.406948 -97.890838)
		(width 0.0889)
		(layer "In11.Cu")
		(net "M_F_DQ<21>")
	)
	(arc
		(start 239.031272 -94.81439)
		(mid 238.83963 -94.871556)
		(end 238.699548 -95.014288)
		(width 0.0889)
		(layer "In11.Cu")
		(net "M_F_DQ<21>")
	)
	(arc
		(start 234.413298 -99.882706)
		(mid 234.407121 -100.462638)
		(end 233.908092 -100.75799)
		(width 0.0889)
		(layer "In11.Cu")
		(net "M_F_DQ<21>")
	)
	(arc
		(start 240.745264 -93.82379)
		(mid 240.555335 -93.88166)
		(end 240.416588 -94.023688)
		(width 0.0889)
		(layer "In11.Cu")
		(net "M_F_DQ<21>")
	)
	(arc
		(start 233.880152 -100.75799)
		(mid 233.68851 -100.815156)
		(end 233.548428 -100.957888)
		(width 0.0889)
		(layer "In11.Cu")
		(net "M_F_DQ<21>")
	)
	(arc
		(start 241.610642 -93.32849)
		(mid 241.416792 -93.38484)
		(end 241.275108 -93.528642)
		(width 0.0889)
		(layer "In11.Cu")
		(net "M_F_DQ<21>")
	)
	(arc
		(start 238.176562 -95.309436)
		(mid 237.982712 -95.365786)
		(end 237.841028 -95.509588)
		(width 0.0889)
		(layer "In11.Cu")
		(net "M_F_DQ<21>")
	)
	(arc
		(start 237.314232 -95.80499)
		(mid 237.12259 -95.862156)
		(end 236.982508 -96.004888)
		(width 0.0889)
		(layer "In11.Cu")
		(net "M_F_DQ<21>")
	)
	(segment
		(start 215.949784 -155.547568)
		(end 215.85174 -155.0162)
		(width 0.1651)
		(layer "F.Cu")
		(net "M_F_DQ<20>")
	)
	(segment
		(start 215.950292 -156.87294)
		(end 215.949784 -156.87294)
		(width 0.1651)
		(layer "F.Cu")
		(net "M_F_DQ<20>")
	)
	(segment
		(start 215.949784 -156.87294)
		(end 215.949784 -155.547568)
		(width 0.1651)
		(layer "F.Cu")
		(net "M_F_DQ<20>")
	)
	(segment
		(start 245.627144 -91.747086)
		(end 245.055644 -91.747086)
		(width 0.1651)
		(layer "F.Cu")
		(net "M_F_DQ<20>")
	)
	(via
		(at 215.0999 -150.814278)
		(size 0.508)
		(drill 0.254)
		(layers "F.Cu" "B.Cu")
		(net "M_F_DQ<20>")
	)
	(via
		(at 245.055644 -91.747086)
		(size 0.508)
		(drill 0.254)
		(layers "F.Cu" "B.Cu")
		(net "M_F_DQ<20>")
	)
	(via
		(at 215.85174 -155.0162)
		(size 0.508)
		(drill 0.254)
		(layers "F.Cu" "B.Cu")
		(net "M_F_DQ<20>")
	)
	(segment
		(start 215.0999 -152.078182)
		(end 215.0999 -150.814278)
		(width 0.1651)
		(layer "B.Cu")
		(net "M_F_DQ<20>")
	)
	(segment
		(start 215.100408 -152.078436)
		(end 215.0999 -152.078182)
		(width 0.1651)
		(layer "B.Cu")
		(net "M_F_DQ<20>")
	)
	(segment
		(start 235.623354 -96.60509)
		(end 235.590588 -96.60509)
		(width 0.0889)
		(layer "In11.Cu")
		(net "M_F_DQ<20>")
	)
	(segment
		(start 215.58504 -148.50364)
		(end 215.58504 -148.960078)
		(width 0.14224)
		(layer "In11.Cu")
		(net "M_F_DQ<20>")
	)
	(segment
		(start 215.39581 -144.267936)
		(end 215.39581 -145.592038)
		(width 0.14224)
		(layer "In11.Cu")
		(net "M_F_DQ<20>")
	)
	(segment
		(start 233.383328 -100.862638)
		(end 233.1212 -101.261164)
		(width 0.0889)
		(layer "In11.Cu")
		(net "M_F_DQ<20>")
	)
	(segment
		(start 215.399874 -139.556744)
		(end 215.399874 -140.812012)
		(width 0.14224)
		(layer "In11.Cu")
		(net "M_F_DQ<20>")
	)
	(segment
		(start 215.519 -138.7348)
		(end 215.597994 -138.813794)
		(width 0.14224)
		(layer "In11.Cu")
		(net "M_F_DQ<20>")
	)
	(segment
		(start 214.99195 -150.706328)
		(end 215.0999 -150.814278)
		(width 0.14224)
		(layer "In11.Cu")
		(net "M_F_DQ<20>")
	)
	(segment
		(start 215.53805 -148.45665)
		(end 215.58504 -148.50364)
		(width 0.14224)
		(layer "In11.Cu")
		(net "M_F_DQ<20>")
	)
	(segment
		(start 216.2048 -125.857)
		(end 216.2048 -126.7968)
		(width 0.14224)
		(layer "In11.Cu")
		(net "M_F_DQ<20>")
	)
	(segment
		(start 215.559386 -143.753586)
		(end 215.594946 -143.789146)
		(width 0.14224)
		(layer "In11.Cu")
		(net "M_F_DQ<20>")
	)
	(segment
		(start 215.6206 -127.381)
		(end 215.6206 -129.744978)
		(width 0.14224)
		(layer "In11.Cu")
		(net "M_F_DQ<20>")
	)
	(segment
		(start 239.057434 -94.623636)
		(end 239.033304 -94.623636)
		(width 0.0889)
		(layer "In11.Cu")
		(net "M_F_DQ<20>")
	)
	(segment
		(start 215.559386 -140.971524)
		(end 215.559386 -143.753586)
		(width 0.14224)
		(layer "In11.Cu")
		(net "M_F_DQ<20>")
	)
	(segment
		(start 214.824818 -154.24023)
		(end 215.600788 -155.0162)
		(width 0.14224)
		(layer "In11.Cu")
		(net "M_F_DQ<20>")
	)
	(segment
		(start 215.600788 -155.0162)
		(end 215.85174 -155.0162)
		(width 0.14224)
		(layer "In11.Cu")
		(net "M_F_DQ<20>")
	)
	(segment
		(start 239.922812 -94.128336)
		(end 239.883188 -94.128336)
		(width 0.0889)
		(layer "In11.Cu")
		(net "M_F_DQ<20>")
	)
	(segment
		(start 215.576404 -136.158732)
		(end 215.576404 -136.597136)
		(width 0.14224)
		(layer "In11.Cu")
		(net "M_F_DQ<20>")
	)
	(segment
		(start 214.99195 -149.553168)
		(end 214.99195 -150.706328)
		(width 0.14224)
		(layer "In11.Cu")
		(net "M_F_DQ<20>")
	)
	(segment
		(start 215.570308 -134.112508)
		(end 215.570308 -134.517892)
		(width 0.14224)
		(layer "In11.Cu")
		(net "M_F_DQ<20>")
	)
	(segment
		(start 242.826794 -92.442538)
		(end 242.823492 -92.44838)
		(width 0.0889)
		(layer "In11.Cu")
		(net "M_F_DQ<20>")
	)
	(segment
		(start 244.233192 -91.84259)
		(end 243.86667 -91.84259)
		(width 0.0889)
		(layer "In11.Cu")
		(net "M_F_DQ<20>")
	)
	(segment
		(start 215.597994 -138.813794)
		(end 215.597994 -139.358624)
		(width 0.14224)
		(layer "In11.Cu")
		(net "M_F_DQ<20>")
	)
	(segment
		(start 233.1212 -101.261164)
		(end 233.119422 -101.263958)
		(width 0.0889)
		(layer "In11.Cu")
		(net "M_F_DQ<20>")
	)
	(segment
		(start 215.519 -131.95554)
		(end 215.519 -134.0612)
		(width 0.14224)
		(layer "In11.Cu")
		(net "M_F_DQ<20>")
	)
	(segment
		(start 238.202724 -95.118936)
		(end 238.169958 -95.118936)
		(width 0.0889)
		(layer "In11.Cu")
		(net "M_F_DQ<20>")
	)
	(segment
		(start 245.055644 -91.747086)
		(end 244.233192 -91.84259)
		(width 0.0889)
		(layer "In11.Cu")
		(net "M_F_DQ<20>")
	)
	(segment
		(start 215.576404 -136.597136)
		(end 215.519 -136.65454)
		(width 0.14224)
		(layer "In11.Cu")
		(net "M_F_DQ<20>")
	)
	(segment
		(start 215.420194 -131.231132)
		(end 215.538304 -131.349242)
		(width 0.14224)
		(layer "In11.Cu")
		(net "M_F_DQ<20>")
	)
	(segment
		(start 243.35359 -92.147136)
		(end 243.320824 -92.147136)
		(width 0.0889)
		(layer "In11.Cu")
		(net "M_F_DQ<20>")
	)
	(segment
		(start 231.09174 -103.01986)
		(end 231.09174 -105.665524)
		(width 0.14224)
		(layer "In11.Cu")
		(net "M_F_DQ<20>")
	)
	(segment
		(start 237.340394 -95.61449)
		(end 237.307628 -95.61449)
		(width 0.0889)
		(layer "In11.Cu")
		(net "M_F_DQ<20>")
	)
	(segment
		(start 215.6206 -129.744978)
		(end 215.420194 -129.945384)
		(width 0.14224)
		(layer "In11.Cu")
		(net "M_F_DQ<20>")
	)
	(segment
		(start 233.119422 -101.263958)
		(end 232.759758 -101.623622)
		(width 0.0889)
		(layer "In11.Cu")
		(net "M_F_DQ<20>")
	)
	(segment
		(start 214.824818 -153.938478)
		(end 214.824818 -154.24023)
		(width 0.14224)
		(layer "In11.Cu")
		(net "M_F_DQ<20>")
	)
	(segment
		(start 242.480338 -92.64269)
		(end 242.458748 -92.64269)
		(width 0.0889)
		(layer "In11.Cu")
		(net "M_F_DQ<20>")
	)
	(segment
		(start 215.538304 -131.936236)
		(end 215.519 -131.95554)
		(width 0.14224)
		(layer "In11.Cu")
		(net "M_F_DQ<20>")
	)
	(segment
		(start 215.0999 -150.814278)
		(end 214.66683 -151.247348)
		(width 0.14224)
		(layer "In11.Cu")
		(net "M_F_DQ<20>")
	)
	(segment
		(start 233.906314 -100.567236)
		(end 233.882184 -100.567236)
		(width 0.0889)
		(layer "In11.Cu")
		(net "M_F_DQ<20>")
	)
	(segment
		(start 232.759758 -101.623622)
		(end 232.487978 -101.623622)
		(width 0.0889)
		(layer "In11.Cu")
		(net "M_F_DQ<20>")
	)
	(segment
		(start 217.1446 -124.9172)
		(end 216.2048 -125.857)
		(width 0.14224)
		(layer "In11.Cu")
		(net "M_F_DQ<20>")
	)
	(segment
		(start 240.781332 -93.633036)
		(end 240.745518 -93.633036)
		(width 0.0889)
		(layer "In11.Cu")
		(net "M_F_DQ<20>")
	)
	(segment
		(start 214.66683 -151.247348)
		(end 214.66683 -153.78049)
		(width 0.14224)
		(layer "In11.Cu")
		(net "M_F_DQ<20>")
	)
	(segment
		(start 216.2048 -126.7968)
		(end 215.6206 -127.381)
		(width 0.14224)
		(layer "In11.Cu")
		(net "M_F_DQ<20>")
	)
	(segment
		(start 215.36914 -135.951468)
		(end 215.576404 -136.158732)
		(width 0.14224)
		(layer "In11.Cu")
		(net "M_F_DQ<20>")
	)
	(segment
		(start 215.399874 -140.812012)
		(end 215.559386 -140.971524)
		(width 0.14224)
		(layer "In11.Cu")
		(net "M_F_DQ<20>")
	)
	(segment
		(start 215.570308 -134.517892)
		(end 215.36914 -134.71906)
		(width 0.14224)
		(layer "In11.Cu")
		(net "M_F_DQ<20>")
	)
	(segment
		(start 234.235498 -99.95662)
		(end 234.241848 -99.967288)
		(width 0.0889)
		(layer "In11.Cu")
		(net "M_F_DQ<20>")
	)
	(segment
		(start 215.594946 -143.789146)
		(end 215.594946 -144.0688)
		(width 0.14224)
		(layer "In11.Cu")
		(net "M_F_DQ<20>")
	)
	(segment
		(start 232.487978 -101.623622)
		(end 231.09174 -103.01986)
		(width 0.14224)
		(layer "In11.Cu")
		(net "M_F_DQ<20>")
	)
	(segment
		(start 241.636804 -93.137736)
		(end 241.608864 -93.137736)
		(width 0.0889)
		(layer "In11.Cu")
		(net "M_F_DQ<20>")
	)
	(segment
		(start 217.1446 -119.612664)
		(end 217.1446 -124.9172)
		(width 0.14224)
		(layer "In11.Cu")
		(net "M_F_DQ<20>")
	)
	(segment
		(start 215.594946 -144.0688)
		(end 215.39581 -144.267936)
		(width 0.14224)
		(layer "In11.Cu")
		(net "M_F_DQ<20>")
	)
	(segment
		(start 215.519 -134.0612)
		(end 215.570308 -134.112508)
		(width 0.14224)
		(layer "In11.Cu")
		(net "M_F_DQ<20>")
	)
	(segment
		(start 215.538304 -131.349242)
		(end 215.538304 -131.936236)
		(width 0.14224)
		(layer "In11.Cu")
		(net "M_F_DQ<20>")
	)
	(segment
		(start 215.519 -136.65454)
		(end 215.519 -138.7348)
		(width 0.14224)
		(layer "In11.Cu")
		(net "M_F_DQ<20>")
	)
	(segment
		(start 214.66683 -153.78049)
		(end 214.824818 -153.938478)
		(width 0.14224)
		(layer "In11.Cu")
		(net "M_F_DQ<20>")
	)
	(segment
		(start 236.485684 -96.109536)
		(end 236.452918 -96.109536)
		(width 0.0889)
		(layer "In11.Cu")
		(net "M_F_DQ<20>")
	)
	(segment
		(start 215.420194 -129.945384)
		(end 215.420194 -131.231132)
		(width 0.14224)
		(layer "In11.Cu")
		(net "M_F_DQ<20>")
	)
	(segment
		(start 234.768644 -97.100136)
		(end 234.740704 -97.100136)
		(width 0.0889)
		(layer "In11.Cu")
		(net "M_F_DQ<20>")
	)
	(segment
		(start 215.597994 -139.358624)
		(end 215.399874 -139.556744)
		(width 0.14224)
		(layer "In11.Cu")
		(net "M_F_DQ<20>")
	)
	(segment
		(start 215.53805 -145.734278)
		(end 215.53805 -148.45665)
		(width 0.14224)
		(layer "In11.Cu")
		(net "M_F_DQ<20>")
	)
	(segment
		(start 215.39581 -145.592038)
		(end 215.53805 -145.734278)
		(width 0.14224)
		(layer "In11.Cu")
		(net "M_F_DQ<20>")
	)
	(segment
		(start 215.58504 -148.960078)
		(end 214.99195 -149.553168)
		(width 0.14224)
		(layer "In11.Cu")
		(net "M_F_DQ<20>")
	)
	(segment
		(start 231.09174 -105.665524)
		(end 217.1446 -119.612664)
		(width 0.14224)
		(layer "In11.Cu")
		(net "M_F_DQ<20>")
	)
	(segment
		(start 215.36914 -134.71906)
		(end 215.36914 -135.951468)
		(width 0.14224)
		(layer "In11.Cu")
		(net "M_F_DQ<20>")
	)
	(arc
		(start 235.958888 -96.404938)
		(mid 235.817205 -96.548742)
		(end 235.623354 -96.60509)
		(width 0.0889)
		(layer "In11.Cu")
		(net "M_F_DQ<20>")
	)
	(arc
		(start 236.452918 -96.109536)
		(mid 236.167494 -96.193003)
		(end 235.958888 -96.404938)
		(width 0.0889)
		(layer "In11.Cu")
		(net "M_F_DQ<20>")
	)
	(arc
		(start 239.883188 -94.128336)
		(mid 239.599971 -94.212617)
		(end 239.392968 -94.423484)
		(width 0.0889)
		(layer "In11.Cu")
		(net "M_F_DQ<20>")
	)
	(arc
		(start 234.740704 -97.100136)
		(mid 234.238695 -97.40106)
		(end 234.241848 -97.986342)
		(width 0.0889)
		(layer "In11.Cu")
		(net "M_F_DQ<20>")
	)
	(arc
		(start 236.817408 -95.909638)
		(mid 236.677329 -96.052374)
		(end 236.485684 -96.109536)
		(width 0.0889)
		(layer "In11.Cu")
		(net "M_F_DQ<20>")
	)
	(arc
		(start 233.882184 -100.567236)
		(mid 233.594039 -100.649555)
		(end 233.383328 -100.862638)
		(width 0.0889)
		(layer "In11.Cu")
		(net "M_F_DQ<20>")
	)
	(arc
		(start 235.100368 -96.900238)
		(mid 234.960289 -97.042974)
		(end 234.768644 -97.100136)
		(width 0.0889)
		(layer "In11.Cu")
		(net "M_F_DQ<20>")
	)
	(arc
		(start 240.251488 -93.928438)
		(mid 240.112744 -94.070471)
		(end 239.922812 -94.128336)
		(width 0.0889)
		(layer "In11.Cu")
		(net "M_F_DQ<20>")
	)
	(arc
		(start 238.534448 -94.919038)
		(mid 238.394369 -95.061774)
		(end 238.202724 -95.118936)
		(width 0.0889)
		(layer "In11.Cu")
		(net "M_F_DQ<20>")
	)
	(arc
		(start 239.392968 -94.423484)
		(mid 239.251285 -94.567288)
		(end 239.057434 -94.623636)
		(width 0.0889)
		(layer "In11.Cu")
		(net "M_F_DQ<20>")
	)
	(arc
		(start 234.241848 -98.386138)
		(mid 234.162717 -98.68154)
		(end 234.241848 -98.976942)
		(width 0.0889)
		(layer "In11.Cu")
		(net "M_F_DQ<20>")
	)
	(arc
		(start 242.458748 -92.64269)
		(mid 242.175531 -92.726971)
		(end 241.968528 -92.937838)
		(width 0.0889)
		(layer "In11.Cu")
		(net "M_F_DQ<20>")
	)
	(arc
		(start 241.110008 -93.433138)
		(mid 240.971264 -93.575171)
		(end 240.781332 -93.633036)
		(width 0.0889)
		(layer "In11.Cu")
		(net "M_F_DQ<20>")
	)
	(arc
		(start 241.968528 -92.937838)
		(mid 241.828449 -93.080574)
		(end 241.636804 -93.137736)
		(width 0.0889)
		(layer "In11.Cu")
		(net "M_F_DQ<20>")
	)
	(arc
		(start 243.685314 -91.947238)
		(mid 243.545235 -92.089974)
		(end 243.35359 -92.147136)
		(width 0.0889)
		(layer "In11.Cu")
		(net "M_F_DQ<20>")
	)
	(arc
		(start 234.241848 -97.986342)
		(mid 234.295347 -98.18624)
		(end 234.241848 -98.386138)
		(width 0.0889)
		(layer "In11.Cu")
		(net "M_F_DQ<20>")
	)
	(arc
		(start 237.307628 -95.61449)
		(mid 237.024411 -95.698771)
		(end 236.817408 -95.909638)
		(width 0.0889)
		(layer "In11.Cu")
		(net "M_F_DQ<20>")
	)
	(arc
		(start 234.241848 -99.967288)
		(mid 234.244431 -100.362535)
		(end 233.906314 -100.567236)
		(width 0.0889)
		(layer "In11.Cu")
		(net "M_F_DQ<20>")
	)
	(arc
		(start 238.169958 -95.118936)
		(mid 237.884534 -95.202403)
		(end 237.675928 -95.414338)
		(width 0.0889)
		(layer "In11.Cu")
		(net "M_F_DQ<20>")
	)
	(arc
		(start 240.745518 -93.633036)
		(mid 240.460094 -93.716503)
		(end 240.251488 -93.928438)
		(width 0.0889)
		(layer "In11.Cu")
		(net "M_F_DQ<20>")
	)
	(arc
		(start 234.241848 -98.976942)
		(mid 234.295347 -99.17684)
		(end 234.241848 -99.376738)
		(width 0.0889)
		(layer "In11.Cu")
		(net "M_F_DQ<20>")
	)
	(arc
		(start 243.86667 -91.84259)
		(mid 243.761969 -91.870622)
		(end 243.685314 -91.947238)
		(width 0.0889)
		(layer "In11.Cu")
		(net "M_F_DQ<20>")
	)
	(arc
		(start 239.033304 -94.623636)
		(mid 238.745159 -94.705955)
		(end 238.534448 -94.919038)
		(width 0.0889)
		(layer "In11.Cu")
		(net "M_F_DQ<20>")
	)
	(arc
		(start 243.320824 -92.147136)
		(mid 243.0354 -92.230603)
		(end 242.826794 -92.442538)
		(width 0.0889)
		(layer "In11.Cu")
		(net "M_F_DQ<20>")
	)
	(arc
		(start 234.241848 -99.376738)
		(mid 234.162626 -99.665856)
		(end 234.235498 -99.95662)
		(width 0.0889)
		(layer "In11.Cu")
		(net "M_F_DQ<20>")
	)
	(arc
		(start 242.823492 -92.44838)
		(mid 242.677526 -92.590779)
		(end 242.480338 -92.64269)
		(width 0.0889)
		(layer "In11.Cu")
		(net "M_F_DQ<20>")
	)
	(arc
		(start 237.675928 -95.414338)
		(mid 237.534245 -95.558142)
		(end 237.340394 -95.61449)
		(width 0.0889)
		(layer "In11.Cu")
		(net "M_F_DQ<20>")
	)
	(arc
		(start 235.590588 -96.60509)
		(mid 235.307371 -96.689371)
		(end 235.100368 -96.900238)
		(width 0.0889)
		(layer "In11.Cu")
		(net "M_F_DQ<20>")
	)
	(arc
		(start 241.608864 -93.137736)
		(mid 241.320719 -93.220055)
		(end 241.110008 -93.433138)
		(width 0.0889)
		(layer "In11.Cu")
		(net "M_F_DQ<20>")
	)
	(segment
		(start 241.334798 -85.30844)
		(end 240.763298 -85.30844)
		(width 0.1651)
		(layer "F.Cu")
		(net "M_F_DQ<1>")
	)
	(segment
		(start 198.100442 -152.273)
		(end 198.099934 -152.278842)
		(width 0.1651)
		(layer "F.Cu")
		(net "M_F_DQ<1>")
	)
	(segment
		(start 198.099934 -152.278842)
		(end 198.099934 -153.542746)
		(width 0.1651)
		(layer "F.Cu")
		(net "M_F_DQ<1>")
	)
	(via
		(at 198.099934 -153.542746)
		(size 0.508)
		(drill 0.254)
		(layers "F.Cu" "B.Cu")
		(net "M_F_DQ<1>")
	)
	(via
		(at 198.772018 -149.533356)
		(size 0.508)
		(drill 0.254)
		(layers "F.Cu" "B.Cu")
		(net "M_F_DQ<1>")
	)
	(via
		(at 240.763298 -85.30844)
		(size 0.508)
		(drill 0.254)
		(layers "F.Cu" "B.Cu")
		(net "M_F_DQ<1>")
	)
	(segment
		(start 198.772018 -149.030182)
		(end 198.772018 -149.533356)
		(width 0.1651)
		(layer "B.Cu")
		(net "M_F_DQ<1>")
	)
	(segment
		(start 198.950326 -147.478496)
		(end 198.949818 -147.478496)
		(width 0.1651)
		(layer "B.Cu")
		(net "M_F_DQ<1>")
	)
	(segment
		(start 198.949818 -148.852382)
		(end 198.772018 -149.030182)
		(width 0.1651)
		(layer "B.Cu")
		(net "M_F_DQ<1>")
	)
	(segment
		(start 198.949818 -147.478496)
		(end 198.949818 -148.852382)
		(width 0.1651)
		(layer "B.Cu")
		(net "M_F_DQ<1>")
	)
	(segment
		(start 198.772018 -149.444456)
		(end 198.772018 -149.533356)
		(width 0.14224)
		(layer "In11.Cu")
		(net "M_F_DQ<1>")
	)
	(segment
		(start 199.35444 -114.652552)
		(end 199.2122 -114.794792)
		(width 0.14224)
		(layer "In11.Cu")
		(net "M_F_DQ<1>")
	)
	(segment
		(start 204.851 -107.518454)
		(end 204.851 -108.051854)
		(width 0.14224)
		(layer "In11.Cu")
		(net "M_F_DQ<1>")
	)
	(segment
		(start 201.0156 -114.510312)
		(end 200.87336 -114.652552)
		(width 0.14224)
		(layer "In11.Cu")
		(net "M_F_DQ<1>")
	)
	(segment
		(start 199.259952 -138.839448)
		(end 199.259952 -141.271752)
		(width 0.14224)
		(layer "In11.Cu")
		(net "M_F_DQ<1>")
	)
	(segment
		(start 198.772018 -149.533356)
		(end 198.749666 -149.533356)
		(width 0.14224)
		(layer "In11.Cu")
		(net "M_F_DQ<1>")
	)
	(segment
		(start 208.0641 -104.305354)
		(end 204.851 -107.518454)
		(width 0.14224)
		(layer "In11.Cu")
		(net "M_F_DQ<1>")
	)
	(segment
		(start 198.261224 -151.316944)
		(end 198.261224 -151.677624)
		(width 0.14224)
		(layer "In11.Cu")
		(net "M_F_DQ<1>")
	)
	(segment
		(start 204.851 -108.051854)
		(end 200.7616 -112.141254)
		(width 0.14224)
		(layer "In11.Cu")
		(net "M_F_DQ<1>")
	)
	(segment
		(start 199.2122 -117.9576)
		(end 199.2122 -126.8222)
		(width 0.14224)
		(layer "In11.Cu")
		(net "M_F_DQ<1>")
	)
	(segment
		(start 198.261224 -152.846024)
		(end 198.501 -153.0858)
		(width 0.14224)
		(layer "In11.Cu")
		(net "M_F_DQ<1>")
	)
	(segment
		(start 199.3646 -143.637)
		(end 199.259952 -143.741648)
		(width 0.14224)
		(layer "In11.Cu")
		(net "M_F_DQ<1>")
	)
	(segment
		(start 198.90232 -128.582928)
		(end 199.20966 -128.582928)
		(width 0.14224)
		(layer "In11.Cu")
		(net "M_F_DQ<1>")
	)
	(segment
		(start 214.164926 -101.8032)
		(end 208.915 -101.8032)
		(width 0.14224)
		(layer "In11.Cu")
		(net "M_F_DQ<1>")
	)
	(segment
		(start 200.7616 -112.8268)
		(end 200.5838 -113.0046)
		(width 0.14224)
		(layer "In11.Cu")
		(net "M_F_DQ<1>")
	)
	(segment
		(start 199.259952 -141.271752)
		(end 199.3646 -141.3764)
		(width 0.14224)
		(layer "In11.Cu")
		(net "M_F_DQ<1>")
	)
	(segment
		(start 199.259952 -136.572752)
		(end 199.39 -136.7028)
		(width 0.14224)
		(layer "In11.Cu")
		(net "M_F_DQ<1>")
	)
	(segment
		(start 199.3646 -148.2598)
		(end 199.259952 -148.364448)
		(width 0.14224)
		(layer "In11.Cu")
		(net "M_F_DQ<1>")
	)
	(segment
		(start 199.5932 -117.1702)
		(end 199.5932 -117.5766)
		(width 0.14224)
		(layer "In11.Cu")
		(net "M_F_DQ<1>")
	)
	(segment
		(start 199.259952 -143.741648)
		(end 199.259952 -146.2024)
		(width 0.14224)
		(layer "In11.Cu")
		(net "M_F_DQ<1>")
	)
	(segment
		(start 234.775248 -86.394036)
		(end 234.742482 -86.394036)
		(width 0.0889)
		(layer "In11.Cu")
		(net "M_F_DQ<1>")
	)
	(segment
		(start 200.87336 -114.652552)
		(end 199.35444 -114.652552)
		(width 0.14224)
		(layer "In11.Cu")
		(net "M_F_DQ<1>")
	)
	(segment
		(start 198.501 -153.0858)
		(end 198.501 -153.3906)
		(width 0.14224)
		(layer "In11.Cu")
		(net "M_F_DQ<1>")
	)
	(segment
		(start 200.87336 -114.002312)
		(end 201.0156 -114.144552)
		(width 0.14224)
		(layer "In11.Cu")
		(net "M_F_DQ<1>")
	)
	(segment
		(start 198.261224 -152.538176)
		(end 198.261224 -152.846024)
		(width 0.14224)
		(layer "In11.Cu")
		(net "M_F_DQ<1>")
	)
	(segment
		(start 217.15857 -98.081592)
		(end 217.15857 -98.809556)
		(width 0.14224)
		(layer "In11.Cu")
		(net "M_F_DQ<1>")
	)
	(segment
		(start 229.472744 -87.398606)
		(end 229.259638 -87.611712)
		(width 0.0889)
		(layer "In11.Cu")
		(net "M_F_DQ<1>")
	)
	(segment
		(start 199.2122 -126.8222)
		(end 199.3646 -126.9746)
		(width 0.14224)
		(layer "In11.Cu")
		(net "M_F_DQ<1>")
	)
	(segment
		(start 208.915 -101.8032)
		(end 208.0641 -102.6541)
		(width 0.14224)
		(layer "In11.Cu")
		(net "M_F_DQ<1>")
	)
	(segment
		(start 199.39 -138.7094)
		(end 199.259952 -138.839448)
		(width 0.14224)
		(layer "In11.Cu")
		(net "M_F_DQ<1>")
	)
	(segment
		(start 198.74738 -127.925068)
		(end 198.74738 -128.427988)
		(width 0.14224)
		(layer "In11.Cu")
		(net "M_F_DQ<1>")
	)
	(segment
		(start 198.4756 -151.892)
		(end 198.4756 -152.3238)
		(width 0.14224)
		(layer "In11.Cu")
		(net "M_F_DQ<1>")
	)
	(segment
		(start 199.259952 -134.115048)
		(end 199.259952 -136.572752)
		(width 0.14224)
		(layer "In11.Cu")
		(net "M_F_DQ<1>")
	)
	(segment
		(start 199.3646 -129.1336)
		(end 199.259952 -129.238248)
		(width 0.14224)
		(layer "In11.Cu")
		(net "M_F_DQ<1>")
	)
	(segment
		(start 198.5518 -150.621746)
		(end 198.5518 -151.026368)
		(width 0.14224)
		(layer "In11.Cu")
		(net "M_F_DQ<1>")
	)
	(segment
		(start 233.058208 -87.384636)
		(end 233.025442 -87.384636)
		(width 0.0889)
		(layer "In11.Cu")
		(net "M_F_DQ<1>")
	)
	(segment
		(start 199.3646 -146.307048)
		(end 199.3646 -148.2598)
		(width 0.14224)
		(layer "In11.Cu")
		(net "M_F_DQ<1>")
	)
	(segment
		(start 236.492288 -85.403436)
		(end 236.459522 -85.403436)
		(width 0.0889)
		(layer "In11.Cu")
		(net "M_F_DQ<1>")
	)
	(segment
		(start 237.346998 -84.90839)
		(end 237.314232 -84.90839)
		(width 0.0889)
		(layer "In11.Cu")
		(net "M_F_DQ<1>")
	)
	(segment
		(start 199.259952 -148.364448)
		(end 199.259952 -148.956522)
		(width 0.14224)
		(layer "In11.Cu")
		(net "M_F_DQ<1>")
	)
	(segment
		(start 229.259638 -87.611712)
		(end 227.62845 -87.611712)
		(width 0.14224)
		(layer "In11.Cu")
		(net "M_F_DQ<1>")
	)
	(segment
		(start 199.39 -131.9276)
		(end 199.39 -133.985)
		(width 0.14224)
		(layer "In11.Cu")
		(net "M_F_DQ<1>")
	)
	(segment
		(start 199.3646 -126.9746)
		(end 199.3646 -127.615188)
		(width 0.14224)
		(layer "In11.Cu")
		(net "M_F_DQ<1>")
	)
	(segment
		(start 200.7616 -112.141254)
		(end 200.7616 -112.8268)
		(width 0.14224)
		(layer "In11.Cu")
		(net "M_F_DQ<1>")
	)
	(segment
		(start 198.501 -153.3906)
		(end 198.348854 -153.542746)
		(width 0.14224)
		(layer "In11.Cu")
		(net "M_F_DQ<1>")
	)
	(segment
		(start 198.749666 -149.533356)
		(end 198.321422 -149.9616)
		(width 0.14224)
		(layer "In11.Cu")
		(net "M_F_DQ<1>")
	)
	(segment
		(start 217.15857 -98.809556)
		(end 214.164926 -101.8032)
		(width 0.14224)
		(layer "In11.Cu")
		(net "M_F_DQ<1>")
	)
	(segment
		(start 199.2122 -114.794792)
		(end 199.2122 -116.7892)
		(width 0.14224)
		(layer "In11.Cu")
		(net "M_F_DQ<1>")
	)
	(segment
		(start 199.4408 -113.0046)
		(end 199.2122 -113.2332)
		(width 0.14224)
		(layer "In11.Cu")
		(net "M_F_DQ<1>")
	)
	(segment
		(start 199.259952 -131.797552)
		(end 199.39 -131.9276)
		(width 0.14224)
		(layer "In11.Cu")
		(net "M_F_DQ<1>")
	)
	(segment
		(start 199.2122 -116.7892)
		(end 199.5932 -117.1702)
		(width 0.14224)
		(layer "In11.Cu")
		(net "M_F_DQ<1>")
	)
	(segment
		(start 233.912918 -86.88959)
		(end 233.880152 -86.88959)
		(width 0.0889)
		(layer "In11.Cu")
		(net "M_F_DQ<1>")
	)
	(segment
		(start 201.0156 -114.144552)
		(end 201.0156 -114.510312)
		(width 0.14224)
		(layer "In11.Cu")
		(net "M_F_DQ<1>")
	)
	(segment
		(start 199.2122 -113.2332)
		(end 199.2122 -113.860072)
		(width 0.14224)
		(layer "In11.Cu")
		(net "M_F_DQ<1>")
	)
	(segment
		(start 235.629958 -85.89899)
		(end 235.597192 -85.89899)
		(width 0.0889)
		(layer "In11.Cu")
		(net "M_F_DQ<1>")
	)
	(segment
		(start 198.348854 -153.542746)
		(end 198.099934 -153.542746)
		(width 0.14224)
		(layer "In11.Cu")
		(net "M_F_DQ<1>")
	)
	(segment
		(start 240.268252 -84.642452)
		(end 240.251488 -84.612988)
		(width 0.0889)
		(layer "In11.Cu")
		(net "M_F_DQ<1>")
	)
	(segment
		(start 199.2122 -113.860072)
		(end 199.35444 -114.002312)
		(width 0.14224)
		(layer "In11.Cu")
		(net "M_F_DQ<1>")
	)
	(segment
		(start 238.209328 -84.412836)
		(end 238.176562 -84.412836)
		(width 0.0889)
		(layer "In11.Cu")
		(net "M_F_DQ<1>")
	)
	(segment
		(start 199.39 -133.985)
		(end 199.259952 -134.115048)
		(width 0.14224)
		(layer "In11.Cu")
		(net "M_F_DQ<1>")
	)
	(segment
		(start 199.3646 -127.615188)
		(end 199.20966 -127.770128)
		(width 0.14224)
		(layer "In11.Cu")
		(net "M_F_DQ<1>")
	)
	(segment
		(start 231.645968 -87.88019)
		(end 231.164384 -87.398606)
		(width 0.0889)
		(layer "In11.Cu")
		(net "M_F_DQ<1>")
	)
	(segment
		(start 199.20966 -128.582928)
		(end 199.3646 -128.737868)
		(width 0.14224)
		(layer "In11.Cu")
		(net "M_F_DQ<1>")
	)
	(segment
		(start 199.259952 -148.956522)
		(end 198.772018 -149.444456)
		(width 0.14224)
		(layer "In11.Cu")
		(net "M_F_DQ<1>")
	)
	(segment
		(start 200.5838 -113.0046)
		(end 199.4408 -113.0046)
		(width 0.14224)
		(layer "In11.Cu")
		(net "M_F_DQ<1>")
	)
	(segment
		(start 198.4756 -152.3238)
		(end 198.261224 -152.538176)
		(width 0.14224)
		(layer "In11.Cu")
		(net "M_F_DQ<1>")
	)
	(segment
		(start 199.3646 -141.3764)
		(end 199.3646 -143.637)
		(width 0.14224)
		(layer "In11.Cu")
		(net "M_F_DQ<1>")
	)
	(segment
		(start 227.62845 -87.611712)
		(end 217.15857 -98.081592)
		(width 0.14224)
		(layer "In11.Cu")
		(net "M_F_DQ<1>")
	)
	(segment
		(start 198.5518 -151.026368)
		(end 198.261224 -151.316944)
		(width 0.14224)
		(layer "In11.Cu")
		(net "M_F_DQ<1>")
	)
	(segment
		(start 239.915954 -84.412836)
		(end 239.883188 -84.412836)
		(width 0.0889)
		(layer "In11.Cu")
		(net "M_F_DQ<1>")
	)
	(segment
		(start 199.259952 -146.2024)
		(end 199.3646 -146.307048)
		(width 0.14224)
		(layer "In11.Cu")
		(net "M_F_DQ<1>")
	)
	(segment
		(start 199.259952 -129.238248)
		(end 199.259952 -131.797552)
		(width 0.14224)
		(layer "In11.Cu")
		(net "M_F_DQ<1>")
	)
	(segment
		(start 198.74738 -128.427988)
		(end 198.90232 -128.582928)
		(width 0.14224)
		(layer "In11.Cu")
		(net "M_F_DQ<1>")
	)
	(segment
		(start 198.321422 -150.391368)
		(end 198.5518 -150.621746)
		(width 0.14224)
		(layer "In11.Cu")
		(net "M_F_DQ<1>")
	)
	(segment
		(start 240.763298 -85.30844)
		(end 240.268252 -84.642452)
		(width 0.0889)
		(layer "In11.Cu")
		(net "M_F_DQ<1>")
	)
	(segment
		(start 208.0641 -102.6541)
		(end 208.0641 -104.305354)
		(width 0.14224)
		(layer "In11.Cu")
		(net "M_F_DQ<1>")
	)
	(segment
		(start 199.5932 -117.5766)
		(end 199.2122 -117.9576)
		(width 0.14224)
		(layer "In11.Cu")
		(net "M_F_DQ<1>")
	)
	(segment
		(start 198.261224 -151.677624)
		(end 198.4756 -151.892)
		(width 0.14224)
		(layer "In11.Cu")
		(net "M_F_DQ<1>")
	)
	(segment
		(start 198.90232 -127.770128)
		(end 198.74738 -127.925068)
		(width 0.14224)
		(layer "In11.Cu")
		(net "M_F_DQ<1>")
	)
	(segment
		(start 198.321422 -149.9616)
		(end 198.321422 -150.391368)
		(width 0.14224)
		(layer "In11.Cu")
		(net "M_F_DQ<1>")
	)
	(segment
		(start 239.061244 -83.91779)
		(end 239.031272 -83.91779)
		(width 0.0889)
		(layer "In11.Cu")
		(net "M_F_DQ<1>")
	)
	(segment
		(start 199.35444 -114.002312)
		(end 200.87336 -114.002312)
		(width 0.14224)
		(layer "In11.Cu")
		(net "M_F_DQ<1>")
	)
	(segment
		(start 199.39 -136.7028)
		(end 199.39 -138.7094)
		(width 0.14224)
		(layer "In11.Cu")
		(net "M_F_DQ<1>")
	)
	(segment
		(start 199.3646 -128.737868)
		(end 199.3646 -129.1336)
		(width 0.14224)
		(layer "In11.Cu")
		(net "M_F_DQ<1>")
	)
	(segment
		(start 232.191814 -87.88019)
		(end 231.645968 -87.88019)
		(width 0.0889)
		(layer "In11.Cu")
		(net "M_F_DQ<1>")
	)
	(segment
		(start 199.20966 -127.770128)
		(end 198.90232 -127.770128)
		(width 0.14224)
		(layer "In11.Cu")
		(net "M_F_DQ<1>")
	)
	(segment
		(start 231.164384 -87.398606)
		(end 229.472744 -87.398606)
		(width 0.0889)
		(layer "In11.Cu")
		(net "M_F_DQ<1>")
	)
	(arc
		(start 236.982508 -85.108288)
		(mid 236.775504 -85.319152)
		(end 236.492288 -85.403436)
		(width 0.0889)
		(layer "In11.Cu")
		(net "M_F_DQ<1>")
	)
	(arc
		(start 234.742482 -86.394036)
		(mid 234.548632 -86.450386)
		(end 234.406948 -86.594188)
		(width 0.0889)
		(layer "In11.Cu")
		(net "M_F_DQ<1>")
	)
	(arc
		(start 237.841028 -84.612988)
		(mid 237.63242 -84.82492)
		(end 237.346998 -84.90839)
		(width 0.0889)
		(layer "In11.Cu")
		(net "M_F_DQ<1>")
	)
	(arc
		(start 234.406948 -86.594188)
		(mid 234.19834 -86.80612)
		(end 233.912918 -86.88959)
		(width 0.0889)
		(layer "In11.Cu")
		(net "M_F_DQ<1>")
	)
	(arc
		(start 233.025442 -87.384636)
		(mid 232.831592 -87.440986)
		(end 232.689908 -87.584788)
		(width 0.0889)
		(layer "In11.Cu")
		(net "M_F_DQ<1>")
	)
	(arc
		(start 236.459522 -85.403436)
		(mid 236.265672 -85.459786)
		(end 236.123988 -85.603588)
		(width 0.0889)
		(layer "In11.Cu")
		(net "M_F_DQ<1>")
	)
	(arc
		(start 239.883188 -84.412836)
		(mid 239.599971 -84.328555)
		(end 239.392968 -84.117688)
		(width 0.0889)
		(layer "In11.Cu")
		(net "M_F_DQ<1>")
	)
	(arc
		(start 238.699548 -84.117688)
		(mid 238.492544 -84.328552)
		(end 238.209328 -84.412836)
		(width 0.0889)
		(layer "In11.Cu")
		(net "M_F_DQ<1>")
	)
	(arc
		(start 233.548428 -87.089488)
		(mid 233.341424 -87.300352)
		(end 233.058208 -87.384636)
		(width 0.0889)
		(layer "In11.Cu")
		(net "M_F_DQ<1>")
	)
	(arc
		(start 232.689908 -87.584788)
		(mid 232.479555 -87.79776)
		(end 232.191814 -87.88019)
		(width 0.0889)
		(layer "In11.Cu")
		(net "M_F_DQ<1>")
	)
	(arc
		(start 237.314232 -84.90839)
		(mid 237.12259 -84.965556)
		(end 236.982508 -85.108288)
		(width 0.0889)
		(layer "In11.Cu")
		(net "M_F_DQ<1>")
	)
	(arc
		(start 239.031272 -83.91779)
		(mid 238.83963 -83.974956)
		(end 238.699548 -84.117688)
		(width 0.0889)
		(layer "In11.Cu")
		(net "M_F_DQ<1>")
	)
	(arc
		(start 233.880152 -86.88959)
		(mid 233.68851 -86.946756)
		(end 233.548428 -87.089488)
		(width 0.0889)
		(layer "In11.Cu")
		(net "M_F_DQ<1>")
	)
	(arc
		(start 236.123988 -85.603588)
		(mid 235.91538 -85.81552)
		(end 235.629958 -85.89899)
		(width 0.0889)
		(layer "In11.Cu")
		(net "M_F_DQ<1>")
	)
	(arc
		(start 235.597192 -85.89899)
		(mid 235.40555 -85.956156)
		(end 235.265468 -86.098888)
		(width 0.0889)
		(layer "In11.Cu")
		(net "M_F_DQ<1>")
	)
	(arc
		(start 238.176562 -84.412836)
		(mid 237.982712 -84.469186)
		(end 237.841028 -84.612988)
		(width 0.0889)
		(layer "In11.Cu")
		(net "M_F_DQ<1>")
	)
	(arc
		(start 240.251488 -84.612988)
		(mid 240.109805 -84.469184)
		(end 239.915954 -84.412836)
		(width 0.0889)
		(layer "In11.Cu")
		(net "M_F_DQ<1>")
	)
	(arc
		(start 239.392968 -84.117688)
		(mid 239.252889 -83.974952)
		(end 239.061244 -83.91779)
		(width 0.0889)
		(layer "In11.Cu")
		(net "M_F_DQ<1>")
	)
	(arc
		(start 235.265468 -86.098888)
		(mid 235.058464 -86.309752)
		(end 234.775248 -86.394036)
		(width 0.0889)
		(layer "In11.Cu")
		(net "M_F_DQ<1>")
	)
	(segment
		(start 222.75038 -152.273)
		(end 222.749872 -152.278842)
		(width 0.1651)
		(layer "F.Cu")
		(net "M_F_DQ<19>")
	)
	(segment
		(start 222.749872 -152.278842)
		(end 222.749872 -153.542746)
		(width 0.1651)
		(layer "F.Cu")
		(net "M_F_DQ<19>")
	)
	(segment
		(start 246.485664 -95.21444)
		(end 245.914164 -95.21444)
		(width 0.1651)
		(layer "F.Cu")
		(net "M_F_DQ<19>")
	)
	(via
		(at 222.749872 -153.542746)
		(size 0.508)
		(drill 0.254)
		(layers "F.Cu" "B.Cu")
		(net "M_F_DQ<19>")
	)
	(via
		(at 245.914164 -95.21444)
		(size 0.508)
		(drill 0.254)
		(layers "F.Cu" "B.Cu")
		(net "M_F_DQ<19>")
	)
	(via
		(at 223.599756 -149.533356)
		(size 0.508)
		(drill 0.254)
		(layers "F.Cu" "B.Cu")
		(net "M_F_DQ<19>")
	)
	(segment
		(start 223.600518 -149.532594)
		(end 223.599756 -149.533356)
		(width 0.1651)
		(layer "B.Cu")
		(net "M_F_DQ<19>")
	)
	(segment
		(start 223.600518 -147.478496)
		(end 223.600518 -149.532594)
		(width 0.1651)
		(layer "B.Cu")
		(net "M_F_DQ<19>")
	)
	(segment
		(start 224.10674 -130.113278)
		(end 224.10674 -131.268978)
		(width 0.14224)
		(layer "In11.Cu")
		(net "M_F_DQ<19>")
	)
	(segment
		(start 223.92894 -146.1516)
		(end 224.028 -146.25066)
		(width 0.14224)
		(layer "In11.Cu")
		(net "M_F_DQ<19>")
	)
	(segment
		(start 223.7994 -127.0254)
		(end 224.0534 -127.2794)
		(width 0.14224)
		(layer "In11.Cu")
		(net "M_F_DQ<19>")
	)
	(segment
		(start 244.214904 -96.79559)
		(end 244.182138 -96.79559)
		(width 0.0889)
		(layer "In11.Cu")
		(net "M_F_DQ<19>")
	)
	(segment
		(start 223.92894 -149.21738)
		(end 223.599756 -149.546564)
		(width 0.14224)
		(layer "In11.Cu")
		(net "M_F_DQ<19>")
	)
	(segment
		(start 241.643408 -98.281236)
		(end 241.610642 -98.281236)
		(width 0.0889)
		(layer "In11.Cu")
		(net "M_F_DQ<19>")
	)
	(segment
		(start 235.518452 -112.817148)
		(end 235.518452 -113.104676)
		(width 0.14224)
		(layer "In11.Cu")
		(net "M_F_DQ<19>")
	)
	(segment
		(start 224.18294 -144.398238)
		(end 224.18294 -145.59026)
		(width 0.14224)
		(layer "In11.Cu")
		(net "M_F_DQ<19>")
	)
	(segment
		(start 236.03839 -113.899696)
		(end 235.751116 -114.18697)
		(width 0.14224)
		(layer "In11.Cu")
		(net "M_F_DQ<19>")
	)
	(segment
		(start 245.584218 -95.976186)
		(end 245.567454 -96.004888)
		(width 0.0889)
		(layer "In11.Cu")
		(net "M_F_DQ<19>")
	)
	(segment
		(start 236.453426 -112.890046)
		(end 236.093254 -112.529874)
		(width 0.14224)
		(layer "In11.Cu")
		(net "M_F_DQ<19>")
	)
	(segment
		(start 237.617 -106.538522)
		(end 237.617 -112.014)
		(width 0.14224)
		(layer "In11.Cu")
		(net "M_F_DQ<19>")
	)
	(segment
		(start 223.95434 -139.562078)
		(end 224.10674 -139.714478)
		(width 0.14224)
		(layer "In11.Cu")
		(net "M_F_DQ<19>")
	)
	(segment
		(start 223.92894 -145.84426)
		(end 223.92894 -146.1516)
		(width 0.14224)
		(layer "In11.Cu")
		(net "M_F_DQ<19>")
	)
	(segment
		(start 233.72572 -116.23802)
		(end 233.438446 -116.525294)
		(width 0.14224)
		(layer "In11.Cu")
		(net "M_F_DQ<19>")
	)
	(segment
		(start 224.028 -137.287)
		(end 223.8248 -137.4902)
		(width 0.14224)
		(layer "In11.Cu")
		(net "M_F_DQ<19>")
	)
	(segment
		(start 235.451142 -114.18697)
		(end 234.94365 -113.679478)
		(width 0.14224)
		(layer "In11.Cu")
		(net "M_F_DQ<19>")
	)
	(segment
		(start 223.02216 -153.542746)
		(end 222.749872 -153.542746)
		(width 0.14224)
		(layer "In11.Cu")
		(net "M_F_DQ<19>")
	)
	(segment
		(start 223.96704 -144.182338)
		(end 224.18294 -144.398238)
		(width 0.14224)
		(layer "In11.Cu")
		(net "M_F_DQ<19>")
	)
	(segment
		(start 240.540286 -101.580188)
		(end 240.540286 -103.465884)
		(width 0.0889)
		(layer "In11.Cu")
		(net "M_F_DQ<19>")
	)
	(segment
		(start 223.19996 -153.364946)
		(end 223.02216 -153.542746)
		(width 0.14224)
		(layer "In11.Cu")
		(net "M_F_DQ<19>")
	)
	(segment
		(start 224.028 -136.59866)
		(end 224.028 -137.287)
		(width 0.14224)
		(layer "In11.Cu")
		(net "M_F_DQ<19>")
	)
	(segment
		(start 233.120438 -116.525294)
		(end 232.609136 -116.013992)
		(width 0.14224)
		(layer "In11.Cu")
		(net "M_F_DQ<19>")
	)
	(segment
		(start 223.95434 -136.19226)
		(end 223.95434 -136.525)
		(width 0.14224)
		(layer "In11.Cu")
		(net "M_F_DQ<19>")
	)
	(segment
		(start 240.540286 -103.465884)
		(end 238.322866 -105.683304)
		(width 0.0889)
		(layer "In11.Cu")
		(net "M_F_DQ<19>")
	)
	(segment
		(start 223.96704 -131.408678)
		(end 223.96704 -131.8768)
		(width 0.14224)
		(layer "In11.Cu")
		(net "M_F_DQ<19>")
	)
	(segment
		(start 238.322866 -105.683304)
		(end 238.322866 -105.832656)
		(width 0.0889)
		(layer "In11.Cu")
		(net "M_F_DQ<19>")
	)
	(segment
		(start 223.95434 -129.33426)
		(end 223.95434 -129.960878)
		(width 0.14224)
		(layer "In11.Cu")
		(net "M_F_DQ<19>")
	)
	(segment
		(start 223.95434 -136.525)
		(end 224.028 -136.59866)
		(width 0.14224)
		(layer "In11.Cu")
		(net "M_F_DQ<19>")
	)
	(segment
		(start 223.8248 -138.0744)
		(end 224.028 -138.2776)
		(width 0.14224)
		(layer "In11.Cu")
		(net "M_F_DQ<19>")
	)
	(segment
		(start 235.805726 -112.529874)
		(end 235.518452 -112.817148)
		(width 0.14224)
		(layer "In11.Cu")
		(net "M_F_DQ<19>")
	)
	(segment
		(start 223.96704 -131.8768)
		(end 224.028 -131.93776)
		(width 0.14224)
		(layer "In11.Cu")
		(net "M_F_DQ<19>")
	)
	(segment
		(start 233.183938 -115.43919)
		(end 233.72572 -115.980972)
		(width 0.14224)
		(layer "In11.Cu")
		(net "M_F_DQ<19>")
	)
	(segment
		(start 224.10674 -140.870178)
		(end 223.96704 -141.009878)
		(width 0.14224)
		(layer "In11.Cu")
		(net "M_F_DQ<19>")
	)
	(segment
		(start 223.96704 -141.4526)
		(end 224.028 -141.51356)
		(width 0.14224)
		(layer "In11.Cu")
		(net "M_F_DQ<19>")
	)
	(segment
		(start 224.028 -141.51356)
		(end 224.028 -143.637)
		(width 0.14224)
		(layer "In11.Cu")
		(net "M_F_DQ<19>")
	)
	(segment
		(start 234.950254 -114.835686)
		(end 234.950254 -115.110768)
		(width 0.14224)
		(layer "In11.Cu")
		(net "M_F_DQ<19>")
	)
	(segment
		(start 242.498118 -97.78619)
		(end 242.465352 -97.78619)
		(width 0.0889)
		(layer "In11.Cu")
		(net "M_F_DQ<19>")
	)
	(segment
		(start 223.19996 -153.04135)
		(end 223.19996 -153.364946)
		(width 0.14224)
		(layer "In11.Cu")
		(net "M_F_DQ<19>")
	)
	(segment
		(start 232.609136 -116.013992)
		(end 232.321608 -116.013992)
		(width 0.14224)
		(layer "In11.Cu")
		(net "M_F_DQ<19>")
	)
	(segment
		(start 245.077234 -96.300036)
		(end 245.044468 -96.300036)
		(width 0.0889)
		(layer "In11.Cu")
		(net "M_F_DQ<19>")
	)
	(segment
		(start 234.950254 -115.110768)
		(end 234.66298 -115.398042)
		(width 0.14224)
		(layer "In11.Cu")
		(net "M_F_DQ<19>")
	)
	(segment
		(start 223.96704 -134.573264)
		(end 224.13214 -134.738364)
		(width 0.14224)
		(layer "In11.Cu")
		(net "M_F_DQ<19>")
	)
	(segment
		(start 234.656122 -113.679478)
		(end 234.368848 -113.966752)
		(width 0.14224)
		(layer "In11.Cu")
		(net "M_F_DQ<19>")
	)
	(segment
		(start 242.99545 -97.484946)
		(end 242.992148 -97.490788)
		(width 0.0889)
		(layer "In11.Cu")
		(net "M_F_DQ<19>")
	)
	(segment
		(start 233.72572 -115.980972)
		(end 233.72572 -116.23802)
		(width 0.14224)
		(layer "In11.Cu")
		(net "M_F_DQ<19>")
	)
	(segment
		(start 224.10674 -139.714478)
		(end 224.10674 -140.870178)
		(width 0.14224)
		(layer "In11.Cu")
		(net "M_F_DQ<19>")
	)
	(segment
		(start 234.66298 -115.398042)
		(end 234.363006 -115.398042)
		(width 0.14224)
		(layer "In11.Cu")
		(net "M_F_DQ<19>")
	)
	(segment
		(start 245.914164 -95.21444)
		(end 245.584218 -95.976186)
		(width 0.0889)
		(layer "In11.Cu")
		(net "M_F_DQ<19>")
	)
	(segment
		(start 224.0534 -127.2794)
		(end 224.0534 -129.2352)
		(width 0.14224)
		(layer "In11.Cu")
		(net "M_F_DQ<19>")
	)
	(segment
		(start 224.13214 -136.01446)
		(end 223.95434 -136.19226)
		(width 0.14224)
		(layer "In11.Cu")
		(net "M_F_DQ<19>")
	)
	(segment
		(start 233.506518 -114.829082)
		(end 233.183938 -115.151662)
		(width 0.14224)
		(layer "In11.Cu")
		(net "M_F_DQ<19>")
	)
	(segment
		(start 223.95434 -138.83386)
		(end 223.95434 -139.562078)
		(width 0.14224)
		(layer "In11.Cu")
		(net "M_F_DQ<19>")
	)
	(segment
		(start 235.751116 -114.18697)
		(end 235.451142 -114.18697)
		(width 0.14224)
		(layer "In11.Cu")
		(net "M_F_DQ<19>")
	)
	(segment
		(start 236.03839 -113.624614)
		(end 236.03839 -113.899696)
		(width 0.14224)
		(layer "In11.Cu")
		(net "M_F_DQ<19>")
	)
	(segment
		(start 224.028 -138.2776)
		(end 224.028 -138.7602)
		(width 0.14224)
		(layer "In11.Cu")
		(net "M_F_DQ<19>")
	)
	(segment
		(start 243.360194 -97.290636)
		(end 243.338604 -97.290636)
		(width 0.0889)
		(layer "In11.Cu")
		(net "M_F_DQ<19>")
	)
	(segment
		(start 233.438446 -116.525294)
		(end 233.120438 -116.525294)
		(width 0.14224)
		(layer "In11.Cu")
		(net "M_F_DQ<19>")
	)
	(segment
		(start 234.94365 -113.679478)
		(end 234.656122 -113.679478)
		(width 0.14224)
		(layer "In11.Cu")
		(net "M_F_DQ<19>")
	)
	(segment
		(start 223.14916 -150.391368)
		(end 223.19361 -150.435818)
		(width 0.14224)
		(layer "In11.Cu")
		(net "M_F_DQ<19>")
	)
	(segment
		(start 224.18294 -145.59026)
		(end 223.92894 -145.84426)
		(width 0.14224)
		(layer "In11.Cu")
		(net "M_F_DQ<19>")
	)
	(segment
		(start 233.794046 -114.829082)
		(end 233.506518 -114.829082)
		(width 0.14224)
		(layer "In11.Cu")
		(net "M_F_DQ<19>")
	)
	(segment
		(start 224.028 -131.93776)
		(end 224.028 -134.0358)
		(width 0.14224)
		(layer "In11.Cu")
		(net "M_F_DQ<19>")
	)
	(segment
		(start 223.92894 -148.53666)
		(end 223.92894 -149.21738)
		(width 0.14224)
		(layer "In11.Cu")
		(net "M_F_DQ<19>")
	)
	(segment
		(start 236.740954 -112.890046)
		(end 236.453426 -112.890046)
		(width 0.14224)
		(layer "In11.Cu")
		(net "M_F_DQ<19>")
	)
	(segment
		(start 223.599756 -149.533356)
		(end 223.577404 -149.533356)
		(width 0.14224)
		(layer "In11.Cu")
		(net "M_F_DQ<19>")
	)
	(segment
		(start 234.363006 -115.398042)
		(end 233.794046 -114.829082)
		(width 0.14224)
		(layer "In11.Cu")
		(net "M_F_DQ<19>")
	)
	(segment
		(start 223.14916 -149.9616)
		(end 223.14916 -150.391368)
		(width 0.14224)
		(layer "In11.Cu")
		(net "M_F_DQ<19>")
	)
	(segment
		(start 224.0534 -129.2352)
		(end 223.95434 -129.33426)
		(width 0.14224)
		(layer "In11.Cu")
		(net "M_F_DQ<19>")
	)
	(segment
		(start 223.8248 -137.4902)
		(end 223.8248 -138.0744)
		(width 0.14224)
		(layer "In11.Cu")
		(net "M_F_DQ<19>")
	)
	(segment
		(start 223.599756 -149.546564)
		(end 223.599756 -149.533356)
		(width 0.14224)
		(layer "In11.Cu")
		(net "M_F_DQ<19>")
	)
	(segment
		(start 235.518452 -113.104676)
		(end 236.03839 -113.624614)
		(width 0.14224)
		(layer "In11.Cu")
		(net "M_F_DQ<19>")
	)
	(segment
		(start 236.093254 -112.529874)
		(end 235.805726 -112.529874)
		(width 0.14224)
		(layer "In11.Cu")
		(net "M_F_DQ<19>")
	)
	(segment
		(start 240.781078 -98.77679)
		(end 240.748312 -98.77679)
		(width 0.0889)
		(layer "In11.Cu")
		(net "M_F_DQ<19>")
	)
	(segment
		(start 224.13214 -134.738364)
		(end 224.13214 -136.01446)
		(width 0.14224)
		(layer "In11.Cu")
		(net "M_F_DQ<19>")
	)
	(segment
		(start 222.911162 -151.387048)
		(end 222.911162 -151.660352)
		(width 0.14224)
		(layer "In11.Cu")
		(net "M_F_DQ<19>")
	)
	(segment
		(start 240.422938 -99.95662)
		(end 240.416588 -99.967288)
		(width 0.0889)
		(layer "In11.Cu")
		(net "M_F_DQ<19>")
	)
	(segment
		(start 223.96704 -141.009878)
		(end 223.96704 -141.4526)
		(width 0.14224)
		(layer "In11.Cu")
		(net "M_F_DQ<19>")
	)
	(segment
		(start 224.10674 -131.268978)
		(end 223.96704 -131.408678)
		(width 0.14224)
		(layer "In11.Cu")
		(net "M_F_DQ<19>")
	)
	(segment
		(start 224.028 -148.4376)
		(end 223.92894 -148.53666)
		(width 0.14224)
		(layer "In11.Cu")
		(net "M_F_DQ<19>")
	)
	(segment
		(start 224.028 -134.0358)
		(end 223.96704 -134.09676)
		(width 0.14224)
		(layer "In11.Cu")
		(net "M_F_DQ<19>")
	)
	(segment
		(start 230.505 -116.3066)
		(end 223.7994 -123.0122)
		(width 0.14224)
		(layer "In11.Cu")
		(net "M_F_DQ<19>")
	)
	(segment
		(start 224.028 -143.637)
		(end 223.96704 -143.69796)
		(width 0.14224)
		(layer "In11.Cu")
		(net "M_F_DQ<19>")
	)
	(segment
		(start 222.911162 -152.479248)
		(end 222.911162 -152.752552)
		(width 0.14224)
		(layer "In11.Cu")
		(net "M_F_DQ<19>")
	)
	(segment
		(start 223.96704 -134.09676)
		(end 223.96704 -134.573264)
		(width 0.14224)
		(layer "In11.Cu")
		(net "M_F_DQ<19>")
	)
	(segment
		(start 224.028 -138.7602)
		(end 223.95434 -138.83386)
		(width 0.14224)
		(layer "In11.Cu")
		(net "M_F_DQ<19>")
	)
	(segment
		(start 223.19361 -151.1046)
		(end 222.911162 -151.387048)
		(width 0.14224)
		(layer "In11.Cu")
		(net "M_F_DQ<19>")
	)
	(segment
		(start 223.16821 -151.9174)
		(end 223.16821 -152.2222)
		(width 0.14224)
		(layer "In11.Cu")
		(net "M_F_DQ<19>")
	)
	(segment
		(start 223.19361 -150.435818)
		(end 223.19361 -151.1046)
		(width 0.14224)
		(layer "In11.Cu")
		(net "M_F_DQ<19>")
	)
	(segment
		(start 237.617 -112.014)
		(end 236.740954 -112.890046)
		(width 0.14224)
		(layer "In11.Cu")
		(net "M_F_DQ<19>")
	)
	(segment
		(start 232.321608 -116.013992)
		(end 232.029 -116.3066)
		(width 0.14224)
		(layer "In11.Cu")
		(net "M_F_DQ<19>")
	)
	(segment
		(start 223.96704 -143.69796)
		(end 223.96704 -144.182338)
		(width 0.14224)
		(layer "In11.Cu")
		(net "M_F_DQ<19>")
	)
	(segment
		(start 222.911162 -152.752552)
		(end 223.19996 -153.04135)
		(width 0.14224)
		(layer "In11.Cu")
		(net "M_F_DQ<19>")
	)
	(segment
		(start 224.028 -146.25066)
		(end 224.028 -148.4376)
		(width 0.14224)
		(layer "In11.Cu")
		(net "M_F_DQ<19>")
	)
	(segment
		(start 234.368848 -113.966752)
		(end 234.368848 -114.25428)
		(width 0.14224)
		(layer "In11.Cu")
		(net "M_F_DQ<19>")
	)
	(segment
		(start 233.183938 -115.151662)
		(end 233.183938 -115.43919)
		(width 0.14224)
		(layer "In11.Cu")
		(net "M_F_DQ<19>")
	)
	(segment
		(start 223.7994 -123.0122)
		(end 223.7994 -127.0254)
		(width 0.14224)
		(layer "In11.Cu")
		(net "M_F_DQ<19>")
	)
	(segment
		(start 240.411762 -101.349302)
		(end 240.540286 -101.580188)
		(width 0.0889)
		(layer "In11.Cu")
		(net "M_F_DQ<19>")
	)
	(segment
		(start 223.16821 -152.2222)
		(end 222.911162 -152.479248)
		(width 0.14224)
		(layer "In11.Cu")
		(net "M_F_DQ<19>")
	)
	(segment
		(start 223.577404 -149.533356)
		(end 223.14916 -149.9616)
		(width 0.14224)
		(layer "In11.Cu")
		(net "M_F_DQ<19>")
	)
	(segment
		(start 238.322866 -105.832656)
		(end 237.617 -106.538522)
		(width 0.14224)
		(layer "In11.Cu")
		(net "M_F_DQ<19>")
	)
	(segment
		(start 222.911162 -151.660352)
		(end 223.16821 -151.9174)
		(width 0.14224)
		(layer "In11.Cu")
		(net "M_F_DQ<19>")
	)
	(segment
		(start 223.95434 -129.960878)
		(end 224.10674 -130.113278)
		(width 0.14224)
		(layer "In11.Cu")
		(net "M_F_DQ<19>")
	)
	(segment
		(start 240.411762 -99.368102)
		(end 240.416588 -99.376738)
		(width 0.0889)
		(layer "In11.Cu")
		(net "M_F_DQ<19>")
	)
	(segment
		(start 232.029 -116.3066)
		(end 230.505 -116.3066)
		(width 0.14224)
		(layer "In11.Cu")
		(net "M_F_DQ<19>")
	)
	(segment
		(start 234.368848 -114.25428)
		(end 234.950254 -114.835686)
		(width 0.14224)
		(layer "In11.Cu")
		(net "M_F_DQ<19>")
	)
	(arc
		(start 243.338604 -97.290636)
		(mid 243.141443 -97.342595)
		(end 242.99545 -97.484946)
		(width 0.0889)
		(layer "In11.Cu")
		(net "M_F_DQ<19>")
	)
	(arc
		(start 240.416588 -100.957888)
		(mid 240.363118 -101.152951)
		(end 240.411762 -101.349302)
		(width 0.0889)
		(layer "In11.Cu")
		(net "M_F_DQ<19>")
	)
	(arc
		(start 240.416588 -99.376738)
		(mid 240.49581 -99.665856)
		(end 240.422938 -99.95662)
		(width 0.0889)
		(layer "In11.Cu")
		(net "M_F_DQ<19>")
	)
	(arc
		(start 244.708934 -96.500188)
		(mid 244.500326 -96.71212)
		(end 244.214904 -96.79559)
		(width 0.0889)
		(layer "In11.Cu")
		(net "M_F_DQ<19>")
	)
	(arc
		(start 242.992148 -97.490788)
		(mid 242.78354 -97.70272)
		(end 242.498118 -97.78619)
		(width 0.0889)
		(layer "In11.Cu")
		(net "M_F_DQ<19>")
	)
	(arc
		(start 241.610642 -98.281236)
		(mid 241.416792 -98.337586)
		(end 241.275108 -98.481388)
		(width 0.0889)
		(layer "In11.Cu")
		(net "M_F_DQ<19>")
	)
	(arc
		(start 240.748312 -98.77679)
		(mid 240.415394 -98.978781)
		(end 240.411762 -99.368102)
		(width 0.0889)
		(layer "In11.Cu")
		(net "M_F_DQ<19>")
	)
	(arc
		(start 245.044468 -96.300036)
		(mid 244.850618 -96.356386)
		(end 244.708934 -96.500188)
		(width 0.0889)
		(layer "In11.Cu")
		(net "M_F_DQ<19>")
	)
	(arc
		(start 244.182138 -96.79559)
		(mid 243.990496 -96.852756)
		(end 243.850414 -96.995488)
		(width 0.0889)
		(layer "In11.Cu")
		(net "M_F_DQ<19>")
	)
	(arc
		(start 240.416588 -99.967288)
		(mid 240.363089 -100.167186)
		(end 240.416588 -100.367084)
		(width 0.0889)
		(layer "In11.Cu")
		(net "M_F_DQ<19>")
	)
	(arc
		(start 240.416588 -100.367084)
		(mid 240.495719 -100.662486)
		(end 240.416588 -100.957888)
		(width 0.0889)
		(layer "In11.Cu")
		(net "M_F_DQ<19>")
	)
	(arc
		(start 245.567454 -96.004888)
		(mid 245.36045 -96.215752)
		(end 245.077234 -96.300036)
		(width 0.0889)
		(layer "In11.Cu")
		(net "M_F_DQ<19>")
	)
	(arc
		(start 242.133628 -97.986088)
		(mid 241.926624 -98.196952)
		(end 241.643408 -98.281236)
		(width 0.0889)
		(layer "In11.Cu")
		(net "M_F_DQ<19>")
	)
	(arc
		(start 243.850414 -96.995488)
		(mid 243.64341 -97.206352)
		(end 243.360194 -97.290636)
		(width 0.0889)
		(layer "In11.Cu")
		(net "M_F_DQ<19>")
	)
	(arc
		(start 242.465352 -97.78619)
		(mid 242.27371 -97.843356)
		(end 242.133628 -97.986088)
		(width 0.0889)
		(layer "In11.Cu")
		(net "M_F_DQ<19>")
	)
	(arc
		(start 241.275108 -98.481388)
		(mid 241.0665 -98.69332)
		(end 240.781078 -98.77679)
		(width 0.0889)
		(layer "In11.Cu")
		(net "M_F_DQ<19>")
	)
	(segment
		(start 223.731328 -155.52674)
		(end 223.731328 -155.75026)
		(width 0.1651)
		(layer "F.Cu")
		(net "M_F_DQ<18>")
	)
	(segment
		(start 247.344184 -94.718886)
		(end 246.772684 -94.718886)
		(width 0.1651)
		(layer "F.Cu")
		(net "M_F_DQ<18>")
	)
	(segment
		(start 223.731328 -155.75026)
		(end 223.599756 -155.881832)
		(width 0.1651)
		(layer "F.Cu")
		(net "M_F_DQ<18>")
	)
	(segment
		(start 223.599756 -155.881832)
		(end 223.599756 -156.87294)
		(width 0.1651)
		(layer "F.Cu")
		(net "M_F_DQ<18>")
	)
	(segment
		(start 223.599756 -155.395168)
		(end 223.731328 -155.52674)
		(width 0.1651)
		(layer "F.Cu")
		(net "M_F_DQ<18>")
	)
	(segment
		(start 223.599756 -155.1178)
		(end 223.599756 -155.395168)
		(width 0.1651)
		(layer "F.Cu")
		(net "M_F_DQ<18>")
	)
	(segment
		(start 223.599756 -156.87294)
		(end 223.600518 -156.87294)
		(width 0.1651)
		(layer "F.Cu")
		(net "M_F_DQ<18>")
	)
	(via
		(at 222.749872 -150.814278)
		(size 0.508)
		(drill 0.254)
		(layers "F.Cu" "B.Cu")
		(net "M_F_DQ<18>")
	)
	(via
		(at 246.772684 -94.718886)
		(size 0.508)
		(drill 0.254)
		(layers "F.Cu" "B.Cu")
		(net "M_F_DQ<18>")
	)
	(via
		(at 223.599756 -155.1178)
		(size 0.508)
		(drill 0.254)
		(layers "F.Cu" "B.Cu")
		(net "M_F_DQ<18>")
	)
	(segment
		(start 222.75038 -152.078436)
		(end 222.749872 -152.078182)
		(width 0.1651)
		(layer "B.Cu")
		(net "M_F_DQ<18>")
	)
	(segment
		(start 222.749872 -152.078182)
		(end 222.749872 -150.814278)
		(width 0.1651)
		(layer "B.Cu")
		(net "M_F_DQ<18>")
	)
	(segment
		(start 241.636804 -98.090736)
		(end 241.604038 -98.090736)
		(width 0.0889)
		(layer "In11.Cu")
		(net "M_F_DQ<18>")
	)
	(segment
		(start 223.3676 -146.2532)
		(end 223.0882 -146.5326)
		(width 0.14224)
		(layer "In11.Cu")
		(net "M_F_DQ<18>")
	)
	(segment
		(start 222.316802 -153.834846)
		(end 223.599756 -155.1178)
		(width 0.14224)
		(layer "In11.Cu")
		(net "M_F_DQ<18>")
	)
	(segment
		(start 245.07063 -96.109536)
		(end 245.037864 -96.109536)
		(width 0.0889)
		(layer "In11.Cu")
		(net "M_F_DQ<18>")
	)
	(segment
		(start 236.063282 -111.57712)
		(end 235.776262 -111.57712)
		(width 0.14224)
		(layer "In11.Cu")
		(net "M_F_DQ<18>")
	)
	(segment
		(start 242.480338 -97.59569)
		(end 242.458748 -97.59569)
		(width 0.0889)
		(layer "In11.Cu")
		(net "M_F_DQ<18>")
	)
	(segment
		(start 223.11614 -139.722606)
		(end 223.11614 -140.794486)
		(width 0.14224)
		(layer "In11.Cu")
		(net "M_F_DQ<18>")
	)
	(segment
		(start 236.9566 -110.396782)
		(end 236.638084 -110.715298)
		(width 0.14224)
		(layer "In11.Cu")
		(net "M_F_DQ<18>")
	)
	(segment
		(start 223.4184 -143.5354)
		(end 223.4184 -143.994378)
		(width 0.14224)
		(layer "In11.Cu")
		(net "M_F_DQ<18>")
	)
	(segment
		(start 223.012 -134.7978)
		(end 223.012 -135.9916)
		(width 0.14224)
		(layer "In11.Cu")
		(net "M_F_DQ<18>")
	)
	(segment
		(start 223.1898 -141.8336)
		(end 223.1898 -143.3068)
		(width 0.14224)
		(layer "In11.Cu")
		(net "M_F_DQ<18>")
	)
	(segment
		(start 222.7072 -149.3774)
		(end 222.40494 -149.67966)
		(width 0.14224)
		(layer "In11.Cu")
		(net "M_F_DQ<18>")
	)
	(segment
		(start 236.638084 -110.715298)
		(end 236.638084 -111.002318)
		(width 0.14224)
		(layer "In11.Cu")
		(net "M_F_DQ<18>")
	)
	(segment
		(start 240.350294 -101.629972)
		(end 240.350294 -103.387144)
		(width 0.0889)
		(layer "In11.Cu")
		(net "M_F_DQ<18>")
	)
	(segment
		(start 223.012 -135.9916)
		(end 223.335342 -136.314942)
		(width 0.14224)
		(layer "In11.Cu")
		(net "M_F_DQ<18>")
	)
	(segment
		(start 236.406944 -111.920528)
		(end 236.063282 -111.57712)
		(width 0.14224)
		(layer "In11.Cu")
		(net "M_F_DQ<18>")
	)
	(segment
		(start 223.063054 -149.3774)
		(end 222.7072 -149.3774)
		(width 0.14224)
		(layer "In11.Cu")
		(net "M_F_DQ<18>")
	)
	(segment
		(start 222.40494 -149.67966)
		(end 222.40494 -150.469346)
		(width 0.14224)
		(layer "In11.Cu")
		(net "M_F_DQ<18>")
	)
	(segment
		(start 223.0374 -130.039618)
		(end 223.0374 -131.141978)
		(width 0.14224)
		(layer "In11.Cu")
		(net "M_F_DQ<18>")
	)
	(segment
		(start 231.581452 -114.265456)
		(end 231.581452 -114.552984)
		(width 0.14224)
		(layer "In11.Cu")
		(net "M_F_DQ<18>")
	)
	(segment
		(start 223.0882 -146.5326)
		(end 223.0882 -148.3868)
		(width 0.14224)
		(layer "In11.Cu")
		(net "M_F_DQ<18>")
	)
	(segment
		(start 237.873794 -105.383584)
		(end 236.9566 -106.300778)
		(width 0.14224)
		(layer "In11.Cu")
		(net "M_F_DQ<18>")
	)
	(segment
		(start 223.03994 -144.372838)
		(end 223.03994 -145.59534)
		(width 0.14224)
		(layer "In11.Cu")
		(net "M_F_DQ<18>")
	)
	(segment
		(start 223.3168 -149.123654)
		(end 223.063054 -149.3774)
		(width 0.14224)
		(layer "In11.Cu")
		(net "M_F_DQ<18>")
	)
	(segment
		(start 223.0374 -131.141978)
		(end 223.2152 -131.319778)
		(width 0.14224)
		(layer "In11.Cu")
		(net "M_F_DQ<18>")
	)
	(segment
		(start 245.567454 -95.014288)
		(end 245.402354 -95.300292)
		(width 0.0889)
		(layer "In11.Cu")
		(net "M_F_DQ<18>")
	)
	(segment
		(start 240.774474 -98.58629)
		(end 240.741708 -98.58629)
		(width 0.0889)
		(layer "In11.Cu")
		(net "M_F_DQ<18>")
	)
	(segment
		(start 230.719122 -115.127786)
		(end 223.217994 -122.628914)
		(width 0.14224)
		(layer "In11.Cu")
		(net "M_F_DQ<18>")
	)
	(segment
		(start 236.9566 -106.300778)
		(end 236.9566 -110.396782)
		(width 0.14224)
		(layer "In11.Cu")
		(net "M_F_DQ<18>")
	)
	(segment
		(start 245.948708 -94.81439)
		(end 245.899178 -94.81439)
		(width 0.0889)
		(layer "In11.Cu")
		(net "M_F_DQ<18>")
	)
	(segment
		(start 223.03994 -145.59534)
		(end 223.3676 -145.923)
		(width 0.14224)
		(layer "In11.Cu")
		(net "M_F_DQ<18>")
	)
	(segment
		(start 223.217994 -129.859024)
		(end 223.0374 -130.039618)
		(width 0.14224)
		(layer "In11.Cu")
		(net "M_F_DQ<18>")
	)
	(segment
		(start 222.749872 -150.814278)
		(end 222.316802 -151.247348)
		(width 0.14224)
		(layer "In11.Cu")
		(net "M_F_DQ<18>")
	)
	(segment
		(start 240.245138 -101.44252)
		(end 240.350294 -101.629972)
		(width 0.0889)
		(layer "In11.Cu")
		(net "M_F_DQ<18>")
	)
	(segment
		(start 232.06837 -115.32743)
		(end 231.781096 -115.614704)
		(width 0.14224)
		(layer "In11.Cu")
		(net "M_F_DQ<18>")
	)
	(segment
		(start 231.814878 -114.03203)
		(end 231.581452 -114.265456)
		(width 0.14224)
		(layer "In11.Cu")
		(net "M_F_DQ<18>")
	)
	(segment
		(start 223.4184 -133.9342)
		(end 223.4184 -134.3914)
		(width 0.14224)
		(layer "In11.Cu")
		(net "M_F_DQ<18>")
	)
	(segment
		(start 231.493568 -115.614704)
		(end 231.00665 -115.127786)
		(width 0.14224)
		(layer "In11.Cu")
		(net "M_F_DQ<18>")
	)
	(segment
		(start 236.981746 -111.632746)
		(end 236.693964 -111.920528)
		(width 0.14224)
		(layer "In11.Cu")
		(net "M_F_DQ<18>")
	)
	(segment
		(start 223.3676 -145.923)
		(end 223.3676 -146.2532)
		(width 0.14224)
		(layer "In11.Cu")
		(net "M_F_DQ<18>")
	)
	(segment
		(start 222.40494 -150.469346)
		(end 222.749872 -150.814278)
		(width 0.14224)
		(layer "In11.Cu")
		(net "M_F_DQ<18>")
	)
	(segment
		(start 232.06837 -115.039902)
		(end 232.06837 -115.32743)
		(width 0.14224)
		(layer "In11.Cu")
		(net "M_F_DQ<18>")
	)
	(segment
		(start 232.101898 -114.03203)
		(end 231.814878 -114.03203)
		(width 0.14224)
		(layer "In11.Cu")
		(net "M_F_DQ<18>")
	)
	(segment
		(start 223.3676 -139.0396)
		(end 223.3676 -139.471146)
		(width 0.14224)
		(layer "In11.Cu")
		(net "M_F_DQ<18>")
	)
	(segment
		(start 238.353854 -105.383584)
		(end 237.873794 -105.383584)
		(width 0.0889)
		(layer "In11.Cu")
		(net "M_F_DQ<18>")
	)
	(segment
		(start 231.00665 -115.127786)
		(end 230.719122 -115.127786)
		(width 0.14224)
		(layer "In11.Cu")
		(net "M_F_DQ<18>")
	)
	(segment
		(start 223.0882 -148.3868)
		(end 223.3168 -148.6154)
		(width 0.14224)
		(layer "In11.Cu")
		(net "M_F_DQ<18>")
	)
	(segment
		(start 236.693964 -111.920528)
		(end 236.406944 -111.920528)
		(width 0.14224)
		(layer "In11.Cu")
		(net "M_F_DQ<18>")
	)
	(segment
		(start 223.4184 -134.3914)
		(end 223.012 -134.7978)
		(width 0.14224)
		(layer "In11.Cu")
		(net "M_F_DQ<18>")
	)
	(segment
		(start 223.335342 -136.314942)
		(end 223.335342 -136.582658)
		(width 0.14224)
		(layer "In11.Cu")
		(net "M_F_DQ<18>")
	)
	(segment
		(start 232.567988 -114.498374)
		(end 232.101898 -114.03203)
		(width 0.14224)
		(layer "In11.Cu")
		(net "M_F_DQ<18>")
	)
	(segment
		(start 235.776262 -111.57712)
		(end 232.855008 -114.498374)
		(width 0.14224)
		(layer "In11.Cu")
		(net "M_F_DQ<18>")
	)
	(segment
		(start 245.402354 -95.509588)
		(end 245.40718 -95.518224)
		(width 0.0889)
		(layer "In11.Cu")
		(net "M_F_DQ<18>")
	)
	(segment
		(start 223.1898 -143.3068)
		(end 223.4184 -143.5354)
		(width 0.14224)
		(layer "In11.Cu")
		(net "M_F_DQ<18>")
	)
	(segment
		(start 223.0374 -136.8806)
		(end 223.0374 -138.7094)
		(width 0.14224)
		(layer "In11.Cu")
		(net "M_F_DQ<18>")
	)
	(segment
		(start 231.781096 -115.614704)
		(end 231.493568 -115.614704)
		(width 0.14224)
		(layer "In11.Cu")
		(net "M_F_DQ<18>")
	)
	(segment
		(start 223.3676 -139.471146)
		(end 223.11614 -139.722606)
		(width 0.14224)
		(layer "In11.Cu")
		(net "M_F_DQ<18>")
	)
	(segment
		(start 223.217994 -122.628914)
		(end 223.217994 -129.859024)
		(width 0.14224)
		(layer "In11.Cu")
		(net "M_F_DQ<18>")
	)
	(segment
		(start 236.981746 -111.345726)
		(end 236.981746 -111.632746)
		(width 0.14224)
		(layer "In11.Cu")
		(net "M_F_DQ<18>")
	)
	(segment
		(start 246.772684 -94.718886)
		(end 245.948708 -94.81439)
		(width 0.0889)
		(layer "In11.Cu")
		(net "M_F_DQ<18>")
	)
	(segment
		(start 240.251488 -100.462588)
		(end 240.256314 -100.471224)
		(width 0.0889)
		(layer "In11.Cu")
		(net "M_F_DQ<18>")
	)
	(segment
		(start 223.3168 -148.6154)
		(end 223.3168 -149.123654)
		(width 0.14224)
		(layer "In11.Cu")
		(net "M_F_DQ<18>")
	)
	(segment
		(start 244.2083 -96.60509)
		(end 244.175534 -96.60509)
		(width 0.0889)
		(layer "In11.Cu")
		(net "M_F_DQ<18>")
	)
	(segment
		(start 223.0374 -138.7094)
		(end 223.3676 -139.0396)
		(width 0.14224)
		(layer "In11.Cu")
		(net "M_F_DQ<18>")
	)
	(segment
		(start 223.4184 -143.994378)
		(end 223.03994 -144.372838)
		(width 0.14224)
		(layer "In11.Cu")
		(net "M_F_DQ<18>")
	)
	(segment
		(start 223.11614 -140.794486)
		(end 223.4184 -141.096746)
		(width 0.14224)
		(layer "In11.Cu")
		(net "M_F_DQ<18>")
	)
	(segment
		(start 236.638084 -111.002318)
		(end 236.981746 -111.345726)
		(width 0.14224)
		(layer "In11.Cu")
		(net "M_F_DQ<18>")
	)
	(segment
		(start 242.826794 -97.395538)
		(end 242.823492 -97.40138)
		(width 0.0889)
		(layer "In11.Cu")
		(net "M_F_DQ<18>")
	)
	(segment
		(start 223.4184 -141.096746)
		(end 223.4184 -141.605)
		(width 0.14224)
		(layer "In11.Cu")
		(net "M_F_DQ<18>")
	)
	(segment
		(start 222.316802 -151.247348)
		(end 222.316802 -153.834846)
		(width 0.14224)
		(layer "In11.Cu")
		(net "M_F_DQ<18>")
	)
	(segment
		(start 223.335342 -136.582658)
		(end 223.0374 -136.8806)
		(width 0.14224)
		(layer "In11.Cu")
		(net "M_F_DQ<18>")
	)
	(segment
		(start 223.2152 -131.319778)
		(end 223.2152 -133.731)
		(width 0.14224)
		(layer "In11.Cu")
		(net "M_F_DQ<18>")
	)
	(segment
		(start 240.350294 -103.387144)
		(end 238.353854 -105.383584)
		(width 0.0889)
		(layer "In11.Cu")
		(net "M_F_DQ<18>")
	)
	(segment
		(start 240.251488 -99.872038)
		(end 240.245138 -99.882706)
		(width 0.0889)
		(layer "In11.Cu")
		(net "M_F_DQ<18>")
	)
	(segment
		(start 223.2152 -133.731)
		(end 223.4184 -133.9342)
		(width 0.14224)
		(layer "In11.Cu")
		(net "M_F_DQ<18>")
	)
	(segment
		(start 223.4184 -141.605)
		(end 223.1898 -141.8336)
		(width 0.14224)
		(layer "In11.Cu")
		(net "M_F_DQ<18>")
	)
	(segment
		(start 232.855008 -114.498374)
		(end 232.567988 -114.498374)
		(width 0.14224)
		(layer "In11.Cu")
		(net "M_F_DQ<18>")
	)
	(segment
		(start 231.581452 -114.552984)
		(end 232.06837 -115.039902)
		(width 0.14224)
		(layer "In11.Cu")
		(net "M_F_DQ<18>")
	)
	(segment
		(start 243.35359 -97.100136)
		(end 243.320824 -97.100136)
		(width 0.0889)
		(layer "In11.Cu")
		(net "M_F_DQ<18>")
	)
	(arc
		(start 243.685314 -96.900238)
		(mid 243.545235 -97.042974)
		(end 243.35359 -97.100136)
		(width 0.0889)
		(layer "In11.Cu")
		(net "M_F_DQ<18>")
	)
	(arc
		(start 243.320824 -97.100136)
		(mid 243.0354 -97.183603)
		(end 242.826794 -97.395538)
		(width 0.0889)
		(layer "In11.Cu")
		(net "M_F_DQ<18>")
	)
	(arc
		(start 241.604038 -98.090736)
		(mid 241.318614 -98.174203)
		(end 241.110008 -98.386138)
		(width 0.0889)
		(layer "In11.Cu")
		(net "M_F_DQ<18>")
	)
	(arc
		(start 240.741708 -98.58629)
		(mid 240.246231 -98.890733)
		(end 240.251488 -99.472242)
		(width 0.0889)
		(layer "In11.Cu")
		(net "M_F_DQ<18>")
	)
	(arc
		(start 244.175534 -96.60509)
		(mid 243.892317 -96.689371)
		(end 243.685314 -96.900238)
		(width 0.0889)
		(layer "In11.Cu")
		(net "M_F_DQ<18>")
	)
	(arc
		(start 241.968528 -97.890838)
		(mid 241.828449 -98.033574)
		(end 241.636804 -98.090736)
		(width 0.0889)
		(layer "In11.Cu")
		(net "M_F_DQ<18>")
	)
	(arc
		(start 242.823492 -97.40138)
		(mid 242.677526 -97.543779)
		(end 242.480338 -97.59569)
		(width 0.0889)
		(layer "In11.Cu")
		(net "M_F_DQ<18>")
	)
	(arc
		(start 245.40718 -95.518224)
		(mid 245.403433 -95.90748)
		(end 245.07063 -96.109536)
		(width 0.0889)
		(layer "In11.Cu")
		(net "M_F_DQ<18>")
	)
	(arc
		(start 241.110008 -98.386138)
		(mid 240.968325 -98.529942)
		(end 240.774474 -98.58629)
		(width 0.0889)
		(layer "In11.Cu")
		(net "M_F_DQ<18>")
	)
	(arc
		(start 245.402354 -95.300292)
		(mid 245.374327 -95.40494)
		(end 245.402354 -95.509588)
		(width 0.0889)
		(layer "In11.Cu")
		(net "M_F_DQ<18>")
	)
	(arc
		(start 244.543834 -96.404938)
		(mid 244.402151 -96.548742)
		(end 244.2083 -96.60509)
		(width 0.0889)
		(layer "In11.Cu")
		(net "M_F_DQ<18>")
	)
	(arc
		(start 240.245138 -99.882706)
		(mid 240.17234 -100.173469)
		(end 240.251488 -100.462588)
		(width 0.0889)
		(layer "In11.Cu")
		(net "M_F_DQ<18>")
	)
	(arc
		(start 240.251488 -99.472242)
		(mid 240.304987 -99.67214)
		(end 240.251488 -99.872038)
		(width 0.0889)
		(layer "In11.Cu")
		(net "M_F_DQ<18>")
	)
	(arc
		(start 240.251488 -100.862638)
		(mid 240.172266 -101.151756)
		(end 240.245138 -101.44252)
		(width 0.0889)
		(layer "In11.Cu")
		(net "M_F_DQ<18>")
	)
	(arc
		(start 245.037864 -96.109536)
		(mid 244.75244 -96.193003)
		(end 244.543834 -96.404938)
		(width 0.0889)
		(layer "In11.Cu")
		(net "M_F_DQ<18>")
	)
	(arc
		(start 240.256314 -100.471224)
		(mid 240.305069 -100.667576)
		(end 240.251488 -100.862638)
		(width 0.0889)
		(layer "In11.Cu")
		(net "M_F_DQ<18>")
	)
	(arc
		(start 245.899178 -94.81439)
		(mid 245.707536 -94.871556)
		(end 245.567454 -95.014288)
		(width 0.0889)
		(layer "In11.Cu")
		(net "M_F_DQ<18>")
	)
	(arc
		(start 242.458748 -97.59569)
		(mid 242.175531 -97.679971)
		(end 241.968528 -97.890838)
		(width 0.0889)
		(layer "In11.Cu")
		(net "M_F_DQ<18>")
	)
	(segment
		(start 216.799922 -152.278842)
		(end 216.799922 -153.542746)
		(width 0.1651)
		(layer "F.Cu")
		(net "M_F_DQ<17>")
	)
	(segment
		(start 216.80043 -152.273)
		(end 216.799922 -152.278842)
		(width 0.1651)
		(layer "F.Cu")
		(net "M_F_DQ<17>")
	)
	(segment
		(start 244.768624 -93.23324)
		(end 244.197124 -93.23324)
		(width 0.1651)
		(layer "F.Cu")
		(net "M_F_DQ<17>")
	)
	(via
		(at 216.799922 -153.542746)
		(size 0.508)
		(drill 0.254)
		(layers "F.Cu" "B.Cu")
		(net "M_F_DQ<17>")
	)
	(via
		(at 217.472006 -149.533356)
		(size 0.508)
		(drill 0.254)
		(layers "F.Cu" "B.Cu")
		(net "M_F_DQ<17>")
	)
	(via
		(at 244.197124 -93.23324)
		(size 0.508)
		(drill 0.254)
		(layers "F.Cu" "B.Cu")
		(net "M_F_DQ<17>")
	)
	(segment
		(start 217.649806 -148.852382)
		(end 217.472006 -149.030182)
		(width 0.1651)
		(layer "B.Cu")
		(net "M_F_DQ<17>")
	)
	(segment
		(start 217.649806 -147.478496)
		(end 217.649806 -148.852382)
		(width 0.1651)
		(layer "B.Cu")
		(net "M_F_DQ<17>")
	)
	(segment
		(start 217.472006 -149.030182)
		(end 217.472006 -149.533356)
		(width 0.1651)
		(layer "B.Cu")
		(net "M_F_DQ<17>")
	)
	(segment
		(start 217.650314 -147.478496)
		(end 217.649806 -147.478496)
		(width 0.1651)
		(layer "B.Cu")
		(net "M_F_DQ<17>")
	)
	(segment
		(start 219.380816 -123.17349)
		(end 219.535756 -123.32843)
		(width 0.14224)
		(layer "In11.Cu")
		(net "M_F_DQ<17>")
	)
	(segment
		(start 236.492288 -97.290636)
		(end 236.459522 -97.290636)
		(width 0.0889)
		(layer "In11.Cu")
		(net "M_F_DQ<17>")
	)
	(segment
		(start 217.8304 -147.4978)
		(end 218.0844 -147.7518)
		(width 0.14224)
		(layer "In11.Cu")
		(net "M_F_DQ<17>")
	)
	(segment
		(start 218.0844 -146.8628)
		(end 217.8304 -147.1168)
		(width 0.14224)
		(layer "In11.Cu")
		(net "M_F_DQ<17>")
	)
	(segment
		(start 219.485972 -120.58015)
		(end 219.331032 -120.73509)
		(width 0.14224)
		(layer "In11.Cu")
		(net "M_F_DQ<17>")
	)
	(segment
		(start 218.970098 -121.39295)
		(end 219.125038 -121.54789)
		(width 0.14224)
		(layer "In11.Cu")
		(net "M_F_DQ<17>")
	)
	(segment
		(start 218.0844 -141.5034)
		(end 218.0844 -142.2146)
		(width 0.14224)
		(layer "In11.Cu")
		(net "M_F_DQ<17>")
	)
	(segment
		(start 219.535756 -123.32843)
		(end 219.535756 -123.83135)
		(width 0.14224)
		(layer "In11.Cu")
		(net "M_F_DQ<17>")
	)
	(segment
		(start 216.961212 -152.846024)
		(end 217.200988 -153.0858)
		(width 0.14224)
		(layer "In11.Cu")
		(net "M_F_DQ<17>")
	)
	(segment
		(start 218.0844 -148.2598)
		(end 217.95994 -148.38426)
		(width 0.14224)
		(layer "In11.Cu")
		(net "M_F_DQ<17>")
	)
	(segment
		(start 218.970098 -124.14123)
		(end 218.970098 -124.64415)
		(width 0.14224)
		(layer "In11.Cu")
		(net "M_F_DQ<17>")
	)
	(segment
		(start 234.406948 -101.453188)
		(end 234.276392 -101.679756)
		(width 0.0889)
		(layer "In11.Cu")
		(net "M_F_DQ<17>")
	)
	(segment
		(start 218.258898 -133.962902)
		(end 217.95994 -134.26186)
		(width 0.14224)
		(layer "In11.Cu")
		(net "M_F_DQ<17>")
	)
	(segment
		(start 217.95994 -148.38426)
		(end 217.95994 -148.956522)
		(width 0.14224)
		(layer "In11.Cu")
		(net "M_F_DQ<17>")
	)
	(segment
		(start 219.331032 -120.73509)
		(end 219.125038 -120.73509)
		(width 0.14224)
		(layer "In11.Cu")
		(net "M_F_DQ<17>")
	)
	(segment
		(start 240.776252 -94.81439)
		(end 240.748312 -94.81439)
		(width 0.0889)
		(layer "In11.Cu")
		(net "M_F_DQ<17>")
	)
	(segment
		(start 218.970098 -123.01855)
		(end 219.125038 -123.17349)
		(width 0.14224)
		(layer "In11.Cu")
		(net "M_F_DQ<17>")
	)
	(segment
		(start 218.1606 -126.7714)
		(end 218.1606 -129.01168)
		(width 0.14224)
		(layer "In11.Cu")
		(net "M_F_DQ<17>")
	)
	(segment
		(start 232.52811 -104.49052)
		(end 232.52811 -106.923586)
		(width 0.14224)
		(layer "In11.Cu")
		(net "M_F_DQ<17>")
	)
	(segment
		(start 217.95994 -143.86306)
		(end 217.95994 -146.20494)
		(width 0.14224)
		(layer "In11.Cu")
		(net "M_F_DQ<17>")
	)
	(segment
		(start 217.048842 -153.542746)
		(end 216.799922 -153.542746)
		(width 0.14224)
		(layer "In11.Cu")
		(net "M_F_DQ<17>")
	)
	(segment
		(start 242.99545 -93.5228)
		(end 242.992148 -93.528642)
		(width 0.0889)
		(layer "In11.Cu")
		(net "M_F_DQ<17>")
	)
	(segment
		(start 219.331032 -122.36069)
		(end 219.125038 -122.36069)
		(width 0.14224)
		(layer "In11.Cu")
		(net "M_F_DQ<17>")
	)
	(segment
		(start 219.125038 -122.36069)
		(end 218.970098 -122.51563)
		(width 0.14224)
		(layer "In11.Cu")
		(net "M_F_DQ<17>")
	)
	(segment
		(start 219.125038 -123.17349)
		(end 219.380816 -123.17349)
		(width 0.14224)
		(layer "In11.Cu")
		(net "M_F_DQ<17>")
	)
	(segment
		(start 219.125038 -120.73509)
		(end 218.970098 -120.89003)
		(width 0.14224)
		(layer "In11.Cu")
		(net "M_F_DQ<17>")
	)
	(segment
		(start 218.202002 -136.820402)
		(end 218.202002 -137.2616)
		(width 0.14224)
		(layer "In11.Cu")
		(net "M_F_DQ<17>")
	)
	(segment
		(start 235.271818 -99.95662)
		(end 235.265468 -99.967288)
		(width 0.0889)
		(layer "In11.Cu")
		(net "M_F_DQ<17>")
	)
	(segment
		(start 219.485972 -124.95403)
		(end 219.485972 -125.446028)
		(width 0.14224)
		(layer "In11.Cu")
		(net "M_F_DQ<17>")
	)
	(segment
		(start 232.52811 -106.923586)
		(end 219.485972 -119.965724)
		(width 0.14224)
		(layer "In11.Cu")
		(net "M_F_DQ<17>")
	)
	(segment
		(start 217.932 -137.855198)
		(end 218.202002 -138.1252)
		(width 0.14224)
		(layer "In11.Cu")
		(net "M_F_DQ<17>")
	)
	(segment
		(start 217.95994 -148.956522)
		(end 217.472006 -149.444456)
		(width 0.14224)
		(layer "In11.Cu")
		(net "M_F_DQ<17>")
	)
	(segment
		(start 218.1606 -129.01168)
		(end 217.946478 -129.225802)
		(width 0.14224)
		(layer "In11.Cu")
		(net "M_F_DQ<17>")
	)
	(segment
		(start 217.175588 -151.892)
		(end 217.175588 -152.3238)
		(width 0.14224)
		(layer "In11.Cu")
		(net "M_F_DQ<17>")
	)
	(segment
		(start 217.946478 -129.225802)
		(end 217.946478 -131.713478)
		(width 0.14224)
		(layer "In11.Cu")
		(net "M_F_DQ<17>")
	)
	(segment
		(start 238.209328 -96.300036)
		(end 238.176562 -96.300036)
		(width 0.0889)
		(layer "In11.Cu")
		(net "M_F_DQ<17>")
	)
	(segment
		(start 217.946478 -131.713478)
		(end 218.3384 -132.1054)
		(width 0.14224)
		(layer "In11.Cu")
		(net "M_F_DQ<17>")
	)
	(segment
		(start 217.8304 -143.1036)
		(end 218.0844 -143.3576)
		(width 0.14224)
		(layer "In11.Cu")
		(net "M_F_DQ<17>")
	)
	(segment
		(start 217.95994 -146.20494)
		(end 218.0844 -146.3294)
		(width 0.14224)
		(layer "In11.Cu")
		(net "M_F_DQ<17>")
	)
	(segment
		(start 217.472006 -149.533356)
		(end 217.449654 -149.533356)
		(width 0.14224)
		(layer "In11.Cu")
		(net "M_F_DQ<17>")
	)
	(segment
		(start 218.0844 -143.7386)
		(end 217.95994 -143.86306)
		(width 0.14224)
		(layer "In11.Cu")
		(net "M_F_DQ<17>")
	)
	(segment
		(start 217.8304 -142.4686)
		(end 217.8304 -143.1036)
		(width 0.14224)
		(layer "In11.Cu")
		(net "M_F_DQ<17>")
	)
	(segment
		(start 217.02141 -150.391368)
		(end 217.251788 -150.621746)
		(width 0.14224)
		(layer "In11.Cu")
		(net "M_F_DQ<17>")
	)
	(segment
		(start 243.641626 -93.326458)
		(end 243.619528 -93.32849)
		(width 0.0889)
		(layer "In11.Cu")
		(net "M_F_DQ<17>")
	)
	(segment
		(start 218.0844 -147.7518)
		(end 218.0844 -148.2598)
		(width 0.14224)
		(layer "In11.Cu")
		(net "M_F_DQ<17>")
	)
	(segment
		(start 217.251788 -150.621746)
		(end 217.251788 -151.026368)
		(width 0.14224)
		(layer "In11.Cu")
		(net "M_F_DQ<17>")
	)
	(segment
		(start 217.251788 -151.026368)
		(end 216.961212 -151.316944)
		(width 0.14224)
		(layer "In11.Cu")
		(net "M_F_DQ<17>")
	)
	(segment
		(start 217.95994 -138.85926)
		(end 217.95994 -141.37894)
		(width 0.14224)
		(layer "In11.Cu")
		(net "M_F_DQ<17>")
	)
	(segment
		(start 219.125038 -124.79909)
		(end 219.331032 -124.79909)
		(width 0.14224)
		(layer "In11.Cu")
		(net "M_F_DQ<17>")
	)
	(segment
		(start 218.3384 -132.439664)
		(end 217.946478 -132.831586)
		(width 0.14224)
		(layer "In11.Cu")
		(net "M_F_DQ<17>")
	)
	(segment
		(start 219.535756 -123.83135)
		(end 219.380816 -123.98629)
		(width 0.14224)
		(layer "In11.Cu")
		(net "M_F_DQ<17>")
	)
	(segment
		(start 218.258898 -133.611874)
		(end 218.258898 -133.962902)
		(width 0.14224)
		(layer "In11.Cu")
		(net "M_F_DQ<17>")
	)
	(segment
		(start 218.0844 -146.3294)
		(end 218.0844 -146.8628)
		(width 0.14224)
		(layer "In11.Cu")
		(net "M_F_DQ<17>")
	)
	(segment
		(start 219.331032 -121.54789)
		(end 219.485972 -121.70283)
		(width 0.14224)
		(layer "In11.Cu")
		(net "M_F_DQ<17>")
	)
	(segment
		(start 219.125038 -123.98629)
		(end 218.970098 -124.14123)
		(width 0.14224)
		(layer "In11.Cu")
		(net "M_F_DQ<17>")
	)
	(segment
		(start 217.95994 -141.37894)
		(end 218.0844 -141.5034)
		(width 0.14224)
		(layer "In11.Cu")
		(net "M_F_DQ<17>")
	)
	(segment
		(start 218.0844 -142.2146)
		(end 217.8304 -142.4686)
		(width 0.14224)
		(layer "In11.Cu")
		(net "M_F_DQ<17>")
	)
	(segment
		(start 219.125038 -121.54789)
		(end 219.331032 -121.54789)
		(width 0.14224)
		(layer "In11.Cu")
		(net "M_F_DQ<17>")
	)
	(segment
		(start 219.485972 -119.965724)
		(end 219.485972 -120.58015)
		(width 0.14224)
		(layer "In11.Cu")
		(net "M_F_DQ<17>")
	)
	(segment
		(start 217.02141 -149.9616)
		(end 217.02141 -150.391368)
		(width 0.14224)
		(layer "In11.Cu")
		(net "M_F_DQ<17>")
	)
	(segment
		(start 233.80192 -103.21671)
		(end 232.52811 -104.49052)
		(width 0.14224)
		(layer "In11.Cu")
		(net "M_F_DQ<17>")
	)
	(segment
		(start 239.064038 -95.80499)
		(end 239.031272 -95.80499)
		(width 0.0889)
		(layer "In11.Cu")
		(net "M_F_DQ<17>")
	)
	(segment
		(start 218.970098 -120.89003)
		(end 218.970098 -121.39295)
		(width 0.14224)
		(layer "In11.Cu")
		(net "M_F_DQ<17>")
	)
	(segment
		(start 217.8304 -147.1168)
		(end 217.8304 -147.4978)
		(width 0.14224)
		(layer "In11.Cu")
		(net "M_F_DQ<17>")
	)
	(segment
		(start 219.331032 -124.79909)
		(end 219.485972 -124.95403)
		(width 0.14224)
		(layer "In11.Cu")
		(net "M_F_DQ<17>")
	)
	(segment
		(start 218.202002 -138.617198)
		(end 217.95994 -138.85926)
		(width 0.14224)
		(layer "In11.Cu")
		(net "M_F_DQ<17>")
	)
	(segment
		(start 219.485972 -125.446028)
		(end 218.1606 -126.7714)
		(width 0.14224)
		(layer "In11.Cu")
		(net "M_F_DQ<17>")
	)
	(segment
		(start 217.200988 -153.0858)
		(end 217.200988 -153.3906)
		(width 0.14224)
		(layer "In11.Cu")
		(net "M_F_DQ<17>")
	)
	(segment
		(start 234.276392 -101.679756)
		(end 234.276392 -102.414578)
		(width 0.0889)
		(layer "In11.Cu")
		(net "M_F_DQ<17>")
	)
	(segment
		(start 217.946478 -132.831586)
		(end 217.946478 -133.299454)
		(width 0.14224)
		(layer "In11.Cu")
		(net "M_F_DQ<17>")
	)
	(segment
		(start 218.3384 -132.1054)
		(end 218.3384 -132.439664)
		(width 0.14224)
		(layer "In11.Cu")
		(net "M_F_DQ<17>")
	)
	(segment
		(start 219.485972 -121.70283)
		(end 219.485972 -122.20575)
		(width 0.14224)
		(layer "In11.Cu")
		(net "M_F_DQ<17>")
	)
	(segment
		(start 243.619528 -93.32849)
		(end 243.338604 -93.32849)
		(width 0.0889)
		(layer "In11.Cu")
		(net "M_F_DQ<17>")
	)
	(segment
		(start 218.202002 -137.2616)
		(end 217.932 -137.531602)
		(width 0.14224)
		(layer "In11.Cu")
		(net "M_F_DQ<17>")
	)
	(segment
		(start 242.501928 -93.82379)
		(end 242.462304 -93.82379)
		(width 0.0889)
		(layer "In11.Cu")
		(net "M_F_DQ<17>")
	)
	(segment
		(start 219.380816 -123.98629)
		(end 219.125038 -123.98629)
		(width 0.14224)
		(layer "In11.Cu")
		(net "M_F_DQ<17>")
	)
	(segment
		(start 235.629958 -97.78619)
		(end 235.601002 -97.78619)
		(width 0.0889)
		(layer "In11.Cu")
		(net "M_F_DQ<17>")
	)
	(segment
		(start 244.197124 -93.23324)
		(end 243.641626 -93.326458)
		(width 0.0889)
		(layer "In11.Cu")
		(net "M_F_DQ<17>")
	)
	(segment
		(start 216.961212 -151.677624)
		(end 217.175588 -151.892)
		(width 0.14224)
		(layer "In11.Cu")
		(net "M_F_DQ<17>")
	)
	(segment
		(start 217.200988 -153.3906)
		(end 217.048842 -153.542746)
		(width 0.14224)
		(layer "In11.Cu")
		(net "M_F_DQ<17>")
	)
	(segment
		(start 233.80192 -102.88905)
		(end 233.80192 -103.21671)
		(width 0.0889)
		(layer "In11.Cu")
		(net "M_F_DQ<17>")
	)
	(segment
		(start 217.472006 -149.444456)
		(end 217.472006 -149.533356)
		(width 0.14224)
		(layer "In11.Cu")
		(net "M_F_DQ<17>")
	)
	(segment
		(start 217.95994 -136.57834)
		(end 218.202002 -136.820402)
		(width 0.14224)
		(layer "In11.Cu")
		(net "M_F_DQ<17>")
	)
	(segment
		(start 218.0844 -143.3576)
		(end 218.0844 -143.7386)
		(width 0.14224)
		(layer "In11.Cu")
		(net "M_F_DQ<17>")
	)
	(segment
		(start 218.970098 -124.64415)
		(end 219.125038 -124.79909)
		(width 0.14224)
		(layer "In11.Cu")
		(net "M_F_DQ<17>")
	)
	(segment
		(start 241.639598 -94.31909)
		(end 241.603784 -94.31909)
		(width 0.0889)
		(layer "In11.Cu")
		(net "M_F_DQ<17>")
	)
	(segment
		(start 217.449654 -149.533356)
		(end 217.02141 -149.9616)
		(width 0.14224)
		(layer "In11.Cu")
		(net "M_F_DQ<17>")
	)
	(segment
		(start 239.926368 -95.309436)
		(end 239.893602 -95.309436)
		(width 0.0889)
		(layer "In11.Cu")
		(net "M_F_DQ<17>")
	)
	(segment
		(start 237.346998 -96.79559)
		(end 237.314232 -96.79559)
		(width 0.0889)
		(layer "In11.Cu")
		(net "M_F_DQ<17>")
	)
	(segment
		(start 216.961212 -151.316944)
		(end 216.961212 -151.677624)
		(width 0.14224)
		(layer "In11.Cu")
		(net "M_F_DQ<17>")
	)
	(segment
		(start 216.961212 -152.538176)
		(end 216.961212 -152.846024)
		(width 0.14224)
		(layer "In11.Cu")
		(net "M_F_DQ<17>")
	)
	(segment
		(start 218.970098 -122.51563)
		(end 218.970098 -123.01855)
		(width 0.14224)
		(layer "In11.Cu")
		(net "M_F_DQ<17>")
	)
	(segment
		(start 217.95994 -134.26186)
		(end 217.95994 -136.57834)
		(width 0.14224)
		(layer "In11.Cu")
		(net "M_F_DQ<17>")
	)
	(segment
		(start 217.946478 -133.299454)
		(end 218.258898 -133.611874)
		(width 0.14224)
		(layer "In11.Cu")
		(net "M_F_DQ<17>")
	)
	(segment
		(start 217.175588 -152.3238)
		(end 216.961212 -152.538176)
		(width 0.14224)
		(layer "In11.Cu")
		(net "M_F_DQ<17>")
	)
	(segment
		(start 218.202002 -138.1252)
		(end 218.202002 -138.617198)
		(width 0.14224)
		(layer "In11.Cu")
		(net "M_F_DQ<17>")
	)
	(segment
		(start 234.276392 -102.414578)
		(end 233.80192 -102.88905)
		(width 0.0889)
		(layer "In11.Cu")
		(net "M_F_DQ<17>")
	)
	(segment
		(start 234.775248 -101.253036)
		(end 234.742482 -101.253036)
		(width 0.0889)
		(layer "In11.Cu")
		(net "M_F_DQ<17>")
	)
	(segment
		(start 219.485972 -122.20575)
		(end 219.331032 -122.36069)
		(width 0.14224)
		(layer "In11.Cu")
		(net "M_F_DQ<17>")
	)
	(segment
		(start 217.932 -137.531602)
		(end 217.932 -137.855198)
		(width 0.14224)
		(layer "In11.Cu")
		(net "M_F_DQ<17>")
	)
	(arc
		(start 239.031272 -95.80499)
		(mid 238.83963 -95.862156)
		(end 238.699548 -96.004888)
		(width 0.0889)
		(layer "In11.Cu")
		(net "M_F_DQ<17>")
	)
	(arc
		(start 237.841028 -96.500188)
		(mid 237.63242 -96.71212)
		(end 237.346998 -96.79559)
		(width 0.0889)
		(layer "In11.Cu")
		(net "M_F_DQ<17>")
	)
	(arc
		(start 242.133628 -94.023688)
		(mid 241.92502 -94.23562)
		(end 241.639598 -94.31909)
		(width 0.0889)
		(layer "In11.Cu")
		(net "M_F_DQ<17>")
	)
	(arc
		(start 240.416588 -95.014288)
		(mid 240.209584 -95.225152)
		(end 239.926368 -95.309436)
		(width 0.0889)
		(layer "In11.Cu")
		(net "M_F_DQ<17>")
	)
	(arc
		(start 236.459522 -97.290636)
		(mid 236.265672 -97.346986)
		(end 236.123988 -97.490788)
		(width 0.0889)
		(layer "In11.Cu")
		(net "M_F_DQ<17>")
	)
	(arc
		(start 234.742482 -101.253036)
		(mid 234.548632 -101.309386)
		(end 234.406948 -101.453188)
		(width 0.0889)
		(layer "In11.Cu")
		(net "M_F_DQ<17>")
	)
	(arc
		(start 242.462304 -93.82379)
		(mid 242.272375 -93.88166)
		(end 242.133628 -94.023688)
		(width 0.0889)
		(layer "In11.Cu")
		(net "M_F_DQ<17>")
	)
	(arc
		(start 243.338604 -93.32849)
		(mid 243.141443 -93.380449)
		(end 242.99545 -93.5228)
		(width 0.0889)
		(layer "In11.Cu")
		(net "M_F_DQ<17>")
	)
	(arc
		(start 242.992148 -93.528642)
		(mid 242.785144 -93.739506)
		(end 242.501928 -93.82379)
		(width 0.0889)
		(layer "In11.Cu")
		(net "M_F_DQ<17>")
	)
	(arc
		(start 235.265468 -98.976942)
		(mid 235.211969 -99.17684)
		(end 235.265468 -99.376738)
		(width 0.0889)
		(layer "In11.Cu")
		(net "M_F_DQ<17>")
	)
	(arc
		(start 240.748312 -94.81439)
		(mid 240.55667 -94.871556)
		(end 240.416588 -95.014288)
		(width 0.0889)
		(layer "In11.Cu")
		(net "M_F_DQ<17>")
	)
	(arc
		(start 235.265468 -100.367084)
		(mid 235.270722 -100.948592)
		(end 234.775248 -101.253036)
		(width 0.0889)
		(layer "In11.Cu")
		(net "M_F_DQ<17>")
	)
	(arc
		(start 235.265468 -99.967288)
		(mid 235.211969 -100.167186)
		(end 235.265468 -100.367084)
		(width 0.0889)
		(layer "In11.Cu")
		(net "M_F_DQ<17>")
	)
	(arc
		(start 239.558068 -95.509588)
		(mid 239.34946 -95.72152)
		(end 239.064038 -95.80499)
		(width 0.0889)
		(layer "In11.Cu")
		(net "M_F_DQ<17>")
	)
	(arc
		(start 239.893602 -95.309436)
		(mid 239.699752 -95.365786)
		(end 239.558068 -95.509588)
		(width 0.0889)
		(layer "In11.Cu")
		(net "M_F_DQ<17>")
	)
	(arc
		(start 241.275108 -94.518988)
		(mid 241.064395 -94.732067)
		(end 240.776252 -94.81439)
		(width 0.0889)
		(layer "In11.Cu")
		(net "M_F_DQ<17>")
	)
	(arc
		(start 236.123988 -97.490788)
		(mid 235.91538 -97.70272)
		(end 235.629958 -97.78619)
		(width 0.0889)
		(layer "In11.Cu")
		(net "M_F_DQ<17>")
	)
	(arc
		(start 238.699548 -96.004888)
		(mid 238.492544 -96.215752)
		(end 238.209328 -96.300036)
		(width 0.0889)
		(layer "In11.Cu")
		(net "M_F_DQ<17>")
	)
	(arc
		(start 235.265468 -98.386138)
		(mid 235.344599 -98.68154)
		(end 235.265468 -98.976942)
		(width 0.0889)
		(layer "In11.Cu")
		(net "M_F_DQ<17>")
	)
	(arc
		(start 235.265468 -99.376738)
		(mid 235.34469 -99.665856)
		(end 235.271818 -99.95662)
		(width 0.0889)
		(layer "In11.Cu")
		(net "M_F_DQ<17>")
	)
	(arc
		(start 235.601002 -97.78619)
		(mid 235.262887 -97.990892)
		(end 235.265468 -98.386138)
		(width 0.0889)
		(layer "In11.Cu")
		(net "M_F_DQ<17>")
	)
	(arc
		(start 236.982508 -96.995488)
		(mid 236.775504 -97.206352)
		(end 236.492288 -97.290636)
		(width 0.0889)
		(layer "In11.Cu")
		(net "M_F_DQ<17>")
	)
	(arc
		(start 237.314232 -96.79559)
		(mid 237.12259 -96.852756)
		(end 236.982508 -96.995488)
		(width 0.0889)
		(layer "In11.Cu")
		(net "M_F_DQ<17>")
	)
	(arc
		(start 238.176562 -96.300036)
		(mid 237.982712 -96.356386)
		(end 237.841028 -96.500188)
		(width 0.0889)
		(layer "In11.Cu")
		(net "M_F_DQ<17>")
	)
	(arc
		(start 241.603784 -94.31909)
		(mid 241.413855 -94.37696)
		(end 241.275108 -94.518988)
		(width 0.0889)
		(layer "In11.Cu")
		(net "M_F_DQ<17>")
	)
	(segment
		(start 246.485664 -92.24264)
		(end 245.914164 -92.24264)
		(width 0.1651)
		(layer "F.Cu")
		(net "M_F_DQ<16>")
	)
	(segment
		(start 217.649806 -156.878782)
		(end 217.472006 -155.0162)
		(width 0.1651)
		(layer "F.Cu")
		(net "M_F_DQ<16>")
	)
	(segment
		(start 217.650314 -156.87294)
		(end 217.649806 -156.878782)
		(width 0.1651)
		(layer "F.Cu")
		(net "M_F_DQ<16>")
	)
	(via
		(at 245.914164 -92.24264)
		(size 0.508)
		(drill 0.254)
		(layers "F.Cu" "B.Cu")
		(net "M_F_DQ<16>")
	)
	(via
		(at 217.472006 -155.0162)
		(size 0.508)
		(drill 0.254)
		(layers "F.Cu" "B.Cu")
		(net "M_F_DQ<16>")
	)
	(via
		(at 216.799922 -150.814278)
		(size 0.508)
		(drill 0.254)
		(layers "F.Cu" "B.Cu")
		(net "M_F_DQ<16>")
	)
	(segment
		(start 216.80043 -152.078436)
		(end 216.799922 -152.078182)
		(width 0.1651)
		(layer "B.Cu")
		(net "M_F_DQ<16>")
	)
	(segment
		(start 216.799922 -152.078182)
		(end 216.799922 -150.814278)
		(width 0.1651)
		(layer "B.Cu")
		(net "M_F_DQ<16>")
	)
	(segment
		(start 216.799922 -150.814278)
		(end 216.366852 -151.247348)
		(width 0.14224)
		(layer "In11.Cu")
		(net "M_F_DQ<16>")
	)
	(segment
		(start 216.98204 -140.743178)
		(end 217.27414 -141.035278)
		(width 0.14224)
		(layer "In11.Cu")
		(net "M_F_DQ<16>")
	)
	(segment
		(start 245.914164 -92.24264)
		(end 245.092728 -92.337636)
		(width 0.0889)
		(layer "In11.Cu")
		(net "M_F_DQ<16>")
	)
	(segment
		(start 216.98204 -130.062478)
		(end 216.98204 -131.141978)
		(width 0.14224)
		(layer "In11.Cu")
		(net "M_F_DQ<16>")
	)
	(segment
		(start 218.4908 -125.5014)
		(end 217.5002 -126.492)
		(width 0.14224)
		(layer "In11.Cu")
		(net "M_F_DQ<16>")
	)
	(segment
		(start 217.32494 -134.16534)
		(end 217.32494 -134.433818)
		(width 0.14224)
		(layer "In11.Cu")
		(net "M_F_DQ<16>")
	)
	(segment
		(start 242.82654 -93.433138)
		(end 242.826794 -93.433138)
		(width 0.0889)
		(layer "In11.Cu")
		(net "M_F_DQ<16>")
	)
	(segment
		(start 217.2208 -143.6878)
		(end 217.27414 -143.74114)
		(width 0.14224)
		(layer "In11.Cu")
		(net "M_F_DQ<16>")
	)
	(segment
		(start 218.4908 -120.062752)
		(end 218.4908 -125.5014)
		(width 0.14224)
		(layer "In11.Cu")
		(net "M_F_DQ<16>")
	)
	(segment
		(start 216.98204 -135.95604)
		(end 217.32494 -136.29894)
		(width 0.14224)
		(layer "In11.Cu")
		(net "M_F_DQ<16>")
	)
	(segment
		(start 235.623354 -97.59569)
		(end 235.590588 -97.59569)
		(width 0.0889)
		(layer "In11.Cu")
		(net "M_F_DQ<16>")
	)
	(segment
		(start 236.485684 -97.100136)
		(end 236.452918 -97.100136)
		(width 0.0889)
		(layer "In11.Cu")
		(net "M_F_DQ<16>")
	)
	(segment
		(start 235.100368 -99.872038)
		(end 235.094018 -99.882706)
		(width 0.0889)
		(layer "In11.Cu")
		(net "M_F_DQ<16>")
	)
	(segment
		(start 241.639852 -94.128336)
		(end 241.600228 -94.128336)
		(width 0.0889)
		(layer "In11.Cu")
		(net "M_F_DQ<16>")
	)
	(segment
		(start 217.32494 -129.719578)
		(end 216.98204 -130.062478)
		(width 0.14224)
		(layer "In11.Cu")
		(net "M_F_DQ<16>")
	)
	(segment
		(start 217.2208 -148.4122)
		(end 217.28684 -148.47824)
		(width 0.14224)
		(layer "In11.Cu")
		(net "M_F_DQ<16>")
	)
	(segment
		(start 217.32494 -139.320778)
		(end 216.98204 -139.663678)
		(width 0.14224)
		(layer "In11.Cu")
		(net "M_F_DQ<16>")
	)
	(segment
		(start 216.43594 -150.450296)
		(end 216.799922 -150.814278)
		(width 0.14224)
		(layer "In11.Cu")
		(net "M_F_DQ<16>")
	)
	(segment
		(start 234.241848 -101.357938)
		(end 234.0864 -101.627686)
		(width 0.0889)
		(layer "In11.Cu")
		(net "M_F_DQ<16>")
	)
	(segment
		(start 217.5002 -126.492)
		(end 217.5002 -128.6002)
		(width 0.14224)
		(layer "In11.Cu")
		(net "M_F_DQ<16>")
	)
	(segment
		(start 217.32494 -136.29894)
		(end 217.32494 -136.77646)
		(width 0.14224)
		(layer "In11.Cu")
		(net "M_F_DQ<16>")
	)
	(segment
		(start 240.774474 -94.623636)
		(end 240.750344 -94.623636)
		(width 0.0889)
		(layer "In11.Cu")
		(net "M_F_DQ<16>")
	)
	(segment
		(start 217.32494 -134.433818)
		(end 216.98204 -134.776718)
		(width 0.14224)
		(layer "In11.Cu")
		(net "M_F_DQ<16>")
	)
	(segment
		(start 243.981986 -92.89288)
		(end 243.57584 -93.137482)
		(width 0.0889)
		(layer "In11.Cu")
		(net "M_F_DQ<16>")
	)
	(segment
		(start 216.98204 -139.663678)
		(end 216.98204 -140.743178)
		(width 0.14224)
		(layer "In11.Cu")
		(net "M_F_DQ<16>")
	)
	(segment
		(start 232.04932 -106.504232)
		(end 218.4908 -120.062752)
		(width 0.14224)
		(layer "In11.Cu")
		(net "M_F_DQ<16>")
	)
	(segment
		(start 217.2208 -146.26844)
		(end 217.2208 -148.4122)
		(width 0.14224)
		(layer "In11.Cu")
		(net "M_F_DQ<16>")
	)
	(segment
		(start 233.352848 -102.767638)
		(end 232.04932 -104.071166)
		(width 0.14224)
		(layer "In11.Cu")
		(net "M_F_DQ<16>")
	)
	(segment
		(start 239.057434 -95.61449)
		(end 239.024668 -95.61449)
		(width 0.0889)
		(layer "In11.Cu")
		(net "M_F_DQ<16>")
	)
	(segment
		(start 234.768644 -101.062536)
		(end 234.735878 -101.062536)
		(width 0.0889)
		(layer "In11.Cu")
		(net "M_F_DQ<16>")
	)
	(segment
		(start 217.2208 -138.7094)
		(end 217.32494 -138.81354)
		(width 0.14224)
		(layer "In11.Cu")
		(net "M_F_DQ<16>")
	)
	(segment
		(start 217.28684 -148.960078)
		(end 216.43594 -149.810978)
		(width 0.14224)
		(layer "In11.Cu")
		(net "M_F_DQ<16>")
	)
	(segment
		(start 242.830096 -93.426788)
		(end 242.82654 -93.433138)
		(width 0.0889)
		(layer "In11.Cu")
		(net "M_F_DQ<16>")
	)
	(segment
		(start 242.49253 -93.633036)
		(end 242.462558 -93.633036)
		(width 0.0889)
		(layer "In11.Cu")
		(net "M_F_DQ<16>")
	)
	(segment
		(start 217.2208 -141.63294)
		(end 217.2208 -143.6878)
		(width 0.14224)
		(layer "In11.Cu")
		(net "M_F_DQ<16>")
	)
	(segment
		(start 217.5002 -128.6002)
		(end 217.32494 -128.77546)
		(width 0.14224)
		(layer "In11.Cu")
		(net "M_F_DQ<16>")
	)
	(segment
		(start 217.32494 -136.77646)
		(end 217.2208 -136.8806)
		(width 0.14224)
		(layer "In11.Cu")
		(net "M_F_DQ<16>")
	)
	(segment
		(start 217.28684 -148.47824)
		(end 217.28684 -148.960078)
		(width 0.14224)
		(layer "In11.Cu")
		(net "M_F_DQ<16>")
	)
	(segment
		(start 216.43594 -149.810978)
		(end 216.43594 -150.450296)
		(width 0.14224)
		(layer "In11.Cu")
		(net "M_F_DQ<16>")
	)
	(segment
		(start 217.27414 -141.5796)
		(end 217.2208 -141.63294)
		(width 0.14224)
		(layer "In11.Cu")
		(net "M_F_DQ<16>")
	)
	(segment
		(start 216.366852 -151.247348)
		(end 216.366852 -154.20721)
		(width 0.14224)
		(layer "In11.Cu")
		(net "M_F_DQ<16>")
	)
	(segment
		(start 217.27414 -143.74114)
		(end 217.27414 -144.085818)
		(width 0.14224)
		(layer "In11.Cu")
		(net "M_F_DQ<16>")
	)
	(segment
		(start 217.2208 -132.05714)
		(end 217.2208 -134.0612)
		(width 0.14224)
		(layer "In11.Cu")
		(net "M_F_DQ<16>")
	)
	(segment
		(start 217.2208 -136.8806)
		(end 217.2208 -138.7094)
		(width 0.14224)
		(layer "In11.Cu")
		(net "M_F_DQ<16>")
	)
	(segment
		(start 217.32494 -128.77546)
		(end 217.32494 -129.719578)
		(width 0.14224)
		(layer "In11.Cu")
		(net "M_F_DQ<16>")
	)
	(segment
		(start 217.2208 -134.0612)
		(end 217.32494 -134.16534)
		(width 0.14224)
		(layer "In11.Cu")
		(net "M_F_DQ<16>")
	)
	(segment
		(start 217.27414 -144.085818)
		(end 216.99474 -144.365218)
		(width 0.14224)
		(layer "In11.Cu")
		(net "M_F_DQ<16>")
	)
	(segment
		(start 234.0864 -101.627686)
		(end 234.0864 -102.335838)
		(width 0.0889)
		(layer "In11.Cu")
		(net "M_F_DQ<16>")
	)
	(segment
		(start 245.092728 -92.337636)
		(end 245.044468 -92.337636)
		(width 0.0889)
		(layer "In11.Cu")
		(net "M_F_DQ<16>")
	)
	(segment
		(start 217.32494 -131.953)
		(end 217.2208 -132.05714)
		(width 0.14224)
		(layer "In11.Cu")
		(net "M_F_DQ<16>")
	)
	(segment
		(start 232.04932 -104.071166)
		(end 232.04932 -106.504232)
		(width 0.14224)
		(layer "In11.Cu")
		(net "M_F_DQ<16>")
	)
	(segment
		(start 239.919764 -95.118936)
		(end 239.886998 -95.118936)
		(width 0.0889)
		(layer "In11.Cu")
		(net "M_F_DQ<16>")
	)
	(segment
		(start 216.366852 -154.20721)
		(end 217.175842 -155.0162)
		(width 0.14224)
		(layer "In11.Cu")
		(net "M_F_DQ<16>")
	)
	(segment
		(start 217.32494 -138.81354)
		(end 217.32494 -139.320778)
		(width 0.14224)
		(layer "In11.Cu")
		(net "M_F_DQ<16>")
	)
	(segment
		(start 217.175842 -155.0162)
		(end 217.472006 -155.0162)
		(width 0.14224)
		(layer "In11.Cu")
		(net "M_F_DQ<16>")
	)
	(segment
		(start 244.214904 -92.83319)
		(end 244.182138 -92.83319)
		(width 0.0889)
		(layer "In11.Cu")
		(net "M_F_DQ<16>")
	)
	(segment
		(start 237.340394 -96.60509)
		(end 237.307628 -96.60509)
		(width 0.0889)
		(layer "In11.Cu")
		(net "M_F_DQ<16>")
	)
	(segment
		(start 216.98204 -131.141978)
		(end 217.32494 -131.484878)
		(width 0.14224)
		(layer "In11.Cu")
		(net "M_F_DQ<16>")
	)
	(segment
		(start 217.32494 -131.484878)
		(end 217.32494 -131.953)
		(width 0.14224)
		(layer "In11.Cu")
		(net "M_F_DQ<16>")
	)
	(segment
		(start 243.57584 -93.137482)
		(end 243.338604 -93.137482)
		(width 0.0889)
		(layer "In11.Cu")
		(net "M_F_DQ<16>")
	)
	(segment
		(start 216.98204 -134.776718)
		(end 216.98204 -135.95604)
		(width 0.14224)
		(layer "In11.Cu")
		(net "M_F_DQ<16>")
	)
	(segment
		(start 217.28684 -145.861786)
		(end 217.28684 -146.2024)
		(width 0.14224)
		(layer "In11.Cu")
		(net "M_F_DQ<16>")
	)
	(segment
		(start 234.0864 -102.335838)
		(end 233.6546 -102.767638)
		(width 0.0889)
		(layer "In11.Cu")
		(net "M_F_DQ<16>")
	)
	(segment
		(start 233.6546 -102.767638)
		(end 233.352848 -102.767638)
		(width 0.0889)
		(layer "In11.Cu")
		(net "M_F_DQ<16>")
	)
	(segment
		(start 216.99474 -145.569686)
		(end 217.28684 -145.861786)
		(width 0.14224)
		(layer "In11.Cu")
		(net "M_F_DQ<16>")
	)
	(segment
		(start 235.100368 -100.462588)
		(end 235.105194 -100.471224)
		(width 0.0889)
		(layer "In11.Cu")
		(net "M_F_DQ<16>")
	)
	(segment
		(start 216.99474 -144.365218)
		(end 216.99474 -145.569686)
		(width 0.14224)
		(layer "In11.Cu")
		(net "M_F_DQ<16>")
	)
	(segment
		(start 217.27414 -141.035278)
		(end 217.27414 -141.5796)
		(width 0.14224)
		(layer "In11.Cu")
		(net "M_F_DQ<16>")
	)
	(segment
		(start 217.28684 -146.2024)
		(end 217.2208 -146.26844)
		(width 0.14224)
		(layer "In11.Cu")
		(net "M_F_DQ<16>")
	)
	(segment
		(start 238.202724 -96.109536)
		(end 238.169958 -96.109536)
		(width 0.0889)
		(layer "In11.Cu")
		(net "M_F_DQ<16>")
	)
	(arc
		(start 235.105194 -100.471224)
		(mid 235.101447 -100.86048)
		(end 234.768644 -101.062536)
		(width 0.0889)
		(layer "In11.Cu")
		(net "M_F_DQ<16>")
	)
	(arc
		(start 239.392968 -95.414338)
		(mid 239.251285 -95.558142)
		(end 239.057434 -95.61449)
		(width 0.0889)
		(layer "In11.Cu")
		(net "M_F_DQ<16>")
	)
	(arc
		(start 241.110008 -94.423484)
		(mid 240.968325 -94.567288)
		(end 240.774474 -94.623636)
		(width 0.0889)
		(layer "In11.Cu")
		(net "M_F_DQ<16>")
	)
	(arc
		(start 239.886998 -95.118936)
		(mid 239.601574 -95.202403)
		(end 239.392968 -95.414338)
		(width 0.0889)
		(layer "In11.Cu")
		(net "M_F_DQ<16>")
	)
	(arc
		(start 240.750344 -94.623636)
		(mid 240.462199 -94.705955)
		(end 240.251488 -94.919038)
		(width 0.0889)
		(layer "In11.Cu")
		(net "M_F_DQ<16>")
	)
	(arc
		(start 235.094018 -99.882706)
		(mid 235.02122 -100.173469)
		(end 235.100368 -100.462588)
		(width 0.0889)
		(layer "In11.Cu")
		(net "M_F_DQ<16>")
	)
	(arc
		(start 235.100368 -98.881438)
		(mid 235.021237 -99.17684)
		(end 235.100368 -99.472242)
		(width 0.0889)
		(layer "In11.Cu")
		(net "M_F_DQ<16>")
	)
	(arc
		(start 235.590588 -97.59569)
		(mid 235.095111 -97.900133)
		(end 235.100368 -98.481642)
		(width 0.0889)
		(layer "In11.Cu")
		(net "M_F_DQ<16>")
	)
	(arc
		(start 235.958888 -97.395538)
		(mid 235.817205 -97.539342)
		(end 235.623354 -97.59569)
		(width 0.0889)
		(layer "In11.Cu")
		(net "M_F_DQ<16>")
	)
	(arc
		(start 241.968528 -93.928438)
		(mid 241.829784 -94.070471)
		(end 241.639852 -94.128336)
		(width 0.0889)
		(layer "In11.Cu")
		(net "M_F_DQ<16>")
	)
	(arc
		(start 235.100368 -99.472242)
		(mid 235.153867 -99.67214)
		(end 235.100368 -99.872038)
		(width 0.0889)
		(layer "In11.Cu")
		(net "M_F_DQ<16>")
	)
	(arc
		(start 240.251488 -94.919038)
		(mid 240.111409 -95.061774)
		(end 239.919764 -95.118936)
		(width 0.0889)
		(layer "In11.Cu")
		(net "M_F_DQ<16>")
	)
	(arc
		(start 244.708934 -92.537788)
		(mid 244.500326 -92.74972)
		(end 244.214904 -92.83319)
		(width 0.0889)
		(layer "In11.Cu")
		(net "M_F_DQ<16>")
	)
	(arc
		(start 239.024668 -95.61449)
		(mid 238.741451 -95.698771)
		(end 238.534448 -95.909638)
		(width 0.0889)
		(layer "In11.Cu")
		(net "M_F_DQ<16>")
	)
	(arc
		(start 245.044468 -92.337636)
		(mid 244.850618 -92.393986)
		(end 244.708934 -92.537788)
		(width 0.0889)
		(layer "In11.Cu")
		(net "M_F_DQ<16>")
	)
	(arc
		(start 241.600228 -94.128336)
		(mid 241.317011 -94.212617)
		(end 241.110008 -94.423484)
		(width 0.0889)
		(layer "In11.Cu")
		(net "M_F_DQ<16>")
	)
	(arc
		(start 234.735878 -101.062536)
		(mid 234.450454 -101.146003)
		(end 234.241848 -101.357938)
		(width 0.0889)
		(layer "In11.Cu")
		(net "M_F_DQ<16>")
	)
	(arc
		(start 242.462558 -93.633036)
		(mid 242.177134 -93.716503)
		(end 241.968528 -93.928438)
		(width 0.0889)
		(layer "In11.Cu")
		(net "M_F_DQ<16>")
	)
	(arc
		(start 235.100368 -98.481642)
		(mid 235.153867 -98.68154)
		(end 235.100368 -98.881438)
		(width 0.0889)
		(layer "In11.Cu")
		(net "M_F_DQ<16>")
	)
	(arc
		(start 244.182138 -92.83319)
		(mid 244.078297 -92.850393)
		(end 243.981986 -92.89288)
		(width 0.0889)
		(layer "In11.Cu")
		(net "M_F_DQ<16>")
	)
	(arc
		(start 236.817408 -96.900238)
		(mid 236.677329 -97.042974)
		(end 236.485684 -97.100136)
		(width 0.0889)
		(layer "In11.Cu")
		(net "M_F_DQ<16>")
	)
	(arc
		(start 238.534448 -95.909638)
		(mid 238.394369 -96.052374)
		(end 238.202724 -96.109536)
		(width 0.0889)
		(layer "In11.Cu")
		(net "M_F_DQ<16>")
	)
	(arc
		(start 242.826794 -93.433138)
		(mid 242.685637 -93.576523)
		(end 242.49253 -93.633036)
		(width 0.0889)
		(layer "In11.Cu")
		(net "M_F_DQ<16>")
	)
	(arc
		(start 237.675928 -96.404938)
		(mid 237.534245 -96.548742)
		(end 237.340394 -96.60509)
		(width 0.0889)
		(layer "In11.Cu")
		(net "M_F_DQ<16>")
	)
	(arc
		(start 238.169958 -96.109536)
		(mid 237.884534 -96.193003)
		(end 237.675928 -96.404938)
		(width 0.0889)
		(layer "In11.Cu")
		(net "M_F_DQ<16>")
	)
	(arc
		(start 237.307628 -96.60509)
		(mid 237.024411 -96.689371)
		(end 236.817408 -96.900238)
		(width 0.0889)
		(layer "In11.Cu")
		(net "M_F_DQ<16>")
	)
	(arc
		(start 243.338604 -93.137482)
		(mid 243.046023 -93.214795)
		(end 242.830096 -93.426788)
		(width 0.0889)
		(layer "In11.Cu")
		(net "M_F_DQ<16>")
	)
	(arc
		(start 236.452918 -97.100136)
		(mid 236.167494 -97.183603)
		(end 235.958888 -97.395538)
		(width 0.0889)
		(layer "In11.Cu")
		(net "M_F_DQ<16>")
	)
	(segment
		(start 211.699856 -152.278842)
		(end 211.699856 -153.542746)
		(width 0.1651)
		(layer "F.Cu")
		(net "M_F_DQ<15>")
	)
	(segment
		(start 240.476278 -92.737686)
		(end 239.904778 -92.737686)
		(width 0.1651)
		(layer "F.Cu")
		(net "M_F_DQ<15>")
	)
	(segment
		(start 211.700364 -152.273)
		(end 211.699856 -152.278842)
		(width 0.1651)
		(layer "F.Cu")
		(net "M_F_DQ<15>")
	)
	(via
		(at 239.904778 -92.737686)
		(size 0.508)
		(drill 0.254)
		(layers "F.Cu" "B.Cu")
		(net "M_F_DQ<15>")
	)
	(via
		(at 212.54974 -149.533356)
		(size 0.508)
		(drill 0.254)
		(layers "F.Cu" "B.Cu")
		(net "M_F_DQ<15>")
	)
	(via
		(at 211.699856 -153.542746)
		(size 0.508)
		(drill 0.254)
		(layers "F.Cu" "B.Cu")
		(net "M_F_DQ<15>")
	)
	(segment
		(start 212.550502 -149.532594)
		(end 212.54974 -149.533356)
		(width 0.1651)
		(layer "B.Cu")
		(net "M_F_DQ<15>")
	)
	(segment
		(start 212.550502 -147.478496)
		(end 212.550502 -149.532594)
		(width 0.1651)
		(layer "B.Cu")
		(net "M_F_DQ<15>")
	)
	(segment
		(start 212.979 -134.0104)
		(end 212.81263 -134.17677)
		(width 0.14224)
		(layer "In11.Cu")
		(net "M_F_DQ<15>")
	)
	(segment
		(start 225.478086 -107.77474)
		(end 225.478086 -108.036868)
		(width 0.14224)
		(layer "In11.Cu")
		(net "M_F_DQ<15>")
	)
	(segment
		(start 234.771438 -95.30969)
		(end 234.735624 -95.30969)
		(width 0.0889)
		(layer "In11.Cu")
		(net "M_F_DQ<15>")
	)
	(segment
		(start 212.979 -131.953254)
		(end 212.979 -134.0104)
		(width 0.14224)
		(layer "In11.Cu")
		(net "M_F_DQ<15>")
	)
	(segment
		(start 212.741764 -141.105636)
		(end 212.741764 -141.444218)
		(width 0.14224)
		(layer "In11.Cu")
		(net "M_F_DQ<15>")
	)
	(segment
		(start 212.979 -146.5072)
		(end 212.979 -148.411946)
		(width 0.14224)
		(layer "In11.Cu")
		(net "M_F_DQ<15>")
	)
	(segment
		(start 212.8012 -136.322054)
		(end 212.8012 -136.652254)
		(width 0.14224)
		(layer "In11.Cu")
		(net "M_F_DQ<15>")
	)
	(segment
		(start 232.172764 -98.930206)
		(end 230.14559 -98.930206)
		(width 0.0889)
		(layer "In11.Cu")
		(net "M_F_DQ<15>")
	)
	(segment
		(start 212.149944 -153.04135)
		(end 212.149944 -153.364946)
		(width 0.14224)
		(layer "In11.Cu")
		(net "M_F_DQ<15>")
	)
	(segment
		(start 237.350808 -93.82379)
		(end 237.311184 -93.82379)
		(width 0.0889)
		(layer "In11.Cu")
		(net "M_F_DQ<15>")
	)
	(segment
		(start 213.233 -134.884922)
		(end 213.233 -135.890254)
		(width 0.14224)
		(layer "In11.Cu")
		(net "M_F_DQ<15>")
	)
	(segment
		(start 212.54974 -149.533356)
		(end 212.527388 -149.533356)
		(width 0.14224)
		(layer "In11.Cu")
		(net "M_F_DQ<15>")
	)
	(segment
		(start 229.0064 -102.209346)
		(end 221.09811 -110.117636)
		(width 0.14224)
		(layer "In11.Cu")
		(net "M_F_DQ<15>")
	)
	(segment
		(start 232.909364 -96.060006)
		(end 232.487216 -96.482154)
		(width 0.0889)
		(layer "In11.Cu")
		(net "M_F_DQ<15>")
	)
	(segment
		(start 213.106 -129.1082)
		(end 212.8774 -129.3368)
		(width 0.14224)
		(layer "In11.Cu")
		(net "M_F_DQ<15>")
	)
	(segment
		(start 213.1314 -145.6182)
		(end 212.817964 -145.931636)
		(width 0.14224)
		(layer "In11.Cu")
		(net "M_F_DQ<15>")
	)
	(segment
		(start 211.861146 -152.479248)
		(end 211.861146 -152.752552)
		(width 0.14224)
		(layer "In11.Cu")
		(net "M_F_DQ<15>")
	)
	(segment
		(start 212.8012 -139.359132)
		(end 213.2076 -139.765532)
		(width 0.14224)
		(layer "In11.Cu")
		(net "M_F_DQ<15>")
	)
	(segment
		(start 212.979 -141.681454)
		(end 212.979 -143.5608)
		(width 0.14224)
		(layer "In11.Cu")
		(net "M_F_DQ<15>")
	)
	(segment
		(start 212.81263 -134.17677)
		(end 212.81263 -134.464552)
		(width 0.14224)
		(layer "In11.Cu")
		(net "M_F_DQ<15>")
	)
	(segment
		(start 238.200692 -93.32849)
		(end 238.176562 -93.32849)
		(width 0.0889)
		(layer "In11.Cu")
		(net "M_F_DQ<15>")
	)
	(segment
		(start 225.478086 -108.036868)
		(end 213.106 -120.408954)
		(width 0.14224)
		(layer "In11.Cu")
		(net "M_F_DQ<15>")
	)
	(segment
		(start 239.904778 -92.737686)
		(end 239.082326 -92.83319)
		(width 0.0889)
		(layer "In11.Cu")
		(net "M_F_DQ<15>")
	)
	(segment
		(start 212.143594 -151.1046)
		(end 211.861146 -151.387048)
		(width 0.14224)
		(layer "In11.Cu")
		(net "M_F_DQ<15>")
	)
	(segment
		(start 212.741764 -141.444218)
		(end 212.979 -141.681454)
		(width 0.14224)
		(layer "In11.Cu")
		(net "M_F_DQ<15>")
	)
	(segment
		(start 213.1314 -144.373092)
		(end 213.1314 -145.6182)
		(width 0.14224)
		(layer "In11.Cu")
		(net "M_F_DQ<15>")
	)
	(segment
		(start 212.099144 -149.9616)
		(end 212.099144 -150.391368)
		(width 0.14224)
		(layer "In11.Cu")
		(net "M_F_DQ<15>")
	)
	(segment
		(start 229.0064 -100.069396)
		(end 229.0064 -102.209346)
		(width 0.14224)
		(layer "In11.Cu")
		(net "M_F_DQ<15>")
	)
	(segment
		(start 212.817964 -145.931636)
		(end 212.817964 -146.346164)
		(width 0.14224)
		(layer "In11.Cu")
		(net "M_F_DQ<15>")
	)
	(segment
		(start 212.143594 -150.435818)
		(end 212.143594 -151.1046)
		(width 0.14224)
		(layer "In11.Cu")
		(net "M_F_DQ<15>")
	)
	(segment
		(start 211.861146 -151.660352)
		(end 212.118194 -151.9174)
		(width 0.14224)
		(layer "In11.Cu")
		(net "M_F_DQ<15>")
	)
	(segment
		(start 212.902546 -149.191472)
		(end 212.891624 -149.191472)
		(width 0.14224)
		(layer "In11.Cu")
		(net "M_F_DQ<15>")
	)
	(segment
		(start 234.376214 -95.54845)
		(end 233.864658 -96.060006)
		(width 0.0889)
		(layer "In11.Cu")
		(net "M_F_DQ<15>")
	)
	(segment
		(start 229.94239 -99.133406)
		(end 229.0064 -100.069396)
		(width 0.14224)
		(layer "In11.Cu")
		(net "M_F_DQ<15>")
	)
	(segment
		(start 211.972144 -153.542746)
		(end 211.699856 -153.542746)
		(width 0.14224)
		(layer "In11.Cu")
		(net "M_F_DQ<15>")
	)
	(segment
		(start 212.891624 -149.191472)
		(end 212.54974 -149.533356)
		(width 0.14224)
		(layer "In11.Cu")
		(net "M_F_DQ<15>")
	)
	(segment
		(start 212.118194 -151.9174)
		(end 212.118194 -152.2222)
		(width 0.14224)
		(layer "In11.Cu")
		(net "M_F_DQ<15>")
	)
	(segment
		(start 212.825076 -131.79933)
		(end 212.979 -131.953254)
		(width 0.14224)
		(layer "In11.Cu")
		(net "M_F_DQ<15>")
	)
	(segment
		(start 232.487216 -98.615754)
		(end 232.172764 -98.930206)
		(width 0.0889)
		(layer "In11.Cu")
		(net "M_F_DQ<15>")
	)
	(segment
		(start 225.190812 -107.487466)
		(end 225.478086 -107.77474)
		(width 0.14224)
		(layer "In11.Cu")
		(net "M_F_DQ<15>")
	)
	(segment
		(start 235.625132 -94.81439)
		(end 235.597192 -94.81439)
		(width 0.0889)
		(layer "In11.Cu")
		(net "M_F_DQ<15>")
	)
	(segment
		(start 213.2076 -139.765532)
		(end 213.2076 -140.6398)
		(width 0.14224)
		(layer "In11.Cu")
		(net "M_F_DQ<15>")
	)
	(segment
		(start 221.09811 -110.405164)
		(end 221.385384 -110.692438)
		(width 0.14224)
		(layer "In11.Cu")
		(net "M_F_DQ<15>")
	)
	(segment
		(start 221.672912 -110.692438)
		(end 224.877884 -107.487466)
		(width 0.14224)
		(layer "In11.Cu")
		(net "M_F_DQ<15>")
	)
	(segment
		(start 212.792818 -144.03451)
		(end 213.1314 -144.373092)
		(width 0.14224)
		(layer "In11.Cu")
		(net "M_F_DQ<15>")
	)
	(segment
		(start 213.233 -135.890254)
		(end 212.8012 -136.322054)
		(width 0.14224)
		(layer "In11.Cu")
		(net "M_F_DQ<15>")
	)
	(segment
		(start 221.385384 -110.692438)
		(end 221.672912 -110.692438)
		(width 0.14224)
		(layer "In11.Cu")
		(net "M_F_DQ<15>")
	)
	(segment
		(start 213.131146 -131.140454)
		(end 212.825076 -131.446524)
		(width 0.14224)
		(layer "In11.Cu")
		(net "M_F_DQ<15>")
	)
	(segment
		(start 212.81263 -134.464552)
		(end 213.233 -134.884922)
		(width 0.14224)
		(layer "In11.Cu")
		(net "M_F_DQ<15>")
	)
	(segment
		(start 212.527388 -149.533356)
		(end 212.099144 -149.9616)
		(width 0.14224)
		(layer "In11.Cu")
		(net "M_F_DQ<15>")
	)
	(segment
		(start 211.861146 -152.752552)
		(end 212.149944 -153.04135)
		(width 0.14224)
		(layer "In11.Cu")
		(net "M_F_DQ<15>")
	)
	(segment
		(start 212.792818 -143.746982)
		(end 212.792818 -144.03451)
		(width 0.14224)
		(layer "In11.Cu")
		(net "M_F_DQ<15>")
	)
	(segment
		(start 224.877884 -107.487466)
		(end 225.190812 -107.487466)
		(width 0.14224)
		(layer "In11.Cu")
		(net "M_F_DQ<15>")
	)
	(segment
		(start 230.14559 -98.930206)
		(end 229.94239 -99.133406)
		(width 0.0889)
		(layer "In11.Cu")
		(net "M_F_DQ<15>")
	)
	(segment
		(start 239.082326 -92.83319)
		(end 239.031272 -92.83319)
		(width 0.0889)
		(layer "In11.Cu")
		(net "M_F_DQ<15>")
	)
	(segment
		(start 212.149944 -153.364946)
		(end 211.972144 -153.542746)
		(width 0.14224)
		(layer "In11.Cu")
		(net "M_F_DQ<15>")
	)
	(segment
		(start 212.8012 -136.652254)
		(end 212.979 -136.830054)
		(width 0.14224)
		(layer "In11.Cu")
		(net "M_F_DQ<15>")
	)
	(segment
		(start 212.817964 -146.346164)
		(end 212.979 -146.5072)
		(width 0.14224)
		(layer "In11.Cu")
		(net "M_F_DQ<15>")
	)
	(segment
		(start 213.106 -120.408954)
		(end 213.106 -129.1082)
		(width 0.14224)
		(layer "In11.Cu")
		(net "M_F_DQ<15>")
	)
	(segment
		(start 221.09811 -110.117636)
		(end 221.09811 -110.405164)
		(width 0.14224)
		(layer "In11.Cu")
		(net "M_F_DQ<15>")
	)
	(segment
		(start 211.861146 -151.387048)
		(end 211.861146 -151.660352)
		(width 0.14224)
		(layer "In11.Cu")
		(net "M_F_DQ<15>")
	)
	(segment
		(start 213.2076 -140.6398)
		(end 212.741764 -141.105636)
		(width 0.14224)
		(layer "In11.Cu")
		(net "M_F_DQ<15>")
	)
	(segment
		(start 236.488478 -94.31909)
		(end 236.452664 -94.31909)
		(width 0.0889)
		(layer "In11.Cu")
		(net "M_F_DQ<15>")
	)
	(segment
		(start 233.864658 -96.060006)
		(end 232.909364 -96.060006)
		(width 0.0889)
		(layer "In11.Cu")
		(net "M_F_DQ<15>")
	)
	(segment
		(start 213.131146 -130.087878)
		(end 213.131146 -131.140454)
		(width 0.14224)
		(layer "In11.Cu")
		(net "M_F_DQ<15>")
	)
	(segment
		(start 212.8012 -138.9126)
		(end 212.8012 -139.359132)
		(width 0.14224)
		(layer "In11.Cu")
		(net "M_F_DQ<15>")
	)
	(segment
		(start 212.979 -136.830054)
		(end 212.979 -138.7348)
		(width 0.14224)
		(layer "In11.Cu")
		(net "M_F_DQ<15>")
	)
	(segment
		(start 212.8774 -129.3368)
		(end 212.8774 -129.834132)
		(width 0.14224)
		(layer "In11.Cu")
		(net "M_F_DQ<15>")
	)
	(segment
		(start 212.8774 -129.834132)
		(end 213.131146 -130.087878)
		(width 0.14224)
		(layer "In11.Cu")
		(net "M_F_DQ<15>")
	)
	(segment
		(start 212.902546 -148.4884)
		(end 212.902546 -149.191472)
		(width 0.14224)
		(layer "In11.Cu")
		(net "M_F_DQ<15>")
	)
	(segment
		(start 212.825076 -131.446524)
		(end 212.825076 -131.79933)
		(width 0.14224)
		(layer "In11.Cu")
		(net "M_F_DQ<15>")
	)
	(segment
		(start 212.979 -143.5608)
		(end 212.792818 -143.746982)
		(width 0.14224)
		(layer "In11.Cu")
		(net "M_F_DQ<15>")
	)
	(segment
		(start 212.118194 -152.2222)
		(end 211.861146 -152.479248)
		(width 0.14224)
		(layer "In11.Cu")
		(net "M_F_DQ<15>")
	)
	(segment
		(start 232.487216 -96.482154)
		(end 232.487216 -98.615754)
		(width 0.0889)
		(layer "In11.Cu")
		(net "M_F_DQ<15>")
	)
	(segment
		(start 212.979 -138.7348)
		(end 212.8012 -138.9126)
		(width 0.14224)
		(layer "In11.Cu")
		(net "M_F_DQ<15>")
	)
	(segment
		(start 212.979 -148.411946)
		(end 212.902546 -148.4884)
		(width 0.14224)
		(layer "In11.Cu")
		(net "M_F_DQ<15>")
	)
	(segment
		(start 212.099144 -150.391368)
		(end 212.143594 -150.435818)
		(width 0.14224)
		(layer "In11.Cu")
		(net "M_F_DQ<15>")
	)
	(arc
		(start 237.311184 -93.82379)
		(mid 237.121255 -93.88166)
		(end 236.982508 -94.023688)
		(width 0.0889)
		(layer "In11.Cu")
		(net "M_F_DQ<15>")
	)
	(arc
		(start 239.031272 -92.83319)
		(mid 238.83963 -92.890356)
		(end 238.699548 -93.033088)
		(width 0.0889)
		(layer "In11.Cu")
		(net "M_F_DQ<15>")
	)
	(arc
		(start 236.452664 -94.31909)
		(mid 236.262735 -94.37696)
		(end 236.123988 -94.518988)
		(width 0.0889)
		(layer "In11.Cu")
		(net "M_F_DQ<15>")
	)
	(arc
		(start 237.841028 -93.528642)
		(mid 237.634024 -93.739506)
		(end 237.350808 -93.82379)
		(width 0.0889)
		(layer "In11.Cu")
		(net "M_F_DQ<15>")
	)
	(arc
		(start 234.406948 -95.509588)
		(mid 234.392989 -95.530131)
		(end 234.376214 -95.54845)
		(width 0.0889)
		(layer "In11.Cu")
		(net "M_F_DQ<15>")
	)
	(arc
		(start 235.597192 -94.81439)
		(mid 235.40555 -94.871556)
		(end 235.265468 -95.014288)
		(width 0.0889)
		(layer "In11.Cu")
		(net "M_F_DQ<15>")
	)
	(arc
		(start 236.123988 -94.518988)
		(mid 235.913275 -94.732067)
		(end 235.625132 -94.81439)
		(width 0.0889)
		(layer "In11.Cu")
		(net "M_F_DQ<15>")
	)
	(arc
		(start 235.265468 -95.014288)
		(mid 235.05686 -95.22622)
		(end 234.771438 -95.30969)
		(width 0.0889)
		(layer "In11.Cu")
		(net "M_F_DQ<15>")
	)
	(arc
		(start 238.176562 -93.32849)
		(mid 237.982712 -93.38484)
		(end 237.841028 -93.528642)
		(width 0.0889)
		(layer "In11.Cu")
		(net "M_F_DQ<15>")
	)
	(arc
		(start 236.982508 -94.023688)
		(mid 236.7739 -94.23562)
		(end 236.488478 -94.31909)
		(width 0.0889)
		(layer "In11.Cu")
		(net "M_F_DQ<15>")
	)
	(arc
		(start 234.735624 -95.30969)
		(mid 234.545695 -95.36756)
		(end 234.406948 -95.509588)
		(width 0.0889)
		(layer "In11.Cu")
		(net "M_F_DQ<15>")
	)
	(arc
		(start 238.699548 -93.033088)
		(mid 238.488835 -93.246167)
		(end 238.200692 -93.32849)
		(width 0.0889)
		(layer "In11.Cu")
		(net "M_F_DQ<15>")
	)
	(segment
		(start 212.549994 -156.87294)
		(end 212.549994 -155.9052)
		(width 0.1651)
		(layer "F.Cu")
		(net "M_F_DQ<14>")
	)
	(segment
		(start 212.550502 -156.87294)
		(end 212.549994 -156.87294)
		(width 0.1651)
		(layer "F.Cu")
		(net "M_F_DQ<14>")
	)
	(segment
		(start 212.549994 -155.4226)
		(end 212.549994 -155.118054)
		(width 0.1651)
		(layer "F.Cu")
		(net "M_F_DQ<14>")
	)
	(segment
		(start 212.549994 -155.118054)
		(end 212.54974 -155.1178)
		(width 0.1651)
		(layer "F.Cu")
		(net "M_F_DQ<14>")
	)
	(segment
		(start 212.549994 -155.9052)
		(end 212.682074 -155.77312)
		(width 0.1651)
		(layer "F.Cu")
		(net "M_F_DQ<14>")
	)
	(segment
		(start 240.476278 -91.747086)
		(end 239.904778 -91.747086)
		(width 0.1651)
		(layer "F.Cu")
		(net "M_F_DQ<14>")
	)
	(segment
		(start 212.682074 -155.77312)
		(end 212.682074 -155.55468)
		(width 0.1651)
		(layer "F.Cu")
		(net "M_F_DQ<14>")
	)
	(segment
		(start 212.682074 -155.55468)
		(end 212.549994 -155.4226)
		(width 0.1651)
		(layer "F.Cu")
		(net "M_F_DQ<14>")
	)
	(via
		(at 239.904778 -91.747086)
		(size 0.508)
		(drill 0.254)
		(layers "F.Cu" "B.Cu")
		(net "M_F_DQ<14>")
	)
	(via
		(at 211.699856 -150.814278)
		(size 0.508)
		(drill 0.254)
		(layers "F.Cu" "B.Cu")
		(net "M_F_DQ<14>")
	)
	(via
		(at 212.54974 -155.1178)
		(size 0.508)
		(drill 0.254)
		(layers "F.Cu" "B.Cu")
		(net "M_F_DQ<14>")
	)
	(segment
		(start 211.700364 -152.078436)
		(end 211.699856 -152.078182)
		(width 0.1651)
		(layer "B.Cu")
		(net "M_F_DQ<14>")
	)
	(segment
		(start 211.699856 -152.078182)
		(end 211.699856 -150.814278)
		(width 0.1651)
		(layer "B.Cu")
		(net "M_F_DQ<14>")
	)
	(segment
		(start 236.488732 -94.128336)
		(end 236.449108 -94.128336)
		(width 0.0889)
		(layer "In11.Cu")
		(net "M_F_DQ<14>")
	)
	(segment
		(start 212.216746 -141.060678)
		(end 212.216746 -141.5542)
		(width 0.14224)
		(layer "In11.Cu")
		(net "M_F_DQ<14>")
	)
	(segment
		(start 221.02064 -111.579914)
		(end 212.471 -120.129554)
		(width 0.14224)
		(layer "In11.Cu")
		(net "M_F_DQ<14>")
	)
	(segment
		(start 212.267546 -136.270492)
		(end 212.267546 -136.4996)
		(width 0.14224)
		(layer "In11.Cu")
		(net "M_F_DQ<14>")
	)
	(segment
		(start 221.02064 -111.292386)
		(end 221.02064 -111.579914)
		(width 0.14224)
		(layer "In11.Cu")
		(net "M_F_DQ<14>")
	)
	(segment
		(start 228.3968 -99.5172)
		(end 228.3968 -101.904546)
		(width 0.14224)
		(layer "In11.Cu")
		(net "M_F_DQ<14>")
	)
	(segment
		(start 211.530946 -149.671278)
		(end 211.530946 -150.645368)
		(width 0.14224)
		(layer "In11.Cu")
		(net "M_F_DQ<14>")
	)
	(segment
		(start 237.347252 -93.633036)
		(end 237.311438 -93.633036)
		(width 0.0889)
		(layer "In11.Cu")
		(net "M_F_DQ<14>")
	)
	(segment
		(start 212.064346 -136.067292)
		(end 212.267546 -136.270492)
		(width 0.14224)
		(layer "In11.Cu")
		(net "M_F_DQ<14>")
	)
	(segment
		(start 230.02367 -98.498406)
		(end 229.415594 -98.498406)
		(width 0.14224)
		(layer "In11.Cu")
		(net "M_F_DQ<14>")
	)
	(segment
		(start 212.267546 -148.934678)
		(end 211.530946 -149.671278)
		(width 0.14224)
		(layer "In11.Cu")
		(net "M_F_DQ<14>")
	)
	(segment
		(start 212.064346 -139.663678)
		(end 212.064346 -140.908278)
		(width 0.14224)
		(layer "In11.Cu")
		(net "M_F_DQ<14>")
	)
	(segment
		(start 239.057434 -92.64269)
		(end 239.024668 -92.64269)
		(width 0.0889)
		(layer "In11.Cu")
		(net "M_F_DQ<14>")
	)
	(segment
		(start 239.409732 -92.413074)
		(end 239.392968 -92.442538)
		(width 0.0889)
		(layer "In11.Cu")
		(net "M_F_DQ<14>")
	)
	(segment
		(start 232.830624 -95.870014)
		(end 232.297224 -96.403414)
		(width 0.0889)
		(layer "In11.Cu")
		(net "M_F_DQ<14>")
	)
	(segment
		(start 216.856564 -113.444782)
		(end 216.856564 -113.73231)
		(width 0.14224)
		(layer "In11.Cu")
		(net "M_F_DQ<14>")
	)
	(segment
		(start 212.165946 -131.408678)
		(end 212.165946 -134.579868)
		(width 0.14224)
		(layer "In11.Cu")
		(net "M_F_DQ<14>")
	)
	(segment
		(start 212.267546 -138.963146)
		(end 212.267546 -139.460478)
		(width 0.14224)
		(layer "In11.Cu")
		(net "M_F_DQ<14>")
	)
	(segment
		(start 212.165946 -134.579868)
		(end 212.064346 -134.681468)
		(width 0.14224)
		(layer "In11.Cu")
		(net "M_F_DQ<14>")
	)
	(segment
		(start 220.733366 -111.005112)
		(end 221.02064 -111.292386)
		(width 0.14224)
		(layer "In11.Cu")
		(net "M_F_DQ<14>")
	)
	(segment
		(start 217.431366 -114.019584)
		(end 220.445838 -111.005112)
		(width 0.14224)
		(layer "In11.Cu")
		(net "M_F_DQ<14>")
	)
	(segment
		(start 211.266786 -151.247348)
		(end 211.266786 -153.834846)
		(width 0.14224)
		(layer "In11.Cu")
		(net "M_F_DQ<14>")
	)
	(segment
		(start 212.1154 -143.637)
		(end 212.216746 -143.738346)
		(width 0.14224)
		(layer "In11.Cu")
		(net "M_F_DQ<14>")
	)
	(segment
		(start 232.094024 -98.740214)
		(end 230.265478 -98.740214)
		(width 0.0889)
		(layer "In11.Cu")
		(net "M_F_DQ<14>")
	)
	(segment
		(start 212.216746 -144.118838)
		(end 211.944204 -144.39138)
		(width 0.14224)
		(layer "In11.Cu")
		(net "M_F_DQ<14>")
	)
	(segment
		(start 211.530946 -150.645368)
		(end 211.699856 -150.814278)
		(width 0.14224)
		(layer "In11.Cu")
		(net "M_F_DQ<14>")
	)
	(segment
		(start 232.297224 -98.537014)
		(end 232.094024 -98.740214)
		(width 0.0889)
		(layer "In11.Cu")
		(net "M_F_DQ<14>")
	)
	(segment
		(start 234.241848 -95.414084)
		(end 233.785918 -95.870014)
		(width 0.0889)
		(layer "In11.Cu")
		(net "M_F_DQ<14>")
	)
	(segment
		(start 212.1154 -141.655546)
		(end 212.1154 -143.637)
		(width 0.14224)
		(layer "In11.Cu")
		(net "M_F_DQ<14>")
	)
	(segment
		(start 211.699856 -150.814278)
		(end 211.266786 -151.247348)
		(width 0.14224)
		(layer "In11.Cu")
		(net "M_F_DQ<14>")
	)
	(segment
		(start 212.1154 -136.651746)
		(end 212.1154 -138.811)
		(width 0.14224)
		(layer "In11.Cu")
		(net "M_F_DQ<14>")
	)
	(segment
		(start 238.202724 -93.137736)
		(end 238.174784 -93.137736)
		(width 0.0889)
		(layer "In11.Cu")
		(net "M_F_DQ<14>")
	)
	(segment
		(start 211.944204 -145.534126)
		(end 212.1916 -145.781522)
		(width 0.14224)
		(layer "In11.Cu")
		(net "M_F_DQ<14>")
	)
	(segment
		(start 212.1916 -146.176746)
		(end 212.1154 -146.252946)
		(width 0.14224)
		(layer "In11.Cu")
		(net "M_F_DQ<14>")
	)
	(segment
		(start 211.266786 -153.834846)
		(end 212.54974 -155.1178)
		(width 0.14224)
		(layer "In11.Cu")
		(net "M_F_DQ<14>")
	)
	(segment
		(start 228.3968 -101.904546)
		(end 216.856564 -113.444782)
		(width 0.14224)
		(layer "In11.Cu")
		(net "M_F_DQ<14>")
	)
	(segment
		(start 230.265478 -98.740214)
		(end 230.02367 -98.498406)
		(width 0.0889)
		(layer "In11.Cu")
		(net "M_F_DQ<14>")
	)
	(segment
		(start 216.856564 -113.73231)
		(end 217.143838 -114.019584)
		(width 0.14224)
		(layer "In11.Cu")
		(net "M_F_DQ<14>")
	)
	(segment
		(start 212.1154 -138.811)
		(end 212.267546 -138.963146)
		(width 0.14224)
		(layer "In11.Cu")
		(net "M_F_DQ<14>")
	)
	(segment
		(start 212.471 -128.8034)
		(end 212.1662 -129.1082)
		(width 0.14224)
		(layer "In11.Cu")
		(net "M_F_DQ<14>")
	)
	(segment
		(start 212.064346 -140.908278)
		(end 212.216746 -141.060678)
		(width 0.14224)
		(layer "In11.Cu")
		(net "M_F_DQ<14>")
	)
	(segment
		(start 217.143838 -114.019584)
		(end 217.431366 -114.019584)
		(width 0.14224)
		(layer "In11.Cu")
		(net "M_F_DQ<14>")
	)
	(segment
		(start 220.445838 -111.005112)
		(end 220.733366 -111.005112)
		(width 0.14224)
		(layer "In11.Cu")
		(net "M_F_DQ<14>")
	)
	(segment
		(start 234.771692 -95.118936)
		(end 234.732068 -95.118936)
		(width 0.0889)
		(layer "In11.Cu")
		(net "M_F_DQ<14>")
	)
	(segment
		(start 211.944204 -144.39138)
		(end 211.944204 -145.534126)
		(width 0.14224)
		(layer "In11.Cu")
		(net "M_F_DQ<14>")
	)
	(segment
		(start 212.267546 -136.4996)
		(end 212.1154 -136.651746)
		(width 0.14224)
		(layer "In11.Cu")
		(net "M_F_DQ<14>")
	)
	(segment
		(start 212.216746 -141.5542)
		(end 212.1154 -141.655546)
		(width 0.14224)
		(layer "In11.Cu")
		(net "M_F_DQ<14>")
	)
	(segment
		(start 239.904778 -91.747086)
		(end 239.409732 -92.413074)
		(width 0.0889)
		(layer "In11.Cu")
		(net "M_F_DQ<14>")
	)
	(segment
		(start 233.785918 -95.870014)
		(end 232.830624 -95.870014)
		(width 0.0889)
		(layer "In11.Cu")
		(net "M_F_DQ<14>")
	)
	(segment
		(start 212.1662 -129.960624)
		(end 212.064346 -130.062478)
		(width 0.14224)
		(layer "In11.Cu")
		(net "M_F_DQ<14>")
	)
	(segment
		(start 212.216746 -143.738346)
		(end 212.216746 -144.118838)
		(width 0.14224)
		(layer "In11.Cu")
		(net "M_F_DQ<14>")
	)
	(segment
		(start 212.267546 -148.615146)
		(end 212.267546 -148.934678)
		(width 0.14224)
		(layer "In11.Cu")
		(net "M_F_DQ<14>")
	)
	(segment
		(start 212.064346 -131.307078)
		(end 212.165946 -131.408678)
		(width 0.14224)
		(layer "In11.Cu")
		(net "M_F_DQ<14>")
	)
	(segment
		(start 232.297224 -96.403414)
		(end 232.297224 -98.537014)
		(width 0.0889)
		(layer "In11.Cu")
		(net "M_F_DQ<14>")
	)
	(segment
		(start 212.064346 -130.062478)
		(end 212.064346 -131.307078)
		(width 0.14224)
		(layer "In11.Cu")
		(net "M_F_DQ<14>")
	)
	(segment
		(start 212.1154 -148.463)
		(end 212.267546 -148.615146)
		(width 0.14224)
		(layer "In11.Cu")
		(net "M_F_DQ<14>")
	)
	(segment
		(start 212.267546 -139.460478)
		(end 212.064346 -139.663678)
		(width 0.14224)
		(layer "In11.Cu")
		(net "M_F_DQ<14>")
	)
	(segment
		(start 212.1662 -129.1082)
		(end 212.1662 -129.960624)
		(width 0.14224)
		(layer "In11.Cu")
		(net "M_F_DQ<14>")
	)
	(segment
		(start 212.1154 -146.252946)
		(end 212.1154 -148.463)
		(width 0.14224)
		(layer "In11.Cu")
		(net "M_F_DQ<14>")
	)
	(segment
		(start 212.1916 -145.781522)
		(end 212.1916 -146.176746)
		(width 0.14224)
		(layer "In11.Cu")
		(net "M_F_DQ<14>")
	)
	(segment
		(start 229.415594 -98.498406)
		(end 228.3968 -99.5172)
		(width 0.14224)
		(layer "In11.Cu")
		(net "M_F_DQ<14>")
	)
	(segment
		(start 235.623354 -94.623636)
		(end 235.599224 -94.623636)
		(width 0.0889)
		(layer "In11.Cu")
		(net "M_F_DQ<14>")
	)
	(segment
		(start 212.064346 -134.681468)
		(end 212.064346 -136.067292)
		(width 0.14224)
		(layer "In11.Cu")
		(net "M_F_DQ<14>")
	)
	(segment
		(start 212.471 -120.129554)
		(end 212.471 -128.8034)
		(width 0.14224)
		(layer "In11.Cu")
		(net "M_F_DQ<14>")
	)
	(arc
		(start 239.392968 -92.442538)
		(mid 239.251285 -92.586342)
		(end 239.057434 -92.64269)
		(width 0.0889)
		(layer "In11.Cu")
		(net "M_F_DQ<14>")
	)
	(arc
		(start 238.174784 -93.137736)
		(mid 237.886639 -93.220055)
		(end 237.675928 -93.433138)
		(width 0.0889)
		(layer "In11.Cu")
		(net "M_F_DQ<14>")
	)
	(arc
		(start 236.817408 -93.928438)
		(mid 236.678664 -94.070471)
		(end 236.488732 -94.128336)
		(width 0.0889)
		(layer "In11.Cu")
		(net "M_F_DQ<14>")
	)
	(arc
		(start 236.449108 -94.128336)
		(mid 236.165891 -94.212617)
		(end 235.958888 -94.423484)
		(width 0.0889)
		(layer "In11.Cu")
		(net "M_F_DQ<14>")
	)
	(arc
		(start 239.024668 -92.64269)
		(mid 238.741451 -92.726971)
		(end 238.534448 -92.937838)
		(width 0.0889)
		(layer "In11.Cu")
		(net "M_F_DQ<14>")
	)
	(arc
		(start 235.100368 -94.919038)
		(mid 234.961624 -95.061071)
		(end 234.771692 -95.118936)
		(width 0.0889)
		(layer "In11.Cu")
		(net "M_F_DQ<14>")
	)
	(arc
		(start 235.958888 -94.423484)
		(mid 235.817205 -94.567288)
		(end 235.623354 -94.623636)
		(width 0.0889)
		(layer "In11.Cu")
		(net "M_F_DQ<14>")
	)
	(arc
		(start 235.599224 -94.623636)
		(mid 235.311079 -94.705955)
		(end 235.100368 -94.919038)
		(width 0.0889)
		(layer "In11.Cu")
		(net "M_F_DQ<14>")
	)
	(arc
		(start 238.534448 -92.937838)
		(mid 238.394369 -93.080574)
		(end 238.202724 -93.137736)
		(width 0.0889)
		(layer "In11.Cu")
		(net "M_F_DQ<14>")
	)
	(arc
		(start 237.311438 -93.633036)
		(mid 237.026014 -93.716503)
		(end 236.817408 -93.928438)
		(width 0.0889)
		(layer "In11.Cu")
		(net "M_F_DQ<14>")
	)
	(arc
		(start 237.675928 -93.433138)
		(mid 237.537184 -93.575171)
		(end 237.347252 -93.633036)
		(width 0.0889)
		(layer "In11.Cu")
		(net "M_F_DQ<14>")
	)
	(arc
		(start 234.732068 -95.118936)
		(mid 234.448851 -95.203217)
		(end 234.241848 -95.414084)
		(width 0.0889)
		(layer "In11.Cu")
		(net "M_F_DQ<14>")
	)
	(segment
		(start 242.193318 -89.765886)
		(end 241.621818 -89.765886)
		(width 0.1651)
		(layer "F.Cu")
		(net "M_F_DQ<13>")
	)
	(segment
		(start 205.749906 -152.278842)
		(end 205.749906 -153.542746)
		(width 0.1651)
		(layer "F.Cu")
		(net "M_F_DQ<13>")
	)
	(segment
		(start 205.750414 -152.273)
		(end 205.749906 -152.278842)
		(width 0.1651)
		(layer "F.Cu")
		(net "M_F_DQ<13>")
	)
	(via
		(at 241.621818 -89.765886)
		(size 0.508)
		(drill 0.254)
		(layers "F.Cu" "B.Cu")
		(net "M_F_DQ<13>")
	)
	(via
		(at 205.749906 -153.542746)
		(size 0.508)
		(drill 0.254)
		(layers "F.Cu" "B.Cu")
		(net "M_F_DQ<13>")
	)
	(via
		(at 206.52359 -149.533356)
		(size 0.508)
		(drill 0.254)
		(layers "F.Cu" "B.Cu")
		(net "M_F_DQ<13>")
	)
	(segment
		(start 206.600298 -147.478496)
		(end 206.59979 -147.478496)
		(width 0.1651)
		(layer "B.Cu")
		(net "M_F_DQ<13>")
	)
	(segment
		(start 206.59979 -147.478496)
		(end 206.59979 -149.457156)
		(width 0.1651)
		(layer "B.Cu")
		(net "M_F_DQ<13>")
	)
	(segment
		(start 206.59979 -149.457156)
		(end 206.52359 -149.533356)
		(width 0.1651)
		(layer "B.Cu")
		(net "M_F_DQ<13>")
	)
	(segment
		(start 207.0354 -143.637)
		(end 206.933546 -143.738854)
		(width 0.14224)
		(layer "In11.Cu")
		(net "M_F_DQ<13>")
	)
	(segment
		(start 238.209328 -89.365836)
		(end 238.176562 -89.365836)
		(width 0.0889)
		(layer "In11.Cu")
		(net "M_F_DQ<13>")
	)
	(segment
		(start 206.933546 -129.417572)
		(end 206.933546 -129.920238)
		(width 0.14224)
		(layer "In11.Cu")
		(net "M_F_DQ<13>")
	)
	(segment
		(start 207.246982 -125.848872)
		(end 206.9846 -126.111254)
		(width 0.14224)
		(layer "In11.Cu")
		(net "M_F_DQ<13>")
	)
	(segment
		(start 207.01 -122.521218)
		(end 207.246982 -122.7582)
		(width 0.14224)
		(layer "In11.Cu")
		(net "M_F_DQ<13>")
	)
	(segment
		(start 206.81315 -141.383004)
		(end 207.0354 -141.605254)
		(width 0.14224)
		(layer "In11.Cu")
		(net "M_F_DQ<13>")
	)
	(segment
		(start 206.841598 -131.412234)
		(end 206.841598 -132.121148)
		(width 0.14224)
		(layer "In11.Cu")
		(net "M_F_DQ<13>")
	)
	(segment
		(start 207.246982 -123.825)
		(end 206.9592 -124.112782)
		(width 0.14224)
		(layer "In11.Cu")
		(net "M_F_DQ<13>")
	)
	(segment
		(start 239.064038 -88.87079)
		(end 239.031272 -88.87079)
		(width 0.0889)
		(layer "In11.Cu")
		(net "M_F_DQ<13>")
	)
	(segment
		(start 207.246982 -124.968)
		(end 207.246982 -125.848872)
		(width 0.14224)
		(layer "In11.Cu")
		(net "M_F_DQ<13>")
	)
	(segment
		(start 206.52359 -149.533356)
		(end 206.501238 -149.533356)
		(width 0.14224)
		(layer "In11.Cu")
		(net "M_F_DQ<13>")
	)
	(segment
		(start 207.246982 -117.616986)
		(end 207.246982 -118.4656)
		(width 0.14224)
		(layer "In11.Cu")
		(net "M_F_DQ<13>")
	)
	(segment
		(start 206.908146 -138.862054)
		(end 206.908146 -139.308078)
		(width 0.14224)
		(layer "In11.Cu")
		(net "M_F_DQ<13>")
	)
	(segment
		(start 207.0354 -141.605254)
		(end 207.0354 -143.637)
		(width 0.14224)
		(layer "In11.Cu")
		(net "M_F_DQ<13>")
	)
	(segment
		(start 224.5614 -100.302568)
		(end 207.246982 -117.616986)
		(width 0.14224)
		(layer "In11.Cu")
		(net "M_F_DQ<13>")
	)
	(segment
		(start 241.126772 -89.100152)
		(end 241.110008 -89.070688)
		(width 0.0889)
		(layer "In11.Cu")
		(net "M_F_DQ<13>")
	)
	(segment
		(start 206.9846 -120.726454)
		(end 206.9846 -121.132346)
		(width 0.14224)
		(layer "In11.Cu")
		(net "M_F_DQ<13>")
	)
	(segment
		(start 206.997046 -139.396978)
		(end 206.997046 -140.821918)
		(width 0.14224)
		(layer "In11.Cu")
		(net "M_F_DQ<13>")
	)
	(segment
		(start 207.115918 -130.10261)
		(end 207.115918 -131.137914)
		(width 0.14224)
		(layer "In11.Cu")
		(net "M_F_DQ<13>")
	)
	(segment
		(start 206.9846 -118.727982)
		(end 206.9846 -119.066818)
		(width 0.14224)
		(layer "In11.Cu")
		(net "M_F_DQ<13>")
	)
	(segment
		(start 207.109314 -128.62052)
		(end 207.253586 -128.764792)
		(width 0.14224)
		(layer "In11.Cu")
		(net "M_F_DQ<13>")
	)
	(segment
		(start 206.5528 -128.49352)
		(end 206.6798 -128.62052)
		(width 0.14224)
		(layer "In11.Cu")
		(net "M_F_DQ<13>")
	)
	(segment
		(start 206.9846 -126.111254)
		(end 206.9846 -126.440946)
		(width 0.14224)
		(layer "In11.Cu")
		(net "M_F_DQ<13>")
	)
	(segment
		(start 232.096564 -92.427806)
		(end 230.902764 -93.621606)
		(width 0.0889)
		(layer "In11.Cu")
		(net "M_F_DQ<13>")
	)
	(segment
		(start 206.997046 -135.938768)
		(end 206.849218 -136.086596)
		(width 0.14224)
		(layer "In11.Cu")
		(net "M_F_DQ<13>")
	)
	(segment
		(start 206.933546 -143.738854)
		(end 206.933546 -144.271238)
		(width 0.14224)
		(layer "In11.Cu")
		(net "M_F_DQ<13>")
	)
	(segment
		(start 206.9592 -124.680218)
		(end 207.246982 -124.968)
		(width 0.14224)
		(layer "In11.Cu")
		(net "M_F_DQ<13>")
	)
	(segment
		(start 206.908146 -139.308078)
		(end 206.997046 -139.396978)
		(width 0.14224)
		(layer "In11.Cu")
		(net "M_F_DQ<13>")
	)
	(segment
		(start 205.911196 -151.755856)
		(end 206.149194 -151.993854)
		(width 0.14224)
		(layer "In11.Cu")
		(net "M_F_DQ<13>")
	)
	(segment
		(start 206.933546 -144.271238)
		(end 207.060546 -144.398238)
		(width 0.14224)
		(layer "In11.Cu")
		(net "M_F_DQ<13>")
	)
	(segment
		(start 207.246982 -127.603758)
		(end 207.04302 -127.80772)
		(width 0.14224)
		(layer "In11.Cu")
		(net "M_F_DQ<13>")
	)
	(segment
		(start 241.621818 -89.765886)
		(end 241.126772 -89.100152)
		(width 0.0889)
		(layer "In11.Cu")
		(net "M_F_DQ<13>")
	)
	(segment
		(start 206.022194 -153.542746)
		(end 205.749906 -153.542746)
		(width 0.14224)
		(layer "In11.Cu")
		(net "M_F_DQ<13>")
	)
	(segment
		(start 207.0354 -146.278854)
		(end 207.0354 -148.2852)
		(width 0.14224)
		(layer "In11.Cu")
		(net "M_F_DQ<13>")
	)
	(segment
		(start 206.501238 -149.533356)
		(end 206.072994 -149.9616)
		(width 0.14224)
		(layer "In11.Cu")
		(net "M_F_DQ<13>")
	)
	(segment
		(start 207.060546 -145.454624)
		(end 206.908146 -145.607024)
		(width 0.14224)
		(layer "In11.Cu")
		(net "M_F_DQ<13>")
	)
	(segment
		(start 206.908146 -149.1488)
		(end 206.52359 -149.533356)
		(width 0.14224)
		(layer "In11.Cu")
		(net "M_F_DQ<13>")
	)
	(segment
		(start 234.570016 -91.347036)
		(end 234.359958 -91.557094)
		(width 0.0889)
		(layer "In11.Cu")
		(net "M_F_DQ<13>")
	)
	(segment
		(start 207.246982 -121.937272)
		(end 207.01 -122.174254)
		(width 0.14224)
		(layer "In11.Cu")
		(net "M_F_DQ<13>")
	)
	(segment
		(start 206.174594 -153.162254)
		(end 206.174594 -153.390346)
		(width 0.14224)
		(layer "In11.Cu")
		(net "M_F_DQ<13>")
	)
	(segment
		(start 234.359958 -91.557094)
		(end 234.085638 -91.557094)
		(width 0.0889)
		(layer "In11.Cu")
		(net "M_F_DQ<13>")
	)
	(segment
		(start 207.0354 -132.31495)
		(end 207.0354 -133.950456)
		(width 0.14224)
		(layer "In11.Cu")
		(net "M_F_DQ<13>")
	)
	(segment
		(start 206.9846 -121.132346)
		(end 207.246982 -121.394728)
		(width 0.14224)
		(layer "In11.Cu")
		(net "M_F_DQ<13>")
	)
	(segment
		(start 206.072994 -150.5204)
		(end 206.199994 -150.6474)
		(width 0.14224)
		(layer "In11.Cu")
		(net "M_F_DQ<13>")
	)
	(segment
		(start 207.060546 -144.398238)
		(end 207.060546 -145.454624)
		(width 0.14224)
		(layer "In11.Cu")
		(net "M_F_DQ<13>")
	)
	(segment
		(start 207.246982 -120.464072)
		(end 206.9846 -120.726454)
		(width 0.14224)
		(layer "In11.Cu")
		(net "M_F_DQ<13>")
	)
	(segment
		(start 205.911196 -152.586944)
		(end 205.911196 -152.898856)
		(width 0.14224)
		(layer "In11.Cu")
		(net "M_F_DQ<13>")
	)
	(segment
		(start 207.246982 -122.7582)
		(end 207.246982 -123.825)
		(width 0.14224)
		(layer "In11.Cu")
		(net "M_F_DQ<13>")
	)
	(segment
		(start 233.214926 -92.427806)
		(end 232.096564 -92.427806)
		(width 0.0889)
		(layer "In11.Cu")
		(net "M_F_DQ<13>")
	)
	(segment
		(start 205.911196 -151.418544)
		(end 205.911196 -151.755856)
		(width 0.14224)
		(layer "In11.Cu")
		(net "M_F_DQ<13>")
	)
	(segment
		(start 206.841598 -132.121148)
		(end 207.0354 -132.31495)
		(width 0.14224)
		(layer "In11.Cu")
		(net "M_F_DQ<13>")
	)
	(segment
		(start 206.849218 -136.086596)
		(end 206.849218 -136.604756)
		(width 0.14224)
		(layer "In11.Cu")
		(net "M_F_DQ<13>")
	)
	(segment
		(start 206.849218 -136.604756)
		(end 207.0354 -136.790938)
		(width 0.14224)
		(layer "In11.Cu")
		(net "M_F_DQ<13>")
	)
	(segment
		(start 206.6798 -127.80772)
		(end 206.5528 -127.93472)
		(width 0.14224)
		(layer "In11.Cu")
		(net "M_F_DQ<13>")
	)
	(segment
		(start 207.253586 -129.097532)
		(end 206.933546 -129.417572)
		(width 0.14224)
		(layer "In11.Cu")
		(net "M_F_DQ<13>")
	)
	(segment
		(start 207.246982 -126.703328)
		(end 207.246982 -127.603758)
		(width 0.14224)
		(layer "In11.Cu")
		(net "M_F_DQ<13>")
	)
	(segment
		(start 207.04302 -127.80772)
		(end 206.6798 -127.80772)
		(width 0.14224)
		(layer "In11.Cu")
		(net "M_F_DQ<13>")
	)
	(segment
		(start 229.404164 -93.962474)
		(end 229.361238 -94.0054)
		(width 0.14224)
		(layer "In11.Cu")
		(net "M_F_DQ<13>")
	)
	(segment
		(start 240.778284 -88.87079)
		(end 240.745518 -88.87079)
		(width 0.0889)
		(layer "In11.Cu")
		(net "M_F_DQ<13>")
	)
	(segment
		(start 229.745032 -93.621606)
		(end 229.404164 -93.962474)
		(width 0.0889)
		(layer "In11.Cu")
		(net "M_F_DQ<13>")
	)
	(segment
		(start 206.997046 -134.681468)
		(end 206.997046 -135.938768)
		(width 0.14224)
		(layer "In11.Cu")
		(net "M_F_DQ<13>")
	)
	(segment
		(start 206.072994 -149.9616)
		(end 206.072994 -150.5204)
		(width 0.14224)
		(layer "In11.Cu")
		(net "M_F_DQ<13>")
	)
	(segment
		(start 206.9846 -126.440946)
		(end 207.246982 -126.703328)
		(width 0.14224)
		(layer "In11.Cu")
		(net "M_F_DQ<13>")
	)
	(segment
		(start 207.0354 -133.950456)
		(end 206.866744 -134.119112)
		(width 0.14224)
		(layer "In11.Cu")
		(net "M_F_DQ<13>")
	)
	(segment
		(start 234.085638 -91.557094)
		(end 233.214926 -92.427806)
		(width 0.0889)
		(layer "In11.Cu")
		(net "M_F_DQ<13>")
	)
	(segment
		(start 207.0354 -148.2852)
		(end 206.908146 -148.412454)
		(width 0.14224)
		(layer "In11.Cu")
		(net "M_F_DQ<13>")
	)
	(segment
		(start 207.246982 -119.3292)
		(end 207.246982 -120.464072)
		(width 0.14224)
		(layer "In11.Cu")
		(net "M_F_DQ<13>")
	)
	(segment
		(start 237.346998 -89.86139)
		(end 237.314232 -89.86139)
		(width 0.0889)
		(layer "In11.Cu")
		(net "M_F_DQ<13>")
	)
	(segment
		(start 234.775248 -91.347036)
		(end 234.570016 -91.347036)
		(width 0.0889)
		(layer "In11.Cu")
		(net "M_F_DQ<13>")
	)
	(segment
		(start 235.629958 -90.85199)
		(end 235.597192 -90.85199)
		(width 0.0889)
		(layer "In11.Cu")
		(net "M_F_DQ<13>")
	)
	(segment
		(start 206.997046 -140.821918)
		(end 206.81315 -141.005814)
		(width 0.14224)
		(layer "In11.Cu")
		(net "M_F_DQ<13>")
	)
	(segment
		(start 206.81315 -141.005814)
		(end 206.81315 -141.383004)
		(width 0.14224)
		(layer "In11.Cu")
		(net "M_F_DQ<13>")
	)
	(segment
		(start 206.908146 -146.1516)
		(end 207.0354 -146.278854)
		(width 0.14224)
		(layer "In11.Cu")
		(net "M_F_DQ<13>")
	)
	(segment
		(start 230.902764 -93.621606)
		(end 229.745032 -93.621606)
		(width 0.0889)
		(layer "In11.Cu")
		(net "M_F_DQ<13>")
	)
	(segment
		(start 207.0354 -136.790938)
		(end 207.0354 -138.7348)
		(width 0.14224)
		(layer "In11.Cu")
		(net "M_F_DQ<13>")
	)
	(segment
		(start 206.149194 -151.993854)
		(end 206.149194 -152.348946)
		(width 0.14224)
		(layer "In11.Cu")
		(net "M_F_DQ<13>")
	)
	(segment
		(start 206.866744 -134.119112)
		(end 206.866744 -134.551166)
		(width 0.14224)
		(layer "In11.Cu")
		(net "M_F_DQ<13>")
	)
	(segment
		(start 205.911196 -152.898856)
		(end 206.174594 -153.162254)
		(width 0.14224)
		(layer "In11.Cu")
		(net "M_F_DQ<13>")
	)
	(segment
		(start 207.01 -122.174254)
		(end 207.01 -122.521218)
		(width 0.14224)
		(layer "In11.Cu")
		(net "M_F_DQ<13>")
	)
	(segment
		(start 229.361238 -94.0054)
		(end 228.321108 -94.0054)
		(width 0.14224)
		(layer "In11.Cu")
		(net "M_F_DQ<13>")
	)
	(segment
		(start 206.908146 -148.412454)
		(end 206.908146 -149.1488)
		(width 0.14224)
		(layer "In11.Cu")
		(net "M_F_DQ<13>")
	)
	(segment
		(start 207.246982 -121.394728)
		(end 207.246982 -121.937272)
		(width 0.14224)
		(layer "In11.Cu")
		(net "M_F_DQ<13>")
	)
	(segment
		(start 207.246982 -118.4656)
		(end 206.9846 -118.727982)
		(width 0.14224)
		(layer "In11.Cu")
		(net "M_F_DQ<13>")
	)
	(segment
		(start 206.9846 -119.066818)
		(end 207.246982 -119.3292)
		(width 0.14224)
		(layer "In11.Cu")
		(net "M_F_DQ<13>")
	)
	(segment
		(start 206.866744 -134.551166)
		(end 206.997046 -134.681468)
		(width 0.14224)
		(layer "In11.Cu")
		(net "M_F_DQ<13>")
	)
	(segment
		(start 206.199994 -150.6474)
		(end 206.199994 -151.129746)
		(width 0.14224)
		(layer "In11.Cu")
		(net "M_F_DQ<13>")
	)
	(segment
		(start 206.933546 -129.920238)
		(end 207.115918 -130.10261)
		(width 0.14224)
		(layer "In11.Cu")
		(net "M_F_DQ<13>")
	)
	(segment
		(start 207.0354 -138.7348)
		(end 206.908146 -138.862054)
		(width 0.14224)
		(layer "In11.Cu")
		(net "M_F_DQ<13>")
	)
	(segment
		(start 206.174594 -153.390346)
		(end 206.022194 -153.542746)
		(width 0.14224)
		(layer "In11.Cu")
		(net "M_F_DQ<13>")
	)
	(segment
		(start 206.199994 -151.129746)
		(end 205.911196 -151.418544)
		(width 0.14224)
		(layer "In11.Cu")
		(net "M_F_DQ<13>")
	)
	(segment
		(start 236.492288 -90.356436)
		(end 236.459522 -90.356436)
		(width 0.0889)
		(layer "In11.Cu")
		(net "M_F_DQ<13>")
	)
	(segment
		(start 206.5528 -127.93472)
		(end 206.5528 -128.49352)
		(width 0.14224)
		(layer "In11.Cu")
		(net "M_F_DQ<13>")
	)
	(segment
		(start 206.908146 -145.607024)
		(end 206.908146 -146.1516)
		(width 0.14224)
		(layer "In11.Cu")
		(net "M_F_DQ<13>")
	)
	(segment
		(start 224.5614 -97.765108)
		(end 224.5614 -100.302568)
		(width 0.14224)
		(layer "In11.Cu")
		(net "M_F_DQ<13>")
	)
	(segment
		(start 206.9592 -124.112782)
		(end 206.9592 -124.680218)
		(width 0.14224)
		(layer "In11.Cu")
		(net "M_F_DQ<13>")
	)
	(segment
		(start 206.6798 -128.62052)
		(end 207.109314 -128.62052)
		(width 0.14224)
		(layer "In11.Cu")
		(net "M_F_DQ<13>")
	)
	(segment
		(start 207.115918 -131.137914)
		(end 206.841598 -131.412234)
		(width 0.14224)
		(layer "In11.Cu")
		(net "M_F_DQ<13>")
	)
	(segment
		(start 228.321108 -94.0054)
		(end 224.5614 -97.765108)
		(width 0.14224)
		(layer "In11.Cu")
		(net "M_F_DQ<13>")
	)
	(segment
		(start 206.149194 -152.348946)
		(end 205.911196 -152.586944)
		(width 0.14224)
		(layer "In11.Cu")
		(net "M_F_DQ<13>")
	)
	(segment
		(start 207.253586 -128.764792)
		(end 207.253586 -129.097532)
		(width 0.14224)
		(layer "In11.Cu")
		(net "M_F_DQ<13>")
	)
	(arc
		(start 240.745518 -88.87079)
		(mid 240.460094 -88.787323)
		(end 240.251488 -88.575388)
		(width 0.0889)
		(layer "In11.Cu")
		(net "M_F_DQ<13>")
	)
	(arc
		(start 236.459522 -90.356436)
		(mid 236.265672 -90.412786)
		(end 236.123988 -90.556588)
		(width 0.0889)
		(layer "In11.Cu")
		(net "M_F_DQ<13>")
	)
	(arc
		(start 237.314232 -89.86139)
		(mid 237.12259 -89.918556)
		(end 236.982508 -90.061288)
		(width 0.0889)
		(layer "In11.Cu")
		(net "M_F_DQ<13>")
	)
	(arc
		(start 241.110008 -89.070688)
		(mid 240.969929 -88.927952)
		(end 240.778284 -88.87079)
		(width 0.0889)
		(layer "In11.Cu")
		(net "M_F_DQ<13>")
	)
	(arc
		(start 237.841028 -89.565988)
		(mid 237.63242 -89.77792)
		(end 237.346998 -89.86139)
		(width 0.0889)
		(layer "In11.Cu")
		(net "M_F_DQ<13>")
	)
	(arc
		(start 240.251488 -88.575388)
		(mid 239.904778 -88.375077)
		(end 239.558068 -88.575388)
		(width 0.0889)
		(layer "In11.Cu")
		(net "M_F_DQ<13>")
	)
	(arc
		(start 238.176562 -89.365836)
		(mid 237.982712 -89.422186)
		(end 237.841028 -89.565988)
		(width 0.0889)
		(layer "In11.Cu")
		(net "M_F_DQ<13>")
	)
	(arc
		(start 236.123988 -90.556588)
		(mid 235.91538 -90.76852)
		(end 235.629958 -90.85199)
		(width 0.0889)
		(layer "In11.Cu")
		(net "M_F_DQ<13>")
	)
	(arc
		(start 238.699548 -89.070688)
		(mid 238.492544 -89.281552)
		(end 238.209328 -89.365836)
		(width 0.0889)
		(layer "In11.Cu")
		(net "M_F_DQ<13>")
	)
	(arc
		(start 235.265468 -91.051888)
		(mid 235.058464 -91.262752)
		(end 234.775248 -91.347036)
		(width 0.0889)
		(layer "In11.Cu")
		(net "M_F_DQ<13>")
	)
	(arc
		(start 239.031272 -88.87079)
		(mid 238.83963 -88.927956)
		(end 238.699548 -89.070688)
		(width 0.0889)
		(layer "In11.Cu")
		(net "M_F_DQ<13>")
	)
	(arc
		(start 236.982508 -90.061288)
		(mid 236.775504 -90.272152)
		(end 236.492288 -90.356436)
		(width 0.0889)
		(layer "In11.Cu")
		(net "M_F_DQ<13>")
	)
	(arc
		(start 235.597192 -90.85199)
		(mid 235.40555 -90.909156)
		(end 235.265468 -91.051888)
		(width 0.0889)
		(layer "In11.Cu")
		(net "M_F_DQ<13>")
	)
	(arc
		(start 239.558068 -88.575388)
		(mid 239.34946 -88.78732)
		(end 239.064038 -88.87079)
		(width 0.0889)
		(layer "In11.Cu")
		(net "M_F_DQ<13>")
	)
	(segment
		(start 206.59979 -156.87294)
		(end 206.59979 -155.547568)
		(width 0.1651)
		(layer "F.Cu")
		(net "M_F_DQ<12>")
	)
	(segment
		(start 243.051838 -90.26144)
		(end 242.480338 -90.26144)
		(width 0.1651)
		(layer "F.Cu")
		(net "M_F_DQ<12>")
	)
	(segment
		(start 206.59979 -155.547568)
		(end 206.501746 -155.0162)
		(width 0.1651)
		(layer "F.Cu")
		(net "M_F_DQ<12>")
	)
	(segment
		(start 206.600298 -156.87294)
		(end 206.59979 -156.87294)
		(width 0.1651)
		(layer "F.Cu")
		(net "M_F_DQ<12>")
	)
	(via
		(at 206.501746 -155.0162)
		(size 0.508)
		(drill 0.254)
		(layers "F.Cu" "B.Cu")
		(net "M_F_DQ<12>")
	)
	(via
		(at 205.749906 -150.814278)
		(size 0.508)
		(drill 0.254)
		(layers "F.Cu" "B.Cu")
		(net "M_F_DQ<12>")
	)
	(via
		(at 242.480338 -90.26144)
		(size 0.508)
		(drill 0.254)
		(layers "F.Cu" "B.Cu")
		(net "M_F_DQ<12>")
	)
	(segment
		(start 205.749906 -152.078182)
		(end 205.749906 -150.814278)
		(width 0.1651)
		(layer "B.Cu")
		(net "M_F_DQ<12>")
	)
	(segment
		(start 205.750414 -152.078436)
		(end 205.749906 -152.078182)
		(width 0.1651)
		(layer "B.Cu")
		(net "M_F_DQ<12>")
	)
	(segment
		(start 242.480338 -90.26144)
		(end 242.1509 -89.500456)
		(width 0.0889)
		(layer "In11.Cu")
		(net "M_F_DQ<12>")
	)
	(segment
		(start 206.4766 -127.0254)
		(end 205.8416 -127.6604)
		(width 0.14224)
		(layer "In11.Cu")
		(net "M_F_DQ<12>")
	)
	(segment
		(start 224.0788 -99.887024)
		(end 206.4766 -117.489224)
		(width 0.14224)
		(layer "In11.Cu")
		(net "M_F_DQ<12>")
	)
	(segment
		(start 206.019146 -135.951468)
		(end 206.224378 -136.1567)
		(width 0.14224)
		(layer "In11.Cu")
		(net "M_F_DQ<12>")
	)
	(segment
		(start 206.019146 -134.722108)
		(end 206.019146 -135.951468)
		(width 0.14224)
		(layer "In11.Cu")
		(net "M_F_DQ<12>")
	)
	(segment
		(start 206.207614 -131.993132)
		(end 206.1718 -132.028946)
		(width 0.14224)
		(layer "In11.Cu")
		(net "M_F_DQ<12>")
	)
	(segment
		(start 206.019146 -131.180078)
		(end 206.207614 -131.368546)
		(width 0.14224)
		(layer "In11.Cu")
		(net "M_F_DQ<12>")
	)
	(segment
		(start 206.189834 -129.82575)
		(end 206.019146 -129.996438)
		(width 0.14224)
		(layer "In11.Cu")
		(net "M_F_DQ<12>")
	)
	(segment
		(start 229.73538 -93.431614)
		(end 229.630224 -93.326458)
		(width 0.0889)
		(layer "In11.Cu")
		(net "M_F_DQ<12>")
	)
	(segment
		(start 206.273146 -138.785346)
		(end 206.273146 -139.333478)
		(width 0.14224)
		(layer "In11.Cu")
		(net "M_F_DQ<12>")
	)
	(segment
		(start 205.8416 -128.9304)
		(end 206.189834 -129.278634)
		(width 0.14224)
		(layer "In11.Cu")
		(net "M_F_DQ<12>")
	)
	(segment
		(start 205.749906 -150.814278)
		(end 205.316836 -151.247348)
		(width 0.14224)
		(layer "In11.Cu")
		(net "M_F_DQ<12>")
	)
	(segment
		(start 235.623354 -90.66149)
		(end 235.590588 -90.66149)
		(width 0.0889)
		(layer "In11.Cu")
		(net "M_F_DQ<12>")
	)
	(segment
		(start 206.1718 -134.061454)
		(end 206.20736 -134.097014)
		(width 0.14224)
		(layer "In11.Cu")
		(net "M_F_DQ<12>")
	)
	(segment
		(start 205.316836 -153.83129)
		(end 206.501746 -155.0162)
		(width 0.14224)
		(layer "In11.Cu")
		(net "M_F_DQ<12>")
	)
	(segment
		(start 206.273146 -139.333478)
		(end 206.019146 -139.587478)
		(width 0.14224)
		(layer "In11.Cu")
		(net "M_F_DQ<12>")
	)
	(segment
		(start 206.247746 -141.478)
		(end 206.1718 -141.553946)
		(width 0.14224)
		(layer "In11.Cu")
		(net "M_F_DQ<12>")
	)
	(segment
		(start 206.1718 -132.028946)
		(end 206.1718 -134.061454)
		(width 0.14224)
		(layer "In11.Cu")
		(net "M_F_DQ<12>")
	)
	(segment
		(start 234.768644 -91.156536)
		(end 234.490514 -91.156536)
		(width 0.0889)
		(layer "In11.Cu")
		(net "M_F_DQ<12>")
	)
	(segment
		(start 228.329744 -93.3196)
		(end 224.0788 -97.570544)
		(width 0.14224)
		(layer "In11.Cu")
		(net "M_F_DQ<12>")
	)
	(segment
		(start 206.1718 -143.6116)
		(end 206.247746 -143.687546)
		(width 0.14224)
		(layer "In11.Cu")
		(net "M_F_DQ<12>")
	)
	(segment
		(start 236.485684 -90.165936)
		(end 236.452918 -90.165936)
		(width 0.0889)
		(layer "In11.Cu")
		(net "M_F_DQ<12>")
	)
	(segment
		(start 205.434946 -150.499318)
		(end 205.749906 -150.814278)
		(width 0.14224)
		(layer "In11.Cu")
		(net "M_F_DQ<12>")
	)
	(segment
		(start 206.247746 -144.069054)
		(end 205.981554 -144.335246)
		(width 0.14224)
		(layer "In11.Cu")
		(net "M_F_DQ<12>")
	)
	(segment
		(start 233.135424 -92.237814)
		(end 232.017824 -92.237814)
		(width 0.0889)
		(layer "In11.Cu")
		(net "M_F_DQ<12>")
	)
	(segment
		(start 205.981554 -144.335246)
		(end 205.981554 -145.527776)
		(width 0.14224)
		(layer "In11.Cu")
		(net "M_F_DQ<12>")
	)
	(segment
		(start 229.623366 -93.3196)
		(end 228.329744 -93.3196)
		(width 0.14224)
		(layer "In11.Cu")
		(net "M_F_DQ<12>")
	)
	(segment
		(start 242.1509 -89.500456)
		(end 242.133628 -89.470738)
		(width 0.0889)
		(layer "In11.Cu")
		(net "M_F_DQ<12>")
	)
	(segment
		(start 206.20736 -134.533894)
		(end 206.019146 -134.722108)
		(width 0.14224)
		(layer "In11.Cu")
		(net "M_F_DQ<12>")
	)
	(segment
		(start 206.1718 -138.684)
		(end 206.273146 -138.785346)
		(width 0.14224)
		(layer "In11.Cu")
		(net "M_F_DQ<12>")
	)
	(segment
		(start 241.639598 -89.175336)
		(end 241.606832 -89.175336)
		(width 0.0889)
		(layer "In11.Cu")
		(net "M_F_DQ<12>")
	)
	(segment
		(start 206.207614 -131.368546)
		(end 206.207614 -131.993132)
		(width 0.14224)
		(layer "In11.Cu")
		(net "M_F_DQ<12>")
	)
	(segment
		(start 229.630224 -93.326458)
		(end 229.623366 -93.3196)
		(width 0.14224)
		(layer "In11.Cu")
		(net "M_F_DQ<12>")
	)
	(segment
		(start 206.1718 -141.553946)
		(end 206.1718 -143.6116)
		(width 0.14224)
		(layer "In11.Cu")
		(net "M_F_DQ<12>")
	)
	(segment
		(start 206.235046 -145.781268)
		(end 206.235046 -146.2024)
		(width 0.14224)
		(layer "In11.Cu")
		(net "M_F_DQ<12>")
	)
	(segment
		(start 240.784888 -88.68029)
		(end 240.752122 -88.68029)
		(width 0.0889)
		(layer "In11.Cu")
		(net "M_F_DQ<12>")
	)
	(segment
		(start 206.1718 -146.265646)
		(end 206.1718 -148.2852)
		(width 0.14224)
		(layer "In11.Cu")
		(net "M_F_DQ<12>")
	)
	(segment
		(start 230.824024 -93.431614)
		(end 229.73538 -93.431614)
		(width 0.0889)
		(layer "In11.Cu")
		(net "M_F_DQ<12>")
	)
	(segment
		(start 206.20736 -134.097014)
		(end 206.20736 -134.533894)
		(width 0.14224)
		(layer "In11.Cu")
		(net "M_F_DQ<12>")
	)
	(segment
		(start 239.057434 -88.68029)
		(end 239.024668 -88.68029)
		(width 0.0889)
		(layer "In11.Cu")
		(net "M_F_DQ<12>")
	)
	(segment
		(start 234.490514 -91.156536)
		(end 234.280456 -91.366594)
		(width 0.0889)
		(layer "In11.Cu")
		(net "M_F_DQ<12>")
	)
	(segment
		(start 205.981554 -145.527776)
		(end 206.235046 -145.781268)
		(width 0.14224)
		(layer "In11.Cu")
		(net "M_F_DQ<12>")
	)
	(segment
		(start 206.247746 -143.687546)
		(end 206.247746 -144.069054)
		(width 0.14224)
		(layer "In11.Cu")
		(net "M_F_DQ<12>")
	)
	(segment
		(start 234.006644 -91.366594)
		(end 233.135424 -92.237814)
		(width 0.0889)
		(layer "In11.Cu")
		(net "M_F_DQ<12>")
	)
	(segment
		(start 205.316836 -151.247348)
		(end 205.316836 -153.83129)
		(width 0.14224)
		(layer "In11.Cu")
		(net "M_F_DQ<12>")
	)
	(segment
		(start 206.019146 -129.996438)
		(end 206.019146 -131.180078)
		(width 0.14224)
		(layer "In11.Cu")
		(net "M_F_DQ<12>")
	)
	(segment
		(start 206.224378 -136.1567)
		(end 206.224378 -136.599168)
		(width 0.14224)
		(layer "In11.Cu")
		(net "M_F_DQ<12>")
	)
	(segment
		(start 206.189834 -129.278634)
		(end 206.189834 -129.82575)
		(width 0.14224)
		(layer "In11.Cu")
		(net "M_F_DQ<12>")
	)
	(segment
		(start 206.235046 -146.2024)
		(end 206.1718 -146.265646)
		(width 0.14224)
		(layer "In11.Cu")
		(net "M_F_DQ<12>")
	)
	(segment
		(start 206.235046 -148.960078)
		(end 205.434946 -149.760178)
		(width 0.14224)
		(layer "In11.Cu")
		(net "M_F_DQ<12>")
	)
	(segment
		(start 239.922558 -88.184736)
		(end 239.886998 -88.184736)
		(width 0.0889)
		(layer "In11.Cu")
		(net "M_F_DQ<12>")
	)
	(segment
		(start 206.019146 -140.781278)
		(end 206.247746 -141.009878)
		(width 0.14224)
		(layer "In11.Cu")
		(net "M_F_DQ<12>")
	)
	(segment
		(start 205.8416 -127.6604)
		(end 205.8416 -128.9304)
		(width 0.14224)
		(layer "In11.Cu")
		(net "M_F_DQ<12>")
	)
	(segment
		(start 234.280456 -91.366594)
		(end 234.006644 -91.366594)
		(width 0.0889)
		(layer "In11.Cu")
		(net "M_F_DQ<12>")
	)
	(segment
		(start 206.224378 -136.599168)
		(end 206.1718 -136.651746)
		(width 0.14224)
		(layer "In11.Cu")
		(net "M_F_DQ<12>")
	)
	(segment
		(start 238.202724 -89.175336)
		(end 238.169958 -89.175336)
		(width 0.0889)
		(layer "In11.Cu")
		(net "M_F_DQ<12>")
	)
	(segment
		(start 232.017824 -92.237814)
		(end 230.824024 -93.431614)
		(width 0.0889)
		(layer "In11.Cu")
		(net "M_F_DQ<12>")
	)
	(segment
		(start 206.235046 -148.348446)
		(end 206.235046 -148.960078)
		(width 0.14224)
		(layer "In11.Cu")
		(net "M_F_DQ<12>")
	)
	(segment
		(start 206.1718 -136.651746)
		(end 206.1718 -138.684)
		(width 0.14224)
		(layer "In11.Cu")
		(net "M_F_DQ<12>")
	)
	(segment
		(start 206.019146 -139.587478)
		(end 206.019146 -140.781278)
		(width 0.14224)
		(layer "In11.Cu")
		(net "M_F_DQ<12>")
	)
	(segment
		(start 224.0788 -97.570544)
		(end 224.0788 -99.887024)
		(width 0.14224)
		(layer "In11.Cu")
		(net "M_F_DQ<12>")
	)
	(segment
		(start 206.247746 -141.009878)
		(end 206.247746 -141.478)
		(width 0.14224)
		(layer "In11.Cu")
		(net "M_F_DQ<12>")
	)
	(segment
		(start 206.1718 -148.2852)
		(end 206.235046 -148.348446)
		(width 0.14224)
		(layer "In11.Cu")
		(net "M_F_DQ<12>")
	)
	(segment
		(start 206.4766 -117.489224)
		(end 206.4766 -127.0254)
		(width 0.14224)
		(layer "In11.Cu")
		(net "M_F_DQ<12>")
	)
	(segment
		(start 205.434946 -149.760178)
		(end 205.434946 -150.499318)
		(width 0.14224)
		(layer "In11.Cu")
		(net "M_F_DQ<12>")
	)
	(segment
		(start 237.340394 -89.67089)
		(end 237.307628 -89.67089)
		(width 0.0889)
		(layer "In11.Cu")
		(net "M_F_DQ<12>")
	)
	(arc
		(start 235.100368 -90.956638)
		(mid 234.960289 -91.099374)
		(end 234.768644 -91.156536)
		(width 0.0889)
		(layer "In11.Cu")
		(net "M_F_DQ<12>")
	)
	(arc
		(start 238.169958 -89.175336)
		(mid 237.884534 -89.258803)
		(end 237.675928 -89.470738)
		(width 0.0889)
		(layer "In11.Cu")
		(net "M_F_DQ<12>")
	)
	(arc
		(start 237.307628 -89.67089)
		(mid 237.024411 -89.755171)
		(end 236.817408 -89.966038)
		(width 0.0889)
		(layer "In11.Cu")
		(net "M_F_DQ<12>")
	)
	(arc
		(start 239.392968 -88.480138)
		(mid 239.251285 -88.623942)
		(end 239.057434 -88.68029)
		(width 0.0889)
		(layer "In11.Cu")
		(net "M_F_DQ<12>")
	)
	(arc
		(start 236.817408 -89.966038)
		(mid 236.677329 -90.108774)
		(end 236.485684 -90.165936)
		(width 0.0889)
		(layer "In11.Cu")
		(net "M_F_DQ<12>")
	)
	(arc
		(start 240.752122 -88.68029)
		(mid 240.558272 -88.62394)
		(end 240.416588 -88.480138)
		(width 0.0889)
		(layer "In11.Cu")
		(net "M_F_DQ<12>")
	)
	(arc
		(start 241.275108 -88.975438)
		(mid 241.068104 -88.764574)
		(end 240.784888 -88.68029)
		(width 0.0889)
		(layer "In11.Cu")
		(net "M_F_DQ<12>")
	)
	(arc
		(start 238.534448 -88.975438)
		(mid 238.394369 -89.118174)
		(end 238.202724 -89.175336)
		(width 0.0889)
		(layer "In11.Cu")
		(net "M_F_DQ<12>")
	)
	(arc
		(start 242.133628 -89.470738)
		(mid 241.92502 -89.258806)
		(end 241.639598 -89.175336)
		(width 0.0889)
		(layer "In11.Cu")
		(net "M_F_DQ<12>")
	)
	(arc
		(start 240.416588 -88.480138)
		(mid 240.20798 -88.268206)
		(end 239.922558 -88.184736)
		(width 0.0889)
		(layer "In11.Cu")
		(net "M_F_DQ<12>")
	)
	(arc
		(start 241.606832 -89.175336)
		(mid 241.41519 -89.11817)
		(end 241.275108 -88.975438)
		(width 0.0889)
		(layer "In11.Cu")
		(net "M_F_DQ<12>")
	)
	(arc
		(start 235.590588 -90.66149)
		(mid 235.307371 -90.745771)
		(end 235.100368 -90.956638)
		(width 0.0889)
		(layer "In11.Cu")
		(net "M_F_DQ<12>")
	)
	(arc
		(start 239.024668 -88.68029)
		(mid 238.741451 -88.764571)
		(end 238.534448 -88.975438)
		(width 0.0889)
		(layer "In11.Cu")
		(net "M_F_DQ<12>")
	)
	(arc
		(start 237.675928 -89.470738)
		(mid 237.534245 -89.614542)
		(end 237.340394 -89.67089)
		(width 0.0889)
		(layer "In11.Cu")
		(net "M_F_DQ<12>")
	)
	(arc
		(start 236.452918 -90.165936)
		(mid 236.167494 -90.249403)
		(end 235.958888 -90.461338)
		(width 0.0889)
		(layer "In11.Cu")
		(net "M_F_DQ<12>")
	)
	(arc
		(start 235.958888 -90.461338)
		(mid 235.817205 -90.605142)
		(end 235.623354 -90.66149)
		(width 0.0889)
		(layer "In11.Cu")
		(net "M_F_DQ<12>")
	)
	(arc
		(start 239.886998 -88.184736)
		(mid 239.601574 -88.268203)
		(end 239.392968 -88.480138)
		(width 0.0889)
		(layer "In11.Cu")
		(net "M_F_DQ<12>")
	)
	(segment
		(start 241.334798 -93.23324)
		(end 240.763298 -93.23324)
		(width 0.1651)
		(layer "F.Cu")
		(net "M_F_DQ<11>")
	)
	(segment
		(start 213.399878 -152.278842)
		(end 213.399878 -153.542746)
		(width 0.1651)
		(layer "F.Cu")
		(net "M_F_DQ<11>")
	)
	(segment
		(start 213.400386 -152.273)
		(end 213.399878 -152.278842)
		(width 0.1651)
		(layer "F.Cu")
		(net "M_F_DQ<11>")
	)
	(via
		(at 214.249762 -149.533356)
		(size 0.508)
		(drill 0.254)
		(layers "F.Cu" "B.Cu")
		(net "M_F_DQ<11>")
	)
	(via
		(at 240.763298 -93.23324)
		(size 0.508)
		(drill 0.254)
		(layers "F.Cu" "B.Cu")
		(net "M_F_DQ<11>")
	)
	(via
		(at 213.399878 -153.542746)
		(size 0.508)
		(drill 0.254)
		(layers "F.Cu" "B.Cu")
		(net "M_F_DQ<11>")
	)
	(segment
		(start 214.250524 -147.478496)
		(end 214.249762 -147.478496)
		(width 0.1651)
		(layer "B.Cu")
		(net "M_F_DQ<11>")
	)
	(segment
		(start 214.249762 -147.478496)
		(end 214.249762 -149.533356)
		(width 0.1651)
		(layer "B.Cu")
		(net "M_F_DQ<11>")
	)
	(segment
		(start 214.5284 -136.271254)
		(end 214.5284 -136.703054)
		(width 0.14224)
		(layer "In11.Cu")
		(net "M_F_DQ<11>")
	)
	(segment
		(start 214.249762 -149.533356)
		(end 214.22741 -149.533356)
		(width 0.14224)
		(layer "In11.Cu")
		(net "M_F_DQ<11>")
	)
	(segment
		(start 213.849966 -153.364946)
		(end 213.672166 -153.542746)
		(width 0.14224)
		(layer "In11.Cu")
		(net "M_F_DQ<11>")
	)
	(segment
		(start 214.6808 -136.855454)
		(end 214.6808 -138.8872)
		(width 0.14224)
		(layer "In11.Cu")
		(net "M_F_DQ<11>")
	)
	(segment
		(start 233.554778 -99.95662)
		(end 233.53014 -99.997768)
		(width 0.0889)
		(layer "In11.Cu")
		(net "M_F_DQ<11>")
	)
	(segment
		(start 214.5284 -133.9596)
		(end 214.5284 -134.484618)
		(width 0.14224)
		(layer "In11.Cu")
		(net "M_F_DQ<11>")
	)
	(segment
		(start 214.756746 -139.714478)
		(end 214.756746 -140.817854)
		(width 0.14224)
		(layer "In11.Cu")
		(net "M_F_DQ<11>")
	)
	(segment
		(start 216.1286 -124.4854)
		(end 215.9254 -124.6886)
		(width 0.14224)
		(layer "In11.Cu")
		(net "M_F_DQ<11>")
	)
	(segment
		(start 214.4776 -141.579346)
		(end 214.6808 -141.782546)
		(width 0.14224)
		(layer "In11.Cu")
		(net "M_F_DQ<11>")
	)
	(segment
		(start 233.46537 -97.251266)
		(end 233.554778 -97.406206)
		(width 0.0889)
		(layer "In11.Cu")
		(net "M_F_DQ<11>")
	)
	(segment
		(start 230.3272 -104.993186)
		(end 216.1286 -119.191786)
		(width 0.14224)
		(layer "In11.Cu")
		(net "M_F_DQ<11>")
	)
	(segment
		(start 214.782146 -134.738364)
		(end 214.782146 -136.017508)
		(width 0.14224)
		(layer "In11.Cu")
		(net "M_F_DQ<11>")
	)
	(segment
		(start 214.756746 -140.817854)
		(end 214.4776 -141.097)
		(width 0.14224)
		(layer "In11.Cu")
		(net "M_F_DQ<11>")
	)
	(segment
		(start 215.519 -124.6886)
		(end 215.3158 -124.4854)
		(width 0.14224)
		(layer "In11.Cu")
		(net "M_F_DQ<11>")
	)
	(segment
		(start 240.763298 -93.23324)
		(end 239.939576 -93.32849)
		(width 0.0889)
		(layer "In11.Cu")
		(net "M_F_DQ<11>")
	)
	(segment
		(start 214.617046 -131.8768)
		(end 214.6808 -131.940554)
		(width 0.14224)
		(layer "In11.Cu")
		(net "M_F_DQ<11>")
	)
	(segment
		(start 214.832946 -145.618708)
		(end 214.4776 -145.974054)
		(width 0.14224)
		(layer "In11.Cu")
		(net "M_F_DQ<11>")
	)
	(segment
		(start 231.150668 -100.301552)
		(end 230.913178 -100.539042)
		(width 0.0889)
		(layer "In11.Cu")
		(net "M_F_DQ<11>")
	)
	(segment
		(start 230.3272 -101.12502)
		(end 230.3272 -103.31323)
		(width 0.14224)
		(layer "In11.Cu")
		(net "M_F_DQ<11>")
	)
	(segment
		(start 214.6808 -131.940554)
		(end 214.6808 -133.8072)
		(width 0.14224)
		(layer "In11.Cu")
		(net "M_F_DQ<11>")
	)
	(segment
		(start 214.7062 -120.429274)
		(end 214.503 -120.632474)
		(width 0.14224)
		(layer "In11.Cu")
		(net "M_F_DQ<11>")
	)
	(segment
		(start 214.617046 -131.408678)
		(end 214.617046 -131.8768)
		(width 0.14224)
		(layer "In11.Cu")
		(net "M_F_DQ<11>")
	)
	(segment
		(start 235.629958 -95.80499)
		(end 235.597192 -95.80499)
		(width 0.0889)
		(layer "In11.Cu")
		(net "M_F_DQ<11>")
	)
	(segment
		(start 230.3272 -103.31323)
		(end 230.165148 -103.475282)
		(width 0.14224)
		(layer "In11.Cu")
		(net "M_F_DQ<11>")
	)
	(segment
		(start 214.4776 -141.097)
		(end 214.4776 -141.579346)
		(width 0.14224)
		(layer "In11.Cu")
		(net "M_F_DQ<11>")
	)
	(segment
		(start 233.912918 -96.79559)
		(end 233.72826 -96.79559)
		(width 0.0889)
		(layer "In11.Cu")
		(net "M_F_DQ<11>")
	)
	(segment
		(start 214.782146 -136.017508)
		(end 214.5284 -136.271254)
		(width 0.14224)
		(layer "In11.Cu")
		(net "M_F_DQ<11>")
	)
	(segment
		(start 215.039448 -126.699518)
		(end 214.758524 -126.699518)
		(width 0.14224)
		(layer "In11.Cu")
		(net "M_F_DQ<11>")
	)
	(segment
		(start 229.325424 -103.97617)
		(end 229.487476 -104.138222)
		(width 0.14224)
		(layer "In11.Cu")
		(net "M_F_DQ<11>")
	)
	(segment
		(start 229.473252 -103.475282)
		(end 229.325424 -103.62311)
		(width 0.14224)
		(layer "In11.Cu")
		(net "M_F_DQ<11>")
	)
	(segment
		(start 214.604346 -138.963654)
		(end 214.604346 -139.562078)
		(width 0.14224)
		(layer "In11.Cu")
		(net "M_F_DQ<11>")
	)
	(segment
		(start 214.578946 -149.21738)
		(end 214.249762 -149.546564)
		(width 0.14224)
		(layer "In11.Cu")
		(net "M_F_DQ<11>")
	)
	(segment
		(start 214.604346 -129.960878)
		(end 214.8332 -130.189732)
		(width 0.14224)
		(layer "In11.Cu")
		(net "M_F_DQ<11>")
	)
	(segment
		(start 213.561168 -151.387048)
		(end 213.561168 -151.660352)
		(width 0.14224)
		(layer "In11.Cu")
		(net "M_F_DQ<11>")
	)
	(segment
		(start 214.249762 -149.546564)
		(end 214.249762 -149.533356)
		(width 0.14224)
		(layer "In11.Cu")
		(net "M_F_DQ<11>")
	)
	(segment
		(start 237.342172 -94.81439)
		(end 237.314232 -94.81439)
		(width 0.0889)
		(layer "In11.Cu")
		(net "M_F_DQ<11>")
	)
	(segment
		(start 215.060784 -125.886718)
		(end 215.253316 -126.07925)
		(width 0.14224)
		(layer "In11.Cu")
		(net "M_F_DQ<11>")
	)
	(segment
		(start 214.4776 -146.253454)
		(end 214.7824 -146.558254)
		(width 0.14224)
		(layer "In11.Cu")
		(net "M_F_DQ<11>")
	)
	(segment
		(start 216.1286 -119.191786)
		(end 216.1286 -124.4854)
		(width 0.14224)
		(layer "In11.Cu")
		(net "M_F_DQ<11>")
	)
	(segment
		(start 230.165148 -103.475282)
		(end 229.473252 -103.475282)
		(width 0.14224)
		(layer "In11.Cu")
		(net "M_F_DQ<11>")
	)
	(segment
		(start 213.561168 -151.660352)
		(end 213.818216 -151.9174)
		(width 0.14224)
		(layer "In11.Cu")
		(net "M_F_DQ<11>")
	)
	(segment
		(start 214.6808 -143.4592)
		(end 214.503 -143.637)
		(width 0.14224)
		(layer "In11.Cu")
		(net "M_F_DQ<11>")
	)
	(segment
		(start 214.22741 -149.533356)
		(end 213.799166 -149.9616)
		(width 0.14224)
		(layer "In11.Cu")
		(net "M_F_DQ<11>")
	)
	(segment
		(start 213.843616 -151.1046)
		(end 213.561168 -151.387048)
		(width 0.14224)
		(layer "In11.Cu")
		(net "M_F_DQ<11>")
	)
	(segment
		(start 233.543602 -98.377502)
		(end 233.548428 -98.386138)
		(width 0.0889)
		(layer "In11.Cu")
		(net "M_F_DQ<11>")
	)
	(segment
		(start 214.503 -120.632474)
		(end 214.503 -125.738382)
		(width 0.14224)
		(layer "In11.Cu")
		(net "M_F_DQ<11>")
	)
	(segment
		(start 214.503 -125.738382)
		(end 214.651336 -125.886718)
		(width 0.14224)
		(layer "In11.Cu")
		(net "M_F_DQ<11>")
	)
	(segment
		(start 213.818216 -151.9174)
		(end 213.818216 -152.2222)
		(width 0.14224)
		(layer "In11.Cu")
		(net "M_F_DQ<11>")
	)
	(segment
		(start 229.487476 -104.138222)
		(end 230.165148 -104.138222)
		(width 0.14224)
		(layer "In11.Cu")
		(net "M_F_DQ<11>")
	)
	(segment
		(start 214.6808 -141.782546)
		(end 214.6808 -143.4592)
		(width 0.14224)
		(layer "In11.Cu")
		(net "M_F_DQ<11>")
	)
	(segment
		(start 233.543602 -99.368102)
		(end 233.548428 -99.376738)
		(width 0.0889)
		(layer "In11.Cu")
		(net "M_F_DQ<11>")
	)
	(segment
		(start 214.6808 -138.8872)
		(end 214.604346 -138.963654)
		(width 0.14224)
		(layer "In11.Cu")
		(net "M_F_DQ<11>")
	)
	(segment
		(start 214.651336 -125.886718)
		(end 215.060784 -125.886718)
		(width 0.14224)
		(layer "In11.Cu")
		(net "M_F_DQ<11>")
	)
	(segment
		(start 214.832946 -144.398238)
		(end 214.832946 -145.618708)
		(width 0.14224)
		(layer "In11.Cu")
		(net "M_F_DQ<11>")
	)
	(segment
		(start 230.165148 -104.138222)
		(end 230.3272 -104.300274)
		(width 0.14224)
		(layer "In11.Cu")
		(net "M_F_DQ<11>")
	)
	(segment
		(start 213.672166 -153.542746)
		(end 213.399878 -153.542746)
		(width 0.14224)
		(layer "In11.Cu")
		(net "M_F_DQ<11>")
	)
	(segment
		(start 215.253316 -126.07925)
		(end 215.253316 -126.48565)
		(width 0.14224)
		(layer "In11.Cu")
		(net "M_F_DQ<11>")
	)
	(segment
		(start 215.1126 -120.429274)
		(end 214.7062 -120.429274)
		(width 0.14224)
		(layer "In11.Cu")
		(net "M_F_DQ<11>")
	)
	(segment
		(start 214.604346 -126.853696)
		(end 214.604346 -129.960878)
		(width 0.14224)
		(layer "In11.Cu")
		(net "M_F_DQ<11>")
	)
	(segment
		(start 214.503 -144.068292)
		(end 214.832946 -144.398238)
		(width 0.14224)
		(layer "In11.Cu")
		(net "M_F_DQ<11>")
	)
	(segment
		(start 238.205518 -94.31909)
		(end 238.169704 -94.31909)
		(width 0.0889)
		(layer "In11.Cu")
		(net "M_F_DQ<11>")
	)
	(segment
		(start 233.469942 -100.102924)
		(end 233.166666 -100.301552)
		(width 0.0889)
		(layer "In11.Cu")
		(net "M_F_DQ<11>")
	)
	(segment
		(start 233.166666 -100.301552)
		(end 231.150668 -100.301552)
		(width 0.0889)
		(layer "In11.Cu")
		(net "M_F_DQ<11>")
	)
	(segment
		(start 236.492288 -95.309436)
		(end 236.459522 -95.309436)
		(width 0.0889)
		(layer "In11.Cu")
		(net "M_F_DQ<11>")
	)
	(segment
		(start 229.325424 -103.62311)
		(end 229.325424 -103.97617)
		(width 0.14224)
		(layer "In11.Cu")
		(net "M_F_DQ<11>")
	)
	(segment
		(start 214.4776 -145.974054)
		(end 214.4776 -146.253454)
		(width 0.14224)
		(layer "In11.Cu")
		(net "M_F_DQ<11>")
	)
	(segment
		(start 215.9254 -124.6886)
		(end 215.519 -124.6886)
		(width 0.14224)
		(layer "In11.Cu")
		(net "M_F_DQ<11>")
	)
	(segment
		(start 214.8332 -130.189732)
		(end 214.8332 -131.192524)
		(width 0.14224)
		(layer "In11.Cu")
		(net "M_F_DQ<11>")
	)
	(segment
		(start 214.6808 -133.8072)
		(end 214.5284 -133.9596)
		(width 0.14224)
		(layer "In11.Cu")
		(net "M_F_DQ<11>")
	)
	(segment
		(start 239.939576 -93.32849)
		(end 239.893602 -93.32849)
		(width 0.0889)
		(layer "In11.Cu")
		(net "M_F_DQ<11>")
	)
	(segment
		(start 214.578946 -148.514054)
		(end 214.578946 -149.21738)
		(width 0.14224)
		(layer "In11.Cu")
		(net "M_F_DQ<11>")
	)
	(segment
		(start 214.503 -143.637)
		(end 214.503 -144.068292)
		(width 0.14224)
		(layer "In11.Cu")
		(net "M_F_DQ<11>")
	)
	(segment
		(start 214.604346 -139.562078)
		(end 214.756746 -139.714478)
		(width 0.14224)
		(layer "In11.Cu")
		(net "M_F_DQ<11>")
	)
	(segment
		(start 215.253316 -126.48565)
		(end 215.039448 -126.699518)
		(width 0.14224)
		(layer "In11.Cu")
		(net "M_F_DQ<11>")
	)
	(segment
		(start 213.799166 -149.9616)
		(end 213.799166 -150.391368)
		(width 0.14224)
		(layer "In11.Cu")
		(net "M_F_DQ<11>")
	)
	(segment
		(start 214.8332 -131.192524)
		(end 214.617046 -131.408678)
		(width 0.14224)
		(layer "In11.Cu")
		(net "M_F_DQ<11>")
	)
	(segment
		(start 213.818216 -152.2222)
		(end 213.561168 -152.479248)
		(width 0.14224)
		(layer "In11.Cu")
		(net "M_F_DQ<11>")
	)
	(segment
		(start 230.913178 -100.539042)
		(end 230.3272 -101.12502)
		(width 0.14224)
		(layer "In11.Cu")
		(net "M_F_DQ<11>")
	)
	(segment
		(start 233.53014 -99.997768)
		(end 233.469942 -100.102924)
		(width 0.0889)
		(layer "In11.Cu")
		(net "M_F_DQ<11>")
	)
	(segment
		(start 215.3158 -120.632474)
		(end 215.1126 -120.429274)
		(width 0.14224)
		(layer "In11.Cu")
		(net "M_F_DQ<11>")
	)
	(segment
		(start 213.799166 -150.391368)
		(end 213.843616 -150.435818)
		(width 0.14224)
		(layer "In11.Cu")
		(net "M_F_DQ<11>")
	)
	(segment
		(start 214.758524 -126.699518)
		(end 214.604346 -126.853696)
		(width 0.14224)
		(layer "In11.Cu")
		(net "M_F_DQ<11>")
	)
	(segment
		(start 215.3158 -124.4854)
		(end 215.3158 -120.632474)
		(width 0.14224)
		(layer "In11.Cu")
		(net "M_F_DQ<11>")
	)
	(segment
		(start 213.561168 -152.752552)
		(end 213.849966 -153.04135)
		(width 0.14224)
		(layer "In11.Cu")
		(net "M_F_DQ<11>")
	)
	(segment
		(start 233.548428 -98.386138)
		(end 233.554778 -98.396806)
		(width 0.0889)
		(layer "In11.Cu")
		(net "M_F_DQ<11>")
	)
	(segment
		(start 213.843616 -150.435818)
		(end 213.843616 -151.1046)
		(width 0.14224)
		(layer "In11.Cu")
		(net "M_F_DQ<11>")
	)
	(segment
		(start 230.3272 -104.300274)
		(end 230.3272 -104.993186)
		(width 0.14224)
		(layer "In11.Cu")
		(net "M_F_DQ<11>")
	)
	(segment
		(start 214.7824 -148.3106)
		(end 214.578946 -148.514054)
		(width 0.14224)
		(layer "In11.Cu")
		(net "M_F_DQ<11>")
	)
	(segment
		(start 214.5284 -134.484618)
		(end 214.782146 -134.738364)
		(width 0.14224)
		(layer "In11.Cu")
		(net "M_F_DQ<11>")
	)
	(segment
		(start 213.849966 -153.04135)
		(end 213.849966 -153.364946)
		(width 0.14224)
		(layer "In11.Cu")
		(net "M_F_DQ<11>")
	)
	(segment
		(start 214.7824 -146.558254)
		(end 214.7824 -148.3106)
		(width 0.14224)
		(layer "In11.Cu")
		(net "M_F_DQ<11>")
	)
	(segment
		(start 214.5284 -136.703054)
		(end 214.6808 -136.855454)
		(width 0.14224)
		(layer "In11.Cu")
		(net "M_F_DQ<11>")
	)
	(segment
		(start 239.067848 -93.82379)
		(end 239.028224 -93.82379)
		(width 0.0889)
		(layer "In11.Cu")
		(net "M_F_DQ<11>")
	)
	(segment
		(start 234.775248 -96.300036)
		(end 234.742482 -96.300036)
		(width 0.0889)
		(layer "In11.Cu")
		(net "M_F_DQ<11>")
	)
	(segment
		(start 213.561168 -152.479248)
		(end 213.561168 -152.752552)
		(width 0.14224)
		(layer "In11.Cu")
		(net "M_F_DQ<11>")
	)
	(arc
		(start 239.558068 -93.528642)
		(mid 239.351064 -93.739506)
		(end 239.067848 -93.82379)
		(width 0.0889)
		(layer "In11.Cu")
		(net "M_F_DQ<11>")
	)
	(arc
		(start 239.893602 -93.32849)
		(mid 239.699752 -93.38484)
		(end 239.558068 -93.528642)
		(width 0.0889)
		(layer "In11.Cu")
		(net "M_F_DQ<11>")
	)
	(arc
		(start 233.554778 -98.396806)
		(mid 233.627576 -98.687569)
		(end 233.548428 -98.976688)
		(width 0.0889)
		(layer "In11.Cu")
		(net "M_F_DQ<11>")
	)
	(arc
		(start 237.314232 -94.81439)
		(mid 237.12259 -94.871556)
		(end 236.982508 -95.014288)
		(width 0.0889)
		(layer "In11.Cu")
		(net "M_F_DQ<11>")
	)
	(arc
		(start 233.72826 -96.79559)
		(mid 233.519716 -96.978969)
		(end 233.46537 -97.251266)
		(width 0.0889)
		(layer "In11.Cu")
		(net "M_F_DQ<11>")
	)
	(arc
		(start 238.699548 -94.023688)
		(mid 238.49094 -94.23562)
		(end 238.205518 -94.31909)
		(width 0.0889)
		(layer "In11.Cu")
		(net "M_F_DQ<11>")
	)
	(arc
		(start 234.742482 -96.300036)
		(mid 234.548632 -96.356386)
		(end 234.406948 -96.500188)
		(width 0.0889)
		(layer "In11.Cu")
		(net "M_F_DQ<11>")
	)
	(arc
		(start 236.123988 -95.509588)
		(mid 235.91538 -95.72152)
		(end 235.629958 -95.80499)
		(width 0.0889)
		(layer "In11.Cu")
		(net "M_F_DQ<11>")
	)
	(arc
		(start 236.982508 -95.014288)
		(mid 236.775504 -95.225152)
		(end 236.492288 -95.309436)
		(width 0.0889)
		(layer "In11.Cu")
		(net "M_F_DQ<11>")
	)
	(arc
		(start 238.169704 -94.31909)
		(mid 237.979775 -94.37696)
		(end 237.841028 -94.518988)
		(width 0.0889)
		(layer "In11.Cu")
		(net "M_F_DQ<11>")
	)
	(arc
		(start 235.597192 -95.80499)
		(mid 235.40555 -95.862156)
		(end 235.265468 -96.004888)
		(width 0.0889)
		(layer "In11.Cu")
		(net "M_F_DQ<11>")
	)
	(arc
		(start 239.028224 -93.82379)
		(mid 238.838295 -93.88166)
		(end 238.699548 -94.023688)
		(width 0.0889)
		(layer "In11.Cu")
		(net "M_F_DQ<11>")
	)
	(arc
		(start 233.548428 -99.376738)
		(mid 233.62765 -99.665856)
		(end 233.554778 -99.95662)
		(width 0.0889)
		(layer "In11.Cu")
		(net "M_F_DQ<11>")
	)
	(arc
		(start 234.406948 -96.500188)
		(mid 234.19834 -96.71212)
		(end 233.912918 -96.79559)
		(width 0.0889)
		(layer "In11.Cu")
		(net "M_F_DQ<11>")
	)
	(arc
		(start 233.548428 -97.986088)
		(mid 233.494958 -98.181151)
		(end 233.543602 -98.377502)
		(width 0.0889)
		(layer "In11.Cu")
		(net "M_F_DQ<11>")
	)
	(arc
		(start 237.841028 -94.518988)
		(mid 237.630315 -94.732067)
		(end 237.342172 -94.81439)
		(width 0.0889)
		(layer "In11.Cu")
		(net "M_F_DQ<11>")
	)
	(arc
		(start 233.548428 -98.976688)
		(mid 233.494958 -99.171751)
		(end 233.543602 -99.368102)
		(width 0.0889)
		(layer "In11.Cu")
		(net "M_F_DQ<11>")
	)
	(arc
		(start 235.265468 -96.004888)
		(mid 235.058464 -96.215752)
		(end 234.775248 -96.300036)
		(width 0.0889)
		(layer "In11.Cu")
		(net "M_F_DQ<11>")
	)
	(arc
		(start 236.459522 -95.309436)
		(mid 236.265672 -95.365786)
		(end 236.123988 -95.509588)
		(width 0.0889)
		(layer "In11.Cu")
		(net "M_F_DQ<11>")
	)
	(arc
		(start 233.554778 -97.406206)
		(mid 233.627576 -97.696969)
		(end 233.548428 -97.986088)
		(width 0.0889)
		(layer "In11.Cu")
		(net "M_F_DQ<11>")
	)
	(segment
		(start 214.249762 -155.395168)
		(end 214.249762 -155.1178)
		(width 0.1651)
		(layer "F.Cu")
		(net "M_F_DQ<10>")
	)
	(segment
		(start 242.193318 -92.737686)
		(end 241.621818 -92.737686)
		(width 0.1651)
		(layer "F.Cu")
		(net "M_F_DQ<10>")
	)
	(segment
		(start 214.381334 -155.75026)
		(end 214.381334 -155.52674)
		(width 0.1651)
		(layer "F.Cu")
		(net "M_F_DQ<10>")
	)
	(segment
		(start 214.250524 -156.87294)
		(end 214.249762 -156.87294)
		(width 0.1651)
		(layer "F.Cu")
		(net "M_F_DQ<10>")
	)
	(segment
		(start 214.249762 -156.87294)
		(end 214.249762 -155.881832)
		(width 0.1651)
		(layer "F.Cu")
		(net "M_F_DQ<10>")
	)
	(segment
		(start 214.381334 -155.52674)
		(end 214.249762 -155.395168)
		(width 0.1651)
		(layer "F.Cu")
		(net "M_F_DQ<10>")
	)
	(segment
		(start 214.249762 -155.881832)
		(end 214.381334 -155.75026)
		(width 0.1651)
		(layer "F.Cu")
		(net "M_F_DQ<10>")
	)
	(via
		(at 241.621818 -92.737686)
		(size 0.508)
		(drill 0.254)
		(layers "F.Cu" "B.Cu")
		(net "M_F_DQ<10>")
	)
	(via
		(at 214.249762 -155.1178)
		(size 0.508)
		(drill 0.254)
		(layers "F.Cu" "B.Cu")
		(net "M_F_DQ<10>")
	)
	(via
		(at 213.399878 -150.814278)
		(size 0.508)
		(drill 0.254)
		(layers "F.Cu" "B.Cu")
		(net "M_F_DQ<10>")
	)
	(segment
		(start 213.399878 -152.078182)
		(end 213.399878 -150.814278)
		(width 0.1651)
		(layer "B.Cu")
		(net "M_F_DQ<10>")
	)
	(segment
		(start 213.400386 -152.078436)
		(end 213.399878 -152.078182)
		(width 0.1651)
		(layer "B.Cu")
		(net "M_F_DQ<10>")
	)
	(segment
		(start 230.4288 -99.8982)
		(end 229.616 -100.711)
		(width 0.14224)
		(layer "In11.Cu")
		(net "M_F_DQ<10>")
	)
	(segment
		(start 225.98761 -107.285028)
		(end 228.824282 -104.448356)
		(width 0.14224)
		(layer "In11.Cu")
		(net "M_F_DQ<10>")
	)
	(segment
		(start 213.982046 -134.200646)
		(end 213.982046 -134.471664)
		(width 0.14224)
		(layer "In11.Cu")
		(net "M_F_DQ<10>")
	)
	(segment
		(start 213.998048 -136.299194)
		(end 213.998048 -136.674098)
		(width 0.14224)
		(layer "In11.Cu")
		(net "M_F_DQ<10>")
	)
	(segment
		(start 213.969346 -143.789146)
		(end 213.969346 -144.093438)
		(width 0.14224)
		(layer "In11.Cu")
		(net "M_F_DQ<10>")
	)
	(segment
		(start 213.918546 -146.177)
		(end 213.8172 -146.278346)
		(width 0.14224)
		(layer "In11.Cu")
		(net "M_F_DQ<10>")
	)
	(segment
		(start 233.383328 -99.872038)
		(end 233.327448 -99.968812)
		(width 0.0889)
		(layer "In11.Cu")
		(net "M_F_DQ<10>")
	)
	(segment
		(start 240.800382 -92.64269)
		(end 240.741708 -92.64269)
		(width 0.0889)
		(layer "In11.Cu")
		(net "M_F_DQ<10>")
	)
	(segment
		(start 233.376978 -98.47072)
		(end 233.383328 -98.481388)
		(width 0.0889)
		(layer "In11.Cu")
		(net "M_F_DQ<10>")
	)
	(segment
		(start 230.911146 -99.8982)
		(end 230.4288 -99.8982)
		(width 0.14224)
		(layer "In11.Cu")
		(net "M_F_DQ<10>")
	)
	(segment
		(start 213.766146 -131.190746)
		(end 214.0966 -131.5212)
		(width 0.14224)
		(layer "In11.Cu")
		(net "M_F_DQ<10>")
	)
	(segment
		(start 213.740746 -136.041892)
		(end 213.998048 -136.299194)
		(width 0.14224)
		(layer "In11.Cu")
		(net "M_F_DQ<10>")
	)
	(segment
		(start 213.998048 -136.674098)
		(end 213.8426 -136.829546)
		(width 0.14224)
		(layer "In11.Cu")
		(net "M_F_DQ<10>")
	)
	(segment
		(start 233.10977 -100.11156)
		(end 231.12857 -100.11156)
		(width 0.0889)
		(layer "In11.Cu")
		(net "M_F_DQ<10>")
	)
	(segment
		(start 214.086948 -138.953748)
		(end 214.086948 -139.241276)
		(width 0.14224)
		(layer "In11.Cu")
		(net "M_F_DQ<10>")
	)
	(segment
		(start 213.8172 -129.2606)
		(end 213.995 -129.4384)
		(width 0.14224)
		(layer "In11.Cu")
		(net "M_F_DQ<10>")
	)
	(segment
		(start 213.054946 -150.469346)
		(end 213.399878 -150.814278)
		(width 0.14224)
		(layer "In11.Cu")
		(net "M_F_DQ<10>")
	)
	(segment
		(start 233.906314 -96.60509)
		(end 233.691938 -96.60509)
		(width 0.0889)
		(layer "In11.Cu")
		(net "M_F_DQ<10>")
	)
	(segment
		(start 214.086948 -139.241276)
		(end 213.766146 -139.562078)
		(width 0.14224)
		(layer "In11.Cu")
		(net "M_F_DQ<10>")
	)
	(segment
		(start 233.282236 -97.315528)
		(end 233.388154 -97.499424)
		(width 0.0889)
		(layer "In11.Cu")
		(net "M_F_DQ<10>")
	)
	(segment
		(start 228.824282 -104.448356)
		(end 229.11181 -104.448356)
		(width 0.14224)
		(layer "In11.Cu")
		(net "M_F_DQ<10>")
	)
	(segment
		(start 213.8426 -138.7094)
		(end 214.086948 -138.953748)
		(width 0.14224)
		(layer "In11.Cu")
		(net "M_F_DQ<10>")
	)
	(segment
		(start 213.8172 -120.605042)
		(end 213.8172 -129.2606)
		(width 0.14224)
		(layer "In11.Cu")
		(net "M_F_DQ<10>")
	)
	(segment
		(start 213.969346 -144.093438)
		(end 213.689946 -144.372838)
		(width 0.14224)
		(layer "In11.Cu")
		(net "M_F_DQ<10>")
	)
	(segment
		(start 213.399878 -150.814278)
		(end 212.966808 -151.247348)
		(width 0.14224)
		(layer "In11.Cu")
		(net "M_F_DQ<10>")
	)
	(segment
		(start 238.205772 -94.128336)
		(end 238.166148 -94.128336)
		(width 0.0889)
		(layer "In11.Cu")
		(net "M_F_DQ<10>")
	)
	(segment
		(start 212.966808 -151.247348)
		(end 212.966808 -153.834846)
		(width 0.14224)
		(layer "In11.Cu")
		(net "M_F_DQ<10>")
	)
	(segment
		(start 213.8172 -132.092446)
		(end 213.8172 -134.0358)
		(width 0.14224)
		(layer "In11.Cu")
		(net "M_F_DQ<10>")
	)
	(segment
		(start 230.913178 -99.896168)
		(end 230.911146 -99.8982)
		(width 0.14224)
		(layer "In11.Cu")
		(net "M_F_DQ<10>")
	)
	(segment
		(start 213.918546 -145.806668)
		(end 213.918546 -146.177)
		(width 0.14224)
		(layer "In11.Cu")
		(net "M_F_DQ<10>")
	)
	(segment
		(start 212.966808 -153.834846)
		(end 214.249762 -155.1178)
		(width 0.14224)
		(layer "In11.Cu")
		(net "M_F_DQ<10>")
	)
	(segment
		(start 225.412808 -106.710226)
		(end 225.412808 -106.997754)
		(width 0.14224)
		(layer "In11.Cu")
		(net "M_F_DQ<10>")
	)
	(segment
		(start 229.399084 -104.73563)
		(end 229.399084 -105.023158)
		(width 0.14224)
		(layer "In11.Cu")
		(net "M_F_DQ<10>")
	)
	(segment
		(start 213.995 -129.4384)
		(end 213.995 -129.732024)
		(width 0.14224)
		(layer "In11.Cu")
		(net "M_F_DQ<10>")
	)
	(segment
		(start 225.700082 -107.285028)
		(end 225.98761 -107.285028)
		(width 0.14224)
		(layer "In11.Cu")
		(net "M_F_DQ<10>")
	)
	(segment
		(start 213.995 -129.732024)
		(end 213.766146 -129.960878)
		(width 0.14224)
		(layer "In11.Cu")
		(net "M_F_DQ<10>")
	)
	(segment
		(start 225.412808 -106.997754)
		(end 225.700082 -107.285028)
		(width 0.14224)
		(layer "In11.Cu")
		(net "M_F_DQ<10>")
	)
	(segment
		(start 213.766146 -140.933678)
		(end 213.969346 -141.136878)
		(width 0.14224)
		(layer "In11.Cu")
		(net "M_F_DQ<10>")
	)
	(segment
		(start 233.327448 -99.968812)
		(end 233.10977 -100.11156)
		(width 0.0889)
		(layer "In11.Cu")
		(net "M_F_DQ<10>")
	)
	(segment
		(start 213.8172 -148.3868)
		(end 213.918546 -148.488146)
		(width 0.14224)
		(layer "In11.Cu")
		(net "M_F_DQ<10>")
	)
	(segment
		(start 235.623354 -95.61449)
		(end 235.590588 -95.61449)
		(width 0.0889)
		(layer "In11.Cu")
		(net "M_F_DQ<10>")
	)
	(segment
		(start 213.918546 -148.488146)
		(end 213.918546 -148.972778)
		(width 0.14224)
		(layer "In11.Cu")
		(net "M_F_DQ<10>")
	)
	(segment
		(start 213.969346 -141.136878)
		(end 213.969346 -141.5288)
		(width 0.14224)
		(layer "In11.Cu")
		(net "M_F_DQ<10>")
	)
	(segment
		(start 213.8426 -136.829546)
		(end 213.8426 -138.7094)
		(width 0.14224)
		(layer "In11.Cu")
		(net "M_F_DQ<10>")
	)
	(segment
		(start 229.11181 -104.448356)
		(end 229.399084 -104.73563)
		(width 0.14224)
		(layer "In11.Cu")
		(net "M_F_DQ<10>")
	)
	(segment
		(start 213.054946 -149.836378)
		(end 213.054946 -150.469346)
		(width 0.14224)
		(layer "In11.Cu")
		(net "M_F_DQ<10>")
	)
	(segment
		(start 237.340394 -94.623636)
		(end 237.316264 -94.623636)
		(width 0.0889)
		(layer "In11.Cu")
		(net "M_F_DQ<10>")
	)
	(segment
		(start 213.8172 -141.680946)
		(end 213.8172 -143.637)
		(width 0.14224)
		(layer "In11.Cu")
		(net "M_F_DQ<10>")
	)
	(segment
		(start 233.383328 -98.481388)
		(end 233.388154 -98.490024)
		(width 0.0889)
		(layer "In11.Cu")
		(net "M_F_DQ<10>")
	)
	(segment
		(start 229.616 -102.507034)
		(end 225.412808 -106.710226)
		(width 0.14224)
		(layer "In11.Cu")
		(net "M_F_DQ<10>")
	)
	(segment
		(start 234.768644 -96.109536)
		(end 234.735878 -96.109536)
		(width 0.0889)
		(layer "In11.Cu")
		(net "M_F_DQ<10>")
	)
	(segment
		(start 213.8172 -146.278346)
		(end 213.8172 -148.3868)
		(width 0.14224)
		(layer "In11.Cu")
		(net "M_F_DQ<10>")
	)
	(segment
		(start 231.12857 -100.11156)
		(end 230.913178 -99.896168)
		(width 0.0889)
		(layer "In11.Cu")
		(net "M_F_DQ<10>")
	)
	(segment
		(start 213.766146 -129.960878)
		(end 213.766146 -131.190746)
		(width 0.14224)
		(layer "In11.Cu")
		(net "M_F_DQ<10>")
	)
	(segment
		(start 213.689946 -144.372838)
		(end 213.689946 -145.578068)
		(width 0.14224)
		(layer "In11.Cu")
		(net "M_F_DQ<10>")
	)
	(segment
		(start 213.740746 -134.712964)
		(end 213.740746 -136.041892)
		(width 0.14224)
		(layer "In11.Cu")
		(net "M_F_DQ<10>")
	)
	(segment
		(start 213.982046 -134.471664)
		(end 213.740746 -134.712964)
		(width 0.14224)
		(layer "In11.Cu")
		(net "M_F_DQ<10>")
	)
	(segment
		(start 213.766146 -139.562078)
		(end 213.766146 -140.933678)
		(width 0.14224)
		(layer "In11.Cu")
		(net "M_F_DQ<10>")
	)
	(segment
		(start 229.399084 -105.023158)
		(end 213.8172 -120.605042)
		(width 0.14224)
		(layer "In11.Cu")
		(net "M_F_DQ<10>")
	)
	(segment
		(start 239.064292 -93.633036)
		(end 239.028478 -93.633036)
		(width 0.0889)
		(layer "In11.Cu")
		(net "M_F_DQ<10>")
	)
	(segment
		(start 213.8172 -143.637)
		(end 213.969346 -143.789146)
		(width 0.14224)
		(layer "In11.Cu")
		(net "M_F_DQ<10>")
	)
	(segment
		(start 213.8172 -134.0358)
		(end 213.982046 -134.200646)
		(width 0.14224)
		(layer "In11.Cu")
		(net "M_F_DQ<10>")
	)
	(segment
		(start 213.689946 -145.578068)
		(end 213.918546 -145.806668)
		(width 0.14224)
		(layer "In11.Cu")
		(net "M_F_DQ<10>")
	)
	(segment
		(start 213.969346 -141.5288)
		(end 213.8172 -141.680946)
		(width 0.14224)
		(layer "In11.Cu")
		(net "M_F_DQ<10>")
	)
	(segment
		(start 213.918546 -148.972778)
		(end 213.054946 -149.836378)
		(width 0.14224)
		(layer "In11.Cu")
		(net "M_F_DQ<10>")
	)
	(segment
		(start 241.621818 -92.737686)
		(end 240.800382 -92.64269)
		(width 0.0889)
		(layer "In11.Cu")
		(net "M_F_DQ<10>")
	)
	(segment
		(start 236.485684 -95.118936)
		(end 236.452918 -95.118936)
		(width 0.0889)
		(layer "In11.Cu")
		(net "M_F_DQ<10>")
	)
	(segment
		(start 214.0966 -131.5212)
		(end 214.0966 -131.813046)
		(width 0.14224)
		(layer "In11.Cu")
		(net "M_F_DQ<10>")
	)
	(segment
		(start 214.0966 -131.813046)
		(end 213.8172 -132.092446)
		(width 0.14224)
		(layer "In11.Cu")
		(net "M_F_DQ<10>")
	)
	(segment
		(start 239.919764 -93.137736)
		(end 239.891824 -93.137736)
		(width 0.0889)
		(layer "In11.Cu")
		(net "M_F_DQ<10>")
	)
	(segment
		(start 229.616 -100.711)
		(end 229.616 -102.507034)
		(width 0.14224)
		(layer "In11.Cu")
		(net "M_F_DQ<10>")
	)
	(arc
		(start 239.891824 -93.137736)
		(mid 239.603679 -93.220055)
		(end 239.392968 -93.433138)
		(width 0.0889)
		(layer "In11.Cu")
		(net "M_F_DQ<10>")
	)
	(arc
		(start 237.316264 -94.623636)
		(mid 237.028119 -94.705955)
		(end 236.817408 -94.919038)
		(width 0.0889)
		(layer "In11.Cu")
		(net "M_F_DQ<10>")
	)
	(arc
		(start 238.534448 -93.928438)
		(mid 238.395704 -94.070471)
		(end 238.205772 -94.128336)
		(width 0.0889)
		(layer "In11.Cu")
		(net "M_F_DQ<10>")
	)
	(arc
		(start 234.241848 -96.404938)
		(mid 234.100165 -96.548742)
		(end 233.906314 -96.60509)
		(width 0.0889)
		(layer "In11.Cu")
		(net "M_F_DQ<10>")
	)
	(arc
		(start 233.383328 -97.890838)
		(mid 233.304106 -98.179956)
		(end 233.376978 -98.47072)
		(width 0.0889)
		(layer "In11.Cu")
		(net "M_F_DQ<10>")
	)
	(arc
		(start 238.166148 -94.128336)
		(mid 237.882931 -94.212617)
		(end 237.675928 -94.423484)
		(width 0.0889)
		(layer "In11.Cu")
		(net "M_F_DQ<10>")
	)
	(arc
		(start 236.817408 -94.919038)
		(mid 236.677329 -95.061774)
		(end 236.485684 -95.118936)
		(width 0.0889)
		(layer "In11.Cu")
		(net "M_F_DQ<10>")
	)
	(arc
		(start 235.100368 -95.909638)
		(mid 234.960289 -96.052374)
		(end 234.768644 -96.109536)
		(width 0.0889)
		(layer "In11.Cu")
		(net "M_F_DQ<10>")
	)
	(arc
		(start 236.452918 -95.118936)
		(mid 236.167494 -95.202403)
		(end 235.958888 -95.414338)
		(width 0.0889)
		(layer "In11.Cu")
		(net "M_F_DQ<10>")
	)
	(arc
		(start 240.251488 -92.937838)
		(mid 240.111409 -93.080574)
		(end 239.919764 -93.137736)
		(width 0.0889)
		(layer "In11.Cu")
		(net "M_F_DQ<10>")
	)
	(arc
		(start 235.590588 -95.61449)
		(mid 235.307371 -95.698771)
		(end 235.100368 -95.909638)
		(width 0.0889)
		(layer "In11.Cu")
		(net "M_F_DQ<10>")
	)
	(arc
		(start 233.388154 -97.499424)
		(mid 233.436909 -97.695776)
		(end 233.383328 -97.890838)
		(width 0.0889)
		(layer "In11.Cu")
		(net "M_F_DQ<10>")
	)
	(arc
		(start 239.392968 -93.433138)
		(mid 239.254224 -93.575171)
		(end 239.064292 -93.633036)
		(width 0.0889)
		(layer "In11.Cu")
		(net "M_F_DQ<10>")
	)
	(arc
		(start 237.675928 -94.423484)
		(mid 237.534245 -94.567288)
		(end 237.340394 -94.623636)
		(width 0.0889)
		(layer "In11.Cu")
		(net "M_F_DQ<10>")
	)
	(arc
		(start 239.028478 -93.633036)
		(mid 238.743054 -93.716503)
		(end 238.534448 -93.928438)
		(width 0.0889)
		(layer "In11.Cu")
		(net "M_F_DQ<10>")
	)
	(arc
		(start 234.735878 -96.109536)
		(mid 234.450454 -96.193003)
		(end 234.241848 -96.404938)
		(width 0.0889)
		(layer "In11.Cu")
		(net "M_F_DQ<10>")
	)
	(arc
		(start 233.383328 -99.472242)
		(mid 233.436827 -99.67214)
		(end 233.383328 -99.872038)
		(width 0.0889)
		(layer "In11.Cu")
		(net "M_F_DQ<10>")
	)
	(arc
		(start 233.388154 -98.490024)
		(mid 233.436909 -98.686376)
		(end 233.383328 -98.881438)
		(width 0.0889)
		(layer "In11.Cu")
		(net "M_F_DQ<10>")
	)
	(arc
		(start 233.691938 -96.60509)
		(mid 233.354127 -96.883636)
		(end 233.282236 -97.315528)
		(width 0.0889)
		(layer "In11.Cu")
		(net "M_F_DQ<10>")
	)
	(arc
		(start 233.383328 -98.881438)
		(mid 233.304197 -99.17684)
		(end 233.383328 -99.472242)
		(width 0.0889)
		(layer "In11.Cu")
		(net "M_F_DQ<10>")
	)
	(arc
		(start 235.958888 -95.414338)
		(mid 235.817205 -95.558142)
		(end 235.623354 -95.61449)
		(width 0.0889)
		(layer "In11.Cu")
		(net "M_F_DQ<10>")
	)
	(arc
		(start 240.741708 -92.64269)
		(mid 240.458491 -92.726971)
		(end 240.251488 -92.937838)
		(width 0.0889)
		(layer "In11.Cu")
		(net "M_F_DQ<10>")
	)
	(segment
		(start 243.051838 -86.29904)
		(end 242.480338 -86.29904)
		(width 0.1651)
		(layer "F.Cu")
		(net "M_F_DQ<0>")
	)
	(segment
		(start 198.949818 -156.878782)
		(end 198.772018 -155.0162)
		(width 0.1651)
		(layer "F.Cu")
		(net "M_F_DQ<0>")
	)
	(segment
		(start 198.950326 -156.87294)
		(end 198.949818 -156.878782)
		(width 0.1651)
		(layer "F.Cu")
		(net "M_F_DQ<0>")
	)
	(via
		(at 198.772018 -155.0162)
		(size 0.508)
		(drill 0.254)
		(layers "F.Cu" "B.Cu")
		(net "M_F_DQ<0>")
	)
	(via
		(at 198.099934 -150.814278)
		(size 0.508)
		(drill 0.254)
		(layers "F.Cu" "B.Cu")
		(net "M_F_DQ<0>")
	)
	(via
		(at 242.480338 -86.29904)
		(size 0.508)
		(drill 0.254)
		(layers "F.Cu" "B.Cu")
		(net "M_F_DQ<0>")
	)
	(segment
		(start 198.099934 -152.078182)
		(end 198.099934 -150.814278)
		(width 0.1651)
		(layer "B.Cu")
		(net "M_F_DQ<0>")
	)
	(segment
		(start 198.100442 -152.078436)
		(end 198.099934 -152.078182)
		(width 0.1651)
		(layer "B.Cu")
		(net "M_F_DQ<0>")
	)
	(segment
		(start 208.6102 -101.3206)
		(end 206.6798 -103.251)
		(width 0.14224)
		(layer "In11.Cu")
		(net "M_F_DQ<0>")
	)
	(segment
		(start 235.623354 -85.70849)
		(end 235.590588 -85.70849)
		(width 0.0889)
		(layer "In11.Cu")
		(net "M_F_DQ<0>")
	)
	(segment
		(start 198.624952 -138.858752)
		(end 198.624952 -139.320778)
		(width 0.14224)
		(layer "In11.Cu")
		(net "M_F_DQ<0>")
	)
	(segment
		(start 236.485684 -85.212936)
		(end 236.452918 -85.212936)
		(width 0.0889)
		(layer "In11.Cu")
		(net "M_F_DQ<0>")
	)
	(segment
		(start 198.282052 -139.663678)
		(end 198.282052 -140.743178)
		(width 0.14224)
		(layer "In11.Cu")
		(net "M_F_DQ<0>")
	)
	(segment
		(start 239.922558 -84.222336)
		(end 239.889792 -84.222336)
		(width 0.0889)
		(layer "In11.Cu")
		(net "M_F_DQ<0>")
	)
	(segment
		(start 198.586852 -148.498052)
		(end 198.586852 -148.960078)
		(width 0.14224)
		(layer "In11.Cu")
		(net "M_F_DQ<0>")
	)
	(segment
		(start 198.314818 -131.208272)
		(end 198.6534 -131.546854)
		(width 0.14224)
		(layer "In11.Cu")
		(net "M_F_DQ<0>")
	)
	(segment
		(start 231.7242 -87.68969)
		(end 231.243124 -87.208614)
		(width 0.0889)
		(layer "In11.Cu")
		(net "M_F_DQ<0>")
	)
	(segment
		(start 241.639598 -85.212936)
		(end 241.606832 -85.212936)
		(width 0.0889)
		(layer "In11.Cu")
		(net "M_F_DQ<0>")
	)
	(segment
		(start 233.051604 -87.194136)
		(end 233.018838 -87.194136)
		(width 0.0889)
		(layer "In11.Cu")
		(net "M_F_DQ<0>")
	)
	(segment
		(start 229.465886 -87.208614)
		(end 229.233984 -86.976712)
		(width 0.0889)
		(layer "In11.Cu")
		(net "M_F_DQ<0>")
	)
	(segment
		(start 213.893654 -101.3206)
		(end 208.6102 -101.3206)
		(width 0.14224)
		(layer "In11.Cu")
		(net "M_F_DQ<0>")
	)
	(segment
		(start 197.666864 -151.247348)
		(end 197.666864 -153.911046)
		(width 0.14224)
		(layer "In11.Cu")
		(net "M_F_DQ<0>")
	)
	(segment
		(start 240.784888 -84.71789)
		(end 240.752122 -84.71789)
		(width 0.0889)
		(layer "In11.Cu")
		(net "M_F_DQ<0>")
	)
	(segment
		(start 232.189274 -87.68969)
		(end 231.7242 -87.68969)
		(width 0.0889)
		(layer "In11.Cu")
		(net "M_F_DQ<0>")
	)
	(segment
		(start 198.099934 -150.814278)
		(end 197.666864 -151.247348)
		(width 0.14224)
		(layer "In11.Cu")
		(net "M_F_DQ<0>")
	)
	(segment
		(start 227.586286 -86.976712)
		(end 216.67978 -97.883218)
		(width 0.14224)
		(layer "In11.Cu")
		(net "M_F_DQ<0>")
	)
	(segment
		(start 198.5264 -132.026152)
		(end 198.5264 -133.9088)
		(width 0.14224)
		(layer "In11.Cu")
		(net "M_F_DQ<0>")
	)
	(segment
		(start 198.574152 -144.085818)
		(end 198.294752 -144.365218)
		(width 0.14224)
		(layer "In11.Cu")
		(net "M_F_DQ<0>")
	)
	(segment
		(start 197.735952 -150.450296)
		(end 198.099934 -150.814278)
		(width 0.14224)
		(layer "In11.Cu")
		(net "M_F_DQ<0>")
	)
	(segment
		(start 198.624952 -134.007352)
		(end 198.624952 -134.433818)
		(width 0.14224)
		(layer "In11.Cu")
		(net "M_F_DQ<0>")
	)
	(segment
		(start 198.624952 -136.5758)
		(end 198.5264 -136.674352)
		(width 0.14224)
		(layer "In11.Cu")
		(net "M_F_DQ<0>")
	)
	(segment
		(start 242.1509 -85.538056)
		(end 242.133628 -85.508338)
		(width 0.0889)
		(layer "In11.Cu")
		(net "M_F_DQ<0>")
	)
	(segment
		(start 198.586852 -145.856706)
		(end 198.586852 -146.2024)
		(width 0.14224)
		(layer "In11.Cu")
		(net "M_F_DQ<0>")
	)
	(segment
		(start 198.624952 -134.433818)
		(end 198.282052 -134.776718)
		(width 0.14224)
		(layer "In11.Cu")
		(net "M_F_DQ<0>")
	)
	(segment
		(start 198.624952 -139.320778)
		(end 198.282052 -139.663678)
		(width 0.14224)
		(layer "In11.Cu")
		(net "M_F_DQ<0>")
	)
	(segment
		(start 198.314818 -130.030728)
		(end 198.314818 -131.208272)
		(width 0.14224)
		(layer "In11.Cu")
		(net "M_F_DQ<0>")
	)
	(segment
		(start 198.5264 -143.6116)
		(end 198.574152 -143.659352)
		(width 0.14224)
		(layer "In11.Cu")
		(net "M_F_DQ<0>")
	)
	(segment
		(start 197.735952 -149.810978)
		(end 197.735952 -150.450296)
		(width 0.14224)
		(layer "In11.Cu")
		(net "M_F_DQ<0>")
	)
	(segment
		(start 198.574152 -143.659352)
		(end 198.574152 -144.085818)
		(width 0.14224)
		(layer "In11.Cu")
		(net "M_F_DQ<0>")
	)
	(segment
		(start 198.128636 -127.143764)
		(end 198.128636 -128.888236)
		(width 0.14224)
		(layer "In11.Cu")
		(net "M_F_DQ<0>")
	)
	(segment
		(start 198.6534 -131.546854)
		(end 198.6534 -131.899152)
		(width 0.14224)
		(layer "In11.Cu")
		(net "M_F_DQ<0>")
	)
	(segment
		(start 198.128636 -128.888236)
		(end 198.624952 -129.384552)
		(width 0.14224)
		(layer "In11.Cu")
		(net "M_F_DQ<0>")
	)
	(segment
		(start 198.5264 -133.9088)
		(end 198.624952 -134.007352)
		(width 0.14224)
		(layer "In11.Cu")
		(net "M_F_DQ<0>")
	)
	(segment
		(start 197.666864 -153.911046)
		(end 198.772018 -155.0162)
		(width 0.14224)
		(layer "In11.Cu")
		(net "M_F_DQ<0>")
	)
	(segment
		(start 198.294752 -144.365218)
		(end 198.294752 -145.564606)
		(width 0.14224)
		(layer "In11.Cu")
		(net "M_F_DQ<0>")
	)
	(segment
		(start 198.282052 -134.776718)
		(end 198.282052 -135.950452)
		(width 0.14224)
		(layer "In11.Cu")
		(net "M_F_DQ<0>")
	)
	(segment
		(start 198.586852 -148.960078)
		(end 197.735952 -149.810978)
		(width 0.14224)
		(layer "In11.Cu")
		(net "M_F_DQ<0>")
	)
	(segment
		(start 238.202724 -84.222336)
		(end 238.169958 -84.222336)
		(width 0.0889)
		(layer "In11.Cu")
		(net "M_F_DQ<0>")
	)
	(segment
		(start 199.36333 -112.3442)
		(end 198.5772 -113.13033)
		(width 0.14224)
		(layer "In11.Cu")
		(net "M_F_DQ<0>")
	)
	(segment
		(start 204.343 -107.315254)
		(end 204.343 -107.874054)
		(width 0.14224)
		(layer "In11.Cu")
		(net "M_F_DQ<0>")
	)
	(segment
		(start 231.243124 -87.208614)
		(end 229.465886 -87.208614)
		(width 0.0889)
		(layer "In11.Cu")
		(net "M_F_DQ<0>")
	)
	(segment
		(start 198.294752 -145.564606)
		(end 198.586852 -145.856706)
		(width 0.14224)
		(layer "In11.Cu")
		(net "M_F_DQ<0>")
	)
	(segment
		(start 198.624952 -129.384552)
		(end 198.624952 -129.720594)
		(width 0.14224)
		(layer "In11.Cu")
		(net "M_F_DQ<0>")
	)
	(segment
		(start 198.5264 -146.262852)
		(end 198.5264 -148.4376)
		(width 0.14224)
		(layer "In11.Cu")
		(net "M_F_DQ<0>")
	)
	(segment
		(start 198.5264 -148.4376)
		(end 198.586852 -148.498052)
		(width 0.14224)
		(layer "In11.Cu")
		(net "M_F_DQ<0>")
	)
	(segment
		(start 206.6798 -103.251)
		(end 206.6798 -104.978454)
		(width 0.14224)
		(layer "In11.Cu")
		(net "M_F_DQ<0>")
	)
	(segment
		(start 198.586852 -146.2024)
		(end 198.5264 -146.262852)
		(width 0.14224)
		(layer "In11.Cu")
		(net "M_F_DQ<0>")
	)
	(segment
		(start 234.768644 -86.203536)
		(end 234.735878 -86.203536)
		(width 0.0889)
		(layer "In11.Cu")
		(net "M_F_DQ<0>")
	)
	(segment
		(start 198.282052 -140.743178)
		(end 198.574152 -141.035278)
		(width 0.14224)
		(layer "In11.Cu")
		(net "M_F_DQ<0>")
	)
	(segment
		(start 216.67978 -97.883218)
		(end 216.67978 -98.534474)
		(width 0.14224)
		(layer "In11.Cu")
		(net "M_F_DQ<0>")
	)
	(segment
		(start 198.5264 -136.674352)
		(end 198.5264 -138.7602)
		(width 0.14224)
		(layer "In11.Cu")
		(net "M_F_DQ<0>")
	)
	(segment
		(start 198.5264 -141.551152)
		(end 198.5264 -143.6116)
		(width 0.14224)
		(layer "In11.Cu")
		(net "M_F_DQ<0>")
	)
	(segment
		(start 198.574152 -141.035278)
		(end 198.574152 -141.5034)
		(width 0.14224)
		(layer "In11.Cu")
		(net "M_F_DQ<0>")
	)
	(segment
		(start 198.5772 -126.6952)
		(end 198.128636 -127.143764)
		(width 0.14224)
		(layer "In11.Cu")
		(net "M_F_DQ<0>")
	)
	(segment
		(start 233.906314 -86.69909)
		(end 233.873548 -86.69909)
		(width 0.0889)
		(layer "In11.Cu")
		(net "M_F_DQ<0>")
	)
	(segment
		(start 237.340394 -84.71789)
		(end 237.307628 -84.71789)
		(width 0.0889)
		(layer "In11.Cu")
		(net "M_F_DQ<0>")
	)
	(segment
		(start 198.574152 -141.5034)
		(end 198.5264 -141.551152)
		(width 0.14224)
		(layer "In11.Cu")
		(net "M_F_DQ<0>")
	)
	(segment
		(start 198.5772 -113.13033)
		(end 198.5772 -126.6952)
		(width 0.14224)
		(layer "In11.Cu")
		(net "M_F_DQ<0>")
	)
	(segment
		(start 204.343 -107.874054)
		(end 199.872854 -112.3442)
		(width 0.14224)
		(layer "In11.Cu")
		(net "M_F_DQ<0>")
	)
	(segment
		(start 198.624952 -136.293352)
		(end 198.624952 -136.5758)
		(width 0.14224)
		(layer "In11.Cu")
		(net "M_F_DQ<0>")
	)
	(segment
		(start 198.6534 -131.899152)
		(end 198.5264 -132.026152)
		(width 0.14224)
		(layer "In11.Cu")
		(net "M_F_DQ<0>")
	)
	(segment
		(start 229.233984 -86.976712)
		(end 227.586286 -86.976712)
		(width 0.14224)
		(layer "In11.Cu")
		(net "M_F_DQ<0>")
	)
	(segment
		(start 206.6798 -104.978454)
		(end 204.343 -107.315254)
		(width 0.14224)
		(layer "In11.Cu")
		(net "M_F_DQ<0>")
	)
	(segment
		(start 199.872854 -112.3442)
		(end 199.36333 -112.3442)
		(width 0.14224)
		(layer "In11.Cu")
		(net "M_F_DQ<0>")
	)
	(segment
		(start 198.624952 -129.720594)
		(end 198.314818 -130.030728)
		(width 0.14224)
		(layer "In11.Cu")
		(net "M_F_DQ<0>")
	)
	(segment
		(start 216.67978 -98.534474)
		(end 213.893654 -101.3206)
		(width 0.14224)
		(layer "In11.Cu")
		(net "M_F_DQ<0>")
	)
	(segment
		(start 198.282052 -135.950452)
		(end 198.624952 -136.293352)
		(width 0.14224)
		(layer "In11.Cu")
		(net "M_F_DQ<0>")
	)
	(segment
		(start 198.5264 -138.7602)
		(end 198.624952 -138.858752)
		(width 0.14224)
		(layer "In11.Cu")
		(net "M_F_DQ<0>")
	)
	(segment
		(start 242.480338 -86.29904)
		(end 242.1509 -85.538056)
		(width 0.0889)
		(layer "In11.Cu")
		(net "M_F_DQ<0>")
	)
	(segment
		(start 239.067848 -83.72729)
		(end 239.024668 -83.72729)
		(width 0.0889)
		(layer "In11.Cu")
		(net "M_F_DQ<0>")
	)
	(arc
		(start 239.024668 -83.72729)
		(mid 238.741451 -83.811571)
		(end 238.534448 -84.022438)
		(width 0.0889)
		(layer "In11.Cu")
		(net "M_F_DQ<0>")
	)
	(arc
		(start 237.307628 -84.71789)
		(mid 237.024411 -84.802171)
		(end 236.817408 -85.013038)
		(width 0.0889)
		(layer "In11.Cu")
		(net "M_F_DQ<0>")
	)
	(arc
		(start 233.018838 -87.194136)
		(mid 232.733414 -87.277603)
		(end 232.524808 -87.489538)
		(width 0.0889)
		(layer "In11.Cu")
		(net "M_F_DQ<0>")
	)
	(arc
		(start 234.735878 -86.203536)
		(mid 234.450454 -86.287003)
		(end 234.241848 -86.498938)
		(width 0.0889)
		(layer "In11.Cu")
		(net "M_F_DQ<0>")
	)
	(arc
		(start 240.752122 -84.71789)
		(mid 240.558272 -84.66154)
		(end 240.416588 -84.517738)
		(width 0.0889)
		(layer "In11.Cu")
		(net "M_F_DQ<0>")
	)
	(arc
		(start 240.416588 -84.517738)
		(mid 240.20798 -84.305806)
		(end 239.922558 -84.222336)
		(width 0.0889)
		(layer "In11.Cu")
		(net "M_F_DQ<0>")
	)
	(arc
		(start 235.100368 -86.003638)
		(mid 234.960289 -86.146374)
		(end 234.768644 -86.203536)
		(width 0.0889)
		(layer "In11.Cu")
		(net "M_F_DQ<0>")
	)
	(arc
		(start 238.169958 -84.222336)
		(mid 237.884534 -84.305803)
		(end 237.675928 -84.517738)
		(width 0.0889)
		(layer "In11.Cu")
		(net "M_F_DQ<0>")
	)
	(arc
		(start 241.606832 -85.212936)
		(mid 241.41519 -85.15577)
		(end 241.275108 -85.013038)
		(width 0.0889)
		(layer "In11.Cu")
		(net "M_F_DQ<0>")
	)
	(arc
		(start 238.534448 -84.022438)
		(mid 238.394369 -84.165174)
		(end 238.202724 -84.222336)
		(width 0.0889)
		(layer "In11.Cu")
		(net "M_F_DQ<0>")
	)
	(arc
		(start 242.133628 -85.508338)
		(mid 241.92502 -85.296406)
		(end 241.639598 -85.212936)
		(width 0.0889)
		(layer "In11.Cu")
		(net "M_F_DQ<0>")
	)
	(arc
		(start 234.241848 -86.498938)
		(mid 234.100165 -86.642742)
		(end 233.906314 -86.69909)
		(width 0.0889)
		(layer "In11.Cu")
		(net "M_F_DQ<0>")
	)
	(arc
		(start 233.873548 -86.69909)
		(mid 233.590331 -86.783371)
		(end 233.383328 -86.994238)
		(width 0.0889)
		(layer "In11.Cu")
		(net "M_F_DQ<0>")
	)
	(arc
		(start 232.524808 -87.489538)
		(mid 232.383125 -87.633342)
		(end 232.189274 -87.68969)
		(width 0.0889)
		(layer "In11.Cu")
		(net "M_F_DQ<0>")
	)
	(arc
		(start 236.817408 -85.013038)
		(mid 236.677329 -85.155774)
		(end 236.485684 -85.212936)
		(width 0.0889)
		(layer "In11.Cu")
		(net "M_F_DQ<0>")
	)
	(arc
		(start 236.452918 -85.212936)
		(mid 236.167494 -85.296403)
		(end 235.958888 -85.508338)
		(width 0.0889)
		(layer "In11.Cu")
		(net "M_F_DQ<0>")
	)
	(arc
		(start 237.675928 -84.517738)
		(mid 237.534245 -84.661542)
		(end 237.340394 -84.71789)
		(width 0.0889)
		(layer "In11.Cu")
		(net "M_F_DQ<0>")
	)
	(arc
		(start 239.558068 -84.022438)
		(mid 239.351064 -83.811574)
		(end 239.067848 -83.72729)
		(width 0.0889)
		(layer "In11.Cu")
		(net "M_F_DQ<0>")
	)
	(arc
		(start 233.383328 -86.994238)
		(mid 233.243249 -87.136974)
		(end 233.051604 -87.194136)
		(width 0.0889)
		(layer "In11.Cu")
		(net "M_F_DQ<0>")
	)
	(arc
		(start 239.889792 -84.222336)
		(mid 239.69815 -84.16517)
		(end 239.558068 -84.022438)
		(width 0.0889)
		(layer "In11.Cu")
		(net "M_F_DQ<0>")
	)
	(arc
		(start 241.275108 -85.013038)
		(mid 241.068104 -84.802174)
		(end 240.784888 -84.71789)
		(width 0.0889)
		(layer "In11.Cu")
		(net "M_F_DQ<0>")
	)
	(arc
		(start 235.590588 -85.70849)
		(mid 235.307371 -85.792771)
		(end 235.100368 -86.003638)
		(width 0.0889)
		(layer "In11.Cu")
		(net "M_F_DQ<0>")
	)
	(arc
		(start 235.958888 -85.508338)
		(mid 235.817205 -85.652142)
		(end 235.623354 -85.70849)
		(width 0.0889)
		(layer "In11.Cu")
		(net "M_F_DQ<0>")
	)
	(segment
		(start 267.948156 -93.72854)
		(end 267.376656 -93.72854)
		(width 0.1016)
		(layer "F.Cu")
		(net "M_F_CS_N<7>")
	)
	(via
		(at 267.376656 -93.72854)
		(size 0.508)
		(drill 0.254)
		(layers "F.Cu" "B.Cu")
		(net "M_F_CS_N<7>")
	)
	(via
		(at 277.999952 -148.773388)
		(size 0.4572)
		(drill 0.2032)
		(layers "F.Cu" "B.Cu")
		(net "M_F_CS_N<7>")
	)
	(segment
		(start 278.00046 -147.478496)
		(end 277.999952 -147.478496)
		(width 0.1651)
		(layer "B.Cu")
		(net "M_F_CS_N<7>")
	)
	(segment
		(start 277.999952 -147.478496)
		(end 277.999952 -148.773388)
		(width 0.1651)
		(layer "B.Cu")
		(net "M_F_CS_N<7>")
	)
	(segment
		(start 273.942302 -125.279658)
		(end 274.16125 -125.279658)
		(width 0.14224)
		(layer "In2.Cu")
		(net "M_F_CS_N<7>")
	)
	(segment
		(start 277.6982 -130.5306)
		(end 277.4696 -130.7592)
		(width 0.14224)
		(layer "In2.Cu")
		(net "M_F_CS_N<7>")
	)
	(segment
		(start 276.58695 -128.617218)
		(end 276.812502 -128.617218)
		(width 0.14224)
		(layer "In2.Cu")
		(net "M_F_CS_N<7>")
	)
	(segment
		(start 273.486372 -125.51664)
		(end 273.70532 -125.51664)
		(width 0.14224)
		(layer "In2.Cu")
		(net "M_F_CS_N<7>")
	)
	(segment
		(start 268.986 -103.153464)
		(end 268.986 -119.996966)
		(width 0.14224)
		(layer "In2.Cu")
		(net "M_F_CS_N<7>")
	)
	(segment
		(start 272.640806 -124.671074)
		(end 273.486372 -125.51664)
		(width 0.14224)
		(layer "In2.Cu")
		(net "M_F_CS_N<7>")
	)
	(segment
		(start 274.16125 -125.279658)
		(end 274.411186 -125.529594)
		(width 0.14224)
		(layer "In2.Cu")
		(net "M_F_CS_N<7>")
	)
	(segment
		(start 267.376656 -93.72854)
		(end 268.351 -94.702884)
		(width 0.14224)
		(layer "In2.Cu")
		(net "M_F_CS_N<7>")
	)
	(segment
		(start 277.585424 -146.470624)
		(end 277.999952 -146.885152)
		(width 0.14224)
		(layer "In2.Cu")
		(net "M_F_CS_N<7>")
	)
	(segment
		(start 272.640806 -123.651772)
		(end 272.640806 -124.671074)
		(width 0.14224)
		(layer "In2.Cu")
		(net "M_F_CS_N<7>")
	)
	(segment
		(start 277.4696 -130.7592)
		(end 277.4696 -131.1148)
		(width 0.14224)
		(layer "In2.Cu")
		(net "M_F_CS_N<7>")
	)
	(segment
		(start 274.411186 -125.748542)
		(end 274.174204 -125.985524)
		(width 0.14224)
		(layer "In2.Cu")
		(net "M_F_CS_N<7>")
	)
	(segment
		(start 274.174204 -126.204472)
		(end 276.58695 -128.617218)
		(width 0.14224)
		(layer "In2.Cu")
		(net "M_F_CS_N<7>")
	)
	(segment
		(start 277.6982 -133.6294)
		(end 277.585424 -133.742176)
		(width 0.14224)
		(layer "In2.Cu")
		(net "M_F_CS_N<7>")
	)
	(segment
		(start 268.351 -96.7994)
		(end 268.9098 -97.3582)
		(width 0.14224)
		(layer "In2.Cu")
		(net "M_F_CS_N<7>")
	)
	(segment
		(start 268.9098 -100.30714)
		(end 269.2654 -100.66274)
		(width 0.14224)
		(layer "In2.Cu")
		(net "M_F_CS_N<7>")
	)
	(segment
		(start 268.351 -94.702884)
		(end 268.351 -96.7994)
		(width 0.14224)
		(layer "In2.Cu")
		(net "M_F_CS_N<7>")
	)
	(segment
		(start 276.812502 -128.617218)
		(end 277.5204 -129.325116)
		(width 0.14224)
		(layer "In2.Cu")
		(net "M_F_CS_N<7>")
	)
	(segment
		(start 269.2654 -100.66274)
		(end 269.2654 -102.874064)
		(width 0.14224)
		(layer "In2.Cu")
		(net "M_F_CS_N<7>")
	)
	(segment
		(start 277.585424 -133.742176)
		(end 277.585424 -146.470624)
		(width 0.14224)
		(layer "In2.Cu")
		(net "M_F_CS_N<7>")
	)
	(segment
		(start 268.986 -119.996966)
		(end 272.640806 -123.651772)
		(width 0.14224)
		(layer "In2.Cu")
		(net "M_F_CS_N<7>")
	)
	(segment
		(start 268.9098 -97.3582)
		(end 268.9098 -100.30714)
		(width 0.14224)
		(layer "In2.Cu")
		(net "M_F_CS_N<7>")
	)
	(segment
		(start 277.6982 -130.048)
		(end 277.6982 -130.5306)
		(width 0.14224)
		(layer "In2.Cu")
		(net "M_F_CS_N<7>")
	)
	(segment
		(start 274.411186 -125.529594)
		(end 274.411186 -125.748542)
		(width 0.14224)
		(layer "In2.Cu")
		(net "M_F_CS_N<7>")
	)
	(segment
		(start 277.5204 -129.325116)
		(end 277.5204 -129.8702)
		(width 0.14224)
		(layer "In2.Cu")
		(net "M_F_CS_N<7>")
	)
	(segment
		(start 273.70532 -125.51664)
		(end 273.942302 -125.279658)
		(width 0.14224)
		(layer "In2.Cu")
		(net "M_F_CS_N<7>")
	)
	(segment
		(start 274.174204 -125.985524)
		(end 274.174204 -126.204472)
		(width 0.14224)
		(layer "In2.Cu")
		(net "M_F_CS_N<7>")
	)
	(segment
		(start 277.5204 -129.8702)
		(end 277.6982 -130.048)
		(width 0.14224)
		(layer "In2.Cu")
		(net "M_F_CS_N<7>")
	)
	(segment
		(start 277.4696 -131.1148)
		(end 277.6982 -131.3434)
		(width 0.14224)
		(layer "In2.Cu")
		(net "M_F_CS_N<7>")
	)
	(segment
		(start 269.2654 -102.874064)
		(end 268.986 -103.153464)
		(width 0.14224)
		(layer "In2.Cu")
		(net "M_F_CS_N<7>")
	)
	(segment
		(start 277.6982 -131.3434)
		(end 277.6982 -133.6294)
		(width 0.14224)
		(layer "In2.Cu")
		(net "M_F_CS_N<7>")
	)
	(segment
		(start 277.999952 -146.885152)
		(end 277.999952 -148.773388)
		(width 0.14224)
		(layer "In2.Cu")
		(net "M_F_CS_N<7>")
	)
	(segment
		(start 267.948156 -94.718886)
		(end 267.376656 -94.718886)
		(width 0.1016)
		(layer "F.Cu")
		(net "M_F_CS_N<6>")
	)
	(via
		(at 267.376656 -94.718886)
		(size 0.508)
		(drill 0.254)
		(layers "F.Cu" "B.Cu")
		(net "M_F_CS_N<6>")
	)
	(via
		(at 277.999952 -150.789386)
		(size 0.4572)
		(drill 0.2032)
		(layers "F.Cu" "B.Cu")
		(net "M_F_CS_N<6>")
	)
	(segment
		(start 278.00046 -152.078436)
		(end 277.999952 -152.078182)
		(width 0.1651)
		(layer "B.Cu")
		(net "M_F_CS_N<6>")
	)
	(segment
		(start 277.999952 -152.078182)
		(end 277.999952 -150.789386)
		(width 0.1651)
		(layer "B.Cu")
		(net "M_F_CS_N<6>")
	)
	(segment
		(start 276.6568 -131.318)
		(end 276.6568 -134.0358)
		(width 0.14224)
		(layer "In2.Cu")
		(net "M_F_CS_N<6>")
	)
	(segment
		(start 276.712172 -141.588744)
		(end 276.712172 -146.460972)
		(width 0.14224)
		(layer "In2.Cu")
		(net "M_F_CS_N<6>")
	)
	(segment
		(start 268.7574 -100.8634)
		(end 268.7574 -102.6668)
		(width 0.14224)
		(layer "In2.Cu")
		(net "M_F_CS_N<6>")
	)
	(segment
		(start 277.999952 -150.104856)
		(end 277.999952 -150.789386)
		(width 0.14224)
		(layer "In2.Cu")
		(net "M_F_CS_N<6>")
	)
	(segment
		(start 276.6568 -134.0358)
		(end 276.712172 -134.091172)
		(width 0.14224)
		(layer "In2.Cu")
		(net "M_F_CS_N<6>")
	)
	(segment
		(start 267.8684 -97.1042)
		(end 268.3764 -97.6122)
		(width 0.14224)
		(layer "In2.Cu")
		(net "M_F_CS_N<6>")
	)
	(segment
		(start 276.712172 -146.460972)
		(end 277.585424 -147.334224)
		(width 0.14224)
		(layer "In2.Cu")
		(net "M_F_CS_N<6>")
	)
	(segment
		(start 276.494748 -129.116836)
		(end 276.75713 -129.379218)
		(width 0.14224)
		(layer "In2.Cu")
		(net "M_F_CS_N<6>")
	)
	(segment
		(start 276.75713 -129.379218)
		(end 276.75713 -129.84607)
		(width 0.14224)
		(layer "In2.Cu")
		(net "M_F_CS_N<6>")
	)
	(segment
		(start 276.7584 -130.7084)
		(end 276.7584 -131.2164)
		(width 0.14224)
		(layer "In2.Cu")
		(net "M_F_CS_N<6>")
	)
	(segment
		(start 276.5552 -130.5052)
		(end 276.7584 -130.7084)
		(width 0.14224)
		(layer "In2.Cu")
		(net "M_F_CS_N<6>")
	)
	(segment
		(start 276.714458 -140.240258)
		(end 276.714458 -141.586458)
		(width 0.14224)
		(layer "In2.Cu")
		(net "M_F_CS_N<6>")
	)
	(segment
		(start 277.585424 -149.086824)
		(end 277.7236 -149.225)
		(width 0.14224)
		(layer "In2.Cu")
		(net "M_F_CS_N<6>")
	)
	(segment
		(start 268.478 -120.207532)
		(end 272.132806 -123.862338)
		(width 0.14224)
		(layer "In2.Cu")
		(net "M_F_CS_N<6>")
	)
	(segment
		(start 268.7574 -102.6668)
		(end 268.478 -102.9462)
		(width 0.14224)
		(layer "In2.Cu")
		(net "M_F_CS_N<6>")
	)
	(segment
		(start 276.7584 -131.2164)
		(end 276.6568 -131.318)
		(width 0.14224)
		(layer "In2.Cu")
		(net "M_F_CS_N<6>")
	)
	(segment
		(start 267.376656 -94.718886)
		(end 267.8684 -95.21063)
		(width 0.14224)
		(layer "In2.Cu")
		(net "M_F_CS_N<6>")
	)
	(segment
		(start 276.712172 -140.237972)
		(end 276.714458 -140.240258)
		(width 0.14224)
		(layer "In2.Cu")
		(net "M_F_CS_N<6>")
	)
	(segment
		(start 276.75713 -129.84607)
		(end 276.5552 -130.048)
		(width 0.14224)
		(layer "In2.Cu")
		(net "M_F_CS_N<6>")
	)
	(segment
		(start 268.3764 -100.4824)
		(end 268.7574 -100.8634)
		(width 0.14224)
		(layer "In2.Cu")
		(net "M_F_CS_N<6>")
	)
	(segment
		(start 276.714458 -141.586458)
		(end 276.712172 -141.588744)
		(width 0.14224)
		(layer "In2.Cu")
		(net "M_F_CS_N<6>")
	)
	(segment
		(start 277.585424 -147.334224)
		(end 277.585424 -149.086824)
		(width 0.14224)
		(layer "In2.Cu")
		(net "M_F_CS_N<6>")
	)
	(segment
		(start 268.478 -102.9462)
		(end 268.478 -120.207532)
		(width 0.14224)
		(layer "In2.Cu")
		(net "M_F_CS_N<6>")
	)
	(segment
		(start 276.5552 -130.048)
		(end 276.5552 -130.5052)
		(width 0.14224)
		(layer "In2.Cu")
		(net "M_F_CS_N<6>")
	)
	(segment
		(start 267.8684 -95.21063)
		(end 267.8684 -97.1042)
		(width 0.14224)
		(layer "In2.Cu")
		(net "M_F_CS_N<6>")
	)
	(segment
		(start 272.132806 -124.88164)
		(end 276.368002 -129.116836)
		(width 0.14224)
		(layer "In2.Cu")
		(net "M_F_CS_N<6>")
	)
	(segment
		(start 276.368002 -129.116836)
		(end 276.494748 -129.116836)
		(width 0.14224)
		(layer "In2.Cu")
		(net "M_F_CS_N<6>")
	)
	(segment
		(start 276.712172 -134.091172)
		(end 276.712172 -140.237972)
		(width 0.14224)
		(layer "In2.Cu")
		(net "M_F_CS_N<6>")
	)
	(segment
		(start 277.7236 -149.828504)
		(end 277.999952 -150.104856)
		(width 0.14224)
		(layer "In2.Cu")
		(net "M_F_CS_N<6>")
	)
	(segment
		(start 277.7236 -149.225)
		(end 277.7236 -149.828504)
		(width 0.14224)
		(layer "In2.Cu")
		(net "M_F_CS_N<6>")
	)
	(segment
		(start 268.3764 -97.6122)
		(end 268.3764 -100.4824)
		(width 0.14224)
		(layer "In2.Cu")
		(net "M_F_CS_N<6>")
	)
	(segment
		(start 272.132806 -123.862338)
		(end 272.132806 -124.88164)
		(width 0.14224)
		(layer "In2.Cu")
		(net "M_F_CS_N<6>")
	)
	(segment
		(start 265.372596 -93.23324)
		(end 264.801096 -93.23324)
		(width 0.1016)
		(layer "F.Cu")
		(net "M_F_CS_N<5>")
	)
	(via
		(at 264.801096 -93.23324)
		(size 0.508)
		(drill 0.254)
		(layers "F.Cu" "B.Cu")
		(net "M_F_CS_N<5>")
	)
	(via
		(at 274.599908 -150.785068)
		(size 0.4572)
		(drill 0.2032)
		(layers "F.Cu" "B.Cu")
		(net "M_F_CS_N<5>")
	)
	(segment
		(start 274.599908 -152.078182)
		(end 274.599908 -150.785068)
		(width 0.1651)
		(layer "B.Cu")
		(net "M_F_CS_N<5>")
	)
	(segment
		(start 274.600416 -152.078436)
		(end 274.599908 -152.078182)
		(width 0.1651)
		(layer "B.Cu")
		(net "M_F_CS_N<5>")
	)
	(segment
		(start 274.16379 -147.41779)
		(end 274.16379 -149.09419)
		(width 0.14224)
		(layer "In2.Cu")
		(net "M_F_CS_N<5>")
	)
	(segment
		(start 269.555722 -124.394214)
		(end 269.783814 -124.394214)
		(width 0.14224)
		(layer "In2.Cu")
		(net "M_F_CS_N<5>")
	)
	(segment
		(start 265.147806 -96.404938)
		(end 265.141456 -96.415606)
		(width 0.0889)
		(layer "In2.Cu")
		(net "M_F_CS_N<5>")
	)
	(segment
		(start 266.420854 -122.057414)
		(end 266.711176 -122.347736)
		(width 0.14224)
		(layer "In2.Cu")
		(net "M_F_CS_N<5>")
	)
	(segment
		(start 268.393926 -123.256802)
		(end 268.646402 -123.256802)
		(width 0.14224)
		(layer "In2.Cu")
		(net "M_F_CS_N<5>")
	)
	(segment
		(start 268.646402 -123.256802)
		(end 268.951202 -123.561602)
		(width 0.14224)
		(layer "In2.Cu")
		(net "M_F_CS_N<5>")
	)
	(segment
		(start 274.16379 -149.09419)
		(end 274.4216 -149.352)
		(width 0.14224)
		(layer "In2.Cu")
		(net "M_F_CS_N<5>")
	)
	(segment
		(start 273.3802 -130.683)
		(end 273.3802 -131.2164)
		(width 0.14224)
		(layer "In2.Cu")
		(net "M_F_CS_N<5>")
	)
	(segment
		(start 267.51153 -122.108214)
		(end 267.813536 -122.41022)
		(width 0.14224)
		(layer "In2.Cu")
		(net "M_F_CS_N<5>")
	)
	(segment
		(start 269.783814 -124.394214)
		(end 270.100806 -124.711206)
		(width 0.14224)
		(layer "In2.Cu")
		(net "M_F_CS_N<5>")
	)
	(segment
		(start 273.2278 -132.3594)
		(end 273.342608 -132.474208)
		(width 0.14224)
		(layer "In2.Cu")
		(net "M_F_CS_N<5>")
	)
	(segment
		(start 267.479526 -123.021598)
		(end 267.479526 -123.252738)
		(width 0.14224)
		(layer "In2.Cu")
		(net "M_F_CS_N<5>")
	)
	(segment
		(start 269.854172 -125.245368)
		(end 269.854172 -125.495812)
		(width 0.14224)
		(layer "In2.Cu")
		(net "M_F_CS_N<5>")
	)
	(segment
		(start 270.100806 -124.711206)
		(end 270.100806 -124.998734)
		(width 0.14224)
		(layer "In2.Cu")
		(net "M_F_CS_N<5>")
	)
	(segment
		(start 269.854172 -125.495812)
		(end 273.3802 -129.02184)
		(width 0.14224)
		(layer "In2.Cu")
		(net "M_F_CS_N<5>")
	)
	(segment
		(start 265.152632 -95.405702)
		(end 265.147806 -95.414338)
		(width 0.0889)
		(layer "In2.Cu")
		(net "M_F_CS_N<5>")
	)
	(segment
		(start 265.6078 -99.540822)
		(end 265.6078 -102.278688)
		(width 0.0889)
		(layer "In2.Cu")
		(net "M_F_CS_N<5>")
	)
	(segment
		(start 264.801096 -93.23324)
		(end 265.104626 -93.93174)
		(width 0.0889)
		(layer "In2.Cu")
		(net "M_F_CS_N<5>")
	)
	(segment
		(start 273.338544 -141.893544)
		(end 273.338544 -146.592544)
		(width 0.14224)
		(layer "In2.Cu")
		(net "M_F_CS_N<5>")
	)
	(segment
		(start 265.6078 -102.278688)
		(end 266.4206 -103.091488)
		(width 0.0889)
		(layer "In2.Cu")
		(net "M_F_CS_N<5>")
	)
	(segment
		(start 268.07287 -123.577858)
		(end 268.393926 -123.256802)
		(width 0.14224)
		(layer "In2.Cu")
		(net "M_F_CS_N<5>")
	)
	(segment
		(start 265.147806 -98.386138)
		(end 265.141456 -98.396806)
		(width 0.0889)
		(layer "In2.Cu")
		(net "M_F_CS_N<5>")
	)
	(segment
		(start 268.951202 -123.561602)
		(end 268.951202 -123.84913)
		(width 0.14224)
		(layer "In2.Cu")
		(net "M_F_CS_N<5>")
	)
	(segment
		(start 273.2278 -131.3688)
		(end 273.2278 -132.3594)
		(width 0.14224)
		(layer "In2.Cu")
		(net "M_F_CS_N<5>")
	)
	(segment
		(start 274.4216 -149.352)
		(end 274.4216 -149.926548)
		(width 0.14224)
		(layer "In2.Cu")
		(net "M_F_CS_N<5>")
	)
	(segment
		(start 274.599908 -150.104856)
		(end 274.599908 -150.785068)
		(width 0.14224)
		(layer "In2.Cu")
		(net "M_F_CS_N<5>")
	)
	(segment
		(start 266.711176 -122.347736)
		(end 267.003784 -122.347736)
		(width 0.14224)
		(layer "In2.Cu")
		(net "M_F_CS_N<5>")
	)
	(segment
		(start 267.813536 -122.41022)
		(end 267.813536 -122.687588)
		(width 0.14224)
		(layer "In2.Cu")
		(net "M_F_CS_N<5>")
	)
	(segment
		(start 265.290046 -99.223068)
		(end 265.6078 -99.540822)
		(width 0.0889)
		(layer "In2.Cu")
		(net "M_F_CS_N<5>")
	)
	(segment
		(start 267.479526 -123.252738)
		(end 267.804646 -123.577858)
		(width 0.14224)
		(layer "In2.Cu")
		(net "M_F_CS_N<5>")
	)
	(segment
		(start 273.334988 -140.201396)
		(end 273.316192 -140.220192)
		(width 0.14224)
		(layer "In2.Cu")
		(net "M_F_CS_N<5>")
	)
	(segment
		(start 273.3802 -131.2164)
		(end 273.2278 -131.3688)
		(width 0.14224)
		(layer "In2.Cu")
		(net "M_F_CS_N<5>")
	)
	(segment
		(start 265.152632 -98.377502)
		(end 265.147806 -98.386138)
		(width 0.0889)
		(layer "In2.Cu")
		(net "M_F_CS_N<5>")
	)
	(segment
		(start 273.3802 -129.02184)
		(end 273.3802 -129.8702)
		(width 0.14224)
		(layer "In2.Cu")
		(net "M_F_CS_N<5>")
	)
	(segment
		(start 268.638528 -124.385578)
		(end 268.99108 -124.73813)
		(width 0.14224)
		(layer "In2.Cu")
		(net "M_F_CS_N<5>")
	)
	(segment
		(start 273.342608 -132.474208)
		(end 273.342608 -134.682992)
		(width 0.14224)
		(layer "In2.Cu")
		(net "M_F_CS_N<5>")
	)
	(segment
		(start 273.316192 -141.871192)
		(end 273.338544 -141.893544)
		(width 0.14224)
		(layer "In2.Cu")
		(net "M_F_CS_N<5>")
	)
	(segment
		(start 273.342608 -134.682992)
		(end 273.334988 -134.690612)
		(width 0.14224)
		(layer "In2.Cu")
		(net "M_F_CS_N<5>")
	)
	(segment
		(start 265.141456 -94.01302)
		(end 265.147806 -94.023688)
		(width 0.0889)
		(layer "In2.Cu")
		(net "M_F_CS_N<5>")
	)
	(segment
		(start 273.338544 -146.592544)
		(end 274.16379 -147.41779)
		(width 0.14224)
		(layer "In2.Cu")
		(net "M_F_CS_N<5>")
	)
	(segment
		(start 273.2024 -130.048)
		(end 273.2024 -130.5052)
		(width 0.14224)
		(layer "In2.Cu")
		(net "M_F_CS_N<5>")
	)
	(segment
		(start 266.4206 -103.091488)
		(end 266.4206 -103.406194)
		(width 0.0889)
		(layer "In2.Cu")
		(net "M_F_CS_N<5>")
	)
	(segment
		(start 267.813536 -122.687588)
		(end 267.479526 -123.021598)
		(width 0.14224)
		(layer "In2.Cu")
		(net "M_F_CS_N<5>")
	)
	(segment
		(start 265.147806 -95.414338)
		(end 265.141456 -95.425006)
		(width 0.0889)
		(layer "In2.Cu")
		(net "M_F_CS_N<5>")
	)
	(segment
		(start 273.316192 -140.220192)
		(end 273.316192 -141.871192)
		(width 0.14224)
		(layer "In2.Cu")
		(net "M_F_CS_N<5>")
	)
	(segment
		(start 268.638528 -124.161804)
		(end 268.638528 -124.385578)
		(width 0.14224)
		(layer "In2.Cu")
		(net "M_F_CS_N<5>")
	)
	(segment
		(start 267.243306 -122.108214)
		(end 267.51153 -122.108214)
		(width 0.14224)
		(layer "In2.Cu")
		(net "M_F_CS_N<5>")
	)
	(segment
		(start 273.2024 -130.5052)
		(end 273.3802 -130.683)
		(width 0.14224)
		(layer "In2.Cu")
		(net "M_F_CS_N<5>")
	)
	(segment
		(start 265.152632 -96.396302)
		(end 265.147806 -96.404938)
		(width 0.0889)
		(layer "In2.Cu")
		(net "M_F_CS_N<5>")
	)
	(segment
		(start 274.4216 -149.926548)
		(end 274.599908 -150.104856)
		(width 0.14224)
		(layer "In2.Cu")
		(net "M_F_CS_N<5>")
	)
	(segment
		(start 268.99108 -124.73813)
		(end 269.211806 -124.73813)
		(width 0.14224)
		(layer "In2.Cu")
		(net "M_F_CS_N<5>")
	)
	(segment
		(start 267.003784 -122.347736)
		(end 267.243306 -122.108214)
		(width 0.14224)
		(layer "In2.Cu")
		(net "M_F_CS_N<5>")
	)
	(segment
		(start 266.420854 -121.02465)
		(end 266.420854 -122.057414)
		(width 0.14224)
		(layer "In2.Cu")
		(net "M_F_CS_N<5>")
	)
	(segment
		(start 268.951202 -123.84913)
		(end 268.638528 -124.161804)
		(width 0.14224)
		(layer "In2.Cu")
		(net "M_F_CS_N<5>")
	)
	(segment
		(start 267.804646 -123.577858)
		(end 268.07287 -123.577858)
		(width 0.14224)
		(layer "In2.Cu")
		(net "M_F_CS_N<5>")
	)
	(segment
		(start 269.211806 -124.73813)
		(end 269.555722 -124.394214)
		(width 0.14224)
		(layer "In2.Cu")
		(net "M_F_CS_N<5>")
	)
	(segment
		(start 265.147806 -97.395538)
		(end 265.141456 -97.406206)
		(width 0.0889)
		(layer "In2.Cu")
		(net "M_F_CS_N<5>")
	)
	(segment
		(start 270.100806 -124.998734)
		(end 269.854172 -125.245368)
		(width 0.14224)
		(layer "In2.Cu")
		(net "M_F_CS_N<5>")
	)
	(segment
		(start 273.334988 -134.690612)
		(end 273.334988 -140.201396)
		(width 0.14224)
		(layer "In2.Cu")
		(net "M_F_CS_N<5>")
	)
	(segment
		(start 273.3802 -129.8702)
		(end 273.2024 -130.048)
		(width 0.14224)
		(layer "In2.Cu")
		(net "M_F_CS_N<5>")
	)
	(segment
		(start 265.152632 -97.386902)
		(end 265.147806 -97.395538)
		(width 0.0889)
		(layer "In2.Cu")
		(net "M_F_CS_N<5>")
	)
	(segment
		(start 266.4206 -121.024396)
		(end 266.420854 -121.02465)
		(width 0.14224)
		(layer "In2.Cu")
		(net "M_F_CS_N<5>")
	)
	(segment
		(start 265.147806 -98.976688)
		(end 265.290046 -99.223068)
		(width 0.0889)
		(layer "In2.Cu")
		(net "M_F_CS_N<5>")
	)
	(segment
		(start 266.4206 -103.406194)
		(end 266.4206 -121.024396)
		(width 0.14224)
		(layer "In2.Cu")
		(net "M_F_CS_N<5>")
	)
	(arc
		(start 265.141456 -96.415606)
		(mid 265.068658 -96.706369)
		(end 265.147806 -96.995488)
		(width 0.0889)
		(layer "In2.Cu")
		(net "M_F_CS_N<5>")
	)
	(arc
		(start 265.147806 -94.423484)
		(mid 265.068675 -94.718886)
		(end 265.147806 -95.014288)
		(width 0.0889)
		(layer "In2.Cu")
		(net "M_F_CS_N<5>")
	)
	(arc
		(start 265.141456 -98.396806)
		(mid 265.068658 -98.687569)
		(end 265.147806 -98.976688)
		(width 0.0889)
		(layer "In2.Cu")
		(net "M_F_CS_N<5>")
	)
	(arc
		(start 265.147806 -94.023688)
		(mid 265.201305 -94.223586)
		(end 265.147806 -94.423484)
		(width 0.0889)
		(layer "In2.Cu")
		(net "M_F_CS_N<5>")
	)
	(arc
		(start 265.141456 -95.425006)
		(mid 265.068658 -95.715769)
		(end 265.147806 -96.004888)
		(width 0.0889)
		(layer "In2.Cu")
		(net "M_F_CS_N<5>")
	)
	(arc
		(start 265.147806 -97.986088)
		(mid 265.201276 -98.181151)
		(end 265.152632 -98.377502)
		(width 0.0889)
		(layer "In2.Cu")
		(net "M_F_CS_N<5>")
	)
	(arc
		(start 265.147806 -95.014288)
		(mid 265.201276 -95.209351)
		(end 265.152632 -95.405702)
		(width 0.0889)
		(layer "In2.Cu")
		(net "M_F_CS_N<5>")
	)
	(arc
		(start 265.147806 -96.004888)
		(mid 265.201276 -96.199951)
		(end 265.152632 -96.396302)
		(width 0.0889)
		(layer "In2.Cu")
		(net "M_F_CS_N<5>")
	)
	(arc
		(start 265.141456 -97.406206)
		(mid 265.068658 -97.696969)
		(end 265.147806 -97.986088)
		(width 0.0889)
		(layer "In2.Cu")
		(net "M_F_CS_N<5>")
	)
	(arc
		(start 265.104626 -93.93174)
		(mid 265.12151 -93.973074)
		(end 265.141456 -94.01302)
		(width 0.0889)
		(layer "In2.Cu")
		(net "M_F_CS_N<5>")
	)
	(arc
		(start 265.147806 -96.995488)
		(mid 265.201276 -97.190551)
		(end 265.152632 -97.386902)
		(width 0.0889)
		(layer "In2.Cu")
		(net "M_F_CS_N<5>")
	)
	(segment
		(start 262.79729 -91.747086)
		(end 262.22579 -91.747086)
		(width 0.1016)
		(layer "F.Cu")
		(net "M_F_CS_N<4>")
	)
	(via
		(at 270.350234 -150.788878)
		(size 0.4572)
		(drill 0.2032)
		(layers "F.Cu" "B.Cu")
		(net "M_F_CS_N<4>")
	)
	(via
		(at 262.22579 -91.747086)
		(size 0.508)
		(drill 0.254)
		(layers "F.Cu" "B.Cu")
		(net "M_F_CS_N<4>")
	)
	(segment
		(start 270.34998 -152.078182)
		(end 270.34998 -150.789132)
		(width 0.1651)
		(layer "B.Cu")
		(net "M_F_CS_N<4>")
	)
	(segment
		(start 270.34998 -150.789132)
		(end 270.350234 -150.788878)
		(width 0.1651)
		(layer "B.Cu")
		(net "M_F_CS_N<4>")
	)
	(segment
		(start 270.350488 -152.078436)
		(end 270.34998 -152.078182)
		(width 0.1651)
		(layer "B.Cu")
		(net "M_F_CS_N<4>")
	)
	(segment
		(start 262.74395 -94.01302)
		(end 262.7376 -94.023688)
		(width 0.0889)
		(layer "In2.Cu")
		(net "M_F_CS_N<4>")
	)
	(segment
		(start 262.732774 -97.386902)
		(end 262.7376 -97.395538)
		(width 0.0889)
		(layer "In2.Cu")
		(net "M_F_CS_N<4>")
	)
	(segment
		(start 262.7376 -96.404938)
		(end 262.74395 -96.415606)
		(width 0.0889)
		(layer "In2.Cu")
		(net "M_F_CS_N<4>")
	)
	(segment
		(start 266.5222 -126.891034)
		(end 268.9606 -129.329434)
		(width 0.14224)
		(layer "In2.Cu")
		(net "M_F_CS_N<4>")
	)
	(segment
		(start 263.6774 -102.683564)
		(end 263.8552 -102.861364)
		(width 0.0889)
		(layer "In2.Cu")
		(net "M_F_CS_N<4>")
	)
	(segment
		(start 262.22579 -92.12199)
		(end 262.690102 -92.586302)
		(width 0.0889)
		(layer "In2.Cu")
		(net "M_F_CS_N<4>")
	)
	(segment
		(start 269.113 -140.512546)
		(end 269.065756 -140.55979)
		(width 0.14224)
		(layer "In2.Cu")
		(net "M_F_CS_N<4>")
	)
	(segment
		(start 269.1892 -136.996932)
		(end 269.1892 -138.5062)
		(width 0.14224)
		(layer "In2.Cu")
		(net "M_F_CS_N<4>")
	)
	(segment
		(start 269.087854 -135.73125)
		(end 269.087854 -136.895586)
		(width 0.14224)
		(layer "In2.Cu")
		(net "M_F_CS_N<4>")
	)
	(segment
		(start 262.732774 -93.424502)
		(end 262.7376 -93.433138)
		(width 0.0889)
		(layer "In2.Cu")
		(net "M_F_CS_N<4>")
	)
	(segment
		(start 269.151862 -145.726658)
		(end 269.084552 -145.793968)
		(width 0.14224)
		(layer "In2.Cu")
		(net "M_F_CS_N<4>")
	)
	(segment
		(start 269.151862 -144.463262)
		(end 269.151862 -145.726658)
		(width 0.14224)
		(layer "In2.Cu")
		(net "M_F_CS_N<4>")
	)
	(segment
		(start 269.1384 -135.680704)
		(end 269.087854 -135.73125)
		(width 0.14224)
		(layer "In2.Cu")
		(net "M_F_CS_N<4>")
	)
	(segment
		(start 268.9606 -129.794)
		(end 269.2146 -130.048)
		(width 0.14224)
		(layer "In2.Cu")
		(net "M_F_CS_N<4>")
	)
	(segment
		(start 262.660384 -100.34016)
		(end 263.6774 -101.357176)
		(width 0.0889)
		(layer "In2.Cu")
		(net "M_F_CS_N<4>")
	)
	(segment
		(start 269.927578 -149.569678)
		(end 270.350234 -149.992334)
		(width 0.14224)
		(layer "In2.Cu")
		(net "M_F_CS_N<4>")
	)
	(segment
		(start 263.8552 -102.861364)
		(end 263.8552 -103.078534)
		(width 0.0889)
		(layer "In2.Cu")
		(net "M_F_CS_N<4>")
	)
	(segment
		(start 269.2146 -130.048)
		(end 269.2146 -130.4544)
		(width 0.14224)
		(layer "In2.Cu")
		(net "M_F_CS_N<4>")
	)
	(segment
		(start 262.732774 -98.377502)
		(end 262.7376 -98.386138)
		(width 0.0889)
		(layer "In2.Cu")
		(net "M_F_CS_N<4>")
	)
	(segment
		(start 268.9606 -129.329434)
		(end 268.9606 -129.794)
		(width 0.14224)
		(layer "In2.Cu")
		(net "M_F_CS_N<4>")
	)
	(segment
		(start 263.6774 -101.357176)
		(end 263.6774 -102.683564)
		(width 0.0889)
		(layer "In2.Cu")
		(net "M_F_CS_N<4>")
	)
	(segment
		(start 262.7376 -95.414338)
		(end 262.74395 -95.425006)
		(width 0.0889)
		(layer "In2.Cu")
		(net "M_F_CS_N<4>")
	)
	(segment
		(start 269.084552 -147.24126)
		(end 269.927578 -148.084286)
		(width 0.14224)
		(layer "In2.Cu")
		(net "M_F_CS_N<4>")
	)
	(segment
		(start 262.22579 -91.747086)
		(end 262.22579 -92.12199)
		(width 0.0889)
		(layer "In2.Cu")
		(net "M_F_CS_N<4>")
	)
	(segment
		(start 269.1384 -134.8232)
		(end 269.1384 -135.680704)
		(width 0.14224)
		(layer "In2.Cu")
		(net "M_F_CS_N<4>")
	)
	(segment
		(start 269.091664 -134.776464)
		(end 269.1384 -134.8232)
		(width 0.14224)
		(layer "In2.Cu")
		(net "M_F_CS_N<4>")
	)
	(segment
		(start 262.732774 -95.405702)
		(end 262.7376 -95.414338)
		(width 0.0889)
		(layer "In2.Cu")
		(net "M_F_CS_N<4>")
	)
	(segment
		(start 269.1892 -138.5062)
		(end 269.087854 -138.607546)
		(width 0.14224)
		(layer "In2.Cu")
		(net "M_F_CS_N<4>")
	)
	(segment
		(start 266.5222 -125.75667)
		(end 266.5222 -126.891034)
		(width 0.14224)
		(layer "In2.Cu")
		(net "M_F_CS_N<4>")
	)
	(segment
		(start 262.732774 -96.396302)
		(end 262.7376 -96.404938)
		(width 0.0889)
		(layer "In2.Cu")
		(net "M_F_CS_N<4>")
	)
	(segment
		(start 269.2146 -130.4544)
		(end 269.0114 -130.6576)
		(width 0.14224)
		(layer "In2.Cu")
		(net "M_F_CS_N<4>")
	)
	(segment
		(start 269.087854 -136.895586)
		(end 269.1892 -136.996932)
		(width 0.14224)
		(layer "In2.Cu")
		(net "M_F_CS_N<4>")
	)
	(segment
		(start 269.0114 -131.1148)
		(end 269.091664 -131.195064)
		(width 0.14224)
		(layer "In2.Cu")
		(net "M_F_CS_N<4>")
	)
	(segment
		(start 263.8552 -103.078534)
		(end 263.8552 -123.08967)
		(width 0.14224)
		(layer "In2.Cu")
		(net "M_F_CS_N<4>")
	)
	(segment
		(start 269.113 -139.5476)
		(end 269.113 -140.512546)
		(width 0.14224)
		(layer "In2.Cu")
		(net "M_F_CS_N<4>")
	)
	(segment
		(start 269.091664 -143.251936)
		(end 269.091664 -144.403064)
		(width 0.14224)
		(layer "In2.Cu")
		(net "M_F_CS_N<4>")
	)
	(segment
		(start 269.065756 -140.55979)
		(end 269.065756 -143.226028)
		(width 0.14224)
		(layer "In2.Cu")
		(net "M_F_CS_N<4>")
	)
	(segment
		(start 262.660384 -99.594416)
		(end 262.660384 -100.34016)
		(width 0.0889)
		(layer "In2.Cu")
		(net "M_F_CS_N<4>")
	)
	(segment
		(start 269.091664 -144.403064)
		(end 269.151862 -144.463262)
		(width 0.14224)
		(layer "In2.Cu")
		(net "M_F_CS_N<4>")
	)
	(segment
		(start 269.087854 -139.522454)
		(end 269.113 -139.5476)
		(width 0.14224)
		(layer "In2.Cu")
		(net "M_F_CS_N<4>")
	)
	(segment
		(start 263.8552 -123.08967)
		(end 266.5222 -125.75667)
		(width 0.14224)
		(layer "In2.Cu")
		(net "M_F_CS_N<4>")
	)
	(segment
		(start 269.091664 -131.195064)
		(end 269.091664 -134.776464)
		(width 0.14224)
		(layer "In2.Cu")
		(net "M_F_CS_N<4>")
	)
	(segment
		(start 270.350234 -149.992334)
		(end 270.350234 -150.788878)
		(width 0.14224)
		(layer "In2.Cu")
		(net "M_F_CS_N<4>")
	)
	(segment
		(start 262.6614 -99.5934)
		(end 262.660384 -99.594416)
		(width 0.0889)
		(layer "In2.Cu")
		(net "M_F_CS_N<4>")
	)
	(segment
		(start 262.690102 -92.586302)
		(end 262.690102 -93.16339)
		(width 0.0889)
		(layer "In2.Cu")
		(net "M_F_CS_N<4>")
	)
	(segment
		(start 269.065756 -143.226028)
		(end 269.091664 -143.251936)
		(width 0.14224)
		(layer "In2.Cu")
		(net "M_F_CS_N<4>")
	)
	(segment
		(start 269.087854 -138.607546)
		(end 269.087854 -139.522454)
		(width 0.14224)
		(layer "In2.Cu")
		(net "M_F_CS_N<4>")
	)
	(segment
		(start 262.7376 -98.386138)
		(end 262.74395 -98.396806)
		(width 0.0889)
		(layer "In2.Cu")
		(net "M_F_CS_N<4>")
	)
	(segment
		(start 269.084552 -145.793968)
		(end 269.084552 -147.24126)
		(width 0.14224)
		(layer "In2.Cu")
		(net "M_F_CS_N<4>")
	)
	(segment
		(start 262.7376 -97.395538)
		(end 262.74395 -97.406206)
		(width 0.0889)
		(layer "In2.Cu")
		(net "M_F_CS_N<4>")
	)
	(segment
		(start 269.927578 -148.084286)
		(end 269.927578 -149.569678)
		(width 0.14224)
		(layer "In2.Cu")
		(net "M_F_CS_N<4>")
	)
	(segment
		(start 269.0114 -130.6576)
		(end 269.0114 -131.1148)
		(width 0.14224)
		(layer "In2.Cu")
		(net "M_F_CS_N<4>")
	)
	(arc
		(start 262.74395 -95.425006)
		(mid 262.816748 -95.715769)
		(end 262.7376 -96.004888)
		(width 0.0889)
		(layer "In2.Cu")
		(net "M_F_CS_N<4>")
	)
	(arc
		(start 262.7376 -98.976688)
		(mid 262.636832 -99.277303)
		(end 262.6614 -99.5934)
		(width 0.0889)
		(layer "In2.Cu")
		(net "M_F_CS_N<4>")
	)
	(arc
		(start 262.7376 -93.433138)
		(mid 262.816822 -93.722256)
		(end 262.74395 -94.01302)
		(width 0.0889)
		(layer "In2.Cu")
		(net "M_F_CS_N<4>")
	)
	(arc
		(start 262.7376 -96.995488)
		(mid 262.68413 -97.190551)
		(end 262.732774 -97.386902)
		(width 0.0889)
		(layer "In2.Cu")
		(net "M_F_CS_N<4>")
	)
	(arc
		(start 262.7376 -94.023688)
		(mid 262.684101 -94.223586)
		(end 262.7376 -94.423484)
		(width 0.0889)
		(layer "In2.Cu")
		(net "M_F_CS_N<4>")
	)
	(arc
		(start 262.74395 -97.406206)
		(mid 262.816748 -97.696969)
		(end 262.7376 -97.986088)
		(width 0.0889)
		(layer "In2.Cu")
		(net "M_F_CS_N<4>")
	)
	(arc
		(start 262.690102 -93.16339)
		(mid 262.68925 -93.297571)
		(end 262.732774 -93.424502)
		(width 0.0889)
		(layer "In2.Cu")
		(net "M_F_CS_N<4>")
	)
	(arc
		(start 262.7376 -95.014288)
		(mid 262.68413 -95.209351)
		(end 262.732774 -95.405702)
		(width 0.0889)
		(layer "In2.Cu")
		(net "M_F_CS_N<4>")
	)
	(arc
		(start 262.74395 -96.415606)
		(mid 262.816748 -96.706369)
		(end 262.7376 -96.995488)
		(width 0.0889)
		(layer "In2.Cu")
		(net "M_F_CS_N<4>")
	)
	(arc
		(start 262.7376 -97.986088)
		(mid 262.68413 -98.181151)
		(end 262.732774 -98.377502)
		(width 0.0889)
		(layer "In2.Cu")
		(net "M_F_CS_N<4>")
	)
	(arc
		(start 262.7376 -94.423484)
		(mid 262.816731 -94.718886)
		(end 262.7376 -95.014288)
		(width 0.0889)
		(layer "In2.Cu")
		(net "M_F_CS_N<4>")
	)
	(arc
		(start 262.7376 -96.004888)
		(mid 262.68413 -96.199951)
		(end 262.732774 -96.396302)
		(width 0.0889)
		(layer "In2.Cu")
		(net "M_F_CS_N<4>")
	)
	(arc
		(start 262.74395 -98.396806)
		(mid 262.816748 -98.687569)
		(end 262.7376 -98.976688)
		(width 0.0889)
		(layer "In2.Cu")
		(net "M_F_CS_N<4>")
	)
	(segment
		(start 267.089636 -92.24264)
		(end 266.518136 -92.24264)
		(width 0.1016)
		(layer "F.Cu")
		(net "M_F_CS_N<3>")
	)
	(segment
		(start 277.999952 -154.905456)
		(end 277.999952 -156.87294)
		(width 0.1651)
		(layer "F.Cu")
		(net "M_F_CS_N<3>")
	)
	(segment
		(start 277.999952 -156.87294)
		(end 278.00046 -156.87294)
		(width 0.1651)
		(layer "F.Cu")
		(net "M_F_CS_N<3>")
	)
	(via
		(at 266.518136 -92.24264)
		(size 0.508)
		(drill 0.254)
		(layers "F.Cu" "B.Cu")
		(net "M_F_CS_N<3>")
	)
	(via
		(at 277.999952 -154.905456)
		(size 0.508)
		(drill 0.254)
		(layers "F.Cu" "B.Cu")
		(net "M_F_CS_N<3>")
	)
	(segment
		(start 278.33701 -144.36979)
		(end 278.33701 -144.98701)
		(width 0.14224)
		(layer "In2.Cu")
		(net "M_F_CS_N<3>")
	)
	(segment
		(start 268.859 -96.3168)
		(end 269.2146 -96.6724)
		(width 0.14224)
		(layer "In2.Cu")
		(net "M_F_CS_N<3>")
	)
	(segment
		(start 278.2316 -149.225)
		(end 278.2316 -149.606)
		(width 0.14224)
		(layer "In2.Cu")
		(net "M_F_CS_N<3>")
	)
	(segment
		(start 278.407622 -131.472178)
		(end 278.407622 -135.456422)
		(width 0.14224)
		(layer "In2.Cu")
		(net "M_F_CS_N<3>")
	)
	(segment
		(start 278.473154 -128.765554)
		(end 278.473154 -129.806446)
		(width 0.14224)
		(layer "In2.Cu")
		(net "M_F_CS_N<3>")
	)
	(segment
		(start 278.4856 -149.86)
		(end 278.4856 -153.0604)
		(width 0.14224)
		(layer "In2.Cu")
		(net "M_F_CS_N<3>")
	)
	(segment
		(start 269.873222 -96.950022)
		(end 269.873222 -102.985062)
		(width 0.14224)
		(layer "In2.Cu")
		(net "M_F_CS_N<3>")
	)
	(segment
		(start 278.5618 -153.1366)
		(end 278.5618 -153.6954)
		(width 0.14224)
		(layer "In2.Cu")
		(net "M_F_CS_N<3>")
	)
	(segment
		(start 266.8143 -92.8497)
		(end 267.208 -93.2434)
		(width 0.14224)
		(layer "In2.Cu")
		(net "M_F_CS_N<3>")
	)
	(segment
		(start 267.208 -93.2434)
		(end 267.6652 -93.2434)
		(width 0.14224)
		(layer "In2.Cu")
		(net "M_F_CS_N<3>")
	)
	(segment
		(start 267.6652 -93.2434)
		(end 268.859 -94.4372)
		(width 0.14224)
		(layer "In2.Cu")
		(net "M_F_CS_N<3>")
	)
	(segment
		(start 269.873222 -102.985062)
		(end 269.494 -103.364284)
		(width 0.14224)
		(layer "In2.Cu")
		(net "M_F_CS_N<3>")
	)
	(segment
		(start 278.41194 -144.29486)
		(end 278.33701 -144.36979)
		(width 0.14224)
		(layer "In2.Cu")
		(net "M_F_CS_N<3>")
	)
	(segment
		(start 278.275796 -130.003804)
		(end 278.275796 -130.498596)
		(width 0.14224)
		(layer "In2.Cu")
		(net "M_F_CS_N<3>")
	)
	(segment
		(start 278.407622 -135.456422)
		(end 278.4602 -135.509)
		(width 0.14224)
		(layer "In2.Cu")
		(net "M_F_CS_N<3>")
	)
	(segment
		(start 266.8143 -92.538804)
		(end 266.8143 -92.8497)
		(width 0.14224)
		(layer "In2.Cu")
		(net "M_F_CS_N<3>")
	)
	(segment
		(start 278.2316 -149.606)
		(end 278.4856 -149.86)
		(width 0.14224)
		(layer "In2.Cu")
		(net "M_F_CS_N<3>")
	)
	(segment
		(start 277.999952 -154.257248)
		(end 277.999952 -154.905456)
		(width 0.14224)
		(layer "In2.Cu")
		(net "M_F_CS_N<3>")
	)
	(segment
		(start 278.4856 -153.0604)
		(end 278.5618 -153.1366)
		(width 0.14224)
		(layer "In2.Cu")
		(net "M_F_CS_N<3>")
	)
	(segment
		(start 278.4602 -135.509)
		(end 278.4602 -139.3698)
		(width 0.14224)
		(layer "In2.Cu")
		(net "M_F_CS_N<3>")
	)
	(segment
		(start 278.413972 -145.063972)
		(end 278.413972 -146.384772)
		(width 0.14224)
		(layer "In2.Cu")
		(net "M_F_CS_N<3>")
	)
	(segment
		(start 266.518136 -92.24264)
		(end 266.8143 -92.538804)
		(width 0.14224)
		(layer "In2.Cu")
		(net "M_F_CS_N<3>")
	)
	(segment
		(start 268.859 -94.4372)
		(end 268.859 -96.3168)
		(width 0.14224)
		(layer "In2.Cu")
		(net "M_F_CS_N<3>")
	)
	(segment
		(start 278.5618 -153.6954)
		(end 277.999952 -154.257248)
		(width 0.14224)
		(layer "In2.Cu")
		(net "M_F_CS_N<3>")
	)
	(segment
		(start 278.33701 -144.98701)
		(end 278.413972 -145.063972)
		(width 0.14224)
		(layer "In2.Cu")
		(net "M_F_CS_N<3>")
	)
	(segment
		(start 278.511 -130.7338)
		(end 278.511 -131.3688)
		(width 0.14224)
		(layer "In2.Cu")
		(net "M_F_CS_N<3>")
	)
	(segment
		(start 278.41194 -139.41806)
		(end 278.41194 -144.29486)
		(width 0.14224)
		(layer "In2.Cu")
		(net "M_F_CS_N<3>")
	)
	(segment
		(start 269.2146 -96.6724)
		(end 269.5956 -96.6724)
		(width 0.14224)
		(layer "In2.Cu")
		(net "M_F_CS_N<3>")
	)
	(segment
		(start 278.473154 -129.806446)
		(end 278.275796 -130.003804)
		(width 0.14224)
		(layer "In2.Cu")
		(net "M_F_CS_N<3>")
	)
	(segment
		(start 269.494 -103.364284)
		(end 269.494 -119.7864)
		(width 0.14224)
		(layer "In2.Cu")
		(net "M_F_CS_N<3>")
	)
	(segment
		(start 269.494 -119.7864)
		(end 278.473154 -128.765554)
		(width 0.14224)
		(layer "In2.Cu")
		(net "M_F_CS_N<3>")
	)
	(segment
		(start 278.275796 -130.498596)
		(end 278.511 -130.7338)
		(width 0.14224)
		(layer "In2.Cu")
		(net "M_F_CS_N<3>")
	)
	(segment
		(start 278.511 -131.3688)
		(end 278.407622 -131.472178)
		(width 0.14224)
		(layer "In2.Cu")
		(net "M_F_CS_N<3>")
	)
	(segment
		(start 278.413972 -146.384772)
		(end 278.473662 -146.444462)
		(width 0.14224)
		(layer "In2.Cu")
		(net "M_F_CS_N<3>")
	)
	(segment
		(start 278.4602 -139.3698)
		(end 278.41194 -139.41806)
		(width 0.14224)
		(layer "In2.Cu")
		(net "M_F_CS_N<3>")
	)
	(segment
		(start 278.473662 -146.444462)
		(end 278.473662 -148.982938)
		(width 0.14224)
		(layer "In2.Cu")
		(net "M_F_CS_N<3>")
	)
	(segment
		(start 278.473662 -148.982938)
		(end 278.2316 -149.225)
		(width 0.14224)
		(layer "In2.Cu")
		(net "M_F_CS_N<3>")
	)
	(segment
		(start 269.5956 -96.6724)
		(end 269.873222 -96.950022)
		(width 0.14224)
		(layer "In2.Cu")
		(net "M_F_CS_N<3>")
	)
	(segment
		(start 267.089636 -93.23324)
		(end 266.518136 -93.23324)
		(width 0.1016)
		(layer "F.Cu")
		(net "M_F_CS_N<2>")
	)
	(segment
		(start 278.00046 -152.273)
		(end 277.999952 -152.278842)
		(width 0.1651)
		(layer "F.Cu")
		(net "M_F_CS_N<2>")
	)
	(segment
		(start 277.999952 -152.278842)
		(end 277.999952 -153.571956)
		(width 0.1651)
		(layer "F.Cu")
		(net "M_F_CS_N<2>")
	)
	(via
		(at 277.999952 -153.571956)
		(size 0.508)
		(drill 0.254)
		(layers "F.Cu" "B.Cu")
		(net "M_F_CS_N<2>")
	)
	(via
		(at 266.518136 -93.23324)
		(size 0.508)
		(drill 0.254)
		(layers "F.Cu" "B.Cu")
		(net "M_F_CS_N<2>")
	)
	(segment
		(start 275.864828 -133.786372)
		(end 275.864828 -134.564628)
		(width 0.14224)
		(layer "In2.Cu")
		(net "M_F_CS_N<2>")
	)
	(segment
		(start 275.86178 -145.68678)
		(end 275.876258 -145.701258)
		(width 0.14224)
		(layer "In2.Cu")
		(net "M_F_CS_N<2>")
	)
	(segment
		(start 275.970746 -131.419346)
		(end 275.970746 -133.680454)
		(width 0.14224)
		(layer "In2.Cu")
		(net "M_F_CS_N<2>")
	)
	(segment
		(start 275.864828 -134.564628)
		(end 275.883624 -134.583424)
		(width 0.14224)
		(layer "In2.Cu")
		(net "M_F_CS_N<2>")
	)
	(segment
		(start 266.9032 -96.8756)
		(end 267.8684 -97.8408)
		(width 0.14224)
		(layer "In2.Cu")
		(net "M_F_CS_N<2>")
	)
	(segment
		(start 266.9032 -96.52)
		(end 266.9032 -96.8756)
		(width 0.14224)
		(layer "In2.Cu")
		(net "M_F_CS_N<2>")
	)
	(segment
		(start 267.716 -102.362)
		(end 267.97 -102.616)
		(width 0.14224)
		(layer "In2.Cu")
		(net "M_F_CS_N<2>")
	)
	(segment
		(start 275.970746 -133.680454)
		(end 275.864828 -133.786372)
		(width 0.14224)
		(layer "In2.Cu")
		(net "M_F_CS_N<2>")
	)
	(segment
		(start 266.9032 -94.8944)
		(end 267.0302 -95.0214)
		(width 0.14224)
		(layer "In2.Cu")
		(net "M_F_CS_N<2>")
	)
	(segment
		(start 266.9032 -95.9104)
		(end 267.0048 -96.012)
		(width 0.14224)
		(layer "In2.Cu")
		(net "M_F_CS_N<2>")
	)
	(segment
		(start 277.185882 -149.584918)
		(end 277.185882 -150.185882)
		(width 0.14224)
		(layer "In2.Cu")
		(net "M_F_CS_N<2>")
	)
	(segment
		(start 266.9032 -93.9038)
		(end 267.0556 -94.0562)
		(width 0.14224)
		(layer "In2.Cu")
		(net "M_F_CS_N<2>")
	)
	(segment
		(start 271.624806 -125.092206)
		(end 275.8186 -129.286)
		(width 0.14224)
		(layer "In2.Cu")
		(net "M_F_CS_N<2>")
	)
	(segment
		(start 277.185882 -150.185882)
		(end 277.585678 -150.585678)
		(width 0.14224)
		(layer "In2.Cu")
		(net "M_F_CS_N<2>")
	)
	(segment
		(start 267.0048 -96.4184)
		(end 266.9032 -96.52)
		(width 0.14224)
		(layer "In2.Cu")
		(net "M_F_CS_N<2>")
	)
	(segment
		(start 275.909532 -130.011932)
		(end 275.909532 -130.515868)
		(width 0.14224)
		(layer "In2.Cu")
		(net "M_F_CS_N<2>")
	)
	(segment
		(start 267.0302 -95.0214)
		(end 267.0302 -95.4024)
		(width 0.14224)
		(layer "In2.Cu")
		(net "M_F_CS_N<2>")
	)
	(segment
		(start 267.0302 -95.4024)
		(end 266.9032 -95.5294)
		(width 0.14224)
		(layer "In2.Cu")
		(net "M_F_CS_N<2>")
	)
	(segment
		(start 275.848318 -130.577082)
		(end 275.848318 -131.296918)
		(width 0.14224)
		(layer "In2.Cu")
		(net "M_F_CS_N<2>")
	)
	(segment
		(start 267.0048 -96.012)
		(end 267.0048 -96.4184)
		(width 0.14224)
		(layer "In2.Cu")
		(net "M_F_CS_N<2>")
	)
	(segment
		(start 275.8186 -129.921)
		(end 275.909532 -130.011932)
		(width 0.14224)
		(layer "In2.Cu")
		(net "M_F_CS_N<2>")
	)
	(segment
		(start 267.8684 -97.8408)
		(end 267.8684 -101.854)
		(width 0.14224)
		(layer "In2.Cu")
		(net "M_F_CS_N<2>")
	)
	(segment
		(start 275.876258 -145.701258)
		(end 275.876258 -146.437858)
		(width 0.14224)
		(layer "In2.Cu")
		(net "M_F_CS_N<2>")
	)
	(segment
		(start 275.883624 -134.583424)
		(end 275.883624 -141.971776)
		(width 0.14224)
		(layer "In2.Cu")
		(net "M_F_CS_N<2>")
	)
	(segment
		(start 277.585678 -150.585678)
		(end 277.585678 -153.157682)
		(width 0.14224)
		(layer "In2.Cu")
		(net "M_F_CS_N<2>")
	)
	(segment
		(start 267.8684 -101.854)
		(end 267.716 -102.0064)
		(width 0.14224)
		(layer "In2.Cu")
		(net "M_F_CS_N<2>")
	)
	(segment
		(start 275.876258 -146.437858)
		(end 276.715982 -147.277582)
		(width 0.14224)
		(layer "In2.Cu")
		(net "M_F_CS_N<2>")
	)
	(segment
		(start 267.0556 -94.0562)
		(end 267.0556 -94.3864)
		(width 0.14224)
		(layer "In2.Cu")
		(net "M_F_CS_N<2>")
	)
	(segment
		(start 267.97 -120.418098)
		(end 271.624806 -124.072904)
		(width 0.14224)
		(layer "In2.Cu")
		(net "M_F_CS_N<2>")
	)
	(segment
		(start 266.9032 -93.618304)
		(end 266.9032 -93.9038)
		(width 0.14224)
		(layer "In2.Cu")
		(net "M_F_CS_N<2>")
	)
	(segment
		(start 276.715982 -147.277582)
		(end 276.715982 -149.115018)
		(width 0.14224)
		(layer "In2.Cu")
		(net "M_F_CS_N<2>")
	)
	(segment
		(start 277.585678 -153.157682)
		(end 277.999952 -153.571956)
		(width 0.14224)
		(layer "In2.Cu")
		(net "M_F_CS_N<2>")
	)
	(segment
		(start 266.9032 -94.5388)
		(end 266.9032 -94.8944)
		(width 0.14224)
		(layer "In2.Cu")
		(net "M_F_CS_N<2>")
	)
	(segment
		(start 267.0556 -94.3864)
		(end 266.9032 -94.5388)
		(width 0.14224)
		(layer "In2.Cu")
		(net "M_F_CS_N<2>")
	)
	(segment
		(start 267.716 -102.0064)
		(end 267.716 -102.362)
		(width 0.14224)
		(layer "In2.Cu")
		(net "M_F_CS_N<2>")
	)
	(segment
		(start 275.86178 -141.99362)
		(end 275.86178 -145.68678)
		(width 0.14224)
		(layer "In2.Cu")
		(net "M_F_CS_N<2>")
	)
	(segment
		(start 275.883624 -141.971776)
		(end 275.86178 -141.99362)
		(width 0.14224)
		(layer "In2.Cu")
		(net "M_F_CS_N<2>")
	)
	(segment
		(start 266.518136 -93.23324)
		(end 266.9032 -93.618304)
		(width 0.14224)
		(layer "In2.Cu")
		(net "M_F_CS_N<2>")
	)
	(segment
		(start 276.715982 -149.115018)
		(end 277.185882 -149.584918)
		(width 0.14224)
		(layer "In2.Cu")
		(net "M_F_CS_N<2>")
	)
	(segment
		(start 271.624806 -124.072904)
		(end 271.624806 -125.092206)
		(width 0.14224)
		(layer "In2.Cu")
		(net "M_F_CS_N<2>")
	)
	(segment
		(start 275.8186 -129.286)
		(end 275.8186 -129.921)
		(width 0.14224)
		(layer "In2.Cu")
		(net "M_F_CS_N<2>")
	)
	(segment
		(start 275.909532 -130.515868)
		(end 275.848318 -130.577082)
		(width 0.14224)
		(layer "In2.Cu")
		(net "M_F_CS_N<2>")
	)
	(segment
		(start 275.848318 -131.296918)
		(end 275.970746 -131.419346)
		(width 0.14224)
		(layer "In2.Cu")
		(net "M_F_CS_N<2>")
	)
	(segment
		(start 267.97 -102.616)
		(end 267.97 -120.418098)
		(width 0.14224)
		(layer "In2.Cu")
		(net "M_F_CS_N<2>")
	)
	(segment
		(start 266.9032 -95.5294)
		(end 266.9032 -95.9104)
		(width 0.14224)
		(layer "In2.Cu")
		(net "M_F_CS_N<2>")
	)
	(segment
		(start 274.600416 -152.273)
		(end 274.599908 -152.278842)
		(width 0.1651)
		(layer "F.Cu")
		(net "M_F_CS_N<1>")
	)
	(segment
		(start 274.599908 -152.278842)
		(end 274.599908 -153.542746)
		(width 0.1651)
		(layer "F.Cu")
		(net "M_F_CS_N<1>")
	)
	(segment
		(start 264.51433 -91.747086)
		(end 263.94283 -91.747086)
		(width 0.1016)
		(layer "F.Cu")
		(net "M_F_CS_N<1>")
	)
	(via
		(at 263.94283 -91.747086)
		(size 0.508)
		(drill 0.254)
		(layers "F.Cu" "B.Cu")
		(net "M_F_CS_N<1>")
	)
	(via
		(at 274.599908 -153.542746)
		(size 0.508)
		(drill 0.254)
		(layers "F.Cu" "B.Cu")
		(net "M_F_CS_N<1>")
	)
	(segment
		(start 264.45464 -95.414338)
		(end 264.46353 -95.429578)
		(width 0.0889)
		(layer "In2.Cu")
		(net "M_F_CS_N<1>")
	)
	(segment
		(start 272.3896 -129.8194)
		(end 272.52295 -129.95275)
		(width 0.14224)
		(layer "In2.Cu")
		(net "M_F_CS_N<1>")
	)
	(segment
		(start 264.45464 -98.976942)
		(end 264.446512 -98.991166)
		(width 0.0889)
		(layer "In2.Cu")
		(net "M_F_CS_N<1>")
	)
	(segment
		(start 265.3792 -100.210112)
		(end 265.3792 -102.438454)
		(width 0.0889)
		(layer "In2.Cu")
		(net "M_F_CS_N<1>")
	)
	(segment
		(start 273.338544 -149.742144)
		(end 274.189444 -150.593044)
		(width 0.14224)
		(layer "In2.Cu")
		(net "M_F_CS_N<1>")
	)
	(segment
		(start 263.94283 -91.747086)
		(end 264.438384 -92.413836)
		(width 0.0889)
		(layer "In2.Cu")
		(net "M_F_CS_N<1>")
	)
	(segment
		(start 272.451068 -130.646932)
		(end 272.451068 -131.303268)
		(width 0.14224)
		(layer "In2.Cu")
		(net "M_F_CS_N<1>")
	)
	(segment
		(start 272.457926 -133.738874)
		(end 272.457926 -134.739126)
		(width 0.14224)
		(layer "In2.Cu")
		(net "M_F_CS_N<1>")
	)
	(segment
		(start 272.465292 -134.746492)
		(end 272.465292 -139.470892)
		(width 0.14224)
		(layer "In2.Cu")
		(net "M_F_CS_N<1>")
	)
	(segment
		(start 272.457926 -134.739126)
		(end 272.465292 -134.746492)
		(width 0.14224)
		(layer "In2.Cu")
		(net "M_F_CS_N<1>")
	)
	(segment
		(start 274.189444 -153.132282)
		(end 274.599908 -153.542746)
		(width 0.14224)
		(layer "In2.Cu")
		(net "M_F_CS_N<1>")
	)
	(segment
		(start 265.9126 -102.971854)
		(end 265.9126 -103.334566)
		(width 0.0889)
		(layer "In2.Cu")
		(net "M_F_CS_N<1>")
	)
	(segment
		(start 272.6182 -133.5786)
		(end 272.457926 -133.738874)
		(width 0.14224)
		(layer "In2.Cu")
		(net "M_F_CS_N<1>")
	)
	(segment
		(start 264.45464 -94.423484)
		(end 264.46099 -94.434152)
		(width 0.0889)
		(layer "In2.Cu")
		(net "M_F_CS_N<1>")
	)
	(segment
		(start 264.844276 -99.675188)
		(end 265.3792 -100.210112)
		(width 0.0889)
		(layer "In2.Cu")
		(net "M_F_CS_N<1>")
	)
	(segment
		(start 272.457926 -144.340326)
		(end 272.461736 -144.344136)
		(width 0.14224)
		(layer "In2.Cu")
		(net "M_F_CS_N<1>")
	)
	(segment
		(start 272.480278 -143.495522)
		(end 272.457926 -143.517874)
		(width 0.14224)
		(layer "In2.Cu")
		(net "M_F_CS_N<1>")
	)
	(segment
		(start 272.6182 -131.4704)
		(end 272.6182 -133.5786)
		(width 0.14224)
		(layer "In2.Cu")
		(net "M_F_CS_N<1>")
	)
	(segment
		(start 264.45464 -98.386138)
		(end 264.46353 -98.401378)
		(width 0.0889)
		(layer "In2.Cu")
		(net "M_F_CS_N<1>")
	)
	(segment
		(start 272.52295 -129.95275)
		(end 272.52295 -130.57505)
		(width 0.14224)
		(layer "In2.Cu")
		(net "M_F_CS_N<1>")
	)
	(segment
		(start 272.461736 -144.344136)
		(end 272.461736 -146.655536)
		(width 0.14224)
		(layer "In2.Cu")
		(net "M_F_CS_N<1>")
	)
	(segment
		(start 272.457926 -143.517874)
		(end 272.457926 -144.340326)
		(width 0.14224)
		(layer "In2.Cu")
		(net "M_F_CS_N<1>")
	)
	(segment
		(start 264.45464 -97.395538)
		(end 264.46353 -97.410778)
		(width 0.0889)
		(layer "In2.Cu")
		(net "M_F_CS_N<1>")
	)
	(segment
		(start 272.480278 -139.485878)
		(end 272.480278 -143.495522)
		(width 0.14224)
		(layer "In2.Cu")
		(net "M_F_CS_N<1>")
	)
	(segment
		(start 274.189444 -150.593044)
		(end 274.189444 -153.132282)
		(width 0.14224)
		(layer "In2.Cu")
		(net "M_F_CS_N<1>")
	)
	(segment
		(start 272.52295 -130.57505)
		(end 272.451068 -130.646932)
		(width 0.14224)
		(layer "In2.Cu")
		(net "M_F_CS_N<1>")
	)
	(segment
		(start 265.3792 -102.438454)
		(end 265.9126 -102.971854)
		(width 0.0889)
		(layer "In2.Cu")
		(net "M_F_CS_N<1>")
	)
	(segment
		(start 272.461736 -146.655536)
		(end 273.338544 -147.532344)
		(width 0.14224)
		(layer "In2.Cu")
		(net "M_F_CS_N<1>")
	)
	(segment
		(start 264.46099 -94.01302)
		(end 264.45464 -94.023688)
		(width 0.0889)
		(layer "In2.Cu")
		(net "M_F_CS_N<1>")
	)
	(segment
		(start 273.338544 -147.532344)
		(end 273.338544 -149.742144)
		(width 0.14224)
		(layer "In2.Cu")
		(net "M_F_CS_N<1>")
	)
	(segment
		(start 272.3896 -128.749806)
		(end 272.3896 -129.8194)
		(width 0.14224)
		(layer "In2.Cu")
		(net "M_F_CS_N<1>")
	)
	(segment
		(start 264.45464 -96.404938)
		(end 264.46353 -96.420178)
		(width 0.0889)
		(layer "In2.Cu")
		(net "M_F_CS_N<1>")
	)
	(segment
		(start 272.465292 -139.470892)
		(end 272.480278 -139.485878)
		(width 0.14224)
		(layer "In2.Cu")
		(net "M_F_CS_N<1>")
	)
	(segment
		(start 272.451068 -131.303268)
		(end 272.6182 -131.4704)
		(width 0.14224)
		(layer "In2.Cu")
		(net "M_F_CS_N<1>")
	)
	(segment
		(start 265.9126 -122.272806)
		(end 272.3896 -128.749806)
		(width 0.14224)
		(layer "In2.Cu")
		(net "M_F_CS_N<1>")
	)
	(segment
		(start 264.438384 -92.413836)
		(end 264.46353 -92.457778)
		(width 0.0889)
		(layer "In2.Cu")
		(net "M_F_CS_N<1>")
	)
	(segment
		(start 265.9126 -103.334566)
		(end 265.9126 -122.272806)
		(width 0.14224)
		(layer "In2.Cu")
		(net "M_F_CS_N<1>")
	)
	(arc
		(start 264.446512 -98.991166)
		(mid 264.400925 -99.185079)
		(end 264.454386 -99.376992)
		(width 0.0889)
		(layer "In2.Cu")
		(net "M_F_CS_N<1>")
	)
	(arc
		(start 264.454386 -99.376992)
		(mid 264.619537 -99.56505)
		(end 264.844276 -99.675188)
		(width 0.0889)
		(layer "In2.Cu")
		(net "M_F_CS_N<1>")
	)
	(arc
		(start 264.45464 -96.995742)
		(mid 264.401107 -97.19564)
		(end 264.45464 -97.395538)
		(width 0.0889)
		(layer "In2.Cu")
		(net "M_F_CS_N<1>")
	)
	(arc
		(start 264.45464 -97.986342)
		(mid 264.401107 -98.18624)
		(end 264.45464 -98.386138)
		(width 0.0889)
		(layer "In2.Cu")
		(net "M_F_CS_N<1>")
	)
	(arc
		(start 264.45464 -94.023688)
		(mid 264.401107 -94.223586)
		(end 264.45464 -94.423484)
		(width 0.0889)
		(layer "In2.Cu")
		(net "M_F_CS_N<1>")
	)
	(arc
		(start 264.46353 -96.420178)
		(mid 264.533927 -96.709129)
		(end 264.45464 -96.995742)
		(width 0.0889)
		(layer "In2.Cu")
		(net "M_F_CS_N<1>")
	)
	(arc
		(start 264.45464 -96.005142)
		(mid 264.401107 -96.20504)
		(end 264.45464 -96.404938)
		(width 0.0889)
		(layer "In2.Cu")
		(net "M_F_CS_N<1>")
	)
	(arc
		(start 264.46353 -95.429578)
		(mid 264.533927 -95.718529)
		(end 264.45464 -96.005142)
		(width 0.0889)
		(layer "In2.Cu")
		(net "M_F_CS_N<1>")
	)
	(arc
		(start 264.46353 -92.457778)
		(mid 264.533927 -92.746729)
		(end 264.45464 -93.033342)
		(width 0.0889)
		(layer "In2.Cu")
		(net "M_F_CS_N<1>")
	)
	(arc
		(start 264.45464 -95.014542)
		(mid 264.401107 -95.21444)
		(end 264.45464 -95.414338)
		(width 0.0889)
		(layer "In2.Cu")
		(net "M_F_CS_N<1>")
	)
	(arc
		(start 264.45464 -93.433138)
		(mid 264.533862 -93.722256)
		(end 264.46099 -94.01302)
		(width 0.0889)
		(layer "In2.Cu")
		(net "M_F_CS_N<1>")
	)
	(arc
		(start 264.45464 -93.033342)
		(mid 264.401107 -93.23324)
		(end 264.45464 -93.433138)
		(width 0.0889)
		(layer "In2.Cu")
		(net "M_F_CS_N<1>")
	)
	(arc
		(start 264.46099 -94.434152)
		(mid 264.53391 -94.725169)
		(end 264.45464 -95.014542)
		(width 0.0889)
		(layer "In2.Cu")
		(net "M_F_CS_N<1>")
	)
	(arc
		(start 264.46353 -97.410778)
		(mid 264.533927 -97.699729)
		(end 264.45464 -97.986342)
		(width 0.0889)
		(layer "In2.Cu")
		(net "M_F_CS_N<1>")
	)
	(arc
		(start 264.46353 -98.401378)
		(mid 264.533927 -98.690329)
		(end 264.45464 -98.976942)
		(width 0.0889)
		(layer "In2.Cu")
		(net "M_F_CS_N<1>")
	)
	(segment
		(start 270.350488 -152.273)
		(end 270.34998 -152.278842)
		(width 0.1651)
		(layer "F.Cu")
		(net "M_F_CS_N<0>")
	)
	(segment
		(start 270.34998 -154.251914)
		(end 270.349726 -154.252168)
		(width 0.1651)
		(layer "F.Cu")
		(net "M_F_CS_N<0>")
	)
	(segment
		(start 270.34998 -152.278842)
		(end 270.34998 -154.251914)
		(width 0.1651)
		(layer "F.Cu")
		(net "M_F_CS_N<0>")
	)
	(segment
		(start 262.79729 -93.72854)
		(end 262.22579 -93.72854)
		(width 0.1016)
		(layer "F.Cu")
		(net "M_F_CS_N<0>")
	)
	(via
		(at 270.349726 -154.252168)
		(size 0.508)
		(drill 0.254)
		(layers "F.Cu" "B.Cu")
		(net "M_F_CS_N<0>")
	)
	(via
		(at 262.22579 -93.72854)
		(size 0.508)
		(drill 0.254)
		(layers "F.Cu" "B.Cu")
		(net "M_F_CS_N<0>")
	)
	(segment
		(start 266.0142 -127.1016)
		(end 268.254988 -129.342388)
		(width 0.14224)
		(layer "In2.Cu")
		(net "M_F_CS_N<0>")
	)
	(segment
		(start 268.218666 -140.177266)
		(end 268.218666 -141.752066)
		(width 0.14224)
		(layer "In2.Cu")
		(net "M_F_CS_N<0>")
	)
	(segment
		(start 268.212062 -141.75867)
		(end 268.212062 -144.945862)
		(width 0.14224)
		(layer "In2.Cu")
		(net "M_F_CS_N<0>")
	)
	(segment
		(start 262.55599 -94.49054)
		(end 262.577326 -94.527624)
		(width 0.0889)
		(layer "In2.Cu")
		(net "M_F_CS_N<0>")
	)
	(segment
		(start 270.129 -151.426164)
		(end 270.129 -154.031442)
		(width 0.14224)
		(layer "In2.Cu")
		(net "M_F_CS_N<0>")
	)
	(segment
		(start 262.5725 -96.500188)
		(end 262.577326 -96.508824)
		(width 0.0889)
		(layer "In2.Cu")
		(net "M_F_CS_N<0>")
	)
	(segment
		(start 269.938754 -151.235918)
		(end 270.129 -151.426164)
		(width 0.14224)
		(layer "In2.Cu")
		(net "M_F_CS_N<0>")
	)
	(segment
		(start 262.56615 -98.47072)
		(end 262.5725 -98.481388)
		(width 0.0889)
		(layer "In2.Cu")
		(net "M_F_CS_N<0>")
	)
	(segment
		(start 263.3472 -101.565456)
		(end 263.3472 -102.9208)
		(width 0.0889)
		(layer "In2.Cu")
		(net "M_F_CS_N<0>")
	)
	(segment
		(start 269.938754 -150.423118)
		(end 269.938754 -151.235918)
		(width 0.14224)
		(layer "In2.Cu")
		(net "M_F_CS_N<0>")
	)
	(segment
		(start 268.211046 -133.692646)
		(end 268.211046 -135.394446)
		(width 0.14224)
		(layer "In2.Cu")
		(net "M_F_CS_N<0>")
	)
	(segment
		(start 268.218666 -141.752066)
		(end 268.212062 -141.75867)
		(width 0.14224)
		(layer "In2.Cu")
		(net "M_F_CS_N<0>")
	)
	(segment
		(start 268.0716 -131.4196)
		(end 268.0716 -133.5532)
		(width 0.14224)
		(layer "In2.Cu")
		(net "M_F_CS_N<0>")
	)
	(segment
		(start 269.087854 -148.076158)
		(end 269.087854 -149.572218)
		(width 0.14224)
		(layer "In2.Cu")
		(net "M_F_CS_N<0>")
	)
	(segment
		(start 269.087854 -149.572218)
		(end 269.938754 -150.423118)
		(width 0.14224)
		(layer "In2.Cu")
		(net "M_F_CS_N<0>")
	)
	(segment
		(start 262.56615 -97.48012)
		(end 262.5725 -97.490788)
		(width 0.0889)
		(layer "In2.Cu")
		(net "M_F_CS_N<0>")
	)
	(segment
		(start 262.5725 -98.481388)
		(end 262.577326 -98.490024)
		(width 0.0889)
		(layer "In2.Cu")
		(net "M_F_CS_N<0>")
	)
	(segment
		(start 262.5725 -97.490788)
		(end 262.577326 -97.499424)
		(width 0.0889)
		(layer "In2.Cu")
		(net "M_F_CS_N<0>")
	)
	(segment
		(start 264.950702 -125.191266)
		(end 264.664952 -125.477016)
		(width 0.14224)
		(layer "In2.Cu")
		(net "M_F_CS_N<0>")
	)
	(segment
		(start 262.383524 -99.544124)
		(end 262.383524 -100.60178)
		(width 0.0889)
		(layer "In2.Cu")
		(net "M_F_CS_N<0>")
	)
	(segment
		(start 265.806174 -125.765814)
		(end 266.0142 -125.97384)
		(width 0.14224)
		(layer "In2.Cu")
		(net "M_F_CS_N<0>")
	)
	(segment
		(start 264.950702 -124.903738)
		(end 264.950702 -125.191266)
		(width 0.14224)
		(layer "In2.Cu")
		(net "M_F_CS_N<0>")
	)
	(segment
		(start 265.21156 -126.080012)
		(end 265.525758 -125.765814)
		(width 0.14224)
		(layer "In2.Cu")
		(net "M_F_CS_N<0>")
	)
	(segment
		(start 268.214856 -144.948656)
		(end 268.214856 -147.20316)
		(width 0.14224)
		(layer "In2.Cu")
		(net "M_F_CS_N<0>")
	)
	(segment
		(start 268.163294 -130.083306)
		(end 268.163294 -130.520694)
		(width 0.14224)
		(layer "In2.Cu")
		(net "M_F_CS_N<0>")
	)
	(segment
		(start 262.383524 -100.60178)
		(end 263.3472 -101.565456)
		(width 0.0889)
		(layer "In2.Cu")
		(net "M_F_CS_N<0>")
	)
	(segment
		(start 262.56615 -95.49892)
		(end 262.5725 -95.509588)
		(width 0.0889)
		(layer "In2.Cu")
		(net "M_F_CS_N<0>")
	)
	(segment
		(start 268.212062 -144.945862)
		(end 268.214856 -144.948656)
		(width 0.14224)
		(layer "In2.Cu")
		(net "M_F_CS_N<0>")
	)
	(segment
		(start 268.24813 -131.24307)
		(end 268.0716 -131.4196)
		(width 0.14224)
		(layer "In2.Cu")
		(net "M_F_CS_N<0>")
	)
	(segment
		(start 268.214856 -147.20316)
		(end 269.087854 -148.076158)
		(width 0.14224)
		(layer "In2.Cu")
		(net "M_F_CS_N<0>")
	)
	(segment
		(start 262.5725 -95.509588)
		(end 262.577326 -95.518224)
		(width 0.0889)
		(layer "In2.Cu")
		(net "M_F_CS_N<0>")
	)
	(segment
		(start 268.214602 -140.173202)
		(end 268.218666 -140.177266)
		(width 0.14224)
		(layer "In2.Cu")
		(net "M_F_CS_N<0>")
	)
	(segment
		(start 262.382 -99.5426)
		(end 262.383524 -99.544124)
		(width 0.0889)
		(layer "In2.Cu")
		(net "M_F_CS_N<0>")
	)
	(segment
		(start 268.24813 -130.60553)
		(end 268.24813 -131.24307)
		(width 0.14224)
		(layer "In2.Cu")
		(net "M_F_CS_N<0>")
	)
	(segment
		(start 264.664952 -125.477016)
		(end 264.664952 -125.767592)
		(width 0.14224)
		(layer "In2.Cu")
		(net "M_F_CS_N<0>")
	)
	(segment
		(start 264.664952 -125.767592)
		(end 264.977372 -126.080012)
		(width 0.14224)
		(layer "In2.Cu")
		(net "M_F_CS_N<0>")
	)
	(segment
		(start 270.129 -154.031442)
		(end 270.349726 -154.252168)
		(width 0.14224)
		(layer "In2.Cu")
		(net "M_F_CS_N<0>")
	)
	(segment
		(start 262.22579 -93.72854)
		(end 262.55599 -94.49054)
		(width 0.0889)
		(layer "In2.Cu")
		(net "M_F_CS_N<0>")
	)
	(segment
		(start 266.0142 -125.97384)
		(end 266.0142 -127.1016)
		(width 0.14224)
		(layer "In2.Cu")
		(net "M_F_CS_N<0>")
	)
	(segment
		(start 263.3472 -102.9208)
		(end 263.3472 -123.300236)
		(width 0.14224)
		(layer "In2.Cu")
		(net "M_F_CS_N<0>")
	)
	(segment
		(start 268.214602 -135.398002)
		(end 268.214602 -140.173202)
		(width 0.14224)
		(layer "In2.Cu")
		(net "M_F_CS_N<0>")
	)
	(segment
		(start 263.3472 -123.300236)
		(end 264.950702 -124.903738)
		(width 0.14224)
		(layer "In2.Cu")
		(net "M_F_CS_N<0>")
	)
	(segment
		(start 265.525758 -125.765814)
		(end 265.806174 -125.765814)
		(width 0.14224)
		(layer "In2.Cu")
		(net "M_F_CS_N<0>")
	)
	(segment
		(start 262.56615 -96.48952)
		(end 262.5725 -96.500188)
		(width 0.0889)
		(layer "In2.Cu")
		(net "M_F_CS_N<0>")
	)
	(segment
		(start 268.211046 -135.394446)
		(end 268.214602 -135.398002)
		(width 0.14224)
		(layer "In2.Cu")
		(net "M_F_CS_N<0>")
	)
	(segment
		(start 268.0716 -133.5532)
		(end 268.211046 -133.692646)
		(width 0.14224)
		(layer "In2.Cu")
		(net "M_F_CS_N<0>")
	)
	(segment
		(start 268.254988 -129.342388)
		(end 268.254988 -129.991612)
		(width 0.14224)
		(layer "In2.Cu")
		(net "M_F_CS_N<0>")
	)
	(segment
		(start 264.977372 -126.080012)
		(end 265.21156 -126.080012)
		(width 0.14224)
		(layer "In2.Cu")
		(net "M_F_CS_N<0>")
	)
	(segment
		(start 268.254988 -129.991612)
		(end 268.163294 -130.083306)
		(width 0.14224)
		(layer "In2.Cu")
		(net "M_F_CS_N<0>")
	)
	(segment
		(start 268.163294 -130.520694)
		(end 268.24813 -130.60553)
		(width 0.14224)
		(layer "In2.Cu")
		(net "M_F_CS_N<0>")
	)
	(arc
		(start 262.5725 -98.881438)
		(mid 262.436953 -99.200411)
		(end 262.382 -99.5426)
		(width 0.0889)
		(layer "In2.Cu")
		(net "M_F_CS_N<0>")
	)
	(arc
		(start 262.577326 -95.518224)
		(mid 262.626081 -95.714576)
		(end 262.5725 -95.909638)
		(width 0.0889)
		(layer "In2.Cu")
		(net "M_F_CS_N<0>")
	)
	(arc
		(start 262.577326 -96.508824)
		(mid 262.626081 -96.705176)
		(end 262.5725 -96.900238)
		(width 0.0889)
		(layer "In2.Cu")
		(net "M_F_CS_N<0>")
	)
	(arc
		(start 262.577326 -97.499424)
		(mid 262.626081 -97.695776)
		(end 262.5725 -97.890838)
		(width 0.0889)
		(layer "In2.Cu")
		(net "M_F_CS_N<0>")
	)
	(arc
		(start 262.577326 -94.527624)
		(mid 262.626081 -94.723976)
		(end 262.5725 -94.919038)
		(width 0.0889)
		(layer "In2.Cu")
		(net "M_F_CS_N<0>")
	)
	(arc
		(start 262.5725 -96.900238)
		(mid 262.493278 -97.189356)
		(end 262.56615 -97.48012)
		(width 0.0889)
		(layer "In2.Cu")
		(net "M_F_CS_N<0>")
	)
	(arc
		(start 262.5725 -95.909638)
		(mid 262.493278 -96.198756)
		(end 262.56615 -96.48952)
		(width 0.0889)
		(layer "In2.Cu")
		(net "M_F_CS_N<0>")
	)
	(arc
		(start 262.577326 -98.490024)
		(mid 262.626081 -98.686376)
		(end 262.5725 -98.881438)
		(width 0.0889)
		(layer "In2.Cu")
		(net "M_F_CS_N<0>")
	)
	(arc
		(start 262.5725 -97.890838)
		(mid 262.493278 -98.179956)
		(end 262.56615 -98.47072)
		(width 0.0889)
		(layer "In2.Cu")
		(net "M_F_CS_N<0>")
	)
	(arc
		(start 262.5725 -94.919038)
		(mid 262.493278 -95.208156)
		(end 262.56615 -95.49892)
		(width 0.0889)
		(layer "In2.Cu")
		(net "M_F_CS_N<0>")
	)
	(segment
		(start 258.50469 -92.24264)
		(end 257.93319 -92.24264)
		(width 0.1016)
		(layer "F.Cu")
		(net "M_F_CLK_DP<3>")
	)
	(via
		(at 256.826004 -148.771356)
		(size 0.508)
		(drill 0.254)
		(layers "F.Cu" "B.Cu")
		(net "M_F_CLK_DP<3>")
	)
	(via
		(at 257.93319 -92.24264)
		(size 0.508)
		(drill 0.254)
		(layers "F.Cu" "B.Cu")
		(net "M_F_CLK_DP<3>")
	)
	(segment
		(start 256.749804 -147.478496)
		(end 256.750312 -147.478496)
		(width 0.1651)
		(layer "B.Cu")
		(net "M_F_CLK_DP<3>")
	)
	(segment
		(start 256.826004 -148.771356)
		(end 256.749804 -148.695156)
		(width 0.1651)
		(layer "B.Cu")
		(net "M_F_CLK_DP<3>")
	)
	(segment
		(start 256.749804 -148.695156)
		(end 256.749804 -147.478496)
		(width 0.1651)
		(layer "B.Cu")
		(net "M_F_CLK_DP<3>")
	)
	(segment
		(start 258.45135 -96.48952)
		(end 258.445 -96.500188)
		(width 0.0889)
		(layer "In2.Cu")
		(net "M_F_CLK_DP<3>")
	)
	(segment
		(start 257.922014 -92.64269)
		(end 257.95478 -92.64269)
		(width 0.0889)
		(layer "In2.Cu")
		(net "M_F_CLK_DP<3>")
	)
	(segment
		(start 260.211062 -139.002008)
		(end 260.7056 -139.496546)
		(width 0.14224)
		(layer "In2.Cu")
		(net "M_F_CLK_DP<3>")
	)
	(segment
		(start 258.7244 -100.254054)
		(end 258.7244 -102.026974)
		(width 0.0889)
		(layer "In2.Cu")
		(net "M_F_CLK_DP<3>")
	)
	(segment
		(start 260.7056 -139.496546)
		(end 260.7056 -145.0594)
		(width 0.14224)
		(layer "In2.Cu")
		(net "M_F_CLK_DP<3>")
	)
	(segment
		(start 259.04952 -126.377954)
		(end 259.842 -127.170434)
		(width 0.14224)
		(layer "In2.Cu")
		(net "M_F_CLK_DP<3>")
	)
	(segment
		(start 258.7244 -102.026974)
		(end 258.76377 -102.066344)
		(width 0.0889)
		(layer "In2.Cu")
		(net "M_F_CLK_DP<3>")
	)
	(segment
		(start 259.049266 -103.491792)
		(end 259.04952 -103.492046)
		(width 0.14224)
		(layer "In2.Cu")
		(net "M_F_CLK_DP<3>")
	)
	(segment
		(start 260.7056 -145.0594)
		(end 260.2738 -145.4912)
		(width 0.14224)
		(layer "In2.Cu")
		(net "M_F_CLK_DP<3>")
	)
	(segment
		(start 258.76377 -102.088442)
		(end 258.76377 -103.206804)
		(width 0.14224)
		(layer "In2.Cu")
		(net "M_F_CLK_DP<3>")
	)
	(segment
		(start 257.027172 -148.972524)
		(end 256.826004 -148.771356)
		(width 0.14224)
		(layer "In2.Cu")
		(net "M_F_CLK_DP<3>")
	)
	(segment
		(start 258.397502 -99.554284)
		(end 258.388612 -99.563174)
		(width 0.0889)
		(layer "In2.Cu")
		(net "M_F_CLK_DP<3>")
	)
	(segment
		(start 258.445 -97.490788)
		(end 258.440174 -97.499424)
		(width 0.0889)
		(layer "In2.Cu")
		(net "M_F_CLK_DP<3>")
	)
	(segment
		(start 257.640074 -92.073476)
		(end 257.561334 -92.094812)
		(width 0.0889)
		(layer "In2.Cu")
		(net "M_F_CLK_DP<3>")
	)
	(segment
		(start 259.048758 -103.491792)
		(end 259.049266 -103.491792)
		(width 0.14224)
		(layer "In2.Cu")
		(net "M_F_CLK_DP<3>")
	)
	(segment
		(start 258.445 -99.472242)
		(end 258.397502 -99.554284)
		(width 0.0889)
		(layer "In2.Cu")
		(net "M_F_CLK_DP<3>")
	)
	(segment
		(start 258.76377 -103.206804)
		(end 259.048758 -103.491792)
		(width 0.14224)
		(layer "In2.Cu")
		(net "M_F_CLK_DP<3>")
	)
	(segment
		(start 260.2738 -149.318726)
		(end 259.615686 -149.97684)
		(width 0.14224)
		(layer "In2.Cu")
		(net "M_F_CLK_DP<3>")
	)
	(segment
		(start 259.615686 -149.97684)
		(end 257.49504 -149.97684)
		(width 0.14224)
		(layer "In2.Cu")
		(net "M_F_CLK_DP<3>")
	)
	(segment
		(start 258.45135 -97.48012)
		(end 258.445 -97.490788)
		(width 0.0889)
		(layer "In2.Cu")
		(net "M_F_CLK_DP<3>")
	)
	(segment
		(start 257.027172 -149.508972)
		(end 257.027172 -148.972524)
		(width 0.14224)
		(layer "In2.Cu")
		(net "M_F_CLK_DP<3>")
	)
	(segment
		(start 259.842 -132.87248)
		(end 260.211062 -133.241542)
		(width 0.14224)
		(layer "In2.Cu")
		(net "M_F_CLK_DP<3>")
	)
	(segment
		(start 260.2738 -145.4912)
		(end 260.2738 -149.318726)
		(width 0.14224)
		(layer "In2.Cu")
		(net "M_F_CLK_DP<3>")
	)
	(segment
		(start 258.445 -93.928438)
		(end 258.45135 -93.939106)
		(width 0.0889)
		(layer "In2.Cu")
		(net "M_F_CLK_DP<3>")
	)
	(segment
		(start 257.49504 -149.97684)
		(end 257.027172 -149.508972)
		(width 0.14224)
		(layer "In2.Cu")
		(net "M_F_CLK_DP<3>")
	)
	(segment
		(start 258.445 -98.481388)
		(end 258.440174 -98.490024)
		(width 0.0889)
		(layer "In2.Cu")
		(net "M_F_CLK_DP<3>")
	)
	(segment
		(start 258.445 -94.518988)
		(end 258.440174 -94.527624)
		(width 0.0889)
		(layer "In2.Cu")
		(net "M_F_CLK_DP<3>")
	)
	(segment
		(start 257.93319 -92.24264)
		(end 257.640074 -92.073476)
		(width 0.0889)
		(layer "In2.Cu")
		(net "M_F_CLK_DP<3>")
	)
	(segment
		(start 258.388612 -99.918266)
		(end 258.7244 -100.254054)
		(width 0.0889)
		(layer "In2.Cu")
		(net "M_F_CLK_DP<3>")
	)
	(segment
		(start 258.388612 -99.563174)
		(end 258.388612 -99.918266)
		(width 0.0889)
		(layer "In2.Cu")
		(net "M_F_CLK_DP<3>")
	)
	(segment
		(start 258.76377 -102.066344)
		(end 258.76377 -102.088442)
		(width 0.0889)
		(layer "In2.Cu")
		(net "M_F_CLK_DP<3>")
	)
	(segment
		(start 258.445 -95.509588)
		(end 258.440174 -95.518224)
		(width 0.0889)
		(layer "In2.Cu")
		(net "M_F_CLK_DP<3>")
	)
	(segment
		(start 259.04952 -103.492046)
		(end 259.04952 -126.377954)
		(width 0.14224)
		(layer "In2.Cu")
		(net "M_F_CLK_DP<3>")
	)
	(segment
		(start 259.842 -127.170434)
		(end 259.842 -132.87248)
		(width 0.14224)
		(layer "In2.Cu")
		(net "M_F_CLK_DP<3>")
	)
	(segment
		(start 258.45135 -95.49892)
		(end 258.445 -95.509588)
		(width 0.0889)
		(layer "In2.Cu")
		(net "M_F_CLK_DP<3>")
	)
	(segment
		(start 258.45135 -98.47072)
		(end 258.445 -98.481388)
		(width 0.0889)
		(layer "In2.Cu")
		(net "M_F_CLK_DP<3>")
	)
	(segment
		(start 258.445 -96.500188)
		(end 258.440174 -96.508824)
		(width 0.0889)
		(layer "In2.Cu")
		(net "M_F_CLK_DP<3>")
	)
	(segment
		(start 260.211062 -133.241542)
		(end 260.211062 -139.002008)
		(width 0.14224)
		(layer "In2.Cu")
		(net "M_F_CLK_DP<3>")
	)
	(arc
		(start 258.445 -96.900238)
		(mid 258.524222 -97.189356)
		(end 258.45135 -97.48012)
		(width 0.0889)
		(layer "In2.Cu")
		(net "M_F_CLK_DP<3>")
	)
	(arc
		(start 258.445 -94.919038)
		(mid 258.524222 -95.208156)
		(end 258.45135 -95.49892)
		(width 0.0889)
		(layer "In2.Cu")
		(net "M_F_CLK_DP<3>")
	)
	(arc
		(start 257.561334 -92.094812)
		(mid 257.598961 -92.462688)
		(end 257.922014 -92.64269)
		(width 0.0889)
		(layer "In2.Cu")
		(net "M_F_CLK_DP<3>")
	)
	(arc
		(start 258.440174 -95.518224)
		(mid 258.391419 -95.714576)
		(end 258.445 -95.909638)
		(width 0.0889)
		(layer "In2.Cu")
		(net "M_F_CLK_DP<3>")
	)
	(arc
		(start 258.45135 -93.939106)
		(mid 258.524148 -94.229869)
		(end 258.445 -94.518988)
		(width 0.0889)
		(layer "In2.Cu")
		(net "M_F_CLK_DP<3>")
	)
	(arc
		(start 258.440174 -96.508824)
		(mid 258.391419 -96.705176)
		(end 258.445 -96.900238)
		(width 0.0889)
		(layer "In2.Cu")
		(net "M_F_CLK_DP<3>")
	)
	(arc
		(start 257.95478 -92.64269)
		(mid 258.450257 -92.947133)
		(end 258.445 -93.528642)
		(width 0.0889)
		(layer "In2.Cu")
		(net "M_F_CLK_DP<3>")
	)
	(arc
		(start 258.445 -98.881438)
		(mid 258.524131 -99.17684)
		(end 258.445 -99.472242)
		(width 0.0889)
		(layer "In2.Cu")
		(net "M_F_CLK_DP<3>")
	)
	(arc
		(start 258.445 -95.909638)
		(mid 258.524222 -96.198756)
		(end 258.45135 -96.48952)
		(width 0.0889)
		(layer "In2.Cu")
		(net "M_F_CLK_DP<3>")
	)
	(arc
		(start 258.440174 -98.490024)
		(mid 258.391419 -98.686376)
		(end 258.445 -98.881438)
		(width 0.0889)
		(layer "In2.Cu")
		(net "M_F_CLK_DP<3>")
	)
	(arc
		(start 258.440174 -97.499424)
		(mid 258.391419 -97.695776)
		(end 258.445 -97.890838)
		(width 0.0889)
		(layer "In2.Cu")
		(net "M_F_CLK_DP<3>")
	)
	(arc
		(start 258.445 -93.528642)
		(mid 258.391501 -93.72854)
		(end 258.445 -93.928438)
		(width 0.0889)
		(layer "In2.Cu")
		(net "M_F_CLK_DP<3>")
	)
	(arc
		(start 258.440174 -94.527624)
		(mid 258.391419 -94.723976)
		(end 258.445 -94.919038)
		(width 0.0889)
		(layer "In2.Cu")
		(net "M_F_CLK_DP<3>")
	)
	(arc
		(start 258.445 -97.890838)
		(mid 258.524222 -98.179956)
		(end 258.45135 -98.47072)
		(width 0.0889)
		(layer "In2.Cu")
		(net "M_F_CLK_DP<3>")
	)
	(segment
		(start 256.749804 -155.509468)
		(end 256.749804 -156.87294)
		(width 0.1651)
		(layer "F.Cu")
		(net "M_F_CLK_DP<1>")
	)
	(segment
		(start 256.749804 -156.87294)
		(end 256.750312 -156.87294)
		(width 0.1651)
		(layer "F.Cu")
		(net "M_F_CLK_DP<1>")
	)
	(segment
		(start 259.65023 -92.24264)
		(end 260.22173 -92.24264)
		(width 0.1016)
		(layer "F.Cu")
		(net "M_F_CLK_DP<1>")
	)
	(via
		(at 256.749804 -155.509468)
		(size 0.508)
		(drill 0.254)
		(layers "F.Cu" "B.Cu")
		(net "M_F_CLK_DP<1>")
	)
	(via
		(at 259.65023 -92.24264)
		(size 0.508)
		(drill 0.254)
		(layers "F.Cu" "B.Cu")
		(net "M_F_CLK_DP<1>")
	)
	(segment
		(start 260.4389 -101.968046)
		(end 260.47192 -102.001066)
		(width 0.0889)
		(layer "In2.Cu")
		(net "M_F_CLK_DP<1>")
	)
	(segment
		(start 262.2042 -142.1384)
		(end 262.288782 -142.222982)
		(width 0.14224)
		(layer "In2.Cu")
		(net "M_F_CLK_DP<1>")
	)
	(segment
		(start 259.357114 -92.073476)
		(end 259.278374 -92.094812)
		(width 0.0889)
		(layer "In2.Cu")
		(net "M_F_CLK_DP<1>")
	)
	(segment
		(start 261.943342 -126.756414)
		(end 261.943342 -129.197862)
		(width 0.14224)
		(layer "In2.Cu")
		(net "M_F_CLK_DP<1>")
	)
	(segment
		(start 260.1087 -99.568)
		(end 260.1087 -99.9109)
		(width 0.0889)
		(layer "In2.Cu")
		(net "M_F_CLK_DP<1>")
	)
	(segment
		(start 260.77672 -125.589792)
		(end 261.943342 -126.756414)
		(width 0.14224)
		(layer "In2.Cu")
		(net "M_F_CLK_DP<1>")
	)
	(segment
		(start 260.16204 -94.518988)
		(end 260.157214 -94.527624)
		(width 0.0889)
		(layer "In2.Cu")
		(net "M_F_CLK_DP<1>")
	)
	(segment
		(start 260.1087 -99.9109)
		(end 260.4389 -100.2411)
		(width 0.0889)
		(layer "In2.Cu")
		(net "M_F_CLK_DP<1>")
	)
	(segment
		(start 260.4389 -100.2411)
		(end 260.4389 -101.968046)
		(width 0.0889)
		(layer "In2.Cu")
		(net "M_F_CLK_DP<1>")
	)
	(segment
		(start 260.16204 -98.481388)
		(end 260.157214 -98.490024)
		(width 0.0889)
		(layer "In2.Cu")
		(net "M_F_CLK_DP<1>")
	)
	(segment
		(start 260.16204 -95.509588)
		(end 260.157214 -95.518224)
		(width 0.0889)
		(layer "In2.Cu")
		(net "M_F_CLK_DP<1>")
	)
	(segment
		(start 257.00228 -155.761944)
		(end 256.749804 -155.509468)
		(width 0.14224)
		(layer "In2.Cu")
		(net "M_F_CLK_DP<1>")
	)
	(segment
		(start 257.436112 -156.728668)
		(end 257.00228 -156.294836)
		(width 0.14224)
		(layer "In2.Cu")
		(net "M_F_CLK_DP<1>")
	)
	(segment
		(start 260.47192 -102.526592)
		(end 260.77672 -102.831392)
		(width 0.14224)
		(layer "In2.Cu")
		(net "M_F_CLK_DP<1>")
	)
	(segment
		(start 260.16839 -99.461066)
		(end 260.1087 -99.568)
		(width 0.0889)
		(layer "In2.Cu")
		(net "M_F_CLK_DP<1>")
	)
	(segment
		(start 260.47192 -102.001066)
		(end 260.47192 -102.526592)
		(width 0.14224)
		(layer "In2.Cu")
		(net "M_F_CLK_DP<1>")
	)
	(segment
		(start 260.16839 -98.47072)
		(end 260.16204 -98.481388)
		(width 0.0889)
		(layer "In2.Cu")
		(net "M_F_CLK_DP<1>")
	)
	(segment
		(start 262.288782 -142.222982)
		(end 262.288782 -154.236166)
		(width 0.14224)
		(layer "In2.Cu")
		(net "M_F_CLK_DP<1>")
	)
	(segment
		(start 261.943342 -129.197862)
		(end 262.316214 -129.570734)
		(width 0.14224)
		(layer "In2.Cu")
		(net "M_F_CLK_DP<1>")
	)
	(segment
		(start 260.16204 -93.928438)
		(end 260.16839 -93.939106)
		(width 0.0889)
		(layer "In2.Cu")
		(net "M_F_CLK_DP<1>")
	)
	(segment
		(start 259.639054 -92.64269)
		(end 259.67182 -92.64269)
		(width 0.0889)
		(layer "In2.Cu")
		(net "M_F_CLK_DP<1>")
	)
	(segment
		(start 262.288782 -154.236166)
		(end 259.79628 -156.728668)
		(width 0.14224)
		(layer "In2.Cu")
		(net "M_F_CLK_DP<1>")
	)
	(segment
		(start 260.16204 -97.490788)
		(end 260.157214 -97.499424)
		(width 0.0889)
		(layer "In2.Cu")
		(net "M_F_CLK_DP<1>")
	)
	(segment
		(start 259.79628 -156.728668)
		(end 257.436112 -156.728668)
		(width 0.14224)
		(layer "In2.Cu")
		(net "M_F_CLK_DP<1>")
	)
	(segment
		(start 260.16839 -96.48952)
		(end 260.16204 -96.500188)
		(width 0.0889)
		(layer "In2.Cu")
		(net "M_F_CLK_DP<1>")
	)
	(segment
		(start 262.2042 -140.71092)
		(end 262.2042 -142.1384)
		(width 0.14224)
		(layer "In2.Cu")
		(net "M_F_CLK_DP<1>")
	)
	(segment
		(start 262.316214 -129.570734)
		(end 262.316214 -140.598906)
		(width 0.14224)
		(layer "In2.Cu")
		(net "M_F_CLK_DP<1>")
	)
	(segment
		(start 262.316214 -140.598906)
		(end 262.2042 -140.71092)
		(width 0.14224)
		(layer "In2.Cu")
		(net "M_F_CLK_DP<1>")
	)
	(segment
		(start 260.16839 -97.48012)
		(end 260.16204 -97.490788)
		(width 0.0889)
		(layer "In2.Cu")
		(net "M_F_CLK_DP<1>")
	)
	(segment
		(start 257.00228 -156.294836)
		(end 257.00228 -155.761944)
		(width 0.14224)
		(layer "In2.Cu")
		(net "M_F_CLK_DP<1>")
	)
	(segment
		(start 260.16839 -95.49892)
		(end 260.16204 -95.509588)
		(width 0.0889)
		(layer "In2.Cu")
		(net "M_F_CLK_DP<1>")
	)
	(segment
		(start 260.16204 -98.881438)
		(end 260.162294 -98.881692)
		(width 0.0889)
		(layer "In2.Cu")
		(net "M_F_CLK_DP<1>")
	)
	(segment
		(start 260.16204 -96.500188)
		(end 260.157214 -96.508824)
		(width 0.0889)
		(layer "In2.Cu")
		(net "M_F_CLK_DP<1>")
	)
	(segment
		(start 260.77672 -102.831392)
		(end 260.77672 -125.589792)
		(width 0.14224)
		(layer "In2.Cu")
		(net "M_F_CLK_DP<1>")
	)
	(segment
		(start 259.65023 -92.24264)
		(end 259.357114 -92.073476)
		(width 0.0889)
		(layer "In2.Cu")
		(net "M_F_CLK_DP<1>")
	)
	(arc
		(start 260.157214 -95.518224)
		(mid 260.108459 -95.714576)
		(end 260.16204 -95.909638)
		(width 0.0889)
		(layer "In2.Cu")
		(net "M_F_CLK_DP<1>")
	)
	(arc
		(start 260.16204 -96.900238)
		(mid 260.241262 -97.189356)
		(end 260.16839 -97.48012)
		(width 0.0889)
		(layer "In2.Cu")
		(net "M_F_CLK_DP<1>")
	)
	(arc
		(start 260.16204 -95.909638)
		(mid 260.241262 -96.198756)
		(end 260.16839 -96.48952)
		(width 0.0889)
		(layer "In2.Cu")
		(net "M_F_CLK_DP<1>")
	)
	(arc
		(start 259.25018 -92.231464)
		(mid 259.359449 -92.517615)
		(end 259.639054 -92.64269)
		(width 0.0889)
		(layer "In2.Cu")
		(net "M_F_CLK_DP<1>")
	)
	(arc
		(start 259.278374 -92.094812)
		(mid 259.258255 -92.161897)
		(end 259.25018 -92.231464)
		(width 0.0889)
		(layer "In2.Cu")
		(net "M_F_CLK_DP<1>")
	)
	(arc
		(start 260.16839 -93.939106)
		(mid 260.241188 -94.229869)
		(end 260.16204 -94.518988)
		(width 0.0889)
		(layer "In2.Cu")
		(net "M_F_CLK_DP<1>")
	)
	(arc
		(start 259.67182 -92.64269)
		(mid 260.167297 -92.947133)
		(end 260.16204 -93.528642)
		(width 0.0889)
		(layer "In2.Cu")
		(net "M_F_CLK_DP<1>")
	)
	(arc
		(start 260.16204 -94.919038)
		(mid 260.241262 -95.208156)
		(end 260.16839 -95.49892)
		(width 0.0889)
		(layer "In2.Cu")
		(net "M_F_CLK_DP<1>")
	)
	(arc
		(start 260.16204 -97.890838)
		(mid 260.241262 -98.179956)
		(end 260.16839 -98.47072)
		(width 0.0889)
		(layer "In2.Cu")
		(net "M_F_CLK_DP<1>")
	)
	(arc
		(start 260.162294 -98.881692)
		(mid 260.241231 -99.170586)
		(end 260.16839 -99.461066)
		(width 0.0889)
		(layer "In2.Cu")
		(net "M_F_CLK_DP<1>")
	)
	(arc
		(start 260.157214 -96.508824)
		(mid 260.108459 -96.705176)
		(end 260.16204 -96.900238)
		(width 0.0889)
		(layer "In2.Cu")
		(net "M_F_CLK_DP<1>")
	)
	(arc
		(start 260.16204 -93.528642)
		(mid 260.108541 -93.72854)
		(end 260.16204 -93.928438)
		(width 0.0889)
		(layer "In2.Cu")
		(net "M_F_CLK_DP<1>")
	)
	(arc
		(start 260.157214 -97.499424)
		(mid 260.108459 -97.695776)
		(end 260.16204 -97.890838)
		(width 0.0889)
		(layer "In2.Cu")
		(net "M_F_CLK_DP<1>")
	)
	(arc
		(start 260.157214 -98.490024)
		(mid 260.108459 -98.686376)
		(end 260.16204 -98.881438)
		(width 0.0889)
		(layer "In2.Cu")
		(net "M_F_CLK_DP<1>")
	)
	(arc
		(start 260.157214 -94.527624)
		(mid 260.108459 -94.723976)
		(end 260.16204 -94.919038)
		(width 0.0889)
		(layer "In2.Cu")
		(net "M_F_CLK_DP<1>")
	)
	(segment
		(start 258.50469 -93.23324)
		(end 257.93319 -93.23324)
		(width 0.1016)
		(layer "F.Cu")
		(net "M_F_CLK_DP<2>")
	)
	(via
		(at 257.93319 -93.23324)
		(size 0.508)
		(drill 0.254)
		(layers "F.Cu" "B.Cu")
		(net "M_F_CLK_DP<2>")
	)
	(via
		(at 256.939288 -150.785068)
		(size 0.508)
		(drill 0.254)
		(layers "F.Cu" "B.Cu")
		(net "M_F_CLK_DP<2>")
	)
	(segment
		(start 256.750312 -152.078436)
		(end 256.749804 -152.078182)
		(width 0.1651)
		(layer "B.Cu")
		(net "M_F_CLK_DP<2>")
	)
	(segment
		(start 256.749804 -150.974552)
		(end 256.939288 -150.785068)
		(width 0.1651)
		(layer "B.Cu")
		(net "M_F_CLK_DP<2>")
	)
	(segment
		(start 256.749804 -152.078182)
		(end 256.749804 -150.974552)
		(width 0.1651)
		(layer "B.Cu")
		(net "M_F_CLK_DP<2>")
	)
	(segment
		(start 257.6703 -99.535234)
		(end 257.6703 -100.2157)
		(width 0.0889)
		(layer "In2.Cu")
		(net "M_F_CLK_DP<2>")
	)
	(segment
		(start 259.25272 -143.306546)
		(end 259.366512 -143.420338)
		(width 0.14224)
		(layer "In2.Cu")
		(net "M_F_CLK_DP<2>")
	)
	(segment
		(start 259.366512 -135.258556)
		(end 259.25272 -135.372348)
		(width 0.14224)
		(layer "In2.Cu")
		(net "M_F_CLK_DP<2>")
	)
	(segment
		(start 259.25272 -146.063462)
		(end 258.642104 -146.674078)
		(width 0.14224)
		(layer "In2.Cu")
		(net "M_F_CLK_DP<2>")
	)
	(segment
		(start 256.392934 -151.551132)
		(end 256.519934 -151.678132)
		(width 0.14224)
		(layer "In2.Cu")
		(net "M_F_CLK_DP<2>")
	)
	(segment
		(start 258.9276 -133.32968)
		(end 259.25272 -133.6548)
		(width 0.14224)
		(layer "In2.Cu")
		(net "M_F_CLK_DP<2>")
	)
	(segment
		(start 257.874516 -100.419916)
		(end 257.874516 -101.89972)
		(width 0.0889)
		(layer "In2.Cu")
		(net "M_F_CLK_DP<2>")
	)
	(segment
		(start 259.041392 -131.129024)
		(end 259.041392 -131.593844)
		(width 0.14224)
		(layer "In2.Cu")
		(net "M_F_CLK_DP<2>")
	)
	(segment
		(start 259.25272 -138.84402)
		(end 259.25272 -139.30884)
		(width 0.14224)
		(layer "In2.Cu")
		(net "M_F_CLK_DP<2>")
	)
	(segment
		(start 259.25272 -145.142458)
		(end 259.25272 -146.063462)
		(width 0.14224)
		(layer "In2.Cu")
		(net "M_F_CLK_DP<2>")
	)
	(segment
		(start 259.25272 -144.477486)
		(end 259.352796 -144.577562)
		(width 0.14224)
		(layer "In2.Cu")
		(net "M_F_CLK_DP<2>")
	)
	(segment
		(start 259.25272 -136.529572)
		(end 259.25272 -136.994392)
		(width 0.14224)
		(layer "In2.Cu")
		(net "M_F_CLK_DP<2>")
	)
	(segment
		(start 257.907536 -101.93274)
		(end 257.907536 -101.954838)
		(width 0.0889)
		(layer "In2.Cu")
		(net "M_F_CLK_DP<2>")
	)
	(segment
		(start 257.576574 -99.359974)
		(end 257.598418 -99.398328)
		(width 0.0889)
		(layer "In2.Cu")
		(net "M_F_CLK_DP<2>")
	)
	(segment
		(start 259.25272 -135.837168)
		(end 259.366512 -135.95096)
		(width 0.14224)
		(layer "In2.Cu")
		(net "M_F_CLK_DP<2>")
	)
	(segment
		(start 258.9276 -129.889758)
		(end 259.014214 -129.976372)
		(width 0.14224)
		(layer "In2.Cu")
		(net "M_F_CLK_DP<2>")
	)
	(segment
		(start 259.7404 -141.8082)
		(end 259.25272 -142.29588)
		(width 0.14224)
		(layer "In2.Cu")
		(net "M_F_CLK_DP<2>")
	)
	(segment
		(start 257.907536 -103.543608)
		(end 258.21132 -103.847392)
		(width 0.14224)
		(layer "In2.Cu")
		(net "M_F_CLK_DP<2>")
	)
	(segment
		(start 257.59283 -94.01302)
		(end 257.58648 -94.023688)
		(width 0.0889)
		(layer "In2.Cu")
		(net "M_F_CLK_DP<2>")
	)
	(segment
		(start 258.9276 -131.015232)
		(end 259.041392 -131.129024)
		(width 0.14224)
		(layer "In2.Cu")
		(net "M_F_CLK_DP<2>")
	)
	(segment
		(start 257.581654 -96.396302)
		(end 257.58648 -96.404938)
		(width 0.0889)
		(layer "In2.Cu")
		(net "M_F_CLK_DP<2>")
	)
	(segment
		(start 256.84988 -151.678132)
		(end 257.22707 -151.300942)
		(width 0.14224)
		(layer "In2.Cu")
		(net "M_F_CLK_DP<2>")
	)
	(segment
		(start 259.366512 -138.265408)
		(end 259.366512 -138.730228)
		(width 0.14224)
		(layer "In2.Cu")
		(net "M_F_CLK_DP<2>")
	)
	(segment
		(start 259.352796 -144.577562)
		(end 259.352796 -145.042382)
		(width 0.14224)
		(layer "In2.Cu")
		(net "M_F_CLK_DP<2>")
	)
	(segment
		(start 257.907536 -101.954838)
		(end 257.907536 -103.543608)
		(width 0.14224)
		(layer "In2.Cu")
		(net "M_F_CLK_DP<2>")
	)
	(segment
		(start 259.366512 -136.41578)
		(end 259.25272 -136.529572)
		(width 0.14224)
		(layer "In2.Cu")
		(net "M_F_CLK_DP<2>")
	)
	(segment
		(start 259.366512 -137.108184)
		(end 259.366512 -137.573004)
		(width 0.14224)
		(layer "In2.Cu")
		(net "M_F_CLK_DP<2>")
	)
	(segment
		(start 259.366512 -135.95096)
		(end 259.366512 -136.41578)
		(width 0.14224)
		(layer "In2.Cu")
		(net "M_F_CLK_DP<2>")
	)
	(segment
		(start 257.581654 -97.386902)
		(end 257.597148 -97.41408)
		(width 0.0889)
		(layer "In2.Cu")
		(net "M_F_CLK_DP<2>")
	)
	(segment
		(start 258.21132 -126.758192)
		(end 258.9276 -127.474472)
		(width 0.14224)
		(layer "In2.Cu")
		(net "M_F_CLK_DP<2>")
	)
	(segment
		(start 256.81178 -147.617688)
		(end 256.392934 -148.036534)
		(width 0.14224)
		(layer "In2.Cu")
		(net "M_F_CLK_DP<2>")
	)
	(segment
		(start 257.581654 -95.405702)
		(end 257.58648 -95.414338)
		(width 0.0889)
		(layer "In2.Cu")
		(net "M_F_CLK_DP<2>")
	)
	(segment
		(start 259.25272 -139.30884)
		(end 259.7404 -139.79652)
		(width 0.14224)
		(layer "In2.Cu")
		(net "M_F_CLK_DP<2>")
	)
	(segment
		(start 259.041392 -132.286248)
		(end 259.041392 -132.751068)
		(width 0.14224)
		(layer "In2.Cu")
		(net "M_F_CLK_DP<2>")
	)
	(segment
		(start 259.366512 -134.793736)
		(end 259.366512 -135.258556)
		(width 0.14224)
		(layer "In2.Cu")
		(net "M_F_CLK_DP<2>")
	)
	(segment
		(start 259.25272 -133.6548)
		(end 259.25272 -134.679944)
		(width 0.14224)
		(layer "In2.Cu")
		(net "M_F_CLK_DP<2>")
	)
	(segment
		(start 258.642104 -146.674078)
		(end 258.642104 -146.785076)
		(width 0.14224)
		(layer "In2.Cu")
		(net "M_F_CLK_DP<2>")
	)
	(segment
		(start 256.519934 -151.678132)
		(end 256.84988 -151.678132)
		(width 0.14224)
		(layer "In2.Cu")
		(net "M_F_CLK_DP<2>")
	)
	(segment
		(start 257.22707 -151.07285)
		(end 256.939288 -150.785068)
		(width 0.14224)
		(layer "In2.Cu")
		(net "M_F_CLK_DP<2>")
	)
	(segment
		(start 258.9276 -127.474472)
		(end 258.9276 -129.889758)
		(width 0.14224)
		(layer "In2.Cu")
		(net "M_F_CLK_DP<2>")
	)
	(segment
		(start 259.041392 -132.751068)
		(end 258.9276 -132.86486)
		(width 0.14224)
		(layer "In2.Cu")
		(net "M_F_CLK_DP<2>")
	)
	(segment
		(start 258.9276 -130.527806)
		(end 258.9276 -131.015232)
		(width 0.14224)
		(layer "In2.Cu")
		(net "M_F_CLK_DP<2>")
	)
	(segment
		(start 257.6703 -100.2157)
		(end 257.874516 -100.419916)
		(width 0.0889)
		(layer "In2.Cu")
		(net "M_F_CLK_DP<2>")
	)
	(segment
		(start 259.7404 -139.79652)
		(end 259.7404 -141.8082)
		(width 0.14224)
		(layer "In2.Cu")
		(net "M_F_CLK_DP<2>")
	)
	(segment
		(start 259.25272 -135.372348)
		(end 259.25272 -135.837168)
		(width 0.14224)
		(layer "In2.Cu")
		(net "M_F_CLK_DP<2>")
	)
	(segment
		(start 259.25272 -143.99895)
		(end 259.25272 -144.477486)
		(width 0.14224)
		(layer "In2.Cu")
		(net "M_F_CLK_DP<2>")
	)
	(segment
		(start 259.366512 -143.420338)
		(end 259.366512 -143.885158)
		(width 0.14224)
		(layer "In2.Cu")
		(net "M_F_CLK_DP<2>")
	)
	(segment
		(start 258.9276 -132.86486)
		(end 258.9276 -133.32968)
		(width 0.14224)
		(layer "In2.Cu")
		(net "M_F_CLK_DP<2>")
	)
	(segment
		(start 257.874516 -101.89972)
		(end 257.907536 -101.93274)
		(width 0.0889)
		(layer "In2.Cu")
		(net "M_F_CLK_DP<2>")
	)
	(segment
		(start 256.392934 -148.036534)
		(end 256.392934 -151.551132)
		(width 0.14224)
		(layer "In2.Cu")
		(net "M_F_CLK_DP<2>")
	)
	(segment
		(start 257.576574 -98.36912)
		(end 257.600196 -98.410268)
		(width 0.0889)
		(layer "In2.Cu")
		(net "M_F_CLK_DP<2>")
	)
	(segment
		(start 259.041392 -131.593844)
		(end 258.9276 -131.707636)
		(width 0.14224)
		(layer "In2.Cu")
		(net "M_F_CLK_DP<2>")
	)
	(segment
		(start 259.25272 -136.994392)
		(end 259.366512 -137.108184)
		(width 0.14224)
		(layer "In2.Cu")
		(net "M_F_CLK_DP<2>")
	)
	(segment
		(start 257.698494 -147.617688)
		(end 256.81178 -147.617688)
		(width 0.14224)
		(layer "In2.Cu")
		(net "M_F_CLK_DP<2>")
	)
	(segment
		(start 258.642104 -146.785076)
		(end 258.313174 -147.114006)
		(width 0.14224)
		(layer "In2.Cu")
		(net "M_F_CLK_DP<2>")
	)
	(segment
		(start 258.9276 -132.172456)
		(end 259.041392 -132.286248)
		(width 0.14224)
		(layer "In2.Cu")
		(net "M_F_CLK_DP<2>")
	)
	(segment
		(start 257.58648 -95.414338)
		(end 257.59283 -95.425006)
		(width 0.0889)
		(layer "In2.Cu")
		(net "M_F_CLK_DP<2>")
	)
	(segment
		(start 257.598418 -99.398328)
		(end 257.6703 -99.535234)
		(width 0.0889)
		(layer "In2.Cu")
		(net "M_F_CLK_DP<2>")
	)
	(segment
		(start 258.9276 -131.707636)
		(end 258.9276 -132.172456)
		(width 0.14224)
		(layer "In2.Cu")
		(net "M_F_CLK_DP<2>")
	)
	(segment
		(start 259.25272 -134.679944)
		(end 259.366512 -134.793736)
		(width 0.14224)
		(layer "In2.Cu")
		(net "M_F_CLK_DP<2>")
	)
	(segment
		(start 259.25272 -137.686796)
		(end 259.25272 -138.151616)
		(width 0.14224)
		(layer "In2.Cu")
		(net "M_F_CLK_DP<2>")
	)
	(segment
		(start 259.352796 -145.042382)
		(end 259.25272 -145.142458)
		(width 0.14224)
		(layer "In2.Cu")
		(net "M_F_CLK_DP<2>")
	)
	(segment
		(start 259.014214 -129.976372)
		(end 259.014214 -130.441192)
		(width 0.14224)
		(layer "In2.Cu")
		(net "M_F_CLK_DP<2>")
	)
	(segment
		(start 259.25272 -142.29588)
		(end 259.25272 -143.306546)
		(width 0.14224)
		(layer "In2.Cu")
		(net "M_F_CLK_DP<2>")
	)
	(segment
		(start 258.21132 -103.847392)
		(end 258.21132 -126.758192)
		(width 0.14224)
		(layer "In2.Cu")
		(net "M_F_CLK_DP<2>")
	)
	(segment
		(start 257.93319 -93.23324)
		(end 257.82524 -93.34119)
		(width 0.0889)
		(layer "In2.Cu")
		(net "M_F_CLK_DP<2>")
	)
	(segment
		(start 257.58648 -96.404938)
		(end 257.59283 -96.415606)
		(width 0.0889)
		(layer "In2.Cu")
		(net "M_F_CLK_DP<2>")
	)
	(segment
		(start 259.25272 -138.151616)
		(end 259.366512 -138.265408)
		(width 0.14224)
		(layer "In2.Cu")
		(net "M_F_CLK_DP<2>")
	)
	(segment
		(start 259.366512 -143.885158)
		(end 259.25272 -143.99895)
		(width 0.14224)
		(layer "In2.Cu")
		(net "M_F_CLK_DP<2>")
	)
	(segment
		(start 259.366512 -137.573004)
		(end 259.25272 -137.686796)
		(width 0.14224)
		(layer "In2.Cu")
		(net "M_F_CLK_DP<2>")
	)
	(segment
		(start 258.202176 -147.114006)
		(end 257.698494 -147.617688)
		(width 0.14224)
		(layer "In2.Cu")
		(net "M_F_CLK_DP<2>")
	)
	(segment
		(start 257.22707 -151.300942)
		(end 257.22707 -151.07285)
		(width 0.14224)
		(layer "In2.Cu")
		(net "M_F_CLK_DP<2>")
	)
	(segment
		(start 259.366512 -138.730228)
		(end 259.25272 -138.84402)
		(width 0.14224)
		(layer "In2.Cu")
		(net "M_F_CLK_DP<2>")
	)
	(segment
		(start 259.014214 -130.441192)
		(end 258.9276 -130.527806)
		(width 0.14224)
		(layer "In2.Cu")
		(net "M_F_CLK_DP<2>")
	)
	(segment
		(start 258.313174 -147.114006)
		(end 258.202176 -147.114006)
		(width 0.14224)
		(layer "In2.Cu")
		(net "M_F_CLK_DP<2>")
	)
	(arc
		(start 257.58648 -94.423484)
		(mid 257.665611 -94.718886)
		(end 257.58648 -95.014288)
		(width 0.0889)
		(layer "In2.Cu")
		(net "M_F_CLK_DP<2>")
	)
	(arc
		(start 257.58648 -96.004888)
		(mid 257.53301 -96.199951)
		(end 257.581654 -96.396302)
		(width 0.0889)
		(layer "In2.Cu")
		(net "M_F_CLK_DP<2>")
	)
	(arc
		(start 257.59283 -95.425006)
		(mid 257.665628 -95.715769)
		(end 257.58648 -96.004888)
		(width 0.0889)
		(layer "In2.Cu")
		(net "M_F_CLK_DP<2>")
	)
	(arc
		(start 257.59283 -96.415606)
		(mid 257.665628 -96.706369)
		(end 257.58648 -96.995488)
		(width 0.0889)
		(layer "In2.Cu")
		(net "M_F_CLK_DP<2>")
	)
	(arc
		(start 257.600196 -98.410268)
		(mid 257.66579 -98.695607)
		(end 257.58648 -98.97745)
		(width 0.0889)
		(layer "In2.Cu")
		(net "M_F_CLK_DP<2>")
	)
	(arc
		(start 257.58648 -98.97745)
		(mid 257.532862 -99.167456)
		(end 257.576574 -99.359974)
		(width 0.0889)
		(layer "In2.Cu")
		(net "M_F_CLK_DP<2>")
	)
	(arc
		(start 257.665728 -93.726254)
		(mid 257.64754 -93.874282)
		(end 257.59283 -94.01302)
		(width 0.0889)
		(layer "In2.Cu")
		(net "M_F_CLK_DP<2>")
	)
	(arc
		(start 257.58648 -95.014288)
		(mid 257.53301 -95.209351)
		(end 257.581654 -95.405702)
		(width 0.0889)
		(layer "In2.Cu")
		(net "M_F_CLK_DP<2>")
	)
	(arc
		(start 257.58648 -94.023688)
		(mid 257.532981 -94.223586)
		(end 257.58648 -94.423484)
		(width 0.0889)
		(layer "In2.Cu")
		(net "M_F_CLK_DP<2>")
	)
	(arc
		(start 257.597148 -97.41408)
		(mid 257.665747 -97.701714)
		(end 257.58648 -97.986596)
		(width 0.0889)
		(layer "In2.Cu")
		(net "M_F_CLK_DP<2>")
	)
	(arc
		(start 257.58648 -97.986596)
		(mid 257.532862 -98.176602)
		(end 257.576574 -98.36912)
		(width 0.0889)
		(layer "In2.Cu")
		(net "M_F_CLK_DP<2>")
	)
	(arc
		(start 257.58648 -96.995488)
		(mid 257.53301 -97.190551)
		(end 257.581654 -97.386902)
		(width 0.0889)
		(layer "In2.Cu")
		(net "M_F_CLK_DP<2>")
	)
	(arc
		(start 257.82524 -93.34119)
		(mid 257.707194 -93.517859)
		(end 257.665728 -93.726254)
		(width 0.0889)
		(layer "In2.Cu")
		(net "M_F_CLK_DP<2>")
	)
	(segment
		(start 256.750312 -152.273)
		(end 256.749804 -152.278842)
		(width 0.1651)
		(layer "F.Cu")
		(net "M_F_CLK_DP<0>")
	)
	(segment
		(start 259.65023 -93.23324)
		(end 260.22173 -93.23324)
		(width 0.1016)
		(layer "F.Cu")
		(net "M_F_CLK_DP<0>")
	)
	(segment
		(start 256.749804 -152.278842)
		(end 256.749804 -153.571956)
		(width 0.1651)
		(layer "F.Cu")
		(net "M_F_CLK_DP<0>")
	)
	(via
		(at 259.65023 -93.23324)
		(size 0.508)
		(drill 0.254)
		(layers "F.Cu" "B.Cu")
		(net "M_F_CLK_DP<0>")
	)
	(via
		(at 256.749804 -153.571956)
		(size 0.508)
		(drill 0.254)
		(layers "F.Cu" "B.Cu")
		(net "M_F_CLK_DP<0>")
	)
	(segment
		(start 259.298694 -98.377502)
		(end 259.310632 -98.398838)
		(width 0.0889)
		(layer "In2.Cu")
		(net "M_F_CLK_DP<0>")
	)
	(segment
		(start 259.298694 -95.405702)
		(end 259.30352 -95.414338)
		(width 0.0889)
		(layer "In2.Cu")
		(net "M_F_CLK_DP<0>")
	)
	(segment
		(start 259.314696 -99.395534)
		(end 259.461 -99.621086)
		(width 0.0889)
		(layer "In2.Cu")
		(net "M_F_CLK_DP<0>")
	)
	(segment
		(start 259.88772 -125.935232)
		(end 260.951472 -126.998984)
		(width 0.14224)
		(layer "In2.Cu")
		(net "M_F_CLK_DP<0>")
	)
	(segment
		(start 260.951472 -126.998984)
		(end 260.951472 -129.652776)
		(width 0.14224)
		(layer "In2.Cu")
		(net "M_F_CLK_DP<0>")
	)
	(segment
		(start 259.298694 -96.396302)
		(end 259.30352 -96.404938)
		(width 0.0889)
		(layer "In2.Cu")
		(net "M_F_CLK_DP<0>")
	)
	(segment
		(start 259.30987 -94.01302)
		(end 259.30352 -94.023688)
		(width 0.0889)
		(layer "In2.Cu")
		(net "M_F_CLK_DP<0>")
	)
	(segment
		(start 259.60832 -102.856792)
		(end 259.88772 -103.136192)
		(width 0.14224)
		(layer "In2.Cu")
		(net "M_F_CLK_DP<0>")
	)
	(segment
		(start 258.351782 -152.656286)
		(end 260.149848 -152.656286)
		(width 0.14224)
		(layer "In2.Cu")
		(net "M_F_CLK_DP<0>")
	)
	(segment
		(start 261.433818 -151.359362)
		(end 260.953758 -151.839422)
		(width 0.14224)
		(layer "In2.Cu")
		(net "M_F_CLK_DP<0>")
	)
	(segment
		(start 259.60832 -101.981254)
		(end 259.60832 -102.856792)
		(width 0.14224)
		(layer "In2.Cu")
		(net "M_F_CLK_DP<0>")
	)
	(segment
		(start 260.149848 -152.656286)
		(end 260.577076 -153.083514)
		(width 0.14224)
		(layer "In2.Cu")
		(net "M_F_CLK_DP<0>")
	)
	(segment
		(start 259.58292 -100.37572)
		(end 259.58292 -101.933756)
		(width 0.0889)
		(layer "In2.Cu")
		(net "M_F_CLK_DP<0>")
	)
	(segment
		(start 260.951472 -129.652776)
		(end 261.433818 -130.135122)
		(width 0.14224)
		(layer "In2.Cu")
		(net "M_F_CLK_DP<0>")
	)
	(segment
		(start 259.461 -99.621086)
		(end 259.461 -100.2538)
		(width 0.0889)
		(layer "In2.Cu")
		(net "M_F_CLK_DP<0>")
	)
	(segment
		(start 259.88772 -103.136192)
		(end 259.88772 -125.935232)
		(width 0.14224)
		(layer "In2.Cu")
		(net "M_F_CLK_DP<0>")
	)
	(segment
		(start 259.30352 -95.414338)
		(end 259.30987 -95.425006)
		(width 0.0889)
		(layer "In2.Cu")
		(net "M_F_CLK_DP<0>")
	)
	(segment
		(start 260.577076 -153.083514)
		(end 260.577076 -154.207718)
		(width 0.14224)
		(layer "In2.Cu")
		(net "M_F_CLK_DP<0>")
	)
	(segment
		(start 260.116828 -154.667966)
		(end 257.421634 -154.667966)
		(width 0.14224)
		(layer "In2.Cu")
		(net "M_F_CLK_DP<0>")
	)
	(segment
		(start 258.351782 -151.839422)
		(end 258.196334 -151.99487)
		(width 0.14224)
		(layer "In2.Cu")
		(net "M_F_CLK_DP<0>")
	)
	(segment
		(start 260.953758 -151.839422)
		(end 258.351782 -151.839422)
		(width 0.14224)
		(layer "In2.Cu")
		(net "M_F_CLK_DP<0>")
	)
	(segment
		(start 257.029204 -154.275536)
		(end 257.029204 -153.851356)
		(width 0.14224)
		(layer "In2.Cu")
		(net "M_F_CLK_DP<0>")
	)
	(segment
		(start 259.58292 -101.933756)
		(end 259.60832 -101.959156)
		(width 0.0889)
		(layer "In2.Cu")
		(net "M_F_CLK_DP<0>")
	)
	(segment
		(start 259.298694 -97.386902)
		(end 259.30352 -97.395538)
		(width 0.0889)
		(layer "In2.Cu")
		(net "M_F_CLK_DP<0>")
	)
	(segment
		(start 258.196334 -151.99487)
		(end 258.196334 -152.500838)
		(width 0.14224)
		(layer "In2.Cu")
		(net "M_F_CLK_DP<0>")
	)
	(segment
		(start 257.029204 -153.851356)
		(end 256.749804 -153.571956)
		(width 0.14224)
		(layer "In2.Cu")
		(net "M_F_CLK_DP<0>")
	)
	(segment
		(start 259.60832 -101.959156)
		(end 259.60832 -101.981254)
		(width 0.0889)
		(layer "In2.Cu")
		(net "M_F_CLK_DP<0>")
	)
	(segment
		(start 258.196334 -152.500838)
		(end 258.351782 -152.656286)
		(width 0.14224)
		(layer "In2.Cu")
		(net "M_F_CLK_DP<0>")
	)
	(segment
		(start 259.461 -100.2538)
		(end 259.58292 -100.37572)
		(width 0.0889)
		(layer "In2.Cu")
		(net "M_F_CLK_DP<0>")
	)
	(segment
		(start 259.310632 -98.398838)
		(end 259.30987 -98.396806)
		(width 0.0889)
		(layer "In2.Cu")
		(net "M_F_CLK_DP<0>")
	)
	(segment
		(start 259.30352 -96.404938)
		(end 259.30987 -96.415606)
		(width 0.0889)
		(layer "In2.Cu")
		(net "M_F_CLK_DP<0>")
	)
	(segment
		(start 259.30352 -97.395538)
		(end 259.30987 -97.406206)
		(width 0.0889)
		(layer "In2.Cu")
		(net "M_F_CLK_DP<0>")
	)
	(segment
		(start 260.577076 -154.207718)
		(end 260.116828 -154.667966)
		(width 0.14224)
		(layer "In2.Cu")
		(net "M_F_CLK_DP<0>")
	)
	(segment
		(start 261.433818 -130.135122)
		(end 261.433818 -151.359362)
		(width 0.14224)
		(layer "In2.Cu")
		(net "M_F_CLK_DP<0>")
	)
	(segment
		(start 257.421634 -154.667966)
		(end 257.029204 -154.275536)
		(width 0.14224)
		(layer "In2.Cu")
		(net "M_F_CLK_DP<0>")
	)
	(segment
		(start 259.65023 -93.23324)
		(end 259.543296 -93.340174)
		(width 0.0889)
		(layer "In2.Cu")
		(net "M_F_CLK_DP<0>")
	)
	(arc
		(start 259.30352 -96.004888)
		(mid 259.25005 -96.199951)
		(end 259.298694 -96.396302)
		(width 0.0889)
		(layer "In2.Cu")
		(net "M_F_CLK_DP<0>")
	)
	(arc
		(start 259.382768 -93.727778)
		(mid 259.364388 -93.875019)
		(end 259.30987 -94.01302)
		(width 0.0889)
		(layer "In2.Cu")
		(net "M_F_CLK_DP<0>")
	)
	(arc
		(start 259.30987 -97.406206)
		(mid 259.382668 -97.696969)
		(end 259.30352 -97.986088)
		(width 0.0889)
		(layer "In2.Cu")
		(net "M_F_CLK_DP<0>")
	)
	(arc
		(start 259.30352 -94.023688)
		(mid 259.250021 -94.223586)
		(end 259.30352 -94.423484)
		(width 0.0889)
		(layer "In2.Cu")
		(net "M_F_CLK_DP<0>")
	)
	(arc
		(start 259.30987 -98.396806)
		(mid 259.382668 -98.687569)
		(end 259.30352 -98.976688)
		(width 0.0889)
		(layer "In2.Cu")
		(net "M_F_CLK_DP<0>")
	)
	(arc
		(start 259.30987 -95.425006)
		(mid 259.382668 -95.715769)
		(end 259.30352 -96.004888)
		(width 0.0889)
		(layer "In2.Cu")
		(net "M_F_CLK_DP<0>")
	)
	(arc
		(start 259.30352 -98.976688)
		(mid 259.25001 -99.187703)
		(end 259.314696 -99.395534)
		(width 0.0889)
		(layer "In2.Cu")
		(net "M_F_CLK_DP<0>")
	)
	(arc
		(start 259.30352 -95.014288)
		(mid 259.25005 -95.209351)
		(end 259.298694 -95.405702)
		(width 0.0889)
		(layer "In2.Cu")
		(net "M_F_CLK_DP<0>")
	)
	(arc
		(start 259.543296 -93.340174)
		(mid 259.424471 -93.518008)
		(end 259.382768 -93.727778)
		(width 0.0889)
		(layer "In2.Cu")
		(net "M_F_CLK_DP<0>")
	)
	(arc
		(start 259.30352 -96.995488)
		(mid 259.25005 -97.190551)
		(end 259.298694 -97.386902)
		(width 0.0889)
		(layer "In2.Cu")
		(net "M_F_CLK_DP<0>")
	)
	(arc
		(start 259.30352 -97.986088)
		(mid 259.25005 -98.181151)
		(end 259.298694 -98.377502)
		(width 0.0889)
		(layer "In2.Cu")
		(net "M_F_CLK_DP<0>")
	)
	(arc
		(start 259.30352 -94.423484)
		(mid 259.382651 -94.718886)
		(end 259.30352 -95.014288)
		(width 0.0889)
		(layer "In2.Cu")
		(net "M_F_CLK_DP<0>")
	)
	(arc
		(start 259.30987 -96.415606)
		(mid 259.382668 -96.706369)
		(end 259.30352 -96.995488)
		(width 0.0889)
		(layer "In2.Cu")
		(net "M_F_CLK_DP<0>")
	)
	(segment
		(start 257.64617 -91.747086)
		(end 257.07467 -91.747086)
		(width 0.1016)
		(layer "F.Cu")
		(net "M_F_CLK_DN<3>")
	)
	(via
		(at 257.523742 -148.771356)
		(size 0.508)
		(drill 0.254)
		(layers "F.Cu" "B.Cu")
		(net "M_F_CLK_DN<3>")
	)
	(via
		(at 257.07467 -91.747086)
		(size 0.508)
		(drill 0.254)
		(layers "F.Cu" "B.Cu")
		(net "M_F_CLK_DN<3>")
	)
	(segment
		(start 257.60045 -147.478496)
		(end 257.599942 -147.478496)
		(width 0.1651)
		(layer "B.Cu")
		(net "M_F_CLK_DN<3>")
	)
	(segment
		(start 257.599942 -147.478496)
		(end 257.599942 -148.695156)
		(width 0.1651)
		(layer "B.Cu")
		(net "M_F_CLK_DN<3>")
	)
	(segment
		(start 257.599942 -148.695156)
		(end 257.523742 -148.771356)
		(width 0.1651)
		(layer "B.Cu")
		(net "M_F_CLK_DN<3>")
	)
	(segment
		(start 257.296412 -149.397212)
		(end 257.296412 -148.998686)
		(width 0.14224)
		(layer "In2.Cu")
		(net "M_F_CLK_DN<3>")
	)
	(segment
		(start 260.322568 -142.44955)
		(end 260.43636 -142.563342)
		(width 0.14224)
		(layer "In2.Cu")
		(net "M_F_CLK_DN<3>")
	)
	(segment
		(start 259.941822 -133.818122)
		(end 259.82803 -133.931914)
		(width 0.14224)
		(layer "In2.Cu")
		(net "M_F_CLK_DN<3>")
	)
	(segment
		(start 259.458968 -129.48285)
		(end 259.57276 -129.596642)
		(width 0.14224)
		(layer "In2.Cu")
		(net "M_F_CLK_DN<3>")
	)
	(segment
		(start 259.57276 -128.439418)
		(end 259.57276 -128.904238)
		(width 0.14224)
		(layer "In2.Cu")
		(net "M_F_CLK_DN<3>")
	)
	(segment
		(start 259.57276 -128.904238)
		(end 259.458968 -129.01803)
		(width 0.14224)
		(layer "In2.Cu")
		(net "M_F_CLK_DN<3>")
	)
	(segment
		(start 259.82803 -133.931914)
		(end 259.82803 -134.396734)
		(width 0.14224)
		(layer "In2.Cu")
		(net "M_F_CLK_DN<3>")
	)
	(segment
		(start 258.131056 -149.7076)
		(end 257.6068 -149.7076)
		(width 0.14224)
		(layer "In2.Cu")
		(net "M_F_CLK_DN<3>")
	)
	(segment
		(start 257.296412 -148.998686)
		(end 257.523742 -148.771356)
		(width 0.14224)
		(layer "In2.Cu")
		(net "M_F_CLK_DN<3>")
	)
	(segment
		(start 258.2799 -98.386138)
		(end 258.27355 -98.396806)
		(width 0.0889)
		(layer "In2.Cu")
		(net "M_F_CLK_DN<3>")
	)
	(segment
		(start 258.49453 -102.066344)
		(end 258.49453 -102.088442)
		(width 0.0889)
		(layer "In2.Cu")
		(net "M_F_CLK_DN<3>")
	)
	(segment
		(start 260.00456 -146.773138)
		(end 259.890768 -146.88693)
		(width 0.14224)
		(layer "In2.Cu")
		(net "M_F_CLK_DN<3>")
	)
	(segment
		(start 260.00456 -145.37944)
		(end 260.00456 -146.773138)
		(width 0.14224)
		(layer "In2.Cu")
		(net "M_F_CLK_DN<3>")
	)
	(segment
		(start 258.198112 -99.48418)
		(end 258.198112 -99.99726)
		(width 0.0889)
		(layer "In2.Cu")
		(net "M_F_CLK_DN<3>")
	)
	(segment
		(start 259.941822 -139.113768)
		(end 260.43636 -139.608306)
		(width 0.14224)
		(layer "In2.Cu")
		(net "M_F_CLK_DN<3>")
	)
	(segment
		(start 259.890768 -146.88693)
		(end 259.890768 -147.35175)
		(width 0.14224)
		(layer "In2.Cu")
		(net "M_F_CLK_DN<3>")
	)
	(segment
		(start 260.43636 -140.713714)
		(end 260.322568 -140.827506)
		(width 0.14224)
		(layer "In2.Cu")
		(net "M_F_CLK_DN<3>")
	)
	(segment
		(start 260.322568 -141.98473)
		(end 260.322568 -142.44955)
		(width 0.14224)
		(layer "In2.Cu")
		(net "M_F_CLK_DN<3>")
	)
	(segment
		(start 258.5339 -100.333048)
		(end 258.5339 -102.026974)
		(width 0.0889)
		(layer "In2.Cu")
		(net "M_F_CLK_DN<3>")
	)
	(segment
		(start 259.458968 -127.860806)
		(end 259.458968 -128.325626)
		(width 0.14224)
		(layer "In2.Cu")
		(net "M_F_CLK_DN<3>")
	)
	(segment
		(start 259.941822 -134.510526)
		(end 259.941822 -139.113768)
		(width 0.14224)
		(layer "In2.Cu")
		(net "M_F_CLK_DN<3>")
	)
	(segment
		(start 259.941822 -133.353302)
		(end 259.941822 -133.818122)
		(width 0.14224)
		(layer "In2.Cu")
		(net "M_F_CLK_DN<3>")
	)
	(segment
		(start 257.91541 -92.83319)
		(end 257.948176 -92.83319)
		(width 0.0889)
		(layer "In2.Cu")
		(net "M_F_CLK_DN<3>")
	)
	(segment
		(start 260.00456 -147.930362)
		(end 259.890768 -148.044154)
		(width 0.14224)
		(layer "In2.Cu")
		(net "M_F_CLK_DN<3>")
	)
	(segment
		(start 258.284726 -93.424502)
		(end 258.2799 -93.433138)
		(width 0.0889)
		(layer "In2.Cu")
		(net "M_F_CLK_DN<3>")
	)
	(segment
		(start 259.503926 -149.7076)
		(end 258.82346 -149.7076)
		(width 0.14224)
		(layer "In2.Cu")
		(net "M_F_CLK_DN<3>")
	)
	(segment
		(start 259.57276 -132.98424)
		(end 259.941822 -133.353302)
		(width 0.14224)
		(layer "In2.Cu")
		(net "M_F_CLK_DN<3>")
	)
	(segment
		(start 260.43636 -139.608306)
		(end 260.43636 -140.713714)
		(width 0.14224)
		(layer "In2.Cu")
		(net "M_F_CLK_DN<3>")
	)
	(segment
		(start 260.43636 -142.563342)
		(end 260.43636 -143.790416)
		(width 0.14224)
		(layer "In2.Cu")
		(net "M_F_CLK_DN<3>")
	)
	(segment
		(start 258.2799 -97.395538)
		(end 258.27355 -97.406206)
		(width 0.0889)
		(layer "In2.Cu")
		(net "M_F_CLK_DN<3>")
	)
	(segment
		(start 258.284726 -99.368102)
		(end 258.245102 -99.43719)
		(width 0.0889)
		(layer "In2.Cu")
		(net "M_F_CLK_DN<3>")
	)
	(segment
		(start 260.322568 -143.904208)
		(end 260.322568 -144.369028)
		(width 0.14224)
		(layer "In2.Cu")
		(net "M_F_CLK_DN<3>")
	)
	(segment
		(start 258.284726 -95.405702)
		(end 258.2799 -95.414338)
		(width 0.0889)
		(layer "In2.Cu")
		(net "M_F_CLK_DN<3>")
	)
	(segment
		(start 258.49453 -102.088442)
		(end 258.49453 -103.318564)
		(width 0.14224)
		(layer "In2.Cu")
		(net "M_F_CLK_DN<3>")
	)
	(segment
		(start 258.709668 -149.593808)
		(end 258.244848 -149.593808)
		(width 0.14224)
		(layer "In2.Cu")
		(net "M_F_CLK_DN<3>")
	)
	(segment
		(start 260.43636 -144.48282)
		(end 260.43636 -144.94764)
		(width 0.14224)
		(layer "In2.Cu")
		(net "M_F_CLK_DN<3>")
	)
	(segment
		(start 259.458968 -128.325626)
		(end 259.57276 -128.439418)
		(width 0.14224)
		(layer "In2.Cu")
		(net "M_F_CLK_DN<3>")
	)
	(segment
		(start 260.00456 -148.622766)
		(end 260.00456 -149.206966)
		(width 0.14224)
		(layer "In2.Cu")
		(net "M_F_CLK_DN<3>")
	)
	(segment
		(start 258.78028 -126.489714)
		(end 259.57276 -127.282194)
		(width 0.14224)
		(layer "In2.Cu")
		(net "M_F_CLK_DN<3>")
	)
	(segment
		(start 259.890768 -148.044154)
		(end 259.890768 -148.508974)
		(width 0.14224)
		(layer "In2.Cu")
		(net "M_F_CLK_DN<3>")
	)
	(segment
		(start 257.6068 -149.7076)
		(end 257.296412 -149.397212)
		(width 0.14224)
		(layer "In2.Cu")
		(net "M_F_CLK_DN<3>")
	)
	(segment
		(start 258.49453 -103.318564)
		(end 258.78028 -103.604314)
		(width 0.14224)
		(layer "In2.Cu")
		(net "M_F_CLK_DN<3>")
	)
	(segment
		(start 260.00456 -147.465542)
		(end 260.00456 -147.930362)
		(width 0.14224)
		(layer "In2.Cu")
		(net "M_F_CLK_DN<3>")
	)
	(segment
		(start 259.890768 -147.35175)
		(end 260.00456 -147.465542)
		(width 0.14224)
		(layer "In2.Cu")
		(net "M_F_CLK_DN<3>")
	)
	(segment
		(start 258.244848 -149.593808)
		(end 258.131056 -149.7076)
		(width 0.14224)
		(layer "In2.Cu")
		(net "M_F_CLK_DN<3>")
	)
	(segment
		(start 260.322568 -140.827506)
		(end 260.322568 -141.292326)
		(width 0.14224)
		(layer "In2.Cu")
		(net "M_F_CLK_DN<3>")
	)
	(segment
		(start 260.43636 -141.870938)
		(end 260.322568 -141.98473)
		(width 0.14224)
		(layer "In2.Cu")
		(net "M_F_CLK_DN<3>")
	)
	(segment
		(start 260.43636 -143.790416)
		(end 260.322568 -143.904208)
		(width 0.14224)
		(layer "In2.Cu")
		(net "M_F_CLK_DN<3>")
	)
	(segment
		(start 259.57276 -127.282194)
		(end 259.57276 -127.747014)
		(width 0.14224)
		(layer "In2.Cu")
		(net "M_F_CLK_DN<3>")
	)
	(segment
		(start 258.82346 -149.7076)
		(end 258.709668 -149.593808)
		(width 0.14224)
		(layer "In2.Cu")
		(net "M_F_CLK_DN<3>")
	)
	(segment
		(start 260.00456 -149.206966)
		(end 259.503926 -149.7076)
		(width 0.14224)
		(layer "In2.Cu")
		(net "M_F_CLK_DN<3>")
	)
	(segment
		(start 260.322568 -141.292326)
		(end 260.43636 -141.406118)
		(width 0.14224)
		(layer "In2.Cu")
		(net "M_F_CLK_DN<3>")
	)
	(segment
		(start 258.78028 -103.604314)
		(end 258.78028 -126.489714)
		(width 0.14224)
		(layer "In2.Cu")
		(net "M_F_CLK_DN<3>")
	)
	(segment
		(start 260.43636 -144.94764)
		(end 260.00456 -145.37944)
		(width 0.14224)
		(layer "In2.Cu")
		(net "M_F_CLK_DN<3>")
	)
	(segment
		(start 258.5339 -102.026974)
		(end 258.49453 -102.066344)
		(width 0.0889)
		(layer "In2.Cu")
		(net "M_F_CLK_DN<3>")
	)
	(segment
		(start 257.07467 -91.747086)
		(end 257.191764 -91.864434)
		(width 0.0889)
		(layer "In2.Cu")
		(net "M_F_CLK_DN<3>")
	)
	(segment
		(start 258.284726 -96.396302)
		(end 258.2799 -96.404938)
		(width 0.0889)
		(layer "In2.Cu")
		(net "M_F_CLK_DN<3>")
	)
	(segment
		(start 258.27355 -94.01302)
		(end 258.2799 -94.023688)
		(width 0.0889)
		(layer "In2.Cu")
		(net "M_F_CLK_DN<3>")
	)
	(segment
		(start 259.890768 -148.508974)
		(end 260.00456 -148.622766)
		(width 0.14224)
		(layer "In2.Cu")
		(net "M_F_CLK_DN<3>")
	)
	(segment
		(start 258.198112 -99.99726)
		(end 258.5339 -100.333048)
		(width 0.0889)
		(layer "In2.Cu")
		(net "M_F_CLK_DN<3>")
	)
	(segment
		(start 258.284726 -98.377502)
		(end 258.2799 -98.386138)
		(width 0.0889)
		(layer "In2.Cu")
		(net "M_F_CLK_DN<3>")
	)
	(segment
		(start 260.43636 -141.406118)
		(end 260.43636 -141.870938)
		(width 0.14224)
		(layer "In2.Cu")
		(net "M_F_CLK_DN<3>")
	)
	(segment
		(start 258.2799 -95.414338)
		(end 258.27355 -95.425006)
		(width 0.0889)
		(layer "In2.Cu")
		(net "M_F_CLK_DN<3>")
	)
	(segment
		(start 258.245102 -99.43719)
		(end 258.198112 -99.48418)
		(width 0.0889)
		(layer "In2.Cu")
		(net "M_F_CLK_DN<3>")
	)
	(segment
		(start 258.2799 -96.404938)
		(end 258.27355 -96.415606)
		(width 0.0889)
		(layer "In2.Cu")
		(net "M_F_CLK_DN<3>")
	)
	(segment
		(start 259.57276 -129.596642)
		(end 259.57276 -132.98424)
		(width 0.14224)
		(layer "In2.Cu")
		(net "M_F_CLK_DN<3>")
	)
	(segment
		(start 259.82803 -134.396734)
		(end 259.941822 -134.510526)
		(width 0.14224)
		(layer "In2.Cu")
		(net "M_F_CLK_DN<3>")
	)
	(segment
		(start 258.284726 -97.386902)
		(end 258.2799 -97.395538)
		(width 0.0889)
		(layer "In2.Cu")
		(net "M_F_CLK_DN<3>")
	)
	(segment
		(start 260.322568 -144.369028)
		(end 260.43636 -144.48282)
		(width 0.14224)
		(layer "In2.Cu")
		(net "M_F_CLK_DN<3>")
	)
	(segment
		(start 259.458968 -129.01803)
		(end 259.458968 -129.48285)
		(width 0.14224)
		(layer "In2.Cu")
		(net "M_F_CLK_DN<3>")
	)
	(segment
		(start 259.57276 -127.747014)
		(end 259.458968 -127.860806)
		(width 0.14224)
		(layer "In2.Cu")
		(net "M_F_CLK_DN<3>")
	)
	(arc
		(start 258.2799 -98.976688)
		(mid 258.33337 -99.171751)
		(end 258.284726 -99.368102)
		(width 0.0889)
		(layer "In2.Cu")
		(net "M_F_CLK_DN<3>")
	)
	(arc
		(start 258.27355 -97.406206)
		(mid 258.200752 -97.696969)
		(end 258.2799 -97.986088)
		(width 0.0889)
		(layer "In2.Cu")
		(net "M_F_CLK_DN<3>")
	)
	(arc
		(start 257.948176 -92.83319)
		(mid 258.281094 -93.035181)
		(end 258.284726 -93.424502)
		(width 0.0889)
		(layer "In2.Cu")
		(net "M_F_CLK_DN<3>")
	)
	(arc
		(start 258.2799 -93.433138)
		(mid 258.200678 -93.722256)
		(end 258.27355 -94.01302)
		(width 0.0889)
		(layer "In2.Cu")
		(net "M_F_CLK_DN<3>")
	)
	(arc
		(start 258.2799 -97.986088)
		(mid 258.33337 -98.181151)
		(end 258.284726 -98.377502)
		(width 0.0889)
		(layer "In2.Cu")
		(net "M_F_CLK_DN<3>")
	)
	(arc
		(start 257.191764 -91.864434)
		(mid 257.303197 -92.031066)
		(end 257.342386 -92.227654)
		(width 0.0889)
		(layer "In2.Cu")
		(net "M_F_CLK_DN<3>")
	)
	(arc
		(start 258.27355 -98.396806)
		(mid 258.200752 -98.687569)
		(end 258.2799 -98.976688)
		(width 0.0889)
		(layer "In2.Cu")
		(net "M_F_CLK_DN<3>")
	)
	(arc
		(start 258.2799 -94.023688)
		(mid 258.333399 -94.223586)
		(end 258.2799 -94.423484)
		(width 0.0889)
		(layer "In2.Cu")
		(net "M_F_CLK_DN<3>")
	)
	(arc
		(start 258.2799 -96.995488)
		(mid 258.33337 -97.190551)
		(end 258.284726 -97.386902)
		(width 0.0889)
		(layer "In2.Cu")
		(net "M_F_CLK_DN<3>")
	)
	(arc
		(start 257.342386 -92.227654)
		(mid 257.503884 -92.648704)
		(end 257.91541 -92.83319)
		(width 0.0889)
		(layer "In2.Cu")
		(net "M_F_CLK_DN<3>")
	)
	(arc
		(start 258.2799 -96.004888)
		(mid 258.33337 -96.199951)
		(end 258.284726 -96.396302)
		(width 0.0889)
		(layer "In2.Cu")
		(net "M_F_CLK_DN<3>")
	)
	(arc
		(start 258.2799 -95.014288)
		(mid 258.33337 -95.209351)
		(end 258.284726 -95.405702)
		(width 0.0889)
		(layer "In2.Cu")
		(net "M_F_CLK_DN<3>")
	)
	(arc
		(start 258.27355 -96.415606)
		(mid 258.200752 -96.706369)
		(end 258.2799 -96.995488)
		(width 0.0889)
		(layer "In2.Cu")
		(net "M_F_CLK_DN<3>")
	)
	(arc
		(start 258.27355 -95.425006)
		(mid 258.200752 -95.715769)
		(end 258.2799 -96.004888)
		(width 0.0889)
		(layer "In2.Cu")
		(net "M_F_CLK_DN<3>")
	)
	(arc
		(start 258.2799 -94.423484)
		(mid 258.200769 -94.718886)
		(end 258.2799 -95.014288)
		(width 0.0889)
		(layer "In2.Cu")
		(net "M_F_CLK_DN<3>")
	)
	(segment
		(start 257.599942 -156.87294)
		(end 257.60045 -156.87294)
		(width 0.1651)
		(layer "F.Cu")
		(net "M_F_CLK_DN<1>")
	)
	(segment
		(start 257.599942 -155.509468)
		(end 257.599942 -156.87294)
		(width 0.1651)
		(layer "F.Cu")
		(net "M_F_CLK_DN<1>")
	)
	(segment
		(start 259.36321 -91.747086)
		(end 258.79171 -91.747086)
		(width 0.1016)
		(layer "F.Cu")
		(net "M_F_CLK_DN<1>")
	)
	(via
		(at 258.79171 -91.747086)
		(size 0.508)
		(drill 0.254)
		(layers "F.Cu" "B.Cu")
		(net "M_F_CLK_DN<1>")
	)
	(via
		(at 257.599942 -155.509468)
		(size 0.508)
		(drill 0.254)
		(layers "F.Cu" "B.Cu")
		(net "M_F_CLK_DN<1>")
	)
	(segment
		(start 261.90575 -151.92375)
		(end 261.90575 -152.38857)
		(width 0.14224)
		(layer "In2.Cu")
		(net "M_F_CLK_DN<1>")
	)
	(segment
		(start 261.674102 -126.868174)
		(end 261.674102 -129.309622)
		(width 0.14224)
		(layer "In2.Cu")
		(net "M_F_CLK_DN<1>")
	)
	(segment
		(start 262.019542 -154.124406)
		(end 261.321296 -154.822652)
		(width 0.14224)
		(layer "In2.Cu")
		(net "M_F_CLK_DN<1>")
	)
	(segment
		(start 262.046974 -140.487146)
		(end 261.93496 -140.59916)
		(width 0.14224)
		(layer "In2.Cu")
		(net "M_F_CLK_DN<1>")
	)
	(segment
		(start 262.019542 -142.334742)
		(end 262.019542 -151.809958)
		(width 0.14224)
		(layer "In2.Cu")
		(net "M_F_CLK_DN<1>")
	)
	(segment
		(start 261.93496 -142.25016)
		(end 262.019542 -142.334742)
		(width 0.14224)
		(layer "In2.Cu")
		(net "M_F_CLK_DN<1>")
	)
	(segment
		(start 261.933182 -138.00709)
		(end 261.933182 -138.47191)
		(width 0.14224)
		(layer "In2.Cu")
		(net "M_F_CLK_DN<1>")
	)
	(segment
		(start 262.046974 -137.428478)
		(end 262.046974 -137.893298)
		(width 0.14224)
		(layer "In2.Cu")
		(net "M_F_CLK_DN<1>")
	)
	(segment
		(start 261.933182 -136.157462)
		(end 262.046974 -136.271254)
		(width 0.14224)
		(layer "In2.Cu")
		(net "M_F_CLK_DN<1>")
	)
	(segment
		(start 260.001766 -98.377502)
		(end 259.99694 -98.386138)
		(width 0.0889)
		(layer "In2.Cu")
		(net "M_F_CLK_DN<1>")
	)
	(segment
		(start 262.046974 -137.893298)
		(end 261.933182 -138.00709)
		(width 0.14224)
		(layer "In2.Cu")
		(net "M_F_CLK_DN<1>")
	)
	(segment
		(start 261.90575 -152.38857)
		(end 262.019542 -152.502362)
		(width 0.14224)
		(layer "In2.Cu")
		(net "M_F_CLK_DN<1>")
	)
	(segment
		(start 260.50748 -102.943914)
		(end 260.50748 -125.701552)
		(width 0.14224)
		(layer "In2.Cu")
		(net "M_F_CLK_DN<1>")
	)
	(segment
		(start 260.001512 -99.368864)
		(end 259.9182 -99.518216)
		(width 0.0889)
		(layer "In2.Cu")
		(net "M_F_CLK_DN<1>")
	)
	(segment
		(start 261.93496 -140.59916)
		(end 261.93496 -142.25016)
		(width 0.14224)
		(layer "In2.Cu")
		(net "M_F_CLK_DN<1>")
	)
	(segment
		(start 262.046974 -139.742926)
		(end 262.046974 -140.487146)
		(width 0.14224)
		(layer "In2.Cu")
		(net "M_F_CLK_DN<1>")
	)
	(segment
		(start 262.046974 -138.585702)
		(end 262.046974 -139.050522)
		(width 0.14224)
		(layer "In2.Cu")
		(net "M_F_CLK_DN<1>")
	)
	(segment
		(start 260.001766 -97.386902)
		(end 259.99694 -97.395538)
		(width 0.0889)
		(layer "In2.Cu")
		(net "M_F_CLK_DN<1>")
	)
	(segment
		(start 262.046974 -139.050522)
		(end 261.933182 -139.164314)
		(width 0.14224)
		(layer "In2.Cu")
		(net "M_F_CLK_DN<1>")
	)
	(segment
		(start 260.20268 -102.639114)
		(end 260.50748 -102.943914)
		(width 0.14224)
		(layer "In2.Cu")
		(net "M_F_CLK_DN<1>")
	)
	(segment
		(start 259.9182 -99.989894)
		(end 260.2484 -100.320094)
		(width 0.0889)
		(layer "In2.Cu")
		(net "M_F_CLK_DN<1>")
	)
	(segment
		(start 261.321296 -154.822652)
		(end 261.160514 -154.822652)
		(width 0.14224)
		(layer "In2.Cu")
		(net "M_F_CLK_DN<1>")
	)
	(segment
		(start 259.99059 -94.01302)
		(end 259.99694 -94.023688)
		(width 0.0889)
		(layer "In2.Cu")
		(net "M_F_CLK_DN<1>")
	)
	(segment
		(start 260.2484 -101.963728)
		(end 260.20268 -102.009448)
		(width 0.0889)
		(layer "In2.Cu")
		(net "M_F_CLK_DN<1>")
	)
	(segment
		(start 262.046974 -136.271254)
		(end 262.046974 -136.736074)
		(width 0.14224)
		(layer "In2.Cu")
		(net "M_F_CLK_DN<1>")
	)
	(segment
		(start 262.046974 -135.57885)
		(end 261.933182 -135.692642)
		(width 0.14224)
		(layer "In2.Cu")
		(net "M_F_CLK_DN<1>")
	)
	(segment
		(start 258.287266 -156.459428)
		(end 257.547872 -156.459428)
		(width 0.14224)
		(layer "In2.Cu")
		(net "M_F_CLK_DN<1>")
	)
	(segment
		(start 261.933182 -139.629134)
		(end 262.046974 -139.742926)
		(width 0.14224)
		(layer "In2.Cu")
		(net "M_F_CLK_DN<1>")
	)
	(segment
		(start 257.27152 -156.183076)
		(end 257.27152 -155.83789)
		(width 0.14224)
		(layer "In2.Cu")
		(net "M_F_CLK_DN<1>")
	)
	(segment
		(start 261.933182 -137.314686)
		(end 262.046974 -137.428478)
		(width 0.14224)
		(layer "In2.Cu")
		(net "M_F_CLK_DN<1>")
	)
	(segment
		(start 260.20268 -102.031546)
		(end 260.20268 -102.639114)
		(width 0.14224)
		(layer "In2.Cu")
		(net "M_F_CLK_DN<1>")
	)
	(segment
		(start 261.933182 -139.164314)
		(end 261.933182 -139.629134)
		(width 0.14224)
		(layer "In2.Cu")
		(net "M_F_CLK_DN<1>")
	)
	(segment
		(start 259.99694 -95.414338)
		(end 259.99059 -95.425006)
		(width 0.0889)
		(layer "In2.Cu")
		(net "M_F_CLK_DN<1>")
	)
	(segment
		(start 261.933182 -135.692642)
		(end 261.933182 -136.157462)
		(width 0.14224)
		(layer "In2.Cu")
		(net "M_F_CLK_DN<1>")
	)
	(segment
		(start 260.001766 -93.424502)
		(end 259.99694 -93.433138)
		(width 0.0889)
		(layer "In2.Cu")
		(net "M_F_CLK_DN<1>")
	)
	(segment
		(start 260.013196 -155.96997)
		(end 260.013196 -156.130752)
		(width 0.14224)
		(layer "In2.Cu")
		(net "M_F_CLK_DN<1>")
	)
	(segment
		(start 261.160514 -154.822652)
		(end 260.831584 -155.151582)
		(width 0.14224)
		(layer "In2.Cu")
		(net "M_F_CLK_DN<1>")
	)
	(segment
		(start 260.013196 -156.130752)
		(end 259.68452 -156.459428)
		(width 0.14224)
		(layer "In2.Cu")
		(net "M_F_CLK_DN<1>")
	)
	(segment
		(start 257.547872 -156.459428)
		(end 257.27152 -156.183076)
		(width 0.14224)
		(layer "In2.Cu")
		(net "M_F_CLK_DN<1>")
	)
	(segment
		(start 260.831584 -155.151582)
		(end 260.831584 -155.312364)
		(width 0.14224)
		(layer "In2.Cu")
		(net "M_F_CLK_DN<1>")
	)
	(segment
		(start 262.019542 -151.809958)
		(end 261.90575 -151.92375)
		(width 0.14224)
		(layer "In2.Cu")
		(net "M_F_CLK_DN<1>")
	)
	(segment
		(start 259.9182 -99.518216)
		(end 259.9182 -99.989894)
		(width 0.0889)
		(layer "In2.Cu")
		(net "M_F_CLK_DN<1>")
	)
	(segment
		(start 260.831584 -155.312364)
		(end 260.502908 -155.64104)
		(width 0.14224)
		(layer "In2.Cu")
		(net "M_F_CLK_DN<1>")
	)
	(segment
		(start 261.674102 -129.309622)
		(end 262.046974 -129.682494)
		(width 0.14224)
		(layer "In2.Cu")
		(net "M_F_CLK_DN<1>")
	)
	(segment
		(start 262.046974 -129.682494)
		(end 262.046974 -135.57885)
		(width 0.14224)
		(layer "In2.Cu")
		(net "M_F_CLK_DN<1>")
	)
	(segment
		(start 259.99694 -98.386138)
		(end 259.99059 -98.396806)
		(width 0.0889)
		(layer "In2.Cu")
		(net "M_F_CLK_DN<1>")
	)
	(segment
		(start 262.019542 -152.967182)
		(end 261.90575 -153.080974)
		(width 0.14224)
		(layer "In2.Cu")
		(net "M_F_CLK_DN<1>")
	)
	(segment
		(start 261.90575 -153.545794)
		(end 262.019542 -153.659586)
		(width 0.14224)
		(layer "In2.Cu")
		(net "M_F_CLK_DN<1>")
	)
	(segment
		(start 259.68452 -156.459428)
		(end 258.943094 -156.459428)
		(width 0.14224)
		(layer "In2.Cu")
		(net "M_F_CLK_DN<1>")
	)
	(segment
		(start 257.27152 -155.83789)
		(end 257.599942 -155.509468)
		(width 0.14224)
		(layer "In2.Cu")
		(net "M_F_CLK_DN<1>")
	)
	(segment
		(start 259.99694 -97.395538)
		(end 259.99059 -97.406206)
		(width 0.0889)
		(layer "In2.Cu")
		(net "M_F_CLK_DN<1>")
	)
	(segment
		(start 260.342126 -155.64104)
		(end 260.013196 -155.96997)
		(width 0.14224)
		(layer "In2.Cu")
		(net "M_F_CLK_DN<1>")
	)
	(segment
		(start 261.933182 -136.849866)
		(end 261.933182 -137.314686)
		(width 0.14224)
		(layer "In2.Cu")
		(net "M_F_CLK_DN<1>")
	)
	(segment
		(start 260.2484 -100.320094)
		(end 260.2484 -101.963728)
		(width 0.0889)
		(layer "In2.Cu")
		(net "M_F_CLK_DN<1>")
	)
	(segment
		(start 258.84759 -156.363924)
		(end 258.38277 -156.363924)
		(width 0.14224)
		(layer "In2.Cu")
		(net "M_F_CLK_DN<1>")
	)
	(segment
		(start 258.79171 -91.747086)
		(end 258.910074 -91.865196)
		(width 0.0889)
		(layer "In2.Cu")
		(net "M_F_CLK_DN<1>")
	)
	(segment
		(start 259.63245 -92.83319)
		(end 259.665216 -92.83319)
		(width 0.0889)
		(layer "In2.Cu")
		(net "M_F_CLK_DN<1>")
	)
	(segment
		(start 260.001766 -95.405702)
		(end 259.99694 -95.414338)
		(width 0.0889)
		(layer "In2.Cu")
		(net "M_F_CLK_DN<1>")
	)
	(segment
		(start 261.933182 -138.47191)
		(end 262.046974 -138.585702)
		(width 0.14224)
		(layer "In2.Cu")
		(net "M_F_CLK_DN<1>")
	)
	(segment
		(start 260.001766 -96.396302)
		(end 259.99694 -96.404938)
		(width 0.0889)
		(layer "In2.Cu")
		(net "M_F_CLK_DN<1>")
	)
	(segment
		(start 258.943094 -156.459428)
		(end 258.84759 -156.363924)
		(width 0.14224)
		(layer "In2.Cu")
		(net "M_F_CLK_DN<1>")
	)
	(segment
		(start 259.99694 -98.976688)
		(end 259.997194 -98.976942)
		(width 0.0889)
		(layer "In2.Cu")
		(net "M_F_CLK_DN<1>")
	)
	(segment
		(start 262.019542 -152.502362)
		(end 262.019542 -152.967182)
		(width 0.14224)
		(layer "In2.Cu")
		(net "M_F_CLK_DN<1>")
	)
	(segment
		(start 260.20268 -102.009448)
		(end 260.20268 -102.031546)
		(width 0.0889)
		(layer "In2.Cu")
		(net "M_F_CLK_DN<1>")
	)
	(segment
		(start 260.502908 -155.64104)
		(end 260.342126 -155.64104)
		(width 0.14224)
		(layer "In2.Cu")
		(net "M_F_CLK_DN<1>")
	)
	(segment
		(start 262.019542 -153.659586)
		(end 262.019542 -154.124406)
		(width 0.14224)
		(layer "In2.Cu")
		(net "M_F_CLK_DN<1>")
	)
	(segment
		(start 262.046974 -136.736074)
		(end 261.933182 -136.849866)
		(width 0.14224)
		(layer "In2.Cu")
		(net "M_F_CLK_DN<1>")
	)
	(segment
		(start 258.38277 -156.363924)
		(end 258.287266 -156.459428)
		(width 0.14224)
		(layer "In2.Cu")
		(net "M_F_CLK_DN<1>")
	)
	(segment
		(start 259.99694 -96.404938)
		(end 259.99059 -96.415606)
		(width 0.0889)
		(layer "In2.Cu")
		(net "M_F_CLK_DN<1>")
	)
	(segment
		(start 261.90575 -153.080974)
		(end 261.90575 -153.545794)
		(width 0.14224)
		(layer "In2.Cu")
		(net "M_F_CLK_DN<1>")
	)
	(segment
		(start 260.50748 -125.701552)
		(end 261.674102 -126.868174)
		(width 0.14224)
		(layer "In2.Cu")
		(net "M_F_CLK_DN<1>")
	)
	(arc
		(start 259.99059 -97.406206)
		(mid 259.917792 -97.696969)
		(end 259.99694 -97.986088)
		(width 0.0889)
		(layer "In2.Cu")
		(net "M_F_CLK_DN<1>")
	)
	(arc
		(start 259.99059 -95.425006)
		(mid 259.917792 -95.715769)
		(end 259.99694 -96.004888)
		(width 0.0889)
		(layer "In2.Cu")
		(net "M_F_CLK_DN<1>")
	)
	(arc
		(start 259.99694 -94.423484)
		(mid 259.917809 -94.718886)
		(end 259.99694 -95.014288)
		(width 0.0889)
		(layer "In2.Cu")
		(net "M_F_CLK_DN<1>")
	)
	(arc
		(start 259.665216 -92.83319)
		(mid 259.998134 -93.035181)
		(end 260.001766 -93.424502)
		(width 0.0889)
		(layer "In2.Cu")
		(net "M_F_CLK_DN<1>")
	)
	(arc
		(start 259.99694 -95.014288)
		(mid 260.05041 -95.209351)
		(end 260.001766 -95.405702)
		(width 0.0889)
		(layer "In2.Cu")
		(net "M_F_CLK_DN<1>")
	)
	(arc
		(start 259.99694 -94.023688)
		(mid 260.050439 -94.223586)
		(end 259.99694 -94.423484)
		(width 0.0889)
		(layer "In2.Cu")
		(net "M_F_CLK_DN<1>")
	)
	(arc
		(start 259.99059 -98.396806)
		(mid 259.917792 -98.687569)
		(end 259.99694 -98.976688)
		(width 0.0889)
		(layer "In2.Cu")
		(net "M_F_CLK_DN<1>")
	)
	(arc
		(start 259.99694 -96.995488)
		(mid 260.05041 -97.190551)
		(end 260.001766 -97.386902)
		(width 0.0889)
		(layer "In2.Cu")
		(net "M_F_CLK_DN<1>")
	)
	(arc
		(start 259.99694 -97.986088)
		(mid 260.05041 -98.181151)
		(end 260.001766 -98.377502)
		(width 0.0889)
		(layer "In2.Cu")
		(net "M_F_CLK_DN<1>")
	)
	(arc
		(start 259.99059 -96.415606)
		(mid 259.917792 -96.706369)
		(end 259.99694 -96.995488)
		(width 0.0889)
		(layer "In2.Cu")
		(net "M_F_CLK_DN<1>")
	)
	(arc
		(start 259.997194 -98.976942)
		(mid 260.050634 -99.17235)
		(end 260.001512 -99.368864)
		(width 0.0889)
		(layer "In2.Cu")
		(net "M_F_CLK_DN<1>")
	)
	(arc
		(start 259.059426 -92.22613)
		(mid 259.220371 -92.648178)
		(end 259.63245 -92.83319)
		(width 0.0889)
		(layer "In2.Cu")
		(net "M_F_CLK_DN<1>")
	)
	(arc
		(start 259.99694 -93.433138)
		(mid 259.917718 -93.722256)
		(end 259.99059 -94.01302)
		(width 0.0889)
		(layer "In2.Cu")
		(net "M_F_CLK_DN<1>")
	)
	(arc
		(start 259.99694 -96.004888)
		(mid 260.05041 -96.199951)
		(end 260.001766 -96.396302)
		(width 0.0889)
		(layer "In2.Cu")
		(net "M_F_CLK_DN<1>")
	)
	(arc
		(start 258.910074 -91.865196)
		(mid 259.02064 -92.030809)
		(end 259.059426 -92.22613)
		(width 0.0889)
		(layer "In2.Cu")
		(net "M_F_CLK_DN<1>")
	)
	(segment
		(start 257.64617 -93.72854)
		(end 257.07467 -93.72854)
		(width 0.1016)
		(layer "F.Cu")
		(net "M_F_CLK_DN<2>")
	)
	(via
		(at 257.789426 -150.785068)
		(size 0.508)
		(drill 0.254)
		(layers "F.Cu" "B.Cu")
		(net "M_F_CLK_DN<2>")
	)
	(via
		(at 257.07467 -93.72854)
		(size 0.508)
		(drill 0.254)
		(layers "F.Cu" "B.Cu")
		(net "M_F_CLK_DN<2>")
	)
	(segment
		(start 257.599942 -150.974552)
		(end 257.789426 -150.785068)
		(width 0.1651)
		(layer "B.Cu")
		(net "M_F_CLK_DN<2>")
	)
	(segment
		(start 257.60045 -152.078436)
		(end 257.599942 -152.078182)
		(width 0.1651)
		(layer "B.Cu")
		(net "M_F_CLK_DN<2>")
	)
	(segment
		(start 257.599942 -152.078182)
		(end 257.599942 -150.974552)
		(width 0.1651)
		(layer "B.Cu")
		(net "M_F_CLK_DN<2>")
	)
	(segment
		(start 257.638296 -103.65613)
		(end 257.94208 -103.959914)
		(width 0.14224)
		(layer "In2.Cu")
		(net "M_F_CLK_DN<2>")
	)
	(segment
		(start 258.98348 -139.4206)
		(end 259.47116 -139.90828)
		(width 0.14224)
		(layer "In2.Cu")
		(net "M_F_CLK_DN<2>")
	)
	(segment
		(start 258.65836 -133.44144)
		(end 258.98348 -133.76656)
		(width 0.14224)
		(layer "In2.Cu")
		(net "M_F_CLK_DN<2>")
	)
	(segment
		(start 257.07467 -93.72854)
		(end 257.367786 -93.55963)
		(width 0.0889)
		(layer "In2.Cu")
		(net "M_F_CLK_DN<2>")
	)
	(segment
		(start 257.431032 -99.489514)
		(end 257.4798 -99.582224)
		(width 0.0889)
		(layer "In2.Cu")
		(net "M_F_CLK_DN<2>")
	)
	(segment
		(start 258.98348 -133.76656)
		(end 258.98348 -139.4206)
		(width 0.14224)
		(layer "In2.Cu")
		(net "M_F_CLK_DN<2>")
	)
	(segment
		(start 257.407664 -99.448874)
		(end 257.41122 -99.454716)
		(width 0.0889)
		(layer "In2.Cu")
		(net "M_F_CLK_DN<2>")
	)
	(segment
		(start 257.41503 -95.49892)
		(end 257.42138 -95.509588)
		(width 0.0889)
		(layer "In2.Cu")
		(net "M_F_CLK_DN<2>")
	)
	(segment
		(start 257.408934 -98.46056)
		(end 257.431286 -98.499168)
		(width 0.0889)
		(layer "In2.Cu")
		(net "M_F_CLK_DN<2>")
	)
	(segment
		(start 258.98348 -142.18412)
		(end 258.98348 -145.951702)
		(width 0.14224)
		(layer "In2.Cu")
		(net "M_F_CLK_DN<2>")
	)
	(segment
		(start 259.47116 -139.90828)
		(end 259.47116 -141.69644)
		(width 0.14224)
		(layer "In2.Cu")
		(net "M_F_CLK_DN<2>")
	)
	(segment
		(start 257.41503 -97.48012)
		(end 257.428492 -97.50298)
		(width 0.0889)
		(layer "In2.Cu")
		(net "M_F_CLK_DN<2>")
	)
	(segment
		(start 257.49631 -151.078184)
		(end 257.789426 -150.785068)
		(width 0.14224)
		(layer "In2.Cu")
		(net "M_F_CLK_DN<2>")
	)
	(segment
		(start 256.408174 -151.947372)
		(end 256.96164 -151.947372)
		(width 0.14224)
		(layer "In2.Cu")
		(net "M_F_CLK_DN<2>")
	)
	(segment
		(start 257.586734 -147.348448)
		(end 256.70002 -147.348448)
		(width 0.14224)
		(layer "In2.Cu")
		(net "M_F_CLK_DN<2>")
	)
	(segment
		(start 257.684016 -100.49891)
		(end 257.684016 -101.878638)
		(width 0.0889)
		(layer "In2.Cu")
		(net "M_F_CLK_DN<2>")
	)
	(segment
		(start 257.638296 -101.924358)
		(end 257.638296 -103.65613)
		(width 0.14224)
		(layer "In2.Cu")
		(net "M_F_CLK_DN<2>")
	)
	(segment
		(start 257.41122 -99.454716)
		(end 257.431032 -99.489514)
		(width 0.0889)
		(layer "In2.Cu")
		(net "M_F_CLK_DN<2>")
	)
	(segment
		(start 257.41503 -96.48952)
		(end 257.42138 -96.500188)
		(width 0.0889)
		(layer "In2.Cu")
		(net "M_F_CLK_DN<2>")
	)
	(segment
		(start 257.684016 -101.878638)
		(end 257.638296 -101.924358)
		(width 0.0889)
		(layer "In2.Cu")
		(net "M_F_CLK_DN<2>")
	)
	(segment
		(start 257.4798 -100.294694)
		(end 257.684016 -100.49891)
		(width 0.0889)
		(layer "In2.Cu")
		(net "M_F_CLK_DN<2>")
	)
	(segment
		(start 257.94208 -126.869952)
		(end 258.65836 -127.586232)
		(width 0.14224)
		(layer "In2.Cu")
		(net "M_F_CLK_DN<2>")
	)
	(segment
		(start 257.49631 -151.412702)
		(end 257.49631 -151.078184)
		(width 0.14224)
		(layer "In2.Cu")
		(net "M_F_CLK_DN<2>")
	)
	(segment
		(start 257.4798 -99.582224)
		(end 257.4798 -100.294694)
		(width 0.0889)
		(layer "In2.Cu")
		(net "M_F_CLK_DN<2>")
	)
	(segment
		(start 259.47116 -141.69644)
		(end 258.98348 -142.18412)
		(width 0.14224)
		(layer "In2.Cu")
		(net "M_F_CLK_DN<2>")
	)
	(segment
		(start 257.42138 -96.500188)
		(end 257.426206 -96.508824)
		(width 0.0889)
		(layer "In2.Cu")
		(net "M_F_CLK_DN<2>")
	)
	(segment
		(start 256.96164 -151.947372)
		(end 257.49631 -151.412702)
		(width 0.14224)
		(layer "In2.Cu")
		(net "M_F_CLK_DN<2>")
	)
	(segment
		(start 258.98348 -145.951702)
		(end 257.586734 -147.348448)
		(width 0.14224)
		(layer "In2.Cu")
		(net "M_F_CLK_DN<2>")
	)
	(segment
		(start 257.94208 -103.959914)
		(end 257.94208 -126.869952)
		(width 0.14224)
		(layer "In2.Cu")
		(net "M_F_CLK_DN<2>")
	)
	(segment
		(start 257.42138 -93.928438)
		(end 257.41503 -93.939106)
		(width 0.0889)
		(layer "In2.Cu")
		(net "M_F_CLK_DN<2>")
	)
	(segment
		(start 257.367786 -93.55963)
		(end 257.446526 -93.580966)
		(width 0.0889)
		(layer "In2.Cu")
		(net "M_F_CLK_DN<2>")
	)
	(segment
		(start 256.123694 -151.662892)
		(end 256.408174 -151.947372)
		(width 0.14224)
		(layer "In2.Cu")
		(net "M_F_CLK_DN<2>")
	)
	(segment
		(start 256.123694 -147.924774)
		(end 256.123694 -151.662892)
		(width 0.14224)
		(layer "In2.Cu")
		(net "M_F_CLK_DN<2>")
	)
	(segment
		(start 257.42138 -94.518988)
		(end 257.426206 -94.527624)
		(width 0.0889)
		(layer "In2.Cu")
		(net "M_F_CLK_DN<2>")
	)
	(segment
		(start 257.42138 -95.509588)
		(end 257.426206 -95.518224)
		(width 0.0889)
		(layer "In2.Cu")
		(net "M_F_CLK_DN<2>")
	)
	(segment
		(start 256.70002 -147.348448)
		(end 256.123694 -147.924774)
		(width 0.14224)
		(layer "In2.Cu")
		(net "M_F_CLK_DN<2>")
	)
	(segment
		(start 258.65836 -127.586232)
		(end 258.65836 -133.44144)
		(width 0.14224)
		(layer "In2.Cu")
		(net "M_F_CLK_DN<2>")
	)
	(arc
		(start 257.446526 -93.580966)
		(mid 257.467465 -93.65267)
		(end 257.47472 -93.727016)
		(width 0.0889)
		(layer "In2.Cu")
		(net "M_F_CLK_DN<2>")
	)
	(arc
		(start 257.426206 -95.518224)
		(mid 257.474961 -95.714576)
		(end 257.42138 -95.909638)
		(width 0.0889)
		(layer "In2.Cu")
		(net "M_F_CLK_DN<2>")
	)
	(arc
		(start 257.42138 -96.900238)
		(mid 257.342158 -97.189356)
		(end 257.41503 -97.48012)
		(width 0.0889)
		(layer "In2.Cu")
		(net "M_F_CLK_DN<2>")
	)
	(arc
		(start 257.42138 -95.909638)
		(mid 257.342158 -96.198756)
		(end 257.41503 -96.48952)
		(width 0.0889)
		(layer "In2.Cu")
		(net "M_F_CLK_DN<2>")
	)
	(arc
		(start 257.42138 -98.881692)
		(mid 257.342041 -99.163534)
		(end 257.407664 -99.448874)
		(width 0.0889)
		(layer "In2.Cu")
		(net "M_F_CLK_DN<2>")
	)
	(arc
		(start 257.426206 -94.527624)
		(mid 257.474961 -94.723976)
		(end 257.42138 -94.919038)
		(width 0.0889)
		(layer "In2.Cu")
		(net "M_F_CLK_DN<2>")
	)
	(arc
		(start 257.47472 -93.727016)
		(mid 257.461388 -93.83126)
		(end 257.42138 -93.928438)
		(width 0.0889)
		(layer "In2.Cu")
		(net "M_F_CLK_DN<2>")
	)
	(arc
		(start 257.426206 -96.508824)
		(mid 257.474961 -96.705176)
		(end 257.42138 -96.900238)
		(width 0.0889)
		(layer "In2.Cu")
		(net "M_F_CLK_DN<2>")
	)
	(arc
		(start 257.42138 -97.891092)
		(mid 257.342011 -98.174241)
		(end 257.408934 -98.46056)
		(width 0.0889)
		(layer "In2.Cu")
		(net "M_F_CLK_DN<2>")
	)
	(arc
		(start 257.41503 -93.939106)
		(mid 257.342232 -94.229869)
		(end 257.42138 -94.518988)
		(width 0.0889)
		(layer "In2.Cu")
		(net "M_F_CLK_DN<2>")
	)
	(arc
		(start 257.431286 -98.499168)
		(mid 257.474962 -98.691685)
		(end 257.42138 -98.881692)
		(width 0.0889)
		(layer "In2.Cu")
		(net "M_F_CLK_DN<2>")
	)
	(arc
		(start 257.42138 -94.919038)
		(mid 257.342158 -95.208156)
		(end 257.41503 -95.49892)
		(width 0.0889)
		(layer "In2.Cu")
		(net "M_F_CLK_DN<2>")
	)
	(arc
		(start 257.428492 -97.50298)
		(mid 257.475133 -97.697964)
		(end 257.42138 -97.891092)
		(width 0.0889)
		(layer "In2.Cu")
		(net "M_F_CLK_DN<2>")
	)
	(segment
		(start 257.599942 -152.278842)
		(end 257.599942 -153.571956)
		(width 0.1651)
		(layer "F.Cu")
		(net "M_F_CLK_DN<0>")
	)
	(segment
		(start 259.36321 -93.72854)
		(end 258.79171 -93.72854)
		(width 0.1016)
		(layer "F.Cu")
		(net "M_F_CLK_DN<0>")
	)
	(segment
		(start 257.60045 -152.273)
		(end 257.599942 -152.278842)
		(width 0.1651)
		(layer "F.Cu")
		(net "M_F_CLK_DN<0>")
	)
	(via
		(at 258.79171 -93.72854)
		(size 0.508)
		(drill 0.254)
		(layers "F.Cu" "B.Cu")
		(net "M_F_CLK_DN<0>")
	)
	(via
		(at 257.599942 -153.571956)
		(size 0.508)
		(drill 0.254)
		(layers "F.Cu" "B.Cu")
		(net "M_F_CLK_DN<0>")
	)
	(segment
		(start 259.13207 -97.48012)
		(end 259.13842 -97.490788)
		(width 0.0889)
		(layer "In2.Cu")
		(net "M_F_CLK_DN<0>")
	)
	(segment
		(start 259.369814 -152.925526)
		(end 260.038088 -152.925526)
		(width 0.14224)
		(layer "In2.Cu")
		(net "M_F_CLK_DN<0>")
	)
	(segment
		(start 260.841998 -151.570182)
		(end 259.37464 -151.570182)
		(width 0.14224)
		(layer "In2.Cu")
		(net "M_F_CLK_DN<0>")
	)
	(segment
		(start 259.61848 -126.046992)
		(end 260.682232 -127.110744)
		(width 0.14224)
		(layer "In2.Cu")
		(net "M_F_CLK_DN<0>")
	)
	(segment
		(start 259.288026 -151.483568)
		(end 258.823206 -151.483568)
		(width 0.14224)
		(layer "In2.Cu")
		(net "M_F_CLK_DN<0>")
	)
	(segment
		(start 261.164578 -151.247602)
		(end 260.841998 -151.570182)
		(width 0.14224)
		(layer "In2.Cu")
		(net "M_F_CLK_DN<0>")
	)
	(segment
		(start 261.050786 -135.843518)
		(end 261.050786 -136.308338)
		(width 0.14224)
		(layer "In2.Cu")
		(net "M_F_CLK_DN<0>")
	)
	(segment
		(start 259.13842 -95.509588)
		(end 259.143246 -95.518224)
		(width 0.0889)
		(layer "In2.Cu")
		(net "M_F_CLK_DN<0>")
	)
	(segment
		(start 257.298444 -154.163776)
		(end 257.298444 -153.873454)
		(width 0.14224)
		(layer "In2.Cu")
		(net "M_F_CLK_DN<0>")
	)
	(segment
		(start 260.038088 -152.925526)
		(end 260.307836 -153.195274)
		(width 0.14224)
		(layer "In2.Cu")
		(net "M_F_CLK_DN<0>")
	)
	(segment
		(start 261.050786 -132.836666)
		(end 261.164578 -132.950458)
		(width 0.14224)
		(layer "In2.Cu")
		(net "M_F_CLK_DN<0>")
	)
	(segment
		(start 259.33908 -102.969314)
		(end 259.61848 -103.248714)
		(width 0.14224)
		(layer "In2.Cu")
		(net "M_F_CLK_DN<0>")
	)
	(segment
		(start 260.005068 -154.398726)
		(end 258.968748 -154.398726)
		(width 0.14224)
		(layer "In2.Cu")
		(net "M_F_CLK_DN<0>")
	)
	(segment
		(start 259.13842 -96.500188)
		(end 259.143246 -96.508824)
		(width 0.0889)
		(layer "In2.Cu")
		(net "M_F_CLK_DN<0>")
	)
	(segment
		(start 259.084826 -93.55963)
		(end 259.163566 -93.580966)
		(width 0.0889)
		(layer "In2.Cu")
		(net "M_F_CLK_DN<0>")
	)
	(segment
		(start 257.533394 -154.398726)
		(end 257.298444 -154.163776)
		(width 0.14224)
		(layer "In2.Cu")
		(net "M_F_CLK_DN<0>")
	)
	(segment
		(start 261.164578 -133.415278)
		(end 261.050786 -133.52907)
		(width 0.14224)
		(layer "In2.Cu")
		(net "M_F_CLK_DN<0>")
	)
	(segment
		(start 259.13842 -98.481388)
		(end 259.143246 -98.490024)
		(width 0.0889)
		(layer "In2.Cu")
		(net "M_F_CLK_DN<0>")
	)
	(segment
		(start 261.164578 -149.625558)
		(end 261.164578 -150.090378)
		(width 0.14224)
		(layer "In2.Cu")
		(net "M_F_CLK_DN<0>")
	)
	(segment
		(start 261.164578 -132.950458)
		(end 261.164578 -133.415278)
		(width 0.14224)
		(layer "In2.Cu")
		(net "M_F_CLK_DN<0>")
	)
	(segment
		(start 259.13207 -96.48952)
		(end 259.13842 -96.500188)
		(width 0.0889)
		(layer "In2.Cu")
		(net "M_F_CLK_DN<0>")
	)
	(segment
		(start 260.682232 -127.110744)
		(end 260.682232 -129.764536)
		(width 0.14224)
		(layer "In2.Cu")
		(net "M_F_CLK_DN<0>")
	)
	(segment
		(start 260.307836 -154.095958)
		(end 260.005068 -154.398726)
		(width 0.14224)
		(layer "In2.Cu")
		(net "M_F_CLK_DN<0>")
	)
	(segment
		(start 261.164578 -134.572502)
		(end 261.050786 -134.686294)
		(width 0.14224)
		(layer "In2.Cu")
		(net "M_F_CLK_DN<0>")
	)
	(segment
		(start 261.050786 -150.20417)
		(end 261.050786 -150.66899)
		(width 0.14224)
		(layer "In2.Cu")
		(net "M_F_CLK_DN<0>")
	)
	(segment
		(start 261.164578 -148.933154)
		(end 261.050786 -149.046946)
		(width 0.14224)
		(layer "In2.Cu")
		(net "M_F_CLK_DN<0>")
	)
	(segment
		(start 259.13207 -95.49892)
		(end 259.13842 -95.509588)
		(width 0.0889)
		(layer "In2.Cu")
		(net "M_F_CLK_DN<0>")
	)
	(segment
		(start 257.927094 -151.88311)
		(end 257.927094 -152.612598)
		(width 0.14224)
		(layer "In2.Cu")
		(net "M_F_CLK_DN<0>")
	)
	(segment
		(start 259.154676 -99.49942)
		(end 259.15493 -99.49942)
		(width 0.0889)
		(layer "In2.Cu")
		(net "M_F_CLK_DN<0>")
	)
	(segment
		(start 259.61848 -103.248714)
		(end 259.61848 -126.046992)
		(width 0.14224)
		(layer "In2.Cu")
		(net "M_F_CLK_DN<0>")
	)
	(segment
		(start 258.818634 -153.011886)
		(end 259.283454 -153.011886)
		(width 0.14224)
		(layer "In2.Cu")
		(net "M_F_CLK_DN<0>")
	)
	(segment
		(start 261.164578 -135.264906)
		(end 261.164578 -135.729726)
		(width 0.14224)
		(layer "In2.Cu")
		(net "M_F_CLK_DN<0>")
	)
	(segment
		(start 258.736592 -151.570182)
		(end 258.240022 -151.570182)
		(width 0.14224)
		(layer "In2.Cu")
		(net "M_F_CLK_DN<0>")
	)
	(segment
		(start 261.050786 -135.151114)
		(end 261.164578 -135.264906)
		(width 0.14224)
		(layer "In2.Cu")
		(net "M_F_CLK_DN<0>")
	)
	(segment
		(start 257.298444 -153.873454)
		(end 257.599942 -153.571956)
		(width 0.14224)
		(layer "In2.Cu")
		(net "M_F_CLK_DN<0>")
	)
	(segment
		(start 258.79171 -93.72854)
		(end 259.084826 -93.55963)
		(width 0.0889)
		(layer "In2.Cu")
		(net "M_F_CLK_DN<0>")
	)
	(segment
		(start 261.164578 -130.246882)
		(end 261.164578 -132.258054)
		(width 0.14224)
		(layer "In2.Cu")
		(net "M_F_CLK_DN<0>")
	)
	(segment
		(start 258.8641 -154.294078)
		(end 258.39928 -154.294078)
		(width 0.14224)
		(layer "In2.Cu")
		(net "M_F_CLK_DN<0>")
	)
	(segment
		(start 261.050786 -146.015964)
		(end 261.164578 -146.129756)
		(width 0.14224)
		(layer "In2.Cu")
		(net "M_F_CLK_DN<0>")
	)
	(segment
		(start 259.37464 -151.570182)
		(end 259.288026 -151.483568)
		(width 0.14224)
		(layer "In2.Cu")
		(net "M_F_CLK_DN<0>")
	)
	(segment
		(start 258.294632 -154.398726)
		(end 257.533394 -154.398726)
		(width 0.14224)
		(layer "In2.Cu")
		(net "M_F_CLK_DN<0>")
	)
	(segment
		(start 261.050786 -149.046946)
		(end 261.050786 -149.511766)
		(width 0.14224)
		(layer "In2.Cu")
		(net "M_F_CLK_DN<0>")
	)
	(segment
		(start 259.13207 -98.47072)
		(end 259.13842 -98.481388)
		(width 0.0889)
		(layer "In2.Cu")
		(net "M_F_CLK_DN<0>")
	)
	(segment
		(start 259.39242 -100.454714)
		(end 259.39242 -101.897434)
		(width 0.0889)
		(layer "In2.Cu")
		(net "M_F_CLK_DN<0>")
	)
	(segment
		(start 261.164578 -136.42213)
		(end 261.164578 -145.437352)
		(width 0.14224)
		(layer "In2.Cu")
		(net "M_F_CLK_DN<0>")
	)
	(segment
		(start 259.2705 -99.677474)
		(end 259.2705 -100.332794)
		(width 0.0889)
		(layer "In2.Cu")
		(net "M_F_CLK_DN<0>")
	)
	(segment
		(start 259.2705 -100.332794)
		(end 259.39242 -100.454714)
		(width 0.0889)
		(layer "In2.Cu")
		(net "M_F_CLK_DN<0>")
	)
	(segment
		(start 259.39242 -101.897434)
		(end 259.33908 -101.950774)
		(width 0.0889)
		(layer "In2.Cu")
		(net "M_F_CLK_DN<0>")
	)
	(segment
		(start 261.164578 -146.129756)
		(end 261.164578 -148.933154)
		(width 0.14224)
		(layer "In2.Cu")
		(net "M_F_CLK_DN<0>")
	)
	(segment
		(start 258.732274 -152.925526)
		(end 258.818634 -153.011886)
		(width 0.14224)
		(layer "In2.Cu")
		(net "M_F_CLK_DN<0>")
	)
	(segment
		(start 261.050786 -132.371846)
		(end 261.050786 -132.836666)
		(width 0.14224)
		(layer "In2.Cu")
		(net "M_F_CLK_DN<0>")
	)
	(segment
		(start 261.050786 -150.66899)
		(end 261.164578 -150.782782)
		(width 0.14224)
		(layer "In2.Cu")
		(net "M_F_CLK_DN<0>")
	)
	(segment
		(start 261.164578 -150.782782)
		(end 261.164578 -151.247602)
		(width 0.14224)
		(layer "In2.Cu")
		(net "M_F_CLK_DN<0>")
	)
	(segment
		(start 259.283454 -153.011886)
		(end 259.369814 -152.925526)
		(width 0.14224)
		(layer "In2.Cu")
		(net "M_F_CLK_DN<0>")
	)
	(segment
		(start 261.050786 -133.99389)
		(end 261.164578 -134.107682)
		(width 0.14224)
		(layer "In2.Cu")
		(net "M_F_CLK_DN<0>")
	)
	(segment
		(start 257.927094 -152.612598)
		(end 258.240022 -152.925526)
		(width 0.14224)
		(layer "In2.Cu")
		(net "M_F_CLK_DN<0>")
	)
	(segment
		(start 261.164578 -145.437352)
		(end 261.050786 -145.551144)
		(width 0.14224)
		(layer "In2.Cu")
		(net "M_F_CLK_DN<0>")
	)
	(segment
		(start 261.050786 -133.52907)
		(end 261.050786 -133.99389)
		(width 0.14224)
		(layer "In2.Cu")
		(net "M_F_CLK_DN<0>")
	)
	(segment
		(start 258.823206 -151.483568)
		(end 258.736592 -151.570182)
		(width 0.14224)
		(layer "In2.Cu")
		(net "M_F_CLK_DN<0>")
	)
	(segment
		(start 260.307836 -153.195274)
		(end 260.307836 -154.095958)
		(width 0.14224)
		(layer "In2.Cu")
		(net "M_F_CLK_DN<0>")
	)
	(segment
		(start 258.240022 -152.925526)
		(end 258.732274 -152.925526)
		(width 0.14224)
		(layer "In2.Cu")
		(net "M_F_CLK_DN<0>")
	)
	(segment
		(start 259.13842 -94.518988)
		(end 259.143246 -94.527624)
		(width 0.0889)
		(layer "In2.Cu")
		(net "M_F_CLK_DN<0>")
	)
	(segment
		(start 258.240022 -151.570182)
		(end 257.927094 -151.88311)
		(width 0.14224)
		(layer "In2.Cu")
		(net "M_F_CLK_DN<0>")
	)
	(segment
		(start 260.682232 -129.764536)
		(end 261.164578 -130.246882)
		(width 0.14224)
		(layer "In2.Cu")
		(net "M_F_CLK_DN<0>")
	)
	(segment
		(start 259.13842 -93.928438)
		(end 259.13207 -93.939106)
		(width 0.0889)
		(layer "In2.Cu")
		(net "M_F_CLK_DN<0>")
	)
	(segment
		(start 261.050786 -149.511766)
		(end 261.164578 -149.625558)
		(width 0.14224)
		(layer "In2.Cu")
		(net "M_F_CLK_DN<0>")
	)
	(segment
		(start 259.15493 -99.49942)
		(end 259.2705 -99.677474)
		(width 0.0889)
		(layer "In2.Cu")
		(net "M_F_CLK_DN<0>")
	)
	(segment
		(start 261.164578 -135.729726)
		(end 261.050786 -135.843518)
		(width 0.14224)
		(layer "In2.Cu")
		(net "M_F_CLK_DN<0>")
	)
	(segment
		(start 258.39928 -154.294078)
		(end 258.294632 -154.398726)
		(width 0.14224)
		(layer "In2.Cu")
		(net "M_F_CLK_DN<0>")
	)
	(segment
		(start 261.164578 -132.258054)
		(end 261.050786 -132.371846)
		(width 0.14224)
		(layer "In2.Cu")
		(net "M_F_CLK_DN<0>")
	)
	(segment
		(start 259.13842 -97.490788)
		(end 259.143246 -97.499424)
		(width 0.0889)
		(layer "In2.Cu")
		(net "M_F_CLK_DN<0>")
	)
	(segment
		(start 261.164578 -150.090378)
		(end 261.050786 -150.20417)
		(width 0.14224)
		(layer "In2.Cu")
		(net "M_F_CLK_DN<0>")
	)
	(segment
		(start 258.968748 -154.398726)
		(end 258.8641 -154.294078)
		(width 0.14224)
		(layer "In2.Cu")
		(net "M_F_CLK_DN<0>")
	)
	(segment
		(start 261.164578 -134.107682)
		(end 261.164578 -134.572502)
		(width 0.14224)
		(layer "In2.Cu")
		(net "M_F_CLK_DN<0>")
	)
	(segment
		(start 261.050786 -134.686294)
		(end 261.050786 -135.151114)
		(width 0.14224)
		(layer "In2.Cu")
		(net "M_F_CLK_DN<0>")
	)
	(segment
		(start 259.33908 -101.950774)
		(end 259.33908 -102.969314)
		(width 0.14224)
		(layer "In2.Cu")
		(net "M_F_CLK_DN<0>")
	)
	(segment
		(start 261.050786 -136.308338)
		(end 261.164578 -136.42213)
		(width 0.14224)
		(layer "In2.Cu")
		(net "M_F_CLK_DN<0>")
	)
	(segment
		(start 261.050786 -145.551144)
		(end 261.050786 -146.015964)
		(width 0.14224)
		(layer "In2.Cu")
		(net "M_F_CLK_DN<0>")
	)
	(arc
		(start 259.13842 -97.890838)
		(mid 259.059198 -98.179956)
		(end 259.13207 -98.47072)
		(width 0.0889)
		(layer "In2.Cu")
		(net "M_F_CLK_DN<0>")
	)
	(arc
		(start 259.19176 -93.728032)
		(mid 259.178294 -93.83175)
		(end 259.13842 -93.928438)
		(width 0.0889)
		(layer "In2.Cu")
		(net "M_F_CLK_DN<0>")
	)
	(arc
		(start 259.143246 -97.499424)
		(mid 259.192001 -97.695776)
		(end 259.13842 -97.890838)
		(width 0.0889)
		(layer "In2.Cu")
		(net "M_F_CLK_DN<0>")
	)
	(arc
		(start 259.13842 -96.900238)
		(mid 259.059198 -97.189356)
		(end 259.13207 -97.48012)
		(width 0.0889)
		(layer "In2.Cu")
		(net "M_F_CLK_DN<0>")
	)
	(arc
		(start 259.13842 -95.909638)
		(mid 259.059198 -96.198756)
		(end 259.13207 -96.48952)
		(width 0.0889)
		(layer "In2.Cu")
		(net "M_F_CLK_DN<0>")
	)
	(arc
		(start 259.143246 -98.490024)
		(mid 259.192001 -98.686376)
		(end 259.13842 -98.881438)
		(width 0.0889)
		(layer "In2.Cu")
		(net "M_F_CLK_DN<0>")
	)
	(arc
		(start 259.13842 -94.919038)
		(mid 259.059198 -95.208156)
		(end 259.13207 -95.49892)
		(width 0.0889)
		(layer "In2.Cu")
		(net "M_F_CLK_DN<0>")
	)
	(arc
		(start 259.13207 -93.939106)
		(mid 259.059272 -94.229869)
		(end 259.13842 -94.518988)
		(width 0.0889)
		(layer "In2.Cu")
		(net "M_F_CLK_DN<0>")
	)
	(arc
		(start 259.163566 -93.580966)
		(mid 259.184601 -93.653169)
		(end 259.19176 -93.728032)
		(width 0.0889)
		(layer "In2.Cu")
		(net "M_F_CLK_DN<0>")
	)
	(arc
		(start 259.143246 -96.508824)
		(mid 259.192001 -96.705176)
		(end 259.13842 -96.900238)
		(width 0.0889)
		(layer "In2.Cu")
		(net "M_F_CLK_DN<0>")
	)
	(arc
		(start 259.143246 -95.518224)
		(mid 259.192001 -95.714576)
		(end 259.13842 -95.909638)
		(width 0.0889)
		(layer "In2.Cu")
		(net "M_F_CLK_DN<0>")
	)
	(arc
		(start 259.13842 -98.881438)
		(mid 259.059436 -99.19271)
		(end 259.154676 -99.49942)
		(width 0.0889)
		(layer "In2.Cu")
		(net "M_F_CLK_DN<0>")
	)
	(arc
		(start 259.143246 -94.527624)
		(mid 259.192001 -94.723976)
		(end 259.13842 -94.919038)
		(width 0.0889)
		(layer "In2.Cu")
		(net "M_F_CLK_DN<0>")
	)
	(segment
		(start 252.495304 -91.747086)
		(end 251.923804 -91.747086)
		(width 0.1016)
		(layer "F.Cu")
		(net "M_F_CKE<3>")
	)
	(via
		(at 243.999766 -148.771356)
		(size 0.4572)
		(drill 0.2032)
		(layers "F.Cu" "B.Cu")
		(net "M_F_CKE<3>")
	)
	(via
		(at 251.923804 -91.747086)
		(size 0.508)
		(drill 0.254)
		(layers "F.Cu" "B.Cu")
		(net "M_F_CKE<3>")
	)
	(segment
		(start 244.000274 -147.478496)
		(end 243.999766 -147.478496)
		(width 0.1651)
		(layer "B.Cu")
		(net "M_F_CKE<3>")
	)
	(segment
		(start 243.999766 -147.478496)
		(end 243.999766 -148.771356)
		(width 0.1651)
		(layer "B.Cu")
		(net "M_F_CKE<3>")
	)
	(segment
		(start 251.3076 -121.3866)
		(end 245.237 -127.4572)
		(width 0.14224)
		(layer "In2.Cu")
		(net "M_F_CKE<3>")
	)
	(segment
		(start 245.28653 -146.538188)
		(end 243.999766 -147.824952)
		(width 0.14224)
		(layer "In2.Cu")
		(net "M_F_CKE<3>")
	)
	(segment
		(start 251.577094 -96.500188)
		(end 251.572268 -96.508824)
		(width 0.0889)
		(layer "In2.Cu")
		(net "M_F_CKE<3>")
	)
	(segment
		(start 251.583444 -98.47072)
		(end 251.577094 -98.481388)
		(width 0.0889)
		(layer "In2.Cu")
		(net "M_F_CKE<3>")
	)
	(segment
		(start 245.237 -129.8448)
		(end 245.3132 -129.921)
		(width 0.14224)
		(layer "In2.Cu")
		(net "M_F_CKE<3>")
	)
	(segment
		(start 251.4346 -99.2886)
		(end 251.4346 -101.131116)
		(width 0.0889)
		(layer "In2.Cu")
		(net "M_F_CKE<3>")
	)
	(segment
		(start 251.923804 -91.747086)
		(end 251.594366 -92.50807)
		(width 0.0889)
		(layer "In2.Cu")
		(net "M_F_CKE<3>")
	)
	(segment
		(start 251.498862 -98.754438)
		(end 251.498862 -99.224338)
		(width 0.0889)
		(layer "In2.Cu")
		(net "M_F_CKE<3>")
	)
	(segment
		(start 251.583444 -96.48952)
		(end 251.577094 -96.500188)
		(width 0.0889)
		(layer "In2.Cu")
		(net "M_F_CKE<3>")
	)
	(segment
		(start 251.4346 -101.131116)
		(end 251.3076 -101.258116)
		(width 0.0889)
		(layer "In2.Cu")
		(net "M_F_CKE<3>")
	)
	(segment
		(start 245.1608 -131.1148)
		(end 245.364 -131.318)
		(width 0.14224)
		(layer "In2.Cu")
		(net "M_F_CKE<3>")
	)
	(segment
		(start 245.264178 -134.697978)
		(end 245.364 -134.7978)
		(width 0.14224)
		(layer "In2.Cu")
		(net "M_F_CKE<3>")
	)
	(segment
		(start 243.999766 -147.824952)
		(end 243.999766 -148.771356)
		(width 0.14224)
		(layer "In2.Cu")
		(net "M_F_CKE<3>")
	)
	(segment
		(start 245.264178 -144.349978)
		(end 245.28653 -144.37233)
		(width 0.14224)
		(layer "In2.Cu")
		(net "M_F_CKE<3>")
	)
	(segment
		(start 245.28653 -140.20927)
		(end 245.264178 -140.231622)
		(width 0.14224)
		(layer "In2.Cu")
		(net "M_F_CKE<3>")
	)
	(segment
		(start 251.583444 -97.48012)
		(end 251.577094 -97.490788)
		(width 0.0889)
		(layer "In2.Cu")
		(net "M_F_CKE<3>")
	)
	(segment
		(start 251.583444 -95.49892)
		(end 251.577094 -95.509588)
		(width 0.0889)
		(layer "In2.Cu")
		(net "M_F_CKE<3>")
	)
	(segment
		(start 251.3076 -101.500178)
		(end 251.3076 -121.3866)
		(width 0.14224)
		(layer "In2.Cu")
		(net "M_F_CKE<3>")
	)
	(segment
		(start 245.264178 -140.231622)
		(end 245.264178 -144.349978)
		(width 0.14224)
		(layer "In2.Cu")
		(net "M_F_CKE<3>")
	)
	(segment
		(start 251.498862 -99.224338)
		(end 251.4346 -99.2886)
		(width 0.0889)
		(layer "In2.Cu")
		(net "M_F_CKE<3>")
	)
	(segment
		(start 251.577094 -93.928438)
		(end 251.583444 -93.939106)
		(width 0.0889)
		(layer "In2.Cu")
		(net "M_F_CKE<3>")
	)
	(segment
		(start 251.594366 -92.50807)
		(end 251.572268 -92.546424)
		(width 0.0889)
		(layer "In2.Cu")
		(net "M_F_CKE<3>")
	)
	(segment
		(start 245.1608 -130.6576)
		(end 245.1608 -131.1148)
		(width 0.14224)
		(layer "In2.Cu")
		(net "M_F_CKE<3>")
	)
	(segment
		(start 245.3132 -130.5052)
		(end 245.1608 -130.6576)
		(width 0.14224)
		(layer "In2.Cu")
		(net "M_F_CKE<3>")
	)
	(segment
		(start 245.364 -131.8514)
		(end 245.264178 -131.951222)
		(width 0.14224)
		(layer "In2.Cu")
		(net "M_F_CKE<3>")
	)
	(segment
		(start 245.237 -127.4572)
		(end 245.237 -129.8448)
		(width 0.14224)
		(layer "In2.Cu")
		(net "M_F_CKE<3>")
	)
	(segment
		(start 251.3076 -101.258116)
		(end 251.3076 -101.500178)
		(width 0.0889)
		(layer "In2.Cu")
		(net "M_F_CKE<3>")
	)
	(segment
		(start 245.28653 -135.40867)
		(end 245.28653 -140.20927)
		(width 0.14224)
		(layer "In2.Cu")
		(net "M_F_CKE<3>")
	)
	(segment
		(start 251.577094 -94.518988)
		(end 251.572268 -94.527624)
		(width 0.0889)
		(layer "In2.Cu")
		(net "M_F_CKE<3>")
	)
	(segment
		(start 245.364 -134.7978)
		(end 245.364 -135.3312)
		(width 0.14224)
		(layer "In2.Cu")
		(net "M_F_CKE<3>")
	)
	(segment
		(start 245.264178 -131.951222)
		(end 245.264178 -134.697978)
		(width 0.14224)
		(layer "In2.Cu")
		(net "M_F_CKE<3>")
	)
	(segment
		(start 251.577094 -95.509588)
		(end 251.572268 -95.518224)
		(width 0.0889)
		(layer "In2.Cu")
		(net "M_F_CKE<3>")
	)
	(segment
		(start 245.28653 -144.37233)
		(end 245.28653 -146.538188)
		(width 0.14224)
		(layer "In2.Cu")
		(net "M_F_CKE<3>")
	)
	(segment
		(start 245.364 -135.3312)
		(end 245.28653 -135.40867)
		(width 0.14224)
		(layer "In2.Cu")
		(net "M_F_CKE<3>")
	)
	(segment
		(start 251.577094 -97.490788)
		(end 251.572268 -97.499424)
		(width 0.0889)
		(layer "In2.Cu")
		(net "M_F_CKE<3>")
	)
	(segment
		(start 245.3132 -129.921)
		(end 245.3132 -130.5052)
		(width 0.14224)
		(layer "In2.Cu")
		(net "M_F_CKE<3>")
	)
	(segment
		(start 245.364 -131.318)
		(end 245.364 -131.8514)
		(width 0.14224)
		(layer "In2.Cu")
		(net "M_F_CKE<3>")
	)
	(arc
		(start 251.572268 -97.499424)
		(mid 251.523513 -97.695776)
		(end 251.577094 -97.890838)
		(width 0.0889)
		(layer "In2.Cu")
		(net "M_F_CKE<3>")
	)
	(arc
		(start 251.572268 -96.508824)
		(mid 251.523513 -96.705176)
		(end 251.577094 -96.900238)
		(width 0.0889)
		(layer "In2.Cu")
		(net "M_F_CKE<3>")
	)
	(arc
		(start 251.577094 -93.528642)
		(mid 251.523595 -93.72854)
		(end 251.577094 -93.928438)
		(width 0.0889)
		(layer "In2.Cu")
		(net "M_F_CKE<3>")
	)
	(arc
		(start 251.572268 -94.527624)
		(mid 251.523513 -94.723976)
		(end 251.577094 -94.919038)
		(width 0.0889)
		(layer "In2.Cu")
		(net "M_F_CKE<3>")
	)
	(arc
		(start 251.577094 -97.890838)
		(mid 251.656316 -98.179956)
		(end 251.583444 -98.47072)
		(width 0.0889)
		(layer "In2.Cu")
		(net "M_F_CKE<3>")
	)
	(arc
		(start 251.577094 -96.900238)
		(mid 251.656316 -97.189356)
		(end 251.583444 -97.48012)
		(width 0.0889)
		(layer "In2.Cu")
		(net "M_F_CKE<3>")
	)
	(arc
		(start 251.572268 -92.546424)
		(mid 251.523513 -92.742776)
		(end 251.577094 -92.937838)
		(width 0.0889)
		(layer "In2.Cu")
		(net "M_F_CKE<3>")
	)
	(arc
		(start 251.572268 -95.518224)
		(mid 251.523513 -95.714576)
		(end 251.577094 -95.909638)
		(width 0.0889)
		(layer "In2.Cu")
		(net "M_F_CKE<3>")
	)
	(arc
		(start 251.583444 -93.939106)
		(mid 251.656242 -94.229869)
		(end 251.577094 -94.518988)
		(width 0.0889)
		(layer "In2.Cu")
		(net "M_F_CKE<3>")
	)
	(arc
		(start 251.577094 -95.909638)
		(mid 251.656316 -96.198756)
		(end 251.583444 -96.48952)
		(width 0.0889)
		(layer "In2.Cu")
		(net "M_F_CKE<3>")
	)
	(arc
		(start 251.577094 -94.919038)
		(mid 251.656316 -95.208156)
		(end 251.583444 -95.49892)
		(width 0.0889)
		(layer "In2.Cu")
		(net "M_F_CKE<3>")
	)
	(arc
		(start 251.577094 -98.481388)
		(mid 251.520293 -98.612846)
		(end 251.498862 -98.754438)
		(width 0.0889)
		(layer "In2.Cu")
		(net "M_F_CKE<3>")
	)
	(arc
		(start 251.577094 -92.937838)
		(mid 251.656225 -93.23324)
		(end 251.577094 -93.528642)
		(width 0.0889)
		(layer "In2.Cu")
		(net "M_F_CKE<3>")
	)
	(segment
		(start 252.495304 -93.72854)
		(end 251.923804 -93.72854)
		(width 0.1016)
		(layer "F.Cu")
		(net "M_F_CKE<2>")
	)
	(via
		(at 251.923804 -93.72854)
		(size 0.508)
		(drill 0.254)
		(layers "F.Cu" "B.Cu")
		(net "M_F_CKE<2>")
	)
	(via
		(at 244.849904 -150.788878)
		(size 0.4572)
		(drill 0.2032)
		(layers "F.Cu" "B.Cu")
		(net "M_F_CKE<2>")
	)
	(segment
		(start 244.849904 -152.078182)
		(end 244.849904 -150.788878)
		(width 0.1651)
		(layer "B.Cu")
		(net "M_F_CKE<2>")
	)
	(segment
		(start 244.850412 -152.078436)
		(end 244.849904 -152.078182)
		(width 0.1651)
		(layer "B.Cu")
		(net "M_F_CKE<2>")
	)
	(segment
		(start 252.264164 -98.47072)
		(end 252.270514 -98.481388)
		(width 0.0889)
		(layer "In2.Cu")
		(net "M_F_CKE<2>")
	)
	(segment
		(start 252.270514 -94.518988)
		(end 252.27534 -94.527624)
		(width 0.0889)
		(layer "In2.Cu")
		(net "M_F_CKE<2>")
	)
	(segment
		(start 251.8156 -121.6152)
		(end 246.1768 -127.254)
		(width 0.14224)
		(layer "In2.Cu")
		(net "M_F_CKE<2>")
	)
	(segment
		(start 244.413278 -149.87778)
		(end 244.849904 -150.314406)
		(width 0.14224)
		(layer "In2.Cu")
		(net "M_F_CKE<2>")
	)
	(segment
		(start 246.1768 -129.921)
		(end 246.0752 -130.0226)
		(width 0.14224)
		(layer "In2.Cu")
		(net "M_F_CKE<2>")
	)
	(segment
		(start 252.264164 -95.49892)
		(end 252.270514 -95.509588)
		(width 0.0889)
		(layer "In2.Cu")
		(net "M_F_CKE<2>")
	)
	(segment
		(start 252.270514 -95.509588)
		(end 252.27534 -95.518224)
		(width 0.0889)
		(layer "In2.Cu")
		(net "M_F_CKE<2>")
	)
	(segment
		(start 246.133874 -140.75029)
		(end 246.133874 -144.314926)
		(width 0.14224)
		(layer "In2.Cu")
		(net "M_F_CKE<2>")
	)
	(segment
		(start 246.13362 -132.03682)
		(end 246.13362 -134.76478)
		(width 0.14224)
		(layer "In2.Cu")
		(net "M_F_CKE<2>")
	)
	(segment
		(start 246.1768 -127.254)
		(end 246.1768 -129.921)
		(width 0.14224)
		(layer "In2.Cu")
		(net "M_F_CKE<2>")
	)
	(segment
		(start 252.264164 -97.48012)
		(end 252.270514 -97.490788)
		(width 0.0889)
		(layer "In2.Cu")
		(net "M_F_CKE<2>")
	)
	(segment
		(start 252.264164 -96.48952)
		(end 252.270514 -96.500188)
		(width 0.0889)
		(layer "In2.Cu")
		(net "M_F_CKE<2>")
	)
	(segment
		(start 246.0752 -130.0226)
		(end 246.0752 -130.5306)
		(width 0.14224)
		(layer "In2.Cu")
		(net "M_F_CKE<2>")
	)
	(segment
		(start 246.0752 -130.5306)
		(end 246.2022 -130.6576)
		(width 0.14224)
		(layer "In2.Cu")
		(net "M_F_CKE<2>")
	)
	(segment
		(start 244.413278 -148.270722)
		(end 244.413278 -149.87778)
		(width 0.14224)
		(layer "In2.Cu")
		(net "M_F_CKE<2>")
	)
	(segment
		(start 246.2022 -131.1402)
		(end 246.0498 -131.2926)
		(width 0.14224)
		(layer "In2.Cu")
		(net "M_F_CKE<2>")
	)
	(segment
		(start 246.0752 -145.6944)
		(end 246.107458 -145.726658)
		(width 0.14224)
		(layer "In2.Cu")
		(net "M_F_CKE<2>")
	)
	(segment
		(start 246.107458 -139.515342)
		(end 246.0498 -139.573)
		(width 0.14224)
		(layer "In2.Cu")
		(net "M_F_CKE<2>")
	)
	(segment
		(start 252.2982 -99.5934)
		(end 252.2982 -100.838)
		(width 0.0889)
		(layer "In2.Cu")
		(net "M_F_CKE<2>")
	)
	(segment
		(start 246.0498 -139.573)
		(end 246.0498 -140.666216)
		(width 0.14224)
		(layer "In2.Cu")
		(net "M_F_CKE<2>")
	)
	(segment
		(start 252.270514 -96.500188)
		(end 252.27534 -96.508824)
		(width 0.0889)
		(layer "In2.Cu")
		(net "M_F_CKE<2>")
	)
	(segment
		(start 246.0752 -144.3736)
		(end 246.0752 -145.6944)
		(width 0.14224)
		(layer "In2.Cu")
		(net "M_F_CKE<2>")
	)
	(segment
		(start 246.0498 -131.2926)
		(end 246.0498 -131.953)
		(width 0.14224)
		(layer "In2.Cu")
		(net "M_F_CKE<2>")
	)
	(segment
		(start 246.133874 -144.314926)
		(end 246.0752 -144.3736)
		(width 0.14224)
		(layer "In2.Cu")
		(net "M_F_CKE<2>")
	)
	(segment
		(start 246.13362 -134.76478)
		(end 246.107458 -134.790942)
		(width 0.14224)
		(layer "In2.Cu")
		(net "M_F_CKE<2>")
	)
	(segment
		(start 252.270514 -98.481388)
		(end 252.27534 -98.490024)
		(width 0.0889)
		(layer "In2.Cu")
		(net "M_F_CKE<2>")
	)
	(segment
		(start 246.0498 -131.953)
		(end 246.13362 -132.03682)
		(width 0.14224)
		(layer "In2.Cu")
		(net "M_F_CKE<2>")
	)
	(segment
		(start 251.8156 -101.571806)
		(end 251.8156 -121.6152)
		(width 0.14224)
		(layer "In2.Cu")
		(net "M_F_CKE<2>")
	)
	(segment
		(start 252.242574 -99.417886)
		(end 252.242574 -99.459034)
		(width 0.0889)
		(layer "In2.Cu")
		(net "M_F_CKE<2>")
	)
	(segment
		(start 251.8156 -101.3206)
		(end 251.8156 -101.571806)
		(width 0.0889)
		(layer "In2.Cu")
		(net "M_F_CKE<2>")
	)
	(segment
		(start 246.107458 -146.576542)
		(end 244.413278 -148.270722)
		(width 0.14224)
		(layer "In2.Cu")
		(net "M_F_CKE<2>")
	)
	(segment
		(start 246.0498 -140.666216)
		(end 246.133874 -140.75029)
		(width 0.14224)
		(layer "In2.Cu")
		(net "M_F_CKE<2>")
	)
	(segment
		(start 252.2982 -100.838)
		(end 251.8156 -101.3206)
		(width 0.0889)
		(layer "In2.Cu")
		(net "M_F_CKE<2>")
	)
	(segment
		(start 244.849904 -150.314406)
		(end 244.849904 -150.788878)
		(width 0.14224)
		(layer "In2.Cu")
		(net "M_F_CKE<2>")
	)
	(segment
		(start 246.107458 -134.790942)
		(end 246.107458 -139.515342)
		(width 0.14224)
		(layer "In2.Cu")
		(net "M_F_CKE<2>")
	)
	(segment
		(start 252.270514 -97.490788)
		(end 252.27534 -97.499424)
		(width 0.0889)
		(layer "In2.Cu")
		(net "M_F_CKE<2>")
	)
	(segment
		(start 246.2022 -130.6576)
		(end 246.2022 -131.1402)
		(width 0.14224)
		(layer "In2.Cu")
		(net "M_F_CKE<2>")
	)
	(segment
		(start 246.107458 -145.726658)
		(end 246.107458 -146.576542)
		(width 0.14224)
		(layer "In2.Cu")
		(net "M_F_CKE<2>")
	)
	(arc
		(start 252.242574 -99.459034)
		(mid 252.257036 -99.531741)
		(end 252.2982 -99.5934)
		(width 0.0889)
		(layer "In2.Cu")
		(net "M_F_CKE<2>")
	)
	(arc
		(start 252.270514 -97.890838)
		(mid 252.191292 -98.179956)
		(end 252.264164 -98.47072)
		(width 0.0889)
		(layer "In2.Cu")
		(net "M_F_CKE<2>")
	)
	(arc
		(start 252.270514 -95.909638)
		(mid 252.191292 -96.198756)
		(end 252.264164 -96.48952)
		(width 0.0889)
		(layer "In2.Cu")
		(net "M_F_CKE<2>")
	)
	(arc
		(start 252.27534 -98.490024)
		(mid 252.324095 -98.686376)
		(end 252.270514 -98.881438)
		(width 0.0889)
		(layer "In2.Cu")
		(net "M_F_CKE<2>")
	)
	(arc
		(start 252.27534 -96.508824)
		(mid 252.324095 -96.705176)
		(end 252.270514 -96.900238)
		(width 0.0889)
		(layer "In2.Cu")
		(net "M_F_CKE<2>")
	)
	(arc
		(start 252.270514 -94.919038)
		(mid 252.191292 -95.208156)
		(end 252.264164 -95.49892)
		(width 0.0889)
		(layer "In2.Cu")
		(net "M_F_CKE<2>")
	)
	(arc
		(start 252.27534 -97.499424)
		(mid 252.324095 -97.695776)
		(end 252.270514 -97.890838)
		(width 0.0889)
		(layer "In2.Cu")
		(net "M_F_CKE<2>")
	)
	(arc
		(start 252.27534 -95.518224)
		(mid 252.324095 -95.714576)
		(end 252.270514 -95.909638)
		(width 0.0889)
		(layer "In2.Cu")
		(net "M_F_CKE<2>")
	)
	(arc
		(start 252.270514 -98.881438)
		(mid 252.192058 -99.146309)
		(end 252.242574 -99.417886)
		(width 0.0889)
		(layer "In2.Cu")
		(net "M_F_CKE<2>")
	)
	(arc
		(start 251.923804 -93.72854)
		(mid 251.93582 -93.968631)
		(end 252.0442 -94.1832)
		(width 0.0889)
		(layer "In2.Cu")
		(net "M_F_CKE<2>")
	)
	(arc
		(start 252.270514 -96.900238)
		(mid 252.191292 -97.189356)
		(end 252.264164 -97.48012)
		(width 0.0889)
		(layer "In2.Cu")
		(net "M_F_CKE<2>")
	)
	(arc
		(start 252.0442 -94.1832)
		(mid 252.164375 -94.346364)
		(end 252.270514 -94.518988)
		(width 0.0889)
		(layer "In2.Cu")
		(net "M_F_CKE<2>")
	)
	(arc
		(start 252.27534 -94.527624)
		(mid 252.324095 -94.723976)
		(end 252.270514 -94.919038)
		(width 0.0889)
		(layer "In2.Cu")
		(net "M_F_CKE<2>")
	)
	(segment
		(start 243.999766 -156.87294)
		(end 244.000274 -156.87294)
		(width 0.1651)
		(layer "F.Cu")
		(net "M_F_CKE<1>")
	)
	(segment
		(start 252.495304 -90.756486)
		(end 251.923804 -90.756486)
		(width 0.1016)
		(layer "F.Cu")
		(net "M_F_CKE<1>")
	)
	(segment
		(start 243.999766 -154.905456)
		(end 243.999766 -156.87294)
		(width 0.1651)
		(layer "F.Cu")
		(net "M_F_CKE<1>")
	)
	(via
		(at 243.999766 -154.905456)
		(size 0.508)
		(drill 0.254)
		(layers "F.Cu" "B.Cu")
		(net "M_F_CKE<1>")
	)
	(via
		(at 251.923804 -90.756486)
		(size 0.508)
		(drill 0.254)
		(layers "F.Cu" "B.Cu")
		(net "M_F_CKE<1>")
	)
	(segment
		(start 250.7996 -101.520498)
		(end 250.7996 -121.1072)
		(width 0.14224)
		(layer "In2.Cu")
		(net "M_F_CKE<1>")
	)
	(segment
		(start 244.409468 -146.598132)
		(end 243.58854 -147.41906)
		(width 0.14224)
		(layer "In2.Cu")
		(net "M_F_CKE<1>")
	)
	(segment
		(start 251.346716 -91.680284)
		(end 251.346716 -91.87434)
		(width 0.0889)
		(layer "In2.Cu")
		(net "M_F_CKE<1>")
	)
	(segment
		(start 243.459 -153.7462)
		(end 243.999766 -154.286966)
		(width 0.14224)
		(layer "In2.Cu")
		(net "M_F_CKE<1>")
	)
	(segment
		(start 251.411994 -97.395538)
		(end 251.405644 -97.406206)
		(width 0.0889)
		(layer "In2.Cu")
		(net "M_F_CKE<1>")
	)
	(segment
		(start 251.2314 -100.8634)
		(end 250.7996 -101.2952)
		(width 0.0889)
		(layer "In2.Cu")
		(net "M_F_CKE<1>")
	)
	(segment
		(start 244.435884 -140.245084)
		(end 244.435884 -144.336516)
		(width 0.14224)
		(layer "In2.Cu")
		(net "M_F_CKE<1>")
	)
	(segment
		(start 244.475 -127.4318)
		(end 244.475 -129.8956)
		(width 0.14224)
		(layer "In2.Cu")
		(net "M_F_CKE<1>")
	)
	(segment
		(start 250.7996 -121.1072)
		(end 244.475 -127.4318)
		(width 0.14224)
		(layer "In2.Cu")
		(net "M_F_CKE<1>")
	)
	(segment
		(start 244.348 -131.953)
		(end 244.43944 -132.04444)
		(width 0.14224)
		(layer "In2.Cu")
		(net "M_F_CKE<1>")
	)
	(segment
		(start 243.999766 -154.286966)
		(end 243.999766 -154.905456)
		(width 0.14224)
		(layer "In2.Cu")
		(net "M_F_CKE<1>")
	)
	(segment
		(start 244.348 -131.3434)
		(end 244.348 -131.953)
		(width 0.14224)
		(layer "In2.Cu")
		(net "M_F_CKE<1>")
	)
	(segment
		(start 251.41682 -92.433902)
		(end 251.411994 -92.442538)
		(width 0.0889)
		(layer "In2.Cu")
		(net "M_F_CKE<1>")
	)
	(segment
		(start 244.5258 -135.8646)
		(end 244.413278 -135.977122)
		(width 0.14224)
		(layer "In2.Cu")
		(net "M_F_CKE<1>")
	)
	(segment
		(start 251.2822 -99.1616)
		(end 251.2314 -99.2124)
		(width 0.0889)
		(layer "In2.Cu")
		(net "M_F_CKE<1>")
	)
	(segment
		(start 244.435884 -144.336516)
		(end 244.409468 -144.362932)
		(width 0.14224)
		(layer "In2.Cu")
		(net "M_F_CKE<1>")
	)
	(segment
		(start 244.413278 -135.977122)
		(end 244.413278 -140.222478)
		(width 0.14224)
		(layer "In2.Cu")
		(net "M_F_CKE<1>")
	)
	(segment
		(start 251.41682 -96.396302)
		(end 251.411994 -96.404938)
		(width 0.0889)
		(layer "In2.Cu")
		(net "M_F_CKE<1>")
	)
	(segment
		(start 251.41682 -97.386902)
		(end 251.411994 -97.395538)
		(width 0.0889)
		(layer "In2.Cu")
		(net "M_F_CKE<1>")
	)
	(segment
		(start 244.413278 -140.222478)
		(end 244.435884 -140.245084)
		(width 0.14224)
		(layer "In2.Cu")
		(net "M_F_CKE<1>")
	)
	(segment
		(start 244.409468 -144.362932)
		(end 244.409468 -146.598132)
		(width 0.14224)
		(layer "In2.Cu")
		(net "M_F_CKE<1>")
	)
	(segment
		(start 243.58854 -149.04974)
		(end 243.7384 -149.1996)
		(width 0.14224)
		(layer "In2.Cu")
		(net "M_F_CKE<1>")
	)
	(segment
		(start 244.43944 -135.39724)
		(end 244.5258 -135.4836)
		(width 0.14224)
		(layer "In2.Cu")
		(net "M_F_CKE<1>")
	)
	(segment
		(start 244.43944 -132.04444)
		(end 244.43944 -135.39724)
		(width 0.14224)
		(layer "In2.Cu")
		(net "M_F_CKE<1>")
	)
	(segment
		(start 251.41682 -98.377502)
		(end 251.411994 -98.386138)
		(width 0.0889)
		(layer "In2.Cu")
		(net "M_F_CKE<1>")
	)
	(segment
		(start 251.411994 -95.414338)
		(end 251.405644 -95.425006)
		(width 0.0889)
		(layer "In2.Cu")
		(net "M_F_CKE<1>")
	)
	(segment
		(start 244.475 -129.8956)
		(end 244.3226 -130.048)
		(width 0.14224)
		(layer "In2.Cu")
		(net "M_F_CKE<1>")
	)
	(segment
		(start 243.58854 -147.41906)
		(end 243.58854 -149.04974)
		(width 0.14224)
		(layer "In2.Cu")
		(net "M_F_CKE<1>")
	)
	(segment
		(start 251.405644 -94.01302)
		(end 251.411994 -94.023688)
		(width 0.0889)
		(layer "In2.Cu")
		(net "M_F_CKE<1>")
	)
	(segment
		(start 244.3226 -130.429)
		(end 244.5258 -130.6322)
		(width 0.14224)
		(layer "In2.Cu")
		(net "M_F_CKE<1>")
	)
	(segment
		(start 251.41682 -93.424502)
		(end 251.411994 -93.433138)
		(width 0.0889)
		(layer "In2.Cu")
		(net "M_F_CKE<1>")
	)
	(segment
		(start 251.2822 -98.541078)
		(end 251.2822 -99.1616)
		(width 0.0889)
		(layer "In2.Cu")
		(net "M_F_CKE<1>")
	)
	(segment
		(start 243.459 -151.6888)
		(end 243.459 -153.7462)
		(width 0.14224)
		(layer "In2.Cu")
		(net "M_F_CKE<1>")
	)
	(segment
		(start 244.5258 -131.1656)
		(end 244.348 -131.3434)
		(width 0.14224)
		(layer "In2.Cu")
		(net "M_F_CKE<1>")
	)
	(segment
		(start 250.7996 -101.2952)
		(end 250.7996 -101.520498)
		(width 0.0889)
		(layer "In2.Cu")
		(net "M_F_CKE<1>")
	)
	(segment
		(start 243.7384 -149.1996)
		(end 243.7384 -150.213568)
		(width 0.14224)
		(layer "In2.Cu")
		(net "M_F_CKE<1>")
	)
	(segment
		(start 251.411994 -96.404938)
		(end 251.405644 -96.415606)
		(width 0.0889)
		(layer "In2.Cu")
		(net "M_F_CKE<1>")
	)
	(segment
		(start 251.41682 -95.405702)
		(end 251.411994 -95.414338)
		(width 0.0889)
		(layer "In2.Cu")
		(net "M_F_CKE<1>")
	)
	(segment
		(start 243.7384 -150.213568)
		(end 243.558822 -150.393146)
		(width 0.14224)
		(layer "In2.Cu")
		(net "M_F_CKE<1>")
	)
	(segment
		(start 251.327666 -98.495612)
		(end 251.2822 -98.541078)
		(width 0.0889)
		(layer "In2.Cu")
		(net "M_F_CKE<1>")
	)
	(segment
		(start 244.5258 -130.6322)
		(end 244.5258 -131.1656)
		(width 0.14224)
		(layer "In2.Cu")
		(net "M_F_CKE<1>")
	)
	(segment
		(start 243.558822 -150.393146)
		(end 243.558822 -151.588978)
		(width 0.14224)
		(layer "In2.Cu")
		(net "M_F_CKE<1>")
	)
	(segment
		(start 251.411994 -92.442538)
		(end 251.405644 -92.453206)
		(width 0.0889)
		(layer "In2.Cu")
		(net "M_F_CKE<1>")
	)
	(segment
		(start 244.5258 -135.4836)
		(end 244.5258 -135.8646)
		(width 0.14224)
		(layer "In2.Cu")
		(net "M_F_CKE<1>")
	)
	(segment
		(start 251.923804 -91.103196)
		(end 251.346716 -91.680284)
		(width 0.0889)
		(layer "In2.Cu")
		(net "M_F_CKE<1>")
	)
	(segment
		(start 251.923804 -90.756486)
		(end 251.923804 -91.103196)
		(width 0.0889)
		(layer "In2.Cu")
		(net "M_F_CKE<1>")
	)
	(segment
		(start 243.558822 -151.588978)
		(end 243.459 -151.6888)
		(width 0.14224)
		(layer "In2.Cu")
		(net "M_F_CKE<1>")
	)
	(segment
		(start 244.3226 -130.048)
		(end 244.3226 -130.429)
		(width 0.14224)
		(layer "In2.Cu")
		(net "M_F_CKE<1>")
	)
	(segment
		(start 251.2314 -99.2124)
		(end 251.2314 -100.8634)
		(width 0.0889)
		(layer "In2.Cu")
		(net "M_F_CKE<1>")
	)
	(arc
		(start 251.411994 -96.004888)
		(mid 251.465464 -96.199951)
		(end 251.41682 -96.396302)
		(width 0.0889)
		(layer "In2.Cu")
		(net "M_F_CKE<1>")
	)
	(arc
		(start 251.346716 -91.87434)
		(mid 251.372897 -91.960922)
		(end 251.411994 -92.042488)
		(width 0.0889)
		(layer "In2.Cu")
		(net "M_F_CKE<1>")
	)
	(arc
		(start 251.405644 -92.453206)
		(mid 251.332846 -92.743969)
		(end 251.411994 -93.033088)
		(width 0.0889)
		(layer "In2.Cu")
		(net "M_F_CKE<1>")
	)
	(arc
		(start 251.411994 -98.386138)
		(mid 251.373842 -98.443966)
		(end 251.327666 -98.495612)
		(width 0.0889)
		(layer "In2.Cu")
		(net "M_F_CKE<1>")
	)
	(arc
		(start 251.411994 -94.423484)
		(mid 251.332863 -94.718886)
		(end 251.411994 -95.014288)
		(width 0.0889)
		(layer "In2.Cu")
		(net "M_F_CKE<1>")
	)
	(arc
		(start 251.411994 -93.033088)
		(mid 251.465464 -93.228151)
		(end 251.41682 -93.424502)
		(width 0.0889)
		(layer "In2.Cu")
		(net "M_F_CKE<1>")
	)
	(arc
		(start 251.405644 -97.406206)
		(mid 251.332846 -97.696969)
		(end 251.411994 -97.986088)
		(width 0.0889)
		(layer "In2.Cu")
		(net "M_F_CKE<1>")
	)
	(arc
		(start 251.411994 -97.986088)
		(mid 251.465464 -98.181151)
		(end 251.41682 -98.377502)
		(width 0.0889)
		(layer "In2.Cu")
		(net "M_F_CKE<1>")
	)
	(arc
		(start 251.411994 -92.042488)
		(mid 251.465464 -92.237551)
		(end 251.41682 -92.433902)
		(width 0.0889)
		(layer "In2.Cu")
		(net "M_F_CKE<1>")
	)
	(arc
		(start 251.405644 -95.425006)
		(mid 251.332846 -95.715769)
		(end 251.411994 -96.004888)
		(width 0.0889)
		(layer "In2.Cu")
		(net "M_F_CKE<1>")
	)
	(arc
		(start 251.411994 -95.014288)
		(mid 251.465464 -95.209351)
		(end 251.41682 -95.405702)
		(width 0.0889)
		(layer "In2.Cu")
		(net "M_F_CKE<1>")
	)
	(arc
		(start 251.405644 -96.415606)
		(mid 251.332846 -96.706369)
		(end 251.411994 -96.995488)
		(width 0.0889)
		(layer "In2.Cu")
		(net "M_F_CKE<1>")
	)
	(arc
		(start 251.411994 -93.433138)
		(mid 251.332772 -93.722256)
		(end 251.405644 -94.01302)
		(width 0.0889)
		(layer "In2.Cu")
		(net "M_F_CKE<1>")
	)
	(arc
		(start 251.411994 -96.995488)
		(mid 251.465464 -97.190551)
		(end 251.41682 -97.386902)
		(width 0.0889)
		(layer "In2.Cu")
		(net "M_F_CKE<1>")
	)
	(arc
		(start 251.411994 -94.023688)
		(mid 251.465493 -94.223586)
		(end 251.411994 -94.423484)
		(width 0.0889)
		(layer "In2.Cu")
		(net "M_F_CKE<1>")
	)
	(segment
		(start 244.849904 -152.278842)
		(end 244.849904 -154.252168)
		(width 0.1651)
		(layer "F.Cu")
		(net "M_F_CKE<0>")
	)
	(segment
		(start 253.353824 -92.24264)
		(end 252.782324 -92.24264)
		(width 0.1016)
		(layer "F.Cu")
		(net "M_F_CKE<0>")
	)
	(segment
		(start 244.850412 -152.273)
		(end 244.849904 -152.278842)
		(width 0.1651)
		(layer "F.Cu")
		(net "M_F_CKE<0>")
	)
	(via
		(at 252.782324 -92.24264)
		(size 0.508)
		(drill 0.254)
		(layers "F.Cu" "B.Cu")
		(net "M_F_CKE<0>")
	)
	(via
		(at 244.849904 -154.252168)
		(size 0.508)
		(drill 0.254)
		(layers "F.Cu" "B.Cu")
		(net "M_F_CKE<0>")
	)
	(segment
		(start 246.9134 -129.3368)
		(end 246.9134 -129.794)
		(width 0.14224)
		(layer "In2.Cu")
		(net "M_F_CKE<0>")
	)
	(segment
		(start 246.99214 -138.52906)
		(end 246.98833 -138.53287)
		(width 0.14224)
		(layer "In2.Cu")
		(net "M_F_CKE<0>")
	)
	(segment
		(start 247.115076 -135.59663)
		(end 246.99214 -135.719566)
		(width 0.14224)
		(layer "In2.Cu")
		(net "M_F_CKE<0>")
	)
	(segment
		(start 246.965724 -140.687044)
		(end 246.965724 -143.463264)
		(width 0.14224)
		(layer "In2.Cu")
		(net "M_F_CKE<0>")
	)
	(segment
		(start 246.98833 -143.48587)
		(end 246.98833 -144.32153)
		(width 0.14224)
		(layer "In2.Cu")
		(net "M_F_CKE<0>")
	)
	(segment
		(start 252.5268 -101.08184)
		(end 252.3236 -101.28504)
		(width 0.0889)
		(layer "In2.Cu")
		(net "M_F_CKE<0>")
	)
	(segment
		(start 247.0658 -144.399)
		(end 247.0658 -145.233136)
		(width 0.14224)
		(layer "In2.Cu")
		(net "M_F_CKE<0>")
	)
	(segment
		(start 252.3236 -121.825766)
		(end 248.5898 -125.559566)
		(width 0.14224)
		(layer "In2.Cu")
		(net "M_F_CKE<0>")
	)
	(segment
		(start 247.0658 -145.233136)
		(end 246.98833 -145.310606)
		(width 0.14224)
		(layer "In2.Cu")
		(net "M_F_CKE<0>")
	)
	(segment
		(start 248.5898 -125.559566)
		(end 248.5898 -127.6604)
		(width 0.14224)
		(layer "In2.Cu")
		(net "M_F_CKE<0>")
	)
	(segment
		(start 247.0404 -129.921)
		(end 247.0404 -130.5052)
		(width 0.14224)
		(layer "In2.Cu")
		(net "M_F_CKE<0>")
	)
	(segment
		(start 244.849904 -152.299924)
		(end 244.849904 -154.252168)
		(width 0.14224)
		(layer "In2.Cu")
		(net "M_F_CKE<0>")
	)
	(segment
		(start 252.430788 -96.396302)
		(end 252.435614 -96.404938)
		(width 0.0889)
		(layer "In2.Cu")
		(net "M_F_CKE<0>")
	)
	(segment
		(start 246.9134 -130.6322)
		(end 246.9134 -131.1656)
		(width 0.14224)
		(layer "In2.Cu")
		(net "M_F_CKE<0>")
	)
	(segment
		(start 246.977154 -134.709154)
		(end 247.115076 -134.847076)
		(width 0.14224)
		(layer "In2.Cu")
		(net "M_F_CKE<0>")
	)
	(segment
		(start 246.965724 -143.463264)
		(end 246.98833 -143.48587)
		(width 0.14224)
		(layer "In2.Cu")
		(net "M_F_CKE<0>")
	)
	(segment
		(start 246.977154 -133.718046)
		(end 246.977154 -134.709154)
		(width 0.14224)
		(layer "In2.Cu")
		(net "M_F_CKE<0>")
	)
	(segment
		(start 252.349 -93.346524)
		(end 252.435614 -93.433138)
		(width 0.0889)
		(layer "In2.Cu")
		(net "M_F_CKE<0>")
	)
	(segment
		(start 248.5898 -127.6604)
		(end 246.9134 -129.3368)
		(width 0.14224)
		(layer "In2.Cu")
		(net "M_F_CKE<0>")
	)
	(segment
		(start 247.0658 -133.6294)
		(end 246.977154 -133.718046)
		(width 0.14224)
		(layer "In2.Cu")
		(net "M_F_CKE<0>")
	)
	(segment
		(start 252.441964 -94.01302)
		(end 252.435614 -94.023688)
		(width 0.0889)
		(layer "In2.Cu")
		(net "M_F_CKE<0>")
	)
	(segment
		(start 246.98833 -139.54633)
		(end 246.999506 -139.557506)
		(width 0.14224)
		(layer "In2.Cu")
		(net "M_F_CKE<0>")
	)
	(segment
		(start 247.0658 -131.318)
		(end 247.0658 -133.6294)
		(width 0.14224)
		(layer "In2.Cu")
		(net "M_F_CKE<0>")
	)
	(segment
		(start 252.430788 -95.405702)
		(end 252.435614 -95.414338)
		(width 0.0889)
		(layer "In2.Cu")
		(net "M_F_CKE<0>")
	)
	(segment
		(start 246.999506 -140.653262)
		(end 246.965724 -140.687044)
		(width 0.14224)
		(layer "In2.Cu")
		(net "M_F_CKE<0>")
	)
	(segment
		(start 246.9134 -131.1656)
		(end 247.0658 -131.318)
		(width 0.14224)
		(layer "In2.Cu")
		(net "M_F_CKE<0>")
	)
	(segment
		(start 252.430788 -97.386902)
		(end 252.435614 -97.395538)
		(width 0.0889)
		(layer "In2.Cu")
		(net "M_F_CKE<0>")
	)
	(segment
		(start 245.264178 -151.88565)
		(end 244.849904 -152.299924)
		(width 0.14224)
		(layer "In2.Cu")
		(net "M_F_CKE<0>")
	)
	(segment
		(start 252.5268 -99.537774)
		(end 252.5268 -101.08184)
		(width 0.0889)
		(layer "In2.Cu")
		(net "M_F_CKE<0>")
	)
	(segment
		(start 252.3236 -101.510338)
		(end 252.3236 -121.825766)
		(width 0.14224)
		(layer "In2.Cu")
		(net "M_F_CKE<0>")
	)
	(segment
		(start 246.98833 -146.45767)
		(end 245.28653 -148.15947)
		(width 0.14224)
		(layer "In2.Cu")
		(net "M_F_CKE<0>")
	)
	(segment
		(start 252.435614 -95.414338)
		(end 252.441964 -95.425006)
		(width 0.0889)
		(layer "In2.Cu")
		(net "M_F_CKE<0>")
	)
	(segment
		(start 252.435614 -98.386138)
		(end 252.441964 -98.396806)
		(width 0.0889)
		(layer "In2.Cu")
		(net "M_F_CKE<0>")
	)
	(segment
		(start 252.782324 -92.24264)
		(end 252.349 -92.675964)
		(width 0.0889)
		(layer "In2.Cu")
		(net "M_F_CKE<0>")
	)
	(segment
		(start 246.99214 -135.719566)
		(end 246.99214 -138.52906)
		(width 0.14224)
		(layer "In2.Cu")
		(net "M_F_CKE<0>")
	)
	(segment
		(start 245.28653 -148.15947)
		(end 245.28653 -149.81047)
		(width 0.14224)
		(layer "In2.Cu")
		(net "M_F_CKE<0>")
	)
	(segment
		(start 246.98833 -144.32153)
		(end 247.0658 -144.399)
		(width 0.14224)
		(layer "In2.Cu")
		(net "M_F_CKE<0>")
	)
	(segment
		(start 252.349 -92.675964)
		(end 252.349 -93.346524)
		(width 0.0889)
		(layer "In2.Cu")
		(net "M_F_CKE<0>")
	)
	(segment
		(start 247.0404 -130.5052)
		(end 246.9134 -130.6322)
		(width 0.14224)
		(layer "In2.Cu")
		(net "M_F_CKE<0>")
	)
	(segment
		(start 246.9134 -129.794)
		(end 247.0404 -129.921)
		(width 0.14224)
		(layer "In2.Cu")
		(net "M_F_CKE<0>")
	)
	(segment
		(start 252.435614 -96.404938)
		(end 252.441964 -96.415606)
		(width 0.0889)
		(layer "In2.Cu")
		(net "M_F_CKE<0>")
	)
	(segment
		(start 245.28653 -149.81047)
		(end 245.264178 -149.832822)
		(width 0.14224)
		(layer "In2.Cu")
		(net "M_F_CKE<0>")
	)
	(segment
		(start 246.98833 -145.310606)
		(end 246.98833 -146.45767)
		(width 0.14224)
		(layer "In2.Cu")
		(net "M_F_CKE<0>")
	)
	(segment
		(start 246.98833 -138.53287)
		(end 246.98833 -139.54633)
		(width 0.14224)
		(layer "In2.Cu")
		(net "M_F_CKE<0>")
	)
	(segment
		(start 252.435614 -97.395538)
		(end 252.441964 -97.406206)
		(width 0.0889)
		(layer "In2.Cu")
		(net "M_F_CKE<0>")
	)
	(segment
		(start 245.264178 -149.832822)
		(end 245.264178 -151.88565)
		(width 0.14224)
		(layer "In2.Cu")
		(net "M_F_CKE<0>")
	)
	(segment
		(start 246.999506 -139.557506)
		(end 246.999506 -140.653262)
		(width 0.14224)
		(layer "In2.Cu")
		(net "M_F_CKE<0>")
	)
	(segment
		(start 252.430788 -99.368102)
		(end 252.5268 -99.537774)
		(width 0.0889)
		(layer "In2.Cu")
		(net "M_F_CKE<0>")
	)
	(segment
		(start 252.3236 -101.28504)
		(end 252.3236 -101.510338)
		(width 0.0889)
		(layer "In2.Cu")
		(net "M_F_CKE<0>")
	)
	(segment
		(start 252.430788 -98.377502)
		(end 252.435614 -98.386138)
		(width 0.0889)
		(layer "In2.Cu")
		(net "M_F_CKE<0>")
	)
	(segment
		(start 247.115076 -134.847076)
		(end 247.115076 -135.59663)
		(width 0.14224)
		(layer "In2.Cu")
		(net "M_F_CKE<0>")
	)
	(arc
		(start 252.435614 -98.976688)
		(mid 252.382144 -99.171751)
		(end 252.430788 -99.368102)
		(width 0.0889)
		(layer "In2.Cu")
		(net "M_F_CKE<0>")
	)
	(arc
		(start 252.435614 -96.004888)
		(mid 252.382144 -96.199951)
		(end 252.430788 -96.396302)
		(width 0.0889)
		(layer "In2.Cu")
		(net "M_F_CKE<0>")
	)
	(arc
		(start 252.435614 -94.423484)
		(mid 252.514745 -94.718886)
		(end 252.435614 -95.014288)
		(width 0.0889)
		(layer "In2.Cu")
		(net "M_F_CKE<0>")
	)
	(arc
		(start 252.441964 -95.425006)
		(mid 252.514762 -95.715769)
		(end 252.435614 -96.004888)
		(width 0.0889)
		(layer "In2.Cu")
		(net "M_F_CKE<0>")
	)
	(arc
		(start 252.435614 -97.986088)
		(mid 252.382144 -98.181151)
		(end 252.430788 -98.377502)
		(width 0.0889)
		(layer "In2.Cu")
		(net "M_F_CKE<0>")
	)
	(arc
		(start 252.441964 -97.406206)
		(mid 252.514762 -97.696969)
		(end 252.435614 -97.986088)
		(width 0.0889)
		(layer "In2.Cu")
		(net "M_F_CKE<0>")
	)
	(arc
		(start 252.435614 -96.995488)
		(mid 252.382144 -97.190551)
		(end 252.430788 -97.386902)
		(width 0.0889)
		(layer "In2.Cu")
		(net "M_F_CKE<0>")
	)
	(arc
		(start 252.441964 -98.396806)
		(mid 252.514762 -98.687569)
		(end 252.435614 -98.976688)
		(width 0.0889)
		(layer "In2.Cu")
		(net "M_F_CKE<0>")
	)
	(arc
		(start 252.435614 -95.014288)
		(mid 252.382144 -95.209351)
		(end 252.430788 -95.405702)
		(width 0.0889)
		(layer "In2.Cu")
		(net "M_F_CKE<0>")
	)
	(arc
		(start 252.435614 -93.433138)
		(mid 252.514836 -93.722256)
		(end 252.441964 -94.01302)
		(width 0.0889)
		(layer "In2.Cu")
		(net "M_F_CKE<0>")
	)
	(arc
		(start 252.435614 -94.023688)
		(mid 252.382115 -94.223586)
		(end 252.435614 -94.423484)
		(width 0.0889)
		(layer "In2.Cu")
		(net "M_F_CKE<0>")
	)
	(arc
		(start 252.441964 -96.415606)
		(mid 252.514762 -96.706369)
		(end 252.435614 -96.995488)
		(width 0.0889)
		(layer "In2.Cu")
		(net "M_F_CKE<0>")
	)
	(segment
		(start 267.948156 -91.747086)
		(end 267.376656 -91.747086)
		(width 0.1016)
		(layer "F.Cu")
		(net "M_F_C<2>")
	)
	(segment
		(start 276.29993 -154.905456)
		(end 276.29993 -156.87294)
		(width 0.1651)
		(layer "F.Cu")
		(net "M_F_C<2>")
	)
	(segment
		(start 276.29993 -156.87294)
		(end 276.300438 -156.87294)
		(width 0.1651)
		(layer "F.Cu")
		(net "M_F_C<2>")
	)
	(via
		(at 267.376656 -91.747086)
		(size 0.508)
		(drill 0.254)
		(layers "F.Cu" "B.Cu")
		(net "M_F_C<2>")
	)
	(via
		(at 276.29993 -154.905456)
		(size 0.508)
		(drill 0.254)
		(layers "F.Cu" "B.Cu")
		(net "M_F_C<2>")
	)
	(via
		(at 276.300438 -148.773388)
		(size 0.4572)
		(drill 0.2032)
		(layers "F.Cu" "B.Cu")
		(net "M_F_C<2>")
	)
	(segment
		(start 276.300438 -147.478496)
		(end 276.29993 -147.478496)
		(width 0.10795)
		(layer "B.Cu")
		(net "M_F_C<2>")
	)
	(segment
		(start 276.29993 -148.77288)
		(end 276.300438 -148.773388)
		(width 0.10795)
		(layer "B.Cu")
		(net "M_F_C<2>")
	)
	(segment
		(start 276.29993 -147.478496)
		(end 276.29993 -148.77288)
		(width 0.10795)
		(layer "B.Cu")
		(net "M_F_C<2>")
	)
	(segment
		(start 278.377396 -139.452604)
		(end 278.377396 -140.150596)
		(width 0.14224)
		(layer "In11.Cu")
		(net "M_F_C<2>")
	)
	(segment
		(start 276.29993 -148.773896)
		(end 276.29993 -149.32533)
		(width 0.14224)
		(layer "In11.Cu")
		(net "M_F_C<2>")
	)
	(segment
		(start 278.511 -136.8044)
		(end 278.511 -139.319)
		(width 0.14224)
		(layer "In11.Cu")
		(net "M_F_C<2>")
	)
	(segment
		(start 278.257 -130.5052)
		(end 278.511 -130.7592)
		(width 0.14224)
		(layer "In11.Cu")
		(net "M_F_C<2>")
	)
	(segment
		(start 278.454866 -140.228066)
		(end 278.454866 -141.472666)
		(width 0.14224)
		(layer "In11.Cu")
		(net "M_F_C<2>")
	)
	(segment
		(start 268.6558 -92.382086)
		(end 268.6558 -99.9744)
		(width 0.0889)
		(layer "In11.Cu")
		(net "M_F_C<2>")
	)
	(segment
		(start 270.815054 -101.473254)
		(end 270.815054 -101.997764)
		(width 0.0889)
		(layer "In11.Cu")
		(net "M_F_C<2>")
	)
	(segment
		(start 276.712172 -151.032972)
		(end 276.9362 -151.257)
		(width 0.14224)
		(layer "In11.Cu")
		(net "M_F_C<2>")
	)
	(segment
		(start 276.712172 -149.737572)
		(end 276.712172 -151.032972)
		(width 0.14224)
		(layer "In11.Cu")
		(net "M_F_C<2>")
	)
	(segment
		(start 278.5364 -141.5542)
		(end 278.5364 -144.0942)
		(width 0.14224)
		(layer "In11.Cu")
		(net "M_F_C<2>")
	)
	(segment
		(start 278.511 -130.7592)
		(end 278.511 -131.4704)
		(width 0.14224)
		(layer "In11.Cu")
		(net "M_F_C<2>")
	)
	(segment
		(start 268.0208 -91.747086)
		(end 268.6558 -92.382086)
		(width 0.0889)
		(layer "In11.Cu")
		(net "M_F_C<2>")
	)
	(segment
		(start 278.413718 -146.660108)
		(end 276.300438 -148.773388)
		(width 0.14224)
		(layer "In11.Cu")
		(net "M_F_C<2>")
	)
	(segment
		(start 278.257 -129.9972)
		(end 278.257 -130.5052)
		(width 0.14224)
		(layer "In11.Cu")
		(net "M_F_C<2>")
	)
	(segment
		(start 278.407622 -134.92607)
		(end 278.4348 -134.953248)
		(width 0.14224)
		(layer "In11.Cu")
		(net "M_F_C<2>")
	)
	(segment
		(start 278.407622 -131.573778)
		(end 278.407622 -134.92607)
		(width 0.14224)
		(layer "In11.Cu")
		(net "M_F_C<2>")
	)
	(segment
		(start 269.4051 -100.7237)
		(end 270.0655 -100.7237)
		(width 0.0889)
		(layer "In11.Cu")
		(net "M_F_C<2>")
	)
	(segment
		(start 278.377396 -140.150596)
		(end 278.454866 -140.228066)
		(width 0.14224)
		(layer "In11.Cu")
		(net "M_F_C<2>")
	)
	(segment
		(start 278.511 -129.7432)
		(end 278.257 -129.9972)
		(width 0.14224)
		(layer "In11.Cu")
		(net "M_F_C<2>")
	)
	(segment
		(start 276.9362 -151.257)
		(end 276.9362 -153.6446)
		(width 0.14224)
		(layer "In11.Cu")
		(net "M_F_C<2>")
	)
	(segment
		(start 278.413718 -144.216882)
		(end 278.413718 -146.660108)
		(width 0.14224)
		(layer "In11.Cu")
		(net "M_F_C<2>")
	)
	(segment
		(start 270.815054 -101.997764)
		(end 270.815054 -118.796054)
		(width 0.14224)
		(layer "In11.Cu")
		(net "M_F_C<2>")
	)
	(segment
		(start 276.29993 -149.32533)
		(end 276.712172 -149.737572)
		(width 0.14224)
		(layer "In11.Cu")
		(net "M_F_C<2>")
	)
	(segment
		(start 278.5364 -144.0942)
		(end 278.413718 -144.216882)
		(width 0.14224)
		(layer "In11.Cu")
		(net "M_F_C<2>")
	)
	(segment
		(start 270.0655 -100.7237)
		(end 270.815054 -101.473254)
		(width 0.0889)
		(layer "In11.Cu")
		(net "M_F_C<2>")
	)
	(segment
		(start 276.300438 -148.773388)
		(end 276.29993 -148.773896)
		(width 0.14224)
		(layer "In11.Cu")
		(net "M_F_C<2>")
	)
	(segment
		(start 278.511 -131.4704)
		(end 278.407622 -131.573778)
		(width 0.14224)
		(layer "In11.Cu")
		(net "M_F_C<2>")
	)
	(segment
		(start 276.29993 -154.28087)
		(end 276.29993 -154.905456)
		(width 0.14224)
		(layer "In11.Cu")
		(net "M_F_C<2>")
	)
	(segment
		(start 268.6558 -99.9744)
		(end 269.4051 -100.7237)
		(width 0.0889)
		(layer "In11.Cu")
		(net "M_F_C<2>")
	)
	(segment
		(start 278.4348 -134.953248)
		(end 278.4348 -136.7282)
		(width 0.14224)
		(layer "In11.Cu")
		(net "M_F_C<2>")
	)
	(segment
		(start 270.815054 -118.796054)
		(end 278.511 -126.492)
		(width 0.14224)
		(layer "In11.Cu")
		(net "M_F_C<2>")
	)
	(segment
		(start 278.454866 -141.472666)
		(end 278.5364 -141.5542)
		(width 0.14224)
		(layer "In11.Cu")
		(net "M_F_C<2>")
	)
	(segment
		(start 278.511 -139.319)
		(end 278.377396 -139.452604)
		(width 0.14224)
		(layer "In11.Cu")
		(net "M_F_C<2>")
	)
	(segment
		(start 278.4348 -136.7282)
		(end 278.511 -136.8044)
		(width 0.14224)
		(layer "In11.Cu")
		(net "M_F_C<2>")
	)
	(segment
		(start 276.9362 -153.6446)
		(end 276.29993 -154.28087)
		(width 0.14224)
		(layer "In11.Cu")
		(net "M_F_C<2>")
	)
	(segment
		(start 267.376656 -91.747086)
		(end 268.0208 -91.747086)
		(width 0.0889)
		(layer "In11.Cu")
		(net "M_F_C<2>")
	)
	(segment
		(start 278.511 -126.492)
		(end 278.511 -129.7432)
		(width 0.14224)
		(layer "In11.Cu")
		(net "M_F_C<2>")
	)
	(segment
		(start 247.39981 -156.87294)
		(end 247.400318 -156.87294)
		(width 0.1651)
		(layer "F.Cu")
		(net "M_F_BG<1>")
	)
	(segment
		(start 247.39981 -154.905456)
		(end 247.39981 -156.87294)
		(width 0.1651)
		(layer "F.Cu")
		(net "M_F_BG<1>")
	)
	(segment
		(start 254.212344 -91.747086)
		(end 253.640844 -91.747086)
		(width 0.1016)
		(layer "F.Cu")
		(net "M_F_BG<1>")
	)
	(via
		(at 247.39981 -154.905456)
		(size 0.508)
		(drill 0.254)
		(layers "F.Cu" "B.Cu")
		(net "M_F_BG<1>")
	)
	(via
		(at 253.640844 -91.747086)
		(size 0.508)
		(drill 0.254)
		(layers "F.Cu" "B.Cu")
		(net "M_F_BG<1>")
	)
	(via
		(at 247.39981 -148.771356)
		(size 0.4572)
		(drill 0.2032)
		(layers "F.Cu" "B.Cu")
		(net "M_F_BG<1>")
	)
	(segment
		(start 247.400318 -147.478496)
		(end 247.39981 -147.478496)
		(width 0.1651)
		(layer "B.Cu")
		(net "M_F_BG<1>")
	)
	(segment
		(start 247.39981 -147.478496)
		(end 247.39981 -148.771356)
		(width 0.1651)
		(layer "B.Cu")
		(net "M_F_BG<1>")
	)
	(segment
		(start 249.428 -131.2926)
		(end 249.5804 -131.1402)
		(width 0.14224)
		(layer "In2.Cu")
		(net "M_F_BG<1>")
	)
	(segment
		(start 249.4788 -129.9718)
		(end 249.6058 -129.8448)
		(width 0.14224)
		(layer "In2.Cu")
		(net "M_F_BG<1>")
	)
	(segment
		(start 253.9873 -93.528642)
		(end 253.98095 -93.517974)
		(width 0.0889)
		(layer "In2.Cu")
		(net "M_F_BG<1>")
	)
	(segment
		(start 253.9873 -97.490788)
		(end 253.97841 -97.475548)
		(width 0.0889)
		(layer "In2.Cu")
		(net "M_F_BG<1>")
	)
	(segment
		(start 253.98095 -93.939106)
		(end 253.9873 -93.928438)
		(width 0.0889)
		(layer "In2.Cu")
		(net "M_F_BG<1>")
	)
	(segment
		(start 249.6058 -129.8448)
		(end 249.6058 -129.368296)
		(width 0.14224)
		(layer "In2.Cu")
		(net "M_F_BG<1>")
	)
	(segment
		(start 249.5804 -131.1402)
		(end 249.5804 -130.6576)
		(width 0.14224)
		(layer "In2.Cu")
		(net "M_F_BG<1>")
	)
	(segment
		(start 252.30455 -124.986796)
		(end 252.591824 -124.699522)
		(width 0.14224)
		(layer "In2.Cu")
		(net "M_F_BG<1>")
	)
	(segment
		(start 252.975364 -123.64593)
		(end 253.166626 -123.837192)
		(width 0.14224)
		(layer "In2.Cu")
		(net "M_F_BG<1>")
	)
	(segment
		(start 252.017022 -124.986796)
		(end 252.30455 -124.986796)
		(width 0.14224)
		(layer "In2.Cu")
		(net "M_F_BG<1>")
	)
	(segment
		(start 253.8476 -102.7176)
		(end 253.803404 -102.673404)
		(width 0.0889)
		(layer "In2.Cu")
		(net "M_F_BG<1>")
	)
	(segment
		(start 253.803404 -101.364796)
		(end 254.0762 -101.092)
		(width 0.0889)
		(layer "In2.Cu")
		(net "M_F_BG<1>")
	)
	(segment
		(start 249.4788 -130.556)
		(end 249.4788 -129.9718)
		(width 0.14224)
		(layer "In2.Cu")
		(net "M_F_BG<1>")
	)
	(segment
		(start 247.944386 -150.429214)
		(end 247.816878 -150.556722)
		(width 0.14224)
		(layer "In2.Cu")
		(net "M_F_BG<1>")
	)
	(segment
		(start 253.9873 -92.537788)
		(end 253.970536 -92.508832)
		(width 0.0889)
		(layer "In2.Cu")
		(net "M_F_BG<1>")
	)
	(segment
		(start 247.816878 -151.079454)
		(end 247.941338 -151.203914)
		(width 0.14224)
		(layer "In2.Cu")
		(net "M_F_BG<1>")
	)
	(segment
		(start 251.852176 -124.82195)
		(end 252.017022 -124.986796)
		(width 0.14224)
		(layer "In2.Cu")
		(net "M_F_BG<1>")
	)
	(segment
		(start 249.5296 -134.6962)
		(end 249.5296 -133.6548)
		(width 0.14224)
		(layer "In2.Cu")
		(net "M_F_BG<1>")
	)
	(segment
		(start 251.280676 -125.109224)
		(end 251.56795 -124.82195)
		(width 0.14224)
		(layer "In2.Cu")
		(net "M_F_BG<1>")
	)
	(segment
		(start 249.52579 -140.489178)
		(end 249.4026 -140.365988)
		(width 0.14224)
		(layer "In2.Cu")
		(net "M_F_BG<1>")
	)
	(segment
		(start 247.39981 -154.35199)
		(end 247.39981 -154.905456)
		(width 0.14224)
		(layer "In2.Cu")
		(net "M_F_BG<1>")
	)
	(segment
		(start 252.591824 -124.411994)
		(end 252.400562 -124.220732)
		(width 0.14224)
		(layer "In2.Cu")
		(net "M_F_BG<1>")
	)
	(segment
		(start 249.53341 -135.816848)
		(end 249.4534 -135.736838)
		(width 0.14224)
		(layer "In2.Cu")
		(net "M_F_BG<1>")
	)
	(segment
		(start 249.5296 -133.6548)
		(end 249.428 -133.5532)
		(width 0.14224)
		(layer "In2.Cu")
		(net "M_F_BG<1>")
	)
	(segment
		(start 251.56795 -124.82195)
		(end 251.852176 -124.82195)
		(width 0.14224)
		(layer "In2.Cu")
		(net "M_F_BG<1>")
	)
	(segment
		(start 249.3772 -144.4498)
		(end 249.514868 -144.312132)
		(width 0.14224)
		(layer "In2.Cu")
		(net "M_F_BG<1>")
	)
	(segment
		(start 249.4026 -139.6238)
		(end 249.53341 -139.49299)
		(width 0.14224)
		(layer "In2.Cu")
		(net "M_F_BG<1>")
	)
	(segment
		(start 253.9873 -96.500188)
		(end 253.97841 -96.484948)
		(width 0.0889)
		(layer "In2.Cu")
		(net "M_F_BG<1>")
	)
	(segment
		(start 247.941338 -151.203914)
		(end 247.941338 -153.810462)
		(width 0.14224)
		(layer "In2.Cu")
		(net "M_F_BG<1>")
	)
	(segment
		(start 250.1138 -128.860296)
		(end 250.1138 -127.177546)
		(width 0.14224)
		(layer "In2.Cu")
		(net "M_F_BG<1>")
	)
	(segment
		(start 251.44222 -125.849126)
		(end 251.44222 -125.561598)
		(width 0.14224)
		(layer "In2.Cu")
		(net "M_F_BG<1>")
	)
	(segment
		(start 247.816878 -150.556722)
		(end 247.816878 -151.079454)
		(width 0.14224)
		(layer "In2.Cu")
		(net "M_F_BG<1>")
	)
	(segment
		(start 249.536966 -145.636234)
		(end 249.3772 -145.476468)
		(width 0.14224)
		(layer "In2.Cu")
		(net "M_F_BG<1>")
	)
	(segment
		(start 253.8476 -123.443746)
		(end 253.8476 -103.049324)
		(width 0.14224)
		(layer "In2.Cu")
		(net "M_F_BG<1>")
	)
	(segment
		(start 249.4534 -134.7724)
		(end 249.5296 -134.6962)
		(width 0.14224)
		(layer "In2.Cu")
		(net "M_F_BG<1>")
	)
	(segment
		(start 253.9873 -98.481388)
		(end 253.97841 -98.466148)
		(width 0.0889)
		(layer "In2.Cu")
		(net "M_F_BG<1>")
	)
	(segment
		(start 249.3772 -143.3576)
		(end 249.3772 -141.8844)
		(width 0.14224)
		(layer "In2.Cu")
		(net "M_F_BG<1>")
	)
	(segment
		(start 249.3772 -145.476468)
		(end 249.3772 -144.4498)
		(width 0.14224)
		(layer "In2.Cu")
		(net "M_F_BG<1>")
	)
	(segment
		(start 251.280676 -125.400054)
		(end 251.280676 -125.109224)
		(width 0.14224)
		(layer "In2.Cu")
		(net "M_F_BG<1>")
	)
	(segment
		(start 249.53341 -139.49299)
		(end 249.53341 -135.816848)
		(width 0.14224)
		(layer "In2.Cu")
		(net "M_F_BG<1>")
	)
	(segment
		(start 252.591824 -124.699522)
		(end 252.591824 -124.411994)
		(width 0.14224)
		(layer "In2.Cu")
		(net "M_F_BG<1>")
	)
	(segment
		(start 249.4534 -135.736838)
		(end 249.4534 -134.7724)
		(width 0.14224)
		(layer "In2.Cu")
		(net "M_F_BG<1>")
	)
	(segment
		(start 251.44222 -125.561598)
		(end 251.280676 -125.400054)
		(width 0.14224)
		(layer "In2.Cu")
		(net "M_F_BG<1>")
	)
	(segment
		(start 247.944386 -149.814534)
		(end 247.944386 -150.429214)
		(width 0.14224)
		(layer "In2.Cu")
		(net "M_F_BG<1>")
	)
	(segment
		(start 249.3772 -141.8844)
		(end 249.52579 -141.73581)
		(width 0.14224)
		(layer "In2.Cu")
		(net "M_F_BG<1>")
	)
	(segment
		(start 247.39981 -149.269958)
		(end 247.944386 -149.814534)
		(width 0.14224)
		(layer "In2.Cu")
		(net "M_F_BG<1>")
	)
	(segment
		(start 254.0762 -101.092)
		(end 254.0762 -98.810318)
		(width 0.0889)
		(layer "In2.Cu")
		(net "M_F_BG<1>")
	)
	(segment
		(start 252.687836 -123.64593)
		(end 252.975364 -123.64593)
		(width 0.14224)
		(layer "In2.Cu")
		(net "M_F_BG<1>")
	)
	(segment
		(start 252.400562 -123.933204)
		(end 252.687836 -123.64593)
		(width 0.14224)
		(layer "In2.Cu")
		(net "M_F_BG<1>")
	)
	(segment
		(start 249.4026 -140.365988)
		(end 249.4026 -139.6238)
		(width 0.14224)
		(layer "In2.Cu")
		(net "M_F_BG<1>")
	)
	(segment
		(start 250.1138 -127.177546)
		(end 251.44222 -125.849126)
		(width 0.14224)
		(layer "In2.Cu")
		(net "M_F_BG<1>")
	)
	(segment
		(start 253.970536 -92.508832)
		(end 253.640844 -91.747086)
		(width 0.0889)
		(layer "In2.Cu")
		(net "M_F_BG<1>")
	)
	(segment
		(start 253.9873 -95.509588)
		(end 253.97841 -95.494348)
		(width 0.0889)
		(layer "In2.Cu")
		(net "M_F_BG<1>")
	)
	(segment
		(start 249.6058 -129.368296)
		(end 250.1138 -128.860296)
		(width 0.14224)
		(layer "In2.Cu")
		(net "M_F_BG<1>")
	)
	(segment
		(start 249.514868 -144.312132)
		(end 249.514868 -143.495268)
		(width 0.14224)
		(layer "In2.Cu")
		(net "M_F_BG<1>")
	)
	(segment
		(start 247.39981 -148.771356)
		(end 247.39981 -149.269958)
		(width 0.14224)
		(layer "In2.Cu")
		(net "M_F_BG<1>")
	)
	(segment
		(start 249.52579 -141.73581)
		(end 249.52579 -140.489178)
		(width 0.14224)
		(layer "In2.Cu")
		(net "M_F_BG<1>")
	)
	(segment
		(start 247.941338 -153.810462)
		(end 247.39981 -154.35199)
		(width 0.14224)
		(layer "In2.Cu")
		(net "M_F_BG<1>")
	)
	(segment
		(start 253.803404 -102.673404)
		(end 253.803404 -101.364796)
		(width 0.0889)
		(layer "In2.Cu")
		(net "M_F_BG<1>")
	)
	(segment
		(start 249.428 -133.5532)
		(end 249.428 -131.2926)
		(width 0.14224)
		(layer "In2.Cu")
		(net "M_F_BG<1>")
	)
	(segment
		(start 249.514868 -143.495268)
		(end 249.3772 -143.3576)
		(width 0.14224)
		(layer "In2.Cu")
		(net "M_F_BG<1>")
	)
	(segment
		(start 253.8476 -103.049324)
		(end 253.8476 -102.7176)
		(width 0.0889)
		(layer "In2.Cu")
		(net "M_F_BG<1>")
	)
	(segment
		(start 249.536966 -146.6342)
		(end 249.536966 -145.636234)
		(width 0.14224)
		(layer "In2.Cu")
		(net "M_F_BG<1>")
	)
	(segment
		(start 253.166626 -123.837192)
		(end 253.454154 -123.837192)
		(width 0.14224)
		(layer "In2.Cu")
		(net "M_F_BG<1>")
	)
	(segment
		(start 252.400562 -124.220732)
		(end 252.400562 -123.933204)
		(width 0.14224)
		(layer "In2.Cu")
		(net "M_F_BG<1>")
	)
	(segment
		(start 247.39981 -148.771356)
		(end 249.536966 -146.6342)
		(width 0.14224)
		(layer "In2.Cu")
		(net "M_F_BG<1>")
	)
	(segment
		(start 249.5804 -130.6576)
		(end 249.4788 -130.556)
		(width 0.14224)
		(layer "In2.Cu")
		(net "M_F_BG<1>")
	)
	(segment
		(start 253.454154 -123.837192)
		(end 253.8476 -123.443746)
		(width 0.14224)
		(layer "In2.Cu")
		(net "M_F_BG<1>")
	)
	(arc
		(start 253.98095 -93.517974)
		(mid 253.90803 -93.226957)
		(end 253.9873 -92.937584)
		(width 0.0889)
		(layer "In2.Cu")
		(net "M_F_BG<1>")
	)
	(arc
		(start 253.97841 -96.484948)
		(mid 253.908013 -96.195997)
		(end 253.9873 -95.909384)
		(width 0.0889)
		(layer "In2.Cu")
		(net "M_F_BG<1>")
	)
	(arc
		(start 253.97841 -95.494348)
		(mid 253.908013 -95.205397)
		(end 253.9873 -94.918784)
		(width 0.0889)
		(layer "In2.Cu")
		(net "M_F_BG<1>")
	)
	(arc
		(start 253.9873 -92.937584)
		(mid 254.040833 -92.737686)
		(end 253.9873 -92.537788)
		(width 0.0889)
		(layer "In2.Cu")
		(net "M_F_BG<1>")
	)
	(arc
		(start 253.97841 -97.475548)
		(mid 253.908013 -97.186597)
		(end 253.9873 -96.899984)
		(width 0.0889)
		(layer "In2.Cu")
		(net "M_F_BG<1>")
	)
	(arc
		(start 253.9873 -95.909384)
		(mid 254.040833 -95.709486)
		(end 253.9873 -95.509588)
		(width 0.0889)
		(layer "In2.Cu")
		(net "M_F_BG<1>")
	)
	(arc
		(start 254.0762 -98.810318)
		(mid 254.053569 -98.63996)
		(end 253.9873 -98.481388)
		(width 0.0889)
		(layer "In2.Cu")
		(net "M_F_BG<1>")
	)
	(arc
		(start 253.9873 -94.518988)
		(mid 253.908078 -94.22987)
		(end 253.98095 -93.939106)
		(width 0.0889)
		(layer "In2.Cu")
		(net "M_F_BG<1>")
	)
	(arc
		(start 253.9873 -96.899984)
		(mid 254.040833 -96.700086)
		(end 253.9873 -96.500188)
		(width 0.0889)
		(layer "In2.Cu")
		(net "M_F_BG<1>")
	)
	(arc
		(start 253.9873 -97.890584)
		(mid 254.040833 -97.690686)
		(end 253.9873 -97.490788)
		(width 0.0889)
		(layer "In2.Cu")
		(net "M_F_BG<1>")
	)
	(arc
		(start 253.97841 -98.466148)
		(mid 253.908013 -98.177197)
		(end 253.9873 -97.890584)
		(width 0.0889)
		(layer "In2.Cu")
		(net "M_F_BG<1>")
	)
	(arc
		(start 253.9873 -93.928438)
		(mid 254.040833 -93.72854)
		(end 253.9873 -93.528642)
		(width 0.0889)
		(layer "In2.Cu")
		(net "M_F_BG<1>")
	)
	(arc
		(start 253.9873 -94.918784)
		(mid 254.040833 -94.718886)
		(end 253.9873 -94.518988)
		(width 0.0889)
		(layer "In2.Cu")
		(net "M_F_BG<1>")
	)
	(segment
		(start 247.400318 -152.273)
		(end 247.39981 -152.278842)
		(width 0.1651)
		(layer "F.Cu")
		(net "M_F_BG<0>")
	)
	(segment
		(start 253.353824 -89.27084)
		(end 252.782324 -89.27084)
		(width 0.1016)
		(layer "F.Cu")
		(net "M_F_BG<0>")
	)
	(segment
		(start 247.39981 -152.278842)
		(end 247.39981 -153.542746)
		(width 0.1651)
		(layer "F.Cu")
		(net "M_F_BG<0>")
	)
	(via
		(at 247.39981 -153.542746)
		(size 0.508)
		(drill 0.254)
		(layers "F.Cu" "B.Cu")
		(net "M_F_BG<0>")
	)
	(via
		(at 247.39981 -150.788878)
		(size 0.4572)
		(drill 0.2032)
		(layers "F.Cu" "B.Cu")
		(net "M_F_BG<0>")
	)
	(via
		(at 252.782324 -89.27084)
		(size 0.508)
		(drill 0.254)
		(layers "F.Cu" "B.Cu")
		(net "M_F_BG<0>")
	)
	(segment
		(start 247.400318 -152.078436)
		(end 247.39981 -152.078182)
		(width 0.1651)
		(layer "B.Cu")
		(net "M_F_BG<0>")
	)
	(segment
		(start 247.39981 -152.078182)
		(end 247.39981 -150.788878)
		(width 0.1651)
		(layer "B.Cu")
		(net "M_F_BG<0>")
	)
	(segment
		(start 253.294134 -97.490788)
		(end 253.289308 -97.499424)
		(width 0.0889)
		(layer "In2.Cu")
		(net "M_F_BG<0>")
	)
	(segment
		(start 253.300484 -96.48952)
		(end 253.294134 -96.500188)
		(width 0.0889)
		(layer "In2.Cu")
		(net "M_F_BG<0>")
	)
	(segment
		(start 247.39981 -152.051004)
		(end 247.39981 -152.302464)
		(width 0.14224)
		(layer "In2.Cu")
		(net "M_F_BG<0>")
	)
	(segment
		(start 248.663968 -140.866368)
		(end 248.689876 -140.892276)
		(width 0.14224)
		(layer "In2.Cu")
		(net "M_F_BG<0>")
	)
	(segment
		(start 248.7676 -129.9718)
		(end 248.7676 -130.5052)
		(width 0.14224)
		(layer "In2.Cu")
		(net "M_F_BG<0>")
	)
	(segment
		(start 253.294134 -96.500188)
		(end 253.289308 -96.508824)
		(width 0.0889)
		(layer "In2.Cu")
		(net "M_F_BG<0>")
	)
	(segment
		(start 253.300484 -95.49892)
		(end 253.294134 -95.509588)
		(width 0.0889)
		(layer "In2.Cu")
		(net "M_F_BG<0>")
	)
	(segment
		(start 246.85498 -151.741124)
		(end 247.00992 -151.896064)
		(width 0.14224)
		(layer "In2.Cu")
		(net "M_F_BG<0>")
	)
	(segment
		(start 247.24487 -153.018744)
		(end 247.39981 -153.173684)
		(width 0.14224)
		(layer "In2.Cu")
		(net "M_F_BG<0>")
	)
	(segment
		(start 248.642632 -129.410968)
		(end 248.642632 -129.846832)
		(width 0.14224)
		(layer "In2.Cu")
		(net "M_F_BG<0>")
	)
	(segment
		(start 248.6152 -130.6576)
		(end 248.6152 -131.191)
		(width 0.14224)
		(layer "In2.Cu")
		(net "M_F_BG<0>")
	)
	(segment
		(start 247.39981 -151.179784)
		(end 247.24487 -151.334724)
		(width 0.14224)
		(layer "In2.Cu")
		(net "M_F_BG<0>")
	)
	(segment
		(start 253.294134 -93.928438)
		(end 253.300484 -93.939106)
		(width 0.0889)
		(layer "In2.Cu")
		(net "M_F_BG<0>")
	)
	(segment
		(start 253.294134 -91.547188)
		(end 253.289308 -91.555824)
		(width 0.0889)
		(layer "In2.Cu")
		(net "M_F_BG<0>")
	)
	(segment
		(start 248.689876 -145.010124)
		(end 248.663714 -145.036286)
		(width 0.14224)
		(layer "In2.Cu")
		(net "M_F_BG<0>")
	)
	(segment
		(start 246.98833 -149.592792)
		(end 247.39981 -150.004272)
		(width 0.14224)
		(layer "In2.Cu")
		(net "M_F_BG<0>")
	)
	(segment
		(start 247.39981 -150.788878)
		(end 247.39981 -151.179784)
		(width 0.14224)
		(layer "In2.Cu")
		(net "M_F_BG<0>")
	)
	(segment
		(start 247.00992 -151.334724)
		(end 246.85498 -151.489664)
		(width 0.14224)
		(layer "In2.Cu")
		(net "M_F_BG<0>")
	)
	(segment
		(start 253.294134 -94.518988)
		(end 253.289308 -94.527624)
		(width 0.0889)
		(layer "In2.Cu")
		(net "M_F_BG<0>")
	)
	(segment
		(start 253.294134 -90.556588)
		(end 253.289308 -90.565224)
		(width 0.0889)
		(layer "In2.Cu")
		(net "M_F_BG<0>")
	)
	(segment
		(start 253.3396 -122.2756)
		(end 249.6058 -126.0094)
		(width 0.14224)
		(layer "In2.Cu")
		(net "M_F_BG<0>")
	)
	(segment
		(start 253.294134 -92.537788)
		(end 253.289308 -92.546424)
		(width 0.0889)
		(layer "In2.Cu")
		(net "M_F_BG<0>")
	)
	(segment
		(start 248.663714 -146.636486)
		(end 246.98833 -148.31187)
		(width 0.14224)
		(layer "In2.Cu")
		(net "M_F_BG<0>")
	)
	(segment
		(start 248.68632 -131.26212)
		(end 248.68632 -135.025384)
		(width 0.14224)
		(layer "In2.Cu")
		(net "M_F_BG<0>")
	)
	(segment
		(start 247.39981 -150.004272)
		(end 247.39981 -150.788878)
		(width 0.14224)
		(layer "In2.Cu")
		(net "M_F_BG<0>")
	)
	(segment
		(start 253.294134 -98.481642)
		(end 253.294134 -98.481388)
		(width 0.0889)
		(layer "In2.Cu")
		(net "M_F_BG<0>")
	)
	(segment
		(start 248.6152 -131.191)
		(end 248.68632 -131.26212)
		(width 0.14224)
		(layer "In2.Cu")
		(net "M_F_BG<0>")
	)
	(segment
		(start 246.85498 -151.489664)
		(end 246.85498 -151.741124)
		(width 0.14224)
		(layer "In2.Cu")
		(net "M_F_BG<0>")
	)
	(segment
		(start 248.663714 -145.036286)
		(end 248.663714 -146.636486)
		(width 0.14224)
		(layer "In2.Cu")
		(net "M_F_BG<0>")
	)
	(segment
		(start 247.24487 -151.334724)
		(end 247.00992 -151.334724)
		(width 0.14224)
		(layer "In2.Cu")
		(net "M_F_BG<0>")
	)
	(segment
		(start 246.98833 -148.31187)
		(end 246.98833 -149.592792)
		(width 0.14224)
		(layer "In2.Cu")
		(net "M_F_BG<0>")
	)
	(segment
		(start 246.748808 -152.863804)
		(end 246.903748 -153.018744)
		(width 0.14224)
		(layer "In2.Cu")
		(net "M_F_BG<0>")
	)
	(segment
		(start 246.903748 -153.018744)
		(end 247.24487 -153.018744)
		(width 0.14224)
		(layer "In2.Cu")
		(net "M_F_BG<0>")
	)
	(segment
		(start 253.300484 -92.52712)
		(end 253.294134 -92.537788)
		(width 0.0889)
		(layer "In2.Cu")
		(net "M_F_BG<0>")
	)
	(segment
		(start 248.642632 -129.846832)
		(end 248.7676 -129.9718)
		(width 0.14224)
		(layer "In2.Cu")
		(net "M_F_BG<0>")
	)
	(segment
		(start 253.300484 -90.54592)
		(end 253.294134 -90.556588)
		(width 0.0889)
		(layer "In2.Cu")
		(net "M_F_BG<0>")
	)
	(segment
		(start 248.68632 -135.025384)
		(end 248.660158 -135.051546)
		(width 0.14224)
		(layer "In2.Cu")
		(net "M_F_BG<0>")
	)
	(segment
		(start 247.24487 -152.457404)
		(end 246.903748 -152.457404)
		(width 0.14224)
		(layer "In2.Cu")
		(net "M_F_BG<0>")
	)
	(segment
		(start 247.39981 -153.173684)
		(end 247.39981 -153.542746)
		(width 0.14224)
		(layer "In2.Cu")
		(net "M_F_BG<0>")
	)
	(segment
		(start 253.294134 -99.472242)
		(end 253.238 -99.57181)
		(width 0.0889)
		(layer "In2.Cu")
		(net "M_F_BG<0>")
	)
	(segment
		(start 246.748808 -152.612344)
		(end 246.748808 -152.863804)
		(width 0.14224)
		(layer "In2.Cu")
		(net "M_F_BG<0>")
	)
	(segment
		(start 247.24487 -151.896064)
		(end 247.39981 -152.051004)
		(width 0.14224)
		(layer "In2.Cu")
		(net "M_F_BG<0>")
	)
	(segment
		(start 252.782324 -89.27084)
		(end 253.25324 -89.904316)
		(width 0.0889)
		(layer "In2.Cu")
		(net "M_F_BG<0>")
	)
	(segment
		(start 248.7676 -130.5052)
		(end 248.6152 -130.6576)
		(width 0.14224)
		(layer "In2.Cu")
		(net "M_F_BG<0>")
	)
	(segment
		(start 249.6058 -126.0094)
		(end 249.6058 -128.4478)
		(width 0.14224)
		(layer "In2.Cu")
		(net "M_F_BG<0>")
	)
	(segment
		(start 248.660158 -135.051546)
		(end 248.660158 -136.75741)
		(width 0.14224)
		(layer "In2.Cu")
		(net "M_F_BG<0>")
	)
	(segment
		(start 253.238 -99.57181)
		(end 253.238 -100.06584)
		(width 0.0889)
		(layer "In2.Cu")
		(net "M_F_BG<0>")
	)
	(segment
		(start 253.3396 -100.528374)
		(end 253.3396 -122.2756)
		(width 0.14224)
		(layer "In2.Cu")
		(net "M_F_BG<0>")
	)
	(segment
		(start 248.660158 -136.75741)
		(end 248.663968 -136.76122)
		(width 0.14224)
		(layer "In2.Cu")
		(net "M_F_BG<0>")
	)
	(segment
		(start 253.238 -100.06584)
		(end 253.3396 -100.16744)
		(width 0.0889)
		(layer "In2.Cu")
		(net "M_F_BG<0>")
	)
	(segment
		(start 253.294134 -95.509588)
		(end 253.289308 -95.518224)
		(width 0.0889)
		(layer "In2.Cu")
		(net "M_F_BG<0>")
	)
	(segment
		(start 253.300484 -97.48012)
		(end 253.294134 -97.490788)
		(width 0.0889)
		(layer "In2.Cu")
		(net "M_F_BG<0>")
	)
	(segment
		(start 248.689876 -140.892276)
		(end 248.689876 -145.010124)
		(width 0.14224)
		(layer "In2.Cu")
		(net "M_F_BG<0>")
	)
	(segment
		(start 253.294134 -98.481388)
		(end 253.289308 -98.490024)
		(width 0.0889)
		(layer "In2.Cu")
		(net "M_F_BG<0>")
	)
	(segment
		(start 248.663968 -136.76122)
		(end 248.663968 -140.866368)
		(width 0.14224)
		(layer "In2.Cu")
		(net "M_F_BG<0>")
	)
	(segment
		(start 247.00992 -151.896064)
		(end 247.24487 -151.896064)
		(width 0.14224)
		(layer "In2.Cu")
		(net "M_F_BG<0>")
	)
	(segment
		(start 253.300484 -91.53652)
		(end 253.294134 -91.547188)
		(width 0.0889)
		(layer "In2.Cu")
		(net "M_F_BG<0>")
	)
	(segment
		(start 247.39981 -152.302464)
		(end 247.24487 -152.457404)
		(width 0.14224)
		(layer "In2.Cu")
		(net "M_F_BG<0>")
	)
	(segment
		(start 253.3396 -100.16744)
		(end 253.3396 -100.528374)
		(width 0.0889)
		(layer "In2.Cu")
		(net "M_F_BG<0>")
	)
	(segment
		(start 249.6058 -128.4478)
		(end 248.642632 -129.410968)
		(width 0.14224)
		(layer "In2.Cu")
		(net "M_F_BG<0>")
	)
	(segment
		(start 246.903748 -152.457404)
		(end 246.748808 -152.612344)
		(width 0.14224)
		(layer "In2.Cu")
		(net "M_F_BG<0>")
	)
	(arc
		(start 253.25324 -89.904316)
		(mid 253.37175 -90.218116)
		(end 253.300484 -90.54592)
		(width 0.0889)
		(layer "In2.Cu")
		(net "M_F_BG<0>")
	)
	(arc
		(start 253.289308 -95.518224)
		(mid 253.240553 -95.714576)
		(end 253.294134 -95.909638)
		(width 0.0889)
		(layer "In2.Cu")
		(net "M_F_BG<0>")
	)
	(arc
		(start 253.294134 -91.947238)
		(mid 253.373356 -92.236356)
		(end 253.300484 -92.52712)
		(width 0.0889)
		(layer "In2.Cu")
		(net "M_F_BG<0>")
	)
	(arc
		(start 253.300484 -93.939106)
		(mid 253.373282 -94.229869)
		(end 253.294134 -94.518988)
		(width 0.0889)
		(layer "In2.Cu")
		(net "M_F_BG<0>")
	)
	(arc
		(start 253.289308 -94.527624)
		(mid 253.240553 -94.723976)
		(end 253.294134 -94.919038)
		(width 0.0889)
		(layer "In2.Cu")
		(net "M_F_BG<0>")
	)
	(arc
		(start 253.294134 -95.909638)
		(mid 253.373356 -96.198756)
		(end 253.300484 -96.48952)
		(width 0.0889)
		(layer "In2.Cu")
		(net "M_F_BG<0>")
	)
	(arc
		(start 253.289308 -98.490024)
		(mid 253.240553 -98.686376)
		(end 253.294134 -98.881438)
		(width 0.0889)
		(layer "In2.Cu")
		(net "M_F_BG<0>")
	)
	(arc
		(start 253.289308 -90.565224)
		(mid 253.240553 -90.761576)
		(end 253.294134 -90.956638)
		(width 0.0889)
		(layer "In2.Cu")
		(net "M_F_BG<0>")
	)
	(arc
		(start 253.294134 -96.900238)
		(mid 253.373356 -97.189356)
		(end 253.300484 -97.48012)
		(width 0.0889)
		(layer "In2.Cu")
		(net "M_F_BG<0>")
	)
	(arc
		(start 253.294134 -97.890838)
		(mid 253.373265 -98.18624)
		(end 253.294134 -98.481642)
		(width 0.0889)
		(layer "In2.Cu")
		(net "M_F_BG<0>")
	)
	(arc
		(start 253.294134 -93.528642)
		(mid 253.240635 -93.72854)
		(end 253.294134 -93.928438)
		(width 0.0889)
		(layer "In2.Cu")
		(net "M_F_BG<0>")
	)
	(arc
		(start 253.294134 -90.956638)
		(mid 253.373356 -91.245756)
		(end 253.300484 -91.53652)
		(width 0.0889)
		(layer "In2.Cu")
		(net "M_F_BG<0>")
	)
	(arc
		(start 253.289308 -91.555824)
		(mid 253.240553 -91.752176)
		(end 253.294134 -91.947238)
		(width 0.0889)
		(layer "In2.Cu")
		(net "M_F_BG<0>")
	)
	(arc
		(start 253.289308 -92.546424)
		(mid 253.240553 -92.742776)
		(end 253.294134 -92.937838)
		(width 0.0889)
		(layer "In2.Cu")
		(net "M_F_BG<0>")
	)
	(arc
		(start 253.289308 -96.508824)
		(mid 253.240553 -96.705176)
		(end 253.294134 -96.900238)
		(width 0.0889)
		(layer "In2.Cu")
		(net "M_F_BG<0>")
	)
	(arc
		(start 253.294134 -98.881438)
		(mid 253.373265 -99.17684)
		(end 253.294134 -99.472242)
		(width 0.0889)
		(layer "In2.Cu")
		(net "M_F_BG<0>")
	)
	(arc
		(start 253.294134 -94.919038)
		(mid 253.373356 -95.208156)
		(end 253.300484 -95.49892)
		(width 0.0889)
		(layer "In2.Cu")
		(net "M_F_BG<0>")
	)
	(arc
		(start 253.289308 -97.499424)
		(mid 253.240553 -97.695776)
		(end 253.294134 -97.890838)
		(width 0.0889)
		(layer "In2.Cu")
		(net "M_F_BG<0>")
	)
	(arc
		(start 253.294134 -92.937838)
		(mid 253.373265 -93.23324)
		(end 253.294134 -93.528642)
		(width 0.0889)
		(layer "In2.Cu")
		(net "M_F_BG<0>")
	)
	(segment
		(start 258.50469 -90.26144)
		(end 257.93319 -90.26144)
		(width 0.1016)
		(layer "F.Cu")
		(net "M_F_BA<1>")
	)
	(segment
		(start 266.949936 -156.87294)
		(end 266.950444 -156.87294)
		(width 0.1651)
		(layer "F.Cu")
		(net "M_F_BA<1>")
	)
	(segment
		(start 266.949936 -155.615132)
		(end 266.949936 -156.87294)
		(width 0.1651)
		(layer "F.Cu")
		(net "M_F_BA<1>")
	)
	(via
		(at 266.949936 -155.615132)
		(size 0.508)
		(drill 0.254)
		(layers "F.Cu" "B.Cu")
		(net "M_F_BA<1>")
	)
	(via
		(at 257.93319 -90.26144)
		(size 0.508)
		(drill 0.254)
		(layers "F.Cu" "B.Cu")
		(net "M_F_BA<1>")
	)
	(via
		(at 266.95019 -148.773388)
		(size 0.4572)
		(drill 0.2032)
		(layers "F.Cu" "B.Cu")
		(net "M_F_BA<1>")
	)
	(segment
		(start 266.949936 -148.773134)
		(end 266.95019 -148.773388)
		(width 0.1651)
		(layer "B.Cu")
		(net "M_F_BA<1>")
	)
	(segment
		(start 266.949936 -147.478496)
		(end 266.949936 -148.773134)
		(width 0.1651)
		(layer "B.Cu")
		(net "M_F_BA<1>")
	)
	(segment
		(start 266.950444 -147.478496)
		(end 266.949936 -147.478496)
		(width 0.1651)
		(layer "B.Cu")
		(net "M_F_BA<1>")
	)
	(segment
		(start 266.509754 -150.549864)
		(end 266.509754 -151.142954)
		(width 0.14224)
		(layer "In11.Cu")
		(net "M_F_BA<1>")
	)
	(segment
		(start 260.8326 -127.714502)
		(end 260.8326 -136.0424)
		(width 0.14224)
		(layer "In11.Cu")
		(net "M_F_BA<1>")
	)
	(segment
		(start 265.568684 -147.391882)
		(end 266.95019 -148.773388)
		(width 0.14224)
		(layer "In11.Cu")
		(net "M_F_BA<1>")
	)
	(segment
		(start 266.593574 -151.226774)
		(end 266.593574 -153.808938)
		(width 0.14224)
		(layer "In11.Cu")
		(net "M_F_BA<1>")
	)
	(segment
		(start 258.2291 -100.2919)
		(end 259.679948 -101.742748)
		(width 0.14224)
		(layer "In11.Cu")
		(net "M_F_BA<1>")
	)
	(segment
		(start 266.509754 -151.142954)
		(end 266.593574 -151.226774)
		(width 0.14224)
		(layer "In11.Cu")
		(net "M_F_BA<1>")
	)
	(segment
		(start 266.949936 -154.994864)
		(end 266.949936 -155.615132)
		(width 0.14224)
		(layer "In11.Cu")
		(net "M_F_BA<1>")
	)
	(segment
		(start 258.0894 -98.106992)
		(end 258.0894 -100.1522)
		(width 0.0889)
		(layer "In11.Cu")
		(net "M_F_BA<1>")
	)
	(segment
		(start 259.679948 -101.742748)
		(end 259.679948 -126.56185)
		(width 0.14224)
		(layer "In11.Cu")
		(net "M_F_BA<1>")
	)
	(segment
		(start 261.5438 -145.951448)
		(end 262.984234 -147.391882)
		(width 0.14224)
		(layer "In11.Cu")
		(net "M_F_BA<1>")
	)
	(segment
		(start 266.593574 -153.808938)
		(end 266.47267 -153.929842)
		(width 0.14224)
		(layer "In11.Cu")
		(net "M_F_BA<1>")
	)
	(segment
		(start 266.95019 -150.109428)
		(end 266.509754 -150.549864)
		(width 0.14224)
		(layer "In11.Cu")
		(net "M_F_BA<1>")
	)
	(segment
		(start 260.8326 -136.0424)
		(end 261.5438 -136.7536)
		(width 0.14224)
		(layer "In11.Cu")
		(net "M_F_BA<1>")
	)
	(segment
		(start 266.47267 -154.517598)
		(end 266.949936 -154.994864)
		(width 0.14224)
		(layer "In11.Cu")
		(net "M_F_BA<1>")
	)
	(segment
		(start 259.679948 -126.56185)
		(end 260.8326 -127.714502)
		(width 0.14224)
		(layer "In11.Cu")
		(net "M_F_BA<1>")
	)
	(segment
		(start 257.93319 -90.26144)
		(end 258.245102 -90.981276)
		(width 0.0889)
		(layer "In11.Cu")
		(net "M_F_BA<1>")
	)
	(segment
		(start 261.5438 -136.7536)
		(end 261.5438 -145.951448)
		(width 0.14224)
		(layer "In11.Cu")
		(net "M_F_BA<1>")
	)
	(segment
		(start 266.95019 -148.773388)
		(end 266.95019 -150.109428)
		(width 0.14224)
		(layer "In11.Cu")
		(net "M_F_BA<1>")
	)
	(segment
		(start 258.0894 -100.1522)
		(end 258.2291 -100.2919)
		(width 0.0889)
		(layer "In11.Cu")
		(net "M_F_BA<1>")
	)
	(segment
		(start 262.984234 -147.391882)
		(end 265.568684 -147.391882)
		(width 0.14224)
		(layer "In11.Cu")
		(net "M_F_BA<1>")
	)
	(segment
		(start 266.47267 -153.929842)
		(end 266.47267 -154.517598)
		(width 0.14224)
		(layer "In11.Cu")
		(net "M_F_BA<1>")
	)
	(arc
		(start 258.2799 -96.004888)
		(mid 258.333399 -96.204786)
		(end 258.2799 -96.404684)
		(width 0.0889)
		(layer "In11.Cu")
		(net "M_F_BA<1>")
	)
	(arc
		(start 258.2799 -91.051888)
		(mid 258.333399 -91.251786)
		(end 258.2799 -91.451684)
		(width 0.0889)
		(layer "In11.Cu")
		(net "M_F_BA<1>")
	)
	(arc
		(start 258.2799 -93.432884)
		(mid 258.200769 -93.728286)
		(end 258.2799 -94.023688)
		(width 0.0889)
		(layer "In11.Cu")
		(net "M_F_BA<1>")
	)
	(arc
		(start 258.2799 -93.033088)
		(mid 258.333399 -93.232986)
		(end 258.2799 -93.432884)
		(width 0.0889)
		(layer "In11.Cu")
		(net "M_F_BA<1>")
	)
	(arc
		(start 258.2799 -91.451684)
		(mid 258.200769 -91.747086)
		(end 258.2799 -92.042488)
		(width 0.0889)
		(layer "In11.Cu")
		(net "M_F_BA<1>")
	)
	(arc
		(start 258.2799 -96.404684)
		(mid 258.200769 -96.700086)
		(end 258.2799 -96.995488)
		(width 0.0889)
		(layer "In11.Cu")
		(net "M_F_BA<1>")
	)
	(arc
		(start 258.2799 -94.423484)
		(mid 258.200769 -94.718886)
		(end 258.2799 -95.014288)
		(width 0.0889)
		(layer "In11.Cu")
		(net "M_F_BA<1>")
	)
	(arc
		(start 258.2799 -97.395284)
		(mid 258.137895 -97.738619)
		(end 258.0894 -98.106992)
		(width 0.0889)
		(layer "In11.Cu")
		(net "M_F_BA<1>")
	)
	(arc
		(start 258.2799 -92.442284)
		(mid 258.200769 -92.737686)
		(end 258.2799 -93.033088)
		(width 0.0889)
		(layer "In11.Cu")
		(net "M_F_BA<1>")
	)
	(arc
		(start 258.2799 -95.414084)
		(mid 258.200769 -95.709486)
		(end 258.2799 -96.004888)
		(width 0.0889)
		(layer "In11.Cu")
		(net "M_F_BA<1>")
	)
	(arc
		(start 258.2799 -96.995488)
		(mid 258.333399 -97.195386)
		(end 258.2799 -97.395284)
		(width 0.0889)
		(layer "In11.Cu")
		(net "M_F_BA<1>")
	)
	(arc
		(start 258.2799 -92.042488)
		(mid 258.333399 -92.242386)
		(end 258.2799 -92.442284)
		(width 0.0889)
		(layer "In11.Cu")
		(net "M_F_BA<1>")
	)
	(arc
		(start 258.2799 -95.014288)
		(mid 258.333399 -95.214186)
		(end 258.2799 -95.414084)
		(width 0.0889)
		(layer "In11.Cu")
		(net "M_F_BA<1>")
	)
	(arc
		(start 258.245102 -90.981276)
		(mid 258.26132 -91.017164)
		(end 258.2799 -91.051888)
		(width 0.0889)
		(layer "In11.Cu")
		(net "M_F_BA<1>")
	)
	(arc
		(start 258.2799 -94.023688)
		(mid 258.333399 -94.223586)
		(end 258.2799 -94.423484)
		(width 0.0889)
		(layer "In11.Cu")
		(net "M_F_BA<1>")
	)
	(segment
		(start 261.93877 -93.23324)
		(end 261.36727 -93.23324)
		(width 0.1016)
		(layer "F.Cu")
		(net "M_F_BA<0>")
	)
	(segment
		(start 267.800328 -152.273)
		(end 267.79982 -152.278842)
		(width 0.1651)
		(layer "F.Cu")
		(net "M_F_BA<0>")
	)
	(segment
		(start 267.79982 -152.278842)
		(end 267.79982 -153.542746)
		(width 0.1651)
		(layer "F.Cu")
		(net "M_F_BA<0>")
	)
	(via
		(at 267.79982 -153.542746)
		(size 0.508)
		(drill 0.254)
		(layers "F.Cu" "B.Cu")
		(net "M_F_BA<0>")
	)
	(via
		(at 267.800074 -150.788878)
		(size 0.4572)
		(drill 0.2032)
		(layers "F.Cu" "B.Cu")
		(net "M_F_BA<0>")
	)
	(via
		(at 261.36727 -93.23324)
		(size 0.508)
		(drill 0.254)
		(layers "F.Cu" "B.Cu")
		(net "M_F_BA<0>")
	)
	(segment
		(start 267.79982 -150.789132)
		(end 267.800074 -150.788878)
		(width 0.1651)
		(layer "B.Cu")
		(net "M_F_BA<0>")
	)
	(segment
		(start 267.79982 -152.078182)
		(end 267.79982 -150.789132)
		(width 0.1651)
		(layer "B.Cu")
		(net "M_F_BA<0>")
	)
	(segment
		(start 267.800328 -152.078436)
		(end 267.79982 -152.078182)
		(width 0.1651)
		(layer "B.Cu")
		(net "M_F_BA<0>")
	)
	(segment
		(start 267.652754 -153.39568)
		(end 267.79982 -153.542746)
		(width 0.14224)
		(layer "In2.Cu")
		(net "M_F_BA<0>")
	)
	(segment
		(start 261.718806 -97.386902)
		(end 261.71398 -97.395538)
		(width 0.0889)
		(layer "In2.Cu")
		(net "M_F_BA<0>")
	)
	(segment
		(start 266.535408 -133.845808)
		(end 266.535408 -135.395208)
		(width 0.14224)
		(layer "In2.Cu")
		(net "M_F_BA<0>")
	)
	(segment
		(start 261.718806 -95.405702)
		(end 261.71398 -95.414338)
		(width 0.0889)
		(layer "In2.Cu")
		(net "M_F_BA<0>")
	)
	(segment
		(start 261.718806 -96.396302)
		(end 261.71398 -96.404938)
		(width 0.0889)
		(layer "In2.Cu")
		(net "M_F_BA<0>")
	)
	(segment
		(start 262.3312 -124.945648)
		(end 262.5852 -125.199648)
		(width 0.14224)
		(layer "In2.Cu")
		(net "M_F_BA<0>")
	)
	(segment
		(start 261.718806 -98.377502)
		(end 261.71398 -98.386138)
		(width 0.0889)
		(layer "In2.Cu")
		(net "M_F_BA<0>")
	)
	(segment
		(start 267.652754 -150.936198)
		(end 267.652754 -153.39568)
		(width 0.14224)
		(layer "In2.Cu")
		(net "M_F_BA<0>")
	)
	(segment
		(start 266.53617 -140.80363)
		(end 266.513056 -140.826744)
		(width 0.14224)
		(layer "In2.Cu")
		(net "M_F_BA<0>")
	)
	(segment
		(start 261.36727 -93.23324)
		(end 261.669022 -93.927168)
		(width 0.0889)
		(layer "In2.Cu")
		(net "M_F_BA<0>")
	)
	(segment
		(start 261.71398 -97.395538)
		(end 261.70763 -97.406206)
		(width 0.0889)
		(layer "In2.Cu")
		(net "M_F_BA<0>")
	)
	(segment
		(start 262.3312 -102.318312)
		(end 262.3312 -124.945648)
		(width 0.14224)
		(layer "In2.Cu")
		(net "M_F_BA<0>")
	)
	(segment
		(start 262.872728 -125.199648)
		(end 263.15797 -124.914406)
		(width 0.14224)
		(layer "In2.Cu")
		(net "M_F_BA<0>")
	)
	(segment
		(start 261.70763 -94.01302)
		(end 261.71398 -94.023688)
		(width 0.0889)
		(layer "In2.Cu")
		(net "M_F_BA<0>")
	)
	(segment
		(start 266.571476 -130.603244)
		(end 266.571476 -131.243324)
		(width 0.14224)
		(layer "In2.Cu")
		(net "M_F_BA<0>")
	)
	(segment
		(start 261.76859 -101.226366)
		(end 262.3312 -101.788976)
		(width 0.0889)
		(layer "In2.Cu")
		(net "M_F_BA<0>")
	)
	(segment
		(start 266.535408 -147.275296)
		(end 267.362178 -148.102066)
		(width 0.14224)
		(layer "In2.Cu")
		(net "M_F_BA<0>")
	)
	(segment
		(start 261.76859 -99.36861)
		(end 261.76859 -101.226366)
		(width 0.0889)
		(layer "In2.Cu")
		(net "M_F_BA<0>")
	)
	(segment
		(start 261.7724 -99.3648)
		(end 261.76859 -99.36861)
		(width 0.0889)
		(layer "In2.Cu")
		(net "M_F_BA<0>")
	)
	(segment
		(start 266.44854 -129.94386)
		(end 266.44854 -130.480308)
		(width 0.14224)
		(layer "In2.Cu")
		(net "M_F_BA<0>")
	)
	(segment
		(start 262.5852 -125.199648)
		(end 262.872728 -125.199648)
		(width 0.14224)
		(layer "In2.Cu")
		(net "M_F_BA<0>")
	)
	(segment
		(start 267.362178 -148.102066)
		(end 267.362178 -149.150578)
		(width 0.14224)
		(layer "In2.Cu")
		(net "M_F_BA<0>")
	)
	(segment
		(start 261.71398 -98.386138)
		(end 261.70763 -98.396806)
		(width 0.0889)
		(layer "In2.Cu")
		(net "M_F_BA<0>")
	)
	(segment
		(start 266.571476 -131.243324)
		(end 266.4714 -131.3434)
		(width 0.14224)
		(layer "In2.Cu")
		(net "M_F_BA<0>")
	)
	(segment
		(start 267.800074 -150.788878)
		(end 267.652754 -150.936198)
		(width 0.14224)
		(layer "In2.Cu")
		(net "M_F_BA<0>")
	)
	(segment
		(start 266.687046 -141.642846)
		(end 266.687046 -142.953994)
		(width 0.14224)
		(layer "In2.Cu")
		(net "M_F_BA<0>")
	)
	(segment
		(start 266.53617 -135.39597)
		(end 266.53617 -140.80363)
		(width 0.14224)
		(layer "In2.Cu")
		(net "M_F_BA<0>")
	)
	(segment
		(start 263.732772 -125.20168)
		(end 263.732772 -125.489208)
		(width 0.14224)
		(layer "In2.Cu")
		(net "M_F_BA<0>")
	)
	(segment
		(start 266.687046 -142.953994)
		(end 266.535408 -143.105632)
		(width 0.14224)
		(layer "In2.Cu")
		(net "M_F_BA<0>")
	)
	(segment
		(start 266.513056 -140.826744)
		(end 266.513056 -141.468856)
		(width 0.14224)
		(layer "In2.Cu")
		(net "M_F_BA<0>")
	)
	(segment
		(start 262.3312 -101.788976)
		(end 262.3312 -102.318312)
		(width 0.0889)
		(layer "In2.Cu")
		(net "M_F_BA<0>")
	)
	(segment
		(start 266.513056 -141.468856)
		(end 266.687046 -141.642846)
		(width 0.14224)
		(layer "In2.Cu")
		(net "M_F_BA<0>")
	)
	(segment
		(start 261.71398 -95.414338)
		(end 261.70763 -95.425006)
		(width 0.0889)
		(layer "In2.Cu")
		(net "M_F_BA<0>")
	)
	(segment
		(start 261.71398 -96.404938)
		(end 261.70763 -96.415606)
		(width 0.0889)
		(layer "In2.Cu")
		(net "M_F_BA<0>")
	)
	(segment
		(start 263.732772 -125.489208)
		(end 263.44753 -125.77445)
		(width 0.14224)
		(layer "In2.Cu")
		(net "M_F_BA<0>")
	)
	(segment
		(start 267.362178 -149.150578)
		(end 267.800074 -149.588474)
		(width 0.14224)
		(layer "In2.Cu")
		(net "M_F_BA<0>")
	)
	(segment
		(start 267.800074 -149.588474)
		(end 267.800074 -150.788878)
		(width 0.14224)
		(layer "In2.Cu")
		(net "M_F_BA<0>")
	)
	(segment
		(start 263.15797 -124.914406)
		(end 263.445498 -124.914406)
		(width 0.14224)
		(layer "In2.Cu")
		(net "M_F_BA<0>")
	)
	(segment
		(start 263.44753 -125.77445)
		(end 263.44753 -126.061978)
		(width 0.14224)
		(layer "In2.Cu")
		(net "M_F_BA<0>")
	)
	(segment
		(start 266.535408 -143.105632)
		(end 266.535408 -147.275296)
		(width 0.14224)
		(layer "In2.Cu")
		(net "M_F_BA<0>")
	)
	(segment
		(start 266.44854 -130.480308)
		(end 266.571476 -130.603244)
		(width 0.14224)
		(layer "In2.Cu")
		(net "M_F_BA<0>")
	)
	(segment
		(start 266.4714 -133.7818)
		(end 266.535408 -133.845808)
		(width 0.14224)
		(layer "In2.Cu")
		(net "M_F_BA<0>")
	)
	(segment
		(start 263.44753 -126.061978)
		(end 266.564364 -129.178812)
		(width 0.14224)
		(layer "In2.Cu")
		(net "M_F_BA<0>")
	)
	(segment
		(start 266.564364 -129.178812)
		(end 266.564364 -129.828036)
		(width 0.14224)
		(layer "In2.Cu")
		(net "M_F_BA<0>")
	)
	(segment
		(start 263.445498 -124.914406)
		(end 263.732772 -125.20168)
		(width 0.14224)
		(layer "In2.Cu")
		(net "M_F_BA<0>")
	)
	(segment
		(start 266.564364 -129.828036)
		(end 266.44854 -129.94386)
		(width 0.14224)
		(layer "In2.Cu")
		(net "M_F_BA<0>")
	)
	(segment
		(start 266.4714 -131.3434)
		(end 266.4714 -133.7818)
		(width 0.14224)
		(layer "In2.Cu")
		(net "M_F_BA<0>")
	)
	(segment
		(start 266.535408 -135.395208)
		(end 266.53617 -135.39597)
		(width 0.14224)
		(layer "In2.Cu")
		(net "M_F_BA<0>")
	)
	(arc
		(start 261.70763 -98.396806)
		(mid 261.634832 -98.687569)
		(end 261.71398 -98.976688)
		(width 0.0889)
		(layer "In2.Cu")
		(net "M_F_BA<0>")
	)
	(arc
		(start 261.70763 -97.406206)
		(mid 261.634832 -97.696969)
		(end 261.71398 -97.986088)
		(width 0.0889)
		(layer "In2.Cu")
		(net "M_F_BA<0>")
	)
	(arc
		(start 261.71398 -94.423484)
		(mid 261.634849 -94.718886)
		(end 261.71398 -95.014288)
		(width 0.0889)
		(layer "In2.Cu")
		(net "M_F_BA<0>")
	)
	(arc
		(start 261.70763 -95.425006)
		(mid 261.634832 -95.715769)
		(end 261.71398 -96.004888)
		(width 0.0889)
		(layer "In2.Cu")
		(net "M_F_BA<0>")
	)
	(arc
		(start 261.71398 -96.995488)
		(mid 261.76745 -97.190551)
		(end 261.718806 -97.386902)
		(width 0.0889)
		(layer "In2.Cu")
		(net "M_F_BA<0>")
	)
	(arc
		(start 261.70763 -96.415606)
		(mid 261.634832 -96.706369)
		(end 261.71398 -96.995488)
		(width 0.0889)
		(layer "In2.Cu")
		(net "M_F_BA<0>")
	)
	(arc
		(start 261.71398 -95.014288)
		(mid 261.76745 -95.209351)
		(end 261.718806 -95.405702)
		(width 0.0889)
		(layer "In2.Cu")
		(net "M_F_BA<0>")
	)
	(arc
		(start 261.71398 -94.023688)
		(mid 261.767479 -94.223586)
		(end 261.71398 -94.423484)
		(width 0.0889)
		(layer "In2.Cu")
		(net "M_F_BA<0>")
	)
	(arc
		(start 261.71398 -97.986088)
		(mid 261.76745 -98.181151)
		(end 261.718806 -98.377502)
		(width 0.0889)
		(layer "In2.Cu")
		(net "M_F_BA<0>")
	)
	(arc
		(start 261.71398 -98.976688)
		(mid 261.779989 -99.165212)
		(end 261.7724 -99.3648)
		(width 0.0889)
		(layer "In2.Cu")
		(net "M_F_BA<0>")
	)
	(arc
		(start 261.669022 -93.927168)
		(mid 261.686612 -93.970865)
		(end 261.70763 -94.01302)
		(width 0.0889)
		(layer "In2.Cu")
		(net "M_F_BA<0>")
	)
	(arc
		(start 261.71398 -96.004888)
		(mid 261.76745 -96.199951)
		(end 261.718806 -96.396302)
		(width 0.0889)
		(layer "In2.Cu")
		(net "M_F_BA<0>")
	)
	(segment
		(start 248.249948 -156.87294)
		(end 248.249948 -155.564078)
		(width 0.1651)
		(layer "F.Cu")
		(net "M_F_ALERT_N")
	)
	(segment
		(start 248.250456 -156.87294)
		(end 248.249948 -156.87294)
		(width 0.1651)
		(layer "F.Cu")
		(net "M_F_ALERT_N")
	)
	(segment
		(start 254.212344 -90.756486)
		(end 253.640844 -90.756486)
		(width 0.1651)
		(layer "F.Cu")
		(net "M_F_ALERT_N")
	)
	(via
		(at 253.640844 -90.756486)
		(size 0.508)
		(drill 0.254)
		(layers "F.Cu" "B.Cu")
		(net "M_F_ALERT_N")
	)
	(via
		(at 248.249948 -148.771356)
		(size 0.4572)
		(drill 0.2032)
		(layers "F.Cu" "B.Cu")
		(net "M_F_ALERT_N")
	)
	(via
		(at 248.249948 -155.564078)
		(size 0.508)
		(drill 0.254)
		(layers "F.Cu" "B.Cu")
		(net "M_F_ALERT_N")
	)
	(segment
		(start 248.250456 -147.478496)
		(end 248.249948 -147.478496)
		(width 0.1651)
		(layer "B.Cu")
		(net "M_F_ALERT_N")
	)
	(segment
		(start 248.249948 -147.478496)
		(end 248.249948 -148.771356)
		(width 0.1651)
		(layer "B.Cu")
		(net "M_F_ALERT_N")
	)
	(segment
		(start 255.69799 -96.48952)
		(end 255.70434 -96.500188)
		(width 0.0889)
		(layer "In11.Cu")
		(net "M_F_ALERT_N")
	)
	(segment
		(start 251.216414 -146.325844)
		(end 250.984258 -146.558)
		(width 0.14224)
		(layer "In11.Cu")
		(net "M_F_ALERT_N")
	)
	(segment
		(start 254.73279 -130.686302)
		(end 254.73279 -131.236974)
		(width 0.14224)
		(layer "In11.Cu")
		(net "M_F_ALERT_N")
	)
	(segment
		(start 252.910848 -144.319752)
		(end 252.6284 -144.6022)
		(width 0.14224)
		(layer "In11.Cu")
		(net "M_F_ALERT_N")
	)
	(segment
		(start 254.634746 -138.261344)
		(end 254.634746 -139.971526)
		(width 0.14224)
		(layer "In11.Cu")
		(net "M_F_ALERT_N")
	)
	(segment
		(start 247.813068 -151.217884)
		(end 246.9134 -152.117552)
		(width 0.14224)
		(layer "In11.Cu")
		(net "M_F_ALERT_N")
	)
	(segment
		(start 255.463548 -137.432542)
		(end 254.634746 -138.261344)
		(width 0.14224)
		(layer "In11.Cu")
		(net "M_F_ALERT_N")
	)
	(segment
		(start 257.139948 -102.834948)
		(end 257.139948 -124.665486)
		(width 0.14224)
		(layer "In11.Cu")
		(net "M_F_ALERT_N")
	)
	(segment
		(start 253.97841 -92.522548)
		(end 253.9873 -92.537788)
		(width 0.0889)
		(layer "In11.Cu")
		(net "M_F_ALERT_N")
	)
	(segment
		(start 255.784604 -96.804734)
		(end 255.784604 -98.68662)
		(width 0.0889)
		(layer "In11.Cu")
		(net "M_F_ALERT_N")
	)
	(segment
		(start 254.520954 -129.816352)
		(end 254.520954 -130.474466)
		(width 0.14224)
		(layer "In11.Cu")
		(net "M_F_ALERT_N")
	)
	(segment
		(start 255.6002 -133.153404)
		(end 255.6002 -133.8834)
		(width 0.14224)
		(layer "In11.Cu")
		(net "M_F_ALERT_N")
	)
	(segment
		(start 255.463548 -136.186164)
		(end 255.463548 -137.432542)
		(width 0.14224)
		(layer "In11.Cu")
		(net "M_F_ALERT_N")
	)
	(segment
		(start 249.3772 -147.644104)
		(end 248.249948 -148.771356)
		(width 0.14224)
		(layer "In11.Cu")
		(net "M_F_ALERT_N")
	)
	(segment
		(start 248.249948 -154.949652)
		(end 248.249948 -155.564078)
		(width 0.14224)
		(layer "In11.Cu")
		(net "M_F_ALERT_N")
	)
	(segment
		(start 251.216414 -145.734786)
		(end 251.216414 -146.325844)
		(width 0.14224)
		(layer "In11.Cu")
		(net "M_F_ALERT_N")
	)
	(segment
		(start 249.3772 -146.812)
		(end 249.3772 -147.644104)
		(width 0.14224)
		(layer "In11.Cu")
		(net "M_F_ALERT_N")
	)
	(segment
		(start 257.139948 -124.665486)
		(end 255.6002 -126.205234)
		(width 0.14224)
		(layer "In11.Cu")
		(net "M_F_ALERT_N")
	)
	(segment
		(start 253.783846 -141.516354)
		(end 252.910848 -142.389352)
		(width 0.14224)
		(layer "In11.Cu")
		(net "M_F_ALERT_N")
	)
	(segment
		(start 252.6284 -144.6022)
		(end 252.349 -144.6022)
		(width 0.14224)
		(layer "In11.Cu")
		(net "M_F_ALERT_N")
	)
	(segment
		(start 255.321308 -136.043924)
		(end 255.463548 -136.186164)
		(width 0.14224)
		(layer "In11.Cu")
		(net "M_F_ALERT_N")
	)
	(segment
		(start 253.640844 -90.756486)
		(end 253.970536 -91.518232)
		(width 0.0889)
		(layer "In11.Cu")
		(net "M_F_ALERT_N")
	)
	(segment
		(start 247.813068 -149.208236)
		(end 247.813068 -151.217884)
		(width 0.14224)
		(layer "In11.Cu")
		(net "M_F_ALERT_N")
	)
	(segment
		(start 255.321308 -134.853172)
		(end 255.321308 -136.043924)
		(width 0.14224)
		(layer "In11.Cu")
		(net "M_F_ALERT_N")
	)
	(segment
		(start 253.970536 -91.518232)
		(end 253.9873 -91.547188)
		(width 0.0889)
		(layer "In11.Cu")
		(net "M_F_ALERT_N")
	)
	(segment
		(start 250.984258 -146.558)
		(end 249.6312 -146.558)
		(width 0.14224)
		(layer "In11.Cu")
		(net "M_F_ALERT_N")
	)
	(segment
		(start 254.579628 -132.132832)
		(end 255.6002 -133.153404)
		(width 0.14224)
		(layer "In11.Cu")
		(net "M_F_ALERT_N")
	)
	(segment
		(start 254.520954 -130.474466)
		(end 254.73279 -130.686302)
		(width 0.14224)
		(layer "In11.Cu")
		(net "M_F_ALERT_N")
	)
	(segment
		(start 253.783846 -140.822426)
		(end 253.783846 -141.516354)
		(width 0.14224)
		(layer "In11.Cu")
		(net "M_F_ALERT_N")
	)
	(segment
		(start 256.286 -101.981)
		(end 257.139948 -102.834948)
		(width 0.14224)
		(layer "In11.Cu")
		(net "M_F_ALERT_N")
	)
	(segment
		(start 255.69799 -95.49892)
		(end 255.70434 -95.509588)
		(width 0.0889)
		(layer "In11.Cu")
		(net "M_F_ALERT_N")
	)
	(segment
		(start 246.9134 -152.117552)
		(end 246.9134 -153.70302)
		(width 0.14224)
		(layer "In11.Cu")
		(net "M_F_ALERT_N")
	)
	(segment
		(start 254.634746 -139.971526)
		(end 253.783846 -140.822426)
		(width 0.14224)
		(layer "In11.Cu")
		(net "M_F_ALERT_N")
	)
	(segment
		(start 255.46304 -134.02056)
		(end 255.46304 -134.71144)
		(width 0.14224)
		(layer "In11.Cu")
		(net "M_F_ALERT_N")
	)
	(segment
		(start 247.300242 -153.999946)
		(end 248.249948 -154.949652)
		(width 0.14224)
		(layer "In11.Cu")
		(net "M_F_ALERT_N")
	)
	(segment
		(start 255.6002 -126.205234)
		(end 255.6002 -128.737106)
		(width 0.14224)
		(layer "In11.Cu")
		(net "M_F_ALERT_N")
	)
	(segment
		(start 255.70434 -96.500188)
		(end 255.709166 -96.508824)
		(width 0.0889)
		(layer "In11.Cu")
		(net "M_F_ALERT_N")
	)
	(segment
		(start 255.987804 -98.88982)
		(end 255.987804 -101.682804)
		(width 0.0889)
		(layer "In11.Cu")
		(net "M_F_ALERT_N")
	)
	(segment
		(start 252.349 -144.6022)
		(end 251.216414 -145.734786)
		(width 0.14224)
		(layer "In11.Cu")
		(net "M_F_ALERT_N")
	)
	(segment
		(start 255.70434 -95.509588)
		(end 255.709166 -95.518224)
		(width 0.0889)
		(layer "In11.Cu")
		(net "M_F_ALERT_N")
	)
	(segment
		(start 255.46304 -134.71144)
		(end 255.321308 -134.853172)
		(width 0.14224)
		(layer "In11.Cu")
		(net "M_F_ALERT_N")
	)
	(segment
		(start 255.987804 -101.682804)
		(end 256.286 -101.981)
		(width 0.0889)
		(layer "In11.Cu")
		(net "M_F_ALERT_N")
	)
	(segment
		(start 254.73279 -131.236974)
		(end 254.579628 -131.390136)
		(width 0.14224)
		(layer "In11.Cu")
		(net "M_F_ALERT_N")
	)
	(segment
		(start 254.47752 -93.82379)
		(end 254.517144 -93.82379)
		(width 0.0889)
		(layer "In11.Cu")
		(net "M_F_ALERT_N")
	)
	(segment
		(start 255.33985 -94.31909)
		(end 255.375664 -94.31909)
		(width 0.0889)
		(layer "In11.Cu")
		(net "M_F_ALERT_N")
	)
	(segment
		(start 255.784604 -98.68662)
		(end 255.987804 -98.88982)
		(width 0.0889)
		(layer "In11.Cu")
		(net "M_F_ALERT_N")
	)
	(segment
		(start 252.910848 -142.389352)
		(end 252.910848 -144.319752)
		(width 0.14224)
		(layer "In11.Cu")
		(net "M_F_ALERT_N")
	)
	(segment
		(start 247.210326 -153.999946)
		(end 247.300242 -153.999946)
		(width 0.14224)
		(layer "In11.Cu")
		(net "M_F_ALERT_N")
	)
	(segment
		(start 246.9134 -153.70302)
		(end 247.210326 -153.999946)
		(width 0.14224)
		(layer "In11.Cu")
		(net "M_F_ALERT_N")
	)
	(segment
		(start 249.6312 -146.558)
		(end 249.3772 -146.812)
		(width 0.14224)
		(layer "In11.Cu")
		(net "M_F_ALERT_N")
	)
	(segment
		(start 255.6002 -128.737106)
		(end 254.520954 -129.816352)
		(width 0.14224)
		(layer "In11.Cu")
		(net "M_F_ALERT_N")
	)
	(segment
		(start 254.579628 -131.390136)
		(end 254.579628 -132.132832)
		(width 0.14224)
		(layer "In11.Cu")
		(net "M_F_ALERT_N")
	)
	(segment
		(start 255.6002 -133.8834)
		(end 255.46304 -134.02056)
		(width 0.14224)
		(layer "In11.Cu")
		(net "M_F_ALERT_N")
	)
	(segment
		(start 248.249948 -148.771356)
		(end 247.813068 -149.208236)
		(width 0.14224)
		(layer "In11.Cu")
		(net "M_F_ALERT_N")
	)
	(arc
		(start 255.70434 -94.919038)
		(mid 255.625118 -95.208156)
		(end 255.69799 -95.49892)
		(width 0.0889)
		(layer "In11.Cu")
		(net "M_F_ALERT_N")
	)
	(arc
		(start 253.9873 -92.937584)
		(mid 253.981882 -93.519311)
		(end 254.47752 -93.82379)
		(width 0.0889)
		(layer "In11.Cu")
		(net "M_F_ALERT_N")
	)
	(arc
		(start 255.709166 -95.518224)
		(mid 255.757921 -95.714576)
		(end 255.70434 -95.909638)
		(width 0.0889)
		(layer "In11.Cu")
		(net "M_F_ALERT_N")
	)
	(arc
		(start 254.84582 -94.023688)
		(mid 255.054428 -94.23562)
		(end 255.33985 -94.31909)
		(width 0.0889)
		(layer "In11.Cu")
		(net "M_F_ALERT_N")
	)
	(arc
		(start 253.9873 -92.537788)
		(mid 254.040833 -92.737686)
		(end 253.9873 -92.937584)
		(width 0.0889)
		(layer "In11.Cu")
		(net "M_F_ALERT_N")
	)
	(arc
		(start 254.517144 -93.82379)
		(mid 254.707073 -93.88166)
		(end 254.84582 -94.023688)
		(width 0.0889)
		(layer "In11.Cu")
		(net "M_F_ALERT_N")
	)
	(arc
		(start 255.709166 -96.508824)
		(mid 255.765411 -96.652053)
		(end 255.784604 -96.804734)
		(width 0.0889)
		(layer "In11.Cu")
		(net "M_F_ALERT_N")
	)
	(arc
		(start 255.70434 -95.909638)
		(mid 255.625118 -96.198756)
		(end 255.69799 -96.48952)
		(width 0.0889)
		(layer "In11.Cu")
		(net "M_F_ALERT_N")
	)
	(arc
		(start 255.375664 -94.31909)
		(mid 255.708633 -94.526638)
		(end 255.70434 -94.919038)
		(width 0.0889)
		(layer "In11.Cu")
		(net "M_F_ALERT_N")
	)
	(arc
		(start 253.9873 -91.547188)
		(mid 254.040833 -91.747086)
		(end 253.9873 -91.946984)
		(width 0.0889)
		(layer "In11.Cu")
		(net "M_F_ALERT_N")
	)
	(arc
		(start 253.9873 -91.946984)
		(mid 253.908111 -92.233599)
		(end 253.97841 -92.522548)
		(width 0.0889)
		(layer "In11.Cu")
		(net "M_F_ALERT_N")
	)
	(segment
		(start 246.549926 -152.278842)
		(end 246.549926 -154.252168)
		(width 0.1651)
		(layer "F.Cu")
		(net "M_F_ACT_N")
	)
	(segment
		(start 246.550434 -152.273)
		(end 246.549926 -152.278842)
		(width 0.1651)
		(layer "F.Cu")
		(net "M_F_ACT_N")
	)
	(segment
		(start 253.353824 -90.26144)
		(end 252.782324 -90.26144)
		(width 0.1651)
		(layer "F.Cu")
		(net "M_F_ACT_N")
	)
	(via
		(at 246.549926 -150.788878)
		(size 0.4572)
		(drill 0.2032)
		(layers "F.Cu" "B.Cu")
		(net "M_F_ACT_N")
	)
	(via
		(at 252.782324 -90.26144)
		(size 0.508)
		(drill 0.254)
		(layers "F.Cu" "B.Cu")
		(net "M_F_ACT_N")
	)
	(via
		(at 246.549926 -154.252168)
		(size 0.508)
		(drill 0.254)
		(layers "F.Cu" "B.Cu")
		(net "M_F_ACT_N")
	)
	(segment
		(start 246.549926 -152.078182)
		(end 246.549926 -150.788878)
		(width 0.1651)
		(layer "B.Cu")
		(net "M_F_ACT_N")
	)
	(segment
		(start 246.550434 -152.078436)
		(end 246.549926 -152.078182)
		(width 0.1651)
		(layer "B.Cu")
		(net "M_F_ACT_N")
	)
	(segment
		(start 246.262906 -151.075898)
		(end 246.262906 -153.965148)
		(width 0.14224)
		(layer "In2.Cu")
		(net "M_F_ACT_N")
	)
	(segment
		(start 249.0978 -128.168146)
		(end 249.0978 -125.770132)
		(width 0.14224)
		(layer "In2.Cu")
		(net "M_F_ACT_N")
	)
	(segment
		(start 247.954546 -137.426954)
		(end 247.64746 -137.426954)
		(width 0.14224)
		(layer "In2.Cu")
		(net "M_F_ACT_N")
	)
	(segment
		(start 252.8316 -99.889056)
		(end 253.13386 -99.368102)
		(width 0.0889)
		(layer "In2.Cu")
		(net "M_F_ACT_N")
	)
	(segment
		(start 253.122684 -98.396806)
		(end 253.129034 -98.386138)
		(width 0.0889)
		(layer "In2.Cu")
		(net "M_F_ACT_N")
	)
	(segment
		(start 246.107712 -150.117048)
		(end 246.107712 -148.227288)
		(width 0.14224)
		(layer "In2.Cu")
		(net "M_F_ACT_N")
	)
	(segment
		(start 246.549926 -150.788878)
		(end 246.549926 -150.559262)
		(width 0.14224)
		(layer "In2.Cu")
		(net "M_F_ACT_N")
	)
	(segment
		(start 247.64746 -137.426954)
		(end 247.49252 -137.272014)
		(width 0.14224)
		(layer "In2.Cu")
		(net "M_F_ACT_N")
	)
	(segment
		(start 247.904 -129.361946)
		(end 249.0978 -128.168146)
		(width 0.14224)
		(layer "In2.Cu")
		(net "M_F_ACT_N")
	)
	(segment
		(start 253.129034 -92.442538)
		(end 253.13386 -92.433902)
		(width 0.0889)
		(layer "In2.Cu")
		(net "M_F_ACT_N")
	)
	(segment
		(start 247.503188 -138.588496)
		(end 247.503188 -138.288776)
		(width 0.14224)
		(layer "In2.Cu")
		(net "M_F_ACT_N")
	)
	(segment
		(start 247.813068 -138.898376)
		(end 247.503188 -138.588496)
		(width 0.14224)
		(layer "In2.Cu")
		(net "M_F_ACT_N")
	)
	(segment
		(start 253.129034 -91.451938)
		(end 253.13386 -91.443302)
		(width 0.0889)
		(layer "In2.Cu")
		(net "M_F_ACT_N")
	)
	(segment
		(start 253.122684 -95.425006)
		(end 253.129034 -95.414338)
		(width 0.0889)
		(layer "In2.Cu")
		(net "M_F_ACT_N")
	)
	(segment
		(start 253.129034 -93.433138)
		(end 253.13386 -93.424502)
		(width 0.0889)
		(layer "In2.Cu")
		(net "M_F_ACT_N")
	)
	(segment
		(start 247.49252 -137.272014)
		(end 247.49252 -136.898126)
		(width 0.14224)
		(layer "In2.Cu")
		(net "M_F_ACT_N")
	)
	(segment
		(start 253.122684 -91.462606)
		(end 253.129034 -91.451938)
		(width 0.0889)
		(layer "In2.Cu")
		(net "M_F_ACT_N")
	)
	(segment
		(start 249.0978 -125.770132)
		(end 252.8316 -122.036332)
		(width 0.14224)
		(layer "In2.Cu")
		(net "M_F_ACT_N")
	)
	(segment
		(start 252.8316 -101.332792)
		(end 252.8316 -99.889056)
		(width 0.0889)
		(layer "In2.Cu")
		(net "M_F_ACT_N")
	)
	(segment
		(start 247.816878 -145.023078)
		(end 247.813068 -145.019268)
		(width 0.14224)
		(layer "In2.Cu")
		(net "M_F_ACT_N")
	)
	(segment
		(start 253.122684 -97.406206)
		(end 253.129034 -97.395538)
		(width 0.0889)
		(layer "In2.Cu")
		(net "M_F_ACT_N")
	)
	(segment
		(start 246.549926 -150.788878)
		(end 246.262906 -151.075898)
		(width 0.14224)
		(layer "In2.Cu")
		(net "M_F_ACT_N")
	)
	(segment
		(start 247.813068 -136.577578)
		(end 247.813068 -131.231132)
		(width 0.14224)
		(layer "In2.Cu")
		(net "M_F_ACT_N")
	)
	(segment
		(start 253.122684 -92.453206)
		(end 253.129034 -92.442538)
		(width 0.0889)
		(layer "In2.Cu")
		(net "M_F_ACT_N")
	)
	(segment
		(start 247.66524 -138.126724)
		(end 247.926098 -138.126724)
		(width 0.14224)
		(layer "In2.Cu")
		(net "M_F_ACT_N")
	)
	(segment
		(start 253.129034 -98.386138)
		(end 253.13386 -98.377502)
		(width 0.0889)
		(layer "In2.Cu")
		(net "M_F_ACT_N")
	)
	(segment
		(start 247.813068 -131.231132)
		(end 247.85447 -131.18973)
		(width 0.14224)
		(layer "In2.Cu")
		(net "M_F_ACT_N")
	)
	(segment
		(start 253.129034 -94.023688)
		(end 253.122684 -94.01302)
		(width 0.0889)
		(layer "In2.Cu")
		(net "M_F_ACT_N")
	)
	(segment
		(start 247.85447 -130.60807)
		(end 247.797574 -130.551174)
		(width 0.14224)
		(layer "In2.Cu")
		(net "M_F_ACT_N")
	)
	(segment
		(start 246.549926 -150.559262)
		(end 246.107712 -150.117048)
		(width 0.14224)
		(layer "In2.Cu")
		(net "M_F_ACT_N")
	)
	(segment
		(start 247.813068 -145.019268)
		(end 247.813068 -138.898376)
		(width 0.14224)
		(layer "In2.Cu")
		(net "M_F_ACT_N")
	)
	(segment
		(start 247.85447 -131.18973)
		(end 247.85447 -130.60807)
		(width 0.14224)
		(layer "In2.Cu")
		(net "M_F_ACT_N")
	)
	(segment
		(start 253.129034 -95.414338)
		(end 253.13386 -95.405702)
		(width 0.0889)
		(layer "In2.Cu")
		(net "M_F_ACT_N")
	)
	(segment
		(start 247.926098 -138.126724)
		(end 248.095262 -137.95756)
		(width 0.14224)
		(layer "In2.Cu")
		(net "M_F_ACT_N")
	)
	(segment
		(start 246.262906 -153.965148)
		(end 246.549926 -154.252168)
		(width 0.14224)
		(layer "In2.Cu")
		(net "M_F_ACT_N")
	)
	(segment
		(start 253.122684 -96.415606)
		(end 253.129034 -96.404938)
		(width 0.0889)
		(layer "In2.Cu")
		(net "M_F_ACT_N")
	)
	(segment
		(start 248.095262 -137.95756)
		(end 248.095262 -137.56767)
		(width 0.14224)
		(layer "In2.Cu")
		(net "M_F_ACT_N")
	)
	(segment
		(start 247.797574 -130.551174)
		(end 247.797574 -130.052826)
		(width 0.14224)
		(layer "In2.Cu")
		(net "M_F_ACT_N")
	)
	(segment
		(start 247.904 -129.9464)
		(end 247.904 -129.361946)
		(width 0.14224)
		(layer "In2.Cu")
		(net "M_F_ACT_N")
	)
	(segment
		(start 253.129034 -97.395538)
		(end 253.13386 -97.386902)
		(width 0.0889)
		(layer "In2.Cu")
		(net "M_F_ACT_N")
	)
	(segment
		(start 253.063756 -90.883994)
		(end 252.782324 -90.26144)
		(width 0.0889)
		(layer "In2.Cu")
		(net "M_F_ACT_N")
	)
	(segment
		(start 247.816878 -146.518122)
		(end 247.816878 -145.023078)
		(width 0.14224)
		(layer "In2.Cu")
		(net "M_F_ACT_N")
	)
	(segment
		(start 252.8316 -122.036332)
		(end 252.8316 -101.332792)
		(width 0.14224)
		(layer "In2.Cu")
		(net "M_F_ACT_N")
	)
	(segment
		(start 247.797574 -130.052826)
		(end 247.904 -129.9464)
		(width 0.14224)
		(layer "In2.Cu")
		(net "M_F_ACT_N")
	)
	(segment
		(start 253.129034 -96.404938)
		(end 253.13386 -96.396302)
		(width 0.0889)
		(layer "In2.Cu")
		(net "M_F_ACT_N")
	)
	(segment
		(start 246.107712 -148.227288)
		(end 247.816878 -146.518122)
		(width 0.14224)
		(layer "In2.Cu")
		(net "M_F_ACT_N")
	)
	(segment
		(start 247.503188 -138.288776)
		(end 247.66524 -138.126724)
		(width 0.14224)
		(layer "In2.Cu")
		(net "M_F_ACT_N")
	)
	(segment
		(start 247.49252 -136.898126)
		(end 247.813068 -136.577578)
		(width 0.14224)
		(layer "In2.Cu")
		(net "M_F_ACT_N")
	)
	(segment
		(start 248.095262 -137.56767)
		(end 247.954546 -137.426954)
		(width 0.14224)
		(layer "In2.Cu")
		(net "M_F_ACT_N")
	)
	(arc
		(start 253.122684 -94.01302)
		(mid 253.049886 -93.722257)
		(end 253.129034 -93.433138)
		(width 0.0889)
		(layer "In2.Cu")
		(net "M_F_ACT_N")
	)
	(arc
		(start 253.13386 -97.386902)
		(mid 253.182615 -97.19055)
		(end 253.129034 -96.995488)
		(width 0.0889)
		(layer "In2.Cu")
		(net "M_F_ACT_N")
	)
	(arc
		(start 253.129034 -97.986088)
		(mid 253.049812 -97.69697)
		(end 253.122684 -97.406206)
		(width 0.0889)
		(layer "In2.Cu")
		(net "M_F_ACT_N")
	)
	(arc
		(start 253.13386 -96.396302)
		(mid 253.182615 -96.19995)
		(end 253.129034 -96.004888)
		(width 0.0889)
		(layer "In2.Cu")
		(net "M_F_ACT_N")
	)
	(arc
		(start 253.129034 -96.995488)
		(mid 253.049812 -96.70637)
		(end 253.122684 -96.415606)
		(width 0.0889)
		(layer "In2.Cu")
		(net "M_F_ACT_N")
	)
	(arc
		(start 253.13386 -91.443302)
		(mid 253.182615 -91.24695)
		(end 253.129034 -91.051888)
		(width 0.0889)
		(layer "In2.Cu")
		(net "M_F_ACT_N")
	)
	(arc
		(start 253.129034 -98.976688)
		(mid 253.049812 -98.68757)
		(end 253.122684 -98.396806)
		(width 0.0889)
		(layer "In2.Cu")
		(net "M_F_ACT_N")
	)
	(arc
		(start 253.129034 -91.051888)
		(mid 253.089958 -90.970443)
		(end 253.063756 -90.883994)
		(width 0.0889)
		(layer "In2.Cu")
		(net "M_F_ACT_N")
	)
	(arc
		(start 253.13386 -93.424502)
		(mid 253.182615 -93.22815)
		(end 253.129034 -93.033088)
		(width 0.0889)
		(layer "In2.Cu")
		(net "M_F_ACT_N")
	)
	(arc
		(start 253.13386 -92.433902)
		(mid 253.182615 -92.23755)
		(end 253.129034 -92.042488)
		(width 0.0889)
		(layer "In2.Cu")
		(net "M_F_ACT_N")
	)
	(arc
		(start 253.129034 -95.014288)
		(mid 253.049903 -94.718886)
		(end 253.129034 -94.423484)
		(width 0.0889)
		(layer "In2.Cu")
		(net "M_F_ACT_N")
	)
	(arc
		(start 253.13386 -95.405702)
		(mid 253.182615 -95.20935)
		(end 253.129034 -95.014288)
		(width 0.0889)
		(layer "In2.Cu")
		(net "M_F_ACT_N")
	)
	(arc
		(start 253.129034 -92.042488)
		(mid 253.049812 -91.75337)
		(end 253.122684 -91.462606)
		(width 0.0889)
		(layer "In2.Cu")
		(net "M_F_ACT_N")
	)
	(arc
		(start 253.129034 -96.004888)
		(mid 253.049812 -95.71577)
		(end 253.122684 -95.425006)
		(width 0.0889)
		(layer "In2.Cu")
		(net "M_F_ACT_N")
	)
	(arc
		(start 253.129034 -93.033088)
		(mid 253.049812 -92.74397)
		(end 253.122684 -92.453206)
		(width 0.0889)
		(layer "In2.Cu")
		(net "M_F_ACT_N")
	)
	(arc
		(start 253.13386 -99.368102)
		(mid 253.182615 -99.17175)
		(end 253.129034 -98.976688)
		(width 0.0889)
		(layer "In2.Cu")
		(net "M_F_ACT_N")
	)
	(arc
		(start 253.13386 -98.377502)
		(mid 253.182615 -98.18115)
		(end 253.129034 -97.986088)
		(width 0.0889)
		(layer "In2.Cu")
		(net "M_F_ACT_N")
	)
	(arc
		(start 253.129034 -94.423484)
		(mid 253.182533 -94.223586)
		(end 253.129034 -94.023688)
		(width 0.0889)
		(layer "In2.Cu")
		(net "M_F_ACT_N")
	)
	(segment
		(start 265.250422 -147.27174)
		(end 265.249914 -147.27174)
		(width 0.1651)
		(layer "F.Cu")
		(net "M_E_PAR")
	)
	(segment
		(start 265.249914 -146.013932)
		(end 265.250168 -146.013678)
		(width 0.1651)
		(layer "F.Cu")
		(net "M_E_PAR")
	)
	(segment
		(start 265.249914 -147.27174)
		(end 265.249914 -146.013932)
		(width 0.1651)
		(layer "F.Cu")
		(net "M_E_PAR")
	)
	(segment
		(start 265.250168 -146.013678)
		(end 265.250168 -145.988278)
		(width 0.1651)
		(layer "F.Cu")
		(net "M_E_PAR")
	)
	(segment
		(start 260.50875 -97.690686)
		(end 261.08025 -97.690686)
		(width 0.1651)
		(layer "F.Cu")
		(net "M_E_PAR")
	)
	(via
		(at 260.50875 -97.690686)
		(size 0.508)
		(drill 0.254)
		(layers "F.Cu" "B.Cu")
		(net "M_E_PAR")
	)
	(via
		(at 265.24966 -139.850368)
		(size 0.508)
		(drill 0.254)
		(layers "F.Cu" "B.Cu")
		(net "M_E_PAR")
	)
	(via
		(at 265.250168 -145.988278)
		(size 0.4572)
		(drill 0.2032)
		(layers "F.Cu" "B.Cu")
		(net "M_E_PAR")
	)
	(segment
		(start 265.249914 -137.877296)
		(end 265.249914 -139.850114)
		(width 0.1651)
		(layer "B.Cu")
		(net "M_E_PAR")
	)
	(segment
		(start 265.250422 -137.877296)
		(end 265.249914 -137.877296)
		(width 0.1651)
		(layer "B.Cu")
		(net "M_E_PAR")
	)
	(segment
		(start 265.249914 -139.850114)
		(end 265.24966 -139.850368)
		(width 0.1651)
		(layer "B.Cu")
		(net "M_E_PAR")
	)
	(segment
		(start 262.0772 -103.388922)
		(end 262.0772 -126.1364)
		(width 0.14224)
		(layer "In4.Cu")
		(net "M_E_PAR")
	)
	(segment
		(start 262.0772 -126.1364)
		(end 263.5504 -127.6096)
		(width 0.14224)
		(layer "In4.Cu")
		(net "M_E_PAR")
	)
	(segment
		(start 265.684762 -141.528038)
		(end 265.5316 -141.6812)
		(width 0.14224)
		(layer "In4.Cu")
		(net "M_E_PAR")
	)
	(segment
		(start 265.5316 -141.6812)
		(end 265.5316 -144.2212)
		(width 0.14224)
		(layer "In4.Cu")
		(net "M_E_PAR")
	)
	(segment
		(start 264.79246 -129.15646)
		(end 264.79246 -139.393168)
		(width 0.14224)
		(layer "In4.Cu")
		(net "M_E_PAR")
	)
	(segment
		(start 265.7602 -144.8562)
		(end 265.24966 -145.36674)
		(width 0.14224)
		(layer "In4.Cu")
		(net "M_E_PAR")
	)
	(segment
		(start 265.24966 -145.36674)
		(end 265.24966 -145.98777)
		(width 0.14224)
		(layer "In4.Cu")
		(net "M_E_PAR")
	)
	(segment
		(start 262.0772 -102.632256)
		(end 262.0772 -103.388922)
		(width 0.0889)
		(layer "In4.Cu")
		(net "M_E_PAR")
	)
	(segment
		(start 260.50875 -97.690686)
		(end 260.838188 -98.45167)
		(width 0.0889)
		(layer "In4.Cu")
		(net "M_E_PAR")
	)
	(segment
		(start 261.0104 -100.0506)
		(end 261.0104 -101.565456)
		(width 0.0889)
		(layer "In4.Cu")
		(net "M_E_PAR")
	)
	(segment
		(start 265.24966 -140.48486)
		(end 265.684762 -140.919962)
		(width 0.14224)
		(layer "In4.Cu")
		(net "M_E_PAR")
	)
	(segment
		(start 265.24966 -139.850368)
		(end 265.24966 -140.48486)
		(width 0.14224)
		(layer "In4.Cu")
		(net "M_E_PAR")
	)
	(segment
		(start 261.0104 -101.565456)
		(end 262.0772 -102.632256)
		(width 0.0889)
		(layer "In4.Cu")
		(net "M_E_PAR")
	)
	(segment
		(start 264.79246 -139.393168)
		(end 265.24966 -139.850368)
		(width 0.14224)
		(layer "In4.Cu")
		(net "M_E_PAR")
	)
	(segment
		(start 265.5316 -144.2212)
		(end 265.7602 -144.4498)
		(width 0.14224)
		(layer "In4.Cu")
		(net "M_E_PAR")
	)
	(segment
		(start 265.24966 -145.98777)
		(end 265.250168 -145.988278)
		(width 0.14224)
		(layer "In4.Cu")
		(net "M_E_PAR")
	)
	(segment
		(start 263.5504 -127.9144)
		(end 264.79246 -129.15646)
		(width 0.14224)
		(layer "In4.Cu")
		(net "M_E_PAR")
	)
	(segment
		(start 265.684762 -140.919962)
		(end 265.684762 -141.528038)
		(width 0.14224)
		(layer "In4.Cu")
		(net "M_E_PAR")
	)
	(segment
		(start 263.5504 -127.6096)
		(end 263.5504 -127.9144)
		(width 0.14224)
		(layer "In4.Cu")
		(net "M_E_PAR")
	)
	(segment
		(start 265.7602 -144.4498)
		(end 265.7602 -144.8562)
		(width 0.14224)
		(layer "In4.Cu")
		(net "M_E_PAR")
	)
	(segment
		(start 260.838188 -98.45167)
		(end 260.860286 -98.490024)
		(width 0.0889)
		(layer "In4.Cu")
		(net "M_E_PAR")
	)
	(arc
		(start 260.85546 -98.881438)
		(mid 260.776329 -99.17684)
		(end 260.85546 -99.472242)
		(width 0.0889)
		(layer "In4.Cu")
		(net "M_E_PAR")
	)
	(arc
		(start 260.860286 -98.490024)
		(mid 260.909041 -98.686376)
		(end 260.85546 -98.881438)
		(width 0.0889)
		(layer "In4.Cu")
		(net "M_E_PAR")
	)
	(arc
		(start 260.85546 -99.472242)
		(mid 260.970988 -99.751225)
		(end 261.0104 -100.0506)
		(width 0.0889)
		(layer "In4.Cu")
		(net "M_E_PAR")
	)
	(segment
		(start 266.231116 -94.718886)
		(end 265.659616 -94.718886)
		(width 0.1016)
		(layer "F.Cu")
		(net "M_E_ODT<3>")
	)
	(via
		(at 265.659616 -94.718886)
		(size 0.508)
		(drill 0.254)
		(layers "F.Cu" "B.Cu")
		(net "M_E_ODT<3>")
	)
	(via
		(at 276.29993 -141.188186)
		(size 0.4572)
		(drill 0.2032)
		(layers "F.Cu" "B.Cu")
		(net "M_E_ODT<3>")
	)
	(segment
		(start 276.300438 -142.477236)
		(end 276.29993 -142.476982)
		(width 0.1651)
		(layer "B.Cu")
		(net "M_E_ODT<3>")
	)
	(segment
		(start 276.29993 -142.476982)
		(end 276.29993 -141.188186)
		(width 0.1651)
		(layer "B.Cu")
		(net "M_E_ODT<3>")
	)
	(segment
		(start 275.872448 -138.890248)
		(end 275.872448 -139.474448)
		(width 0.14224)
		(layer "In4.Cu")
		(net "M_E_ODT<3>")
	)
	(segment
		(start 267.0556 -97.7138)
		(end 267.8938 -98.552)
		(width 0.0889)
		(layer "In4.Cu")
		(net "M_E_ODT<3>")
	)
	(segment
		(start 267.7922 -102.4382)
		(end 268.1732 -102.8192)
		(width 0.0889)
		(layer "In4.Cu")
		(net "M_E_ODT<3>")
	)
	(segment
		(start 274.961096 -131.362704)
		(end 274.961096 -131.933696)
		(width 0.14224)
		(layer "In4.Cu")
		(net "M_E_ODT<3>")
	)
	(segment
		(start 275.04009 -136.100058)
		(end 275.04009 -138.05789)
		(width 0.14224)
		(layer "In4.Cu")
		(net "M_E_ODT<3>")
	)
	(segment
		(start 275.074888 -130.650488)
		(end 275.074888 -131.248912)
		(width 0.14224)
		(layer "In4.Cu")
		(net "M_E_ODT<3>")
	)
	(segment
		(start 266.1666 -96.396302)
		(end 266.171426 -96.404938)
		(width 0.0889)
		(layer "In4.Cu")
		(net "M_E_ODT<3>")
	)
	(segment
		(start 271.22882 -124.11202)
		(end 271.22882 -125.071378)
		(width 0.14224)
		(layer "In4.Cu")
		(net "M_E_ODT<3>")
	)
	(segment
		(start 275.036534 -134.665466)
		(end 274.670774 -135.031226)
		(width 0.14224)
		(layer "In4.Cu")
		(net "M_E_ODT<3>")
	)
	(segment
		(start 266.171426 -96.404938)
		(end 266.177776 -96.415606)
		(width 0.0889)
		(layer "In4.Cu")
		(net "M_E_ODT<3>")
	)
	(segment
		(start 275.04009 -138.05789)
		(end 275.872448 -138.890248)
		(width 0.14224)
		(layer "In4.Cu")
		(net "M_E_ODT<3>")
	)
	(segment
		(start 274.670774 -135.730742)
		(end 275.04009 -136.100058)
		(width 0.14224)
		(layer "In4.Cu")
		(net "M_E_ODT<3>")
	)
	(segment
		(start 266.154662 -95.384874)
		(end 266.171426 -95.414338)
		(width 0.0889)
		(layer "In4.Cu")
		(net "M_E_ODT<3>")
	)
	(segment
		(start 265.659616 -94.718886)
		(end 266.154662 -95.384874)
		(width 0.0889)
		(layer "In4.Cu")
		(net "M_E_ODT<3>")
	)
	(segment
		(start 267.7922 -102.0064)
		(end 267.7922 -102.4382)
		(width 0.0889)
		(layer "In4.Cu")
		(net "M_E_ODT<3>")
	)
	(segment
		(start 275.872448 -139.474448)
		(end 276.29993 -139.90193)
		(width 0.14224)
		(layer "In4.Cu")
		(net "M_E_ODT<3>")
	)
	(segment
		(start 275.053552 -128.89611)
		(end 275.053552 -129.822448)
		(width 0.14224)
		(layer "In4.Cu")
		(net "M_E_ODT<3>")
	)
	(segment
		(start 267.8938 -101.9048)
		(end 267.7922 -102.0064)
		(width 0.0889)
		(layer "In4.Cu")
		(net "M_E_ODT<3>")
	)
	(segment
		(start 266.50696 -97.59569)
		(end 266.68349 -97.59569)
		(width 0.0889)
		(layer "In4.Cu")
		(net "M_E_ODT<3>")
	)
	(segment
		(start 276.29993 -139.90193)
		(end 276.29993 -141.188186)
		(width 0.14224)
		(layer "In4.Cu")
		(net "M_E_ODT<3>")
	)
	(segment
		(start 274.961096 -131.933696)
		(end 275.036534 -132.009134)
		(width 0.14224)
		(layer "In4.Cu")
		(net "M_E_ODT<3>")
	)
	(segment
		(start 268.1732 -102.8192)
		(end 268.1732 -103.056436)
		(width 0.0889)
		(layer "In4.Cu")
		(net "M_E_ODT<3>")
	)
	(segment
		(start 267.8938 -98.552)
		(end 267.8938 -101.9048)
		(width 0.0889)
		(layer "In4.Cu")
		(net "M_E_ODT<3>")
	)
	(segment
		(start 275.053552 -129.822448)
		(end 274.955 -129.921)
		(width 0.14224)
		(layer "In4.Cu")
		(net "M_E_ODT<3>")
	)
	(segment
		(start 275.036534 -132.009134)
		(end 275.036534 -134.665466)
		(width 0.14224)
		(layer "In4.Cu")
		(net "M_E_ODT<3>")
	)
	(segment
		(start 275.074888 -131.248912)
		(end 274.961096 -131.362704)
		(width 0.14224)
		(layer "In4.Cu")
		(net "M_E_ODT<3>")
	)
	(segment
		(start 274.670774 -135.031226)
		(end 274.670774 -135.730742)
		(width 0.14224)
		(layer "In4.Cu")
		(net "M_E_ODT<3>")
	)
	(segment
		(start 266.171426 -95.414338)
		(end 266.177776 -95.425006)
		(width 0.0889)
		(layer "In4.Cu")
		(net "M_E_ODT<3>")
	)
	(segment
		(start 271.22882 -125.071378)
		(end 275.053552 -128.89611)
		(width 0.14224)
		(layer "In4.Cu")
		(net "M_E_ODT<3>")
	)
	(segment
		(start 268.1732 -103.056436)
		(end 268.1732 -121.0564)
		(width 0.14224)
		(layer "In4.Cu")
		(net "M_E_ODT<3>")
	)
	(segment
		(start 268.1732 -121.0564)
		(end 271.22882 -124.11202)
		(width 0.14224)
		(layer "In4.Cu")
		(net "M_E_ODT<3>")
	)
	(segment
		(start 274.955 -130.5306)
		(end 275.074888 -130.650488)
		(width 0.14224)
		(layer "In4.Cu")
		(net "M_E_ODT<3>")
	)
	(segment
		(start 266.68349 -97.59569)
		(end 266.8016 -97.7138)
		(width 0.0889)
		(layer "In4.Cu")
		(net "M_E_ODT<3>")
	)
	(segment
		(start 266.8016 -97.7138)
		(end 267.0556 -97.7138)
		(width 0.0889)
		(layer "In4.Cu")
		(net "M_E_ODT<3>")
	)
	(segment
		(start 274.955 -129.921)
		(end 274.955 -130.5306)
		(width 0.14224)
		(layer "In4.Cu")
		(net "M_E_ODT<3>")
	)
	(arc
		(start 266.177776 -95.425006)
		(mid 266.250574 -95.715769)
		(end 266.171426 -96.004888)
		(width 0.0889)
		(layer "In4.Cu")
		(net "M_E_ODT<3>")
	)
	(arc
		(start 266.171426 -96.004888)
		(mid 266.117956 -96.199951)
		(end 266.1666 -96.396302)
		(width 0.0889)
		(layer "In4.Cu")
		(net "M_E_ODT<3>")
	)
	(arc
		(start 266.177776 -96.415606)
		(mid 266.250574 -96.706369)
		(end 266.171426 -96.995488)
		(width 0.0889)
		(layer "In4.Cu")
		(net "M_E_ODT<3>")
	)
	(arc
		(start 266.171426 -96.995488)
		(mid 266.168678 -97.390955)
		(end 266.50696 -97.59569)
		(width 0.0889)
		(layer "In4.Cu")
		(net "M_E_ODT<3>")
	)
	(segment
		(start 264.51433 -96.700086)
		(end 263.94283 -96.700086)
		(width 0.1016)
		(layer "F.Cu")
		(net "M_E_ODT<2>")
	)
	(via
		(at 263.94283 -96.700086)
		(size 0.508)
		(drill 0.254)
		(layers "F.Cu" "B.Cu")
		(net "M_E_ODT<2>")
	)
	(via
		(at 272.899886 -141.183868)
		(size 0.4572)
		(drill 0.2032)
		(layers "F.Cu" "B.Cu")
		(net "M_E_ODT<2>")
	)
	(segment
		(start 272.900394 -142.477236)
		(end 272.899886 -142.476982)
		(width 0.1651)
		(layer "B.Cu")
		(net "M_E_ODT<2>")
	)
	(segment
		(start 272.899886 -142.476982)
		(end 272.899886 -141.183868)
		(width 0.1651)
		(layer "B.Cu")
		(net "M_E_ODT<2>")
	)
	(segment
		(start 271.64538 -129.85242)
		(end 271.551908 -129.945892)
		(width 0.14224)
		(layer "In4.Cu")
		(net "M_E_ODT<2>")
	)
	(segment
		(start 266.1412 -103.411528)
		(end 266.1412 -121.657872)
		(width 0.14224)
		(layer "In4.Cu")
		(net "M_E_ODT<2>")
	)
	(segment
		(start 271.551908 -129.945892)
		(end 271.551908 -130.531108)
		(width 0.14224)
		(layer "In4.Cu")
		(net "M_E_ODT<2>")
	)
	(segment
		(start 272.6944 -139.6492)
		(end 272.6944 -140.323062)
		(width 0.14224)
		(layer "In4.Cu")
		(net "M_E_ODT<2>")
	)
	(segment
		(start 265.5062 -102.5652)
		(end 266.1412 -103.2002)
		(width 0.0889)
		(layer "In4.Cu")
		(net "M_E_ODT<2>")
	)
	(segment
		(start 272.465292 -139.420092)
		(end 272.6944 -139.6492)
		(width 0.14224)
		(layer "In4.Cu")
		(net "M_E_ODT<2>")
	)
	(segment
		(start 264.45464 -97.395538)
		(end 264.46353 -97.410778)
		(width 0.0889)
		(layer "In4.Cu")
		(net "M_E_ODT<2>")
	)
	(segment
		(start 271.663922 -131.205478)
		(end 271.567402 -131.301998)
		(width 0.14224)
		(layer "In4.Cu")
		(net "M_E_ODT<2>")
	)
	(segment
		(start 271.636998 -138.083798)
		(end 272.465292 -138.912092)
		(width 0.14224)
		(layer "In4.Cu")
		(net "M_E_ODT<2>")
	)
	(segment
		(start 271.636998 -136.033002)
		(end 271.636998 -138.083798)
		(width 0.14224)
		(layer "In4.Cu")
		(net "M_E_ODT<2>")
	)
	(segment
		(start 271.567402 -131.301998)
		(end 271.567402 -134.001002)
		(width 0.14224)
		(layer "In4.Cu")
		(net "M_E_ODT<2>")
	)
	(segment
		(start 271.567402 -134.001002)
		(end 271.636998 -134.070598)
		(width 0.14224)
		(layer "In4.Cu")
		(net "M_E_ODT<2>")
	)
	(segment
		(start 264.45464 -98.386138)
		(end 264.46353 -98.401378)
		(width 0.0889)
		(layer "In4.Cu")
		(net "M_E_ODT<2>")
	)
	(segment
		(start 269.19682 -125.913642)
		(end 271.64538 -128.362202)
		(width 0.14224)
		(layer "In4.Cu")
		(net "M_E_ODT<2>")
	)
	(segment
		(start 264.438384 -97.366836)
		(end 264.45464 -97.395538)
		(width 0.0889)
		(layer "In4.Cu")
		(net "M_E_ODT<2>")
	)
	(segment
		(start 263.94283 -96.700086)
		(end 264.438384 -97.366836)
		(width 0.0889)
		(layer "In4.Cu")
		(net "M_E_ODT<2>")
	)
	(segment
		(start 272.465292 -138.912092)
		(end 272.465292 -139.420092)
		(width 0.14224)
		(layer "In4.Cu")
		(net "M_E_ODT<2>")
	)
	(segment
		(start 264.3886 -99.223322)
		(end 264.3886 -99.4156)
		(width 0.0889)
		(layer "In4.Cu")
		(net "M_E_ODT<2>")
	)
	(segment
		(start 264.3886 -99.4156)
		(end 265.5062 -100.5332)
		(width 0.0889)
		(layer "In4.Cu")
		(net "M_E_ODT<2>")
	)
	(segment
		(start 271.64538 -128.362202)
		(end 271.64538 -129.85242)
		(width 0.14224)
		(layer "In4.Cu")
		(net "M_E_ODT<2>")
	)
	(segment
		(start 266.1412 -121.657872)
		(end 269.19682 -124.713492)
		(width 0.14224)
		(layer "In4.Cu")
		(net "M_E_ODT<2>")
	)
	(segment
		(start 271.5768 -135.972804)
		(end 271.636998 -136.033002)
		(width 0.14224)
		(layer "In4.Cu")
		(net "M_E_ODT<2>")
	)
	(segment
		(start 271.663922 -130.643122)
		(end 271.663922 -131.205478)
		(width 0.14224)
		(layer "In4.Cu")
		(net "M_E_ODT<2>")
	)
	(segment
		(start 265.5062 -100.5332)
		(end 265.5062 -102.5652)
		(width 0.0889)
		(layer "In4.Cu")
		(net "M_E_ODT<2>")
	)
	(segment
		(start 272.899886 -140.528548)
		(end 272.899886 -141.183868)
		(width 0.14224)
		(layer "In4.Cu")
		(net "M_E_ODT<2>")
	)
	(segment
		(start 269.19682 -124.713492)
		(end 269.19682 -125.913642)
		(width 0.14224)
		(layer "In4.Cu")
		(net "M_E_ODT<2>")
	)
	(segment
		(start 266.1412 -103.2002)
		(end 266.1412 -103.411528)
		(width 0.0889)
		(layer "In4.Cu")
		(net "M_E_ODT<2>")
	)
	(segment
		(start 271.5768 -134.6708)
		(end 271.5768 -135.972804)
		(width 0.14224)
		(layer "In4.Cu")
		(net "M_E_ODT<2>")
	)
	(segment
		(start 271.636998 -134.610602)
		(end 271.5768 -134.6708)
		(width 0.14224)
		(layer "In4.Cu")
		(net "M_E_ODT<2>")
	)
	(segment
		(start 271.636998 -134.070598)
		(end 271.636998 -134.610602)
		(width 0.14224)
		(layer "In4.Cu")
		(net "M_E_ODT<2>")
	)
	(segment
		(start 272.6944 -140.323062)
		(end 272.899886 -140.528548)
		(width 0.14224)
		(layer "In4.Cu")
		(net "M_E_ODT<2>")
	)
	(segment
		(start 271.551908 -130.531108)
		(end 271.663922 -130.643122)
		(width 0.14224)
		(layer "In4.Cu")
		(net "M_E_ODT<2>")
	)
	(arc
		(start 264.45464 -98.976942)
		(mid 264.405386 -99.095782)
		(end 264.3886 -99.223322)
		(width 0.0889)
		(layer "In4.Cu")
		(net "M_E_ODT<2>")
	)
	(arc
		(start 264.46353 -97.410778)
		(mid 264.533927 -97.699729)
		(end 264.45464 -97.986342)
		(width 0.0889)
		(layer "In4.Cu")
		(net "M_E_ODT<2>")
	)
	(arc
		(start 264.45464 -97.986342)
		(mid 264.401107 -98.18624)
		(end 264.45464 -98.386138)
		(width 0.0889)
		(layer "In4.Cu")
		(net "M_E_ODT<2>")
	)
	(arc
		(start 264.46353 -98.401378)
		(mid 264.533927 -98.690329)
		(end 264.45464 -98.976942)
		(width 0.0889)
		(layer "In4.Cu")
		(net "M_E_ODT<2>")
	)
	(segment
		(start 265.372596 -95.21444)
		(end 264.801096 -95.21444)
		(width 0.1016)
		(layer "F.Cu")
		(net "M_E_ODT<1>")
	)
	(segment
		(start 276.300438 -142.6718)
		(end 276.29993 -142.677642)
		(width 0.1651)
		(layer "F.Cu")
		(net "M_E_ODT<1>")
	)
	(segment
		(start 276.29993 -143.97228)
		(end 276.300438 -143.972788)
		(width 0.1651)
		(layer "F.Cu")
		(net "M_E_ODT<1>")
	)
	(segment
		(start 276.29993 -142.677642)
		(end 276.29993 -143.97228)
		(width 0.1651)
		(layer "F.Cu")
		(net "M_E_ODT<1>")
	)
	(via
		(at 264.801096 -95.21444)
		(size 0.508)
		(drill 0.254)
		(layers "F.Cu" "B.Cu")
		(net "M_E_ODT<1>")
	)
	(via
		(at 276.300438 -143.972788)
		(size 0.4572)
		(drill 0.2032)
		(layers "F.Cu" "B.Cu")
		(net "M_E_ODT<1>")
	)
	(segment
		(start 266.006326 -96.500188)
		(end 266.011152 -96.508824)
		(width 0.0889)
		(layer "In4.Cu")
		(net "M_E_ODT<1>")
	)
	(segment
		(start 274.25269 -131.35229)
		(end 274.25269 -131.91871)
		(width 0.14224)
		(layer "In4.Cu")
		(net "M_E_ODT<1>")
	)
	(segment
		(start 267.6652 -121.224548)
		(end 270.72082 -124.280168)
		(width 0.14224)
		(layer "In4.Cu")
		(net "M_E_ODT<1>")
	)
	(segment
		(start 266.954 -102.0572)
		(end 266.954 -102.5144)
		(width 0.0889)
		(layer "In4.Cu")
		(net "M_E_ODT<1>")
	)
	(segment
		(start 275.674582 -140.041122)
		(end 275.674582 -140.724382)
		(width 0.14224)
		(layer "In4.Cu")
		(net "M_E_ODT<1>")
	)
	(segment
		(start 265.622532 -95.309436)
		(end 265.670792 -95.309436)
		(width 0.0889)
		(layer "In4.Cu")
		(net "M_E_ODT<1>")
	)
	(segment
		(start 264.801096 -95.21444)
		(end 265.622532 -95.309436)
		(width 0.0889)
		(layer "In4.Cu")
		(net "M_E_ODT<1>")
	)
	(segment
		(start 265.999976 -97.48012)
		(end 266.006326 -97.490788)
		(width 0.0889)
		(layer "In4.Cu")
		(net "M_E_ODT<1>")
	)
	(segment
		(start 266.954 -102.5144)
		(end 267.6652 -103.2256)
		(width 0.0889)
		(layer "In4.Cu")
		(net "M_E_ODT<1>")
	)
	(segment
		(start 266.4714 -99.8982)
		(end 266.4714 -101.5746)
		(width 0.0889)
		(layer "In4.Cu")
		(net "M_E_ODT<1>")
	)
	(segment
		(start 273.9644 -129.6416)
		(end 274.2184 -129.8956)
		(width 0.14224)
		(layer "In4.Cu")
		(net "M_E_ODT<1>")
	)
	(segment
		(start 267.6652 -103.2256)
		(end 267.6652 -103.547926)
		(width 0.0889)
		(layer "In4.Cu")
		(net "M_E_ODT<1>")
	)
	(segment
		(start 274.2184 -130.5814)
		(end 274.066 -130.7338)
		(width 0.14224)
		(layer "In4.Cu")
		(net "M_E_ODT<1>")
	)
	(segment
		(start 270.72082 -124.280168)
		(end 270.72082 -125.281944)
		(width 0.14224)
		(layer "In4.Cu")
		(net "M_E_ODT<1>")
	)
	(segment
		(start 275.883624 -140.933424)
		(end 275.883624 -143.555974)
		(width 0.14224)
		(layer "In4.Cu")
		(net "M_E_ODT<1>")
	)
	(segment
		(start 274.166838 -132.004562)
		(end 274.166838 -135.408162)
		(width 0.14224)
		(layer "In4.Cu")
		(net "M_E_ODT<1>")
	)
	(segment
		(start 274.066 -130.7338)
		(end 274.066 -131.1656)
		(width 0.14224)
		(layer "In4.Cu")
		(net "M_E_ODT<1>")
	)
	(segment
		(start 274.25269 -131.91871)
		(end 274.166838 -132.004562)
		(width 0.14224)
		(layer "In4.Cu")
		(net "M_E_ODT<1>")
	)
	(segment
		(start 266.05992 -99.48672)
		(end 266.4714 -99.8982)
		(width 0.0889)
		(layer "In4.Cu")
		(net "M_E_ODT<1>")
	)
	(segment
		(start 275.036534 -138.816334)
		(end 275.036534 -139.403074)
		(width 0.14224)
		(layer "In4.Cu")
		(net "M_E_ODT<1>")
	)
	(segment
		(start 274.2184 -129.8956)
		(end 274.2184 -130.5814)
		(width 0.14224)
		(layer "In4.Cu")
		(net "M_E_ODT<1>")
	)
	(segment
		(start 275.036534 -139.403074)
		(end 275.674582 -140.041122)
		(width 0.14224)
		(layer "In4.Cu")
		(net "M_E_ODT<1>")
	)
	(segment
		(start 274.066 -131.1656)
		(end 274.25269 -131.35229)
		(width 0.14224)
		(layer "In4.Cu")
		(net "M_E_ODT<1>")
	)
	(segment
		(start 274.166838 -135.408162)
		(end 274.159472 -135.415528)
		(width 0.14224)
		(layer "In4.Cu")
		(net "M_E_ODT<1>")
	)
	(segment
		(start 273.9644 -128.525524)
		(end 273.9644 -129.6416)
		(width 0.14224)
		(layer "In4.Cu")
		(net "M_E_ODT<1>")
	)
	(segment
		(start 266.05992 -97.685606)
		(end 266.05992 -99.48672)
		(width 0.0889)
		(layer "In4.Cu")
		(net "M_E_ODT<1>")
	)
	(segment
		(start 270.72082 -125.281944)
		(end 273.9644 -128.525524)
		(width 0.14224)
		(layer "In4.Cu")
		(net "M_E_ODT<1>")
	)
	(segment
		(start 265.999976 -96.48952)
		(end 266.006326 -96.500188)
		(width 0.0889)
		(layer "In4.Cu")
		(net "M_E_ODT<1>")
	)
	(segment
		(start 267.6652 -103.547926)
		(end 267.6652 -121.224548)
		(width 0.14224)
		(layer "In4.Cu")
		(net "M_E_ODT<1>")
	)
	(segment
		(start 266.4714 -101.5746)
		(end 266.954 -102.0572)
		(width 0.0889)
		(layer "In4.Cu")
		(net "M_E_ODT<1>")
	)
	(segment
		(start 274.159472 -137.939272)
		(end 275.036534 -138.816334)
		(width 0.14224)
		(layer "In4.Cu")
		(net "M_E_ODT<1>")
	)
	(segment
		(start 275.883624 -143.555974)
		(end 276.300438 -143.972788)
		(width 0.14224)
		(layer "In4.Cu")
		(net "M_E_ODT<1>")
	)
	(segment
		(start 275.674582 -140.724382)
		(end 275.883624 -140.933424)
		(width 0.14224)
		(layer "In4.Cu")
		(net "M_E_ODT<1>")
	)
	(segment
		(start 274.159472 -135.415528)
		(end 274.159472 -137.939272)
		(width 0.14224)
		(layer "In4.Cu")
		(net "M_E_ODT<1>")
	)
	(arc
		(start 265.670792 -95.309436)
		(mid 266.008961 -95.514234)
		(end 266.006326 -95.909638)
		(width 0.0889)
		(layer "In4.Cu")
		(net "M_E_ODT<1>")
	)
	(arc
		(start 266.006326 -96.900238)
		(mid 265.927104 -97.189356)
		(end 265.999976 -97.48012)
		(width 0.0889)
		(layer "In4.Cu")
		(net "M_E_ODT<1>")
	)
	(arc
		(start 266.006326 -97.490788)
		(mid 266.046265 -97.58458)
		(end 266.05992 -97.685606)
		(width 0.0889)
		(layer "In4.Cu")
		(net "M_E_ODT<1>")
	)
	(arc
		(start 266.011152 -96.508824)
		(mid 266.059907 -96.705176)
		(end 266.006326 -96.900238)
		(width 0.0889)
		(layer "In4.Cu")
		(net "M_E_ODT<1>")
	)
	(arc
		(start 266.006326 -95.909638)
		(mid 265.927104 -96.198756)
		(end 265.999976 -96.48952)
		(width 0.0889)
		(layer "In4.Cu")
		(net "M_E_ODT<1>")
	)
	(segment
		(start 263.65581 -96.20504)
		(end 263.08431 -96.20504)
		(width 0.1016)
		(layer "F.Cu")
		(net "M_E_ODT<0>")
	)
	(segment
		(start 272.899886 -142.677642)
		(end 272.899886 -143.968978)
		(width 0.1651)
		(layer "F.Cu")
		(net "M_E_ODT<0>")
	)
	(segment
		(start 272.900394 -142.6718)
		(end 272.899886 -142.677642)
		(width 0.1651)
		(layer "F.Cu")
		(net "M_E_ODT<0>")
	)
	(via
		(at 263.08431 -96.20504)
		(size 0.508)
		(drill 0.254)
		(layers "F.Cu" "B.Cu")
		(net "M_E_ODT<0>")
	)
	(via
		(at 272.899886 -143.968978)
		(size 0.508)
		(drill 0.254)
		(layers "F.Cu" "B.Cu")
		(net "M_E_ODT<0>")
	)
	(segment
		(start 270.765524 -136.06526)
		(end 270.765524 -134.085076)
		(width 0.14224)
		(layer "In4.Cu")
		(net "M_E_ODT<0>")
	)
	(segment
		(start 271.853406 -140.672058)
		(end 271.5768 -140.395452)
		(width 0.14224)
		(layer "In4.Cu")
		(net "M_E_ODT<0>")
	)
	(segment
		(start 264.289286 -98.481388)
		(end 264.280396 -98.466148)
		(width 0.0889)
		(layer "In4.Cu")
		(net "M_E_ODT<0>")
	)
	(segment
		(start 270.6116 -129.7178)
		(end 270.6116 -128.046988)
		(width 0.14224)
		(layer "In4.Cu")
		(net "M_E_ODT<0>")
	)
	(segment
		(start 270.765524 -134.085076)
		(end 270.8402 -134.0104)
		(width 0.14224)
		(layer "In4.Cu")
		(net "M_E_ODT<0>")
	)
	(segment
		(start 265.6332 -103.178356)
		(end 265.2268 -102.771956)
		(width 0.0889)
		(layer "In4.Cu")
		(net "M_E_ODT<0>")
	)
	(segment
		(start 268.6558 -126.091188)
		(end 268.6558 -124.849636)
		(width 0.14224)
		(layer "In4.Cu")
		(net "M_E_ODT<0>")
	)
	(segment
		(start 270.763492 -136.067292)
		(end 270.765524 -136.06526)
		(width 0.14224)
		(layer "In4.Cu")
		(net "M_E_ODT<0>")
	)
	(segment
		(start 272.899886 -143.968978)
		(end 272.472912 -143.542004)
		(width 0.14224)
		(layer "In4.Cu")
		(net "M_E_ODT<0>")
	)
	(segment
		(start 270.6116 -128.046988)
		(end 268.6558 -126.091188)
		(width 0.14224)
		(layer "In4.Cu")
		(net "M_E_ODT<0>")
	)
	(segment
		(start 270.7386 -131.1656)
		(end 270.7386 -130.683)
		(width 0.14224)
		(layer "In4.Cu")
		(net "M_E_ODT<0>")
	)
	(segment
		(start 270.891 -129.9972)
		(end 270.6116 -129.7178)
		(width 0.14224)
		(layer "In4.Cu")
		(net "M_E_ODT<0>")
	)
	(segment
		(start 271.5768 -140.395452)
		(end 271.5768 -139.5476)
		(width 0.14224)
		(layer "In4.Cu")
		(net "M_E_ODT<0>")
	)
	(segment
		(start 272.170906 -140.672058)
		(end 271.853406 -140.672058)
		(width 0.14224)
		(layer "In4.Cu")
		(net "M_E_ODT<0>")
	)
	(segment
		(start 271.621758 -138.830558)
		(end 270.763492 -137.972292)
		(width 0.14224)
		(layer "In4.Cu")
		(net "M_E_ODT<0>")
	)
	(segment
		(start 270.763492 -137.972292)
		(end 270.763492 -136.067292)
		(width 0.14224)
		(layer "In4.Cu")
		(net "M_E_ODT<0>")
	)
	(segment
		(start 270.8402 -134.0104)
		(end 270.8402 -131.2672)
		(width 0.14224)
		(layer "In4.Cu")
		(net "M_E_ODT<0>")
	)
	(segment
		(start 270.7386 -130.683)
		(end 270.891 -130.5306)
		(width 0.14224)
		(layer "In4.Cu")
		(net "M_E_ODT<0>")
	)
	(segment
		(start 268.6558 -124.849636)
		(end 265.6332 -121.827036)
		(width 0.14224)
		(layer "In4.Cu")
		(net "M_E_ODT<0>")
	)
	(segment
		(start 271.5768 -139.5476)
		(end 271.621758 -139.502642)
		(width 0.14224)
		(layer "In4.Cu")
		(net "M_E_ODT<0>")
	)
	(segment
		(start 264.16 -99.040696)
		(end 264.200894 -98.999802)
		(width 0.0889)
		(layer "In4.Cu")
		(net "M_E_ODT<0>")
	)
	(segment
		(start 263.43102 -96.995488)
		(end 263.08431 -96.20504)
		(width 0.0889)
		(layer "In4.Cu")
		(net "M_E_ODT<0>")
	)
	(segment
		(start 265.6332 -121.827036)
		(end 265.6332 -103.36149)
		(width 0.14224)
		(layer "In4.Cu")
		(net "M_E_ODT<0>")
	)
	(segment
		(start 271.621758 -139.502642)
		(end 271.621758 -138.830558)
		(width 0.14224)
		(layer "In4.Cu")
		(net "M_E_ODT<0>")
	)
	(segment
		(start 272.472912 -143.542004)
		(end 272.472912 -140.974064)
		(width 0.14224)
		(layer "In4.Cu")
		(net "M_E_ODT<0>")
	)
	(segment
		(start 270.8402 -131.2672)
		(end 270.7386 -131.1656)
		(width 0.14224)
		(layer "In4.Cu")
		(net "M_E_ODT<0>")
	)
	(segment
		(start 265.2268 -100.584)
		(end 264.16 -99.5172)
		(width 0.0889)
		(layer "In4.Cu")
		(net "M_E_ODT<0>")
	)
	(segment
		(start 263.94283 -97.290636)
		(end 263.92124 -97.290636)
		(width 0.0889)
		(layer "In4.Cu")
		(net "M_E_ODT<0>")
	)
	(segment
		(start 265.2268 -102.771956)
		(end 265.2268 -100.584)
		(width 0.0889)
		(layer "In4.Cu")
		(net "M_E_ODT<0>")
	)
	(segment
		(start 265.6332 -103.36149)
		(end 265.6332 -103.178356)
		(width 0.0889)
		(layer "In4.Cu")
		(net "M_E_ODT<0>")
	)
	(segment
		(start 270.891 -130.5306)
		(end 270.891 -129.9972)
		(width 0.14224)
		(layer "In4.Cu")
		(net "M_E_ODT<0>")
	)
	(segment
		(start 264.16 -99.5172)
		(end 264.16 -99.040696)
		(width 0.0889)
		(layer "In4.Cu")
		(net "M_E_ODT<0>")
	)
	(segment
		(start 272.472912 -140.974064)
		(end 272.170906 -140.672058)
		(width 0.14224)
		(layer "In4.Cu")
		(net "M_E_ODT<0>")
	)
	(arc
		(start 264.280396 -98.466148)
		(mid 264.209999 -98.177197)
		(end 264.289286 -97.890584)
		(width 0.0889)
		(layer "In4.Cu")
		(net "M_E_ODT<0>")
	)
	(arc
		(start 264.289286 -98.881184)
		(mid 264.342819 -98.681286)
		(end 264.289286 -98.481388)
		(width 0.0889)
		(layer "In4.Cu")
		(net "M_E_ODT<0>")
	)
	(arc
		(start 263.92124 -97.290636)
		(mid 263.638023 -97.206355)
		(end 263.43102 -96.995488)
		(width 0.0889)
		(layer "In4.Cu")
		(net "M_E_ODT<0>")
	)
	(arc
		(start 264.289286 -97.890584)
		(mid 264.289203 -97.490643)
		(end 263.94283 -97.290636)
		(width 0.0889)
		(layer "In4.Cu")
		(net "M_E_ODT<0>")
	)
	(arc
		(start 264.200894 -98.999802)
		(mid 264.248524 -98.943052)
		(end 264.289286 -98.881184)
		(width 0.0889)
		(layer "In4.Cu")
		(net "M_E_ODT<0>")
	)
	(segment
		(start 249.950478 -142.6718)
		(end 249.94997 -142.677642)
		(width 0.1651)
		(layer "F.Cu")
		(net "M_E_MA<9>")
	)
	(segment
		(start 249.94997 -143.970502)
		(end 249.949716 -143.970756)
		(width 0.1651)
		(layer "F.Cu")
		(net "M_E_MA<9>")
	)
	(segment
		(start 255.92913 -97.690686)
		(end 255.35763 -97.690686)
		(width 0.1016)
		(layer "F.Cu")
		(net "M_E_MA<9>")
	)
	(segment
		(start 249.94997 -142.677642)
		(end 249.94997 -143.970502)
		(width 0.1651)
		(layer "F.Cu")
		(net "M_E_MA<9>")
	)
	(via
		(at 255.35763 -97.690686)
		(size 0.508)
		(drill 0.254)
		(layers "F.Cu" "B.Cu")
		(net "M_E_MA<9>")
	)
	(via
		(at 249.949716 -143.970756)
		(size 0.4572)
		(drill 0.2032)
		(layers "F.Cu" "B.Cu")
		(net "M_E_MA<9>")
	)
	(via
		(at 249.94997 -141.187678)
		(size 0.4572)
		(drill 0.2032)
		(layers "F.Cu" "B.Cu")
		(net "M_E_MA<9>")
	)
	(segment
		(start 249.950478 -142.477236)
		(end 249.94997 -142.476982)
		(width 0.1651)
		(layer "B.Cu")
		(net "M_E_MA<9>")
	)
	(segment
		(start 249.94997 -142.476982)
		(end 249.94997 -141.187678)
		(width 0.1651)
		(layer "B.Cu")
		(net "M_E_MA<9>")
	)
	(segment
		(start 255.028192 -98.45167)
		(end 254.946404 -98.593148)
		(width 0.0889)
		(layer "In11.Cu")
		(net "M_E_MA<9>")
	)
	(segment
		(start 255.517904 -102.482904)
		(end 256.327148 -103.292148)
		(width 0.0889)
		(layer "In11.Cu")
		(net "M_E_MA<9>")
	)
	(segment
		(start 256.327148 -103.292148)
		(end 256.327148 -103.576374)
		(width 0.0889)
		(layer "In11.Cu")
		(net "M_E_MA<9>")
	)
	(segment
		(start 253.8476 -130.0226)
		(end 253.8476 -130.5306)
		(width 0.14224)
		(layer "In11.Cu")
		(net "M_E_MA<9>")
	)
	(segment
		(start 251.852938 -140.293598)
		(end 251.692664 -140.133324)
		(width 0.14224)
		(layer "In11.Cu")
		(net "M_E_MA<9>")
	)
	(segment
		(start 254.832104 -128.157732)
		(end 253.661926 -129.32791)
		(width 0.14224)
		(layer "In11.Cu")
		(net "M_E_MA<9>")
	)
	(segment
		(start 253.7206 -131.1656)
		(end 253.8222 -131.2672)
		(width 0.14224)
		(layer "In11.Cu")
		(net "M_E_MA<9>")
	)
	(segment
		(start 253.661926 -129.32791)
		(end 253.661926 -129.836926)
		(width 0.14224)
		(layer "In11.Cu")
		(net "M_E_MA<9>")
	)
	(segment
		(start 254.946404 -99.84232)
		(end 255.517904 -100.41382)
		(width 0.0889)
		(layer "In11.Cu")
		(net "M_E_MA<9>")
	)
	(segment
		(start 253.7841 -133.631432)
		(end 253.7841 -135.3947)
		(width 0.14224)
		(layer "In11.Cu")
		(net "M_E_MA<9>")
	)
	(segment
		(start 255.35763 -97.690686)
		(end 255.029462 -98.448876)
		(width 0.0889)
		(layer "In11.Cu")
		(net "M_E_MA<9>")
	)
	(segment
		(start 250.419108 -140.71854)
		(end 249.94997 -141.187678)
		(width 0.14224)
		(layer "In11.Cu")
		(net "M_E_MA<9>")
	)
	(segment
		(start 253.8222 -131.2672)
		(end 253.8222 -132.660136)
		(width 0.14224)
		(layer "In11.Cu")
		(net "M_E_MA<9>")
	)
	(segment
		(start 254.946404 -98.593148)
		(end 254.946404 -99.84232)
		(width 0.0889)
		(layer "In11.Cu")
		(net "M_E_MA<9>")
	)
	(segment
		(start 253.975616 -132.813552)
		(end 254.306832 -132.813552)
		(width 0.14224)
		(layer "In11.Cu")
		(net "M_E_MA<9>")
	)
	(segment
		(start 252.932946 -140.453872)
		(end 252.668278 -140.71854)
		(width 0.14224)
		(layer "In11.Cu")
		(net "M_E_MA<9>")
	)
	(segment
		(start 253.8476 -130.5306)
		(end 253.7206 -130.6576)
		(width 0.14224)
		(layer "In11.Cu")
		(net "M_E_MA<9>")
	)
	(segment
		(start 256.327148 -103.576374)
		(end 256.327148 -124.317252)
		(width 0.14224)
		(layer "In11.Cu")
		(net "M_E_MA<9>")
	)
	(segment
		(start 253.7841 -135.3947)
		(end 253.761748 -135.417052)
		(width 0.14224)
		(layer "In11.Cu")
		(net "M_E_MA<9>")
	)
	(segment
		(start 254.832104 -125.812296)
		(end 254.832104 -128.157732)
		(width 0.14224)
		(layer "In11.Cu")
		(net "M_E_MA<9>")
	)
	(segment
		(start 252.007878 -140.71854)
		(end 251.852938 -140.5636)
		(width 0.14224)
		(layer "In11.Cu")
		(net "M_E_MA<9>")
	)
	(segment
		(start 254.306832 -132.813552)
		(end 254.45085 -132.95757)
		(width 0.14224)
		(layer "In11.Cu")
		(net "M_E_MA<9>")
	)
	(segment
		(start 253.761748 -135.417052)
		(end 253.761748 -137.596372)
		(width 0.14224)
		(layer "In11.Cu")
		(net "M_E_MA<9>")
	)
	(segment
		(start 253.7206 -130.6576)
		(end 253.7206 -131.1656)
		(width 0.14224)
		(layer "In11.Cu")
		(net "M_E_MA<9>")
	)
	(segment
		(start 256.327148 -124.317252)
		(end 254.832104 -125.812296)
		(width 0.14224)
		(layer "In11.Cu")
		(net "M_E_MA<9>")
	)
	(segment
		(start 253.93904 -133.476492)
		(end 253.7841 -133.631432)
		(width 0.14224)
		(layer "In11.Cu")
		(net "M_E_MA<9>")
	)
	(segment
		(start 249.94997 -141.187678)
		(end 249.94997 -143.970502)
		(width 0.14224)
		(layer "In11.Cu")
		(net "M_E_MA<9>")
	)
	(segment
		(start 251.189998 -140.28293)
		(end 251.189998 -140.5636)
		(width 0.14224)
		(layer "In11.Cu")
		(net "M_E_MA<9>")
	)
	(segment
		(start 251.189998 -140.5636)
		(end 251.035058 -140.71854)
		(width 0.14224)
		(layer "In11.Cu")
		(net "M_E_MA<9>")
	)
	(segment
		(start 254.45085 -133.31063)
		(end 254.284988 -133.476492)
		(width 0.14224)
		(layer "In11.Cu")
		(net "M_E_MA<9>")
	)
	(segment
		(start 254.284988 -133.476492)
		(end 253.93904 -133.476492)
		(width 0.14224)
		(layer "In11.Cu")
		(net "M_E_MA<9>")
	)
	(segment
		(start 251.852938 -140.5636)
		(end 251.852938 -140.293598)
		(width 0.14224)
		(layer "In11.Cu")
		(net "M_E_MA<9>")
	)
	(segment
		(start 253.661926 -129.836926)
		(end 253.8476 -130.0226)
		(width 0.14224)
		(layer "In11.Cu")
		(net "M_E_MA<9>")
	)
	(segment
		(start 251.692664 -140.133324)
		(end 251.339604 -140.133324)
		(width 0.14224)
		(layer "In11.Cu")
		(net "M_E_MA<9>")
	)
	(segment
		(start 254.45085 -132.95757)
		(end 254.45085 -133.31063)
		(width 0.14224)
		(layer "In11.Cu")
		(net "M_E_MA<9>")
	)
	(segment
		(start 253.8222 -132.660136)
		(end 253.975616 -132.813552)
		(width 0.14224)
		(layer "In11.Cu")
		(net "M_E_MA<9>")
	)
	(segment
		(start 255.517904 -100.41382)
		(end 255.517904 -102.482904)
		(width 0.0889)
		(layer "In11.Cu")
		(net "M_E_MA<9>")
	)
	(segment
		(start 253.761748 -137.596372)
		(end 252.932946 -138.425174)
		(width 0.14224)
		(layer "In11.Cu")
		(net "M_E_MA<9>")
	)
	(segment
		(start 255.029462 -98.448876)
		(end 255.028192 -98.45167)
		(width 0.0889)
		(layer "In11.Cu")
		(net "M_E_MA<9>")
	)
	(segment
		(start 252.932946 -138.425174)
		(end 252.932946 -140.453872)
		(width 0.14224)
		(layer "In11.Cu")
		(net "M_E_MA<9>")
	)
	(segment
		(start 249.94997 -143.970502)
		(end 249.949716 -143.970756)
		(width 0.14224)
		(layer "In11.Cu")
		(net "M_E_MA<9>")
	)
	(segment
		(start 251.035058 -140.71854)
		(end 250.419108 -140.71854)
		(width 0.14224)
		(layer "In11.Cu")
		(net "M_E_MA<9>")
	)
	(segment
		(start 251.339604 -140.133324)
		(end 251.189998 -140.28293)
		(width 0.14224)
		(layer "In11.Cu")
		(net "M_E_MA<9>")
	)
	(segment
		(start 252.668278 -140.71854)
		(end 252.007878 -140.71854)
		(width 0.14224)
		(layer "In11.Cu")
		(net "M_E_MA<9>")
	)
	(segment
		(start 255.07061 -93.23324)
		(end 254.49911 -93.23324)
		(width 0.1016)
		(layer "F.Cu")
		(net "M_E_MA<8>")
	)
	(segment
		(start 251.649992 -142.677642)
		(end 251.649992 -143.972788)
		(width 0.1651)
		(layer "F.Cu")
		(net "M_E_MA<8>")
	)
	(segment
		(start 251.6505 -142.6718)
		(end 251.649992 -142.677642)
		(width 0.1651)
		(layer "F.Cu")
		(net "M_E_MA<8>")
	)
	(via
		(at 251.649992 -143.972788)
		(size 0.4572)
		(drill 0.2032)
		(layers "F.Cu" "B.Cu")
		(net "M_E_MA<8>")
	)
	(via
		(at 251.649992 -141.187678)
		(size 0.4572)
		(drill 0.2032)
		(layers "F.Cu" "B.Cu")
		(net "M_E_MA<8>")
	)
	(via
		(at 254.49911 -93.23324)
		(size 0.508)
		(drill 0.254)
		(layers "F.Cu" "B.Cu")
		(net "M_E_MA<8>")
	)
	(segment
		(start 251.6505 -142.477236)
		(end 251.649992 -142.476982)
		(width 0.1651)
		(layer "B.Cu")
		(net "M_E_MA<8>")
	)
	(segment
		(start 251.649992 -142.476982)
		(end 251.649992 -141.187678)
		(width 0.1651)
		(layer "B.Cu")
		(net "M_E_MA<8>")
	)
	(segment
		(start 250.39701 -142.844266)
		(end 250.735338 -142.844266)
		(width 0.14224)
		(layer "In4.Cu")
		(net "M_E_MA<8>")
	)
	(segment
		(start 250.890278 -143.352012)
		(end 250.756674 -143.485616)
		(width 0.14224)
		(layer "In4.Cu")
		(net "M_E_MA<8>")
	)
	(segment
		(start 254.381 -100.33)
		(end 255.117092 -101.066092)
		(width 0.0889)
		(layer "In4.Cu")
		(net "M_E_MA<8>")
	)
	(segment
		(start 255.117092 -101.066092)
		(end 255.117092 -103.562658)
		(width 0.0889)
		(layer "In4.Cu")
		(net "M_E_MA<8>")
	)
	(segment
		(start 251.968 -128.735582)
		(end 251.2822 -129.421382)
		(width 0.14224)
		(layer "In4.Cu")
		(net "M_E_MA<8>")
	)
	(segment
		(start 250.516136 -143.485616)
		(end 250.363482 -143.63827)
		(width 0.14224)
		(layer "In4.Cu")
		(net "M_E_MA<8>")
	)
	(segment
		(start 251.649992 -141.187678)
		(end 251.449332 -141.187678)
		(width 0.14224)
		(layer "In4.Cu")
		(net "M_E_MA<8>")
	)
	(segment
		(start 250.735338 -142.844266)
		(end 250.890278 -142.999206)
		(width 0.14224)
		(layer "In4.Cu")
		(net "M_E_MA<8>")
	)
	(segment
		(start 251.111512 -145.308066)
		(end 251.630434 -145.308066)
		(width 0.14224)
		(layer "In4.Cu")
		(net "M_E_MA<8>")
	)
	(segment
		(start 250.945904 -145.142458)
		(end 251.111512 -145.308066)
		(width 0.14224)
		(layer "In4.Cu")
		(net "M_E_MA<8>")
	)
	(segment
		(start 251.1552 -130.048)
		(end 251.1552 -130.5052)
		(width 0.14224)
		(layer "In4.Cu")
		(net "M_E_MA<8>")
	)
	(segment
		(start 251.212604 -140.189204)
		(end 251.649992 -140.626592)
		(width 0.14224)
		(layer "In4.Cu")
		(net "M_E_MA<8>")
	)
	(segment
		(start 251.2822 -129.921)
		(end 251.1552 -130.048)
		(width 0.14224)
		(layer "In4.Cu")
		(net "M_E_MA<8>")
	)
	(segment
		(start 254.152654 -95.414338)
		(end 254.161544 -95.429578)
		(width 0.0889)
		(layer "In4.Cu")
		(net "M_E_MA<8>")
	)
	(segment
		(start 251.23521 -134.11581)
		(end 251.23521 -134.74319)
		(width 0.14224)
		(layer "In4.Cu")
		(net "M_E_MA<8>")
	)
	(segment
		(start 254.49911 -93.23324)
		(end 254.169164 -93.99524)
		(width 0.0889)
		(layer "In4.Cu")
		(net "M_E_MA<8>")
	)
	(segment
		(start 251.80671 -144.129506)
		(end 251.649992 -143.972788)
		(width 0.14224)
		(layer "In4.Cu")
		(net "M_E_MA<8>")
	)
	(segment
		(start 254.381 -98.8568)
		(end 254.381 -100.33)
		(width 0.0889)
		(layer "In4.Cu")
		(net "M_E_MA<8>")
	)
	(segment
		(start 250.890278 -141.746732)
		(end 250.890278 -142.127986)
		(width 0.14224)
		(layer "In4.Cu")
		(net "M_E_MA<8>")
	)
	(segment
		(start 251.23521 -134.74319)
		(end 251.192538 -134.785862)
		(width 0.14224)
		(layer "In4.Cu")
		(net "M_E_MA<8>")
	)
	(segment
		(start 250.890278 -142.127986)
		(end 250.735338 -142.282926)
		(width 0.14224)
		(layer "In4.Cu")
		(net "M_E_MA<8>")
	)
	(segment
		(start 254.152654 -94.423484)
		(end 254.159004 -94.434152)
		(width 0.0889)
		(layer "In4.Cu")
		(net "M_E_MA<8>")
	)
	(segment
		(start 251.649992 -140.626592)
		(end 251.649992 -141.187678)
		(width 0.14224)
		(layer "In4.Cu")
		(net "M_E_MA<8>")
	)
	(segment
		(start 250.945904 -144.765522)
		(end 250.945904 -145.142458)
		(width 0.14224)
		(layer "In4.Cu")
		(net "M_E_MA<8>")
	)
	(segment
		(start 250.363482 -143.63827)
		(end 250.363482 -144.1831)
		(width 0.14224)
		(layer "In4.Cu")
		(net "M_E_MA<8>")
	)
	(segment
		(start 250.735338 -142.282926)
		(end 250.408186 -142.282926)
		(width 0.14224)
		(layer "In4.Cu")
		(net "M_E_MA<8>")
	)
	(segment
		(start 251.192792 -131.305808)
		(end 251.192792 -134.073392)
		(width 0.14224)
		(layer "In4.Cu")
		(net "M_E_MA<8>")
	)
	(segment
		(start 254.169164 -93.99524)
		(end 254.152654 -94.023688)
		(width 0.0889)
		(layer "In4.Cu")
		(net "M_E_MA<8>")
	)
	(segment
		(start 250.408186 -142.282926)
		(end 250.247658 -142.443454)
		(width 0.14224)
		(layer "In4.Cu")
		(net "M_E_MA<8>")
	)
	(segment
		(start 251.80671 -145.13179)
		(end 251.80671 -144.129506)
		(width 0.14224)
		(layer "In4.Cu")
		(net "M_E_MA<8>")
	)
	(segment
		(start 254.152654 -96.404938)
		(end 254.161544 -96.420178)
		(width 0.0889)
		(layer "In4.Cu")
		(net "M_E_MA<8>")
	)
	(segment
		(start 251.1552 -130.5052)
		(end 251.3076 -130.6576)
		(width 0.14224)
		(layer "In4.Cu")
		(net "M_E_MA<8>")
	)
	(segment
		(start 250.247658 -142.694914)
		(end 250.39701 -142.844266)
		(width 0.14224)
		(layer "In4.Cu")
		(net "M_E_MA<8>")
	)
	(segment
		(start 254.152654 -97.395538)
		(end 254.161544 -97.410778)
		(width 0.0889)
		(layer "In4.Cu")
		(net "M_E_MA<8>")
	)
	(segment
		(start 250.247658 -142.443454)
		(end 250.247658 -142.694914)
		(width 0.14224)
		(layer "In4.Cu")
		(net "M_E_MA<8>")
	)
	(segment
		(start 251.3076 -130.6576)
		(end 251.3076 -131.191)
		(width 0.14224)
		(layer "In4.Cu")
		(net "M_E_MA<8>")
	)
	(segment
		(start 251.449332 -141.187678)
		(end 250.890278 -141.746732)
		(width 0.14224)
		(layer "In4.Cu")
		(net "M_E_MA<8>")
	)
	(segment
		(start 250.756674 -143.485616)
		(end 250.516136 -143.485616)
		(width 0.14224)
		(layer "In4.Cu")
		(net "M_E_MA<8>")
	)
	(segment
		(start 251.192792 -134.073392)
		(end 251.23521 -134.11581)
		(width 0.14224)
		(layer "In4.Cu")
		(net "M_E_MA<8>")
	)
	(segment
		(start 251.192538 -134.785862)
		(end 251.192538 -135.317738)
		(width 0.14224)
		(layer "In4.Cu")
		(net "M_E_MA<8>")
	)
	(segment
		(start 251.968 -126.70536)
		(end 251.968 -128.735582)
		(width 0.14224)
		(layer "In4.Cu")
		(net "M_E_MA<8>")
	)
	(segment
		(start 250.363482 -144.1831)
		(end 250.945904 -144.765522)
		(width 0.14224)
		(layer "In4.Cu")
		(net "M_E_MA<8>")
	)
	(segment
		(start 251.2822 -129.421382)
		(end 251.2822 -129.921)
		(width 0.14224)
		(layer "In4.Cu")
		(net "M_E_MA<8>")
	)
	(segment
		(start 251.3076 -131.191)
		(end 251.192792 -131.305808)
		(width 0.14224)
		(layer "In4.Cu")
		(net "M_E_MA<8>")
	)
	(segment
		(start 251.212604 -135.337804)
		(end 251.212604 -140.189204)
		(width 0.14224)
		(layer "In4.Cu")
		(net "M_E_MA<8>")
	)
	(segment
		(start 251.630434 -145.308066)
		(end 251.80671 -145.13179)
		(width 0.14224)
		(layer "In4.Cu")
		(net "M_E_MA<8>")
	)
	(segment
		(start 255.117092 -123.556268)
		(end 251.968 -126.70536)
		(width 0.14224)
		(layer "In4.Cu")
		(net "M_E_MA<8>")
	)
	(segment
		(start 255.117092 -103.562658)
		(end 255.117092 -123.556268)
		(width 0.14224)
		(layer "In4.Cu")
		(net "M_E_MA<8>")
	)
	(segment
		(start 251.192538 -135.317738)
		(end 251.212604 -135.337804)
		(width 0.14224)
		(layer "In4.Cu")
		(net "M_E_MA<8>")
	)
	(segment
		(start 250.890278 -142.999206)
		(end 250.890278 -143.352012)
		(width 0.14224)
		(layer "In4.Cu")
		(net "M_E_MA<8>")
	)
	(arc
		(start 254.161544 -97.410778)
		(mid 254.231941 -97.699729)
		(end 254.152654 -97.986342)
		(width 0.0889)
		(layer "In4.Cu")
		(net "M_E_MA<8>")
	)
	(arc
		(start 254.152654 -98.386138)
		(mid 254.202284 -98.469706)
		(end 254.254 -98.552)
		(width 0.0889)
		(layer "In4.Cu")
		(net "M_E_MA<8>")
	)
	(arc
		(start 254.161544 -96.420178)
		(mid 254.231941 -96.709129)
		(end 254.152654 -96.995742)
		(width 0.0889)
		(layer "In4.Cu")
		(net "M_E_MA<8>")
	)
	(arc
		(start 254.159004 -94.434152)
		(mid 254.231924 -94.725169)
		(end 254.152654 -95.014542)
		(width 0.0889)
		(layer "In4.Cu")
		(net "M_E_MA<8>")
	)
	(arc
		(start 254.152654 -95.014542)
		(mid 254.099121 -95.21444)
		(end 254.152654 -95.414338)
		(width 0.0889)
		(layer "In4.Cu")
		(net "M_E_MA<8>")
	)
	(arc
		(start 254.152654 -97.986342)
		(mid 254.099121 -98.18624)
		(end 254.152654 -98.386138)
		(width 0.0889)
		(layer "In4.Cu")
		(net "M_E_MA<8>")
	)
	(arc
		(start 254.152654 -94.023688)
		(mid 254.099121 -94.223586)
		(end 254.152654 -94.423484)
		(width 0.0889)
		(layer "In4.Cu")
		(net "M_E_MA<8>")
	)
	(arc
		(start 254.152654 -96.995742)
		(mid 254.099121 -97.19564)
		(end 254.152654 -97.395538)
		(width 0.0889)
		(layer "In4.Cu")
		(net "M_E_MA<8>")
	)
	(arc
		(start 254.161544 -95.429578)
		(mid 254.231941 -95.718529)
		(end 254.152654 -96.005142)
		(width 0.0889)
		(layer "In4.Cu")
		(net "M_E_MA<8>")
	)
	(arc
		(start 254.254 -98.552)
		(mid 254.331188 -98.698699)
		(end 254.381 -98.8568)
		(width 0.0889)
		(layer "In4.Cu")
		(net "M_E_MA<8>")
	)
	(arc
		(start 254.152654 -96.005142)
		(mid 254.099121 -96.20504)
		(end 254.152654 -96.404938)
		(width 0.0889)
		(layer "In4.Cu")
		(net "M_E_MA<8>")
	)
	(segment
		(start 250.800362 -147.27174)
		(end 250.799854 -147.27174)
		(width 0.1651)
		(layer "F.Cu")
		(net "M_E_MA<7>")
	)
	(segment
		(start 250.799854 -147.27174)
		(end 250.799854 -145.988278)
		(width 0.1651)
		(layer "F.Cu")
		(net "M_E_MA<7>")
	)
	(segment
		(start 254.212344 -93.72854)
		(end 253.640844 -93.72854)
		(width 0.1016)
		(layer "F.Cu")
		(net "M_E_MA<7>")
	)
	(via
		(at 250.799854 -145.988278)
		(size 0.4572)
		(drill 0.2032)
		(layers "F.Cu" "B.Cu")
		(net "M_E_MA<7>")
	)
	(via
		(at 253.640844 -93.72854)
		(size 0.508)
		(drill 0.254)
		(layers "F.Cu" "B.Cu")
		(net "M_E_MA<7>")
	)
	(via
		(at 250.799854 -139.170156)
		(size 0.4572)
		(drill 0.2032)
		(layers "F.Cu" "B.Cu")
		(net "M_E_MA<7>")
	)
	(segment
		(start 250.800362 -137.877296)
		(end 250.799854 -137.877296)
		(width 0.1651)
		(layer "B.Cu")
		(net "M_E_MA<7>")
	)
	(segment
		(start 250.799854 -137.877296)
		(end 250.799854 -139.170156)
		(width 0.1651)
		(layer "B.Cu")
		(net "M_E_MA<7>")
	)
	(segment
		(start 250.426474 -144.891252)
		(end 250.426474 -145.614898)
		(width 0.14224)
		(layer "In4.Cu")
		(net "M_E_MA<7>")
	)
	(segment
		(start 254.609092 -123.345448)
		(end 254.356362 -123.598178)
		(width 0.14224)
		(layer "In4.Cu")
		(net "M_E_MA<7>")
	)
	(segment
		(start 249.772424 -140.752576)
		(end 249.528076 -140.996924)
		(width 0.14224)
		(layer "In4.Cu")
		(net "M_E_MA<7>")
	)
	(segment
		(start 252.402086 -125.092714)
		(end 252.402086 -125.552454)
		(width 0.14224)
		(layer "In4.Cu")
		(net "M_E_MA<7>")
	)
	(segment
		(start 251.291852 -128.45034)
		(end 251.088652 -128.65354)
		(width 0.14224)
		(layer "In4.Cu")
		(net "M_E_MA<7>")
	)
	(segment
		(start 250.799854 -139.170156)
		(end 250.799854 -139.826746)
		(width 0.14224)
		(layer "In4.Cu")
		(net "M_E_MA<7>")
	)
	(segment
		(start 250.426474 -145.614898)
		(end 250.799854 -145.988278)
		(width 0.14224)
		(layer "In4.Cu")
		(net "M_E_MA<7>")
	)
	(segment
		(start 253.97841 -96.484948)
		(end 253.9873 -96.500188)
		(width 0.0889)
		(layer "In4.Cu")
		(net "M_E_MA<7>")
	)
	(segment
		(start 250.4186 -131.2926)
		(end 250.4186 -134.0358)
		(width 0.14224)
		(layer "In4.Cu")
		(net "M_E_MA<7>")
	)
	(segment
		(start 250.317 -131.191)
		(end 250.4186 -131.2926)
		(width 0.14224)
		(layer "In4.Cu")
		(net "M_E_MA<7>")
	)
	(segment
		(start 250.543314 -126.967742)
		(end 250.356624 -127.154432)
		(width 0.14224)
		(layer "In4.Cu")
		(net "M_E_MA<7>")
	)
	(segment
		(start 249.528076 -144.205198)
		(end 249.813064 -144.490186)
		(width 0.14224)
		(layer "In4.Cu")
		(net "M_E_MA<7>")
	)
	(segment
		(start 254.609092 -103.5558)
		(end 254.609092 -123.345448)
		(width 0.14224)
		(layer "In4.Cu")
		(net "M_E_MA<7>")
	)
	(segment
		(start 254.889 -101.219)
		(end 254.889 -102.9335)
		(width 0.0889)
		(layer "In4.Cu")
		(net "M_E_MA<7>")
	)
	(segment
		(start 249.813064 -144.490186)
		(end 250.025408 -144.490186)
		(width 0.14224)
		(layer "In4.Cu")
		(net "M_E_MA<7>")
	)
	(segment
		(start 254.094488 -98.69678)
		(end 254.094488 -100.424488)
		(width 0.0889)
		(layer "In4.Cu")
		(net "M_E_MA<7>")
	)
	(segment
		(start 250.437396 -130.486404)
		(end 250.317 -130.6068)
		(width 0.14224)
		(layer "In4.Cu")
		(net "M_E_MA<7>")
	)
	(segment
		(start 252.402086 -125.552454)
		(end 250.986798 -126.967742)
		(width 0.14224)
		(layer "In4.Cu")
		(net "M_E_MA<7>")
	)
	(segment
		(start 250.356624 -127.154432)
		(end 250.356624 -127.677164)
		(width 0.14224)
		(layer "In4.Cu")
		(net "M_E_MA<7>")
	)
	(segment
		(start 253.97841 -97.475548)
		(end 253.9873 -97.490788)
		(width 0.0889)
		(layer "In4.Cu")
		(net "M_E_MA<7>")
	)
	(segment
		(start 251.291852 -128.04394)
		(end 251.291852 -128.45034)
		(width 0.14224)
		(layer "In4.Cu")
		(net "M_E_MA<7>")
	)
	(segment
		(start 250.358148 -140.268452)
		(end 250.358148 -140.445236)
		(width 0.14224)
		(layer "In4.Cu")
		(net "M_E_MA<7>")
	)
	(segment
		(start 250.025408 -144.490186)
		(end 250.426474 -144.891252)
		(width 0.14224)
		(layer "In4.Cu")
		(net "M_E_MA<7>")
	)
	(segment
		(start 250.384056 -134.763256)
		(end 250.384056 -138.754358)
		(width 0.14224)
		(layer "In4.Cu")
		(net "M_E_MA<7>")
	)
	(segment
		(start 250.361704 -134.092696)
		(end 250.361704 -134.740904)
		(width 0.14224)
		(layer "In4.Cu")
		(net "M_E_MA<7>")
	)
	(segment
		(start 250.5202 -127.84074)
		(end 251.088652 -127.84074)
		(width 0.14224)
		(layer "In4.Cu")
		(net "M_E_MA<7>")
	)
	(segment
		(start 250.437396 -129.990596)
		(end 250.437396 -130.486404)
		(width 0.14224)
		(layer "In4.Cu")
		(net "M_E_MA<7>")
	)
	(segment
		(start 252.747018 -124.747782)
		(end 252.402086 -125.092714)
		(width 0.14224)
		(layer "In4.Cu")
		(net "M_E_MA<7>")
	)
	(segment
		(start 253.97841 -95.494348)
		(end 253.9873 -95.509588)
		(width 0.0889)
		(layer "In4.Cu")
		(net "M_E_MA<7>")
	)
	(segment
		(start 249.528076 -140.996924)
		(end 249.528076 -144.205198)
		(width 0.14224)
		(layer "In4.Cu")
		(net "M_E_MA<7>")
	)
	(segment
		(start 254.889 -102.9335)
		(end 254.609092 -103.213408)
		(width 0.0889)
		(layer "In4.Cu")
		(net "M_E_MA<7>")
	)
	(segment
		(start 250.384056 -138.754358)
		(end 250.799854 -139.170156)
		(width 0.14224)
		(layer "In4.Cu")
		(net "M_E_MA<7>")
	)
	(segment
		(start 254.356362 -123.598178)
		(end 253.896622 -123.598178)
		(width 0.14224)
		(layer "In4.Cu")
		(net "M_E_MA<7>")
	)
	(segment
		(start 254.609092 -103.213408)
		(end 254.609092 -103.5558)
		(width 0.0889)
		(layer "In4.Cu")
		(net "M_E_MA<7>")
	)
	(segment
		(start 250.317 -129.8702)
		(end 250.437396 -129.990596)
		(width 0.14224)
		(layer "In4.Cu")
		(net "M_E_MA<7>")
	)
	(segment
		(start 250.317 -128.85674)
		(end 250.317 -129.8702)
		(width 0.14224)
		(layer "In4.Cu")
		(net "M_E_MA<7>")
	)
	(segment
		(start 250.986798 -126.967742)
		(end 250.543314 -126.967742)
		(width 0.14224)
		(layer "In4.Cu")
		(net "M_E_MA<7>")
	)
	(segment
		(start 253.206758 -124.747782)
		(end 252.747018 -124.747782)
		(width 0.14224)
		(layer "In4.Cu")
		(net "M_E_MA<7>")
	)
	(segment
		(start 254.094488 -100.424488)
		(end 254.889 -101.219)
		(width 0.0889)
		(layer "In4.Cu")
		(net "M_E_MA<7>")
	)
	(segment
		(start 250.4186 -134.0358)
		(end 250.361704 -134.092696)
		(width 0.14224)
		(layer "In4.Cu")
		(net "M_E_MA<7>")
	)
	(segment
		(start 250.5202 -128.65354)
		(end 250.317 -128.85674)
		(width 0.14224)
		(layer "In4.Cu")
		(net "M_E_MA<7>")
	)
	(segment
		(start 250.361704 -134.740904)
		(end 250.384056 -134.763256)
		(width 0.14224)
		(layer "In4.Cu")
		(net "M_E_MA<7>")
	)
	(segment
		(start 250.050808 -140.752576)
		(end 249.772424 -140.752576)
		(width 0.14224)
		(layer "In4.Cu")
		(net "M_E_MA<7>")
	)
	(segment
		(start 253.55169 -123.94311)
		(end 253.55169 -124.40285)
		(width 0.14224)
		(layer "In4.Cu")
		(net "M_E_MA<7>")
	)
	(segment
		(start 251.088652 -127.84074)
		(end 251.291852 -128.04394)
		(width 0.14224)
		(layer "In4.Cu")
		(net "M_E_MA<7>")
	)
	(segment
		(start 251.088652 -128.65354)
		(end 250.5202 -128.65354)
		(width 0.14224)
		(layer "In4.Cu")
		(net "M_E_MA<7>")
	)
	(segment
		(start 250.317 -130.6068)
		(end 250.317 -131.191)
		(width 0.14224)
		(layer "In4.Cu")
		(net "M_E_MA<7>")
	)
	(segment
		(start 250.799854 -139.826746)
		(end 250.358148 -140.268452)
		(width 0.14224)
		(layer "In4.Cu")
		(net "M_E_MA<7>")
	)
	(segment
		(start 250.356624 -127.677164)
		(end 250.5202 -127.84074)
		(width 0.14224)
		(layer "In4.Cu")
		(net "M_E_MA<7>")
	)
	(segment
		(start 253.896622 -123.598178)
		(end 253.55169 -123.94311)
		(width 0.14224)
		(layer "In4.Cu")
		(net "M_E_MA<7>")
	)
	(segment
		(start 250.358148 -140.445236)
		(end 250.050808 -140.752576)
		(width 0.14224)
		(layer "In4.Cu")
		(net "M_E_MA<7>")
	)
	(segment
		(start 253.55169 -124.40285)
		(end 253.206758 -124.747782)
		(width 0.14224)
		(layer "In4.Cu")
		(net "M_E_MA<7>")
	)
	(segment
		(start 253.97841 -98.466148)
		(end 253.9873 -98.481388)
		(width 0.0889)
		(layer "In4.Cu")
		(net "M_E_MA<7>")
	)
	(arc
		(start 253.9873 -95.509588)
		(mid 254.040833 -95.709486)
		(end 253.9873 -95.909384)
		(width 0.0889)
		(layer "In4.Cu")
		(net "M_E_MA<7>")
	)
	(arc
		(start 253.9873 -94.518988)
		(mid 254.040833 -94.718886)
		(end 253.9873 -94.918784)
		(width 0.0889)
		(layer "In4.Cu")
		(net "M_E_MA<7>")
	)
	(arc
		(start 253.9873 -95.909384)
		(mid 253.908111 -96.195999)
		(end 253.97841 -96.484948)
		(width 0.0889)
		(layer "In4.Cu")
		(net "M_E_MA<7>")
	)
	(arc
		(start 253.9873 -94.918784)
		(mid 253.908111 -95.205399)
		(end 253.97841 -95.494348)
		(width 0.0889)
		(layer "In4.Cu")
		(net "M_E_MA<7>")
	)
	(arc
		(start 253.9873 -96.899984)
		(mid 253.908111 -97.186599)
		(end 253.97841 -97.475548)
		(width 0.0889)
		(layer "In4.Cu")
		(net "M_E_MA<7>")
	)
	(arc
		(start 253.9873 -97.490788)
		(mid 254.040833 -97.690686)
		(end 253.9873 -97.890584)
		(width 0.0889)
		(layer "In4.Cu")
		(net "M_E_MA<7>")
	)
	(arc
		(start 253.640844 -93.72854)
		(mid 253.716457 -94.087105)
		(end 253.930404 -94.384622)
		(width 0.0889)
		(layer "In4.Cu")
		(net "M_E_MA<7>")
	)
	(arc
		(start 253.9873 -96.500188)
		(mid 254.040833 -96.700086)
		(end 253.9873 -96.899984)
		(width 0.0889)
		(layer "In4.Cu")
		(net "M_E_MA<7>")
	)
	(arc
		(start 253.9873 -98.481388)
		(mid 254.044474 -98.587303)
		(end 254.094488 -98.69678)
		(width 0.0889)
		(layer "In4.Cu")
		(net "M_E_MA<7>")
	)
	(arc
		(start 253.930404 -94.384622)
		(mid 253.954696 -94.453564)
		(end 253.9873 -94.518988)
		(width 0.0889)
		(layer "In4.Cu")
		(net "M_E_MA<7>")
	)
	(arc
		(start 253.9873 -97.890584)
		(mid 253.908111 -98.177199)
		(end 253.97841 -98.466148)
		(width 0.0889)
		(layer "In4.Cu")
		(net "M_E_MA<7>")
	)
	(segment
		(start 255.92913 -94.718886)
		(end 255.35763 -94.718886)
		(width 0.1016)
		(layer "F.Cu")
		(net "M_E_MA<6>")
	)
	(segment
		(start 252.499876 -142.677642)
		(end 252.499876 -143.972788)
		(width 0.1651)
		(layer "F.Cu")
		(net "M_E_MA<6>")
	)
	(segment
		(start 252.500384 -142.6718)
		(end 252.499876 -142.677642)
		(width 0.1651)
		(layer "F.Cu")
		(net "M_E_MA<6>")
	)
	(via
		(at 252.499876 -143.972788)
		(size 0.4572)
		(drill 0.2032)
		(layers "F.Cu" "B.Cu")
		(net "M_E_MA<6>")
	)
	(via
		(at 252.499876 -141.187678)
		(size 0.4572)
		(drill 0.2032)
		(layers "F.Cu" "B.Cu")
		(net "M_E_MA<6>")
	)
	(via
		(at 255.35763 -94.718886)
		(size 0.508)
		(drill 0.254)
		(layers "F.Cu" "B.Cu")
		(net "M_E_MA<6>")
	)
	(segment
		(start 252.500384 -142.477236)
		(end 252.499876 -142.476982)
		(width 0.1651)
		(layer "B.Cu")
		(net "M_E_MA<6>")
	)
	(segment
		(start 252.499876 -142.476982)
		(end 252.499876 -141.187678)
		(width 0.1651)
		(layer "B.Cu")
		(net "M_E_MA<6>")
	)
	(segment
		(start 251.318014 -141.907768)
		(end 251.318014 -142.159228)
		(width 0.14224)
		(layer "In4.Cu")
		(net "M_E_MA<6>")
	)
	(segment
		(start 252.499876 -141.187678)
		(end 252.499876 -141.614144)
		(width 0.14224)
		(layer "In4.Cu")
		(net "M_E_MA<6>")
	)
	(segment
		(start 251.35586 -143.303498)
		(end 251.505466 -143.453104)
		(width 0.14224)
		(layer "In4.Cu")
		(net "M_E_MA<6>")
	)
	(segment
		(start 255.625092 -103.428292)
		(end 255.625092 -103.627428)
		(width 0.0889)
		(layer "In4.Cu")
		(net "M_E_MA<6>")
	)
	(segment
		(start 252.109986 -131.887214)
		(end 252.0696 -131.9276)
		(width 0.14224)
		(layer "In4.Cu")
		(net "M_E_MA<6>")
	)
	(segment
		(start 252.03404 -130.59156)
		(end 252.03404 -131.20624)
		(width 0.14224)
		(layer "In4.Cu")
		(net "M_E_MA<6>")
	)
	(segment
		(start 255.625092 -123.767088)
		(end 252.476 -126.91618)
		(width 0.14224)
		(layer "In4.Cu")
		(net "M_E_MA<6>")
	)
	(segment
		(start 252.868938 -142.726156)
		(end 252.70333 -142.891764)
		(width 0.14224)
		(layer "In4.Cu")
		(net "M_E_MA<6>")
	)
	(segment
		(start 252.499876 -143.608044)
		(end 252.499876 -143.972788)
		(width 0.14224)
		(layer "In4.Cu")
		(net "M_E_MA<6>")
	)
	(segment
		(start 251.318014 -142.159228)
		(end 251.48921 -142.330424)
		(width 0.14224)
		(layer "In4.Cu")
		(net "M_E_MA<6>")
	)
	(segment
		(start 252.499876 -141.614144)
		(end 252.344936 -141.769084)
		(width 0.14224)
		(layer "In4.Cu")
		(net "M_E_MA<6>")
	)
	(segment
		(start 254.850646 -98.377502)
		(end 254.654304 -98.72853)
		(width 0.0889)
		(layer "In4.Cu")
		(net "M_E_MA<6>")
	)
	(segment
		(start 255.372616 -96.109536)
		(end 255.33985 -96.109536)
		(width 0.0889)
		(layer "In4.Cu")
		(net "M_E_MA<6>")
	)
	(segment
		(start 255.338834 -103.142034)
		(end 255.625092 -103.428292)
		(width 0.0889)
		(layer "In4.Cu")
		(net "M_E_MA<6>")
	)
	(segment
		(start 252.476 -126.91618)
		(end 252.476 -128.946148)
		(width 0.14224)
		(layer "In4.Cu")
		(net "M_E_MA<6>")
	)
	(segment
		(start 252.03404 -131.20624)
		(end 252.109986 -131.282186)
		(width 0.14224)
		(layer "In4.Cu")
		(net "M_E_MA<6>")
	)
	(segment
		(start 252.044962 -129.870962)
		(end 252.109986 -129.935986)
		(width 0.14224)
		(layer "In4.Cu")
		(net "M_E_MA<6>")
	)
	(segment
		(start 255.70434 -95.509588)
		(end 255.709166 -95.518224)
		(width 0.0889)
		(layer "In4.Cu")
		(net "M_E_MA<6>")
	)
	(segment
		(start 252.109986 -131.282186)
		(end 252.109986 -131.887214)
		(width 0.14224)
		(layer "In4.Cu")
		(net "M_E_MA<6>")
	)
	(segment
		(start 254.654304 -98.72853)
		(end 254.654304 -100.222304)
		(width 0.0889)
		(layer "In4.Cu")
		(net "M_E_MA<6>")
	)
	(segment
		(start 252.088142 -140.196316)
		(end 252.499876 -140.60805)
		(width 0.14224)
		(layer "In4.Cu")
		(net "M_E_MA<6>")
	)
	(segment
		(start 255.625092 -103.627428)
		(end 255.625092 -123.767088)
		(width 0.14224)
		(layer "In4.Cu")
		(net "M_E_MA<6>")
	)
	(segment
		(start 255.35763 -94.718886)
		(end 255.659382 -95.413068)
		(width 0.0889)
		(layer "In4.Cu")
		(net "M_E_MA<6>")
	)
	(segment
		(start 252.344936 -143.453104)
		(end 252.499876 -143.608044)
		(width 0.14224)
		(layer "In4.Cu")
		(net "M_E_MA<6>")
	)
	(segment
		(start 252.044962 -129.377186)
		(end 252.044962 -129.870962)
		(width 0.14224)
		(layer "In4.Cu")
		(net "M_E_MA<6>")
	)
	(segment
		(start 252.088142 -136.111742)
		(end 252.088142 -140.196316)
		(width 0.14224)
		(layer "In4.Cu")
		(net "M_E_MA<6>")
	)
	(segment
		(start 252.868938 -142.474696)
		(end 252.868938 -142.726156)
		(width 0.14224)
		(layer "In4.Cu")
		(net "M_E_MA<6>")
	)
	(segment
		(start 252.0696 -131.9276)
		(end 252.0696 -134.7216)
		(width 0.14224)
		(layer "In4.Cu")
		(net "M_E_MA<6>")
	)
	(segment
		(start 252.70333 -142.891764)
		(end 251.516134 -142.891764)
		(width 0.14224)
		(layer "In4.Cu")
		(net "M_E_MA<6>")
	)
	(segment
		(start 255.338834 -100.906834)
		(end 255.338834 -103.142034)
		(width 0.0889)
		(layer "In4.Cu")
		(net "M_E_MA<6>")
	)
	(segment
		(start 251.516134 -142.891764)
		(end 251.35586 -143.052038)
		(width 0.14224)
		(layer "In4.Cu")
		(net "M_E_MA<6>")
	)
	(segment
		(start 251.48921 -142.330424)
		(end 252.724666 -142.330424)
		(width 0.14224)
		(layer "In4.Cu")
		(net "M_E_MA<6>")
	)
	(segment
		(start 252.0696 -134.7216)
		(end 252.1458 -134.7978)
		(width 0.14224)
		(layer "In4.Cu")
		(net "M_E_MA<6>")
	)
	(segment
		(start 255.69799 -95.49892)
		(end 255.70434 -95.509588)
		(width 0.0889)
		(layer "In4.Cu")
		(net "M_E_MA<6>")
	)
	(segment
		(start 254.850646 -97.386902)
		(end 254.84582 -97.395538)
		(width 0.0889)
		(layer "In4.Cu")
		(net "M_E_MA<6>")
	)
	(segment
		(start 254.654304 -100.222304)
		(end 255.338834 -100.906834)
		(width 0.0889)
		(layer "In4.Cu")
		(net "M_E_MA<6>")
	)
	(segment
		(start 252.109986 -129.935986)
		(end 252.109986 -130.515614)
		(width 0.14224)
		(layer "In4.Cu")
		(net "M_E_MA<6>")
	)
	(segment
		(start 251.456698 -141.769084)
		(end 251.318014 -141.907768)
		(width 0.14224)
		(layer "In4.Cu")
		(net "M_E_MA<6>")
	)
	(segment
		(start 252.001782 -136.025382)
		(end 252.088142 -136.111742)
		(width 0.14224)
		(layer "In4.Cu")
		(net "M_E_MA<6>")
	)
	(segment
		(start 252.499876 -140.60805)
		(end 252.499876 -141.187678)
		(width 0.14224)
		(layer "In4.Cu")
		(net "M_E_MA<6>")
	)
	(segment
		(start 254.84582 -97.395538)
		(end 254.83947 -97.406206)
		(width 0.0889)
		(layer "In4.Cu")
		(net "M_E_MA<6>")
	)
	(segment
		(start 252.476 -128.946148)
		(end 252.044962 -129.377186)
		(width 0.14224)
		(layer "In4.Cu")
		(net "M_E_MA<6>")
	)
	(segment
		(start 252.344936 -141.769084)
		(end 251.456698 -141.769084)
		(width 0.14224)
		(layer "In4.Cu")
		(net "M_E_MA<6>")
	)
	(segment
		(start 251.505466 -143.453104)
		(end 252.344936 -143.453104)
		(width 0.14224)
		(layer "In4.Cu")
		(net "M_E_MA<6>")
	)
	(segment
		(start 252.1458 -134.7978)
		(end 252.1458 -135.4074)
		(width 0.14224)
		(layer "In4.Cu")
		(net "M_E_MA<6>")
	)
	(segment
		(start 252.109986 -130.515614)
		(end 252.03404 -130.59156)
		(width 0.14224)
		(layer "In4.Cu")
		(net "M_E_MA<6>")
	)
	(segment
		(start 252.1458 -135.4074)
		(end 252.001782 -135.551418)
		(width 0.14224)
		(layer "In4.Cu")
		(net "M_E_MA<6>")
	)
	(segment
		(start 251.35586 -143.052038)
		(end 251.35586 -143.303498)
		(width 0.14224)
		(layer "In4.Cu")
		(net "M_E_MA<6>")
	)
	(segment
		(start 252.001782 -135.551418)
		(end 252.001782 -136.025382)
		(width 0.14224)
		(layer "In4.Cu")
		(net "M_E_MA<6>")
	)
	(segment
		(start 252.724666 -142.330424)
		(end 252.868938 -142.474696)
		(width 0.14224)
		(layer "In4.Cu")
		(net "M_E_MA<6>")
	)
	(arc
		(start 255.709166 -95.518224)
		(mid 255.705419 -95.90748)
		(end 255.372616 -96.109536)
		(width 0.0889)
		(layer "In4.Cu")
		(net "M_E_MA<6>")
	)
	(arc
		(start 254.84582 -96.995488)
		(mid 254.89929 -97.190551)
		(end 254.850646 -97.386902)
		(width 0.0889)
		(layer "In4.Cu")
		(net "M_E_MA<6>")
	)
	(arc
		(start 255.33985 -96.109536)
		(mid 254.841599 -96.412376)
		(end 254.84582 -96.995488)
		(width 0.0889)
		(layer "In4.Cu")
		(net "M_E_MA<6>")
	)
	(arc
		(start 254.84582 -97.986088)
		(mid 254.89929 -98.181151)
		(end 254.850646 -98.377502)
		(width 0.0889)
		(layer "In4.Cu")
		(net "M_E_MA<6>")
	)
	(arc
		(start 254.83947 -97.406206)
		(mid 254.766672 -97.696969)
		(end 254.84582 -97.986088)
		(width 0.0889)
		(layer "In4.Cu")
		(net "M_E_MA<6>")
	)
	(arc
		(start 255.659382 -95.413068)
		(mid 255.676972 -95.456765)
		(end 255.69799 -95.49892)
		(width 0.0889)
		(layer "In4.Cu")
		(net "M_E_MA<6>")
	)
	(segment
		(start 252.499876 -147.27174)
		(end 252.499876 -145.988278)
		(width 0.1651)
		(layer "F.Cu")
		(net "M_E_MA<5>")
	)
	(segment
		(start 252.500384 -147.27174)
		(end 252.499876 -147.27174)
		(width 0.1651)
		(layer "F.Cu")
		(net "M_E_MA<5>")
	)
	(segment
		(start 256.78765 -95.21444)
		(end 256.21615 -95.21444)
		(width 0.1016)
		(layer "F.Cu")
		(net "M_E_MA<5>")
	)
	(via
		(at 256.21615 -95.21444)
		(size 0.508)
		(drill 0.254)
		(layers "F.Cu" "B.Cu")
		(net "M_E_MA<5>")
	)
	(via
		(at 252.499876 -139.172188)
		(size 0.4572)
		(drill 0.2032)
		(layers "F.Cu" "B.Cu")
		(net "M_E_MA<5>")
	)
	(via
		(at 252.499876 -145.988278)
		(size 0.4572)
		(drill 0.2032)
		(layers "F.Cu" "B.Cu")
		(net "M_E_MA<5>")
	)
	(segment
		(start 252.499876 -137.877296)
		(end 252.500384 -137.877296)
		(width 0.1651)
		(layer "B.Cu")
		(net "M_E_MA<5>")
	)
	(segment
		(start 252.499876 -139.172188)
		(end 252.499876 -137.877296)
		(width 0.1651)
		(layer "B.Cu")
		(net "M_E_MA<5>")
	)
	(segment
		(start 252.910594 -140.129514)
		(end 252.910594 -141.53388)
		(width 0.14224)
		(layer "In4.Cu")
		(net "M_E_MA<5>")
	)
	(segment
		(start 254.882142 -126.22149)
		(end 254.882142 -126.509018)
		(width 0.14224)
		(layer "In4.Cu")
		(net "M_E_MA<5>")
	)
	(segment
		(start 252.499876 -139.172188)
		(end 252.499876 -139.718796)
		(width 0.14224)
		(layer "In4.Cu")
		(net "M_E_MA<5>")
	)
	(segment
		(start 253.010416 -131.17068)
		(end 252.77699 -131.404106)
		(width 0.14224)
		(layer "In4.Cu")
		(net "M_E_MA<5>")
	)
	(segment
		(start 252.732032 -129.990088)
		(end 252.732032 -130.405632)
		(width 0.14224)
		(layer "In4.Cu")
		(net "M_E_MA<5>")
	)
	(segment
		(start 254.014986 -126.503938)
		(end 253.73457 -126.503938)
		(width 0.14224)
		(layer "In4.Cu")
		(net "M_E_MA<5>")
	)
	(segment
		(start 255.01092 -98.481388)
		(end 254.957834 -98.576384)
		(width 0.0889)
		(layer "In4.Cu")
		(net "M_E_MA<5>")
	)
	(segment
		(start 255.122426 -125.31217)
		(end 254.809498 -125.31217)
		(width 0.14224)
		(layer "In4.Cu")
		(net "M_E_MA<5>")
	)
	(segment
		(start 252.9332 -135.4328)
		(end 252.9332 -138.1252)
		(width 0.14224)
		(layer "In4.Cu")
		(net "M_E_MA<5>")
	)
	(segment
		(start 254.522224 -125.861572)
		(end 254.882142 -126.22149)
		(width 0.14224)
		(layer "In4.Cu")
		(net "M_E_MA<5>")
	)
	(segment
		(start 256.133092 -103.555292)
		(end 256.133092 -103.780844)
		(width 0.0889)
		(layer "In4.Cu")
		(net "M_E_MA<5>")
	)
	(segment
		(start 255.529334 -102.951534)
		(end 256.133092 -103.555292)
		(width 0.0889)
		(layer "In4.Cu")
		(net "M_E_MA<5>")
	)
	(segment
		(start 252.499876 -138.558524)
		(end 252.499876 -139.172188)
		(width 0.14224)
		(layer "In4.Cu")
		(net "M_E_MA<5>")
	)
	(segment
		(start 253.686818 -127.325374)
		(end 253.686818 -127.704342)
		(width 0.14224)
		(layer "In4.Cu")
		(net "M_E_MA<5>")
	)
	(segment
		(start 252.77699 -132.119878)
		(end 252.914404 -132.257292)
		(width 0.14224)
		(layer "In4.Cu")
		(net "M_E_MA<5>")
	)
	(segment
		(start 252.910594 -144.463262)
		(end 252.499876 -144.87398)
		(width 0.14224)
		(layer "In4.Cu")
		(net "M_E_MA<5>")
	)
	(segment
		(start 255.01092 -97.490788)
		(end 255.006094 -97.499424)
		(width 0.0889)
		(layer "In4.Cu")
		(net "M_E_MA<5>")
	)
	(segment
		(start 253.303278 -141.926564)
		(end 253.303278 -143.198342)
		(width 0.14224)
		(layer "In4.Cu")
		(net "M_E_MA<5>")
	)
	(segment
		(start 254.957834 -100.144834)
		(end 255.529334 -100.716334)
		(width 0.0889)
		(layer "In4.Cu")
		(net "M_E_MA<5>")
	)
	(segment
		(start 256.21615 -95.21444)
		(end 255.886204 -95.976186)
		(width 0.0889)
		(layer "In4.Cu")
		(net "M_E_MA<5>")
	)
	(segment
		(start 256.133092 -125.286008)
		(end 255.788922 -125.630178)
		(width 0.14224)
		(layer "In4.Cu")
		(net "M_E_MA<5>")
	)
	(segment
		(start 254.809498 -125.31217)
		(end 254.522224 -125.599444)
		(width 0.14224)
		(layer "In4.Cu")
		(net "M_E_MA<5>")
	)
	(segment
		(start 252.984 -128.40716)
		(end 252.984 -129.73812)
		(width 0.14224)
		(layer "In4.Cu")
		(net "M_E_MA<5>")
	)
	(segment
		(start 255.01727 -97.48012)
		(end 255.01092 -97.490788)
		(width 0.0889)
		(layer "In4.Cu")
		(net "M_E_MA<5>")
	)
	(segment
		(start 252.9332 -138.1252)
		(end 252.499876 -138.558524)
		(width 0.14224)
		(layer "In4.Cu")
		(net "M_E_MA<5>")
	)
	(segment
		(start 253.303278 -143.198342)
		(end 252.910594 -143.591026)
		(width 0.14224)
		(layer "In4.Cu")
		(net "M_E_MA<5>")
	)
	(segment
		(start 253.686818 -127.704342)
		(end 252.984 -128.40716)
		(width 0.14224)
		(layer "In4.Cu")
		(net "M_E_MA<5>")
	)
	(segment
		(start 254.30734 -126.796292)
		(end 254.014986 -126.503938)
		(width 0.14224)
		(layer "In4.Cu")
		(net "M_E_MA<5>")
	)
	(segment
		(start 252.910594 -143.591026)
		(end 252.910594 -144.463262)
		(width 0.14224)
		(layer "In4.Cu")
		(net "M_E_MA<5>")
	)
	(segment
		(start 254.522224 -125.599444)
		(end 254.522224 -125.861572)
		(width 0.14224)
		(layer "In4.Cu")
		(net "M_E_MA<5>")
	)
	(segment
		(start 253.73457 -126.503938)
		(end 253.447296 -126.791212)
		(width 0.14224)
		(layer "In4.Cu")
		(net "M_E_MA<5>")
	)
	(segment
		(start 255.37922 -96.300036)
		(end 255.346454 -96.300036)
		(width 0.0889)
		(layer "In4.Cu")
		(net "M_E_MA<5>")
	)
	(segment
		(start 252.499876 -144.87398)
		(end 252.499876 -145.988278)
		(width 0.14224)
		(layer "In4.Cu")
		(net "M_E_MA<5>")
	)
	(segment
		(start 253.010416 -130.684016)
		(end 253.010416 -131.17068)
		(width 0.14224)
		(layer "In4.Cu")
		(net "M_E_MA<5>")
	)
	(segment
		(start 252.910594 -141.53388)
		(end 253.303278 -141.926564)
		(width 0.14224)
		(layer "In4.Cu")
		(net "M_E_MA<5>")
	)
	(segment
		(start 252.984 -129.73812)
		(end 252.732032 -129.990088)
		(width 0.14224)
		(layer "In4.Cu")
		(net "M_E_MA<5>")
	)
	(segment
		(start 255.440434 -125.630178)
		(end 255.122426 -125.31217)
		(width 0.14224)
		(layer "In4.Cu")
		(net "M_E_MA<5>")
	)
	(segment
		(start 252.499876 -139.718796)
		(end 252.910594 -140.129514)
		(width 0.14224)
		(layer "In4.Cu")
		(net "M_E_MA<5>")
	)
	(segment
		(start 256.133092 -103.780844)
		(end 256.133092 -125.286008)
		(width 0.14224)
		(layer "In4.Cu")
		(net "M_E_MA<5>")
	)
	(segment
		(start 252.732032 -130.405632)
		(end 253.010416 -130.684016)
		(width 0.14224)
		(layer "In4.Cu")
		(net "M_E_MA<5>")
	)
	(segment
		(start 255.886204 -95.976186)
		(end 255.86944 -96.004888)
		(width 0.0889)
		(layer "In4.Cu")
		(net "M_E_MA<5>")
	)
	(segment
		(start 253.447296 -127.085852)
		(end 253.686818 -127.325374)
		(width 0.14224)
		(layer "In4.Cu")
		(net "M_E_MA<5>")
	)
	(segment
		(start 254.882142 -126.509018)
		(end 254.594868 -126.796292)
		(width 0.14224)
		(layer "In4.Cu")
		(net "M_E_MA<5>")
	)
	(segment
		(start 252.914404 -132.257292)
		(end 252.914404 -134.714996)
		(width 0.14224)
		(layer "In4.Cu")
		(net "M_E_MA<5>")
	)
	(segment
		(start 255.529334 -100.716334)
		(end 255.529334 -102.951534)
		(width 0.0889)
		(layer "In4.Cu")
		(net "M_E_MA<5>")
	)
	(segment
		(start 252.857 -135.3566)
		(end 252.9332 -135.4328)
		(width 0.14224)
		(layer "In4.Cu")
		(net "M_E_MA<5>")
	)
	(segment
		(start 252.857 -134.7724)
		(end 252.857 -135.3566)
		(width 0.14224)
		(layer "In4.Cu")
		(net "M_E_MA<5>")
	)
	(segment
		(start 253.447296 -126.791212)
		(end 253.447296 -127.085852)
		(width 0.14224)
		(layer "In4.Cu")
		(net "M_E_MA<5>")
	)
	(segment
		(start 254.957834 -98.576384)
		(end 254.957834 -100.144834)
		(width 0.0889)
		(layer "In4.Cu")
		(net "M_E_MA<5>")
	)
	(segment
		(start 254.594868 -126.796292)
		(end 254.30734 -126.796292)
		(width 0.14224)
		(layer "In4.Cu")
		(net "M_E_MA<5>")
	)
	(segment
		(start 255.788922 -125.630178)
		(end 255.440434 -125.630178)
		(width 0.14224)
		(layer "In4.Cu")
		(net "M_E_MA<5>")
	)
	(segment
		(start 252.77699 -131.404106)
		(end 252.77699 -132.119878)
		(width 0.14224)
		(layer "In4.Cu")
		(net "M_E_MA<5>")
	)
	(segment
		(start 255.01727 -98.47072)
		(end 255.01092 -98.481388)
		(width 0.0889)
		(layer "In4.Cu")
		(net "M_E_MA<5>")
	)
	(segment
		(start 252.914404 -134.714996)
		(end 252.857 -134.7724)
		(width 0.14224)
		(layer "In4.Cu")
		(net "M_E_MA<5>")
	)
	(arc
		(start 255.01092 -96.900238)
		(mid 255.090142 -97.189356)
		(end 255.01727 -97.48012)
		(width 0.0889)
		(layer "In4.Cu")
		(net "M_E_MA<5>")
	)
	(arc
		(start 255.86944 -96.004888)
		(mid 255.662436 -96.215752)
		(end 255.37922 -96.300036)
		(width 0.0889)
		(layer "In4.Cu")
		(net "M_E_MA<5>")
	)
	(arc
		(start 255.006094 -97.499424)
		(mid 254.957339 -97.695776)
		(end 255.01092 -97.890838)
		(width 0.0889)
		(layer "In4.Cu")
		(net "M_E_MA<5>")
	)
	(arc
		(start 255.01092 -97.890838)
		(mid 255.090142 -98.179956)
		(end 255.01727 -98.47072)
		(width 0.0889)
		(layer "In4.Cu")
		(net "M_E_MA<5>")
	)
	(arc
		(start 255.346454 -96.300036)
		(mid 255.008285 -96.504834)
		(end 255.01092 -96.900238)
		(width 0.0889)
		(layer "In4.Cu")
		(net "M_E_MA<5>")
	)
	(segment
		(start 253.350014 -147.27174)
		(end 253.350014 -145.988278)
		(width 0.1651)
		(layer "F.Cu")
		(net "M_E_MA<4>")
	)
	(segment
		(start 253.350522 -147.27174)
		(end 253.350014 -147.27174)
		(width 0.1651)
		(layer "F.Cu")
		(net "M_E_MA<4>")
	)
	(segment
		(start 255.92913 -96.700086)
		(end 255.35763 -96.700086)
		(width 0.1016)
		(layer "F.Cu")
		(net "M_E_MA<4>")
	)
	(via
		(at 253.350014 -139.172188)
		(size 0.4572)
		(drill 0.2032)
		(layers "F.Cu" "B.Cu")
		(net "M_E_MA<4>")
	)
	(via
		(at 255.35763 -96.700086)
		(size 0.508)
		(drill 0.254)
		(layers "F.Cu" "B.Cu")
		(net "M_E_MA<4>")
	)
	(via
		(at 253.350014 -145.988278)
		(size 0.4572)
		(drill 0.2032)
		(layers "F.Cu" "B.Cu")
		(net "M_E_MA<4>")
	)
	(segment
		(start 253.350014 -137.877296)
		(end 253.350014 -139.172188)
		(width 0.1651)
		(layer "B.Cu")
		(net "M_E_MA<4>")
	)
	(segment
		(start 253.350522 -137.877296)
		(end 253.350014 -137.877296)
		(width 0.1651)
		(layer "B.Cu")
		(net "M_E_MA<4>")
	)
	(segment
		(start 253.5682 -140.068554)
		(end 253.5682 -140.6652)
		(width 0.14224)
		(layer "In4.Cu")
		(net "M_E_MA<4>")
	)
	(segment
		(start 253.492 -128.61798)
		(end 253.492 -129.6162)
		(width 0.14224)
		(layer "In4.Cu")
		(net "M_E_MA<4>")
	)
	(segment
		(start 256.343404 -103.206804)
		(end 256.641092 -103.504492)
		(width 0.0889)
		(layer "In4.Cu")
		(net "M_E_MA<4>")
	)
	(segment
		(start 253.757684 -138.037316)
		(end 253.350014 -138.444986)
		(width 0.14224)
		(layer "In4.Cu")
		(net "M_E_MA<4>")
	)
	(segment
		(start 253.8476 -131.2164)
		(end 253.8476 -131.826)
		(width 0.14224)
		(layer "In4.Cu")
		(net "M_E_MA<4>")
	)
	(segment
		(start 253.787656 -135.391144)
		(end 253.7206 -135.4582)
		(width 0.14224)
		(layer "In4.Cu")
		(net "M_E_MA<4>")
	)
	(segment
		(start 253.350014 -139.172188)
		(end 253.350014 -139.850368)
		(width 0.14224)
		(layer "In4.Cu")
		(net "M_E_MA<4>")
	)
	(segment
		(start 253.6952 -130.6322)
		(end 253.6952 -131.064)
		(width 0.14224)
		(layer "In4.Cu")
		(net "M_E_MA<4>")
	)
	(segment
		(start 253.492 -129.6162)
		(end 253.8476 -129.9718)
		(width 0.14224)
		(layer "In4.Cu")
		(net "M_E_MA<4>")
	)
	(segment
		(start 253.757684 -136.130284)
		(end 253.757684 -138.037316)
		(width 0.14224)
		(layer "In4.Cu")
		(net "M_E_MA<4>")
	)
	(segment
		(start 253.350014 -145.227802)
		(end 253.350014 -145.988278)
		(width 0.14224)
		(layer "In4.Cu")
		(net "M_E_MA<4>")
	)
	(segment
		(start 256.641092 -103.72979)
		(end 256.641092 -125.468888)
		(width 0.14224)
		(layer "In4.Cu")
		(net "M_E_MA<4>")
	)
	(segment
		(start 255.687068 -97.46107)
		(end 255.709166 -97.499424)
		(width 0.0889)
		(layer "In4.Cu")
		(net "M_E_MA<4>")
	)
	(segment
		(start 253.787656 -140.884656)
		(end 253.787656 -144.79016)
		(width 0.14224)
		(layer "In4.Cu")
		(net "M_E_MA<4>")
	)
	(segment
		(start 253.6952 -131.064)
		(end 253.8476 -131.2164)
		(width 0.14224)
		(layer "In4.Cu")
		(net "M_E_MA<4>")
	)
	(segment
		(start 253.7206 -135.4582)
		(end 253.7206 -136.0932)
		(width 0.14224)
		(layer "In4.Cu")
		(net "M_E_MA<4>")
	)
	(segment
		(start 253.350014 -138.444986)
		(end 253.350014 -139.172188)
		(width 0.14224)
		(layer "In4.Cu")
		(net "M_E_MA<4>")
	)
	(segment
		(start 256.641092 -125.468888)
		(end 253.492 -128.61798)
		(width 0.14224)
		(layer "In4.Cu")
		(net "M_E_MA<4>")
	)
	(segment
		(start 253.5682 -140.6652)
		(end 253.787656 -140.884656)
		(width 0.14224)
		(layer "In4.Cu")
		(net "M_E_MA<4>")
	)
	(segment
		(start 253.787656 -131.885944)
		(end 253.787656 -135.391144)
		(width 0.14224)
		(layer "In4.Cu")
		(net "M_E_MA<4>")
	)
	(segment
		(start 253.787656 -144.79016)
		(end 253.350014 -145.227802)
		(width 0.14224)
		(layer "In4.Cu")
		(net "M_E_MA<4>")
	)
	(segment
		(start 253.7206 -136.0932)
		(end 253.757684 -136.130284)
		(width 0.14224)
		(layer "In4.Cu")
		(net "M_E_MA<4>")
	)
	(segment
		(start 256.343404 -101.454204)
		(end 256.343404 -103.206804)
		(width 0.0889)
		(layer "In4.Cu")
		(net "M_E_MA<4>")
	)
	(segment
		(start 253.8476 -130.4798)
		(end 253.6952 -130.6322)
		(width 0.14224)
		(layer "In4.Cu")
		(net "M_E_MA<4>")
	)
	(segment
		(start 253.350014 -139.850368)
		(end 253.5682 -140.068554)
		(width 0.14224)
		(layer "In4.Cu")
		(net "M_E_MA<4>")
	)
	(segment
		(start 255.8288 -100.9396)
		(end 256.343404 -101.454204)
		(width 0.0889)
		(layer "In4.Cu")
		(net "M_E_MA<4>")
	)
	(segment
		(start 253.8476 -129.9718)
		(end 253.8476 -130.4798)
		(width 0.14224)
		(layer "In4.Cu")
		(net "M_E_MA<4>")
	)
	(segment
		(start 256.641092 -103.504492)
		(end 256.641092 -103.72979)
		(width 0.0889)
		(layer "In4.Cu")
		(net "M_E_MA<4>")
	)
	(segment
		(start 255.8288 -98.7298)
		(end 255.8288 -100.9396)
		(width 0.0889)
		(layer "In4.Cu")
		(net "M_E_MA<4>")
	)
	(segment
		(start 255.35763 -96.700086)
		(end 255.687068 -97.46107)
		(width 0.0889)
		(layer "In4.Cu")
		(net "M_E_MA<4>")
	)
	(segment
		(start 253.8476 -131.826)
		(end 253.787656 -131.885944)
		(width 0.14224)
		(layer "In4.Cu")
		(net "M_E_MA<4>")
	)
	(arc
		(start 255.70434 -97.890838)
		(mid 255.629342 -98.256016)
		(end 255.787906 -98.593402)
		(width 0.0889)
		(layer "In4.Cu")
		(net "M_E_MA<4>")
	)
	(arc
		(start 255.709166 -97.499424)
		(mid 255.757921 -97.695776)
		(end 255.70434 -97.890838)
		(width 0.0889)
		(layer "In4.Cu")
		(net "M_E_MA<4>")
	)
	(arc
		(start 255.787906 -98.593402)
		(mid 255.824571 -98.656724)
		(end 255.8288 -98.7298)
		(width 0.0889)
		(layer "In4.Cu")
		(net "M_E_MA<4>")
	)
	(segment
		(start 254.199898 -142.677642)
		(end 254.199898 -143.972788)
		(width 0.1651)
		(layer "F.Cu")
		(net "M_E_MA<3>")
	)
	(segment
		(start 254.200406 -142.6718)
		(end 254.199898 -142.677642)
		(width 0.1651)
		(layer "F.Cu")
		(net "M_E_MA<3>")
	)
	(segment
		(start 256.78765 -96.20504)
		(end 256.21615 -96.20504)
		(width 0.1016)
		(layer "F.Cu")
		(net "M_E_MA<3>")
	)
	(via
		(at 254.199898 -141.187678)
		(size 0.4572)
		(drill 0.2032)
		(layers "F.Cu" "B.Cu")
		(net "M_E_MA<3>")
	)
	(via
		(at 254.199898 -143.972788)
		(size 0.4572)
		(drill 0.2032)
		(layers "F.Cu" "B.Cu")
		(net "M_E_MA<3>")
	)
	(via
		(at 256.21615 -96.20504)
		(size 0.508)
		(drill 0.254)
		(layers "F.Cu" "B.Cu")
		(net "M_E_MA<3>")
	)
	(segment
		(start 254.200406 -142.477236)
		(end 254.199898 -142.476982)
		(width 0.1651)
		(layer "B.Cu")
		(net "M_E_MA<3>")
	)
	(segment
		(start 254.199898 -142.476982)
		(end 254.199898 -141.187678)
		(width 0.1651)
		(layer "B.Cu")
		(net "M_E_MA<3>")
	)
	(segment
		(start 254.5842 -132.0292)
		(end 254.638302 -132.083302)
		(width 0.14224)
		(layer "In4.Cu")
		(net "M_E_MA<3>")
	)
	(segment
		(start 254.046482 -140.492226)
		(end 254.199898 -140.645642)
		(width 0.14224)
		(layer "In4.Cu")
		(net "M_E_MA<3>")
	)
	(segment
		(start 255.886204 -96.966786)
		(end 255.86944 -96.995488)
		(width 0.0889)
		(layer "In4.Cu")
		(net "M_E_MA<3>")
	)
	(segment
		(start 255.864614 -97.386902)
		(end 255.86944 -97.395538)
		(width 0.0889)
		(layer "In4.Cu")
		(net "M_E_MA<3>")
	)
	(segment
		(start 256.21615 -96.20504)
		(end 255.886204 -96.966786)
		(width 0.0889)
		(layer "In4.Cu")
		(net "M_E_MA<3>")
	)
	(segment
		(start 256.0828 -98.7044)
		(end 256.0828 -100.6602)
		(width 0.0889)
		(layer "In4.Cu")
		(net "M_E_MA<3>")
	)
	(segment
		(start 256.648204 -102.953058)
		(end 257.149092 -103.453946)
		(width 0.0889)
		(layer "In4.Cu")
		(net "M_E_MA<3>")
	)
	(segment
		(start 253.761748 -138.769852)
		(end 253.761748 -139.512548)
		(width 0.14224)
		(layer "In4.Cu")
		(net "M_E_MA<3>")
	)
	(segment
		(start 254.7112 -128.117346)
		(end 254.7112 -129.8194)
		(width 0.14224)
		(layer "In4.Cu")
		(net "M_E_MA<3>")
	)
	(segment
		(start 254.451866 -130.398266)
		(end 254.692658 -130.639058)
		(width 0.14224)
		(layer "In4.Cu")
		(net "M_E_MA<3>")
	)
	(segment
		(start 256.648204 -101.225604)
		(end 256.648204 -102.953058)
		(width 0.0889)
		(layer "In4.Cu")
		(net "M_E_MA<3>")
	)
	(segment
		(start 254.199898 -140.645642)
		(end 254.199898 -141.187678)
		(width 0.14224)
		(layer "In4.Cu")
		(net "M_E_MA<3>")
	)
	(segment
		(start 257.149092 -103.716074)
		(end 257.149092 -125.679454)
		(width 0.14224)
		(layer "In4.Cu")
		(net "M_E_MA<3>")
	)
	(segment
		(start 254.7112 -129.8194)
		(end 254.451866 -130.078734)
		(width 0.14224)
		(layer "In4.Cu")
		(net "M_E_MA<3>")
	)
	(segment
		(start 254.3302 -138.2014)
		(end 253.761748 -138.769852)
		(width 0.14224)
		(layer "In4.Cu")
		(net "M_E_MA<3>")
	)
	(segment
		(start 256.0828 -100.6602)
		(end 256.648204 -101.225604)
		(width 0.0889)
		(layer "In4.Cu")
		(net "M_E_MA<3>")
	)
	(segment
		(start 254.692658 -130.639058)
		(end 254.692658 -131.107942)
		(width 0.14224)
		(layer "In4.Cu")
		(net "M_E_MA<3>")
	)
	(segment
		(start 254.451866 -130.078734)
		(end 254.451866 -130.398266)
		(width 0.14224)
		(layer "In4.Cu")
		(net "M_E_MA<3>")
	)
	(segment
		(start 254.199898 -141.187678)
		(end 254.199898 -143.972788)
		(width 0.14224)
		(layer "In4.Cu")
		(net "M_E_MA<3>")
	)
	(segment
		(start 254.638302 -136.992106)
		(end 254.3302 -137.300208)
		(width 0.14224)
		(layer "In4.Cu")
		(net "M_E_MA<3>")
	)
	(segment
		(start 254.3302 -137.300208)
		(end 254.3302 -138.2014)
		(width 0.14224)
		(layer "In4.Cu")
		(net "M_E_MA<3>")
	)
	(segment
		(start 257.149092 -125.679454)
		(end 254.7112 -128.117346)
		(width 0.14224)
		(layer "In4.Cu")
		(net "M_E_MA<3>")
	)
	(segment
		(start 254.5842 -131.2164)
		(end 254.5842 -132.0292)
		(width 0.14224)
		(layer "In4.Cu")
		(net "M_E_MA<3>")
	)
	(segment
		(start 255.86944 -97.395538)
		(end 255.87579 -97.406206)
		(width 0.0889)
		(layer "In4.Cu")
		(net "M_E_MA<3>")
	)
	(segment
		(start 257.149092 -103.453946)
		(end 257.149092 -103.716074)
		(width 0.0889)
		(layer "In4.Cu")
		(net "M_E_MA<3>")
	)
	(segment
		(start 254.692658 -131.107942)
		(end 254.5842 -131.2164)
		(width 0.14224)
		(layer "In4.Cu")
		(net "M_E_MA<3>")
	)
	(segment
		(start 254.638302 -132.083302)
		(end 254.638302 -136.992106)
		(width 0.14224)
		(layer "In4.Cu")
		(net "M_E_MA<3>")
	)
	(segment
		(start 254.046482 -139.797282)
		(end 254.046482 -140.492226)
		(width 0.14224)
		(layer "In4.Cu")
		(net "M_E_MA<3>")
	)
	(segment
		(start 253.761748 -139.512548)
		(end 254.046482 -139.797282)
		(width 0.14224)
		(layer "In4.Cu")
		(net "M_E_MA<3>")
	)
	(arc
		(start 255.87579 -97.406206)
		(mid 255.948588 -97.696969)
		(end 255.86944 -97.986088)
		(width 0.0889)
		(layer "In4.Cu")
		(net "M_E_MA<3>")
	)
	(arc
		(start 255.86944 -97.986088)
		(mid 255.820624 -98.248108)
		(end 255.947164 -98.482658)
		(width 0.0889)
		(layer "In4.Cu")
		(net "M_E_MA<3>")
	)
	(arc
		(start 255.86944 -96.995488)
		(mid 255.81597 -97.190551)
		(end 255.864614 -97.386902)
		(width 0.0889)
		(layer "In4.Cu")
		(net "M_E_MA<3>")
	)
	(arc
		(start 255.947164 -98.482658)
		(mid 256.030892 -98.583798)
		(end 256.0828 -98.7044)
		(width 0.0889)
		(layer "In4.Cu")
		(net "M_E_MA<3>")
	)
	(segment
		(start 257.64617 -97.690686)
		(end 257.07467 -97.690686)
		(width 0.1016)
		(layer "F.Cu")
		(net "M_E_MA<2>")
	)
	(segment
		(start 255.049782 -147.27174)
		(end 255.049782 -146.013932)
		(width 0.1651)
		(layer "F.Cu")
		(net "M_E_MA<2>")
	)
	(segment
		(start 255.049782 -146.013932)
		(end 255.050036 -146.013678)
		(width 0.1651)
		(layer "F.Cu")
		(net "M_E_MA<2>")
	)
	(segment
		(start 255.05029 -147.27174)
		(end 255.049782 -147.27174)
		(width 0.1651)
		(layer "F.Cu")
		(net "M_E_MA<2>")
	)
	(segment
		(start 255.050036 -146.013678)
		(end 255.050036 -145.988278)
		(width 0.1651)
		(layer "F.Cu")
		(net "M_E_MA<2>")
	)
	(via
		(at 255.050036 -145.988278)
		(size 0.4572)
		(drill 0.2032)
		(layers "F.Cu" "B.Cu")
		(net "M_E_MA<2>")
	)
	(via
		(at 255.049782 -139.172188)
		(size 0.4572)
		(drill 0.2032)
		(layers "F.Cu" "B.Cu")
		(net "M_E_MA<2>")
	)
	(via
		(at 257.07467 -97.690686)
		(size 0.508)
		(drill 0.254)
		(layers "F.Cu" "B.Cu")
		(net "M_E_MA<2>")
	)
	(segment
		(start 255.049782 -137.877296)
		(end 255.049782 -139.172188)
		(width 0.1651)
		(layer "B.Cu")
		(net "M_E_MA<2>")
	)
	(segment
		(start 255.05029 -137.877296)
		(end 255.049782 -137.877296)
		(width 0.1651)
		(layer "B.Cu")
		(net "M_E_MA<2>")
	)
	(segment
		(start 255.366266 -140.166598)
		(end 255.366266 -140.859002)
		(width 0.14224)
		(layer "In4.Cu")
		(net "M_E_MA<2>")
	)
	(segment
		(start 255.476502 -144.359122)
		(end 255.050036 -144.785588)
		(width 0.14224)
		(layer "In4.Cu")
		(net "M_E_MA<2>")
	)
	(segment
		(start 255.740408 -130.705606)
		(end 255.740408 -131.027932)
		(width 0.14224)
		(layer "In4.Cu")
		(net "M_E_MA<2>")
	)
	(segment
		(start 258.165092 -127.028956)
		(end 257.770376 -127.423672)
		(width 0.14224)
		(layer "In4.Cu")
		(net "M_E_MA<2>")
	)
	(segment
		(start 255.476502 -140.969238)
		(end 255.476502 -144.359122)
		(width 0.14224)
		(layer "In4.Cu")
		(net "M_E_MA<2>")
	)
	(segment
		(start 255.696212 -128.972056)
		(end 255.696212 -129.712212)
		(width 0.14224)
		(layer "In4.Cu")
		(net "M_E_MA<2>")
	)
	(segment
		(start 256.1844 -137.177272)
		(end 256.1844 -137.763758)
		(width 0.14224)
		(layer "In4.Cu")
		(net "M_E_MA<2>")
	)
	(segment
		(start 255.049782 -138.898376)
		(end 255.049782 -139.172188)
		(width 0.14224)
		(layer "In4.Cu")
		(net "M_E_MA<2>")
	)
	(segment
		(start 256.3876 -134.112)
		(end 256.3876 -136.974072)
		(width 0.14224)
		(layer "In4.Cu")
		(net "M_E_MA<2>")
	)
	(segment
		(start 255.050036 -139.850368)
		(end 255.366266 -140.166598)
		(width 0.14224)
		(layer "In4.Cu")
		(net "M_E_MA<2>")
	)
	(segment
		(start 255.861058 -130.584956)
		(end 255.740408 -130.705606)
		(width 0.14224)
		(layer "In4.Cu")
		(net "M_E_MA<2>")
	)
	(segment
		(start 256.1082 -131.395724)
		(end 256.1082 -133.8326)
		(width 0.14224)
		(layer "In4.Cu")
		(net "M_E_MA<2>")
	)
	(segment
		(start 255.049782 -139.172188)
		(end 255.050036 -139.172442)
		(width 0.14224)
		(layer "In4.Cu")
		(net "M_E_MA<2>")
	)
	(segment
		(start 257.257804 -100.844604)
		(end 257.257804 -102.673658)
		(width 0.0889)
		(layer "In4.Cu")
		(net "M_E_MA<2>")
	)
	(segment
		(start 257.770376 -128.505966)
		(end 257.483102 -128.79324)
		(width 0.14224)
		(layer "In4.Cu")
		(net "M_E_MA<2>")
	)
	(segment
		(start 257.257804 -102.673658)
		(end 258.165092 -103.580946)
		(width 0.0889)
		(layer "In4.Cu")
		(net "M_E_MA<2>")
	)
	(segment
		(start 258.165092 -103.808276)
		(end 258.165092 -127.028956)
		(width 0.14224)
		(layer "In4.Cu")
		(net "M_E_MA<2>")
	)
	(segment
		(start 256.1844 -137.763758)
		(end 255.049782 -138.898376)
		(width 0.14224)
		(layer "In4.Cu")
		(net "M_E_MA<2>")
	)
	(segment
		(start 255.740408 -131.027932)
		(end 256.1082 -131.395724)
		(width 0.14224)
		(layer "In4.Cu")
		(net "M_E_MA<2>")
	)
	(segment
		(start 257.07467 -97.690686)
		(end 256.673604 -98.56216)
		(width 0.0889)
		(layer "In4.Cu")
		(net "M_E_MA<2>")
	)
	(segment
		(start 256.3876 -136.974072)
		(end 256.1844 -137.177272)
		(width 0.14224)
		(layer "In4.Cu")
		(net "M_E_MA<2>")
	)
	(segment
		(start 255.050036 -144.785588)
		(end 255.050036 -145.988278)
		(width 0.14224)
		(layer "In4.Cu")
		(net "M_E_MA<2>")
	)
	(segment
		(start 258.165092 -103.580946)
		(end 258.165092 -103.808276)
		(width 0.0889)
		(layer "In4.Cu")
		(net "M_E_MA<2>")
	)
	(segment
		(start 256.673604 -98.56216)
		(end 256.673604 -100.260404)
		(width 0.0889)
		(layer "In4.Cu")
		(net "M_E_MA<2>")
	)
	(segment
		(start 255.875028 -128.79324)
		(end 255.696212 -128.972056)
		(width 0.14224)
		(layer "In4.Cu")
		(net "M_E_MA<2>")
	)
	(segment
		(start 256.1082 -133.8326)
		(end 256.3876 -134.112)
		(width 0.14224)
		(layer "In4.Cu")
		(net "M_E_MA<2>")
	)
	(segment
		(start 255.366266 -140.859002)
		(end 255.476502 -140.969238)
		(width 0.14224)
		(layer "In4.Cu")
		(net "M_E_MA<2>")
	)
	(segment
		(start 255.696212 -129.712212)
		(end 255.861058 -129.877058)
		(width 0.14224)
		(layer "In4.Cu")
		(net "M_E_MA<2>")
	)
	(segment
		(start 255.050036 -139.172442)
		(end 255.050036 -139.850368)
		(width 0.14224)
		(layer "In4.Cu")
		(net "M_E_MA<2>")
	)
	(segment
		(start 255.861058 -129.877058)
		(end 255.861058 -130.584956)
		(width 0.14224)
		(layer "In4.Cu")
		(net "M_E_MA<2>")
	)
	(segment
		(start 257.770376 -127.423672)
		(end 257.770376 -128.505966)
		(width 0.14224)
		(layer "In4.Cu")
		(net "M_E_MA<2>")
	)
	(segment
		(start 257.483102 -128.79324)
		(end 255.875028 -128.79324)
		(width 0.14224)
		(layer "In4.Cu")
		(net "M_E_MA<2>")
	)
	(segment
		(start 256.673604 -100.260404)
		(end 257.257804 -100.844604)
		(width 0.0889)
		(layer "In4.Cu")
		(net "M_E_MA<2>")
	)
	(segment
		(start 255.049782 -142.677642)
		(end 255.049782 -143.972788)
		(width 0.1651)
		(layer "F.Cu")
		(net "M_E_MA<1>")
	)
	(segment
		(start 256.78765 -98.18624)
		(end 256.21615 -98.18624)
		(width 0.1016)
		(layer "F.Cu")
		(net "M_E_MA<1>")
	)
	(segment
		(start 255.05029 -142.6718)
		(end 255.049782 -142.677642)
		(width 0.1651)
		(layer "F.Cu")
		(net "M_E_MA<1>")
	)
	(via
		(at 255.050036 -141.187678)
		(size 0.4572)
		(drill 0.2032)
		(layers "F.Cu" "B.Cu")
		(net "M_E_MA<1>")
	)
	(via
		(at 255.049782 -143.972788)
		(size 0.4572)
		(drill 0.2032)
		(layers "F.Cu" "B.Cu")
		(net "M_E_MA<1>")
	)
	(via
		(at 256.21615 -98.18624)
		(size 0.508)
		(drill 0.254)
		(layers "F.Cu" "B.Cu")
		(net "M_E_MA<1>")
	)
	(segment
		(start 255.049782 -142.476982)
		(end 255.049782 -141.213332)
		(width 0.1651)
		(layer "B.Cu")
		(net "M_E_MA<1>")
	)
	(segment
		(start 255.050036 -141.213078)
		(end 255.050036 -141.187678)
		(width 0.1651)
		(layer "B.Cu")
		(net "M_E_MA<1>")
	)
	(segment
		(start 255.049782 -141.213332)
		(end 255.050036 -141.213078)
		(width 0.1651)
		(layer "B.Cu")
		(net "M_E_MA<1>")
	)
	(segment
		(start 255.05029 -142.477236)
		(end 255.049782 -142.476982)
		(width 0.1651)
		(layer "B.Cu")
		(net "M_E_MA<1>")
	)
	(segment
		(start 257.657092 -126.6698)
		(end 257.438398 -126.888494)
		(width 0.14224)
		(layer "In4.Cu")
		(net "M_E_MA<1>")
	)
	(segment
		(start 257.657092 -103.478838)
		(end 257.657092 -103.75011)
		(width 0.0889)
		(layer "In4.Cu")
		(net "M_E_MA<1>")
	)
	(segment
		(start 256.749804 -127.747268)
		(end 256.749804 -128.034796)
		(width 0.14224)
		(layer "In4.Cu")
		(net "M_E_MA<1>")
	)
	(segment
		(start 255.3589 -136.11606)
		(end 255.463548 -136.220708)
		(width 0.14224)
		(layer "In4.Cu")
		(net "M_E_MA<1>")
	)
	(segment
		(start 254.955802 -141.093444)
		(end 255.050036 -141.187678)
		(width 0.14224)
		(layer "In4.Cu")
		(net "M_E_MA<1>")
	)
	(segment
		(start 256.953004 -102.77475)
		(end 257.657092 -103.478838)
		(width 0.0889)
		(layer "In4.Cu")
		(net "M_E_MA<1>")
	)
	(segment
		(start 255.050036 -141.187678)
		(end 255.050036 -143.972534)
		(width 0.14224)
		(layer "In4.Cu")
		(net "M_E_MA<1>")
	)
	(segment
		(start 255.44272 -130.419856)
		(end 255.280922 -130.581654)
		(width 0.14224)
		(layer "In4.Cu")
		(net "M_E_MA<1>")
	)
	(segment
		(start 255.6002 -132.1435)
		(end 255.413256 -132.330444)
		(width 0.14224)
		(layer "In4.Cu")
		(net "M_E_MA<1>")
	)
	(segment
		(start 257.438398 -126.888494)
		(end 256.753106 -126.888494)
		(width 0.14224)
		(layer "In4.Cu")
		(net "M_E_MA<1>")
	)
	(segment
		(start 256.21615 -98.52152)
		(end 256.368804 -98.674174)
		(width 0.0889)
		(layer "In4.Cu")
		(net "M_E_MA<1>")
	)
	(segment
		(start 254.635 -140.1572)
		(end 254.955802 -140.478002)
		(width 0.14224)
		(layer "In4.Cu")
		(net "M_E_MA<1>")
	)
	(segment
		(start 255.413256 -133.069076)
		(end 255.6002 -133.25602)
		(width 0.14224)
		(layer "In4.Cu")
		(net "M_E_MA<1>")
	)
	(segment
		(start 255.463548 -137.880852)
		(end 254.635 -138.7094)
		(width 0.14224)
		(layer "In4.Cu")
		(net "M_E_MA<1>")
	)
	(segment
		(start 255.463548 -136.220708)
		(end 255.463548 -137.880852)
		(width 0.14224)
		(layer "In4.Cu")
		(net "M_E_MA<1>")
	)
	(segment
		(start 255.6002 -131.535424)
		(end 255.6002 -132.1435)
		(width 0.14224)
		(layer "In4.Cu")
		(net "M_E_MA<1>")
	)
	(segment
		(start 256.753106 -126.888494)
		(end 256.465832 -127.175768)
		(width 0.14224)
		(layer "In4.Cu")
		(net "M_E_MA<1>")
	)
	(segment
		(start 255.280922 -131.216146)
		(end 255.6002 -131.535424)
		(width 0.14224)
		(layer "In4.Cu")
		(net "M_E_MA<1>")
	)
	(segment
		(start 256.46253 -128.32207)
		(end 256.175002 -128.32207)
		(width 0.14224)
		(layer "In4.Cu")
		(net "M_E_MA<1>")
	)
	(segment
		(start 255.413256 -132.330444)
		(end 255.413256 -133.069076)
		(width 0.14224)
		(layer "In4.Cu")
		(net "M_E_MA<1>")
	)
	(segment
		(start 255.465326 -134.739126)
		(end 255.3589 -134.845552)
		(width 0.14224)
		(layer "In4.Cu")
		(net "M_E_MA<1>")
	)
	(segment
		(start 256.175002 -128.32207)
		(end 255.952244 -128.099312)
		(width 0.14224)
		(layer "In4.Cu")
		(net "M_E_MA<1>")
	)
	(segment
		(start 255.44272 -130.049524)
		(end 255.44272 -130.419856)
		(width 0.14224)
		(layer "In4.Cu")
		(net "M_E_MA<1>")
	)
	(segment
		(start 255.050036 -143.972534)
		(end 255.049782 -143.972788)
		(width 0.14224)
		(layer "In4.Cu")
		(net "M_E_MA<1>")
	)
	(segment
		(start 255.465326 -134.094474)
		(end 255.465326 -134.739126)
		(width 0.14224)
		(layer "In4.Cu")
		(net "M_E_MA<1>")
	)
	(segment
		(start 254.955802 -140.478002)
		(end 254.955802 -141.093444)
		(width 0.14224)
		(layer "In4.Cu")
		(net "M_E_MA<1>")
	)
	(segment
		(start 255.151128 -129.757932)
		(end 255.44272 -130.049524)
		(width 0.14224)
		(layer "In4.Cu")
		(net "M_E_MA<1>")
	)
	(segment
		(start 255.542288 -128.099312)
		(end 255.151128 -128.490472)
		(width 0.14224)
		(layer "In4.Cu")
		(net "M_E_MA<1>")
	)
	(segment
		(start 256.465832 -127.175768)
		(end 256.465832 -127.463296)
		(width 0.14224)
		(layer "In4.Cu")
		(net "M_E_MA<1>")
	)
	(segment
		(start 256.368804 -98.674174)
		(end 256.368804 -100.489004)
		(width 0.0889)
		(layer "In4.Cu")
		(net "M_E_MA<1>")
	)
	(segment
		(start 255.6002 -133.25602)
		(end 255.6002 -133.9596)
		(width 0.14224)
		(layer "In4.Cu")
		(net "M_E_MA<1>")
	)
	(segment
		(start 255.952244 -128.099312)
		(end 255.542288 -128.099312)
		(width 0.14224)
		(layer "In4.Cu")
		(net "M_E_MA<1>")
	)
	(segment
		(start 255.6002 -133.9596)
		(end 255.465326 -134.094474)
		(width 0.14224)
		(layer "In4.Cu")
		(net "M_E_MA<1>")
	)
	(segment
		(start 255.151128 -128.490472)
		(end 255.151128 -129.757932)
		(width 0.14224)
		(layer "In4.Cu")
		(net "M_E_MA<1>")
	)
	(segment
		(start 255.3589 -134.845552)
		(end 255.3589 -136.11606)
		(width 0.14224)
		(layer "In4.Cu")
		(net "M_E_MA<1>")
	)
	(segment
		(start 256.465832 -127.463296)
		(end 256.749804 -127.747268)
		(width 0.14224)
		(layer "In4.Cu")
		(net "M_E_MA<1>")
	)
	(segment
		(start 256.749804 -128.034796)
		(end 256.46253 -128.32207)
		(width 0.14224)
		(layer "In4.Cu")
		(net "M_E_MA<1>")
	)
	(segment
		(start 257.657092 -103.75011)
		(end 257.657092 -126.6698)
		(width 0.14224)
		(layer "In4.Cu")
		(net "M_E_MA<1>")
	)
	(segment
		(start 256.953004 -101.073204)
		(end 256.953004 -102.77475)
		(width 0.0889)
		(layer "In4.Cu")
		(net "M_E_MA<1>")
	)
	(segment
		(start 256.368804 -100.489004)
		(end 256.953004 -101.073204)
		(width 0.0889)
		(layer "In4.Cu")
		(net "M_E_MA<1>")
	)
	(segment
		(start 255.280922 -130.581654)
		(end 255.280922 -131.216146)
		(width 0.14224)
		(layer "In4.Cu")
		(net "M_E_MA<1>")
	)
	(segment
		(start 256.21615 -98.18624)
		(end 256.21615 -98.52152)
		(width 0.0889)
		(layer "In4.Cu")
		(net "M_E_MA<1>")
	)
	(segment
		(start 254.635 -138.7094)
		(end 254.635 -140.1572)
		(width 0.14224)
		(layer "In4.Cu")
		(net "M_E_MA<1>")
	)
	(segment
		(start 265.372596 -96.20504)
		(end 264.801096 -96.20504)
		(width 0.1016)
		(layer "F.Cu")
		(net "M_E_MA<17>")
	)
	(segment
		(start 275.449792 -145.988786)
		(end 275.449792 -147.27174)
		(width 0.1651)
		(layer "F.Cu")
		(net "M_E_MA<17>")
	)
	(segment
		(start 275.4503 -145.988278)
		(end 275.449792 -145.988786)
		(width 0.1651)
		(layer "F.Cu")
		(net "M_E_MA<17>")
	)
	(segment
		(start 275.449792 -147.27174)
		(end 275.4503 -147.27174)
		(width 0.1651)
		(layer "F.Cu")
		(net "M_E_MA<17>")
	)
	(via
		(at 275.4503 -145.988278)
		(size 0.4572)
		(drill 0.2032)
		(layers "F.Cu" "B.Cu")
		(net "M_E_MA<17>")
	)
	(via
		(at 275.4503 -139.172188)
		(size 0.4572)
		(drill 0.2032)
		(layers "F.Cu" "B.Cu")
		(net "M_E_MA<17>")
	)
	(via
		(at 264.801096 -96.20504)
		(size 0.508)
		(drill 0.254)
		(layers "F.Cu" "B.Cu")
		(net "M_E_MA<17>")
	)
	(segment
		(start 275.449792 -139.17168)
		(end 275.4503 -139.172188)
		(width 0.1651)
		(layer "B.Cu")
		(net "M_E_MA<17>")
	)
	(segment
		(start 275.4503 -137.877296)
		(end 275.449792 -137.877296)
		(width 0.1651)
		(layer "B.Cu")
		(net "M_E_MA<17>")
	)
	(segment
		(start 275.449792 -137.877296)
		(end 275.449792 -139.17168)
		(width 0.1651)
		(layer "B.Cu")
		(net "M_E_MA<17>")
	)
	(segment
		(start 274.396962 -132.926328)
		(end 274.396962 -133.812788)
		(width 0.14224)
		(layer "In11.Cu")
		(net "M_E_MA<17>")
	)
	(segment
		(start 264.801096 -96.20504)
		(end 265.131296 -96.966786)
		(width 0.0889)
		(layer "In11.Cu")
		(net "M_E_MA<17>")
	)
	(segment
		(start 274.3454 -127.406146)
		(end 274.3454 -129.1082)
		(width 0.14224)
		(layer "In11.Cu")
		(net "M_E_MA<17>")
	)
	(segment
		(start 265.6078 -100.2538)
		(end 266.8778 -101.5238)
		(width 0.14224)
		(layer "In11.Cu")
		(net "M_E_MA<17>")
	)
	(segment
		(start 274.1422 -130.7084)
		(end 274.1422 -131.2418)
		(width 0.14224)
		(layer "In11.Cu")
		(net "M_E_MA<17>")
	)
	(segment
		(start 274.2184 -132.747766)
		(end 274.396962 -132.926328)
		(width 0.14224)
		(layer "In11.Cu")
		(net "M_E_MA<17>")
	)
	(segment
		(start 274.2184 -131.318)
		(end 274.2184 -132.747766)
		(width 0.14224)
		(layer "In11.Cu")
		(net "M_E_MA<17>")
	)
	(segment
		(start 274.321524 -130.529076)
		(end 274.1422 -130.7084)
		(width 0.14224)
		(layer "In11.Cu")
		(net "M_E_MA<17>")
	)
	(segment
		(start 274.321524 -129.922524)
		(end 274.321524 -130.529076)
		(width 0.14224)
		(layer "In11.Cu")
		(net "M_E_MA<17>")
	)
	(segment
		(start 275.4503 -145.4785)
		(end 275.4503 -145.988278)
		(width 0.14224)
		(layer "In11.Cu")
		(net "M_E_MA<17>")
	)
	(segment
		(start 267.6398 -120.700546)
		(end 274.3454 -127.406146)
		(width 0.14224)
		(layer "In11.Cu")
		(net "M_E_MA<17>")
	)
	(segment
		(start 275.54936 -139.271248)
		(end 275.54936 -140.453872)
		(width 0.14224)
		(layer "In11.Cu")
		(net "M_E_MA<17>")
	)
	(segment
		(start 265.201146 -98.88093)
		(end 265.6078 -99.287584)
		(width 0.0889)
		(layer "In11.Cu")
		(net "M_E_MA<17>")
	)
	(segment
		(start 274.159726 -137.881614)
		(end 275.4503 -139.172188)
		(width 0.14224)
		(layer "In11.Cu")
		(net "M_E_MA<17>")
	)
	(segment
		(start 275.012658 -140.990574)
		(end 275.012658 -142.321534)
		(width 0.14224)
		(layer "In11.Cu")
		(net "M_E_MA<17>")
	)
	(segment
		(start 265.131296 -96.966786)
		(end 265.147806 -96.995234)
		(width 0.0889)
		(layer "In11.Cu")
		(net "M_E_MA<17>")
	)
	(segment
		(start 274.16379 -129.28981)
		(end 274.16379 -129.76479)
		(width 0.14224)
		(layer "In11.Cu")
		(net "M_E_MA<17>")
	)
	(segment
		(start 266.8778 -102.2604)
		(end 267.6398 -103.0224)
		(width 0.14224)
		(layer "In11.Cu")
		(net "M_E_MA<17>")
	)
	(segment
		(start 275.042376 -142.351252)
		(end 275.042376 -144.159224)
		(width 0.14224)
		(layer "In11.Cu")
		(net "M_E_MA<17>")
	)
	(segment
		(start 275.012658 -142.321534)
		(end 275.042376 -142.351252)
		(width 0.14224)
		(layer "In11.Cu")
		(net "M_E_MA<17>")
	)
	(segment
		(start 274.16379 -129.76479)
		(end 274.321524 -129.922524)
		(width 0.14224)
		(layer "In11.Cu")
		(net "M_E_MA<17>")
	)
	(segment
		(start 274.3454 -129.1082)
		(end 274.16379 -129.28981)
		(width 0.14224)
		(layer "In11.Cu")
		(net "M_E_MA<17>")
	)
	(segment
		(start 274.159726 -134.050024)
		(end 274.159726 -137.881614)
		(width 0.14224)
		(layer "In11.Cu")
		(net "M_E_MA<17>")
	)
	(segment
		(start 275.559266 -145.369534)
		(end 275.4503 -145.4785)
		(width 0.14224)
		(layer "In11.Cu")
		(net "M_E_MA<17>")
	)
	(segment
		(start 265.6078 -99.696778)
		(end 265.6078 -100.2538)
		(width 0.14224)
		(layer "In11.Cu")
		(net "M_E_MA<17>")
	)
	(segment
		(start 265.201146 -98.19513)
		(end 265.201146 -98.88093)
		(width 0.0889)
		(layer "In11.Cu")
		(net "M_E_MA<17>")
	)
	(segment
		(start 275.559266 -144.676114)
		(end 275.559266 -145.369534)
		(width 0.14224)
		(layer "In11.Cu")
		(net "M_E_MA<17>")
	)
	(segment
		(start 267.6398 -103.0224)
		(end 267.6398 -120.700546)
		(width 0.14224)
		(layer "In11.Cu")
		(net "M_E_MA<17>")
	)
	(segment
		(start 274.1422 -131.2418)
		(end 274.2184 -131.318)
		(width 0.14224)
		(layer "In11.Cu")
		(net "M_E_MA<17>")
	)
	(segment
		(start 275.54936 -140.453872)
		(end 275.012658 -140.990574)
		(width 0.14224)
		(layer "In11.Cu")
		(net "M_E_MA<17>")
	)
	(segment
		(start 275.042376 -144.159224)
		(end 275.559266 -144.676114)
		(width 0.14224)
		(layer "In11.Cu")
		(net "M_E_MA<17>")
	)
	(segment
		(start 275.4503 -139.172188)
		(end 275.54936 -139.271248)
		(width 0.14224)
		(layer "In11.Cu")
		(net "M_E_MA<17>")
	)
	(segment
		(start 265.6078 -99.287584)
		(end 265.6078 -99.696778)
		(width 0.0889)
		(layer "In11.Cu")
		(net "M_E_MA<17>")
	)
	(segment
		(start 274.396962 -133.812788)
		(end 274.159726 -134.050024)
		(width 0.14224)
		(layer "In11.Cu")
		(net "M_E_MA<17>")
	)
	(segment
		(start 266.8778 -101.5238)
		(end 266.8778 -102.2604)
		(width 0.14224)
		(layer "In11.Cu")
		(net "M_E_MA<17>")
	)
	(arc
		(start 265.147806 -96.995234)
		(mid 265.201305 -97.195132)
		(end 265.147806 -97.39503)
		(width 0.0889)
		(layer "In11.Cu")
		(net "M_E_MA<17>")
	)
	(arc
		(start 265.147806 -97.985834)
		(mid 265.188887 -98.086813)
		(end 265.201146 -98.19513)
		(width 0.0889)
		(layer "In11.Cu")
		(net "M_E_MA<17>")
	)
	(arc
		(start 265.147806 -97.39503)
		(mid 265.068675 -97.690432)
		(end 265.147806 -97.985834)
		(width 0.0889)
		(layer "In11.Cu")
		(net "M_E_MA<17>")
	)
	(segment
		(start 268.650466 -142.6718)
		(end 268.649958 -142.677642)
		(width 0.1651)
		(layer "F.Cu")
		(net "M_E_MA<16>")
	)
	(segment
		(start 261.93877 -95.21444)
		(end 261.36727 -95.21444)
		(width 0.1016)
		(layer "F.Cu")
		(net "M_E_MA<16>")
	)
	(segment
		(start 268.649958 -142.677642)
		(end 268.649958 -143.968978)
		(width 0.1651)
		(layer "F.Cu")
		(net "M_E_MA<16>")
	)
	(via
		(at 268.649958 -141.183868)
		(size 0.4572)
		(drill 0.2032)
		(layers "F.Cu" "B.Cu")
		(net "M_E_MA<16>")
	)
	(via
		(at 268.649958 -143.968978)
		(size 0.508)
		(drill 0.254)
		(layers "F.Cu" "B.Cu")
		(net "M_E_MA<16>")
	)
	(via
		(at 261.36727 -95.21444)
		(size 0.508)
		(drill 0.254)
		(layers "F.Cu" "B.Cu")
		(net "M_E_MA<16>")
	)
	(segment
		(start 268.650466 -142.477236)
		(end 268.649958 -142.476982)
		(width 0.1651)
		(layer "B.Cu")
		(net "M_E_MA<16>")
	)
	(segment
		(start 268.649958 -142.476982)
		(end 268.649958 -141.183868)
		(width 0.1651)
		(layer "B.Cu")
		(net "M_E_MA<16>")
	)
	(segment
		(start 268.416278 -142.764002)
		(end 268.660626 -142.764002)
		(width 0.14224)
		(layer "In4.Cu")
		(net "M_E_MA<16>")
	)
	(segment
		(start 267.3096 -129.8702)
		(end 267.4366 -129.9972)
		(width 0.14224)
		(layer "In4.Cu")
		(net "M_E_MA<16>")
	)
	(segment
		(start 268.802104 -142.622524)
		(end 268.802104 -142.303754)
		(width 0.14224)
		(layer "In4.Cu")
		(net "M_E_MA<16>")
	)
	(segment
		(start 268.211046 -140.37818)
		(end 268.649958 -140.817092)
		(width 0.14224)
		(layer "In4.Cu")
		(net "M_E_MA<16>")
	)
	(segment
		(start 268.649958 -140.817092)
		(end 268.649958 -141.183868)
		(width 0.14224)
		(layer "In4.Cu")
		(net "M_E_MA<16>")
	)
	(segment
		(start 269.61846 -142.148814)
		(end 269.781274 -142.311628)
		(width 0.14224)
		(layer "In4.Cu")
		(net "M_E_MA<16>")
	)
	(segment
		(start 267.2842 -130.6576)
		(end 267.2842 -131.1148)
		(width 0.14224)
		(layer "In4.Cu")
		(net "M_E_MA<16>")
	)
	(segment
		(start 263.6012 -103.283766)
		(end 263.6012 -123.91136)
		(width 0.14224)
		(layer "In4.Cu")
		(net "M_E_MA<16>")
	)
	(segment
		(start 267.375132 -135.955532)
		(end 267.3858 -135.9662)
		(width 0.14224)
		(layer "In4.Cu")
		(net "M_E_MA<16>")
	)
	(segment
		(start 261.87908 -97.490788)
		(end 261.874254 -97.499424)
		(width 0.0889)
		(layer "In4.Cu")
		(net "M_E_MA<16>")
	)
	(segment
		(start 268.219174 -142.566898)
		(end 268.416278 -142.764002)
		(width 0.14224)
		(layer "In4.Cu")
		(net "M_E_MA<16>")
	)
	(segment
		(start 267.2842 -131.1148)
		(end 267.462 -131.2926)
		(width 0.14224)
		(layer "In4.Cu")
		(net "M_E_MA<16>")
	)
	(segment
		(start 269.599918 -143.366236)
		(end 268.401292 -143.366236)
		(width 0.14224)
		(layer "In4.Cu")
		(net "M_E_MA<16>")
	)
	(segment
		(start 263.42848 -102.57028)
		(end 263.42848 -102.924864)
		(width 0.0889)
		(layer "In4.Cu")
		(net "M_E_MA<16>")
	)
	(segment
		(start 261.87908 -98.481388)
		(end 261.874254 -98.490024)
		(width 0.0889)
		(layer "In4.Cu")
		(net "M_E_MA<16>")
	)
	(segment
		(start 268.246352 -143.521176)
		(end 268.246352 -143.797528)
		(width 0.14224)
		(layer "In4.Cu")
		(net "M_E_MA<16>")
	)
	(segment
		(start 267.462 -131.9022)
		(end 267.375132 -131.989068)
		(width 0.14224)
		(layer "In4.Cu")
		(net "M_E_MA<16>")
	)
	(segment
		(start 266.9286 -127.584454)
		(end 266.503912 -128.009142)
		(width 0.14224)
		(layer "In4.Cu")
		(net "M_E_MA<16>")
	)
	(segment
		(start 267.462 -131.2926)
		(end 267.462 -131.9022)
		(width 0.14224)
		(layer "In4.Cu")
		(net "M_E_MA<16>")
	)
	(segment
		(start 266.9286 -127.23876)
		(end 266.9286 -127.584454)
		(width 0.14224)
		(layer "In4.Cu")
		(net "M_E_MA<16>")
	)
	(segment
		(start 268.660626 -142.764002)
		(end 268.802104 -142.622524)
		(width 0.14224)
		(layer "In4.Cu")
		(net "M_E_MA<16>")
	)
	(segment
		(start 267.4366 -129.9972)
		(end 267.4366 -130.5052)
		(width 0.14224)
		(layer "In4.Cu")
		(net "M_E_MA<16>")
	)
	(segment
		(start 267.3858 -137.9728)
		(end 268.211046 -138.798046)
		(width 0.14224)
		(layer "In4.Cu")
		(net "M_E_MA<16>")
	)
	(segment
		(start 261.87908 -96.500188)
		(end 261.874254 -96.508824)
		(width 0.0889)
		(layer "In4.Cu")
		(net "M_E_MA<16>")
	)
	(segment
		(start 268.401292 -143.366236)
		(end 268.246352 -143.521176)
		(width 0.14224)
		(layer "In4.Cu")
		(net "M_E_MA<16>")
	)
	(segment
		(start 268.219174 -141.389608)
		(end 268.219174 -142.566898)
		(width 0.14224)
		(layer "In4.Cu")
		(net "M_E_MA<16>")
	)
	(segment
		(start 262.0518 -101.1936)
		(end 263.42848 -102.57028)
		(width 0.0889)
		(layer "In4.Cu")
		(net "M_E_MA<16>")
	)
	(segment
		(start 263.6012 -123.91136)
		(end 266.9286 -127.23876)
		(width 0.14224)
		(layer "In4.Cu")
		(net "M_E_MA<16>")
	)
	(segment
		(start 268.211046 -138.798046)
		(end 268.211046 -140.37818)
		(width 0.14224)
		(layer "In4.Cu")
		(net "M_E_MA<16>")
	)
	(segment
		(start 267.3858 -135.9662)
		(end 267.3858 -137.9728)
		(width 0.14224)
		(layer "In4.Cu")
		(net "M_E_MA<16>")
	)
	(segment
		(start 266.503912 -128.009142)
		(end 266.503912 -128.57861)
		(width 0.14224)
		(layer "In4.Cu")
		(net "M_E_MA<16>")
	)
	(segment
		(start 263.6012 -103.097584)
		(end 263.6012 -103.283766)
		(width 0.0889)
		(layer "In4.Cu")
		(net "M_E_MA<16>")
	)
	(segment
		(start 268.802104 -142.303754)
		(end 268.957044 -142.148814)
		(width 0.14224)
		(layer "In4.Cu")
		(net "M_E_MA<16>")
	)
	(segment
		(start 267.375132 -131.989068)
		(end 267.375132 -135.955532)
		(width 0.14224)
		(layer "In4.Cu")
		(net "M_E_MA<16>")
	)
	(segment
		(start 269.781274 -143.18488)
		(end 269.599918 -143.366236)
		(width 0.14224)
		(layer "In4.Cu")
		(net "M_E_MA<16>")
	)
	(segment
		(start 262.0518 -99.1616)
		(end 262.0518 -101.1936)
		(width 0.0889)
		(layer "In4.Cu")
		(net "M_E_MA<16>")
	)
	(segment
		(start 267.4366 -130.5052)
		(end 267.2842 -130.6576)
		(width 0.14224)
		(layer "In4.Cu")
		(net "M_E_MA<16>")
	)
	(segment
		(start 263.42848 -102.924864)
		(end 263.6012 -103.097584)
		(width 0.0889)
		(layer "In4.Cu")
		(net "M_E_MA<16>")
	)
	(segment
		(start 268.246352 -143.797528)
		(end 268.417802 -143.968978)
		(width 0.14224)
		(layer "In4.Cu")
		(net "M_E_MA<16>")
	)
	(segment
		(start 261.88543 -96.48952)
		(end 261.87908 -96.500188)
		(width 0.0889)
		(layer "In4.Cu")
		(net "M_E_MA<16>")
	)
	(segment
		(start 261.88543 -98.47072)
		(end 261.87908 -98.481388)
		(width 0.0889)
		(layer "In4.Cu")
		(net "M_E_MA<16>")
	)
	(segment
		(start 261.88543 -97.48012)
		(end 261.87908 -97.490788)
		(width 0.0889)
		(layer "In4.Cu")
		(net "M_E_MA<16>")
	)
	(segment
		(start 266.503912 -128.57861)
		(end 267.3096 -129.384298)
		(width 0.14224)
		(layer "In4.Cu")
		(net "M_E_MA<16>")
	)
	(segment
		(start 268.417802 -143.968978)
		(end 268.649958 -143.968978)
		(width 0.14224)
		(layer "In4.Cu")
		(net "M_E_MA<16>")
	)
	(segment
		(start 268.424914 -141.183868)
		(end 268.219174 -141.389608)
		(width 0.14224)
		(layer "In4.Cu")
		(net "M_E_MA<16>")
	)
	(segment
		(start 269.781274 -142.311628)
		(end 269.781274 -143.18488)
		(width 0.14224)
		(layer "In4.Cu")
		(net "M_E_MA<16>")
	)
	(segment
		(start 268.649958 -141.183868)
		(end 268.424914 -141.183868)
		(width 0.14224)
		(layer "In4.Cu")
		(net "M_E_MA<16>")
	)
	(segment
		(start 267.3096 -129.384298)
		(end 267.3096 -129.8702)
		(width 0.14224)
		(layer "In4.Cu")
		(net "M_E_MA<16>")
	)
	(segment
		(start 268.957044 -142.148814)
		(end 269.61846 -142.148814)
		(width 0.14224)
		(layer "In4.Cu")
		(net "M_E_MA<16>")
	)
	(arc
		(start 261.826248 -95.73387)
		(mid 261.842478 -95.824813)
		(end 261.87908 -95.909638)
		(width 0.0889)
		(layer "In4.Cu")
		(net "M_E_MA<16>")
	)
	(arc
		(start 261.36727 -95.21444)
		(mid 261.695016 -95.387315)
		(end 261.826248 -95.73387)
		(width 0.0889)
		(layer "In4.Cu")
		(net "M_E_MA<16>")
	)
	(arc
		(start 261.87908 -97.890838)
		(mid 261.958302 -98.179956)
		(end 261.88543 -98.47072)
		(width 0.0889)
		(layer "In4.Cu")
		(net "M_E_MA<16>")
	)
	(arc
		(start 261.874254 -98.490024)
		(mid 261.825499 -98.686376)
		(end 261.87908 -98.881438)
		(width 0.0889)
		(layer "In4.Cu")
		(net "M_E_MA<16>")
	)
	(arc
		(start 261.874254 -96.508824)
		(mid 261.825499 -96.705176)
		(end 261.87908 -96.900238)
		(width 0.0889)
		(layer "In4.Cu")
		(net "M_E_MA<16>")
	)
	(arc
		(start 261.87908 -96.900238)
		(mid 261.958302 -97.189356)
		(end 261.88543 -97.48012)
		(width 0.0889)
		(layer "In4.Cu")
		(net "M_E_MA<16>")
	)
	(arc
		(start 261.87908 -95.909638)
		(mid 261.958302 -96.198756)
		(end 261.88543 -96.48952)
		(width 0.0889)
		(layer "In4.Cu")
		(net "M_E_MA<16>")
	)
	(arc
		(start 261.87908 -98.881438)
		(mid 261.963375 -99.022792)
		(end 262.0518 -99.1616)
		(width 0.0889)
		(layer "In4.Cu")
		(net "M_E_MA<16>")
	)
	(arc
		(start 261.874254 -97.499424)
		(mid 261.825499 -97.695776)
		(end 261.87908 -97.890838)
		(width 0.0889)
		(layer "In4.Cu")
		(net "M_E_MA<16>")
	)
	(segment
		(start 272.050002 -143.972534)
		(end 272.050256 -143.972788)
		(width 0.1651)
		(layer "F.Cu")
		(net "M_E_MA<15>")
	)
	(segment
		(start 272.05051 -142.6718)
		(end 272.050002 -142.677642)
		(width 0.1651)
		(layer "F.Cu")
		(net "M_E_MA<15>")
	)
	(segment
		(start 261.93877 -96.20504)
		(end 261.36727 -96.20504)
		(width 0.1016)
		(layer "F.Cu")
		(net "M_E_MA<15>")
	)
	(segment
		(start 272.050002 -142.677642)
		(end 272.050002 -143.972534)
		(width 0.1651)
		(layer "F.Cu")
		(net "M_E_MA<15>")
	)
	(via
		(at 261.36727 -96.20504)
		(size 0.508)
		(drill 0.254)
		(layers "F.Cu" "B.Cu")
		(net "M_E_MA<15>")
	)
	(via
		(at 272.050256 -143.972788)
		(size 0.4572)
		(drill 0.2032)
		(layers "F.Cu" "B.Cu")
		(net "M_E_MA<15>")
	)
	(via
		(at 272.050256 -141.187678)
		(size 0.4572)
		(drill 0.2032)
		(layers "F.Cu" "B.Cu")
		(net "M_E_MA<15>")
	)
	(segment
		(start 272.05051 -142.477236)
		(end 272.050002 -142.476982)
		(width 0.10795)
		(layer "B.Cu")
		(net "M_E_MA<15>")
	)
	(segment
		(start 272.050002 -141.187932)
		(end 272.050256 -141.187678)
		(width 0.10795)
		(layer "B.Cu")
		(net "M_E_MA<15>")
	)
	(segment
		(start 272.050002 -142.476982)
		(end 272.050002 -141.187932)
		(width 0.10795)
		(layer "B.Cu")
		(net "M_E_MA<15>")
	)
	(segment
		(start 270.002 -129.3876)
		(end 270.002 -129.8448)
		(width 0.14224)
		(layer "In11.Cu")
		(net "M_E_MA<15>")
	)
	(segment
		(start 262.0772 -99.2124)
		(end 262.0772 -99.3902)
		(width 0.14224)
		(layer "In11.Cu")
		(net "M_E_MA<15>")
	)
	(segment
		(start 273.154648 -142.225268)
		(end 272.205196 -142.225268)
		(width 0.14224)
		(layer "In11.Cu")
		(net "M_E_MA<15>")
	)
	(segment
		(start 272.050256 -142.380208)
		(end 272.050256 -142.631668)
		(width 0.14224)
		(layer "In11.Cu")
		(net "M_E_MA<15>")
	)
	(segment
		(start 272.050256 -143.502888)
		(end 272.050256 -143.972788)
		(width 0.14224)
		(layer "In11.Cu")
		(net "M_E_MA<15>")
	)
	(segment
		(start 269.875 -131.318)
		(end 269.875 -133.8834)
		(width 0.14224)
		(layer "In11.Cu")
		(net "M_E_MA<15>")
	)
	(segment
		(start 261.747 -97.4852)
		(end 261.747 -97.917)
		(width 0.14224)
		(layer "In11.Cu")
		(net "M_E_MA<15>")
	)
	(segment
		(start 261.747 -97.917)
		(end 261.882636 -98.052636)
		(width 0.14224)
		(layer "In11.Cu")
		(net "M_E_MA<15>")
	)
	(segment
		(start 263.5504 -100.8634)
		(end 263.5504 -102.6922)
		(width 0.14224)
		(layer "In11.Cu")
		(net "M_E_MA<15>")
	)
	(segment
		(start 261.8486 -97.002346)
		(end 261.8486 -97.3836)
		(width 0.14224)
		(layer "In11.Cu")
		(net "M_E_MA<15>")
	)
	(segment
		(start 263.5504 -102.6922)
		(end 264.963148 -104.104948)
		(width 0.14224)
		(layer "In11.Cu")
		(net "M_E_MA<15>")
	)
	(segment
		(start 273.14398 -141.663928)
		(end 273.304254 -141.824202)
		(width 0.14224)
		(layer "In11.Cu")
		(net "M_E_MA<15>")
	)
	(segment
		(start 272.050256 -141.187678)
		(end 272.050256 -141.508988)
		(width 0.14224)
		(layer "In11.Cu")
		(net "M_E_MA<15>")
	)
	(segment
		(start 271.526 -139.6238)
		(end 271.526 -140.663422)
		(width 0.14224)
		(layer "In11.Cu")
		(net "M_E_MA<15>")
	)
	(segment
		(start 264.963148 -104.104948)
		(end 264.963148 -121.788174)
		(width 0.14224)
		(layer "In11.Cu")
		(net "M_E_MA<15>")
	)
	(segment
		(start 272.205196 -142.786608)
		(end 273.181064 -142.786608)
		(width 0.14224)
		(layer "In11.Cu")
		(net "M_E_MA<15>")
	)
	(segment
		(start 269.9766 -131.2164)
		(end 269.875 -131.318)
		(width 0.14224)
		(layer "In11.Cu")
		(net "M_E_MA<15>")
	)
	(segment
		(start 272.050256 -141.508988)
		(end 272.205196 -141.663928)
		(width 0.14224)
		(layer "In11.Cu")
		(net "M_E_MA<15>")
	)
	(segment
		(start 261.8486 -97.3836)
		(end 261.747 -97.4852)
		(width 0.14224)
		(layer "In11.Cu")
		(net "M_E_MA<15>")
	)
	(segment
		(start 272.205196 -143.347948)
		(end 272.050256 -143.502888)
		(width 0.14224)
		(layer "In11.Cu")
		(net "M_E_MA<15>")
	)
	(segment
		(start 271.636998 -139.512802)
		(end 271.526 -139.6238)
		(width 0.14224)
		(layer "In11.Cu")
		(net "M_E_MA<15>")
	)
	(segment
		(start 269.875 -130.5306)
		(end 269.9766 -130.6322)
		(width 0.14224)
		(layer "In11.Cu")
		(net "M_E_MA<15>")
	)
	(segment
		(start 269.875 -133.8834)
		(end 269.927832 -133.936232)
		(width 0.14224)
		(layer "In11.Cu")
		(net "M_E_MA<15>")
	)
	(segment
		(start 272.205196 -142.225268)
		(end 272.050256 -142.380208)
		(width 0.14224)
		(layer "In11.Cu")
		(net "M_E_MA<15>")
	)
	(segment
		(start 269.8242 -126.649226)
		(end 269.8242 -129.2098)
		(width 0.14224)
		(layer "In11.Cu")
		(net "M_E_MA<15>")
	)
	(segment
		(start 270.763492 -138.063732)
		(end 271.636998 -138.937238)
		(width 0.14224)
		(layer "In11.Cu")
		(net "M_E_MA<15>")
	)
	(segment
		(start 261.36727 -96.20504)
		(end 261.36727 -96.521016)
		(width 0.14224)
		(layer "In11.Cu")
		(net "M_E_MA<15>")
	)
	(segment
		(start 262.0772 -99.3902)
		(end 263.5504 -100.8634)
		(width 0.14224)
		(layer "In11.Cu")
		(net "M_E_MA<15>")
	)
	(segment
		(start 261.36727 -96.521016)
		(end 261.8486 -97.002346)
		(width 0.14224)
		(layer "In11.Cu")
		(net "M_E_MA<15>")
	)
	(segment
		(start 261.882636 -98.052636)
		(end 261.882636 -98.340164)
		(width 0.14224)
		(layer "In11.Cu")
		(net "M_E_MA<15>")
	)
	(segment
		(start 269.9766 -130.6322)
		(end 269.9766 -131.2164)
		(width 0.14224)
		(layer "In11.Cu")
		(net "M_E_MA<15>")
	)
	(segment
		(start 261.747 -98.8822)
		(end 262.0772 -99.2124)
		(width 0.14224)
		(layer "In11.Cu")
		(net "M_E_MA<15>")
	)
	(segment
		(start 269.927832 -133.936232)
		(end 269.927832 -135.180832)
		(width 0.14224)
		(layer "In11.Cu")
		(net "M_E_MA<15>")
	)
	(segment
		(start 271.526 -140.663422)
		(end 272.050256 -141.187678)
		(width 0.14224)
		(layer "In11.Cu")
		(net "M_E_MA<15>")
	)
	(segment
		(start 273.336004 -143.193008)
		(end 273.181064 -143.347948)
		(width 0.14224)
		(layer "In11.Cu")
		(net "M_E_MA<15>")
	)
	(segment
		(start 261.747 -98.4758)
		(end 261.747 -98.8822)
		(width 0.14224)
		(layer "In11.Cu")
		(net "M_E_MA<15>")
	)
	(segment
		(start 272.205196 -141.663928)
		(end 273.14398 -141.663928)
		(width 0.14224)
		(layer "In11.Cu")
		(net "M_E_MA<15>")
	)
	(segment
		(start 269.8242 -129.2098)
		(end 270.002 -129.3876)
		(width 0.14224)
		(layer "In11.Cu")
		(net "M_E_MA<15>")
	)
	(segment
		(start 273.304254 -141.824202)
		(end 273.304254 -142.075662)
		(width 0.14224)
		(layer "In11.Cu")
		(net "M_E_MA<15>")
	)
	(segment
		(start 273.304254 -142.075662)
		(end 273.154648 -142.225268)
		(width 0.14224)
		(layer "In11.Cu")
		(net "M_E_MA<15>")
	)
	(segment
		(start 270.763492 -136.016492)
		(end 270.763492 -138.063732)
		(width 0.14224)
		(layer "In11.Cu")
		(net "M_E_MA<15>")
	)
	(segment
		(start 272.050256 -142.631668)
		(end 272.205196 -142.786608)
		(width 0.14224)
		(layer "In11.Cu")
		(net "M_E_MA<15>")
	)
	(segment
		(start 271.636998 -138.937238)
		(end 271.636998 -139.512802)
		(width 0.14224)
		(layer "In11.Cu")
		(net "M_E_MA<15>")
	)
	(segment
		(start 273.181064 -142.786608)
		(end 273.336004 -142.941548)
		(width 0.14224)
		(layer "In11.Cu")
		(net "M_E_MA<15>")
	)
	(segment
		(start 270.002 -129.8448)
		(end 269.875 -129.9718)
		(width 0.14224)
		(layer "In11.Cu")
		(net "M_E_MA<15>")
	)
	(segment
		(start 269.927832 -135.180832)
		(end 270.763492 -136.016492)
		(width 0.14224)
		(layer "In11.Cu")
		(net "M_E_MA<15>")
	)
	(segment
		(start 273.181064 -143.347948)
		(end 272.205196 -143.347948)
		(width 0.14224)
		(layer "In11.Cu")
		(net "M_E_MA<15>")
	)
	(segment
		(start 261.882636 -98.340164)
		(end 261.747 -98.4758)
		(width 0.14224)
		(layer "In11.Cu")
		(net "M_E_MA<15>")
	)
	(segment
		(start 273.336004 -142.941548)
		(end 273.336004 -143.193008)
		(width 0.14224)
		(layer "In11.Cu")
		(net "M_E_MA<15>")
	)
	(segment
		(start 269.875 -129.9718)
		(end 269.875 -130.5306)
		(width 0.14224)
		(layer "In11.Cu")
		(net "M_E_MA<15>")
	)
	(segment
		(start 264.963148 -121.788174)
		(end 269.8242 -126.649226)
		(width 0.14224)
		(layer "In11.Cu")
		(net "M_E_MA<15>")
	)
	(segment
		(start 270.34998 -147.27174)
		(end 270.350488 -147.27174)
		(width 0.1651)
		(layer "F.Cu")
		(net "M_E_MA<14>")
	)
	(segment
		(start 262.79729 -94.718886)
		(end 262.22579 -94.718886)
		(width 0.1016)
		(layer "F.Cu")
		(net "M_E_MA<14>")
	)
	(segment
		(start 270.350234 -145.988278)
		(end 270.34998 -145.988532)
		(width 0.1651)
		(layer "F.Cu")
		(net "M_E_MA<14>")
	)
	(segment
		(start 270.34998 -145.988532)
		(end 270.34998 -147.27174)
		(width 0.1651)
		(layer "F.Cu")
		(net "M_E_MA<14>")
	)
	(via
		(at 270.350234 -145.988278)
		(size 0.4572)
		(drill 0.2032)
		(layers "F.Cu" "B.Cu")
		(net "M_E_MA<14>")
	)
	(via
		(at 262.22579 -94.718886)
		(size 0.508)
		(drill 0.254)
		(layers "F.Cu" "B.Cu")
		(net "M_E_MA<14>")
	)
	(via
		(at 270.350234 -139.172188)
		(size 0.4572)
		(drill 0.2032)
		(layers "F.Cu" "B.Cu")
		(net "M_E_MA<14>")
	)
	(segment
		(start 270.34998 -137.877296)
		(end 270.34998 -139.171934)
		(width 0.1651)
		(layer "B.Cu")
		(net "M_E_MA<14>")
	)
	(segment
		(start 270.350488 -137.877296)
		(end 270.34998 -137.877296)
		(width 0.1651)
		(layer "B.Cu")
		(net "M_E_MA<14>")
	)
	(segment
		(start 270.34998 -139.171934)
		(end 270.350234 -139.172188)
		(width 0.1651)
		(layer "B.Cu")
		(net "M_E_MA<14>")
	)
	(segment
		(start 270.350234 -139.172188)
		(end 270.759936 -139.58189)
		(width 0.14224)
		(layer "In4.Cu")
		(net "M_E_MA<14>")
	)
	(segment
		(start 269.935198 -134.712202)
		(end 269.875 -134.7724)
		(width 0.14224)
		(layer "In4.Cu")
		(net "M_E_MA<14>")
	)
	(segment
		(start 269.875 -135.3058)
		(end 269.909036 -135.339836)
		(width 0.14224)
		(layer "In4.Cu")
		(net "M_E_MA<14>")
	)
	(segment
		(start 263.48436 -98.81616)
		(end 263.7409 -99.0727)
		(width 0.0889)
		(layer "In4.Cu")
		(net "M_E_MA<14>")
	)
	(segment
		(start 263.06653 -97.78619)
		(end 263.099296 -97.78619)
		(width 0.0889)
		(layer "In4.Cu")
		(net "M_E_MA<14>")
	)
	(segment
		(start 269.875 -134.0358)
		(end 269.935198 -134.095998)
		(width 0.14224)
		(layer "In4.Cu")
		(net "M_E_MA<14>")
	)
	(segment
		(start 267.220192 -125.154944)
		(end 267.628624 -124.746512)
		(width 0.14224)
		(layer "In4.Cu")
		(net "M_E_MA<14>")
	)
	(segment
		(start 269.935198 -134.095998)
		(end 269.935198 -134.712202)
		(width 0.14224)
		(layer "In4.Cu")
		(net "M_E_MA<14>")
	)
	(segment
		(start 266.634976 -123.519438)
		(end 266.634976 -124.78893)
		(width 0.14224)
		(layer "In4.Cu")
		(net "M_E_MA<14>")
	)
	(segment
		(start 263.48436 -98.195384)
		(end 263.48436 -98.81616)
		(width 0.0889)
		(layer "In4.Cu")
		(net "M_E_MA<14>")
	)
	(segment
		(start 263.7409 -99.0727)
		(end 263.7409 -100.8761)
		(width 0.0889)
		(layer "In4.Cu")
		(net "M_E_MA<14>")
	)
	(segment
		(start 270.0274 -128.181354)
		(end 270.0274 -129.7432)
		(width 0.14224)
		(layer "In4.Cu")
		(net "M_E_MA<14>")
	)
	(segment
		(start 265.1252 -122.009662)
		(end 266.634976 -123.519438)
		(width 0.14224)
		(layer "In4.Cu")
		(net "M_E_MA<14>")
	)
	(segment
		(start 262.22579 -94.718886)
		(end 262.555228 -95.47987)
		(width 0.0889)
		(layer "In4.Cu")
		(net "M_E_MA<14>")
	)
	(segment
		(start 267.628624 -124.746512)
		(end 267.842238 -124.746512)
		(width 0.14224)
		(layer "In4.Cu")
		(net "M_E_MA<14>")
	)
	(segment
		(start 269.875 -129.8956)
		(end 269.875 -130.6068)
		(width 0.14224)
		(layer "In4.Cu")
		(net "M_E_MA<14>")
	)
	(segment
		(start 268.092174 -125.220476)
		(end 267.688822 -125.623828)
		(width 0.14224)
		(layer "In4.Cu")
		(net "M_E_MA<14>")
	)
	(segment
		(start 269.875 -131.191)
		(end 269.875 -134.0358)
		(width 0.14224)
		(layer "In4.Cu")
		(net "M_E_MA<14>")
	)
	(segment
		(start 269.9766 -131.0894)
		(end 269.875 -131.191)
		(width 0.14224)
		(layer "In4.Cu")
		(net "M_E_MA<14>")
	)
	(segment
		(start 267.688822 -125.623828)
		(end 267.688822 -125.842776)
		(width 0.14224)
		(layer "In4.Cu")
		(net "M_E_MA<14>")
	)
	(segment
		(start 270.759936 -145.038064)
		(end 270.349726 -145.448274)
		(width 0.14224)
		(layer "In4.Cu")
		(net "M_E_MA<14>")
	)
	(segment
		(start 270.349726 -145.448274)
		(end 270.350234 -145.448782)
		(width 0.14224)
		(layer "In4.Cu")
		(net "M_E_MA<14>")
	)
	(segment
		(start 269.875 -130.6068)
		(end 269.9766 -130.7084)
		(width 0.14224)
		(layer "In4.Cu")
		(net "M_E_MA<14>")
	)
	(segment
		(start 267.00099 -125.154944)
		(end 267.220192 -125.154944)
		(width 0.14224)
		(layer "In4.Cu")
		(net "M_E_MA<14>")
	)
	(segment
		(start 262.555228 -95.47987)
		(end 262.577326 -95.518224)
		(width 0.0889)
		(layer "In4.Cu")
		(net "M_E_MA<14>")
	)
	(segment
		(start 262.56615 -96.48952)
		(end 262.5725 -96.500188)
		(width 0.0889)
		(layer "In4.Cu")
		(net "M_E_MA<14>")
	)
	(segment
		(start 263.7409 -100.8761)
		(end 264.9474 -102.0826)
		(width 0.0889)
		(layer "In4.Cu")
		(net "M_E_MA<14>")
	)
	(segment
		(start 268.092174 -124.996448)
		(end 268.092174 -125.220476)
		(width 0.14224)
		(layer "In4.Cu")
		(net "M_E_MA<14>")
	)
	(segment
		(start 264.9474 -102.0826)
		(end 264.9474 -102.87)
		(width 0.0889)
		(layer "In4.Cu")
		(net "M_E_MA<14>")
	)
	(segment
		(start 269.875 -134.7724)
		(end 269.875 -135.3058)
		(width 0.14224)
		(layer "In4.Cu")
		(net "M_E_MA<14>")
	)
	(segment
		(start 262.5725 -96.500188)
		(end 262.577326 -96.508824)
		(width 0.0889)
		(layer "In4.Cu")
		(net "M_E_MA<14>")
	)
	(segment
		(start 267.842238 -124.746512)
		(end 268.092174 -124.996448)
		(width 0.14224)
		(layer "In4.Cu")
		(net "M_E_MA<14>")
	)
	(segment
		(start 264.9474 -102.87)
		(end 265.1252 -103.0478)
		(width 0.0889)
		(layer "In4.Cu")
		(net "M_E_MA<14>")
	)
	(segment
		(start 270.350234 -145.448782)
		(end 270.350234 -145.988278)
		(width 0.14224)
		(layer "In4.Cu")
		(net "M_E_MA<14>")
	)
	(segment
		(start 265.1252 -103.0478)
		(end 265.1252 -103.297736)
		(width 0.0889)
		(layer "In4.Cu")
		(net "M_E_MA<14>")
	)
	(segment
		(start 269.9766 -130.7084)
		(end 269.9766 -131.0894)
		(width 0.14224)
		(layer "In4.Cu")
		(net "M_E_MA<14>")
	)
	(segment
		(start 265.1252 -103.297736)
		(end 265.1252 -122.009662)
		(width 0.14224)
		(layer "In4.Cu")
		(net "M_E_MA<14>")
	)
	(segment
		(start 266.634976 -124.78893)
		(end 267.00099 -125.154944)
		(width 0.14224)
		(layer "In4.Cu")
		(net "M_E_MA<14>")
	)
	(segment
		(start 270.0274 -129.7432)
		(end 269.875 -129.8956)
		(width 0.14224)
		(layer "In4.Cu")
		(net "M_E_MA<14>")
	)
	(segment
		(start 267.688822 -125.842776)
		(end 270.0274 -128.181354)
		(width 0.14224)
		(layer "In4.Cu")
		(net "M_E_MA<14>")
	)
	(segment
		(start 269.909036 -135.339836)
		(end 269.909036 -138.048746)
		(width 0.14224)
		(layer "In4.Cu")
		(net "M_E_MA<14>")
	)
	(segment
		(start 269.909036 -138.048746)
		(end 270.350234 -138.489944)
		(width 0.14224)
		(layer "In4.Cu")
		(net "M_E_MA<14>")
	)
	(segment
		(start 270.350234 -138.489944)
		(end 270.350234 -139.172188)
		(width 0.14224)
		(layer "In4.Cu")
		(net "M_E_MA<14>")
	)
	(segment
		(start 270.759936 -139.58189)
		(end 270.759936 -145.038064)
		(width 0.14224)
		(layer "In4.Cu")
		(net "M_E_MA<14>")
	)
	(arc
		(start 262.5725 -95.909638)
		(mid 262.493278 -96.198756)
		(end 262.56615 -96.48952)
		(width 0.0889)
		(layer "In4.Cu")
		(net "M_E_MA<14>")
	)
	(arc
		(start 262.5725 -96.900238)
		(mid 262.568171 -97.48341)
		(end 263.06653 -97.78619)
		(width 0.0889)
		(layer "In4.Cu")
		(net "M_E_MA<14>")
	)
	(arc
		(start 263.099296 -97.78619)
		(mid 263.375791 -97.911825)
		(end 263.48436 -98.195384)
		(width 0.0889)
		(layer "In4.Cu")
		(net "M_E_MA<14>")
	)
	(arc
		(start 262.577326 -95.518224)
		(mid 262.626081 -95.714576)
		(end 262.5725 -95.909638)
		(width 0.0889)
		(layer "In4.Cu")
		(net "M_E_MA<14>")
	)
	(arc
		(start 262.577326 -96.508824)
		(mid 262.626081 -96.705176)
		(end 262.5725 -96.900238)
		(width 0.0889)
		(layer "In4.Cu")
		(net "M_E_MA<14>")
	)
	(segment
		(start 273.750278 -145.988278)
		(end 273.74977 -145.988786)
		(width 0.1651)
		(layer "F.Cu")
		(net "M_E_MA<13>")
	)
	(segment
		(start 273.74977 -147.27174)
		(end 273.750278 -147.27174)
		(width 0.1651)
		(layer "F.Cu")
		(net "M_E_MA<13>")
	)
	(segment
		(start 262.79729 -96.700086)
		(end 262.22579 -96.700086)
		(width 0.1016)
		(layer "F.Cu")
		(net "M_E_MA<13>")
	)
	(segment
		(start 273.74977 -145.988786)
		(end 273.74977 -147.27174)
		(width 0.1651)
		(layer "F.Cu")
		(net "M_E_MA<13>")
	)
	(via
		(at 262.22579 -96.700086)
		(size 0.508)
		(drill 0.254)
		(layers "F.Cu" "B.Cu")
		(net "M_E_MA<13>")
	)
	(via
		(at 273.750278 -145.988278)
		(size 0.4572)
		(drill 0.2032)
		(layers "F.Cu" "B.Cu")
		(net "M_E_MA<13>")
	)
	(via
		(at 273.750278 -139.172188)
		(size 0.4572)
		(drill 0.2032)
		(layers "F.Cu" "B.Cu")
		(net "M_E_MA<13>")
	)
	(segment
		(start 273.74977 -137.877296)
		(end 273.74977 -139.17168)
		(width 0.1651)
		(layer "B.Cu")
		(net "M_E_MA<13>")
	)
	(segment
		(start 273.750278 -137.877296)
		(end 273.74977 -137.877296)
		(width 0.1651)
		(layer "B.Cu")
		(net "M_E_MA<13>")
	)
	(segment
		(start 273.74977 -139.17168)
		(end 273.750278 -139.172188)
		(width 0.1651)
		(layer "B.Cu")
		(net "M_E_MA<13>")
	)
	(segment
		(start 263.6012 -99.7204)
		(end 263.6012 -100.2284)
		(width 0.14224)
		(layer "In11.Cu")
		(net "M_E_MA<13>")
	)
	(segment
		(start 274.189444 -139.611354)
		(end 274.189444 -141.506956)
		(width 0.14224)
		(layer "In11.Cu")
		(net "M_E_MA<13>")
	)
	(segment
		(start 270.6878 -129.3114)
		(end 270.6878 -129.8448)
		(width 0.14224)
		(layer "In11.Cu")
		(net "M_E_MA<13>")
	)
	(segment
		(start 272.0848 -138.627612)
		(end 273.205702 -138.627612)
		(width 0.14224)
		(layer "In11.Cu")
		(net "M_E_MA<13>")
	)
	(segment
		(start 264.0076 -100.6348)
		(end 264.0076 -102.489)
		(width 0.14224)
		(layer "In11.Cu")
		(net "M_E_MA<13>")
	)
	(segment
		(start 265.471148 -103.952548)
		(end 265.471148 -121.577354)
		(width 0.14224)
		(layer "In11.Cu")
		(net "M_E_MA<13>")
	)
	(segment
		(start 270.759936 -132.490464)
		(end 270.759936 -134.590536)
		(width 0.14224)
		(layer "In11.Cu")
		(net "M_E_MA<13>")
	)
	(segment
		(start 262.6868 -97.4852)
		(end 262.6868 -97.8916)
		(width 0.14224)
		(layer "In11.Cu")
		(net "M_E_MA<13>")
	)
	(segment
		(start 274.189444 -141.506956)
		(end 274.159726 -141.536674)
		(width 0.14224)
		(layer "In11.Cu")
		(net "M_E_MA<13>")
	)
	(segment
		(start 271.892522 -137.062972)
		(end 272.424144 -137.062972)
		(width 0.14224)
		(layer "In11.Cu")
		(net "M_E_MA<13>")
	)
	(segment
		(start 274.159726 -144.289526)
		(end 273.74977 -144.699482)
		(width 0.14224)
		(layer "In11.Cu")
		(net "M_E_MA<13>")
	)
	(segment
		(start 270.8402 -129.9972)
		(end 270.8402 -130.5306)
		(width 0.14224)
		(layer "In11.Cu")
		(net "M_E_MA<13>")
	)
	(segment
		(start 262.6868 -97.8916)
		(end 262.6106 -97.9678)
		(width 0.14224)
		(layer "In11.Cu")
		(net "M_E_MA<13>")
	)
	(segment
		(start 273.74977 -145.98777)
		(end 273.750278 -145.988278)
		(width 0.14224)
		(layer "In11.Cu")
		(net "M_E_MA<13>")
	)
	(segment
		(start 273.205702 -138.627612)
		(end 273.750278 -139.172188)
		(width 0.14224)
		(layer "In11.Cu")
		(net "M_E_MA<13>")
	)
	(segment
		(start 270.8402 -126.946406)
		(end 270.8402 -129.159)
		(width 0.14224)
		(layer "In11.Cu")
		(net "M_E_MA<13>")
	)
	(segment
		(start 270.759936 -134.590536)
		(end 271.394174 -135.224774)
		(width 0.14224)
		(layer "In11.Cu")
		(net "M_E_MA<13>")
	)
	(segment
		(start 272.403316 -137.725912)
		(end 271.795494 -137.725912)
		(width 0.14224)
		(layer "In11.Cu")
		(net "M_E_MA<13>")
	)
	(segment
		(start 262.7376 -98.5266)
		(end 262.7376 -98.8568)
		(width 0.14224)
		(layer "In11.Cu")
		(net "M_E_MA<13>")
	)
	(segment
		(start 271.640554 -136.811004)
		(end 271.892522 -137.062972)
		(width 0.14224)
		(layer "In11.Cu")
		(net "M_E_MA<13>")
	)
	(segment
		(start 262.7376 -98.8568)
		(end 263.6012 -99.7204)
		(width 0.14224)
		(layer "In11.Cu")
		(net "M_E_MA<13>")
	)
	(segment
		(start 271.640554 -137.880852)
		(end 271.640554 -138.183366)
		(width 0.14224)
		(layer "In11.Cu")
		(net "M_E_MA<13>")
	)
	(segment
		(start 272.56867 -137.207498)
		(end 272.56867 -137.560558)
		(width 0.14224)
		(layer "In11.Cu")
		(net "M_E_MA<13>")
	)
	(segment
		(start 262.509 -97.3074)
		(end 262.6868 -97.4852)
		(width 0.14224)
		(layer "In11.Cu")
		(net "M_E_MA<13>")
	)
	(segment
		(start 271.795494 -137.725912)
		(end 271.640554 -137.880852)
		(width 0.14224)
		(layer "In11.Cu")
		(net "M_E_MA<13>")
	)
	(segment
		(start 273.74977 -144.699482)
		(end 273.74977 -145.98777)
		(width 0.14224)
		(layer "In11.Cu")
		(net "M_E_MA<13>")
	)
	(segment
		(start 263.6012 -100.2284)
		(end 264.0076 -100.6348)
		(width 0.14224)
		(layer "In11.Cu")
		(net "M_E_MA<13>")
	)
	(segment
		(start 271.394174 -135.224774)
		(end 271.394174 -135.780018)
		(width 0.14224)
		(layer "In11.Cu")
		(net "M_E_MA<13>")
	)
	(segment
		(start 262.6106 -98.3996)
		(end 262.7376 -98.5266)
		(width 0.14224)
		(layer "In11.Cu")
		(net "M_E_MA<13>")
	)
	(segment
		(start 270.7132 -130.6576)
		(end 270.7132 -131.2164)
		(width 0.14224)
		(layer "In11.Cu")
		(net "M_E_MA<13>")
	)
	(segment
		(start 262.6106 -97.9678)
		(end 262.6106 -98.3996)
		(width 0.14224)
		(layer "In11.Cu")
		(net "M_E_MA<13>")
	)
	(segment
		(start 264.0076 -102.489)
		(end 265.471148 -103.952548)
		(width 0.14224)
		(layer "In11.Cu")
		(net "M_E_MA<13>")
	)
	(segment
		(start 271.394174 -135.780018)
		(end 271.640554 -136.026398)
		(width 0.14224)
		(layer "In11.Cu")
		(net "M_E_MA<13>")
	)
	(segment
		(start 272.424144 -137.062972)
		(end 272.56867 -137.207498)
		(width 0.14224)
		(layer "In11.Cu")
		(net "M_E_MA<13>")
	)
	(segment
		(start 262.22579 -96.700086)
		(end 262.509 -96.983296)
		(width 0.14224)
		(layer "In11.Cu")
		(net "M_E_MA<13>")
	)
	(segment
		(start 271.640554 -138.183366)
		(end 272.0848 -138.627612)
		(width 0.14224)
		(layer "In11.Cu")
		(net "M_E_MA<13>")
	)
	(segment
		(start 270.8402 -130.5306)
		(end 270.7132 -130.6576)
		(width 0.14224)
		(layer "In11.Cu")
		(net "M_E_MA<13>")
	)
	(segment
		(start 265.471148 -121.577354)
		(end 270.8402 -126.946406)
		(width 0.14224)
		(layer "In11.Cu")
		(net "M_E_MA<13>")
	)
	(segment
		(start 274.159726 -141.536674)
		(end 274.159726 -144.289526)
		(width 0.14224)
		(layer "In11.Cu")
		(net "M_E_MA<13>")
	)
	(segment
		(start 270.7132 -131.2164)
		(end 271.032478 -131.535678)
		(width 0.14224)
		(layer "In11.Cu")
		(net "M_E_MA<13>")
	)
	(segment
		(start 271.032478 -132.217922)
		(end 270.759936 -132.490464)
		(width 0.14224)
		(layer "In11.Cu")
		(net "M_E_MA<13>")
	)
	(segment
		(start 262.509 -96.983296)
		(end 262.509 -97.3074)
		(width 0.14224)
		(layer "In11.Cu")
		(net "M_E_MA<13>")
	)
	(segment
		(start 271.640554 -136.026398)
		(end 271.640554 -136.811004)
		(width 0.14224)
		(layer "In11.Cu")
		(net "M_E_MA<13>")
	)
	(segment
		(start 273.750278 -139.172188)
		(end 274.189444 -139.611354)
		(width 0.14224)
		(layer "In11.Cu")
		(net "M_E_MA<13>")
	)
	(segment
		(start 270.8402 -129.159)
		(end 270.6878 -129.3114)
		(width 0.14224)
		(layer "In11.Cu")
		(net "M_E_MA<13>")
	)
	(segment
		(start 272.56867 -137.560558)
		(end 272.403316 -137.725912)
		(width 0.14224)
		(layer "In11.Cu")
		(net "M_E_MA<13>")
	)
	(segment
		(start 271.032478 -131.535678)
		(end 271.032478 -132.217922)
		(width 0.14224)
		(layer "In11.Cu")
		(net "M_E_MA<13>")
	)
	(segment
		(start 270.6878 -129.8448)
		(end 270.8402 -129.9972)
		(width 0.14224)
		(layer "In11.Cu")
		(net "M_E_MA<13>")
	)
	(segment
		(start 249.099832 -142.677642)
		(end 249.099832 -143.970756)
		(width 0.1651)
		(layer "F.Cu")
		(net "M_E_MA<12>")
	)
	(segment
		(start 255.07061 -95.21444)
		(end 254.49911 -95.21444)
		(width 0.1016)
		(layer "F.Cu")
		(net "M_E_MA<12>")
	)
	(segment
		(start 249.10034 -142.6718)
		(end 249.099832 -142.677642)
		(width 0.1651)
		(layer "F.Cu")
		(net "M_E_MA<12>")
	)
	(via
		(at 249.099832 -143.970756)
		(size 0.4572)
		(drill 0.2032)
		(layers "F.Cu" "B.Cu")
		(net "M_E_MA<12>")
	)
	(via
		(at 254.49911 -95.21444)
		(size 0.508)
		(drill 0.254)
		(layers "F.Cu" "B.Cu")
		(net "M_E_MA<12>")
	)
	(via
		(at 249.099832 -141.187678)
		(size 0.4572)
		(drill 0.2032)
		(layers "F.Cu" "B.Cu")
		(net "M_E_MA<12>")
	)
	(segment
		(start 249.099832 -142.476982)
		(end 249.099832 -141.187678)
		(width 0.1651)
		(layer "B.Cu")
		(net "M_E_MA<12>")
	)
	(segment
		(start 249.10034 -142.477236)
		(end 249.099832 -142.476982)
		(width 0.1651)
		(layer "B.Cu")
		(net "M_E_MA<12>")
	)
	(segment
		(start 254.959104 -100.731066)
		(end 254.959104 -102.686104)
		(width 0.0889)
		(layer "In11.Cu")
		(net "M_E_MA<12>")
	)
	(segment
		(start 252.1204 -131.9276)
		(end 252.0696 -131.9784)
		(width 0.14224)
		(layer "In11.Cu")
		(net "M_E_MA<12>")
	)
	(segment
		(start 251.212604 -136.035796)
		(end 251.212604 -136.821164)
		(width 0.14224)
		(layer "In11.Cu")
		(net "M_E_MA<12>")
	)
	(segment
		(start 254.49911 -95.21444)
		(end 254.168656 -95.977964)
		(width 0.0889)
		(layer "In11.Cu")
		(net "M_E_MA<12>")
	)
	(segment
		(start 251.46 -135.7884)
		(end 251.212604 -136.035796)
		(width 0.14224)
		(layer "In11.Cu")
		(net "M_E_MA<12>")
	)
	(segment
		(start 252.476 -126.5682)
		(end 252.476 -128.778)
		(width 0.14224)
		(layer "In11.Cu")
		(net "M_E_MA<12>")
	)
	(segment
		(start 255.311148 -103.586534)
		(end 255.311148 -123.733052)
		(width 0.14224)
		(layer "In11.Cu")
		(net "M_E_MA<12>")
	)
	(segment
		(start 252.1458 -130.5306)
		(end 252.0188 -130.6576)
		(width 0.14224)
		(layer "In11.Cu")
		(net "M_E_MA<12>")
	)
	(segment
		(start 248.663714 -140.75156)
		(end 249.099832 -141.187678)
		(width 0.14224)
		(layer "In11.Cu")
		(net "M_E_MA<12>")
	)
	(segment
		(start 251.212604 -136.821164)
		(end 250.026424 -138.007344)
		(width 0.14224)
		(layer "In11.Cu")
		(net "M_E_MA<12>")
	)
	(segment
		(start 255.311148 -123.733052)
		(end 252.476 -126.5682)
		(width 0.14224)
		(layer "In11.Cu")
		(net "M_E_MA<12>")
	)
	(segment
		(start 252.0188 -130.6576)
		(end 252.0188 -131.2164)
		(width 0.14224)
		(layer "In11.Cu")
		(net "M_E_MA<12>")
	)
	(segment
		(start 254.959104 -102.686104)
		(end 255.311148 -103.038148)
		(width 0.0889)
		(layer "In11.Cu")
		(net "M_E_MA<12>")
	)
	(segment
		(start 252.0696 -135.079232)
		(end 251.46 -135.688832)
		(width 0.14224)
		(layer "In11.Cu")
		(net "M_E_MA<12>")
	)
	(segment
		(start 248.663714 -138.897614)
		(end 248.663714 -140.75156)
		(width 0.14224)
		(layer "In11.Cu")
		(net "M_E_MA<12>")
	)
	(segment
		(start 251.46 -135.688832)
		(end 251.46 -135.7884)
		(width 0.14224)
		(layer "In11.Cu")
		(net "M_E_MA<12>")
	)
	(segment
		(start 249.099832 -141.187678)
		(end 249.099832 -143.970756)
		(width 0.14224)
		(layer "In11.Cu")
		(net "M_E_MA<12>")
	)
	(segment
		(start 252.1204 -131.318)
		(end 252.1204 -131.9276)
		(width 0.14224)
		(layer "In11.Cu")
		(net "M_E_MA<12>")
	)
	(segment
		(start 252.1458 -129.9718)
		(end 252.1458 -130.5306)
		(width 0.14224)
		(layer "In11.Cu")
		(net "M_E_MA<12>")
	)
	(segment
		(start 252.0188 -129.8448)
		(end 252.1458 -129.9718)
		(width 0.14224)
		(layer "In11.Cu")
		(net "M_E_MA<12>")
	)
	(segment
		(start 255.311148 -103.038148)
		(end 255.311148 -103.586534)
		(width 0.0889)
		(layer "In11.Cu")
		(net "M_E_MA<12>")
	)
	(segment
		(start 254.349504 -100.121466)
		(end 254.959104 -100.731066)
		(width 0.0889)
		(layer "In11.Cu")
		(net "M_E_MA<12>")
	)
	(segment
		(start 249.553984 -138.007344)
		(end 248.663714 -138.897614)
		(width 0.14224)
		(layer "In11.Cu")
		(net "M_E_MA<12>")
	)
	(segment
		(start 254.349504 -98.728276)
		(end 254.349504 -100.121466)
		(width 0.0889)
		(layer "In11.Cu")
		(net "M_E_MA<12>")
	)
	(segment
		(start 254.152654 -97.395538)
		(end 254.161544 -97.410778)
		(width 0.0889)
		(layer "In11.Cu")
		(net "M_E_MA<12>")
	)
	(segment
		(start 252.0188 -131.2164)
		(end 252.1204 -131.318)
		(width 0.14224)
		(layer "In11.Cu")
		(net "M_E_MA<12>")
	)
	(segment
		(start 254.168656 -95.977964)
		(end 254.152654 -96.005142)
		(width 0.0889)
		(layer "In11.Cu")
		(net "M_E_MA<12>")
	)
	(segment
		(start 252.0696 -131.9784)
		(end 252.0696 -135.079232)
		(width 0.14224)
		(layer "In11.Cu")
		(net "M_E_MA<12>")
	)
	(segment
		(start 250.026424 -138.007344)
		(end 249.553984 -138.007344)
		(width 0.14224)
		(layer "In11.Cu")
		(net "M_E_MA<12>")
	)
	(segment
		(start 254.152654 -96.404938)
		(end 254.161544 -96.420178)
		(width 0.0889)
		(layer "In11.Cu")
		(net "M_E_MA<12>")
	)
	(segment
		(start 252.476 -128.778)
		(end 252.0188 -129.2352)
		(width 0.14224)
		(layer "In11.Cu")
		(net "M_E_MA<12>")
	)
	(segment
		(start 252.0188 -129.2352)
		(end 252.0188 -129.8448)
		(width 0.14224)
		(layer "In11.Cu")
		(net "M_E_MA<12>")
	)
	(arc
		(start 254.152654 -96.005142)
		(mid 254.099121 -96.20504)
		(end 254.152654 -96.404938)
		(width 0.0889)
		(layer "In11.Cu")
		(net "M_E_MA<12>")
	)
	(arc
		(start 254.161544 -97.410778)
		(mid 254.231941 -97.699729)
		(end 254.152654 -97.986342)
		(width 0.0889)
		(layer "In11.Cu")
		(net "M_E_MA<12>")
	)
	(arc
		(start 254.152654 -98.386138)
		(mid 254.251184 -98.557147)
		(end 254.349504 -98.728276)
		(width 0.0889)
		(layer "In11.Cu")
		(net "M_E_MA<12>")
	)
	(arc
		(start 254.152654 -97.986342)
		(mid 254.099121 -98.18624)
		(end 254.152654 -98.386138)
		(width 0.0889)
		(layer "In11.Cu")
		(net "M_E_MA<12>")
	)
	(arc
		(start 254.152654 -96.995742)
		(mid 254.099121 -97.19564)
		(end 254.152654 -97.395538)
		(width 0.0889)
		(layer "In11.Cu")
		(net "M_E_MA<12>")
	)
	(arc
		(start 254.161544 -96.420178)
		(mid 254.231941 -96.709129)
		(end 254.152654 -96.995742)
		(width 0.0889)
		(layer "In11.Cu")
		(net "M_E_MA<12>")
	)
	(segment
		(start 249.94997 -147.27174)
		(end 249.94997 -145.988278)
		(width 0.1651)
		(layer "F.Cu")
		(net "M_E_MA<11>")
	)
	(segment
		(start 249.950478 -147.27174)
		(end 249.94997 -147.27174)
		(width 0.1651)
		(layer "F.Cu")
		(net "M_E_MA<11>")
	)
	(segment
		(start 255.07061 -96.20504)
		(end 254.49911 -96.20504)
		(width 0.1016)
		(layer "F.Cu")
		(net "M_E_MA<11>")
	)
	(via
		(at 249.94997 -145.988278)
		(size 0.4572)
		(drill 0.2032)
		(layers "F.Cu" "B.Cu")
		(net "M_E_MA<11>")
	)
	(via
		(at 254.49911 -96.20504)
		(size 0.508)
		(drill 0.254)
		(layers "F.Cu" "B.Cu")
		(net "M_E_MA<11>")
	)
	(via
		(at 249.949716 -139.170156)
		(size 0.4572)
		(drill 0.2032)
		(layers "F.Cu" "B.Cu")
		(net "M_E_MA<11>")
	)
	(segment
		(start 249.950478 -137.877296)
		(end 249.94997 -137.877296)
		(width 0.1651)
		(layer "B.Cu")
		(net "M_E_MA<11>")
	)
	(segment
		(start 249.94997 -137.877296)
		(end 249.94997 -139.169902)
		(width 0.1651)
		(layer "B.Cu")
		(net "M_E_MA<11>")
	)
	(segment
		(start 249.94997 -139.169902)
		(end 249.949716 -139.170156)
		(width 0.1651)
		(layer "B.Cu")
		(net "M_E_MA<11>")
	)
	(segment
		(start 254.315468 -126.44882)
		(end 253.992888 -126.12624)
		(width 0.14224)
		(layer "In11.Cu")
		(net "M_E_MA<11>")
	)
	(segment
		(start 253.0856 -129.3876)
		(end 252.9332 -129.2352)
		(width 0.14224)
		(layer "In11.Cu")
		(net "M_E_MA<11>")
	)
	(segment
		(start 252.7046 -134.9248)
		(end 252.910848 -134.718552)
		(width 0.14224)
		(layer "In11.Cu")
		(net "M_E_MA<11>")
	)
	(segment
		(start 255.819148 -103.562658)
		(end 255.819148 -103.215948)
		(width 0.0889)
		(layer "In11.Cu")
		(net "M_E_MA<11>")
	)
	(segment
		(start 252.9332 -128.727962)
		(end 253.08814 -128.573022)
		(width 0.14224)
		(layer "In11.Cu")
		(net "M_E_MA<11>")
	)
	(segment
		(start 252.910848 -134.718552)
		(end 252.910848 -131.289552)
		(width 0.14224)
		(layer "In11.Cu")
		(net "M_E_MA<11>")
	)
	(segment
		(start 249.949716 -139.170156)
		(end 252.084586 -137.035286)
		(width 0.14224)
		(layer "In11.Cu")
		(net "M_E_MA<11>")
	)
	(segment
		(start 249.35815 -139.761722)
		(end 249.949716 -139.170156)
		(width 0.14224)
		(layer "In11.Cu")
		(net "M_E_MA<11>")
	)
	(segment
		(start 252.866398 -130.514598)
		(end 252.866398 -129.962402)
		(width 0.14224)
		(layer "In11.Cu")
		(net "M_E_MA<11>")
	)
	(segment
		(start 255.819148 -124.012452)
		(end 255.819148 -103.562658)
		(width 0.14224)
		(layer "In11.Cu")
		(net "M_E_MA<11>")
	)
	(segment
		(start 252.866398 -129.962402)
		(end 253.0856 -129.7432)
		(width 0.14224)
		(layer "In11.Cu")
		(net "M_E_MA<11>")
	)
	(segment
		(start 252.084586 -135.798814)
		(end 252.7046 -135.1788)
		(width 0.14224)
		(layer "In11.Cu")
		(net "M_E_MA<11>")
	)
	(segment
		(start 253.0856 -129.7432)
		(end 253.0856 -129.3876)
		(width 0.14224)
		(layer "In11.Cu")
		(net "M_E_MA<11>")
	)
	(segment
		(start 253.008892 -130.657092)
		(end 252.866398 -130.514598)
		(width 0.14224)
		(layer "In11.Cu")
		(net "M_E_MA<11>")
	)
	(segment
		(start 253.459996 -126.742952)
		(end 253.765304 -127.04826)
		(width 0.14224)
		(layer "In11.Cu")
		(net "M_E_MA<11>")
	)
	(segment
		(start 254.650494 -98.725482)
		(end 254.850646 -98.377502)
		(width 0.0889)
		(layer "In11.Cu")
		(net "M_E_MA<11>")
	)
	(segment
		(start 249.46991 -145.508218)
		(end 249.46991 -144.25549)
		(width 0.14224)
		(layer "In11.Cu")
		(net "M_E_MA<11>")
	)
	(segment
		(start 252.9332 -127.755142)
		(end 252.9332 -126.952756)
		(width 0.14224)
		(layer "In11.Cu")
		(net "M_E_MA<11>")
	)
	(segment
		(start 253.613412 -128.408176)
		(end 253.613412 -128.055116)
		(width 0.14224)
		(layer "In11.Cu")
		(net "M_E_MA<11>")
	)
	(segment
		(start 254.028194 -127.04826)
		(end 254.315468 -126.760986)
		(width 0.14224)
		(layer "In11.Cu")
		(net "M_E_MA<11>")
	)
	(segment
		(start 253.765304 -127.04826)
		(end 254.028194 -127.04826)
		(width 0.14224)
		(layer "In11.Cu")
		(net "M_E_MA<11>")
	)
	(segment
		(start 254.83947 -97.406206)
		(end 254.84582 -97.395538)
		(width 0.0889)
		(layer "In11.Cu")
		(net "M_E_MA<11>")
	)
	(segment
		(start 252.9332 -129.2352)
		(end 252.9332 -128.727962)
		(width 0.14224)
		(layer "In11.Cu")
		(net "M_E_MA<11>")
	)
	(segment
		(start 249.35815 -140.776452)
		(end 249.35815 -139.761722)
		(width 0.14224)
		(layer "In11.Cu")
		(net "M_E_MA<11>")
	)
	(segment
		(start 249.94997 -145.988278)
		(end 249.46991 -145.508218)
		(width 0.14224)
		(layer "In11.Cu")
		(net "M_E_MA<11>")
	)
	(segment
		(start 253.992888 -125.838712)
		(end 255.819148 -124.012452)
		(width 0.14224)
		(layer "In11.Cu")
		(net "M_E_MA<11>")
	)
	(segment
		(start 249.5296 -140.947902)
		(end 249.35815 -140.776452)
		(width 0.14224)
		(layer "In11.Cu")
		(net "M_E_MA<11>")
	)
	(segment
		(start 254.84582 -97.395538)
		(end 254.850646 -97.386902)
		(width 0.0889)
		(layer "In11.Cu")
		(net "M_E_MA<11>")
	)
	(segment
		(start 252.084586 -137.035286)
		(end 252.084586 -135.798814)
		(width 0.14224)
		(layer "In11.Cu")
		(net "M_E_MA<11>")
	)
	(segment
		(start 249.5296 -144.1958)
		(end 249.5296 -140.947902)
		(width 0.14224)
		(layer "In11.Cu")
		(net "M_E_MA<11>")
	)
	(segment
		(start 254.315468 -126.760986)
		(end 254.315468 -126.44882)
		(width 0.14224)
		(layer "In11.Cu")
		(net "M_E_MA<11>")
	)
	(segment
		(start 253.08814 -128.573022)
		(end 253.448566 -128.573022)
		(width 0.14224)
		(layer "In11.Cu")
		(net "M_E_MA<11>")
	)
	(segment
		(start 254.650494 -100.00361)
		(end 254.650494 -98.725482)
		(width 0.0889)
		(layer "In11.Cu")
		(net "M_E_MA<11>")
	)
	(segment
		(start 249.46991 -144.25549)
		(end 249.5296 -144.1958)
		(width 0.14224)
		(layer "In11.Cu")
		(net "M_E_MA<11>")
	)
	(segment
		(start 253.448566 -128.573022)
		(end 253.613412 -128.408176)
		(width 0.14224)
		(layer "In11.Cu")
		(net "M_E_MA<11>")
	)
	(segment
		(start 253.08814 -127.910082)
		(end 252.9332 -127.755142)
		(width 0.14224)
		(layer "In11.Cu")
		(net "M_E_MA<11>")
	)
	(segment
		(start 255.251204 -102.648004)
		(end 255.251204 -100.60432)
		(width 0.0889)
		(layer "In11.Cu")
		(net "M_E_MA<11>")
	)
	(segment
		(start 255.251204 -100.60432)
		(end 254.650494 -100.00361)
		(width 0.0889)
		(layer "In11.Cu")
		(net "M_E_MA<11>")
	)
	(segment
		(start 253.992888 -126.12624)
		(end 253.992888 -125.838712)
		(width 0.14224)
		(layer "In11.Cu")
		(net "M_E_MA<11>")
	)
	(segment
		(start 252.9332 -126.952756)
		(end 253.143004 -126.742952)
		(width 0.14224)
		(layer "In11.Cu")
		(net "M_E_MA<11>")
	)
	(segment
		(start 255.819148 -103.215948)
		(end 255.251204 -102.648004)
		(width 0.0889)
		(layer "In11.Cu")
		(net "M_E_MA<11>")
	)
	(segment
		(start 253.613412 -128.055116)
		(end 253.468378 -127.910082)
		(width 0.14224)
		(layer "In11.Cu")
		(net "M_E_MA<11>")
	)
	(segment
		(start 253.008892 -131.191508)
		(end 253.008892 -130.657092)
		(width 0.14224)
		(layer "In11.Cu")
		(net "M_E_MA<11>")
	)
	(segment
		(start 253.143004 -126.742952)
		(end 253.459996 -126.742952)
		(width 0.14224)
		(layer "In11.Cu")
		(net "M_E_MA<11>")
	)
	(segment
		(start 253.468378 -127.910082)
		(end 253.08814 -127.910082)
		(width 0.14224)
		(layer "In11.Cu")
		(net "M_E_MA<11>")
	)
	(segment
		(start 252.910848 -131.289552)
		(end 253.008892 -131.191508)
		(width 0.14224)
		(layer "In11.Cu")
		(net "M_E_MA<11>")
	)
	(segment
		(start 252.7046 -135.1788)
		(end 252.7046 -134.9248)
		(width 0.14224)
		(layer "In11.Cu")
		(net "M_E_MA<11>")
	)
	(arc
		(start 254.84582 -97.986088)
		(mid 254.766598 -97.69697)
		(end 254.83947 -97.406206)
		(width 0.0889)
		(layer "In11.Cu")
		(net "M_E_MA<11>")
	)
	(arc
		(start 254.850646 -97.386902)
		(mid 254.899401 -97.19055)
		(end 254.84582 -96.995488)
		(width 0.0889)
		(layer "In11.Cu")
		(net "M_E_MA<11>")
	)
	(arc
		(start 254.850646 -98.377502)
		(mid 254.899401 -98.18115)
		(end 254.84582 -97.986088)
		(width 0.0889)
		(layer "In11.Cu")
		(net "M_E_MA<11>")
	)
	(arc
		(start 254.84582 -96.995488)
		(mid 254.650782 -96.609775)
		(end 254.49911 -96.20504)
		(width 0.0889)
		(layer "In11.Cu")
		(net "M_E_MA<11>")
	)
	(segment
		(start 267.800074 -145.988278)
		(end 267.800074 -146.013678)
		(width 0.1651)
		(layer "F.Cu")
		(net "M_E_MA<10>")
	)
	(segment
		(start 267.79982 -147.27174)
		(end 267.800328 -147.27174)
		(width 0.1651)
		(layer "F.Cu")
		(net "M_E_MA<10>")
	)
	(segment
		(start 267.800074 -146.013678)
		(end 267.79982 -146.013932)
		(width 0.1651)
		(layer "F.Cu")
		(net "M_E_MA<10>")
	)
	(segment
		(start 259.36321 -96.700086)
		(end 258.79171 -96.700086)
		(width 0.1016)
		(layer "F.Cu")
		(net "M_E_MA<10>")
	)
	(segment
		(start 267.79982 -146.013932)
		(end 267.79982 -147.27174)
		(width 0.1651)
		(layer "F.Cu")
		(net "M_E_MA<10>")
	)
	(via
		(at 267.800074 -145.988278)
		(size 0.4572)
		(drill 0.2032)
		(layers "F.Cu" "B.Cu")
		(net "M_E_MA<10>")
	)
	(via
		(at 258.79171 -96.700086)
		(size 0.508)
		(drill 0.254)
		(layers "F.Cu" "B.Cu")
		(net "M_E_MA<10>")
	)
	(via
		(at 267.800074 -139.172188)
		(size 0.4572)
		(drill 0.2032)
		(layers "F.Cu" "B.Cu")
		(net "M_E_MA<10>")
	)
	(segment
		(start 267.800328 -137.877296)
		(end 267.79982 -137.877296)
		(width 0.1651)
		(layer "B.Cu")
		(net "M_E_MA<10>")
	)
	(segment
		(start 267.79982 -139.171934)
		(end 267.800074 -139.172188)
		(width 0.1651)
		(layer "B.Cu")
		(net "M_E_MA<10>")
	)
	(segment
		(start 267.79982 -137.877296)
		(end 267.79982 -139.171934)
		(width 0.1651)
		(layer "B.Cu")
		(net "M_E_MA<10>")
	)
	(segment
		(start 265.66241 -130.57759)
		(end 265.66241 -135.243316)
		(width 0.14224)
		(layer "In11.Cu")
		(net "M_E_MA<10>")
	)
	(segment
		(start 267.800074 -139.911836)
		(end 267.390118 -140.321792)
		(width 0.14224)
		(layer "In11.Cu")
		(net "M_E_MA<10>")
	)
	(segment
		(start 267.390118 -144.25676)
		(end 267.800074 -144.666716)
		(width 0.14224)
		(layer "In11.Cu")
		(net "M_E_MA<10>")
	)
	(segment
		(start 259.1562 -97.3582)
		(end 259.315458 -97.517458)
		(width 0.0889)
		(layer "In11.Cu")
		(net "M_E_MA<10>")
	)
	(segment
		(start 259.298694 -98.377502)
		(end 259.30352 -98.386138)
		(width 0.0889)
		(layer "In11.Cu")
		(net "M_E_MA<10>")
	)
	(segment
		(start 265.7856 -130.048)
		(end 265.7856 -130.4544)
		(width 0.14224)
		(layer "In11.Cu")
		(net "M_E_MA<10>")
	)
	(segment
		(start 259.1562 -97.064576)
		(end 259.1562 -97.3582)
		(width 0.0889)
		(layer "In11.Cu")
		(net "M_E_MA<10>")
	)
	(segment
		(start 261.6962 -102.0064)
		(end 261.6962 -103.1748)
		(width 0.0889)
		(layer "In11.Cu")
		(net "M_E_MA<10>")
	)
	(segment
		(start 265.66241 -135.243316)
		(end 266.53363 -136.114536)
		(width 0.14224)
		(layer "In11.Cu")
		(net "M_E_MA<10>")
	)
	(segment
		(start 266.53363 -136.114536)
		(end 266.53363 -137.905744)
		(width 0.14224)
		(layer "In11.Cu")
		(net "M_E_MA<10>")
	)
	(segment
		(start 261.508748 -104.319324)
		(end 261.508748 -125.491748)
		(width 0.14224)
		(layer "In11.Cu")
		(net "M_E_MA<10>")
	)
	(segment
		(start 264.199116 -128.182116)
		(end 264.199116 -128.461516)
		(width 0.14224)
		(layer "In11.Cu")
		(net "M_E_MA<10>")
	)
	(segment
		(start 266.53363 -137.905744)
		(end 267.800074 -139.172188)
		(width 0.14224)
		(layer "In11.Cu")
		(net "M_E_MA<10>")
	)
	(segment
		(start 259.461 -99.7712)
		(end 261.6962 -102.0064)
		(width 0.0889)
		(layer "In11.Cu")
		(net "M_E_MA<10>")
	)
	(segment
		(start 261.6962 -103.1748)
		(end 261.508748 -103.362252)
		(width 0.0889)
		(layer "In11.Cu")
		(net "M_E_MA<10>")
	)
	(segment
		(start 267.390118 -140.321792)
		(end 267.390118 -144.25676)
		(width 0.14224)
		(layer "In11.Cu")
		(net "M_E_MA<10>")
	)
	(segment
		(start 267.800074 -139.172188)
		(end 267.800074 -139.911836)
		(width 0.14224)
		(layer "In11.Cu")
		(net "M_E_MA<10>")
	)
	(segment
		(start 259.315458 -97.517458)
		(end 259.315458 -97.941638)
		(width 0.0889)
		(layer "In11.Cu")
		(net "M_E_MA<10>")
	)
	(segment
		(start 261.508748 -103.362252)
		(end 261.508748 -104.319324)
		(width 0.0889)
		(layer "In11.Cu")
		(net "M_E_MA<10>")
	)
	(segment
		(start 267.800074 -144.666716)
		(end 267.800074 -145.988278)
		(width 0.14224)
		(layer "In11.Cu")
		(net "M_E_MA<10>")
	)
	(segment
		(start 264.199116 -128.461516)
		(end 265.7856 -130.048)
		(width 0.14224)
		(layer "In11.Cu")
		(net "M_E_MA<10>")
	)
	(segment
		(start 258.79171 -96.700086)
		(end 259.1562 -97.064576)
		(width 0.0889)
		(layer "In11.Cu")
		(net "M_E_MA<10>")
	)
	(segment
		(start 265.7856 -130.4544)
		(end 265.66241 -130.57759)
		(width 0.14224)
		(layer "In11.Cu")
		(net "M_E_MA<10>")
	)
	(segment
		(start 259.461 -99.568)
		(end 259.461 -99.7712)
		(width 0.0889)
		(layer "In11.Cu")
		(net "M_E_MA<10>")
	)
	(segment
		(start 259.30352 -98.386138)
		(end 259.30987 -98.396806)
		(width 0.0889)
		(layer "In11.Cu")
		(net "M_E_MA<10>")
	)
	(segment
		(start 261.508748 -125.491748)
		(end 264.199116 -128.182116)
		(width 0.14224)
		(layer "In11.Cu")
		(net "M_E_MA<10>")
	)
	(arc
		(start 259.30352 -98.976688)
		(mid 259.25005 -99.171751)
		(end 259.298694 -99.368102)
		(width 0.0889)
		(layer "In11.Cu")
		(net "M_E_MA<10>")
	)
	(arc
		(start 259.298694 -99.368102)
		(mid 259.370683 -99.475489)
		(end 259.461 -99.568)
		(width 0.0889)
		(layer "In11.Cu")
		(net "M_E_MA<10>")
	)
	(arc
		(start 259.30352 -97.986088)
		(mid 259.25005 -98.181151)
		(end 259.298694 -98.377502)
		(width 0.0889)
		(layer "In11.Cu")
		(net "M_E_MA<10>")
	)
	(arc
		(start 259.30987 -98.396806)
		(mid 259.382668 -98.687569)
		(end 259.30352 -98.976688)
		(width 0.0889)
		(layer "In11.Cu")
		(net "M_E_MA<10>")
	)
	(arc
		(start 259.315458 -97.941638)
		(mid 259.312435 -97.964658)
		(end 259.30352 -97.986088)
		(width 0.0889)
		(layer "In11.Cu")
		(net "M_E_MA<10>")
	)
	(segment
		(start 261.93877 -98.18624)
		(end 261.36727 -98.18624)
		(width 0.1016)
		(layer "F.Cu")
		(net "M_E_MA<0>")
	)
	(segment
		(start 266.100306 -142.6718)
		(end 266.099798 -142.677642)
		(width 0.1651)
		(layer "F.Cu")
		(net "M_E_MA<0>")
	)
	(segment
		(start 266.099798 -142.677642)
		(end 266.099798 -143.968978)
		(width 0.1651)
		(layer "F.Cu")
		(net "M_E_MA<0>")
	)
	(via
		(at 266.099798 -141.183868)
		(size 0.4572)
		(drill 0.2032)
		(layers "F.Cu" "B.Cu")
		(net "M_E_MA<0>")
	)
	(via
		(at 261.36727 -98.18624)
		(size 0.508)
		(drill 0.254)
		(layers "F.Cu" "B.Cu")
		(net "M_E_MA<0>")
	)
	(via
		(at 266.099798 -143.968978)
		(size 0.508)
		(drill 0.254)
		(layers "F.Cu" "B.Cu")
		(net "M_E_MA<0>")
	)
	(segment
		(start 266.100306 -142.477236)
		(end 266.099798 -142.476982)
		(width 0.1651)
		(layer "B.Cu")
		(net "M_E_MA<0>")
	)
	(segment
		(start 266.099798 -142.476982)
		(end 266.099798 -141.183868)
		(width 0.1651)
		(layer "B.Cu")
		(net "M_E_MA<0>")
	)
	(segment
		(start 265.487912 -127.52324)
		(end 264.860786 -128.150366)
		(width 0.14224)
		(layer "In4.Cu")
		(net "M_E_MA<0>")
	)
	(segment
		(start 263.164066 -126.398274)
		(end 263.763506 -125.798834)
		(width 0.14224)
		(layer "In4.Cu")
		(net "M_E_MA<0>")
	)
	(segment
		(start 262.922766 -126.398274)
		(end 263.164066 -126.398274)
		(width 0.14224)
		(layer "In4.Cu")
		(net "M_E_MA<0>")
	)
	(segment
		(start 265.487912 -127.235712)
		(end 265.487912 -127.52324)
		(width 0.14224)
		(layer "In4.Cu")
		(net "M_E_MA<0>")
	)
	(segment
		(start 265.415014 -131.490974)
		(end 265.664188 -131.740148)
		(width 0.14224)
		(layer "In4.Cu")
		(net "M_E_MA<0>")
	)
	(segment
		(start 264.91311 -126.948438)
		(end 265.200638 -126.948438)
		(width 0.14224)
		(layer "In4.Cu")
		(net "M_E_MA<0>")
	)
	(segment
		(start 265.837924 -130.452876)
		(end 265.415014 -130.875786)
		(width 0.14224)
		(layer "In4.Cu")
		(net "M_E_MA<0>")
	)
	(segment
		(start 261.3152 -100.129594)
		(end 261.3152 -101.423216)
		(width 0.0889)
		(layer "In4.Cu")
		(net "M_E_MA<0>")
	)
	(segment
		(start 264.051034 -125.798834)
		(end 264.338308 -126.086108)
		(width 0.14224)
		(layer "In4.Cu")
		(net "M_E_MA<0>")
	)
	(segment
		(start 264.860786 -128.150366)
		(end 264.860786 -128.437894)
		(width 0.14224)
		(layer "In4.Cu")
		(net "M_E_MA<0>")
	)
	(segment
		(start 264.338308 -126.086108)
		(end 264.338308 -126.373636)
		(width 0.14224)
		(layer "In4.Cu")
		(net "M_E_MA<0>")
	)
	(segment
		(start 265.733022 -134.61873)
		(end 265.733022 -135.307578)
		(width 0.14224)
		(layer "In4.Cu")
		(net "M_E_MA<0>")
	)
	(segment
		(start 265.642598 -139.462002)
		(end 266.099798 -139.919202)
		(width 0.14224)
		(layer "In4.Cu")
		(net "M_E_MA<0>")
	)
	(segment
		(start 262.5852 -126.060708)
		(end 262.922766 -126.398274)
		(width 0.14224)
		(layer "In4.Cu")
		(net "M_E_MA<0>")
	)
	(segment
		(start 263.733788 -126.978156)
		(end 263.733788 -127.157988)
		(width 0.14224)
		(layer "In4.Cu")
		(net "M_E_MA<0>")
	)
	(segment
		(start 265.200638 -126.948438)
		(end 265.487912 -127.235712)
		(width 0.14224)
		(layer "In4.Cu")
		(net "M_E_MA<0>")
	)
	(segment
		(start 265.664188 -134.549896)
		(end 265.733022 -134.61873)
		(width 0.14224)
		(layer "In4.Cu")
		(net "M_E_MA<0>")
	)
	(segment
		(start 263.104376 -124.765308)
		(end 263.104376 -125.258576)
		(width 0.14224)
		(layer "In4.Cu")
		(net "M_E_MA<0>")
	)
	(segment
		(start 263.763506 -125.798834)
		(end 264.051034 -125.798834)
		(width 0.14224)
		(layer "In4.Cu")
		(net "M_E_MA<0>")
	)
	(segment
		(start 264.338308 -126.373636)
		(end 263.733788 -126.978156)
		(width 0.14224)
		(layer "In4.Cu")
		(net "M_E_MA<0>")
	)
	(segment
		(start 264.128758 -127.552958)
		(end 264.30859 -127.552958)
		(width 0.14224)
		(layer "In4.Cu")
		(net "M_E_MA<0>")
	)
	(segment
		(start 265.733022 -135.307578)
		(end 265.665966 -135.374634)
		(width 0.14224)
		(layer "In4.Cu")
		(net "M_E_MA<0>")
	)
	(segment
		(start 262.5852 -124.246132)
		(end 263.104376 -124.765308)
		(width 0.14224)
		(layer "In4.Cu")
		(net "M_E_MA<0>")
	)
	(segment
		(start 262.5852 -125.777752)
		(end 262.5852 -126.060708)
		(width 0.14224)
		(layer "In4.Cu")
		(net "M_E_MA<0>")
	)
	(segment
		(start 262.5852 -102.693216)
		(end 262.5852 -103.310436)
		(width 0.0889)
		(layer "In4.Cu")
		(net "M_E_MA<0>")
	)
	(segment
		(start 265.642598 -138.951462)
		(end 265.642598 -139.462002)
		(width 0.14224)
		(layer "In4.Cu")
		(net "M_E_MA<0>")
	)
	(segment
		(start 262.5852 -103.310436)
		(end 262.5852 -124.246132)
		(width 0.14224)
		(layer "In4.Cu")
		(net "M_E_MA<0>")
	)
	(segment
		(start 266.099798 -139.919202)
		(end 266.099798 -141.183868)
		(width 0.14224)
		(layer "In4.Cu")
		(net "M_E_MA<0>")
	)
	(segment
		(start 261.3152 -101.423216)
		(end 262.5852 -102.693216)
		(width 0.0889)
		(layer "In4.Cu")
		(net "M_E_MA<0>")
	)
	(segment
		(start 265.664188 -131.740148)
		(end 265.664188 -134.549896)
		(width 0.14224)
		(layer "In4.Cu")
		(net "M_E_MA<0>")
	)
	(segment
		(start 264.30859 -127.552958)
		(end 264.91311 -126.948438)
		(width 0.14224)
		(layer "In4.Cu")
		(net "M_E_MA<0>")
	)
	(segment
		(start 265.415014 -130.875786)
		(end 265.415014 -131.490974)
		(width 0.14224)
		(layer "In4.Cu")
		(net "M_E_MA<0>")
	)
	(segment
		(start 265.4554 -129.032508)
		(end 265.4554 -129.667)
		(width 0.14224)
		(layer "In4.Cu")
		(net "M_E_MA<0>")
	)
	(segment
		(start 265.665966 -135.374634)
		(end 265.665966 -138.928094)
		(width 0.14224)
		(layer "In4.Cu")
		(net "M_E_MA<0>")
	)
	(segment
		(start 265.4554 -129.667)
		(end 265.837924 -130.049524)
		(width 0.14224)
		(layer "In4.Cu")
		(net "M_E_MA<0>")
	)
	(segment
		(start 265.837924 -130.049524)
		(end 265.837924 -130.452876)
		(width 0.14224)
		(layer "In4.Cu")
		(net "M_E_MA<0>")
	)
	(segment
		(start 263.104376 -125.258576)
		(end 262.5852 -125.777752)
		(width 0.14224)
		(layer "In4.Cu")
		(net "M_E_MA<0>")
	)
	(segment
		(start 266.099798 -141.183868)
		(end 266.099798 -143.968978)
		(width 0.14224)
		(layer "In4.Cu")
		(net "M_E_MA<0>")
	)
	(segment
		(start 265.665966 -138.928094)
		(end 265.642598 -138.951462)
		(width 0.14224)
		(layer "In4.Cu")
		(net "M_E_MA<0>")
	)
	(segment
		(start 264.860786 -128.437894)
		(end 265.4554 -129.032508)
		(width 0.14224)
		(layer "In4.Cu")
		(net "M_E_MA<0>")
	)
	(segment
		(start 263.733788 -127.157988)
		(end 264.128758 -127.552958)
		(width 0.14224)
		(layer "In4.Cu")
		(net "M_E_MA<0>")
	)
	(segment
		(start 261.015734 -99.368102)
		(end 261.02056 -99.376738)
		(width 0.0889)
		(layer "In4.Cu")
		(net "M_E_MA<0>")
	)
	(arc
		(start 261.09549 -98.753168)
		(mid 261.089968 -98.788803)
		(end 261.082282 -98.824034)
		(width 0.0889)
		(layer "In4.Cu")
		(net "M_E_MA<0>")
	)
	(arc
		(start 261.099808 -98.679)
		(mid 261.098815 -98.716152)
		(end 261.09549 -98.753168)
		(width 0.0889)
		(layer "In4.Cu")
		(net "M_E_MA<0>")
	)
	(arc
		(start 261.02056 -98.976688)
		(mid 260.96709 -99.171751)
		(end 261.015734 -99.368102)
		(width 0.0889)
		(layer "In4.Cu")
		(net "M_E_MA<0>")
	)
	(arc
		(start 261.02056 -99.376738)
		(mid 261.132913 -99.585039)
		(end 261.239 -99.7966)
		(width 0.0889)
		(layer "In4.Cu")
		(net "M_E_MA<0>")
	)
	(arc
		(start 261.082282 -98.824034)
		(mid 261.056773 -98.902526)
		(end 261.02056 -98.976688)
		(width 0.0889)
		(layer "In4.Cu")
		(net "M_E_MA<0>")
	)
	(arc
		(start 261.36727 -98.18624)
		(mid 261.171018 -98.398678)
		(end 261.099808 -98.679)
		(width 0.0889)
		(layer "In4.Cu")
		(net "M_E_MA<0>")
	)
	(arc
		(start 261.239 -99.7966)
		(mid 261.295898 -99.958795)
		(end 261.3152 -100.129594)
		(width 0.0889)
		(layer "In4.Cu")
		(net "M_E_MA<0>")
	)
	(segment
		(start 240.963196 -125.403102)
		(end 240.650522 -125.715776)
		(width 0.1651)
		(layer "F.Cu")
		(net "M_E_ECC<7>")
	)
	(segment
		(start 249.952764 -100.360226)
		(end 249.952764 -100.492814)
		(width 0.0889)
		(layer "F.Cu")
		(net "M_E_ECC<7>")
	)
	(segment
		(start 241.934492 -113.542064)
		(end 241.782092 -113.389664)
		(width 0.1651)
		(layer "F.Cu")
		(net "M_E_ECC<7>")
	)
	(segment
		(start 249.952764 -100.492814)
		(end 249.952764 -103.796338)
		(width 0.1016)
		(layer "F.Cu")
		(net "M_E_ECC<7>")
	)
	(segment
		(start 249.264424 -105.36301)
		(end 244.563646 -110.063788)
		(width 0.1016)
		(layer "F.Cu")
		(net "M_E_ECC<7>")
	)
	(segment
		(start 240.963196 -124.288804)
		(end 240.963196 -125.403102)
		(width 0.1651)
		(layer "F.Cu")
		(net "M_E_ECC<7>")
	)
	(segment
		(start 241.261392 -123.990608)
		(end 240.963196 -124.288804)
		(width 0.1651)
		(layer "F.Cu")
		(net "M_E_ECC<7>")
	)
	(segment
		(start 249.952764 -103.796338)
		(end 249.264424 -104.484678)
		(width 0.1016)
		(layer "F.Cu")
		(net "M_E_ECC<7>")
	)
	(segment
		(start 242.061492 -115.7732)
		(end 241.934492 -115.6462)
		(width 0.1651)
		(layer "F.Cu")
		(net "M_E_ECC<7>")
	)
	(segment
		(start 239.750346 -142.6718)
		(end 239.749838 -142.677642)
		(width 0.1651)
		(layer "F.Cu")
		(net "M_E_ECC<7>")
	)
	(segment
		(start 239.749838 -142.677642)
		(end 239.749838 -143.941546)
		(width 0.1651)
		(layer "F.Cu")
		(net "M_E_ECC<7>")
	)
	(segment
		(start 244.563646 -110.248446)
		(end 244.371114 -110.440978)
		(width 0.1016)
		(layer "F.Cu")
		(net "M_E_ECC<7>")
	)
	(segment
		(start 249.921014 -100.328476)
		(end 249.952764 -100.360226)
		(width 0.0889)
		(layer "F.Cu")
		(net "M_E_ECC<7>")
	)
	(segment
		(start 244.371114 -110.440978)
		(end 242.607592 -112.2045)
		(width 0.1651)
		(layer "F.Cu")
		(net "M_E_ECC<7>")
	)
	(segment
		(start 241.261392 -113.567464)
		(end 241.261392 -123.990608)
		(width 0.1651)
		(layer "F.Cu")
		(net "M_E_ECC<7>")
	)
	(segment
		(start 242.607592 -112.2045)
		(end 242.607592 -115.6462)
		(width 0.1651)
		(layer "F.Cu")
		(net "M_E_ECC<7>")
	)
	(segment
		(start 241.934492 -115.6462)
		(end 241.934492 -113.542064)
		(width 0.1651)
		(layer "F.Cu")
		(net "M_E_ECC<7>")
	)
	(segment
		(start 242.607592 -115.6462)
		(end 242.480592 -115.7732)
		(width 0.1651)
		(layer "F.Cu")
		(net "M_E_ECC<7>")
	)
	(segment
		(start 249.919744 -99.17684)
		(end 249.921014 -99.17811)
		(width 0.0889)
		(layer "F.Cu")
		(net "M_E_ECC<7>")
	)
	(segment
		(start 244.563646 -110.063788)
		(end 244.563646 -110.248446)
		(width 0.1016)
		(layer "F.Cu")
		(net "M_E_ECC<7>")
	)
	(segment
		(start 249.264424 -104.484678)
		(end 249.264424 -105.36301)
		(width 0.1016)
		(layer "F.Cu")
		(net "M_E_ECC<7>")
	)
	(segment
		(start 241.782092 -113.389664)
		(end 241.439192 -113.389664)
		(width 0.1651)
		(layer "F.Cu")
		(net "M_E_ECC<7>")
	)
	(segment
		(start 249.921014 -99.17811)
		(end 249.921014 -100.328476)
		(width 0.0889)
		(layer "F.Cu")
		(net "M_E_ECC<7>")
	)
	(segment
		(start 242.480592 -115.7732)
		(end 242.061492 -115.7732)
		(width 0.1651)
		(layer "F.Cu")
		(net "M_E_ECC<7>")
	)
	(segment
		(start 241.439192 -113.389664)
		(end 241.261392 -113.567464)
		(width 0.1651)
		(layer "F.Cu")
		(net "M_E_ECC<7>")
	)
	(via
		(at 240.650522 -125.715776)
		(size 0.508)
		(drill 0.254)
		(layers "F.Cu" "B.Cu")
		(net "M_E_ECC<7>")
	)
	(via
		(at 240.599722 -139.932156)
		(size 0.508)
		(drill 0.254)
		(layers "F.Cu" "B.Cu")
		(net "M_E_ECC<7>")
	)
	(via
		(at 239.749838 -143.941546)
		(size 0.508)
		(drill 0.254)
		(layers "F.Cu" "B.Cu")
		(net "M_E_ECC<7>")
	)
	(segment
		(start 240.599722 -137.877296)
		(end 240.600484 -137.877296)
		(width 0.1651)
		(layer "B.Cu")
		(net "M_E_ECC<7>")
	)
	(segment
		(start 240.599722 -139.932156)
		(end 240.599722 -137.877296)
		(width 0.1651)
		(layer "B.Cu")
		(net "M_E_ECC<7>")
	)
	(segment
		(start 240.57737 -139.932156)
		(end 240.599722 -139.932156)
		(width 0.14224)
		(layer "In9.Cu")
		(net "M_E_ECC<7>")
	)
	(segment
		(start 240.168176 -142.3162)
		(end 239.911128 -142.059152)
		(width 0.14224)
		(layer "In9.Cu")
		(net "M_E_ECC<7>")
	)
	(segment
		(start 239.911128 -142.059152)
		(end 239.911128 -141.785848)
		(width 0.14224)
		(layer "In9.Cu")
		(net "M_E_ECC<7>")
	)
	(segment
		(start 239.911128 -143.151352)
		(end 239.911128 -142.878048)
		(width 0.14224)
		(layer "In9.Cu")
		(net "M_E_ECC<7>")
	)
	(segment
		(start 239.911128 -142.878048)
		(end 240.168176 -142.621)
		(width 0.14224)
		(layer "In9.Cu")
		(net "M_E_ECC<7>")
	)
	(segment
		(start 240.149126 -140.790168)
		(end 240.149126 -140.3604)
		(width 0.14224)
		(layer "In9.Cu")
		(net "M_E_ECC<7>")
	)
	(segment
		(start 239.911128 -141.785848)
		(end 240.193576 -141.5034)
		(width 0.14224)
		(layer "In9.Cu")
		(net "M_E_ECC<7>")
	)
	(segment
		(start 240.193576 -140.834618)
		(end 240.149126 -140.790168)
		(width 0.14224)
		(layer "In9.Cu")
		(net "M_E_ECC<7>")
	)
	(segment
		(start 240.149126 -140.3604)
		(end 240.57737 -139.932156)
		(width 0.14224)
		(layer "In9.Cu")
		(net "M_E_ECC<7>")
	)
	(segment
		(start 239.749838 -143.941546)
		(end 240.022126 -143.941546)
		(width 0.14224)
		(layer "In9.Cu")
		(net "M_E_ECC<7>")
	)
	(segment
		(start 240.199926 -143.763746)
		(end 240.199926 -143.44015)
		(width 0.14224)
		(layer "In9.Cu")
		(net "M_E_ECC<7>")
	)
	(segment
		(start 240.193576 -141.5034)
		(end 240.193576 -140.834618)
		(width 0.14224)
		(layer "In9.Cu")
		(net "M_E_ECC<7>")
	)
	(segment
		(start 240.199926 -143.44015)
		(end 239.911128 -143.151352)
		(width 0.14224)
		(layer "In9.Cu")
		(net "M_E_ECC<7>")
	)
	(segment
		(start 240.168176 -142.621)
		(end 240.168176 -142.3162)
		(width 0.14224)
		(layer "In9.Cu")
		(net "M_E_ECC<7>")
	)
	(segment
		(start 240.022126 -143.941546)
		(end 240.199926 -143.763746)
		(width 0.14224)
		(layer "In9.Cu")
		(net "M_E_ECC<7>")
	)
	(segment
		(start 240.952528 -136.5758)
		(end 240.952528 -136.186418)
		(width 0.14224)
		(layer "In11.Cu")
		(net "M_E_ECC<7>")
	)
	(segment
		(start 240.86566 -127.55626)
		(end 240.86566 -126.97714)
		(width 0.14224)
		(layer "In11.Cu")
		(net "M_E_ECC<7>")
	)
	(segment
		(start 240.901728 -131.484878)
		(end 241.181128 -131.205478)
		(width 0.14224)
		(layer "In11.Cu")
		(net "M_E_ECC<7>")
	)
	(segment
		(start 240.901728 -131.8514)
		(end 240.901728 -131.484878)
		(width 0.14224)
		(layer "In11.Cu")
		(net "M_E_ECC<7>")
	)
	(segment
		(start 240.952528 -127.643128)
		(end 240.86566 -127.55626)
		(width 0.14224)
		(layer "In11.Cu")
		(net "M_E_ECC<7>")
	)
	(segment
		(start 240.977928 -134.568438)
		(end 240.977928 -134.129272)
		(width 0.14224)
		(layer "In11.Cu")
		(net "M_E_ECC<7>")
	)
	(segment
		(start 241.0206 -131.970272)
		(end 240.901728 -131.8514)
		(width 0.14224)
		(layer "In11.Cu")
		(net "M_E_ECC<7>")
	)
	(segment
		(start 241.173 -126.6698)
		(end 241.173 -126.238254)
		(width 0.14224)
		(layer "In11.Cu")
		(net "M_E_ECC<7>")
	)
	(segment
		(start 241.0206 -136.643872)
		(end 240.952528 -136.5758)
		(width 0.14224)
		(layer "In11.Cu")
		(net "M_E_ECC<7>")
	)
	(segment
		(start 240.952528 -136.186418)
		(end 241.121692 -136.017254)
		(width 0.14224)
		(layer "In11.Cu")
		(net "M_E_ECC<7>")
	)
	(segment
		(start 240.977928 -134.129272)
		(end 241.0206 -134.0866)
		(width 0.14224)
		(layer "In11.Cu")
		(net "M_E_ECC<7>")
	)
	(segment
		(start 240.952528 -138.828272)
		(end 241.0206 -138.7602)
		(width 0.14224)
		(layer "In11.Cu")
		(net "M_E_ECC<7>")
	)
	(segment
		(start 241.121692 -136.017254)
		(end 241.121692 -134.712202)
		(width 0.14224)
		(layer "In11.Cu")
		(net "M_E_ECC<7>")
	)
	(segment
		(start 240.86566 -126.97714)
		(end 241.173 -126.6698)
		(width 0.14224)
		(layer "In11.Cu")
		(net "M_E_ECC<7>")
	)
	(segment
		(start 240.599722 -139.932156)
		(end 240.941606 -139.590272)
		(width 0.14224)
		(layer "In11.Cu")
		(net "M_E_ECC<7>")
	)
	(segment
		(start 241.173 -126.238254)
		(end 240.650522 -125.715776)
		(width 0.14224)
		(layer "In11.Cu")
		(net "M_E_ECC<7>")
	)
	(segment
		(start 241.181128 -131.205478)
		(end 241.181128 -130.087878)
		(width 0.14224)
		(layer "In11.Cu")
		(net "M_E_ECC<7>")
	)
	(segment
		(start 241.121692 -134.712202)
		(end 240.977928 -134.568438)
		(width 0.14224)
		(layer "In11.Cu")
		(net "M_E_ECC<7>")
	)
	(segment
		(start 241.0206 -138.7602)
		(end 241.0206 -136.643872)
		(width 0.14224)
		(layer "In11.Cu")
		(net "M_E_ECC<7>")
	)
	(segment
		(start 241.181128 -130.087878)
		(end 240.952528 -129.859278)
		(width 0.14224)
		(layer "In11.Cu")
		(net "M_E_ECC<7>")
	)
	(segment
		(start 240.952528 -139.590272)
		(end 240.952528 -138.828272)
		(width 0.14224)
		(layer "In11.Cu")
		(net "M_E_ECC<7>")
	)
	(segment
		(start 240.941606 -139.590272)
		(end 240.952528 -139.590272)
		(width 0.14224)
		(layer "In11.Cu")
		(net "M_E_ECC<7>")
	)
	(segment
		(start 240.952528 -129.859278)
		(end 240.952528 -127.643128)
		(width 0.14224)
		(layer "In11.Cu")
		(net "M_E_ECC<7>")
	)
	(segment
		(start 241.0206 -134.0866)
		(end 241.0206 -131.970272)
		(width 0.14224)
		(layer "In11.Cu")
		(net "M_E_ECC<7>")
	)
	(segment
		(start 240.320068 -124.703332)
		(end 239.776 -125.2474)
		(width 0.1651)
		(layer "F.Cu")
		(net "M_E_ECC<6>")
	)
	(segment
		(start 249.647964 -100.121466)
		(end 249.647964 -100.492814)
		(width 0.0889)
		(layer "F.Cu")
		(net "M_E_ECC<6>")
	)
	(segment
		(start 240.062512 -121.171462)
		(end 239.897412 -121.336562)
		(width 0.1651)
		(layer "F.Cu")
		(net "M_E_ECC<6>")
	)
	(segment
		(start 240.6142 -121.006362)
		(end 240.4491 -121.171462)
		(width 0.1651)
		(layer "F.Cu")
		(net "M_E_ECC<6>")
	)
	(segment
		(start 240.599976 -145.8214)
		(end 240.599976 -145.516854)
		(width 0.1651)
		(layer "F.Cu")
		(net "M_E_ECC<6>")
	)
	(segment
		(start 249.919744 -97.19564)
		(end 249.532394 -97.58299)
		(width 0.0889)
		(layer "F.Cu")
		(net "M_E_ECC<6>")
	)
	(segment
		(start 249.568208 -99.368102)
		(end 249.573034 -99.376738)
		(width 0.0889)
		(layer "F.Cu")
		(net "M_E_ECC<6>")
	)
	(segment
		(start 248.959624 -104.358186)
		(end 248.959624 -105.111042)
		(width 0.1016)
		(layer "F.Cu")
		(net "M_E_ECC<6>")
	)
	(segment
		(start 240.600484 -147.27174)
		(end 240.599976 -147.27174)
		(width 0.1651)
		(layer "F.Cu")
		(net "M_E_ECC<6>")
	)
	(segment
		(start 240.4491 -122.517662)
		(end 240.062512 -122.517662)
		(width 0.1651)
		(layer "F.Cu")
		(net "M_E_ECC<6>")
	)
	(segment
		(start 244.268498 -109.63656)
		(end 244.037866 -109.867192)
		(width 0.1016)
		(layer "F.Cu")
		(net "M_E_ECC<6>")
	)
	(segment
		(start 249.573034 -99.376738)
		(end 249.581924 -99.391978)
		(width 0.0889)
		(layer "F.Cu")
		(net "M_E_ECC<6>")
	)
	(segment
		(start 240.6142 -113.290858)
		(end 240.6142 -121.006362)
		(width 0.1651)
		(layer "F.Cu")
		(net "M_E_ECC<6>")
	)
	(segment
		(start 249.532394 -97.58299)
		(end 249.532394 -98.59264)
		(width 0.0889)
		(layer "F.Cu")
		(net "M_E_ECC<6>")
	)
	(segment
		(start 240.062512 -122.517662)
		(end 239.897412 -122.682762)
		(width 0.1651)
		(layer "F.Cu")
		(net "M_E_ECC<6>")
	)
	(segment
		(start 239.897412 -123.025662)
		(end 240.062512 -123.190762)
		(width 0.1651)
		(layer "F.Cu")
		(net "M_E_ECC<6>")
	)
	(segment
		(start 239.897412 -121.336562)
		(end 239.897412 -121.679462)
		(width 0.1651)
		(layer "F.Cu")
		(net "M_E_ECC<6>")
	)
	(segment
		(start 239.897412 -121.679462)
		(end 240.062512 -121.844562)
		(width 0.1651)
		(layer "F.Cu")
		(net "M_E_ECC<6>")
	)
	(segment
		(start 240.599976 -147.27174)
		(end 240.599976 -146.304)
		(width 0.1651)
		(layer "F.Cu")
		(net "M_E_ECC<6>")
	)
	(segment
		(start 249.652282 -99.675188)
		(end 249.652282 -100.117148)
		(width 0.0889)
		(layer "F.Cu")
		(net "M_E_ECC<6>")
	)
	(segment
		(start 240.320068 -123.992132)
		(end 240.320068 -124.703332)
		(width 0.1651)
		(layer "F.Cu")
		(net "M_E_ECC<6>")
	)
	(segment
		(start 249.647964 -100.492814)
		(end 249.647964 -103.669846)
		(width 0.1016)
		(layer "F.Cu")
		(net "M_E_ECC<6>")
	)
	(segment
		(start 249.63882 -98.699066)
		(end 249.63882 -98.87839)
		(width 0.0889)
		(layer "F.Cu")
		(net "M_E_ECC<6>")
	)
	(segment
		(start 249.652282 -100.117148)
		(end 249.647964 -100.121466)
		(width 0.0889)
		(layer "F.Cu")
		(net "M_E_ECC<6>")
	)
	(segment
		(start 248.959624 -105.111042)
		(end 244.434106 -109.63656)
		(width 0.1016)
		(layer "F.Cu")
		(net "M_E_ECC<6>")
	)
	(segment
		(start 244.434106 -109.63656)
		(end 244.268498 -109.63656)
		(width 0.1016)
		(layer "F.Cu")
		(net "M_E_ECC<6>")
	)
	(segment
		(start 240.6142 -123.355862)
		(end 240.6142 -123.698)
		(width 0.1651)
		(layer "F.Cu")
		(net "M_E_ECC<6>")
	)
	(segment
		(start 239.897412 -122.682762)
		(end 239.897412 -123.025662)
		(width 0.1651)
		(layer "F.Cu")
		(net "M_E_ECC<6>")
	)
	(segment
		(start 240.4491 -121.844562)
		(end 240.6142 -122.009662)
		(width 0.1651)
		(layer "F.Cu")
		(net "M_E_ECC<6>")
	)
	(segment
		(start 249.532394 -98.59264)
		(end 249.63882 -98.699066)
		(width 0.0889)
		(layer "F.Cu")
		(net "M_E_ECC<6>")
	)
	(segment
		(start 240.732056 -145.95348)
		(end 240.599976 -145.8214)
		(width 0.1651)
		(layer "F.Cu")
		(net "M_E_ECC<6>")
	)
	(segment
		(start 240.4491 -123.190762)
		(end 240.6142 -123.355862)
		(width 0.1651)
		(layer "F.Cu")
		(net "M_E_ECC<6>")
	)
	(segment
		(start 240.6142 -123.698)
		(end 240.320068 -123.992132)
		(width 0.1651)
		(layer "F.Cu")
		(net "M_E_ECC<6>")
	)
	(segment
		(start 240.6142 -122.352562)
		(end 240.4491 -122.517662)
		(width 0.1651)
		(layer "F.Cu")
		(net "M_E_ECC<6>")
	)
	(segment
		(start 240.599976 -145.516854)
		(end 240.599722 -145.5166)
		(width 0.1651)
		(layer "F.Cu")
		(net "M_E_ECC<6>")
	)
	(segment
		(start 240.4491 -121.171462)
		(end 240.062512 -121.171462)
		(width 0.1651)
		(layer "F.Cu")
		(net "M_E_ECC<6>")
	)
	(segment
		(start 249.647964 -103.669846)
		(end 248.959624 -104.358186)
		(width 0.1016)
		(layer "F.Cu")
		(net "M_E_ECC<6>")
	)
	(segment
		(start 244.037866 -109.867192)
		(end 240.6142 -113.290858)
		(width 0.1651)
		(layer "F.Cu")
		(net "M_E_ECC<6>")
	)
	(segment
		(start 240.062512 -121.844562)
		(end 240.4491 -121.844562)
		(width 0.1651)
		(layer "F.Cu")
		(net "M_E_ECC<6>")
	)
	(segment
		(start 240.599976 -146.304)
		(end 240.732056 -146.17192)
		(width 0.1651)
		(layer "F.Cu")
		(net "M_E_ECC<6>")
	)
	(segment
		(start 240.732056 -146.17192)
		(end 240.732056 -145.95348)
		(width 0.1651)
		(layer "F.Cu")
		(net "M_E_ECC<6>")
	)
	(segment
		(start 240.062512 -123.190762)
		(end 240.4491 -123.190762)
		(width 0.1651)
		(layer "F.Cu")
		(net "M_E_ECC<6>")
	)
	(segment
		(start 240.6142 -122.009662)
		(end 240.6142 -122.352562)
		(width 0.1651)
		(layer "F.Cu")
		(net "M_E_ECC<6>")
	)
	(via
		(at 240.599722 -145.5166)
		(size 0.508)
		(drill 0.254)
		(layers "F.Cu" "B.Cu")
		(net "M_E_ECC<6>")
	)
	(via
		(at 239.776 -125.2474)
		(size 0.508)
		(drill 0.254)
		(layers "F.Cu" "B.Cu")
		(net "M_E_ECC<6>")
	)
	(via
		(at 239.749838 -141.213078)
		(size 0.508)
		(drill 0.254)
		(layers "F.Cu" "B.Cu")
		(net "M_E_ECC<6>")
	)
	(arc
		(start 249.63882 -98.87839)
		(mid 249.522133 -99.111511)
		(end 249.568208 -99.368102)
		(width 0.0889)
		(layer "F.Cu")
		(net "M_E_ECC<6>")
	)
	(arc
		(start 249.581924 -99.391978)
		(mid 249.634845 -99.529174)
		(end 249.652282 -99.675188)
		(width 0.0889)
		(layer "F.Cu")
		(net "M_E_ECC<6>")
	)
	(segment
		(start 239.750346 -142.477236)
		(end 239.749838 -142.476982)
		(width 0.1651)
		(layer "B.Cu")
		(net "M_E_ECC<6>")
	)
	(segment
		(start 239.749838 -142.476982)
		(end 239.749838 -141.213078)
		(width 0.1651)
		(layer "B.Cu")
		(net "M_E_ECC<6>")
	)
	(segment
		(start 239.316768 -141.646148)
		(end 239.316768 -144.233646)
		(width 0.14224)
		(layer "In9.Cu")
		(net "M_E_ECC<6>")
	)
	(segment
		(start 239.316768 -144.233646)
		(end 240.599722 -145.5166)
		(width 0.14224)
		(layer "In9.Cu")
		(net "M_E_ECC<6>")
	)
	(segment
		(start 239.749838 -141.213078)
		(end 239.316768 -141.646148)
		(width 0.14224)
		(layer "In9.Cu")
		(net "M_E_ECC<6>")
	)
	(segment
		(start 239.580928 -141.044168)
		(end 239.580928 -140.070078)
		(width 0.14224)
		(layer "In11.Cu")
		(net "M_E_ECC<6>")
	)
	(segment
		(start 240.1824 -132.011928)
		(end 240.266728 -131.9276)
		(width 0.14224)
		(layer "In11.Cu")
		(net "M_E_ECC<6>")
	)
	(segment
		(start 240.114328 -131.307078)
		(end 240.114328 -130.062478)
		(width 0.14224)
		(layer "In11.Cu")
		(net "M_E_ECC<6>")
	)
	(segment
		(start 239.749838 -141.213078)
		(end 239.580928 -141.044168)
		(width 0.14224)
		(layer "In11.Cu")
		(net "M_E_ECC<6>")
	)
	(segment
		(start 240.317528 -138.869928)
		(end 240.1824 -138.7348)
		(width 0.14224)
		(layer "In11.Cu")
		(net "M_E_ECC<6>")
	)
	(segment
		(start 240.317528 -136.5758)
		(end 240.317528 -136.256268)
		(width 0.14224)
		(layer "In11.Cu")
		(net "M_E_ECC<6>")
	)
	(segment
		(start 240.266728 -131.9276)
		(end 240.266728 -131.459478)
		(width 0.14224)
		(layer "In11.Cu")
		(net "M_E_ECC<6>")
	)
	(segment
		(start 239.580928 -140.070078)
		(end 240.317528 -139.333478)
		(width 0.14224)
		(layer "In11.Cu")
		(net "M_E_ECC<6>")
	)
	(segment
		(start 240.2078 -127.5334)
		(end 240.2078 -125.6792)
		(width 0.14224)
		(layer "In11.Cu")
		(net "M_E_ECC<6>")
	)
	(segment
		(start 240.266728 -131.459478)
		(end 240.114328 -131.307078)
		(width 0.14224)
		(layer "In11.Cu")
		(net "M_E_ECC<6>")
	)
	(segment
		(start 240.317528 -139.333478)
		(end 240.317528 -138.869928)
		(width 0.14224)
		(layer "In11.Cu")
		(net "M_E_ECC<6>")
	)
	(segment
		(start 240.2078 -125.6792)
		(end 239.776 -125.2474)
		(width 0.14224)
		(layer "In11.Cu")
		(net "M_E_ECC<6>")
	)
	(segment
		(start 240.317528 -127.643128)
		(end 240.2078 -127.5334)
		(width 0.14224)
		(layer "In11.Cu")
		(net "M_E_ECC<6>")
	)
	(segment
		(start 240.1824 -138.7348)
		(end 240.1824 -136.710928)
		(width 0.14224)
		(layer "In11.Cu")
		(net "M_E_ECC<6>")
	)
	(segment
		(start 239.994186 -134.79018)
		(end 240.266728 -134.517638)
		(width 0.14224)
		(layer "In11.Cu")
		(net "M_E_ECC<6>")
	)
	(segment
		(start 240.1824 -134.0866)
		(end 240.1824 -132.011928)
		(width 0.14224)
		(layer "In11.Cu")
		(net "M_E_ECC<6>")
	)
	(segment
		(start 239.994186 -135.932926)
		(end 239.994186 -134.79018)
		(width 0.14224)
		(layer "In11.Cu")
		(net "M_E_ECC<6>")
	)
	(segment
		(start 240.266728 -134.170928)
		(end 240.1824 -134.0866)
		(width 0.14224)
		(layer "In11.Cu")
		(net "M_E_ECC<6>")
	)
	(segment
		(start 240.317528 -129.859278)
		(end 240.317528 -127.643128)
		(width 0.14224)
		(layer "In11.Cu")
		(net "M_E_ECC<6>")
	)
	(segment
		(start 240.317528 -136.256268)
		(end 239.994186 -135.932926)
		(width 0.14224)
		(layer "In11.Cu")
		(net "M_E_ECC<6>")
	)
	(segment
		(start 240.266728 -134.517638)
		(end 240.266728 -134.170928)
		(width 0.14224)
		(layer "In11.Cu")
		(net "M_E_ECC<6>")
	)
	(segment
		(start 240.114328 -130.062478)
		(end 240.317528 -129.859278)
		(width 0.14224)
		(layer "In11.Cu")
		(net "M_E_ECC<6>")
	)
	(segment
		(start 240.1824 -136.710928)
		(end 240.317528 -136.5758)
		(width 0.14224)
		(layer "In11.Cu")
		(net "M_E_ECC<6>")
	)
	(segment
		(start 234.7722 -125.410976)
		(end 234.5944 -125.410976)
		(width 0.1651)
		(layer "F.Cu")
		(net "M_E_ECC<5>")
	)
	(segment
		(start 234.994196 -113.31448)
		(end 234.994196 -114.467132)
		(width 0.1651)
		(layer "F.Cu")
		(net "M_E_ECC<5>")
	)
	(segment
		(start 233.799888 -142.677642)
		(end 233.799888 -143.941546)
		(width 0.1651)
		(layer "F.Cu")
		(net "M_E_ECC<5>")
	)
	(segment
		(start 235.165646 -116.657882)
		(end 234.994196 -116.829332)
		(width 0.1651)
		(layer "F.Cu")
		(net "M_E_ECC<5>")
	)
	(segment
		(start 247.105424 -102.346506)
		(end 247.168924 -102.410006)
		(width 0.0889)
		(layer "F.Cu")
		(net "M_E_ECC<5>")
	)
	(segment
		(start 247.050814 -100.319332)
		(end 246.916194 -100.552504)
		(width 0.0889)
		(layer "F.Cu")
		(net "M_E_ECC<5>")
	)
	(segment
		(start 246.916194 -100.552504)
		(end 246.916194 -100.772468)
		(width 0.0889)
		(layer "F.Cu")
		(net "M_E_ECC<5>")
	)
	(segment
		(start 247.076722 -99.300792)
		(end 246.902732 -99.60229)
		(width 0.0889)
		(layer "F.Cu")
		(net "M_E_ECC<5>")
	)
	(segment
		(start 235.670598 -114.803682)
		(end 235.670598 -115.146582)
		(width 0.1651)
		(layer "F.Cu")
		(net "M_E_ECC<5>")
	)
	(segment
		(start 247.076722 -99.17684)
		(end 247.076722 -99.300792)
		(width 0.0889)
		(layer "F.Cu")
		(net "M_E_ECC<5>")
	)
	(segment
		(start 235.670598 -116.149882)
		(end 235.670598 -116.492782)
		(width 0.1651)
		(layer "F.Cu")
		(net "M_E_ECC<5>")
	)
	(segment
		(start 235.505498 -115.984782)
		(end 235.670598 -116.149882)
		(width 0.1651)
		(layer "F.Cu")
		(net "M_E_ECC<5>")
	)
	(segment
		(start 247.009412 -101.69906)
		(end 247.105424 -101.906832)
		(width 0.0889)
		(layer "F.Cu")
		(net "M_E_ECC<5>")
	)
	(segment
		(start 246.902732 -99.60229)
		(end 246.902732 -99.740974)
		(width 0.0889)
		(layer "F.Cu")
		(net "M_E_ECC<5>")
	)
	(segment
		(start 247.009412 -101.493828)
		(end 247.009412 -101.69906)
		(width 0.0889)
		(layer "F.Cu")
		(net "M_E_ECC<5>")
	)
	(segment
		(start 235.670598 -115.146582)
		(end 235.505498 -115.311682)
		(width 0.1651)
		(layer "F.Cu")
		(net "M_E_ECC<5>")
	)
	(segment
		(start 247.050814 -99.996244)
		(end 247.050814 -100.319332)
		(width 0.0889)
		(layer "F.Cu")
		(net "M_E_ECC<5>")
	)
	(segment
		(start 234.994196 -116.829332)
		(end 234.994196 -124.046996)
		(width 0.1651)
		(layer "F.Cu")
		(net "M_E_ECC<5>")
	)
	(segment
		(start 235.0516 -124.1044)
		(end 235.0516 -125.131576)
		(width 0.1651)
		(layer "F.Cu")
		(net "M_E_ECC<5>")
	)
	(segment
		(start 247.105424 -101.906832)
		(end 247.105424 -102.346506)
		(width 0.0889)
		(layer "F.Cu")
		(net "M_E_ECC<5>")
	)
	(segment
		(start 235.505498 -115.311682)
		(end 235.2548 -115.311682)
		(width 0.1651)
		(layer "F.Cu")
		(net "M_E_ECC<5>")
	)
	(segment
		(start 243.425472 -106.747564)
		(end 241.561112 -106.747564)
		(width 0.1016)
		(layer "F.Cu")
		(net "M_E_ECC<5>")
	)
	(segment
		(start 246.916194 -100.772468)
		(end 247.080024 -101.05644)
		(width 0.0889)
		(layer "F.Cu")
		(net "M_E_ECC<5>")
	)
	(segment
		(start 235.0516 -125.131576)
		(end 234.7722 -125.410976)
		(width 0.1651)
		(layer "F.Cu")
		(net "M_E_ECC<5>")
	)
	(segment
		(start 235.505498 -114.638582)
		(end 235.670598 -114.803682)
		(width 0.1651)
		(layer "F.Cu")
		(net "M_E_ECC<5>")
	)
	(segment
		(start 247.080024 -101.32314)
		(end 247.009412 -101.493828)
		(width 0.0889)
		(layer "F.Cu")
		(net "M_E_ECC<5>")
	)
	(segment
		(start 247.344184 -97.690686)
		(end 247.014746 -98.45167)
		(width 0.0889)
		(layer "F.Cu")
		(net "M_E_ECC<5>")
	)
	(segment
		(start 246.902732 -99.740974)
		(end 247.050814 -99.996244)
		(width 0.0889)
		(layer "F.Cu")
		(net "M_E_ECC<5>")
	)
	(segment
		(start 235.505498 -116.657882)
		(end 235.165646 -116.657882)
		(width 0.1651)
		(layer "F.Cu")
		(net "M_E_ECC<5>")
	)
	(segment
		(start 235.670598 -116.492782)
		(end 235.505498 -116.657882)
		(width 0.1651)
		(layer "F.Cu")
		(net "M_E_ECC<5>")
	)
	(segment
		(start 234.994196 -124.046996)
		(end 235.0516 -124.1044)
		(width 0.1651)
		(layer "F.Cu")
		(net "M_E_ECC<5>")
	)
	(segment
		(start 247.168924 -102.410006)
		(end 247.168924 -103.004112)
		(width 0.1016)
		(layer "F.Cu")
		(net "M_E_ECC<5>")
	)
	(segment
		(start 247.014746 -98.45167)
		(end 246.992648 -98.490024)
		(width 0.0889)
		(layer "F.Cu")
		(net "M_E_ECC<5>")
	)
	(segment
		(start 235.165646 -114.638582)
		(end 235.505498 -114.638582)
		(width 0.1651)
		(layer "F.Cu")
		(net "M_E_ECC<5>")
	)
	(segment
		(start 247.168924 -103.004112)
		(end 243.425472 -106.747564)
		(width 0.1016)
		(layer "F.Cu")
		(net "M_E_ECC<5>")
	)
	(segment
		(start 241.561112 -106.747564)
		(end 241.39017 -106.918506)
		(width 0.1016)
		(layer "F.Cu")
		(net "M_E_ECC<5>")
	)
	(segment
		(start 234.994196 -114.467132)
		(end 235.165646 -114.638582)
		(width 0.1651)
		(layer "F.Cu")
		(net "M_E_ECC<5>")
	)
	(segment
		(start 247.080024 -101.05644)
		(end 247.080024 -101.32314)
		(width 0.0889)
		(layer "F.Cu")
		(net "M_E_ECC<5>")
	)
	(segment
		(start 235.1278 -115.857782)
		(end 235.2548 -115.984782)
		(width 0.1651)
		(layer "F.Cu")
		(net "M_E_ECC<5>")
	)
	(segment
		(start 235.1278 -115.438682)
		(end 235.1278 -115.857782)
		(width 0.1651)
		(layer "F.Cu")
		(net "M_E_ECC<5>")
	)
	(segment
		(start 235.2548 -115.984782)
		(end 235.505498 -115.984782)
		(width 0.1651)
		(layer "F.Cu")
		(net "M_E_ECC<5>")
	)
	(segment
		(start 241.39017 -106.918506)
		(end 234.994196 -113.31448)
		(width 0.1651)
		(layer "F.Cu")
		(net "M_E_ECC<5>")
	)
	(segment
		(start 235.2548 -115.311682)
		(end 235.1278 -115.438682)
		(width 0.1651)
		(layer "F.Cu")
		(net "M_E_ECC<5>")
	)
	(segment
		(start 233.800396 -142.6718)
		(end 233.799888 -142.677642)
		(width 0.1651)
		(layer "F.Cu")
		(net "M_E_ECC<5>")
	)
	(via
		(at 234.573572 -139.932156)
		(size 0.508)
		(drill 0.254)
		(layers "F.Cu" "B.Cu")
		(net "M_E_ECC<5>")
	)
	(via
		(at 234.5944 -125.410976)
		(size 0.508)
		(drill 0.254)
		(layers "F.Cu" "B.Cu")
		(net "M_E_ECC<5>")
	)
	(via
		(at 233.799888 -143.941546)
		(size 0.508)
		(drill 0.254)
		(layers "F.Cu" "B.Cu")
		(net "M_E_ECC<5>")
	)
	(arc
		(start 246.997474 -98.881438)
		(mid 247.056541 -99.023924)
		(end 247.076722 -99.17684)
		(width 0.0889)
		(layer "F.Cu")
		(net "M_E_ECC<5>")
	)
	(arc
		(start 246.992648 -98.490024)
		(mid 246.943893 -98.686376)
		(end 246.997474 -98.881438)
		(width 0.0889)
		(layer "F.Cu")
		(net "M_E_ECC<5>")
	)
	(segment
		(start 234.649772 -137.877296)
		(end 234.649772 -139.855956)
		(width 0.1651)
		(layer "B.Cu")
		(net "M_E_ECC<5>")
	)
	(segment
		(start 234.65028 -137.877296)
		(end 234.649772 -137.877296)
		(width 0.1651)
		(layer "B.Cu")
		(net "M_E_ECC<5>")
	)
	(segment
		(start 234.649772 -139.855956)
		(end 234.573572 -139.932156)
		(width 0.1651)
		(layer "B.Cu")
		(net "M_E_ECC<5>")
	)
	(segment
		(start 233.961178 -142.985744)
		(end 234.199176 -142.747746)
		(width 0.14224)
		(layer "In9.Cu")
		(net "M_E_ECC<5>")
	)
	(segment
		(start 234.249976 -141.528546)
		(end 234.249976 -141.0462)
		(width 0.14224)
		(layer "In9.Cu")
		(net "M_E_ECC<5>")
	)
	(segment
		(start 234.122976 -140.3604)
		(end 234.55122 -139.932156)
		(width 0.14224)
		(layer "In9.Cu")
		(net "M_E_ECC<5>")
	)
	(segment
		(start 234.55122 -139.932156)
		(end 234.573572 -139.932156)
		(width 0.14224)
		(layer "In9.Cu")
		(net "M_E_ECC<5>")
	)
	(segment
		(start 233.799888 -143.941546)
		(end 234.072176 -143.941546)
		(width 0.14224)
		(layer "In9.Cu")
		(net "M_E_ECC<5>")
	)
	(segment
		(start 234.199176 -142.392654)
		(end 233.961178 -142.154656)
		(width 0.14224)
		(layer "In9.Cu")
		(net "M_E_ECC<5>")
	)
	(segment
		(start 234.224576 -143.561054)
		(end 233.961178 -143.297656)
		(width 0.14224)
		(layer "In9.Cu")
		(net "M_E_ECC<5>")
	)
	(segment
		(start 233.961178 -143.297656)
		(end 233.961178 -142.985744)
		(width 0.14224)
		(layer "In9.Cu")
		(net "M_E_ECC<5>")
	)
	(segment
		(start 234.122976 -140.9192)
		(end 234.122976 -140.3604)
		(width 0.14224)
		(layer "In9.Cu")
		(net "M_E_ECC<5>")
	)
	(segment
		(start 233.961178 -142.154656)
		(end 233.961178 -141.817344)
		(width 0.14224)
		(layer "In9.Cu")
		(net "M_E_ECC<5>")
	)
	(segment
		(start 234.224576 -143.789146)
		(end 234.224576 -143.561054)
		(width 0.14224)
		(layer "In9.Cu")
		(net "M_E_ECC<5>")
	)
	(segment
		(start 234.072176 -143.941546)
		(end 234.224576 -143.789146)
		(width 0.14224)
		(layer "In9.Cu")
		(net "M_E_ECC<5>")
	)
	(segment
		(start 234.249976 -141.0462)
		(end 234.122976 -140.9192)
		(width 0.14224)
		(layer "In9.Cu")
		(net "M_E_ECC<5>")
	)
	(segment
		(start 233.961178 -141.817344)
		(end 234.249976 -141.528546)
		(width 0.14224)
		(layer "In9.Cu")
		(net "M_E_ECC<5>")
	)
	(segment
		(start 234.199176 -142.747746)
		(end 234.199176 -142.392654)
		(width 0.14224)
		(layer "In9.Cu")
		(net "M_E_ECC<5>")
	)
	(segment
		(start 234.983528 -131.434078)
		(end 235.047028 -131.370578)
		(width 0.14224)
		(layer "In11.Cu")
		(net "M_E_ECC<5>")
	)
	(segment
		(start 234.958128 -139.5476)
		(end 234.958128 -138.777472)
		(width 0.14224)
		(layer "In11.Cu")
		(net "M_E_ECC<5>")
	)
	(segment
		(start 234.983528 -131.9276)
		(end 234.983528 -131.434078)
		(width 0.14224)
		(layer "In11.Cu")
		(net "M_E_ECC<5>")
	)
	(segment
		(start 235.077 -138.6586)
		(end 235.077 -136.643872)
		(width 0.14224)
		(layer "In11.Cu")
		(net "M_E_ECC<5>")
	)
	(segment
		(start 234.958128 -136.005824)
		(end 235.110528 -135.853424)
		(width 0.14224)
		(layer "In11.Cu")
		(net "M_E_ECC<5>")
	)
	(segment
		(start 235.047028 -131.370578)
		(end 235.047028 -129.795778)
		(width 0.14224)
		(layer "In11.Cu")
		(net "M_E_ECC<5>")
	)
	(segment
		(start 235.0516 -127.8128)
		(end 235.0516 -125.868176)
		(width 0.14224)
		(layer "In11.Cu")
		(net "M_E_ECC<5>")
	)
	(segment
		(start 235.0008 -127.8636)
		(end 235.0516 -127.8128)
		(width 0.14224)
		(layer "In11.Cu")
		(net "M_E_ECC<5>")
	)
	(segment
		(start 235.0008 -129.74955)
		(end 235.0008 -127.8636)
		(width 0.14224)
		(layer "In11.Cu")
		(net "M_E_ECC<5>")
	)
	(segment
		(start 234.983528 -134.180072)
		(end 235.077 -134.0866)
		(width 0.14224)
		(layer "In11.Cu")
		(net "M_E_ECC<5>")
	)
	(segment
		(start 235.047028 -129.795778)
		(end 235.0008 -129.74955)
		(width 0.14224)
		(layer "In11.Cu")
		(net "M_E_ECC<5>")
	)
	(segment
		(start 234.573572 -139.932156)
		(end 234.958128 -139.5476)
		(width 0.14224)
		(layer "In11.Cu")
		(net "M_E_ECC<5>")
	)
	(segment
		(start 234.958128 -138.777472)
		(end 235.077 -138.6586)
		(width 0.14224)
		(layer "In11.Cu")
		(net "M_E_ECC<5>")
	)
	(segment
		(start 235.077 -136.643872)
		(end 234.958128 -136.525)
		(width 0.14224)
		(layer "In11.Cu")
		(net "M_E_ECC<5>")
	)
	(segment
		(start 234.983528 -134.670038)
		(end 234.983528 -134.180072)
		(width 0.14224)
		(layer "In11.Cu")
		(net "M_E_ECC<5>")
	)
	(segment
		(start 234.958128 -136.525)
		(end 234.958128 -136.005824)
		(width 0.14224)
		(layer "In11.Cu")
		(net "M_E_ECC<5>")
	)
	(segment
		(start 235.110528 -134.797038)
		(end 234.983528 -134.670038)
		(width 0.14224)
		(layer "In11.Cu")
		(net "M_E_ECC<5>")
	)
	(segment
		(start 235.0516 -125.868176)
		(end 234.5944 -125.410976)
		(width 0.14224)
		(layer "In11.Cu")
		(net "M_E_ECC<5>")
	)
	(segment
		(start 235.077 -134.0866)
		(end 235.077 -132.021072)
		(width 0.14224)
		(layer "In11.Cu")
		(net "M_E_ECC<5>")
	)
	(segment
		(start 235.077 -132.021072)
		(end 234.983528 -131.9276)
		(width 0.14224)
		(layer "In11.Cu")
		(net "M_E_ECC<5>")
	)
	(segment
		(start 235.110528 -135.853424)
		(end 235.110528 -134.797038)
		(width 0.14224)
		(layer "In11.Cu")
		(net "M_E_ECC<5>")
	)
	(segment
		(start 246.8372 -102.761034)
		(end 243.25707 -106.341164)
		(width 0.127)
		(layer "F.Cu")
		(net "M_E_ECC<4>")
	)
	(segment
		(start 241.028474 -106.341164)
		(end 234.295696 -113.073942)
		(width 0.1651)
		(layer "F.Cu")
		(net "M_E_ECC<4>")
	)
	(segment
		(start 246.902224 -102.378256)
		(end 246.8372 -102.44328)
		(width 0.0889)
		(layer "F.Cu")
		(net "M_E_ECC<4>")
	)
	(segment
		(start 234.649772 -145.946368)
		(end 234.551728 -145.415)
		(width 0.1651)
		(layer "F.Cu")
		(net "M_E_ECC<4>")
	)
	(segment
		(start 246.803164 -101.763576)
		(end 246.902224 -101.978206)
		(width 0.0889)
		(layer "F.Cu")
		(net "M_E_ECC<4>")
	)
	(segment
		(start 246.8753 -101.290628)
		(end 246.803164 -101.453442)
		(width 0.0889)
		(layer "F.Cu")
		(net "M_E_ECC<4>")
	)
	(segment
		(start 246.725694 -100.823776)
		(end 246.8753 -101.08311)
		(width 0.0889)
		(layer "F.Cu")
		(net "M_E_ECC<4>")
	)
	(segment
		(start 234.1118 -124.587)
		(end 234.1118 -125.577854)
		(width 0.1651)
		(layer "F.Cu")
		(net "M_E_ECC<4>")
	)
	(segment
		(start 234.315 -126.390146)
		(end 234.04957 -126.655576)
		(width 0.1651)
		(layer "F.Cu")
		(net "M_E_ECC<4>")
	)
	(segment
		(start 246.8753 -101.08311)
		(end 246.8753 -101.290628)
		(width 0.0889)
		(layer "F.Cu")
		(net "M_E_ECC<4>")
	)
	(segment
		(start 234.295696 -113.073942)
		(end 234.295696 -124.403104)
		(width 0.1651)
		(layer "F.Cu")
		(net "M_E_ECC<4>")
	)
	(segment
		(start 246.803164 -101.453442)
		(end 246.803164 -101.763576)
		(width 0.0889)
		(layer "F.Cu")
		(net "M_E_ECC<4>")
	)
	(segment
		(start 246.71274 -99.549966)
		(end 246.71274 -99.811332)
		(width 0.0889)
		(layer "F.Cu")
		(net "M_E_ECC<4>")
	)
	(segment
		(start 243.25707 -106.341164)
		(end 241.028474 -106.341164)
		(width 0.127)
		(layer "F.Cu")
		(net "M_E_ECC<4>")
	)
	(segment
		(start 246.8372 -102.44328)
		(end 246.8372 -102.761034)
		(width 0.1016)
		(layer "F.Cu")
		(net "M_E_ECC<4>")
	)
	(segment
		(start 246.885968 -99.249738)
		(end 246.71274 -99.549966)
		(width 0.0889)
		(layer "F.Cu")
		(net "M_E_ECC<4>")
	)
	(segment
		(start 234.65028 -147.27174)
		(end 234.649772 -147.27174)
		(width 0.1651)
		(layer "F.Cu")
		(net "M_E_ECC<4>")
	)
	(segment
		(start 246.902224 -101.978206)
		(end 246.902224 -102.378256)
		(width 0.0889)
		(layer "F.Cu")
		(net "M_E_ECC<4>")
	)
	(segment
		(start 234.315 -125.781054)
		(end 234.315 -126.390146)
		(width 0.1651)
		(layer "F.Cu")
		(net "M_E_ECC<4>")
	)
	(segment
		(start 246.860314 -100.268024)
		(end 246.725694 -100.501196)
		(width 0.0889)
		(layer "F.Cu")
		(net "M_E_ECC<4>")
	)
	(segment
		(start 234.295696 -124.403104)
		(end 234.1118 -124.587)
		(width 0.1651)
		(layer "F.Cu")
		(net "M_E_ECC<4>")
	)
	(segment
		(start 234.649772 -147.27174)
		(end 234.649772 -145.946368)
		(width 0.1651)
		(layer "F.Cu")
		(net "M_E_ECC<4>")
	)
	(segment
		(start 234.04957 -126.655576)
		(end 233.8578 -126.655576)
		(width 0.1651)
		(layer "F.Cu")
		(net "M_E_ECC<4>")
	)
	(segment
		(start 246.885968 -99.17684)
		(end 246.885968 -99.249738)
		(width 0.0889)
		(layer "F.Cu")
		(net "M_E_ECC<4>")
	)
	(segment
		(start 246.860314 -100.066602)
		(end 246.860314 -100.268024)
		(width 0.0889)
		(layer "F.Cu")
		(net "M_E_ECC<4>")
	)
	(segment
		(start 246.71274 -99.811332)
		(end 246.860314 -100.066602)
		(width 0.0889)
		(layer "F.Cu")
		(net "M_E_ECC<4>")
	)
	(segment
		(start 234.1118 -125.577854)
		(end 234.315 -125.781054)
		(width 0.1651)
		(layer "F.Cu")
		(net "M_E_ECC<4>")
	)
	(segment
		(start 246.725694 -100.501196)
		(end 246.725694 -100.823776)
		(width 0.0889)
		(layer "F.Cu")
		(net "M_E_ECC<4>")
	)
	(via
		(at 233.799888 -141.213078)
		(size 0.508)
		(drill 0.254)
		(layers "F.Cu" "B.Cu")
		(net "M_E_ECC<4>")
	)
	(via
		(at 234.551728 -145.415)
		(size 0.508)
		(drill 0.254)
		(layers "F.Cu" "B.Cu")
		(net "M_E_ECC<4>")
	)
	(via
		(at 233.8578 -126.655576)
		(size 0.508)
		(drill 0.254)
		(layers "F.Cu" "B.Cu")
		(net "M_E_ECC<4>")
	)
	(arc
		(start 248.202704 -97.19564)
		(mid 247.769777 -97.260723)
		(end 247.333008 -97.290636)
		(width 0.0889)
		(layer "F.Cu")
		(net "M_E_ECC<4>")
	)
	(arc
		(start 246.832374 -98.976688)
		(mid 246.872361 -99.073234)
		(end 246.885968 -99.17684)
		(width 0.0889)
		(layer "F.Cu")
		(net "M_E_ECC<4>")
	)
	(arc
		(start 247.333008 -97.290636)
		(mid 247.139158 -97.346986)
		(end 246.997474 -97.490788)
		(width 0.0889)
		(layer "F.Cu")
		(net "M_E_ECC<4>")
	)
	(arc
		(start 246.997474 -97.490788)
		(mid 246.976524 -97.532627)
		(end 246.960644 -97.57664)
		(width 0.0889)
		(layer "F.Cu")
		(net "M_E_ECC<4>")
	)
	(arc
		(start 246.826024 -98.396806)
		(mid 246.753226 -98.687569)
		(end 246.832374 -98.976688)
		(width 0.0889)
		(layer "F.Cu")
		(net "M_E_ECC<4>")
	)
	(arc
		(start 246.944896 -97.716086)
		(mid 246.925897 -98.063509)
		(end 246.826024 -98.396806)
		(width 0.0889)
		(layer "F.Cu")
		(net "M_E_ECC<4>")
	)
	(arc
		(start 246.960644 -97.57664)
		(mid 246.946588 -97.645667)
		(end 246.944896 -97.716086)
		(width 0.0889)
		(layer "F.Cu")
		(net "M_E_ECC<4>")
	)
	(segment
		(start 233.799888 -142.476982)
		(end 233.799888 -141.213078)
		(width 0.1651)
		(layer "B.Cu")
		(net "M_E_ECC<4>")
	)
	(segment
		(start 233.800396 -142.477236)
		(end 233.799888 -142.476982)
		(width 0.1651)
		(layer "B.Cu")
		(net "M_E_ECC<4>")
	)
	(segment
		(start 233.524806 -144.63903)
		(end 234.300776 -145.415)
		(width 0.14224)
		(layer "In9.Cu")
		(net "M_E_ECC<4>")
	)
	(segment
		(start 233.524806 -144.337278)
		(end 233.524806 -144.63903)
		(width 0.14224)
		(layer "In9.Cu")
		(net "M_E_ECC<4>")
	)
	(segment
		(start 233.799888 -141.213078)
		(end 233.366818 -141.646148)
		(width 0.14224)
		(layer "In9.Cu")
		(net "M_E_ECC<4>")
	)
	(segment
		(start 233.366818 -141.646148)
		(end 233.366818 -144.17929)
		(width 0.14224)
		(layer "In9.Cu")
		(net "M_E_ECC<4>")
	)
	(segment
		(start 234.300776 -145.415)
		(end 234.551728 -145.415)
		(width 0.14224)
		(layer "In9.Cu")
		(net "M_E_ECC<4>")
	)
	(segment
		(start 233.366818 -144.17929)
		(end 233.524806 -144.337278)
		(width 0.14224)
		(layer "In9.Cu")
		(net "M_E_ECC<4>")
	)
	(segment
		(start 233.8578 -128.721612)
		(end 234.323128 -129.18694)
		(width 0.14224)
		(layer "In11.Cu")
		(net "M_E_ECC<4>")
	)
	(segment
		(start 234.069128 -131.180078)
		(end 234.297728 -131.408678)
		(width 0.14224)
		(layer "In11.Cu")
		(net "M_E_ECC<4>")
	)
	(segment
		(start 234.069128 -129.986278)
		(end 234.069128 -131.180078)
		(width 0.14224)
		(layer "In11.Cu")
		(net "M_E_ECC<4>")
	)
	(segment
		(start 233.798872 -139.845034)
		(end 233.798872 -141.212062)
		(width 0.1016)
		(layer "In11.Cu")
		(net "M_E_ECC<4>")
	)
	(segment
		(start 234.2388 -136.698228)
		(end 234.2388 -138.8364)
		(width 0.14224)
		(layer "In11.Cu")
		(net "M_E_ECC<4>")
	)
	(segment
		(start 234.323128 -129.732278)
		(end 234.069128 -129.986278)
		(width 0.14224)
		(layer "In11.Cu")
		(net "M_E_ECC<4>")
	)
	(segment
		(start 234.285028 -139.358878)
		(end 233.798872 -139.845034)
		(width 0.1016)
		(layer "In11.Cu")
		(net "M_E_ECC<4>")
	)
	(segment
		(start 234.297728 -134.485126)
		(end 234.031536 -134.751318)
		(width 0.14224)
		(layer "In11.Cu")
		(net "M_E_ECC<4>")
	)
	(segment
		(start 234.2388 -131.961128)
		(end 234.2388 -134.0358)
		(width 0.14224)
		(layer "In11.Cu")
		(net "M_E_ECC<4>")
	)
	(segment
		(start 234.2388 -134.0358)
		(end 234.297728 -134.094728)
		(width 0.14224)
		(layer "In11.Cu")
		(net "M_E_ECC<4>")
	)
	(segment
		(start 234.2388 -138.8364)
		(end 234.285028 -138.882628)
		(width 0.14224)
		(layer "In11.Cu")
		(net "M_E_ECC<4>")
	)
	(segment
		(start 233.798872 -141.212062)
		(end 233.799888 -141.213078)
		(width 0.1016)
		(layer "In11.Cu")
		(net "M_E_ECC<4>")
	)
	(segment
		(start 234.285028 -136.652)
		(end 234.2388 -136.698228)
		(width 0.14224)
		(layer "In11.Cu")
		(net "M_E_ECC<4>")
	)
	(segment
		(start 234.297728 -131.9022)
		(end 234.2388 -131.961128)
		(width 0.14224)
		(layer "In11.Cu")
		(net "M_E_ECC<4>")
	)
	(segment
		(start 234.285028 -138.882628)
		(end 234.285028 -139.358878)
		(width 0.14224)
		(layer "In11.Cu")
		(net "M_E_ECC<4>")
	)
	(segment
		(start 234.031536 -135.926576)
		(end 234.285028 -136.180068)
		(width 0.14224)
		(layer "In11.Cu")
		(net "M_E_ECC<4>")
	)
	(segment
		(start 234.031536 -134.751318)
		(end 234.031536 -135.926576)
		(width 0.14224)
		(layer "In11.Cu")
		(net "M_E_ECC<4>")
	)
	(segment
		(start 234.285028 -136.180068)
		(end 234.285028 -136.652)
		(width 0.14224)
		(layer "In11.Cu")
		(net "M_E_ECC<4>")
	)
	(segment
		(start 234.323128 -129.18694)
		(end 234.323128 -129.732278)
		(width 0.14224)
		(layer "In11.Cu")
		(net "M_E_ECC<4>")
	)
	(segment
		(start 234.297728 -131.408678)
		(end 234.297728 -131.9022)
		(width 0.14224)
		(layer "In11.Cu")
		(net "M_E_ECC<4>")
	)
	(segment
		(start 233.8578 -126.655576)
		(end 233.8578 -128.721612)
		(width 0.14224)
		(layer "In11.Cu")
		(net "M_E_ECC<4>")
	)
	(segment
		(start 234.297728 -134.094728)
		(end 234.297728 -134.485126)
		(width 0.14224)
		(layer "In11.Cu")
		(net "M_E_ECC<4>")
	)
	(segment
		(start 243.379498 -121.92)
		(end 243.252498 -121.793)
		(width 0.1651)
		(layer "F.Cu")
		(net "M_E_ECC<3>")
	)
	(segment
		(start 242.744498 -119.186452)
		(end 242.579398 -119.351552)
		(width 0.1651)
		(layer "F.Cu")
		(net "M_E_ECC<3>")
	)
	(segment
		(start 245.305834 -110.452916)
		(end 245.305834 -111.328454)
		(width 0.127)
		(layer "F.Cu")
		(net "M_E_ECC<3>")
	)
	(segment
		(start 243.925598 -121.793)
		(end 243.798598 -121.92)
		(width 0.1651)
		(layer "F.Cu")
		(net "M_E_ECC<3>")
	)
	(segment
		(start 242.579398 -119.351552)
		(end 242.579398 -125.085602)
		(width 0.1651)
		(layer "F.Cu")
		(net "M_E_ECC<3>")
	)
	(segment
		(start 243.252498 -119.351552)
		(end 243.087398 -119.186452)
		(width 0.1651)
		(layer "F.Cu")
		(net "M_E_ECC<3>")
	)
	(segment
		(start 243.252498 -121.793)
		(end 243.252498 -119.351552)
		(width 0.1651)
		(layer "F.Cu")
		(net "M_E_ECC<3>")
	)
	(segment
		(start 250.403614 -99.482148)
		(end 250.403614 -99.956112)
		(width 0.0889)
		(layer "F.Cu")
		(net "M_E_ECC<3>")
	)
	(segment
		(start 243.087398 -119.186452)
		(end 242.744498 -119.186452)
		(width 0.1651)
		(layer "F.Cu")
		(net "M_E_ECC<3>")
	)
	(segment
		(start 243.925598 -112.70869)
		(end 243.925598 -121.793)
		(width 0.1651)
		(layer "F.Cu")
		(net "M_E_ECC<3>")
	)
	(segment
		(start 250.778264 -98.681286)
		(end 250.496324 -99.313492)
		(width 0.0889)
		(layer "F.Cu")
		(net "M_E_ECC<3>")
	)
	(segment
		(start 241.450368 -142.6718)
		(end 241.44986 -142.677642)
		(width 0.1651)
		(layer "F.Cu")
		(net "M_E_ECC<3>")
	)
	(segment
		(start 250.496324 -99.313492)
		(end 250.403614 -99.482148)
		(width 0.0889)
		(layer "F.Cu")
		(net "M_E_ECC<3>")
	)
	(segment
		(start 250.575064 -100.127562)
		(end 250.575064 -100.492814)
		(width 0.0889)
		(layer "F.Cu")
		(net "M_E_ECC<3>")
	)
	(segment
		(start 243.798598 -121.92)
		(end 243.379498 -121.92)
		(width 0.1651)
		(layer "F.Cu")
		(net "M_E_ECC<3>")
	)
	(segment
		(start 242.316 -125.349)
		(end 242.316 -125.6538)
		(width 0.1651)
		(layer "F.Cu")
		(net "M_E_ECC<3>")
	)
	(segment
		(start 245.168166 -111.466122)
		(end 243.925598 -112.70869)
		(width 0.1651)
		(layer "F.Cu")
		(net "M_E_ECC<3>")
	)
	(segment
		(start 250.575064 -100.492814)
		(end 250.575064 -104.054402)
		(width 0.127)
		(layer "F.Cu")
		(net "M_E_ECC<3>")
	)
	(segment
		(start 242.579398 -125.085602)
		(end 242.316 -125.349)
		(width 0.1651)
		(layer "F.Cu")
		(net "M_E_ECC<3>")
	)
	(segment
		(start 245.305834 -111.328454)
		(end 245.168166 -111.466122)
		(width 0.127)
		(layer "F.Cu")
		(net "M_E_ECC<3>")
	)
	(segment
		(start 241.44986 -142.677642)
		(end 241.44986 -143.941546)
		(width 0.1651)
		(layer "F.Cu")
		(net "M_E_ECC<3>")
	)
	(segment
		(start 250.403614 -99.956112)
		(end 250.575064 -100.127562)
		(width 0.0889)
		(layer "F.Cu")
		(net "M_E_ECC<3>")
	)
	(segment
		(start 250.575064 -104.054402)
		(end 249.886724 -104.742742)
		(width 0.127)
		(layer "F.Cu")
		(net "M_E_ECC<3>")
	)
	(segment
		(start 249.886724 -105.872026)
		(end 245.305834 -110.452916)
		(width 0.127)
		(layer "F.Cu")
		(net "M_E_ECC<3>")
	)
	(segment
		(start 249.886724 -104.742742)
		(end 249.886724 -105.872026)
		(width 0.127)
		(layer "F.Cu")
		(net "M_E_ECC<3>")
	)
	(via
		(at 242.299744 -139.932156)
		(size 0.508)
		(drill 0.254)
		(layers "F.Cu" "B.Cu")
		(net "M_E_ECC<3>")
	)
	(via
		(at 242.316 -125.6538)
		(size 0.508)
		(drill 0.254)
		(layers "F.Cu" "B.Cu")
		(net "M_E_ECC<3>")
	)
	(via
		(at 241.44986 -143.941546)
		(size 0.508)
		(drill 0.254)
		(layers "F.Cu" "B.Cu")
		(net "M_E_ECC<3>")
	)
	(segment
		(start 242.299744 -138.626596)
		(end 242.299744 -139.932156)
		(width 0.1651)
		(layer "B.Cu")
		(net "M_E_ECC<3>")
	)
	(segment
		(start 242.300506 -137.877296)
		(end 242.299998 -137.877296)
		(width 0.1651)
		(layer "B.Cu")
		(net "M_E_ECC<3>")
	)
	(segment
		(start 242.299998 -137.877296)
		(end 242.299998 -138.626342)
		(width 0.1651)
		(layer "B.Cu")
		(net "M_E_ECC<3>")
	)
	(segment
		(start 242.299998 -138.626342)
		(end 242.299744 -138.626596)
		(width 0.1651)
		(layer "B.Cu")
		(net "M_E_ECC<3>")
	)
	(segment
		(start 241.893598 -141.5034)
		(end 241.893598 -140.834618)
		(width 0.14224)
		(layer "In9.Cu")
		(net "M_E_ECC<3>")
	)
	(segment
		(start 241.899948 -143.44015)
		(end 241.61115 -143.151352)
		(width 0.14224)
		(layer "In9.Cu")
		(net "M_E_ECC<3>")
	)
	(segment
		(start 241.899948 -143.763746)
		(end 241.899948 -143.44015)
		(width 0.14224)
		(layer "In9.Cu")
		(net "M_E_ECC<3>")
	)
	(segment
		(start 241.868198 -142.621)
		(end 241.868198 -142.3162)
		(width 0.14224)
		(layer "In9.Cu")
		(net "M_E_ECC<3>")
	)
	(segment
		(start 241.893598 -140.834618)
		(end 241.849148 -140.790168)
		(width 0.14224)
		(layer "In9.Cu")
		(net "M_E_ECC<3>")
	)
	(segment
		(start 241.61115 -142.878048)
		(end 241.868198 -142.621)
		(width 0.14224)
		(layer "In9.Cu")
		(net "M_E_ECC<3>")
	)
	(segment
		(start 241.849148 -140.790168)
		(end 241.849148 -140.3604)
		(width 0.14224)
		(layer "In9.Cu")
		(net "M_E_ECC<3>")
	)
	(segment
		(start 241.849148 -140.3604)
		(end 242.277392 -139.932156)
		(width 0.14224)
		(layer "In9.Cu")
		(net "M_E_ECC<3>")
	)
	(segment
		(start 242.277392 -139.932156)
		(end 242.299744 -139.932156)
		(width 0.14224)
		(layer "In9.Cu")
		(net "M_E_ECC<3>")
	)
	(segment
		(start 241.44986 -143.941546)
		(end 241.722148 -143.941546)
		(width 0.14224)
		(layer "In9.Cu")
		(net "M_E_ECC<3>")
	)
	(segment
		(start 241.61115 -141.785848)
		(end 241.893598 -141.5034)
		(width 0.14224)
		(layer "In9.Cu")
		(net "M_E_ECC<3>")
	)
	(segment
		(start 241.868198 -142.3162)
		(end 241.61115 -142.059152)
		(width 0.14224)
		(layer "In9.Cu")
		(net "M_E_ECC<3>")
	)
	(segment
		(start 241.61115 -142.059152)
		(end 241.61115 -141.785848)
		(width 0.14224)
		(layer "In9.Cu")
		(net "M_E_ECC<3>")
	)
	(segment
		(start 241.61115 -143.151352)
		(end 241.61115 -142.878048)
		(width 0.14224)
		(layer "In9.Cu")
		(net "M_E_ECC<3>")
	)
	(segment
		(start 241.722148 -143.941546)
		(end 241.899948 -143.763746)
		(width 0.14224)
		(layer "In9.Cu")
		(net "M_E_ECC<3>")
	)
	(segment
		(start 242.868196 -126.205996)
		(end 242.316 -125.6538)
		(width 0.14224)
		(layer "In11.Cu")
		(net "M_E_ECC<3>")
	)
	(segment
		(start 242.628928 -136.288272)
		(end 242.791996 -136.125204)
		(width 0.14224)
		(layer "In11.Cu")
		(net "M_E_ECC<3>")
	)
	(segment
		(start 242.654328 -129.658872)
		(end 242.868196 -129.445004)
		(width 0.14224)
		(layer "In11.Cu")
		(net "M_E_ECC<3>")
	)
	(segment
		(start 242.791996 -134.706106)
		(end 242.667028 -134.581138)
		(width 0.14224)
		(layer "In11.Cu")
		(net "M_E_ECC<3>")
	)
	(segment
		(start 242.628928 -139.61618)
		(end 242.628928 -136.288272)
		(width 0.14224)
		(layer "In11.Cu")
		(net "M_E_ECC<3>")
	)
	(segment
		(start 242.791996 -136.125204)
		(end 242.791996 -134.706106)
		(width 0.14224)
		(layer "In11.Cu")
		(net "M_E_ECC<3>")
	)
	(segment
		(start 242.806728 -130.113278)
		(end 242.654328 -129.960878)
		(width 0.14224)
		(layer "In11.Cu")
		(net "M_E_ECC<3>")
	)
	(segment
		(start 242.654328 -129.960878)
		(end 242.654328 -129.658872)
		(width 0.14224)
		(layer "In11.Cu")
		(net "M_E_ECC<3>")
	)
	(segment
		(start 242.299744 -139.932156)
		(end 242.299744 -139.945364)
		(width 0.14224)
		(layer "In11.Cu")
		(net "M_E_ECC<3>")
	)
	(segment
		(start 242.299744 -139.945364)
		(end 242.628928 -139.61618)
		(width 0.14224)
		(layer "In11.Cu")
		(net "M_E_ECC<3>")
	)
	(segment
		(start 242.667028 -131.408678)
		(end 242.806728 -131.268978)
		(width 0.14224)
		(layer "In11.Cu")
		(net "M_E_ECC<3>")
	)
	(segment
		(start 242.667028 -134.581138)
		(end 242.667028 -131.408678)
		(width 0.14224)
		(layer "In11.Cu")
		(net "M_E_ECC<3>")
	)
	(segment
		(start 242.806728 -131.268978)
		(end 242.806728 -130.113278)
		(width 0.14224)
		(layer "In11.Cu")
		(net "M_E_ECC<3>")
	)
	(segment
		(start 242.868196 -129.445004)
		(end 242.868196 -126.205996)
		(width 0.14224)
		(layer "In11.Cu")
		(net "M_E_ECC<3>")
	)
	(segment
		(start 242.434618 -117.060218)
		(end 242.091718 -117.060218)
		(width 0.1651)
		(layer "F.Cu")
		(net "M_E_ECC<2>")
	)
	(segment
		(start 242.599718 -117.9068)
		(end 242.599718 -117.225318)
		(width 0.1651)
		(layer "F.Cu")
		(net "M_E_ECC<2>")
	)
	(segment
		(start 242.431316 -145.92554)
		(end 242.299744 -145.793968)
		(width 0.1651)
		(layer "F.Cu")
		(net "M_E_ECC<2>")
	)
	(segment
		(start 250.270518 -99.317302)
		(end 250.173236 -99.495864)
		(width 0.0889)
		(layer "F.Cu")
		(net "M_E_ECC<2>")
	)
	(segment
		(start 244.937534 -110.790228)
		(end 244.77726 -110.950502)
		(width 0.1016)
		(layer "F.Cu")
		(net "M_E_ECC<2>")
	)
	(segment
		(start 250.778264 -97.691448)
		(end 250.300236 -98.33356)
		(width 0.0889)
		(layer "F.Cu")
		(net "M_E_ECC<2>")
	)
	(segment
		(start 243.272818 -112.454944)
		(end 243.272818 -117.9068)
		(width 0.1651)
		(layer "F.Cu")
		(net "M_E_ECC<2>")
	)
	(segment
		(start 250.173236 -100.069904)
		(end 250.257564 -100.154232)
		(width 0.0889)
		(layer "F.Cu")
		(net "M_E_ECC<2>")
	)
	(segment
		(start 250.257564 -103.92283)
		(end 249.569224 -104.61117)
		(width 0.1016)
		(layer "F.Cu")
		(net "M_E_ECC<2>")
	)
	(segment
		(start 249.569224 -105.614978)
		(end 244.937534 -110.246668)
		(width 0.1016)
		(layer "F.Cu")
		(net "M_E_ECC<2>")
	)
	(segment
		(start 242.726718 -118.0338)
		(end 242.599718 -117.9068)
		(width 0.1651)
		(layer "F.Cu")
		(net "M_E_ECC<2>")
	)
	(segment
		(start 244.77726 -110.950502)
		(end 243.272818 -112.454944)
		(width 0.1651)
		(layer "F.Cu")
		(net "M_E_ECC<2>")
	)
	(segment
		(start 241.935 -117.216936)
		(end 241.935 -124.841)
		(width 0.1651)
		(layer "F.Cu")
		(net "M_E_ECC<2>")
	)
	(segment
		(start 250.257564 -100.154232)
		(end 250.257564 -100.492814)
		(width 0.0889)
		(layer "F.Cu")
		(net "M_E_ECC<2>")
	)
	(segment
		(start 242.431316 -146.14906)
		(end 242.431316 -145.92554)
		(width 0.1651)
		(layer "F.Cu")
		(net "M_E_ECC<2>")
	)
	(segment
		(start 242.299744 -147.27174)
		(end 242.299744 -146.280632)
		(width 0.1651)
		(layer "F.Cu")
		(net "M_E_ECC<2>")
	)
	(segment
		(start 249.569224 -104.61117)
		(end 249.569224 -105.614978)
		(width 0.1016)
		(layer "F.Cu")
		(net "M_E_ECC<2>")
	)
	(segment
		(start 242.300506 -147.27174)
		(end 242.299744 -147.27174)
		(width 0.1651)
		(layer "F.Cu")
		(net "M_E_ECC<2>")
	)
	(segment
		(start 241.935 -124.841)
		(end 241.4778 -125.2982)
		(width 0.1651)
		(layer "F.Cu")
		(net "M_E_ECC<2>")
	)
	(segment
		(start 243.272818 -117.9068)
		(end 243.145818 -118.0338)
		(width 0.1651)
		(layer "F.Cu")
		(net "M_E_ECC<2>")
	)
	(segment
		(start 242.599718 -117.225318)
		(end 242.434618 -117.060218)
		(width 0.1651)
		(layer "F.Cu")
		(net "M_E_ECC<2>")
	)
	(segment
		(start 250.257564 -100.492814)
		(end 250.257564 -103.92283)
		(width 0.1016)
		(layer "F.Cu")
		(net "M_E_ECC<2>")
	)
	(segment
		(start 242.299744 -146.280632)
		(end 242.431316 -146.14906)
		(width 0.1651)
		(layer "F.Cu")
		(net "M_E_ECC<2>")
	)
	(segment
		(start 242.299744 -145.793968)
		(end 242.299744 -145.5166)
		(width 0.1651)
		(layer "F.Cu")
		(net "M_E_ECC<2>")
	)
	(segment
		(start 250.778264 -97.690686)
		(end 250.778264 -97.691448)
		(width 0.0889)
		(layer "F.Cu")
		(net "M_E_ECC<2>")
	)
	(segment
		(start 244.937534 -110.246668)
		(end 244.937534 -110.790228)
		(width 0.1016)
		(layer "F.Cu")
		(net "M_E_ECC<2>")
	)
	(segment
		(start 243.145818 -118.0338)
		(end 242.726718 -118.0338)
		(width 0.1651)
		(layer "F.Cu")
		(net "M_E_ECC<2>")
	)
	(segment
		(start 250.173236 -99.495864)
		(end 250.173236 -100.069904)
		(width 0.0889)
		(layer "F.Cu")
		(net "M_E_ECC<2>")
	)
	(segment
		(start 242.091718 -117.060218)
		(end 241.935 -117.216936)
		(width 0.1651)
		(layer "F.Cu")
		(net "M_E_ECC<2>")
	)
	(via
		(at 242.299744 -145.5166)
		(size 0.508)
		(drill 0.254)
		(layers "F.Cu" "B.Cu")
		(net "M_E_ECC<2>")
	)
	(via
		(at 241.4778 -125.2982)
		(size 0.508)
		(drill 0.254)
		(layers "F.Cu" "B.Cu")
		(net "M_E_ECC<2>")
	)
	(via
		(at 241.44986 -141.213078)
		(size 0.508)
		(drill 0.254)
		(layers "F.Cu" "B.Cu")
		(net "M_E_ECC<2>")
	)
	(arc
		(start 250.300236 -98.33356)
		(mid 250.188102 -98.650107)
		(end 250.266454 -98.976688)
		(width 0.0889)
		(layer "F.Cu")
		(net "M_E_ECC<2>")
	)
	(arc
		(start 250.266454 -98.976688)
		(mid 250.312997 -99.146471)
		(end 250.270518 -99.317302)
		(width 0.0889)
		(layer "F.Cu")
		(net "M_E_ECC<2>")
	)
	(segment
		(start 241.44986 -142.476982)
		(end 241.44986 -141.213078)
		(width 0.1651)
		(layer "B.Cu")
		(net "M_E_ECC<2>")
	)
	(segment
		(start 241.450368 -142.477236)
		(end 241.44986 -142.476982)
		(width 0.1651)
		(layer "B.Cu")
		(net "M_E_ECC<2>")
	)
	(segment
		(start 241.44986 -141.213078)
		(end 241.01679 -141.646148)
		(width 0.14224)
		(layer "In9.Cu")
		(net "M_E_ECC<2>")
	)
	(segment
		(start 241.01679 -144.233646)
		(end 242.299744 -145.5166)
		(width 0.14224)
		(layer "In9.Cu")
		(net "M_E_ECC<2>")
	)
	(segment
		(start 241.01679 -141.646148)
		(end 241.01679 -144.233646)
		(width 0.14224)
		(layer "In9.Cu")
		(net "M_E_ECC<2>")
	)
	(segment
		(start 241.816128 -129.960878)
		(end 241.943128 -129.833878)
		(width 0.14224)
		(layer "In11.Cu")
		(net "M_E_ECC<2>")
	)
	(segment
		(start 241.44986 -141.213078)
		(end 241.104928 -140.868146)
		(width 0.14224)
		(layer "In11.Cu")
		(net "M_E_ECC<2>")
	)
	(segment
		(start 241.8588 -138.7094)
		(end 241.8588 -136.736328)
		(width 0.14224)
		(layer "In11.Cu")
		(net "M_E_ECC<2>")
	)
	(segment
		(start 241.968528 -136.205468)
		(end 241.739928 -135.976868)
		(width 0.14224)
		(layer "In11.Cu")
		(net "M_E_ECC<2>")
	)
	(segment
		(start 241.968528 -138.819128)
		(end 241.8588 -138.7094)
		(width 0.14224)
		(layer "In11.Cu")
		(net "M_E_ECC<2>")
	)
	(segment
		(start 241.104928 -140.235178)
		(end 241.968528 -139.371578)
		(width 0.14224)
		(layer "In11.Cu")
		(net "M_E_ECC<2>")
	)
	(segment
		(start 241.968528 -136.6266)
		(end 241.968528 -136.205468)
		(width 0.14224)
		(layer "In11.Cu")
		(net "M_E_ECC<2>")
	)
	(segment
		(start 241.8842 -127.482854)
		(end 241.8842 -125.7046)
		(width 0.14224)
		(layer "In11.Cu")
		(net "M_E_ECC<2>")
	)
	(segment
		(start 242.019328 -134.492238)
		(end 242.019328 -131.535678)
		(width 0.14224)
		(layer "In11.Cu")
		(net "M_E_ECC<2>")
	)
	(segment
		(start 241.8842 -125.7046)
		(end 241.4778 -125.2982)
		(width 0.14224)
		(layer "In11.Cu")
		(net "M_E_ECC<2>")
	)
	(segment
		(start 241.943128 -129.833878)
		(end 241.943128 -127.541782)
		(width 0.14224)
		(layer "In11.Cu")
		(net "M_E_ECC<2>")
	)
	(segment
		(start 241.739928 -134.771638)
		(end 242.019328 -134.492238)
		(width 0.14224)
		(layer "In11.Cu")
		(net "M_E_ECC<2>")
	)
	(segment
		(start 241.943128 -127.541782)
		(end 241.8842 -127.482854)
		(width 0.14224)
		(layer "In11.Cu")
		(net "M_E_ECC<2>")
	)
	(segment
		(start 241.739928 -135.976868)
		(end 241.739928 -134.771638)
		(width 0.14224)
		(layer "In11.Cu")
		(net "M_E_ECC<2>")
	)
	(segment
		(start 241.968528 -139.371578)
		(end 241.968528 -138.819128)
		(width 0.14224)
		(layer "In11.Cu")
		(net "M_E_ECC<2>")
	)
	(segment
		(start 241.8588 -136.736328)
		(end 241.968528 -136.6266)
		(width 0.14224)
		(layer "In11.Cu")
		(net "M_E_ECC<2>")
	)
	(segment
		(start 242.019328 -131.535678)
		(end 241.816128 -131.332478)
		(width 0.14224)
		(layer "In11.Cu")
		(net "M_E_ECC<2>")
	)
	(segment
		(start 241.816128 -131.332478)
		(end 241.816128 -129.960878)
		(width 0.14224)
		(layer "In11.Cu")
		(net "M_E_ECC<2>")
	)
	(segment
		(start 241.104928 -140.868146)
		(end 241.104928 -140.235178)
		(width 0.14224)
		(layer "In11.Cu")
		(net "M_E_ECC<2>")
	)
	(segment
		(start 248.123964 -103.037386)
		(end 247.435624 -103.725726)
		(width 0.1016)
		(layer "F.Cu")
		(net "M_E_ECC<1>")
	)
	(segment
		(start 236.8423 -118.71833)
		(end 236.495336 -118.71833)
		(width 0.1651)
		(layer "F.Cu")
		(net "M_E_ECC<1>")
	)
	(segment
		(start 236.887512 -123.759468)
		(end 236.887512 -124.156216)
		(width 0.1651)
		(layer "F.Cu")
		(net "M_E_ECC<1>")
	)
	(segment
		(start 236.887512 -124.156216)
		(end 236.670596 -124.373132)
		(width 0.1651)
		(layer "F.Cu")
		(net "M_E_ECC<1>")
	)
	(segment
		(start 237.0074 -121.339864)
		(end 236.772196 -121.575068)
		(width 0.1651)
		(layer "F.Cu")
		(net "M_E_ECC<1>")
	)
	(segment
		(start 237.033054 -119.89308)
		(end 236.861604 -120.06453)
		(width 0.1651)
		(layer "F.Cu")
		(net "M_E_ECC<1>")
	)
	(segment
		(start 236.861604 -120.06453)
		(end 236.495336 -120.06453)
		(width 0.1651)
		(layer "F.Cu")
		(net "M_E_ECC<1>")
	)
	(segment
		(start 236.495336 -118.71833)
		(end 236.330236 -118.88343)
		(width 0.1651)
		(layer "F.Cu")
		(net "M_E_ECC<1>")
	)
	(segment
		(start 236.8804 -118.04523)
		(end 237.02645 -118.19128)
		(width 0.1651)
		(layer "F.Cu")
		(net "M_E_ECC<1>")
	)
	(segment
		(start 236.5248 -117.91823)
		(end 236.6518 -118.04523)
		(width 0.1651)
		(layer "F.Cu")
		(net "M_E_ECC<1>")
	)
	(segment
		(start 236.33684 -123.429268)
		(end 236.50194 -123.594368)
		(width 0.1651)
		(layer "F.Cu")
		(net "M_E_ECC<1>")
	)
	(segment
		(start 235.49991 -142.677642)
		(end 235.49991 -143.941546)
		(width 0.1651)
		(layer "F.Cu")
		(net "M_E_ECC<1>")
	)
	(segment
		(start 236.33684 -121.740168)
		(end 236.33684 -122.083068)
		(width 0.1651)
		(layer "F.Cu")
		(net "M_E_ECC<1>")
	)
	(segment
		(start 237.02645 -118.53418)
		(end 236.8423 -118.71833)
		(width 0.1651)
		(layer "F.Cu")
		(net "M_E_ECC<1>")
	)
	(segment
		(start 236.33684 -123.086368)
		(end 236.33684 -123.429268)
		(width 0.1651)
		(layer "F.Cu")
		(net "M_E_ECC<1>")
	)
	(segment
		(start 236.8423 -117.37213)
		(end 236.6518 -117.37213)
		(width 0.1651)
		(layer "F.Cu")
		(net "M_E_ECC<1>")
	)
	(segment
		(start 247.435624 -103.851202)
		(end 243.75237 -107.534456)
		(width 0.1016)
		(layer "F.Cu")
		(net "M_E_ECC<1>")
	)
	(segment
		(start 236.6518 -118.04523)
		(end 236.8804 -118.04523)
		(width 0.1651)
		(layer "F.Cu")
		(net "M_E_ECC<1>")
	)
	(segment
		(start 236.330236 -118.88343)
		(end 236.330236 -119.22633)
		(width 0.1651)
		(layer "F.Cu")
		(net "M_E_ECC<1>")
	)
	(segment
		(start 247.435624 -103.725726)
		(end 247.435624 -103.851202)
		(width 0.1016)
		(layer "F.Cu")
		(net "M_E_ECC<1>")
	)
	(segment
		(start 237.033054 -119.55018)
		(end 237.033054 -119.89308)
		(width 0.1651)
		(layer "F.Cu")
		(net "M_E_ECC<1>")
	)
	(segment
		(start 236.495336 -120.73763)
		(end 236.8423 -120.73763)
		(width 0.1651)
		(layer "F.Cu")
		(net "M_E_ECC<1>")
	)
	(segment
		(start 236.8423 -120.73763)
		(end 237.0074 -120.90273)
		(width 0.1651)
		(layer "F.Cu")
		(net "M_E_ECC<1>")
	)
	(segment
		(start 248.123964 -100.492814)
		(end 248.123964 -103.037386)
		(width 0.1016)
		(layer "F.Cu")
		(net "M_E_ECC<1>")
	)
	(segment
		(start 236.722412 -122.921268)
		(end 236.50194 -122.921268)
		(width 0.1651)
		(layer "F.Cu")
		(net "M_E_ECC<1>")
	)
	(segment
		(start 243.75237 -107.534456)
		(end 242.606576 -107.534456)
		(width 0.1016)
		(layer "F.Cu")
		(net "M_E_ECC<1>")
	)
	(segment
		(start 248.123964 -99.25558)
		(end 248.123964 -100.492814)
		(width 0.0889)
		(layer "F.Cu")
		(net "M_E_ECC<1>")
	)
	(segment
		(start 236.6518 -117.37213)
		(end 236.5248 -117.49913)
		(width 0.1651)
		(layer "F.Cu")
		(net "M_E_ECC<1>")
	)
	(segment
		(start 242.365784 -107.775248)
		(end 237.0074 -113.133632)
		(width 0.1651)
		(layer "F.Cu")
		(net "M_E_ECC<1>")
	)
	(segment
		(start 236.722412 -123.594368)
		(end 236.887512 -123.759468)
		(width 0.1651)
		(layer "F.Cu")
		(net "M_E_ECC<1>")
	)
	(segment
		(start 236.330236 -119.22633)
		(end 236.495336 -119.39143)
		(width 0.1651)
		(layer "F.Cu")
		(net "M_E_ECC<1>")
	)
	(segment
		(start 236.722412 -122.248168)
		(end 236.887512 -122.413268)
		(width 0.1651)
		(layer "F.Cu")
		(net "M_E_ECC<1>")
	)
	(segment
		(start 236.330236 -120.22963)
		(end 236.330236 -120.57253)
		(width 0.1651)
		(layer "F.Cu")
		(net "M_E_ECC<1>")
	)
	(segment
		(start 236.670596 -124.373132)
		(end 236.670596 -124.785374)
		(width 0.1651)
		(layer "F.Cu")
		(net "M_E_ECC<1>")
	)
	(segment
		(start 236.887512 -122.413268)
		(end 236.887512 -122.756168)
		(width 0.1651)
		(layer "F.Cu")
		(net "M_E_ECC<1>")
	)
	(segment
		(start 236.33684 -122.083068)
		(end 236.50194 -122.248168)
		(width 0.1651)
		(layer "F.Cu")
		(net "M_E_ECC<1>")
	)
	(segment
		(start 237.02645 -118.19128)
		(end 237.02645 -118.53418)
		(width 0.1651)
		(layer "F.Cu")
		(net "M_E_ECC<1>")
	)
	(segment
		(start 236.50194 -121.575068)
		(end 236.33684 -121.740168)
		(width 0.1651)
		(layer "F.Cu")
		(net "M_E_ECC<1>")
	)
	(segment
		(start 236.50194 -122.248168)
		(end 236.722412 -122.248168)
		(width 0.1651)
		(layer "F.Cu")
		(net "M_E_ECC<1>")
	)
	(segment
		(start 236.495336 -119.39143)
		(end 236.874304 -119.39143)
		(width 0.1651)
		(layer "F.Cu")
		(net "M_E_ECC<1>")
	)
	(segment
		(start 248.202704 -99.17684)
		(end 248.123964 -99.25558)
		(width 0.0889)
		(layer "F.Cu")
		(net "M_E_ECC<1>")
	)
	(segment
		(start 236.772196 -121.575068)
		(end 236.50194 -121.575068)
		(width 0.1651)
		(layer "F.Cu")
		(net "M_E_ECC<1>")
	)
	(segment
		(start 237.0074 -113.133632)
		(end 237.0074 -117.20703)
		(width 0.1651)
		(layer "F.Cu")
		(net "M_E_ECC<1>")
	)
	(segment
		(start 242.606576 -107.534456)
		(end 242.365784 -107.775248)
		(width 0.1016)
		(layer "F.Cu")
		(net "M_E_ECC<1>")
	)
	(segment
		(start 236.330236 -120.57253)
		(end 236.495336 -120.73763)
		(width 0.1651)
		(layer "F.Cu")
		(net "M_E_ECC<1>")
	)
	(segment
		(start 236.5248 -117.49913)
		(end 236.5248 -117.91823)
		(width 0.1651)
		(layer "F.Cu")
		(net "M_E_ECC<1>")
	)
	(segment
		(start 236.874304 -119.39143)
		(end 237.033054 -119.55018)
		(width 0.1651)
		(layer "F.Cu")
		(net "M_E_ECC<1>")
	)
	(segment
		(start 236.887512 -122.756168)
		(end 236.722412 -122.921268)
		(width 0.1651)
		(layer "F.Cu")
		(net "M_E_ECC<1>")
	)
	(segment
		(start 237.0074 -120.90273)
		(end 237.0074 -121.339864)
		(width 0.1651)
		(layer "F.Cu")
		(net "M_E_ECC<1>")
	)
	(segment
		(start 236.50194 -122.921268)
		(end 236.33684 -123.086368)
		(width 0.1651)
		(layer "F.Cu")
		(net "M_E_ECC<1>")
	)
	(segment
		(start 236.495336 -120.06453)
		(end 236.330236 -120.22963)
		(width 0.1651)
		(layer "F.Cu")
		(net "M_E_ECC<1>")
	)
	(segment
		(start 237.0074 -117.20703)
		(end 236.8423 -117.37213)
		(width 0.1651)
		(layer "F.Cu")
		(net "M_E_ECC<1>")
	)
	(segment
		(start 236.50194 -123.594368)
		(end 236.722412 -123.594368)
		(width 0.1651)
		(layer "F.Cu")
		(net "M_E_ECC<1>")
	)
	(segment
		(start 236.670596 -124.785374)
		(end 236.171994 -125.283976)
		(width 0.1651)
		(layer "F.Cu")
		(net "M_E_ECC<1>")
	)
	(segment
		(start 235.500418 -142.6718)
		(end 235.49991 -142.677642)
		(width 0.1651)
		(layer "F.Cu")
		(net "M_E_ECC<1>")
	)
	(via
		(at 236.171994 -139.932156)
		(size 0.508)
		(drill 0.254)
		(layers "F.Cu" "B.Cu")
		(net "M_E_ECC<1>")
	)
	(via
		(at 236.171994 -125.283976)
		(size 0.508)
		(drill 0.254)
		(layers "F.Cu" "B.Cu")
		(net "M_E_ECC<1>")
	)
	(via
		(at 235.49991 -143.941546)
		(size 0.508)
		(drill 0.254)
		(layers "F.Cu" "B.Cu")
		(net "M_E_ECC<1>")
	)
	(segment
		(start 236.349794 -137.877296)
		(end 236.349794 -139.251182)
		(width 0.1651)
		(layer "B.Cu")
		(net "M_E_ECC<1>")
	)
	(segment
		(start 236.349794 -139.251182)
		(end 236.171994 -139.428982)
		(width 0.1651)
		(layer "B.Cu")
		(net "M_E_ECC<1>")
	)
	(segment
		(start 236.171994 -139.428982)
		(end 236.171994 -139.932156)
		(width 0.1651)
		(layer "B.Cu")
		(net "M_E_ECC<1>")
	)
	(segment
		(start 236.350302 -137.877296)
		(end 236.349794 -137.877296)
		(width 0.1651)
		(layer "B.Cu")
		(net "M_E_ECC<1>")
	)
	(segment
		(start 235.875576 -142.7226)
		(end 235.875576 -142.2908)
		(width 0.14224)
		(layer "In9.Cu")
		(net "M_E_ECC<1>")
	)
	(segment
		(start 235.875576 -142.2908)
		(end 235.6612 -142.076424)
		(width 0.14224)
		(layer "In9.Cu")
		(net "M_E_ECC<1>")
	)
	(segment
		(start 235.6612 -143.244824)
		(end 235.6612 -142.936976)
		(width 0.14224)
		(layer "In9.Cu")
		(net "M_E_ECC<1>")
	)
	(segment
		(start 235.951776 -141.020546)
		(end 235.721398 -140.790168)
		(width 0.14224)
		(layer "In9.Cu")
		(net "M_E_ECC<1>")
	)
	(segment
		(start 235.74883 -143.941546)
		(end 235.900976 -143.7894)
		(width 0.14224)
		(layer "In9.Cu")
		(net "M_E_ECC<1>")
	)
	(segment
		(start 235.951776 -141.425168)
		(end 235.951776 -141.020546)
		(width 0.14224)
		(layer "In9.Cu")
		(net "M_E_ECC<1>")
	)
	(segment
		(start 235.721398 -140.790168)
		(end 235.721398 -140.3604)
		(width 0.14224)
		(layer "In9.Cu")
		(net "M_E_ECC<1>")
	)
	(segment
		(start 236.149642 -139.932156)
		(end 236.171994 -139.932156)
		(width 0.14224)
		(layer "In9.Cu")
		(net "M_E_ECC<1>")
	)
	(segment
		(start 235.900976 -143.7894)
		(end 235.900976 -143.4846)
		(width 0.14224)
		(layer "In9.Cu")
		(net "M_E_ECC<1>")
	)
	(segment
		(start 235.49991 -143.941546)
		(end 235.74883 -143.941546)
		(width 0.14224)
		(layer "In9.Cu")
		(net "M_E_ECC<1>")
	)
	(segment
		(start 235.721398 -140.3604)
		(end 236.149642 -139.932156)
		(width 0.14224)
		(layer "In9.Cu")
		(net "M_E_ECC<1>")
	)
	(segment
		(start 235.900976 -143.4846)
		(end 235.6612 -143.244824)
		(width 0.14224)
		(layer "In9.Cu")
		(net "M_E_ECC<1>")
	)
	(segment
		(start 235.6612 -142.936976)
		(end 235.875576 -142.7226)
		(width 0.14224)
		(layer "In9.Cu")
		(net "M_E_ECC<1>")
	)
	(segment
		(start 235.6612 -142.076424)
		(end 235.6612 -141.715744)
		(width 0.14224)
		(layer "In9.Cu")
		(net "M_E_ECC<1>")
	)
	(segment
		(start 235.6612 -141.715744)
		(end 235.951776 -141.425168)
		(width 0.14224)
		(layer "In9.Cu")
		(net "M_E_ECC<1>")
	)
	(segment
		(start 236.659928 -136.5758)
		(end 236.7788 -136.694672)
		(width 0.14224)
		(layer "In11.Cu")
		(net "M_E_ECC<1>")
	)
	(segment
		(start 236.659928 -138.879072)
		(end 236.659928 -139.355322)
		(width 0.14224)
		(layer "In11.Cu")
		(net "M_E_ECC<1>")
	)
	(segment
		(start 236.659928 -134.180072)
		(end 236.659928 -136.5758)
		(width 0.14224)
		(layer "In11.Cu")
		(net "M_E_ECC<1>")
	)
	(segment
		(start 236.659928 -139.355322)
		(end 236.171994 -139.843256)
		(width 0.14224)
		(layer "In11.Cu")
		(net "M_E_ECC<1>")
	)
	(segment
		(start 236.659928 -128.475994)
		(end 236.659928 -131.681728)
		(width 0.14224)
		(layer "In11.Cu")
		(net "M_E_ECC<1>")
	)
	(segment
		(start 236.171994 -139.843256)
		(end 236.171994 -139.932156)
		(width 0.14224)
		(layer "In11.Cu")
		(net "M_E_ECC<1>")
	)
	(segment
		(start 236.171994 -127.98806)
		(end 236.659928 -128.475994)
		(width 0.14224)
		(layer "In11.Cu")
		(net "M_E_ECC<1>")
	)
	(segment
		(start 236.171994 -125.283976)
		(end 236.171994 -127.98806)
		(width 0.14224)
		(layer "In11.Cu")
		(net "M_E_ECC<1>")
	)
	(segment
		(start 236.659928 -131.681728)
		(end 236.7788 -131.8006)
		(width 0.14224)
		(layer "In11.Cu")
		(net "M_E_ECC<1>")
	)
	(segment
		(start 236.7788 -131.8006)
		(end 236.7788 -134.0612)
		(width 0.14224)
		(layer "In11.Cu")
		(net "M_E_ECC<1>")
	)
	(segment
		(start 236.7788 -138.7602)
		(end 236.659928 -138.879072)
		(width 0.14224)
		(layer "In11.Cu")
		(net "M_E_ECC<1>")
	)
	(segment
		(start 236.7788 -134.0612)
		(end 236.659928 -134.180072)
		(width 0.14224)
		(layer "In11.Cu")
		(net "M_E_ECC<1>")
	)
	(segment
		(start 236.7788 -136.694672)
		(end 236.7788 -138.7602)
		(width 0.14224)
		(layer "In11.Cu")
		(net "M_E_ECC<1>")
	)
	(segment
		(start 235.6358 -117.434614)
		(end 235.6358 -123.7742)
		(width 0.1651)
		(layer "F.Cu")
		(net "M_E_ECC<0>")
	)
	(segment
		(start 236.349794 -147.277582)
		(end 236.171994 -145.415)
		(width 0.1651)
		(layer "F.Cu")
		(net "M_E_ECC<0>")
	)
	(segment
		(start 247.584976 -98.922078)
		(end 247.584976 -99.32543)
		(width 0.0889)
		(layer "F.Cu")
		(net "M_E_ECC<0>")
	)
	(segment
		(start 247.344184 -98.681286)
		(end 247.584976 -98.922078)
		(width 0.0889)
		(layer "F.Cu")
		(net "M_E_ECC<0>")
	)
	(segment
		(start 247.584976 -99.32543)
		(end 247.819164 -99.559618)
		(width 0.0889)
		(layer "F.Cu")
		(net "M_E_ECC<0>")
	)
	(segment
		(start 236.342936 -112.870996)
		(end 236.342936 -113.238788)
		(width 0.1651)
		(layer "F.Cu")
		(net "M_E_ECC<0>")
	)
	(segment
		(start 236.350302 -147.27174)
		(end 236.349794 -147.277582)
		(width 0.1651)
		(layer "F.Cu")
		(net "M_E_ECC<0>")
	)
	(segment
		(start 243.589048 -107.14101)
		(end 242.072922 -107.14101)
		(width 0.1016)
		(layer "F.Cu")
		(net "M_E_ECC<0>")
	)
	(segment
		(start 247.819164 -100.492814)
		(end 247.819164 -102.910894)
		(width 0.1016)
		(layer "F.Cu")
		(net "M_E_ECC<0>")
	)
	(segment
		(start 236.342936 -116.727478)
		(end 235.6358 -117.434614)
		(width 0.1651)
		(layer "F.Cu")
		(net "M_E_ECC<0>")
	)
	(segment
		(start 236.342936 -114.242088)
		(end 236.342936 -116.727478)
		(width 0.1651)
		(layer "F.Cu")
		(net "M_E_ECC<0>")
	)
	(segment
		(start 236.342936 -113.238788)
		(end 236.177836 -113.403888)
		(width 0.1651)
		(layer "F.Cu")
		(net "M_E_ECC<0>")
	)
	(segment
		(start 235.7628 -113.949988)
		(end 235.8898 -114.076988)
		(width 0.1651)
		(layer "F.Cu")
		(net "M_E_ECC<0>")
	)
	(segment
		(start 235.8898 -113.403888)
		(end 235.7628 -113.530888)
		(width 0.1651)
		(layer "F.Cu")
		(net "M_E_ECC<0>")
	)
	(segment
		(start 235.705396 -123.843796)
		(end 235.705396 -125.469396)
		(width 0.1651)
		(layer "F.Cu")
		(net "M_E_ECC<0>")
	)
	(segment
		(start 236.177836 -114.076988)
		(end 236.342936 -114.242088)
		(width 0.1651)
		(layer "F.Cu")
		(net "M_E_ECC<0>")
	)
	(segment
		(start 247.819164 -102.910894)
		(end 243.589048 -107.14101)
		(width 0.1016)
		(layer "F.Cu")
		(net "M_E_ECC<0>")
	)
	(segment
		(start 242.072922 -107.14101)
		(end 241.7064 -107.507532)
		(width 0.1016)
		(layer "F.Cu")
		(net "M_E_ECC<0>")
	)
	(segment
		(start 235.966 -126.189486)
		(end 235.49991 -126.655576)
		(width 0.1651)
		(layer "F.Cu")
		(net "M_E_ECC<0>")
	)
	(segment
		(start 235.6358 -123.7742)
		(end 235.705396 -123.843796)
		(width 0.1651)
		(layer "F.Cu")
		(net "M_E_ECC<0>")
	)
	(segment
		(start 235.8898 -114.076988)
		(end 236.177836 -114.076988)
		(width 0.1651)
		(layer "F.Cu")
		(net "M_E_ECC<0>")
	)
	(segment
		(start 235.7628 -113.530888)
		(end 235.7628 -113.949988)
		(width 0.1651)
		(layer "F.Cu")
		(net "M_E_ECC<0>")
	)
	(segment
		(start 236.177836 -113.403888)
		(end 235.8898 -113.403888)
		(width 0.1651)
		(layer "F.Cu")
		(net "M_E_ECC<0>")
	)
	(segment
		(start 235.705396 -125.469396)
		(end 235.966 -125.73)
		(width 0.1651)
		(layer "F.Cu")
		(net "M_E_ECC<0>")
	)
	(segment
		(start 241.7064 -107.507532)
		(end 236.342936 -112.870996)
		(width 0.1651)
		(layer "F.Cu")
		(net "M_E_ECC<0>")
	)
	(segment
		(start 247.819164 -99.559618)
		(end 247.819164 -100.492814)
		(width 0.0889)
		(layer "F.Cu")
		(net "M_E_ECC<0>")
	)
	(segment
		(start 235.966 -125.73)
		(end 235.966 -126.189486)
		(width 0.1651)
		(layer "F.Cu")
		(net "M_E_ECC<0>")
	)
	(via
		(at 235.49991 -126.655576)
		(size 0.508)
		(drill 0.254)
		(layers "F.Cu" "B.Cu")
		(net "M_E_ECC<0>")
	)
	(via
		(at 235.49991 -141.213078)
		(size 0.508)
		(drill 0.254)
		(layers "F.Cu" "B.Cu")
		(net "M_E_ECC<0>")
	)
	(via
		(at 236.171994 -145.415)
		(size 0.508)
		(drill 0.254)
		(layers "F.Cu" "B.Cu")
		(net "M_E_ECC<0>")
	)
	(segment
		(start 235.49991 -142.476982)
		(end 235.49991 -141.213078)
		(width 0.1651)
		(layer "B.Cu")
		(net "M_E_ECC<0>")
	)
	(segment
		(start 235.500418 -142.477236)
		(end 235.49991 -142.476982)
		(width 0.1651)
		(layer "B.Cu")
		(net "M_E_ECC<0>")
	)
	(segment
		(start 236.171994 -145.415)
		(end 235.87583 -145.415)
		(width 0.14224)
		(layer "In9.Cu")
		(net "M_E_ECC<0>")
	)
	(segment
		(start 235.06684 -141.646148)
		(end 235.49991 -141.213078)
		(width 0.14224)
		(layer "In9.Cu")
		(net "M_E_ECC<0>")
	)
	(segment
		(start 235.06684 -144.60601)
		(end 235.06684 -141.646148)
		(width 0.14224)
		(layer "In9.Cu")
		(net "M_E_ECC<0>")
	)
	(segment
		(start 235.87583 -145.415)
		(end 235.06684 -144.60601)
		(width 0.14224)
		(layer "In9.Cu")
		(net "M_E_ECC<0>")
	)
	(segment
		(start 235.49991 -128.280668)
		(end 236.024928 -128.805686)
		(width 0.14224)
		(layer "In11.Cu")
		(net "M_E_ECC<0>")
	)
	(segment
		(start 235.9152 -134.0866)
		(end 235.974128 -134.145528)
		(width 0.14224)
		(layer "In11.Cu")
		(net "M_E_ECC<0>")
	)
	(segment
		(start 235.974128 -131.434078)
		(end 235.974128 -131.9784)
		(width 0.14224)
		(layer "In11.Cu")
		(net "M_E_ECC<0>")
	)
	(segment
		(start 235.135928 -140.209778)
		(end 235.135928 -140.849096)
		(width 0.14224)
		(layer "In11.Cu")
		(net "M_E_ECC<0>")
	)
	(segment
		(start 235.694728 -134.764018)
		(end 235.694728 -135.949182)
		(width 0.14224)
		(layer "In11.Cu")
		(net "M_E_ECC<0>")
	)
	(segment
		(start 236.024928 -129.719578)
		(end 235.682028 -130.062478)
		(width 0.14224)
		(layer "In11.Cu")
		(net "M_E_ECC<0>")
	)
	(segment
		(start 236.024928 -128.805686)
		(end 236.024928 -129.719578)
		(width 0.14224)
		(layer "In11.Cu")
		(net "M_E_ECC<0>")
	)
	(segment
		(start 235.986828 -136.241282)
		(end 235.986828 -136.5758)
		(width 0.14224)
		(layer "In11.Cu")
		(net "M_E_ECC<0>")
	)
	(segment
		(start 235.9152 -136.647428)
		(end 235.9152 -138.811)
		(width 0.14224)
		(layer "In11.Cu")
		(net "M_E_ECC<0>")
	)
	(segment
		(start 235.694728 -135.949182)
		(end 235.986828 -136.241282)
		(width 0.14224)
		(layer "In11.Cu")
		(net "M_E_ECC<0>")
	)
	(segment
		(start 235.986828 -138.882628)
		(end 235.986828 -139.358878)
		(width 0.14224)
		(layer "In11.Cu")
		(net "M_E_ECC<0>")
	)
	(segment
		(start 235.974128 -131.9784)
		(end 235.9152 -132.037328)
		(width 0.14224)
		(layer "In11.Cu")
		(net "M_E_ECC<0>")
	)
	(segment
		(start 235.986828 -136.5758)
		(end 235.9152 -136.647428)
		(width 0.14224)
		(layer "In11.Cu")
		(net "M_E_ECC<0>")
	)
	(segment
		(start 235.974128 -134.145528)
		(end 235.974128 -134.484618)
		(width 0.14224)
		(layer "In11.Cu")
		(net "M_E_ECC<0>")
	)
	(segment
		(start 235.9152 -138.811)
		(end 235.986828 -138.882628)
		(width 0.14224)
		(layer "In11.Cu")
		(net "M_E_ECC<0>")
	)
	(segment
		(start 235.974128 -134.484618)
		(end 235.694728 -134.764018)
		(width 0.14224)
		(layer "In11.Cu")
		(net "M_E_ECC<0>")
	)
	(segment
		(start 235.682028 -131.141978)
		(end 235.974128 -131.434078)
		(width 0.14224)
		(layer "In11.Cu")
		(net "M_E_ECC<0>")
	)
	(segment
		(start 235.135928 -140.849096)
		(end 235.49991 -141.213078)
		(width 0.14224)
		(layer "In11.Cu")
		(net "M_E_ECC<0>")
	)
	(segment
		(start 235.49991 -126.655576)
		(end 235.49991 -128.280668)
		(width 0.14224)
		(layer "In11.Cu")
		(net "M_E_ECC<0>")
	)
	(segment
		(start 235.682028 -130.062478)
		(end 235.682028 -131.141978)
		(width 0.14224)
		(layer "In11.Cu")
		(net "M_E_ECC<0>")
	)
	(segment
		(start 235.9152 -132.037328)
		(end 235.9152 -134.0866)
		(width 0.14224)
		(layer "In11.Cu")
		(net "M_E_ECC<0>")
	)
	(segment
		(start 235.986828 -139.358878)
		(end 235.135928 -140.209778)
		(width 0.14224)
		(layer "In11.Cu")
		(net "M_E_ECC<0>")
	)
	(segment
		(start 199.799956 -142.677642)
		(end 199.799956 -143.294354)
		(width 0.1651)
		(layer "F.Cu")
		(net "M_E_DQS_DP<9>")
	)
	(segment
		(start 199.799956 -143.294354)
		(end 199.363838 -143.730472)
		(width 0.1651)
		(layer "F.Cu")
		(net "M_E_DQS_DP<9>")
	)
	(segment
		(start 199.36079 -144.956784)
		(end 199.742552 -145.338546)
		(width 0.1651)
		(layer "F.Cu")
		(net "M_E_DQS_DP<9>")
	)
	(segment
		(start 199.800464 -142.6718)
		(end 199.799956 -142.677642)
		(width 0.1651)
		(layer "F.Cu")
		(net "M_E_DQS_DP<9>")
	)
	(segment
		(start 199.279256 -144.732502)
		(end 199.36079 -144.956784)
		(width 0.1651)
		(layer "F.Cu")
		(net "M_E_DQS_DP<9>")
	)
	(segment
		(start 199.363838 -143.730472)
		(end 199.279256 -143.914368)
		(width 0.1651)
		(layer "F.Cu")
		(net "M_E_DQS_DP<9>")
	)
	(segment
		(start 199.279256 -143.914368)
		(end 199.279256 -144.732502)
		(width 0.1651)
		(layer "F.Cu")
		(net "M_E_DQS_DP<9>")
	)
	(segment
		(start 238.759238 -85.803486)
		(end 238.187738 -85.803486)
		(width 0.1651)
		(layer "F.Cu")
		(net "M_E_DQS_DP<9>")
	)
	(via
		(at 199.742552 -145.338546)
		(size 0.508)
		(drill 0.254)
		(layers "F.Cu" "B.Cu")
		(net "M_E_DQS_DP<9>")
	)
	(via
		(at 238.187738 -85.803486)
		(size 0.508)
		(drill 0.254)
		(layers "F.Cu" "B.Cu")
		(net "M_E_DQS_DP<9>")
	)
	(via
		(at 199.742552 -139.827)
		(size 0.508)
		(drill 0.254)
		(layers "F.Cu" "B.Cu")
		(net "M_E_DQS_DP<9>")
	)
	(segment
		(start 199.799956 -142.476982)
		(end 199.799956 -141.859254)
		(width 0.1651)
		(layer "B.Cu")
		(net "M_E_DQS_DP<9>")
	)
	(segment
		(start 199.353932 -140.21562)
		(end 199.742552 -139.827)
		(width 0.1651)
		(layer "B.Cu")
		(net "M_E_DQS_DP<9>")
	)
	(segment
		(start 199.800464 -142.477236)
		(end 199.799956 -142.476982)
		(width 0.1651)
		(layer "B.Cu")
		(net "M_E_DQS_DP<9>")
	)
	(segment
		(start 199.266556 -140.375132)
		(end 199.353932 -140.21562)
		(width 0.1651)
		(layer "B.Cu")
		(net "M_E_DQS_DP<9>")
	)
	(segment
		(start 199.266556 -141.270736)
		(end 199.266556 -140.375132)
		(width 0.1651)
		(layer "B.Cu")
		(net "M_E_DQS_DP<9>")
	)
	(segment
		(start 199.343772 -141.40307)
		(end 199.266556 -141.270736)
		(width 0.1651)
		(layer "B.Cu")
		(net "M_E_DQS_DP<9>")
	)
	(segment
		(start 199.799956 -141.859254)
		(end 199.343772 -141.40307)
		(width 0.1651)
		(layer "B.Cu")
		(net "M_E_DQS_DP<9>")
	)
	(segment
		(start 232.833926 -84.222336)
		(end 233.051604 -84.222336)
		(width 0.0889)
		(layer "In4.Cu")
		(net "M_E_DQS_DP<9>")
	)
	(segment
		(start 208.548986 -108.89996)
		(end 220.350334 -97.098612)
		(width 0.14224)
		(layer "In4.Cu")
		(net "M_E_DQS_DP<9>")
	)
	(segment
		(start 231.8131 -84.71789)
		(end 232.269792 -84.71789)
		(width 0.0889)
		(layer "In4.Cu")
		(net "M_E_DQS_DP<9>")
	)
	(segment
		(start 231.23017 -84.60105)
		(end 231.69626 -84.60105)
		(width 0.0889)
		(layer "In4.Cu")
		(net "M_E_DQS_DP<9>")
	)
	(segment
		(start 237.894622 -85.634576)
		(end 238.187738 -85.803486)
		(width 0.0889)
		(layer "In4.Cu")
		(net "M_E_DQS_DP<9>")
	)
	(segment
		(start 200.640188 -118.830344)
		(end 200.4187 -118.608856)
		(width 0.14224)
		(layer "In4.Cu")
		(net "M_E_DQS_DP<9>")
	)
	(segment
		(start 199.769984 -118.608856)
		(end 199.44588 -118.284752)
		(width 0.14224)
		(layer "In4.Cu")
		(net "M_E_DQS_DP<9>")
	)
	(segment
		(start 207.398874 -108.89996)
		(end 208.548986 -108.89996)
		(width 0.14224)
		(layer "In4.Cu")
		(net "M_E_DQS_DP<9>")
	)
	(segment
		(start 231.69626 -84.60105)
		(end 231.8131 -84.71789)
		(width 0.0889)
		(layer "In4.Cu")
		(net "M_E_DQS_DP<9>")
	)
	(segment
		(start 199.6694 -139.827)
		(end 199.742552 -139.827)
		(width 0.14224)
		(layer "In4.Cu")
		(net "M_E_DQS_DP<9>")
	)
	(segment
		(start 220.350334 -93.154246)
		(end 228.9429 -84.56168)
		(width 0.14224)
		(layer "In4.Cu")
		(net "M_E_DQS_DP<9>")
	)
	(segment
		(start 220.350334 -97.098612)
		(end 220.350334 -93.154246)
		(width 0.14224)
		(layer "In4.Cu")
		(net "M_E_DQS_DP<9>")
	)
	(segment
		(start 231.1908 -84.56168)
		(end 231.23017 -84.60105)
		(width 0.0889)
		(layer "In4.Cu")
		(net "M_E_DQS_DP<9>")
	)
	(segment
		(start 199.991726 -139.827)
		(end 200.255632 -139.563094)
		(width 0.14224)
		(layer "In4.Cu")
		(net "M_E_DQS_DP<9>")
	)
	(segment
		(start 199.44588 -118.284752)
		(end 199.44588 -117.681248)
		(width 0.14224)
		(layer "In4.Cu")
		(net "M_E_DQS_DP<9>")
	)
	(segment
		(start 200.4187 -118.608856)
		(end 199.769984 -118.608856)
		(width 0.14224)
		(layer "In4.Cu")
		(net "M_E_DQS_DP<9>")
	)
	(segment
		(start 199.742552 -139.827)
		(end 199.991726 -139.827)
		(width 0.14224)
		(layer "In4.Cu")
		(net "M_E_DQS_DP<9>")
	)
	(segment
		(start 236.455712 -84.222336)
		(end 236.488478 -84.222336)
		(width 0.0889)
		(layer "In4.Cu")
		(net "M_E_DQS_DP<9>")
	)
	(segment
		(start 232.485184 -84.520786)
		(end 232.48493 -84.520532)
		(width 0.0889)
		(layer "In4.Cu")
		(net "M_E_DQS_DP<9>")
	)
	(segment
		(start 199.742552 -145.338546)
		(end 199.2376 -144.833594)
		(width 0.14224)
		(layer "In4.Cu")
		(net "M_E_DQS_DP<9>")
	)
	(segment
		(start 200.255632 -129.406142)
		(end 199.44588 -128.59639)
		(width 0.14224)
		(layer "In4.Cu")
		(net "M_E_DQS_DP<9>")
	)
	(segment
		(start 237.318042 -84.71789)
		(end 237.350808 -84.71789)
		(width 0.0889)
		(layer "In4.Cu")
		(net "M_E_DQS_DP<9>")
	)
	(segment
		(start 199.824848 -119.482616)
		(end 200.419462 -119.482616)
		(width 0.14224)
		(layer "In4.Cu")
		(net "M_E_DQS_DP<9>")
	)
	(segment
		(start 228.9429 -84.56168)
		(end 231.168702 -84.56168)
		(width 0.14224)
		(layer "In4.Cu")
		(net "M_E_DQS_DP<9>")
	)
	(segment
		(start 199.2376 -144.833594)
		(end 199.2376 -140.2588)
		(width 0.14224)
		(layer "In4.Cu")
		(net "M_E_DQS_DP<9>")
	)
	(segment
		(start 231.168702 -84.56168)
		(end 231.1908 -84.56168)
		(width 0.0889)
		(layer "In4.Cu")
		(net "M_E_DQS_DP<9>")
	)
	(segment
		(start 235.601002 -83.72729)
		(end 235.633768 -83.72729)
		(width 0.0889)
		(layer "In4.Cu")
		(net "M_E_DQS_DP<9>")
	)
	(segment
		(start 233.873548 -83.72729)
		(end 233.906314 -83.72729)
		(width 0.0889)
		(layer "In4.Cu")
		(net "M_E_DQS_DP<9>")
	)
	(segment
		(start 200.640188 -119.26189)
		(end 200.640188 -118.830344)
		(width 0.14224)
		(layer "In4.Cu")
		(net "M_E_DQS_DP<9>")
	)
	(segment
		(start 232.485184 -84.52104)
		(end 232.485184 -84.520786)
		(width 0.0889)
		(layer "In4.Cu")
		(net "M_E_DQS_DP<9>")
	)
	(segment
		(start 199.44588 -119.861584)
		(end 199.824848 -119.482616)
		(width 0.14224)
		(layer "In4.Cu")
		(net "M_E_DQS_DP<9>")
	)
	(segment
		(start 202.867006 -114.260122)
		(end 202.867006 -113.431828)
		(width 0.14224)
		(layer "In4.Cu")
		(net "M_E_DQS_DP<9>")
	)
	(segment
		(start 199.44588 -128.59639)
		(end 199.44588 -119.861584)
		(width 0.14224)
		(layer "In4.Cu")
		(net "M_E_DQS_DP<9>")
	)
	(segment
		(start 199.44588 -117.681248)
		(end 202.867006 -114.260122)
		(width 0.14224)
		(layer "In4.Cu")
		(net "M_E_DQS_DP<9>")
	)
	(segment
		(start 199.2376 -140.2588)
		(end 199.6694 -139.827)
		(width 0.14224)
		(layer "In4.Cu")
		(net "M_E_DQS_DP<9>")
	)
	(segment
		(start 200.255632 -139.563094)
		(end 200.255632 -129.406142)
		(width 0.14224)
		(layer "In4.Cu")
		(net "M_E_DQS_DP<9>")
	)
	(segment
		(start 237.870746 -85.545422)
		(end 237.894622 -85.634576)
		(width 0.0889)
		(layer "In4.Cu")
		(net "M_E_DQS_DP<9>")
	)
	(segment
		(start 202.867006 -113.431828)
		(end 207.398874 -108.89996)
		(width 0.14224)
		(layer "In4.Cu")
		(net "M_E_DQS_DP<9>")
	)
	(segment
		(start 234.735878 -83.231736)
		(end 234.771438 -83.231736)
		(width 0.0889)
		(layer "In4.Cu")
		(net "M_E_DQS_DP<9>")
	)
	(segment
		(start 200.419462 -119.482616)
		(end 200.640188 -119.26189)
		(width 0.14224)
		(layer "In4.Cu")
		(net "M_E_DQS_DP<9>")
	)
	(arc
		(start 236.123988 -84.022438)
		(mid 236.264067 -84.165174)
		(end 236.455712 -84.222336)
		(width 0.0889)
		(layer "In4.Cu")
		(net "M_E_DQS_DP<9>")
	)
	(arc
		(start 236.488478 -84.222336)
		(mid 236.773902 -84.305803)
		(end 236.982508 -84.517738)
		(width 0.0889)
		(layer "In4.Cu")
		(net "M_E_DQS_DP<9>")
	)
	(arc
		(start 232.516426 -84.467446)
		(mid 232.65494 -84.318669)
		(end 232.833926 -84.222336)
		(width 0.0889)
		(layer "In4.Cu")
		(net "M_E_DQS_DP<9>")
	)
	(arc
		(start 232.269792 -84.71789)
		(mid 232.394548 -84.638128)
		(end 232.485184 -84.52104)
		(width 0.0889)
		(layer "In4.Cu")
		(net "M_E_DQS_DP<9>")
	)
	(arc
		(start 233.906314 -83.72729)
		(mid 234.100164 -83.67094)
		(end 234.241848 -83.527138)
		(width 0.0889)
		(layer "In4.Cu")
		(net "M_E_DQS_DP<9>")
	)
	(arc
		(start 235.633768 -83.72729)
		(mid 235.916985 -83.811571)
		(end 236.123988 -84.022438)
		(width 0.0889)
		(layer "In4.Cu")
		(net "M_E_DQS_DP<9>")
	)
	(arc
		(start 236.982508 -84.517738)
		(mid 237.124191 -84.661542)
		(end 237.318042 -84.71789)
		(width 0.0889)
		(layer "In4.Cu")
		(net "M_E_DQS_DP<9>")
	)
	(arc
		(start 234.771438 -83.231736)
		(mid 235.056862 -83.315203)
		(end 235.265468 -83.527138)
		(width 0.0889)
		(layer "In4.Cu")
		(net "M_E_DQS_DP<9>")
	)
	(arc
		(start 234.241848 -83.527138)
		(mid 234.450456 -83.315206)
		(end 234.735878 -83.231736)
		(width 0.0889)
		(layer "In4.Cu")
		(net "M_E_DQS_DP<9>")
	)
	(arc
		(start 237.350808 -84.71789)
		(mid 237.829625 -84.994102)
		(end 237.870746 -85.545422)
		(width 0.0889)
		(layer "In4.Cu")
		(net "M_E_DQS_DP<9>")
	)
	(arc
		(start 233.051604 -84.222336)
		(mid 233.243246 -84.16517)
		(end 233.383328 -84.022438)
		(width 0.0889)
		(layer "In4.Cu")
		(net "M_E_DQS_DP<9>")
	)
	(arc
		(start 233.383328 -84.022438)
		(mid 233.590332 -83.811574)
		(end 233.873548 -83.72729)
		(width 0.0889)
		(layer "In4.Cu")
		(net "M_E_DQS_DP<9>")
	)
	(arc
		(start 232.48493 -84.520532)
		(mid 232.500017 -84.493596)
		(end 232.516426 -84.467446)
		(width 0.0889)
		(layer "In4.Cu")
		(net "M_E_DQS_DP<9>")
	)
	(arc
		(start 235.265468 -83.527138)
		(mid 235.407151 -83.670942)
		(end 235.601002 -83.72729)
		(width 0.0889)
		(layer "In4.Cu")
		(net "M_E_DQS_DP<9>")
	)
	(segment
		(start 239.235996 -125.171708)
		(end 238.437928 -125.969776)
		(width 0.1651)
		(layer "F.Cu")
		(net "M_E_DQS_DP<8>")
	)
	(segment
		(start 238.952532 -117.880384)
		(end 238.952532 -118.25859)
		(width 0.1651)
		(layer "F.Cu")
		(net "M_E_DQS_DP<8>")
	)
	(segment
		(start 238.899954 -146.265646)
		(end 238.9378 -146.2278)
		(width 0.1651)
		(layer "F.Cu")
		(net "M_E_DQS_DP<8>")
	)
	(segment
		(start 239.9284 -119.343424)
		(end 239.592358 -119.679466)
		(width 0.1651)
		(layer "F.Cu")
		(net "M_E_DQS_DP<8>")
	)
	(segment
		(start 239.908334 -113.086642)
		(end 239.908334 -117.36324)
		(width 0.1651)
		(layer "F.Cu")
		(net "M_E_DQS_DP<8>")
	)
	(segment
		(start 238.900462 -147.27174)
		(end 238.899954 -147.27174)
		(width 0.1651)
		(layer "F.Cu")
		(net "M_E_DQS_DP<8>")
	)
	(segment
		(start 239.592358 -118.434866)
		(end 239.9284 -118.770908)
		(width 0.1651)
		(layer "F.Cu")
		(net "M_E_DQS_DP<8>")
	)
	(segment
		(start 239.571022 -117.700552)
		(end 239.132364 -117.700552)
		(width 0.1651)
		(layer "F.Cu")
		(net "M_E_DQS_DP<8>")
	)
	(segment
		(start 238.899954 -147.27174)
		(end 238.899954 -146.265646)
		(width 0.1651)
		(layer "F.Cu")
		(net "M_E_DQS_DP<8>")
	)
	(segment
		(start 248.654824 -104.231694)
		(end 248.654824 -104.859074)
		(width 0.1016)
		(layer "F.Cu")
		(net "M_E_DQS_DP<8>")
	)
	(segment
		(start 244.350032 -109.163866)
		(end 243.83111 -109.163866)
		(width 0.1016)
		(layer "F.Cu")
		(net "M_E_DQS_DP<8>")
	)
	(segment
		(start 249.343164 -99.996498)
		(end 249.343164 -100.492814)
		(width 0.0889)
		(layer "F.Cu")
		(net "M_E_DQS_DP<8>")
	)
	(segment
		(start 239.128808 -118.434866)
		(end 239.592358 -118.434866)
		(width 0.1651)
		(layer "F.Cu")
		(net "M_E_DQS_DP<8>")
	)
	(segment
		(start 239.132364 -117.700552)
		(end 238.952532 -117.880384)
		(width 0.1651)
		(layer "F.Cu")
		(net "M_E_DQS_DP<8>")
	)
	(segment
		(start 238.9378 -146.2278)
		(end 238.9378 -144.8562)
		(width 0.1651)
		(layer "F.Cu")
		(net "M_E_DQS_DP<8>")
	)
	(segment
		(start 249.343164 -103.543354)
		(end 248.654824 -104.231694)
		(width 0.1016)
		(layer "F.Cu")
		(net "M_E_DQS_DP<8>")
	)
	(segment
		(start 239.100106 -119.679466)
		(end 238.935006 -119.844566)
		(width 0.1651)
		(layer "F.Cu")
		(net "M_E_DQS_DP<8>")
	)
	(segment
		(start 238.952532 -118.25859)
		(end 239.128808 -118.434866)
		(width 0.1651)
		(layer "F.Cu")
		(net "M_E_DQS_DP<8>")
	)
	(segment
		(start 249.39117 -99.443286)
		(end 249.40768 -99.471734)
		(width 0.0889)
		(layer "F.Cu")
		(net "M_E_DQS_DP<8>")
	)
	(segment
		(start 249.442224 -99.897438)
		(end 249.343164 -99.996498)
		(width 0.0889)
		(layer "F.Cu")
		(net "M_E_DQS_DP<8>")
	)
	(segment
		(start 248.654824 -104.859074)
		(end 244.350032 -109.163866)
		(width 0.1016)
		(layer "F.Cu")
		(net "M_E_DQS_DP<8>")
	)
	(segment
		(start 243.83111 -109.163866)
		(end 243.653818 -109.341158)
		(width 0.1016)
		(layer "F.Cu")
		(net "M_E_DQS_DP<8>")
	)
	(segment
		(start 239.235996 -120.475756)
		(end 239.235996 -125.171708)
		(width 0.1651)
		(layer "F.Cu")
		(net "M_E_DQS_DP<8>")
	)
	(segment
		(start 238.9378 -144.8562)
		(end 238.69396 -144.61236)
		(width 0.1651)
		(layer "F.Cu")
		(net "M_E_DQS_DP<8>")
	)
	(segment
		(start 249.442224 -99.600766)
		(end 249.442224 -99.897438)
		(width 0.0889)
		(layer "F.Cu")
		(net "M_E_DQS_DP<8>")
	)
	(segment
		(start 238.935006 -119.844566)
		(end 238.935006 -120.174766)
		(width 0.1651)
		(layer "F.Cu")
		(net "M_E_DQS_DP<8>")
	)
	(segment
		(start 249.061224 -98.681286)
		(end 249.39117 -99.443286)
		(width 0.0889)
		(layer "F.Cu")
		(net "M_E_DQS_DP<8>")
	)
	(segment
		(start 243.653818 -109.341158)
		(end 239.908334 -113.086642)
		(width 0.1651)
		(layer "F.Cu")
		(net "M_E_DQS_DP<8>")
	)
	(segment
		(start 249.343164 -100.492814)
		(end 249.343164 -103.543354)
		(width 0.1016)
		(layer "F.Cu")
		(net "M_E_DQS_DP<8>")
	)
	(segment
		(start 239.592358 -119.679466)
		(end 239.100106 -119.679466)
		(width 0.1651)
		(layer "F.Cu")
		(net "M_E_DQS_DP<8>")
	)
	(segment
		(start 239.908334 -117.36324)
		(end 239.571022 -117.700552)
		(width 0.1651)
		(layer "F.Cu")
		(net "M_E_DQS_DP<8>")
	)
	(segment
		(start 238.69396 -144.61236)
		(end 238.437928 -144.61236)
		(width 0.1651)
		(layer "F.Cu")
		(net "M_E_DQS_DP<8>")
	)
	(segment
		(start 239.9284 -118.770908)
		(end 239.9284 -119.343424)
		(width 0.1651)
		(layer "F.Cu")
		(net "M_E_DQS_DP<8>")
	)
	(segment
		(start 238.935006 -120.174766)
		(end 239.235996 -120.475756)
		(width 0.1651)
		(layer "F.Cu")
		(net "M_E_DQS_DP<8>")
	)
	(via
		(at 238.437928 -140.541756)
		(size 0.508)
		(drill 0.254)
		(layers "F.Cu" "B.Cu")
		(net "M_E_DQS_DP<8>")
	)
	(via
		(at 238.437928 -144.61236)
		(size 0.508)
		(drill 0.254)
		(layers "F.Cu" "B.Cu")
		(net "M_E_DQS_DP<8>")
	)
	(via
		(at 238.437928 -125.969776)
		(size 0.508)
		(drill 0.254)
		(layers "F.Cu" "B.Cu")
		(net "M_E_DQS_DP<8>")
	)
	(arc
		(start 249.40768 -99.471734)
		(mid 249.433408 -99.533983)
		(end 249.442224 -99.600766)
		(width 0.0889)
		(layer "F.Cu")
		(net "M_E_DQS_DP<8>")
	)
	(segment
		(start 238.9378 -139.065)
		(end 238.9378 -140.2842)
		(width 0.1651)
		(layer "B.Cu")
		(net "M_E_DQS_DP<8>")
	)
	(segment
		(start 238.9378 -140.2842)
		(end 238.680244 -140.541756)
		(width 0.1651)
		(layer "B.Cu")
		(net "M_E_DQS_DP<8>")
	)
	(segment
		(start 238.899954 -139.027154)
		(end 238.9378 -139.065)
		(width 0.1651)
		(layer "B.Cu")
		(net "M_E_DQS_DP<8>")
	)
	(segment
		(start 238.900462 -137.877296)
		(end 238.899954 -137.877296)
		(width 0.1651)
		(layer "B.Cu")
		(net "M_E_DQS_DP<8>")
	)
	(segment
		(start 238.680244 -140.541756)
		(end 238.437928 -140.541756)
		(width 0.1651)
		(layer "B.Cu")
		(net "M_E_DQS_DP<8>")
	)
	(segment
		(start 238.899954 -137.877296)
		(end 238.899954 -139.027154)
		(width 0.1651)
		(layer "B.Cu")
		(net "M_E_DQS_DP<8>")
	)
	(segment
		(start 238.872776 -140.976604)
		(end 238.437928 -140.541756)
		(width 0.14224)
		(layer "In9.Cu")
		(net "M_E_DQS_DP<8>")
	)
	(segment
		(start 238.898176 -144.152112)
		(end 238.898176 -143.7132)
		(width 0.14224)
		(layer "In9.Cu")
		(net "M_E_DQS_DP<8>")
	)
	(segment
		(start 238.233712 -141.6558)
		(end 238.618776 -141.6558)
		(width 0.14224)
		(layer "In9.Cu")
		(net "M_E_DQS_DP<8>")
	)
	(segment
		(start 238.644176 -143.4592)
		(end 238.259112 -143.4592)
		(width 0.14224)
		(layer "In9.Cu")
		(net "M_E_DQS_DP<8>")
	)
	(segment
		(start 238.178086 -142.2654)
		(end 238.063278 -142.150592)
		(width 0.14224)
		(layer "In9.Cu")
		(net "M_E_DQS_DP<8>")
	)
	(segment
		(start 238.618776 -141.6558)
		(end 238.872776 -141.4018)
		(width 0.14224)
		(layer "In9.Cu")
		(net "M_E_DQS_DP<8>")
	)
	(segment
		(start 238.260636 -142.899892)
		(end 238.440976 -142.719552)
		(width 0.14224)
		(layer "In9.Cu")
		(net "M_E_DQS_DP<8>")
	)
	(segment
		(start 238.437928 -144.61236)
		(end 238.898176 -144.152112)
		(width 0.14224)
		(layer "In9.Cu")
		(net "M_E_DQS_DP<8>")
	)
	(segment
		(start 238.898176 -143.7132)
		(end 238.644176 -143.4592)
		(width 0.14224)
		(layer "In9.Cu")
		(net "M_E_DQS_DP<8>")
	)
	(segment
		(start 238.063278 -143.263366)
		(end 238.063278 -143.037052)
		(width 0.14224)
		(layer "In9.Cu")
		(net "M_E_DQS_DP<8>")
	)
	(segment
		(start 238.263176 -142.2654)
		(end 238.178086 -142.2654)
		(width 0.14224)
		(layer "In9.Cu")
		(net "M_E_DQS_DP<8>")
	)
	(segment
		(start 238.259112 -143.4592)
		(end 238.063278 -143.263366)
		(width 0.14224)
		(layer "In9.Cu")
		(net "M_E_DQS_DP<8>")
	)
	(segment
		(start 238.063278 -142.150592)
		(end 238.063278 -141.826234)
		(width 0.14224)
		(layer "In9.Cu")
		(net "M_E_DQS_DP<8>")
	)
	(segment
		(start 238.063278 -141.826234)
		(end 238.233712 -141.6558)
		(width 0.14224)
		(layer "In9.Cu")
		(net "M_E_DQS_DP<8>")
	)
	(segment
		(start 238.063278 -143.037052)
		(end 238.200438 -142.899892)
		(width 0.14224)
		(layer "In9.Cu")
		(net "M_E_DQS_DP<8>")
	)
	(segment
		(start 238.872776 -141.4018)
		(end 238.872776 -140.976604)
		(width 0.14224)
		(layer "In9.Cu")
		(net "M_E_DQS_DP<8>")
	)
	(segment
		(start 238.440976 -142.4432)
		(end 238.263176 -142.2654)
		(width 0.14224)
		(layer "In9.Cu")
		(net "M_E_DQS_DP<8>")
	)
	(segment
		(start 238.440976 -142.719552)
		(end 238.440976 -142.4432)
		(width 0.14224)
		(layer "In9.Cu")
		(net "M_E_DQS_DP<8>")
	)
	(segment
		(start 238.200438 -142.899892)
		(end 238.260636 -142.899892)
		(width 0.14224)
		(layer "In9.Cu")
		(net "M_E_DQS_DP<8>")
	)
	(segment
		(start 238.97844 -138.41984)
		(end 238.97844 -137.55116)
		(width 0.14224)
		(layer "In11.Cu")
		(net "M_E_DQS_DP<8>")
	)
	(segment
		(start 239.220248 -137.309352)
		(end 239.220248 -133.861048)
		(width 0.14224)
		(layer "In11.Cu")
		(net "M_E_DQS_DP<8>")
	)
	(segment
		(start 238.97844 -137.55116)
		(end 239.220248 -137.309352)
		(width 0.14224)
		(layer "In11.Cu")
		(net "M_E_DQS_DP<8>")
	)
	(segment
		(start 239.220248 -138.661648)
		(end 238.97844 -138.41984)
		(width 0.14224)
		(layer "In11.Cu")
		(net "M_E_DQS_DP<8>")
	)
	(segment
		(start 238.438182 -140.541756)
		(end 239.220248 -139.75969)
		(width 0.14224)
		(layer "In11.Cu")
		(net "M_E_DQS_DP<8>")
	)
	(segment
		(start 238.7092 -133.35)
		(end 238.7092 -132.804408)
		(width 0.14224)
		(layer "In11.Cu")
		(net "M_E_DQS_DP<8>")
	)
	(segment
		(start 239.220248 -133.861048)
		(end 238.7092 -133.35)
		(width 0.14224)
		(layer "In11.Cu")
		(net "M_E_DQS_DP<8>")
	)
	(segment
		(start 239.220248 -132.29336)
		(end 239.220248 -127.980694)
		(width 0.14224)
		(layer "In11.Cu")
		(net "M_E_DQS_DP<8>")
	)
	(segment
		(start 239.220248 -127.980694)
		(end 238.887 -127.647446)
		(width 0.14224)
		(layer "In11.Cu")
		(net "M_E_DQS_DP<8>")
	)
	(segment
		(start 238.7092 -132.804408)
		(end 239.220248 -132.29336)
		(width 0.14224)
		(layer "In11.Cu")
		(net "M_E_DQS_DP<8>")
	)
	(segment
		(start 238.437928 -140.541756)
		(end 238.438182 -140.541756)
		(width 0.14224)
		(layer "In11.Cu")
		(net "M_E_DQS_DP<8>")
	)
	(segment
		(start 238.887 -126.418848)
		(end 238.437928 -125.969776)
		(width 0.14224)
		(layer "In11.Cu")
		(net "M_E_DQS_DP<8>")
	)
	(segment
		(start 238.887 -127.647446)
		(end 238.887 -126.418848)
		(width 0.14224)
		(layer "In11.Cu")
		(net "M_E_DQS_DP<8>")
	)
	(segment
		(start 239.220248 -139.75969)
		(end 239.220248 -138.661648)
		(width 0.14224)
		(layer "In11.Cu")
		(net "M_E_DQS_DP<8>")
	)
	(segment
		(start 312.887868 -146.2278)
		(end 312.887868 -144.8562)
		(width 0.1651)
		(layer "F.Cu")
		(net "M_E_DQS_DP<7>")
	)
	(segment
		(start 312.644028 -144.61236)
		(end 312.387996 -144.61236)
		(width 0.1651)
		(layer "F.Cu")
		(net "M_E_DQS_DP<7>")
	)
	(segment
		(start 312.887868 -144.8562)
		(end 312.644028 -144.61236)
		(width 0.1651)
		(layer "F.Cu")
		(net "M_E_DQS_DP<7>")
	)
	(segment
		(start 312.850022 -146.265646)
		(end 312.887868 -146.2278)
		(width 0.1651)
		(layer "F.Cu")
		(net "M_E_DQS_DP<7>")
	)
	(segment
		(start 312.850022 -147.27174)
		(end 312.850022 -146.265646)
		(width 0.1651)
		(layer "F.Cu")
		(net "M_E_DQS_DP<7>")
	)
	(segment
		(start 312.850276 -147.27174)
		(end 312.850022 -147.27174)
		(width 0.1651)
		(layer "F.Cu")
		(net "M_E_DQS_DP<7>")
	)
	(segment
		(start 285.7881 -95.033084)
		(end 286.3596 -95.033084)
		(width 0.1651)
		(layer "F.Cu")
		(net "M_E_DQS_DP<7>")
	)
	(via
		(at 312.387996 -144.61236)
		(size 0.508)
		(drill 0.254)
		(layers "F.Cu" "B.Cu")
		(net "M_E_DQS_DP<7>")
	)
	(via
		(at 286.3596 -95.033084)
		(size 0.508)
		(drill 0.254)
		(layers "F.Cu" "B.Cu")
		(net "M_E_DQS_DP<7>")
	)
	(via
		(at 312.387996 -140.541756)
		(size 0.508)
		(drill 0.254)
		(layers "F.Cu" "B.Cu")
		(net "M_E_DQS_DP<7>")
	)
	(segment
		(start 312.387996 -140.541756)
		(end 312.630312 -140.541756)
		(width 0.1651)
		(layer "B.Cu")
		(net "M_E_DQS_DP<7>")
	)
	(segment
		(start 312.887868 -139.065)
		(end 312.850022 -139.027154)
		(width 0.1651)
		(layer "B.Cu")
		(net "M_E_DQS_DP<7>")
	)
	(segment
		(start 312.850022 -139.027154)
		(end 312.850022 -137.877296)
		(width 0.1651)
		(layer "B.Cu")
		(net "M_E_DQS_DP<7>")
	)
	(segment
		(start 312.887868 -140.2842)
		(end 312.887868 -139.065)
		(width 0.1651)
		(layer "B.Cu")
		(net "M_E_DQS_DP<7>")
	)
	(segment
		(start 312.850022 -137.877296)
		(end 312.850276 -137.877296)
		(width 0.1651)
		(layer "B.Cu")
		(net "M_E_DQS_DP<7>")
	)
	(segment
		(start 312.630312 -140.541756)
		(end 312.887868 -140.2842)
		(width 0.1651)
		(layer "B.Cu")
		(net "M_E_DQS_DP<7>")
	)
	(segment
		(start 286.87141 -100.281486)
		(end 286.866584 -100.290122)
		(width 0.0889)
		(layer "In4.Cu")
		(net "M_E_DQS_DP<7>")
	)
	(segment
		(start 311.613296 -123.87834)
		(end 311.831736 -123.87834)
		(width 0.14224)
		(layer "In4.Cu")
		(net "M_E_DQS_DP<7>")
	)
	(segment
		(start 311.134252 -122.3772)
		(end 311.541668 -122.784616)
		(width 0.14224)
		(layer "In4.Cu")
		(net "M_E_DQS_DP<7>")
	)
	(segment
		(start 290.291266 -105.883964)
		(end 291.468302 -107.061)
		(width 0.0889)
		(layer "In4.Cu")
		(net "M_E_DQS_DP<7>")
	)
	(segment
		(start 312.18378 -141.6558)
		(end 312.013346 -141.826234)
		(width 0.14224)
		(layer "In4.Cu")
		(net "M_E_DQS_DP<7>")
	)
	(segment
		(start 312.213244 -142.2654)
		(end 312.391044 -142.4432)
		(width 0.14224)
		(layer "In4.Cu")
		(net "M_E_DQS_DP<7>")
	)
	(segment
		(start 312.128154 -142.2654)
		(end 312.213244 -142.2654)
		(width 0.14224)
		(layer "In4.Cu")
		(net "M_E_DQS_DP<7>")
	)
	(segment
		(start 286.87141 -99.290886)
		(end 286.866584 -99.299522)
		(width 0.0889)
		(layer "In4.Cu")
		(net "M_E_DQS_DP<7>")
	)
	(segment
		(start 287.725104 -103.1494)
		(end 287.72993 -103.158036)
		(width 0.0889)
		(layer "In4.Cu")
		(net "M_E_DQS_DP<7>")
	)
	(segment
		(start 292.0238 -107.02163)
		(end 292.045898 -107.02163)
		(width 0.0889)
		(layer "In4.Cu")
		(net "M_E_DQS_DP<7>")
	)
	(segment
		(start 310.222392 -122.056144)
		(end 310.543448 -122.3772)
		(width 0.14224)
		(layer "In4.Cu")
		(net "M_E_DQS_DP<7>")
	)
	(segment
		(start 312.568844 -141.6558)
		(end 312.18378 -141.6558)
		(width 0.14224)
		(layer "In4.Cu")
		(net "M_E_DQS_DP<7>")
	)
	(segment
		(start 312.013346 -143.263366)
		(end 312.20918 -143.4592)
		(width 0.14224)
		(layer "In4.Cu")
		(net "M_E_DQS_DP<7>")
	)
	(segment
		(start 312.150506 -142.899892)
		(end 312.013346 -143.037052)
		(width 0.14224)
		(layer "In4.Cu")
		(net "M_E_DQS_DP<7>")
	)
	(segment
		(start 288.065464 -104.348788)
		(end 288.09823 -104.348788)
		(width 0.0889)
		(layer "In4.Cu")
		(net "M_E_DQS_DP<7>")
	)
	(segment
		(start 312.848244 -144.152112)
		(end 312.387996 -144.61236)
		(width 0.14224)
		(layer "In4.Cu")
		(net "M_E_DQS_DP<7>")
	)
	(segment
		(start 312.20918 -143.4592)
		(end 312.594244 -143.4592)
		(width 0.14224)
		(layer "In4.Cu")
		(net "M_E_DQS_DP<7>")
	)
	(segment
		(start 312.391044 -142.719552)
		(end 312.210704 -142.899892)
		(width 0.14224)
		(layer "In4.Cu")
		(net "M_E_DQS_DP<7>")
	)
	(segment
		(start 312.391044 -142.4432)
		(end 312.391044 -142.719552)
		(width 0.14224)
		(layer "In4.Cu")
		(net "M_E_DQS_DP<7>")
	)
	(segment
		(start 286.87776 -101.261418)
		(end 286.87141 -101.272086)
		(width 0.0889)
		(layer "In4.Cu")
		(net "M_E_DQS_DP<7>")
	)
	(segment
		(start 312.822844 -140.976604)
		(end 312.822844 -141.4018)
		(width 0.14224)
		(layer "In4.Cu")
		(net "M_E_DQS_DP<7>")
	)
	(segment
		(start 309.043324 -120.288812)
		(end 310.222392 -121.46788)
		(width 0.14224)
		(layer "In4.Cu")
		(net "M_E_DQS_DP<7>")
	)
	(segment
		(start 313.170316 -124.415804)
		(end 313.170316 -139.759436)
		(width 0.14224)
		(layer "In4.Cu")
		(net "M_E_DQS_DP<7>")
	)
	(segment
		(start 311.362344 -123.627388)
		(end 311.613296 -123.87834)
		(width 0.14224)
		(layer "In4.Cu")
		(net "M_E_DQS_DP<7>")
	)
	(segment
		(start 312.453528 -123.699016)
		(end 313.170316 -124.415804)
		(width 0.14224)
		(layer "In4.Cu")
		(net "M_E_DQS_DP<7>")
	)
	(segment
		(start 286.87141 -101.272086)
		(end 286.866584 -101.280722)
		(width 0.0889)
		(layer "In4.Cu")
		(net "M_E_DQS_DP<7>")
	)
	(segment
		(start 311.541668 -123.229624)
		(end 311.362344 -123.408948)
		(width 0.14224)
		(layer "In4.Cu")
		(net "M_E_DQS_DP<7>")
	)
	(segment
		(start 286.87141 -98.300794)
		(end 286.87141 -98.30054)
		(width 0.0889)
		(layer "In4.Cu")
		(net "M_E_DQS_DP<7>")
	)
	(segment
		(start 311.831736 -123.87834)
		(end 312.01106 -123.699016)
		(width 0.14224)
		(layer "In4.Cu")
		(net "M_E_DQS_DP<7>")
	)
	(segment
		(start 311.541668 -122.784616)
		(end 311.541668 -123.229624)
		(width 0.14224)
		(layer "In4.Cu")
		(net "M_E_DQS_DP<7>")
	)
	(segment
		(start 288.920174 -104.843834)
		(end 288.95294 -104.843834)
		(width 0.0889)
		(layer "In4.Cu")
		(net "M_E_DQS_DP<7>")
	)
	(segment
		(start 310.543448 -122.3772)
		(end 311.134252 -122.3772)
		(width 0.14224)
		(layer "In4.Cu")
		(net "M_E_DQS_DP<7>")
	)
	(segment
		(start 310.222392 -121.46788)
		(end 310.222392 -122.056144)
		(width 0.14224)
		(layer "In4.Cu")
		(net "M_E_DQS_DP<7>")
	)
	(segment
		(start 294.523668 -107.02163)
		(end 307.79085 -120.288812)
		(width 0.14224)
		(layer "In4.Cu")
		(net "M_E_DQS_DP<7>")
	)
	(segment
		(start 287.203134 -101.872034)
		(end 287.2359 -101.872034)
		(width 0.0889)
		(layer "In4.Cu")
		(net "M_E_DQS_DP<7>")
	)
	(segment
		(start 290.291266 -105.611168)
		(end 290.291266 -105.883964)
		(width 0.0889)
		(layer "In4.Cu")
		(net "M_E_DQS_DP<7>")
	)
	(segment
		(start 286.87776 -99.280218)
		(end 286.87141 -99.290886)
		(width 0.0889)
		(layer "In4.Cu")
		(net "M_E_DQS_DP<7>")
	)
	(segment
		(start 286.87776 -100.270818)
		(end 286.87141 -100.281486)
		(width 0.0889)
		(layer "In4.Cu")
		(net "M_E_DQS_DP<7>")
	)
	(segment
		(start 289.782504 -105.339388)
		(end 289.81527 -105.339388)
		(width 0.0889)
		(layer "In4.Cu")
		(net "M_E_DQS_DP<7>")
	)
	(segment
		(start 312.594244 -143.4592)
		(end 312.848244 -143.7132)
		(width 0.14224)
		(layer "In4.Cu")
		(net "M_E_DQS_DP<7>")
	)
	(segment
		(start 312.01106 -123.699016)
		(end 312.453528 -123.699016)
		(width 0.14224)
		(layer "In4.Cu")
		(net "M_E_DQS_DP<7>")
	)
	(segment
		(start 307.79085 -120.288812)
		(end 309.043324 -120.288812)
		(width 0.14224)
		(layer "In4.Cu")
		(net "M_E_DQS_DP<7>")
	)
	(segment
		(start 311.362344 -123.408948)
		(end 311.362344 -123.627388)
		(width 0.14224)
		(layer "In4.Cu")
		(net "M_E_DQS_DP<7>")
	)
	(segment
		(start 291.98443 -107.061)
		(end 292.0238 -107.02163)
		(width 0.0889)
		(layer "In4.Cu")
		(net "M_E_DQS_DP<7>")
	)
	(segment
		(start 312.848244 -143.7132)
		(end 312.848244 -144.152112)
		(width 0.14224)
		(layer "In4.Cu")
		(net "M_E_DQS_DP<7>")
	)
	(segment
		(start 313.170316 -139.759436)
		(end 312.387996 -140.541756)
		(width 0.14224)
		(layer "In4.Cu")
		(net "M_E_DQS_DP<7>")
	)
	(segment
		(start 292.045898 -107.02163)
		(end 294.523668 -107.02163)
		(width 0.14224)
		(layer "In4.Cu")
		(net "M_E_DQS_DP<7>")
	)
	(segment
		(start 312.013346 -142.150592)
		(end 312.128154 -142.2654)
		(width 0.14224)
		(layer "In4.Cu")
		(net "M_E_DQS_DP<7>")
	)
	(segment
		(start 287.72993 -103.158036)
		(end 287.73628 -103.168704)
		(width 0.0889)
		(layer "In4.Cu")
		(net "M_E_DQS_DP<7>")
	)
	(segment
		(start 291.468302 -107.061)
		(end 291.98443 -107.061)
		(width 0.0889)
		(layer "In4.Cu")
		(net "M_E_DQS_DP<7>")
	)
	(segment
		(start 312.387996 -140.541756)
		(end 312.822844 -140.976604)
		(width 0.14224)
		(layer "In4.Cu")
		(net "M_E_DQS_DP<7>")
	)
	(segment
		(start 312.210704 -142.899892)
		(end 312.150506 -142.899892)
		(width 0.14224)
		(layer "In4.Cu")
		(net "M_E_DQS_DP<7>")
	)
	(segment
		(start 312.013346 -141.826234)
		(end 312.013346 -142.150592)
		(width 0.14224)
		(layer "In4.Cu")
		(net "M_E_DQS_DP<7>")
	)
	(segment
		(start 312.013346 -143.037052)
		(end 312.013346 -143.263366)
		(width 0.14224)
		(layer "In4.Cu")
		(net "M_E_DQS_DP<7>")
	)
	(segment
		(start 312.822844 -141.4018)
		(end 312.568844 -141.6558)
		(width 0.14224)
		(layer "In4.Cu")
		(net "M_E_DQS_DP<7>")
	)
	(arc
		(start 286.866584 -99.299522)
		(mid 286.817829 -99.495874)
		(end 286.87141 -99.690936)
		(width 0.0889)
		(layer "In4.Cu")
		(net "M_E_DQS_DP<7>")
	)
	(arc
		(start 286.756348 -96.076008)
		(mid 286.764046 -96.406609)
		(end 286.87141 -96.71939)
		(width 0.0889)
		(layer "In4.Cu")
		(net "M_E_DQS_DP<7>")
	)
	(arc
		(start 286.918654 -98.804476)
		(mid 286.948373 -99.046654)
		(end 286.87776 -99.280218)
		(width 0.0889)
		(layer "In4.Cu")
		(net "M_E_DQS_DP<7>")
	)
	(arc
		(start 287.72993 -103.748586)
		(mid 287.727182 -104.144053)
		(end 288.065464 -104.348788)
		(width 0.0889)
		(layer "In4.Cu")
		(net "M_E_DQS_DP<7>")
	)
	(arc
		(start 286.87141 -100.681536)
		(mid 286.950632 -100.970654)
		(end 286.87776 -101.261418)
		(width 0.0889)
		(layer "In4.Cu")
		(net "M_E_DQS_DP<7>")
	)
	(arc
		(start 288.09823 -104.348788)
		(mid 288.381447 -104.433069)
		(end 288.58845 -104.643936)
		(width 0.0889)
		(layer "In4.Cu")
		(net "M_E_DQS_DP<7>")
	)
	(arc
		(start 286.87141 -98.700844)
		(mid 286.897561 -98.751507)
		(end 286.918654 -98.804476)
		(width 0.0889)
		(layer "In4.Cu")
		(net "M_E_DQS_DP<7>")
	)
	(arc
		(start 286.87141 -98.30054)
		(mid 286.817784 -98.500692)
		(end 286.87141 -98.700844)
		(width 0.0889)
		(layer "In4.Cu")
		(net "M_E_DQS_DP<7>")
	)
	(arc
		(start 286.70631 -95.824294)
		(mid 286.752023 -95.946031)
		(end 286.756348 -96.076008)
		(width 0.0889)
		(layer "In4.Cu")
		(net "M_E_DQS_DP<7>")
	)
	(arc
		(start 289.81527 -105.339388)
		(mid 290.086687 -105.41675)
		(end 290.291266 -105.611168)
		(width 0.0889)
		(layer "In4.Cu")
		(net "M_E_DQS_DP<7>")
	)
	(arc
		(start 286.87141 -99.690936)
		(mid 286.950632 -99.980054)
		(end 286.87776 -100.270818)
		(width 0.0889)
		(layer "In4.Cu")
		(net "M_E_DQS_DP<7>")
	)
	(arc
		(start 288.95294 -104.843834)
		(mid 289.238364 -104.927301)
		(end 289.44697 -105.139236)
		(width 0.0889)
		(layer "In4.Cu")
		(net "M_E_DQS_DP<7>")
	)
	(arc
		(start 286.866584 -100.290122)
		(mid 286.817829 -100.486474)
		(end 286.87141 -100.681536)
		(width 0.0889)
		(layer "In4.Cu")
		(net "M_E_DQS_DP<7>")
	)
	(arc
		(start 286.87141 -97.310194)
		(mid 286.817911 -97.510092)
		(end 286.87141 -97.70999)
		(width 0.0889)
		(layer "In4.Cu")
		(net "M_E_DQS_DP<7>")
	)
	(arc
		(start 289.44697 -105.139236)
		(mid 289.588653 -105.28304)
		(end 289.782504 -105.339388)
		(width 0.0889)
		(layer "In4.Cu")
		(net "M_E_DQS_DP<7>")
	)
	(arc
		(start 286.3596 -95.033084)
		(mid 286.511284 -95.438185)
		(end 286.70631 -95.824294)
		(width 0.0889)
		(layer "In4.Cu")
		(net "M_E_DQS_DP<7>")
	)
	(arc
		(start 286.87141 -96.71939)
		(mid 286.950541 -97.014792)
		(end 286.87141 -97.310194)
		(width 0.0889)
		(layer "In4.Cu")
		(net "M_E_DQS_DP<7>")
	)
	(arc
		(start 288.58845 -104.643936)
		(mid 288.728529 -104.786672)
		(end 288.920174 -104.843834)
		(width 0.0889)
		(layer "In4.Cu")
		(net "M_E_DQS_DP<7>")
	)
	(arc
		(start 287.73628 -103.168704)
		(mid 287.809078 -103.459467)
		(end 287.72993 -103.748586)
		(width 0.0889)
		(layer "In4.Cu")
		(net "M_E_DQS_DP<7>")
	)
	(arc
		(start 286.866584 -101.280722)
		(mid 286.870331 -101.669978)
		(end 287.203134 -101.872034)
		(width 0.0889)
		(layer "In4.Cu")
		(net "M_E_DQS_DP<7>")
	)
	(arc
		(start 287.72993 -102.757986)
		(mid 287.67646 -102.953049)
		(end 287.725104 -103.1494)
		(width 0.0889)
		(layer "In4.Cu")
		(net "M_E_DQS_DP<7>")
	)
	(arc
		(start 287.2359 -101.872034)
		(mid 287.734151 -102.174874)
		(end 287.72993 -102.757986)
		(width 0.0889)
		(layer "In4.Cu")
		(net "M_E_DQS_DP<7>")
	)
	(arc
		(start 286.87141 -97.70999)
		(mid 286.950541 -98.005392)
		(end 286.87141 -98.300794)
		(width 0.0889)
		(layer "In4.Cu")
		(net "M_E_DQS_DP<7>")
	)
	(segment
		(start 285.9786 -103.450136)
		(end 285.9786 -104.5718)
		(width 0.0889)
		(layer "F.Cu")
		(net "M_E_DQS_DP<6>")
	)
	(segment
		(start 299.72 -109.6772)
		(end 299.72 -109.738414)
		(width 0.1016)
		(layer "F.Cu")
		(net "M_E_DQS_DP<6>")
	)
	(segment
		(start 303.537874 -144.8562)
		(end 303.294034 -144.61236)
		(width 0.1651)
		(layer "F.Cu")
		(net "M_E_DQS_DP<6>")
	)
	(segment
		(start 303.038002 -126.029974)
		(end 303.038002 -126.037086)
		(width 0.1651)
		(layer "F.Cu")
		(net "M_E_DQS_DP<6>")
	)
	(segment
		(start 303.500282 -147.27174)
		(end 303.500028 -147.27174)
		(width 0.1651)
		(layer "F.Cu")
		(net "M_E_DQS_DP<6>")
	)
	(segment
		(start 303.500028 -147.27174)
		(end 303.500028 -146.265646)
		(width 0.1651)
		(layer "F.Cu")
		(net "M_E_DQS_DP<6>")
	)
	(segment
		(start 286.131508 -103.193342)
		(end 285.9786 -103.450136)
		(width 0.0889)
		(layer "F.Cu")
		(net "M_E_DQS_DP<6>")
	)
	(segment
		(start 286.2834 -104.8766)
		(end 286.404558 -104.8766)
		(width 0.1016)
		(layer "F.Cu")
		(net "M_E_DQS_DP<6>")
	)
	(segment
		(start 295.709594 -105.867454)
		(end 299.16247 -109.32033)
		(width 0.1016)
		(layer "F.Cu")
		(net "M_E_DQS_DP<6>")
	)
	(segment
		(start 303.97323 -122.6566)
		(end 303.675796 -122.6566)
		(width 0.1651)
		(layer "F.Cu")
		(net "M_E_DQS_DP<6>")
	)
	(segment
		(start 303.624996 -121.3993)
		(end 303.97323 -121.3993)
		(width 0.1651)
		(layer "F.Cu")
		(net "M_E_DQS_DP<6>")
	)
	(segment
		(start 299.36313 -109.32033)
		(end 299.72 -109.6772)
		(width 0.1016)
		(layer "F.Cu")
		(net "M_E_DQS_DP<6>")
	)
	(segment
		(start 303.500028 -146.265646)
		(end 303.537874 -146.2278)
		(width 0.1651)
		(layer "F.Cu")
		(net "M_E_DQS_DP<6>")
	)
	(segment
		(start 303.675796 -122.6566)
		(end 303.510696 -122.8217)
		(width 0.1651)
		(layer "F.Cu")
		(net "M_E_DQS_DP<6>")
	)
	(segment
		(start 299.16247 -109.32033)
		(end 299.36313 -109.32033)
		(width 0.1016)
		(layer "F.Cu")
		(net "M_E_DQS_DP<6>")
	)
	(segment
		(start 303.510696 -123.170696)
		(end 303.866296 -123.526296)
		(width 0.1651)
		(layer "F.Cu")
		(net "M_E_DQS_DP<6>")
	)
	(segment
		(start 303.52238 -113.540794)
		(end 303.52238 -120.520206)
		(width 0.1651)
		(layer "F.Cu")
		(net "M_E_DQS_DP<6>")
	)
	(segment
		(start 303.537874 -146.2278)
		(end 303.537874 -144.8562)
		(width 0.1651)
		(layer "F.Cu")
		(net "M_E_DQS_DP<6>")
	)
	(segment
		(start 303.294034 -144.61236)
		(end 303.038002 -144.61236)
		(width 0.1651)
		(layer "F.Cu")
		(net "M_E_DQS_DP<6>")
	)
	(segment
		(start 303.510696 -122.8217)
		(end 303.510696 -123.170696)
		(width 0.1651)
		(layer "F.Cu")
		(net "M_E_DQS_DP<6>")
	)
	(segment
		(start 285.7881 -101.967538)
		(end 286.118046 -102.729538)
		(width 0.0889)
		(layer "F.Cu")
		(net "M_E_DQS_DP<6>")
	)
	(segment
		(start 304.271172 -122.358658)
		(end 303.97323 -122.6566)
		(width 0.1651)
		(layer "F.Cu")
		(net "M_E_DQS_DP<6>")
	)
	(segment
		(start 303.866296 -125.20168)
		(end 303.038002 -126.029974)
		(width 0.1651)
		(layer "F.Cu")
		(net "M_E_DQS_DP<6>")
	)
	(segment
		(start 303.97323 -121.3993)
		(end 304.271172 -121.697242)
		(width 0.1651)
		(layer "F.Cu")
		(net "M_E_DQS_DP<6>")
	)
	(segment
		(start 285.9786 -104.5718)
		(end 286.2834 -104.8766)
		(width 0.0889)
		(layer "F.Cu")
		(net "M_E_DQS_DP<6>")
	)
	(segment
		(start 303.52238 -120.520206)
		(end 303.52238 -121.296684)
		(width 0.1651)
		(layer "F.Cu")
		(net "M_E_DQS_DP<6>")
	)
	(segment
		(start 286.118046 -102.729538)
		(end 286.134556 -102.757986)
		(width 0.0889)
		(layer "F.Cu")
		(net "M_E_DQS_DP<6>")
	)
	(segment
		(start 287.395412 -105.867454)
		(end 295.709594 -105.867454)
		(width 0.1016)
		(layer "F.Cu")
		(net "M_E_DQS_DP<6>")
	)
	(segment
		(start 299.72 -109.738414)
		(end 303.52238 -113.540794)
		(width 0.1651)
		(layer "F.Cu")
		(net "M_E_DQS_DP<6>")
	)
	(segment
		(start 286.404558 -104.8766)
		(end 287.395412 -105.867454)
		(width 0.1016)
		(layer "F.Cu")
		(net "M_E_DQS_DP<6>")
	)
	(segment
		(start 304.271172 -121.697242)
		(end 304.271172 -122.358658)
		(width 0.1651)
		(layer "F.Cu")
		(net "M_E_DQS_DP<6>")
	)
	(segment
		(start 303.52238 -121.296684)
		(end 303.624996 -121.3993)
		(width 0.1651)
		(layer "F.Cu")
		(net "M_E_DQS_DP<6>")
	)
	(segment
		(start 303.866296 -123.526296)
		(end 303.866296 -125.20168)
		(width 0.1651)
		(layer "F.Cu")
		(net "M_E_DQS_DP<6>")
	)
	(via
		(at 303.038002 -126.037086)
		(size 0.508)
		(drill 0.254)
		(layers "F.Cu" "B.Cu")
		(net "M_E_DQS_DP<6>")
	)
	(via
		(at 303.038002 -140.541756)
		(size 0.508)
		(drill 0.254)
		(layers "F.Cu" "B.Cu")
		(net "M_E_DQS_DP<6>")
	)
	(via
		(at 303.52238 -120.520206)
		(size 0.508)
		(drill 0.254)
		(layers "F.Cu" "B.Cu")
		(net "M_E_DQS_DP<6>")
	)
	(via
		(at 303.038002 -144.61236)
		(size 0.508)
		(drill 0.254)
		(layers "F.Cu" "B.Cu")
		(net "M_E_DQS_DP<6>")
	)
	(arc
		(start 286.134556 -102.757986)
		(mid 286.192159 -102.976086)
		(end 286.131508 -103.193342)
		(width 0.0889)
		(layer "F.Cu")
		(net "M_E_DQS_DP<6>")
	)
	(segment
		(start 303.537874 -139.065)
		(end 303.500028 -139.027154)
		(width 0.1651)
		(layer "B.Cu")
		(net "M_E_DQS_DP<6>")
	)
	(segment
		(start 303.537874 -140.2842)
		(end 303.537874 -139.065)
		(width 0.1651)
		(layer "B.Cu")
		(net "M_E_DQS_DP<6>")
	)
	(segment
		(start 303.500028 -137.877296)
		(end 303.500282 -137.877296)
		(width 0.1651)
		(layer "B.Cu")
		(net "M_E_DQS_DP<6>")
	)
	(segment
		(start 303.500028 -139.027154)
		(end 303.500028 -137.877296)
		(width 0.1651)
		(layer "B.Cu")
		(net "M_E_DQS_DP<6>")
	)
	(segment
		(start 303.280318 -140.541756)
		(end 303.537874 -140.2842)
		(width 0.1651)
		(layer "B.Cu")
		(net "M_E_DQS_DP<6>")
	)
	(segment
		(start 303.038002 -140.541756)
		(end 303.280318 -140.541756)
		(width 0.1651)
		(layer "B.Cu")
		(net "M_E_DQS_DP<6>")
	)
	(segment
		(start 303.820322 -127.747522)
		(end 303.4792 -127.4064)
		(width 0.14224)
		(layer "In4.Cu")
		(net "M_E_DQS_DP<6>")
	)
	(segment
		(start 303.820322 -138.421618)
		(end 303.422304 -138.0236)
		(width 0.14224)
		(layer "In4.Cu")
		(net "M_E_DQS_DP<6>")
	)
	(segment
		(start 303.820322 -139.759436)
		(end 303.820322 -138.421618)
		(width 0.14224)
		(layer "In4.Cu")
		(net "M_E_DQS_DP<6>")
	)
	(segment
		(start 303.422304 -137.362438)
		(end 303.820322 -136.96442)
		(width 0.14224)
		(layer "In4.Cu")
		(net "M_E_DQS_DP<6>")
	)
	(segment
		(start 303.473866 -133.253734)
		(end 303.473866 -132.407406)
		(width 0.14224)
		(layer "In4.Cu")
		(net "M_E_DQS_DP<6>")
	)
	(segment
		(start 303.4792 -127.4064)
		(end 303.4792 -126.478284)
		(width 0.14224)
		(layer "In4.Cu")
		(net "M_E_DQS_DP<6>")
	)
	(segment
		(start 303.820322 -133.60019)
		(end 303.473866 -133.253734)
		(width 0.14224)
		(layer "In4.Cu")
		(net "M_E_DQS_DP<6>")
	)
	(segment
		(start 303.820322 -132.06095)
		(end 303.820322 -127.747522)
		(width 0.14224)
		(layer "In4.Cu")
		(net "M_E_DQS_DP<6>")
	)
	(segment
		(start 303.038002 -140.541756)
		(end 303.820322 -139.759436)
		(width 0.14224)
		(layer "In4.Cu")
		(net "M_E_DQS_DP<6>")
	)
	(segment
		(start 303.4792 -126.478284)
		(end 303.038002 -126.037086)
		(width 0.14224)
		(layer "In4.Cu")
		(net "M_E_DQS_DP<6>")
	)
	(segment
		(start 303.422304 -138.0236)
		(end 303.422304 -137.362438)
		(width 0.14224)
		(layer "In4.Cu")
		(net "M_E_DQS_DP<6>")
	)
	(segment
		(start 303.820322 -136.96442)
		(end 303.820322 -133.60019)
		(width 0.14224)
		(layer "In4.Cu")
		(net "M_E_DQS_DP<6>")
	)
	(segment
		(start 303.473866 -132.407406)
		(end 303.820322 -132.06095)
		(width 0.14224)
		(layer "In4.Cu")
		(net "M_E_DQS_DP<6>")
	)
	(segment
		(start 302.86071 -142.899892)
		(end 303.04105 -142.719552)
		(width 0.14224)
		(layer "In9.Cu")
		(net "M_E_DQS_DP<6>")
	)
	(segment
		(start 302.833786 -141.6558)
		(end 303.21885 -141.6558)
		(width 0.14224)
		(layer "In9.Cu")
		(net "M_E_DQS_DP<6>")
	)
	(segment
		(start 302.859186 -143.4592)
		(end 302.663352 -143.263366)
		(width 0.14224)
		(layer "In9.Cu")
		(net "M_E_DQS_DP<6>")
	)
	(segment
		(start 302.663352 -143.263366)
		(end 302.663352 -143.037052)
		(width 0.14224)
		(layer "In9.Cu")
		(net "M_E_DQS_DP<6>")
	)
	(segment
		(start 302.663352 -141.826234)
		(end 302.833786 -141.6558)
		(width 0.14224)
		(layer "In9.Cu")
		(net "M_E_DQS_DP<6>")
	)
	(segment
		(start 303.49825 -144.152112)
		(end 303.49825 -143.7132)
		(width 0.14224)
		(layer "In9.Cu")
		(net "M_E_DQS_DP<6>")
	)
	(segment
		(start 303.04105 -142.4432)
		(end 302.86325 -142.2654)
		(width 0.14224)
		(layer "In9.Cu")
		(net "M_E_DQS_DP<6>")
	)
	(segment
		(start 303.47285 -141.4018)
		(end 303.47285 -140.976604)
		(width 0.14224)
		(layer "In9.Cu")
		(net "M_E_DQS_DP<6>")
	)
	(segment
		(start 303.04105 -142.719552)
		(end 303.04105 -142.4432)
		(width 0.14224)
		(layer "In9.Cu")
		(net "M_E_DQS_DP<6>")
	)
	(segment
		(start 303.038002 -144.61236)
		(end 303.49825 -144.152112)
		(width 0.14224)
		(layer "In9.Cu")
		(net "M_E_DQS_DP<6>")
	)
	(segment
		(start 302.800512 -142.899892)
		(end 302.86071 -142.899892)
		(width 0.14224)
		(layer "In9.Cu")
		(net "M_E_DQS_DP<6>")
	)
	(segment
		(start 302.663352 -142.150592)
		(end 302.663352 -141.826234)
		(width 0.14224)
		(layer "In9.Cu")
		(net "M_E_DQS_DP<6>")
	)
	(segment
		(start 302.86325 -142.2654)
		(end 302.77816 -142.2654)
		(width 0.14224)
		(layer "In9.Cu")
		(net "M_E_DQS_DP<6>")
	)
	(segment
		(start 303.49825 -143.7132)
		(end 303.24425 -143.4592)
		(width 0.14224)
		(layer "In9.Cu")
		(net "M_E_DQS_DP<6>")
	)
	(segment
		(start 303.47285 -140.976604)
		(end 303.038002 -140.541756)
		(width 0.14224)
		(layer "In9.Cu")
		(net "M_E_DQS_DP<6>")
	)
	(segment
		(start 302.663352 -143.037052)
		(end 302.800512 -142.899892)
		(width 0.14224)
		(layer "In9.Cu")
		(net "M_E_DQS_DP<6>")
	)
	(segment
		(start 303.21885 -141.6558)
		(end 303.47285 -141.4018)
		(width 0.14224)
		(layer "In9.Cu")
		(net "M_E_DQS_DP<6>")
	)
	(segment
		(start 302.77816 -142.2654)
		(end 302.663352 -142.150592)
		(width 0.14224)
		(layer "In9.Cu")
		(net "M_E_DQS_DP<6>")
	)
	(segment
		(start 303.24425 -143.4592)
		(end 302.859186 -143.4592)
		(width 0.14224)
		(layer "In9.Cu")
		(net "M_E_DQS_DP<6>")
	)
	(segment
		(start 290.6522 -117.9068)
		(end 291.5158 -117.9068)
		(width 0.1651)
		(layer "F.Cu")
		(net "M_E_DQS_DP<5>")
	)
	(segment
		(start 294.735758 -123.522486)
		(end 294.303704 -123.522486)
		(width 0.1651)
		(layer "F.Cu")
		(net "M_E_DQS_DP<5>")
	)
	(segment
		(start 280.95702 -105.802938)
		(end 281.05862 -105.904538)
		(width 0.0889)
		(layer "F.Cu")
		(net "M_E_DQS_DP<5>")
	)
	(segment
		(start 294.480996 -125.23343)
		(end 293.688008 -126.026418)
		(width 0.1651)
		(layer "F.Cu")
		(net "M_E_DQS_DP<5>")
	)
	(segment
		(start 294.150288 -147.27174)
		(end 294.150034 -147.27174)
		(width 0.1651)
		(layer "F.Cu")
		(net "M_E_DQS_DP<5>")
	)
	(segment
		(start 285.279846 -112.8649)
		(end 285.6738 -112.8649)
		(width 0.1016)
		(layer "F.Cu")
		(net "M_E_DQS_DP<5>")
	)
	(segment
		(start 280.94178 -103.268018)
		(end 280.827734 -103.382064)
		(width 0.0889)
		(layer "F.Cu")
		(net "M_E_DQS_DP<5>")
	)
	(segment
		(start 286.1564 -113.411)
		(end 290.6522 -117.9068)
		(width 0.1651)
		(layer "F.Cu")
		(net "M_E_DQS_DP<5>")
	)
	(segment
		(start 295.0337 -123.224544)
		(end 294.735758 -123.522486)
		(width 0.1651)
		(layer "F.Cu")
		(net "M_E_DQS_DP<5>")
	)
	(segment
		(start 294.303704 -123.522486)
		(end 294.1574 -123.66879)
		(width 0.1651)
		(layer "F.Cu")
		(net "M_E_DQS_DP<5>")
	)
	(segment
		(start 294.104822 -121.91492)
		(end 294.302688 -122.112786)
		(width 0.1651)
		(layer "F.Cu")
		(net "M_E_DQS_DP<5>")
	)
	(segment
		(start 294.480996 -124.300996)
		(end 294.480996 -125.23343)
		(width 0.1651)
		(layer "F.Cu")
		(net "M_E_DQS_DP<5>")
	)
	(segment
		(start 294.18788 -144.8562)
		(end 293.94404 -144.61236)
		(width 0.1651)
		(layer "F.Cu")
		(net "M_E_DQS_DP<5>")
	)
	(segment
		(start 280.96718 -102.729538)
		(end 280.98369 -102.757986)
		(width 0.0889)
		(layer "F.Cu")
		(net "M_E_DQS_DP<5>")
	)
	(segment
		(start 294.150034 -146.265646)
		(end 294.18788 -146.2278)
		(width 0.1651)
		(layer "F.Cu")
		(net "M_E_DQS_DP<5>")
	)
	(segment
		(start 293.94404 -144.61236)
		(end 293.688008 -144.61236)
		(width 0.1651)
		(layer "F.Cu")
		(net "M_E_DQS_DP<5>")
	)
	(segment
		(start 294.104822 -120.495822)
		(end 294.104822 -121.91492)
		(width 0.1651)
		(layer "F.Cu")
		(net "M_E_DQS_DP<5>")
	)
	(segment
		(start 294.150034 -147.27174)
		(end 294.150034 -146.265646)
		(width 0.1651)
		(layer "F.Cu")
		(net "M_E_DQS_DP<5>")
	)
	(segment
		(start 280.827734 -103.90124)
		(end 280.95702 -104.030526)
		(width 0.0889)
		(layer "F.Cu")
		(net "M_E_DQS_DP<5>")
	)
	(segment
		(start 286.1564 -113.3475)
		(end 286.1564 -113.411)
		(width 0.1016)
		(layer "F.Cu")
		(net "M_E_DQS_DP<5>")
	)
	(segment
		(start 294.735758 -122.112786)
		(end 295.0337 -122.410728)
		(width 0.1651)
		(layer "F.Cu")
		(net "M_E_DQS_DP<5>")
	)
	(segment
		(start 291.5158 -117.9068)
		(end 294.104822 -120.495822)
		(width 0.1651)
		(layer "F.Cu")
		(net "M_E_DQS_DP<5>")
	)
	(segment
		(start 295.0337 -122.410728)
		(end 295.0337 -123.224544)
		(width 0.1651)
		(layer "F.Cu")
		(net "M_E_DQS_DP<5>")
	)
	(segment
		(start 294.18788 -146.2278)
		(end 294.18788 -144.8562)
		(width 0.1651)
		(layer "F.Cu")
		(net "M_E_DQS_DP<5>")
	)
	(segment
		(start 281.05862 -108.643674)
		(end 285.279846 -112.8649)
		(width 0.1016)
		(layer "F.Cu")
		(net "M_E_DQS_DP<5>")
	)
	(segment
		(start 280.637234 -101.967538)
		(end 280.96718 -102.729538)
		(width 0.0889)
		(layer "F.Cu")
		(net "M_E_DQS_DP<5>")
	)
	(segment
		(start 294.1574 -123.66879)
		(end 294.1574 -123.9774)
		(width 0.1651)
		(layer "F.Cu")
		(net "M_E_DQS_DP<5>")
	)
	(segment
		(start 280.827734 -103.382064)
		(end 280.827734 -103.90124)
		(width 0.0889)
		(layer "F.Cu")
		(net "M_E_DQS_DP<5>")
	)
	(segment
		(start 294.1574 -123.9774)
		(end 294.480996 -124.300996)
		(width 0.1651)
		(layer "F.Cu")
		(net "M_E_DQS_DP<5>")
	)
	(segment
		(start 294.302688 -122.112786)
		(end 294.735758 -122.112786)
		(width 0.1651)
		(layer "F.Cu")
		(net "M_E_DQS_DP<5>")
	)
	(segment
		(start 280.95702 -104.030526)
		(end 280.95702 -105.802938)
		(width 0.0889)
		(layer "F.Cu")
		(net "M_E_DQS_DP<5>")
	)
	(segment
		(start 285.6738 -112.8649)
		(end 286.1564 -113.3475)
		(width 0.1016)
		(layer "F.Cu")
		(net "M_E_DQS_DP<5>")
	)
	(segment
		(start 281.05862 -105.904538)
		(end 281.05862 -108.643674)
		(width 0.1016)
		(layer "F.Cu")
		(net "M_E_DQS_DP<5>")
	)
	(segment
		(start 280.980642 -103.202486)
		(end 280.94178 -103.268018)
		(width 0.0889)
		(layer "F.Cu")
		(net "M_E_DQS_DP<5>")
	)
	(via
		(at 293.688008 -144.61236)
		(size 0.508)
		(drill 0.254)
		(layers "F.Cu" "B.Cu")
		(net "M_E_DQS_DP<5>")
	)
	(via
		(at 293.688008 -126.026418)
		(size 0.508)
		(drill 0.254)
		(layers "F.Cu" "B.Cu")
		(net "M_E_DQS_DP<5>")
	)
	(via
		(at 293.688008 -140.541756)
		(size 0.508)
		(drill 0.254)
		(layers "F.Cu" "B.Cu")
		(net "M_E_DQS_DP<5>")
	)
	(arc
		(start 280.98369 -102.757986)
		(mid 281.042491 -102.980658)
		(end 280.980642 -103.202486)
		(width 0.0889)
		(layer "F.Cu")
		(net "M_E_DQS_DP<5>")
	)
	(segment
		(start 294.150034 -137.877296)
		(end 294.150288 -137.877296)
		(width 0.1651)
		(layer "B.Cu")
		(net "M_E_DQS_DP<5>")
	)
	(segment
		(start 294.18788 -139.065)
		(end 294.150034 -139.027154)
		(width 0.1651)
		(layer "B.Cu")
		(net "M_E_DQS_DP<5>")
	)
	(segment
		(start 294.18788 -140.2842)
		(end 294.18788 -139.065)
		(width 0.1651)
		(layer "B.Cu")
		(net "M_E_DQS_DP<5>")
	)
	(segment
		(start 294.150034 -139.027154)
		(end 294.150034 -137.877296)
		(width 0.1651)
		(layer "B.Cu")
		(net "M_E_DQS_DP<5>")
	)
	(segment
		(start 293.930324 -140.541756)
		(end 294.18788 -140.2842)
		(width 0.1651)
		(layer "B.Cu")
		(net "M_E_DQS_DP<5>")
	)
	(segment
		(start 293.688008 -140.541756)
		(end 293.930324 -140.541756)
		(width 0.1651)
		(layer "B.Cu")
		(net "M_E_DQS_DP<5>")
	)
	(segment
		(start 294.148256 -143.7132)
		(end 294.148256 -144.152112)
		(width 0.14224)
		(layer "In9.Cu")
		(net "M_E_DQS_DP<5>")
	)
	(segment
		(start 293.450518 -142.899892)
		(end 293.313358 -143.037052)
		(width 0.14224)
		(layer "In9.Cu")
		(net "M_E_DQS_DP<5>")
	)
	(segment
		(start 293.509192 -143.4592)
		(end 293.894256 -143.4592)
		(width 0.14224)
		(layer "In9.Cu")
		(net "M_E_DQS_DP<5>")
	)
	(segment
		(start 293.510716 -142.899892)
		(end 293.450518 -142.899892)
		(width 0.14224)
		(layer "In9.Cu")
		(net "M_E_DQS_DP<5>")
	)
	(segment
		(start 294.148256 -144.152112)
		(end 293.688008 -144.61236)
		(width 0.14224)
		(layer "In9.Cu")
		(net "M_E_DQS_DP<5>")
	)
	(segment
		(start 293.513256 -142.2654)
		(end 293.691056 -142.4432)
		(width 0.14224)
		(layer "In9.Cu")
		(net "M_E_DQS_DP<5>")
	)
	(segment
		(start 293.483792 -141.6558)
		(end 293.313358 -141.826234)
		(width 0.14224)
		(layer "In9.Cu")
		(net "M_E_DQS_DP<5>")
	)
	(segment
		(start 294.122856 -141.4018)
		(end 293.868856 -141.6558)
		(width 0.14224)
		(layer "In9.Cu")
		(net "M_E_DQS_DP<5>")
	)
	(segment
		(start 293.688008 -140.54201)
		(end 294.122856 -140.976858)
		(width 0.14224)
		(layer "In9.Cu")
		(net "M_E_DQS_DP<5>")
	)
	(segment
		(start 293.894256 -143.4592)
		(end 294.148256 -143.7132)
		(width 0.14224)
		(layer "In9.Cu")
		(net "M_E_DQS_DP<5>")
	)
	(segment
		(start 293.313358 -141.826234)
		(end 293.313358 -142.150592)
		(width 0.14224)
		(layer "In9.Cu")
		(net "M_E_DQS_DP<5>")
	)
	(segment
		(start 293.691056 -142.719552)
		(end 293.510716 -142.899892)
		(width 0.14224)
		(layer "In9.Cu")
		(net "M_E_DQS_DP<5>")
	)
	(segment
		(start 293.868856 -141.6558)
		(end 293.483792 -141.6558)
		(width 0.14224)
		(layer "In9.Cu")
		(net "M_E_DQS_DP<5>")
	)
	(segment
		(start 293.691056 -142.4432)
		(end 293.691056 -142.719552)
		(width 0.14224)
		(layer "In9.Cu")
		(net "M_E_DQS_DP<5>")
	)
	(segment
		(start 293.313358 -142.150592)
		(end 293.428166 -142.2654)
		(width 0.14224)
		(layer "In9.Cu")
		(net "M_E_DQS_DP<5>")
	)
	(segment
		(start 293.313358 -143.263366)
		(end 293.509192 -143.4592)
		(width 0.14224)
		(layer "In9.Cu")
		(net "M_E_DQS_DP<5>")
	)
	(segment
		(start 293.313358 -143.037052)
		(end 293.313358 -143.263366)
		(width 0.14224)
		(layer "In9.Cu")
		(net "M_E_DQS_DP<5>")
	)
	(segment
		(start 293.688008 -140.541756)
		(end 293.688008 -140.54201)
		(width 0.14224)
		(layer "In9.Cu")
		(net "M_E_DQS_DP<5>")
	)
	(segment
		(start 293.428166 -142.2654)
		(end 293.513256 -142.2654)
		(width 0.14224)
		(layer "In9.Cu")
		(net "M_E_DQS_DP<5>")
	)
	(segment
		(start 294.122856 -140.976858)
		(end 294.122856 -141.4018)
		(width 0.14224)
		(layer "In9.Cu")
		(net "M_E_DQS_DP<5>")
	)
	(segment
		(start 293.9034 -127.609854)
		(end 293.9034 -127.1016)
		(width 0.14224)
		(layer "In11.Cu")
		(net "M_E_DQS_DP<5>")
	)
	(segment
		(start 294.132 -140.0048)
		(end 294.470328 -139.666472)
		(width 0.14224)
		(layer "In11.Cu")
		(net "M_E_DQS_DP<5>")
	)
	(segment
		(start 293.688008 -140.541756)
		(end 294.132 -140.097764)
		(width 0.14224)
		(layer "In11.Cu")
		(net "M_E_DQS_DP<5>")
	)
	(segment
		(start 294.132 -140.097764)
		(end 294.132 -140.0048)
		(width 0.14224)
		(layer "In11.Cu")
		(net "M_E_DQS_DP<5>")
	)
	(segment
		(start 294.132 -126.873)
		(end 294.132 -126.47041)
		(width 0.14224)
		(layer "In11.Cu")
		(net "M_E_DQS_DP<5>")
	)
	(segment
		(start 294.132 -126.47041)
		(end 293.688008 -126.026418)
		(width 0.14224)
		(layer "In11.Cu")
		(net "M_E_DQS_DP<5>")
	)
	(segment
		(start 294.470328 -128.176782)
		(end 293.9034 -127.609854)
		(width 0.14224)
		(layer "In11.Cu")
		(net "M_E_DQS_DP<5>")
	)
	(segment
		(start 294.470328 -139.666472)
		(end 294.470328 -128.176782)
		(width 0.14224)
		(layer "In11.Cu")
		(net "M_E_DQS_DP<5>")
	)
	(segment
		(start 293.9034 -127.1016)
		(end 294.132 -126.873)
		(width 0.14224)
		(layer "In11.Cu")
		(net "M_E_DQS_DP<5>")
	)
	(segment
		(start 284.799786 -147.27174)
		(end 284.800294 -147.27174)
		(width 0.1651)
		(layer "F.Cu")
		(net "M_E_DQS_DP<4>")
	)
	(segment
		(start 284.837632 -144.8562)
		(end 284.837632 -146.2278)
		(width 0.1651)
		(layer "F.Cu")
		(net "M_E_DQS_DP<4>")
	)
	(segment
		(start 284.799786 -146.265646)
		(end 284.799786 -147.27174)
		(width 0.1651)
		(layer "F.Cu")
		(net "M_E_DQS_DP<4>")
	)
	(segment
		(start 284.33776 -144.61236)
		(end 284.593792 -144.61236)
		(width 0.1651)
		(layer "F.Cu")
		(net "M_E_DQS_DP<4>")
	)
	(segment
		(start 284.593792 -144.61236)
		(end 284.837632 -144.8562)
		(width 0.1651)
		(layer "F.Cu")
		(net "M_E_DQS_DP<4>")
	)
	(segment
		(start 284.837632 -146.2278)
		(end 284.799786 -146.265646)
		(width 0.1651)
		(layer "F.Cu")
		(net "M_E_DQS_DP<4>")
	)
	(segment
		(start 272.910808 -98.500184)
		(end 273.482308 -98.500184)
		(width 0.1651)
		(layer "F.Cu")
		(net "M_E_DQS_DP<4>")
	)
	(via
		(at 284.33776 -144.61236)
		(size 0.508)
		(drill 0.254)
		(layers "F.Cu" "B.Cu")
		(net "M_E_DQS_DP<4>")
	)
	(via
		(at 284.33776 -140.541756)
		(size 0.508)
		(drill 0.254)
		(layers "F.Cu" "B.Cu")
		(net "M_E_DQS_DP<4>")
	)
	(via
		(at 273.482308 -98.500184)
		(size 0.508)
		(drill 0.254)
		(layers "F.Cu" "B.Cu")
		(net "M_E_DQS_DP<4>")
	)
	(segment
		(start 284.837632 -140.2842)
		(end 284.837632 -139.065)
		(width 0.1651)
		(layer "B.Cu")
		(net "M_E_DQS_DP<4>")
	)
	(segment
		(start 284.799786 -137.877296)
		(end 284.800294 -137.877296)
		(width 0.1651)
		(layer "B.Cu")
		(net "M_E_DQS_DP<4>")
	)
	(segment
		(start 284.33776 -140.541756)
		(end 284.580076 -140.541756)
		(width 0.1651)
		(layer "B.Cu")
		(net "M_E_DQS_DP<4>")
	)
	(segment
		(start 284.580076 -140.541756)
		(end 284.837632 -140.2842)
		(width 0.1651)
		(layer "B.Cu")
		(net "M_E_DQS_DP<4>")
	)
	(segment
		(start 284.799786 -139.027154)
		(end 284.799786 -137.877296)
		(width 0.1651)
		(layer "B.Cu")
		(net "M_E_DQS_DP<4>")
	)
	(segment
		(start 284.837632 -139.065)
		(end 284.799786 -139.027154)
		(width 0.1651)
		(layer "B.Cu")
		(net "M_E_DQS_DP<4>")
	)
	(segment
		(start 274.98294 -101.209348)
		(end 274.98294 -102.914196)
		(width 0.0889)
		(layer "In4.Cu")
		(net "M_E_DQS_DP<4>")
	)
	(segment
		(start 283.963364 -142.150592)
		(end 283.963364 -141.826234)
		(width 0.14224)
		(layer "In4.Cu")
		(net "M_E_DQS_DP<4>")
	)
	(segment
		(start 285.171134 -128.674114)
		(end 285.171134 -139.708636)
		(width 0.14224)
		(layer "In4.Cu")
		(net "M_E_DQS_DP<4>")
	)
	(segment
		(start 284.107636 -127.46736)
		(end 284.107636 -128.102868)
		(width 0.14224)
		(layer "In4.Cu")
		(net "M_E_DQS_DP<4>")
	)
	(segment
		(start 284.756352 -125.861318)
		(end 285.13532 -126.240286)
		(width 0.14224)
		(layer "In4.Cu")
		(net "M_E_DQS_DP<4>")
	)
	(segment
		(start 275.243544 -103.1748)
		(end 275.243544 -106.50093)
		(width 0.0889)
		(layer "In4.Cu")
		(net "M_E_DQS_DP<4>")
	)
	(segment
		(start 284.341062 -142.719552)
		(end 284.341062 -142.4432)
		(width 0.14224)
		(layer "In4.Cu")
		(net "M_E_DQS_DP<4>")
	)
	(segment
		(start 284.338014 -140.541756)
		(end 284.33776 -140.541756)
		(width 0.14224)
		(layer "In4.Cu")
		(net "M_E_DQS_DP<4>")
	)
	(segment
		(start 284.341062 -142.4432)
		(end 284.163262 -142.2654)
		(width 0.14224)
		(layer "In4.Cu")
		(net "M_E_DQS_DP<4>")
	)
	(segment
		(start 284.301438 -127.273558)
		(end 284.107636 -127.46736)
		(width 0.14224)
		(layer "In4.Cu")
		(net "M_E_DQS_DP<4>")
	)
	(segment
		(start 284.772862 -141.4018)
		(end 284.772862 -140.976604)
		(width 0.14224)
		(layer "In4.Cu")
		(net "M_E_DQS_DP<4>")
	)
	(segment
		(start 284.133798 -141.6558)
		(end 284.518862 -141.6558)
		(width 0.14224)
		(layer "In4.Cu")
		(net "M_E_DQS_DP<4>")
	)
	(segment
		(start 284.163262 -142.2654)
		(end 284.078172 -142.2654)
		(width 0.14224)
		(layer "In4.Cu")
		(net "M_E_DQS_DP<4>")
	)
	(segment
		(start 284.107636 -128.102868)
		(end 284.317948 -128.31318)
		(width 0.14224)
		(layer "In4.Cu")
		(net "M_E_DQS_DP<4>")
	)
	(segment
		(start 275.243544 -106.50093)
		(end 275.282914 -106.5403)
		(width 0.0889)
		(layer "In4.Cu")
		(net "M_E_DQS_DP<4>")
	)
	(segment
		(start 284.159198 -143.4592)
		(end 283.963364 -143.263366)
		(width 0.14224)
		(layer "In4.Cu")
		(net "M_E_DQS_DP<4>")
	)
	(segment
		(start 284.544262 -143.4592)
		(end 284.159198 -143.4592)
		(width 0.14224)
		(layer "In4.Cu")
		(net "M_E_DQS_DP<4>")
	)
	(segment
		(start 275.282914 -106.5403)
		(end 275.282914 -106.562398)
		(width 0.0889)
		(layer "In4.Cu")
		(net "M_E_DQS_DP<4>")
	)
	(segment
		(start 274.98294 -102.914196)
		(end 275.243544 -103.1748)
		(width 0.0889)
		(layer "In4.Cu")
		(net "M_E_DQS_DP<4>")
	)
	(segment
		(start 284.338014 -144.61236)
		(end 284.798262 -144.152112)
		(width 0.14224)
		(layer "In4.Cu")
		(net "M_E_DQS_DP<4>")
	)
	(segment
		(start 273.994118 -100.186998)
		(end 274.039838 -100.266246)
		(width 0.0889)
		(layer "In4.Cu")
		(net "M_E_DQS_DP<4>")
	)
	(segment
		(start 274.039838 -100.266246)
		(end 274.98294 -101.209348)
		(width 0.0889)
		(layer "In4.Cu")
		(net "M_E_DQS_DP<4>")
	)
	(segment
		(start 275.282914 -116.296948)
		(end 284.007814 -125.021848)
		(width 0.14224)
		(layer "In4.Cu")
		(net "M_E_DQS_DP<4>")
	)
	(segment
		(start 284.518862 -141.6558)
		(end 284.772862 -141.4018)
		(width 0.14224)
		(layer "In4.Cu")
		(net "M_E_DQS_DP<4>")
	)
	(segment
		(start 284.230826 -125.861318)
		(end 284.756352 -125.861318)
		(width 0.14224)
		(layer "In4.Cu")
		(net "M_E_DQS_DP<4>")
	)
	(segment
		(start 284.160722 -142.899892)
		(end 284.341062 -142.719552)
		(width 0.14224)
		(layer "In4.Cu")
		(net "M_E_DQS_DP<4>")
	)
	(segment
		(start 284.756352 -127.273558)
		(end 284.301438 -127.273558)
		(width 0.14224)
		(layer "In4.Cu")
		(net "M_E_DQS_DP<4>")
	)
	(segment
		(start 284.100524 -142.899892)
		(end 284.160722 -142.899892)
		(width 0.14224)
		(layer "In4.Cu")
		(net "M_E_DQS_DP<4>")
	)
	(segment
		(start 285.13532 -126.89459)
		(end 284.756352 -127.273558)
		(width 0.14224)
		(layer "In4.Cu")
		(net "M_E_DQS_DP<4>")
	)
	(segment
		(start 284.078172 -142.2654)
		(end 283.963364 -142.150592)
		(width 0.14224)
		(layer "In4.Cu")
		(net "M_E_DQS_DP<4>")
	)
	(segment
		(start 284.798262 -143.7132)
		(end 284.544262 -143.4592)
		(width 0.14224)
		(layer "In4.Cu")
		(net "M_E_DQS_DP<4>")
	)
	(segment
		(start 284.8102 -128.31318)
		(end 285.171134 -128.674114)
		(width 0.14224)
		(layer "In4.Cu")
		(net "M_E_DQS_DP<4>")
	)
	(segment
		(start 284.317948 -128.31318)
		(end 284.8102 -128.31318)
		(width 0.14224)
		(layer "In4.Cu")
		(net "M_E_DQS_DP<4>")
	)
	(segment
		(start 283.963364 -143.263366)
		(end 283.963364 -143.037052)
		(width 0.14224)
		(layer "In4.Cu")
		(net "M_E_DQS_DP<4>")
	)
	(segment
		(start 284.33776 -144.61236)
		(end 284.338014 -144.61236)
		(width 0.14224)
		(layer "In4.Cu")
		(net "M_E_DQS_DP<4>")
	)
	(segment
		(start 275.282914 -106.562398)
		(end 275.282914 -116.296948)
		(width 0.14224)
		(layer "In4.Cu")
		(net "M_E_DQS_DP<4>")
	)
	(segment
		(start 284.007814 -125.021848)
		(end 284.007814 -125.638306)
		(width 0.14224)
		(layer "In4.Cu")
		(net "M_E_DQS_DP<4>")
	)
	(segment
		(start 284.772862 -140.976604)
		(end 284.338014 -140.541756)
		(width 0.14224)
		(layer "In4.Cu")
		(net "M_E_DQS_DP<4>")
	)
	(segment
		(start 283.963364 -143.037052)
		(end 284.100524 -142.899892)
		(width 0.14224)
		(layer "In4.Cu")
		(net "M_E_DQS_DP<4>")
	)
	(segment
		(start 283.963364 -141.826234)
		(end 284.133798 -141.6558)
		(width 0.14224)
		(layer "In4.Cu")
		(net "M_E_DQS_DP<4>")
	)
	(segment
		(start 284.007814 -125.638306)
		(end 284.230826 -125.861318)
		(width 0.14224)
		(layer "In4.Cu")
		(net "M_E_DQS_DP<4>")
	)
	(segment
		(start 285.13532 -126.240286)
		(end 285.13532 -126.89459)
		(width 0.14224)
		(layer "In4.Cu")
		(net "M_E_DQS_DP<4>")
	)
	(segment
		(start 284.798262 -144.152112)
		(end 284.798262 -143.7132)
		(width 0.14224)
		(layer "In4.Cu")
		(net "M_E_DQS_DP<4>")
	)
	(segment
		(start 285.171134 -139.708636)
		(end 284.338014 -140.541756)
		(width 0.14224)
		(layer "In4.Cu")
		(net "M_E_DQS_DP<4>")
	)
	(arc
		(start 273.928586 -99.606354)
		(mid 273.925382 -99.725837)
		(end 273.917664 -99.845114)
		(width 0.0889)
		(layer "In4.Cu")
		(net "M_E_DQS_DP<4>")
	)
	(arc
		(start 273.482308 -98.500184)
		(mid 273.63391 -98.905197)
		(end 273.829018 -99.29114)
		(width 0.0889)
		(layer "In4.Cu")
		(net "M_E_DQS_DP<4>")
	)
	(arc
		(start 273.829018 -99.29114)
		(mid 273.86981 -99.365387)
		(end 273.907504 -99.441254)
		(width 0.0889)
		(layer "In4.Cu")
		(net "M_E_DQS_DP<4>")
	)
	(arc
		(start 273.917664 -99.845114)
		(mid 273.929774 -100.021895)
		(end 273.994118 -100.186998)
		(width 0.0889)
		(layer "In4.Cu")
		(net "M_E_DQS_DP<4>")
	)
	(arc
		(start 273.907504 -99.441254)
		(mid 273.931091 -99.522138)
		(end 273.928586 -99.606354)
		(width 0.0889)
		(layer "In4.Cu")
		(net "M_E_DQS_DP<4>")
	)
	(segment
		(start 229.54996 -147.27174)
		(end 229.54996 -146.265646)
		(width 0.1651)
		(layer "F.Cu")
		(net "M_E_DQS_DP<3>")
	)
	(segment
		(start 239.733836 -104.356154)
		(end 238.070644 -106.019346)
		(width 0.1016)
		(layer "F.Cu")
		(net "M_E_DQS_DP<3>")
	)
	(segment
		(start 228.77272 -117.17147)
		(end 228.77272 -120.474486)
		(width 0.1651)
		(layer "F.Cu")
		(net "M_E_DQS_DP<3>")
	)
	(segment
		(start 228.951028 -115.022122)
		(end 228.77272 -115.20043)
		(width 0.1651)
		(layer "F.Cu")
		(net "M_E_DQS_DP<3>")
	)
	(segment
		(start 229.54996 -146.265646)
		(end 229.587806 -146.2278)
		(width 0.1651)
		(layer "F.Cu")
		(net "M_E_DQS_DP<3>")
	)
	(segment
		(start 229.531926 -116.993162)
		(end 228.951028 -116.993162)
		(width 0.1651)
		(layer "F.Cu")
		(net "M_E_DQS_DP<3>")
	)
	(segment
		(start 228.8667 -113.607342)
		(end 229.00386 -113.744502)
		(width 0.1651)
		(layer "F.Cu")
		(net "M_E_DQS_DP<3>")
	)
	(segment
		(start 229.863396 -125.161294)
		(end 229.087934 -125.936756)
		(width 0.1651)
		(layer "F.Cu")
		(net "M_E_DQS_DP<3>")
	)
	(segment
		(start 244.253258 -101.90607)
		(end 244.233192 -101.939852)
		(width 0.0889)
		(layer "F.Cu")
		(net "M_E_DQS_DP<3>")
	)
	(segment
		(start 228.77272 -115.20043)
		(end 228.77272 -115.537234)
		(width 0.1651)
		(layer "F.Cu")
		(net "M_E_DQS_DP<3>")
	)
	(segment
		(start 228.8667 -112.605058)
		(end 228.8667 -113.607342)
		(width 0.1651)
		(layer "F.Cu")
		(net "M_E_DQS_DP<3>")
	)
	(segment
		(start 229.834186 -116.690902)
		(end 229.531926 -116.993162)
		(width 0.1651)
		(layer "F.Cu")
		(net "M_E_DQS_DP<3>")
	)
	(segment
		(start 229.834186 -116.011452)
		(end 229.834186 -116.690902)
		(width 0.1651)
		(layer "F.Cu")
		(net "M_E_DQS_DP<3>")
	)
	(segment
		(start 237.809024 -106.021886)
		(end 235.449872 -106.021886)
		(width 0.1651)
		(layer "F.Cu")
		(net "M_E_DQS_DP<3>")
	)
	(segment
		(start 243.910104 -100.662486)
		(end 244.24005 -101.424486)
		(width 0.0889)
		(layer "F.Cu")
		(net "M_E_DQS_DP<3>")
	)
	(segment
		(start 244.233192 -101.939852)
		(end 244.100604 -102.745286)
		(width 0.0889)
		(layer "F.Cu")
		(net "M_E_DQS_DP<3>")
	)
	(segment
		(start 235.449872 -106.021886)
		(end 228.8667 -112.605058)
		(width 0.1651)
		(layer "F.Cu")
		(net "M_E_DQS_DP<3>")
	)
	(segment
		(start 229.550468 -147.27174)
		(end 229.54996 -147.27174)
		(width 0.1651)
		(layer "F.Cu")
		(net "M_E_DQS_DP<3>")
	)
	(segment
		(start 237.809024 -106.019346)
		(end 237.809024 -106.021886)
		(width 0.1651)
		(layer "F.Cu")
		(net "M_E_DQS_DP<3>")
	)
	(segment
		(start 229.538276 -115.715542)
		(end 229.834186 -116.011452)
		(width 0.1651)
		(layer "F.Cu")
		(net "M_E_DQS_DP<3>")
	)
	(segment
		(start 244.08765 -102.75824)
		(end 242.489736 -104.356154)
		(width 0.1016)
		(layer "F.Cu")
		(net "M_E_DQS_DP<3>")
	)
	(segment
		(start 228.951028 -116.993162)
		(end 228.77272 -117.17147)
		(width 0.1651)
		(layer "F.Cu")
		(net "M_E_DQS_DP<3>")
	)
	(segment
		(start 229.587806 -146.2278)
		(end 229.587806 -144.8562)
		(width 0.1651)
		(layer "F.Cu")
		(net "M_E_DQS_DP<3>")
	)
	(segment
		(start 229.13467 -113.744502)
		(end 229.48392 -114.093752)
		(width 0.1651)
		(layer "F.Cu")
		(net "M_E_DQS_DP<3>")
	)
	(segment
		(start 242.489736 -104.356154)
		(end 239.733836 -104.356154)
		(width 0.1016)
		(layer "F.Cu")
		(net "M_E_DQS_DP<3>")
	)
	(segment
		(start 229.863396 -124.243338)
		(end 229.863396 -125.161294)
		(width 0.1651)
		(layer "F.Cu")
		(net "M_E_DQS_DP<3>")
	)
	(segment
		(start 228.77272 -120.474486)
		(end 229.3112 -121.012966)
		(width 0.1651)
		(layer "F.Cu")
		(net "M_E_DQS_DP<3>")
	)
	(segment
		(start 229.587806 -144.8562)
		(end 229.343966 -144.61236)
		(width 0.1651)
		(layer "F.Cu")
		(net "M_E_DQS_DP<3>")
	)
	(segment
		(start 229.343966 -144.61236)
		(end 229.087934 -144.61236)
		(width 0.1651)
		(layer "F.Cu")
		(net "M_E_DQS_DP<3>")
	)
	(segment
		(start 228.951028 -115.715542)
		(end 229.538276 -115.715542)
		(width 0.1651)
		(layer "F.Cu")
		(net "M_E_DQS_DP<3>")
	)
	(segment
		(start 244.24005 -101.424486)
		(end 244.25656 -101.452934)
		(width 0.0889)
		(layer "F.Cu")
		(net "M_E_DQS_DP<3>")
	)
	(segment
		(start 229.13467 -115.022122)
		(end 228.951028 -115.022122)
		(width 0.1651)
		(layer "F.Cu")
		(net "M_E_DQS_DP<3>")
	)
	(segment
		(start 229.3112 -121.012966)
		(end 229.3112 -123.691142)
		(width 0.1651)
		(layer "F.Cu")
		(net "M_E_DQS_DP<3>")
	)
	(segment
		(start 229.3112 -123.691142)
		(end 229.863396 -124.243338)
		(width 0.1651)
		(layer "F.Cu")
		(net "M_E_DQS_DP<3>")
	)
	(segment
		(start 238.070644 -106.019346)
		(end 237.809024 -106.019346)
		(width 0.1016)
		(layer "F.Cu")
		(net "M_E_DQS_DP<3>")
	)
	(segment
		(start 229.48392 -114.672872)
		(end 229.13467 -115.022122)
		(width 0.1651)
		(layer "F.Cu")
		(net "M_E_DQS_DP<3>")
	)
	(segment
		(start 229.00386 -113.744502)
		(end 229.13467 -113.744502)
		(width 0.1651)
		(layer "F.Cu")
		(net "M_E_DQS_DP<3>")
	)
	(segment
		(start 229.48392 -114.093752)
		(end 229.48392 -114.672872)
		(width 0.1651)
		(layer "F.Cu")
		(net "M_E_DQS_DP<3>")
	)
	(segment
		(start 244.100604 -102.745286)
		(end 244.08765 -102.75824)
		(width 0.0889)
		(layer "F.Cu")
		(net "M_E_DQS_DP<3>")
	)
	(segment
		(start 228.77272 -115.537234)
		(end 228.951028 -115.715542)
		(width 0.1651)
		(layer "F.Cu")
		(net "M_E_DQS_DP<3>")
	)
	(via
		(at 229.087934 -125.936756)
		(size 0.508)
		(drill 0.254)
		(layers "F.Cu" "B.Cu")
		(net "M_E_DQS_DP<3>")
	)
	(via
		(at 229.087934 -144.61236)
		(size 0.508)
		(drill 0.254)
		(layers "F.Cu" "B.Cu")
		(net "M_E_DQS_DP<3>")
	)
	(via
		(at 229.087934 -140.541756)
		(size 0.508)
		(drill 0.254)
		(layers "F.Cu" "B.Cu")
		(net "M_E_DQS_DP<3>")
	)
	(arc
		(start 244.25656 -101.452934)
		(mid 244.316472 -101.679953)
		(end 244.253258 -101.90607)
		(width 0.0889)
		(layer "F.Cu")
		(net "M_E_DQS_DP<3>")
	)
	(segment
		(start 229.587806 -140.2842)
		(end 229.33025 -140.541756)
		(width 0.1651)
		(layer "B.Cu")
		(net "M_E_DQS_DP<3>")
	)
	(segment
		(start 229.587806 -139.065)
		(end 229.587806 -140.2842)
		(width 0.1651)
		(layer "B.Cu")
		(net "M_E_DQS_DP<3>")
	)
	(segment
		(start 229.54996 -137.877296)
		(end 229.54996 -139.027154)
		(width 0.1651)
		(layer "B.Cu")
		(net "M_E_DQS_DP<3>")
	)
	(segment
		(start 229.54996 -139.027154)
		(end 229.587806 -139.065)
		(width 0.1651)
		(layer "B.Cu")
		(net "M_E_DQS_DP<3>")
	)
	(segment
		(start 229.33025 -140.541756)
		(end 229.087934 -140.541756)
		(width 0.1651)
		(layer "B.Cu")
		(net "M_E_DQS_DP<3>")
	)
	(segment
		(start 229.550468 -137.877296)
		(end 229.54996 -137.877296)
		(width 0.1651)
		(layer "B.Cu")
		(net "M_E_DQS_DP<3>")
	)
	(segment
		(start 229.5398 -127.3048)
		(end 229.870254 -127.635254)
		(width 0.14224)
		(layer "In4.Cu")
		(net "M_E_DQS_DP<3>")
	)
	(segment
		(start 229.088188 -140.541756)
		(end 229.087934 -140.541756)
		(width 0.14224)
		(layer "In4.Cu")
		(net "M_E_DQS_DP<3>")
	)
	(segment
		(start 229.090982 -142.719552)
		(end 228.910642 -142.899892)
		(width 0.14224)
		(layer "In4.Cu")
		(net "M_E_DQS_DP<3>")
	)
	(segment
		(start 229.870254 -139.75969)
		(end 229.088188 -140.541756)
		(width 0.14224)
		(layer "In4.Cu")
		(net "M_E_DQS_DP<3>")
	)
	(segment
		(start 228.713284 -143.263366)
		(end 228.909118 -143.4592)
		(width 0.14224)
		(layer "In4.Cu")
		(net "M_E_DQS_DP<3>")
	)
	(segment
		(start 228.713284 -143.037052)
		(end 228.713284 -143.263366)
		(width 0.14224)
		(layer "In4.Cu")
		(net "M_E_DQS_DP<3>")
	)
	(segment
		(start 228.910642 -142.899892)
		(end 228.850444 -142.899892)
		(width 0.14224)
		(layer "In4.Cu")
		(net "M_E_DQS_DP<3>")
	)
	(segment
		(start 229.522782 -141.4018)
		(end 229.268782 -141.6558)
		(width 0.14224)
		(layer "In4.Cu")
		(net "M_E_DQS_DP<3>")
	)
	(segment
		(start 228.913182 -142.2654)
		(end 229.090982 -142.4432)
		(width 0.14224)
		(layer "In4.Cu")
		(net "M_E_DQS_DP<3>")
	)
	(segment
		(start 229.548182 -144.152112)
		(end 229.087934 -144.61236)
		(width 0.14224)
		(layer "In4.Cu")
		(net "M_E_DQS_DP<3>")
	)
	(segment
		(start 229.548182 -143.7132)
		(end 229.548182 -144.152112)
		(width 0.14224)
		(layer "In4.Cu")
		(net "M_E_DQS_DP<3>")
	)
	(segment
		(start 229.489 -133.4008)
		(end 229.870254 -133.782054)
		(width 0.14224)
		(layer "In4.Cu")
		(net "M_E_DQS_DP<3>")
	)
	(segment
		(start 229.213156 -125.936756)
		(end 229.5398 -126.2634)
		(width 0.14224)
		(layer "In4.Cu")
		(net "M_E_DQS_DP<3>")
	)
	(segment
		(start 229.090982 -142.4432)
		(end 229.090982 -142.719552)
		(width 0.14224)
		(layer "In4.Cu")
		(net "M_E_DQS_DP<3>")
	)
	(segment
		(start 229.5398 -126.2634)
		(end 229.5398 -127.3048)
		(width 0.14224)
		(layer "In4.Cu")
		(net "M_E_DQS_DP<3>")
	)
	(segment
		(start 228.909118 -143.4592)
		(end 229.294182 -143.4592)
		(width 0.14224)
		(layer "In4.Cu")
		(net "M_E_DQS_DP<3>")
	)
	(segment
		(start 229.870254 -127.635254)
		(end 229.870254 -132.461)
		(width 0.14224)
		(layer "In4.Cu")
		(net "M_E_DQS_DP<3>")
	)
	(segment
		(start 229.087934 -140.541756)
		(end 229.522782 -140.976604)
		(width 0.14224)
		(layer "In4.Cu")
		(net "M_E_DQS_DP<3>")
	)
	(segment
		(start 229.294182 -143.4592)
		(end 229.548182 -143.7132)
		(width 0.14224)
		(layer "In4.Cu")
		(net "M_E_DQS_DP<3>")
	)
	(segment
		(start 228.713284 -142.150592)
		(end 228.828092 -142.2654)
		(width 0.14224)
		(layer "In4.Cu")
		(net "M_E_DQS_DP<3>")
	)
	(segment
		(start 228.850444 -142.899892)
		(end 228.713284 -143.037052)
		(width 0.14224)
		(layer "In4.Cu")
		(net "M_E_DQS_DP<3>")
	)
	(segment
		(start 229.087934 -125.936756)
		(end 229.213156 -125.936756)
		(width 0.14224)
		(layer "In4.Cu")
		(net "M_E_DQS_DP<3>")
	)
	(segment
		(start 228.883718 -141.6558)
		(end 228.713284 -141.826234)
		(width 0.14224)
		(layer "In4.Cu")
		(net "M_E_DQS_DP<3>")
	)
	(segment
		(start 229.870254 -133.782054)
		(end 229.870254 -139.75969)
		(width 0.14224)
		(layer "In4.Cu")
		(net "M_E_DQS_DP<3>")
	)
	(segment
		(start 229.489 -132.842254)
		(end 229.489 -133.4008)
		(width 0.14224)
		(layer "In4.Cu")
		(net "M_E_DQS_DP<3>")
	)
	(segment
		(start 228.828092 -142.2654)
		(end 228.913182 -142.2654)
		(width 0.14224)
		(layer "In4.Cu")
		(net "M_E_DQS_DP<3>")
	)
	(segment
		(start 228.713284 -141.826234)
		(end 228.713284 -142.150592)
		(width 0.14224)
		(layer "In4.Cu")
		(net "M_E_DQS_DP<3>")
	)
	(segment
		(start 229.268782 -141.6558)
		(end 228.883718 -141.6558)
		(width 0.14224)
		(layer "In4.Cu")
		(net "M_E_DQS_DP<3>")
	)
	(segment
		(start 229.522782 -140.976604)
		(end 229.522782 -141.4018)
		(width 0.14224)
		(layer "In4.Cu")
		(net "M_E_DQS_DP<3>")
	)
	(segment
		(start 229.870254 -132.461)
		(end 229.489 -132.842254)
		(width 0.14224)
		(layer "In4.Cu")
		(net "M_E_DQS_DP<3>")
	)
	(segment
		(start 219.993972 -144.61236)
		(end 219.73794 -144.61236)
		(width 0.1651)
		(layer "F.Cu")
		(net "M_E_DQS_DP<2>")
	)
	(segment
		(start 220.199966 -147.27174)
		(end 220.199966 -146.265646)
		(width 0.1651)
		(layer "F.Cu")
		(net "M_E_DQS_DP<2>")
	)
	(segment
		(start 238.759238 -99.67214)
		(end 238.187738 -99.67214)
		(width 0.1651)
		(layer "F.Cu")
		(net "M_E_DQS_DP<2>")
	)
	(segment
		(start 220.200474 -147.27174)
		(end 220.199966 -147.27174)
		(width 0.1651)
		(layer "F.Cu")
		(net "M_E_DQS_DP<2>")
	)
	(segment
		(start 220.237812 -144.8562)
		(end 219.993972 -144.61236)
		(width 0.1651)
		(layer "F.Cu")
		(net "M_E_DQS_DP<2>")
	)
	(segment
		(start 220.199966 -146.265646)
		(end 220.237812 -146.2278)
		(width 0.1651)
		(layer "F.Cu")
		(net "M_E_DQS_DP<2>")
	)
	(segment
		(start 220.237812 -146.2278)
		(end 220.237812 -144.8562)
		(width 0.1651)
		(layer "F.Cu")
		(net "M_E_DQS_DP<2>")
	)
	(via
		(at 219.73794 -144.61236)
		(size 0.508)
		(drill 0.254)
		(layers "F.Cu" "B.Cu")
		(net "M_E_DQS_DP<2>")
	)
	(via
		(at 238.187738 -99.67214)
		(size 0.508)
		(drill 0.254)
		(layers "F.Cu" "B.Cu")
		(net "M_E_DQS_DP<2>")
	)
	(via
		(at 219.73794 -140.541756)
		(size 0.508)
		(drill 0.254)
		(layers "F.Cu" "B.Cu")
		(net "M_E_DQS_DP<2>")
	)
	(segment
		(start 220.199966 -137.877296)
		(end 220.199966 -139.027154)
		(width 0.1651)
		(layer "B.Cu")
		(net "M_E_DQS_DP<2>")
	)
	(segment
		(start 219.980256 -140.541756)
		(end 219.73794 -140.541756)
		(width 0.1651)
		(layer "B.Cu")
		(net "M_E_DQS_DP<2>")
	)
	(segment
		(start 220.237812 -139.065)
		(end 220.237812 -140.2842)
		(width 0.1651)
		(layer "B.Cu")
		(net "M_E_DQS_DP<2>")
	)
	(segment
		(start 220.199966 -139.027154)
		(end 220.237812 -139.065)
		(width 0.1651)
		(layer "B.Cu")
		(net "M_E_DQS_DP<2>")
	)
	(segment
		(start 220.237812 -140.2842)
		(end 219.980256 -140.541756)
		(width 0.1651)
		(layer "B.Cu")
		(net "M_E_DQS_DP<2>")
	)
	(segment
		(start 220.200474 -137.877296)
		(end 220.199966 -137.877296)
		(width 0.1651)
		(layer "B.Cu")
		(net "M_E_DQS_DP<2>")
	)
	(segment
		(start 238.534448 -100.862892)
		(end 238.490506 -100.957634)
		(width 0.0889)
		(layer "In4.Cu")
		(net "M_E_DQS_DP<2>")
	)
	(segment
		(start 219.73794 -144.61236)
		(end 220.198188 -144.152112)
		(width 0.14224)
		(layer "In4.Cu")
		(net "M_E_DQS_DP<2>")
	)
	(segment
		(start 219.918788 -141.6558)
		(end 220.172788 -141.4018)
		(width 0.14224)
		(layer "In4.Cu")
		(net "M_E_DQS_DP<2>")
	)
	(segment
		(start 220.172788 -141.4018)
		(end 220.172788 -140.976604)
		(width 0.14224)
		(layer "In4.Cu")
		(net "M_E_DQS_DP<2>")
	)
	(segment
		(start 219.36329 -142.150592)
		(end 219.36329 -141.826234)
		(width 0.14224)
		(layer "In4.Cu")
		(net "M_E_DQS_DP<2>")
	)
	(segment
		(start 237.308898 -101.748336)
		(end 237.35411 -101.748336)
		(width 0.0889)
		(layer "In4.Cu")
		(net "M_E_DQS_DP<2>")
	)
	(segment
		(start 236.979968 -101.955854)
		(end 236.980476 -101.954584)
		(width 0.0889)
		(layer "In4.Cu")
		(net "M_E_DQS_DP<2>")
	)
	(segment
		(start 234.344718 -106.16057)
		(end 234.344718 -104.469438)
		(width 0.14224)
		(layer "In4.Cu")
		(net "M_E_DQS_DP<2>")
	)
	(segment
		(start 219.478098 -142.2654)
		(end 219.36329 -142.150592)
		(width 0.14224)
		(layer "In4.Cu")
		(net "M_E_DQS_DP<2>")
	)
	(segment
		(start 227.638356 -118.874286)
		(end 227.638356 -117.635274)
		(width 0.14224)
		(layer "In4.Cu")
		(net "M_E_DQS_DP<2>")
	)
	(segment
		(start 219.560648 -142.899892)
		(end 219.740988 -142.719552)
		(width 0.14224)
		(layer "In4.Cu")
		(net "M_E_DQS_DP<2>")
	)
	(segment
		(start 219.50045 -142.899892)
		(end 219.560648 -142.899892)
		(width 0.14224)
		(layer "In4.Cu")
		(net "M_E_DQS_DP<2>")
	)
	(segment
		(start 226.050602 -119.22379)
		(end 226.361752 -119.22379)
		(width 0.14224)
		(layer "In4.Cu")
		(net "M_E_DQS_DP<2>")
	)
	(segment
		(start 234.344718 -104.469438)
		(end 234.658154 -104.156002)
		(width 0.14224)
		(layer "In4.Cu")
		(net "M_E_DQS_DP<2>")
	)
	(segment
		(start 236.866938 -102.156768)
		(end 236.974126 -101.966014)
		(width 0.0889)
		(layer "In4.Cu")
		(net "M_E_DQS_DP<2>")
	)
	(segment
		(start 236.105192 -102.918514)
		(end 236.866938 -102.156768)
		(width 0.0889)
		(layer "In4.Cu")
		(net "M_E_DQS_DP<2>")
	)
	(segment
		(start 219.36329 -143.263366)
		(end 219.36329 -143.037052)
		(width 0.14224)
		(layer "In4.Cu")
		(net "M_E_DQS_DP<2>")
	)
	(segment
		(start 219.533724 -141.6558)
		(end 219.918788 -141.6558)
		(width 0.14224)
		(layer "In4.Cu")
		(net "M_E_DQS_DP<2>")
	)
	(segment
		(start 234.673648 -104.140508)
		(end 234.673394 -104.085136)
		(width 0.0889)
		(layer "In4.Cu")
		(net "M_E_DQS_DP<2>")
	)
	(segment
		(start 223.406462 -121.867168)
		(end 224.02419 -121.24944)
		(width 0.14224)
		(layer "In4.Cu")
		(net "M_E_DQS_DP<2>")
	)
	(segment
		(start 235.840016 -102.918514)
		(end 236.105192 -102.918514)
		(width 0.0889)
		(layer "In4.Cu")
		(net "M_E_DQS_DP<2>")
	)
	(segment
		(start 236.981238 -101.953314)
		(end 236.982254 -101.951536)
		(width 0.0889)
		(layer "In4.Cu")
		(net "M_E_DQS_DP<2>")
	)
	(segment
		(start 223.077532 -122.339862)
		(end 223.406462 -122.010932)
		(width 0.14224)
		(layer "In4.Cu")
		(net "M_E_DQS_DP<2>")
	)
	(segment
		(start 230.70312 -109.802168)
		(end 234.344718 -106.16057)
		(width 0.14224)
		(layer "In4.Cu")
		(net "M_E_DQS_DP<2>")
	)
	(segment
		(start 220.198188 -143.7132)
		(end 219.944188 -143.4592)
		(width 0.14224)
		(layer "In4.Cu")
		(net "M_E_DQS_DP<2>")
	)
	(segment
		(start 219.36329 -141.826234)
		(end 219.533724 -141.6558)
		(width 0.14224)
		(layer "In4.Cu")
		(net "M_E_DQS_DP<2>")
	)
	(segment
		(start 221.408244 -123.865386)
		(end 222.933768 -122.339862)
		(width 0.14224)
		(layer "In4.Cu")
		(net "M_E_DQS_DP<2>")
	)
	(segment
		(start 225.933762 -120.318022)
		(end 225.601022 -119.985282)
		(width 0.14224)
		(layer "In4.Cu")
		(net "M_E_DQS_DP<2>")
	)
	(segment
		(start 219.563188 -142.2654)
		(end 219.478098 -142.2654)
		(width 0.14224)
		(layer "In4.Cu")
		(net "M_E_DQS_DP<2>")
	)
	(segment
		(start 224.790762 -121.462038)
		(end 225.32594 -121.462038)
		(width 0.14224)
		(layer "In4.Cu")
		(net "M_E_DQS_DP<2>")
	)
	(segment
		(start 236.980476 -101.954584)
		(end 236.981238 -101.953314)
		(width 0.0889)
		(layer "In4.Cu")
		(net "M_E_DQS_DP<2>")
	)
	(segment
		(start 227.095304 -119.417338)
		(end 227.638356 -118.874286)
		(width 0.14224)
		(layer "In4.Cu")
		(net "M_E_DQS_DP<2>")
	)
	(segment
		(start 220.198188 -144.152112)
		(end 220.198188 -143.7132)
		(width 0.14224)
		(layer "In4.Cu")
		(net "M_E_DQS_DP<2>")
	)
	(segment
		(start 236.982762 -101.950774)
		(end 236.984794 -101.94671)
		(width 0.0889)
		(layer "In4.Cu")
		(net "M_E_DQS_DP<2>")
	)
	(segment
		(start 224.578164 -121.24944)
		(end 224.790762 -121.462038)
		(width 0.14224)
		(layer "In4.Cu")
		(net "M_E_DQS_DP<2>")
	)
	(segment
		(start 223.406462 -122.010932)
		(end 223.406462 -121.867168)
		(width 0.14224)
		(layer "In4.Cu")
		(net "M_E_DQS_DP<2>")
	)
	(segment
		(start 220.52026 -129.457958)
		(end 221.408244 -128.569974)
		(width 0.14224)
		(layer "In4.Cu")
		(net "M_E_DQS_DP<2>")
	)
	(segment
		(start 219.73794 -140.541756)
		(end 219.738194 -140.541756)
		(width 0.14224)
		(layer "In4.Cu")
		(net "M_E_DQS_DP<2>")
	)
	(segment
		(start 236.974126 -101.966014)
		(end 236.979968 -101.955854)
		(width 0.0889)
		(layer "In4.Cu")
		(net "M_E_DQS_DP<2>")
	)
	(segment
		(start 219.944188 -143.4592)
		(end 219.559124 -143.4592)
		(width 0.14224)
		(layer "In4.Cu")
		(net "M_E_DQS_DP<2>")
	)
	(segment
		(start 238.294672 -101.153468)
		(end 238.490506 -100.957634)
		(width 0.0889)
		(layer "In4.Cu")
		(net "M_E_DQS_DP<2>")
	)
	(segment
		(start 219.738194 -140.541756)
		(end 220.52026 -139.75969)
		(width 0.14224)
		(layer "In4.Cu")
		(net "M_E_DQS_DP<2>")
	)
	(segment
		(start 225.601022 -119.985282)
		(end 225.601022 -119.67337)
		(width 0.14224)
		(layer "In4.Cu")
		(net "M_E_DQS_DP<2>")
	)
	(segment
		(start 225.601022 -119.67337)
		(end 226.050602 -119.22379)
		(width 0.14224)
		(layer "In4.Cu")
		(net "M_E_DQS_DP<2>")
	)
	(segment
		(start 225.933762 -120.854216)
		(end 225.933762 -120.318022)
		(width 0.14224)
		(layer "In4.Cu")
		(net "M_E_DQS_DP<2>")
	)
	(segment
		(start 227.638356 -117.635274)
		(end 230.70312 -114.57051)
		(width 0.14224)
		(layer "In4.Cu")
		(net "M_E_DQS_DP<2>")
	)
	(segment
		(start 236.982254 -101.951536)
		(end 236.982762 -101.950774)
		(width 0.0889)
		(layer "In4.Cu")
		(net "M_E_DQS_DP<2>")
	)
	(segment
		(start 220.52026 -139.75969)
		(end 220.52026 -129.457958)
		(width 0.14224)
		(layer "In4.Cu")
		(net "M_E_DQS_DP<2>")
	)
	(segment
		(start 226.5553 -119.417338)
		(end 227.095304 -119.417338)
		(width 0.14224)
		(layer "In4.Cu")
		(net "M_E_DQS_DP<2>")
	)
	(segment
		(start 219.740988 -142.719552)
		(end 219.740988 -142.4432)
		(width 0.14224)
		(layer "In4.Cu")
		(net "M_E_DQS_DP<2>")
	)
	(segment
		(start 230.70312 -114.57051)
		(end 230.70312 -109.802168)
		(width 0.14224)
		(layer "In4.Cu")
		(net "M_E_DQS_DP<2>")
	)
	(segment
		(start 225.32594 -121.462038)
		(end 225.933762 -120.854216)
		(width 0.14224)
		(layer "In4.Cu")
		(net "M_E_DQS_DP<2>")
	)
	(segment
		(start 221.408244 -128.569974)
		(end 221.408244 -123.865386)
		(width 0.14224)
		(layer "In4.Cu")
		(net "M_E_DQS_DP<2>")
	)
	(segment
		(start 219.559124 -143.4592)
		(end 219.36329 -143.263366)
		(width 0.14224)
		(layer "In4.Cu")
		(net "M_E_DQS_DP<2>")
	)
	(segment
		(start 220.172788 -140.976604)
		(end 219.73794 -140.541756)
		(width 0.14224)
		(layer "In4.Cu")
		(net "M_E_DQS_DP<2>")
	)
	(segment
		(start 234.658154 -104.156002)
		(end 234.673648 -104.140508)
		(width 0.0889)
		(layer "In4.Cu")
		(net "M_E_DQS_DP<2>")
	)
	(segment
		(start 222.933768 -122.339862)
		(end 223.077532 -122.339862)
		(width 0.14224)
		(layer "In4.Cu")
		(net "M_E_DQS_DP<2>")
	)
	(segment
		(start 219.36329 -143.037052)
		(end 219.50045 -142.899892)
		(width 0.14224)
		(layer "In4.Cu")
		(net "M_E_DQS_DP<2>")
	)
	(segment
		(start 234.673394 -104.085136)
		(end 235.840016 -102.918514)
		(width 0.0889)
		(layer "In4.Cu")
		(net "M_E_DQS_DP<2>")
	)
	(segment
		(start 226.361752 -119.22379)
		(end 226.5553 -119.417338)
		(width 0.14224)
		(layer "In4.Cu")
		(net "M_E_DQS_DP<2>")
	)
	(segment
		(start 224.02419 -121.24944)
		(end 224.578164 -121.24944)
		(width 0.14224)
		(layer "In4.Cu")
		(net "M_E_DQS_DP<2>")
	)
	(segment
		(start 219.740988 -142.4432)
		(end 219.563188 -142.2654)
		(width 0.14224)
		(layer "In4.Cu")
		(net "M_E_DQS_DP<2>")
	)
	(arc
		(start 238.096806 -101.26345)
		(mid 238.203432 -101.2223)
		(end 238.294672 -101.153468)
		(width 0.0889)
		(layer "In4.Cu")
		(net "M_E_DQS_DP<2>")
	)
	(arc
		(start 238.534448 -100.463096)
		(mid 238.587947 -100.662994)
		(end 238.534448 -100.862892)
		(width 0.0889)
		(layer "In4.Cu")
		(net "M_E_DQS_DP<2>")
	)
	(arc
		(start 237.841028 -101.453188)
		(mid 237.949206 -101.33173)
		(end 238.096806 -101.26345)
		(width 0.0889)
		(layer "In4.Cu")
		(net "M_E_DQS_DP<2>")
	)
	(arc
		(start 237.35411 -101.748336)
		(mid 237.635472 -101.66329)
		(end 237.841028 -101.453188)
		(width 0.0889)
		(layer "In4.Cu")
		(net "M_E_DQS_DP<2>")
	)
	(arc
		(start 236.984794 -101.94671)
		(mid 237.121633 -101.806342)
		(end 237.308898 -101.748336)
		(width 0.0889)
		(layer "In4.Cu")
		(net "M_E_DQS_DP<2>")
	)
	(arc
		(start 238.187738 -99.67214)
		(mid 238.33934 -100.077153)
		(end 238.534448 -100.463096)
		(width 0.0889)
		(layer "In4.Cu")
		(net "M_E_DQS_DP<2>")
	)
	(segment
		(start 237.042198 -89.765886)
		(end 236.470698 -89.765886)
		(width 0.1651)
		(layer "F.Cu")
		(net "M_E_DQS_DP<1>")
	)
	(segment
		(start 210.849972 -146.265646)
		(end 210.887818 -146.2278)
		(width 0.1651)
		(layer "F.Cu")
		(net "M_E_DQS_DP<1>")
	)
	(segment
		(start 210.887818 -144.8562)
		(end 210.643978 -144.61236)
		(width 0.1651)
		(layer "F.Cu")
		(net "M_E_DQS_DP<1>")
	)
	(segment
		(start 210.849972 -147.27174)
		(end 210.849972 -146.265646)
		(width 0.1651)
		(layer "F.Cu")
		(net "M_E_DQS_DP<1>")
	)
	(segment
		(start 210.85048 -147.27174)
		(end 210.849972 -147.27174)
		(width 0.1651)
		(layer "F.Cu")
		(net "M_E_DQS_DP<1>")
	)
	(segment
		(start 210.887818 -146.2278)
		(end 210.887818 -144.8562)
		(width 0.1651)
		(layer "F.Cu")
		(net "M_E_DQS_DP<1>")
	)
	(segment
		(start 210.643978 -144.61236)
		(end 210.387946 -144.61236)
		(width 0.1651)
		(layer "F.Cu")
		(net "M_E_DQS_DP<1>")
	)
	(via
		(at 210.387946 -144.61236)
		(size 0.508)
		(drill 0.254)
		(layers "F.Cu" "B.Cu")
		(net "M_E_DQS_DP<1>")
	)
	(via
		(at 236.470698 -89.765886)
		(size 0.508)
		(drill 0.254)
		(layers "F.Cu" "B.Cu")
		(net "M_E_DQS_DP<1>")
	)
	(via
		(at 210.387946 -140.541756)
		(size 0.508)
		(drill 0.254)
		(layers "F.Cu" "B.Cu")
		(net "M_E_DQS_DP<1>")
	)
	(segment
		(start 210.887818 -139.065)
		(end 210.887818 -140.2842)
		(width 0.1651)
		(layer "B.Cu")
		(net "M_E_DQS_DP<1>")
	)
	(segment
		(start 210.85048 -137.877296)
		(end 210.849972 -137.877296)
		(width 0.1651)
		(layer "B.Cu")
		(net "M_E_DQS_DP<1>")
	)
	(segment
		(start 210.849972 -139.027154)
		(end 210.887818 -139.065)
		(width 0.1651)
		(layer "B.Cu")
		(net "M_E_DQS_DP<1>")
	)
	(segment
		(start 210.887818 -140.2842)
		(end 210.630262 -140.541756)
		(width 0.1651)
		(layer "B.Cu")
		(net "M_E_DQS_DP<1>")
	)
	(segment
		(start 210.849972 -137.877296)
		(end 210.849972 -139.027154)
		(width 0.1651)
		(layer "B.Cu")
		(net "M_E_DQS_DP<1>")
	)
	(segment
		(start 210.630262 -140.541756)
		(end 210.387946 -140.541756)
		(width 0.1651)
		(layer "B.Cu")
		(net "M_E_DQS_DP<1>")
	)
	(segment
		(start 236.088174 -89.621106)
		(end 236.177582 -89.596976)
		(width 0.0889)
		(layer "In4.Cu")
		(net "M_E_DQS_DP<1>")
	)
	(segment
		(start 210.387946 -140.541756)
		(end 210.394296 -140.541756)
		(width 0.14224)
		(layer "In4.Cu")
		(net "M_E_DQS_DP<1>")
	)
	(segment
		(start 235.597192 -89.86139)
		(end 235.629958 -89.86139)
		(width 0.0889)
		(layer "In4.Cu")
		(net "M_E_DQS_DP<1>")
	)
	(segment
		(start 218.785694 -112.816386)
		(end 218.38793 -112.418876)
		(width 0.14224)
		(layer "In4.Cu")
		(net "M_E_DQS_DP<1>")
	)
	(segment
		(start 233.643424 -93.101414)
		(end 234.353608 -92.39123)
		(width 0.0889)
		(layer "In4.Cu")
		(net "M_E_DQS_DP<1>")
	)
	(segment
		(start 218.007946 -112.038892)
		(end 218.007946 -111.726726)
		(width 0.14224)
		(layer "In4.Cu")
		(net "M_E_DQS_DP<1>")
	)
	(segment
		(start 217.642186 -113.960148)
		(end 218.177872 -113.960148)
		(width 0.14224)
		(layer "In4.Cu")
		(net "M_E_DQS_DP<1>")
	)
	(segment
		(start 234.353608 -92.39123)
		(end 234.353608 -90.649044)
		(width 0.0889)
		(layer "In4.Cu")
		(net "M_E_DQS_DP<1>")
	)
	(segment
		(start 216.272872 -115.865148)
		(end 216.880694 -115.257326)
		(width 0.14224)
		(layer "In4.Cu")
		(net "M_E_DQS_DP<1>")
	)
	(segment
		(start 228.41204 -97.425256)
		(end 231.23017 -94.607126)
		(width 0.14224)
		(layer "In4.Cu")
		(net "M_E_DQS_DP<1>")
	)
	(segment
		(start 210.013296 -142.150592)
		(end 210.013296 -141.826234)
		(width 0.14224)
		(layer "In4.Cu")
		(net "M_E_DQS_DP<1>")
	)
	(segment
		(start 218.177872 -113.960148)
		(end 218.785694 -113.352326)
		(width 0.14224)
		(layer "In4.Cu")
		(net "M_E_DQS_DP<1>")
	)
	(segment
		(start 228.41204 -97.42551)
		(end 228.41204 -97.425256)
		(width 0.14224)
		(layer "In4.Cu")
		(net "M_E_DQS_DP<1>")
	)
	(segment
		(start 210.150456 -142.899892)
		(end 210.210654 -142.899892)
		(width 0.14224)
		(layer "In4.Cu")
		(net "M_E_DQS_DP<1>")
	)
	(segment
		(start 216.880694 -115.257326)
		(end 216.880694 -114.721386)
		(width 0.14224)
		(layer "In4.Cu")
		(net "M_E_DQS_DP<1>")
	)
	(segment
		(start 210.387946 -144.61236)
		(end 210.848194 -144.152112)
		(width 0.14224)
		(layer "In4.Cu")
		(net "M_E_DQS_DP<1>")
	)
	(segment
		(start 215.25992 -116.918486)
		(end 214.24392 -115.902486)
		(width 0.14224)
		(layer "In4.Cu")
		(net "M_E_DQS_DP<1>")
	)
	(segment
		(start 210.390994 -142.4432)
		(end 210.213194 -142.2654)
		(width 0.14224)
		(layer "In4.Cu")
		(net "M_E_DQS_DP<1>")
	)
	(segment
		(start 210.568794 -141.6558)
		(end 210.822794 -141.4018)
		(width 0.14224)
		(layer "In4.Cu")
		(net "M_E_DQS_DP<1>")
	)
	(segment
		(start 210.822794 -141.4018)
		(end 210.822794 -140.976604)
		(width 0.14224)
		(layer "In4.Cu")
		(net "M_E_DQS_DP<1>")
	)
	(segment
		(start 232.68051 -93.101414)
		(end 233.643424 -93.101414)
		(width 0.0889)
		(layer "In4.Cu")
		(net "M_E_DQS_DP<1>")
	)
	(segment
		(start 210.013296 -141.826234)
		(end 210.18373 -141.6558)
		(width 0.14224)
		(layer "In4.Cu")
		(net "M_E_DQS_DP<1>")
	)
	(segment
		(start 218.785694 -113.352326)
		(end 218.785694 -112.816386)
		(width 0.14224)
		(layer "In4.Cu")
		(net "M_E_DQS_DP<1>")
	)
	(segment
		(start 210.210654 -142.899892)
		(end 210.390994 -142.719552)
		(width 0.14224)
		(layer "In4.Cu")
		(net "M_E_DQS_DP<1>")
	)
	(segment
		(start 234.742482 -90.356436)
		(end 234.775248 -90.356436)
		(width 0.0889)
		(layer "In4.Cu")
		(net "M_E_DQS_DP<1>")
	)
	(segment
		(start 222.44304 -107.291632)
		(end 222.44304 -104.658414)
		(width 0.14224)
		(layer "In4.Cu")
		(net "M_E_DQS_DP<1>")
	)
	(segment
		(start 231.245918 -94.536006)
		(end 232.68051 -93.101414)
		(width 0.0889)
		(layer "In4.Cu")
		(net "M_E_DQS_DP<1>")
	)
	(segment
		(start 236.177582 -89.596976)
		(end 236.470698 -89.765886)
		(width 0.0889)
		(layer "In4.Cu")
		(net "M_E_DQS_DP<1>")
	)
	(segment
		(start 214.24392 -115.902486)
		(end 214.24392 -115.491514)
		(width 0.14224)
		(layer "In4.Cu")
		(net "M_E_DQS_DP<1>")
	)
	(segment
		(start 214.24392 -115.491514)
		(end 214.576914 -115.15852)
		(width 0.14224)
		(layer "In4.Cu")
		(net "M_E_DQS_DP<1>")
	)
	(segment
		(start 210.390994 -142.719552)
		(end 210.390994 -142.4432)
		(width 0.14224)
		(layer "In4.Cu")
		(net "M_E_DQS_DP<1>")
	)
	(segment
		(start 216.102946 -113.632488)
		(end 216.55278 -113.182654)
		(width 0.14224)
		(layer "In4.Cu")
		(net "M_E_DQS_DP<1>")
	)
	(segment
		(start 211.170266 -139.765786)
		(end 211.170266 -128.1811)
		(width 0.14224)
		(layer "In4.Cu")
		(net "M_E_DQS_DP<1>")
	)
	(segment
		(start 215.03005 -115.15852)
		(end 215.736678 -115.865148)
		(width 0.14224)
		(layer "In4.Cu")
		(net "M_E_DQS_DP<1>")
	)
	(segment
		(start 213.02472 -126.326646)
		(end 213.02472 -119.748808)
		(width 0.14224)
		(layer "In4.Cu")
		(net "M_E_DQS_DP<1>")
	)
	(segment
		(start 218.38793 -112.418876)
		(end 218.007946 -112.038892)
		(width 0.14224)
		(layer "In4.Cu")
		(net "M_E_DQS_DP<1>")
	)
	(segment
		(start 227.57384 -99.527614)
		(end 227.57384 -98.26371)
		(width 0.14224)
		(layer "In4.Cu")
		(net "M_E_DQS_DP<1>")
	)
	(segment
		(start 231.245918 -94.591378)
		(end 231.245918 -94.536006)
		(width 0.0889)
		(layer "In4.Cu")
		(net "M_E_DQS_DP<1>")
	)
	(segment
		(start 215.25992 -117.513608)
		(end 215.25992 -116.918486)
		(width 0.14224)
		(layer "In4.Cu")
		(net "M_E_DQS_DP<1>")
	)
	(segment
		(start 210.848194 -144.152112)
		(end 210.848194 -143.7132)
		(width 0.14224)
		(layer "In4.Cu")
		(net "M_E_DQS_DP<1>")
	)
	(segment
		(start 216.864438 -113.182654)
		(end 217.642186 -113.960148)
		(width 0.14224)
		(layer "In4.Cu")
		(net "M_E_DQS_DP<1>")
	)
	(segment
		(start 210.848194 -143.7132)
		(end 210.594194 -143.4592)
		(width 0.14224)
		(layer "In4.Cu")
		(net "M_E_DQS_DP<1>")
	)
	(segment
		(start 216.55278 -113.182654)
		(end 216.864438 -113.182654)
		(width 0.14224)
		(layer "In4.Cu")
		(net "M_E_DQS_DP<1>")
	)
	(segment
		(start 227.57384 -98.26371)
		(end 228.41204 -97.42551)
		(width 0.14224)
		(layer "In4.Cu")
		(net "M_E_DQS_DP<1>")
	)
	(segment
		(start 222.44304 -104.658414)
		(end 227.57384 -99.527614)
		(width 0.14224)
		(layer "In4.Cu")
		(net "M_E_DQS_DP<1>")
	)
	(segment
		(start 231.23017 -94.607126)
		(end 231.245918 -94.591378)
		(width 0.0889)
		(layer "In4.Cu")
		(net "M_E_DQS_DP<1>")
	)
	(segment
		(start 211.170266 -128.1811)
		(end 213.02472 -126.326646)
		(width 0.14224)
		(layer "In4.Cu")
		(net "M_E_DQS_DP<1>")
	)
	(segment
		(start 216.102946 -113.943892)
		(end 216.102946 -113.632488)
		(width 0.14224)
		(layer "In4.Cu")
		(net "M_E_DQS_DP<1>")
	)
	(segment
		(start 214.576914 -115.15852)
		(end 215.03005 -115.15852)
		(width 0.14224)
		(layer "In4.Cu")
		(net "M_E_DQS_DP<1>")
	)
	(segment
		(start 210.013296 -143.037052)
		(end 210.150456 -142.899892)
		(width 0.14224)
		(layer "In4.Cu")
		(net "M_E_DQS_DP<1>")
	)
	(segment
		(start 213.02472 -119.748808)
		(end 215.25992 -117.513608)
		(width 0.14224)
		(layer "In4.Cu")
		(net "M_E_DQS_DP<1>")
	)
	(segment
		(start 210.213194 -142.2654)
		(end 210.128104 -142.2654)
		(width 0.14224)
		(layer "In4.Cu")
		(net "M_E_DQS_DP<1>")
	)
	(segment
		(start 210.013296 -143.263366)
		(end 210.013296 -143.037052)
		(width 0.14224)
		(layer "In4.Cu")
		(net "M_E_DQS_DP<1>")
	)
	(segment
		(start 210.822794 -140.976604)
		(end 210.387946 -140.541756)
		(width 0.14224)
		(layer "In4.Cu")
		(net "M_E_DQS_DP<1>")
	)
	(segment
		(start 210.594194 -143.4592)
		(end 210.20913 -143.4592)
		(width 0.14224)
		(layer "In4.Cu")
		(net "M_E_DQS_DP<1>")
	)
	(segment
		(start 218.007946 -111.726726)
		(end 222.44304 -107.291632)
		(width 0.14224)
		(layer "In4.Cu")
		(net "M_E_DQS_DP<1>")
	)
	(segment
		(start 215.736678 -115.865148)
		(end 216.272872 -115.865148)
		(width 0.14224)
		(layer "In4.Cu")
		(net "M_E_DQS_DP<1>")
	)
	(segment
		(start 210.18373 -141.6558)
		(end 210.568794 -141.6558)
		(width 0.14224)
		(layer "In4.Cu")
		(net "M_E_DQS_DP<1>")
	)
	(segment
		(start 234.353608 -90.649044)
		(end 234.406948 -90.556588)
		(width 0.0889)
		(layer "In4.Cu")
		(net "M_E_DQS_DP<1>")
	)
	(segment
		(start 210.394296 -140.541756)
		(end 211.170266 -139.765786)
		(width 0.14224)
		(layer "In4.Cu")
		(net "M_E_DQS_DP<1>")
	)
	(segment
		(start 216.880694 -114.721386)
		(end 216.102946 -113.943892)
		(width 0.14224)
		(layer "In4.Cu")
		(net "M_E_DQS_DP<1>")
	)
	(segment
		(start 210.20913 -143.4592)
		(end 210.013296 -143.263366)
		(width 0.14224)
		(layer "In4.Cu")
		(net "M_E_DQS_DP<1>")
	)
	(segment
		(start 210.128104 -142.2654)
		(end 210.013296 -142.150592)
		(width 0.14224)
		(layer "In4.Cu")
		(net "M_E_DQS_DP<1>")
	)
	(arc
		(start 234.775248 -90.356436)
		(mid 235.058465 -90.272155)
		(end 235.265468 -90.061288)
		(width 0.0889)
		(layer "In4.Cu")
		(net "M_E_DQS_DP<1>")
	)
	(arc
		(start 235.265468 -90.061288)
		(mid 235.405547 -89.918552)
		(end 235.597192 -89.86139)
		(width 0.0889)
		(layer "In4.Cu")
		(net "M_E_DQS_DP<1>")
	)
	(arc
		(start 235.629958 -89.86139)
		(mid 235.88678 -89.794089)
		(end 236.088174 -89.621106)
		(width 0.0889)
		(layer "In4.Cu")
		(net "M_E_DQS_DP<1>")
	)
	(arc
		(start 234.406948 -90.556588)
		(mid 234.548631 -90.412784)
		(end 234.742482 -90.356436)
		(width 0.0889)
		(layer "In4.Cu")
		(net "M_E_DQS_DP<1>")
	)
	(segment
		(start 237.546896 -123.19)
		(end 237.546896 -123.444)
		(width 0.1651)
		(layer "F.Cu")
		(net "M_E_DQS_DP<17>")
	)
	(segment
		(start 237.673896 -113.38306)
		(end 237.673896 -121.5517)
		(width 0.1651)
		(layer "F.Cu")
		(net "M_E_DQS_DP<17>")
	)
	(segment
		(start 237.673896 -122.301)
		(end 237.546896 -122.428)
		(width 0.1651)
		(layer "F.Cu")
		(net "M_E_DQS_DP<17>")
	)
	(segment
		(start 237.20044 -142.6718)
		(end 237.199932 -142.677642)
		(width 0.1651)
		(layer "F.Cu")
		(net "M_E_DQS_DP<17>")
	)
	(segment
		(start 237.559596 -121.92)
		(end 237.673896 -122.0343)
		(width 0.1651)
		(layer "F.Cu")
		(net "M_E_DQS_DP<17>")
	)
	(segment
		(start 248.428764 -100.492814)
		(end 248.428764 -103.163878)
		(width 0.1016)
		(layer "F.Cu")
		(net "M_E_DQS_DP<17>")
	)
	(segment
		(start 237.546896 -123.444)
		(end 237.673896 -123.571)
		(width 0.1651)
		(layer "F.Cu")
		(net "M_E_DQS_DP<17>")
	)
	(segment
		(start 247.740424 -103.852218)
		(end 247.740424 -104.10317)
		(width 0.1016)
		(layer "F.Cu")
		(net "M_E_DQS_DP<17>")
	)
	(segment
		(start 237.673896 -124.333)
		(end 237.673896 -125.06198)
		(width 0.1651)
		(layer "F.Cu")
		(net "M_E_DQS_DP<17>")
	)
	(segment
		(start 243.129054 -107.927902)
		(end 242.7732 -108.283756)
		(width 0.1016)
		(layer "F.Cu")
		(net "M_E_DQS_DP<17>")
	)
	(segment
		(start 237.418626 -125.31725)
		(end 237.154212 -125.31725)
		(width 0.1651)
		(layer "F.Cu")
		(net "M_E_DQS_DP<17>")
	)
	(segment
		(start 248.428764 -103.163878)
		(end 247.740424 -103.852218)
		(width 0.1016)
		(layer "F.Cu")
		(net "M_E_DQS_DP<17>")
	)
	(segment
		(start 237.673896 -125.06198)
		(end 237.418626 -125.31725)
		(width 0.1651)
		(layer "F.Cu")
		(net "M_E_DQS_DP<17>")
	)
	(segment
		(start 237.154212 -125.31725)
		(end 237.146338 -125.309376)
		(width 0.1651)
		(layer "F.Cu")
		(net "M_E_DQS_DP<17>")
	)
	(segment
		(start 236.763814 -143.730472)
		(end 236.679232 -143.914368)
		(width 0.1651)
		(layer "F.Cu")
		(net "M_E_DQS_DP<17>")
	)
	(segment
		(start 237.673896 -122.0343)
		(end 237.673896 -122.301)
		(width 0.1651)
		(layer "F.Cu")
		(net "M_E_DQS_DP<17>")
	)
	(segment
		(start 248.428764 -99.50577)
		(end 248.428764 -100.492814)
		(width 0.0889)
		(layer "F.Cu")
		(net "M_E_DQS_DP<17>")
	)
	(segment
		(start 236.679232 -143.914368)
		(end 236.679232 -144.732502)
		(width 0.1651)
		(layer "F.Cu")
		(net "M_E_DQS_DP<17>")
	)
	(segment
		(start 248.549414 -98.386138)
		(end 248.543064 -98.396806)
		(width 0.0889)
		(layer "F.Cu")
		(net "M_E_DQS_DP<17>")
	)
	(segment
		(start 248.55424 -98.377502)
		(end 248.549414 -98.386138)
		(width 0.0889)
		(layer "F.Cu")
		(net "M_E_DQS_DP<17>")
	)
	(segment
		(start 248.549414 -97.395538)
		(end 248.543064 -97.406206)
		(width 0.0889)
		(layer "F.Cu")
		(net "M_E_DQS_DP<17>")
	)
	(segment
		(start 248.53138 -99.371404)
		(end 248.457212 -99.476814)
		(width 0.0889)
		(layer "F.Cu")
		(net "M_E_DQS_DP<17>")
	)
	(segment
		(start 237.541816 -123.94692)
		(end 237.541816 -124.20092)
		(width 0.1651)
		(layer "F.Cu")
		(net "M_E_DQS_DP<17>")
	)
	(segment
		(start 242.7732 -108.283756)
		(end 237.673896 -113.38306)
		(width 0.1651)
		(layer "F.Cu")
		(net "M_E_DQS_DP<17>")
	)
	(segment
		(start 237.673896 -121.5517)
		(end 237.559596 -121.666)
		(width 0.1651)
		(layer "F.Cu")
		(net "M_E_DQS_DP<17>")
	)
	(segment
		(start 248.457212 -99.476814)
		(end 248.456196 -99.478338)
		(width 0.0889)
		(layer "F.Cu")
		(net "M_E_DQS_DP<17>")
	)
	(segment
		(start 237.541816 -124.20092)
		(end 237.673896 -124.333)
		(width 0.1651)
		(layer "F.Cu")
		(net "M_E_DQS_DP<17>")
	)
	(segment
		(start 237.559596 -121.666)
		(end 237.559596 -121.92)
		(width 0.1651)
		(layer "F.Cu")
		(net "M_E_DQS_DP<17>")
	)
	(segment
		(start 236.679232 -144.732502)
		(end 236.760766 -144.956784)
		(width 0.1651)
		(layer "F.Cu")
		(net "M_E_DQS_DP<17>")
	)
	(segment
		(start 247.740424 -104.10317)
		(end 243.915692 -107.927902)
		(width 0.1016)
		(layer "F.Cu")
		(net "M_E_DQS_DP<17>")
	)
	(segment
		(start 237.673896 -123.063)
		(end 237.546896 -123.19)
		(width 0.1651)
		(layer "F.Cu")
		(net "M_E_DQS_DP<17>")
	)
	(segment
		(start 243.915692 -107.927902)
		(end 243.129054 -107.927902)
		(width 0.1016)
		(layer "F.Cu")
		(net "M_E_DQS_DP<17>")
	)
	(segment
		(start 237.546896 -122.428)
		(end 237.546896 -122.682)
		(width 0.1651)
		(layer "F.Cu")
		(net "M_E_DQS_DP<17>")
	)
	(segment
		(start 237.199932 -143.294354)
		(end 236.763814 -143.730472)
		(width 0.1651)
		(layer "F.Cu")
		(net "M_E_DQS_DP<17>")
	)
	(segment
		(start 248.456196 -99.478338)
		(end 248.428764 -99.50577)
		(width 0.0889)
		(layer "F.Cu")
		(net "M_E_DQS_DP<17>")
	)
	(segment
		(start 237.199932 -142.677642)
		(end 237.199932 -143.294354)
		(width 0.1651)
		(layer "F.Cu")
		(net "M_E_DQS_DP<17>")
	)
	(segment
		(start 237.673896 -123.81484)
		(end 237.541816 -123.94692)
		(width 0.1651)
		(layer "F.Cu")
		(net "M_E_DQS_DP<17>")
	)
	(segment
		(start 237.673896 -122.809)
		(end 237.673896 -123.063)
		(width 0.1651)
		(layer "F.Cu")
		(net "M_E_DQS_DP<17>")
	)
	(segment
		(start 236.760766 -144.956784)
		(end 237.142528 -145.338546)
		(width 0.1651)
		(layer "F.Cu")
		(net "M_E_DQS_DP<17>")
	)
	(segment
		(start 237.546896 -122.682)
		(end 237.673896 -122.809)
		(width 0.1651)
		(layer "F.Cu")
		(net "M_E_DQS_DP<17>")
	)
	(segment
		(start 249.061224 -97.03181)
		(end 248.988834 -97.1042)
		(width 0.0889)
		(layer "F.Cu")
		(net "M_E_DQS_DP<17>")
	)
	(segment
		(start 249.061224 -96.700086)
		(end 249.061224 -97.03181)
		(width 0.0889)
		(layer "F.Cu")
		(net "M_E_DQS_DP<17>")
	)
	(segment
		(start 237.673896 -123.571)
		(end 237.673896 -123.81484)
		(width 0.1651)
		(layer "F.Cu")
		(net "M_E_DQS_DP<17>")
	)
	(via
		(at 237.142528 -139.827)
		(size 0.508)
		(drill 0.254)
		(layers "F.Cu" "B.Cu")
		(net "M_E_DQS_DP<17>")
	)
	(via
		(at 237.142528 -145.338546)
		(size 0.508)
		(drill 0.254)
		(layers "F.Cu" "B.Cu")
		(net "M_E_DQS_DP<17>")
	)
	(via
		(at 237.146338 -125.309376)
		(size 0.508)
		(drill 0.254)
		(layers "F.Cu" "B.Cu")
		(net "M_E_DQS_DP<17>")
	)
	(arc
		(start 248.967752 -97.107248)
		(mid 248.725991 -97.204111)
		(end 248.549414 -97.395538)
		(width 0.0889)
		(layer "F.Cu")
		(net "M_E_DQS_DP<17>")
	)
	(arc
		(start 248.988834 -97.1042)
		(mid 248.978279 -97.105628)
		(end 248.967752 -97.107248)
		(width 0.0889)
		(layer "F.Cu")
		(net "M_E_DQS_DP<17>")
	)
	(arc
		(start 248.543064 -97.406206)
		(mid 248.470266 -97.696969)
		(end 248.549414 -97.986088)
		(width 0.0889)
		(layer "F.Cu")
		(net "M_E_DQS_DP<17>")
	)
	(arc
		(start 248.549414 -98.976688)
		(mid 248.598023 -99.17666)
		(end 248.53138 -99.371404)
		(width 0.0889)
		(layer "F.Cu")
		(net "M_E_DQS_DP<17>")
	)
	(arc
		(start 248.543064 -98.396806)
		(mid 248.470266 -98.687569)
		(end 248.549414 -98.976688)
		(width 0.0889)
		(layer "F.Cu")
		(net "M_E_DQS_DP<17>")
	)
	(arc
		(start 248.549414 -97.986088)
		(mid 248.602884 -98.181151)
		(end 248.55424 -98.377502)
		(width 0.0889)
		(layer "F.Cu")
		(net "M_E_DQS_DP<17>")
	)
	(segment
		(start 236.743748 -141.40307)
		(end 236.666532 -141.270736)
		(width 0.1651)
		(layer "B.Cu")
		(net "M_E_DQS_DP<17>")
	)
	(segment
		(start 236.666532 -140.375132)
		(end 236.753908 -140.21562)
		(width 0.1651)
		(layer "B.Cu")
		(net "M_E_DQS_DP<17>")
	)
	(segment
		(start 237.20044 -142.477236)
		(end 237.199932 -142.476982)
		(width 0.1651)
		(layer "B.Cu")
		(net "M_E_DQS_DP<17>")
	)
	(segment
		(start 237.199932 -141.859254)
		(end 236.743748 -141.40307)
		(width 0.1651)
		(layer "B.Cu")
		(net "M_E_DQS_DP<17>")
	)
	(segment
		(start 236.753908 -140.21562)
		(end 237.142528 -139.827)
		(width 0.1651)
		(layer "B.Cu")
		(net "M_E_DQS_DP<17>")
	)
	(segment
		(start 236.666532 -141.270736)
		(end 236.666532 -140.375132)
		(width 0.1651)
		(layer "B.Cu")
		(net "M_E_DQS_DP<17>")
	)
	(segment
		(start 237.199932 -142.476982)
		(end 237.199932 -141.859254)
		(width 0.1651)
		(layer "B.Cu")
		(net "M_E_DQS_DP<17>")
	)
	(segment
		(start 236.637576 -140.2588)
		(end 237.069376 -139.827)
		(width 0.14224)
		(layer "In9.Cu")
		(net "M_E_DQS_DP<17>")
	)
	(segment
		(start 237.069376 -139.827)
		(end 237.142528 -139.827)
		(width 0.14224)
		(layer "In9.Cu")
		(net "M_E_DQS_DP<17>")
	)
	(segment
		(start 237.142528 -145.338546)
		(end 236.637576 -144.833594)
		(width 0.14224)
		(layer "In9.Cu")
		(net "M_E_DQS_DP<17>")
	)
	(segment
		(start 236.637576 -144.833594)
		(end 236.637576 -140.2588)
		(width 0.14224)
		(layer "In9.Cu")
		(net "M_E_DQS_DP<17>")
	)
	(segment
		(start 237.655608 -139.321286)
		(end 237.655608 -128.472692)
		(width 0.14224)
		(layer "In11.Cu")
		(net "M_E_DQS_DP<17>")
	)
	(segment
		(start 237.142528 -139.827)
		(end 237.149894 -139.827)
		(width 0.14224)
		(layer "In11.Cu")
		(net "M_E_DQS_DP<17>")
	)
	(segment
		(start 236.70768 -125.755908)
		(end 237.146338 -125.31725)
		(width 0.14224)
		(layer "In11.Cu")
		(net "M_E_DQS_DP<17>")
	)
	(segment
		(start 236.70768 -127.524764)
		(end 236.70768 -125.755908)
		(width 0.14224)
		(layer "In11.Cu")
		(net "M_E_DQS_DP<17>")
	)
	(segment
		(start 237.149894 -139.827)
		(end 237.655608 -139.321286)
		(width 0.14224)
		(layer "In11.Cu")
		(net "M_E_DQS_DP<17>")
	)
	(segment
		(start 237.146338 -125.31725)
		(end 237.146338 -125.309376)
		(width 0.14224)
		(layer "In11.Cu")
		(net "M_E_DQS_DP<17>")
	)
	(segment
		(start 237.655608 -128.472692)
		(end 236.70768 -127.524764)
		(width 0.14224)
		(layer "In11.Cu")
		(net "M_E_DQS_DP<17>")
	)
	(segment
		(start 285.7881 -93.052138)
		(end 286.3596 -93.052138)
		(width 0.1651)
		(layer "F.Cu")
		(net "M_E_DQS_DP<16>")
	)
	(segment
		(start 311.15 -143.294354)
		(end 310.713882 -143.730472)
		(width 0.1651)
		(layer "F.Cu")
		(net "M_E_DQS_DP<16>")
	)
	(segment
		(start 311.15 -142.677642)
		(end 311.15 -143.294354)
		(width 0.1651)
		(layer "F.Cu")
		(net "M_E_DQS_DP<16>")
	)
	(segment
		(start 310.713882 -143.730472)
		(end 310.6293 -143.914368)
		(width 0.1651)
		(layer "F.Cu")
		(net "M_E_DQS_DP<16>")
	)
	(segment
		(start 310.6293 -144.732502)
		(end 310.710834 -144.956784)
		(width 0.1651)
		(layer "F.Cu")
		(net "M_E_DQS_DP<16>")
	)
	(segment
		(start 310.6293 -143.914368)
		(end 310.6293 -144.732502)
		(width 0.1651)
		(layer "F.Cu")
		(net "M_E_DQS_DP<16>")
	)
	(segment
		(start 311.150508 -142.6718)
		(end 311.15 -142.677642)
		(width 0.1651)
		(layer "F.Cu")
		(net "M_E_DQS_DP<16>")
	)
	(segment
		(start 310.710834 -144.956784)
		(end 311.092596 -145.338546)
		(width 0.1651)
		(layer "F.Cu")
		(net "M_E_DQS_DP<16>")
	)
	(via
		(at 286.3596 -93.052138)
		(size 0.508)
		(drill 0.254)
		(layers "F.Cu" "B.Cu")
		(net "M_E_DQS_DP<16>")
	)
	(via
		(at 311.092596 -139.827)
		(size 0.508)
		(drill 0.254)
		(layers "F.Cu" "B.Cu")
		(net "M_E_DQS_DP<16>")
	)
	(via
		(at 311.092596 -145.338546)
		(size 0.508)
		(drill 0.254)
		(layers "F.Cu" "B.Cu")
		(net "M_E_DQS_DP<16>")
	)
	(segment
		(start 311.15 -142.476982)
		(end 311.15 -141.859254)
		(width 0.1651)
		(layer "B.Cu")
		(net "M_E_DQS_DP<16>")
	)
	(segment
		(start 310.693816 -141.40307)
		(end 310.6166 -141.270736)
		(width 0.1651)
		(layer "B.Cu")
		(net "M_E_DQS_DP<16>")
	)
	(segment
		(start 310.6166 -140.375132)
		(end 310.703976 -140.21562)
		(width 0.1651)
		(layer "B.Cu")
		(net "M_E_DQS_DP<16>")
	)
	(segment
		(start 310.6166 -141.270736)
		(end 310.6166 -140.375132)
		(width 0.1651)
		(layer "B.Cu")
		(net "M_E_DQS_DP<16>")
	)
	(segment
		(start 310.703976 -140.21562)
		(end 311.092596 -139.827)
		(width 0.1651)
		(layer "B.Cu")
		(net "M_E_DQS_DP<16>")
	)
	(segment
		(start 311.15 -141.859254)
		(end 310.693816 -141.40307)
		(width 0.1651)
		(layer "B.Cu")
		(net "M_E_DQS_DP<16>")
	)
	(segment
		(start 311.150508 -142.477236)
		(end 311.15 -142.476982)
		(width 0.1651)
		(layer "B.Cu")
		(net "M_E_DQS_DP<16>")
	)
	(segment
		(start 311.448196 -137.947146)
		(end 311.605676 -138.104626)
		(width 0.14224)
		(layer "In4.Cu")
		(net "M_E_DQS_DP<16>")
	)
	(segment
		(start 311.605676 -138.358626)
		(end 311.448196 -138.516106)
		(width 0.14224)
		(layer "In4.Cu")
		(net "M_E_DQS_DP<16>")
	)
	(segment
		(start 310.587644 -144.833594)
		(end 311.092596 -145.338546)
		(width 0.14224)
		(layer "In4.Cu")
		(net "M_E_DQS_DP<16>")
	)
	(segment
		(start 290.61918 -108.1532)
		(end 294.08882 -108.1532)
		(width 0.14224)
		(layer "In4.Cu")
		(net "M_E_DQS_DP<16>")
	)
	(segment
		(start 311.605676 -138.927586)
		(end 311.605676 -139.59332)
		(width 0.14224)
		(layer "In4.Cu")
		(net "M_E_DQS_DP<16>")
	)
	(segment
		(start 311.605676 -139.59332)
		(end 311.371996 -139.827)
		(width 0.14224)
		(layer "In4.Cu")
		(net "M_E_DQS_DP<16>")
	)
	(segment
		(start 285.8389 -99.275646)
		(end 285.84779 -99.290886)
		(width 0.0889)
		(layer "In4.Cu")
		(net "M_E_DQS_DP<16>")
	)
	(segment
		(start 311.448196 -138.770106)
		(end 311.605676 -138.927586)
		(width 0.14224)
		(layer "In4.Cu")
		(net "M_E_DQS_DP<16>")
	)
	(segment
		(start 311.605676 -125.670056)
		(end 311.605676 -136.753092)
		(width 0.14224)
		(layer "In4.Cu")
		(net "M_E_DQS_DP<16>")
	)
	(segment
		(start 311.605676 -137.24128)
		(end 311.605676 -137.535666)
		(width 0.14224)
		(layer "In4.Cu")
		(net "M_E_DQS_DP<16>")
	)
	(segment
		(start 289.76701 -107.30103)
		(end 290.61918 -108.1532)
		(width 0.14224)
		(layer "In4.Cu")
		(net "M_E_DQS_DP<16>")
	)
	(segment
		(start 289.75177 -107.230164)
		(end 289.751516 -107.285536)
		(width 0.0889)
		(layer "In4.Cu")
		(net "M_E_DQS_DP<16>")
	)
	(segment
		(start 286.70631 -103.158036)
		(end 286.69996 -103.168704)
		(width 0.0889)
		(layer "In4.Cu")
		(net "M_E_DQS_DP<16>")
	)
	(segment
		(start 311.488582 -136.870186)
		(end 311.488582 -137.124186)
		(width 0.14224)
		(layer "In4.Cu")
		(net "M_E_DQS_DP<16>")
	)
	(segment
		(start 286.3596 -93.390212)
		(end 286.294576 -93.455236)
		(width 0.0889)
		(layer "In4.Cu")
		(net "M_E_DQS_DP<16>")
	)
	(segment
		(start 289.401504 -106.879898)
		(end 289.75177 -107.230164)
		(width 0.0889)
		(layer "In4.Cu")
		(net "M_E_DQS_DP<16>")
	)
	(segment
		(start 311.448196 -138.516106)
		(end 311.448196 -138.770106)
		(width 0.14224)
		(layer "In4.Cu")
		(net "M_E_DQS_DP<16>")
	)
	(segment
		(start 287.19653 -105.034334)
		(end 287.229296 -105.034334)
		(width 0.0889)
		(layer "In4.Cu")
		(net "M_E_DQS_DP<16>")
	)
	(segment
		(start 285.8389 -100.266246)
		(end 285.84779 -100.281486)
		(width 0.0889)
		(layer "In4.Cu")
		(net "M_E_DQS_DP<16>")
	)
	(segment
		(start 289.401504 -106.432604)
		(end 289.401504 -106.879898)
		(width 0.0889)
		(layer "In4.Cu")
		(net "M_E_DQS_DP<16>")
	)
	(segment
		(start 311.488582 -137.124186)
		(end 311.605676 -137.24128)
		(width 0.14224)
		(layer "In4.Cu")
		(net "M_E_DQS_DP<16>")
	)
	(segment
		(start 294.08882 -108.1532)
		(end 311.605676 -125.670056)
		(width 0.14224)
		(layer "In4.Cu")
		(net "M_E_DQS_DP<16>")
	)
	(segment
		(start 286.3596 -93.052138)
		(end 286.3596 -93.390212)
		(width 0.0889)
		(layer "In4.Cu")
		(net "M_E_DQS_DP<16>")
	)
	(segment
		(start 286.34182 -102.558088)
		(end 286.374586 -102.558088)
		(width 0.0889)
		(layer "In4.Cu")
		(net "M_E_DQS_DP<16>")
	)
	(segment
		(start 286.711136 -104.14)
		(end 286.70631 -104.148636)
		(width 0.0889)
		(layer "In4.Cu")
		(net "M_E_DQS_DP<16>")
	)
	(segment
		(start 285.84144 -94.327472)
		(end 285.84779 -94.337886)
		(width 0.0889)
		(layer "In4.Cu")
		(net "M_E_DQS_DP<16>")
	)
	(segment
		(start 289.28187 -106.22534)
		(end 289.401504 -106.432604)
		(width 0.0889)
		(layer "In4.Cu")
		(net "M_E_DQS_DP<16>")
	)
	(segment
		(start 311.605676 -138.104626)
		(end 311.605676 -138.358626)
		(width 0.14224)
		(layer "In4.Cu")
		(net "M_E_DQS_DP<16>")
	)
	(segment
		(start 286.711136 -103.1494)
		(end 286.70631 -103.158036)
		(width 0.0889)
		(layer "In4.Cu")
		(net "M_E_DQS_DP<16>")
	)
	(segment
		(start 311.371996 -139.827)
		(end 311.092596 -139.827)
		(width 0.14224)
		(layer "In4.Cu")
		(net "M_E_DQS_DP<16>")
	)
	(segment
		(start 286.70631 -104.148636)
		(end 286.69996 -104.159304)
		(width 0.0889)
		(layer "In4.Cu")
		(net "M_E_DQS_DP<16>")
	)
	(segment
		(start 311.019444 -139.827)
		(end 310.587644 -140.2588)
		(width 0.14224)
		(layer "In4.Cu")
		(net "M_E_DQS_DP<16>")
	)
	(segment
		(start 311.605676 -137.535666)
		(end 311.448196 -137.693146)
		(width 0.14224)
		(layer "In4.Cu")
		(net "M_E_DQS_DP<16>")
	)
	(segment
		(start 310.587644 -140.2588)
		(end 310.587644 -144.833594)
		(width 0.14224)
		(layer "In4.Cu")
		(net "M_E_DQS_DP<16>")
	)
	(segment
		(start 311.092596 -139.827)
		(end 311.019444 -139.827)
		(width 0.14224)
		(layer "In4.Cu")
		(net "M_E_DQS_DP<16>")
	)
	(segment
		(start 288.922206 -106.025188)
		(end 288.939986 -106.025188)
		(width 0.0889)
		(layer "In4.Cu")
		(net "M_E_DQS_DP<16>")
	)
	(segment
		(start 285.84144 -101.261164)
		(end 285.84779 -101.272086)
		(width 0.0889)
		(layer "In4.Cu")
		(net "M_E_DQS_DP<16>")
	)
	(segment
		(start 311.605676 -136.753092)
		(end 311.488582 -136.870186)
		(width 0.14224)
		(layer "In4.Cu")
		(net "M_E_DQS_DP<16>")
	)
	(segment
		(start 311.448196 -137.693146)
		(end 311.448196 -137.947146)
		(width 0.14224)
		(layer "In4.Cu")
		(net "M_E_DQS_DP<16>")
	)
	(segment
		(start 288.05886 -105.529888)
		(end 288.091626 -105.529888)
		(width 0.0889)
		(layer "In4.Cu")
		(net "M_E_DQS_DP<16>")
	)
	(segment
		(start 285.8389 -101.256846)
		(end 285.84144 -101.261164)
		(width 0.0889)
		(layer "In4.Cu")
		(net "M_E_DQS_DP<16>")
	)
	(segment
		(start 289.751516 -107.285536)
		(end 289.76701 -107.30103)
		(width 0.0889)
		(layer "In4.Cu")
		(net "M_E_DQS_DP<16>")
	)
	(arc
		(start 285.84779 -96.718882)
		(mid 285.768659 -97.014284)
		(end 285.84779 -97.309686)
		(width 0.0889)
		(layer "In4.Cu")
		(net "M_E_DQS_DP<16>")
	)
	(arc
		(start 286.70631 -103.748586)
		(mid 286.75978 -103.943649)
		(end 286.711136 -104.14)
		(width 0.0889)
		(layer "In4.Cu")
		(net "M_E_DQS_DP<16>")
	)
	(arc
		(start 285.84779 -101.671882)
		(mid 285.843462 -102.255058)
		(end 286.34182 -102.558088)
		(width 0.0889)
		(layer "In4.Cu")
		(net "M_E_DQS_DP<16>")
	)
	(arc
		(start 285.84779 -94.337886)
		(mid 285.901289 -94.537784)
		(end 285.84779 -94.737682)
		(width 0.0889)
		(layer "In4.Cu")
		(net "M_E_DQS_DP<16>")
	)
	(arc
		(start 286.374586 -102.558088)
		(mid 286.707504 -102.760079)
		(end 286.711136 -103.1494)
		(width 0.0889)
		(layer "In4.Cu")
		(net "M_E_DQS_DP<16>")
	)
	(arc
		(start 285.84779 -101.272086)
		(mid 285.901323 -101.471984)
		(end 285.84779 -101.671882)
		(width 0.0889)
		(layer "In4.Cu")
		(net "M_E_DQS_DP<16>")
	)
	(arc
		(start 288.42335 -105.729786)
		(mid 288.634063 -105.942865)
		(end 288.922206 -106.025188)
		(width 0.0889)
		(layer "In4.Cu")
		(net "M_E_DQS_DP<16>")
	)
	(arc
		(start 285.84779 -99.690682)
		(mid 285.768601 -99.977297)
		(end 285.8389 -100.266246)
		(width 0.0889)
		(layer "In4.Cu")
		(net "M_E_DQS_DP<16>")
	)
	(arc
		(start 285.84779 -97.309686)
		(mid 285.901289 -97.509584)
		(end 285.84779 -97.709482)
		(width 0.0889)
		(layer "In4.Cu")
		(net "M_E_DQS_DP<16>")
	)
	(arc
		(start 285.84779 -100.681282)
		(mid 285.768601 -100.967897)
		(end 285.8389 -101.256846)
		(width 0.0889)
		(layer "In4.Cu")
		(net "M_E_DQS_DP<16>")
	)
	(arc
		(start 285.84779 -97.709482)
		(mid 285.768659 -98.004884)
		(end 285.84779 -98.300286)
		(width 0.0889)
		(layer "In4.Cu")
		(net "M_E_DQS_DP<16>")
	)
	(arc
		(start 287.56483 -105.234486)
		(mid 287.773438 -105.446418)
		(end 288.05886 -105.529888)
		(width 0.0889)
		(layer "In4.Cu")
		(net "M_E_DQS_DP<16>")
	)
	(arc
		(start 285.801816 -98.800158)
		(mid 285.770318 -99.041796)
		(end 285.8389 -99.275646)
		(width 0.0889)
		(layer "In4.Cu")
		(net "M_E_DQS_DP<16>")
	)
	(arc
		(start 285.84779 -94.737682)
		(mid 285.768659 -95.033084)
		(end 285.84779 -95.328486)
		(width 0.0889)
		(layer "In4.Cu")
		(net "M_E_DQS_DP<16>")
	)
	(arc
		(start 285.84779 -95.328486)
		(mid 285.901289 -95.528384)
		(end 285.84779 -95.728282)
		(width 0.0889)
		(layer "In4.Cu")
		(net "M_E_DQS_DP<16>")
	)
	(arc
		(start 286.69996 -103.168704)
		(mid 286.627162 -103.459467)
		(end 286.70631 -103.748586)
		(width 0.0889)
		(layer "In4.Cu")
		(net "M_E_DQS_DP<16>")
	)
	(arc
		(start 286.294576 -93.455236)
		(mid 285.835048 -93.770284)
		(end 285.84144 -94.327472)
		(width 0.0889)
		(layer "In4.Cu")
		(net "M_E_DQS_DP<16>")
	)
	(arc
		(start 285.84779 -95.728282)
		(mid 285.768659 -96.023684)
		(end 285.84779 -96.319086)
		(width 0.0889)
		(layer "In4.Cu")
		(net "M_E_DQS_DP<16>")
	)
	(arc
		(start 285.84779 -98.300286)
		(mid 285.901289 -98.500184)
		(end 285.84779 -98.700082)
		(width 0.0889)
		(layer "In4.Cu")
		(net "M_E_DQS_DP<16>")
	)
	(arc
		(start 288.939986 -106.025188)
		(mid 289.137421 -106.080011)
		(end 289.28187 -106.22534)
		(width 0.0889)
		(layer "In4.Cu")
		(net "M_E_DQS_DP<16>")
	)
	(arc
		(start 285.84779 -100.281486)
		(mid 285.901323 -100.481384)
		(end 285.84779 -100.681282)
		(width 0.0889)
		(layer "In4.Cu")
		(net "M_E_DQS_DP<16>")
	)
	(arc
		(start 285.84779 -96.319086)
		(mid 285.901289 -96.518984)
		(end 285.84779 -96.718882)
		(width 0.0889)
		(layer "In4.Cu")
		(net "M_E_DQS_DP<16>")
	)
	(arc
		(start 288.091626 -105.529888)
		(mid 288.283268 -105.587054)
		(end 288.42335 -105.729786)
		(width 0.0889)
		(layer "In4.Cu")
		(net "M_E_DQS_DP<16>")
	)
	(arc
		(start 285.84779 -99.290886)
		(mid 285.901323 -99.490784)
		(end 285.84779 -99.690682)
		(width 0.0889)
		(layer "In4.Cu")
		(net "M_E_DQS_DP<16>")
	)
	(arc
		(start 286.69996 -104.159304)
		(mid 286.703991 -104.735486)
		(end 287.19653 -105.034334)
		(width 0.0889)
		(layer "In4.Cu")
		(net "M_E_DQS_DP<16>")
	)
	(arc
		(start 285.84779 -98.700082)
		(mid 285.822472 -98.749049)
		(end 285.801816 -98.800158)
		(width 0.0889)
		(layer "In4.Cu")
		(net "M_E_DQS_DP<16>")
	)
	(arc
		(start 287.229296 -105.034334)
		(mid 287.423146 -105.090684)
		(end 287.56483 -105.234486)
		(width 0.0889)
		(layer "In4.Cu")
		(net "M_E_DQS_DP<16>")
	)
	(segment
		(start 285.202884 -103.810562)
		(end 285.202884 -102.814882)
		(width 0.0889)
		(layer "F.Cu")
		(net "M_E_DQS_DP<15>")
	)
	(segment
		(start 298.930822 -111.055658)
		(end 298.930822 -110.87608)
		(width 0.1651)
		(layer "F.Cu")
		(net "M_E_DQS_DP<15>")
	)
	(segment
		(start 300.368208 -112.313466)
		(end 300.188376 -112.313466)
		(width 0.1651)
		(layer "F.Cu")
		(net "M_E_DQS_DP<15>")
	)
	(segment
		(start 298.681902 -110.696502)
		(end 298.2214 -110.236)
		(width 0.1016)
		(layer "F.Cu")
		(net "M_E_DQS_DP<15>")
	)
	(segment
		(start 299.46981 -111.594646)
		(end 299.46981 -111.415068)
		(width 0.1651)
		(layer "F.Cu")
		(net "M_E_DQS_DP<15>")
	)
	(segment
		(start 285.26994 -101.682804)
		(end 285.27629 -101.672136)
		(width 0.0889)
		(layer "F.Cu")
		(net "M_E_DQS_DP<15>")
	)
	(segment
		(start 302.133 -114.078258)
		(end 301.446184 -113.391442)
		(width 0.1651)
		(layer "F.Cu")
		(net "M_E_DQS_DP<15>")
	)
	(segment
		(start 300.547786 -112.672622)
		(end 300.547786 -112.493044)
		(width 0.1651)
		(layer "F.Cu")
		(net "M_E_DQS_DP<15>")
	)
	(segment
		(start 285.4325 -105.57637)
		(end 285.4325 -105.430828)
		(width 0.1016)
		(layer "F.Cu")
		(net "M_E_DQS_DP<15>")
	)
	(segment
		(start 299.46981 -111.415068)
		(end 299.290232 -111.23549)
		(width 0.1651)
		(layer "F.Cu")
		(net "M_E_DQS_DP<15>")
	)
	(segment
		(start 285.0896 -105.087928)
		(end 285.0896 -103.923846)
		(width 0.0889)
		(layer "F.Cu")
		(net "M_E_DQS_DP<15>")
	)
	(segment
		(start 285.202884 -102.814882)
		(end 285.272988 -102.66426)
		(width 0.0889)
		(layer "F.Cu")
		(net "M_E_DQS_DP<15>")
	)
	(segment
		(start 295.219374 -107.048554)
		(end 286.904684 -107.048554)
		(width 0.1016)
		(layer "F.Cu")
		(net "M_E_DQS_DP<15>")
	)
	(segment
		(start 301.800006 -142.677642)
		(end 301.800006 -143.294354)
		(width 0.1651)
		(layer "F.Cu")
		(net "M_E_DQS_DP<15>")
	)
	(segment
		(start 301.266352 -113.391442)
		(end 301.086774 -113.21161)
		(width 0.1651)
		(layer "F.Cu")
		(net "M_E_DQS_DP<15>")
	)
	(segment
		(start 299.290232 -111.23549)
		(end 299.1104 -111.23549)
		(width 0.1651)
		(layer "F.Cu")
		(net "M_E_DQS_DP<15>")
	)
	(segment
		(start 302.227996 -122.225308)
		(end 302.133 -122.130312)
		(width 0.1651)
		(layer "F.Cu")
		(net "M_E_DQS_DP<15>")
	)
	(segment
		(start 298.751244 -110.696502)
		(end 298.681902 -110.696502)
		(width 0.1016)
		(layer "F.Cu")
		(net "M_E_DQS_DP<15>")
	)
	(segment
		(start 301.279306 -144.732502)
		(end 301.36084 -144.956784)
		(width 0.1651)
		(layer "F.Cu")
		(net "M_E_DQS_DP<15>")
	)
	(segment
		(start 285.7881 -100.317808)
		(end 285.7881 -99.986338)
		(width 0.0889)
		(layer "F.Cu")
		(net "M_E_DQS_DP<15>")
	)
	(segment
		(start 302.227996 -124.793502)
		(end 302.227996 -122.225308)
		(width 0.1651)
		(layer "F.Cu")
		(net "M_E_DQS_DP<15>")
	)
	(segment
		(start 286.904684 -107.048554)
		(end 285.4325 -105.57637)
		(width 0.1016)
		(layer "F.Cu")
		(net "M_E_DQS_DP<15>")
	)
	(segment
		(start 301.800006 -143.294354)
		(end 301.363888 -143.730472)
		(width 0.1651)
		(layer "F.Cu")
		(net "M_E_DQS_DP<15>")
	)
	(segment
		(start 299.82922 -111.774478)
		(end 299.649388 -111.774478)
		(width 0.1651)
		(layer "F.Cu")
		(net "M_E_DQS_DP<15>")
	)
	(segment
		(start 301.086774 -113.21161)
		(end 301.086774 -113.032032)
		(width 0.1651)
		(layer "F.Cu")
		(net "M_E_DQS_DP<15>")
	)
	(segment
		(start 300.547786 -112.493044)
		(end 300.368208 -112.313466)
		(width 0.1651)
		(layer "F.Cu")
		(net "M_E_DQS_DP<15>")
	)
	(segment
		(start 298.9834 -111.10849)
		(end 298.930822 -111.055658)
		(width 0.1651)
		(layer "F.Cu")
		(net "M_E_DQS_DP<15>")
	)
	(segment
		(start 301.086774 -113.032032)
		(end 300.907196 -112.852454)
		(width 0.1651)
		(layer "F.Cu")
		(net "M_E_DQS_DP<15>")
	)
	(segment
		(start 300.907196 -112.852454)
		(end 300.727364 -112.852454)
		(width 0.1651)
		(layer "F.Cu")
		(net "M_E_DQS_DP<15>")
	)
	(segment
		(start 285.4325 -105.430828)
		(end 285.0896 -105.087928)
		(width 0.0889)
		(layer "F.Cu")
		(net "M_E_DQS_DP<15>")
	)
	(segment
		(start 298.930822 -110.87608)
		(end 298.751244 -110.696502)
		(width 0.1651)
		(layer "F.Cu")
		(net "M_E_DQS_DP<15>")
	)
	(segment
		(start 301.800514 -142.6718)
		(end 301.800006 -142.677642)
		(width 0.1651)
		(layer "F.Cu")
		(net "M_E_DQS_DP<15>")
	)
	(segment
		(start 300.008798 -112.133634)
		(end 300.008798 -111.954056)
		(width 0.1651)
		(layer "F.Cu")
		(net "M_E_DQS_DP<15>")
	)
	(segment
		(start 301.279306 -143.914368)
		(end 301.279306 -144.732502)
		(width 0.1651)
		(layer "F.Cu")
		(net "M_E_DQS_DP<15>")
	)
	(segment
		(start 301.446184 -113.391442)
		(end 301.266352 -113.391442)
		(width 0.1651)
		(layer "F.Cu")
		(net "M_E_DQS_DP<15>")
	)
	(segment
		(start 299.1104 -111.23549)
		(end 298.9834 -111.10849)
		(width 0.1651)
		(layer "F.Cu")
		(net "M_E_DQS_DP<15>")
	)
	(segment
		(start 298.2214 -110.05058)
		(end 295.219374 -107.048554)
		(width 0.1016)
		(layer "F.Cu")
		(net "M_E_DQS_DP<15>")
	)
	(segment
		(start 298.2214 -110.236)
		(end 298.2214 -110.05058)
		(width 0.1016)
		(layer "F.Cu")
		(net "M_E_DQS_DP<15>")
	)
	(segment
		(start 301.746412 -125.275086)
		(end 302.227996 -124.793502)
		(width 0.1651)
		(layer "F.Cu")
		(net "M_E_DQS_DP<15>")
	)
	(segment
		(start 302.133 -122.130312)
		(end 302.133 -114.078258)
		(width 0.1651)
		(layer "F.Cu")
		(net "M_E_DQS_DP<15>")
	)
	(segment
		(start 300.727364 -112.852454)
		(end 300.547786 -112.672622)
		(width 0.1651)
		(layer "F.Cu")
		(net "M_E_DQS_DP<15>")
	)
	(segment
		(start 301.36084 -144.956784)
		(end 301.742602 -145.338546)
		(width 0.1651)
		(layer "F.Cu")
		(net "M_E_DQS_DP<15>")
	)
	(segment
		(start 285.272988 -102.66426)
		(end 285.27629 -102.66299)
		(width 0.0889)
		(layer "F.Cu")
		(net "M_E_DQS_DP<15>")
	)
	(segment
		(start 299.649388 -111.774478)
		(end 299.46981 -111.594646)
		(width 0.1651)
		(layer "F.Cu")
		(net "M_E_DQS_DP<15>")
	)
	(segment
		(start 301.363888 -143.730472)
		(end 301.279306 -143.914368)
		(width 0.1651)
		(layer "F.Cu")
		(net "M_E_DQS_DP<15>")
	)
	(segment
		(start 300.008798 -111.954056)
		(end 299.82922 -111.774478)
		(width 0.1651)
		(layer "F.Cu")
		(net "M_E_DQS_DP<15>")
	)
	(segment
		(start 285.0896 -103.923846)
		(end 285.202884 -103.810562)
		(width 0.0889)
		(layer "F.Cu")
		(net "M_E_DQS_DP<15>")
	)
	(segment
		(start 300.188376 -112.313466)
		(end 300.008798 -112.133634)
		(width 0.1651)
		(layer "F.Cu")
		(net "M_E_DQS_DP<15>")
	)
	(segment
		(start 285.71571 -100.390198)
		(end 285.7881 -100.317808)
		(width 0.0889)
		(layer "F.Cu")
		(net "M_E_DQS_DP<15>")
	)
	(via
		(at 301.742602 -139.827)
		(size 0.508)
		(drill 0.254)
		(layers "F.Cu" "B.Cu")
		(net "M_E_DQS_DP<15>")
	)
	(via
		(at 301.746412 -125.275086)
		(size 0.508)
		(drill 0.254)
		(layers "F.Cu" "B.Cu")
		(net "M_E_DQS_DP<15>")
	)
	(via
		(at 301.742602 -145.338546)
		(size 0.508)
		(drill 0.254)
		(layers "F.Cu" "B.Cu")
		(net "M_E_DQS_DP<15>")
	)
	(arc
		(start 285.27629 -102.66299)
		(mid 285.329823 -102.463092)
		(end 285.27629 -102.263194)
		(width 0.0889)
		(layer "F.Cu")
		(net "M_E_DQS_DP<15>")
	)
	(arc
		(start 285.27629 -101.672136)
		(mid 285.329857 -101.472128)
		(end 285.27629 -101.272086)
		(width 0.0889)
		(layer "F.Cu")
		(net "M_E_DQS_DP<15>")
	)
	(arc
		(start 285.27629 -102.263194)
		(mid 285.196941 -101.973822)
		(end 285.26994 -101.682804)
		(width 0.0889)
		(layer "F.Cu")
		(net "M_E_DQS_DP<15>")
	)
	(arc
		(start 285.27629 -101.272086)
		(mid 285.254487 -100.722755)
		(end 285.694628 -100.393246)
		(width 0.0889)
		(layer "F.Cu")
		(net "M_E_DQS_DP<15>")
	)
	(arc
		(start 285.694628 -100.393246)
		(mid 285.705155 -100.391628)
		(end 285.71571 -100.390198)
		(width 0.0889)
		(layer "F.Cu")
		(net "M_E_DQS_DP<15>")
	)
	(segment
		(start 301.266606 -141.270736)
		(end 301.266606 -140.375132)
		(width 0.1651)
		(layer "B.Cu")
		(net "M_E_DQS_DP<15>")
	)
	(segment
		(start 301.353982 -140.21562)
		(end 301.742602 -139.827)
		(width 0.1651)
		(layer "B.Cu")
		(net "M_E_DQS_DP<15>")
	)
	(segment
		(start 301.343822 -141.40307)
		(end 301.266606 -141.270736)
		(width 0.1651)
		(layer "B.Cu")
		(net "M_E_DQS_DP<15>")
	)
	(segment
		(start 301.266606 -140.375132)
		(end 301.353982 -140.21562)
		(width 0.1651)
		(layer "B.Cu")
		(net "M_E_DQS_DP<15>")
	)
	(segment
		(start 301.800006 -142.476982)
		(end 301.800006 -141.859254)
		(width 0.1651)
		(layer "B.Cu")
		(net "M_E_DQS_DP<15>")
	)
	(segment
		(start 301.800006 -141.859254)
		(end 301.343822 -141.40307)
		(width 0.1651)
		(layer "B.Cu")
		(net "M_E_DQS_DP<15>")
	)
	(segment
		(start 301.800514 -142.477236)
		(end 301.800006 -142.476982)
		(width 0.1651)
		(layer "B.Cu")
		(net "M_E_DQS_DP<15>")
	)
	(segment
		(start 302.255682 -128.658366)
		(end 301.68596 -128.088644)
		(width 0.14224)
		(layer "In4.Cu")
		(net "M_E_DQS_DP<15>")
	)
	(segment
		(start 301.268892 -126.847092)
		(end 301.268892 -125.752606)
		(width 0.14224)
		(layer "In4.Cu")
		(net "M_E_DQS_DP<15>")
	)
	(segment
		(start 301.68596 -128.088644)
		(end 301.68596 -127.26416)
		(width 0.14224)
		(layer "In4.Cu")
		(net "M_E_DQS_DP<15>")
	)
	(segment
		(start 301.791878 -139.827)
		(end 302.255682 -139.363196)
		(width 0.14224)
		(layer "In4.Cu")
		(net "M_E_DQS_DP<15>")
	)
	(segment
		(start 302.255682 -139.363196)
		(end 302.255682 -128.658366)
		(width 0.14224)
		(layer "In4.Cu")
		(net "M_E_DQS_DP<15>")
	)
	(segment
		(start 301.68596 -127.26416)
		(end 301.268892 -126.847092)
		(width 0.14224)
		(layer "In4.Cu")
		(net "M_E_DQS_DP<15>")
	)
	(segment
		(start 301.742602 -139.827)
		(end 301.791878 -139.827)
		(width 0.14224)
		(layer "In4.Cu")
		(net "M_E_DQS_DP<15>")
	)
	(segment
		(start 301.268892 -125.752606)
		(end 301.746412 -125.275086)
		(width 0.14224)
		(layer "In4.Cu")
		(net "M_E_DQS_DP<15>")
	)
	(segment
		(start 301.23765 -144.833594)
		(end 301.23765 -140.2588)
		(width 0.14224)
		(layer "In9.Cu")
		(net "M_E_DQS_DP<15>")
	)
	(segment
		(start 301.66945 -139.827)
		(end 301.742602 -139.827)
		(width 0.14224)
		(layer "In9.Cu")
		(net "M_E_DQS_DP<15>")
	)
	(segment
		(start 301.23765 -140.2588)
		(end 301.66945 -139.827)
		(width 0.14224)
		(layer "In9.Cu")
		(net "M_E_DQS_DP<15>")
	)
	(segment
		(start 301.742602 -145.338546)
		(end 301.23765 -144.833594)
		(width 0.14224)
		(layer "In9.Cu")
		(net "M_E_DQS_DP<15>")
	)
	(segment
		(start 290.83 -119.666258)
		(end 290.83 -119.92229)
		(width 0.1651)
		(layer "F.Cu")
		(net "M_E_DQS_DP<14>")
	)
	(segment
		(start 280.052272 -103.091996)
		(end 280.054304 -103.099362)
		(width 0.0889)
		(layer "F.Cu")
		(net "M_E_DQS_DP<14>")
	)
	(segment
		(start 292.412674 -121.504964)
		(end 292.668706 -121.504964)
		(width 0.1651)
		(layer "F.Cu")
		(net "M_E_DQS_DP<14>")
	)
	(segment
		(start 279.87752 -105.917238)
		(end 279.87752 -109.133894)
		(width 0.1016)
		(layer "F.Cu")
		(net "M_E_DQS_DP<14>")
	)
	(segment
		(start 292.450012 -142.677642)
		(end 292.450012 -143.294354)
		(width 0.1651)
		(layer "F.Cu")
		(net "M_E_DQS_DP<14>")
	)
	(segment
		(start 284.1244 -113.510822)
		(end 285.35757 -114.743992)
		(width 0.1016)
		(layer "F.Cu")
		(net "M_E_DQS_DP<14>")
	)
	(segment
		(start 290.83 -119.92229)
		(end 291.02431 -120.1166)
		(width 0.1651)
		(layer "F.Cu")
		(net "M_E_DQS_DP<14>")
	)
	(segment
		(start 291.5158 -120.352058)
		(end 291.5158 -120.60809)
		(width 0.1651)
		(layer "F.Cu")
		(net "M_E_DQS_DP<14>")
	)
	(segment
		(start 291.02431 -120.1166)
		(end 291.280342 -120.1166)
		(width 0.1651)
		(layer "F.Cu")
		(net "M_E_DQS_DP<14>")
	)
	(segment
		(start 292.45052 -142.6718)
		(end 292.450012 -142.677642)
		(width 0.1651)
		(layer "F.Cu")
		(net "M_E_DQS_DP<14>")
	)
	(segment
		(start 292.013894 -143.730472)
		(end 291.929312 -143.914368)
		(width 0.1651)
		(layer "F.Cu")
		(net "M_E_DQS_DP<14>")
	)
	(segment
		(start 280.637234 -99.986338)
		(end 280.543508 -100.393246)
		(width 0.0889)
		(layer "F.Cu")
		(net "M_E_DQS_DP<14>")
	)
	(segment
		(start 285.35757 -114.743992)
		(end 285.431992 -114.743992)
		(width 0.1016)
		(layer "F.Cu")
		(net "M_E_DQS_DP<14>")
	)
	(segment
		(start 292.010846 -144.956784)
		(end 292.392608 -145.338546)
		(width 0.1651)
		(layer "F.Cu")
		(net "M_E_DQS_DP<14>")
	)
	(segment
		(start 284.1244 -113.380774)
		(end 284.1244 -113.510822)
		(width 0.1016)
		(layer "F.Cu")
		(net "M_E_DQS_DP<14>")
	)
	(segment
		(start 291.929312 -143.914368)
		(end 291.929312 -144.732502)
		(width 0.1651)
		(layer "F.Cu")
		(net "M_E_DQS_DP<14>")
	)
	(segment
		(start 290.536122 -119.37238)
		(end 290.83 -119.666258)
		(width 0.1651)
		(layer "F.Cu")
		(net "M_E_DQS_DP<14>")
	)
	(segment
		(start 292.86962 -121.705878)
		(end 292.86962 -125.177042)
		(width 0.1651)
		(layer "F.Cu")
		(net "M_E_DQS_DP<14>")
	)
	(segment
		(start 291.929312 -144.732502)
		(end 292.010846 -144.956784)
		(width 0.1651)
		(layer "F.Cu")
		(net "M_E_DQS_DP<14>")
	)
	(segment
		(start 292.706044 -125.340618)
		(end 292.396672 -125.340618)
		(width 0.1651)
		(layer "F.Cu")
		(net "M_E_DQS_DP<14>")
	)
	(segment
		(start 292.668706 -121.504964)
		(end 292.86962 -121.705878)
		(width 0.1651)
		(layer "F.Cu")
		(net "M_E_DQS_DP<14>")
	)
	(segment
		(start 280.125424 -101.272086)
		(end 280.13025 -101.280722)
		(width 0.0889)
		(layer "F.Cu")
		(net "M_E_DQS_DP<14>")
	)
	(segment
		(start 280.054304 -103.099362)
		(end 280.054304 -103.77805)
		(width 0.0889)
		(layer "F.Cu")
		(net "M_E_DQS_DP<14>")
	)
	(segment
		(start 291.5158 -120.60809)
		(end 291.68471 -120.777)
		(width 0.1651)
		(layer "F.Cu")
		(net "M_E_DQS_DP<14>")
	)
	(segment
		(start 279.97912 -105.815638)
		(end 279.87752 -105.917238)
		(width 0.0889)
		(layer "F.Cu")
		(net "M_E_DQS_DP<14>")
	)
	(segment
		(start 291.280342 -120.1166)
		(end 291.5158 -120.352058)
		(width 0.1651)
		(layer "F.Cu")
		(net "M_E_DQS_DP<14>")
	)
	(segment
		(start 291.68471 -120.777)
		(end 291.940742 -120.777)
		(width 0.1651)
		(layer "F.Cu")
		(net "M_E_DQS_DP<14>")
	)
	(segment
		(start 292.450012 -143.294354)
		(end 292.013894 -143.730472)
		(width 0.1651)
		(layer "F.Cu")
		(net "M_E_DQS_DP<14>")
	)
	(segment
		(start 279.97912 -103.853234)
		(end 279.97912 -105.815638)
		(width 0.0889)
		(layer "F.Cu")
		(net "M_E_DQS_DP<14>")
	)
	(segment
		(start 285.431992 -114.743992)
		(end 290.06038 -119.37238)
		(width 0.1651)
		(layer "F.Cu")
		(net "M_E_DQS_DP<14>")
	)
	(segment
		(start 280.125424 -102.662736)
		(end 280.093166 -102.718616)
		(width 0.0889)
		(layer "F.Cu")
		(net "M_E_DQS_DP<14>")
	)
	(segment
		(start 292.2524 -121.088658)
		(end 292.2524 -121.34469)
		(width 0.1651)
		(layer "F.Cu")
		(net "M_E_DQS_DP<14>")
	)
	(segment
		(start 292.2524 -121.34469)
		(end 292.412674 -121.504964)
		(width 0.1651)
		(layer "F.Cu")
		(net "M_E_DQS_DP<14>")
	)
	(segment
		(start 291.940742 -120.777)
		(end 292.2524 -121.088658)
		(width 0.1651)
		(layer "F.Cu")
		(net "M_E_DQS_DP<14>")
	)
	(segment
		(start 292.86962 -125.177042)
		(end 292.706044 -125.340618)
		(width 0.1651)
		(layer "F.Cu")
		(net "M_E_DQS_DP<14>")
	)
	(segment
		(start 280.119074 -102.252018)
		(end 280.125424 -102.262686)
		(width 0.0889)
		(layer "F.Cu")
		(net "M_E_DQS_DP<14>")
	)
	(segment
		(start 279.87752 -109.133894)
		(end 284.1244 -113.380774)
		(width 0.1016)
		(layer "F.Cu")
		(net "M_E_DQS_DP<14>")
	)
	(segment
		(start 290.06038 -119.37238)
		(end 290.536122 -119.37238)
		(width 0.1651)
		(layer "F.Cu")
		(net "M_E_DQS_DP<14>")
	)
	(segment
		(start 280.054304 -103.77805)
		(end 279.97912 -103.853234)
		(width 0.0889)
		(layer "F.Cu")
		(net "M_E_DQS_DP<14>")
	)
	(segment
		(start 280.125424 -102.262686)
		(end 280.13025 -102.271322)
		(width 0.0889)
		(layer "F.Cu")
		(net "M_E_DQS_DP<14>")
	)
	(via
		(at 292.392608 -139.827)
		(size 0.508)
		(drill 0.254)
		(layers "F.Cu" "B.Cu")
		(net "M_E_DQS_DP<14>")
	)
	(via
		(at 292.392608 -145.338546)
		(size 0.508)
		(drill 0.254)
		(layers "F.Cu" "B.Cu")
		(net "M_E_DQS_DP<14>")
	)
	(via
		(at 292.396672 -125.340618)
		(size 0.508)
		(drill 0.254)
		(layers "F.Cu" "B.Cu")
		(net "M_E_DQS_DP<14>")
	)
	(arc
		(start 280.125424 -101.672136)
		(mid 280.046202 -101.961254)
		(end 280.119074 -102.252018)
		(width 0.0889)
		(layer "F.Cu")
		(net "M_E_DQS_DP<14>")
	)
	(arc
		(start 280.13025 -101.280722)
		(mid 280.179005 -101.477074)
		(end 280.125424 -101.672136)
		(width 0.0889)
		(layer "F.Cu")
		(net "M_E_DQS_DP<14>")
	)
	(arc
		(start 280.093166 -102.718616)
		(mid 280.033427 -102.901006)
		(end 280.052272 -103.091996)
		(width 0.0889)
		(layer "F.Cu")
		(net "M_E_DQS_DP<14>")
	)
	(arc
		(start 280.13025 -102.271322)
		(mid 280.179005 -102.467674)
		(end 280.125424 -102.662736)
		(width 0.0889)
		(layer "F.Cu")
		(net "M_E_DQS_DP<14>")
	)
	(arc
		(start 280.543508 -100.393246)
		(mid 280.103617 -100.722839)
		(end 280.125424 -101.272086)
		(width 0.0889)
		(layer "F.Cu")
		(net "M_E_DQS_DP<14>")
	)
	(segment
		(start 292.450012 -142.476982)
		(end 292.450012 -141.859254)
		(width 0.1651)
		(layer "B.Cu")
		(net "M_E_DQS_DP<14>")
	)
	(segment
		(start 291.916612 -140.375132)
		(end 292.003988 -140.21562)
		(width 0.1651)
		(layer "B.Cu")
		(net "M_E_DQS_DP<14>")
	)
	(segment
		(start 292.003988 -140.21562)
		(end 292.392608 -139.827)
		(width 0.1651)
		(layer "B.Cu")
		(net "M_E_DQS_DP<14>")
	)
	(segment
		(start 291.993828 -141.40307)
		(end 291.916612 -141.270736)
		(width 0.1651)
		(layer "B.Cu")
		(net "M_E_DQS_DP<14>")
	)
	(segment
		(start 292.45052 -142.477236)
		(end 292.450012 -142.476982)
		(width 0.1651)
		(layer "B.Cu")
		(net "M_E_DQS_DP<14>")
	)
	(segment
		(start 291.916612 -141.270736)
		(end 291.916612 -140.375132)
		(width 0.1651)
		(layer "B.Cu")
		(net "M_E_DQS_DP<14>")
	)
	(segment
		(start 292.450012 -141.859254)
		(end 291.993828 -141.40307)
		(width 0.1651)
		(layer "B.Cu")
		(net "M_E_DQS_DP<14>")
	)
	(segment
		(start 292.392354 -145.338546)
		(end 291.887656 -144.833848)
		(width 0.14224)
		(layer "In9.Cu")
		(net "M_E_DQS_DP<14>")
	)
	(segment
		(start 291.887656 -144.833848)
		(end 291.887656 -140.2588)
		(width 0.14224)
		(layer "In9.Cu")
		(net "M_E_DQS_DP<14>")
	)
	(segment
		(start 292.319456 -139.827)
		(end 292.392608 -139.827)
		(width 0.14224)
		(layer "In9.Cu")
		(net "M_E_DQS_DP<14>")
	)
	(segment
		(start 291.887656 -140.2588)
		(end 292.319456 -139.827)
		(width 0.14224)
		(layer "In9.Cu")
		(net "M_E_DQS_DP<14>")
	)
	(segment
		(start 292.392608 -145.338546)
		(end 292.392354 -145.338546)
		(width 0.14224)
		(layer "In9.Cu")
		(net "M_E_DQS_DP<14>")
	)
	(segment
		(start 291.958776 -125.778514)
		(end 292.396672 -125.340618)
		(width 0.14224)
		(layer "In11.Cu")
		(net "M_E_DQS_DP<14>")
	)
	(segment
		(start 292.905688 -128.288288)
		(end 292.46576 -127.84836)
		(width 0.14224)
		(layer "In11.Cu")
		(net "M_E_DQS_DP<14>")
	)
	(segment
		(start 291.958776 -126.985776)
		(end 291.958776 -125.778514)
		(width 0.14224)
		(layer "In11.Cu")
		(net "M_E_DQS_DP<14>")
	)
	(segment
		(start 292.441884 -139.827)
		(end 292.905688 -139.363196)
		(width 0.14224)
		(layer "In11.Cu")
		(net "M_E_DQS_DP<14>")
	)
	(segment
		(start 292.46576 -127.84836)
		(end 292.46576 -127.49276)
		(width 0.14224)
		(layer "In11.Cu")
		(net "M_E_DQS_DP<14>")
	)
	(segment
		(start 292.905688 -139.363196)
		(end 292.905688 -128.288288)
		(width 0.14224)
		(layer "In11.Cu")
		(net "M_E_DQS_DP<14>")
	)
	(segment
		(start 292.46576 -127.49276)
		(end 291.958776 -126.985776)
		(width 0.14224)
		(layer "In11.Cu")
		(net "M_E_DQS_DP<14>")
	)
	(segment
		(start 292.392608 -139.827)
		(end 292.441884 -139.827)
		(width 0.14224)
		(layer "In11.Cu")
		(net "M_E_DQS_DP<14>")
	)
	(segment
		(start 282.579064 -144.732502)
		(end 282.660598 -144.956784)
		(width 0.1651)
		(layer "F.Cu")
		(net "M_E_DQS_DP<13>")
	)
	(segment
		(start 282.660598 -144.956784)
		(end 283.04236 -145.338546)
		(width 0.1651)
		(layer "F.Cu")
		(net "M_E_DQS_DP<13>")
	)
	(segment
		(start 272.910808 -96.518984)
		(end 273.482308 -96.518984)
		(width 0.1651)
		(layer "F.Cu")
		(net "M_E_DQS_DP<13>")
	)
	(segment
		(start 283.099764 -142.677642)
		(end 283.099764 -143.294608)
		(width 0.1651)
		(layer "F.Cu")
		(net "M_E_DQS_DP<13>")
	)
	(segment
		(start 282.579064 -143.914368)
		(end 282.579064 -144.732502)
		(width 0.1651)
		(layer "F.Cu")
		(net "M_E_DQS_DP<13>")
	)
	(segment
		(start 283.099764 -143.294608)
		(end 282.663646 -143.730726)
		(width 0.1651)
		(layer "F.Cu")
		(net "M_E_DQS_DP<13>")
	)
	(segment
		(start 283.100272 -142.6718)
		(end 283.099764 -142.677642)
		(width 0.1651)
		(layer "F.Cu")
		(net "M_E_DQS_DP<13>")
	)
	(segment
		(start 282.663646 -143.730726)
		(end 282.579064 -143.914368)
		(width 0.1651)
		(layer "F.Cu")
		(net "M_E_DQS_DP<13>")
	)
	(via
		(at 273.482308 -96.518984)
		(size 0.508)
		(drill 0.254)
		(layers "F.Cu" "B.Cu")
		(net "M_E_DQS_DP<13>")
	)
	(via
		(at 283.04236 -145.338546)
		(size 0.508)
		(drill 0.254)
		(layers "F.Cu" "B.Cu")
		(net "M_E_DQS_DP<13>")
	)
	(via
		(at 283.04236 -139.827)
		(size 0.508)
		(drill 0.254)
		(layers "F.Cu" "B.Cu")
		(net "M_E_DQS_DP<13>")
	)
	(segment
		(start 282.566364 -140.375132)
		(end 282.65374 -140.21562)
		(width 0.1651)
		(layer "B.Cu")
		(net "M_E_DQS_DP<13>")
	)
	(segment
		(start 282.65374 -140.21562)
		(end 283.04236 -139.827)
		(width 0.1651)
		(layer "B.Cu")
		(net "M_E_DQS_DP<13>")
	)
	(segment
		(start 282.64358 -141.40307)
		(end 282.566364 -141.270736)
		(width 0.1651)
		(layer "B.Cu")
		(net "M_E_DQS_DP<13>")
	)
	(segment
		(start 283.099764 -141.859254)
		(end 282.64358 -141.40307)
		(width 0.1651)
		(layer "B.Cu")
		(net "M_E_DQS_DP<13>")
	)
	(segment
		(start 283.100272 -142.477236)
		(end 283.099764 -142.476982)
		(width 0.1651)
		(layer "B.Cu")
		(net "M_E_DQS_DP<13>")
	)
	(segment
		(start 283.099764 -142.476982)
		(end 283.099764 -141.859254)
		(width 0.1651)
		(layer "B.Cu")
		(net "M_E_DQS_DP<13>")
	)
	(segment
		(start 282.566364 -141.270736)
		(end 282.566364 -140.375132)
		(width 0.1651)
		(layer "B.Cu")
		(net "M_E_DQS_DP<13>")
	)
	(segment
		(start 283.437584 -138.435334)
		(end 283.437584 -138.689334)
		(width 0.14224)
		(layer "In4.Cu")
		(net "M_E_DQS_DP<13>")
	)
	(segment
		(start 283.437584 -137.200894)
		(end 283.555694 -137.319004)
		(width 0.14224)
		(layer "In4.Cu")
		(net "M_E_DQS_DP<13>")
	)
	(segment
		(start 283.322014 -139.827)
		(end 283.04236 -139.827)
		(width 0.14224)
		(layer "In4.Cu")
		(net "M_E_DQS_DP<13>")
	)
	(segment
		(start 274.137374 -106.473498)
		(end 274.137374 -116.918486)
		(width 0.14224)
		(layer "In4.Cu")
		(net "M_E_DQS_DP<13>")
	)
	(segment
		(start 282.990798 -125.77191)
		(end 282.990798 -128.77927)
		(width 0.14224)
		(layer "In4.Cu")
		(net "M_E_DQS_DP<13>")
	)
	(segment
		(start 274.176744 -106.41203)
		(end 274.137374 -106.4514)
		(width 0.0889)
		(layer "In4.Cu")
		(net "M_E_DQS_DP<13>")
	)
	(segment
		(start 283.555694 -137.573004)
		(end 283.437584 -137.691114)
		(width 0.14224)
		(layer "In4.Cu")
		(net "M_E_DQS_DP<13>")
	)
	(segment
		(start 273.024092 -102.022656)
		(end 274.176744 -103.175308)
		(width 0.0889)
		(layer "In4.Cu")
		(net "M_E_DQS_DP<13>")
	)
	(segment
		(start 283.437584 -138.689334)
		(end 283.555694 -138.807444)
		(width 0.14224)
		(layer "In4.Cu")
		(net "M_E_DQS_DP<13>")
	)
	(segment
		(start 273.482308 -96.518984)
		(end 273.482308 -96.85782)
		(width 0.0889)
		(layer "In4.Cu")
		(net "M_E_DQS_DP<13>")
	)
	(segment
		(start 272.970498 -99.786948)
		(end 272.970498 -99.786694)
		(width 0.0889)
		(layer "In4.Cu")
		(net "M_E_DQS_DP<13>")
	)
	(segment
		(start 283.04236 -139.827)
		(end 282.969462 -139.827)
		(width 0.14224)
		(layer "In4.Cu")
		(net "M_E_DQS_DP<13>")
	)
	(segment
		(start 282.969462 -139.827)
		(end 282.537662 -140.2588)
		(width 0.14224)
		(layer "In4.Cu")
		(net "M_E_DQS_DP<13>")
	)
	(segment
		(start 283.555694 -138.807444)
		(end 283.555694 -139.59332)
		(width 0.14224)
		(layer "In4.Cu")
		(net "M_E_DQS_DP<13>")
	)
	(segment
		(start 282.537662 -140.2588)
		(end 282.537662 -144.833848)
		(width 0.14224)
		(layer "In4.Cu")
		(net "M_E_DQS_DP<13>")
	)
	(segment
		(start 283.437584 -137.945114)
		(end 283.555694 -138.063224)
		(width 0.14224)
		(layer "In4.Cu")
		(net "M_E_DQS_DP<13>")
	)
	(segment
		(start 283.555694 -129.344166)
		(end 283.555694 -136.828784)
		(width 0.14224)
		(layer "In4.Cu")
		(net "M_E_DQS_DP<13>")
	)
	(segment
		(start 283.555694 -137.319004)
		(end 283.555694 -137.573004)
		(width 0.14224)
		(layer "In4.Cu")
		(net "M_E_DQS_DP<13>")
	)
	(segment
		(start 283.555694 -139.59332)
		(end 283.322014 -139.827)
		(width 0.14224)
		(layer "In4.Cu")
		(net "M_E_DQS_DP<13>")
	)
	(segment
		(start 282.537662 -144.833848)
		(end 283.04236 -145.338546)
		(width 0.14224)
		(layer "In4.Cu")
		(net "M_E_DQS_DP<13>")
	)
	(segment
		(start 274.137374 -106.4514)
		(end 274.137374 -106.473498)
		(width 0.0889)
		(layer "In4.Cu")
		(net "M_E_DQS_DP<13>")
	)
	(segment
		(start 283.437584 -136.946894)
		(end 283.437584 -137.200894)
		(width 0.14224)
		(layer "In4.Cu")
		(net "M_E_DQS_DP<13>")
	)
	(segment
		(start 283.555694 -138.317224)
		(end 283.437584 -138.435334)
		(width 0.14224)
		(layer "In4.Cu")
		(net "M_E_DQS_DP<13>")
	)
	(segment
		(start 282.990798 -128.77927)
		(end 283.555694 -129.344166)
		(width 0.14224)
		(layer "In4.Cu")
		(net "M_E_DQS_DP<13>")
	)
	(segment
		(start 283.437584 -137.691114)
		(end 283.437584 -137.945114)
		(width 0.14224)
		(layer "In4.Cu")
		(net "M_E_DQS_DP<13>")
	)
	(segment
		(start 273.482308 -96.85782)
		(end 273.417284 -96.922844)
		(width 0.0889)
		(layer "In4.Cu")
		(net "M_E_DQS_DP<13>")
	)
	(segment
		(start 274.176744 -103.175308)
		(end 274.176744 -106.41203)
		(width 0.0889)
		(layer "In4.Cu")
		(net "M_E_DQS_DP<13>")
	)
	(segment
		(start 283.555694 -136.828784)
		(end 283.437584 -136.946894)
		(width 0.14224)
		(layer "In4.Cu")
		(net "M_E_DQS_DP<13>")
	)
	(segment
		(start 273.024092 -99.986084)
		(end 273.024092 -102.022656)
		(width 0.0889)
		(layer "In4.Cu")
		(net "M_E_DQS_DP<13>")
	)
	(segment
		(start 274.137374 -116.918486)
		(end 282.990798 -125.77191)
		(width 0.14224)
		(layer "In4.Cu")
		(net "M_E_DQS_DP<13>")
	)
	(segment
		(start 283.555694 -138.063224)
		(end 283.555694 -138.317224)
		(width 0.14224)
		(layer "In4.Cu")
		(net "M_E_DQS_DP<13>")
	)
	(arc
		(start 272.970498 -97.805748)
		(mid 273.023997 -98.005646)
		(end 272.970498 -98.205544)
		(width 0.0889)
		(layer "In4.Cu")
		(net "M_E_DQS_DP<13>")
	)
	(arc
		(start 272.970498 -98.796348)
		(mid 273.023997 -98.996246)
		(end 272.970498 -99.196144)
		(width 0.0889)
		(layer "In4.Cu")
		(net "M_E_DQS_DP<13>")
	)
	(arc
		(start 272.970498 -99.196144)
		(mid 272.891367 -99.491546)
		(end 272.970498 -99.786948)
		(width 0.0889)
		(layer "In4.Cu")
		(net "M_E_DQS_DP<13>")
	)
	(arc
		(start 272.970498 -99.786694)
		(mid 273.010386 -99.882872)
		(end 273.024092 -99.986084)
		(width 0.0889)
		(layer "In4.Cu")
		(net "M_E_DQS_DP<13>")
	)
	(arc
		(start 272.970498 -98.205544)
		(mid 272.891367 -98.500946)
		(end 272.970498 -98.796348)
		(width 0.0889)
		(layer "In4.Cu")
		(net "M_E_DQS_DP<13>")
	)
	(arc
		(start 273.417284 -96.922844)
		(mid 272.954924 -97.243414)
		(end 272.970498 -97.805748)
		(width 0.0889)
		(layer "In4.Cu")
		(net "M_E_DQS_DP<13>")
	)
	(segment
		(start 243.319554 -102.23246)
		(end 243.295424 -102.25659)
		(width 0.0889)
		(layer "F.Cu")
		(net "M_E_DQS_DP<12>")
	)
	(segment
		(start 227.649532 -123.902216)
		(end 227.829364 -124.082048)
		(width 0.1651)
		(layer "F.Cu")
		(net "M_E_DQS_DP<12>")
	)
	(segment
		(start 233.406442 -105.592626)
		(end 233.208576 -105.790492)
		(width 0.1651)
		(layer "F.Cu")
		(net "M_E_DQS_DP<12>")
	)
	(segment
		(start 227.6475 -122.400314)
		(end 227.48748 -122.560334)
		(width 0.1651)
		(layer "F.Cu")
		(net "M_E_DQS_DP<12>")
	)
	(segment
		(start 237.809024 -104.787446)
		(end 237.687866 -104.787446)
		(width 0.1651)
		(layer "F.Cu")
		(net "M_E_DQS_DP<12>")
	)
	(segment
		(start 237.687612 -104.7877)
		(end 234.390946 -104.7877)
		(width 0.1651)
		(layer "F.Cu")
		(net "M_E_DQS_DP<12>")
	)
	(segment
		(start 227.960936 -124.082048)
		(end 228.275896 -124.397008)
		(width 0.1651)
		(layer "F.Cu")
		(net "M_E_DQS_DP<12>")
	)
	(segment
		(start 234.160568 -105.018078)
		(end 233.98099 -105.018078)
		(width 0.1651)
		(layer "F.Cu")
		(net "M_E_DQS_DP<12>")
	)
	(segment
		(start 239.35436 -103.441754)
		(end 238.008668 -104.787446)
		(width 0.1016)
		(layer "F.Cu")
		(net "M_E_DQS_DP<12>")
	)
	(segment
		(start 237.687866 -104.787446)
		(end 237.687612 -104.7877)
		(width 0.1651)
		(layer "F.Cu")
		(net "M_E_DQS_DP<12>")
	)
	(segment
		(start 243.910104 -99.01301)
		(end 243.83746 -99.085654)
		(width 0.0889)
		(layer "F.Cu")
		(net "M_E_DQS_DP<12>")
	)
	(segment
		(start 227.329238 -143.914368)
		(end 227.329238 -144.732502)
		(width 0.1651)
		(layer "F.Cu")
		(net "M_E_DQS_DP<12>")
	)
	(segment
		(start 227.48748 -122.560334)
		(end 227.48748 -123.608592)
		(width 0.1651)
		(layer "F.Cu")
		(net "M_E_DQS_DP<12>")
	)
	(segment
		(start 233.58602 -105.592626)
		(end 233.406442 -105.592626)
		(width 0.1651)
		(layer "F.Cu")
		(net "M_E_DQS_DP<12>")
	)
	(segment
		(start 228.068886 -125.275086)
		(end 227.796344 -125.275086)
		(width 0.1651)
		(layer "F.Cu")
		(net "M_E_DQS_DP<12>")
	)
	(segment
		(start 227.329238 -144.732502)
		(end 227.410772 -144.956784)
		(width 0.1651)
		(layer "F.Cu")
		(net "M_E_DQS_DP<12>")
	)
	(segment
		(start 227.849938 -142.677642)
		(end 227.849938 -143.294354)
		(width 0.1651)
		(layer "F.Cu")
		(net "M_E_DQS_DP<12>")
	)
	(segment
		(start 243.319554 -101.64826)
		(end 243.319554 -102.23246)
		(width 0.0889)
		(layer "F.Cu")
		(net "M_E_DQS_DP<12>")
	)
	(segment
		(start 227.41382 -143.730472)
		(end 227.329238 -143.914368)
		(width 0.1651)
		(layer "F.Cu")
		(net "M_E_DQS_DP<12>")
	)
	(segment
		(start 243.391944 -99.95662)
		(end 243.398294 -99.967288)
		(width 0.0889)
		(layer "F.Cu")
		(net "M_E_DQS_DP<12>")
	)
	(segment
		(start 233.208576 -105.790492)
		(end 233.208576 -105.97007)
		(width 0.1651)
		(layer "F.Cu")
		(net "M_E_DQS_DP<12>")
	)
	(segment
		(start 238.008668 -104.787446)
		(end 237.809024 -104.787446)
		(width 0.1016)
		(layer "F.Cu")
		(net "M_E_DQS_DP<12>")
	)
	(segment
		(start 233.783378 -105.395268)
		(end 233.58602 -105.592626)
		(width 0.1651)
		(layer "F.Cu")
		(net "M_E_DQS_DP<12>")
	)
	(segment
		(start 228.275896 -125.068076)
		(end 228.068886 -125.275086)
		(width 0.1651)
		(layer "F.Cu")
		(net "M_E_DQS_DP<12>")
	)
	(segment
		(start 227.6475 -121.287032)
		(end 227.6475 -122.400314)
		(width 0.1651)
		(layer "F.Cu")
		(net "M_E_DQS_DP<12>")
	)
	(segment
		(start 233.98099 -105.018078)
		(end 233.783378 -105.21569)
		(width 0.1651)
		(layer "F.Cu")
		(net "M_E_DQS_DP<12>")
	)
	(segment
		(start 227.48748 -111.691166)
		(end 227.48748 -121.127012)
		(width 0.1651)
		(layer "F.Cu")
		(net "M_E_DQS_DP<12>")
	)
	(segment
		(start 227.829364 -124.082048)
		(end 227.960936 -124.082048)
		(width 0.1651)
		(layer "F.Cu")
		(net "M_E_DQS_DP<12>")
	)
	(segment
		(start 243.398294 -101.357938)
		(end 243.39169 -101.370384)
		(width 0.0889)
		(layer "F.Cu")
		(net "M_E_DQS_DP<12>")
	)
	(segment
		(start 243.39169 -101.370384)
		(end 243.390928 -101.370384)
		(width 0.0889)
		(layer "F.Cu")
		(net "M_E_DQS_DP<12>")
	)
	(segment
		(start 227.649532 -123.770644)
		(end 227.649532 -123.902216)
		(width 0.1651)
		(layer "F.Cu")
		(net "M_E_DQS_DP<12>")
	)
	(segment
		(start 228.275896 -124.397008)
		(end 228.275896 -125.068076)
		(width 0.1651)
		(layer "F.Cu")
		(net "M_E_DQS_DP<12>")
	)
	(segment
		(start 243.910104 -98.681286)
		(end 243.910104 -99.01301)
		(width 0.0889)
		(layer "F.Cu")
		(net "M_E_DQS_DP<12>")
	)
	(segment
		(start 233.783378 -105.21569)
		(end 233.783378 -105.395268)
		(width 0.1651)
		(layer "F.Cu")
		(net "M_E_DQS_DP<12>")
	)
	(segment
		(start 243.398294 -100.367084)
		(end 243.391944 -100.377752)
		(width 0.0889)
		(layer "F.Cu")
		(net "M_E_DQS_DP<12>")
	)
	(segment
		(start 234.390946 -104.7877)
		(end 234.160568 -105.018078)
		(width 0.1651)
		(layer "F.Cu")
		(net "M_E_DQS_DP<12>")
	)
	(segment
		(start 227.850446 -142.6718)
		(end 227.849938 -142.677642)
		(width 0.1651)
		(layer "F.Cu")
		(net "M_E_DQS_DP<12>")
	)
	(segment
		(start 227.48748 -123.608592)
		(end 227.649532 -123.770644)
		(width 0.1651)
		(layer "F.Cu")
		(net "M_E_DQS_DP<12>")
	)
	(segment
		(start 227.849938 -143.294354)
		(end 227.41382 -143.730472)
		(width 0.1651)
		(layer "F.Cu")
		(net "M_E_DQS_DP<12>")
	)
	(segment
		(start 233.208576 -105.97007)
		(end 227.48748 -111.691166)
		(width 0.1651)
		(layer "F.Cu")
		(net "M_E_DQS_DP<12>")
	)
	(segment
		(start 243.295424 -102.25659)
		(end 242.11026 -103.441754)
		(width 0.1016)
		(layer "F.Cu")
		(net "M_E_DQS_DP<12>")
	)
	(segment
		(start 242.11026 -103.441754)
		(end 239.35436 -103.441754)
		(width 0.1016)
		(layer "F.Cu")
		(net "M_E_DQS_DP<12>")
	)
	(segment
		(start 227.410772 -144.956784)
		(end 227.792534 -145.338546)
		(width 0.1651)
		(layer "F.Cu")
		(net "M_E_DQS_DP<12>")
	)
	(segment
		(start 227.48748 -121.127012)
		(end 227.6475 -121.287032)
		(width 0.1651)
		(layer "F.Cu")
		(net "M_E_DQS_DP<12>")
	)
	(via
		(at 227.792534 -139.827)
		(size 0.508)
		(drill 0.254)
		(layers "F.Cu" "B.Cu")
		(net "M_E_DQS_DP<12>")
	)
	(via
		(at 227.792534 -145.338546)
		(size 0.508)
		(drill 0.254)
		(layers "F.Cu" "B.Cu")
		(net "M_E_DQS_DP<12>")
	)
	(via
		(at 227.796344 -125.275086)
		(size 0.508)
		(drill 0.254)
		(layers "F.Cu" "B.Cu")
		(net "M_E_DQS_DP<12>")
	)
	(arc
		(start 243.398294 -99.376738)
		(mid 243.319072 -99.665856)
		(end 243.391944 -99.95662)
		(width 0.0889)
		(layer "F.Cu")
		(net "M_E_DQS_DP<12>")
	)
	(arc
		(start 243.391944 -100.377752)
		(mid 243.319024 -100.668769)
		(end 243.398294 -100.958142)
		(width 0.0889)
		(layer "F.Cu")
		(net "M_E_DQS_DP<12>")
	)
	(arc
		(start 243.390928 -101.370384)
		(mid 243.338139 -101.504926)
		(end 243.319554 -101.64826)
		(width 0.0889)
		(layer "F.Cu")
		(net "M_E_DQS_DP<12>")
	)
	(arc
		(start 243.398294 -99.967288)
		(mid 243.451827 -100.167186)
		(end 243.398294 -100.367084)
		(width 0.0889)
		(layer "F.Cu")
		(net "M_E_DQS_DP<12>")
	)
	(arc
		(start 243.398294 -100.958142)
		(mid 243.451827 -101.15804)
		(end 243.398294 -101.357938)
		(width 0.0889)
		(layer "F.Cu")
		(net "M_E_DQS_DP<12>")
	)
	(arc
		(start 243.83746 -99.085654)
		(mid 243.827033 -99.087086)
		(end 243.816632 -99.088702)
		(width 0.0889)
		(layer "F.Cu")
		(net "M_E_DQS_DP<12>")
	)
	(arc
		(start 243.816632 -99.088702)
		(mid 243.574961 -99.185502)
		(end 243.398294 -99.376738)
		(width 0.0889)
		(layer "F.Cu")
		(net "M_E_DQS_DP<12>")
	)
	(segment
		(start 227.850446 -142.477236)
		(end 227.849938 -142.476982)
		(width 0.1651)
		(layer "B.Cu")
		(net "M_E_DQS_DP<12>")
	)
	(segment
		(start 227.316538 -141.270736)
		(end 227.316538 -140.375132)
		(width 0.1651)
		(layer "B.Cu")
		(net "M_E_DQS_DP<12>")
	)
	(segment
		(start 227.849938 -142.476982)
		(end 227.849938 -141.859254)
		(width 0.1651)
		(layer "B.Cu")
		(net "M_E_DQS_DP<12>")
	)
	(segment
		(start 227.316538 -140.375132)
		(end 227.403914 -140.21562)
		(width 0.1651)
		(layer "B.Cu")
		(net "M_E_DQS_DP<12>")
	)
	(segment
		(start 227.849938 -141.859254)
		(end 227.393754 -141.40307)
		(width 0.1651)
		(layer "B.Cu")
		(net "M_E_DQS_DP<12>")
	)
	(segment
		(start 227.393754 -141.40307)
		(end 227.316538 -141.270736)
		(width 0.1651)
		(layer "B.Cu")
		(net "M_E_DQS_DP<12>")
	)
	(segment
		(start 227.403914 -140.21562)
		(end 227.792534 -139.827)
		(width 0.1651)
		(layer "B.Cu")
		(net "M_E_DQS_DP<12>")
	)
	(segment
		(start 227.353876 -126.705614)
		(end 228.305614 -129.003552)
		(width 0.14224)
		(layer "In4.Cu")
		(net "M_E_DQS_DP<12>")
	)
	(segment
		(start 227.796344 -125.275086)
		(end 227.353876 -125.717554)
		(width 0.14224)
		(layer "In4.Cu")
		(net "M_E_DQS_DP<12>")
	)
	(segment
		(start 227.287582 -144.833594)
		(end 227.792534 -145.338546)
		(width 0.14224)
		(layer "In4.Cu")
		(net "M_E_DQS_DP<12>")
	)
	(segment
		(start 227.287582 -140.2588)
		(end 227.287582 -144.833594)
		(width 0.14224)
		(layer "In4.Cu")
		(net "M_E_DQS_DP<12>")
	)
	(segment
		(start 227.719382 -139.827)
		(end 227.287582 -140.2588)
		(width 0.14224)
		(layer "In4.Cu")
		(net "M_E_DQS_DP<12>")
	)
	(segment
		(start 228.0412 -139.827)
		(end 227.792534 -139.827)
		(width 0.14224)
		(layer "In4.Cu")
		(net "M_E_DQS_DP<12>")
	)
	(segment
		(start 228.305614 -139.562586)
		(end 228.0412 -139.827)
		(width 0.14224)
		(layer "In4.Cu")
		(net "M_E_DQS_DP<12>")
	)
	(segment
		(start 227.353876 -125.717554)
		(end 227.353876 -126.705614)
		(width 0.14224)
		(layer "In4.Cu")
		(net "M_E_DQS_DP<12>")
	)
	(segment
		(start 227.792534 -139.827)
		(end 227.719382 -139.827)
		(width 0.14224)
		(layer "In4.Cu")
		(net "M_E_DQS_DP<12>")
	)
	(segment
		(start 228.305614 -129.003552)
		(end 228.305614 -139.562586)
		(width 0.14224)
		(layer "In4.Cu")
		(net "M_E_DQS_DP<12>")
	)
	(segment
		(start 218.500452 -142.6718)
		(end 218.499944 -142.677642)
		(width 0.1651)
		(layer "F.Cu")
		(net "M_E_DQS_DP<11>")
	)
	(segment
		(start 218.499944 -143.294354)
		(end 218.063826 -143.730472)
		(width 0.1651)
		(layer "F.Cu")
		(net "M_E_DQS_DP<11>")
	)
	(segment
		(start 217.979244 -143.914368)
		(end 217.979244 -144.732502)
		(width 0.1651)
		(layer "F.Cu")
		(net "M_E_DQS_DP<11>")
	)
	(segment
		(start 217.979244 -144.732502)
		(end 218.060778 -144.956784)
		(width 0.1651)
		(layer "F.Cu")
		(net "M_E_DQS_DP<11>")
	)
	(segment
		(start 218.060778 -144.956784)
		(end 218.44254 -145.338546)
		(width 0.1651)
		(layer "F.Cu")
		(net "M_E_DQS_DP<11>")
	)
	(segment
		(start 238.759238 -97.690686)
		(end 238.187738 -97.690686)
		(width 0.1651)
		(layer "F.Cu")
		(net "M_E_DQS_DP<11>")
	)
	(segment
		(start 218.063826 -143.730472)
		(end 217.979244 -143.914368)
		(width 0.1651)
		(layer "F.Cu")
		(net "M_E_DQS_DP<11>")
	)
	(segment
		(start 218.499944 -142.677642)
		(end 218.499944 -143.294354)
		(width 0.1651)
		(layer "F.Cu")
		(net "M_E_DQS_DP<11>")
	)
	(via
		(at 218.44254 -145.338546)
		(size 0.508)
		(drill 0.254)
		(layers "F.Cu" "B.Cu")
		(net "M_E_DQS_DP<11>")
	)
	(via
		(at 238.187738 -97.690686)
		(size 0.508)
		(drill 0.254)
		(layers "F.Cu" "B.Cu")
		(net "M_E_DQS_DP<11>")
	)
	(via
		(at 218.44254 -139.827)
		(size 0.508)
		(drill 0.254)
		(layers "F.Cu" "B.Cu")
		(net "M_E_DQS_DP<11>")
	)
	(segment
		(start 218.499944 -141.859254)
		(end 218.04376 -141.40307)
		(width 0.1651)
		(layer "B.Cu")
		(net "M_E_DQS_DP<11>")
	)
	(segment
		(start 218.04376 -141.40307)
		(end 217.966544 -141.270736)
		(width 0.1651)
		(layer "B.Cu")
		(net "M_E_DQS_DP<11>")
	)
	(segment
		(start 217.966544 -141.270736)
		(end 217.966544 -140.375132)
		(width 0.1651)
		(layer "B.Cu")
		(net "M_E_DQS_DP<11>")
	)
	(segment
		(start 218.05392 -140.21562)
		(end 218.44254 -139.827)
		(width 0.1651)
		(layer "B.Cu")
		(net "M_E_DQS_DP<11>")
	)
	(segment
		(start 218.499944 -142.476982)
		(end 218.499944 -141.859254)
		(width 0.1651)
		(layer "B.Cu")
		(net "M_E_DQS_DP<11>")
	)
	(segment
		(start 218.500452 -142.477236)
		(end 218.499944 -142.476982)
		(width 0.1651)
		(layer "B.Cu")
		(net "M_E_DQS_DP<11>")
	)
	(segment
		(start 217.966544 -140.375132)
		(end 218.05392 -140.21562)
		(width 0.1651)
		(layer "B.Cu")
		(net "M_E_DQS_DP<11>")
	)
	(segment
		(start 238.12246 -98.094038)
		(end 238.187738 -98.02876)
		(width 0.0889)
		(layer "In4.Cu")
		(net "M_E_DQS_DP<11>")
	)
	(segment
		(start 218.95562 -129.107946)
		(end 220.14688 -127.916686)
		(width 0.14224)
		(layer "In4.Cu")
		(net "M_E_DQS_DP<11>")
	)
	(segment
		(start 235.876084 -101.501194)
		(end 235.959142 -101.357176)
		(width 0.0889)
		(layer "In4.Cu")
		(net "M_E_DQS_DP<11>")
	)
	(segment
		(start 220.14688 -123.339606)
		(end 229.46868 -114.017806)
		(width 0.14224)
		(layer "In4.Cu")
		(net "M_E_DQS_DP<11>")
	)
	(segment
		(start 232.7656 -105.950766)
		(end 232.7656 -104.306116)
		(width 0.14224)
		(layer "In4.Cu")
		(net "M_E_DQS_DP<11>")
	)
	(segment
		(start 233.320082 -103.751634)
		(end 233.375962 -103.751634)
		(width 0.0889)
		(layer "In4.Cu")
		(net "M_E_DQS_DP<11>")
	)
	(segment
		(start 218.814904 -138.753342)
		(end 218.814904 -138.499342)
		(width 0.14224)
		(layer "In4.Cu")
		(net "M_E_DQS_DP<11>")
	)
	(segment
		(start 218.369388 -139.827)
		(end 218.44254 -139.827)
		(width 0.14224)
		(layer "In4.Cu")
		(net "M_E_DQS_DP<11>")
	)
	(segment
		(start 217.937588 -144.833594)
		(end 217.937588 -140.2588)
		(width 0.14224)
		(layer "In4.Cu")
		(net "M_E_DQS_DP<11>")
	)
	(segment
		(start 218.72194 -139.827)
		(end 218.95562 -139.59332)
		(width 0.14224)
		(layer "In4.Cu")
		(net "M_E_DQS_DP<11>")
	)
	(segment
		(start 237.675928 -99.967288)
		(end 237.669578 -99.95662)
		(width 0.0889)
		(layer "In4.Cu")
		(net "M_E_DQS_DP<11>")
	)
	(segment
		(start 217.937588 -140.2588)
		(end 218.369388 -139.827)
		(width 0.14224)
		(layer "In4.Cu")
		(net "M_E_DQS_DP<11>")
	)
	(segment
		(start 233.304334 -103.767382)
		(end 233.320082 -103.751634)
		(width 0.0889)
		(layer "In4.Cu")
		(net "M_E_DQS_DP<11>")
	)
	(segment
		(start 218.95562 -138.060684)
		(end 218.822016 -137.92708)
		(width 0.14224)
		(layer "In4.Cu")
		(net "M_E_DQS_DP<11>")
	)
	(segment
		(start 229.46868 -114.017806)
		(end 229.46868 -109.247686)
		(width 0.14224)
		(layer "In4.Cu")
		(net "M_E_DQS_DP<11>")
	)
	(segment
		(start 218.95562 -138.358626)
		(end 218.95562 -138.060684)
		(width 0.14224)
		(layer "In4.Cu")
		(net "M_E_DQS_DP<11>")
	)
	(segment
		(start 218.95562 -138.894058)
		(end 218.814904 -138.753342)
		(width 0.14224)
		(layer "In4.Cu")
		(net "M_E_DQS_DP<11>")
	)
	(segment
		(start 238.187738 -98.02876)
		(end 238.187738 -97.690686)
		(width 0.0889)
		(layer "In4.Cu")
		(net "M_E_DQS_DP<11>")
	)
	(segment
		(start 233.375962 -103.751634)
		(end 234.801156 -102.32644)
		(width 0.0889)
		(layer "In4.Cu")
		(net "M_E_DQS_DP<11>")
	)
	(segment
		(start 218.822016 -137.67308)
		(end 218.95562 -137.539476)
		(width 0.14224)
		(layer "In4.Cu")
		(net "M_E_DQS_DP<11>")
	)
	(segment
		(start 218.44254 -145.338546)
		(end 217.937588 -144.833594)
		(width 0.14224)
		(layer "In4.Cu")
		(net "M_E_DQS_DP<11>")
	)
	(segment
		(start 237.316264 -100.567236)
		(end 237.340394 -100.567236)
		(width 0.0889)
		(layer "In4.Cu")
		(net "M_E_DQS_DP<11>")
	)
	(segment
		(start 229.46868 -109.247686)
		(end 232.7656 -105.950766)
		(width 0.14224)
		(layer "In4.Cu")
		(net "M_E_DQS_DP<11>")
	)
	(segment
		(start 220.14688 -127.916686)
		(end 220.14688 -123.339606)
		(width 0.14224)
		(layer "In4.Cu")
		(net "M_E_DQS_DP<11>")
	)
	(segment
		(start 218.95562 -137.539476)
		(end 218.95562 -129.107946)
		(width 0.14224)
		(layer "In4.Cu")
		(net "M_E_DQS_DP<11>")
	)
	(segment
		(start 218.814904 -138.499342)
		(end 218.95562 -138.358626)
		(width 0.14224)
		(layer "In4.Cu")
		(net "M_E_DQS_DP<11>")
	)
	(segment
		(start 234.801156 -102.32644)
		(end 235.050838 -102.32644)
		(width 0.0889)
		(layer "In4.Cu")
		(net "M_E_DQS_DP<11>")
	)
	(segment
		(start 232.7656 -104.306116)
		(end 233.304334 -103.767382)
		(width 0.14224)
		(layer "In4.Cu")
		(net "M_E_DQS_DP<11>")
	)
	(segment
		(start 235.050838 -102.32644)
		(end 235.876084 -101.501194)
		(width 0.0889)
		(layer "In4.Cu")
		(net "M_E_DQS_DP<11>")
	)
	(segment
		(start 218.822016 -137.92708)
		(end 218.822016 -137.67308)
		(width 0.14224)
		(layer "In4.Cu")
		(net "M_E_DQS_DP<11>")
	)
	(segment
		(start 218.95562 -139.59332)
		(end 218.95562 -138.894058)
		(width 0.14224)
		(layer "In4.Cu")
		(net "M_E_DQS_DP<11>")
	)
	(segment
		(start 236.456982 -101.062536)
		(end 236.485684 -101.062536)
		(width 0.0889)
		(layer "In4.Cu")
		(net "M_E_DQS_DP<11>")
	)
	(segment
		(start 218.44254 -139.827)
		(end 218.72194 -139.827)
		(width 0.14224)
		(layer "In4.Cu")
		(net "M_E_DQS_DP<11>")
	)
	(segment
		(start 237.675928 -99.376738)
		(end 237.680754 -99.368102)
		(width 0.0889)
		(layer "In4.Cu")
		(net "M_E_DQS_DP<11>")
	)
	(arc
		(start 237.669578 -99.95662)
		(mid 237.59678 -99.665857)
		(end 237.675928 -99.376738)
		(width 0.0889)
		(layer "In4.Cu")
		(net "M_E_DQS_DP<11>")
	)
	(arc
		(start 237.675928 -98.976688)
		(mid 237.660423 -98.414546)
		(end 238.12246 -98.094038)
		(width 0.0889)
		(layer "In4.Cu")
		(net "M_E_DQS_DP<11>")
	)
	(arc
		(start 236.485684 -101.062536)
		(mid 236.677326 -101.00537)
		(end 236.817408 -100.862638)
		(width 0.0889)
		(layer "In4.Cu")
		(net "M_E_DQS_DP<11>")
	)
	(arc
		(start 235.959142 -101.357176)
		(mid 236.16952 -101.144719)
		(end 236.456982 -101.062536)
		(width 0.0889)
		(layer "In4.Cu")
		(net "M_E_DQS_DP<11>")
	)
	(arc
		(start 236.817408 -100.862638)
		(mid 237.028121 -100.649559)
		(end 237.316264 -100.567236)
		(width 0.0889)
		(layer "In4.Cu")
		(net "M_E_DQS_DP<11>")
	)
	(arc
		(start 237.340394 -100.567236)
		(mid 237.678509 -100.362534)
		(end 237.675928 -99.967288)
		(width 0.0889)
		(layer "In4.Cu")
		(net "M_E_DQS_DP<11>")
	)
	(arc
		(start 237.680754 -99.368102)
		(mid 237.729509 -99.17175)
		(end 237.675928 -98.976688)
		(width 0.0889)
		(layer "In4.Cu")
		(net "M_E_DQS_DP<11>")
	)
	(segment
		(start 209.150458 -142.6718)
		(end 209.14995 -142.677642)
		(width 0.1651)
		(layer "F.Cu")
		(net "M_E_DQS_DP<10>")
	)
	(segment
		(start 208.62925 -143.914368)
		(end 208.62925 -144.732502)
		(width 0.1651)
		(layer "F.Cu")
		(net "M_E_DQS_DP<10>")
	)
	(segment
		(start 209.14995 -142.677642)
		(end 209.14995 -143.294354)
		(width 0.1651)
		(layer "F.Cu")
		(net "M_E_DQS_DP<10>")
	)
	(segment
		(start 209.14995 -143.294354)
		(end 208.713832 -143.730472)
		(width 0.1651)
		(layer "F.Cu")
		(net "M_E_DQS_DP<10>")
	)
	(segment
		(start 208.710784 -144.956784)
		(end 209.092546 -145.338546)
		(width 0.1651)
		(layer "F.Cu")
		(net "M_E_DQS_DP<10>")
	)
	(segment
		(start 238.759238 -90.756486)
		(end 238.187738 -90.756486)
		(width 0.1651)
		(layer "F.Cu")
		(net "M_E_DQS_DP<10>")
	)
	(segment
		(start 208.62925 -144.732502)
		(end 208.710784 -144.956784)
		(width 0.1651)
		(layer "F.Cu")
		(net "M_E_DQS_DP<10>")
	)
	(segment
		(start 208.713832 -143.730472)
		(end 208.62925 -143.914368)
		(width 0.1651)
		(layer "F.Cu")
		(net "M_E_DQS_DP<10>")
	)
	(via
		(at 238.187738 -90.756486)
		(size 0.508)
		(drill 0.254)
		(layers "F.Cu" "B.Cu")
		(net "M_E_DQS_DP<10>")
	)
	(via
		(at 209.092546 -139.827)
		(size 0.508)
		(drill 0.254)
		(layers "F.Cu" "B.Cu")
		(net "M_E_DQS_DP<10>")
	)
	(via
		(at 209.092546 -145.338546)
		(size 0.508)
		(drill 0.254)
		(layers "F.Cu" "B.Cu")
		(net "M_E_DQS_DP<10>")
	)
	(segment
		(start 208.693766 -141.40307)
		(end 208.61655 -141.270736)
		(width 0.1651)
		(layer "B.Cu")
		(net "M_E_DQS_DP<10>")
	)
	(segment
		(start 209.14995 -142.476982)
		(end 209.14995 -141.859254)
		(width 0.1651)
		(layer "B.Cu")
		(net "M_E_DQS_DP<10>")
	)
	(segment
		(start 209.150458 -142.477236)
		(end 209.14995 -142.476982)
		(width 0.1651)
		(layer "B.Cu")
		(net "M_E_DQS_DP<10>")
	)
	(segment
		(start 209.14995 -141.859254)
		(end 208.693766 -141.40307)
		(width 0.1651)
		(layer "B.Cu")
		(net "M_E_DQS_DP<10>")
	)
	(segment
		(start 208.61655 -141.270736)
		(end 208.61655 -140.375132)
		(width 0.1651)
		(layer "B.Cu")
		(net "M_E_DQS_DP<10>")
	)
	(segment
		(start 208.703926 -140.21562)
		(end 209.092546 -139.827)
		(width 0.1651)
		(layer "B.Cu")
		(net "M_E_DQS_DP<10>")
	)
	(segment
		(start 208.61655 -140.375132)
		(end 208.703926 -140.21562)
		(width 0.1651)
		(layer "B.Cu")
		(net "M_E_DQS_DP<10>")
	)
	(segment
		(start 233.280204 -90.14587)
		(end 233.383074 -89.966546)
		(width 0.0889)
		(layer "In4.Cu")
		(net "M_E_DQS_DP<10>")
	)
	(segment
		(start 208.587594 -144.833594)
		(end 208.587594 -140.2588)
		(width 0.14224)
		(layer "In4.Cu")
		(net "M_E_DQS_DP<10>")
	)
	(segment
		(start 231.476042 -92.611448)
		(end 231.53243 -92.611448)
		(width 0.0889)
		(layer "In4.Cu")
		(net "M_E_DQS_DP<10>")
	)
	(segment
		(start 211.79028 -118.719854)
		(end 212.753448 -117.756686)
		(width 0.14224)
		(layer "In4.Cu")
		(net "M_E_DQS_DP<10>")
	)
	(segment
		(start 233.280204 -90.493088)
		(end 233.280204 -90.14587)
		(width 0.0889)
		(layer "In4.Cu")
		(net "M_E_DQS_DP<10>")
	)
	(segment
		(start 237.318042 -89.67089)
		(end 237.350808 -89.67089)
		(width 0.0889)
		(layer "In4.Cu")
		(net "M_E_DQS_DP<10>")
	)
	(segment
		(start 212.65896 -116.679726)
		(end 212.251544 -116.27231)
		(width 0.14224)
		(layer "In4.Cu")
		(net "M_E_DQS_DP<10>")
	)
	(segment
		(start 209.019394 -139.827)
		(end 209.092546 -139.827)
		(width 0.14224)
		(layer "In4.Cu")
		(net "M_E_DQS_DP<10>")
	)
	(segment
		(start 209.605626 -129.72034)
		(end 209.83448 -129.491486)
		(width 0.14224)
		(layer "In4.Cu")
		(net "M_E_DQS_DP<10>")
	)
	(segment
		(start 236.455712 -89.175336)
		(end 236.488478 -89.175336)
		(width 0.0889)
		(layer "In4.Cu")
		(net "M_E_DQS_DP<10>")
	)
	(segment
		(start 212.251544 -115.679728)
		(end 221.2848 -106.646472)
		(width 0.14224)
		(layer "In4.Cu")
		(net "M_E_DQS_DP<10>")
	)
	(segment
		(start 233.436668 -90.649552)
		(end 233.280204 -90.493088)
		(width 0.0889)
		(layer "In4.Cu")
		(net "M_E_DQS_DP<10>")
	)
	(segment
		(start 209.83448 -129.491486)
		(end 209.83448 -127.688086)
		(width 0.14224)
		(layer "In4.Cu")
		(net "M_E_DQS_DP<10>")
	)
	(segment
		(start 233.13263 -92.225114)
		(end 233.436668 -91.921076)
		(width 0.0889)
		(layer "In4.Cu")
		(net "M_E_DQS_DP<10>")
	)
	(segment
		(start 209.379058 -139.827)
		(end 209.605626 -139.600432)
		(width 0.14224)
		(layer "In4.Cu")
		(net "M_E_DQS_DP<10>")
	)
	(segment
		(start 233.873548 -89.67089)
		(end 233.906314 -89.67089)
		(width 0.0889)
		(layer "In4.Cu")
		(net "M_E_DQS_DP<10>")
	)
	(segment
		(start 233.383074 -89.966546)
		(end 233.383328 -89.966038)
		(width 0.0889)
		(layer "In4.Cu")
		(net "M_E_DQS_DP<10>")
	)
	(segment
		(start 231.91851 -92.225114)
		(end 233.13263 -92.225114)
		(width 0.0889)
		(layer "In4.Cu")
		(net "M_E_DQS_DP<10>")
	)
	(segment
		(start 226.4156 -97.67189)
		(end 231.460294 -92.627196)
		(width 0.14224)
		(layer "In4.Cu")
		(net "M_E_DQS_DP<10>")
	)
	(segment
		(start 226.4156 -99.061016)
		(end 226.4156 -97.67189)
		(width 0.14224)
		(layer "In4.Cu")
		(net "M_E_DQS_DP<10>")
	)
	(segment
		(start 213.62416 -117.083332)
		(end 213.220554 -116.679726)
		(width 0.14224)
		(layer "In4.Cu")
		(net "M_E_DQS_DP<10>")
	)
	(segment
		(start 221.2848 -106.646472)
		(end 221.2848 -104.191816)
		(width 0.14224)
		(layer "In4.Cu")
		(net "M_E_DQS_DP<10>")
	)
	(segment
		(start 209.092546 -139.827)
		(end 209.379058 -139.827)
		(width 0.14224)
		(layer "In4.Cu")
		(net "M_E_DQS_DP<10>")
	)
	(segment
		(start 233.436668 -91.921076)
		(end 233.436668 -90.649552)
		(width 0.0889)
		(layer "In4.Cu")
		(net "M_E_DQS_DP<10>")
	)
	(segment
		(start 209.605626 -139.600432)
		(end 209.605626 -129.72034)
		(width 0.14224)
		(layer "In4.Cu")
		(net "M_E_DQS_DP<10>")
	)
	(segment
		(start 237.894622 -90.587576)
		(end 238.187738 -90.756486)
		(width 0.0889)
		(layer "In4.Cu")
		(net "M_E_DQS_DP<10>")
	)
	(segment
		(start 209.092546 -145.338546)
		(end 208.587594 -144.833594)
		(width 0.14224)
		(layer "In4.Cu")
		(net "M_E_DQS_DP<10>")
	)
	(segment
		(start 231.460294 -92.627196)
		(end 231.476042 -92.611448)
		(width 0.0889)
		(layer "In4.Cu")
		(net "M_E_DQS_DP<10>")
	)
	(segment
		(start 231.53243 -92.611448)
		(end 231.91851 -92.225114)
		(width 0.0889)
		(layer "In4.Cu")
		(net "M_E_DQS_DP<10>")
	)
	(segment
		(start 235.590588 -88.68029)
		(end 235.633768 -88.68029)
		(width 0.0889)
		(layer "In4.Cu")
		(net "M_E_DQS_DP<10>")
	)
	(segment
		(start 208.587594 -140.2588)
		(end 209.019394 -139.827)
		(width 0.14224)
		(layer "In4.Cu")
		(net "M_E_DQS_DP<10>")
	)
	(segment
		(start 237.870746 -90.498422)
		(end 237.894622 -90.587576)
		(width 0.0889)
		(layer "In4.Cu")
		(net "M_E_DQS_DP<10>")
	)
	(segment
		(start 213.332314 -117.756686)
		(end 213.62416 -117.46484)
		(width 0.14224)
		(layer "In4.Cu")
		(net "M_E_DQS_DP<10>")
	)
	(segment
		(start 213.62416 -117.46484)
		(end 213.62416 -117.083332)
		(width 0.14224)
		(layer "In4.Cu")
		(net "M_E_DQS_DP<10>")
	)
	(segment
		(start 234.735878 -89.175336)
		(end 234.768644 -89.175336)
		(width 0.0889)
		(layer "In4.Cu")
		(net "M_E_DQS_DP<10>")
	)
	(segment
		(start 209.83448 -127.688086)
		(end 211.79028 -125.732286)
		(width 0.14224)
		(layer "In4.Cu")
		(net "M_E_DQS_DP<10>")
	)
	(segment
		(start 212.753448 -117.756686)
		(end 213.332314 -117.756686)
		(width 0.14224)
		(layer "In4.Cu")
		(net "M_E_DQS_DP<10>")
	)
	(segment
		(start 212.251544 -116.27231)
		(end 212.251544 -115.679728)
		(width 0.14224)
		(layer "In4.Cu")
		(net "M_E_DQS_DP<10>")
	)
	(segment
		(start 211.79028 -125.732286)
		(end 211.79028 -118.719854)
		(width 0.14224)
		(layer "In4.Cu")
		(net "M_E_DQS_DP<10>")
	)
	(segment
		(start 221.2848 -104.191816)
		(end 226.4156 -99.061016)
		(width 0.14224)
		(layer "In4.Cu")
		(net "M_E_DQS_DP<10>")
	)
	(segment
		(start 213.220554 -116.679726)
		(end 212.65896 -116.679726)
		(width 0.14224)
		(layer "In4.Cu")
		(net "M_E_DQS_DP<10>")
	)
	(arc
		(start 235.633768 -88.68029)
		(mid 235.916985 -88.764571)
		(end 236.123988 -88.975438)
		(width 0.0889)
		(layer "In4.Cu")
		(net "M_E_DQS_DP<10>")
	)
	(arc
		(start 236.982508 -89.470738)
		(mid 237.124191 -89.614542)
		(end 237.318042 -89.67089)
		(width 0.0889)
		(layer "In4.Cu")
		(net "M_E_DQS_DP<10>")
	)
	(arc
		(start 234.768644 -89.175336)
		(mid 234.960286 -89.11817)
		(end 235.100368 -88.975438)
		(width 0.0889)
		(layer "In4.Cu")
		(net "M_E_DQS_DP<10>")
	)
	(arc
		(start 234.241848 -89.470738)
		(mid 234.450456 -89.258806)
		(end 234.735878 -89.175336)
		(width 0.0889)
		(layer "In4.Cu")
		(net "M_E_DQS_DP<10>")
	)
	(arc
		(start 236.123988 -88.975438)
		(mid 236.264067 -89.118174)
		(end 236.455712 -89.175336)
		(width 0.0889)
		(layer "In4.Cu")
		(net "M_E_DQS_DP<10>")
	)
	(arc
		(start 236.488478 -89.175336)
		(mid 236.773902 -89.258803)
		(end 236.982508 -89.470738)
		(width 0.0889)
		(layer "In4.Cu")
		(net "M_E_DQS_DP<10>")
	)
	(arc
		(start 237.350808 -89.67089)
		(mid 237.829625 -89.947102)
		(end 237.870746 -90.498422)
		(width 0.0889)
		(layer "In4.Cu")
		(net "M_E_DQS_DP<10>")
	)
	(arc
		(start 233.906314 -89.67089)
		(mid 234.100164 -89.61454)
		(end 234.241848 -89.470738)
		(width 0.0889)
		(layer "In4.Cu")
		(net "M_E_DQS_DP<10>")
	)
	(arc
		(start 235.100368 -88.975438)
		(mid 235.307372 -88.764574)
		(end 235.590588 -88.68029)
		(width 0.0889)
		(layer "In4.Cu")
		(net "M_E_DQS_DP<10>")
	)
	(arc
		(start 233.383328 -89.966038)
		(mid 233.590332 -89.755174)
		(end 233.873548 -89.67089)
		(width 0.0889)
		(layer "In4.Cu")
		(net "M_E_DQS_DP<10>")
	)
	(segment
		(start 201.499978 -147.27174)
		(end 201.499978 -146.265646)
		(width 0.1651)
		(layer "F.Cu")
		(net "M_E_DQS_DP<0>")
	)
	(segment
		(start 237.042198 -84.812886)
		(end 236.470698 -84.812886)
		(width 0.1651)
		(layer "F.Cu")
		(net "M_E_DQS_DP<0>")
	)
	(segment
		(start 201.499978 -146.265646)
		(end 201.537824 -146.2278)
		(width 0.1651)
		(layer "F.Cu")
		(net "M_E_DQS_DP<0>")
	)
	(segment
		(start 201.500486 -147.27174)
		(end 201.499978 -147.27174)
		(width 0.1651)
		(layer "F.Cu")
		(net "M_E_DQS_DP<0>")
	)
	(segment
		(start 201.537824 -144.8562)
		(end 201.293984 -144.61236)
		(width 0.1651)
		(layer "F.Cu")
		(net "M_E_DQS_DP<0>")
	)
	(segment
		(start 201.293984 -144.61236)
		(end 201.037952 -144.61236)
		(width 0.1651)
		(layer "F.Cu")
		(net "M_E_DQS_DP<0>")
	)
	(segment
		(start 201.537824 -146.2278)
		(end 201.537824 -144.8562)
		(width 0.1651)
		(layer "F.Cu")
		(net "M_E_DQS_DP<0>")
	)
	(via
		(at 201.037952 -144.61236)
		(size 0.508)
		(drill 0.254)
		(layers "F.Cu" "B.Cu")
		(net "M_E_DQS_DP<0>")
	)
	(via
		(at 236.470698 -84.812886)
		(size 0.508)
		(drill 0.254)
		(layers "F.Cu" "B.Cu")
		(net "M_E_DQS_DP<0>")
	)
	(via
		(at 201.037952 -140.541756)
		(size 0.508)
		(drill 0.254)
		(layers "F.Cu" "B.Cu")
		(net "M_E_DQS_DP<0>")
	)
	(segment
		(start 201.537824 -139.065)
		(end 201.537824 -140.2842)
		(width 0.1651)
		(layer "B.Cu")
		(net "M_E_DQS_DP<0>")
	)
	(segment
		(start 201.280268 -140.541756)
		(end 201.037952 -140.541756)
		(width 0.1651)
		(layer "B.Cu")
		(net "M_E_DQS_DP<0>")
	)
	(segment
		(start 201.499978 -139.027154)
		(end 201.537824 -139.065)
		(width 0.1651)
		(layer "B.Cu")
		(net "M_E_DQS_DP<0>")
	)
	(segment
		(start 201.537824 -140.2842)
		(end 201.280268 -140.541756)
		(width 0.1651)
		(layer "B.Cu")
		(net "M_E_DQS_DP<0>")
	)
	(segment
		(start 201.500486 -137.877296)
		(end 201.499978 -137.877296)
		(width 0.1651)
		(layer "B.Cu")
		(net "M_E_DQS_DP<0>")
	)
	(segment
		(start 201.499978 -137.877296)
		(end 201.499978 -139.027154)
		(width 0.1651)
		(layer "B.Cu")
		(net "M_E_DQS_DP<0>")
	)
	(segment
		(start 201.4982 -143.7132)
		(end 201.4982 -144.152112)
		(width 0.14224)
		(layer "In4.Cu")
		(net "M_E_DQS_DP<0>")
	)
	(segment
		(start 200.685908 -123.000516)
		(end 200.685908 -123.432824)
		(width 0.14224)
		(layer "In4.Cu")
		(net "M_E_DQS_DP<0>")
	)
	(segment
		(start 200.80732 -121.139204)
		(end 201.028808 -121.360692)
		(width 0.14224)
		(layer "In4.Cu")
		(net "M_E_DQS_DP<0>")
	)
	(segment
		(start 229.867968 -85.849206)
		(end 229.313994 -85.849206)
		(width 0.14224)
		(layer "In4.Cu")
		(net "M_E_DQS_DP<0>")
	)
	(segment
		(start 201.953114 -121.360692)
		(end 202.33132 -121.738898)
		(width 0.14224)
		(layer "In4.Cu")
		(net "M_E_DQS_DP<0>")
	)
	(segment
		(start 200.685908 -123.432824)
		(end 200.899776 -123.646692)
		(width 0.14224)
		(layer "In4.Cu")
		(net "M_E_DQS_DP<0>")
	)
	(segment
		(start 200.86066 -142.899892)
		(end 200.800462 -142.899892)
		(width 0.14224)
		(layer "In4.Cu")
		(net "M_E_DQS_DP<0>")
	)
	(segment
		(start 200.926446 -125.19152)
		(end 200.70572 -125.412246)
		(width 0.14224)
		(layer "In4.Cu")
		(net "M_E_DQS_DP<0>")
	)
	(segment
		(start 201.4728 -140.976604)
		(end 201.4728 -141.4018)
		(width 0.14224)
		(layer "In4.Cu")
		(net "M_E_DQS_DP<0>")
	)
	(segment
		(start 200.663302 -143.037052)
		(end 200.663302 -143.263366)
		(width 0.14224)
		(layer "In4.Cu")
		(net "M_E_DQS_DP<0>")
	)
	(segment
		(start 221.367604 -97.529396)
		(end 208.9404 -109.9566)
		(width 0.14224)
		(layer "In4.Cu")
		(net "M_E_DQS_DP<0>")
	)
	(segment
		(start 234.961684 -84.412836)
		(end 234.742482 -84.412836)
		(width 0.0889)
		(layer "In4.Cu")
		(net "M_E_DQS_DP<0>")
	)
	(segment
		(start 233.058208 -85.403436)
		(end 233.02214 -85.403436)
		(width 0.0889)
		(layer "In4.Cu")
		(net "M_E_DQS_DP<0>")
	)
	(segment
		(start 202.33132 -124.02566)
		(end 202.33132 -124.853446)
		(width 0.14224)
		(layer "In4.Cu")
		(net "M_E_DQS_DP<0>")
	)
	(segment
		(start 201.578464 -117.311424)
		(end 201.578464 -118.188232)
		(width 0.14224)
		(layer "In4.Cu")
		(net "M_E_DQS_DP<0>")
	)
	(segment
		(start 208.094072 -109.9566)
		(end 204.114146 -113.936526)
		(width 0.14224)
		(layer "In4.Cu")
		(net "M_E_DQS_DP<0>")
	)
	(segment
		(start 201.047096 -140.541756)
		(end 201.037952 -140.541756)
		(width 0.14224)
		(layer "In4.Cu")
		(net "M_E_DQS_DP<0>")
	)
	(segment
		(start 229.929436 -85.809836)
		(end 229.890066 -85.849206)
		(width 0.0889)
		(layer "In4.Cu")
		(net "M_E_DQS_DP<0>")
	)
	(segment
		(start 201.952352 -123.646692)
		(end 202.33132 -124.02566)
		(width 0.14224)
		(layer "In4.Cu")
		(net "M_E_DQS_DP<0>")
	)
	(segment
		(start 232.199434 -85.89899)
		(end 231.251506 -85.89899)
		(width 0.0889)
		(layer "In4.Cu")
		(net "M_E_DQS_DP<0>")
	)
	(segment
		(start 201.2188 -141.6558)
		(end 200.833736 -141.6558)
		(width 0.14224)
		(layer "In4.Cu")
		(net "M_E_DQS_DP<0>")
	)
	(segment
		(start 200.913492 -122.772932)
		(end 200.685908 -123.000516)
		(width 0.14224)
		(layer "In4.Cu")
		(net "M_E_DQS_DP<0>")
	)
	(segment
		(start 208.9404 -109.9566)
		(end 208.094072 -109.9566)
		(width 0.14224)
		(layer "In4.Cu")
		(net "M_E_DQS_DP<0>")
	)
	(segment
		(start 204.114146 -114.775742)
		(end 201.578464 -117.311424)
		(width 0.14224)
		(layer "In4.Cu")
		(net "M_E_DQS_DP<0>")
	)
	(segment
		(start 201.4728 -141.4018)
		(end 201.2188 -141.6558)
		(width 0.14224)
		(layer "In4.Cu")
		(net "M_E_DQS_DP<0>")
	)
	(segment
		(start 201.820272 -129.066544)
		(end 201.820272 -139.76858)
		(width 0.14224)
		(layer "In4.Cu")
		(net "M_E_DQS_DP<0>")
	)
	(segment
		(start 229.890066 -85.849206)
		(end 229.867968 -85.849206)
		(width 0.0889)
		(layer "In4.Cu")
		(net "M_E_DQS_DP<0>")
	)
	(segment
		(start 200.859136 -143.4592)
		(end 201.2442 -143.4592)
		(width 0.14224)
		(layer "In4.Cu")
		(net "M_E_DQS_DP<0>")
	)
	(segment
		(start 201.952352 -120.486932)
		(end 201.028808 -120.486932)
		(width 0.14224)
		(layer "In4.Cu")
		(net "M_E_DQS_DP<0>")
	)
	(segment
		(start 229.313994 -85.849206)
		(end 221.367604 -93.795596)
		(width 0.14224)
		(layer "In4.Cu")
		(net "M_E_DQS_DP<0>")
	)
	(segment
		(start 231.162352 -85.809836)
		(end 229.929436 -85.809836)
		(width 0.0889)
		(layer "In4.Cu")
		(net "M_E_DQS_DP<0>")
	)
	(segment
		(start 200.899776 -123.646692)
		(end 201.952352 -123.646692)
		(width 0.14224)
		(layer "In4.Cu")
		(net "M_E_DQS_DP<0>")
	)
	(segment
		(start 201.993246 -125.19152)
		(end 200.926446 -125.19152)
		(width 0.14224)
		(layer "In4.Cu")
		(net "M_E_DQS_DP<0>")
	)
	(segment
		(start 233.912918 -84.90839)
		(end 233.880152 -84.90839)
		(width 0.0889)
		(layer "In4.Cu")
		(net "M_E_DQS_DP<0>")
	)
	(segment
		(start 201.952352 -122.772932)
		(end 200.913492 -122.772932)
		(width 0.14224)
		(layer "In4.Cu")
		(net "M_E_DQS_DP<0>")
	)
	(segment
		(start 201.028808 -120.486932)
		(end 200.80732 -120.70842)
		(width 0.14224)
		(layer "In4.Cu")
		(net "M_E_DQS_DP<0>")
	)
	(segment
		(start 202.33132 -124.853446)
		(end 201.993246 -125.19152)
		(width 0.14224)
		(layer "In4.Cu")
		(net "M_E_DQS_DP<0>")
	)
	(segment
		(start 201.040492 -142.442692)
		(end 201.040492 -142.72006)
		(width 0.14224)
		(layer "In4.Cu")
		(net "M_E_DQS_DP<0>")
	)
	(segment
		(start 202.33132 -122.393964)
		(end 201.952352 -122.772932)
		(width 0.14224)
		(layer "In4.Cu")
		(net "M_E_DQS_DP<0>")
	)
	(segment
		(start 221.367604 -93.795596)
		(end 221.367604 -97.529396)
		(width 0.14224)
		(layer "In4.Cu")
		(net "M_E_DQS_DP<0>")
	)
	(segment
		(start 201.4982 -144.152112)
		(end 201.037952 -144.61236)
		(width 0.14224)
		(layer "In4.Cu")
		(net "M_E_DQS_DP<0>")
	)
	(segment
		(start 200.663302 -141.826234)
		(end 200.663302 -142.150592)
		(width 0.14224)
		(layer "In4.Cu")
		(net "M_E_DQS_DP<0>")
	)
	(segment
		(start 201.2442 -143.4592)
		(end 201.4982 -143.7132)
		(width 0.14224)
		(layer "In4.Cu")
		(net "M_E_DQS_DP<0>")
	)
	(segment
		(start 202.33132 -120.107964)
		(end 201.952352 -120.486932)
		(width 0.14224)
		(layer "In4.Cu")
		(net "M_E_DQS_DP<0>")
	)
	(segment
		(start 202.33132 -118.941088)
		(end 202.33132 -120.107964)
		(width 0.14224)
		(layer "In4.Cu")
		(net "M_E_DQS_DP<0>")
	)
	(segment
		(start 235.505752 -84.716366)
		(end 234.961684 -84.412836)
		(width 0.0889)
		(layer "In4.Cu")
		(net "M_E_DQS_DP<0>")
	)
	(segment
		(start 200.77811 -142.2654)
		(end 200.8632 -142.2654)
		(width 0.14224)
		(layer "In4.Cu")
		(net "M_E_DQS_DP<0>")
	)
	(segment
		(start 200.663302 -142.150592)
		(end 200.77811 -142.2654)
		(width 0.14224)
		(layer "In4.Cu")
		(net "M_E_DQS_DP<0>")
	)
	(segment
		(start 236.470698 -84.812886)
		(end 235.892594 -84.721192)
		(width 0.0889)
		(layer "In4.Cu")
		(net "M_E_DQS_DP<0>")
	)
	(segment
		(start 200.833736 -141.6558)
		(end 200.663302 -141.826234)
		(width 0.14224)
		(layer "In4.Cu")
		(net "M_E_DQS_DP<0>")
	)
	(segment
		(start 200.70572 -127.951992)
		(end 201.820272 -129.066544)
		(width 0.14224)
		(layer "In4.Cu")
		(net "M_E_DQS_DP<0>")
	)
	(segment
		(start 201.820272 -139.76858)
		(end 201.047096 -140.541756)
		(width 0.14224)
		(layer "In4.Cu")
		(net "M_E_DQS_DP<0>")
	)
	(segment
		(start 201.037952 -140.541756)
		(end 201.4728 -140.976604)
		(width 0.14224)
		(layer "In4.Cu")
		(net "M_E_DQS_DP<0>")
	)
	(segment
		(start 202.33132 -121.738898)
		(end 202.33132 -122.393964)
		(width 0.14224)
		(layer "In4.Cu")
		(net "M_E_DQS_DP<0>")
	)
	(segment
		(start 201.040492 -142.72006)
		(end 200.86066 -142.899892)
		(width 0.14224)
		(layer "In4.Cu")
		(net "M_E_DQS_DP<0>")
	)
	(segment
		(start 200.800462 -142.899892)
		(end 200.663302 -143.037052)
		(width 0.14224)
		(layer "In4.Cu")
		(net "M_E_DQS_DP<0>")
	)
	(segment
		(start 231.251506 -85.89899)
		(end 231.162352 -85.809836)
		(width 0.0889)
		(layer "In4.Cu")
		(net "M_E_DQS_DP<0>")
	)
	(segment
		(start 201.028808 -121.360692)
		(end 201.953114 -121.360692)
		(width 0.14224)
		(layer "In4.Cu")
		(net "M_E_DQS_DP<0>")
	)
	(segment
		(start 200.663302 -143.263366)
		(end 200.859136 -143.4592)
		(width 0.14224)
		(layer "In4.Cu")
		(net "M_E_DQS_DP<0>")
	)
	(segment
		(start 200.80732 -120.70842)
		(end 200.80732 -121.139204)
		(width 0.14224)
		(layer "In4.Cu")
		(net "M_E_DQS_DP<0>")
	)
	(segment
		(start 200.8632 -142.2654)
		(end 201.040492 -142.442692)
		(width 0.14224)
		(layer "In4.Cu")
		(net "M_E_DQS_DP<0>")
	)
	(segment
		(start 200.70572 -125.412246)
		(end 200.70572 -127.951992)
		(width 0.14224)
		(layer "In4.Cu")
		(net "M_E_DQS_DP<0>")
	)
	(segment
		(start 204.114146 -113.936526)
		(end 204.114146 -114.775742)
		(width 0.14224)
		(layer "In4.Cu")
		(net "M_E_DQS_DP<0>")
	)
	(segment
		(start 235.892594 -84.721192)
		(end 235.505752 -84.716366)
		(width 0.0889)
		(layer "In4.Cu")
		(net "M_E_DQS_DP<0>")
	)
	(segment
		(start 201.578464 -118.188232)
		(end 202.33132 -118.941088)
		(width 0.14224)
		(layer "In4.Cu")
		(net "M_E_DQS_DP<0>")
	)
	(arc
		(start 234.406948 -84.612988)
		(mid 234.19834 -84.82492)
		(end 233.912918 -84.90839)
		(width 0.0889)
		(layer "In4.Cu")
		(net "M_E_DQS_DP<0>")
	)
	(arc
		(start 233.548428 -85.108288)
		(mid 233.341424 -85.319152)
		(end 233.058208 -85.403436)
		(width 0.0889)
		(layer "In4.Cu")
		(net "M_E_DQS_DP<0>")
	)
	(arc
		(start 232.689908 -85.603588)
		(mid 232.482824 -85.814606)
		(end 232.199434 -85.89899)
		(width 0.0889)
		(layer "In4.Cu")
		(net "M_E_DQS_DP<0>")
	)
	(arc
		(start 233.880152 -84.90839)
		(mid 233.68851 -84.965556)
		(end 233.548428 -85.108288)
		(width 0.0889)
		(layer "In4.Cu")
		(net "M_E_DQS_DP<0>")
	)
	(arc
		(start 233.02214 -85.403436)
		(mid 232.830123 -85.460544)
		(end 232.689908 -85.603588)
		(width 0.0889)
		(layer "In4.Cu")
		(net "M_E_DQS_DP<0>")
	)
	(arc
		(start 234.742482 -84.412836)
		(mid 234.548632 -84.469186)
		(end 234.406948 -84.612988)
		(width 0.0889)
		(layer "In4.Cu")
		(net "M_E_DQS_DP<0>")
	)
	(segment
		(start 200.417684 -144.602962)
		(end 200.165716 -144.85493)
		(width 0.1651)
		(layer "F.Cu")
		(net "M_E_DQS_DN<9>")
	)
	(segment
		(start 200.650348 -142.6718)
		(end 200.64984 -142.677642)
		(width 0.1651)
		(layer "F.Cu")
		(net "M_E_DQS_DN<9>")
	)
	(segment
		(start 200.417684 -144.356328)
		(end 200.417684 -144.602962)
		(width 0.1651)
		(layer "F.Cu")
		(net "M_E_DQS_DN<9>")
	)
	(segment
		(start 199.957436 -144.85493)
		(end 199.768206 -144.6657)
		(width 0.1651)
		(layer "F.Cu")
		(net "M_E_DQS_DN<9>")
	)
	(segment
		(start 200.231756 -144.1704)
		(end 200.417684 -144.356328)
		(width 0.1651)
		(layer "F.Cu")
		(net "M_E_DQS_DN<9>")
	)
	(segment
		(start 200.64984 -142.677642)
		(end 200.64984 -143.331184)
		(width 0.1651)
		(layer "F.Cu")
		(net "M_E_DQS_DN<9>")
	)
	(segment
		(start 199.768206 -144.6657)
		(end 199.749156 -144.6657)
		(width 0.1651)
		(layer "F.Cu")
		(net "M_E_DQS_DN<9>")
	)
	(segment
		(start 200.231756 -143.749268)
		(end 200.231756 -144.1704)
		(width 0.1651)
		(layer "F.Cu")
		(net "M_E_DQS_DN<9>")
	)
	(segment
		(start 237.900718 -85.30844)
		(end 237.329218 -85.30844)
		(width 0.1651)
		(layer "F.Cu")
		(net "M_E_DQS_DN<9>")
	)
	(segment
		(start 200.165716 -144.85493)
		(end 199.957436 -144.85493)
		(width 0.1651)
		(layer "F.Cu")
		(net "M_E_DQS_DN<9>")
	)
	(segment
		(start 200.64984 -143.331184)
		(end 200.231756 -143.749268)
		(width 0.1651)
		(layer "F.Cu")
		(net "M_E_DQS_DN<9>")
	)
	(via
		(at 199.749156 -144.6657)
		(size 0.508)
		(drill 0.254)
		(layers "F.Cu" "B.Cu")
		(net "M_E_DQS_DN<9>")
	)
	(via
		(at 199.742552 -140.4874)
		(size 0.508)
		(drill 0.254)
		(layers "F.Cu" "B.Cu")
		(net "M_E_DQS_DN<9>")
	)
	(via
		(at 237.329218 -85.30844)
		(size 0.508)
		(drill 0.254)
		(layers "F.Cu" "B.Cu")
		(net "M_E_DQS_DN<9>")
	)
	(segment
		(start 200.650094 -141.820392)
		(end 200.650094 -142.476728)
		(width 0.1651)
		(layer "B.Cu")
		(net "M_E_DQS_DN<9>")
	)
	(segment
		(start 199.742552 -140.4874)
		(end 199.937116 -140.292836)
		(width 0.1651)
		(layer "B.Cu")
		(net "M_E_DQS_DN<9>")
	)
	(segment
		(start 200.650094 -142.476728)
		(end 200.650348 -142.477236)
		(width 0.1651)
		(layer "B.Cu")
		(net "M_E_DQS_DN<9>")
	)
	(segment
		(start 200.384156 -140.843)
		(end 200.206356 -141.0208)
		(width 0.1651)
		(layer "B.Cu")
		(net "M_E_DQS_DN<9>")
	)
	(segment
		(start 200.384156 -140.5128)
		(end 200.384156 -140.843)
		(width 0.1651)
		(layer "B.Cu")
		(net "M_E_DQS_DN<9>")
	)
	(segment
		(start 200.206356 -141.0208)
		(end 200.206356 -141.376654)
		(width 0.1651)
		(layer "B.Cu")
		(net "M_E_DQS_DN<9>")
	)
	(segment
		(start 200.164192 -140.292836)
		(end 200.384156 -140.5128)
		(width 0.1651)
		(layer "B.Cu")
		(net "M_E_DQS_DN<9>")
	)
	(segment
		(start 199.937116 -140.292836)
		(end 200.164192 -140.292836)
		(width 0.1651)
		(layer "B.Cu")
		(net "M_E_DQS_DN<9>")
	)
	(segment
		(start 200.206356 -141.376654)
		(end 200.650094 -141.820392)
		(width 0.1651)
		(layer "B.Cu")
		(net "M_E_DQS_DN<9>")
	)
	(segment
		(start 199.6694 -143.5608)
		(end 199.99452 -143.5608)
		(width 0.14224)
		(layer "In4.Cu")
		(net "M_E_DQS_DN<9>")
	)
	(segment
		(start 233.058208 -84.412836)
		(end 232.870248 -84.412836)
		(width 0.0889)
		(layer "In4.Cu")
		(net "M_E_DQS_DN<9>")
	)
	(segment
		(start 234.771692 -83.42249)
		(end 234.735624 -83.42249)
		(width 0.0889)
		(layer "In4.Cu")
		(net "M_E_DQS_DN<9>")
	)
	(segment
		(start 220.619574 -97.210372)
		(end 208.660746 -109.1692)
		(width 0.14224)
		(layer "In4.Cu")
		(net "M_E_DQS_DN<9>")
	)
	(segment
		(start 199.50684 -142.10284)
		(end 199.63892 -142.23492)
		(width 0.14224)
		(layer "In4.Cu")
		(net "M_E_DQS_DN<9>")
	)
	(segment
		(start 200.524872 -138.31824)
		(end 200.682352 -138.47572)
		(width 0.14224)
		(layer "In4.Cu")
		(net "M_E_DQS_DN<9>")
	)
	(segment
		(start 200.524872 -138.8872)
		(end 200.524872 -139.712446)
		(width 0.14224)
		(layer "In4.Cu")
		(net "M_E_DQS_DN<9>")
	)
	(segment
		(start 231.617266 -84.79155)
		(end 231.23017 -84.79155)
		(width 0.0889)
		(layer "In4.Cu")
		(net "M_E_DQS_DN<9>")
	)
	(segment
		(start 199.63892 -142.23492)
		(end 199.79386 -142.23492)
		(width 0.14224)
		(layer "In4.Cu")
		(net "M_E_DQS_DN<9>")
	)
	(segment
		(start 200.531222 -118.339616)
		(end 200.909428 -118.717822)
		(width 0.14224)
		(layer "In4.Cu")
		(net "M_E_DQS_DN<9>")
	)
	(segment
		(start 200.909428 -118.717822)
		(end 200.909428 -119.37365)
		(width 0.14224)
		(layer "In4.Cu")
		(net "M_E_DQS_DN<9>")
	)
	(segment
		(start 231.1908 -84.83092)
		(end 231.168702 -84.83092)
		(width 0.0889)
		(layer "In4.Cu")
		(net "M_E_DQS_DN<9>")
	)
	(segment
		(start 200.682352 -138.47572)
		(end 200.682352 -138.72972)
		(width 0.14224)
		(layer "In4.Cu")
		(net "M_E_DQS_DN<9>")
	)
	(segment
		(start 199.99452 -143.5608)
		(end 200.182226 -143.748506)
		(width 0.14224)
		(layer "In4.Cu")
		(net "M_E_DQS_DN<9>")
	)
	(segment
		(start 237.622334 -85.47735)
		(end 237.701074 -85.456014)
		(width 0.0889)
		(layer "In4.Cu")
		(net "M_E_DQS_DN<9>")
	)
	(segment
		(start 232.675684 -84.588096)
		(end 232.653586 -84.610194)
		(width 0.0889)
		(layer "In4.Cu")
		(net "M_E_DQS_DN<9>")
	)
	(segment
		(start 199.50684 -143.39824)
		(end 199.6694 -143.5608)
		(width 0.14224)
		(layer "In4.Cu")
		(net "M_E_DQS_DN<9>")
	)
	(segment
		(start 236.481874 -84.412836)
		(end 236.449108 -84.412836)
		(width 0.0889)
		(layer "In4.Cu")
		(net "M_E_DQS_DN<9>")
	)
	(segment
		(start 200.909428 -119.37365)
		(end 200.531222 -119.751856)
		(width 0.14224)
		(layer "In4.Cu")
		(net "M_E_DQS_DN<9>")
	)
	(segment
		(start 200.531222 -119.751856)
		(end 199.936608 -119.751856)
		(width 0.14224)
		(layer "In4.Cu")
		(net "M_E_DQS_DN<9>")
	)
	(segment
		(start 199.71512 -118.172992)
		(end 199.881744 -118.339616)
		(width 0.14224)
		(layer "In4.Cu")
		(net "M_E_DQS_DN<9>")
	)
	(segment
		(start 203.136246 -113.543588)
		(end 203.136246 -114.371882)
		(width 0.14224)
		(layer "In4.Cu")
		(net "M_E_DQS_DN<9>")
	)
	(segment
		(start 199.50684 -141.75486)
		(end 199.50684 -142.10284)
		(width 0.14224)
		(layer "In4.Cu")
		(net "M_E_DQS_DN<9>")
	)
	(segment
		(start 199.9488 -142.38986)
		(end 199.9488 -142.74292)
		(width 0.14224)
		(layer "In4.Cu")
		(net "M_E_DQS_DN<9>")
	)
	(segment
		(start 199.898 -141.605)
		(end 199.6567 -141.605)
		(width 0.14224)
		(layer "In4.Cu")
		(net "M_E_DQS_DN<9>")
	)
	(segment
		(start 203.136246 -114.371882)
		(end 199.71512 -117.793008)
		(width 0.14224)
		(layer "In4.Cu")
		(net "M_E_DQS_DN<9>")
	)
	(segment
		(start 199.742552 -140.4874)
		(end 200.1774 -140.922248)
		(width 0.14224)
		(layer "In4.Cu")
		(net "M_E_DQS_DN<9>")
	)
	(segment
		(start 207.510634 -109.1692)
		(end 203.136246 -113.543588)
		(width 0.14224)
		(layer "In4.Cu")
		(net "M_E_DQS_DN<9>")
	)
	(segment
		(start 232.30459 -84.90839)
		(end 231.734106 -84.90839)
		(width 0.0889)
		(layer "In4.Cu")
		(net "M_E_DQS_DN<9>")
	)
	(segment
		(start 199.71512 -119.973344)
		(end 199.71512 -128.48463)
		(width 0.14224)
		(layer "In4.Cu")
		(net "M_E_DQS_DN<9>")
	)
	(segment
		(start 235.627164 -83.91779)
		(end 235.594398 -83.91779)
		(width 0.0889)
		(layer "In4.Cu")
		(net "M_E_DQS_DN<9>")
	)
	(segment
		(start 200.1774 -140.922248)
		(end 200.1774 -141.3256)
		(width 0.14224)
		(layer "In4.Cu")
		(net "M_E_DQS_DN<9>")
	)
	(segment
		(start 199.6567 -141.605)
		(end 199.50684 -141.75486)
		(width 0.14224)
		(layer "In4.Cu")
		(net "M_E_DQS_DN<9>")
	)
	(segment
		(start 199.64654 -142.89786)
		(end 199.50684 -143.03756)
		(width 0.14224)
		(layer "In4.Cu")
		(net "M_E_DQS_DN<9>")
	)
	(segment
		(start 231.168702 -84.83092)
		(end 229.05466 -84.83092)
		(width 0.14224)
		(layer "In4.Cu")
		(net "M_E_DQS_DN<9>")
	)
	(segment
		(start 200.182226 -144.23263)
		(end 199.749156 -144.6657)
		(width 0.14224)
		(layer "In4.Cu")
		(net "M_E_DQS_DN<9>")
	)
	(segment
		(start 237.344204 -84.90839)
		(end 237.311438 -84.90839)
		(width 0.0889)
		(layer "In4.Cu")
		(net "M_E_DQS_DN<9>")
	)
	(segment
		(start 200.524872 -139.712446)
		(end 199.749918 -140.4874)
		(width 0.14224)
		(layer "In4.Cu")
		(net "M_E_DQS_DN<9>")
	)
	(segment
		(start 237.329218 -85.30844)
		(end 237.622334 -85.47735)
		(width 0.0889)
		(layer "In4.Cu")
		(net "M_E_DQS_DN<9>")
	)
	(segment
		(start 199.71512 -128.48463)
		(end 200.524872 -129.294382)
		(width 0.14224)
		(layer "In4.Cu")
		(net "M_E_DQS_DN<9>")
	)
	(segment
		(start 199.50684 -143.03756)
		(end 199.50684 -143.39824)
		(width 0.14224)
		(layer "In4.Cu")
		(net "M_E_DQS_DN<9>")
	)
	(segment
		(start 200.524872 -129.294382)
		(end 200.524872 -137.532364)
		(width 0.14224)
		(layer "In4.Cu")
		(net "M_E_DQS_DN<9>")
	)
	(segment
		(start 200.524872 -137.532364)
		(end 200.645268 -137.65276)
		(width 0.14224)
		(layer "In4.Cu")
		(net "M_E_DQS_DN<9>")
	)
	(segment
		(start 200.1774 -141.3256)
		(end 199.898 -141.605)
		(width 0.14224)
		(layer "In4.Cu")
		(net "M_E_DQS_DN<9>")
	)
	(segment
		(start 229.05466 -84.83092)
		(end 220.619574 -93.266006)
		(width 0.14224)
		(layer "In4.Cu")
		(net "M_E_DQS_DN<9>")
	)
	(segment
		(start 200.182226 -143.748506)
		(end 200.182226 -144.23263)
		(width 0.14224)
		(layer "In4.Cu")
		(net "M_E_DQS_DN<9>")
	)
	(segment
		(start 200.645268 -137.90676)
		(end 200.524872 -138.027156)
		(width 0.14224)
		(layer "In4.Cu")
		(net "M_E_DQS_DN<9>")
	)
	(segment
		(start 220.619574 -93.266006)
		(end 220.619574 -97.210372)
		(width 0.14224)
		(layer "In4.Cu")
		(net "M_E_DQS_DN<9>")
	)
	(segment
		(start 199.936608 -119.751856)
		(end 199.71512 -119.973344)
		(width 0.14224)
		(layer "In4.Cu")
		(net "M_E_DQS_DN<9>")
	)
	(segment
		(start 233.912918 -83.91779)
		(end 233.880152 -83.91779)
		(width 0.0889)
		(layer "In4.Cu")
		(net "M_E_DQS_DN<9>")
	)
	(segment
		(start 208.660746 -109.1692)
		(end 207.510634 -109.1692)
		(width 0.14224)
		(layer "In4.Cu")
		(net "M_E_DQS_DN<9>")
	)
	(segment
		(start 200.645268 -137.65276)
		(end 200.645268 -137.90676)
		(width 0.14224)
		(layer "In4.Cu")
		(net "M_E_DQS_DN<9>")
	)
	(segment
		(start 199.881744 -118.339616)
		(end 200.531222 -118.339616)
		(width 0.14224)
		(layer "In4.Cu")
		(net "M_E_DQS_DN<9>")
	)
	(segment
		(start 232.675684 -84.57311)
		(end 232.675684 -84.588096)
		(width 0.0889)
		(layer "In4.Cu")
		(net "M_E_DQS_DN<9>")
	)
	(segment
		(start 200.524872 -138.027156)
		(end 200.524872 -138.31824)
		(width 0.14224)
		(layer "In4.Cu")
		(net "M_E_DQS_DN<9>")
	)
	(segment
		(start 199.9488 -142.74292)
		(end 199.79386 -142.89786)
		(width 0.14224)
		(layer "In4.Cu")
		(net "M_E_DQS_DN<9>")
	)
	(segment
		(start 199.79386 -142.89786)
		(end 199.64654 -142.89786)
		(width 0.14224)
		(layer "In4.Cu")
		(net "M_E_DQS_DN<9>")
	)
	(segment
		(start 199.71512 -117.793008)
		(end 199.71512 -118.172992)
		(width 0.14224)
		(layer "In4.Cu")
		(net "M_E_DQS_DN<9>")
	)
	(segment
		(start 231.23017 -84.79155)
		(end 231.1908 -84.83092)
		(width 0.0889)
		(layer "In4.Cu")
		(net "M_E_DQS_DN<9>")
	)
	(segment
		(start 200.682352 -138.72972)
		(end 200.524872 -138.8872)
		(width 0.14224)
		(layer "In4.Cu")
		(net "M_E_DQS_DN<9>")
	)
	(segment
		(start 231.734106 -84.90839)
		(end 231.617266 -84.79155)
		(width 0.0889)
		(layer "In4.Cu")
		(net "M_E_DQS_DN<9>")
	)
	(segment
		(start 199.749918 -140.4874)
		(end 199.742552 -140.4874)
		(width 0.14224)
		(layer "In4.Cu")
		(net "M_E_DQS_DN<9>")
	)
	(segment
		(start 199.79386 -142.23492)
		(end 199.9488 -142.38986)
		(width 0.14224)
		(layer "In4.Cu")
		(net "M_E_DQS_DN<9>")
	)
	(arc
		(start 237.311438 -84.90839)
		(mid 237.026014 -84.824923)
		(end 236.817408 -84.612988)
		(width 0.0889)
		(layer "In4.Cu")
		(net "M_E_DQS_DN<9>")
	)
	(arc
		(start 233.548428 -84.117688)
		(mid 233.341424 -84.328552)
		(end 233.058208 -84.412836)
		(width 0.0889)
		(layer "In4.Cu")
		(net "M_E_DQS_DN<9>")
	)
	(arc
		(start 235.594398 -83.91779)
		(mid 235.308974 -83.834323)
		(end 235.100368 -83.622388)
		(width 0.0889)
		(layer "In4.Cu")
		(net "M_E_DQS_DN<9>")
	)
	(arc
		(start 232.653586 -84.610194)
		(mid 232.507486 -84.792528)
		(end 232.30459 -84.90839)
		(width 0.0889)
		(layer "In4.Cu")
		(net "M_E_DQS_DN<9>")
	)
	(arc
		(start 237.701074 -85.456014)
		(mid 237.664334 -85.089875)
		(end 237.344204 -84.90839)
		(width 0.0889)
		(layer "In4.Cu")
		(net "M_E_DQS_DN<9>")
	)
	(arc
		(start 235.958888 -84.117688)
		(mid 235.818809 -83.974952)
		(end 235.627164 -83.91779)
		(width 0.0889)
		(layer "In4.Cu")
		(net "M_E_DQS_DN<9>")
	)
	(arc
		(start 236.449108 -84.412836)
		(mid 236.165891 -84.328555)
		(end 235.958888 -84.117688)
		(width 0.0889)
		(layer "In4.Cu")
		(net "M_E_DQS_DN<9>")
	)
	(arc
		(start 232.870248 -84.412836)
		(mid 232.761073 -84.47853)
		(end 232.675684 -84.57311)
		(width 0.0889)
		(layer "In4.Cu")
		(net "M_E_DQS_DN<9>")
	)
	(arc
		(start 234.406948 -83.622388)
		(mid 234.19834 -83.83432)
		(end 233.912918 -83.91779)
		(width 0.0889)
		(layer "In4.Cu")
		(net "M_E_DQS_DN<9>")
	)
	(arc
		(start 233.880152 -83.91779)
		(mid 233.68851 -83.974956)
		(end 233.548428 -84.117688)
		(width 0.0889)
		(layer "In4.Cu")
		(net "M_E_DQS_DN<9>")
	)
	(arc
		(start 234.735624 -83.42249)
		(mid 234.545695 -83.48036)
		(end 234.406948 -83.622388)
		(width 0.0889)
		(layer "In4.Cu")
		(net "M_E_DQS_DN<9>")
	)
	(arc
		(start 236.817408 -84.612988)
		(mid 236.675725 -84.469184)
		(end 236.481874 -84.412836)
		(width 0.0889)
		(layer "In4.Cu")
		(net "M_E_DQS_DN<9>")
	)
	(arc
		(start 235.100368 -83.622388)
		(mid 234.961624 -83.480355)
		(end 234.771692 -83.42249)
		(width 0.0889)
		(layer "In4.Cu")
		(net "M_E_DQS_DN<9>")
	)
	(segment
		(start 238.8489 -121.909586)
		(end 238.943896 -122.004582)
		(width 0.1651)
		(layer "F.Cu")
		(net "M_E_DQS_DN<8>")
	)
	(segment
		(start 239.795812 -112.59185)
		(end 239.795812 -112.785906)
		(width 0.1651)
		(layer "F.Cu")
		(net "M_E_DQS_DN<8>")
	)
	(segment
		(start 242.991132 -109.590586)
		(end 242.796822 -109.590586)
		(width 0.1651)
		(layer "F.Cu")
		(net "M_E_DQS_DN<8>")
	)
	(segment
		(start 238.816896 -123.1646)
		(end 238.816896 -123.4186)
		(width 0.1651)
		(layer "F.Cu")
		(net "M_E_DQS_DN<8>")
	)
	(segment
		(start 238.978948 -119.387366)
		(end 238.642906 -119.723408)
		(width 0.1651)
		(layer "F.Cu")
		(net "M_E_DQS_DN<8>")
	)
	(segment
		(start 237.6678 -145.389854)
		(end 237.998254 -145.0594)
		(width 0.1651)
		(layer "F.Cu")
		(net "M_E_DQS_DN<8>")
	)
	(segment
		(start 239.616234 -115.34013)
		(end 239.616234 -115.59413)
		(width 0.1651)
		(layer "F.Cu")
		(net "M_E_DQS_DN<8>")
	)
	(segment
		(start 242.188238 -110.199424)
		(end 242.00866 -110.379002)
		(width 0.1651)
		(layer "F.Cu")
		(net "M_E_DQS_DN<8>")
	)
	(segment
		(start 238.222282 -145.0594)
		(end 238.437928 -145.275046)
		(width 0.1651)
		(layer "F.Cu")
		(net "M_E_DQS_DN<8>")
	)
	(segment
		(start 238.943896 -123.5456)
		(end 238.943896 -123.7996)
		(width 0.1651)
		(layer "F.Cu")
		(net "M_E_DQS_DN<8>")
	)
	(segment
		(start 239.616234 -116.98605)
		(end 239.616234 -117.242082)
		(width 0.1651)
		(layer "F.Cu")
		(net "M_E_DQS_DN<8>")
	)
	(segment
		(start 238.68507 -125.309376)
		(end 238.437928 -125.309376)
		(width 0.1651)
		(layer "F.Cu")
		(net "M_E_DQS_DN<8>")
	)
	(segment
		(start 240.722658 -111.85906)
		(end 240.528602 -111.85906)
		(width 0.1651)
		(layer "F.Cu")
		(net "M_E_DQS_DN<8>")
	)
	(segment
		(start 238.816896 -122.6566)
		(end 238.943896 -122.7836)
		(width 0.1651)
		(layer "F.Cu")
		(net "M_E_DQS_DN<8>")
	)
	(segment
		(start 239.458754 -114.10569)
		(end 239.458754 -114.35969)
		(width 0.1651)
		(layer "F.Cu")
		(net "M_E_DQS_DN<8>")
	)
	(segment
		(start 238.050324 -147.27174)
		(end 238.049816 -147.27174)
		(width 0.1651)
		(layer "F.Cu")
		(net "M_E_DQS_DN<8>")
	)
	(segment
		(start 238.816896 -124.1806)
		(end 238.943896 -124.3076)
		(width 0.1651)
		(layer "F.Cu")
		(net "M_E_DQS_DN<8>")
	)
	(segment
		(start 239.458754 -114.35969)
		(end 239.616234 -114.51717)
		(width 0.1651)
		(layer "F.Cu")
		(net "M_E_DQS_DN<8>")
	)
	(segment
		(start 239.458754 -116.57457)
		(end 239.458754 -116.82857)
		(width 0.1651)
		(layer "F.Cu")
		(net "M_E_DQS_DN<8>")
	)
	(segment
		(start 238.943896 -122.2756)
		(end 238.816896 -122.4026)
		(width 0.1651)
		(layer "F.Cu")
		(net "M_E_DQS_DN<8>")
	)
	(segment
		(start 239.616234 -112.965484)
		(end 239.616234 -113.201958)
		(width 0.1651)
		(layer "F.Cu")
		(net "M_E_DQS_DN<8>")
	)
	(segment
		(start 248.350024 -104.105202)
		(end 248.350024 -104.607106)
		(width 0.1016)
		(layer "F.Cu")
		(net "M_E_DQS_DN<8>")
	)
	(segment
		(start 239.458754 -114.92865)
		(end 239.458754 -115.18265)
		(width 0.1651)
		(layer "F.Cu")
		(net "M_E_DQS_DN<8>")
	)
	(segment
		(start 239.4712 -119.387366)
		(end 238.978948 -119.387366)
		(width 0.1651)
		(layer "F.Cu")
		(net "M_E_DQS_DN<8>")
	)
	(segment
		(start 239.011206 -117.408452)
		(end 238.660432 -117.759226)
		(width 0.1651)
		(layer "F.Cu")
		(net "M_E_DQS_DN<8>")
	)
	(segment
		(start 249.061224 -99.67214)
		(end 249.038364 -99.695)
		(width 0.0889)
		(layer "F.Cu")
		(net "M_E_DQS_DN<8>")
	)
	(segment
		(start 239.97539 -112.412272)
		(end 239.795812 -112.59185)
		(width 0.1651)
		(layer "F.Cu")
		(net "M_E_DQS_DN<8>")
	)
	(segment
		(start 238.943896 -122.7836)
		(end 238.943896 -123.0376)
		(width 0.1651)
		(layer "F.Cu")
		(net "M_E_DQS_DN<8>")
	)
	(segment
		(start 242.00866 -110.379002)
		(end 242.00866 -110.573058)
		(width 0.1651)
		(layer "F.Cu")
		(net "M_E_DQS_DN<8>")
	)
	(segment
		(start 242.796822 -109.590586)
		(end 242.617244 -109.770164)
		(width 0.1651)
		(layer "F.Cu")
		(net "M_E_DQS_DN<8>")
	)
	(segment
		(start 239.4712 -118.726966)
		(end 239.6363 -118.892066)
		(width 0.1651)
		(layer "F.Cu")
		(net "M_E_DQS_DN<8>")
	)
	(segment
		(start 238.943896 -120.596914)
		(end 238.943896 -121.503694)
		(width 0.1651)
		(layer "F.Cu")
		(net "M_E_DQS_DN<8>")
	)
	(segment
		(start 239.6363 -119.222266)
		(end 239.4712 -119.387366)
		(width 0.1651)
		(layer "F.Cu")
		(net "M_E_DQS_DN<8>")
	)
	(segment
		(start 248.350024 -104.607106)
		(end 244.242336 -108.714794)
		(width 0.1016)
		(layer "F.Cu")
		(net "M_E_DQS_DN<8>")
	)
	(segment
		(start 238.049816 -146.20367)
		(end 237.6678 -145.821654)
		(width 0.1651)
		(layer "F.Cu")
		(net "M_E_DQS_DN<8>")
	)
	(segment
		(start 239.795812 -112.785906)
		(end 239.616234 -112.965484)
		(width 0.1651)
		(layer "F.Cu")
		(net "M_E_DQS_DN<8>")
	)
	(segment
		(start 249.038364 -103.416862)
		(end 248.350024 -104.105202)
		(width 0.1016)
		(layer "F.Cu")
		(net "M_E_DQS_DN<8>")
	)
	(segment
		(start 240.169446 -112.412272)
		(end 239.97539 -112.412272)
		(width 0.1651)
		(layer "F.Cu")
		(net "M_E_DQS_DN<8>")
	)
	(segment
		(start 238.943896 -123.7996)
		(end 238.816896 -123.9266)
		(width 0.1651)
		(layer "F.Cu")
		(net "M_E_DQS_DN<8>")
	)
	(segment
		(start 239.616234 -113.674906)
		(end 239.616234 -113.94821)
		(width 0.1651)
		(layer "F.Cu")
		(net "M_E_DQS_DN<8>")
	)
	(segment
		(start 239.449864 -117.408452)
		(end 239.011206 -117.408452)
		(width 0.1651)
		(layer "F.Cu")
		(net "M_E_DQS_DN<8>")
	)
	(segment
		(start 241.829082 -110.752636)
		(end 241.635026 -110.752636)
		(width 0.1651)
		(layer "F.Cu")
		(net "M_E_DQS_DN<8>")
	)
	(segment
		(start 238.642906 -119.723408)
		(end 238.642906 -120.295924)
		(width 0.1651)
		(layer "F.Cu")
		(net "M_E_DQS_DN<8>")
	)
	(segment
		(start 240.902236 -111.485426)
		(end 240.902236 -111.679482)
		(width 0.1651)
		(layer "F.Cu")
		(net "M_E_DQS_DN<8>")
	)
	(segment
		(start 238.943896 -121.503694)
		(end 238.8489 -121.59869)
		(width 0.1651)
		(layer "F.Cu")
		(net "M_E_DQS_DN<8>")
	)
	(segment
		(start 243.866924 -108.714794)
		(end 243.447316 -109.134402)
		(width 0.1016)
		(layer "F.Cu")
		(net "M_E_DQS_DN<8>")
	)
	(segment
		(start 239.00765 -118.726966)
		(end 239.4712 -118.726966)
		(width 0.1651)
		(layer "F.Cu")
		(net "M_E_DQS_DN<8>")
	)
	(segment
		(start 240.349024 -112.232694)
		(end 240.169446 -112.412272)
		(width 0.1651)
		(layer "F.Cu")
		(net "M_E_DQS_DN<8>")
	)
	(segment
		(start 239.458754 -115.18265)
		(end 239.616234 -115.34013)
		(width 0.1651)
		(layer "F.Cu")
		(net "M_E_DQS_DN<8>")
	)
	(segment
		(start 238.642906 -120.295924)
		(end 238.943896 -120.596914)
		(width 0.1651)
		(layer "F.Cu")
		(net "M_E_DQS_DN<8>")
	)
	(segment
		(start 238.943896 -125.05055)
		(end 238.68507 -125.309376)
		(width 0.1651)
		(layer "F.Cu")
		(net "M_E_DQS_DN<8>")
	)
	(segment
		(start 239.616234 -116.16309)
		(end 239.616234 -116.41709)
		(width 0.1651)
		(layer "F.Cu")
		(net "M_E_DQS_DN<8>")
	)
	(segment
		(start 238.660432 -117.759226)
		(end 238.660432 -118.379748)
		(width 0.1651)
		(layer "F.Cu")
		(net "M_E_DQS_DN<8>")
	)
	(segment
		(start 239.616234 -117.242082)
		(end 239.449864 -117.408452)
		(width 0.1651)
		(layer "F.Cu")
		(net "M_E_DQS_DN<8>")
	)
	(segment
		(start 238.816896 -122.4026)
		(end 238.816896 -122.6566)
		(width 0.1651)
		(layer "F.Cu")
		(net "M_E_DQS_DN<8>")
	)
	(segment
		(start 249.038364 -100.492814)
		(end 249.038364 -103.416862)
		(width 0.1016)
		(layer "F.Cu")
		(net "M_E_DQS_DN<8>")
	)
	(segment
		(start 238.943896 -123.0376)
		(end 238.816896 -123.1646)
		(width 0.1651)
		(layer "F.Cu")
		(net "M_E_DQS_DN<8>")
	)
	(segment
		(start 244.242336 -108.714794)
		(end 243.866924 -108.714794)
		(width 0.1016)
		(layer "F.Cu")
		(net "M_E_DQS_DN<8>")
	)
	(segment
		(start 240.902236 -111.679482)
		(end 240.722658 -111.85906)
		(width 0.1651)
		(layer "F.Cu")
		(net "M_E_DQS_DN<8>")
	)
	(segment
		(start 239.458754 -116.82857)
		(end 239.616234 -116.98605)
		(width 0.1651)
		(layer "F.Cu")
		(net "M_E_DQS_DN<8>")
	)
	(segment
		(start 238.816896 -123.9266)
		(end 238.816896 -124.1806)
		(width 0.1651)
		(layer "F.Cu")
		(net "M_E_DQS_DN<8>")
	)
	(segment
		(start 243.447316 -109.134402)
		(end 242.991132 -109.590586)
		(width 0.1651)
		(layer "F.Cu")
		(net "M_E_DQS_DN<8>")
	)
	(segment
		(start 239.616234 -114.77117)
		(end 239.458754 -114.92865)
		(width 0.1651)
		(layer "F.Cu")
		(net "M_E_DQS_DN<8>")
	)
	(segment
		(start 242.617244 -109.770164)
		(end 242.617244 -109.964474)
		(width 0.1651)
		(layer "F.Cu")
		(net "M_E_DQS_DN<8>")
	)
	(segment
		(start 238.943896 -122.004582)
		(end 238.943896 -122.2756)
		(width 0.1651)
		(layer "F.Cu")
		(net "M_E_DQS_DN<8>")
	)
	(segment
		(start 241.635026 -110.752636)
		(end 241.455448 -110.932214)
		(width 0.1651)
		(layer "F.Cu")
		(net "M_E_DQS_DN<8>")
	)
	(segment
		(start 241.081814 -111.305848)
		(end 240.902236 -111.485426)
		(width 0.1651)
		(layer "F.Cu")
		(net "M_E_DQS_DN<8>")
	)
	(segment
		(start 239.616234 -114.51717)
		(end 239.616234 -114.77117)
		(width 0.1651)
		(layer "F.Cu")
		(net "M_E_DQS_DN<8>")
	)
	(segment
		(start 242.617244 -109.964474)
		(end 242.382294 -110.199424)
		(width 0.1651)
		(layer "F.Cu")
		(net "M_E_DQS_DN<8>")
	)
	(segment
		(start 239.616234 -115.59413)
		(end 239.458754 -115.75161)
		(width 0.1651)
		(layer "F.Cu")
		(net "M_E_DQS_DN<8>")
	)
	(segment
		(start 239.616234 -113.201958)
		(end 239.50676 -113.311432)
		(width 0.1651)
		(layer "F.Cu")
		(net "M_E_DQS_DN<8>")
	)
	(segment
		(start 240.349024 -112.038638)
		(end 240.349024 -112.232694)
		(width 0.1651)
		(layer "F.Cu")
		(net "M_E_DQS_DN<8>")
	)
	(segment
		(start 239.616234 -116.41709)
		(end 239.458754 -116.57457)
		(width 0.1651)
		(layer "F.Cu")
		(net "M_E_DQS_DN<8>")
	)
	(segment
		(start 238.660432 -118.379748)
		(end 239.00765 -118.726966)
		(width 0.1651)
		(layer "F.Cu")
		(net "M_E_DQS_DN<8>")
	)
	(segment
		(start 239.616234 -113.94821)
		(end 239.458754 -114.10569)
		(width 0.1651)
		(layer "F.Cu")
		(net "M_E_DQS_DN<8>")
	)
	(segment
		(start 242.00866 -110.573058)
		(end 241.829082 -110.752636)
		(width 0.1651)
		(layer "F.Cu")
		(net "M_E_DQS_DN<8>")
	)
	(segment
		(start 241.27587 -111.305848)
		(end 241.081814 -111.305848)
		(width 0.1651)
		(layer "F.Cu")
		(net "M_E_DQS_DN<8>")
	)
	(segment
		(start 239.50676 -113.565432)
		(end 239.616234 -113.674906)
		(width 0.1651)
		(layer "F.Cu")
		(net "M_E_DQS_DN<8>")
	)
	(segment
		(start 242.382294 -110.199424)
		(end 242.188238 -110.199424)
		(width 0.1651)
		(layer "F.Cu")
		(net "M_E_DQS_DN<8>")
	)
	(segment
		(start 240.528602 -111.85906)
		(end 240.349024 -112.038638)
		(width 0.1651)
		(layer "F.Cu")
		(net "M_E_DQS_DN<8>")
	)
	(segment
		(start 237.6678 -145.821654)
		(end 237.6678 -145.389854)
		(width 0.1651)
		(layer "F.Cu")
		(net "M_E_DQS_DN<8>")
	)
	(segment
		(start 239.458754 -116.00561)
		(end 239.616234 -116.16309)
		(width 0.1651)
		(layer "F.Cu")
		(net "M_E_DQS_DN<8>")
	)
	(segment
		(start 239.458754 -115.75161)
		(end 239.458754 -116.00561)
		(width 0.1651)
		(layer "F.Cu")
		(net "M_E_DQS_DN<8>")
	)
	(segment
		(start 238.816896 -123.4186)
		(end 238.943896 -123.5456)
		(width 0.1651)
		(layer "F.Cu")
		(net "M_E_DQS_DN<8>")
	)
	(segment
		(start 238.943896 -124.3076)
		(end 238.943896 -125.05055)
		(width 0.1651)
		(layer "F.Cu")
		(net "M_E_DQS_DN<8>")
	)
	(segment
		(start 238.8489 -121.59869)
		(end 238.8489 -121.909586)
		(width 0.1651)
		(layer "F.Cu")
		(net "M_E_DQS_DN<8>")
	)
	(segment
		(start 237.998254 -145.0594)
		(end 238.222282 -145.0594)
		(width 0.1651)
		(layer "F.Cu")
		(net "M_E_DQS_DN<8>")
	)
	(segment
		(start 239.6363 -118.892066)
		(end 239.6363 -119.222266)
		(width 0.1651)
		(layer "F.Cu")
		(net "M_E_DQS_DN<8>")
	)
	(segment
		(start 241.455448 -111.12627)
		(end 241.27587 -111.305848)
		(width 0.1651)
		(layer "F.Cu")
		(net "M_E_DQS_DN<8>")
	)
	(segment
		(start 239.50676 -113.311432)
		(end 239.50676 -113.565432)
		(width 0.1651)
		(layer "F.Cu")
		(net "M_E_DQS_DN<8>")
	)
	(segment
		(start 241.455448 -110.932214)
		(end 241.455448 -111.12627)
		(width 0.1651)
		(layer "F.Cu")
		(net "M_E_DQS_DN<8>")
	)
	(segment
		(start 238.049816 -147.27174)
		(end 238.049816 -146.20367)
		(width 0.1651)
		(layer "F.Cu")
		(net "M_E_DQS_DN<8>")
	)
	(segment
		(start 249.038364 -99.695)
		(end 249.038364 -100.492814)
		(width 0.0889)
		(layer "F.Cu")
		(net "M_E_DQS_DN<8>")
	)
	(via
		(at 238.437928 -125.309376)
		(size 0.508)
		(drill 0.254)
		(layers "F.Cu" "B.Cu")
		(net "M_E_DQS_DN<8>")
	)
	(via
		(at 238.437928 -145.275046)
		(size 0.508)
		(drill 0.254)
		(layers "F.Cu" "B.Cu")
		(net "M_E_DQS_DN<8>")
	)
	(via
		(at 238.437928 -139.881356)
		(size 0.508)
		(drill 0.254)
		(layers "F.Cu" "B.Cu")
		(net "M_E_DQS_DN<8>")
	)
	(segment
		(start 237.9218 -138.912346)
		(end 237.9218 -139.166346)
		(width 0.1651)
		(layer "B.Cu")
		(net "M_E_DQS_DN<8>")
	)
	(segment
		(start 238.049816 -137.877296)
		(end 238.049816 -138.78433)
		(width 0.1651)
		(layer "B.Cu")
		(net "M_E_DQS_DN<8>")
	)
	(segment
		(start 237.6678 -139.420346)
		(end 237.6678 -139.7508)
		(width 0.1651)
		(layer "B.Cu")
		(net "M_E_DQS_DN<8>")
	)
	(segment
		(start 238.0234 -140.1064)
		(end 238.212884 -140.1064)
		(width 0.1651)
		(layer "B.Cu")
		(net "M_E_DQS_DN<8>")
	)
	(segment
		(start 238.050324 -137.877296)
		(end 238.049816 -137.877296)
		(width 0.1651)
		(layer "B.Cu")
		(net "M_E_DQS_DN<8>")
	)
	(segment
		(start 237.9218 -139.166346)
		(end 237.6678 -139.420346)
		(width 0.1651)
		(layer "B.Cu")
		(net "M_E_DQS_DN<8>")
	)
	(segment
		(start 238.049816 -138.78433)
		(end 237.9218 -138.912346)
		(width 0.1651)
		(layer "B.Cu")
		(net "M_E_DQS_DN<8>")
	)
	(segment
		(start 237.6678 -139.7508)
		(end 238.0234 -140.1064)
		(width 0.1651)
		(layer "B.Cu")
		(net "M_E_DQS_DN<8>")
	)
	(segment
		(start 238.212884 -140.1064)
		(end 238.437928 -139.881356)
		(width 0.1651)
		(layer "B.Cu")
		(net "M_E_DQS_DN<8>")
	)
	(segment
		(start 238.004858 -140.241274)
		(end 238.364776 -139.881356)
		(width 0.14224)
		(layer "In9.Cu")
		(net "M_E_DQS_DN<8>")
	)
	(segment
		(start 237.794038 -141.71422)
		(end 238.004858 -141.5034)
		(width 0.14224)
		(layer "In9.Cu")
		(net "M_E_DQS_DN<8>")
	)
	(segment
		(start 238.437928 -145.275046)
		(end 238.004858 -144.841976)
		(width 0.14224)
		(layer "In9.Cu")
		(net "M_E_DQS_DN<8>")
	)
	(segment
		(start 238.364776 -139.881356)
		(end 238.437928 -139.881356)
		(width 0.14224)
		(layer "In9.Cu")
		(net "M_E_DQS_DN<8>")
	)
	(segment
		(start 237.794038 -143.37538)
		(end 237.794038 -141.71422)
		(width 0.14224)
		(layer "In9.Cu")
		(net "M_E_DQS_DN<8>")
	)
	(segment
		(start 238.004858 -143.5862)
		(end 237.794038 -143.37538)
		(width 0.14224)
		(layer "In9.Cu")
		(net "M_E_DQS_DN<8>")
	)
	(segment
		(start 238.004858 -141.5034)
		(end 238.004858 -140.241274)
		(width 0.14224)
		(layer "In9.Cu")
		(net "M_E_DQS_DN<8>")
	)
	(segment
		(start 238.004858 -144.841976)
		(end 238.004858 -143.5862)
		(width 0.14224)
		(layer "In9.Cu")
		(net "M_E_DQS_DN<8>")
	)
	(segment
		(start 238.438182 -139.881356)
		(end 238.437928 -139.881356)
		(width 0.14224)
		(layer "In11.Cu")
		(net "M_E_DQS_DN<8>")
	)
	(segment
		(start 238.7092 -137.4394)
		(end 238.7092 -138.5316)
		(width 0.14224)
		(layer "In11.Cu")
		(net "M_E_DQS_DN<8>")
	)
	(segment
		(start 238.951008 -138.773408)
		(end 238.951008 -139.36853)
		(width 0.14224)
		(layer "In11.Cu")
		(net "M_E_DQS_DN<8>")
	)
	(segment
		(start 238.7092 -138.5316)
		(end 238.951008 -138.773408)
		(width 0.14224)
		(layer "In11.Cu")
		(net "M_E_DQS_DN<8>")
	)
	(segment
		(start 238.61776 -127.54356)
		(end 238.61776 -127.759206)
		(width 0.14224)
		(layer "In11.Cu")
		(net "M_E_DQS_DN<8>")
	)
	(segment
		(start 238.43996 -132.692648)
		(end 238.43996 -133.46176)
		(width 0.14224)
		(layer "In11.Cu")
		(net "M_E_DQS_DN<8>")
	)
	(segment
		(start 238.951008 -133.972808)
		(end 238.951008 -137.197592)
		(width 0.14224)
		(layer "In11.Cu")
		(net "M_E_DQS_DN<8>")
	)
	(segment
		(start 238.951008 -132.1816)
		(end 238.43996 -132.692648)
		(width 0.14224)
		(layer "In11.Cu")
		(net "M_E_DQS_DN<8>")
	)
	(segment
		(start 237.990888 -126.916688)
		(end 238.61776 -127.54356)
		(width 0.14224)
		(layer "In11.Cu")
		(net "M_E_DQS_DN<8>")
	)
	(segment
		(start 237.990888 -125.756416)
		(end 237.990888 -126.916688)
		(width 0.14224)
		(layer "In11.Cu")
		(net "M_E_DQS_DN<8>")
	)
	(segment
		(start 238.61776 -127.759206)
		(end 238.951008 -128.092454)
		(width 0.14224)
		(layer "In11.Cu")
		(net "M_E_DQS_DN<8>")
	)
	(segment
		(start 238.437928 -125.309376)
		(end 237.990888 -125.756416)
		(width 0.14224)
		(layer "In11.Cu")
		(net "M_E_DQS_DN<8>")
	)
	(segment
		(start 238.951008 -128.092454)
		(end 238.951008 -132.1816)
		(width 0.14224)
		(layer "In11.Cu")
		(net "M_E_DQS_DN<8>")
	)
	(segment
		(start 238.951008 -137.197592)
		(end 238.7092 -137.4394)
		(width 0.14224)
		(layer "In11.Cu")
		(net "M_E_DQS_DN<8>")
	)
	(segment
		(start 238.43996 -133.46176)
		(end 238.951008 -133.972808)
		(width 0.14224)
		(layer "In11.Cu")
		(net "M_E_DQS_DN<8>")
	)
	(segment
		(start 238.951008 -139.36853)
		(end 238.438182 -139.881356)
		(width 0.14224)
		(layer "In11.Cu")
		(net "M_E_DQS_DN<8>")
	)
	(segment
		(start 312.17235 -145.0594)
		(end 312.387996 -145.275046)
		(width 0.1651)
		(layer "F.Cu")
		(net "M_E_DQS_DN<7>")
	)
	(segment
		(start 311.999884 -147.27174)
		(end 311.999884 -146.20367)
		(width 0.1651)
		(layer "F.Cu")
		(net "M_E_DQS_DN<7>")
	)
	(segment
		(start 311.948322 -145.0594)
		(end 312.17235 -145.0594)
		(width 0.1651)
		(layer "F.Cu")
		(net "M_E_DQS_DN<7>")
	)
	(segment
		(start 311.617868 -145.389854)
		(end 311.948322 -145.0594)
		(width 0.1651)
		(layer "F.Cu")
		(net "M_E_DQS_DN<7>")
	)
	(segment
		(start 311.999884 -146.20367)
		(end 311.617868 -145.821654)
		(width 0.1651)
		(layer "F.Cu")
		(net "M_E_DQS_DN<7>")
	)
	(segment
		(start 285.7881 -96.023938)
		(end 286.3596 -96.023938)
		(width 0.1651)
		(layer "F.Cu")
		(net "M_E_DQS_DN<7>")
	)
	(segment
		(start 311.617868 -145.821654)
		(end 311.617868 -145.389854)
		(width 0.1651)
		(layer "F.Cu")
		(net "M_E_DQS_DN<7>")
	)
	(segment
		(start 312.000392 -147.27174)
		(end 311.999884 -147.27174)
		(width 0.1651)
		(layer "F.Cu")
		(net "M_E_DQS_DN<7>")
	)
	(via
		(at 312.387996 -145.275046)
		(size 0.508)
		(drill 0.254)
		(layers "F.Cu" "B.Cu")
		(net "M_E_DQS_DN<7>")
	)
	(via
		(at 312.387996 -139.881356)
		(size 0.508)
		(drill 0.254)
		(layers "F.Cu" "B.Cu")
		(net "M_E_DQS_DN<7>")
	)
	(via
		(at 286.3596 -96.023938)
		(size 0.508)
		(drill 0.254)
		(layers "F.Cu" "B.Cu")
		(net "M_E_DQS_DN<7>")
	)
	(segment
		(start 312.387996 -139.881356)
		(end 312.162952 -140.1064)
		(width 0.1651)
		(layer "B.Cu")
		(net "M_E_DQS_DN<7>")
	)
	(segment
		(start 311.973468 -140.1064)
		(end 311.617868 -139.7508)
		(width 0.1651)
		(layer "B.Cu")
		(net "M_E_DQS_DN<7>")
	)
	(segment
		(start 311.617868 -139.7508)
		(end 311.617868 -139.420346)
		(width 0.1651)
		(layer "B.Cu")
		(net "M_E_DQS_DN<7>")
	)
	(segment
		(start 312.162952 -140.1064)
		(end 311.973468 -140.1064)
		(width 0.1651)
		(layer "B.Cu")
		(net "M_E_DQS_DN<7>")
	)
	(segment
		(start 311.999884 -137.877296)
		(end 312.000392 -137.877296)
		(width 0.1651)
		(layer "B.Cu")
		(net "M_E_DQS_DN<7>")
	)
	(segment
		(start 311.999884 -138.78433)
		(end 311.999884 -137.877296)
		(width 0.1651)
		(layer "B.Cu")
		(net "M_E_DQS_DN<7>")
	)
	(segment
		(start 311.617868 -139.420346)
		(end 311.871868 -139.166346)
		(width 0.1651)
		(layer "B.Cu")
		(net "M_E_DQS_DN<7>")
	)
	(segment
		(start 311.871868 -138.912346)
		(end 311.999884 -138.78433)
		(width 0.1651)
		(layer "B.Cu")
		(net "M_E_DQS_DN<7>")
	)
	(segment
		(start 311.871868 -139.166346)
		(end 311.871868 -138.912346)
		(width 0.1651)
		(layer "B.Cu")
		(net "M_E_DQS_DN<7>")
	)
	(segment
		(start 312.901076 -135.752332)
		(end 312.79084 -135.862568)
		(width 0.14224)
		(layer "In4.Cu")
		(net "M_E_DQS_DN<7>")
	)
	(segment
		(start 286.70631 -101.176836)
		(end 286.69996 -101.187504)
		(width 0.0889)
		(layer "In4.Cu")
		(net "M_E_DQS_DN<7>")
	)
	(segment
		(start 311.022492 -122.64644)
		(end 311.272428 -122.896376)
		(width 0.14224)
		(layer "In4.Cu")
		(net "M_E_DQS_DN<7>")
	)
	(segment
		(start 312.743596 -138.415014)
		(end 312.743596 -138.669014)
		(width 0.14224)
		(layer "In4.Cu")
		(net "M_E_DQS_DN<7>")
	)
	(segment
		(start 312.901076 -138.257534)
		(end 312.743596 -138.415014)
		(width 0.14224)
		(layer "In4.Cu")
		(net "M_E_DQS_DN<7>")
	)
	(segment
		(start 312.901076 -133.234938)
		(end 312.901076 -133.488938)
		(width 0.14224)
		(layer "In4.Cu")
		(net "M_E_DQS_DN<7>")
	)
	(segment
		(start 287.56483 -103.253286)
		(end 287.569656 -103.261922)
		(width 0.0889)
		(layer "In4.Cu")
		(net "M_E_DQS_DN<7>")
	)
	(segment
		(start 312.79084 -136.116568)
		(end 312.901076 -136.226804)
		(width 0.14224)
		(layer "In4.Cu")
		(net "M_E_DQS_DN<7>")
	)
	(segment
		(start 312.743596 -128.20777)
		(end 312.901076 -128.36525)
		(width 0.14224)
		(layer "In4.Cu")
		(net "M_E_DQS_DN<7>")
	)
	(segment
		(start 289.7759 -105.529888)
		(end 289.811206 -105.529888)
		(width 0.0889)
		(layer "In4.Cu")
		(net "M_E_DQS_DN<7>")
	)
	(segment
		(start 312.743596 -126.56185)
		(end 312.901076 -126.71933)
		(width 0.14224)
		(layer "In4.Cu")
		(net "M_E_DQS_DN<7>")
	)
	(segment
		(start 312.743596 -133.077458)
		(end 312.901076 -133.234938)
		(width 0.14224)
		(layer "In4.Cu")
		(net "M_E_DQS_DN<7>")
	)
	(segment
		(start 312.901076 -126.15037)
		(end 312.743596 -126.30785)
		(width 0.14224)
		(layer "In4.Cu")
		(net "M_E_DQS_DN<7>")
	)
	(segment
		(start 290.100766 -105.962958)
		(end 291.389308 -107.2515)
		(width 0.0889)
		(layer "In4.Cu")
		(net "M_E_DQS_DN<7>")
	)
	(segment
		(start 312.901076 -136.226804)
		(end 312.901076 -136.611614)
		(width 0.14224)
		(layer "In4.Cu")
		(net "M_E_DQS_DN<7>")
	)
	(segment
		(start 287.55848 -103.242618)
		(end 287.56483 -103.253286)
		(width 0.0889)
		(layer "In4.Cu")
		(net "M_E_DQS_DN<7>")
	)
	(segment
		(start 312.901076 -136.611614)
		(end 312.743596 -136.769094)
		(width 0.14224)
		(layer "In4.Cu")
		(net "M_E_DQS_DN<7>")
	)
	(segment
		(start 312.901076 -128.36525)
		(end 312.901076 -128.61925)
		(width 0.14224)
		(layer "In4.Cu")
		(net "M_E_DQS_DN<7>")
	)
	(segment
		(start 290.100766 -105.673144)
		(end 290.100766 -105.962958)
		(width 0.0889)
		(layer "In4.Cu")
		(net "M_E_DQS_DN<7>")
	)
	(segment
		(start 312.901076 -137.180574)
		(end 312.901076 -137.434574)
		(width 0.14224)
		(layer "In4.Cu")
		(net "M_E_DQS_DN<7>")
	)
	(segment
		(start 312.901076 -125.32741)
		(end 312.743596 -125.48489)
		(width 0.14224)
		(layer "In4.Cu")
		(net "M_E_DQS_DN<7>")
	)
	(segment
		(start 311.954672 -143.585946)
		(end 311.954672 -144.841722)
		(width 0.14224)
		(layer "In4.Cu")
		(net "M_E_DQS_DN<7>")
	)
	(segment
		(start 312.743596 -132.000498)
		(end 312.743596 -132.254498)
		(width 0.14224)
		(layer "In4.Cu")
		(net "M_E_DQS_DN<7>")
	)
	(segment
		(start 312.743596 -132.823458)
		(end 312.743596 -133.077458)
		(width 0.14224)
		(layer "In4.Cu")
		(net "M_E_DQS_DN<7>")
	)
	(segment
		(start 286.70631 -100.186236)
		(end 286.69996 -100.196904)
		(width 0.0889)
		(layer "In4.Cu")
		(net "M_E_DQS_DN<7>")
	)
	(segment
		(start 312.79084 -135.862568)
		(end 312.79084 -136.116568)
		(width 0.14224)
		(layer "In4.Cu")
		(net "M_E_DQS_DN<7>")
	)
	(segment
		(start 286.711136 -99.187)
		(end 286.70631 -99.195636)
		(width 0.0889)
		(layer "In4.Cu")
		(net "M_E_DQS_DN<7>")
	)
	(segment
		(start 312.12282 -123.968256)
		(end 312.341768 -123.968256)
		(width 0.14224)
		(layer "In4.Cu")
		(net "M_E_DQS_DN<7>")
	)
	(segment
		(start 312.901076 -132.665978)
		(end 312.743596 -132.823458)
		(width 0.14224)
		(layer "In4.Cu")
		(net "M_E_DQS_DN<7>")
	)
	(segment
		(start 312.387996 -139.881356)
		(end 312.314844 -139.881356)
		(width 0.14224)
		(layer "In4.Cu")
		(net "M_E_DQS_DN<7>")
	)
	(segment
		(start 292.0238 -107.29087)
		(end 292.045898 -107.29087)
		(width 0.0889)
		(layer "In4.Cu")
		(net "M_E_DQS_DN<7>")
	)
	(segment
		(start 312.341768 -123.968256)
		(end 312.901076 -124.527564)
		(width 0.14224)
		(layer "In4.Cu")
		(net "M_E_DQS_DN<7>")
	)
	(segment
		(start 312.901076 -130.184652)
		(end 312.901076 -131.843018)
		(width 0.14224)
		(layer "In4.Cu")
		(net "M_E_DQS_DN<7>")
	)
	(segment
		(start 312.743596 -138.669014)
		(end 312.901076 -138.826494)
		(width 0.14224)
		(layer "In4.Cu")
		(net "M_E_DQS_DN<7>")
	)
	(segment
		(start 312.901076 -126.71933)
		(end 312.901076 -126.97333)
		(width 0.14224)
		(layer "In4.Cu")
		(net "M_E_DQS_DN<7>")
	)
	(segment
		(start 312.901076 -125.89637)
		(end 312.901076 -126.15037)
		(width 0.14224)
		(layer "In4.Cu")
		(net "M_E_DQS_DN<7>")
	)
	(segment
		(start 312.743596 -126.30785)
		(end 312.743596 -126.56185)
		(width 0.14224)
		(layer "In4.Cu")
		(net "M_E_DQS_DN<7>")
	)
	(segment
		(start 311.744106 -143.37538)
		(end 311.954672 -143.585946)
		(width 0.14224)
		(layer "In4.Cu")
		(net "M_E_DQS_DN<7>")
	)
	(segment
		(start 312.743596 -127.38481)
		(end 312.901076 -127.54229)
		(width 0.14224)
		(layer "In4.Cu")
		(net "M_E_DQS_DN<7>")
	)
	(segment
		(start 294.411908 -107.29087)
		(end 307.67909 -120.558052)
		(width 0.14224)
		(layer "In4.Cu")
		(net "M_E_DQS_DN<7>")
	)
	(segment
		(start 291.389308 -107.2515)
		(end 291.98443 -107.2515)
		(width 0.0889)
		(layer "In4.Cu")
		(net "M_E_DQS_DN<7>")
	)
	(segment
		(start 291.98443 -107.2515)
		(end 292.0238 -107.29087)
		(width 0.0889)
		(layer "In4.Cu")
		(net "M_E_DQS_DN<7>")
	)
	(segment
		(start 312.78068 -134.813294)
		(end 312.901076 -134.93369)
		(width 0.14224)
		(layer "In4.Cu")
		(net "M_E_DQS_DN<7>")
	)
	(segment
		(start 311.744106 -141.71422)
		(end 311.744106 -143.37538)
		(width 0.14224)
		(layer "In4.Cu")
		(net "M_E_DQS_DN<7>")
	)
	(segment
		(start 310.431688 -122.64644)
		(end 311.022492 -122.64644)
		(width 0.14224)
		(layer "In4.Cu")
		(net "M_E_DQS_DN<7>")
	)
	(segment
		(start 311.954672 -140.241528)
		(end 311.954672 -141.503654)
		(width 0.14224)
		(layer "In4.Cu")
		(net "M_E_DQS_DN<7>")
	)
	(segment
		(start 312.743596 -127.95377)
		(end 312.743596 -128.20777)
		(width 0.14224)
		(layer "In4.Cu")
		(net "M_E_DQS_DN<7>")
	)
	(segment
		(start 286.706056 -97.80524)
		(end 286.70631 -97.805494)
		(width 0.0889)
		(layer "In4.Cu")
		(net "M_E_DQS_DN<7>")
	)
	(segment
		(start 311.093104 -123.297188)
		(end 311.093104 -123.739148)
		(width 0.14224)
		(layer "In4.Cu")
		(net "M_E_DQS_DN<7>")
	)
	(segment
		(start 287.19653 -102.062534)
		(end 287.229296 -102.062534)
		(width 0.0889)
		(layer "In4.Cu")
		(net "M_E_DQS_DN<7>")
	)
	(segment
		(start 312.901076 -134.93369)
		(end 312.901076 -135.752332)
		(width 0.14224)
		(layer "In4.Cu")
		(net "M_E_DQS_DN<7>")
	)
	(segment
		(start 312.78068 -134.559294)
		(end 312.78068 -134.813294)
		(width 0.14224)
		(layer "In4.Cu")
		(net "M_E_DQS_DN<7>")
	)
	(segment
		(start 312.901076 -133.488938)
		(end 312.743596 -133.646418)
		(width 0.14224)
		(layer "In4.Cu")
		(net "M_E_DQS_DN<7>")
	)
	(segment
		(start 309.953152 -122.167904)
		(end 310.431688 -122.64644)
		(width 0.14224)
		(layer "In4.Cu")
		(net "M_E_DQS_DN<7>")
	)
	(segment
		(start 312.901076 -132.411978)
		(end 312.901076 -132.665978)
		(width 0.14224)
		(layer "In4.Cu")
		(net "M_E_DQS_DN<7>")
	)
	(segment
		(start 286.70631 -99.195636)
		(end 286.69996 -99.206304)
		(width 0.0889)
		(layer "In4.Cu")
		(net "M_E_DQS_DN<7>")
	)
	(segment
		(start 312.901076 -138.826494)
		(end 312.901076 -139.647676)
		(width 0.14224)
		(layer "In4.Cu")
		(net "M_E_DQS_DN<7>")
	)
	(segment
		(start 311.272428 -122.896376)
		(end 311.272428 -123.117864)
		(width 0.14224)
		(layer "In4.Cu")
		(net "M_E_DQS_DN<7>")
	)
	(segment
		(start 312.743596 -137.592054)
		(end 312.743596 -137.846054)
		(width 0.14224)
		(layer "In4.Cu")
		(net "M_E_DQS_DN<7>")
	)
	(segment
		(start 312.901076 -129.649728)
		(end 312.760614 -129.79019)
		(width 0.14224)
		(layer "In4.Cu")
		(net "M_E_DQS_DN<7>")
	)
	(segment
		(start 311.943496 -124.14758)
		(end 312.12282 -123.968256)
		(width 0.14224)
		(layer "In4.Cu")
		(net "M_E_DQS_DN<7>")
	)
	(segment
		(start 312.901076 -128.61925)
		(end 312.743596 -128.77673)
		(width 0.14224)
		(layer "In4.Cu")
		(net "M_E_DQS_DN<7>")
	)
	(segment
		(start 288.91357 -105.034334)
		(end 288.946336 -105.034334)
		(width 0.0889)
		(layer "In4.Cu")
		(net "M_E_DQS_DN<7>")
	)
	(segment
		(start 312.667396 -139.881356)
		(end 312.387996 -139.881356)
		(width 0.14224)
		(layer "In4.Cu")
		(net "M_E_DQS_DN<7>")
	)
	(segment
		(start 312.901076 -126.97333)
		(end 312.743596 -127.13081)
		(width 0.14224)
		(layer "In4.Cu")
		(net "M_E_DQS_DN<7>")
	)
	(segment
		(start 311.272428 -123.117864)
		(end 311.093104 -123.297188)
		(width 0.14224)
		(layer "In4.Cu")
		(net "M_E_DQS_DN<7>")
	)
	(segment
		(start 311.501536 -124.14758)
		(end 311.943496 -124.14758)
		(width 0.14224)
		(layer "In4.Cu")
		(net "M_E_DQS_DN<7>")
	)
	(segment
		(start 312.760614 -129.79019)
		(end 312.760614 -130.04419)
		(width 0.14224)
		(layer "In4.Cu")
		(net "M_E_DQS_DN<7>")
	)
	(segment
		(start 312.901076 -137.434574)
		(end 312.743596 -137.592054)
		(width 0.14224)
		(layer "In4.Cu")
		(net "M_E_DQS_DN<7>")
	)
	(segment
		(start 312.760614 -130.04419)
		(end 312.901076 -130.184652)
		(width 0.14224)
		(layer "In4.Cu")
		(net "M_E_DQS_DN<7>")
	)
	(segment
		(start 312.743596 -128.77673)
		(end 312.743596 -129.03073)
		(width 0.14224)
		(layer "In4.Cu")
		(net "M_E_DQS_DN<7>")
	)
	(segment
		(start 309.953152 -121.57964)
		(end 309.953152 -122.167904)
		(width 0.14224)
		(layer "In4.Cu")
		(net "M_E_DQS_DN<7>")
	)
	(segment
		(start 286.70631 -97.21469)
		(end 286.706056 -97.214944)
		(width 0.0889)
		(layer "In4.Cu")
		(net "M_E_DQS_DN<7>")
	)
	(segment
		(start 312.743596 -137.846054)
		(end 312.901076 -138.003534)
		(width 0.14224)
		(layer "In4.Cu")
		(net "M_E_DQS_DN<7>")
	)
	(segment
		(start 312.901076 -138.003534)
		(end 312.901076 -138.257534)
		(width 0.14224)
		(layer "In4.Cu")
		(net "M_E_DQS_DN<7>")
	)
	(segment
		(start 307.67909 -120.558052)
		(end 308.931564 -120.558052)
		(width 0.14224)
		(layer "In4.Cu")
		(net "M_E_DQS_DN<7>")
	)
	(segment
		(start 311.954672 -144.841722)
		(end 312.387996 -145.275046)
		(width 0.14224)
		(layer "In4.Cu")
		(net "M_E_DQS_DN<7>")
	)
	(segment
		(start 308.931564 -120.558052)
		(end 309.953152 -121.57964)
		(width 0.14224)
		(layer "In4.Cu")
		(net "M_E_DQS_DN<7>")
	)
	(segment
		(start 286.711136 -100.1776)
		(end 286.70631 -100.186236)
		(width 0.0889)
		(layer "In4.Cu")
		(net "M_E_DQS_DN<7>")
	)
	(segment
		(start 312.743596 -129.03073)
		(end 312.901076 -129.18821)
		(width 0.14224)
		(layer "In4.Cu")
		(net "M_E_DQS_DN<7>")
	)
	(segment
		(start 312.901076 -134.438898)
		(end 312.78068 -134.559294)
		(width 0.14224)
		(layer "In4.Cu")
		(net "M_E_DQS_DN<7>")
	)
	(segment
		(start 311.093104 -123.739148)
		(end 311.501536 -124.14758)
		(width 0.14224)
		(layer "In4.Cu")
		(net "M_E_DQS_DN<7>")
	)
	(segment
		(start 312.743596 -125.73889)
		(end 312.901076 -125.89637)
		(width 0.14224)
		(layer "In4.Cu")
		(net "M_E_DQS_DN<7>")
	)
	(segment
		(start 312.901076 -127.54229)
		(end 312.901076 -127.79629)
		(width 0.14224)
		(layer "In4.Cu")
		(net "M_E_DQS_DN<7>")
	)
	(segment
		(start 312.901076 -139.647676)
		(end 312.667396 -139.881356)
		(width 0.14224)
		(layer "In4.Cu")
		(net "M_E_DQS_DN<7>")
	)
	(segment
		(start 312.743596 -132.254498)
		(end 312.901076 -132.411978)
		(width 0.14224)
		(layer "In4.Cu")
		(net "M_E_DQS_DN<7>")
	)
	(segment
		(start 311.954672 -141.503654)
		(end 311.744106 -141.71422)
		(width 0.14224)
		(layer "In4.Cu")
		(net "M_E_DQS_DN<7>")
	)
	(segment
		(start 292.045898 -107.29087)
		(end 294.411908 -107.29087)
		(width 0.14224)
		(layer "In4.Cu")
		(net "M_E_DQS_DN<7>")
	)
	(segment
		(start 312.314844 -139.881356)
		(end 311.954672 -140.241528)
		(width 0.14224)
		(layer "In4.Cu")
		(net "M_E_DQS_DN<7>")
	)
	(segment
		(start 288.05886 -104.539288)
		(end 288.091626 -104.539288)
		(width 0.0889)
		(layer "In4.Cu")
		(net "M_E_DQS_DN<7>")
	)
	(segment
		(start 312.743596 -136.769094)
		(end 312.743596 -137.023094)
		(width 0.14224)
		(layer "In4.Cu")
		(net "M_E_DQS_DN<7>")
	)
	(segment
		(start 312.743596 -133.900418)
		(end 312.901076 -134.057898)
		(width 0.14224)
		(layer "In4.Cu")
		(net "M_E_DQS_DN<7>")
	)
	(segment
		(start 312.743596 -127.13081)
		(end 312.743596 -127.38481)
		(width 0.14224)
		(layer "In4.Cu")
		(net "M_E_DQS_DN<7>")
	)
	(segment
		(start 312.901076 -124.527564)
		(end 312.901076 -125.32741)
		(width 0.14224)
		(layer "In4.Cu")
		(net "M_E_DQS_DN<7>")
	)
	(segment
		(start 312.743596 -137.023094)
		(end 312.901076 -137.180574)
		(width 0.14224)
		(layer "In4.Cu")
		(net "M_E_DQS_DN<7>")
	)
	(segment
		(start 312.901076 -131.843018)
		(end 312.743596 -132.000498)
		(width 0.14224)
		(layer "In4.Cu")
		(net "M_E_DQS_DN<7>")
	)
	(segment
		(start 312.901076 -127.79629)
		(end 312.743596 -127.95377)
		(width 0.14224)
		(layer "In4.Cu")
		(net "M_E_DQS_DN<7>")
	)
	(segment
		(start 312.743596 -125.48489)
		(end 312.743596 -125.73889)
		(width 0.14224)
		(layer "In4.Cu")
		(net "M_E_DQS_DN<7>")
	)
	(segment
		(start 312.901076 -129.18821)
		(end 312.901076 -129.649728)
		(width 0.14224)
		(layer "In4.Cu")
		(net "M_E_DQS_DN<7>")
	)
	(segment
		(start 312.743596 -133.646418)
		(end 312.743596 -133.900418)
		(width 0.14224)
		(layer "In4.Cu")
		(net "M_E_DQS_DN<7>")
	)
	(segment
		(start 286.711136 -101.1682)
		(end 286.70631 -101.176836)
		(width 0.0889)
		(layer "In4.Cu")
		(net "M_E_DQS_DN<7>")
	)
	(segment
		(start 312.901076 -134.057898)
		(end 312.901076 -134.438898)
		(width 0.14224)
		(layer "In4.Cu")
		(net "M_E_DQS_DN<7>")
	)
	(arc
		(start 286.70631 -96.814894)
		(mid 286.759809 -97.014792)
		(end 286.70631 -97.21469)
		(width 0.0889)
		(layer "In4.Cu")
		(net "M_E_DQS_DN<7>")
	)
	(arc
		(start 286.70631 -100.776786)
		(mid 286.75978 -100.971849)
		(end 286.711136 -101.1682)
		(width 0.0889)
		(layer "In4.Cu")
		(net "M_E_DQS_DN<7>")
	)
	(arc
		(start 286.69996 -99.206304)
		(mid 286.627162 -99.497067)
		(end 286.70631 -99.786186)
		(width 0.0889)
		(layer "In4.Cu")
		(net "M_E_DQS_DN<7>")
	)
	(arc
		(start 287.229296 -102.062534)
		(mid 287.567465 -102.267332)
		(end 287.56483 -102.662736)
		(width 0.0889)
		(layer "In4.Cu")
		(net "M_E_DQS_DN<7>")
	)
	(arc
		(start 288.946336 -105.034334)
		(mid 289.140186 -105.090684)
		(end 289.28187 -105.234486)
		(width 0.0889)
		(layer "In4.Cu")
		(net "M_E_DQS_DN<7>")
	)
	(arc
		(start 286.706056 -97.214944)
		(mid 286.627085 -97.510092)
		(end 286.706056 -97.80524)
		(width 0.0889)
		(layer "In4.Cu")
		(net "M_E_DQS_DN<7>")
	)
	(arc
		(start 286.3596 -96.023938)
		(mid 286.511202 -96.428951)
		(end 286.70631 -96.814894)
		(width 0.0889)
		(layer "In4.Cu")
		(net "M_E_DQS_DN<7>")
	)
	(arc
		(start 289.811206 -105.529888)
		(mid 289.971055 -105.571045)
		(end 290.100766 -105.673144)
		(width 0.0889)
		(layer "In4.Cu")
		(net "M_E_DQS_DN<7>")
	)
	(arc
		(start 286.70631 -98.20529)
		(mid 286.627179 -98.500692)
		(end 286.70631 -98.796094)
		(width 0.0889)
		(layer "In4.Cu")
		(net "M_E_DQS_DN<7>")
	)
	(arc
		(start 289.28187 -105.234486)
		(mid 289.490478 -105.446418)
		(end 289.7759 -105.529888)
		(width 0.0889)
		(layer "In4.Cu")
		(net "M_E_DQS_DN<7>")
	)
	(arc
		(start 286.70631 -99.786186)
		(mid 286.75978 -99.981249)
		(end 286.711136 -100.1776)
		(width 0.0889)
		(layer "In4.Cu")
		(net "M_E_DQS_DN<7>")
	)
	(arc
		(start 286.70631 -98.796094)
		(mid 286.722208 -98.826473)
		(end 286.73552 -98.85807)
		(width 0.0889)
		(layer "In4.Cu")
		(net "M_E_DQS_DN<7>")
	)
	(arc
		(start 286.73552 -98.85807)
		(mid 286.758747 -99.025153)
		(end 286.711136 -99.187)
		(width 0.0889)
		(layer "In4.Cu")
		(net "M_E_DQS_DN<7>")
	)
	(arc
		(start 286.69996 -101.187504)
		(mid 286.703991 -101.763686)
		(end 287.19653 -102.062534)
		(width 0.0889)
		(layer "In4.Cu")
		(net "M_E_DQS_DN<7>")
	)
	(arc
		(start 287.569656 -103.261922)
		(mid 287.618411 -103.458274)
		(end 287.56483 -103.653336)
		(width 0.0889)
		(layer "In4.Cu")
		(net "M_E_DQS_DN<7>")
	)
	(arc
		(start 288.42335 -104.739186)
		(mid 288.630354 -104.95005)
		(end 288.91357 -105.034334)
		(width 0.0889)
		(layer "In4.Cu")
		(net "M_E_DQS_DN<7>")
	)
	(arc
		(start 288.091626 -104.539288)
		(mid 288.283268 -104.596454)
		(end 288.42335 -104.739186)
		(width 0.0889)
		(layer "In4.Cu")
		(net "M_E_DQS_DN<7>")
	)
	(arc
		(start 286.70631 -97.805494)
		(mid 286.759809 -98.005392)
		(end 286.70631 -98.20529)
		(width 0.0889)
		(layer "In4.Cu")
		(net "M_E_DQS_DN<7>")
	)
	(arc
		(start 287.56483 -103.653336)
		(mid 287.560501 -104.236508)
		(end 288.05886 -104.539288)
		(width 0.0889)
		(layer "In4.Cu")
		(net "M_E_DQS_DN<7>")
	)
	(arc
		(start 287.56483 -102.662736)
		(mid 287.485608 -102.951854)
		(end 287.55848 -103.242618)
		(width 0.0889)
		(layer "In4.Cu")
		(net "M_E_DQS_DN<7>")
	)
	(arc
		(start 286.69996 -100.196904)
		(mid 286.627162 -100.487667)
		(end 286.70631 -100.776786)
		(width 0.0889)
		(layer "In4.Cu")
		(net "M_E_DQS_DN<7>")
	)
	(segment
		(start 301.32147 -111.93272)
		(end 301.501048 -112.112552)
		(width 0.1651)
		(layer "F.Cu")
		(net "M_E_DQS_DN<6>")
	)
	(segment
		(start 303.10328 -119.888)
		(end 303.10328 -120.142)
		(width 0.1651)
		(layer "F.Cu")
		(net "M_E_DQS_DN<6>")
	)
	(segment
		(start 303.447196 -124.2314)
		(end 303.574196 -124.3584)
		(width 0.1651)
		(layer "F.Cu")
		(net "M_E_DQS_DN<6>")
	)
	(segment
		(start 303.10328 -117.602)
		(end 303.10328 -117.856)
		(width 0.1651)
		(layer "F.Cu")
		(net "M_E_DQS_DN<6>")
	)
	(segment
		(start 303.10328 -117.094)
		(end 303.23028 -117.221)
		(width 0.1651)
		(layer "F.Cu")
		(net "M_E_DQS_DN<6>")
	)
	(segment
		(start 303.10328 -119.126)
		(end 303.10328 -119.38)
		(width 0.1651)
		(layer "F.Cu")
		(net "M_E_DQS_DN<6>")
	)
	(segment
		(start 303.979072 -122.2375)
		(end 303.852072 -122.3645)
		(width 0.1651)
		(layer "F.Cu")
		(net "M_E_DQS_DN<6>")
	)
	(segment
		(start 303.10328 -116.84)
		(end 303.10328 -117.094)
		(width 0.1651)
		(layer "F.Cu")
		(net "M_E_DQS_DN<6>")
	)
	(segment
		(start 302.219614 -112.65154)
		(end 302.399192 -112.831118)
		(width 0.1651)
		(layer "F.Cu")
		(net "M_E_DQS_DN<6>")
	)
	(segment
		(start 287.231836 -106.261154)
		(end 295.546272 -106.261154)
		(width 0.1016)
		(layer "F.Cu")
		(net "M_E_DQS_DN<6>")
	)
	(segment
		(start 286.131 -105.160318)
		(end 287.231836 -106.261154)
		(width 0.1016)
		(layer "F.Cu")
		(net "M_E_DQS_DN<6>")
	)
	(segment
		(start 303.852072 -121.6914)
		(end 303.979072 -121.8184)
		(width 0.1651)
		(layer "F.Cu")
		(net "M_E_DQS_DN<6>")
	)
	(segment
		(start 303.23028 -117.221)
		(end 303.23028 -117.475)
		(width 0.1651)
		(layer "F.Cu")
		(net "M_E_DQS_DN<6>")
	)
	(segment
		(start 301.501048 -112.112552)
		(end 301.68088 -112.112552)
		(width 0.1651)
		(layer "F.Cu")
		(net "M_E_DQS_DN<6>")
	)
	(segment
		(start 303.23028 -115.927632)
		(end 303.10328 -116.054632)
		(width 0.1651)
		(layer "F.Cu")
		(net "M_E_DQS_DN<6>")
	)
	(segment
		(start 303.447196 -123.9774)
		(end 303.447196 -124.2314)
		(width 0.1651)
		(layer "F.Cu")
		(net "M_E_DQS_DN<6>")
	)
	(segment
		(start 286.131 -105.011728)
		(end 286.131 -105.160318)
		(width 0.1016)
		(layer "F.Cu")
		(net "M_E_DQS_DN<6>")
	)
	(segment
		(start 303.10328 -117.856)
		(end 303.23028 -117.983)
		(width 0.1651)
		(layer "F.Cu")
		(net "M_E_DQS_DN<6>")
	)
	(segment
		(start 300.962314 -111.573564)
		(end 301.142146 -111.573564)
		(width 0.1651)
		(layer "F.Cu")
		(net "M_E_DQS_DN<6>")
	)
	(segment
		(start 303.23028 -113.66246)
		(end 303.23028 -114.403632)
		(width 0.1651)
		(layer "F.Cu")
		(net "M_E_DQS_DN<6>")
	)
	(segment
		(start 303.10328 -114.530632)
		(end 303.10328 -114.784632)
		(width 0.1651)
		(layer "F.Cu")
		(net "M_E_DQS_DN<6>")
	)
	(segment
		(start 302.650398 -147.27174)
		(end 302.64989 -147.27174)
		(width 0.1651)
		(layer "F.Cu")
		(net "M_E_DQS_DN<6>")
	)
	(segment
		(start 302.398938 -113.010696)
		(end 302.578516 -113.190528)
		(width 0.1651)
		(layer "F.Cu")
		(net "M_E_DQS_DN<6>")
	)
	(segment
		(start 303.10328 -118.618)
		(end 303.23028 -118.745)
		(width 0.1651)
		(layer "F.Cu")
		(net "M_E_DQS_DN<6>")
	)
	(segment
		(start 303.10328 -118.364)
		(end 303.10328 -118.618)
		(width 0.1651)
		(layer "F.Cu")
		(net "M_E_DQS_DN<6>")
	)
	(segment
		(start 302.578516 -113.190528)
		(end 302.758602 -113.190528)
		(width 0.1651)
		(layer "F.Cu")
		(net "M_E_DQS_DN<6>")
	)
	(segment
		(start 303.10328 -115.546632)
		(end 303.23028 -115.673632)
		(width 0.1651)
		(layer "F.Cu")
		(net "M_E_DQS_DN<6>")
	)
	(segment
		(start 302.267874 -145.821654)
		(end 302.267874 -145.389854)
		(width 0.1651)
		(layer "F.Cu")
		(net "M_E_DQS_DN<6>")
	)
	(segment
		(start 300.244002 -110.854744)
		(end 300.42358 -111.034576)
		(width 0.1651)
		(layer "F.Cu")
		(net "M_E_DQS_DN<6>")
	)
	(segment
		(start 302.822356 -145.0594)
		(end 303.038002 -145.275046)
		(width 0.1651)
		(layer "F.Cu")
		(net "M_E_DQS_DN<6>")
	)
	(segment
		(start 303.10328 -114.784632)
		(end 303.23028 -114.911632)
		(width 0.1651)
		(layer "F.Cu")
		(net "M_E_DQS_DN<6>")
	)
	(segment
		(start 302.598328 -145.0594)
		(end 302.822356 -145.0594)
		(width 0.1651)
		(layer "F.Cu")
		(net "M_E_DQS_DN<6>")
	)
	(segment
		(start 299.442378 -109.9566)
		(end 299.525944 -109.9566)
		(width 0.1016)
		(layer "F.Cu")
		(net "M_E_DQS_DN<6>")
	)
	(segment
		(start 303.23028 -116.435632)
		(end 303.23028 -116.713)
		(width 0.1651)
		(layer "F.Cu")
		(net "M_E_DQS_DN<6>")
	)
	(segment
		(start 303.218596 -122.700542)
		(end 303.218596 -123.291854)
		(width 0.1651)
		(layer "F.Cu")
		(net "M_E_DQS_DN<6>")
	)
	(segment
		(start 303.503838 -121.6914)
		(end 303.852072 -121.6914)
		(width 0.1651)
		(layer "F.Cu")
		(net "M_E_DQS_DN<6>")
	)
	(segment
		(start 300.244002 -110.675166)
		(end 300.244002 -110.854744)
		(width 0.1651)
		(layer "F.Cu")
		(net "M_E_DQS_DN<6>")
	)
	(segment
		(start 303.218596 -123.291854)
		(end 303.574196 -123.647454)
		(width 0.1651)
		(layer "F.Cu")
		(net "M_E_DQS_DN<6>")
	)
	(segment
		(start 301.142146 -111.573564)
		(end 301.32147 -111.753142)
		(width 0.1651)
		(layer "F.Cu")
		(net "M_E_DQS_DN<6>")
	)
	(segment
		(start 301.860204 -112.471708)
		(end 302.039782 -112.65154)
		(width 0.1651)
		(layer "F.Cu")
		(net "M_E_DQS_DN<6>")
	)
	(segment
		(start 303.979072 -121.8184)
		(end 303.979072 -122.2375)
		(width 0.1651)
		(layer "F.Cu")
		(net "M_E_DQS_DN<6>")
	)
	(segment
		(start 303.23028 -121.031)
		(end 303.23028 -121.417842)
		(width 0.1651)
		(layer "F.Cu")
		(net "M_E_DQS_DN<6>")
	)
	(segment
		(start 303.23028 -115.673632)
		(end 303.23028 -115.927632)
		(width 0.1651)
		(layer "F.Cu")
		(net "M_E_DQS_DN<6>")
	)
	(segment
		(start 303.299114 -125.351286)
		(end 303.038002 -125.351286)
		(width 0.1651)
		(layer "F.Cu")
		(net "M_E_DQS_DN<6>")
	)
	(segment
		(start 303.10328 -116.054632)
		(end 303.10328 -116.308632)
		(width 0.1651)
		(layer "F.Cu")
		(net "M_E_DQS_DN<6>")
	)
	(segment
		(start 303.23028 -119.761)
		(end 303.10328 -119.888)
		(width 0.1651)
		(layer "F.Cu")
		(net "M_E_DQS_DN<6>")
	)
	(segment
		(start 285.7881 -102.958138)
		(end 285.7881 -104.668828)
		(width 0.0889)
		(layer "F.Cu")
		(net "M_E_DQS_DN<6>")
	)
	(segment
		(start 303.574196 -123.647454)
		(end 303.574196 -123.8504)
		(width 0.1651)
		(layer "F.Cu")
		(net "M_E_DQS_DN<6>")
	)
	(segment
		(start 303.574196 -123.8504)
		(end 303.447196 -123.9774)
		(width 0.1651)
		(layer "F.Cu")
		(net "M_E_DQS_DN<6>")
	)
	(segment
		(start 295.546272 -106.261154)
		(end 298.998132 -109.713014)
		(width 0.1016)
		(layer "F.Cu")
		(net "M_E_DQS_DN<6>")
	)
	(segment
		(start 300.782736 -111.393732)
		(end 300.962314 -111.573564)
		(width 0.1651)
		(layer "F.Cu")
		(net "M_E_DQS_DN<6>")
	)
	(segment
		(start 303.554638 -122.3645)
		(end 303.218596 -122.700542)
		(width 0.1651)
		(layer "F.Cu")
		(net "M_E_DQS_DN<6>")
	)
	(segment
		(start 303.23028 -118.745)
		(end 303.23028 -118.999)
		(width 0.1651)
		(layer "F.Cu")
		(net "M_E_DQS_DN<6>")
	)
	(segment
		(start 303.10328 -116.308632)
		(end 303.23028 -116.435632)
		(width 0.1651)
		(layer "F.Cu")
		(net "M_E_DQS_DN<6>")
	)
	(segment
		(start 299.884846 -110.495588)
		(end 300.064678 -110.495588)
		(width 0.1651)
		(layer "F.Cu")
		(net "M_E_DQS_DN<6>")
	)
	(segment
		(start 300.736 -111.167418)
		(end 300.782736 -111.214154)
		(width 0.1651)
		(layer "F.Cu")
		(net "M_E_DQS_DN<6>")
	)
	(segment
		(start 302.267874 -145.389854)
		(end 302.598328 -145.0594)
		(width 0.1651)
		(layer "F.Cu")
		(net "M_E_DQS_DN<6>")
	)
	(segment
		(start 300.603412 -111.034576)
		(end 300.736 -111.167418)
		(width 0.1651)
		(layer "F.Cu")
		(net "M_E_DQS_DN<6>")
	)
	(segment
		(start 303.23028 -121.417842)
		(end 303.503838 -121.6914)
		(width 0.1651)
		(layer "F.Cu")
		(net "M_E_DQS_DN<6>")
	)
	(segment
		(start 299.198792 -109.713014)
		(end 299.442378 -109.9566)
		(width 0.1016)
		(layer "F.Cu")
		(net "M_E_DQS_DN<6>")
	)
	(segment
		(start 303.574196 -125.076204)
		(end 303.299114 -125.351286)
		(width 0.1651)
		(layer "F.Cu")
		(net "M_E_DQS_DN<6>")
	)
	(segment
		(start 303.23028 -115.165632)
		(end 303.10328 -115.292632)
		(width 0.1651)
		(layer "F.Cu")
		(net "M_E_DQS_DN<6>")
	)
	(segment
		(start 303.10328 -119.38)
		(end 303.23028 -119.507)
		(width 0.1651)
		(layer "F.Cu")
		(net "M_E_DQS_DN<6>")
	)
	(segment
		(start 298.998132 -109.713014)
		(end 299.198792 -109.713014)
		(width 0.1016)
		(layer "F.Cu")
		(net "M_E_DQS_DN<6>")
	)
	(segment
		(start 285.7881 -104.668828)
		(end 286.131 -105.011728)
		(width 0.0889)
		(layer "F.Cu")
		(net "M_E_DQS_DN<6>")
	)
	(segment
		(start 303.23028 -120.523)
		(end 303.10328 -120.65)
		(width 0.1651)
		(layer "F.Cu")
		(net "M_E_DQS_DN<6>")
	)
	(segment
		(start 300.782736 -111.214154)
		(end 300.782736 -111.393732)
		(width 0.1651)
		(layer "F.Cu")
		(net "M_E_DQS_DN<6>")
	)
	(segment
		(start 302.64989 -146.20367)
		(end 302.267874 -145.821654)
		(width 0.1651)
		(layer "F.Cu")
		(net "M_E_DQS_DN<6>")
	)
	(segment
		(start 303.23028 -118.237)
		(end 303.10328 -118.364)
		(width 0.1651)
		(layer "F.Cu")
		(net "M_E_DQS_DN<6>")
	)
	(segment
		(start 302.039782 -112.65154)
		(end 302.219614 -112.65154)
		(width 0.1651)
		(layer "F.Cu")
		(net "M_E_DQS_DN<6>")
	)
	(segment
		(start 301.32147 -111.753142)
		(end 301.32147 -111.93272)
		(width 0.1651)
		(layer "F.Cu")
		(net "M_E_DQS_DN<6>")
	)
	(segment
		(start 303.23028 -114.911632)
		(end 303.23028 -115.165632)
		(width 0.1651)
		(layer "F.Cu")
		(net "M_E_DQS_DN<6>")
	)
	(segment
		(start 299.705268 -110.315756)
		(end 299.884846 -110.495588)
		(width 0.1651)
		(layer "F.Cu")
		(net "M_E_DQS_DN<6>")
	)
	(segment
		(start 302.758602 -113.190528)
		(end 303.23028 -113.66246)
		(width 0.1651)
		(layer "F.Cu")
		(net "M_E_DQS_DN<6>")
	)
	(segment
		(start 303.23028 -118.999)
		(end 303.10328 -119.126)
		(width 0.1651)
		(layer "F.Cu")
		(net "M_E_DQS_DN<6>")
	)
	(segment
		(start 303.10328 -120.65)
		(end 303.10328 -120.904)
		(width 0.1651)
		(layer "F.Cu")
		(net "M_E_DQS_DN<6>")
	)
	(segment
		(start 301.68088 -112.112552)
		(end 301.860204 -112.29213)
		(width 0.1651)
		(layer "F.Cu")
		(net "M_E_DQS_DN<6>")
	)
	(segment
		(start 299.525944 -109.9566)
		(end 299.705268 -110.136178)
		(width 0.1651)
		(layer "F.Cu")
		(net "M_E_DQS_DN<6>")
	)
	(segment
		(start 301.860204 -112.29213)
		(end 301.860204 -112.471708)
		(width 0.1651)
		(layer "F.Cu")
		(net "M_E_DQS_DN<6>")
	)
	(segment
		(start 303.23028 -120.269)
		(end 303.23028 -120.523)
		(width 0.1651)
		(layer "F.Cu")
		(net "M_E_DQS_DN<6>")
	)
	(segment
		(start 302.399192 -112.831118)
		(end 302.398938 -113.010696)
		(width 0.1651)
		(layer "F.Cu")
		(net "M_E_DQS_DN<6>")
	)
	(segment
		(start 303.10328 -120.904)
		(end 303.23028 -121.031)
		(width 0.1651)
		(layer "F.Cu")
		(net "M_E_DQS_DN<6>")
	)
	(segment
		(start 303.10328 -120.142)
		(end 303.23028 -120.269)
		(width 0.1651)
		(layer "F.Cu")
		(net "M_E_DQS_DN<6>")
	)
	(segment
		(start 303.852072 -122.3645)
		(end 303.554638 -122.3645)
		(width 0.1651)
		(layer "F.Cu")
		(net "M_E_DQS_DN<6>")
	)
	(segment
		(start 303.23028 -117.983)
		(end 303.23028 -118.237)
		(width 0.1651)
		(layer "F.Cu")
		(net "M_E_DQS_DN<6>")
	)
	(segment
		(start 303.23028 -119.507)
		(end 303.23028 -119.761)
		(width 0.1651)
		(layer "F.Cu")
		(net "M_E_DQS_DN<6>")
	)
	(segment
		(start 303.23028 -117.475)
		(end 303.10328 -117.602)
		(width 0.1651)
		(layer "F.Cu")
		(net "M_E_DQS_DN<6>")
	)
	(segment
		(start 303.23028 -116.713)
		(end 303.10328 -116.84)
		(width 0.1651)
		(layer "F.Cu")
		(net "M_E_DQS_DN<6>")
	)
	(segment
		(start 300.064678 -110.495588)
		(end 300.244002 -110.675166)
		(width 0.1651)
		(layer "F.Cu")
		(net "M_E_DQS_DN<6>")
	)
	(segment
		(start 300.42358 -111.034576)
		(end 300.603412 -111.034576)
		(width 0.1651)
		(layer "F.Cu")
		(net "M_E_DQS_DN<6>")
	)
	(segment
		(start 303.23028 -114.403632)
		(end 303.10328 -114.530632)
		(width 0.1651)
		(layer "F.Cu")
		(net "M_E_DQS_DN<6>")
	)
	(segment
		(start 302.64989 -147.27174)
		(end 302.64989 -146.20367)
		(width 0.1651)
		(layer "F.Cu")
		(net "M_E_DQS_DN<6>")
	)
	(segment
		(start 303.10328 -115.292632)
		(end 303.10328 -115.546632)
		(width 0.1651)
		(layer "F.Cu")
		(net "M_E_DQS_DN<6>")
	)
	(segment
		(start 299.705268 -110.136178)
		(end 299.705268 -110.315756)
		(width 0.1651)
		(layer "F.Cu")
		(net "M_E_DQS_DN<6>")
	)
	(segment
		(start 303.574196 -124.3584)
		(end 303.574196 -125.076204)
		(width 0.1651)
		(layer "F.Cu")
		(net "M_E_DQS_DN<6>")
	)
	(via
		(at 303.038002 -125.351286)
		(size 0.508)
		(drill 0.254)
		(layers "F.Cu" "B.Cu")
		(net "M_E_DQS_DN<6>")
	)
	(via
		(at 303.038002 -145.275046)
		(size 0.508)
		(drill 0.254)
		(layers "F.Cu" "B.Cu")
		(net "M_E_DQS_DN<6>")
	)
	(via
		(at 303.038002 -139.881356)
		(size 0.508)
		(drill 0.254)
		(layers "F.Cu" "B.Cu")
		(net "M_E_DQS_DN<6>")
	)
	(segment
		(start 302.267874 -139.420346)
		(end 302.267874 -139.7508)
		(width 0.1651)
		(layer "B.Cu")
		(net "M_E_DQS_DN<6>")
	)
	(segment
		(start 302.521874 -139.166346)
		(end 302.267874 -139.420346)
		(width 0.1651)
		(layer "B.Cu")
		(net "M_E_DQS_DN<6>")
	)
	(segment
		(start 302.64989 -137.877296)
		(end 302.64989 -138.78433)
		(width 0.1651)
		(layer "B.Cu")
		(net "M_E_DQS_DN<6>")
	)
	(segment
		(start 302.267874 -139.7508)
		(end 302.623474 -140.1064)
		(width 0.1651)
		(layer "B.Cu")
		(net "M_E_DQS_DN<6>")
	)
	(segment
		(start 302.521874 -138.912346)
		(end 302.521874 -139.166346)
		(width 0.1651)
		(layer "B.Cu")
		(net "M_E_DQS_DN<6>")
	)
	(segment
		(start 302.623474 -140.1064)
		(end 302.812958 -140.1064)
		(width 0.1651)
		(layer "B.Cu")
		(net "M_E_DQS_DN<6>")
	)
	(segment
		(start 302.812958 -140.1064)
		(end 303.038002 -139.881356)
		(width 0.1651)
		(layer "B.Cu")
		(net "M_E_DQS_DN<6>")
	)
	(segment
		(start 302.64989 -138.78433)
		(end 302.521874 -138.912346)
		(width 0.1651)
		(layer "B.Cu")
		(net "M_E_DQS_DN<6>")
	)
	(segment
		(start 302.650398 -137.877296)
		(end 302.64989 -137.877296)
		(width 0.1651)
		(layer "B.Cu")
		(net "M_E_DQS_DN<6>")
	)
	(segment
		(start 303.204626 -132.295646)
		(end 303.551082 -131.94919)
		(width 0.14224)
		(layer "In4.Cu")
		(net "M_E_DQS_DN<6>")
	)
	(segment
		(start 303.551082 -131.94919)
		(end 303.551082 -127.859282)
		(width 0.14224)
		(layer "In4.Cu")
		(net "M_E_DQS_DN<6>")
	)
	(segment
		(start 302.5902 -125.799088)
		(end 303.038002 -125.351286)
		(width 0.14224)
		(layer "In4.Cu")
		(net "M_E_DQS_DN<6>")
	)
	(segment
		(start 303.551082 -133.71195)
		(end 303.204626 -133.365494)
		(width 0.14224)
		(layer "In4.Cu")
		(net "M_E_DQS_DN<6>")
	)
	(segment
		(start 303.153064 -137.250678)
		(end 303.551082 -136.85266)
		(width 0.14224)
		(layer "In4.Cu")
		(net "M_E_DQS_DN<6>")
	)
	(segment
		(start 303.551082 -136.85266)
		(end 303.551082 -133.71195)
		(width 0.14224)
		(layer "In4.Cu")
		(net "M_E_DQS_DN<6>")
	)
	(segment
		(start 303.153064 -138.13536)
		(end 303.153064 -137.250678)
		(width 0.14224)
		(layer "In4.Cu")
		(net "M_E_DQS_DN<6>")
	)
	(segment
		(start 303.551082 -138.533378)
		(end 303.153064 -138.13536)
		(width 0.14224)
		(layer "In4.Cu")
		(net "M_E_DQS_DN<6>")
	)
	(segment
		(start 303.204626 -133.365494)
		(end 303.204626 -132.295646)
		(width 0.14224)
		(layer "In4.Cu")
		(net "M_E_DQS_DN<6>")
	)
	(segment
		(start 302.5902 -126.8984)
		(end 302.5902 -125.799088)
		(width 0.14224)
		(layer "In4.Cu")
		(net "M_E_DQS_DN<6>")
	)
	(segment
		(start 303.551082 -139.368276)
		(end 303.551082 -138.533378)
		(width 0.14224)
		(layer "In4.Cu")
		(net "M_E_DQS_DN<6>")
	)
	(segment
		(start 303.038002 -139.881356)
		(end 303.551082 -139.368276)
		(width 0.14224)
		(layer "In4.Cu")
		(net "M_E_DQS_DN<6>")
	)
	(segment
		(start 303.551082 -127.859282)
		(end 302.5902 -126.8984)
		(width 0.14224)
		(layer "In4.Cu")
		(net "M_E_DQS_DN<6>")
	)
	(segment
		(start 302.604678 -144.841722)
		(end 303.038002 -145.275046)
		(width 0.14224)
		(layer "In9.Cu")
		(net "M_E_DQS_DN<6>")
	)
	(segment
		(start 303.038002 -139.881356)
		(end 302.96485 -139.881356)
		(width 0.14224)
		(layer "In9.Cu")
		(net "M_E_DQS_DN<6>")
	)
	(segment
		(start 302.604678 -140.241528)
		(end 302.604678 -141.503654)
		(width 0.14224)
		(layer "In9.Cu")
		(net "M_E_DQS_DN<6>")
	)
	(segment
		(start 302.96485 -139.881356)
		(end 302.604678 -140.241528)
		(width 0.14224)
		(layer "In9.Cu")
		(net "M_E_DQS_DN<6>")
	)
	(segment
		(start 302.604678 -143.585946)
		(end 302.604678 -144.841722)
		(width 0.14224)
		(layer "In9.Cu")
		(net "M_E_DQS_DN<6>")
	)
	(segment
		(start 302.394112 -141.71422)
		(end 302.394112 -143.37538)
		(width 0.14224)
		(layer "In9.Cu")
		(net "M_E_DQS_DN<6>")
	)
	(segment
		(start 302.604678 -141.503654)
		(end 302.394112 -141.71422)
		(width 0.14224)
		(layer "In9.Cu")
		(net "M_E_DQS_DN<6>")
	)
	(segment
		(start 302.394112 -143.37538)
		(end 302.604678 -143.585946)
		(width 0.14224)
		(layer "In9.Cu")
		(net "M_E_DQS_DN<6>")
	)
	(segment
		(start 293.248334 -145.0594)
		(end 293.472362 -145.0594)
		(width 0.1651)
		(layer "F.Cu")
		(net "M_E_DQS_DN<5>")
	)
	(segment
		(start 294.6146 -122.404886)
		(end 294.7416 -122.531886)
		(width 0.1651)
		(layer "F.Cu")
		(net "M_E_DQS_DN<5>")
	)
	(segment
		(start 287.085278 -114.933476)
		(end 287.26511 -114.933476)
		(width 0.1651)
		(layer "F.Cu")
		(net "M_E_DQS_DN<5>")
	)
	(segment
		(start 292.8112 -119.615458)
		(end 292.8112 -119.87149)
		(width 0.1651)
		(layer "F.Cu")
		(net "M_E_DQS_DN<5>")
	)
	(segment
		(start 286.097218 -113.945162)
		(end 286.222948 -114.070892)
		(width 0.1651)
		(layer "F.Cu")
		(net "M_E_DQS_DN<5>")
	)
	(segment
		(start 289.547046 -117.395498)
		(end 289.672776 -117.521228)
		(width 0.1651)
		(layer "F.Cu")
		(net "M_E_DQS_DN<5>")
	)
	(segment
		(start 293.812722 -120.61698)
		(end 293.812722 -120.867424)
		(width 0.1651)
		(layer "F.Cu")
		(net "M_E_DQS_DN<5>")
	)
	(segment
		(start 288.990278 -116.658644)
		(end 289.115754 -116.78412)
		(width 0.1651)
		(layer "F.Cu")
		(net "M_E_DQS_DN<5>")
	)
	(segment
		(start 289.241484 -117.089936)
		(end 289.42157 -117.089936)
		(width 0.1651)
		(layer "F.Cu")
		(net "M_E_DQS_DN<5>")
	)
	(segment
		(start 287.26511 -114.933476)
		(end 287.390586 -115.058952)
		(width 0.1651)
		(layer "F.Cu")
		(net "M_E_DQS_DN<5>")
	)
	(segment
		(start 292.8112 -119.87149)
		(end 292.95471 -120.015)
		(width 0.1651)
		(layer "F.Cu")
		(net "M_E_DQS_DN<5>")
	)
	(segment
		(start 286.653986 -114.502184)
		(end 286.834072 -114.502184)
		(width 0.1651)
		(layer "F.Cu")
		(net "M_E_DQS_DN<5>")
	)
	(segment
		(start 287.390586 -115.239038)
		(end 287.516316 -115.364768)
		(width 0.1651)
		(layer "F.Cu")
		(net "M_E_DQS_DN<5>")
	)
	(segment
		(start 293.299896 -147.27174)
		(end 293.299896 -146.20367)
		(width 0.1651)
		(layer "F.Cu")
		(net "M_E_DQS_DN<5>")
	)
	(segment
		(start 293.299896 -146.20367)
		(end 292.91788 -145.821654)
		(width 0.1651)
		(layer "F.Cu")
		(net "M_E_DQS_DN<5>")
	)
	(segment
		(start 288.25317 -116.101622)
		(end 288.3789 -116.227352)
		(width 0.1651)
		(layer "F.Cu")
		(net "M_E_DQS_DN<5>")
	)
	(segment
		(start 294.6146 -123.230386)
		(end 294.182546 -123.230386)
		(width 0.1651)
		(layer "F.Cu")
		(net "M_E_DQS_DN<5>")
	)
	(segment
		(start 289.978846 -117.82679)
		(end 290.104576 -117.95252)
		(width 0.1651)
		(layer "F.Cu")
		(net "M_E_DQS_DN<5>")
	)
	(segment
		(start 280.76652 -105.79989)
		(end 280.66492 -105.90149)
		(width 0.0889)
		(layer "F.Cu")
		(net "M_E_DQS_DN<5>")
	)
	(segment
		(start 292.91788 -145.389854)
		(end 293.248334 -145.0594)
		(width 0.1651)
		(layer "F.Cu")
		(net "M_E_DQS_DN<5>")
	)
	(segment
		(start 287.821878 -115.67033)
		(end 287.947608 -115.79606)
		(width 0.1651)
		(layer "F.Cu")
		(net "M_E_DQS_DN<5>")
	)
	(segment
		(start 286.528256 -114.196368)
		(end 286.528256 -114.376454)
		(width 0.1651)
		(layer "F.Cu")
		(net "M_E_DQS_DN<5>")
	)
	(segment
		(start 292.95471 -120.015)
		(end 293.210742 -120.015)
		(width 0.1651)
		(layer "F.Cu")
		(net "M_E_DQS_DN<5>")
	)
	(segment
		(start 294.182546 -123.230386)
		(end 293.8653 -123.547632)
		(width 0.1651)
		(layer "F.Cu")
		(net "M_E_DQS_DN<5>")
	)
	(segment
		(start 280.637234 -102.958138)
		(end 280.637234 -103.980234)
		(width 0.0889)
		(layer "F.Cu")
		(net "M_E_DQS_DN<5>")
	)
	(segment
		(start 292.34511 -119.4054)
		(end 292.601142 -119.4054)
		(width 0.1651)
		(layer "F.Cu")
		(net "M_E_DQS_DN<5>")
	)
	(segment
		(start 289.672776 -117.521228)
		(end 289.85337 -117.521228)
		(width 0.1651)
		(layer "F.Cu")
		(net "M_E_DQS_DN<5>")
	)
	(segment
		(start 293.300404 -147.27174)
		(end 293.299896 -147.27174)
		(width 0.1651)
		(layer "F.Cu")
		(net "M_E_DQS_DN<5>")
	)
	(segment
		(start 280.66492 -108.806996)
		(end 285.116524 -113.2586)
		(width 0.1016)
		(layer "F.Cu")
		(net "M_E_DQS_DN<5>")
	)
	(segment
		(start 291.592 -118.396258)
		(end 291.592 -118.65229)
		(width 0.1651)
		(layer "F.Cu")
		(net "M_E_DQS_DN<5>")
	)
	(segment
		(start 293.675562 -121.184416)
		(end 293.812722 -121.321576)
		(width 0.1651)
		(layer "F.Cu")
		(net "M_E_DQS_DN<5>")
	)
	(segment
		(start 293.93515 -125.366018)
		(end 293.688008 -125.366018)
		(width 0.1651)
		(layer "F.Cu")
		(net "M_E_DQS_DN<5>")
	)
	(segment
		(start 285.971742 -113.6396)
		(end 286.097218 -113.76533)
		(width 0.1651)
		(layer "F.Cu")
		(net "M_E_DQS_DN<5>")
	)
	(segment
		(start 288.3789 -116.227352)
		(end 288.558986 -116.227352)
		(width 0.1651)
		(layer "F.Cu")
		(net "M_E_DQS_DN<5>")
	)
	(segment
		(start 291.73551 -118.7958)
		(end 291.991542 -118.7958)
		(width 0.1651)
		(layer "F.Cu")
		(net "M_E_DQS_DN<5>")
	)
	(segment
		(start 289.42157 -117.089936)
		(end 289.547046 -117.215412)
		(width 0.1651)
		(layer "F.Cu")
		(net "M_E_DQS_DN<5>")
	)
	(segment
		(start 288.684462 -116.352828)
		(end 288.684462 -116.532914)
		(width 0.1651)
		(layer "F.Cu")
		(net "M_E_DQS_DN<5>")
	)
	(segment
		(start 293.812722 -120.867424)
		(end 293.675562 -121.004584)
		(width 0.1651)
		(layer "F.Cu")
		(net "M_E_DQS_DN<5>")
	)
	(segment
		(start 293.812722 -122.036078)
		(end 294.18153 -122.404886)
		(width 0.1651)
		(layer "F.Cu")
		(net "M_E_DQS_DN<5>")
	)
	(segment
		(start 291.394642 -118.1989)
		(end 291.592 -118.396258)
		(width 0.1651)
		(layer "F.Cu")
		(net "M_E_DQS_DN<5>")
	)
	(segment
		(start 288.810192 -116.658644)
		(end 288.990278 -116.658644)
		(width 0.1651)
		(layer "F.Cu")
		(net "M_E_DQS_DN<5>")
	)
	(segment
		(start 292.91788 -145.821654)
		(end 292.91788 -145.389854)
		(width 0.1651)
		(layer "F.Cu")
		(net "M_E_DQS_DN<5>")
	)
	(segment
		(start 285.510478 -113.2586)
		(end 285.891478 -113.6396)
		(width 0.1016)
		(layer "F.Cu")
		(net "M_E_DQS_DN<5>")
	)
	(segment
		(start 294.188896 -125.112272)
		(end 293.93515 -125.366018)
		(width 0.1651)
		(layer "F.Cu")
		(net "M_E_DQS_DN<5>")
	)
	(segment
		(start 288.127694 -115.79606)
		(end 288.25317 -115.921536)
		(width 0.1651)
		(layer "F.Cu")
		(net "M_E_DQS_DN<5>")
	)
	(segment
		(start 290.284662 -117.95252)
		(end 290.531042 -118.1989)
		(width 0.1651)
		(layer "F.Cu")
		(net "M_E_DQS_DN<5>")
	)
	(segment
		(start 280.637234 -103.980234)
		(end 280.76652 -104.10952)
		(width 0.0889)
		(layer "F.Cu")
		(net "M_E_DQS_DN<5>")
	)
	(segment
		(start 290.531042 -118.1989)
		(end 291.394642 -118.1989)
		(width 0.1651)
		(layer "F.Cu")
		(net "M_E_DQS_DN<5>")
	)
	(segment
		(start 289.115754 -116.964206)
		(end 289.241484 -117.089936)
		(width 0.1651)
		(layer "F.Cu")
		(net "M_E_DQS_DN<5>")
	)
	(segment
		(start 293.675562 -121.004584)
		(end 293.675562 -121.184416)
		(width 0.1651)
		(layer "F.Cu")
		(net "M_E_DQS_DN<5>")
	)
	(segment
		(start 286.959548 -114.807746)
		(end 287.085278 -114.933476)
		(width 0.1651)
		(layer "F.Cu")
		(net "M_E_DQS_DN<5>")
	)
	(segment
		(start 288.558986 -116.227352)
		(end 288.684462 -116.352828)
		(width 0.1651)
		(layer "F.Cu")
		(net "M_E_DQS_DN<5>")
	)
	(segment
		(start 288.684462 -116.532914)
		(end 288.810192 -116.658644)
		(width 0.1651)
		(layer "F.Cu")
		(net "M_E_DQS_DN<5>")
	)
	(segment
		(start 293.210742 -120.015)
		(end 293.812722 -120.61698)
		(width 0.1651)
		(layer "F.Cu")
		(net "M_E_DQS_DN<5>")
	)
	(segment
		(start 280.66492 -105.90149)
		(end 280.66492 -108.806996)
		(width 0.1016)
		(layer "F.Cu")
		(net "M_E_DQS_DN<5>")
	)
	(segment
		(start 289.115754 -116.78412)
		(end 289.115754 -116.964206)
		(width 0.1651)
		(layer "F.Cu")
		(net "M_E_DQS_DN<5>")
	)
	(segment
		(start 290.104576 -117.95252)
		(end 290.284662 -117.95252)
		(width 0.1651)
		(layer "F.Cu")
		(net "M_E_DQS_DN<5>")
	)
	(segment
		(start 293.472362 -145.0594)
		(end 293.688008 -145.275046)
		(width 0.1651)
		(layer "F.Cu")
		(net "M_E_DQS_DN<5>")
	)
	(segment
		(start 289.85337 -117.521228)
		(end 289.978846 -117.646704)
		(width 0.1651)
		(layer "F.Cu")
		(net "M_E_DQS_DN<5>")
	)
	(segment
		(start 286.222948 -114.070892)
		(end 286.40278 -114.070892)
		(width 0.1651)
		(layer "F.Cu")
		(net "M_E_DQS_DN<5>")
	)
	(segment
		(start 291.991542 -118.7958)
		(end 292.2016 -119.005858)
		(width 0.1651)
		(layer "F.Cu")
		(net "M_E_DQS_DN<5>")
	)
	(segment
		(start 286.959548 -114.62766)
		(end 286.959548 -114.807746)
		(width 0.1651)
		(layer "F.Cu")
		(net "M_E_DQS_DN<5>")
	)
	(segment
		(start 294.7416 -122.531886)
		(end 294.7416 -123.103386)
		(width 0.1651)
		(layer "F.Cu")
		(net "M_E_DQS_DN<5>")
	)
	(segment
		(start 292.601142 -119.4054)
		(end 292.8112 -119.615458)
		(width 0.1651)
		(layer "F.Cu")
		(net "M_E_DQS_DN<5>")
	)
	(segment
		(start 285.116524 -113.2586)
		(end 285.510478 -113.2586)
		(width 0.1016)
		(layer "F.Cu")
		(net "M_E_DQS_DN<5>")
	)
	(segment
		(start 294.188896 -124.422154)
		(end 294.188896 -125.112272)
		(width 0.1651)
		(layer "F.Cu")
		(net "M_E_DQS_DN<5>")
	)
	(segment
		(start 288.25317 -115.921536)
		(end 288.25317 -116.101622)
		(width 0.1651)
		(layer "F.Cu")
		(net "M_E_DQS_DN<5>")
	)
	(segment
		(start 291.592 -118.65229)
		(end 291.73551 -118.7958)
		(width 0.1651)
		(layer "F.Cu")
		(net "M_E_DQS_DN<5>")
	)
	(segment
		(start 287.696402 -115.364768)
		(end 287.821878 -115.490244)
		(width 0.1651)
		(layer "F.Cu")
		(net "M_E_DQS_DN<5>")
	)
	(segment
		(start 294.18153 -122.404886)
		(end 294.6146 -122.404886)
		(width 0.1651)
		(layer "F.Cu")
		(net "M_E_DQS_DN<5>")
	)
	(segment
		(start 292.2016 -119.26189)
		(end 292.34511 -119.4054)
		(width 0.1651)
		(layer "F.Cu")
		(net "M_E_DQS_DN<5>")
	)
	(segment
		(start 289.978846 -117.646704)
		(end 289.978846 -117.82679)
		(width 0.1651)
		(layer "F.Cu")
		(net "M_E_DQS_DN<5>")
	)
	(segment
		(start 285.891478 -113.6396)
		(end 285.971742 -113.6396)
		(width 0.1016)
		(layer "F.Cu")
		(net "M_E_DQS_DN<5>")
	)
	(segment
		(start 286.528256 -114.376454)
		(end 286.653986 -114.502184)
		(width 0.1651)
		(layer "F.Cu")
		(net "M_E_DQS_DN<5>")
	)
	(segment
		(start 287.390586 -115.058952)
		(end 287.390586 -115.239038)
		(width 0.1651)
		(layer "F.Cu")
		(net "M_E_DQS_DN<5>")
	)
	(segment
		(start 289.547046 -117.215412)
		(end 289.547046 -117.395498)
		(width 0.1651)
		(layer "F.Cu")
		(net "M_E_DQS_DN<5>")
	)
	(segment
		(start 280.76652 -104.10952)
		(end 280.76652 -105.79989)
		(width 0.0889)
		(layer "F.Cu")
		(net "M_E_DQS_DN<5>")
	)
	(segment
		(start 286.097218 -113.76533)
		(end 286.097218 -113.945162)
		(width 0.1651)
		(layer "F.Cu")
		(net "M_E_DQS_DN<5>")
	)
	(segment
		(start 287.516316 -115.364768)
		(end 287.696402 -115.364768)
		(width 0.1651)
		(layer "F.Cu")
		(net "M_E_DQS_DN<5>")
	)
	(segment
		(start 293.8653 -124.098558)
		(end 294.188896 -124.422154)
		(width 0.1651)
		(layer "F.Cu")
		(net "M_E_DQS_DN<5>")
	)
	(segment
		(start 294.7416 -123.103386)
		(end 294.6146 -123.230386)
		(width 0.1651)
		(layer "F.Cu")
		(net "M_E_DQS_DN<5>")
	)
	(segment
		(start 286.834072 -114.502184)
		(end 286.959548 -114.62766)
		(width 0.1651)
		(layer "F.Cu")
		(net "M_E_DQS_DN<5>")
	)
	(segment
		(start 287.947608 -115.79606)
		(end 288.127694 -115.79606)
		(width 0.1651)
		(layer "F.Cu")
		(net "M_E_DQS_DN<5>")
	)
	(segment
		(start 287.821878 -115.490244)
		(end 287.821878 -115.67033)
		(width 0.1651)
		(layer "F.Cu")
		(net "M_E_DQS_DN<5>")
	)
	(segment
		(start 293.8653 -123.547632)
		(end 293.8653 -124.098558)
		(width 0.1651)
		(layer "F.Cu")
		(net "M_E_DQS_DN<5>")
	)
	(segment
		(start 292.2016 -119.005858)
		(end 292.2016 -119.26189)
		(width 0.1651)
		(layer "F.Cu")
		(net "M_E_DQS_DN<5>")
	)
	(segment
		(start 293.812722 -121.321576)
		(end 293.812722 -122.036078)
		(width 0.1651)
		(layer "F.Cu")
		(net "M_E_DQS_DN<5>")
	)
	(segment
		(start 286.40278 -114.070892)
		(end 286.528256 -114.196368)
		(width 0.1651)
		(layer "F.Cu")
		(net "M_E_DQS_DN<5>")
	)
	(via
		(at 293.688008 -145.275046)
		(size 0.508)
		(drill 0.254)
		(layers "F.Cu" "B.Cu")
		(net "M_E_DQS_DN<5>")
	)
	(via
		(at 293.688008 -125.366018)
		(size 0.508)
		(drill 0.254)
		(layers "F.Cu" "B.Cu")
		(net "M_E_DQS_DN<5>")
	)
	(via
		(at 293.688008 -139.881356)
		(size 0.508)
		(drill 0.254)
		(layers "F.Cu" "B.Cu")
		(net "M_E_DQS_DN<5>")
	)
	(segment
		(start 293.462964 -140.1064)
		(end 293.27348 -140.1064)
		(width 0.1651)
		(layer "B.Cu")
		(net "M_E_DQS_DN<5>")
	)
	(segment
		(start 293.17188 -138.912346)
		(end 293.299896 -138.78433)
		(width 0.1651)
		(layer "B.Cu")
		(net "M_E_DQS_DN<5>")
	)
	(segment
		(start 293.17188 -139.166346)
		(end 293.17188 -138.912346)
		(width 0.1651)
		(layer "B.Cu")
		(net "M_E_DQS_DN<5>")
	)
	(segment
		(start 293.299896 -138.78433)
		(end 293.299896 -137.877296)
		(width 0.1651)
		(layer "B.Cu")
		(net "M_E_DQS_DN<5>")
	)
	(segment
		(start 292.91788 -139.420346)
		(end 293.17188 -139.166346)
		(width 0.1651)
		(layer "B.Cu")
		(net "M_E_DQS_DN<5>")
	)
	(segment
		(start 293.688008 -139.881356)
		(end 293.462964 -140.1064)
		(width 0.1651)
		(layer "B.Cu")
		(net "M_E_DQS_DN<5>")
	)
	(segment
		(start 293.27348 -140.1064)
		(end 292.91788 -139.7508)
		(width 0.1651)
		(layer "B.Cu")
		(net "M_E_DQS_DN<5>")
	)
	(segment
		(start 293.299896 -137.877296)
		(end 293.300404 -137.877296)
		(width 0.1651)
		(layer "B.Cu")
		(net "M_E_DQS_DN<5>")
	)
	(segment
		(start 292.91788 -139.7508)
		(end 292.91788 -139.420346)
		(width 0.1651)
		(layer "B.Cu")
		(net "M_E_DQS_DN<5>")
	)
	(segment
		(start 293.254684 -144.890744)
		(end 293.638986 -145.275046)
		(width 0.14224)
		(layer "In9.Cu")
		(net "M_E_DQS_DN<5>")
	)
	(segment
		(start 293.044118 -141.71422)
		(end 293.044118 -143.37538)
		(width 0.14224)
		(layer "In9.Cu")
		(net "M_E_DQS_DN<5>")
	)
	(segment
		(start 293.638986 -145.275046)
		(end 293.688008 -145.275046)
		(width 0.14224)
		(layer "In9.Cu")
		(net "M_E_DQS_DN<5>")
	)
	(segment
		(start 293.254684 -140.27531)
		(end 293.254684 -141.503654)
		(width 0.14224)
		(layer "In9.Cu")
		(net "M_E_DQS_DN<5>")
	)
	(segment
		(start 293.254684 -141.503654)
		(end 293.044118 -141.71422)
		(width 0.14224)
		(layer "In9.Cu")
		(net "M_E_DQS_DN<5>")
	)
	(segment
		(start 293.688008 -139.881356)
		(end 293.648638 -139.881356)
		(width 0.14224)
		(layer "In9.Cu")
		(net "M_E_DQS_DN<5>")
	)
	(segment
		(start 293.254684 -143.585946)
		(end 293.254684 -144.890744)
		(width 0.14224)
		(layer "In9.Cu")
		(net "M_E_DQS_DN<5>")
	)
	(segment
		(start 293.044118 -143.37538)
		(end 293.254684 -143.585946)
		(width 0.14224)
		(layer "In9.Cu")
		(net "M_E_DQS_DN<5>")
	)
	(segment
		(start 293.648638 -139.881356)
		(end 293.254684 -140.27531)
		(width 0.14224)
		(layer "In9.Cu")
		(net "M_E_DQS_DN<5>")
	)
	(segment
		(start 294.201088 -139.554712)
		(end 294.201088 -128.288542)
		(width 0.14224)
		(layer "In11.Cu")
		(net "M_E_DQS_DN<5>")
	)
	(segment
		(start 293.243 -126.873)
		(end 293.243 -125.811026)
		(width 0.14224)
		(layer "In11.Cu")
		(net "M_E_DQS_DN<5>")
	)
	(segment
		(start 293.63416 -127.26416)
		(end 293.243 -126.873)
		(width 0.14224)
		(layer "In11.Cu")
		(net "M_E_DQS_DN<5>")
	)
	(segment
		(start 293.243 -125.811026)
		(end 293.688008 -125.366018)
		(width 0.14224)
		(layer "In11.Cu")
		(net "M_E_DQS_DN<5>")
	)
	(segment
		(start 293.688008 -139.881356)
		(end 293.874444 -139.881356)
		(width 0.14224)
		(layer "In11.Cu")
		(net "M_E_DQS_DN<5>")
	)
	(segment
		(start 294.201088 -128.288542)
		(end 293.63416 -127.721614)
		(width 0.14224)
		(layer "In11.Cu")
		(net "M_E_DQS_DN<5>")
	)
	(segment
		(start 293.874444 -139.881356)
		(end 294.201088 -139.554712)
		(width 0.14224)
		(layer "In11.Cu")
		(net "M_E_DQS_DN<5>")
	)
	(segment
		(start 293.63416 -127.721614)
		(end 293.63416 -127.26416)
		(width 0.14224)
		(layer "In11.Cu")
		(net "M_E_DQS_DN<5>")
	)
	(segment
		(start 283.95041 -147.27174)
		(end 283.949648 -147.27174)
		(width 0.1651)
		(layer "F.Cu")
		(net "M_E_DQS_DN<4>")
	)
	(segment
		(start 283.567632 -145.821654)
		(end 283.567632 -145.389854)
		(width 0.1651)
		(layer "F.Cu")
		(net "M_E_DQS_DN<4>")
	)
	(segment
		(start 283.949648 -146.20367)
		(end 283.567632 -145.821654)
		(width 0.1651)
		(layer "F.Cu")
		(net "M_E_DQS_DN<4>")
	)
	(segment
		(start 283.949648 -147.27174)
		(end 283.949648 -146.20367)
		(width 0.1651)
		(layer "F.Cu")
		(net "M_E_DQS_DN<4>")
	)
	(segment
		(start 283.898086 -145.0594)
		(end 284.122114 -145.0594)
		(width 0.1651)
		(layer "F.Cu")
		(net "M_E_DQS_DN<4>")
	)
	(segment
		(start 284.122114 -145.0594)
		(end 284.33776 -145.275046)
		(width 0.1651)
		(layer "F.Cu")
		(net "M_E_DQS_DN<4>")
	)
	(segment
		(start 283.567632 -145.389854)
		(end 283.898086 -145.0594)
		(width 0.1651)
		(layer "F.Cu")
		(net "M_E_DQS_DN<4>")
	)
	(segment
		(start 272.910808 -99.490784)
		(end 273.482308 -99.490784)
		(width 0.1651)
		(layer "F.Cu")
		(net "M_E_DQS_DN<4>")
	)
	(via
		(at 284.33776 -139.881356)
		(size 0.508)
		(drill 0.254)
		(layers "F.Cu" "B.Cu")
		(net "M_E_DQS_DN<4>")
	)
	(via
		(at 273.482308 -99.490784)
		(size 0.508)
		(drill 0.254)
		(layers "F.Cu" "B.Cu")
		(net "M_E_DQS_DN<4>")
	)
	(via
		(at 284.33776 -145.275046)
		(size 0.508)
		(drill 0.254)
		(layers "F.Cu" "B.Cu")
		(net "M_E_DQS_DN<4>")
	)
	(segment
		(start 283.923232 -140.1064)
		(end 283.567632 -139.7508)
		(width 0.1651)
		(layer "B.Cu")
		(net "M_E_DQS_DN<4>")
	)
	(segment
		(start 284.112716 -140.1064)
		(end 283.923232 -140.1064)
		(width 0.1651)
		(layer "B.Cu")
		(net "M_E_DQS_DN<4>")
	)
	(segment
		(start 283.821632 -139.166346)
		(end 283.821632 -138.912346)
		(width 0.1651)
		(layer "B.Cu")
		(net "M_E_DQS_DN<4>")
	)
	(segment
		(start 284.33776 -139.881356)
		(end 284.112716 -140.1064)
		(width 0.1651)
		(layer "B.Cu")
		(net "M_E_DQS_DN<4>")
	)
	(segment
		(start 283.821632 -138.912346)
		(end 283.949902 -138.784076)
		(width 0.1651)
		(layer "B.Cu")
		(net "M_E_DQS_DN<4>")
	)
	(segment
		(start 283.949902 -137.877296)
		(end 283.95041 -137.877296)
		(width 0.1651)
		(layer "B.Cu")
		(net "M_E_DQS_DN<4>")
	)
	(segment
		(start 283.949902 -138.784076)
		(end 283.949902 -137.877296)
		(width 0.1651)
		(layer "B.Cu")
		(net "M_E_DQS_DN<4>")
	)
	(segment
		(start 283.567632 -139.420346)
		(end 283.821632 -139.166346)
		(width 0.1651)
		(layer "B.Cu")
		(net "M_E_DQS_DN<4>")
	)
	(segment
		(start 283.567632 -139.7508)
		(end 283.567632 -139.420346)
		(width 0.1651)
		(layer "B.Cu")
		(net "M_E_DQS_DN<4>")
	)
	(segment
		(start 284.901894 -129.24536)
		(end 284.744414 -129.40284)
		(width 0.14224)
		(layer "In4.Cu")
		(net "M_E_DQS_DN<4>")
	)
	(segment
		(start 284.744414 -136.086088)
		(end 284.901894 -136.243568)
		(width 0.14224)
		(layer "In4.Cu")
		(net "M_E_DQS_DN<4>")
	)
	(segment
		(start 283.90469 -140.241528)
		(end 283.90469 -141.503654)
		(width 0.14224)
		(layer "In4.Cu")
		(net "M_E_DQS_DN<4>")
	)
	(segment
		(start 284.901894 -130.963416)
		(end 284.761432 -131.103878)
		(width 0.14224)
		(layer "In4.Cu")
		(net "M_E_DQS_DN<4>")
	)
	(segment
		(start 283.90469 -141.503654)
		(end 283.694124 -141.71422)
		(width 0.14224)
		(layer "In4.Cu")
		(net "M_E_DQS_DN<4>")
	)
	(segment
		(start 284.901894 -132.632196)
		(end 284.744414 -132.789676)
		(width 0.14224)
		(layer "In4.Cu")
		(net "M_E_DQS_DN<4>")
	)
	(segment
		(start 284.69844 -128.58242)
		(end 284.901894 -128.785874)
		(width 0.14224)
		(layer "In4.Cu")
		(net "M_E_DQS_DN<4>")
	)
	(segment
		(start 275.013674 -106.5403)
		(end 275.013674 -106.562398)
		(width 0.0889)
		(layer "In4.Cu")
		(net "M_E_DQS_DN<4>")
	)
	(segment
		(start 284.617414 -139.881356)
		(end 284.33776 -139.881356)
		(width 0.14224)
		(layer "In4.Cu")
		(net "M_E_DQS_DN<4>")
	)
	(segment
		(start 284.901894 -132.378196)
		(end 284.901894 -132.632196)
		(width 0.14224)
		(layer "In4.Cu")
		(net "M_E_DQS_DN<4>")
	)
	(segment
		(start 282.903168 -124.521214)
		(end 283.082746 -124.700792)
		(width 0.14224)
		(layer "In4.Cu")
		(net "M_E_DQS_DN<4>")
	)
	(segment
		(start 284.901894 -128.785874)
		(end 284.901894 -129.24536)
		(width 0.14224)
		(layer "In4.Cu")
		(net "M_E_DQS_DN<4>")
	)
	(segment
		(start 284.206188 -128.58242)
		(end 284.69844 -128.58242)
		(width 0.14224)
		(layer "In4.Cu")
		(net "M_E_DQS_DN<4>")
	)
	(segment
		(start 282.72359 -124.118624)
		(end 282.903168 -124.298202)
		(width 0.14224)
		(layer "In4.Cu")
		(net "M_E_DQS_DN<4>")
	)
	(segment
		(start 284.264862 -139.881356)
		(end 283.90469 -140.241528)
		(width 0.14224)
		(layer "In4.Cu")
		(net "M_E_DQS_DN<4>")
	)
	(segment
		(start 284.744414 -137.872978)
		(end 284.901894 -138.030458)
		(width 0.14224)
		(layer "In4.Cu")
		(net "M_E_DQS_DN<4>")
	)
	(segment
		(start 284.901894 -131.809236)
		(end 284.744414 -131.966716)
		(width 0.14224)
		(layer "In4.Cu")
		(net "M_E_DQS_DN<4>")
	)
	(segment
		(start 284.744414 -137.050018)
		(end 284.901894 -137.207498)
		(width 0.14224)
		(layer "In4.Cu")
		(net "M_E_DQS_DN<4>")
	)
	(segment
		(start 284.901894 -133.201156)
		(end 284.901894 -133.455156)
		(width 0.14224)
		(layer "In4.Cu")
		(net "M_E_DQS_DN<4>")
	)
	(segment
		(start 284.781498 -130.54838)
		(end 284.901894 -130.668776)
		(width 0.14224)
		(layer "In4.Cu")
		(net "M_E_DQS_DN<4>")
	)
	(segment
		(start 284.901894 -139.596876)
		(end 284.617414 -139.881356)
		(width 0.14224)
		(layer "In4.Cu")
		(net "M_E_DQS_DN<4>")
	)
	(segment
		(start 282.321 -123.716034)
		(end 282.321 -123.939046)
		(width 0.14224)
		(layer "In4.Cu")
		(net "M_E_DQS_DN<4>")
	)
	(segment
		(start 284.901894 -130.668776)
		(end 284.901894 -130.963416)
		(width 0.14224)
		(layer "In4.Cu")
		(net "M_E_DQS_DN<4>")
	)
	(segment
		(start 282.500832 -124.118624)
		(end 282.72359 -124.118624)
		(width 0.14224)
		(layer "In4.Cu")
		(net "M_E_DQS_DN<4>")
	)
	(segment
		(start 284.744414 -133.612636)
		(end 284.744414 -133.866636)
		(width 0.14224)
		(layer "In4.Cu")
		(net "M_E_DQS_DN<4>")
	)
	(segment
		(start 283.082746 -124.700792)
		(end 283.305758 -124.700792)
		(width 0.14224)
		(layer "In4.Cu")
		(net "M_E_DQS_DN<4>")
	)
	(segment
		(start 275.053044 -106.50093)
		(end 275.013674 -106.5403)
		(width 0.0889)
		(layer "In4.Cu")
		(net "M_E_DQS_DN<4>")
	)
	(segment
		(start 273.887438 -100.38334)
		(end 274.79244 -101.288342)
		(width 0.0889)
		(layer "In4.Cu")
		(net "M_E_DQS_DN<4>")
	)
	(segment
		(start 284.901894 -138.853418)
		(end 284.901894 -139.596876)
		(width 0.14224)
		(layer "In4.Cu")
		(net "M_E_DQS_DN<4>")
	)
	(segment
		(start 284.744414 -134.582662)
		(end 284.744414 -134.836662)
		(width 0.14224)
		(layer "In4.Cu")
		(net "M_E_DQS_DN<4>")
	)
	(segment
		(start 283.694124 -141.71422)
		(end 283.694124 -143.37538)
		(width 0.14224)
		(layer "In4.Cu")
		(net "M_E_DQS_DN<4>")
	)
	(segment
		(start 284.901894 -137.207498)
		(end 284.901894 -137.461498)
		(width 0.14224)
		(layer "In4.Cu")
		(net "M_E_DQS_DN<4>")
	)
	(segment
		(start 283.738574 -125.750066)
		(end 284.119066 -126.130558)
		(width 0.14224)
		(layer "In4.Cu")
		(net "M_E_DQS_DN<4>")
	)
	(segment
		(start 284.901894 -134.994142)
		(end 284.901894 -135.674608)
		(width 0.14224)
		(layer "In4.Cu")
		(net "M_E_DQS_DN<4>")
	)
	(segment
		(start 284.744414 -134.836662)
		(end 284.901894 -134.994142)
		(width 0.14224)
		(layer "In4.Cu")
		(net "M_E_DQS_DN<4>")
	)
	(segment
		(start 284.901894 -134.024116)
		(end 284.901894 -134.425182)
		(width 0.14224)
		(layer "In4.Cu")
		(net "M_E_DQS_DN<4>")
	)
	(segment
		(start 282.321 -123.939046)
		(end 282.500832 -124.118624)
		(width 0.14224)
		(layer "In4.Cu")
		(net "M_E_DQS_DN<4>")
	)
	(segment
		(start 283.694124 -143.37538)
		(end 283.90469 -143.585946)
		(width 0.14224)
		(layer "In4.Cu")
		(net "M_E_DQS_DN<4>")
	)
	(segment
		(start 283.90469 -144.841976)
		(end 284.33776 -145.275046)
		(width 0.14224)
		(layer "In4.Cu")
		(net "M_E_DQS_DN<4>")
	)
	(segment
		(start 275.013674 -106.562398)
		(end 275.013674 -116.408708)
		(width 0.14224)
		(layer "In4.Cu")
		(net "M_E_DQS_DN<4>")
	)
	(segment
		(start 284.781498 -130.29438)
		(end 284.781498 -130.54838)
		(width 0.14224)
		(layer "In4.Cu")
		(net "M_E_DQS_DN<4>")
	)
	(segment
		(start 284.901894 -138.030458)
		(end 284.901894 -138.284458)
		(width 0.14224)
		(layer "In4.Cu")
		(net "M_E_DQS_DN<4>")
	)
	(segment
		(start 284.901894 -134.425182)
		(end 284.744414 -134.582662)
		(width 0.14224)
		(layer "In4.Cu")
		(net "M_E_DQS_DN<4>")
	)
	(segment
		(start 284.644592 -127.004318)
		(end 284.189678 -127.004318)
		(width 0.14224)
		(layer "In4.Cu")
		(net "M_E_DQS_DN<4>")
	)
	(segment
		(start 284.901894 -131.49834)
		(end 284.901894 -131.809236)
		(width 0.14224)
		(layer "In4.Cu")
		(net "M_E_DQS_DN<4>")
	)
	(segment
		(start 284.744414 -136.796018)
		(end 284.744414 -137.050018)
		(width 0.14224)
		(layer "In4.Cu")
		(net "M_E_DQS_DN<4>")
	)
	(segment
		(start 282.903168 -124.298202)
		(end 282.903168 -124.521214)
		(width 0.14224)
		(layer "In4.Cu")
		(net "M_E_DQS_DN<4>")
	)
	(segment
		(start 284.744414 -135.832088)
		(end 284.744414 -136.086088)
		(width 0.14224)
		(layer "In4.Cu")
		(net "M_E_DQS_DN<4>")
	)
	(segment
		(start 284.744414 -138.695938)
		(end 284.901894 -138.853418)
		(width 0.14224)
		(layer "In4.Cu")
		(net "M_E_DQS_DN<4>")
	)
	(segment
		(start 284.744414 -132.220716)
		(end 284.901894 -132.378196)
		(width 0.14224)
		(layer "In4.Cu")
		(net "M_E_DQS_DN<4>")
	)
	(segment
		(start 284.901894 -133.455156)
		(end 284.744414 -133.612636)
		(width 0.14224)
		(layer "In4.Cu")
		(net "M_E_DQS_DN<4>")
	)
	(segment
		(start 283.90469 -143.585946)
		(end 283.90469 -144.841976)
		(width 0.14224)
		(layer "In4.Cu")
		(net "M_E_DQS_DN<4>")
	)
	(segment
		(start 284.761432 -131.357878)
		(end 284.901894 -131.49834)
		(width 0.14224)
		(layer "In4.Cu")
		(net "M_E_DQS_DN<4>")
	)
	(segment
		(start 284.644592 -126.130558)
		(end 284.86608 -126.352046)
		(width 0.14224)
		(layer "In4.Cu")
		(net "M_E_DQS_DN<4>")
	)
	(segment
		(start 284.901894 -136.243568)
		(end 284.901894 -136.638538)
		(width 0.14224)
		(layer "In4.Cu")
		(net "M_E_DQS_DN<4>")
	)
	(segment
		(start 284.744414 -129.65684)
		(end 284.901894 -129.81432)
		(width 0.14224)
		(layer "In4.Cu")
		(net "M_E_DQS_DN<4>")
	)
	(segment
		(start 273.829018 -100.282248)
		(end 273.887438 -100.38334)
		(width 0.0889)
		(layer "In4.Cu")
		(net "M_E_DQS_DN<4>")
	)
	(segment
		(start 274.79244 -101.288342)
		(end 274.79244 -102.99319)
		(width 0.0889)
		(layer "In4.Cu")
		(net "M_E_DQS_DN<4>")
	)
	(segment
		(start 284.744414 -132.789676)
		(end 284.744414 -133.043676)
		(width 0.14224)
		(layer "In4.Cu")
		(net "M_E_DQS_DN<4>")
	)
	(segment
		(start 275.013674 -116.408708)
		(end 282.321 -123.716034)
		(width 0.14224)
		(layer "In4.Cu")
		(net "M_E_DQS_DN<4>")
	)
	(segment
		(start 284.744414 -133.866636)
		(end 284.901894 -134.024116)
		(width 0.14224)
		(layer "In4.Cu")
		(net "M_E_DQS_DN<4>")
	)
	(segment
		(start 283.838396 -128.214628)
		(end 284.206188 -128.58242)
		(width 0.14224)
		(layer "In4.Cu")
		(net "M_E_DQS_DN<4>")
	)
	(segment
		(start 284.744414 -131.966716)
		(end 284.744414 -132.220716)
		(width 0.14224)
		(layer "In4.Cu")
		(net "M_E_DQS_DN<4>")
	)
	(segment
		(start 283.738574 -125.133608)
		(end 283.738574 -125.750066)
		(width 0.14224)
		(layer "In4.Cu")
		(net "M_E_DQS_DN<4>")
	)
	(segment
		(start 284.761432 -131.103878)
		(end 284.761432 -131.357878)
		(width 0.14224)
		(layer "In4.Cu")
		(net "M_E_DQS_DN<4>")
	)
	(segment
		(start 284.901894 -130.173984)
		(end 284.781498 -130.29438)
		(width 0.14224)
		(layer "In4.Cu")
		(net "M_E_DQS_DN<4>")
	)
	(segment
		(start 284.33776 -139.881356)
		(end 284.264862 -139.881356)
		(width 0.14224)
		(layer "In4.Cu")
		(net "M_E_DQS_DN<4>")
	)
	(segment
		(start 284.901894 -129.81432)
		(end 284.901894 -130.173984)
		(width 0.14224)
		(layer "In4.Cu")
		(net "M_E_DQS_DN<4>")
	)
	(segment
		(start 284.901894 -136.638538)
		(end 284.744414 -136.796018)
		(width 0.14224)
		(layer "In4.Cu")
		(net "M_E_DQS_DN<4>")
	)
	(segment
		(start 284.86608 -126.78283)
		(end 284.644592 -127.004318)
		(width 0.14224)
		(layer "In4.Cu")
		(net "M_E_DQS_DN<4>")
	)
	(segment
		(start 284.86608 -126.352046)
		(end 284.86608 -126.78283)
		(width 0.14224)
		(layer "In4.Cu")
		(net "M_E_DQS_DN<4>")
	)
	(segment
		(start 283.305758 -124.700792)
		(end 283.738574 -125.133608)
		(width 0.14224)
		(layer "In4.Cu")
		(net "M_E_DQS_DN<4>")
	)
	(segment
		(start 284.119066 -126.130558)
		(end 284.644592 -126.130558)
		(width 0.14224)
		(layer "In4.Cu")
		(net "M_E_DQS_DN<4>")
	)
	(segment
		(start 284.744414 -133.043676)
		(end 284.901894 -133.201156)
		(width 0.14224)
		(layer "In4.Cu")
		(net "M_E_DQS_DN<4>")
	)
	(segment
		(start 284.744414 -138.441938)
		(end 284.744414 -138.695938)
		(width 0.14224)
		(layer "In4.Cu")
		(net "M_E_DQS_DN<4>")
	)
	(segment
		(start 284.901894 -135.674608)
		(end 284.744414 -135.832088)
		(width 0.14224)
		(layer "In4.Cu")
		(net "M_E_DQS_DN<4>")
	)
	(segment
		(start 284.189678 -127.004318)
		(end 283.838396 -127.3556)
		(width 0.14224)
		(layer "In4.Cu")
		(net "M_E_DQS_DN<4>")
	)
	(segment
		(start 284.901894 -137.461498)
		(end 284.744414 -137.618978)
		(width 0.14224)
		(layer "In4.Cu")
		(net "M_E_DQS_DN<4>")
	)
	(segment
		(start 275.053044 -103.253794)
		(end 275.053044 -106.50093)
		(width 0.0889)
		(layer "In4.Cu")
		(net "M_E_DQS_DN<4>")
	)
	(segment
		(start 283.838396 -127.3556)
		(end 283.838396 -128.214628)
		(width 0.14224)
		(layer "In4.Cu")
		(net "M_E_DQS_DN<4>")
	)
	(segment
		(start 284.901894 -138.284458)
		(end 284.744414 -138.441938)
		(width 0.14224)
		(layer "In4.Cu")
		(net "M_E_DQS_DN<4>")
	)
	(segment
		(start 274.79244 -102.99319)
		(end 275.053044 -103.253794)
		(width 0.0889)
		(layer "In4.Cu")
		(net "M_E_DQS_DN<4>")
	)
	(segment
		(start 284.744414 -137.618978)
		(end 284.744414 -137.872978)
		(width 0.14224)
		(layer "In4.Cu")
		(net "M_E_DQS_DN<4>")
	)
	(segment
		(start 284.744414 -129.40284)
		(end 284.744414 -129.65684)
		(width 0.14224)
		(layer "In4.Cu")
		(net "M_E_DQS_DN<4>")
	)
	(arc
		(start 273.482308 -99.490784)
		(mid 273.633747 -99.896116)
		(end 273.829018 -100.282248)
		(width 0.0889)
		(layer "In4.Cu")
		(net "M_E_DQS_DN<4>")
	)
	(segment
		(start 229.563168 -111.495332)
		(end 229.36581 -111.69269)
		(width 0.1651)
		(layer "F.Cu")
		(net "M_E_DQS_DN<3>")
	)
	(segment
		(start 233.604308 -107.274614)
		(end 233.604308 -107.454192)
		(width 0.1651)
		(layer "F.Cu")
		(net "M_E_DQS_DN<3>")
	)
	(segment
		(start 228.855016 -123.138184)
		(end 228.855016 -123.368816)
		(width 0.1651)
		(layer "F.Cu")
		(net "M_E_DQS_DN<3>")
	)
	(segment
		(start 233.40695 -107.65155)
		(end 233.227372 -107.65155)
		(width 0.1651)
		(layer "F.Cu")
		(net "M_E_DQS_DN<3>")
	)
	(segment
		(start 229.0191 -121.3485)
		(end 228.88702 -121.48058)
		(width 0.1651)
		(layer "F.Cu")
		(net "M_E_DQS_DN<3>")
	)
	(segment
		(start 234.556554 -106.501946)
		(end 234.376976 -106.501946)
		(width 0.1651)
		(layer "F.Cu")
		(net "M_E_DQS_DN<3>")
	)
	(segment
		(start 231.090216 -109.968284)
		(end 230.910638 -109.968284)
		(width 0.1651)
		(layer "F.Cu")
		(net "M_E_DQS_DN<3>")
	)
	(segment
		(start 228.88702 -121.48058)
		(end 228.88702 -121.74982)
		(width 0.1651)
		(layer "F.Cu")
		(net "M_E_DQS_DN<3>")
	)
	(segment
		(start 228.48062 -115.658392)
		(end 228.82987 -116.007642)
		(width 0.1651)
		(layer "F.Cu")
		(net "M_E_DQS_DN<3>")
	)
	(segment
		(start 234.753912 -106.304588)
		(end 234.556554 -106.501946)
		(width 0.1651)
		(layer "F.Cu")
		(net "M_E_DQS_DN<3>")
	)
	(segment
		(start 243.910104 -101.653086)
		(end 243.910104 -102.504494)
		(width 0.0889)
		(layer "F.Cu")
		(net "M_E_DQS_DN<3>")
	)
	(segment
		(start 230.515414 -110.543086)
		(end 230.335836 -110.543086)
		(width 0.1651)
		(layer "F.Cu")
		(net "M_E_DQS_DN<3>")
	)
	(segment
		(start 228.8794 -122.5804)
		(end 229.0191 -122.7201)
		(width 0.1651)
		(layer "F.Cu")
		(net "M_E_DQS_DN<3>")
	)
	(segment
		(start 234.17911 -106.699812)
		(end 234.17911 -106.87939)
		(width 0.1651)
		(layer "F.Cu")
		(net "M_E_DQS_DN<3>")
	)
	(segment
		(start 242.363244 -104.051354)
		(end 239.607344 -104.051354)
		(width 0.1016)
		(layer "F.Cu")
		(net "M_E_DQS_DN<3>")
	)
	(segment
		(start 229.417118 -116.007642)
		(end 229.542086 -116.13261)
		(width 0.1651)
		(layer "F.Cu")
		(net "M_E_DQS_DN<3>")
	)
	(segment
		(start 231.862376 -109.016546)
		(end 231.862376 -109.196124)
		(width 0.1651)
		(layer "F.Cu")
		(net "M_E_DQS_DN<3>")
	)
	(segment
		(start 228.48062 -120.595644)
		(end 229.0191 -121.134124)
		(width 0.1651)
		(layer "F.Cu")
		(net "M_E_DQS_DN<3>")
	)
	(segment
		(start 229.0191 -121.134124)
		(end 229.0191 -121.3485)
		(width 0.1651)
		(layer "F.Cu")
		(net "M_E_DQS_DN<3>")
	)
	(segment
		(start 229.571296 -124.364496)
		(end 229.571296 -125.040136)
		(width 0.1651)
		(layer "F.Cu")
		(net "M_E_DQS_DN<3>")
	)
	(segment
		(start 233.029506 -107.849416)
		(end 233.029506 -108.028994)
		(width 0.1651)
		(layer "F.Cu")
		(net "M_E_DQS_DN<3>")
	)
	(segment
		(start 228.4476 -113.3221)
		(end 228.5746 -113.4491)
		(width 0.1651)
		(layer "F.Cu")
		(net "M_E_DQS_DN<3>")
	)
	(segment
		(start 230.13797 -110.740952)
		(end 230.13797 -110.92053)
		(width 0.1651)
		(layer "F.Cu")
		(net "M_E_DQS_DN<3>")
	)
	(segment
		(start 229.186232 -111.69269)
		(end 228.988366 -111.890556)
		(width 0.1651)
		(layer "F.Cu")
		(net "M_E_DQS_DN<3>")
	)
	(segment
		(start 228.64826 -145.0594)
		(end 228.872288 -145.0594)
		(width 0.1651)
		(layer "F.Cu")
		(net "M_E_DQS_DN<3>")
	)
	(segment
		(start 234.753912 -106.12501)
		(end 234.753912 -106.304588)
		(width 0.1651)
		(layer "F.Cu")
		(net "M_E_DQS_DN<3>")
	)
	(segment
		(start 228.82987 -114.730022)
		(end 228.48062 -115.079272)
		(width 0.1651)
		(layer "F.Cu")
		(net "M_E_DQS_DN<3>")
	)
	(segment
		(start 228.4476 -113.0427)
		(end 228.4476 -113.3221)
		(width 0.1651)
		(layer "F.Cu")
		(net "M_E_DQS_DN<3>")
	)
	(segment
		(start 229.0191 -123.5329)
		(end 229.0191 -123.8123)
		(width 0.1651)
		(layer "F.Cu")
		(net "M_E_DQS_DN<3>")
	)
	(segment
		(start 233.029506 -108.028994)
		(end 232.814622 -108.243878)
		(width 0.1651)
		(layer "F.Cu")
		(net "M_E_DQS_DN<3>")
	)
	(segment
		(start 234.951778 -105.927144)
		(end 234.753912 -106.12501)
		(width 0.1651)
		(layer "F.Cu")
		(net "M_E_DQS_DN<3>")
	)
	(segment
		(start 229.0191 -122.9741)
		(end 228.855016 -123.138184)
		(width 0.1651)
		(layer "F.Cu")
		(net "M_E_DQS_DN<3>")
	)
	(segment
		(start 230.712772 -110.16615)
		(end 230.712772 -110.345728)
		(width 0.1651)
		(layer "F.Cu")
		(net "M_E_DQS_DN<3>")
	)
	(segment
		(start 228.88702 -121.74982)
		(end 229.0191 -121.8819)
		(width 0.1651)
		(layer "F.Cu")
		(net "M_E_DQS_DN<3>")
	)
	(segment
		(start 228.48062 -115.079272)
		(end 228.48062 -115.658392)
		(width 0.1651)
		(layer "F.Cu")
		(net "M_E_DQS_DN<3>")
	)
	(segment
		(start 232.437178 -108.621322)
		(end 232.23982 -108.81868)
		(width 0.1651)
		(layer "F.Cu")
		(net "M_E_DQS_DN<3>")
	)
	(segment
		(start 228.882702 -114.036602)
		(end 229.013512 -114.036602)
		(width 0.1651)
		(layer "F.Cu")
		(net "M_E_DQS_DN<3>")
	)
	(segment
		(start 232.635044 -108.243878)
		(end 232.437178 -108.441744)
		(width 0.1651)
		(layer "F.Cu")
		(net "M_E_DQS_DN<3>")
	)
	(segment
		(start 228.5746 -112.4839)
		(end 228.5746 -112.9157)
		(width 0.1651)
		(layer "F.Cu")
		(net "M_E_DQS_DN<3>")
	)
	(segment
		(start 243.854224 -102.560374)
		(end 242.363244 -104.051354)
		(width 0.1016)
		(layer "F.Cu")
		(net "M_E_DQS_DN<3>")
	)
	(segment
		(start 231.48544 -109.393482)
		(end 231.287574 -109.591348)
		(width 0.1651)
		(layer "F.Cu")
		(net "M_E_DQS_DN<3>")
	)
	(segment
		(start 229.542086 -116.569744)
		(end 229.410768 -116.701062)
		(width 0.1651)
		(layer "F.Cu")
		(net "M_E_DQS_DN<3>")
	)
	(segment
		(start 229.761034 -111.117888)
		(end 229.563168 -111.315754)
		(width 0.1651)
		(layer "F.Cu")
		(net "M_E_DQS_DN<3>")
	)
	(segment
		(start 228.872288 -145.0594)
		(end 229.087934 -145.275046)
		(width 0.1651)
		(layer "F.Cu")
		(net "M_E_DQS_DN<3>")
	)
	(segment
		(start 234.376976 -106.501946)
		(end 234.17911 -106.699812)
		(width 0.1651)
		(layer "F.Cu")
		(net "M_E_DQS_DN<3>")
	)
	(segment
		(start 230.335836 -110.543086)
		(end 230.13797 -110.740952)
		(width 0.1651)
		(layer "F.Cu")
		(net "M_E_DQS_DN<3>")
	)
	(segment
		(start 231.862376 -109.196124)
		(end 231.665018 -109.393482)
		(width 0.1651)
		(layer "F.Cu")
		(net "M_E_DQS_DN<3>")
	)
	(segment
		(start 228.82987 -116.701062)
		(end 228.48062 -117.050312)
		(width 0.1651)
		(layer "F.Cu")
		(net "M_E_DQS_DN<3>")
	)
	(segment
		(start 229.0191 -121.8819)
		(end 229.0191 -122.1867)
		(width 0.1651)
		(layer "F.Cu")
		(net "M_E_DQS_DN<3>")
	)
	(segment
		(start 231.287574 -109.591348)
		(end 231.287574 -109.770926)
		(width 0.1651)
		(layer "F.Cu")
		(net "M_E_DQS_DN<3>")
	)
	(segment
		(start 228.8794 -122.3264)
		(end 228.8794 -122.5804)
		(width 0.1651)
		(layer "F.Cu")
		(net "M_E_DQS_DN<3>")
	)
	(segment
		(start 230.13797 -110.92053)
		(end 229.940612 -111.117888)
		(width 0.1651)
		(layer "F.Cu")
		(net "M_E_DQS_DN<3>")
	)
	(segment
		(start 233.604308 -107.454192)
		(end 233.40695 -107.65155)
		(width 0.1651)
		(layer "F.Cu")
		(net "M_E_DQS_DN<3>")
	)
	(segment
		(start 229.335076 -125.276356)
		(end 229.087934 -125.276356)
		(width 0.1651)
		(layer "F.Cu")
		(net "M_E_DQS_DN<3>")
	)
	(segment
		(start 228.988366 -111.890556)
		(end 228.988366 -112.070134)
		(width 0.1651)
		(layer "F.Cu")
		(net "M_E_DQS_DN<3>")
	)
	(segment
		(start 228.699822 -147.27174)
		(end 228.699822 -146.20367)
		(width 0.1651)
		(layer "F.Cu")
		(net "M_E_DQS_DN<3>")
	)
	(segment
		(start 232.437178 -108.441744)
		(end 232.437178 -108.621322)
		(width 0.1651)
		(layer "F.Cu")
		(net "M_E_DQS_DN<3>")
	)
	(segment
		(start 234.17911 -106.87939)
		(end 233.981752 -107.076748)
		(width 0.1651)
		(layer "F.Cu")
		(net "M_E_DQS_DN<3>")
	)
	(segment
		(start 228.82987 -116.007642)
		(end 229.417118 -116.007642)
		(width 0.1651)
		(layer "F.Cu")
		(net "M_E_DQS_DN<3>")
	)
	(segment
		(start 229.571296 -125.040136)
		(end 229.335076 -125.276356)
		(width 0.1651)
		(layer "F.Cu")
		(net "M_E_DQS_DN<3>")
	)
	(segment
		(start 229.940612 -111.117888)
		(end 229.761034 -111.117888)
		(width 0.1651)
		(layer "F.Cu")
		(net "M_E_DQS_DN<3>")
	)
	(segment
		(start 229.36581 -111.69269)
		(end 229.186232 -111.69269)
		(width 0.1651)
		(layer "F.Cu")
		(net "M_E_DQS_DN<3>")
	)
	(segment
		(start 229.013512 -114.730022)
		(end 228.82987 -114.730022)
		(width 0.1651)
		(layer "F.Cu")
		(net "M_E_DQS_DN<3>")
	)
	(segment
		(start 229.542086 -116.13261)
		(end 229.542086 -116.569744)
		(width 0.1651)
		(layer "F.Cu")
		(net "M_E_DQS_DN<3>")
	)
	(segment
		(start 231.287574 -109.770926)
		(end 231.090216 -109.968284)
		(width 0.1651)
		(layer "F.Cu")
		(net "M_E_DQS_DN<3>")
	)
	(segment
		(start 239.607344 -104.051354)
		(end 237.928912 -105.729786)
		(width 0.1016)
		(layer "F.Cu")
		(net "M_E_DQS_DN<3>")
	)
	(segment
		(start 228.5746 -113.7285)
		(end 228.882702 -114.036602)
		(width 0.1651)
		(layer "F.Cu")
		(net "M_E_DQS_DN<3>")
	)
	(segment
		(start 229.19182 -114.21491)
		(end 229.19182 -114.551714)
		(width 0.1651)
		(layer "F.Cu")
		(net "M_E_DQS_DN<3>")
	)
	(segment
		(start 230.712772 -110.345728)
		(end 230.515414 -110.543086)
		(width 0.1651)
		(layer "F.Cu")
		(net "M_E_DQS_DN<3>")
	)
	(segment
		(start 230.910638 -109.968284)
		(end 230.712772 -110.16615)
		(width 0.1651)
		(layer "F.Cu")
		(net "M_E_DQS_DN<3>")
	)
	(segment
		(start 228.70033 -147.27174)
		(end 228.699822 -147.27174)
		(width 0.1651)
		(layer "F.Cu")
		(net "M_E_DQS_DN<3>")
	)
	(segment
		(start 228.317806 -145.389854)
		(end 228.64826 -145.0594)
		(width 0.1651)
		(layer "F.Cu")
		(net "M_E_DQS_DN<3>")
	)
	(segment
		(start 228.5746 -112.9157)
		(end 228.4476 -113.0427)
		(width 0.1651)
		(layer "F.Cu")
		(net "M_E_DQS_DN<3>")
	)
	(segment
		(start 228.48062 -117.050312)
		(end 228.48062 -120.595644)
		(width 0.1651)
		(layer "F.Cu")
		(net "M_E_DQS_DN<3>")
	)
	(segment
		(start 229.19182 -114.551714)
		(end 229.013512 -114.730022)
		(width 0.1651)
		(layer "F.Cu")
		(net "M_E_DQS_DN<3>")
	)
	(segment
		(start 231.665018 -109.393482)
		(end 231.48544 -109.393482)
		(width 0.1651)
		(layer "F.Cu")
		(net "M_E_DQS_DN<3>")
	)
	(segment
		(start 229.410768 -116.701062)
		(end 228.82987 -116.701062)
		(width 0.1651)
		(layer "F.Cu")
		(net "M_E_DQS_DN<3>")
	)
	(segment
		(start 229.013512 -114.036602)
		(end 229.19182 -114.21491)
		(width 0.1651)
		(layer "F.Cu")
		(net "M_E_DQS_DN<3>")
	)
	(segment
		(start 232.23982 -108.81868)
		(end 232.060242 -108.81868)
		(width 0.1651)
		(layer "F.Cu")
		(net "M_E_DQS_DN<3>")
	)
	(segment
		(start 228.317806 -145.821654)
		(end 228.317806 -145.389854)
		(width 0.1651)
		(layer "F.Cu")
		(net "M_E_DQS_DN<3>")
	)
	(segment
		(start 229.0191 -122.1867)
		(end 228.8794 -122.3264)
		(width 0.1651)
		(layer "F.Cu")
		(net "M_E_DQS_DN<3>")
	)
	(segment
		(start 232.060242 -108.81868)
		(end 231.862376 -109.016546)
		(width 0.1651)
		(layer "F.Cu")
		(net "M_E_DQS_DN<3>")
	)
	(segment
		(start 233.802174 -107.076748)
		(end 233.604308 -107.274614)
		(width 0.1651)
		(layer "F.Cu")
		(net "M_E_DQS_DN<3>")
	)
	(segment
		(start 232.814622 -108.243878)
		(end 232.635044 -108.243878)
		(width 0.1651)
		(layer "F.Cu")
		(net "M_E_DQS_DN<3>")
	)
	(segment
		(start 229.0191 -123.8123)
		(end 229.571296 -124.364496)
		(width 0.1651)
		(layer "F.Cu")
		(net "M_E_DQS_DN<3>")
	)
	(segment
		(start 233.227372 -107.65155)
		(end 233.029506 -107.849416)
		(width 0.1651)
		(layer "F.Cu")
		(net "M_E_DQS_DN<3>")
	)
	(segment
		(start 229.0191 -122.7201)
		(end 229.0191 -122.9741)
		(width 0.1651)
		(layer "F.Cu")
		(net "M_E_DQS_DN<3>")
	)
	(segment
		(start 243.910104 -102.504494)
		(end 243.854224 -102.560374)
		(width 0.0889)
		(layer "F.Cu")
		(net "M_E_DQS_DN<3>")
	)
	(segment
		(start 235.328714 -105.729786)
		(end 235.131356 -105.927144)
		(width 0.1651)
		(layer "F.Cu")
		(net "M_E_DQS_DN<3>")
	)
	(segment
		(start 228.5746 -113.4491)
		(end 228.5746 -113.7285)
		(width 0.1651)
		(layer "F.Cu")
		(net "M_E_DQS_DN<3>")
	)
	(segment
		(start 228.988366 -112.070134)
		(end 228.5746 -112.4839)
		(width 0.1651)
		(layer "F.Cu")
		(net "M_E_DQS_DN<3>")
	)
	(segment
		(start 229.563168 -111.315754)
		(end 229.563168 -111.495332)
		(width 0.1651)
		(layer "F.Cu")
		(net "M_E_DQS_DN<3>")
	)
	(segment
		(start 233.981752 -107.076748)
		(end 233.802174 -107.076748)
		(width 0.1651)
		(layer "F.Cu")
		(net "M_E_DQS_DN<3>")
	)
	(segment
		(start 237.809024 -105.729786)
		(end 235.328714 -105.729786)
		(width 0.1651)
		(layer "F.Cu")
		(net "M_E_DQS_DN<3>")
	)
	(segment
		(start 237.928912 -105.729786)
		(end 237.809024 -105.729786)
		(width 0.1016)
		(layer "F.Cu")
		(net "M_E_DQS_DN<3>")
	)
	(segment
		(start 228.855016 -123.368816)
		(end 229.0191 -123.5329)
		(width 0.1651)
		(layer "F.Cu")
		(net "M_E_DQS_DN<3>")
	)
	(segment
		(start 228.699822 -146.20367)
		(end 228.317806 -145.821654)
		(width 0.1651)
		(layer "F.Cu")
		(net "M_E_DQS_DN<3>")
	)
	(segment
		(start 235.131356 -105.927144)
		(end 234.951778 -105.927144)
		(width 0.1651)
		(layer "F.Cu")
		(net "M_E_DQS_DN<3>")
	)
	(via
		(at 229.087934 -145.275046)
		(size 0.508)
		(drill 0.254)
		(layers "F.Cu" "B.Cu")
		(net "M_E_DQS_DN<3>")
	)
	(via
		(at 229.087934 -125.276356)
		(size 0.508)
		(drill 0.254)
		(layers "F.Cu" "B.Cu")
		(net "M_E_DQS_DN<3>")
	)
	(via
		(at 229.087934 -139.881356)
		(size 0.508)
		(drill 0.254)
		(layers "F.Cu" "B.Cu")
		(net "M_E_DQS_DN<3>")
	)
	(segment
		(start 228.317806 -139.7508)
		(end 228.673406 -140.1064)
		(width 0.1651)
		(layer "B.Cu")
		(net "M_E_DQS_DN<3>")
	)
	(segment
		(start 228.571806 -139.166346)
		(end 228.317806 -139.420346)
		(width 0.1651)
		(layer "B.Cu")
		(net "M_E_DQS_DN<3>")
	)
	(segment
		(start 228.317806 -139.420346)
		(end 228.317806 -139.7508)
		(width 0.1651)
		(layer "B.Cu")
		(net "M_E_DQS_DN<3>")
	)
	(segment
		(start 228.571806 -138.912346)
		(end 228.571806 -139.166346)
		(width 0.1651)
		(layer "B.Cu")
		(net "M_E_DQS_DN<3>")
	)
	(segment
		(start 228.70033 -137.877296)
		(end 228.699822 -137.877296)
		(width 0.1651)
		(layer "B.Cu")
		(net "M_E_DQS_DN<3>")
	)
	(segment
		(start 228.673406 -140.1064)
		(end 228.86289 -140.1064)
		(width 0.1651)
		(layer "B.Cu")
		(net "M_E_DQS_DN<3>")
	)
	(segment
		(start 228.86289 -140.1064)
		(end 229.087934 -139.881356)
		(width 0.1651)
		(layer "B.Cu")
		(net "M_E_DQS_DN<3>")
	)
	(segment
		(start 228.699822 -137.877296)
		(end 228.699822 -138.78433)
		(width 0.1651)
		(layer "B.Cu")
		(net "M_E_DQS_DN<3>")
	)
	(segment
		(start 228.699822 -138.78433)
		(end 228.571806 -138.912346)
		(width 0.1651)
		(layer "B.Cu")
		(net "M_E_DQS_DN<3>")
	)
	(segment
		(start 229.087934 -125.276356)
		(end 228.649276 -125.715014)
		(width 0.14224)
		(layer "In4.Cu")
		(net "M_E_DQS_DN<3>")
	)
	(segment
		(start 229.088188 -139.881356)
		(end 229.087934 -139.881356)
		(width 0.14224)
		(layer "In4.Cu")
		(net "M_E_DQS_DN<3>")
	)
	(segment
		(start 228.654864 -140.241274)
		(end 228.654864 -141.5034)
		(width 0.14224)
		(layer "In4.Cu")
		(net "M_E_DQS_DN<3>")
	)
	(segment
		(start 229.087934 -139.881356)
		(end 229.014782 -139.881356)
		(width 0.14224)
		(layer "In4.Cu")
		(net "M_E_DQS_DN<3>")
	)
	(segment
		(start 228.654864 -143.5862)
		(end 228.654864 -144.841976)
		(width 0.14224)
		(layer "In4.Cu")
		(net "M_E_DQS_DN<3>")
	)
	(segment
		(start 229.21976 -133.51256)
		(end 229.601014 -133.893814)
		(width 0.14224)
		(layer "In4.Cu")
		(net "M_E_DQS_DN<3>")
	)
	(segment
		(start 229.601014 -139.36853)
		(end 229.088188 -139.881356)
		(width 0.14224)
		(layer "In4.Cu")
		(net "M_E_DQS_DN<3>")
	)
	(segment
		(start 228.649276 -125.715014)
		(end 228.649276 -126.795276)
		(width 0.14224)
		(layer "In4.Cu")
		(net "M_E_DQS_DN<3>")
	)
	(segment
		(start 229.21976 -132.730494)
		(end 229.21976 -133.51256)
		(width 0.14224)
		(layer "In4.Cu")
		(net "M_E_DQS_DN<3>")
	)
	(segment
		(start 229.601014 -127.747014)
		(end 229.601014 -132.34924)
		(width 0.14224)
		(layer "In4.Cu")
		(net "M_E_DQS_DN<3>")
	)
	(segment
		(start 229.014782 -139.881356)
		(end 228.654864 -140.241274)
		(width 0.14224)
		(layer "In4.Cu")
		(net "M_E_DQS_DN<3>")
	)
	(segment
		(start 228.444044 -143.37538)
		(end 228.654864 -143.5862)
		(width 0.14224)
		(layer "In4.Cu")
		(net "M_E_DQS_DN<3>")
	)
	(segment
		(start 229.601014 -132.34924)
		(end 229.21976 -132.730494)
		(width 0.14224)
		(layer "In4.Cu")
		(net "M_E_DQS_DN<3>")
	)
	(segment
		(start 228.654864 -144.841976)
		(end 229.087934 -145.275046)
		(width 0.14224)
		(layer "In4.Cu")
		(net "M_E_DQS_DN<3>")
	)
	(segment
		(start 228.444044 -141.71422)
		(end 228.444044 -143.37538)
		(width 0.14224)
		(layer "In4.Cu")
		(net "M_E_DQS_DN<3>")
	)
	(segment
		(start 228.649276 -126.795276)
		(end 229.601014 -127.747014)
		(width 0.14224)
		(layer "In4.Cu")
		(net "M_E_DQS_DN<3>")
	)
	(segment
		(start 228.654864 -141.5034)
		(end 228.444044 -141.71422)
		(width 0.14224)
		(layer "In4.Cu")
		(net "M_E_DQS_DN<3>")
	)
	(segment
		(start 229.601014 -133.893814)
		(end 229.601014 -139.36853)
		(width 0.14224)
		(layer "In4.Cu")
		(net "M_E_DQS_DN<3>")
	)
	(segment
		(start 219.349828 -146.20367)
		(end 218.967812 -145.821654)
		(width 0.1651)
		(layer "F.Cu")
		(net "M_E_DQS_DN<2>")
	)
	(segment
		(start 219.350336 -147.27174)
		(end 219.349828 -147.27174)
		(width 0.1651)
		(layer "F.Cu")
		(net "M_E_DQS_DN<2>")
	)
	(segment
		(start 238.759238 -100.662486)
		(end 238.187738 -100.662486)
		(width 0.1651)
		(layer "F.Cu")
		(net "M_E_DQS_DN<2>")
	)
	(segment
		(start 218.967812 -145.821654)
		(end 218.967812 -145.389854)
		(width 0.1651)
		(layer "F.Cu")
		(net "M_E_DQS_DN<2>")
	)
	(segment
		(start 219.298266 -145.0594)
		(end 219.522294 -145.0594)
		(width 0.1651)
		(layer "F.Cu")
		(net "M_E_DQS_DN<2>")
	)
	(segment
		(start 218.967812 -145.389854)
		(end 219.298266 -145.0594)
		(width 0.1651)
		(layer "F.Cu")
		(net "M_E_DQS_DN<2>")
	)
	(segment
		(start 219.522294 -145.0594)
		(end 219.73794 -145.275046)
		(width 0.1651)
		(layer "F.Cu")
		(net "M_E_DQS_DN<2>")
	)
	(segment
		(start 219.349828 -147.27174)
		(end 219.349828 -146.20367)
		(width 0.1651)
		(layer "F.Cu")
		(net "M_E_DQS_DN<2>")
	)
	(via
		(at 219.73794 -145.275046)
		(size 0.508)
		(drill 0.254)
		(layers "F.Cu" "B.Cu")
		(net "M_E_DQS_DN<2>")
	)
	(via
		(at 238.187738 -100.662486)
		(size 0.508)
		(drill 0.254)
		(layers "F.Cu" "B.Cu")
		(net "M_E_DQS_DN<2>")
	)
	(via
		(at 219.73794 -139.881356)
		(size 0.508)
		(drill 0.254)
		(layers "F.Cu" "B.Cu")
		(net "M_E_DQS_DN<2>")
	)
	(segment
		(start 219.350336 -137.877296)
		(end 219.349828 -137.877296)
		(width 0.1651)
		(layer "B.Cu")
		(net "M_E_DQS_DN<2>")
	)
	(segment
		(start 219.323412 -140.1064)
		(end 219.512896 -140.1064)
		(width 0.1651)
		(layer "B.Cu")
		(net "M_E_DQS_DN<2>")
	)
	(segment
		(start 219.512896 -140.1064)
		(end 219.73794 -139.881356)
		(width 0.1651)
		(layer "B.Cu")
		(net "M_E_DQS_DN<2>")
	)
	(segment
		(start 219.221812 -139.166346)
		(end 218.967812 -139.420346)
		(width 0.1651)
		(layer "B.Cu")
		(net "M_E_DQS_DN<2>")
	)
	(segment
		(start 219.349828 -137.877296)
		(end 219.349828 -138.78433)
		(width 0.1651)
		(layer "B.Cu")
		(net "M_E_DQS_DN<2>")
	)
	(segment
		(start 219.349828 -138.78433)
		(end 219.221812 -138.912346)
		(width 0.1651)
		(layer "B.Cu")
		(net "M_E_DQS_DN<2>")
	)
	(segment
		(start 218.967812 -139.7508)
		(end 219.323412 -140.1064)
		(width 0.1651)
		(layer "B.Cu")
		(net "M_E_DQS_DN<2>")
	)
	(segment
		(start 218.967812 -139.420346)
		(end 218.967812 -139.7508)
		(width 0.1651)
		(layer "B.Cu")
		(net "M_E_DQS_DN<2>")
	)
	(segment
		(start 219.221812 -138.912346)
		(end 219.221812 -139.166346)
		(width 0.1651)
		(layer "B.Cu")
		(net "M_E_DQS_DN<2>")
	)
	(segment
		(start 220.621606 -128.7526)
		(end 220.844618 -128.7526)
		(width 0.14224)
		(layer "In4.Cu")
		(net "M_E_DQS_DN<2>")
	)
	(segment
		(start 236.026198 -102.728014)
		(end 236.713522 -102.040436)
		(width 0.0889)
		(layer "In4.Cu")
		(net "M_E_DQS_DN<2>")
	)
	(segment
		(start 221.139004 -126.744984)
		(end 221.139004 -126.490984)
		(width 0.14224)
		(layer "In4.Cu")
		(net "M_E_DQS_DN<2>")
	)
	(segment
		(start 234.467654 -103.965502)
		(end 234.483402 -103.949754)
		(width 0.0889)
		(layer "In4.Cu")
		(net "M_E_DQS_DN<2>")
	)
	(segment
		(start 220.25102 -137.2616)
		(end 220.09354 -137.10412)
		(width 0.14224)
		(layer "In4.Cu")
		(net "M_E_DQS_DN<2>")
	)
	(segment
		(start 220.130878 -129.800604)
		(end 220.25102 -129.680462)
		(width 0.14224)
		(layer "In4.Cu")
		(net "M_E_DQS_DN<2>")
	)
	(segment
		(start 220.09354 -133.626098)
		(end 220.25102 -133.468618)
		(width 0.14224)
		(layer "In4.Cu")
		(net "M_E_DQS_DN<2>")
	)
	(segment
		(start 221.139004 -127.313944)
		(end 220.981524 -127.156464)
		(width 0.14224)
		(layer "In4.Cu")
		(net "M_E_DQS_DN<2>")
	)
	(segment
		(start 220.25102 -136.226804)
		(end 220.14561 -136.121394)
		(width 0.14224)
		(layer "In4.Cu")
		(net "M_E_DQS_DN<2>")
	)
	(segment
		(start 220.25102 -130.174746)
		(end 220.130878 -130.054604)
		(width 0.14224)
		(layer "In4.Cu")
		(net "M_E_DQS_DN<2>")
	)
	(segment
		(start 226.983544 -119.148098)
		(end 227.369116 -118.762526)
		(width 0.14224)
		(layer "In4.Cu")
		(net "M_E_DQS_DN<2>")
	)
	(segment
		(start 221.139004 -128.458214)
		(end 221.139004 -128.136904)
		(width 0.14224)
		(layer "In4.Cu")
		(net "M_E_DQS_DN<2>")
	)
	(segment
		(start 220.981524 -127.156464)
		(end 220.981524 -126.902464)
		(width 0.14224)
		(layer "In4.Cu")
		(net "M_E_DQS_DN<2>")
	)
	(segment
		(start 220.442028 -128.932178)
		(end 220.621606 -128.7526)
		(width 0.14224)
		(layer "In4.Cu")
		(net "M_E_DQS_DN<2>")
	)
	(segment
		(start 220.25102 -133.468618)
		(end 220.25102 -133.214618)
		(width 0.14224)
		(layer "In4.Cu")
		(net "M_E_DQS_DN<2>")
	)
	(segment
		(start 220.25102 -131.047744)
		(end 220.25102 -130.174746)
		(width 0.14224)
		(layer "In4.Cu")
		(net "M_E_DQS_DN<2>")
	)
	(segment
		(start 220.130878 -130.054604)
		(end 220.130878 -129.800604)
		(width 0.14224)
		(layer "In4.Cu")
		(net "M_E_DQS_DN<2>")
	)
	(segment
		(start 220.09354 -133.880098)
		(end 220.09354 -133.626098)
		(width 0.14224)
		(layer "In4.Cu")
		(net "M_E_DQS_DN<2>")
	)
	(segment
		(start 236.712506 -102.041452)
		(end 236.81436 -101.858064)
		(width 0.0889)
		(layer "In4.Cu")
		(net "M_E_DQS_DN<2>")
	)
	(segment
		(start 224.902522 -121.192798)
		(end 225.213418 -121.192798)
		(width 0.14224)
		(layer "In4.Cu")
		(net "M_E_DQS_DN<2>")
	)
	(segment
		(start 221.139004 -125.668024)
		(end 220.981524 -125.510544)
		(width 0.14224)
		(layer "In4.Cu")
		(net "M_E_DQS_DN<2>")
	)
	(segment
		(start 220.09354 -132.803138)
		(end 220.25102 -132.645658)
		(width 0.14224)
		(layer "In4.Cu")
		(net "M_E_DQS_DN<2>")
	)
	(segment
		(start 230.43388 -114.45875)
		(end 230.43388 -109.689646)
		(width 0.14224)
		(layer "In4.Cu")
		(net "M_E_DQS_DN<2>")
	)
	(segment
		(start 221.139004 -126.490984)
		(end 220.981524 -126.333504)
		(width 0.14224)
		(layer "In4.Cu")
		(net "M_E_DQS_DN<2>")
	)
	(segment
		(start 225.331782 -120.097804)
		(end 225.331782 -119.560848)
		(width 0.14224)
		(layer "In4.Cu")
		(net "M_E_DQS_DN<2>")
	)
	(segment
		(start 220.09354 -138.75004)
		(end 220.09354 -138.49604)
		(width 0.14224)
		(layer "In4.Cu")
		(net "M_E_DQS_DN<2>")
	)
	(segment
		(start 220.25102 -129.680462)
		(end 220.25102 -129.346198)
		(width 0.14224)
		(layer "In4.Cu")
		(net "M_E_DQS_DN<2>")
	)
	(segment
		(start 220.25102 -139.64793)
		(end 220.25102 -138.90752)
		(width 0.14224)
		(layer "In4.Cu")
		(net "M_E_DQS_DN<2>")
	)
	(segment
		(start 220.25102 -138.90752)
		(end 220.09354 -138.75004)
		(width 0.14224)
		(layer "In4.Cu")
		(net "M_E_DQS_DN<2>")
	)
	(segment
		(start 219.664788 -139.881356)
		(end 219.73794 -139.881356)
		(width 0.14224)
		(layer "In4.Cu")
		(net "M_E_DQS_DN<2>")
	)
	(segment
		(start 220.442028 -129.15519)
		(end 220.442028 -128.932178)
		(width 0.14224)
		(layer "In4.Cu")
		(net "M_E_DQS_DN<2>")
	)
	(segment
		(start 220.140276 -134.816342)
		(end 220.140276 -134.562342)
		(width 0.14224)
		(layer "In4.Cu")
		(net "M_E_DQS_DN<2>")
	)
	(segment
		(start 220.09354 -131.980178)
		(end 220.25102 -131.822698)
		(width 0.14224)
		(layer "In4.Cu")
		(net "M_E_DQS_DN<2>")
	)
	(segment
		(start 230.434642 -109.689646)
		(end 234.075478 -106.04881)
		(width 0.14224)
		(layer "In4.Cu")
		(net "M_E_DQS_DN<2>")
	)
	(segment
		(start 219.73794 -145.275046)
		(end 219.30487 -144.841976)
		(width 0.14224)
		(layer "In4.Cu")
		(net "M_E_DQS_DN<2>")
	)
	(segment
		(start 223.91243 -120.9802)
		(end 224.689924 -120.9802)
		(width 0.14224)
		(layer "In4.Cu")
		(net "M_E_DQS_DN<2>")
	)
	(segment
		(start 220.09354 -136.85012)
		(end 220.25102 -136.69264)
		(width 0.14224)
		(layer "In4.Cu")
		(net "M_E_DQS_DN<2>")
	)
	(segment
		(start 220.25102 -134.037578)
		(end 220.09354 -133.880098)
		(width 0.14224)
		(layer "In4.Cu")
		(net "M_E_DQS_DN<2>")
	)
	(segment
		(start 236.81436 -101.858064)
		(end 236.815122 -101.856794)
		(width 0.0889)
		(layer "In4.Cu")
		(net "M_E_DQS_DN<2>")
	)
	(segment
		(start 220.25102 -137.5156)
		(end 220.25102 -137.2616)
		(width 0.14224)
		(layer "In4.Cu")
		(net "M_E_DQS_DN<2>")
	)
	(segment
		(start 220.981524 -126.333504)
		(end 220.981524 -126.079504)
		(width 0.14224)
		(layer "In4.Cu")
		(net "M_E_DQS_DN<2>")
	)
	(segment
		(start 221.139004 -125.099064)
		(end 221.139004 -123.753626)
		(width 0.14224)
		(layer "In4.Cu")
		(net "M_E_DQS_DN<2>")
	)
	(segment
		(start 219.09405 -141.71422)
		(end 219.30487 -141.5034)
		(width 0.14224)
		(layer "In4.Cu")
		(net "M_E_DQS_DN<2>")
	)
	(segment
		(start 236.713522 -102.040436)
		(end 236.712506 -102.041452)
		(width 0.0889)
		(layer "In4.Cu")
		(net "M_E_DQS_DN<2>")
	)
	(segment
		(start 220.25102 -136.69264)
		(end 220.25102 -136.226804)
		(width 0.14224)
		(layer "In4.Cu")
		(net "M_E_DQS_DN<2>")
	)
	(segment
		(start 220.981524 -127.725424)
		(end 221.139004 -127.567944)
		(width 0.14224)
		(layer "In4.Cu")
		(net "M_E_DQS_DN<2>")
	)
	(segment
		(start 230.43388 -109.689646)
		(end 230.434642 -109.689646)
		(width 0.14224)
		(layer "In4.Cu")
		(net "M_E_DQS_DN<2>")
	)
	(segment
		(start 220.25102 -135.761984)
		(end 220.25102 -134.927086)
		(width 0.14224)
		(layer "In4.Cu")
		(net "M_E_DQS_DN<2>")
	)
	(segment
		(start 220.25102 -138.33856)
		(end 220.25102 -138.08456)
		(width 0.14224)
		(layer "In4.Cu")
		(net "M_E_DQS_DN<2>")
	)
	(segment
		(start 236.815122 -101.856794)
		(end 236.816392 -101.854762)
		(width 0.0889)
		(layer "In4.Cu")
		(net "M_E_DQS_DN<2>")
	)
	(segment
		(start 220.14561 -136.121394)
		(end 220.14561 -135.867394)
		(width 0.14224)
		(layer "In4.Cu")
		(net "M_E_DQS_DN<2>")
	)
	(segment
		(start 220.844618 -128.7526)
		(end 221.139004 -128.458214)
		(width 0.14224)
		(layer "In4.Cu")
		(net "M_E_DQS_DN<2>")
	)
	(segment
		(start 225.664522 -120.430544)
		(end 225.331782 -120.097804)
		(width 0.14224)
		(layer "In4.Cu")
		(net "M_E_DQS_DN<2>")
	)
	(segment
		(start 220.150944 -131.14782)
		(end 220.25102 -131.047744)
		(width 0.14224)
		(layer "In4.Cu")
		(net "M_E_DQS_DN<2>")
	)
	(segment
		(start 220.981524 -126.902464)
		(end 221.139004 -126.744984)
		(width 0.14224)
		(layer "In4.Cu")
		(net "M_E_DQS_DN<2>")
	)
	(segment
		(start 220.150944 -131.40182)
		(end 220.150944 -131.14782)
		(width 0.14224)
		(layer "In4.Cu")
		(net "M_E_DQS_DN<2>")
	)
	(segment
		(start 227.369116 -118.762526)
		(end 227.369116 -117.523514)
		(width 0.14224)
		(layer "In4.Cu")
		(net "M_E_DQS_DN<2>")
	)
	(segment
		(start 221.139004 -128.136904)
		(end 220.981524 -127.979424)
		(width 0.14224)
		(layer "In4.Cu")
		(net "M_E_DQS_DN<2>")
	)
	(segment
		(start 220.981524 -125.256544)
		(end 221.139004 -125.099064)
		(width 0.14224)
		(layer "In4.Cu")
		(net "M_E_DQS_DN<2>")
	)
	(segment
		(start 220.09354 -133.057138)
		(end 220.09354 -132.803138)
		(width 0.14224)
		(layer "In4.Cu")
		(net "M_E_DQS_DN<2>")
	)
	(segment
		(start 219.30487 -141.5034)
		(end 219.30487 -140.241274)
		(width 0.14224)
		(layer "In4.Cu")
		(net "M_E_DQS_DN<2>")
	)
	(segment
		(start 226.473512 -118.95455)
		(end 226.66706 -119.148098)
		(width 0.14224)
		(layer "In4.Cu")
		(net "M_E_DQS_DN<2>")
	)
	(segment
		(start 220.25102 -132.391658)
		(end 220.09354 -132.234178)
		(width 0.14224)
		(layer "In4.Cu")
		(net "M_E_DQS_DN<2>")
	)
	(segment
		(start 224.689924 -120.9802)
		(end 224.902522 -121.192798)
		(width 0.14224)
		(layer "In4.Cu")
		(net "M_E_DQS_DN<2>")
	)
	(segment
		(start 220.981524 -127.979424)
		(end 220.981524 -127.725424)
		(width 0.14224)
		(layer "In4.Cu")
		(net "M_E_DQS_DN<2>")
	)
	(segment
		(start 219.09405 -143.37538)
		(end 219.09405 -141.71422)
		(width 0.14224)
		(layer "In4.Cu")
		(net "M_E_DQS_DN<2>")
	)
	(segment
		(start 220.09354 -132.234178)
		(end 220.09354 -131.980178)
		(width 0.14224)
		(layer "In4.Cu")
		(net "M_E_DQS_DN<2>")
	)
	(segment
		(start 219.30487 -143.5862)
		(end 219.09405 -143.37538)
		(width 0.14224)
		(layer "In4.Cu")
		(net "M_E_DQS_DN<2>")
	)
	(segment
		(start 220.09354 -138.49604)
		(end 220.25102 -138.33856)
		(width 0.14224)
		(layer "In4.Cu")
		(net "M_E_DQS_DN<2>")
	)
	(segment
		(start 220.981524 -125.510544)
		(end 220.981524 -125.256544)
		(width 0.14224)
		(layer "In4.Cu")
		(net "M_E_DQS_DN<2>")
	)
	(segment
		(start 226.66706 -119.148098)
		(end 226.983544 -119.148098)
		(width 0.14224)
		(layer "In4.Cu")
		(net "M_E_DQS_DN<2>")
	)
	(segment
		(start 225.331782 -119.560848)
		(end 225.93808 -118.95455)
		(width 0.14224)
		(layer "In4.Cu")
		(net "M_E_DQS_DN<2>")
	)
	(segment
		(start 219.30487 -140.241274)
		(end 219.664788 -139.881356)
		(width 0.14224)
		(layer "In4.Cu")
		(net "M_E_DQS_DN<2>")
	)
	(segment
		(start 220.25102 -133.214618)
		(end 220.09354 -133.057138)
		(width 0.14224)
		(layer "In4.Cu")
		(net "M_E_DQS_DN<2>")
	)
	(segment
		(start 220.25102 -131.822698)
		(end 220.25102 -131.501896)
		(width 0.14224)
		(layer "In4.Cu")
		(net "M_E_DQS_DN<2>")
	)
	(segment
		(start 225.213418 -121.192798)
		(end 225.664522 -120.741694)
		(width 0.14224)
		(layer "In4.Cu")
		(net "M_E_DQS_DN<2>")
	)
	(segment
		(start 234.075478 -104.357678)
		(end 234.467654 -103.965502)
		(width 0.14224)
		(layer "In4.Cu")
		(net "M_E_DQS_DN<2>")
	)
	(segment
		(start 235.761022 -102.728014)
		(end 236.026198 -102.728014)
		(width 0.0889)
		(layer "In4.Cu")
		(net "M_E_DQS_DN<2>")
	)
	(segment
		(start 227.369116 -117.523514)
		(end 230.43388 -114.45875)
		(width 0.14224)
		(layer "In4.Cu")
		(net "M_E_DQS_DN<2>")
	)
	(segment
		(start 221.139004 -127.567944)
		(end 221.139004 -127.313944)
		(width 0.14224)
		(layer "In4.Cu")
		(net "M_E_DQS_DN<2>")
	)
	(segment
		(start 220.25102 -134.927086)
		(end 220.140276 -134.816342)
		(width 0.14224)
		(layer "In4.Cu")
		(net "M_E_DQS_DN<2>")
	)
	(segment
		(start 220.017594 -139.881356)
		(end 220.25102 -139.64793)
		(width 0.14224)
		(layer "In4.Cu")
		(net "M_E_DQS_DN<2>")
	)
	(segment
		(start 236.816392 -101.854762)
		(end 236.817408 -101.852984)
		(width 0.0889)
		(layer "In4.Cu")
		(net "M_E_DQS_DN<2>")
	)
	(segment
		(start 220.25102 -129.346198)
		(end 220.442028 -129.15519)
		(width 0.14224)
		(layer "In4.Cu")
		(net "M_E_DQS_DN<2>")
	)
	(segment
		(start 220.25102 -138.08456)
		(end 220.09354 -137.92708)
		(width 0.14224)
		(layer "In4.Cu")
		(net "M_E_DQS_DN<2>")
	)
	(segment
		(start 225.664522 -120.741694)
		(end 225.664522 -120.430544)
		(width 0.14224)
		(layer "In4.Cu")
		(net "M_E_DQS_DN<2>")
	)
	(segment
		(start 220.981524 -126.079504)
		(end 221.139004 -125.922024)
		(width 0.14224)
		(layer "In4.Cu")
		(net "M_E_DQS_DN<2>")
	)
	(segment
		(start 220.140276 -134.562342)
		(end 220.25102 -134.451598)
		(width 0.14224)
		(layer "In4.Cu")
		(net "M_E_DQS_DN<2>")
	)
	(segment
		(start 234.075478 -106.04881)
		(end 234.075478 -104.357678)
		(width 0.14224)
		(layer "In4.Cu")
		(net "M_E_DQS_DN<2>")
	)
	(segment
		(start 220.09354 -137.92708)
		(end 220.09354 -137.67308)
		(width 0.14224)
		(layer "In4.Cu")
		(net "M_E_DQS_DN<2>")
	)
	(segment
		(start 220.25102 -132.645658)
		(end 220.25102 -132.391658)
		(width 0.14224)
		(layer "In4.Cu")
		(net "M_E_DQS_DN<2>")
	)
	(segment
		(start 219.73794 -139.881356)
		(end 220.017594 -139.881356)
		(width 0.14224)
		(layer "In4.Cu")
		(net "M_E_DQS_DN<2>")
	)
	(segment
		(start 220.25102 -131.501896)
		(end 220.150944 -131.40182)
		(width 0.14224)
		(layer "In4.Cu")
		(net "M_E_DQS_DN<2>")
	)
	(segment
		(start 237.304326 -101.557836)
		(end 237.347252 -101.557836)
		(width 0.0889)
		(layer "In4.Cu")
		(net "M_E_DQS_DN<2>")
	)
	(segment
		(start 220.09354 -137.67308)
		(end 220.25102 -137.5156)
		(width 0.14224)
		(layer "In4.Cu")
		(net "M_E_DQS_DN<2>")
	)
	(segment
		(start 220.09354 -137.10412)
		(end 220.09354 -136.85012)
		(width 0.14224)
		(layer "In4.Cu")
		(net "M_E_DQS_DN<2>")
	)
	(segment
		(start 219.30487 -144.841976)
		(end 219.30487 -143.5862)
		(width 0.14224)
		(layer "In4.Cu")
		(net "M_E_DQS_DN<2>")
	)
	(segment
		(start 234.483402 -103.949754)
		(end 234.539282 -103.949754)
		(width 0.0889)
		(layer "In4.Cu")
		(net "M_E_DQS_DN<2>")
	)
	(segment
		(start 221.139004 -125.922024)
		(end 221.139004 -125.668024)
		(width 0.14224)
		(layer "In4.Cu")
		(net "M_E_DQS_DN<2>")
	)
	(segment
		(start 221.139004 -123.753626)
		(end 223.91243 -120.9802)
		(width 0.14224)
		(layer "In4.Cu")
		(net "M_E_DQS_DN<2>")
	)
	(segment
		(start 234.539282 -103.949754)
		(end 235.761022 -102.728014)
		(width 0.0889)
		(layer "In4.Cu")
		(net "M_E_DQS_DN<2>")
	)
	(segment
		(start 220.25102 -134.451598)
		(end 220.25102 -134.037578)
		(width 0.14224)
		(layer "In4.Cu")
		(net "M_E_DQS_DN<2>")
	)
	(segment
		(start 220.14561 -135.867394)
		(end 220.25102 -135.761984)
		(width 0.14224)
		(layer "In4.Cu")
		(net "M_E_DQS_DN<2>")
	)
	(segment
		(start 225.93808 -118.95455)
		(end 226.473512 -118.95455)
		(width 0.14224)
		(layer "In4.Cu")
		(net "M_E_DQS_DN<2>")
	)
	(arc
		(start 237.675928 -101.357938)
		(mid 237.835583 -101.178693)
		(end 238.053372 -101.077776)
		(width 0.0889)
		(layer "In4.Cu")
		(net "M_E_DQS_DN<2>")
	)
	(arc
		(start 236.817408 -101.852984)
		(mid 237.022967 -101.642887)
		(end 237.304326 -101.557836)
		(width 0.0889)
		(layer "In4.Cu")
		(net "M_E_DQS_DN<2>")
	)
	(arc
		(start 237.347252 -101.557836)
		(mid 237.537181 -101.499966)
		(end 237.675928 -101.357938)
		(width 0.0889)
		(layer "In4.Cu")
		(net "M_E_DQS_DN<2>")
	)
	(arc
		(start 238.053372 -101.077776)
		(mid 238.153317 -100.88073)
		(end 238.187738 -100.662486)
		(width 0.0889)
		(layer "In4.Cu")
		(net "M_E_DQS_DN<2>")
	)
	(segment
		(start 209.948272 -145.0594)
		(end 210.1723 -145.0594)
		(width 0.1651)
		(layer "F.Cu")
		(net "M_E_DQS_DN<1>")
	)
	(segment
		(start 209.999834 -146.20367)
		(end 209.6008 -145.804636)
		(width 0.1651)
		(layer "F.Cu")
		(net "M_E_DQS_DN<1>")
	)
	(segment
		(start 209.6008 -145.804636)
		(end 209.6008 -145.406872)
		(width 0.1651)
		(layer "F.Cu")
		(net "M_E_DQS_DN<1>")
	)
	(segment
		(start 209.6008 -145.406872)
		(end 209.948272 -145.0594)
		(width 0.1651)
		(layer "F.Cu")
		(net "M_E_DQS_DN<1>")
	)
	(segment
		(start 210.000342 -147.27174)
		(end 209.999834 -147.27174)
		(width 0.1651)
		(layer "F.Cu")
		(net "M_E_DQS_DN<1>")
	)
	(segment
		(start 209.999834 -147.27174)
		(end 209.999834 -146.20367)
		(width 0.1651)
		(layer "F.Cu")
		(net "M_E_DQS_DN<1>")
	)
	(segment
		(start 236.183678 -89.27084)
		(end 235.612178 -89.27084)
		(width 0.1651)
		(layer "F.Cu")
		(net "M_E_DQS_DN<1>")
	)
	(segment
		(start 210.1723 -145.0594)
		(end 210.387946 -145.275046)
		(width 0.1651)
		(layer "F.Cu")
		(net "M_E_DQS_DN<1>")
	)
	(via
		(at 210.387946 -145.275046)
		(size 0.508)
		(drill 0.254)
		(layers "F.Cu" "B.Cu")
		(net "M_E_DQS_DN<1>")
	)
	(via
		(at 210.387946 -139.881356)
		(size 0.508)
		(drill 0.254)
		(layers "F.Cu" "B.Cu")
		(net "M_E_DQS_DN<1>")
	)
	(via
		(at 235.612178 -89.27084)
		(size 0.508)
		(drill 0.254)
		(layers "F.Cu" "B.Cu")
		(net "M_E_DQS_DN<1>")
	)
	(segment
		(start 209.871818 -138.912346)
		(end 209.871818 -139.166346)
		(width 0.1651)
		(layer "B.Cu")
		(net "M_E_DQS_DN<1>")
	)
	(segment
		(start 209.617818 -139.420346)
		(end 209.617818 -139.7508)
		(width 0.1651)
		(layer "B.Cu")
		(net "M_E_DQS_DN<1>")
	)
	(segment
		(start 209.871818 -139.166346)
		(end 209.617818 -139.420346)
		(width 0.1651)
		(layer "B.Cu")
		(net "M_E_DQS_DN<1>")
	)
	(segment
		(start 209.999834 -137.877296)
		(end 209.999834 -138.78433)
		(width 0.1651)
		(layer "B.Cu")
		(net "M_E_DQS_DN<1>")
	)
	(segment
		(start 209.617818 -139.7508)
		(end 209.973418 -140.1064)
		(width 0.1651)
		(layer "B.Cu")
		(net "M_E_DQS_DN<1>")
	)
	(segment
		(start 209.999834 -138.78433)
		(end 209.871818 -138.912346)
		(width 0.1651)
		(layer "B.Cu")
		(net "M_E_DQS_DN<1>")
	)
	(segment
		(start 209.973418 -140.1064)
		(end 210.162902 -140.1064)
		(width 0.1651)
		(layer "B.Cu")
		(net "M_E_DQS_DN<1>")
	)
	(segment
		(start 210.162902 -140.1064)
		(end 210.387946 -139.881356)
		(width 0.1651)
		(layer "B.Cu")
		(net "M_E_DQS_DN<1>")
	)
	(segment
		(start 210.000342 -137.877296)
		(end 209.999834 -137.877296)
		(width 0.1651)
		(layer "B.Cu")
		(net "M_E_DQS_DN<1>")
	)
	(segment
		(start 210.743546 -138.743436)
		(end 210.743546 -138.489436)
		(width 0.14224)
		(layer "In4.Cu")
		(net "M_E_DQS_DN<1>")
	)
	(segment
		(start 210.901026 -137.237978)
		(end 210.77047 -137.107422)
		(width 0.14224)
		(layer "In4.Cu")
		(net "M_E_DQS_DN<1>")
	)
	(segment
		(start 216.16035 -115.595908)
		(end 216.611454 -115.144804)
		(width 0.14224)
		(layer "In4.Cu")
		(net "M_E_DQS_DN<1>")
	)
	(segment
		(start 210.901026 -139.610592)
		(end 210.901026 -138.900916)
		(width 0.14224)
		(layer "In4.Cu")
		(net "M_E_DQS_DN<1>")
	)
	(segment
		(start 215.833706 -114.056414)
		(end 215.833706 -113.519966)
		(width 0.14224)
		(layer "In4.Cu")
		(net "M_E_DQS_DN<1>")
	)
	(segment
		(start 234.735878 -90.165936)
		(end 234.768644 -90.165936)
		(width 0.0889)
		(layer "In4.Cu")
		(net "M_E_DQS_DN<1>")
	)
	(segment
		(start 209.954876 -141.5034)
		(end 209.954876 -140.241274)
		(width 0.14224)
		(layer "In4.Cu")
		(net "M_E_DQS_DN<1>")
	)
	(segment
		(start 212.75548 -119.636286)
		(end 214.99068 -117.401086)
		(width 0.14224)
		(layer "In4.Cu")
		(net "M_E_DQS_DN<1>")
	)
	(segment
		(start 210.630262 -139.881356)
		(end 210.901026 -139.610592)
		(width 0.14224)
		(layer "In4.Cu")
		(net "M_E_DQS_DN<1>")
	)
	(segment
		(start 210.901026 -138.900916)
		(end 210.743546 -138.743436)
		(width 0.14224)
		(layer "In4.Cu")
		(net "M_E_DQS_DN<1>")
	)
	(segment
		(start 233.56443 -92.910914)
		(end 234.163108 -92.312236)
		(width 0.0889)
		(layer "In4.Cu")
		(net "M_E_DQS_DN<1>")
	)
	(segment
		(start 210.77047 -136.853422)
		(end 210.901026 -136.722866)
		(width 0.14224)
		(layer "In4.Cu")
		(net "M_E_DQS_DN<1>")
	)
	(segment
		(start 231.03967 -94.416372)
		(end 231.055418 -94.400624)
		(width 0.0889)
		(layer "In4.Cu")
		(net "M_E_DQS_DN<1>")
	)
	(segment
		(start 235.590588 -89.67089)
		(end 235.623354 -89.67089)
		(width 0.0889)
		(layer "In4.Cu")
		(net "M_E_DQS_DN<1>")
	)
	(segment
		(start 218.06535 -113.690908)
		(end 218.516454 -113.239804)
		(width 0.14224)
		(layer "In4.Cu")
		(net "M_E_DQS_DN<1>")
	)
	(segment
		(start 212.75548 -126.214886)
		(end 212.75548 -119.636286)
		(width 0.14224)
		(layer "In4.Cu")
		(net "M_E_DQS_DN<1>")
	)
	(segment
		(start 210.743546 -137.920476)
		(end 210.743546 -137.666476)
		(width 0.14224)
		(layer "In4.Cu")
		(net "M_E_DQS_DN<1>")
	)
	(segment
		(start 234.163108 -92.312236)
		(end 234.163108 -90.59799)
		(width 0.0889)
		(layer "In4.Cu")
		(net "M_E_DQS_DN<1>")
	)
	(segment
		(start 213.97468 -115.378992)
		(end 214.464392 -114.88928)
		(width 0.14224)
		(layer "In4.Cu")
		(net "M_E_DQS_DN<1>")
	)
	(segment
		(start 222.1738 -104.546654)
		(end 227.3046 -99.415854)
		(width 0.14224)
		(layer "In4.Cu")
		(net "M_E_DQS_DN<1>")
	)
	(segment
		(start 216.976198 -112.913414)
		(end 217.753946 -113.690908)
		(width 0.14224)
		(layer "In4.Cu")
		(net "M_E_DQS_DN<1>")
	)
	(segment
		(start 210.800696 -133.984492)
		(end 210.800696 -133.730492)
		(width 0.14224)
		(layer "In4.Cu")
		(net "M_E_DQS_DN<1>")
	)
	(segment
		(start 216.611454 -114.833908)
		(end 215.833706 -114.056414)
		(width 0.14224)
		(layer "In4.Cu")
		(net "M_E_DQS_DN<1>")
	)
	(segment
		(start 210.800696 -133.730492)
		(end 210.901026 -133.630162)
		(width 0.14224)
		(layer "In4.Cu")
		(net "M_E_DQS_DN<1>")
	)
	(segment
		(start 209.954876 -140.241274)
		(end 210.314794 -139.881356)
		(width 0.14224)
		(layer "In4.Cu")
		(net "M_E_DQS_DN<1>")
	)
	(segment
		(start 231.055418 -94.400624)
		(end 231.111806 -94.400624)
		(width 0.0889)
		(layer "In4.Cu")
		(net "M_E_DQS_DN<1>")
	)
	(segment
		(start 210.901026 -134.084822)
		(end 210.800696 -133.984492)
		(width 0.14224)
		(layer "In4.Cu")
		(net "M_E_DQS_DN<1>")
	)
	(segment
		(start 215.142572 -114.88928)
		(end 215.8492 -115.595908)
		(width 0.14224)
		(layer "In4.Cu")
		(net "M_E_DQS_DN<1>")
	)
	(segment
		(start 216.440258 -112.913414)
		(end 216.976198 -112.913414)
		(width 0.14224)
		(layer "In4.Cu")
		(net "M_E_DQS_DN<1>")
	)
	(segment
		(start 210.743546 -137.666476)
		(end 210.901026 -137.508996)
		(width 0.14224)
		(layer "In4.Cu")
		(net "M_E_DQS_DN<1>")
	)
	(segment
		(start 210.77047 -137.107422)
		(end 210.77047 -136.853422)
		(width 0.14224)
		(layer "In4.Cu")
		(net "M_E_DQS_DN<1>")
	)
	(segment
		(start 231.111806 -94.400624)
		(end 232.601516 -92.910914)
		(width 0.0889)
		(layer "In4.Cu")
		(net "M_E_DQS_DN<1>")
	)
	(segment
		(start 218.516454 -112.928908)
		(end 218.38793 -112.800384)
		(width 0.14224)
		(layer "In4.Cu")
		(net "M_E_DQS_DN<1>")
	)
	(segment
		(start 227.3046 -98.151442)
		(end 231.03967 -94.416372)
		(width 0.14224)
		(layer "In4.Cu")
		(net "M_E_DQS_DN<1>")
	)
	(segment
		(start 210.387946 -145.275046)
		(end 209.954876 -144.841976)
		(width 0.14224)
		(layer "In4.Cu")
		(net "M_E_DQS_DN<1>")
	)
	(segment
		(start 210.901026 -136.722866)
		(end 210.901026 -134.084822)
		(width 0.14224)
		(layer "In4.Cu")
		(net "M_E_DQS_DN<1>")
	)
	(segment
		(start 210.901026 -128.06934)
		(end 212.75548 -126.214886)
		(width 0.14224)
		(layer "In4.Cu")
		(net "M_E_DQS_DN<1>")
	)
	(segment
		(start 214.464392 -114.88928)
		(end 215.142572 -114.88928)
		(width 0.14224)
		(layer "In4.Cu")
		(net "M_E_DQS_DN<1>")
	)
	(segment
		(start 215.833706 -113.519966)
		(end 216.440258 -112.913414)
		(width 0.14224)
		(layer "In4.Cu")
		(net "M_E_DQS_DN<1>")
	)
	(segment
		(start 216.611454 -115.144804)
		(end 216.611454 -114.833908)
		(width 0.14224)
		(layer "In4.Cu")
		(net "M_E_DQS_DN<1>")
	)
	(segment
		(start 210.387946 -139.881356)
		(end 210.630262 -139.881356)
		(width 0.14224)
		(layer "In4.Cu")
		(net "M_E_DQS_DN<1>")
	)
	(segment
		(start 210.901026 -137.508996)
		(end 210.901026 -137.237978)
		(width 0.14224)
		(layer "In4.Cu")
		(net "M_E_DQS_DN<1>")
	)
	(segment
		(start 214.99068 -117.031008)
		(end 213.97468 -116.015008)
		(width 0.14224)
		(layer "In4.Cu")
		(net "M_E_DQS_DN<1>")
	)
	(segment
		(start 209.744056 -141.71422)
		(end 209.954876 -141.5034)
		(width 0.14224)
		(layer "In4.Cu")
		(net "M_E_DQS_DN<1>")
	)
	(segment
		(start 210.901026 -138.077956)
		(end 210.743546 -137.920476)
		(width 0.14224)
		(layer "In4.Cu")
		(net "M_E_DQS_DN<1>")
	)
	(segment
		(start 209.744056 -143.37538)
		(end 209.744056 -141.71422)
		(width 0.14224)
		(layer "In4.Cu")
		(net "M_E_DQS_DN<1>")
	)
	(segment
		(start 222.1738 -107.179872)
		(end 222.1738 -104.546654)
		(width 0.14224)
		(layer "In4.Cu")
		(net "M_E_DQS_DN<1>")
	)
	(segment
		(start 213.97468 -116.015008)
		(end 213.97468 -115.378992)
		(width 0.14224)
		(layer "In4.Cu")
		(net "M_E_DQS_DN<1>")
	)
	(segment
		(start 209.954876 -143.5862)
		(end 209.744056 -143.37538)
		(width 0.14224)
		(layer "In4.Cu")
		(net "M_E_DQS_DN<1>")
	)
	(segment
		(start 218.516454 -113.239804)
		(end 218.516454 -112.928908)
		(width 0.14224)
		(layer "In4.Cu")
		(net "M_E_DQS_DN<1>")
	)
	(segment
		(start 210.743546 -138.489436)
		(end 210.901026 -138.331956)
		(width 0.14224)
		(layer "In4.Cu")
		(net "M_E_DQS_DN<1>")
	)
	(segment
		(start 234.163108 -90.59799)
		(end 234.241848 -90.461338)
		(width 0.0889)
		(layer "In4.Cu")
		(net "M_E_DQS_DN<1>")
	)
	(segment
		(start 217.738706 -111.614966)
		(end 222.1738 -107.179872)
		(width 0.14224)
		(layer "In4.Cu")
		(net "M_E_DQS_DN<1>")
	)
	(segment
		(start 235.926376 -89.51849)
		(end 235.905294 -89.43975)
		(width 0.0889)
		(layer "In4.Cu")
		(net "M_E_DQS_DN<1>")
	)
	(segment
		(start 227.3046 -99.415854)
		(end 227.3046 -98.151442)
		(width 0.14224)
		(layer "In4.Cu")
		(net "M_E_DQS_DN<1>")
	)
	(segment
		(start 209.954876 -144.841976)
		(end 209.954876 -143.5862)
		(width 0.14224)
		(layer "In4.Cu")
		(net "M_E_DQS_DN<1>")
	)
	(segment
		(start 210.314794 -139.881356)
		(end 210.387946 -139.881356)
		(width 0.14224)
		(layer "In4.Cu")
		(net "M_E_DQS_DN<1>")
	)
	(segment
		(start 210.901026 -138.331956)
		(end 210.901026 -138.077956)
		(width 0.14224)
		(layer "In4.Cu")
		(net "M_E_DQS_DN<1>")
	)
	(segment
		(start 210.901026 -133.630162)
		(end 210.901026 -128.06934)
		(width 0.14224)
		(layer "In4.Cu")
		(net "M_E_DQS_DN<1>")
	)
	(segment
		(start 214.99068 -117.401086)
		(end 214.99068 -117.031008)
		(width 0.14224)
		(layer "In4.Cu")
		(net "M_E_DQS_DN<1>")
	)
	(segment
		(start 218.38793 -112.800384)
		(end 217.738706 -112.151414)
		(width 0.14224)
		(layer "In4.Cu")
		(net "M_E_DQS_DN<1>")
	)
	(segment
		(start 232.601516 -92.910914)
		(end 233.56443 -92.910914)
		(width 0.0889)
		(layer "In4.Cu")
		(net "M_E_DQS_DN<1>")
	)
	(segment
		(start 235.905294 -89.43975)
		(end 235.612178 -89.27084)
		(width 0.0889)
		(layer "In4.Cu")
		(net "M_E_DQS_DN<1>")
	)
	(segment
		(start 217.753946 -113.690908)
		(end 218.06535 -113.690908)
		(width 0.14224)
		(layer "In4.Cu")
		(net "M_E_DQS_DN<1>")
	)
	(segment
		(start 217.738706 -112.151414)
		(end 217.738706 -111.614966)
		(width 0.14224)
		(layer "In4.Cu")
		(net "M_E_DQS_DN<1>")
	)
	(segment
		(start 215.8492 -115.595908)
		(end 216.16035 -115.595908)
		(width 0.14224)
		(layer "In4.Cu")
		(net "M_E_DQS_DN<1>")
	)
	(arc
		(start 234.241848 -90.461338)
		(mid 234.450456 -90.249406)
		(end 234.735878 -90.165936)
		(width 0.0889)
		(layer "In4.Cu")
		(net "M_E_DQS_DN<1>")
	)
	(arc
		(start 234.768644 -90.165936)
		(mid 234.960286 -90.10877)
		(end 235.100368 -89.966038)
		(width 0.0889)
		(layer "In4.Cu")
		(net "M_E_DQS_DN<1>")
	)
	(arc
		(start 235.623354 -89.67089)
		(mid 235.791791 -89.628357)
		(end 235.926376 -89.51849)
		(width 0.0889)
		(layer "In4.Cu")
		(net "M_E_DQS_DN<1>")
	)
	(arc
		(start 235.100368 -89.966038)
		(mid 235.307372 -89.755174)
		(end 235.590588 -89.67089)
		(width 0.0889)
		(layer "In4.Cu")
		(net "M_E_DQS_DN<1>")
	)
	(segment
		(start 248.720864 -98.47072)
		(end 248.714514 -98.481388)
		(width 0.0889)
		(layer "F.Cu")
		(net "M_E_DQS_DN<17>")
	)
	(segment
		(start 248.619264 -99.872292)
		(end 248.733564 -99.986592)
		(width 0.0889)
		(layer "F.Cu")
		(net "M_E_DQS_DN<17>")
	)
	(segment
		(start 249.061224 -97.690686)
		(end 249.061224 -97.358962)
		(width 0.0889)
		(layer "F.Cu")
		(net "M_E_DQS_DN<17>")
	)
	(segment
		(start 237.631732 -144.1704)
		(end 237.81766 -144.356328)
		(width 0.1651)
		(layer "F.Cu")
		(net "M_E_DQS_DN<17>")
	)
	(segment
		(start 248.619264 -99.577906)
		(end 248.619264 -99.872292)
		(width 0.0889)
		(layer "F.Cu")
		(net "M_E_DQS_DN<17>")
	)
	(segment
		(start 238.049816 -142.677642)
		(end 238.049816 -143.331184)
		(width 0.1651)
		(layer "F.Cu")
		(net "M_E_DQS_DN<17>")
	)
	(segment
		(start 237.179612 -125.969776)
		(end 237.146338 -125.969776)
		(width 0.1651)
		(layer "F.Cu")
		(net "M_E_DQS_DN<17>")
	)
	(segment
		(start 237.965996 -113.504472)
		(end 237.965996 -125.183392)
		(width 0.1651)
		(layer "F.Cu")
		(net "M_E_DQS_DN<17>")
	)
	(segment
		(start 237.631732 -143.749268)
		(end 237.631732 -144.1704)
		(width 0.1651)
		(layer "F.Cu")
		(net "M_E_DQS_DN<17>")
	)
	(segment
		(start 248.045224 -104.355138)
		(end 244.07876 -108.321602)
		(width 0.1016)
		(layer "F.Cu")
		(net "M_E_DQS_DN<17>")
	)
	(segment
		(start 248.714514 -97.490788)
		(end 248.709688 -97.499424)
		(width 0.0889)
		(layer "F.Cu")
		(net "M_E_DQS_DN<17>")
	)
	(segment
		(start 237.357412 -144.85493)
		(end 237.168182 -144.6657)
		(width 0.1651)
		(layer "F.Cu")
		(net "M_E_DQS_DN<17>")
	)
	(segment
		(start 237.168182 -144.6657)
		(end 237.149132 -144.6657)
		(width 0.1651)
		(layer "F.Cu")
		(net "M_E_DQS_DN<17>")
	)
	(segment
		(start 237.565692 -144.85493)
		(end 237.357412 -144.85493)
		(width 0.1651)
		(layer "F.Cu")
		(net "M_E_DQS_DN<17>")
	)
	(segment
		(start 238.050324 -142.6718)
		(end 238.049816 -142.677642)
		(width 0.1651)
		(layer "F.Cu")
		(net "M_E_DQS_DN<17>")
	)
	(segment
		(start 248.733564 -103.29037)
		(end 248.045224 -103.97871)
		(width 0.1016)
		(layer "F.Cu")
		(net "M_E_DQS_DN<17>")
	)
	(segment
		(start 237.965996 -125.183392)
		(end 237.179612 -125.969776)
		(width 0.1651)
		(layer "F.Cu")
		(net "M_E_DQS_DN<17>")
	)
	(segment
		(start 249.061224 -97.358962)
		(end 248.997978 -97.295716)
		(width 0.0889)
		(layer "F.Cu")
		(net "M_E_DQS_DN<17>")
	)
	(segment
		(start 248.045224 -103.97871)
		(end 248.045224 -104.355138)
		(width 0.1016)
		(layer "F.Cu")
		(net "M_E_DQS_DN<17>")
	)
	(segment
		(start 237.81766 -144.602962)
		(end 237.565692 -144.85493)
		(width 0.1651)
		(layer "F.Cu")
		(net "M_E_DQS_DN<17>")
	)
	(segment
		(start 248.714514 -98.481388)
		(end 248.709688 -98.490024)
		(width 0.0889)
		(layer "F.Cu")
		(net "M_E_DQS_DN<17>")
	)
	(segment
		(start 248.687336 -99.481386)
		(end 248.619264 -99.577906)
		(width 0.0889)
		(layer "F.Cu")
		(net "M_E_DQS_DN<17>")
	)
	(segment
		(start 243.148866 -108.321602)
		(end 242.970558 -108.49991)
		(width 0.1016)
		(layer "F.Cu")
		(net "M_E_DQS_DN<17>")
	)
	(segment
		(start 248.733564 -100.492814)
		(end 248.733564 -103.29037)
		(width 0.1016)
		(layer "F.Cu")
		(net "M_E_DQS_DN<17>")
	)
	(segment
		(start 248.733564 -99.986592)
		(end 248.733564 -100.492814)
		(width 0.0889)
		(layer "F.Cu")
		(net "M_E_DQS_DN<17>")
	)
	(segment
		(start 242.970558 -108.49991)
		(end 237.965996 -113.504472)
		(width 0.1651)
		(layer "F.Cu")
		(net "M_E_DQS_DN<17>")
	)
	(segment
		(start 244.07876 -108.321602)
		(end 243.148866 -108.321602)
		(width 0.1016)
		(layer "F.Cu")
		(net "M_E_DQS_DN<17>")
	)
	(segment
		(start 237.81766 -144.356328)
		(end 237.81766 -144.602962)
		(width 0.1651)
		(layer "F.Cu")
		(net "M_E_DQS_DN<17>")
	)
	(segment
		(start 238.049816 -143.331184)
		(end 237.631732 -143.749268)
		(width 0.1651)
		(layer "F.Cu")
		(net "M_E_DQS_DN<17>")
	)
	(via
		(at 237.149132 -144.6657)
		(size 0.508)
		(drill 0.254)
		(layers "F.Cu" "B.Cu")
		(net "M_E_DQS_DN<17>")
	)
	(via
		(at 237.146338 -125.969776)
		(size 0.508)
		(drill 0.254)
		(layers "F.Cu" "B.Cu")
		(net "M_E_DQS_DN<17>")
	)
	(via
		(at 237.142528 -140.4874)
		(size 0.508)
		(drill 0.254)
		(layers "F.Cu" "B.Cu")
		(net "M_E_DQS_DN<17>")
	)
	(arc
		(start 248.714514 -98.881438)
		(mid 248.788569 -99.18537)
		(end 248.687336 -99.481386)
		(width 0.0889)
		(layer "F.Cu")
		(net "M_E_DQS_DN<17>")
	)
	(arc
		(start 248.709688 -98.490024)
		(mid 248.660933 -98.686376)
		(end 248.714514 -98.881438)
		(width 0.0889)
		(layer "F.Cu")
		(net "M_E_DQS_DN<17>")
	)
	(arc
		(start 248.709688 -97.499424)
		(mid 248.660933 -97.695776)
		(end 248.714514 -97.890838)
		(width 0.0889)
		(layer "F.Cu")
		(net "M_E_DQS_DN<17>")
	)
	(arc
		(start 248.997978 -97.295716)
		(mid 248.834171 -97.361194)
		(end 248.714514 -97.490788)
		(width 0.0889)
		(layer "F.Cu")
		(net "M_E_DQS_DN<17>")
	)
	(arc
		(start 248.714514 -97.890838)
		(mid 248.793736 -98.179956)
		(end 248.720864 -98.47072)
		(width 0.0889)
		(layer "F.Cu")
		(net "M_E_DQS_DN<17>")
	)
	(segment
		(start 237.784132 -140.5128)
		(end 237.784132 -140.843)
		(width 0.1651)
		(layer "B.Cu")
		(net "M_E_DQS_DN<17>")
	)
	(segment
		(start 237.606332 -141.0208)
		(end 237.606332 -141.376654)
		(width 0.1651)
		(layer "B.Cu")
		(net "M_E_DQS_DN<17>")
	)
	(segment
		(start 237.606332 -141.376654)
		(end 238.05007 -141.820392)
		(width 0.1651)
		(layer "B.Cu")
		(net "M_E_DQS_DN<17>")
	)
	(segment
		(start 238.05007 -141.820392)
		(end 238.05007 -142.476728)
		(width 0.1651)
		(layer "B.Cu")
		(net "M_E_DQS_DN<17>")
	)
	(segment
		(start 238.05007 -142.476728)
		(end 238.050324 -142.477236)
		(width 0.1651)
		(layer "B.Cu")
		(net "M_E_DQS_DN<17>")
	)
	(segment
		(start 237.142528 -140.4874)
		(end 237.337092 -140.292836)
		(width 0.1651)
		(layer "B.Cu")
		(net "M_E_DQS_DN<17>")
	)
	(segment
		(start 237.784132 -140.843)
		(end 237.606332 -141.0208)
		(width 0.1651)
		(layer "B.Cu")
		(net "M_E_DQS_DN<17>")
	)
	(segment
		(start 237.337092 -140.292836)
		(end 237.564168 -140.292836)
		(width 0.1651)
		(layer "B.Cu")
		(net "M_E_DQS_DN<17>")
	)
	(segment
		(start 237.564168 -140.292836)
		(end 237.784132 -140.5128)
		(width 0.1651)
		(layer "B.Cu")
		(net "M_E_DQS_DN<17>")
	)
	(segment
		(start 237.038896 -142.23492)
		(end 236.906816 -142.10284)
		(width 0.14224)
		(layer "In9.Cu")
		(net "M_E_DQS_DN<17>")
	)
	(segment
		(start 236.906816 -143.39824)
		(end 236.906816 -143.03756)
		(width 0.14224)
		(layer "In9.Cu")
		(net "M_E_DQS_DN<17>")
	)
	(segment
		(start 236.906816 -141.75486)
		(end 237.056676 -141.605)
		(width 0.14224)
		(layer "In9.Cu")
		(net "M_E_DQS_DN<17>")
	)
	(segment
		(start 237.297976 -141.605)
		(end 237.577376 -141.3256)
		(width 0.14224)
		(layer "In9.Cu")
		(net "M_E_DQS_DN<17>")
	)
	(segment
		(start 237.193836 -142.89786)
		(end 237.348776 -142.74292)
		(width 0.14224)
		(layer "In9.Cu")
		(net "M_E_DQS_DN<17>")
	)
	(segment
		(start 237.394496 -143.5608)
		(end 237.069376 -143.5608)
		(width 0.14224)
		(layer "In9.Cu")
		(net "M_E_DQS_DN<17>")
	)
	(segment
		(start 237.582202 -144.23263)
		(end 237.582202 -143.748506)
		(width 0.14224)
		(layer "In9.Cu")
		(net "M_E_DQS_DN<17>")
	)
	(segment
		(start 236.906816 -142.10284)
		(end 236.906816 -141.75486)
		(width 0.14224)
		(layer "In9.Cu")
		(net "M_E_DQS_DN<17>")
	)
	(segment
		(start 237.348776 -142.38986)
		(end 237.193836 -142.23492)
		(width 0.14224)
		(layer "In9.Cu")
		(net "M_E_DQS_DN<17>")
	)
	(segment
		(start 237.069376 -143.5608)
		(end 236.906816 -143.39824)
		(width 0.14224)
		(layer "In9.Cu")
		(net "M_E_DQS_DN<17>")
	)
	(segment
		(start 237.193836 -142.23492)
		(end 237.038896 -142.23492)
		(width 0.14224)
		(layer "In9.Cu")
		(net "M_E_DQS_DN<17>")
	)
	(segment
		(start 237.056676 -141.605)
		(end 237.297976 -141.605)
		(width 0.14224)
		(layer "In9.Cu")
		(net "M_E_DQS_DN<17>")
	)
	(segment
		(start 237.348776 -142.74292)
		(end 237.348776 -142.38986)
		(width 0.14224)
		(layer "In9.Cu")
		(net "M_E_DQS_DN<17>")
	)
	(segment
		(start 236.906816 -143.03756)
		(end 237.046516 -142.89786)
		(width 0.14224)
		(layer "In9.Cu")
		(net "M_E_DQS_DN<17>")
	)
	(segment
		(start 237.577376 -140.922248)
		(end 237.142528 -140.4874)
		(width 0.14224)
		(layer "In9.Cu")
		(net "M_E_DQS_DN<17>")
	)
	(segment
		(start 237.149132 -144.6657)
		(end 237.582202 -144.23263)
		(width 0.14224)
		(layer "In9.Cu")
		(net "M_E_DQS_DN<17>")
	)
	(segment
		(start 237.577376 -141.3256)
		(end 237.577376 -140.922248)
		(width 0.14224)
		(layer "In9.Cu")
		(net "M_E_DQS_DN<17>")
	)
	(segment
		(start 237.046516 -142.89786)
		(end 237.193836 -142.89786)
		(width 0.14224)
		(layer "In9.Cu")
		(net "M_E_DQS_DN<17>")
	)
	(segment
		(start 237.582202 -143.748506)
		(end 237.394496 -143.5608)
		(width 0.14224)
		(layer "In9.Cu")
		(net "M_E_DQS_DN<17>")
	)
	(segment
		(start 237.594648 -126.45136)
		(end 237.146338 -126.00305)
		(width 0.14224)
		(layer "In11.Cu")
		(net "M_E_DQS_DN<17>")
	)
	(segment
		(start 237.146338 -126.00305)
		(end 237.146338 -125.969776)
		(width 0.14224)
		(layer "In11.Cu")
		(net "M_E_DQS_DN<17>")
	)
	(segment
		(start 237.594648 -128.030732)
		(end 237.594648 -126.45136)
		(width 0.14224)
		(layer "In11.Cu")
		(net "M_E_DQS_DN<17>")
	)
	(segment
		(start 237.924848 -128.360932)
		(end 237.594648 -128.030732)
		(width 0.14224)
		(layer "In11.Cu")
		(net "M_E_DQS_DN<17>")
	)
	(segment
		(start 237.142528 -140.4874)
		(end 237.149894 -140.4874)
		(width 0.14224)
		(layer "In11.Cu")
		(net "M_E_DQS_DN<17>")
	)
	(segment
		(start 237.924848 -139.712446)
		(end 237.924848 -128.360932)
		(width 0.14224)
		(layer "In11.Cu")
		(net "M_E_DQS_DN<17>")
	)
	(segment
		(start 237.149894 -140.4874)
		(end 237.924848 -139.712446)
		(width 0.14224)
		(layer "In11.Cu")
		(net "M_E_DQS_DN<17>")
	)
	(segment
		(start 311.30748 -144.85493)
		(end 311.11825 -144.6657)
		(width 0.1651)
		(layer "F.Cu")
		(net "M_E_DQS_DN<16>")
	)
	(segment
		(start 285.7881 -94.042738)
		(end 286.3596 -94.042738)
		(width 0.1651)
		(layer "F.Cu")
		(net "M_E_DQS_DN<16>")
	)
	(segment
		(start 311.51576 -144.85493)
		(end 311.30748 -144.85493)
		(width 0.1651)
		(layer "F.Cu")
		(net "M_E_DQS_DN<16>")
	)
	(segment
		(start 311.11825 -144.6657)
		(end 311.0992 -144.6657)
		(width 0.1651)
		(layer "F.Cu")
		(net "M_E_DQS_DN<16>")
	)
	(segment
		(start 311.767728 -144.356328)
		(end 311.767728 -144.602962)
		(width 0.1651)
		(layer "F.Cu")
		(net "M_E_DQS_DN<16>")
	)
	(segment
		(start 311.5818 -143.749268)
		(end 311.5818 -144.1704)
		(width 0.1651)
		(layer "F.Cu")
		(net "M_E_DQS_DN<16>")
	)
	(segment
		(start 312.000392 -142.6718)
		(end 311.999884 -142.677642)
		(width 0.1651)
		(layer "F.Cu")
		(net "M_E_DQS_DN<16>")
	)
	(segment
		(start 311.999884 -142.677642)
		(end 311.999884 -143.331184)
		(width 0.1651)
		(layer "F.Cu")
		(net "M_E_DQS_DN<16>")
	)
	(segment
		(start 311.5818 -144.1704)
		(end 311.767728 -144.356328)
		(width 0.1651)
		(layer "F.Cu")
		(net "M_E_DQS_DN<16>")
	)
	(segment
		(start 311.999884 -143.331184)
		(end 311.5818 -143.749268)
		(width 0.1651)
		(layer "F.Cu")
		(net "M_E_DQS_DN<16>")
	)
	(segment
		(start 311.767728 -144.602962)
		(end 311.51576 -144.85493)
		(width 0.1651)
		(layer "F.Cu")
		(net "M_E_DQS_DN<16>")
	)
	(via
		(at 286.3596 -94.042738)
		(size 0.508)
		(drill 0.254)
		(layers "F.Cu" "B.Cu")
		(net "M_E_DQS_DN<16>")
	)
	(via
		(at 311.0992 -144.6657)
		(size 0.508)
		(drill 0.254)
		(layers "F.Cu" "B.Cu")
		(net "M_E_DQS_DN<16>")
	)
	(via
		(at 311.092596 -140.4874)
		(size 0.508)
		(drill 0.254)
		(layers "F.Cu" "B.Cu")
		(net "M_E_DQS_DN<16>")
	)
	(segment
		(start 311.7342 -140.5128)
		(end 311.514236 -140.292836)
		(width 0.1651)
		(layer "B.Cu")
		(net "M_E_DQS_DN<16>")
	)
	(segment
		(start 311.514236 -140.292836)
		(end 311.28716 -140.292836)
		(width 0.1651)
		(layer "B.Cu")
		(net "M_E_DQS_DN<16>")
	)
	(segment
		(start 311.5564 -141.376654)
		(end 311.5564 -141.0208)
		(width 0.1651)
		(layer "B.Cu")
		(net "M_E_DQS_DN<16>")
	)
	(segment
		(start 311.5564 -141.0208)
		(end 311.7342 -140.843)
		(width 0.1651)
		(layer "B.Cu")
		(net "M_E_DQS_DN<16>")
	)
	(segment
		(start 312.000392 -142.477236)
		(end 312.000392 -141.820646)
		(width 0.1651)
		(layer "B.Cu")
		(net "M_E_DQS_DN<16>")
	)
	(segment
		(start 311.7342 -140.843)
		(end 311.7342 -140.5128)
		(width 0.1651)
		(layer "B.Cu")
		(net "M_E_DQS_DN<16>")
	)
	(segment
		(start 311.28716 -140.292836)
		(end 311.092596 -140.4874)
		(width 0.1651)
		(layer "B.Cu")
		(net "M_E_DQS_DN<16>")
	)
	(segment
		(start 312.000392 -141.820646)
		(end 311.5564 -141.376654)
		(width 0.1651)
		(layer "B.Cu")
		(net "M_E_DQS_DN<16>")
	)
	(segment
		(start 289.44697 -106.13009)
		(end 289.592004 -106.38155)
		(width 0.0889)
		(layer "In4.Cu")
		(net "M_E_DQS_DN<16>")
	)
	(segment
		(start 286.013144 -94.242636)
		(end 286.01289 -94.242382)
		(width 0.0889)
		(layer "In4.Cu")
		(net "M_E_DQS_DN<16>")
	)
	(segment
		(start 310.988964 -142.23492)
		(end 311.143904 -142.23492)
		(width 0.14224)
		(layer "In4.Cu")
		(net "M_E_DQS_DN<16>")
	)
	(segment
		(start 286.3596 -102.367588)
		(end 286.38119 -102.367588)
		(width 0.0889)
		(layer "In4.Cu")
		(net "M_E_DQS_DN<16>")
	)
	(segment
		(start 311.298844 -142.74292)
		(end 311.143904 -142.89786)
		(width 0.14224)
		(layer "In4.Cu")
		(net "M_E_DQS_DN<16>")
	)
	(segment
		(start 286.87141 -103.253286)
		(end 286.866584 -103.261922)
		(width 0.0889)
		(layer "In4.Cu")
		(net "M_E_DQS_DN<16>")
	)
	(segment
		(start 311.143904 -142.89786)
		(end 310.996584 -142.89786)
		(width 0.14224)
		(layer "In4.Cu")
		(net "M_E_DQS_DN<16>")
	)
	(segment
		(start 286.013144 -100.186236)
		(end 286.022034 -100.201476)
		(width 0.0889)
		(layer "In4.Cu")
		(net "M_E_DQS_DN<16>")
	)
	(segment
		(start 311.53227 -143.748506)
		(end 311.53227 -144.23263)
		(width 0.14224)
		(layer "In4.Cu")
		(net "M_E_DQS_DN<16>")
	)
	(segment
		(start 286.87776 -104.233218)
		(end 286.87141 -104.243886)
		(width 0.0889)
		(layer "In4.Cu")
		(net "M_E_DQS_DN<16>")
	)
	(segment
		(start 311.527444 -140.922248)
		(end 311.527444 -141.3256)
		(width 0.14224)
		(layer "In4.Cu")
		(net "M_E_DQS_DN<16>")
	)
	(segment
		(start 310.856884 -141.75486)
		(end 310.856884 -142.10284)
		(width 0.14224)
		(layer "In4.Cu")
		(net "M_E_DQS_DN<16>")
	)
	(segment
		(start 311.344564 -143.5608)
		(end 311.53227 -143.748506)
		(width 0.14224)
		(layer "In4.Cu")
		(net "M_E_DQS_DN<16>")
	)
	(segment
		(start 311.874916 -125.558296)
		(end 311.874916 -139.70508)
		(width 0.14224)
		(layer "In4.Cu")
		(net "M_E_DQS_DN<16>")
	)
	(segment
		(start 286.87141 -104.243886)
		(end 286.866584 -104.252522)
		(width 0.0889)
		(layer "In4.Cu")
		(net "M_E_DQS_DN<16>")
	)
	(segment
		(start 310.996584 -142.89786)
		(end 310.856884 -143.03756)
		(width 0.14224)
		(layer "In4.Cu")
		(net "M_E_DQS_DN<16>")
	)
	(segment
		(start 289.592004 -106.38155)
		(end 289.592004 -106.800904)
		(width 0.0889)
		(layer "In4.Cu")
		(net "M_E_DQS_DN<16>")
	)
	(segment
		(start 289.592004 -106.800904)
		(end 289.886136 -107.095036)
		(width 0.0889)
		(layer "In4.Cu")
		(net "M_E_DQS_DN<16>")
	)
	(segment
		(start 290.73094 -107.88396)
		(end 294.20058 -107.88396)
		(width 0.14224)
		(layer "In4.Cu")
		(net "M_E_DQS_DN<16>")
	)
	(segment
		(start 288.930334 -105.834688)
		(end 288.948114 -105.834688)
		(width 0.0889)
		(layer "In4.Cu")
		(net "M_E_DQS_DN<16>")
	)
	(segment
		(start 286.013144 -101.176836)
		(end 286.022034 -101.192076)
		(width 0.0889)
		(layer "In4.Cu")
		(net "M_E_DQS_DN<16>")
	)
	(segment
		(start 311.53227 -144.23263)
		(end 311.0992 -144.6657)
		(width 0.14224)
		(layer "In4.Cu")
		(net "M_E_DQS_DN<16>")
	)
	(segment
		(start 287.203134 -104.843834)
		(end 287.2359 -104.843834)
		(width 0.0889)
		(layer "In4.Cu")
		(net "M_E_DQS_DN<16>")
	)
	(segment
		(start 311.248044 -141.605)
		(end 311.006744 -141.605)
		(width 0.14224)
		(layer "In4.Cu")
		(net "M_E_DQS_DN<16>")
	)
	(segment
		(start 311.092596 -140.4874)
		(end 311.527444 -140.922248)
		(width 0.14224)
		(layer "In4.Cu")
		(net "M_E_DQS_DN<16>")
	)
	(segment
		(start 288.065464 -105.339388)
		(end 288.09823 -105.339388)
		(width 0.0889)
		(layer "In4.Cu")
		(net "M_E_DQS_DN<16>")
	)
	(segment
		(start 310.856884 -142.10284)
		(end 310.988964 -142.23492)
		(width 0.14224)
		(layer "In4.Cu")
		(net "M_E_DQS_DN<16>")
	)
	(segment
		(start 311.298844 -142.38986)
		(end 311.298844 -142.74292)
		(width 0.14224)
		(layer "In4.Cu")
		(net "M_E_DQS_DN<16>")
	)
	(segment
		(start 311.143904 -142.23492)
		(end 311.298844 -142.38986)
		(width 0.14224)
		(layer "In4.Cu")
		(net "M_E_DQS_DN<16>")
	)
	(segment
		(start 311.006744 -141.605)
		(end 310.856884 -141.75486)
		(width 0.14224)
		(layer "In4.Cu")
		(net "M_E_DQS_DN<16>")
	)
	(segment
		(start 310.856884 -143.39824)
		(end 311.019444 -143.5608)
		(width 0.14224)
		(layer "In4.Cu")
		(net "M_E_DQS_DN<16>")
	)
	(segment
		(start 286.3596 -93.704664)
		(end 286.301942 -93.647006)
		(width 0.0889)
		(layer "In4.Cu")
		(net "M_E_DQS_DN<16>")
	)
	(segment
		(start 286.87776 -103.242618)
		(end 286.87141 -103.253286)
		(width 0.0889)
		(layer "In4.Cu")
		(net "M_E_DQS_DN<16>")
	)
	(segment
		(start 310.856884 -143.03756)
		(end 310.856884 -143.39824)
		(width 0.14224)
		(layer "In4.Cu")
		(net "M_E_DQS_DN<16>")
	)
	(segment
		(start 294.20058 -107.88396)
		(end 311.874916 -125.558296)
		(width 0.14224)
		(layer "In4.Cu")
		(net "M_E_DQS_DN<16>")
	)
	(segment
		(start 286.3596 -94.042738)
		(end 286.3596 -93.704664)
		(width 0.0889)
		(layer "In4.Cu")
		(net "M_E_DQS_DN<16>")
	)
	(segment
		(start 289.942016 -107.095036)
		(end 289.957764 -107.110784)
		(width 0.0889)
		(layer "In4.Cu")
		(net "M_E_DQS_DN<16>")
	)
	(segment
		(start 286.013144 -99.195636)
		(end 286.022034 -99.210876)
		(width 0.0889)
		(layer "In4.Cu")
		(net "M_E_DQS_DN<16>")
	)
	(segment
		(start 289.886136 -107.095036)
		(end 289.942016 -107.095036)
		(width 0.0889)
		(layer "In4.Cu")
		(net "M_E_DQS_DN<16>")
	)
	(segment
		(start 289.957764 -107.110784)
		(end 290.73094 -107.88396)
		(width 0.14224)
		(layer "In4.Cu")
		(net "M_E_DQS_DN<16>")
	)
	(segment
		(start 311.019444 -143.5608)
		(end 311.344564 -143.5608)
		(width 0.14224)
		(layer "In4.Cu")
		(net "M_E_DQS_DN<16>")
	)
	(segment
		(start 311.874916 -139.70508)
		(end 311.092596 -140.4874)
		(width 0.14224)
		(layer "In4.Cu")
		(net "M_E_DQS_DN<16>")
	)
	(segment
		(start 311.527444 -141.3256)
		(end 311.248044 -141.605)
		(width 0.14224)
		(layer "In4.Cu")
		(net "M_E_DQS_DN<16>")
	)
	(arc
		(start 286.866584 -103.261922)
		(mid 286.817829 -103.458274)
		(end 286.87141 -103.653336)
		(width 0.0889)
		(layer "In4.Cu")
		(net "M_E_DQS_DN<16>")
	)
	(arc
		(start 286.01289 -98.795586)
		(mid 285.996028 -98.828817)
		(end 285.982156 -98.863404)
		(width 0.0889)
		(layer "In4.Cu")
		(net "M_E_DQS_DN<16>")
	)
	(arc
		(start 288.09823 -105.339388)
		(mid 288.381447 -105.423669)
		(end 288.58845 -105.634536)
		(width 0.0889)
		(layer "In4.Cu")
		(net "M_E_DQS_DN<16>")
	)
	(arc
		(start 286.01289 -95.232982)
		(mid 286.092021 -95.528384)
		(end 286.01289 -95.823786)
		(width 0.0889)
		(layer "In4.Cu")
		(net "M_E_DQS_DN<16>")
	)
	(arc
		(start 286.38119 -102.367588)
		(mid 286.87358 -102.666521)
		(end 286.87776 -103.242618)
		(width 0.0889)
		(layer "In4.Cu")
		(net "M_E_DQS_DN<16>")
	)
	(arc
		(start 286.013144 -100.77704)
		(mid 285.959611 -100.976938)
		(end 286.013144 -101.176836)
		(width 0.0889)
		(layer "In4.Cu")
		(net "M_E_DQS_DN<16>")
	)
	(arc
		(start 286.01289 -94.242382)
		(mid 286.092021 -94.537784)
		(end 286.01289 -94.833186)
		(width 0.0889)
		(layer "In4.Cu")
		(net "M_E_DQS_DN<16>")
	)
	(arc
		(start 287.2359 -104.843834)
		(mid 287.521324 -104.927301)
		(end 287.72993 -105.139236)
		(width 0.0889)
		(layer "In4.Cu")
		(net "M_E_DQS_DN<16>")
	)
	(arc
		(start 287.72993 -105.139236)
		(mid 287.871613 -105.28304)
		(end 288.065464 -105.339388)
		(width 0.0889)
		(layer "In4.Cu")
		(net "M_E_DQS_DN<16>")
	)
	(arc
		(start 286.013144 -99.78644)
		(mid 285.959611 -99.986338)
		(end 286.013144 -100.186236)
		(width 0.0889)
		(layer "In4.Cu")
		(net "M_E_DQS_DN<16>")
	)
	(arc
		(start 286.022034 -99.210876)
		(mid 286.092431 -99.499827)
		(end 286.013144 -99.78644)
		(width 0.0889)
		(layer "In4.Cu")
		(net "M_E_DQS_DN<16>")
	)
	(arc
		(start 286.01289 -96.814386)
		(mid 285.959391 -97.014284)
		(end 286.01289 -97.214182)
		(width 0.0889)
		(layer "In4.Cu")
		(net "M_E_DQS_DN<16>")
	)
	(arc
		(start 286.008826 -94.23527)
		(mid 286.010966 -94.238964)
		(end 286.013144 -94.242636)
		(width 0.0889)
		(layer "In4.Cu")
		(net "M_E_DQS_DN<16>")
	)
	(arc
		(start 288.948114 -105.834688)
		(mid 289.236259 -105.917007)
		(end 289.44697 -106.13009)
		(width 0.0889)
		(layer "In4.Cu")
		(net "M_E_DQS_DN<16>")
	)
	(arc
		(start 285.982156 -98.863404)
		(mid 285.96136 -99.032903)
		(end 286.013144 -99.195636)
		(width 0.0889)
		(layer "In4.Cu")
		(net "M_E_DQS_DN<16>")
	)
	(arc
		(start 286.022034 -100.201476)
		(mid 286.092431 -100.490427)
		(end 286.013144 -100.77704)
		(width 0.0889)
		(layer "In4.Cu")
		(net "M_E_DQS_DN<16>")
	)
	(arc
		(start 286.866584 -104.252522)
		(mid 286.870331 -104.641778)
		(end 287.203134 -104.843834)
		(width 0.0889)
		(layer "In4.Cu")
		(net "M_E_DQS_DN<16>")
	)
	(arc
		(start 286.01289 -97.214182)
		(mid 286.092021 -97.509584)
		(end 286.01289 -97.804986)
		(width 0.0889)
		(layer "In4.Cu")
		(net "M_E_DQS_DN<16>")
	)
	(arc
		(start 288.58845 -105.634536)
		(mid 288.732898 -105.779867)
		(end 288.930334 -105.834688)
		(width 0.0889)
		(layer "In4.Cu")
		(net "M_E_DQS_DN<16>")
	)
	(arc
		(start 286.022034 -101.192076)
		(mid 286.092431 -101.481027)
		(end 286.013144 -101.76764)
		(width 0.0889)
		(layer "In4.Cu")
		(net "M_E_DQS_DN<16>")
	)
	(arc
		(start 286.01289 -94.833186)
		(mid 285.959391 -95.033084)
		(end 286.01289 -95.232982)
		(width 0.0889)
		(layer "In4.Cu")
		(net "M_E_DQS_DN<16>")
	)
	(arc
		(start 286.87141 -103.653336)
		(mid 286.950632 -103.942454)
		(end 286.87776 -104.233218)
		(width 0.0889)
		(layer "In4.Cu")
		(net "M_E_DQS_DN<16>")
	)
	(arc
		(start 286.01289 -95.823786)
		(mid 285.959391 -96.023684)
		(end 286.01289 -96.223582)
		(width 0.0889)
		(layer "In4.Cu")
		(net "M_E_DQS_DN<16>")
	)
	(arc
		(start 286.01289 -97.804986)
		(mid 285.959391 -98.004884)
		(end 286.01289 -98.204782)
		(width 0.0889)
		(layer "In4.Cu")
		(net "M_E_DQS_DN<16>")
	)
	(arc
		(start 286.01289 -96.223582)
		(mid 286.092021 -96.518984)
		(end 286.01289 -96.814386)
		(width 0.0889)
		(layer "In4.Cu")
		(net "M_E_DQS_DN<16>")
	)
	(arc
		(start 286.01289 -98.204782)
		(mid 286.092021 -98.500184)
		(end 286.01289 -98.795586)
		(width 0.0889)
		(layer "In4.Cu")
		(net "M_E_DQS_DN<16>")
	)
	(arc
		(start 286.013144 -101.76764)
		(mid 286.013227 -102.167581)
		(end 286.3596 -102.367588)
		(width 0.0889)
		(layer "In4.Cu")
		(net "M_E_DQS_DN<16>")
	)
	(arc
		(start 286.301942 -93.647006)
		(mid 286.001627 -93.864458)
		(end 286.008826 -94.23527)
		(width 0.0889)
		(layer "In4.Cu")
		(net "M_E_DQS_DN<16>")
	)
	(segment
		(start 302.4251 -118.483888)
		(end 302.4251 -122.009154)
		(width 0.1651)
		(layer "F.Cu")
		(net "M_E_DQS_DN<15>")
	)
	(segment
		(start 302.417734 -144.602962)
		(end 302.165766 -144.85493)
		(width 0.1651)
		(layer "F.Cu")
		(net "M_E_DQS_DN<15>")
	)
	(segment
		(start 298.958 -110.41888)
		(end 298.958 -110.49)
		(width 0.1016)
		(layer "F.Cu")
		(net "M_E_DQS_DN<15>")
	)
	(segment
		(start 285.7881 -100.645214)
		(end 285.724854 -100.581968)
		(width 0.0889)
		(layer "F.Cu")
		(net "M_E_DQS_DN<15>")
	)
	(segment
		(start 285.441644 -102.167436)
		(end 285.44139 -102.167944)
		(width 0.0889)
		(layer "F.Cu")
		(net "M_E_DQS_DN<15>")
	)
	(segment
		(start 302.4251 -113.9571)
		(end 302.4251 -118.483888)
		(width 0.1651)
		(layer "F.Cu")
		(net "M_E_DQS_DN<15>")
	)
	(segment
		(start 302.231806 -144.1704)
		(end 302.417734 -144.356328)
		(width 0.1651)
		(layer "F.Cu")
		(net "M_E_DQS_DN<15>")
	)
	(segment
		(start 287.06826 -106.654854)
		(end 295.382696 -106.654854)
		(width 0.1016)
		(layer "F.Cu")
		(net "M_E_DQS_DN<15>")
	)
	(segment
		(start 301.768256 -144.6657)
		(end 301.749206 -144.6657)
		(width 0.1651)
		(layer "F.Cu")
		(net "M_E_DQS_DN<15>")
	)
	(segment
		(start 302.231806 -143.749268)
		(end 302.231806 -144.1704)
		(width 0.1651)
		(layer "F.Cu")
		(net "M_E_DQS_DN<15>")
	)
	(segment
		(start 302.64989 -143.331184)
		(end 302.231806 -143.749268)
		(width 0.1651)
		(layer "F.Cu")
		(net "M_E_DQS_DN<15>")
	)
	(segment
		(start 285.5722 -105.283)
		(end 285.696406 -105.283)
		(width 0.1016)
		(layer "F.Cu")
		(net "M_E_DQS_DN<15>")
	)
	(segment
		(start 298.6151 -109.887258)
		(end 298.6151 -110.07598)
		(width 0.1016)
		(layer "F.Cu")
		(net "M_E_DQS_DN<15>")
	)
	(segment
		(start 302.520096 -124.91466)
		(end 302.227996 -125.20676)
		(width 0.1651)
		(layer "F.Cu")
		(net "M_E_DQS_DN<15>")
	)
	(segment
		(start 302.417734 -144.356328)
		(end 302.417734 -144.602962)
		(width 0.1651)
		(layer "F.Cu")
		(net "M_E_DQS_DN<15>")
	)
	(segment
		(start 302.227996 -125.479302)
		(end 301.746412 -125.960886)
		(width 0.1651)
		(layer "F.Cu")
		(net "M_E_DQS_DN<15>")
	)
	(segment
		(start 285.696406 -105.283)
		(end 287.06826 -106.654854)
		(width 0.1016)
		(layer "F.Cu")
		(net "M_E_DQS_DN<15>")
	)
	(segment
		(start 298.6151 -110.07598)
		(end 298.958 -110.41888)
		(width 0.1016)
		(layer "F.Cu")
		(net "M_E_DQS_DN<15>")
	)
	(segment
		(start 302.64989 -142.677642)
		(end 302.64989 -143.331184)
		(width 0.1651)
		(layer "F.Cu")
		(net "M_E_DQS_DN<15>")
	)
	(segment
		(start 302.165766 -144.85493)
		(end 301.957486 -144.85493)
		(width 0.1651)
		(layer "F.Cu")
		(net "M_E_DQS_DN<15>")
	)
	(segment
		(start 285.393384 -102.857046)
		(end 285.393384 -103.89997)
		(width 0.0889)
		(layer "F.Cu")
		(net "M_E_DQS_DN<15>")
	)
	(segment
		(start 285.432754 -102.772972)
		(end 285.393384 -102.857046)
		(width 0.0889)
		(layer "F.Cu")
		(net "M_E_DQS_DN<15>")
	)
	(segment
		(start 285.7881 -100.976684)
		(end 285.7881 -100.645214)
		(width 0.0889)
		(layer "F.Cu")
		(net "M_E_DQS_DN<15>")
	)
	(segment
		(start 295.382696 -106.654854)
		(end 298.6151 -109.887258)
		(width 0.1016)
		(layer "F.Cu")
		(net "M_E_DQS_DN<15>")
	)
	(segment
		(start 285.2801 -104.9909)
		(end 285.5722 -105.283)
		(width 0.0889)
		(layer "F.Cu")
		(net "M_E_DQS_DN<15>")
	)
	(segment
		(start 302.520096 -122.10415)
		(end 302.520096 -124.91466)
		(width 0.1651)
		(layer "F.Cu")
		(net "M_E_DQS_DN<15>")
	)
	(segment
		(start 302.4251 -122.009154)
		(end 302.520096 -122.10415)
		(width 0.1651)
		(layer "F.Cu")
		(net "M_E_DQS_DN<15>")
	)
	(segment
		(start 285.393384 -103.89997)
		(end 285.2801 -104.013254)
		(width 0.0889)
		(layer "F.Cu")
		(net "M_E_DQS_DN<15>")
	)
	(segment
		(start 302.227996 -125.20676)
		(end 302.227996 -125.479302)
		(width 0.1651)
		(layer "F.Cu")
		(net "M_E_DQS_DN<15>")
	)
	(segment
		(start 301.957486 -144.85493)
		(end 301.768256 -144.6657)
		(width 0.1651)
		(layer "F.Cu")
		(net "M_E_DQS_DN<15>")
	)
	(segment
		(start 285.2801 -104.013254)
		(end 285.2801 -104.9909)
		(width 0.0889)
		(layer "F.Cu")
		(net "M_E_DQS_DN<15>")
	)
	(segment
		(start 298.958 -110.49)
		(end 302.4251 -113.9571)
		(width 0.1651)
		(layer "F.Cu")
		(net "M_E_DQS_DN<15>")
	)
	(segment
		(start 302.650398 -142.6718)
		(end 302.64989 -142.677642)
		(width 0.1651)
		(layer "F.Cu")
		(net "M_E_DQS_DN<15>")
	)
	(via
		(at 301.742602 -140.4874)
		(size 0.508)
		(drill 0.254)
		(layers "F.Cu" "B.Cu")
		(net "M_E_DQS_DN<15>")
	)
	(via
		(at 301.749206 -144.6657)
		(size 0.508)
		(drill 0.254)
		(layers "F.Cu" "B.Cu")
		(net "M_E_DQS_DN<15>")
	)
	(via
		(at 302.4251 -118.483888)
		(size 0.508)
		(drill 0.254)
		(layers "F.Cu" "B.Cu")
		(net "M_E_DQS_DN<15>")
	)
	(via
		(at 301.746412 -125.960886)
		(size 0.508)
		(drill 0.254)
		(layers "F.Cu" "B.Cu")
		(net "M_E_DQS_DN<15>")
	)
	(arc
		(start 285.441644 -101.176582)
		(mid 285.520834 -101.472128)
		(end 285.441644 -101.76764)
		(width 0.0889)
		(layer "F.Cu")
		(net "M_E_DQS_DN<15>")
	)
	(arc
		(start 285.44139 -102.167944)
		(mid 285.520367 -102.471629)
		(end 285.432754 -102.772972)
		(width 0.0889)
		(layer "F.Cu")
		(net "M_E_DQS_DN<15>")
	)
	(arc
		(start 285.724854 -100.581968)
		(mid 285.426989 -100.80489)
		(end 285.441644 -101.176582)
		(width 0.0889)
		(layer "F.Cu")
		(net "M_E_DQS_DN<15>")
	)
	(arc
		(start 285.441644 -101.76764)
		(mid 285.388111 -101.967538)
		(end 285.441644 -102.167436)
		(width 0.0889)
		(layer "F.Cu")
		(net "M_E_DQS_DN<15>")
	)
	(segment
		(start 302.650398 -141.820646)
		(end 302.206406 -141.376654)
		(width 0.1651)
		(layer "B.Cu")
		(net "M_E_DQS_DN<15>")
	)
	(segment
		(start 301.937166 -140.292836)
		(end 301.742602 -140.4874)
		(width 0.1651)
		(layer "B.Cu")
		(net "M_E_DQS_DN<15>")
	)
	(segment
		(start 302.206406 -141.376654)
		(end 302.206406 -141.0208)
		(width 0.1651)
		(layer "B.Cu")
		(net "M_E_DQS_DN<15>")
	)
	(segment
		(start 302.384206 -140.5128)
		(end 302.164242 -140.292836)
		(width 0.1651)
		(layer "B.Cu")
		(net "M_E_DQS_DN<15>")
	)
	(segment
		(start 302.650398 -142.477236)
		(end 302.650398 -141.820646)
		(width 0.1651)
		(layer "B.Cu")
		(net "M_E_DQS_DN<15>")
	)
	(segment
		(start 302.384206 -140.843)
		(end 302.384206 -140.5128)
		(width 0.1651)
		(layer "B.Cu")
		(net "M_E_DQS_DN<15>")
	)
	(segment
		(start 302.164242 -140.292836)
		(end 301.937166 -140.292836)
		(width 0.1651)
		(layer "B.Cu")
		(net "M_E_DQS_DN<15>")
	)
	(segment
		(start 302.206406 -141.0208)
		(end 302.384206 -140.843)
		(width 0.1651)
		(layer "B.Cu")
		(net "M_E_DQS_DN<15>")
	)
	(segment
		(start 301.742602 -140.4874)
		(end 301.779178 -140.4874)
		(width 0.14224)
		(layer "In4.Cu")
		(net "M_E_DQS_DN<15>")
	)
	(segment
		(start 302.524922 -128.546606)
		(end 301.9552 -127.976884)
		(width 0.14224)
		(layer "In4.Cu")
		(net "M_E_DQS_DN<15>")
	)
	(segment
		(start 302.250602 -139.855448)
		(end 302.524922 -139.581128)
		(width 0.14224)
		(layer "In4.Cu")
		(net "M_E_DQS_DN<15>")
	)
	(segment
		(start 301.779178 -140.4874)
		(end 302.250602 -140.015976)
		(width 0.14224)
		(layer "In4.Cu")
		(net "M_E_DQS_DN<15>")
	)
	(segment
		(start 302.524922 -139.581128)
		(end 302.524922 -128.546606)
		(width 0.14224)
		(layer "In4.Cu")
		(net "M_E_DQS_DN<15>")
	)
	(segment
		(start 301.9552 -127.976884)
		(end 301.9552 -127.1524)
		(width 0.14224)
		(layer "In4.Cu")
		(net "M_E_DQS_DN<15>")
	)
	(segment
		(start 301.9552 -127.1524)
		(end 302.1838 -126.9238)
		(width 0.14224)
		(layer "In4.Cu")
		(net "M_E_DQS_DN<15>")
	)
	(segment
		(start 302.250602 -140.015976)
		(end 302.250602 -139.855448)
		(width 0.14224)
		(layer "In4.Cu")
		(net "M_E_DQS_DN<15>")
	)
	(segment
		(start 302.1838 -126.398274)
		(end 301.746412 -125.960886)
		(width 0.14224)
		(layer "In4.Cu")
		(net "M_E_DQS_DN<15>")
	)
	(segment
		(start 302.1838 -126.9238)
		(end 302.1838 -126.398274)
		(width 0.14224)
		(layer "In4.Cu")
		(net "M_E_DQS_DN<15>")
	)
	(segment
		(start 301.64659 -142.89786)
		(end 301.79391 -142.89786)
		(width 0.14224)
		(layer "In9.Cu")
		(net "M_E_DQS_DN<15>")
	)
	(segment
		(start 301.50689 -142.10284)
		(end 301.50689 -141.75486)
		(width 0.14224)
		(layer "In9.Cu")
		(net "M_E_DQS_DN<15>")
	)
	(segment
		(start 301.66945 -143.5608)
		(end 301.50689 -143.39824)
		(width 0.14224)
		(layer "In9.Cu")
		(net "M_E_DQS_DN<15>")
	)
	(segment
		(start 301.94885 -142.74292)
		(end 301.94885 -142.38986)
		(width 0.14224)
		(layer "In9.Cu")
		(net "M_E_DQS_DN<15>")
	)
	(segment
		(start 301.50689 -143.03756)
		(end 301.64659 -142.89786)
		(width 0.14224)
		(layer "In9.Cu")
		(net "M_E_DQS_DN<15>")
	)
	(segment
		(start 301.99457 -143.5608)
		(end 301.66945 -143.5608)
		(width 0.14224)
		(layer "In9.Cu")
		(net "M_E_DQS_DN<15>")
	)
	(segment
		(start 301.89805 -141.605)
		(end 302.17745 -141.3256)
		(width 0.14224)
		(layer "In9.Cu")
		(net "M_E_DQS_DN<15>")
	)
	(segment
		(start 302.17745 -141.3256)
		(end 302.17745 -140.922248)
		(width 0.14224)
		(layer "In9.Cu")
		(net "M_E_DQS_DN<15>")
	)
	(segment
		(start 301.65675 -141.605)
		(end 301.89805 -141.605)
		(width 0.14224)
		(layer "In9.Cu")
		(net "M_E_DQS_DN<15>")
	)
	(segment
		(start 301.50689 -141.75486)
		(end 301.65675 -141.605)
		(width 0.14224)
		(layer "In9.Cu")
		(net "M_E_DQS_DN<15>")
	)
	(segment
		(start 301.79391 -142.23492)
		(end 301.63897 -142.23492)
		(width 0.14224)
		(layer "In9.Cu")
		(net "M_E_DQS_DN<15>")
	)
	(segment
		(start 302.17745 -140.922248)
		(end 301.742602 -140.4874)
		(width 0.14224)
		(layer "In9.Cu")
		(net "M_E_DQS_DN<15>")
	)
	(segment
		(start 302.182276 -144.23263)
		(end 302.182276 -143.748506)
		(width 0.14224)
		(layer "In9.Cu")
		(net "M_E_DQS_DN<15>")
	)
	(segment
		(start 301.50689 -143.39824)
		(end 301.50689 -143.03756)
		(width 0.14224)
		(layer "In9.Cu")
		(net "M_E_DQS_DN<15>")
	)
	(segment
		(start 302.182276 -143.748506)
		(end 301.99457 -143.5608)
		(width 0.14224)
		(layer "In9.Cu")
		(net "M_E_DQS_DN<15>")
	)
	(segment
		(start 301.749206 -144.6657)
		(end 302.182276 -144.23263)
		(width 0.14224)
		(layer "In9.Cu")
		(net "M_E_DQS_DN<15>")
	)
	(segment
		(start 301.79391 -142.89786)
		(end 301.94885 -142.74292)
		(width 0.14224)
		(layer "In9.Cu")
		(net "M_E_DQS_DN<15>")
	)
	(segment
		(start 301.94885 -142.38986)
		(end 301.79391 -142.23492)
		(width 0.14224)
		(layer "In9.Cu")
		(net "M_E_DQS_DN<15>")
	)
	(segment
		(start 301.63897 -142.23492)
		(end 301.50689 -142.10284)
		(width 0.14224)
		(layer "In9.Cu")
		(net "M_E_DQS_DN<15>")
	)
	(segment
		(start 293.16172 -125.2982)
		(end 292.827202 -125.632718)
		(width 0.1651)
		(layer "F.Cu")
		(net "M_E_DQS_DN<14>")
	)
	(segment
		(start 293.299896 -143.331184)
		(end 292.881812 -143.749268)
		(width 0.1651)
		(layer "F.Cu")
		(net "M_E_DQS_DN<14>")
	)
	(segment
		(start 290.181538 -119.08028)
		(end 290.65728 -119.08028)
		(width 0.1651)
		(layer "F.Cu")
		(net "M_E_DQS_DN<14>")
	)
	(segment
		(start 293.299896 -142.677642)
		(end 293.299896 -143.331184)
		(width 0.1651)
		(layer "F.Cu")
		(net "M_E_DQS_DN<14>")
	)
	(segment
		(start 280.16962 -103.932228)
		(end 280.16962 -105.802938)
		(width 0.0889)
		(layer "F.Cu")
		(net "M_E_DQS_DN<14>")
	)
	(segment
		(start 285.638494 -114.467894)
		(end 285.638494 -114.537236)
		(width 0.1016)
		(layer "F.Cu")
		(net "M_E_DQS_DN<14>")
	)
	(segment
		(start 280.637234 -100.976684)
		(end 280.829512 -100.784406)
		(width 0.0889)
		(layer "F.Cu")
		(net "M_E_DQS_DN<14>")
	)
	(segment
		(start 284.5054 -113.3348)
		(end 285.638494 -114.467894)
		(width 0.1016)
		(layer "F.Cu")
		(net "M_E_DQS_DN<14>")
	)
	(segment
		(start 293.300404 -142.6718)
		(end 293.299896 -142.677642)
		(width 0.1651)
		(layer "F.Cu")
		(net "M_E_DQS_DN<14>")
	)
	(segment
		(start 292.815772 -144.85493)
		(end 292.607492 -144.85493)
		(width 0.1651)
		(layer "F.Cu")
		(net "M_E_DQS_DN<14>")
	)
	(segment
		(start 284.5054 -113.204752)
		(end 284.5054 -113.3348)
		(width 0.1016)
		(layer "F.Cu")
		(net "M_E_DQS_DN<14>")
	)
	(segment
		(start 280.829512 -100.658422)
		(end 280.752804 -100.581714)
		(width 0.0889)
		(layer "F.Cu")
		(net "M_E_DQS_DN<14>")
	)
	(segment
		(start 285.638494 -114.537236)
		(end 290.181538 -119.08028)
		(width 0.1651)
		(layer "F.Cu")
		(net "M_E_DQS_DN<14>")
	)
	(segment
		(start 292.418262 -144.6657)
		(end 292.399212 -144.6657)
		(width 0.1651)
		(layer "F.Cu")
		(net "M_E_DQS_DN<14>")
	)
	(segment
		(start 280.244804 -103.073454)
		(end 280.244804 -103.857044)
		(width 0.0889)
		(layer "F.Cu")
		(net "M_E_DQS_DN<14>")
	)
	(segment
		(start 280.234136 -103.034846)
		(end 280.241756 -103.062786)
		(width 0.0889)
		(layer "F.Cu")
		(net "M_E_DQS_DN<14>")
	)
	(segment
		(start 293.16172 -121.58472)
		(end 293.16172 -125.2982)
		(width 0.1651)
		(layer "F.Cu")
		(net "M_E_DQS_DN<14>")
	)
	(segment
		(start 280.16962 -105.802938)
		(end 280.27122 -105.904538)
		(width 0.0889)
		(layer "F.Cu")
		(net "M_E_DQS_DN<14>")
	)
	(segment
		(start 280.27122 -105.904538)
		(end 280.27122 -108.970572)
		(width 0.1016)
		(layer "F.Cu")
		(net "M_E_DQS_DN<14>")
	)
	(segment
		(start 280.829512 -100.784406)
		(end 280.829512 -100.658422)
		(width 0.0889)
		(layer "F.Cu")
		(net "M_E_DQS_DN<14>")
	)
	(segment
		(start 280.27122 -108.970572)
		(end 284.5054 -113.204752)
		(width 0.1016)
		(layer "F.Cu")
		(net "M_E_DQS_DN<14>")
	)
	(segment
		(start 280.285698 -102.1588)
		(end 280.290524 -102.167436)
		(width 0.0889)
		(layer "F.Cu")
		(net "M_E_DQS_DN<14>")
	)
	(segment
		(start 292.881812 -144.1704)
		(end 293.06774 -144.356328)
		(width 0.1651)
		(layer "F.Cu")
		(net "M_E_DQS_DN<14>")
	)
	(segment
		(start 280.258266 -102.813866)
		(end 280.258012 -102.81412)
		(width 0.0889)
		(layer "F.Cu")
		(net "M_E_DQS_DN<14>")
	)
	(segment
		(start 292.607492 -144.85493)
		(end 292.418262 -144.6657)
		(width 0.1651)
		(layer "F.Cu")
		(net "M_E_DQS_DN<14>")
	)
	(segment
		(start 280.290524 -102.167436)
		(end 280.296874 -102.178104)
		(width 0.0889)
		(layer "F.Cu")
		(net "M_E_DQS_DN<14>")
	)
	(segment
		(start 280.244804 -103.857044)
		(end 280.16962 -103.932228)
		(width 0.0889)
		(layer "F.Cu")
		(net "M_E_DQS_DN<14>")
	)
	(segment
		(start 280.752804 -100.581714)
		(end 280.573734 -100.581714)
		(width 0.0889)
		(layer "F.Cu")
		(net "M_E_DQS_DN<14>")
	)
	(segment
		(start 280.290524 -102.757986)
		(end 280.258266 -102.813866)
		(width 0.0889)
		(layer "F.Cu")
		(net "M_E_DQS_DN<14>")
	)
	(segment
		(start 292.801802 -125.632718)
		(end 292.408102 -126.026418)
		(width 0.1651)
		(layer "F.Cu")
		(net "M_E_DQS_DN<14>")
	)
	(segment
		(start 292.881812 -143.749268)
		(end 292.881812 -144.1704)
		(width 0.1651)
		(layer "F.Cu")
		(net "M_E_DQS_DN<14>")
	)
	(segment
		(start 280.241756 -103.062786)
		(end 280.244804 -103.073454)
		(width 0.0889)
		(layer "F.Cu")
		(net "M_E_DQS_DN<14>")
	)
	(segment
		(start 293.06774 -144.602962)
		(end 292.815772 -144.85493)
		(width 0.1651)
		(layer "F.Cu")
		(net "M_E_DQS_DN<14>")
	)
	(segment
		(start 292.827202 -125.632718)
		(end 292.801802 -125.632718)
		(width 0.1651)
		(layer "F.Cu")
		(net "M_E_DQS_DN<14>")
	)
	(segment
		(start 293.06774 -144.356328)
		(end 293.06774 -144.602962)
		(width 0.1651)
		(layer "F.Cu")
		(net "M_E_DQS_DN<14>")
	)
	(segment
		(start 292.408102 -126.026418)
		(end 292.396672 -126.026418)
		(width 0.1651)
		(layer "F.Cu")
		(net "M_E_DQS_DN<14>")
	)
	(segment
		(start 290.65728 -119.08028)
		(end 293.16172 -121.58472)
		(width 0.1651)
		(layer "F.Cu")
		(net "M_E_DQS_DN<14>")
	)
	(via
		(at 292.399212 -144.6657)
		(size 0.508)
		(drill 0.254)
		(layers "F.Cu" "B.Cu")
		(net "M_E_DQS_DN<14>")
	)
	(via
		(at 292.396672 -126.026418)
		(size 0.508)
		(drill 0.254)
		(layers "F.Cu" "B.Cu")
		(net "M_E_DQS_DN<14>")
	)
	(via
		(at 292.392608 -140.4874)
		(size 0.508)
		(drill 0.254)
		(layers "F.Cu" "B.Cu")
		(net "M_E_DQS_DN<14>")
	)
	(arc
		(start 280.258012 -102.81412)
		(mid 280.222884 -102.921969)
		(end 280.234136 -103.034846)
		(width 0.0889)
		(layer "F.Cu")
		(net "M_E_DQS_DN<14>")
	)
	(arc
		(start 280.573734 -100.581714)
		(mid 280.276013 -100.804774)
		(end 280.290524 -101.176582)
		(width 0.0889)
		(layer "F.Cu")
		(net "M_E_DQS_DN<14>")
	)
	(arc
		(start 280.290524 -101.767386)
		(mid 280.237054 -101.962449)
		(end 280.285698 -102.1588)
		(width 0.0889)
		(layer "F.Cu")
		(net "M_E_DQS_DN<14>")
	)
	(arc
		(start 280.290524 -101.176582)
		(mid 280.369655 -101.471984)
		(end 280.290524 -101.767386)
		(width 0.0889)
		(layer "F.Cu")
		(net "M_E_DQS_DN<14>")
	)
	(arc
		(start 280.296874 -102.178104)
		(mid 280.369672 -102.468867)
		(end 280.290524 -102.757986)
		(width 0.0889)
		(layer "F.Cu")
		(net "M_E_DQS_DN<14>")
	)
	(segment
		(start 293.034212 -140.843)
		(end 292.856412 -141.0208)
		(width 0.1651)
		(layer "B.Cu")
		(net "M_E_DQS_DN<14>")
	)
	(segment
		(start 293.30015 -142.476728)
		(end 293.300404 -142.477236)
		(width 0.1651)
		(layer "B.Cu")
		(net "M_E_DQS_DN<14>")
	)
	(segment
		(start 292.856412 -141.0208)
		(end 292.856412 -141.376654)
		(width 0.1651)
		(layer "B.Cu")
		(net "M_E_DQS_DN<14>")
	)
	(segment
		(start 292.392608 -140.4874)
		(end 292.587172 -140.292836)
		(width 0.1651)
		(layer "B.Cu")
		(net "M_E_DQS_DN<14>")
	)
	(segment
		(start 292.856412 -141.376654)
		(end 293.30015 -141.820392)
		(width 0.1651)
		(layer "B.Cu")
		(net "M_E_DQS_DN<14>")
	)
	(segment
		(start 292.587172 -140.292836)
		(end 292.814248 -140.292836)
		(width 0.1651)
		(layer "B.Cu")
		(net "M_E_DQS_DN<14>")
	)
	(segment
		(start 293.30015 -141.820392)
		(end 293.30015 -142.476728)
		(width 0.1651)
		(layer "B.Cu")
		(net "M_E_DQS_DN<14>")
	)
	(segment
		(start 293.034212 -140.5128)
		(end 293.034212 -140.843)
		(width 0.1651)
		(layer "B.Cu")
		(net "M_E_DQS_DN<14>")
	)
	(segment
		(start 292.814248 -140.292836)
		(end 293.034212 -140.5128)
		(width 0.1651)
		(layer "B.Cu")
		(net "M_E_DQS_DN<14>")
	)
	(segment
		(start 292.288976 -142.23492)
		(end 292.156896 -142.10284)
		(width 0.14224)
		(layer "In9.Cu")
		(net "M_E_DQS_DN<14>")
	)
	(segment
		(start 292.156896 -141.75486)
		(end 292.306756 -141.605)
		(width 0.14224)
		(layer "In9.Cu")
		(net "M_E_DQS_DN<14>")
	)
	(segment
		(start 292.827456 -141.3256)
		(end 292.827456 -140.922248)
		(width 0.14224)
		(layer "In9.Cu")
		(net "M_E_DQS_DN<14>")
	)
	(segment
		(start 292.296596 -142.89786)
		(end 292.443916 -142.89786)
		(width 0.14224)
		(layer "In9.Cu")
		(net "M_E_DQS_DN<14>")
	)
	(segment
		(start 292.443916 -142.23492)
		(end 292.288976 -142.23492)
		(width 0.14224)
		(layer "In9.Cu")
		(net "M_E_DQS_DN<14>")
	)
	(segment
		(start 292.156896 -142.10284)
		(end 292.156896 -141.75486)
		(width 0.14224)
		(layer "In9.Cu")
		(net "M_E_DQS_DN<14>")
	)
	(segment
		(start 292.644576 -143.5608)
		(end 292.319456 -143.5608)
		(width 0.14224)
		(layer "In9.Cu")
		(net "M_E_DQS_DN<14>")
	)
	(segment
		(start 292.156896 -143.03756)
		(end 292.296596 -142.89786)
		(width 0.14224)
		(layer "In9.Cu")
		(net "M_E_DQS_DN<14>")
	)
	(segment
		(start 292.598856 -142.38986)
		(end 292.443916 -142.23492)
		(width 0.14224)
		(layer "In9.Cu")
		(net "M_E_DQS_DN<14>")
	)
	(segment
		(start 292.598856 -142.74292)
		(end 292.598856 -142.38986)
		(width 0.14224)
		(layer "In9.Cu")
		(net "M_E_DQS_DN<14>")
	)
	(segment
		(start 292.399212 -144.665446)
		(end 292.832282 -144.232376)
		(width 0.14224)
		(layer "In9.Cu")
		(net "M_E_DQS_DN<14>")
	)
	(segment
		(start 292.319456 -143.5608)
		(end 292.156896 -143.39824)
		(width 0.14224)
		(layer "In9.Cu")
		(net "M_E_DQS_DN<14>")
	)
	(segment
		(start 292.827456 -140.922248)
		(end 292.392608 -140.4874)
		(width 0.14224)
		(layer "In9.Cu")
		(net "M_E_DQS_DN<14>")
	)
	(segment
		(start 292.832282 -144.232376)
		(end 292.832282 -143.748506)
		(width 0.14224)
		(layer "In9.Cu")
		(net "M_E_DQS_DN<14>")
	)
	(segment
		(start 292.443916 -142.89786)
		(end 292.598856 -142.74292)
		(width 0.14224)
		(layer "In9.Cu")
		(net "M_E_DQS_DN<14>")
	)
	(segment
		(start 292.832282 -143.748506)
		(end 292.644576 -143.5608)
		(width 0.14224)
		(layer "In9.Cu")
		(net "M_E_DQS_DN<14>")
	)
	(segment
		(start 292.306756 -141.605)
		(end 292.548056 -141.605)
		(width 0.14224)
		(layer "In9.Cu")
		(net "M_E_DQS_DN<14>")
	)
	(segment
		(start 292.156896 -143.39824)
		(end 292.156896 -143.03756)
		(width 0.14224)
		(layer "In9.Cu")
		(net "M_E_DQS_DN<14>")
	)
	(segment
		(start 292.548056 -141.605)
		(end 292.827456 -141.3256)
		(width 0.14224)
		(layer "In9.Cu")
		(net "M_E_DQS_DN<14>")
	)
	(segment
		(start 292.399212 -144.6657)
		(end 292.399212 -144.665446)
		(width 0.14224)
		(layer "In9.Cu")
		(net "M_E_DQS_DN<14>")
	)
	(segment
		(start 292.392608 -140.4874)
		(end 292.429184 -140.4874)
		(width 0.14224)
		(layer "In11.Cu")
		(net "M_E_DQS_DN<14>")
	)
	(segment
		(start 292.735 -127.1016)
		(end 292.8366 -127)
		(width 0.14224)
		(layer "In11.Cu")
		(net "M_E_DQS_DN<14>")
	)
	(segment
		(start 293.174928 -139.474956)
		(end 293.174928 -128.176528)
		(width 0.14224)
		(layer "In11.Cu")
		(net "M_E_DQS_DN<14>")
	)
	(segment
		(start 293.174928 -128.176528)
		(end 292.735 -127.7366)
		(width 0.14224)
		(layer "In11.Cu")
		(net "M_E_DQS_DN<14>")
	)
	(segment
		(start 292.8366 -126.477776)
		(end 292.396672 -126.037848)
		(width 0.14224)
		(layer "In11.Cu")
		(net "M_E_DQS_DN<14>")
	)
	(segment
		(start 292.429184 -140.4874)
		(end 292.8366 -140.079984)
		(width 0.14224)
		(layer "In11.Cu")
		(net "M_E_DQS_DN<14>")
	)
	(segment
		(start 292.8366 -139.813284)
		(end 293.174928 -139.474956)
		(width 0.14224)
		(layer "In11.Cu")
		(net "M_E_DQS_DN<14>")
	)
	(segment
		(start 292.735 -127.7366)
		(end 292.735 -127.1016)
		(width 0.14224)
		(layer "In11.Cu")
		(net "M_E_DQS_DN<14>")
	)
	(segment
		(start 292.396672 -126.037848)
		(end 292.396672 -126.026418)
		(width 0.14224)
		(layer "In11.Cu")
		(net "M_E_DQS_DN<14>")
	)
	(segment
		(start 292.8366 -127)
		(end 292.8366 -126.477776)
		(width 0.14224)
		(layer "In11.Cu")
		(net "M_E_DQS_DN<14>")
	)
	(segment
		(start 292.8366 -140.079984)
		(end 292.8366 -139.813284)
		(width 0.14224)
		(layer "In11.Cu")
		(net "M_E_DQS_DN<14>")
	)
	(segment
		(start 283.949902 -143.33093)
		(end 283.531564 -143.749268)
		(width 0.1651)
		(layer "F.Cu")
		(net "M_E_DQS_DN<13>")
	)
	(segment
		(start 272.910808 -97.509584)
		(end 273.482308 -97.509584)
		(width 0.1651)
		(layer "F.Cu")
		(net "M_E_DQS_DN<13>")
	)
	(segment
		(start 283.531564 -144.1704)
		(end 283.717492 -144.356328)
		(width 0.1651)
		(layer "F.Cu")
		(net "M_E_DQS_DN<13>")
	)
	(segment
		(start 283.257244 -144.85493)
		(end 283.068014 -144.6657)
		(width 0.1651)
		(layer "F.Cu")
		(net "M_E_DQS_DN<13>")
	)
	(segment
		(start 283.949902 -142.677642)
		(end 283.949902 -143.33093)
		(width 0.1651)
		(layer "F.Cu")
		(net "M_E_DQS_DN<13>")
	)
	(segment
		(start 283.717492 -144.356328)
		(end 283.717492 -144.602962)
		(width 0.1651)
		(layer "F.Cu")
		(net "M_E_DQS_DN<13>")
	)
	(segment
		(start 283.531564 -143.749268)
		(end 283.531564 -144.1704)
		(width 0.1651)
		(layer "F.Cu")
		(net "M_E_DQS_DN<13>")
	)
	(segment
		(start 283.068014 -144.6657)
		(end 283.048964 -144.6657)
		(width 0.1651)
		(layer "F.Cu")
		(net "M_E_DQS_DN<13>")
	)
	(segment
		(start 283.465524 -144.85493)
		(end 283.257244 -144.85493)
		(width 0.1651)
		(layer "F.Cu")
		(net "M_E_DQS_DN<13>")
	)
	(segment
		(start 283.717492 -144.602962)
		(end 283.465524 -144.85493)
		(width 0.1651)
		(layer "F.Cu")
		(net "M_E_DQS_DN<13>")
	)
	(segment
		(start 283.95041 -142.6718)
		(end 283.949902 -142.677642)
		(width 0.1651)
		(layer "F.Cu")
		(net "M_E_DQS_DN<13>")
	)
	(via
		(at 273.482308 -97.509584)
		(size 0.508)
		(drill 0.254)
		(layers "F.Cu" "B.Cu")
		(net "M_E_DQS_DN<13>")
	)
	(via
		(at 283.04236 -140.4874)
		(size 0.508)
		(drill 0.254)
		(layers "F.Cu" "B.Cu")
		(net "M_E_DQS_DN<13>")
	)
	(via
		(at 283.048964 -144.6657)
		(size 0.508)
		(drill 0.254)
		(layers "F.Cu" "B.Cu")
		(net "M_E_DQS_DN<13>")
	)
	(segment
		(start 283.464 -140.292836)
		(end 283.236924 -140.292836)
		(width 0.1651)
		(layer "B.Cu")
		(net "M_E_DQS_DN<13>")
	)
	(segment
		(start 283.506164 -141.376654)
		(end 283.506164 -141.0208)
		(width 0.1651)
		(layer "B.Cu")
		(net "M_E_DQS_DN<13>")
	)
	(segment
		(start 283.949902 -141.820392)
		(end 283.506164 -141.376654)
		(width 0.1651)
		(layer "B.Cu")
		(net "M_E_DQS_DN<13>")
	)
	(segment
		(start 283.949902 -142.476982)
		(end 283.949902 -141.820392)
		(width 0.1651)
		(layer "B.Cu")
		(net "M_E_DQS_DN<13>")
	)
	(segment
		(start 283.95041 -142.477236)
		(end 283.949902 -142.476982)
		(width 0.1651)
		(layer "B.Cu")
		(net "M_E_DQS_DN<13>")
	)
	(segment
		(start 283.683964 -140.843)
		(end 283.683964 -140.5128)
		(width 0.1651)
		(layer "B.Cu")
		(net "M_E_DQS_DN<13>")
	)
	(segment
		(start 283.683964 -140.5128)
		(end 283.464 -140.292836)
		(width 0.1651)
		(layer "B.Cu")
		(net "M_E_DQS_DN<13>")
	)
	(segment
		(start 283.236924 -140.292836)
		(end 283.04236 -140.4874)
		(width 0.1651)
		(layer "B.Cu")
		(net "M_E_DQS_DN<13>")
	)
	(segment
		(start 283.506164 -141.0208)
		(end 283.683964 -140.843)
		(width 0.1651)
		(layer "B.Cu")
		(net "M_E_DQS_DN<13>")
	)
	(segment
		(start 282.806902 -143.39824)
		(end 282.806902 -143.03756)
		(width 0.14224)
		(layer "In4.Cu")
		(net "M_E_DQS_DN<13>")
	)
	(segment
		(start 282.806902 -141.75486)
		(end 282.956762 -141.605)
		(width 0.14224)
		(layer "In4.Cu")
		(net "M_E_DQS_DN<13>")
	)
	(segment
		(start 283.260038 -128.66751)
		(end 283.824934 -129.232406)
		(width 0.14224)
		(layer "In4.Cu")
		(net "M_E_DQS_DN<13>")
	)
	(segment
		(start 282.969462 -143.5608)
		(end 282.806902 -143.39824)
		(width 0.14224)
		(layer "In4.Cu")
		(net "M_E_DQS_DN<13>")
	)
	(segment
		(start 283.25445 -142.737332)
		(end 283.25445 -142.395448)
		(width 0.14224)
		(layer "In4.Cu")
		(net "M_E_DQS_DN<13>")
	)
	(segment
		(start 283.25445 -142.395448)
		(end 283.093922 -142.23492)
		(width 0.14224)
		(layer "In4.Cu")
		(net "M_E_DQS_DN<13>")
	)
	(segment
		(start 282.946602 -142.89786)
		(end 283.093922 -142.89786)
		(width 0.14224)
		(layer "In4.Cu")
		(net "M_E_DQS_DN<13>")
	)
	(segment
		(start 283.477462 -141.3256)
		(end 283.477462 -140.922248)
		(width 0.14224)
		(layer "In4.Cu")
		(net "M_E_DQS_DN<13>")
	)
	(segment
		(start 273.482308 -97.172272)
		(end 273.424396 -97.11436)
		(width 0.0889)
		(layer "In4.Cu")
		(net "M_E_DQS_DN<13>")
	)
	(segment
		(start 283.482288 -143.748506)
		(end 283.294582 -143.5608)
		(width 0.14224)
		(layer "In4.Cu")
		(net "M_E_DQS_DN<13>")
	)
	(segment
		(start 273.214592 -99.986084)
		(end 273.214592 -101.943662)
		(width 0.0889)
		(layer "In4.Cu")
		(net "M_E_DQS_DN<13>")
	)
	(segment
		(start 283.482288 -144.23263)
		(end 283.482288 -143.748506)
		(width 0.14224)
		(layer "In4.Cu")
		(net "M_E_DQS_DN<13>")
	)
	(segment
		(start 274.367244 -106.41203)
		(end 274.406614 -106.4514)
		(width 0.0889)
		(layer "In4.Cu")
		(net "M_E_DQS_DN<13>")
	)
	(segment
		(start 274.406614 -106.4514)
		(end 274.406614 -106.473498)
		(width 0.0889)
		(layer "In4.Cu")
		(net "M_E_DQS_DN<13>")
	)
	(segment
		(start 282.806902 -142.10284)
		(end 282.806902 -141.75486)
		(width 0.14224)
		(layer "In4.Cu")
		(net "M_E_DQS_DN<13>")
	)
	(segment
		(start 282.956762 -141.605)
		(end 283.198062 -141.605)
		(width 0.14224)
		(layer "In4.Cu")
		(net "M_E_DQS_DN<13>")
	)
	(segment
		(start 282.806902 -143.03756)
		(end 282.946602 -142.89786)
		(width 0.14224)
		(layer "In4.Cu")
		(net "M_E_DQS_DN<13>")
	)
	(segment
		(start 283.824934 -139.70508)
		(end 283.042614 -140.4874)
		(width 0.14224)
		(layer "In4.Cu")
		(net "M_E_DQS_DN<13>")
	)
	(segment
		(start 283.824934 -129.232406)
		(end 283.824934 -139.70508)
		(width 0.14224)
		(layer "In4.Cu")
		(net "M_E_DQS_DN<13>")
	)
	(segment
		(start 283.093922 -142.89786)
		(end 283.25445 -142.737332)
		(width 0.14224)
		(layer "In4.Cu")
		(net "M_E_DQS_DN<13>")
	)
	(segment
		(start 283.042614 -140.4874)
		(end 283.04236 -140.4874)
		(width 0.14224)
		(layer "In4.Cu")
		(net "M_E_DQS_DN<13>")
	)
	(segment
		(start 283.294582 -143.5608)
		(end 282.969462 -143.5608)
		(width 0.14224)
		(layer "In4.Cu")
		(net "M_E_DQS_DN<13>")
	)
	(segment
		(start 283.093922 -142.23492)
		(end 282.938982 -142.23492)
		(width 0.14224)
		(layer "In4.Cu")
		(net "M_E_DQS_DN<13>")
	)
	(segment
		(start 274.367244 -103.096314)
		(end 274.367244 -106.41203)
		(width 0.0889)
		(layer "In4.Cu")
		(net "M_E_DQS_DN<13>")
	)
	(segment
		(start 282.938982 -142.23492)
		(end 282.806902 -142.10284)
		(width 0.14224)
		(layer "In4.Cu")
		(net "M_E_DQS_DN<13>")
	)
	(segment
		(start 283.477462 -140.922248)
		(end 283.042614 -140.4874)
		(width 0.14224)
		(layer "In4.Cu")
		(net "M_E_DQS_DN<13>")
	)
	(segment
		(start 283.260038 -125.66015)
		(end 283.260038 -128.66751)
		(width 0.14224)
		(layer "In4.Cu")
		(net "M_E_DQS_DN<13>")
	)
	(segment
		(start 274.406614 -106.473498)
		(end 274.406614 -116.806726)
		(width 0.14224)
		(layer "In4.Cu")
		(net "M_E_DQS_DN<13>")
	)
	(segment
		(start 283.198062 -141.605)
		(end 283.477462 -141.3256)
		(width 0.14224)
		(layer "In4.Cu")
		(net "M_E_DQS_DN<13>")
	)
	(segment
		(start 273.482308 -97.509584)
		(end 273.482308 -97.172272)
		(width 0.0889)
		(layer "In4.Cu")
		(net "M_E_DQS_DN<13>")
	)
	(segment
		(start 283.048964 -144.6657)
		(end 283.049218 -144.6657)
		(width 0.14224)
		(layer "In4.Cu")
		(net "M_E_DQS_DN<13>")
	)
	(segment
		(start 274.406614 -116.806726)
		(end 283.260038 -125.66015)
		(width 0.14224)
		(layer "In4.Cu")
		(net "M_E_DQS_DN<13>")
	)
	(segment
		(start 273.214592 -101.943662)
		(end 274.367244 -103.096314)
		(width 0.0889)
		(layer "In4.Cu")
		(net "M_E_DQS_DN<13>")
	)
	(segment
		(start 283.049218 -144.6657)
		(end 283.482288 -144.23263)
		(width 0.14224)
		(layer "In4.Cu")
		(net "M_E_DQS_DN<13>")
	)
	(arc
		(start 273.135598 -99.291648)
		(mid 273.082099 -99.491546)
		(end 273.135598 -99.691444)
		(width 0.0889)
		(layer "In4.Cu")
		(net "M_E_DQS_DN<13>")
	)
	(arc
		(start 273.135598 -98.700844)
		(mid 273.214729 -98.996246)
		(end 273.135598 -99.291648)
		(width 0.0889)
		(layer "In4.Cu")
		(net "M_E_DQS_DN<13>")
	)
	(arc
		(start 273.135598 -97.710244)
		(mid 273.214729 -98.005646)
		(end 273.135598 -98.301048)
		(width 0.0889)
		(layer "In4.Cu")
		(net "M_E_DQS_DN<13>")
	)
	(arc
		(start 273.424396 -97.11436)
		(mid 273.122175 -97.33581)
		(end 273.135598 -97.710244)
		(width 0.0889)
		(layer "In4.Cu")
		(net "M_E_DQS_DN<13>")
	)
	(arc
		(start 273.135598 -98.301048)
		(mid 273.082099 -98.500946)
		(end 273.135598 -98.700844)
		(width 0.0889)
		(layer "In4.Cu")
		(net "M_E_DQS_DN<13>")
	)
	(arc
		(start 273.135598 -99.691444)
		(mid 273.194444 -99.833577)
		(end 273.214592 -99.986084)
		(width 0.0889)
		(layer "In4.Cu")
		(net "M_E_DQS_DN<13>")
	)
	(segment
		(start 242.236752 -103.746554)
		(end 239.480852 -103.746554)
		(width 0.1016)
		(layer "F.Cu")
		(net "M_E_DQS_DN<12>")
	)
	(segment
		(start 228.567996 -125.189234)
		(end 227.796344 -125.960886)
		(width 0.1651)
		(layer "F.Cu")
		(net "M_E_DQS_DN<12>")
	)
	(segment
		(start 239.480852 -103.746554)
		(end 238.14786 -105.079546)
		(width 0.1016)
		(layer "F.Cu")
		(net "M_E_DQS_DN<12>")
	)
	(segment
		(start 228.567996 -124.27585)
		(end 228.567996 -125.189234)
		(width 0.1651)
		(layer "F.Cu")
		(net "M_E_DQS_DN<12>")
	)
	(segment
		(start 228.699822 -143.331184)
		(end 228.281738 -143.749268)
		(width 0.1651)
		(layer "F.Cu")
		(net "M_E_DQS_DN<12>")
	)
	(segment
		(start 243.524024 -101.598476)
		(end 243.524024 -102.459282)
		(width 0.0889)
		(layer "F.Cu")
		(net "M_E_DQS_DN<12>")
	)
	(segment
		(start 243.572538 -101.437948)
		(end 243.563648 -101.453188)
		(width 0.0889)
		(layer "F.Cu")
		(net "M_E_DQS_DN<12>")
	)
	(segment
		(start 228.467666 -144.602962)
		(end 228.215698 -144.85493)
		(width 0.1651)
		(layer "F.Cu")
		(net "M_E_DQS_DN<12>")
	)
	(segment
		(start 238.14786 -105.079546)
		(end 237.809024 -105.079546)
		(width 0.1016)
		(layer "F.Cu")
		(net "M_E_DQS_DN<12>")
	)
	(segment
		(start 243.563648 -101.453188)
		(end 243.558822 -101.461824)
		(width 0.0889)
		(layer "F.Cu")
		(net "M_E_DQS_DN<12>")
	)
	(segment
		(start 227.77958 -123.487434)
		(end 228.567996 -124.27585)
		(width 0.1651)
		(layer "F.Cu")
		(net "M_E_DQS_DN<12>")
	)
	(segment
		(start 228.281738 -144.1704)
		(end 228.467666 -144.356328)
		(width 0.1651)
		(layer "F.Cu")
		(net "M_E_DQS_DN<12>")
	)
	(segment
		(start 227.77958 -122.681492)
		(end 227.77958 -123.487434)
		(width 0.1651)
		(layer "F.Cu")
		(net "M_E_DQS_DN<12>")
	)
	(segment
		(start 228.215698 -144.85493)
		(end 228.007418 -144.85493)
		(width 0.1651)
		(layer "F.Cu")
		(net "M_E_DQS_DN<12>")
	)
	(segment
		(start 228.281738 -143.749268)
		(end 228.281738 -144.1704)
		(width 0.1651)
		(layer "F.Cu")
		(net "M_E_DQS_DN<12>")
	)
	(segment
		(start 227.9396 -122.521472)
		(end 227.77958 -122.681492)
		(width 0.1651)
		(layer "F.Cu")
		(net "M_E_DQS_DN<12>")
	)
	(segment
		(start 228.70033 -142.6718)
		(end 228.699822 -142.677642)
		(width 0.1651)
		(layer "F.Cu")
		(net "M_E_DQS_DN<12>")
	)
	(segment
		(start 228.007418 -144.85493)
		(end 227.818188 -144.6657)
		(width 0.1651)
		(layer "F.Cu")
		(net "M_E_DQS_DN<12>")
	)
	(segment
		(start 243.910104 -99.67214)
		(end 243.910104 -99.340416)
		(width 0.0889)
		(layer "F.Cu")
		(net "M_E_DQS_DN<12>")
	)
	(segment
		(start 243.473224 -102.510082)
		(end 242.236752 -103.746554)
		(width 0.1016)
		(layer "F.Cu")
		(net "M_E_DQS_DN<12>")
	)
	(segment
		(start 243.56695 -99.4664)
		(end 243.563648 -99.472242)
		(width 0.0889)
		(layer "F.Cu")
		(net "M_E_DQS_DN<12>")
	)
	(segment
		(start 228.699822 -142.677642)
		(end 228.699822 -143.331184)
		(width 0.1651)
		(layer "F.Cu")
		(net "M_E_DQS_DN<12>")
	)
	(segment
		(start 227.77958 -121.005854)
		(end 227.9396 -121.165874)
		(width 0.1651)
		(layer "F.Cu")
		(net "M_E_DQS_DN<12>")
	)
	(segment
		(start 227.9396 -121.165874)
		(end 227.9396 -122.521472)
		(width 0.1651)
		(layer "F.Cu")
		(net "M_E_DQS_DN<12>")
	)
	(segment
		(start 243.524024 -102.459282)
		(end 243.473224 -102.510082)
		(width 0.0889)
		(layer "F.Cu")
		(net "M_E_DQS_DN<12>")
	)
	(segment
		(start 243.910104 -99.340416)
		(end 243.846858 -99.27717)
		(width 0.0889)
		(layer "F.Cu")
		(net "M_E_DQS_DN<12>")
	)
	(segment
		(start 228.467666 -144.356328)
		(end 228.467666 -144.602962)
		(width 0.1651)
		(layer "F.Cu")
		(net "M_E_DQS_DN<12>")
	)
	(segment
		(start 237.809024 -105.079546)
		(end 237.80877 -105.0798)
		(width 0.1651)
		(layer "F.Cu")
		(net "M_E_DQS_DN<12>")
	)
	(segment
		(start 227.77958 -111.812324)
		(end 227.77958 -121.005854)
		(width 0.1651)
		(layer "F.Cu")
		(net "M_E_DQS_DN<12>")
	)
	(segment
		(start 243.563648 -99.872038)
		(end 243.569998 -99.882706)
		(width 0.0889)
		(layer "F.Cu")
		(net "M_E_DQS_DN<12>")
	)
	(segment
		(start 237.80877 -105.0798)
		(end 234.512104 -105.0798)
		(width 0.1651)
		(layer "F.Cu")
		(net "M_E_DQS_DN<12>")
	)
	(segment
		(start 234.512104 -105.0798)
		(end 227.77958 -111.812324)
		(width 0.1651)
		(layer "F.Cu")
		(net "M_E_DQS_DN<12>")
	)
	(segment
		(start 227.818188 -144.6657)
		(end 227.799138 -144.6657)
		(width 0.1651)
		(layer "F.Cu")
		(net "M_E_DQS_DN<12>")
	)
	(via
		(at 227.796344 -125.960886)
		(size 0.508)
		(drill 0.254)
		(layers "F.Cu" "B.Cu")
		(net "M_E_DQS_DN<12>")
	)
	(via
		(at 227.792534 -140.4874)
		(size 0.508)
		(drill 0.254)
		(layers "F.Cu" "B.Cu")
		(net "M_E_DQS_DN<12>")
	)
	(via
		(at 227.799138 -144.6657)
		(size 0.508)
		(drill 0.254)
		(layers "F.Cu" "B.Cu")
		(net "M_E_DQS_DN<12>")
	)
	(arc
		(start 243.569998 -99.882706)
		(mid 243.642796 -100.173469)
		(end 243.563648 -100.462588)
		(width 0.0889)
		(layer "F.Cu")
		(net "M_E_DQS_DN<12>")
	)
	(arc
		(start 243.563648 -100.462588)
		(mid 243.510115 -100.662486)
		(end 243.563648 -100.862384)
		(width 0.0889)
		(layer "F.Cu")
		(net "M_E_DQS_DN<12>")
	)
	(arc
		(start 243.846858 -99.27717)
		(mid 243.685985 -99.340821)
		(end 243.56695 -99.4664)
		(width 0.0889)
		(layer "F.Cu")
		(net "M_E_DQS_DN<12>")
	)
	(arc
		(start 243.563648 -99.472242)
		(mid 243.510115 -99.67214)
		(end 243.563648 -99.872038)
		(width 0.0889)
		(layer "F.Cu")
		(net "M_E_DQS_DN<12>")
	)
	(arc
		(start 243.558822 -101.461824)
		(mid 243.532817 -101.527962)
		(end 243.524024 -101.598476)
		(width 0.0889)
		(layer "F.Cu")
		(net "M_E_DQS_DN<12>")
	)
	(arc
		(start 243.563648 -100.862384)
		(mid 243.642837 -101.148999)
		(end 243.572538 -101.437948)
		(width 0.0889)
		(layer "F.Cu")
		(net "M_E_DQS_DN<12>")
	)
	(segment
		(start 228.214174 -140.292836)
		(end 228.434138 -140.5128)
		(width 0.1651)
		(layer "B.Cu")
		(net "M_E_DQS_DN<12>")
	)
	(segment
		(start 228.256338 -141.376654)
		(end 228.700076 -141.820392)
		(width 0.1651)
		(layer "B.Cu")
		(net "M_E_DQS_DN<12>")
	)
	(segment
		(start 228.700076 -141.820392)
		(end 228.700076 -142.476728)
		(width 0.1651)
		(layer "B.Cu")
		(net "M_E_DQS_DN<12>")
	)
	(segment
		(start 228.256338 -141.0208)
		(end 228.256338 -141.376654)
		(width 0.1651)
		(layer "B.Cu")
		(net "M_E_DQS_DN<12>")
	)
	(segment
		(start 228.434138 -140.5128)
		(end 228.434138 -140.843)
		(width 0.1651)
		(layer "B.Cu")
		(net "M_E_DQS_DN<12>")
	)
	(segment
		(start 227.987098 -140.292836)
		(end 228.214174 -140.292836)
		(width 0.1651)
		(layer "B.Cu")
		(net "M_E_DQS_DN<12>")
	)
	(segment
		(start 228.700076 -142.476728)
		(end 228.70033 -142.477236)
		(width 0.1651)
		(layer "B.Cu")
		(net "M_E_DQS_DN<12>")
	)
	(segment
		(start 228.434138 -140.843)
		(end 228.256338 -141.0208)
		(width 0.1651)
		(layer "B.Cu")
		(net "M_E_DQS_DN<12>")
	)
	(segment
		(start 227.792534 -140.4874)
		(end 227.987098 -140.292836)
		(width 0.1651)
		(layer "B.Cu")
		(net "M_E_DQS_DN<12>")
	)
	(segment
		(start 227.792534 -140.4874)
		(end 228.227382 -140.922248)
		(width 0.14224)
		(layer "In4.Cu")
		(net "M_E_DQS_DN<12>")
	)
	(segment
		(start 227.556822 -143.39824)
		(end 227.719382 -143.5608)
		(width 0.14224)
		(layer "In4.Cu")
		(net "M_E_DQS_DN<12>")
	)
	(segment
		(start 228.227382 -140.922248)
		(end 228.227382 -141.3256)
		(width 0.14224)
		(layer "In4.Cu")
		(net "M_E_DQS_DN<12>")
	)
	(segment
		(start 228.232208 -144.23263)
		(end 227.799138 -144.6657)
		(width 0.14224)
		(layer "In4.Cu")
		(net "M_E_DQS_DN<12>")
	)
	(segment
		(start 227.719382 -143.5608)
		(end 228.044502 -143.5608)
		(width 0.14224)
		(layer "In4.Cu")
		(net "M_E_DQS_DN<12>")
	)
	(segment
		(start 227.556822 -141.75486)
		(end 227.556822 -142.10284)
		(width 0.14224)
		(layer "In4.Cu")
		(net "M_E_DQS_DN<12>")
	)
	(segment
		(start 227.556822 -143.03756)
		(end 227.556822 -143.39824)
		(width 0.14224)
		(layer "In4.Cu")
		(net "M_E_DQS_DN<12>")
	)
	(segment
		(start 228.21011 -126.305564)
		(end 228.21011 -126.856744)
		(width 0.14224)
		(layer "In4.Cu")
		(net "M_E_DQS_DN<12>")
	)
	(segment
		(start 227.688902 -142.23492)
		(end 227.843842 -142.23492)
		(width 0.14224)
		(layer "In4.Cu")
		(net "M_E_DQS_DN<12>")
	)
	(segment
		(start 228.227382 -141.3256)
		(end 227.947982 -141.605)
		(width 0.14224)
		(layer "In4.Cu")
		(net "M_E_DQS_DN<12>")
	)
	(segment
		(start 227.9904 -127.076454)
		(end 227.9904 -127.538988)
		(width 0.14224)
		(layer "In4.Cu")
		(net "M_E_DQS_DN<12>")
	)
	(segment
		(start 227.843842 -142.89786)
		(end 227.696522 -142.89786)
		(width 0.14224)
		(layer "In4.Cu")
		(net "M_E_DQS_DN<12>")
	)
	(segment
		(start 228.574854 -128.949958)
		(end 228.574854 -139.674346)
		(width 0.14224)
		(layer "In4.Cu")
		(net "M_E_DQS_DN<12>")
	)
	(segment
		(start 227.9904 -127.538988)
		(end 228.574854 -128.949958)
		(width 0.14224)
		(layer "In4.Cu")
		(net "M_E_DQS_DN<12>")
	)
	(segment
		(start 228.044502 -143.5608)
		(end 228.232208 -143.748506)
		(width 0.14224)
		(layer "In4.Cu")
		(net "M_E_DQS_DN<12>")
	)
	(segment
		(start 228.232208 -143.748506)
		(end 228.232208 -144.23263)
		(width 0.14224)
		(layer "In4.Cu")
		(net "M_E_DQS_DN<12>")
	)
	(segment
		(start 227.998782 -142.38986)
		(end 227.998782 -142.74292)
		(width 0.14224)
		(layer "In4.Cu")
		(net "M_E_DQS_DN<12>")
	)
	(segment
		(start 227.796344 -125.960886)
		(end 227.865432 -125.960886)
		(width 0.14224)
		(layer "In4.Cu")
		(net "M_E_DQS_DN<12>")
	)
	(segment
		(start 227.696522 -142.89786)
		(end 227.556822 -143.03756)
		(width 0.14224)
		(layer "In4.Cu")
		(net "M_E_DQS_DN<12>")
	)
	(segment
		(start 228.574854 -139.674346)
		(end 227.792534 -140.456666)
		(width 0.14224)
		(layer "In4.Cu")
		(net "M_E_DQS_DN<12>")
	)
	(segment
		(start 227.947982 -141.605)
		(end 227.706682 -141.605)
		(width 0.14224)
		(layer "In4.Cu")
		(net "M_E_DQS_DN<12>")
	)
	(segment
		(start 227.843842 -142.23492)
		(end 227.998782 -142.38986)
		(width 0.14224)
		(layer "In4.Cu")
		(net "M_E_DQS_DN<12>")
	)
	(segment
		(start 227.865432 -125.960886)
		(end 228.21011 -126.305564)
		(width 0.14224)
		(layer "In4.Cu")
		(net "M_E_DQS_DN<12>")
	)
	(segment
		(start 227.706682 -141.605)
		(end 227.556822 -141.75486)
		(width 0.14224)
		(layer "In4.Cu")
		(net "M_E_DQS_DN<12>")
	)
	(segment
		(start 227.556822 -142.10284)
		(end 227.688902 -142.23492)
		(width 0.14224)
		(layer "In4.Cu")
		(net "M_E_DQS_DN<12>")
	)
	(segment
		(start 227.792534 -140.456666)
		(end 227.792534 -140.4874)
		(width 0.14224)
		(layer "In4.Cu")
		(net "M_E_DQS_DN<12>")
	)
	(segment
		(start 227.998782 -142.74292)
		(end 227.843842 -142.89786)
		(width 0.14224)
		(layer "In4.Cu")
		(net "M_E_DQS_DN<12>")
	)
	(segment
		(start 228.21011 -126.856744)
		(end 227.9904 -127.076454)
		(width 0.14224)
		(layer "In4.Cu")
		(net "M_E_DQS_DN<12>")
	)
	(segment
		(start 238.759238 -98.681286)
		(end 238.187738 -98.681286)
		(width 0.1651)
		(layer "F.Cu")
		(net "M_E_DQS_DN<11>")
	)
	(segment
		(start 219.117672 -144.356328)
		(end 219.117672 -144.602962)
		(width 0.1651)
		(layer "F.Cu")
		(net "M_E_DQS_DN<11>")
	)
	(segment
		(start 218.468194 -144.6657)
		(end 218.449144 -144.6657)
		(width 0.1651)
		(layer "F.Cu")
		(net "M_E_DQS_DN<11>")
	)
	(segment
		(start 219.349828 -143.331184)
		(end 218.931744 -143.749268)
		(width 0.1651)
		(layer "F.Cu")
		(net "M_E_DQS_DN<11>")
	)
	(segment
		(start 218.865704 -144.85493)
		(end 218.657424 -144.85493)
		(width 0.1651)
		(layer "F.Cu")
		(net "M_E_DQS_DN<11>")
	)
	(segment
		(start 219.117672 -144.602962)
		(end 218.865704 -144.85493)
		(width 0.1651)
		(layer "F.Cu")
		(net "M_E_DQS_DN<11>")
	)
	(segment
		(start 219.350336 -142.6718)
		(end 219.349828 -142.677642)
		(width 0.1651)
		(layer "F.Cu")
		(net "M_E_DQS_DN<11>")
	)
	(segment
		(start 218.931744 -144.1704)
		(end 219.117672 -144.356328)
		(width 0.1651)
		(layer "F.Cu")
		(net "M_E_DQS_DN<11>")
	)
	(segment
		(start 219.349828 -142.677642)
		(end 219.349828 -143.331184)
		(width 0.1651)
		(layer "F.Cu")
		(net "M_E_DQS_DN<11>")
	)
	(segment
		(start 218.931744 -143.749268)
		(end 218.931744 -144.1704)
		(width 0.1651)
		(layer "F.Cu")
		(net "M_E_DQS_DN<11>")
	)
	(segment
		(start 218.657424 -144.85493)
		(end 218.468194 -144.6657)
		(width 0.1651)
		(layer "F.Cu")
		(net "M_E_DQS_DN<11>")
	)
	(via
		(at 238.187738 -98.681286)
		(size 0.508)
		(drill 0.254)
		(layers "F.Cu" "B.Cu")
		(net "M_E_DQS_DN<11>")
	)
	(via
		(at 218.44254 -140.4874)
		(size 0.508)
		(drill 0.254)
		(layers "F.Cu" "B.Cu")
		(net "M_E_DQS_DN<11>")
	)
	(via
		(at 218.449144 -144.6657)
		(size 0.508)
		(drill 0.254)
		(layers "F.Cu" "B.Cu")
		(net "M_E_DQS_DN<11>")
	)
	(segment
		(start 218.86418 -140.292836)
		(end 219.084144 -140.5128)
		(width 0.1651)
		(layer "B.Cu")
		(net "M_E_DQS_DN<11>")
	)
	(segment
		(start 218.637104 -140.292836)
		(end 218.86418 -140.292836)
		(width 0.1651)
		(layer "B.Cu")
		(net "M_E_DQS_DN<11>")
	)
	(segment
		(start 219.350082 -142.476728)
		(end 219.350336 -142.477236)
		(width 0.1651)
		(layer "B.Cu")
		(net "M_E_DQS_DN<11>")
	)
	(segment
		(start 218.906344 -141.376654)
		(end 219.350082 -141.820392)
		(width 0.1651)
		(layer "B.Cu")
		(net "M_E_DQS_DN<11>")
	)
	(segment
		(start 218.44254 -140.4874)
		(end 218.637104 -140.292836)
		(width 0.1651)
		(layer "B.Cu")
		(net "M_E_DQS_DN<11>")
	)
	(segment
		(start 219.350082 -141.820392)
		(end 219.350082 -142.476728)
		(width 0.1651)
		(layer "B.Cu")
		(net "M_E_DQS_DN<11>")
	)
	(segment
		(start 219.084144 -140.843)
		(end 218.906344 -141.0208)
		(width 0.1651)
		(layer "B.Cu")
		(net "M_E_DQS_DN<11>")
	)
	(segment
		(start 218.906344 -141.0208)
		(end 218.906344 -141.376654)
		(width 0.1651)
		(layer "B.Cu")
		(net "M_E_DQS_DN<11>")
	)
	(segment
		(start 219.084144 -140.5128)
		(end 219.084144 -140.843)
		(width 0.1651)
		(layer "B.Cu")
		(net "M_E_DQS_DN<11>")
	)
	(segment
		(start 220.41612 -123.451366)
		(end 220.41612 -128.028446)
		(width 0.14224)
		(layer "In4.Cu")
		(net "M_E_DQS_DN<11>")
	)
	(segment
		(start 236.492288 -101.253036)
		(end 236.459522 -101.253036)
		(width 0.0889)
		(layer "In4.Cu")
		(net "M_E_DQS_DN<11>")
	)
	(segment
		(start 233.03484 -106.063288)
		(end 229.73792 -109.360208)
		(width 0.14224)
		(layer "In4.Cu")
		(net "M_E_DQS_DN<11>")
	)
	(segment
		(start 218.356688 -141.605)
		(end 218.206828 -141.75486)
		(width 0.14224)
		(layer "In4.Cu")
		(net "M_E_DQS_DN<11>")
	)
	(segment
		(start 233.510074 -103.887016)
		(end 233.510328 -103.942388)
		(width 0.0889)
		(layer "In4.Cu")
		(net "M_E_DQS_DN<11>")
	)
	(segment
		(start 238.187738 -98.681286)
		(end 238.187738 -98.343212)
		(width 0.0889)
		(layer "In4.Cu")
		(net "M_E_DQS_DN<11>")
	)
	(segment
		(start 218.882214 -143.748506)
		(end 218.882214 -144.23263)
		(width 0.14224)
		(layer "In4.Cu")
		(net "M_E_DQS_DN<11>")
	)
	(segment
		(start 237.342172 -100.75799)
		(end 237.314232 -100.75799)
		(width 0.0889)
		(layer "In4.Cu")
		(net "M_E_DQS_DN<11>")
	)
	(segment
		(start 233.03484 -104.417876)
		(end 233.03484 -106.063288)
		(width 0.14224)
		(layer "In4.Cu")
		(net "M_E_DQS_DN<11>")
	)
	(segment
		(start 233.510328 -103.942388)
		(end 233.494834 -103.957882)
		(width 0.0889)
		(layer "In4.Cu")
		(net "M_E_DQS_DN<11>")
	)
	(segment
		(start 218.493848 -142.23492)
		(end 218.648788 -142.38986)
		(width 0.14224)
		(layer "In4.Cu")
		(net "M_E_DQS_DN<11>")
	)
	(segment
		(start 219.22486 -139.70508)
		(end 218.44254 -140.4874)
		(width 0.14224)
		(layer "In4.Cu")
		(net "M_E_DQS_DN<11>")
	)
	(segment
		(start 218.694508 -143.5608)
		(end 218.882214 -143.748506)
		(width 0.14224)
		(layer "In4.Cu")
		(net "M_E_DQS_DN<11>")
	)
	(segment
		(start 218.206828 -141.75486)
		(end 218.206828 -142.10284)
		(width 0.14224)
		(layer "In4.Cu")
		(net "M_E_DQS_DN<11>")
	)
	(segment
		(start 218.206828 -143.03756)
		(end 218.206828 -143.39824)
		(width 0.14224)
		(layer "In4.Cu")
		(net "M_E_DQS_DN<11>")
	)
	(segment
		(start 218.206828 -143.39824)
		(end 218.369388 -143.5608)
		(width 0.14224)
		(layer "In4.Cu")
		(net "M_E_DQS_DN<11>")
	)
	(segment
		(start 218.882214 -144.23263)
		(end 218.449144 -144.6657)
		(width 0.14224)
		(layer "In4.Cu")
		(net "M_E_DQS_DN<11>")
	)
	(segment
		(start 219.22486 -129.219706)
		(end 219.22486 -139.70508)
		(width 0.14224)
		(layer "In4.Cu")
		(net "M_E_DQS_DN<11>")
	)
	(segment
		(start 218.369388 -143.5608)
		(end 218.694508 -143.5608)
		(width 0.14224)
		(layer "In4.Cu")
		(net "M_E_DQS_DN<11>")
	)
	(segment
		(start 218.493848 -142.89786)
		(end 218.346528 -142.89786)
		(width 0.14224)
		(layer "In4.Cu")
		(net "M_E_DQS_DN<11>")
	)
	(segment
		(start 238.187738 -98.343212)
		(end 238.129826 -98.2853)
		(width 0.0889)
		(layer "In4.Cu")
		(net "M_E_DQS_DN<11>")
	)
	(segment
		(start 233.494834 -103.957882)
		(end 233.03484 -104.417876)
		(width 0.14224)
		(layer "In4.Cu")
		(net "M_E_DQS_DN<11>")
	)
	(segment
		(start 218.338908 -142.23492)
		(end 218.493848 -142.23492)
		(width 0.14224)
		(layer "In4.Cu")
		(net "M_E_DQS_DN<11>")
	)
	(segment
		(start 229.73792 -114.129566)
		(end 220.41612 -123.451366)
		(width 0.14224)
		(layer "In4.Cu")
		(net "M_E_DQS_DN<11>")
	)
	(segment
		(start 236.028484 -101.618288)
		(end 235.129832 -102.51694)
		(width 0.0889)
		(layer "In4.Cu")
		(net "M_E_DQS_DN<11>")
	)
	(segment
		(start 234.88015 -102.51694)
		(end 233.510074 -103.887016)
		(width 0.0889)
		(layer "In4.Cu")
		(net "M_E_DQS_DN<11>")
	)
	(segment
		(start 235.129832 -102.51694)
		(end 234.88015 -102.51694)
		(width 0.0889)
		(layer "In4.Cu")
		(net "M_E_DQS_DN<11>")
	)
	(segment
		(start 229.73792 -109.360208)
		(end 229.73792 -114.129566)
		(width 0.14224)
		(layer "In4.Cu")
		(net "M_E_DQS_DN<11>")
	)
	(segment
		(start 218.346528 -142.89786)
		(end 218.206828 -143.03756)
		(width 0.14224)
		(layer "In4.Cu")
		(net "M_E_DQS_DN<11>")
	)
	(segment
		(start 218.206828 -142.10284)
		(end 218.338908 -142.23492)
		(width 0.14224)
		(layer "In4.Cu")
		(net "M_E_DQS_DN<11>")
	)
	(segment
		(start 218.44254 -140.4874)
		(end 218.877388 -140.922248)
		(width 0.14224)
		(layer "In4.Cu")
		(net "M_E_DQS_DN<11>")
	)
	(segment
		(start 218.877388 -140.922248)
		(end 218.877388 -141.3256)
		(width 0.14224)
		(layer "In4.Cu")
		(net "M_E_DQS_DN<11>")
	)
	(segment
		(start 220.41612 -128.028446)
		(end 219.22486 -129.219706)
		(width 0.14224)
		(layer "In4.Cu")
		(net "M_E_DQS_DN<11>")
	)
	(segment
		(start 236.124242 -101.45268)
		(end 236.028484 -101.618288)
		(width 0.0889)
		(layer "In4.Cu")
		(net "M_E_DQS_DN<11>")
	)
	(segment
		(start 218.648788 -142.38986)
		(end 218.648788 -142.74292)
		(width 0.14224)
		(layer "In4.Cu")
		(net "M_E_DQS_DN<11>")
	)
	(segment
		(start 218.648788 -142.74292)
		(end 218.493848 -142.89786)
		(width 0.14224)
		(layer "In4.Cu")
		(net "M_E_DQS_DN<11>")
	)
	(segment
		(start 237.841028 -99.872038)
		(end 237.847378 -99.882706)
		(width 0.0889)
		(layer "In4.Cu")
		(net "M_E_DQS_DN<11>")
	)
	(segment
		(start 218.597988 -141.605)
		(end 218.356688 -141.605)
		(width 0.14224)
		(layer "In4.Cu")
		(net "M_E_DQS_DN<11>")
	)
	(segment
		(start 218.877388 -141.3256)
		(end 218.597988 -141.605)
		(width 0.14224)
		(layer "In4.Cu")
		(net "M_E_DQS_DN<11>")
	)
	(arc
		(start 238.129826 -98.2853)
		(mid 237.827557 -98.506849)
		(end 237.841028 -98.881438)
		(width 0.0889)
		(layer "In4.Cu")
		(net "M_E_DQS_DN<11>")
	)
	(arc
		(start 237.847378 -99.882706)
		(mid 237.841201 -100.462638)
		(end 237.342172 -100.75799)
		(width 0.0889)
		(layer "In4.Cu")
		(net "M_E_DQS_DN<11>")
	)
	(arc
		(start 236.459522 -101.253036)
		(mid 236.265916 -101.309241)
		(end 236.124242 -101.45268)
		(width 0.0889)
		(layer "In4.Cu")
		(net "M_E_DQS_DN<11>")
	)
	(arc
		(start 237.841028 -99.472242)
		(mid 237.787529 -99.67214)
		(end 237.841028 -99.872038)
		(width 0.0889)
		(layer "In4.Cu")
		(net "M_E_DQS_DN<11>")
	)
	(arc
		(start 237.841028 -98.881438)
		(mid 237.920159 -99.17684)
		(end 237.841028 -99.472242)
		(width 0.0889)
		(layer "In4.Cu")
		(net "M_E_DQS_DN<11>")
	)
	(arc
		(start 237.314232 -100.75799)
		(mid 237.12259 -100.815156)
		(end 236.982508 -100.957888)
		(width 0.0889)
		(layer "In4.Cu")
		(net "M_E_DQS_DN<11>")
	)
	(arc
		(start 236.982508 -100.957888)
		(mid 236.775504 -101.168752)
		(end 236.492288 -101.253036)
		(width 0.0889)
		(layer "In4.Cu")
		(net "M_E_DQS_DN<11>")
	)
	(segment
		(start 209.58175 -144.1704)
		(end 209.767678 -144.356328)
		(width 0.1651)
		(layer "F.Cu")
		(net "M_E_DQS_DN<10>")
	)
	(segment
		(start 237.900718 -90.26144)
		(end 237.329218 -90.26144)
		(width 0.1651)
		(layer "F.Cu")
		(net "M_E_DQS_DN<10>")
	)
	(segment
		(start 209.999834 -143.331184)
		(end 209.58175 -143.749268)
		(width 0.1651)
		(layer "F.Cu")
		(net "M_E_DQS_DN<10>")
	)
	(segment
		(start 210.000342 -142.6718)
		(end 209.999834 -142.677642)
		(width 0.1651)
		(layer "F.Cu")
		(net "M_E_DQS_DN<10>")
	)
	(segment
		(start 209.51571 -144.85493)
		(end 209.30743 -144.85493)
		(width 0.1651)
		(layer "F.Cu")
		(net "M_E_DQS_DN<10>")
	)
	(segment
		(start 209.58175 -143.749268)
		(end 209.58175 -144.1704)
		(width 0.1651)
		(layer "F.Cu")
		(net "M_E_DQS_DN<10>")
	)
	(segment
		(start 209.999834 -142.677642)
		(end 209.999834 -143.331184)
		(width 0.1651)
		(layer "F.Cu")
		(net "M_E_DQS_DN<10>")
	)
	(segment
		(start 209.767678 -144.602962)
		(end 209.51571 -144.85493)
		(width 0.1651)
		(layer "F.Cu")
		(net "M_E_DQS_DN<10>")
	)
	(segment
		(start 209.1182 -144.6657)
		(end 209.09915 -144.6657)
		(width 0.1651)
		(layer "F.Cu")
		(net "M_E_DQS_DN<10>")
	)
	(segment
		(start 209.30743 -144.85493)
		(end 209.1182 -144.6657)
		(width 0.1651)
		(layer "F.Cu")
		(net "M_E_DQS_DN<10>")
	)
	(segment
		(start 209.767678 -144.356328)
		(end 209.767678 -144.602962)
		(width 0.1651)
		(layer "F.Cu")
		(net "M_E_DQS_DN<10>")
	)
	(via
		(at 237.329218 -90.26144)
		(size 0.508)
		(drill 0.254)
		(layers "F.Cu" "B.Cu")
		(net "M_E_DQS_DN<10>")
	)
	(via
		(at 209.092546 -140.4874)
		(size 0.508)
		(drill 0.254)
		(layers "F.Cu" "B.Cu")
		(net "M_E_DQS_DN<10>")
	)
	(via
		(at 209.09915 -144.6657)
		(size 0.508)
		(drill 0.254)
		(layers "F.Cu" "B.Cu")
		(net "M_E_DQS_DN<10>")
	)
	(segment
		(start 209.55635 -141.376654)
		(end 210.000088 -141.820392)
		(width 0.1651)
		(layer "B.Cu")
		(net "M_E_DQS_DN<10>")
	)
	(segment
		(start 209.73415 -140.5128)
		(end 209.73415 -140.843)
		(width 0.1651)
		(layer "B.Cu")
		(net "M_E_DQS_DN<10>")
	)
	(segment
		(start 210.000088 -142.476728)
		(end 210.000342 -142.477236)
		(width 0.1651)
		(layer "B.Cu")
		(net "M_E_DQS_DN<10>")
	)
	(segment
		(start 209.55635 -141.0208)
		(end 209.55635 -141.376654)
		(width 0.1651)
		(layer "B.Cu")
		(net "M_E_DQS_DN<10>")
	)
	(segment
		(start 209.092546 -140.4874)
		(end 209.28711 -140.292836)
		(width 0.1651)
		(layer "B.Cu")
		(net "M_E_DQS_DN<10>")
	)
	(segment
		(start 209.73415 -140.843)
		(end 209.55635 -141.0208)
		(width 0.1651)
		(layer "B.Cu")
		(net "M_E_DQS_DN<10>")
	)
	(segment
		(start 209.514186 -140.292836)
		(end 209.73415 -140.5128)
		(width 0.1651)
		(layer "B.Cu")
		(net "M_E_DQS_DN<10>")
	)
	(segment
		(start 210.000088 -141.820392)
		(end 210.000088 -142.476728)
		(width 0.1651)
		(layer "B.Cu")
		(net "M_E_DQS_DN<10>")
	)
	(segment
		(start 209.28711 -140.292836)
		(end 209.514186 -140.292836)
		(width 0.1651)
		(layer "B.Cu")
		(net "M_E_DQS_DN<10>")
	)
	(segment
		(start 209.344514 -143.5608)
		(end 209.53222 -143.748506)
		(width 0.14224)
		(layer "In4.Cu")
		(net "M_E_DQS_DN<10>")
	)
	(segment
		(start 209.143854 -142.89786)
		(end 208.996534 -142.89786)
		(width 0.14224)
		(layer "In4.Cu")
		(net "M_E_DQS_DN<10>")
	)
	(segment
		(start 213.444074 -118.025926)
		(end 212.865208 -118.025926)
		(width 0.14224)
		(layer "In4.Cu")
		(net "M_E_DQS_DN<10>")
	)
	(segment
		(start 237.344204 -89.86139)
		(end 237.311438 -89.86139)
		(width 0.0889)
		(layer "In4.Cu")
		(net "M_E_DQS_DN<10>")
	)
	(segment
		(start 212.77072 -116.410486)
		(end 213.332314 -116.410486)
		(width 0.14224)
		(layer "In4.Cu")
		(net "M_E_DQS_DN<10>")
	)
	(segment
		(start 209.247994 -141.605)
		(end 209.006694 -141.605)
		(width 0.14224)
		(layer "In4.Cu")
		(net "M_E_DQS_DN<10>")
	)
	(segment
		(start 236.481874 -89.365836)
		(end 236.449108 -89.365836)
		(width 0.0889)
		(layer "In4.Cu")
		(net "M_E_DQS_DN<10>")
	)
	(segment
		(start 208.856834 -142.10284)
		(end 208.988914 -142.23492)
		(width 0.14224)
		(layer "In4.Cu")
		(net "M_E_DQS_DN<10>")
	)
	(segment
		(start 235.627164 -88.87079)
		(end 235.597192 -88.87079)
		(width 0.0889)
		(layer "In4.Cu")
		(net "M_E_DQS_DN<10>")
	)
	(segment
		(start 213.332314 -116.410486)
		(end 213.8934 -116.971572)
		(width 0.14224)
		(layer "In4.Cu")
		(net "M_E_DQS_DN<10>")
	)
	(segment
		(start 208.856834 -143.03756)
		(end 208.856834 -143.39824)
		(width 0.14224)
		(layer "In4.Cu")
		(net "M_E_DQS_DN<10>")
	)
	(segment
		(start 213.8934 -117.5766)
		(end 213.444074 -118.025926)
		(width 0.14224)
		(layer "In4.Cu")
		(net "M_E_DQS_DN<10>")
	)
	(segment
		(start 221.55404 -106.758232)
		(end 212.520784 -115.791488)
		(width 0.14224)
		(layer "In4.Cu")
		(net "M_E_DQS_DN<10>")
	)
	(segment
		(start 212.865208 -118.025926)
		(end 212.05952 -118.831614)
		(width 0.14224)
		(layer "In4.Cu")
		(net "M_E_DQS_DN<10>")
	)
	(segment
		(start 208.988914 -142.23492)
		(end 209.143854 -142.23492)
		(width 0.14224)
		(layer "In4.Cu")
		(net "M_E_DQS_DN<10>")
	)
	(segment
		(start 233.627168 -90.570558)
		(end 233.627168 -92.00007)
		(width 0.0889)
		(layer "In4.Cu")
		(net "M_E_DQS_DN<10>")
	)
	(segment
		(start 213.8934 -116.971572)
		(end 213.8934 -117.5766)
		(width 0.14224)
		(layer "In4.Cu")
		(net "M_E_DQS_DN<10>")
	)
	(segment
		(start 226.68484 -99.172776)
		(end 221.55404 -104.303576)
		(width 0.14224)
		(layer "In4.Cu")
		(net "M_E_DQS_DN<10>")
	)
	(segment
		(start 209.989166 -138.68273)
		(end 209.874866 -138.79703)
		(width 0.14224)
		(layer "In4.Cu")
		(net "M_E_DQS_DN<10>")
	)
	(segment
		(start 209.962242 -137.695432)
		(end 209.962242 -137.949432)
		(width 0.14224)
		(layer "In4.Cu")
		(net "M_E_DQS_DN<10>")
	)
	(segment
		(start 209.53222 -143.748506)
		(end 209.53222 -144.23263)
		(width 0.14224)
		(layer "In4.Cu")
		(net "M_E_DQS_DN<10>")
	)
	(segment
		(start 231.666796 -92.802456)
		(end 231.651048 -92.818204)
		(width 0.0889)
		(layer "In4.Cu")
		(net "M_E_DQS_DN<10>")
	)
	(segment
		(start 212.05952 -118.831614)
		(end 212.05952 -125.844808)
		(width 0.14224)
		(layer "In4.Cu")
		(net "M_E_DQS_DN<10>")
	)
	(segment
		(start 209.874866 -138.79703)
		(end 209.874866 -139.712446)
		(width 0.14224)
		(layer "In4.Cu")
		(net "M_E_DQS_DN<10>")
	)
	(segment
		(start 237.329218 -90.26144)
		(end 237.622334 -90.43035)
		(width 0.0889)
		(layer "In4.Cu")
		(net "M_E_DQS_DN<10>")
	)
	(segment
		(start 237.622334 -90.43035)
		(end 237.701074 -90.409014)
		(width 0.0889)
		(layer "In4.Cu")
		(net "M_E_DQS_DN<10>")
	)
	(segment
		(start 209.006694 -141.605)
		(end 208.856834 -141.75486)
		(width 0.14224)
		(layer "In4.Cu")
		(net "M_E_DQS_DN<10>")
	)
	(segment
		(start 233.627168 -92.00007)
		(end 233.211624 -92.415614)
		(width 0.0889)
		(layer "In4.Cu")
		(net "M_E_DQS_DN<10>")
	)
	(segment
		(start 209.874866 -138.036808)
		(end 209.874866 -138.31443)
		(width 0.14224)
		(layer "In4.Cu")
		(net "M_E_DQS_DN<10>")
	)
	(segment
		(start 231.651048 -92.818204)
		(end 229.16769 -95.301308)
		(width 0.14224)
		(layer "In4.Cu")
		(net "M_E_DQS_DN<10>")
	)
	(segment
		(start 233.211624 -92.415614)
		(end 231.997504 -92.415614)
		(width 0.0889)
		(layer "In4.Cu")
		(net "M_E_DQS_DN<10>")
	)
	(segment
		(start 210.10372 -129.604008)
		(end 209.874866 -129.832862)
		(width 0.14224)
		(layer "In4.Cu")
		(net "M_E_DQS_DN<10>")
	)
	(segment
		(start 209.298794 -142.38986)
		(end 209.298794 -142.74292)
		(width 0.14224)
		(layer "In4.Cu")
		(net "M_E_DQS_DN<10>")
	)
	(segment
		(start 229.16769 -95.301308)
		(end 229.167182 -95.301308)
		(width 0.14224)
		(layer "In4.Cu")
		(net "M_E_DQS_DN<10>")
	)
	(segment
		(start 209.874866 -138.31443)
		(end 209.989166 -138.42873)
		(width 0.14224)
		(layer "In4.Cu")
		(net "M_E_DQS_DN<10>")
	)
	(segment
		(start 209.53222 -144.23263)
		(end 209.09915 -144.6657)
		(width 0.14224)
		(layer "In4.Cu")
		(net "M_E_DQS_DN<10>")
	)
	(segment
		(start 233.470704 -90.19667)
		(end 233.470704 -90.414094)
		(width 0.0889)
		(layer "In4.Cu")
		(net "M_E_DQS_DN<10>")
	)
	(segment
		(start 208.856834 -141.75486)
		(end 208.856834 -142.10284)
		(width 0.14224)
		(layer "In4.Cu")
		(net "M_E_DQS_DN<10>")
	)
	(segment
		(start 212.05952 -125.844808)
		(end 210.10372 -127.800608)
		(width 0.14224)
		(layer "In4.Cu")
		(net "M_E_DQS_DN<10>")
	)
	(segment
		(start 209.989166 -138.42873)
		(end 209.989166 -138.68273)
		(width 0.14224)
		(layer "In4.Cu")
		(net "M_E_DQS_DN<10>")
	)
	(segment
		(start 231.666796 -92.746576)
		(end 231.666796 -92.802456)
		(width 0.0889)
		(layer "In4.Cu")
		(net "M_E_DQS_DN<10>")
	)
	(segment
		(start 234.775248 -89.365836)
		(end 234.742482 -89.365836)
		(width 0.0889)
		(layer "In4.Cu")
		(net "M_E_DQS_DN<10>")
	)
	(segment
		(start 209.099912 -140.4874)
		(end 209.092546 -140.4874)
		(width 0.14224)
		(layer "In4.Cu")
		(net "M_E_DQS_DN<10>")
	)
	(segment
		(start 208.856834 -143.39824)
		(end 209.019394 -143.5608)
		(width 0.14224)
		(layer "In4.Cu")
		(net "M_E_DQS_DN<10>")
	)
	(segment
		(start 231.997504 -92.415614)
		(end 231.666796 -92.746576)
		(width 0.0889)
		(layer "In4.Cu")
		(net "M_E_DQS_DN<10>")
	)
	(segment
		(start 209.527394 -140.922248)
		(end 209.527394 -141.3256)
		(width 0.14224)
		(layer "In4.Cu")
		(net "M_E_DQS_DN<10>")
	)
	(segment
		(start 208.996534 -142.89786)
		(end 208.856834 -143.03756)
		(width 0.14224)
		(layer "In4.Cu")
		(net "M_E_DQS_DN<10>")
	)
	(segment
		(start 209.143854 -142.23492)
		(end 209.298794 -142.38986)
		(width 0.14224)
		(layer "In4.Cu")
		(net "M_E_DQS_DN<10>")
	)
	(segment
		(start 221.55404 -104.303576)
		(end 221.55404 -106.758232)
		(width 0.14224)
		(layer "In4.Cu")
		(net "M_E_DQS_DN<10>")
	)
	(segment
		(start 209.874866 -129.832862)
		(end 209.874866 -137.608056)
		(width 0.14224)
		(layer "In4.Cu")
		(net "M_E_DQS_DN<10>")
	)
	(segment
		(start 209.298794 -142.74292)
		(end 209.143854 -142.89786)
		(width 0.14224)
		(layer "In4.Cu")
		(net "M_E_DQS_DN<10>")
	)
	(segment
		(start 226.68484 -97.78365)
		(end 226.68484 -99.172776)
		(width 0.14224)
		(layer "In4.Cu")
		(net "M_E_DQS_DN<10>")
	)
	(segment
		(start 212.520784 -116.16055)
		(end 212.77072 -116.410486)
		(width 0.14224)
		(layer "In4.Cu")
		(net "M_E_DQS_DN<10>")
	)
	(segment
		(start 209.527394 -141.3256)
		(end 209.247994 -141.605)
		(width 0.14224)
		(layer "In4.Cu")
		(net "M_E_DQS_DN<10>")
	)
	(segment
		(start 209.874866 -137.608056)
		(end 209.962242 -137.695432)
		(width 0.14224)
		(layer "In4.Cu")
		(net "M_E_DQS_DN<10>")
	)
	(segment
		(start 209.092546 -140.4874)
		(end 209.527394 -140.922248)
		(width 0.14224)
		(layer "In4.Cu")
		(net "M_E_DQS_DN<10>")
	)
	(segment
		(start 233.912918 -89.86139)
		(end 233.877612 -89.86139)
		(width 0.0889)
		(layer "In4.Cu")
		(net "M_E_DQS_DN<10>")
	)
	(segment
		(start 212.520784 -115.791488)
		(end 212.520784 -116.16055)
		(width 0.14224)
		(layer "In4.Cu")
		(net "M_E_DQS_DN<10>")
	)
	(segment
		(start 209.962242 -137.949432)
		(end 209.874866 -138.036808)
		(width 0.14224)
		(layer "In4.Cu")
		(net "M_E_DQS_DN<10>")
	)
	(segment
		(start 209.874866 -139.712446)
		(end 209.099912 -140.4874)
		(width 0.14224)
		(layer "In4.Cu")
		(net "M_E_DQS_DN<10>")
	)
	(segment
		(start 209.019394 -143.5608)
		(end 209.344514 -143.5608)
		(width 0.14224)
		(layer "In4.Cu")
		(net "M_E_DQS_DN<10>")
	)
	(segment
		(start 229.167182 -95.301308)
		(end 226.68484 -97.78365)
		(width 0.14224)
		(layer "In4.Cu")
		(net "M_E_DQS_DN<10>")
	)
	(segment
		(start 233.470704 -90.414094)
		(end 233.627168 -90.570558)
		(width 0.0889)
		(layer "In4.Cu")
		(net "M_E_DQS_DN<10>")
	)
	(segment
		(start 233.548428 -90.061288)
		(end 233.470704 -90.19667)
		(width 0.0889)
		(layer "In4.Cu")
		(net "M_E_DQS_DN<10>")
	)
	(segment
		(start 210.10372 -127.800608)
		(end 210.10372 -129.604008)
		(width 0.14224)
		(layer "In4.Cu")
		(net "M_E_DQS_DN<10>")
	)
	(arc
		(start 235.958888 -89.070688)
		(mid 235.818809 -88.927952)
		(end 235.627164 -88.87079)
		(width 0.0889)
		(layer "In4.Cu")
		(net "M_E_DQS_DN<10>")
	)
	(arc
		(start 234.406948 -89.565988)
		(mid 234.19834 -89.77792)
		(end 233.912918 -89.86139)
		(width 0.0889)
		(layer "In4.Cu")
		(net "M_E_DQS_DN<10>")
	)
	(arc
		(start 235.265468 -89.070688)
		(mid 235.058464 -89.281552)
		(end 234.775248 -89.365836)
		(width 0.0889)
		(layer "In4.Cu")
		(net "M_E_DQS_DN<10>")
	)
	(arc
		(start 233.877612 -89.86139)
		(mid 233.68737 -89.919125)
		(end 233.548428 -90.061288)
		(width 0.0889)
		(layer "In4.Cu")
		(net "M_E_DQS_DN<10>")
	)
	(arc
		(start 236.817408 -89.565988)
		(mid 236.675725 -89.422184)
		(end 236.481874 -89.365836)
		(width 0.0889)
		(layer "In4.Cu")
		(net "M_E_DQS_DN<10>")
	)
	(arc
		(start 237.701074 -90.409014)
		(mid 237.664334 -90.042875)
		(end 237.344204 -89.86139)
		(width 0.0889)
		(layer "In4.Cu")
		(net "M_E_DQS_DN<10>")
	)
	(arc
		(start 237.311438 -89.86139)
		(mid 237.026014 -89.777923)
		(end 236.817408 -89.565988)
		(width 0.0889)
		(layer "In4.Cu")
		(net "M_E_DQS_DN<10>")
	)
	(arc
		(start 235.597192 -88.87079)
		(mid 235.40555 -88.927956)
		(end 235.265468 -89.070688)
		(width 0.0889)
		(layer "In4.Cu")
		(net "M_E_DQS_DN<10>")
	)
	(arc
		(start 236.449108 -89.365836)
		(mid 236.165891 -89.281555)
		(end 235.958888 -89.070688)
		(width 0.0889)
		(layer "In4.Cu")
		(net "M_E_DQS_DN<10>")
	)
	(arc
		(start 234.742482 -89.365836)
		(mid 234.548632 -89.422186)
		(end 234.406948 -89.565988)
		(width 0.0889)
		(layer "In4.Cu")
		(net "M_E_DQS_DN<10>")
	)
	(segment
		(start 200.822306 -145.0594)
		(end 201.037952 -145.275046)
		(width 0.1651)
		(layer "F.Cu")
		(net "M_E_DQS_DN<0>")
	)
	(segment
		(start 236.183678 -84.31784)
		(end 235.612178 -84.31784)
		(width 0.1651)
		(layer "F.Cu")
		(net "M_E_DQS_DN<0>")
	)
	(segment
		(start 200.267824 -145.389854)
		(end 200.598278 -145.0594)
		(width 0.1651)
		(layer "F.Cu")
		(net "M_E_DQS_DN<0>")
	)
	(segment
		(start 200.267824 -145.821654)
		(end 200.267824 -145.389854)
		(width 0.1651)
		(layer "F.Cu")
		(net "M_E_DQS_DN<0>")
	)
	(segment
		(start 200.64984 -146.20367)
		(end 200.267824 -145.821654)
		(width 0.1651)
		(layer "F.Cu")
		(net "M_E_DQS_DN<0>")
	)
	(segment
		(start 200.64984 -147.27174)
		(end 200.64984 -146.20367)
		(width 0.1651)
		(layer "F.Cu")
		(net "M_E_DQS_DN<0>")
	)
	(segment
		(start 200.598278 -145.0594)
		(end 200.822306 -145.0594)
		(width 0.1651)
		(layer "F.Cu")
		(net "M_E_DQS_DN<0>")
	)
	(segment
		(start 200.650348 -147.27174)
		(end 200.64984 -147.27174)
		(width 0.1651)
		(layer "F.Cu")
		(net "M_E_DQS_DN<0>")
	)
	(via
		(at 201.037952 -145.275046)
		(size 0.508)
		(drill 0.254)
		(layers "F.Cu" "B.Cu")
		(net "M_E_DQS_DN<0>")
	)
	(via
		(at 201.037952 -139.881356)
		(size 0.508)
		(drill 0.254)
		(layers "F.Cu" "B.Cu")
		(net "M_E_DQS_DN<0>")
	)
	(via
		(at 235.612178 -84.31784)
		(size 0.508)
		(drill 0.254)
		(layers "F.Cu" "B.Cu")
		(net "M_E_DQS_DN<0>")
	)
	(segment
		(start 200.812908 -140.1064)
		(end 201.037952 -139.881356)
		(width 0.1651)
		(layer "B.Cu")
		(net "M_E_DQS_DN<0>")
	)
	(segment
		(start 200.623424 -140.1064)
		(end 200.812908 -140.1064)
		(width 0.1651)
		(layer "B.Cu")
		(net "M_E_DQS_DN<0>")
	)
	(segment
		(start 200.64984 -137.877296)
		(end 200.64984 -138.78433)
		(width 0.1651)
		(layer "B.Cu")
		(net "M_E_DQS_DN<0>")
	)
	(segment
		(start 200.64984 -138.78433)
		(end 200.521824 -138.912346)
		(width 0.1651)
		(layer "B.Cu")
		(net "M_E_DQS_DN<0>")
	)
	(segment
		(start 200.267824 -139.420346)
		(end 200.267824 -139.7508)
		(width 0.1651)
		(layer "B.Cu")
		(net "M_E_DQS_DN<0>")
	)
	(segment
		(start 200.521824 -139.166346)
		(end 200.267824 -139.420346)
		(width 0.1651)
		(layer "B.Cu")
		(net "M_E_DQS_DN<0>")
	)
	(segment
		(start 200.521824 -138.912346)
		(end 200.521824 -139.166346)
		(width 0.1651)
		(layer "B.Cu")
		(net "M_E_DQS_DN<0>")
	)
	(segment
		(start 200.267824 -139.7508)
		(end 200.623424 -140.1064)
		(width 0.1651)
		(layer "B.Cu")
		(net "M_E_DQS_DN<0>")
	)
	(segment
		(start 200.650348 -137.877296)
		(end 200.64984 -137.877296)
		(width 0.1651)
		(layer "B.Cu")
		(net "M_E_DQS_DN<0>")
	)
	(segment
		(start 201.551032 -138.09472)
		(end 201.393552 -137.93724)
		(width 0.14224)
		(layer "In4.Cu")
		(net "M_E_DQS_DN<0>")
	)
	(segment
		(start 207.982312 -109.68736)
		(end 208.82864 -109.68736)
		(width 0.14224)
		(layer "In4.Cu")
		(net "M_E_DQS_DN<0>")
	)
	(segment
		(start 201.037952 -145.275046)
		(end 200.604882 -144.841976)
		(width 0.14224)
		(layer "In4.Cu")
		(net "M_E_DQS_DN<0>")
	)
	(segment
		(start 201.551032 -131.8768)
		(end 201.551032 -129.179066)
		(width 0.14224)
		(layer "In4.Cu")
		(net "M_E_DQS_DN<0>")
	)
	(segment
		(start 201.551032 -137.27176)
		(end 201.393552 -137.11428)
		(width 0.14224)
		(layer "In4.Cu")
		(net "M_E_DQS_DN<0>")
	)
	(segment
		(start 201.393552 -137.93724)
		(end 201.393552 -137.68324)
		(width 0.14224)
		(layer "In4.Cu")
		(net "M_E_DQS_DN<0>")
	)
	(segment
		(start 201.393552 -137.11428)
		(end 201.393552 -136.86028)
		(width 0.14224)
		(layer "In4.Cu")
		(net "M_E_DQS_DN<0>")
	)
	(segment
		(start 200.604882 -140.241274)
		(end 200.9648 -139.881356)
		(width 0.14224)
		(layer "In4.Cu")
		(net "M_E_DQS_DN<0>")
	)
	(segment
		(start 233.018838 -85.212936)
		(end 233.051604 -85.212936)
		(width 0.0889)
		(layer "In4.Cu")
		(net "M_E_DQS_DN<0>")
	)
	(segment
		(start 201.393552 -133.9342)
		(end 201.393552 -133.6802)
		(width 0.14224)
		(layer "In4.Cu")
		(net "M_E_DQS_DN<0>")
	)
	(segment
		(start 200.416668 -122.888756)
		(end 200.801732 -122.503692)
		(width 0.14224)
		(layer "In4.Cu")
		(net "M_E_DQS_DN<0>")
	)
	(segment
		(start 200.9648 -139.881356)
		(end 201.037952 -139.881356)
		(width 0.14224)
		(layer "In4.Cu")
		(net "M_E_DQS_DN<0>")
	)
	(segment
		(start 221.098364 -93.683836)
		(end 229.202234 -85.579966)
		(width 0.14224)
		(layer "In4.Cu")
		(net "M_E_DQS_DN<0>")
	)
	(segment
		(start 201.551032 -133.52272)
		(end 201.551032 -133.26872)
		(width 0.14224)
		(layer "In4.Cu")
		(net "M_E_DQS_DN<0>")
	)
	(segment
		(start 202.06208 -119.052848)
		(end 201.309224 -118.299992)
		(width 0.14224)
		(layer "In4.Cu")
		(net "M_E_DQS_DN<0>")
	)
	(segment
		(start 201.393552 -138.7602)
		(end 201.393552 -138.5062)
		(width 0.14224)
		(layer "In4.Cu")
		(net "M_E_DQS_DN<0>")
	)
	(segment
		(start 201.551032 -132.44576)
		(end 201.393552 -132.28828)
		(width 0.14224)
		(layer "In4.Cu")
		(net "M_E_DQS_DN<0>")
	)
	(segment
		(start 202.06208 -119.996204)
		(end 202.06208 -119.052848)
		(width 0.14224)
		(layer "In4.Cu")
		(net "M_E_DQS_DN<0>")
	)
	(segment
		(start 229.890066 -85.579966)
		(end 229.929436 -85.619336)
		(width 0.0889)
		(layer "In4.Cu")
		(net "M_E_DQS_DN<0>")
	)
	(segment
		(start 200.801732 -122.503692)
		(end 201.840592 -122.503692)
		(width 0.14224)
		(layer "In4.Cu")
		(net "M_E_DQS_DN<0>")
	)
	(segment
		(start 200.416668 -123.544584)
		(end 200.416668 -122.888756)
		(width 0.14224)
		(layer "In4.Cu")
		(net "M_E_DQS_DN<0>")
	)
	(segment
		(start 202.06208 -124.741686)
		(end 202.06208 -124.13742)
		(width 0.14224)
		(layer "In4.Cu")
		(net "M_E_DQS_DN<0>")
	)
	(segment
		(start 200.604882 -143.5862)
		(end 200.394062 -143.37538)
		(width 0.14224)
		(layer "In4.Cu")
		(net "M_E_DQS_DN<0>")
	)
	(segment
		(start 221.098364 -97.417636)
		(end 221.098364 -93.683836)
		(width 0.14224)
		(layer "In4.Cu")
		(net "M_E_DQS_DN<0>")
	)
	(segment
		(start 201.551032 -138.91768)
		(end 201.393552 -138.7602)
		(width 0.14224)
		(layer "In4.Cu")
		(net "M_E_DQS_DN<0>")
	)
	(segment
		(start 201.393552 -133.6802)
		(end 201.551032 -133.52272)
		(width 0.14224)
		(layer "In4.Cu")
		(net "M_E_DQS_DN<0>")
	)
	(segment
		(start 203.844906 -114.663982)
		(end 203.844906 -113.824766)
		(width 0.14224)
		(layer "In4.Cu")
		(net "M_E_DQS_DN<0>")
	)
	(segment
		(start 235.05795 -84.222336)
		(end 235.612178 -84.31784)
		(width 0.0889)
		(layer "In4.Cu")
		(net "M_E_DQS_DN<0>")
	)
	(segment
		(start 201.881486 -124.92228)
		(end 202.06208 -124.741686)
		(width 0.14224)
		(layer "In4.Cu")
		(net "M_E_DQS_DN<0>")
	)
	(segment
		(start 201.551032 -134.440422)
		(end 201.551032 -134.09168)
		(width 0.14224)
		(layer "In4.Cu")
		(net "M_E_DQS_DN<0>")
	)
	(segment
		(start 200.788016 -123.915932)
		(end 200.416668 -123.544584)
		(width 0.14224)
		(layer "In4.Cu")
		(net "M_E_DQS_DN<0>")
	)
	(segment
		(start 201.301858 -128.929892)
		(end 201.078846 -128.929892)
		(width 0.14224)
		(layer "In4.Cu")
		(net "M_E_DQS_DN<0>")
	)
	(segment
		(start 201.551032 -134.09168)
		(end 201.393552 -133.9342)
		(width 0.14224)
		(layer "In4.Cu")
		(net "M_E_DQS_DN<0>")
	)
	(segment
		(start 200.916286 -121.629932)
		(end 200.53808 -121.251726)
		(width 0.14224)
		(layer "In4.Cu")
		(net "M_E_DQS_DN<0>")
	)
	(segment
		(start 229.202234 -85.579966)
		(end 229.867968 -85.579966)
		(width 0.14224)
		(layer "In4.Cu")
		(net "M_E_DQS_DN<0>")
	)
	(segment
		(start 201.393552 -132.85724)
		(end 201.551032 -132.69976)
		(width 0.14224)
		(layer "In4.Cu")
		(net "M_E_DQS_DN<0>")
	)
	(segment
		(start 203.844906 -113.824766)
		(end 207.982312 -109.68736)
		(width 0.14224)
		(layer "In4.Cu")
		(net "M_E_DQS_DN<0>")
	)
	(segment
		(start 201.551032 -135.743696)
		(end 201.551032 -134.941818)
		(width 0.14224)
		(layer "In4.Cu")
		(net "M_E_DQS_DN<0>")
	)
	(segment
		(start 201.309224 -118.299992)
		(end 201.309224 -117.199664)
		(width 0.14224)
		(layer "In4.Cu")
		(net "M_E_DQS_DN<0>")
	)
	(segment
		(start 201.393552 -138.5062)
		(end 201.551032 -138.34872)
		(width 0.14224)
		(layer "In4.Cu")
		(net "M_E_DQS_DN<0>")
	)
	(segment
		(start 231.3305 -85.70849)
		(end 232.192576 -85.70849)
		(width 0.0889)
		(layer "In4.Cu")
		(net "M_E_DQS_DN<0>")
	)
	(segment
		(start 231.241346 -85.619336)
		(end 231.3305 -85.70849)
		(width 0.0889)
		(layer "In4.Cu")
		(net "M_E_DQS_DN<0>")
	)
	(segment
		(start 200.394062 -141.71422)
		(end 200.604882 -141.5034)
		(width 0.14224)
		(layer "In4.Cu")
		(net "M_E_DQS_DN<0>")
	)
	(segment
		(start 200.394062 -143.37538)
		(end 200.394062 -141.71422)
		(width 0.14224)
		(layer "In4.Cu")
		(net "M_E_DQS_DN<0>")
	)
	(segment
		(start 229.867968 -85.579966)
		(end 229.890066 -85.579966)
		(width 0.0889)
		(layer "In4.Cu")
		(net "M_E_DQS_DN<0>")
	)
	(segment
		(start 201.393552 -136.86028)
		(end 201.551032 -136.7028)
		(width 0.14224)
		(layer "In4.Cu")
		(net "M_E_DQS_DN<0>")
	)
	(segment
		(start 201.551032 -137.52576)
		(end 201.551032 -137.27176)
		(width 0.14224)
		(layer "In4.Cu")
		(net "M_E_DQS_DN<0>")
	)
	(segment
		(start 234.735878 -84.222336)
		(end 235.05795 -84.222336)
		(width 0.0889)
		(layer "In4.Cu")
		(net "M_E_DQS_DN<0>")
	)
	(segment
		(start 202.06208 -124.13742)
		(end 201.840592 -123.915932)
		(width 0.14224)
		(layer "In4.Cu")
		(net "M_E_DQS_DN<0>")
	)
	(segment
		(start 201.551032 -136.251696)
		(end 201.424032 -136.124696)
		(width 0.14224)
		(layer "In4.Cu")
		(net "M_E_DQS_DN<0>")
	)
	(segment
		(start 201.551032 -138.34872)
		(end 201.551032 -138.09472)
		(width 0.14224)
		(layer "In4.Cu")
		(net "M_E_DQS_DN<0>")
	)
	(segment
		(start 200.814686 -124.92228)
		(end 201.881486 -124.92228)
		(width 0.14224)
		(layer "In4.Cu")
		(net "M_E_DQS_DN<0>")
	)
	(segment
		(start 200.899268 -128.750314)
		(end 200.899268 -128.527302)
		(width 0.14224)
		(layer "In4.Cu")
		(net "M_E_DQS_DN<0>")
	)
	(segment
		(start 201.393552 -133.11124)
		(end 201.393552 -132.85724)
		(width 0.14224)
		(layer "In4.Cu")
		(net "M_E_DQS_DN<0>")
	)
	(segment
		(start 201.393552 -132.03428)
		(end 201.551032 -131.8768)
		(width 0.14224)
		(layer "In4.Cu")
		(net "M_E_DQS_DN<0>")
	)
	(segment
		(start 208.82864 -109.68736)
		(end 221.098364 -97.417636)
		(width 0.14224)
		(layer "In4.Cu")
		(net "M_E_DQS_DN<0>")
	)
	(segment
		(start 200.916286 -120.217692)
		(end 201.840592 -120.217692)
		(width 0.14224)
		(layer "In4.Cu")
		(net "M_E_DQS_DN<0>")
	)
	(segment
		(start 229.929436 -85.619336)
		(end 231.241346 -85.619336)
		(width 0.0889)
		(layer "In4.Cu")
		(net "M_E_DQS_DN<0>")
	)
	(segment
		(start 201.078846 -128.929892)
		(end 200.899268 -128.750314)
		(width 0.14224)
		(layer "In4.Cu")
		(net "M_E_DQS_DN<0>")
	)
	(segment
		(start 201.551032 -133.26872)
		(end 201.393552 -133.11124)
		(width 0.14224)
		(layer "In4.Cu")
		(net "M_E_DQS_DN<0>")
	)
	(segment
		(start 200.53808 -121.251726)
		(end 200.53808 -120.595898)
		(width 0.14224)
		(layer "In4.Cu")
		(net "M_E_DQS_DN<0>")
	)
	(segment
		(start 201.551032 -132.69976)
		(end 201.551032 -132.44576)
		(width 0.14224)
		(layer "In4.Cu")
		(net "M_E_DQS_DN<0>")
	)
	(segment
		(start 201.283062 -139.881356)
		(end 201.551032 -139.613386)
		(width 0.14224)
		(layer "In4.Cu")
		(net "M_E_DQS_DN<0>")
	)
	(segment
		(start 201.840592 -120.217692)
		(end 202.06208 -119.996204)
		(width 0.14224)
		(layer "In4.Cu")
		(net "M_E_DQS_DN<0>")
	)
	(segment
		(start 201.037952 -139.881356)
		(end 201.283062 -139.881356)
		(width 0.14224)
		(layer "In4.Cu")
		(net "M_E_DQS_DN<0>")
	)
	(segment
		(start 201.840592 -121.629932)
		(end 200.916286 -121.629932)
		(width 0.14224)
		(layer "In4.Cu")
		(net "M_E_DQS_DN<0>")
	)
	(segment
		(start 200.43648 -128.064514)
		(end 200.43648 -125.300486)
		(width 0.14224)
		(layer "In4.Cu")
		(net "M_E_DQS_DN<0>")
	)
	(segment
		(start 201.393552 -132.28828)
		(end 201.393552 -132.03428)
		(width 0.14224)
		(layer "In4.Cu")
		(net "M_E_DQS_DN<0>")
	)
	(segment
		(start 200.43648 -125.300486)
		(end 200.814686 -124.92228)
		(width 0.14224)
		(layer "In4.Cu")
		(net "M_E_DQS_DN<0>")
	)
	(segment
		(start 201.427334 -134.81812)
		(end 201.427334 -134.56412)
		(width 0.14224)
		(layer "In4.Cu")
		(net "M_E_DQS_DN<0>")
	)
	(segment
		(start 201.309224 -117.199664)
		(end 203.844906 -114.663982)
		(width 0.14224)
		(layer "In4.Cu")
		(net "M_E_DQS_DN<0>")
	)
	(segment
		(start 201.424032 -136.124696)
		(end 201.424032 -135.870696)
		(width 0.14224)
		(layer "In4.Cu")
		(net "M_E_DQS_DN<0>")
	)
	(segment
		(start 201.551032 -136.7028)
		(end 201.551032 -136.251696)
		(width 0.14224)
		(layer "In4.Cu")
		(net "M_E_DQS_DN<0>")
	)
	(segment
		(start 202.06208 -121.85142)
		(end 201.840592 -121.629932)
		(width 0.14224)
		(layer "In4.Cu")
		(net "M_E_DQS_DN<0>")
	)
	(segment
		(start 201.427334 -134.56412)
		(end 201.551032 -134.440422)
		(width 0.14224)
		(layer "In4.Cu")
		(net "M_E_DQS_DN<0>")
	)
	(segment
		(start 201.551032 -129.179066)
		(end 201.301858 -128.929892)
		(width 0.14224)
		(layer "In4.Cu")
		(net "M_E_DQS_DN<0>")
	)
	(segment
		(start 233.873548 -84.71789)
		(end 233.906314 -84.71789)
		(width 0.0889)
		(layer "In4.Cu")
		(net "M_E_DQS_DN<0>")
	)
	(segment
		(start 200.604882 -141.5034)
		(end 200.604882 -140.241274)
		(width 0.14224)
		(layer "In4.Cu")
		(net "M_E_DQS_DN<0>")
	)
	(segment
		(start 202.06208 -122.282204)
		(end 202.06208 -121.85142)
		(width 0.14224)
		(layer "In4.Cu")
		(net "M_E_DQS_DN<0>")
	)
	(segment
		(start 201.840592 -122.503692)
		(end 202.06208 -122.282204)
		(width 0.14224)
		(layer "In4.Cu")
		(net "M_E_DQS_DN<0>")
	)
	(segment
		(start 200.604882 -144.841976)
		(end 200.604882 -143.5862)
		(width 0.14224)
		(layer "In4.Cu")
		(net "M_E_DQS_DN<0>")
	)
	(segment
		(start 201.840592 -123.915932)
		(end 200.788016 -123.915932)
		(width 0.14224)
		(layer "In4.Cu")
		(net "M_E_DQS_DN<0>")
	)
	(segment
		(start 201.424032 -135.870696)
		(end 201.551032 -135.743696)
		(width 0.14224)
		(layer "In4.Cu")
		(net "M_E_DQS_DN<0>")
	)
	(segment
		(start 201.551032 -139.613386)
		(end 201.551032 -138.91768)
		(width 0.14224)
		(layer "In4.Cu")
		(net "M_E_DQS_DN<0>")
	)
	(segment
		(start 200.899268 -128.527302)
		(end 200.43648 -128.064514)
		(width 0.14224)
		(layer "In4.Cu")
		(net "M_E_DQS_DN<0>")
	)
	(segment
		(start 201.393552 -137.68324)
		(end 201.551032 -137.52576)
		(width 0.14224)
		(layer "In4.Cu")
		(net "M_E_DQS_DN<0>")
	)
	(segment
		(start 200.53808 -120.595898)
		(end 200.916286 -120.217692)
		(width 0.14224)
		(layer "In4.Cu")
		(net "M_E_DQS_DN<0>")
	)
	(segment
		(start 201.551032 -134.941818)
		(end 201.427334 -134.81812)
		(width 0.14224)
		(layer "In4.Cu")
		(net "M_E_DQS_DN<0>")
	)
	(arc
		(start 233.383328 -85.013038)
		(mid 233.590332 -84.802174)
		(end 233.873548 -84.71789)
		(width 0.0889)
		(layer "In4.Cu")
		(net "M_E_DQS_DN<0>")
	)
	(arc
		(start 233.906314 -84.71789)
		(mid 234.100164 -84.66154)
		(end 234.241848 -84.517738)
		(width 0.0889)
		(layer "In4.Cu")
		(net "M_E_DQS_DN<0>")
	)
	(arc
		(start 232.192576 -85.70849)
		(mid 232.384593 -85.651382)
		(end 232.524808 -85.508338)
		(width 0.0889)
		(layer "In4.Cu")
		(net "M_E_DQS_DN<0>")
	)
	(arc
		(start 232.524808 -85.508338)
		(mid 232.733416 -85.296406)
		(end 233.018838 -85.212936)
		(width 0.0889)
		(layer "In4.Cu")
		(net "M_E_DQS_DN<0>")
	)
	(arc
		(start 233.051604 -85.212936)
		(mid 233.243246 -85.15577)
		(end 233.383328 -85.013038)
		(width 0.0889)
		(layer "In4.Cu")
		(net "M_E_DQS_DN<0>")
	)
	(arc
		(start 234.241848 -84.517738)
		(mid 234.450456 -84.305806)
		(end 234.735878 -84.222336)
		(width 0.0889)
		(layer "In4.Cu")
		(net "M_E_DQS_DN<0>")
	)
	(segment
		(start 207.449928 -142.677642)
		(end 207.449928 -143.941546)
		(width 0.1651)
		(layer "F.Cu")
		(net "M_E_DQ<9>")
	)
	(segment
		(start 237.042198 -88.775286)
		(end 236.470698 -88.775286)
		(width 0.1651)
		(layer "F.Cu")
		(net "M_E_DQ<9>")
	)
	(segment
		(start 207.450436 -142.6718)
		(end 207.449928 -142.677642)
		(width 0.1651)
		(layer "F.Cu")
		(net "M_E_DQ<9>")
	)
	(via
		(at 236.470698 -88.775286)
		(size 0.508)
		(drill 0.254)
		(layers "F.Cu" "B.Cu")
		(net "M_E_DQ<9>")
	)
	(via
		(at 208.122012 -139.932156)
		(size 0.508)
		(drill 0.254)
		(layers "F.Cu" "B.Cu")
		(net "M_E_DQ<9>")
	)
	(via
		(at 207.449928 -143.941546)
		(size 0.508)
		(drill 0.254)
		(layers "F.Cu" "B.Cu")
		(net "M_E_DQ<9>")
	)
	(segment
		(start 208.299812 -139.251182)
		(end 208.122012 -139.428982)
		(width 0.1651)
		(layer "B.Cu")
		(net "M_E_DQ<9>")
	)
	(segment
		(start 208.122012 -139.428982)
		(end 208.122012 -139.932156)
		(width 0.1651)
		(layer "B.Cu")
		(net "M_E_DQ<9>")
	)
	(segment
		(start 208.30032 -137.877296)
		(end 208.299812 -137.877296)
		(width 0.1651)
		(layer "B.Cu")
		(net "M_E_DQ<9>")
	)
	(segment
		(start 208.299812 -137.877296)
		(end 208.299812 -139.251182)
		(width 0.1651)
		(layer "B.Cu")
		(net "M_E_DQ<9>")
	)
	(segment
		(start 211.328 -116.815616)
		(end 211.9122 -116.815616)
		(width 0.14224)
		(layer "In4.Cu")
		(net "M_E_DQ<9>")
	)
	(segment
		(start 211.328 -117.628416)
		(end 211.1248 -117.831616)
		(width 0.14224)
		(layer "In4.Cu")
		(net "M_E_DQ<9>")
	)
	(segment
		(start 220.6752 -106.0196)
		(end 220.6752 -106.3244)
		(width 0.14224)
		(layer "In4.Cu")
		(net "M_E_DQ<9>")
	)
	(segment
		(start 208.122012 -139.843256)
		(end 208.122012 -139.932156)
		(width 0.14224)
		(layer "In4.Cu")
		(net "M_E_DQ<9>")
	)
	(segment
		(start 236.470698 -88.775286)
		(end 235.975652 -88.109552)
		(width 0.0889)
		(layer "In4.Cu")
		(net "M_E_DQ<9>")
	)
	(segment
		(start 209.0928 -128.29286)
		(end 209.2198 -128.41986)
		(width 0.14224)
		(layer "In4.Cu")
		(net "M_E_DQ<9>")
	)
	(segment
		(start 219.59697 -106.79303)
		(end 219.59697 -107.63123)
		(width 0.14224)
		(layer "In4.Cu")
		(net "M_E_DQ<9>")
	)
	(segment
		(start 208.46034 -132.69849)
		(end 208.3054 -132.85343)
		(width 0.14224)
		(layer "In4.Cu")
		(net "M_E_DQ<9>")
	)
	(segment
		(start 211.1248 -116.612416)
		(end 211.328 -116.815616)
		(width 0.14224)
		(layer "In4.Cu")
		(net "M_E_DQ<9>")
	)
	(segment
		(start 208.7372 -138.342624)
		(end 208.7372 -138.7856)
		(width 0.14224)
		(layer "In4.Cu")
		(net "M_E_DQ<9>")
	)
	(segment
		(start 208.609946 -139.355322)
		(end 208.122012 -139.843256)
		(width 0.14224)
		(layer "In4.Cu")
		(net "M_E_DQ<9>")
	)
	(segment
		(start 208.8134 -133.9596)
		(end 208.609946 -134.163054)
		(width 0.14224)
		(layer "In4.Cu")
		(net "M_E_DQ<9>")
	)
	(segment
		(start 209.2198 -128.97866)
		(end 209.0928 -129.10566)
		(width 0.14224)
		(layer "In4.Cu")
		(net "M_E_DQ<9>")
	)
	(segment
		(start 225.74377 -97.406206)
		(end 225.74377 -99.055682)
		(width 0.14224)
		(layer "In4.Cu")
		(net "M_E_DQ<9>")
	)
	(segment
		(start 208.609946 -131.7752)
		(end 208.8134 -131.978654)
		(width 0.14224)
		(layer "In4.Cu")
		(net "M_E_DQ<9>")
	)
	(segment
		(start 233.912918 -88.87079)
		(end 233.880152 -88.87079)
		(width 0.0889)
		(layer "In4.Cu")
		(net "M_E_DQ<9>")
	)
	(segment
		(start 208.609946 -129.2606)
		(end 208.609946 -131.7752)
		(width 0.14224)
		(layer "In4.Cu")
		(net "M_E_DQ<9>")
	)
	(segment
		(start 208.8134 -133.66623)
		(end 208.8134 -133.9596)
		(width 0.14224)
		(layer "In4.Cu")
		(net "M_E_DQ<9>")
	)
	(segment
		(start 208.122012 -139.932156)
		(end 208.09966 -139.932156)
		(width 0.14224)
		(layer "In4.Cu")
		(net "M_E_DQ<9>")
	)
	(segment
		(start 208.7372 -137.275824)
		(end 208.407 -137.606024)
		(width 0.14224)
		(layer "In4.Cu")
		(net "M_E_DQ<9>")
	)
	(segment
		(start 232.776268 -90.757502)
		(end 232.350564 -91.183206)
		(width 0.0889)
		(layer "In4.Cu")
		(net "M_E_DQ<9>")
	)
	(segment
		(start 208.609946 -127.863854)
		(end 208.609946 -128.13792)
		(width 0.14224)
		(layer "In4.Cu")
		(net "M_E_DQ<9>")
	)
	(segment
		(start 209.0928 -129.10566)
		(end 208.764886 -129.10566)
		(width 0.14224)
		(layer "In4.Cu")
		(net "M_E_DQ<9>")
	)
	(segment
		(start 212.1154 -117.018816)
		(end 212.1154 -117.425216)
		(width 0.14224)
		(layer "In4.Cu")
		(net "M_E_DQ<9>")
	)
	(segment
		(start 235.975652 -88.109552)
		(end 235.958888 -88.080088)
		(width 0.0889)
		(layer "In4.Cu")
		(net "M_E_DQ<9>")
	)
	(segment
		(start 219.59697 -107.63123)
		(end 211.1248 -116.1034)
		(width 0.14224)
		(layer "In4.Cu")
		(net "M_E_DQ<9>")
	)
	(segment
		(start 233.058208 -89.365836)
		(end 232.870248 -89.365836)
		(width 0.0889)
		(layer "In4.Cu")
		(net "M_E_DQ<9>")
	)
	(segment
		(start 208.3054 -133.35635)
		(end 208.46034 -133.51129)
		(width 0.14224)
		(layer "In4.Cu")
		(net "M_E_DQ<9>")
	)
	(segment
		(start 232.653586 -89.968832)
		(end 232.776268 -90.200226)
		(width 0.0889)
		(layer "In4.Cu")
		(net "M_E_DQ<9>")
	)
	(segment
		(start 207.611218 -142.936976)
		(end 207.611218 -143.244824)
		(width 0.14224)
		(layer "In4.Cu")
		(net "M_E_DQ<9>")
	)
	(segment
		(start 231.0892 -91.80957)
		(end 231.0892 -92.060776)
		(width 0.0889)
		(layer "In4.Cu")
		(net "M_E_DQ<9>")
	)
	(segment
		(start 235.627164 -87.88019)
		(end 235.597192 -87.88019)
		(width 0.0889)
		(layer "In4.Cu")
		(net "M_E_DQ<9>")
	)
	(segment
		(start 211.1248 -125.349)
		(end 208.609946 -127.863854)
		(width 0.14224)
		(layer "In4.Cu")
		(net "M_E_DQ<9>")
	)
	(segment
		(start 220.4466 -106.553)
		(end 219.837 -106.553)
		(width 0.14224)
		(layer "In4.Cu")
		(net "M_E_DQ<9>")
	)
	(segment
		(start 208.609946 -134.163054)
		(end 208.609946 -136.5758)
		(width 0.14224)
		(layer "In4.Cu")
		(net "M_E_DQ<9>")
	)
	(segment
		(start 211.9122 -117.628416)
		(end 211.328 -117.628416)
		(width 0.14224)
		(layer "In4.Cu")
		(net "M_E_DQ<9>")
	)
	(segment
		(start 211.1248 -116.1034)
		(end 211.1248 -116.612416)
		(width 0.14224)
		(layer "In4.Cu")
		(net "M_E_DQ<9>")
	)
	(segment
		(start 208.609946 -136.5758)
		(end 208.7372 -136.703054)
		(width 0.14224)
		(layer "In4.Cu")
		(net "M_E_DQ<9>")
	)
	(segment
		(start 207.611218 -141.715744)
		(end 207.611218 -142.076424)
		(width 0.14224)
		(layer "In4.Cu")
		(net "M_E_DQ<9>")
	)
	(segment
		(start 209.2198 -128.41986)
		(end 209.2198 -128.97866)
		(width 0.14224)
		(layer "In4.Cu")
		(net "M_E_DQ<9>")
	)
	(segment
		(start 211.9122 -116.815616)
		(end 212.1154 -117.018816)
		(width 0.14224)
		(layer "In4.Cu")
		(net "M_E_DQ<9>")
	)
	(segment
		(start 207.611218 -142.076424)
		(end 207.825594 -142.2908)
		(width 0.14224)
		(layer "In4.Cu")
		(net "M_E_DQ<9>")
	)
	(segment
		(start 208.407 -137.606024)
		(end 208.407 -138.012424)
		(width 0.14224)
		(layer "In4.Cu")
		(net "M_E_DQ<9>")
	)
	(segment
		(start 231.0892 -92.060776)
		(end 225.74377 -97.406206)
		(width 0.14224)
		(layer "In4.Cu")
		(net "M_E_DQ<9>")
	)
	(segment
		(start 211.1248 -117.831616)
		(end 211.1248 -125.349)
		(width 0.14224)
		(layer "In4.Cu")
		(net "M_E_DQ<9>")
	)
	(segment
		(start 208.8134 -131.978654)
		(end 208.8134 -132.54355)
		(width 0.14224)
		(layer "In4.Cu")
		(net "M_E_DQ<9>")
	)
	(segment
		(start 220.4974 -105.8418)
		(end 220.6752 -106.0196)
		(width 0.14224)
		(layer "In4.Cu")
		(net "M_E_DQ<9>")
	)
	(segment
		(start 207.901794 -141.425168)
		(end 207.611218 -141.715744)
		(width 0.14224)
		(layer "In4.Cu")
		(net "M_E_DQ<9>")
	)
	(segment
		(start 207.850994 -143.4846)
		(end 207.850994 -143.7894)
		(width 0.14224)
		(layer "In4.Cu")
		(net "M_E_DQ<9>")
	)
	(segment
		(start 219.837 -106.553)
		(end 219.59697 -106.79303)
		(width 0.14224)
		(layer "In4.Cu")
		(net "M_E_DQ<9>")
	)
	(segment
		(start 207.901794 -141.020546)
		(end 207.901794 -141.425168)
		(width 0.14224)
		(layer "In4.Cu")
		(net "M_E_DQ<9>")
	)
	(segment
		(start 208.7372 -136.703054)
		(end 208.7372 -137.275824)
		(width 0.14224)
		(layer "In4.Cu")
		(net "M_E_DQ<9>")
	)
	(segment
		(start 208.65846 -132.69849)
		(end 208.46034 -132.69849)
		(width 0.14224)
		(layer "In4.Cu")
		(net "M_E_DQ<9>")
	)
	(segment
		(start 232.776268 -90.200226)
		(end 232.776268 -90.757502)
		(width 0.0889)
		(layer "In4.Cu")
		(net "M_E_DQ<9>")
	)
	(segment
		(start 232.350564 -91.183206)
		(end 231.715564 -91.183206)
		(width 0.0889)
		(layer "In4.Cu")
		(net "M_E_DQ<9>")
	)
	(segment
		(start 219.59697 -105.202482)
		(end 219.59697 -105.7148)
		(width 0.14224)
		(layer "In4.Cu")
		(net "M_E_DQ<9>")
	)
	(segment
		(start 207.825594 -142.2908)
		(end 207.825594 -142.7226)
		(width 0.14224)
		(layer "In4.Cu")
		(net "M_E_DQ<9>")
	)
	(segment
		(start 212.1154 -117.425216)
		(end 211.9122 -117.628416)
		(width 0.14224)
		(layer "In4.Cu")
		(net "M_E_DQ<9>")
	)
	(segment
		(start 208.609946 -128.13792)
		(end 208.764886 -128.29286)
		(width 0.14224)
		(layer "In4.Cu")
		(net "M_E_DQ<9>")
	)
	(segment
		(start 225.74377 -99.055682)
		(end 219.59697 -105.202482)
		(width 0.14224)
		(layer "In4.Cu")
		(net "M_E_DQ<9>")
	)
	(segment
		(start 207.698848 -143.941546)
		(end 207.449928 -143.941546)
		(width 0.14224)
		(layer "In4.Cu")
		(net "M_E_DQ<9>")
	)
	(segment
		(start 207.611218 -143.244824)
		(end 207.850994 -143.4846)
		(width 0.14224)
		(layer "In4.Cu")
		(net "M_E_DQ<9>")
	)
	(segment
		(start 208.46034 -133.51129)
		(end 208.65846 -133.51129)
		(width 0.14224)
		(layer "In4.Cu")
		(net "M_E_DQ<9>")
	)
	(segment
		(start 208.407 -138.012424)
		(end 208.7372 -138.342624)
		(width 0.14224)
		(layer "In4.Cu")
		(net "M_E_DQ<9>")
	)
	(segment
		(start 208.764886 -129.10566)
		(end 208.609946 -129.2606)
		(width 0.14224)
		(layer "In4.Cu")
		(net "M_E_DQ<9>")
	)
	(segment
		(start 208.65846 -133.51129)
		(end 208.8134 -133.66623)
		(width 0.14224)
		(layer "In4.Cu")
		(net "M_E_DQ<9>")
	)
	(segment
		(start 208.764886 -128.29286)
		(end 209.0928 -128.29286)
		(width 0.14224)
		(layer "In4.Cu")
		(net "M_E_DQ<9>")
	)
	(segment
		(start 208.7372 -138.7856)
		(end 208.609946 -138.912854)
		(width 0.14224)
		(layer "In4.Cu")
		(net "M_E_DQ<9>")
	)
	(segment
		(start 231.715564 -91.183206)
		(end 231.0892 -91.80957)
		(width 0.0889)
		(layer "In4.Cu")
		(net "M_E_DQ<9>")
	)
	(segment
		(start 208.8134 -132.54355)
		(end 208.65846 -132.69849)
		(width 0.14224)
		(layer "In4.Cu")
		(net "M_E_DQ<9>")
	)
	(segment
		(start 207.850994 -143.7894)
		(end 207.698848 -143.941546)
		(width 0.14224)
		(layer "In4.Cu")
		(net "M_E_DQ<9>")
	)
	(segment
		(start 208.09966 -139.932156)
		(end 207.671416 -140.3604)
		(width 0.14224)
		(layer "In4.Cu")
		(net "M_E_DQ<9>")
	)
	(segment
		(start 208.609946 -138.912854)
		(end 208.609946 -139.355322)
		(width 0.14224)
		(layer "In4.Cu")
		(net "M_E_DQ<9>")
	)
	(segment
		(start 220.6752 -106.3244)
		(end 220.4466 -106.553)
		(width 0.14224)
		(layer "In4.Cu")
		(net "M_E_DQ<9>")
	)
	(segment
		(start 208.3054 -132.85343)
		(end 208.3054 -133.35635)
		(width 0.14224)
		(layer "In4.Cu")
		(net "M_E_DQ<9>")
	)
	(segment
		(start 207.671416 -140.790168)
		(end 207.901794 -141.020546)
		(width 0.14224)
		(layer "In4.Cu")
		(net "M_E_DQ<9>")
	)
	(segment
		(start 219.59697 -105.7148)
		(end 219.72397 -105.8418)
		(width 0.14224)
		(layer "In4.Cu")
		(net "M_E_DQ<9>")
	)
	(segment
		(start 234.775248 -88.375236)
		(end 234.742482 -88.375236)
		(width 0.0889)
		(layer "In4.Cu")
		(net "M_E_DQ<9>")
	)
	(segment
		(start 219.72397 -105.8418)
		(end 220.4974 -105.8418)
		(width 0.14224)
		(layer "In4.Cu")
		(net "M_E_DQ<9>")
	)
	(segment
		(start 207.825594 -142.7226)
		(end 207.611218 -142.936976)
		(width 0.14224)
		(layer "In4.Cu")
		(net "M_E_DQ<9>")
	)
	(segment
		(start 207.671416 -140.3604)
		(end 207.671416 -140.790168)
		(width 0.14224)
		(layer "In4.Cu")
		(net "M_E_DQ<9>")
	)
	(arc
		(start 235.597192 -87.88019)
		(mid 235.40555 -87.937356)
		(end 235.265468 -88.080088)
		(width 0.0889)
		(layer "In4.Cu")
		(net "M_E_DQ<9>")
	)
	(arc
		(start 234.406948 -88.575388)
		(mid 234.19834 -88.78732)
		(end 233.912918 -88.87079)
		(width 0.0889)
		(layer "In4.Cu")
		(net "M_E_DQ<9>")
	)
	(arc
		(start 234.742482 -88.375236)
		(mid 234.548632 -88.431586)
		(end 234.406948 -88.575388)
		(width 0.0889)
		(layer "In4.Cu")
		(net "M_E_DQ<9>")
	)
	(arc
		(start 233.548428 -89.070688)
		(mid 233.341424 -89.281552)
		(end 233.058208 -89.365836)
		(width 0.0889)
		(layer "In4.Cu")
		(net "M_E_DQ<9>")
	)
	(arc
		(start 232.870248 -89.365836)
		(mid 232.628842 -89.61947)
		(end 232.653586 -89.968832)
		(width 0.0889)
		(layer "In4.Cu")
		(net "M_E_DQ<9>")
	)
	(arc
		(start 233.880152 -88.87079)
		(mid 233.68851 -88.927956)
		(end 233.548428 -89.070688)
		(width 0.0889)
		(layer "In4.Cu")
		(net "M_E_DQ<9>")
	)
	(arc
		(start 235.958888 -88.080088)
		(mid 235.818809 -87.937352)
		(end 235.627164 -87.88019)
		(width 0.0889)
		(layer "In4.Cu")
		(net "M_E_DQ<9>")
	)
	(arc
		(start 235.265468 -88.080088)
		(mid 235.058464 -88.290952)
		(end 234.775248 -88.375236)
		(width 0.0889)
		(layer "In4.Cu")
		(net "M_E_DQ<9>")
	)
	(segment
		(start 238.759238 -89.765886)
		(end 238.187738 -89.765886)
		(width 0.1651)
		(layer "F.Cu")
		(net "M_E_DQ<8>")
	)
	(segment
		(start 208.299812 -147.277582)
		(end 208.122012 -145.415)
		(width 0.1651)
		(layer "F.Cu")
		(net "M_E_DQ<8>")
	)
	(segment
		(start 208.30032 -147.27174)
		(end 208.299812 -147.277582)
		(width 0.1651)
		(layer "F.Cu")
		(net "M_E_DQ<8>")
	)
	(via
		(at 238.187738 -89.765886)
		(size 0.508)
		(drill 0.254)
		(layers "F.Cu" "B.Cu")
		(net "M_E_DQ<8>")
	)
	(via
		(at 207.449928 -141.213078)
		(size 0.508)
		(drill 0.254)
		(layers "F.Cu" "B.Cu")
		(net "M_E_DQ<8>")
	)
	(via
		(at 208.122012 -145.415)
		(size 0.508)
		(drill 0.254)
		(layers "F.Cu" "B.Cu")
		(net "M_E_DQ<8>")
	)
	(segment
		(start 207.449928 -142.476982)
		(end 207.449928 -141.213078)
		(width 0.1651)
		(layer "B.Cu")
		(net "M_E_DQ<8>")
	)
	(segment
		(start 207.450436 -142.477236)
		(end 207.449928 -142.476982)
		(width 0.1651)
		(layer "B.Cu")
		(net "M_E_DQ<8>")
	)
	(segment
		(start 234.768644 -88.184736)
		(end 234.735878 -88.184736)
		(width 0.0889)
		(layer "In4.Cu")
		(net "M_E_DQ<8>")
	)
	(segment
		(start 236.470698 -88.184736)
		(end 236.455712 -88.184736)
		(width 0.0889)
		(layer "In4.Cu")
		(net "M_E_DQ<8>")
	)
	(segment
		(start 207.936846 -136.258046)
		(end 207.936846 -136.652)
		(width 0.14224)
		(layer "In4.Cu")
		(net "M_E_DQ<8>")
	)
	(segment
		(start 207.085946 -140.849096)
		(end 207.449928 -141.213078)
		(width 0.14224)
		(layer "In4.Cu")
		(net "M_E_DQ<8>")
	)
	(segment
		(start 230.649018 -91.602814)
		(end 225.26498 -96.986852)
		(width 0.14224)
		(layer "In4.Cu")
		(net "M_E_DQ<8>")
	)
	(segment
		(start 208.138776 -129.503424)
		(end 207.632046 -130.010154)
		(width 0.14224)
		(layer "In4.Cu")
		(net "M_E_DQ<8>")
	)
	(segment
		(start 207.8736 -134.0866)
		(end 207.924146 -134.137146)
		(width 0.14224)
		(layer "In4.Cu")
		(net "M_E_DQ<8>")
	)
	(segment
		(start 207.016858 -141.646148)
		(end 207.016858 -144.60601)
		(width 0.14224)
		(layer "In4.Cu")
		(net "M_E_DQ<8>")
	)
	(segment
		(start 208.138776 -127.446024)
		(end 208.138776 -129.503424)
		(width 0.14224)
		(layer "In4.Cu")
		(net "M_E_DQ<8>")
	)
	(segment
		(start 225.26498 -98.857308)
		(end 219.11818 -105.004108)
		(width 0.14224)
		(layer "In4.Cu")
		(net "M_E_DQ<8>")
	)
	(segment
		(start 207.62722 -134.781544)
		(end 207.62722 -135.94842)
		(width 0.14224)
		(layer "In4.Cu")
		(net "M_E_DQ<8>")
	)
	(segment
		(start 207.8736 -131.978146)
		(end 207.8736 -134.0866)
		(width 0.14224)
		(layer "In4.Cu")
		(net "M_E_DQ<8>")
	)
	(segment
		(start 225.26498 -96.986852)
		(end 225.26498 -98.857308)
		(width 0.14224)
		(layer "In4.Cu")
		(net "M_E_DQ<8>")
	)
	(segment
		(start 236.817408 -88.575388)
		(end 236.652816 -88.289892)
		(width 0.0889)
		(layer "In4.Cu")
		(net "M_E_DQ<8>")
	)
	(segment
		(start 237.344204 -88.87079)
		(end 237.311438 -88.87079)
		(width 0.0889)
		(layer "In4.Cu")
		(net "M_E_DQ<8>")
	)
	(segment
		(start 235.633768 -87.68969)
		(end 235.590588 -87.68969)
		(width 0.0889)
		(layer "In4.Cu")
		(net "M_E_DQ<8>")
	)
	(segment
		(start 207.62722 -135.94842)
		(end 207.936846 -136.258046)
		(width 0.14224)
		(layer "In4.Cu")
		(net "M_E_DQ<8>")
	)
	(segment
		(start 233.051604 -89.175336)
		(end 232.833926 -89.175336)
		(width 0.0889)
		(layer "In4.Cu")
		(net "M_E_DQ<8>")
	)
	(segment
		(start 210.4898 -116.87556)
		(end 210.714336 -117.100096)
		(width 0.14224)
		(layer "In4.Cu")
		(net "M_E_DQ<8>")
	)
	(segment
		(start 233.906314 -88.68029)
		(end 233.873548 -88.68029)
		(width 0.0889)
		(layer "In4.Cu")
		(net "M_E_DQ<8>")
	)
	(segment
		(start 207.8736 -138.9126)
		(end 207.936846 -138.975846)
		(width 0.14224)
		(layer "In4.Cu")
		(net "M_E_DQ<8>")
	)
	(segment
		(start 210.714336 -117.343936)
		(end 210.4898 -117.568472)
		(width 0.14224)
		(layer "In4.Cu")
		(net "M_E_DQ<8>")
	)
	(segment
		(start 207.936846 -136.652)
		(end 207.8736 -136.715246)
		(width 0.14224)
		(layer "In4.Cu")
		(net "M_E_DQ<8>")
	)
	(segment
		(start 207.924146 -134.484618)
		(end 207.62722 -134.781544)
		(width 0.14224)
		(layer "In4.Cu")
		(net "M_E_DQ<8>")
	)
	(segment
		(start 207.936846 -138.975846)
		(end 207.936846 -139.358878)
		(width 0.14224)
		(layer "In4.Cu")
		(net "M_E_DQ<8>")
	)
	(segment
		(start 207.924146 -134.137146)
		(end 207.924146 -134.484618)
		(width 0.14224)
		(layer "In4.Cu")
		(net "M_E_DQ<8>")
	)
	(segment
		(start 210.4898 -125.095)
		(end 208.138776 -127.446024)
		(width 0.14224)
		(layer "In4.Cu")
		(net "M_E_DQ<8>")
	)
	(segment
		(start 207.449928 -141.213078)
		(end 207.016858 -141.646148)
		(width 0.14224)
		(layer "In4.Cu")
		(net "M_E_DQ<8>")
	)
	(segment
		(start 232.48493 -90.058494)
		(end 232.586276 -90.247978)
		(width 0.0889)
		(layer "In4.Cu")
		(net "M_E_DQ<8>")
	)
	(segment
		(start 207.9244 -131.434332)
		(end 207.9244 -131.927346)
		(width 0.14224)
		(layer "In4.Cu")
		(net "M_E_DQ<8>")
	)
	(segment
		(start 219.11818 -106.28122)
		(end 210.4898 -114.9096)
		(width 0.14224)
		(layer "In4.Cu")
		(net "M_E_DQ<8>")
	)
	(segment
		(start 207.632046 -131.141978)
		(end 207.9244 -131.434332)
		(width 0.14224)
		(layer "In4.Cu")
		(net "M_E_DQ<8>")
	)
	(segment
		(start 231.636824 -90.993214)
		(end 231.027224 -91.602814)
		(width 0.0889)
		(layer "In4.Cu")
		(net "M_E_DQ<8>")
	)
	(segment
		(start 207.632046 -130.010154)
		(end 207.632046 -131.141978)
		(width 0.14224)
		(layer "In4.Cu")
		(net "M_E_DQ<8>")
	)
	(segment
		(start 232.271824 -90.993214)
		(end 231.636824 -90.993214)
		(width 0.0889)
		(layer "In4.Cu")
		(net "M_E_DQ<8>")
	)
	(segment
		(start 237.692692 -89.100152)
		(end 237.675928 -89.070688)
		(width 0.0889)
		(layer "In4.Cu")
		(net "M_E_DQ<8>")
	)
	(segment
		(start 210.4898 -114.9096)
		(end 210.4898 -116.87556)
		(width 0.14224)
		(layer "In4.Cu")
		(net "M_E_DQ<8>")
	)
	(segment
		(start 207.8736 -136.715246)
		(end 207.8736 -138.9126)
		(width 0.14224)
		(layer "In4.Cu")
		(net "M_E_DQ<8>")
	)
	(segment
		(start 232.586276 -90.247978)
		(end 232.586276 -90.678762)
		(width 0.0889)
		(layer "In4.Cu")
		(net "M_E_DQ<8>")
	)
	(segment
		(start 238.187738 -89.765886)
		(end 237.692692 -89.100152)
		(width 0.0889)
		(layer "In4.Cu")
		(net "M_E_DQ<8>")
	)
	(segment
		(start 231.027224 -91.602814)
		(end 230.649018 -91.602814)
		(width 0.0889)
		(layer "In4.Cu")
		(net "M_E_DQ<8>")
	)
	(segment
		(start 207.016858 -144.60601)
		(end 207.825848 -145.415)
		(width 0.14224)
		(layer "In4.Cu")
		(net "M_E_DQ<8>")
	)
	(segment
		(start 207.825848 -145.415)
		(end 208.122012 -145.415)
		(width 0.14224)
		(layer "In4.Cu")
		(net "M_E_DQ<8>")
	)
	(segment
		(start 207.085946 -140.209778)
		(end 207.085946 -140.849096)
		(width 0.14224)
		(layer "In4.Cu")
		(net "M_E_DQ<8>")
	)
	(segment
		(start 207.9244 -131.927346)
		(end 207.8736 -131.978146)
		(width 0.14224)
		(layer "In4.Cu")
		(net "M_E_DQ<8>")
	)
	(segment
		(start 210.4898 -117.568472)
		(end 210.4898 -125.095)
		(width 0.14224)
		(layer "In4.Cu")
		(net "M_E_DQ<8>")
	)
	(segment
		(start 207.936846 -139.358878)
		(end 207.085946 -140.209778)
		(width 0.14224)
		(layer "In4.Cu")
		(net "M_E_DQ<8>")
	)
	(segment
		(start 210.714336 -117.100096)
		(end 210.714336 -117.343936)
		(width 0.14224)
		(layer "In4.Cu")
		(net "M_E_DQ<8>")
	)
	(segment
		(start 232.586276 -90.678762)
		(end 232.271824 -90.993214)
		(width 0.0889)
		(layer "In4.Cu")
		(net "M_E_DQ<8>")
	)
	(segment
		(start 219.11818 -105.004108)
		(end 219.11818 -106.28122)
		(width 0.14224)
		(layer "In4.Cu")
		(net "M_E_DQ<8>")
	)
	(arc
		(start 234.735878 -88.184736)
		(mid 234.450454 -88.268203)
		(end 234.241848 -88.480138)
		(width 0.0889)
		(layer "In4.Cu")
		(net "M_E_DQ<8>")
	)
	(arc
		(start 237.311438 -88.87079)
		(mid 237.026014 -88.787323)
		(end 236.817408 -88.575388)
		(width 0.0889)
		(layer "In4.Cu")
		(net "M_E_DQ<8>")
	)
	(arc
		(start 235.100368 -87.984838)
		(mid 234.960289 -88.127574)
		(end 234.768644 -88.184736)
		(width 0.0889)
		(layer "In4.Cu")
		(net "M_E_DQ<8>")
	)
	(arc
		(start 233.873548 -88.68029)
		(mid 233.590331 -88.764571)
		(end 233.383328 -88.975438)
		(width 0.0889)
		(layer "In4.Cu")
		(net "M_E_DQ<8>")
	)
	(arc
		(start 237.675928 -89.070688)
		(mid 237.535849 -88.927952)
		(end 237.344204 -88.87079)
		(width 0.0889)
		(layer "In4.Cu")
		(net "M_E_DQ<8>")
	)
	(arc
		(start 235.590588 -87.68969)
		(mid 235.307371 -87.773971)
		(end 235.100368 -87.984838)
		(width 0.0889)
		(layer "In4.Cu")
		(net "M_E_DQ<8>")
	)
	(arc
		(start 236.455712 -88.184736)
		(mid 236.26407 -88.12757)
		(end 236.123988 -87.984838)
		(width 0.0889)
		(layer "In4.Cu")
		(net "M_E_DQ<8>")
	)
	(arc
		(start 236.652816 -88.289892)
		(mid 236.575843 -88.212923)
		(end 236.470698 -88.184736)
		(width 0.0889)
		(layer "In4.Cu")
		(net "M_E_DQ<8>")
	)
	(arc
		(start 233.383328 -88.975438)
		(mid 233.243249 -89.118174)
		(end 233.051604 -89.175336)
		(width 0.0889)
		(layer "In4.Cu")
		(net "M_E_DQ<8>")
	)
	(arc
		(start 236.123988 -87.984838)
		(mid 235.916984 -87.773974)
		(end 235.633768 -87.68969)
		(width 0.0889)
		(layer "In4.Cu")
		(net "M_E_DQ<8>")
	)
	(arc
		(start 234.241848 -88.480138)
		(mid 234.100165 -88.623942)
		(end 233.906314 -88.68029)
		(width 0.0889)
		(layer "In4.Cu")
		(net "M_E_DQ<8>")
	)
	(arc
		(start 232.833926 -89.175336)
		(mid 232.455928 -89.536469)
		(end 232.48493 -90.058494)
		(width 0.0889)
		(layer "In4.Cu")
		(net "M_E_DQ<8>")
	)
	(segment
		(start 202.349862 -142.677642)
		(end 202.349862 -143.941546)
		(width 0.1651)
		(layer "F.Cu")
		(net "M_E_DQ<7>")
	)
	(segment
		(start 236.183678 -85.30844)
		(end 235.612178 -85.30844)
		(width 0.1651)
		(layer "F.Cu")
		(net "M_E_DQ<7>")
	)
	(segment
		(start 202.35037 -142.6718)
		(end 202.349862 -142.677642)
		(width 0.1651)
		(layer "F.Cu")
		(net "M_E_DQ<7>")
	)
	(via
		(at 203.199746 -139.932156)
		(size 0.508)
		(drill 0.254)
		(layers "F.Cu" "B.Cu")
		(net "M_E_DQ<7>")
	)
	(via
		(at 235.612178 -85.30844)
		(size 0.508)
		(drill 0.254)
		(layers "F.Cu" "B.Cu")
		(net "M_E_DQ<7>")
	)
	(via
		(at 202.349862 -143.941546)
		(size 0.508)
		(drill 0.254)
		(layers "F.Cu" "B.Cu")
		(net "M_E_DQ<7>")
	)
	(segment
		(start 203.199746 -137.877296)
		(end 203.199746 -139.932156)
		(width 0.1651)
		(layer "B.Cu")
		(net "M_E_DQ<7>")
	)
	(segment
		(start 203.200508 -137.877296)
		(end 203.199746 -137.877296)
		(width 0.1651)
		(layer "B.Cu")
		(net "M_E_DQ<7>")
	)
	(segment
		(start 229.60584 -87.234014)
		(end 222.325184 -94.51467)
		(width 0.14224)
		(layer "In4.Cu")
		(net "M_E_DQ<7>")
	)
	(segment
		(start 202.74915 -140.3604)
		(end 202.74915 -140.790168)
		(width 0.14224)
		(layer "In4.Cu")
		(net "M_E_DQ<7>")
	)
	(segment
		(start 203.552552 -138.941048)
		(end 203.552552 -139.590272)
		(width 0.14224)
		(layer "In4.Cu")
		(net "M_E_DQ<7>")
	)
	(segment
		(start 203.79944 -118.50878)
		(end 203.6572 -118.65102)
		(width 0.14224)
		(layer "In4.Cu")
		(net "M_E_DQ<7>")
	)
	(segment
		(start 203.79944 -117.85854)
		(end 205.29296 -117.85854)
		(width 0.14224)
		(layer "In4.Cu")
		(net "M_E_DQ<7>")
	)
	(segment
		(start 203.177394 -139.932156)
		(end 202.74915 -140.3604)
		(width 0.14224)
		(layer "In4.Cu")
		(net "M_E_DQ<7>")
	)
	(segment
		(start 205.29296 -117.85854)
		(end 205.4352 -118.00078)
		(width 0.14224)
		(layer "In4.Cu")
		(net "M_E_DQ<7>")
	)
	(segment
		(start 203.6572 -118.65102)
		(end 203.6572 -119.01678)
		(width 0.14224)
		(layer "In4.Cu")
		(net "M_E_DQ<7>")
	)
	(segment
		(start 202.511152 -141.785848)
		(end 202.511152 -142.059152)
		(width 0.14224)
		(layer "In4.Cu")
		(net "M_E_DQ<7>")
	)
	(segment
		(start 203.79944 -121.10974)
		(end 203.6572 -121.25198)
		(width 0.14224)
		(layer "In4.Cu")
		(net "M_E_DQ<7>")
	)
	(segment
		(start 232.195878 -86.88959)
		(end 231.920542 -86.88959)
		(width 0.0889)
		(layer "In4.Cu")
		(net "M_E_DQ<7>")
	)
	(segment
		(start 202.79995 -143.44015)
		(end 202.79995 -143.763746)
		(width 0.14224)
		(layer "In4.Cu")
		(net "M_E_DQ<7>")
	)
	(segment
		(start 230.126032 -86.992206)
		(end 229.884224 -87.234014)
		(width 0.0889)
		(layer "In4.Cu")
		(net "M_E_DQ<7>")
	)
	(segment
		(start 203.552552 -136.572752)
		(end 203.6318 -136.652)
		(width 0.14224)
		(layer "In4.Cu")
		(net "M_E_DQ<7>")
	)
	(segment
		(start 203.6318 -131.981448)
		(end 203.6318 -134.0358)
		(width 0.14224)
		(layer "In4.Cu")
		(net "M_E_DQ<7>")
	)
	(segment
		(start 233.912918 -85.89899)
		(end 233.880152 -85.89899)
		(width 0.0889)
		(layer "In4.Cu")
		(net "M_E_DQ<7>")
	)
	(segment
		(start 205.4352 -122.26798)
		(end 205.29296 -122.41022)
		(width 0.14224)
		(layer "In4.Cu")
		(net "M_E_DQ<7>")
	)
	(segment
		(start 203.869544 -116.92509)
		(end 203.6572 -117.137434)
		(width 0.14224)
		(layer "In4.Cu")
		(net "M_E_DQ<7>")
	)
	(segment
		(start 203.6572 -119.9515)
		(end 203.6572 -120.31726)
		(width 0.14224)
		(layer "In4.Cu")
		(net "M_E_DQ<7>")
	)
	(segment
		(start 203.79944 -121.75998)
		(end 205.29296 -121.75998)
		(width 0.14224)
		(layer "In4.Cu")
		(net "M_E_DQ<7>")
	)
	(segment
		(start 205.29296 -120.4595)
		(end 205.4352 -120.60174)
		(width 0.14224)
		(layer "In4.Cu")
		(net "M_E_DQ<7>")
	)
	(segment
		(start 203.577952 -134.089648)
		(end 203.577952 -134.539482)
		(width 0.14224)
		(layer "In4.Cu")
		(net "M_E_DQ<7>")
	)
	(segment
		(start 203.6572 -122.55246)
		(end 203.6572 -129.232152)
		(width 0.14224)
		(layer "In4.Cu")
		(net "M_E_DQ<7>")
	)
	(segment
		(start 206.9084 -114.5794)
		(end 206.492856 -114.994944)
		(width 0.14224)
		(layer "In4.Cu")
		(net "M_E_DQ<7>")
	)
	(segment
		(start 205.29296 -121.10974)
		(end 203.79944 -121.10974)
		(width 0.14224)
		(layer "In4.Cu")
		(net "M_E_DQ<7>")
	)
	(segment
		(start 205.4352 -119.66702)
		(end 205.29296 -119.80926)
		(width 0.14224)
		(layer "In4.Cu")
		(net "M_E_DQ<7>")
	)
	(segment
		(start 203.721716 -136.07923)
		(end 203.552552 -136.248394)
		(width 0.14224)
		(layer "In4.Cu")
		(net "M_E_DQ<7>")
	)
	(segment
		(start 234.790742 -85.403436)
		(end 234.742482 -85.403436)
		(width 0.0889)
		(layer "In4.Cu")
		(net "M_E_DQ<7>")
	)
	(segment
		(start 203.552552 -139.590272)
		(end 203.54163 -139.590272)
		(width 0.14224)
		(layer "In4.Cu")
		(net "M_E_DQ<7>")
	)
	(segment
		(start 233.058208 -86.394036)
		(end 233.025442 -86.394036)
		(width 0.0889)
		(layer "In4.Cu")
		(net "M_E_DQ<7>")
	)
	(segment
		(start 202.7936 -141.5034)
		(end 202.511152 -141.785848)
		(width 0.14224)
		(layer "In4.Cu")
		(net "M_E_DQ<7>")
	)
	(segment
		(start 203.54163 -139.590272)
		(end 203.199746 -139.932156)
		(width 0.14224)
		(layer "In4.Cu")
		(net "M_E_DQ<7>")
	)
	(segment
		(start 205.4352 -118.36654)
		(end 205.29296 -118.50878)
		(width 0.14224)
		(layer "In4.Cu")
		(net "M_E_DQ<7>")
	)
	(segment
		(start 203.721716 -134.683246)
		(end 203.721716 -136.07923)
		(width 0.14224)
		(layer "In4.Cu")
		(net "M_E_DQ<7>")
	)
	(segment
		(start 202.511152 -142.878048)
		(end 202.511152 -143.151352)
		(width 0.14224)
		(layer "In4.Cu")
		(net "M_E_DQ<7>")
	)
	(segment
		(start 210.125818 -110.142528)
		(end 210.125818 -110.668816)
		(width 0.14224)
		(layer "In4.Cu")
		(net "M_E_DQ<7>")
	)
	(segment
		(start 202.62215 -143.941546)
		(end 202.349862 -143.941546)
		(width 0.14224)
		(layer "In4.Cu")
		(net "M_E_DQ<7>")
	)
	(segment
		(start 206.9084 -113.886234)
		(end 206.9084 -114.5794)
		(width 0.14224)
		(layer "In4.Cu")
		(net "M_E_DQ<7>")
	)
	(segment
		(start 205.29296 -121.75998)
		(end 205.4352 -121.90222)
		(width 0.14224)
		(layer "In4.Cu")
		(net "M_E_DQ<7>")
	)
	(segment
		(start 203.6318 -136.652)
		(end 203.6318 -138.8618)
		(width 0.14224)
		(layer "In4.Cu")
		(net "M_E_DQ<7>")
	)
	(segment
		(start 203.501752 -131.8514)
		(end 203.6318 -131.981448)
		(width 0.14224)
		(layer "In4.Cu")
		(net "M_E_DQ<7>")
	)
	(segment
		(start 203.79944 -122.41022)
		(end 203.6572 -122.55246)
		(width 0.14224)
		(layer "In4.Cu")
		(net "M_E_DQ<7>")
	)
	(segment
		(start 205.4352 -119.30126)
		(end 205.4352 -119.66702)
		(width 0.14224)
		(layer "In4.Cu")
		(net "M_E_DQ<7>")
	)
	(segment
		(start 202.7936 -140.834618)
		(end 202.7936 -141.5034)
		(width 0.14224)
		(layer "In4.Cu")
		(net "M_E_DQ<7>")
	)
	(segment
		(start 202.74915 -140.790168)
		(end 202.7936 -140.834618)
		(width 0.14224)
		(layer "In4.Cu")
		(net "M_E_DQ<7>")
	)
	(segment
		(start 203.577952 -134.539482)
		(end 203.721716 -134.683246)
		(width 0.14224)
		(layer "In4.Cu")
		(net "M_E_DQ<7>")
	)
	(segment
		(start 202.511152 -143.151352)
		(end 202.79995 -143.44015)
		(width 0.14224)
		(layer "In4.Cu")
		(net "M_E_DQ<7>")
	)
	(segment
		(start 203.199746 -139.932156)
		(end 203.177394 -139.932156)
		(width 0.14224)
		(layer "In4.Cu")
		(net "M_E_DQ<7>")
	)
	(segment
		(start 205.4352 -120.60174)
		(end 205.4352 -120.9675)
		(width 0.14224)
		(layer "In4.Cu")
		(net "M_E_DQ<7>")
	)
	(segment
		(start 203.781152 -130.087878)
		(end 203.781152 -131.205478)
		(width 0.14224)
		(layer "In4.Cu")
		(net "M_E_DQ<7>")
	)
	(segment
		(start 235.612178 -85.30844)
		(end 234.790742 -85.403436)
		(width 0.0889)
		(layer "In4.Cu")
		(net "M_E_DQ<7>")
	)
	(segment
		(start 203.6572 -120.31726)
		(end 203.79944 -120.4595)
		(width 0.14224)
		(layer "In4.Cu")
		(net "M_E_DQ<7>")
	)
	(segment
		(start 205.29296 -119.15902)
		(end 205.4352 -119.30126)
		(width 0.14224)
		(layer "In4.Cu")
		(net "M_E_DQ<7>")
	)
	(segment
		(start 203.6572 -117.137434)
		(end 203.6572 -117.7163)
		(width 0.14224)
		(layer "In4.Cu")
		(net "M_E_DQ<7>")
	)
	(segment
		(start 205.29296 -122.41022)
		(end 203.79944 -122.41022)
		(width 0.14224)
		(layer "In4.Cu")
		(net "M_E_DQ<7>")
	)
	(segment
		(start 203.552552 -129.859278)
		(end 203.781152 -130.087878)
		(width 0.14224)
		(layer "In4.Cu")
		(net "M_E_DQ<7>")
	)
	(segment
		(start 203.6318 -134.0358)
		(end 203.577952 -134.089648)
		(width 0.14224)
		(layer "In4.Cu")
		(net "M_E_DQ<7>")
	)
	(segment
		(start 231.817926 -86.992206)
		(end 230.126032 -86.992206)
		(width 0.0889)
		(layer "In4.Cu")
		(net "M_E_DQ<7>")
	)
	(segment
		(start 205.29296 -119.80926)
		(end 203.79944 -119.80926)
		(width 0.14224)
		(layer "In4.Cu")
		(net "M_E_DQ<7>")
	)
	(segment
		(start 203.6572 -121.61774)
		(end 203.79944 -121.75998)
		(width 0.14224)
		(layer "In4.Cu")
		(net "M_E_DQ<7>")
	)
	(segment
		(start 206.492856 -114.994944)
		(end 205.79969 -114.994944)
		(width 0.14224)
		(layer "In4.Cu")
		(net "M_E_DQ<7>")
	)
	(segment
		(start 222.325184 -97.943162)
		(end 210.125818 -110.142528)
		(width 0.14224)
		(layer "In4.Cu")
		(net "M_E_DQ<7>")
	)
	(segment
		(start 205.4352 -120.9675)
		(end 205.29296 -121.10974)
		(width 0.14224)
		(layer "In4.Cu")
		(net "M_E_DQ<7>")
	)
	(segment
		(start 205.2574 -115.537234)
		(end 205.2574 -116.179346)
		(width 0.14224)
		(layer "In4.Cu")
		(net "M_E_DQ<7>")
	)
	(segment
		(start 203.6572 -129.232152)
		(end 203.552552 -129.3368)
		(width 0.14224)
		(layer "In4.Cu")
		(net "M_E_DQ<7>")
	)
	(segment
		(start 202.7682 -142.3162)
		(end 202.7682 -142.621)
		(width 0.14224)
		(layer "In4.Cu")
		(net "M_E_DQ<7>")
	)
	(segment
		(start 203.6318 -138.8618)
		(end 203.552552 -138.941048)
		(width 0.14224)
		(layer "In4.Cu")
		(net "M_E_DQ<7>")
	)
	(segment
		(start 203.79944 -119.80926)
		(end 203.6572 -119.9515)
		(width 0.14224)
		(layer "In4.Cu")
		(net "M_E_DQ<7>")
	)
	(segment
		(start 205.4352 -121.90222)
		(end 205.4352 -122.26798)
		(width 0.14224)
		(layer "In4.Cu")
		(net "M_E_DQ<7>")
	)
	(segment
		(start 203.6572 -121.25198)
		(end 203.6572 -121.61774)
		(width 0.14224)
		(layer "In4.Cu")
		(net "M_E_DQ<7>")
	)
	(segment
		(start 205.29296 -118.50878)
		(end 203.79944 -118.50878)
		(width 0.14224)
		(layer "In4.Cu")
		(net "M_E_DQ<7>")
	)
	(segment
		(start 231.920542 -86.88959)
		(end 231.817926 -86.992206)
		(width 0.0889)
		(layer "In4.Cu")
		(net "M_E_DQ<7>")
	)
	(segment
		(start 202.7682 -142.621)
		(end 202.511152 -142.878048)
		(width 0.14224)
		(layer "In4.Cu")
		(net "M_E_DQ<7>")
	)
	(segment
		(start 203.552552 -136.248394)
		(end 203.552552 -136.572752)
		(width 0.14224)
		(layer "In4.Cu")
		(net "M_E_DQ<7>")
	)
	(segment
		(start 205.4352 -118.00078)
		(end 205.4352 -118.36654)
		(width 0.14224)
		(layer "In4.Cu")
		(net "M_E_DQ<7>")
	)
	(segment
		(start 203.79944 -119.15902)
		(end 205.29296 -119.15902)
		(width 0.14224)
		(layer "In4.Cu")
		(net "M_E_DQ<7>")
	)
	(segment
		(start 203.6572 -119.01678)
		(end 203.79944 -119.15902)
		(width 0.14224)
		(layer "In4.Cu")
		(net "M_E_DQ<7>")
	)
	(segment
		(start 205.79969 -114.994944)
		(end 205.2574 -115.537234)
		(width 0.14224)
		(layer "In4.Cu")
		(net "M_E_DQ<7>")
	)
	(segment
		(start 203.781152 -131.205478)
		(end 203.501752 -131.484878)
		(width 0.14224)
		(layer "In4.Cu")
		(net "M_E_DQ<7>")
	)
	(segment
		(start 210.125818 -110.668816)
		(end 206.9084 -113.886234)
		(width 0.14224)
		(layer "In4.Cu")
		(net "M_E_DQ<7>")
	)
	(segment
		(start 203.552552 -129.3368)
		(end 203.552552 -129.859278)
		(width 0.14224)
		(layer "In4.Cu")
		(net "M_E_DQ<7>")
	)
	(segment
		(start 203.501752 -131.484878)
		(end 203.501752 -131.8514)
		(width 0.14224)
		(layer "In4.Cu")
		(net "M_E_DQ<7>")
	)
	(segment
		(start 205.2574 -116.179346)
		(end 204.511656 -116.92509)
		(width 0.14224)
		(layer "In4.Cu")
		(net "M_E_DQ<7>")
	)
	(segment
		(start 222.325184 -94.51467)
		(end 222.325184 -97.943162)
		(width 0.14224)
		(layer "In4.Cu")
		(net "M_E_DQ<7>")
	)
	(segment
		(start 229.884224 -87.234014)
		(end 229.60584 -87.234014)
		(width 0.14224)
		(layer "In4.Cu")
		(net "M_E_DQ<7>")
	)
	(segment
		(start 202.79995 -143.763746)
		(end 202.62215 -143.941546)
		(width 0.14224)
		(layer "In4.Cu")
		(net "M_E_DQ<7>")
	)
	(segment
		(start 202.511152 -142.059152)
		(end 202.7682 -142.3162)
		(width 0.14224)
		(layer "In4.Cu")
		(net "M_E_DQ<7>")
	)
	(segment
		(start 204.511656 -116.92509)
		(end 203.869544 -116.92509)
		(width 0.14224)
		(layer "In4.Cu")
		(net "M_E_DQ<7>")
	)
	(segment
		(start 203.79944 -120.4595)
		(end 205.29296 -120.4595)
		(width 0.14224)
		(layer "In4.Cu")
		(net "M_E_DQ<7>")
	)
	(segment
		(start 203.6572 -117.7163)
		(end 203.79944 -117.85854)
		(width 0.14224)
		(layer "In4.Cu")
		(net "M_E_DQ<7>")
	)
	(arc
		(start 233.880152 -85.89899)
		(mid 233.68851 -85.956156)
		(end 233.548428 -86.098888)
		(width 0.0889)
		(layer "In4.Cu")
		(net "M_E_DQ<7>")
	)
	(arc
		(start 234.406948 -85.603588)
		(mid 234.19834 -85.81552)
		(end 233.912918 -85.89899)
		(width 0.0889)
		(layer "In4.Cu")
		(net "M_E_DQ<7>")
	)
	(arc
		(start 233.548428 -86.098888)
		(mid 233.341424 -86.309752)
		(end 233.058208 -86.394036)
		(width 0.0889)
		(layer "In4.Cu")
		(net "M_E_DQ<7>")
	)
	(arc
		(start 232.689908 -86.594188)
		(mid 232.4813 -86.80612)
		(end 232.195878 -86.88959)
		(width 0.0889)
		(layer "In4.Cu")
		(net "M_E_DQ<7>")
	)
	(arc
		(start 234.742482 -85.403436)
		(mid 234.548632 -85.459786)
		(end 234.406948 -85.603588)
		(width 0.0889)
		(layer "In4.Cu")
		(net "M_E_DQ<7>")
	)
	(arc
		(start 233.025442 -86.394036)
		(mid 232.831592 -86.450386)
		(end 232.689908 -86.594188)
		(width 0.0889)
		(layer "In4.Cu")
		(net "M_E_DQ<7>")
	)
	(segment
		(start 203.33208 -146.17192)
		(end 203.33208 -145.95348)
		(width 0.1651)
		(layer "F.Cu")
		(net "M_E_DQ<6>")
	)
	(segment
		(start 203.2 -145.516854)
		(end 203.199746 -145.5166)
		(width 0.1651)
		(layer "F.Cu")
		(net "M_E_DQ<6>")
	)
	(segment
		(start 237.900718 -86.29904)
		(end 237.329218 -86.29904)
		(width 0.1651)
		(layer "F.Cu")
		(net "M_E_DQ<6>")
	)
	(segment
		(start 203.200508 -147.27174)
		(end 203.2 -147.27174)
		(width 0.1651)
		(layer "F.Cu")
		(net "M_E_DQ<6>")
	)
	(segment
		(start 203.33208 -145.95348)
		(end 203.2 -145.8214)
		(width 0.1651)
		(layer "F.Cu")
		(net "M_E_DQ<6>")
	)
	(segment
		(start 203.2 -145.8214)
		(end 203.2 -145.516854)
		(width 0.1651)
		(layer "F.Cu")
		(net "M_E_DQ<6>")
	)
	(segment
		(start 203.2 -147.27174)
		(end 203.2 -146.304)
		(width 0.1651)
		(layer "F.Cu")
		(net "M_E_DQ<6>")
	)
	(segment
		(start 203.2 -146.304)
		(end 203.33208 -146.17192)
		(width 0.1651)
		(layer "F.Cu")
		(net "M_E_DQ<6>")
	)
	(via
		(at 203.199746 -145.5166)
		(size 0.508)
		(drill 0.254)
		(layers "F.Cu" "B.Cu")
		(net "M_E_DQ<6>")
	)
	(via
		(at 237.329218 -86.29904)
		(size 0.508)
		(drill 0.254)
		(layers "F.Cu" "B.Cu")
		(net "M_E_DQ<6>")
	)
	(via
		(at 202.349862 -141.213078)
		(size 0.508)
		(drill 0.254)
		(layers "F.Cu" "B.Cu")
		(net "M_E_DQ<6>")
	)
	(segment
		(start 202.349862 -142.476982)
		(end 202.349862 -141.213078)
		(width 0.1651)
		(layer "B.Cu")
		(net "M_E_DQ<6>")
	)
	(segment
		(start 202.35037 -142.477236)
		(end 202.349862 -142.476982)
		(width 0.1651)
		(layer "B.Cu")
		(net "M_E_DQ<6>")
	)
	(segment
		(start 206.239872 -112.758474)
		(end 205.952598 -113.045748)
		(width 0.14224)
		(layer "In4.Cu")
		(net "M_E_DQ<6>")
	)
	(segment
		(start 205.826868 -114.069622)
		(end 205.53934 -114.069622)
		(width 0.14224)
		(layer "In4.Cu")
		(net "M_E_DQ<6>")
	)
	(segment
		(start 204.964538 -114.931952)
		(end 203.0222 -116.87429)
		(width 0.14224)
		(layer "In4.Cu")
		(net "M_E_DQ<6>")
	)
	(segment
		(start 202.866752 -134.48665)
		(end 202.59421 -134.759192)
		(width 0.14224)
		(layer "In4.Cu")
		(net "M_E_DQ<6>")
	)
	(segment
		(start 231.841548 -86.69909)
		(end 231.738424 -86.802214)
		(width 0.0889)
		(layer "In4.Cu")
		(net "M_E_DQ<6>")
	)
	(segment
		(start 209.490818 -110.091728)
		(end 209.490818 -110.405672)
		(width 0.14224)
		(layer "In4.Cu")
		(net "M_E_DQ<6>")
	)
	(segment
		(start 206.976472 -112.920018)
		(end 206.688944 -112.920018)
		(width 0.14224)
		(layer "In4.Cu")
		(net "M_E_DQ<6>")
	)
	(segment
		(start 208.41335 -111.195612)
		(end 208.41335 -111.48314)
		(width 0.14224)
		(layer "In4.Cu")
		(net "M_E_DQ<6>")
	)
	(segment
		(start 208.41335 -111.48314)
		(end 208.126076 -111.770414)
		(width 0.14224)
		(layer "In4.Cu")
		(net "M_E_DQ<6>")
	)
	(segment
		(start 202.773788 -138.892788)
		(end 202.917552 -139.036552)
		(width 0.14224)
		(layer "In4.Cu")
		(net "M_E_DQ<6>")
	)
	(segment
		(start 202.917552 -136.256268)
		(end 202.917552 -136.5504)
		(width 0.14224)
		(layer "In4.Cu")
		(net "M_E_DQ<6>")
	)
	(segment
		(start 207.838548 -111.770414)
		(end 207.677004 -111.60887)
		(width 0.14224)
		(layer "In4.Cu")
		(net "M_E_DQ<6>")
	)
	(segment
		(start 207.102202 -111.896144)
		(end 207.102202 -112.183672)
		(width 0.14224)
		(layer "In4.Cu")
		(net "M_E_DQ<6>")
	)
	(segment
		(start 205.952598 -113.333276)
		(end 206.114142 -113.49482)
		(width 0.14224)
		(layer "In4.Cu")
		(net "M_E_DQ<6>")
	)
	(segment
		(start 208.826608 -110.459266)
		(end 208.53908 -110.459266)
		(width 0.14224)
		(layer "In4.Cu")
		(net "M_E_DQ<6>")
	)
	(segment
		(start 208.251806 -110.74654)
		(end 208.251806 -111.034068)
		(width 0.14224)
		(layer "In4.Cu")
		(net "M_E_DQ<6>")
	)
	(segment
		(start 202.59421 -134.759192)
		(end 202.59421 -135.932926)
		(width 0.14224)
		(layer "In4.Cu")
		(net "M_E_DQ<6>")
	)
	(segment
		(start 201.916792 -144.233646)
		(end 203.199746 -145.5166)
		(width 0.14224)
		(layer "In4.Cu")
		(net "M_E_DQ<6>")
	)
	(segment
		(start 234.768644 -85.212936)
		(end 234.735878 -85.212936)
		(width 0.0889)
		(layer "In4.Cu")
		(net "M_E_DQ<6>")
	)
	(segment
		(start 209.27568 -110.62081)
		(end 208.988152 -110.62081)
		(width 0.14224)
		(layer "In4.Cu")
		(net "M_E_DQ<6>")
	)
	(segment
		(start 229.45344 -86.599014)
		(end 221.846394 -94.20606)
		(width 0.14224)
		(layer "In4.Cu")
		(net "M_E_DQ<6>")
	)
	(segment
		(start 202.807062 -129.019808)
		(end 202.807062 -129.969768)
		(width 0.14224)
		(layer "In4.Cu")
		(net "M_E_DQ<6>")
	)
	(segment
		(start 201.3966 -127.609346)
		(end 202.807062 -129.019808)
		(width 0.14224)
		(layer "In4.Cu")
		(net "M_E_DQ<6>")
	)
	(segment
		(start 201.5998 -125.9586)
		(end 201.3966 -126.1618)
		(width 0.14224)
		(layer "In4.Cu")
		(net "M_E_DQ<6>")
	)
	(segment
		(start 204.802994 -114.48288)
		(end 204.964538 -114.644424)
		(width 0.14224)
		(layer "In4.Cu")
		(net "M_E_DQ<6>")
	)
	(segment
		(start 204.964538 -114.644424)
		(end 204.964538 -114.931952)
		(width 0.14224)
		(layer "In4.Cu")
		(net "M_E_DQ<6>")
	)
	(segment
		(start 202.7682 -131.924552)
		(end 202.7682 -134.0104)
		(width 0.14224)
		(layer "In4.Cu")
		(net "M_E_DQ<6>")
	)
	(segment
		(start 206.5274 -112.758474)
		(end 206.239872 -112.758474)
		(width 0.14224)
		(layer "In4.Cu")
		(net "M_E_DQ<6>")
	)
	(segment
		(start 202.180952 -140.070078)
		(end 202.180952 -141.044168)
		(width 0.14224)
		(layer "In4.Cu")
		(net "M_E_DQ<6>")
	)
	(segment
		(start 202.866752 -134.108952)
		(end 202.866752 -134.48665)
		(width 0.14224)
		(layer "In4.Cu")
		(net "M_E_DQ<6>")
	)
	(segment
		(start 202.180952 -141.044168)
		(end 202.349862 -141.213078)
		(width 0.14224)
		(layer "In4.Cu")
		(net "M_E_DQ<6>")
	)
	(segment
		(start 204.802994 -114.195352)
		(end 204.802994 -114.48288)
		(width 0.14224)
		(layer "In4.Cu")
		(net "M_E_DQ<6>")
	)
	(segment
		(start 202.2094 -127.265176)
		(end 202.2094 -126.1618)
		(width 0.14224)
		(layer "In4.Cu")
		(net "M_E_DQ<6>")
	)
	(segment
		(start 207.263746 -112.632744)
		(end 206.976472 -112.920018)
		(width 0.14224)
		(layer "In4.Cu")
		(net "M_E_DQ<6>")
	)
	(segment
		(start 206.114142 -113.782348)
		(end 205.826868 -114.069622)
		(width 0.14224)
		(layer "In4.Cu")
		(net "M_E_DQ<6>")
	)
	(segment
		(start 201.916792 -141.646148)
		(end 201.916792 -144.233646)
		(width 0.14224)
		(layer "In4.Cu")
		(net "M_E_DQ<6>")
	)
	(segment
		(start 202.59421 -135.932926)
		(end 202.917552 -136.256268)
		(width 0.14224)
		(layer "In4.Cu")
		(net "M_E_DQ<6>")
	)
	(segment
		(start 202.0062 -125.9586)
		(end 201.5998 -125.9586)
		(width 0.14224)
		(layer "In4.Cu")
		(net "M_E_DQ<6>")
	)
	(segment
		(start 233.906314 -85.70849)
		(end 233.873548 -85.70849)
		(width 0.0889)
		(layer "In4.Cu")
		(net "M_E_DQ<6>")
	)
	(segment
		(start 209.490818 -110.405672)
		(end 209.27568 -110.62081)
		(width 0.14224)
		(layer "In4.Cu")
		(net "M_E_DQ<6>")
	)
	(segment
		(start 201.3966 -126.1618)
		(end 201.3966 -127.609346)
		(width 0.14224)
		(layer "In4.Cu")
		(net "M_E_DQ<6>")
	)
	(segment
		(start 235.627164 -84.90839)
		(end 235.281724 -84.90839)
		(width 0.0889)
		(layer "In4.Cu")
		(net "M_E_DQ<6>")
	)
	(segment
		(start 202.349862 -141.213078)
		(end 201.916792 -141.646148)
		(width 0.14224)
		(layer "In4.Cu")
		(net "M_E_DQ<6>")
	)
	(segment
		(start 202.819 -127.468376)
		(end 202.4126 -127.468376)
		(width 0.14224)
		(layer "In4.Cu")
		(net "M_E_DQ<6>")
	)
	(segment
		(start 202.714352 -130.062478)
		(end 202.714352 -131.307078)
		(width 0.14224)
		(layer "In4.Cu")
		(net "M_E_DQ<6>")
	)
	(segment
		(start 207.263746 -112.345216)
		(end 207.263746 -112.632744)
		(width 0.14224)
		(layer "In4.Cu")
		(net "M_E_DQ<6>")
	)
	(segment
		(start 202.714352 -131.307078)
		(end 202.866752 -131.459478)
		(width 0.14224)
		(layer "In4.Cu")
		(net "M_E_DQ<6>")
	)
	(segment
		(start 203.0222 -127.265176)
		(end 202.819 -127.468376)
		(width 0.14224)
		(layer "In4.Cu")
		(net "M_E_DQ<6>")
	)
	(segment
		(start 205.377796 -113.908078)
		(end 205.090268 -113.908078)
		(width 0.14224)
		(layer "In4.Cu")
		(net "M_E_DQ<6>")
	)
	(segment
		(start 202.773788 -136.694164)
		(end 202.773788 -138.892788)
		(width 0.14224)
		(layer "In4.Cu")
		(net "M_E_DQ<6>")
	)
	(segment
		(start 236.834172 -85.633052)
		(end 236.817408 -85.603588)
		(width 0.0889)
		(layer "In4.Cu")
		(net "M_E_DQ<6>")
	)
	(segment
		(start 221.846394 -94.20606)
		(end 221.846394 -97.736152)
		(width 0.14224)
		(layer "In4.Cu")
		(net "M_E_DQ<6>")
	)
	(segment
		(start 202.2094 -126.1618)
		(end 202.0062 -125.9586)
		(width 0.14224)
		(layer "In4.Cu")
		(net "M_E_DQ<6>")
	)
	(segment
		(start 205.952598 -113.045748)
		(end 205.952598 -113.333276)
		(width 0.14224)
		(layer "In4.Cu")
		(net "M_E_DQ<6>")
	)
	(segment
		(start 202.917552 -139.036552)
		(end 202.917552 -139.333478)
		(width 0.14224)
		(layer "In4.Cu")
		(net "M_E_DQ<6>")
	)
	(segment
		(start 236.481874 -85.403436)
		(end 236.449108 -85.403436)
		(width 0.0889)
		(layer "In4.Cu")
		(net "M_E_DQ<6>")
	)
	(segment
		(start 206.688944 -112.920018)
		(end 206.5274 -112.758474)
		(width 0.14224)
		(layer "In4.Cu")
		(net "M_E_DQ<6>")
	)
	(segment
		(start 206.114142 -113.49482)
		(end 206.114142 -113.782348)
		(width 0.14224)
		(layer "In4.Cu")
		(net "M_E_DQ<6>")
	)
	(segment
		(start 232.189274 -86.69909)
		(end 231.841548 -86.69909)
		(width 0.0889)
		(layer "In4.Cu")
		(net "M_E_DQ<6>")
	)
	(segment
		(start 208.251806 -111.034068)
		(end 208.41335 -111.195612)
		(width 0.14224)
		(layer "In4.Cu")
		(net "M_E_DQ<6>")
	)
	(segment
		(start 207.102202 -112.183672)
		(end 207.263746 -112.345216)
		(width 0.14224)
		(layer "In4.Cu")
		(net "M_E_DQ<6>")
	)
	(segment
		(start 230.087424 -86.802214)
		(end 229.884224 -86.599014)
		(width 0.0889)
		(layer "In4.Cu")
		(net "M_E_DQ<6>")
	)
	(segment
		(start 202.866752 -131.459478)
		(end 202.866752 -131.826)
		(width 0.14224)
		(layer "In4.Cu")
		(net "M_E_DQ<6>")
	)
	(segment
		(start 208.126076 -111.770414)
		(end 207.838548 -111.770414)
		(width 0.14224)
		(layer "In4.Cu")
		(net "M_E_DQ<6>")
	)
	(segment
		(start 207.677004 -111.60887)
		(end 207.389476 -111.60887)
		(width 0.14224)
		(layer "In4.Cu")
		(net "M_E_DQ<6>")
	)
	(segment
		(start 203.0222 -116.87429)
		(end 203.0222 -127.265176)
		(width 0.14224)
		(layer "In4.Cu")
		(net "M_E_DQ<6>")
	)
	(segment
		(start 202.7682 -134.0104)
		(end 202.866752 -134.108952)
		(width 0.14224)
		(layer "In4.Cu")
		(net "M_E_DQ<6>")
	)
	(segment
		(start 237.329218 -86.29904)
		(end 236.834172 -85.633052)
		(width 0.0889)
		(layer "In4.Cu")
		(net "M_E_DQ<6>")
	)
	(segment
		(start 229.884224 -86.599014)
		(end 229.45344 -86.599014)
		(width 0.14224)
		(layer "In4.Cu")
		(net "M_E_DQ<6>")
	)
	(segment
		(start 202.4126 -127.468376)
		(end 202.2094 -127.265176)
		(width 0.14224)
		(layer "In4.Cu")
		(net "M_E_DQ<6>")
	)
	(segment
		(start 205.53934 -114.069622)
		(end 205.377796 -113.908078)
		(width 0.14224)
		(layer "In4.Cu")
		(net "M_E_DQ<6>")
	)
	(segment
		(start 205.090268 -113.908078)
		(end 204.802994 -114.195352)
		(width 0.14224)
		(layer "In4.Cu")
		(net "M_E_DQ<6>")
	)
	(segment
		(start 208.988152 -110.62081)
		(end 208.826608 -110.459266)
		(width 0.14224)
		(layer "In4.Cu")
		(net "M_E_DQ<6>")
	)
	(segment
		(start 231.738424 -86.802214)
		(end 230.087424 -86.802214)
		(width 0.0889)
		(layer "In4.Cu")
		(net "M_E_DQ<6>")
	)
	(segment
		(start 202.807062 -129.969768)
		(end 202.714352 -130.062478)
		(width 0.14224)
		(layer "In4.Cu")
		(net "M_E_DQ<6>")
	)
	(segment
		(start 207.389476 -111.60887)
		(end 207.102202 -111.896144)
		(width 0.14224)
		(layer "In4.Cu")
		(net "M_E_DQ<6>")
	)
	(segment
		(start 233.051604 -86.203536)
		(end 233.018838 -86.203536)
		(width 0.0889)
		(layer "In4.Cu")
		(net "M_E_DQ<6>")
	)
	(segment
		(start 208.53908 -110.459266)
		(end 208.251806 -110.74654)
		(width 0.14224)
		(layer "In4.Cu")
		(net "M_E_DQ<6>")
	)
	(segment
		(start 202.917552 -136.5504)
		(end 202.773788 -136.694164)
		(width 0.14224)
		(layer "In4.Cu")
		(net "M_E_DQ<6>")
	)
	(segment
		(start 202.866752 -131.826)
		(end 202.7682 -131.924552)
		(width 0.14224)
		(layer "In4.Cu")
		(net "M_E_DQ<6>")
	)
	(segment
		(start 221.846394 -97.736152)
		(end 209.490818 -110.091728)
		(width 0.14224)
		(layer "In4.Cu")
		(net "M_E_DQ<6>")
	)
	(segment
		(start 202.917552 -139.333478)
		(end 202.180952 -140.070078)
		(width 0.14224)
		(layer "In4.Cu")
		(net "M_E_DQ<6>")
	)
	(arc
		(start 235.958888 -85.108288)
		(mid 235.818809 -84.965552)
		(end 235.627164 -84.90839)
		(width 0.0889)
		(layer "In4.Cu")
		(net "M_E_DQ<6>")
	)
	(arc
		(start 234.735878 -85.212936)
		(mid 234.450454 -85.296403)
		(end 234.241848 -85.508338)
		(width 0.0889)
		(layer "In4.Cu")
		(net "M_E_DQ<6>")
	)
	(arc
		(start 236.449108 -85.403436)
		(mid 236.165891 -85.319155)
		(end 235.958888 -85.108288)
		(width 0.0889)
		(layer "In4.Cu")
		(net "M_E_DQ<6>")
	)
	(arc
		(start 233.018838 -86.203536)
		(mid 232.733414 -86.287003)
		(end 232.524808 -86.498938)
		(width 0.0889)
		(layer "In4.Cu")
		(net "M_E_DQ<6>")
	)
	(arc
		(start 235.100368 -85.013038)
		(mid 234.960289 -85.155774)
		(end 234.768644 -85.212936)
		(width 0.0889)
		(layer "In4.Cu")
		(net "M_E_DQ<6>")
	)
	(arc
		(start 233.383328 -86.003638)
		(mid 233.243249 -86.146374)
		(end 233.051604 -86.203536)
		(width 0.0889)
		(layer "In4.Cu")
		(net "M_E_DQ<6>")
	)
	(arc
		(start 233.873548 -85.70849)
		(mid 233.590331 -85.792771)
		(end 233.383328 -86.003638)
		(width 0.0889)
		(layer "In4.Cu")
		(net "M_E_DQ<6>")
	)
	(arc
		(start 232.524808 -86.498938)
		(mid 232.383125 -86.642742)
		(end 232.189274 -86.69909)
		(width 0.0889)
		(layer "In4.Cu")
		(net "M_E_DQ<6>")
	)
	(arc
		(start 234.241848 -85.508338)
		(mid 234.100165 -85.652142)
		(end 233.906314 -85.70849)
		(width 0.0889)
		(layer "In4.Cu")
		(net "M_E_DQ<6>")
	)
	(arc
		(start 236.817408 -85.603588)
		(mid 236.675725 -85.459784)
		(end 236.481874 -85.403436)
		(width 0.0889)
		(layer "In4.Cu")
		(net "M_E_DQ<6>")
	)
	(arc
		(start 235.281724 -84.90839)
		(mid 235.177023 -84.936422)
		(end 235.100368 -85.013038)
		(width 0.0889)
		(layer "In4.Cu")
		(net "M_E_DQ<6>")
	)
	(segment
		(start 287.21812 -95.528384)
		(end 286.64662 -95.528384)
		(width 0.1651)
		(layer "F.Cu")
		(net "M_E_DQ<63>")
	)
	(segment
		(start 313.700414 -142.6718)
		(end 313.699906 -142.677642)
		(width 0.1651)
		(layer "F.Cu")
		(net "M_E_DQ<63>")
	)
	(segment
		(start 313.699906 -142.677642)
		(end 313.699906 -143.941546)
		(width 0.1651)
		(layer "F.Cu")
		(net "M_E_DQ<63>")
	)
	(via
		(at 313.699906 -143.941546)
		(size 0.508)
		(drill 0.254)
		(layers "F.Cu" "B.Cu")
		(net "M_E_DQ<63>")
	)
	(via
		(at 287.21812 -95.528384)
		(size 0.508)
		(drill 0.254)
		(layers "F.Cu" "B.Cu")
		(net "M_E_DQ<63>")
	)
	(via
		(at 314.54979 -139.932156)
		(size 0.508)
		(drill 0.254)
		(layers "F.Cu" "B.Cu")
		(net "M_E_DQ<63>")
	)
	(segment
		(start 314.54979 -137.877296)
		(end 314.550298 -137.877296)
		(width 0.1651)
		(layer "B.Cu")
		(net "M_E_DQ<63>")
	)
	(segment
		(start 314.54979 -139.932156)
		(end 314.54979 -137.877296)
		(width 0.1651)
		(layer "B.Cu")
		(net "M_E_DQ<63>")
	)
	(segment
		(start 314.256928 -128.12903)
		(end 314.411868 -128.28397)
		(width 0.14224)
		(layer "In4.Cu")
		(net "M_E_DQ<63>")
	)
	(segment
		(start 314.149994 -143.44015)
		(end 314.149994 -143.763746)
		(width 0.14224)
		(layer "In4.Cu")
		(net "M_E_DQ<63>")
	)
	(segment
		(start 314.902596 -138.893804)
		(end 314.902596 -139.590272)
		(width 0.14224)
		(layer "In4.Cu")
		(net "M_E_DQ<63>")
	)
	(segment
		(start 314.099194 -140.790168)
		(end 314.143644 -140.834618)
		(width 0.14224)
		(layer "In4.Cu")
		(net "M_E_DQ<63>")
	)
	(segment
		(start 290.637214 -104.843834)
		(end 290.67379 -104.843834)
		(width 0.0889)
		(layer "In4.Cu")
		(net "M_E_DQ<63>")
	)
	(segment
		(start 314.411868 -127.62103)
		(end 314.256928 -127.77597)
		(width 0.14224)
		(layer "In4.Cu")
		(net "M_E_DQ<63>")
	)
	(segment
		(start 307.764434 -118.645432)
		(end 309.13832 -118.645432)
		(width 0.14224)
		(layer "In4.Cu")
		(net "M_E_DQ<63>")
	)
	(segment
		(start 314.118244 -142.3162)
		(end 314.118244 -142.621)
		(width 0.14224)
		(layer "In4.Cu")
		(net "M_E_DQ<63>")
	)
	(segment
		(start 287.21812 -95.528384)
		(end 287.655254 -96.008444)
		(width 0.0889)
		(layer "In4.Cu")
		(net "M_E_DQ<63>")
	)
	(segment
		(start 289.782504 -104.348788)
		(end 289.81527 -104.348788)
		(width 0.0889)
		(layer "In4.Cu")
		(net "M_E_DQ<63>")
	)
	(segment
		(start 291.588952 -105.664508)
		(end 291.978334 -105.664508)
		(width 0.0889)
		(layer "In4.Cu")
		(net "M_E_DQ<63>")
	)
	(segment
		(start 314.411868 -126.95809)
		(end 314.762134 -126.95809)
		(width 0.14224)
		(layer "In4.Cu")
		(net "M_E_DQ<63>")
	)
	(segment
		(start 314.917074 -126.14021)
		(end 314.762134 -126.29515)
		(width 0.14224)
		(layer "In4.Cu")
		(net "M_E_DQ<63>")
	)
	(segment
		(start 313.861196 -143.151352)
		(end 314.149994 -143.44015)
		(width 0.14224)
		(layer "In4.Cu")
		(net "M_E_DQ<63>")
	)
	(segment
		(start 314.917074 -124.424186)
		(end 314.917074 -126.14021)
		(width 0.14224)
		(layer "In4.Cu")
		(net "M_E_DQ<63>")
	)
	(segment
		(start 314.762134 -126.29515)
		(end 314.411868 -126.29515)
		(width 0.14224)
		(layer "In4.Cu")
		(net "M_E_DQ<63>")
	)
	(segment
		(start 291.16401 -105.138982)
		(end 291.163502 -105.13949)
		(width 0.0889)
		(layer "In4.Cu")
		(net "M_E_DQ<63>")
	)
	(segment
		(start 314.917074 -129.873756)
		(end 315.131196 -130.087878)
		(width 0.14224)
		(layer "In4.Cu")
		(net "M_E_DQ<63>")
	)
	(segment
		(start 314.851796 -131.746752)
		(end 315.314076 -132.209032)
		(width 0.14224)
		(layer "In4.Cu")
		(net "M_E_DQ<63>")
	)
	(segment
		(start 315.131196 -130.087878)
		(end 315.131196 -131.205478)
		(width 0.14224)
		(layer "In4.Cu")
		(net "M_E_DQ<63>")
	)
	(segment
		(start 313.861196 -142.059152)
		(end 314.118244 -142.3162)
		(width 0.14224)
		(layer "In4.Cu")
		(net "M_E_DQ<63>")
	)
	(segment
		(start 291.978334 -105.664508)
		(end 292.333426 -106.0196)
		(width 0.14224)
		(layer "In4.Cu")
		(net "M_E_DQ<63>")
	)
	(segment
		(start 287.725104 -100.1776)
		(end 287.72993 -100.186236)
		(width 0.0889)
		(layer "In4.Cu")
		(net "M_E_DQ<63>")
	)
	(segment
		(start 314.902596 -136.569196)
		(end 314.9854 -136.652)
		(width 0.14224)
		(layer "In4.Cu")
		(net "M_E_DQ<63>")
	)
	(segment
		(start 292.333426 -106.0196)
		(end 295.138602 -106.0196)
		(width 0.14224)
		(layer "In4.Cu")
		(net "M_E_DQ<63>")
	)
	(segment
		(start 314.884054 -133.389624)
		(end 315.159136 -133.389624)
		(width 0.14224)
		(layer "In4.Cu")
		(net "M_E_DQ<63>")
	)
	(segment
		(start 315.07176 -136.083294)
		(end 314.902596 -136.252458)
		(width 0.14224)
		(layer "In4.Cu")
		(net "M_E_DQ<63>")
	)
	(segment
		(start 291.163502 -105.13949)
		(end 291.300154 -105.374948)
		(width 0.0889)
		(layer "In4.Cu")
		(net "M_E_DQ<63>")
	)
	(segment
		(start 314.118244 -142.621)
		(end 313.861196 -142.878048)
		(width 0.14224)
		(layer "In4.Cu")
		(net "M_E_DQ<63>")
	)
	(segment
		(start 288.5948 -103.242618)
		(end 288.58845 -103.253286)
		(width 0.0889)
		(layer "In4.Cu")
		(net "M_E_DQ<63>")
	)
	(segment
		(start 314.917074 -127.11303)
		(end 314.917074 -127.46609)
		(width 0.14224)
		(layer "In4.Cu")
		(net "M_E_DQ<63>")
	)
	(segment
		(start 288.58845 -102.262686)
		(end 288.583624 -102.271322)
		(width 0.0889)
		(layer "In4.Cu")
		(net "M_E_DQ<63>")
	)
	(segment
		(start 288.065464 -101.376988)
		(end 288.09823 -101.376988)
		(width 0.0889)
		(layer "In4.Cu")
		(net "M_E_DQ<63>")
	)
	(segment
		(start 315.314076 -133.761988)
		(end 314.927996 -134.148068)
		(width 0.14224)
		(layer "In4.Cu")
		(net "M_E_DQ<63>")
	)
	(segment
		(start 314.917074 -127.46609)
		(end 314.762134 -127.62103)
		(width 0.14224)
		(layer "In4.Cu")
		(net "M_E_DQ<63>")
	)
	(segment
		(start 315.314076 -132.421884)
		(end 315.159136 -132.576824)
		(width 0.14224)
		(layer "In4.Cu")
		(net "M_E_DQ<63>")
	)
	(segment
		(start 313.861196 -142.878048)
		(end 313.861196 -143.151352)
		(width 0.14224)
		(layer "In4.Cu")
		(net "M_E_DQ<63>")
	)
	(segment
		(start 314.902596 -139.590272)
		(end 314.891674 -139.590272)
		(width 0.14224)
		(layer "In4.Cu")
		(net "M_E_DQ<63>")
	)
	(segment
		(start 287.72993 -100.186236)
		(end 287.73628 -100.196904)
		(width 0.0889)
		(layer "In4.Cu")
		(net "M_E_DQ<63>")
	)
	(segment
		(start 314.884054 -132.576824)
		(end 314.729114 -132.731764)
		(width 0.14224)
		(layer "In4.Cu")
		(net "M_E_DQ<63>")
	)
	(segment
		(start 291.300154 -105.374948)
		(end 291.588952 -105.664508)
		(width 0.0889)
		(layer "In4.Cu")
		(net "M_E_DQ<63>")
	)
	(segment
		(start 315.159136 -133.389624)
		(end 315.314076 -133.544564)
		(width 0.14224)
		(layer "In4.Cu")
		(net "M_E_DQ<63>")
	)
	(segment
		(start 288.58845 -103.253286)
		(end 288.583624 -103.261922)
		(width 0.0889)
		(layer "In4.Cu")
		(net "M_E_DQ<63>")
	)
	(segment
		(start 288.920174 -103.853234)
		(end 288.95294 -103.853234)
		(width 0.0889)
		(layer "In4.Cu")
		(net "M_E_DQ<63>")
	)
	(segment
		(start 314.891674 -139.590272)
		(end 314.54979 -139.932156)
		(width 0.14224)
		(layer "In4.Cu")
		(net "M_E_DQ<63>")
	)
	(segment
		(start 314.527438 -139.932156)
		(end 314.099194 -140.3604)
		(width 0.14224)
		(layer "In4.Cu")
		(net "M_E_DQ<63>")
	)
	(segment
		(start 314.729114 -132.731764)
		(end 314.729114 -133.234684)
		(width 0.14224)
		(layer "In4.Cu")
		(net "M_E_DQ<63>")
	)
	(segment
		(start 309.13832 -118.645432)
		(end 314.917074 -124.424186)
		(width 0.14224)
		(layer "In4.Cu")
		(net "M_E_DQ<63>")
	)
	(segment
		(start 314.927996 -134.526782)
		(end 315.07176 -134.670546)
		(width 0.14224)
		(layer "In4.Cu")
		(net "M_E_DQ<63>")
	)
	(segment
		(start 314.9854 -138.811)
		(end 314.902596 -138.893804)
		(width 0.14224)
		(layer "In4.Cu")
		(net "M_E_DQ<63>")
	)
	(segment
		(start 314.256928 -126.80315)
		(end 314.411868 -126.95809)
		(width 0.14224)
		(layer "In4.Cu")
		(net "M_E_DQ<63>")
	)
	(segment
		(start 314.411868 -128.28397)
		(end 314.762134 -128.28397)
		(width 0.14224)
		(layer "In4.Cu")
		(net "M_E_DQ<63>")
	)
	(segment
		(start 315.131196 -131.205478)
		(end 314.851796 -131.484878)
		(width 0.14224)
		(layer "In4.Cu")
		(net "M_E_DQ<63>")
	)
	(segment
		(start 314.149994 -143.763746)
		(end 313.972194 -143.941546)
		(width 0.14224)
		(layer "In4.Cu")
		(net "M_E_DQ<63>")
	)
	(segment
		(start 314.143644 -140.834618)
		(end 314.143644 -141.5034)
		(width 0.14224)
		(layer "In4.Cu")
		(net "M_E_DQ<63>")
	)
	(segment
		(start 314.902596 -136.252458)
		(end 314.902596 -136.569196)
		(width 0.14224)
		(layer "In4.Cu")
		(net "M_E_DQ<63>")
	)
	(segment
		(start 314.851796 -131.484878)
		(end 314.851796 -131.746752)
		(width 0.14224)
		(layer "In4.Cu")
		(net "M_E_DQ<63>")
	)
	(segment
		(start 314.411868 -126.29515)
		(end 314.256928 -126.45009)
		(width 0.14224)
		(layer "In4.Cu")
		(net "M_E_DQ<63>")
	)
	(segment
		(start 314.143644 -141.5034)
		(end 313.861196 -141.785848)
		(width 0.14224)
		(layer "In4.Cu")
		(net "M_E_DQ<63>")
	)
	(segment
		(start 314.917074 -128.43891)
		(end 314.917074 -129.873756)
		(width 0.14224)
		(layer "In4.Cu")
		(net "M_E_DQ<63>")
	)
	(segment
		(start 313.972194 -143.941546)
		(end 313.699906 -143.941546)
		(width 0.14224)
		(layer "In4.Cu")
		(net "M_E_DQ<63>")
	)
	(segment
		(start 315.314076 -132.209032)
		(end 315.314076 -132.421884)
		(width 0.14224)
		(layer "In4.Cu")
		(net "M_E_DQ<63>")
	)
	(segment
		(start 314.927996 -134.148068)
		(end 314.927996 -134.526782)
		(width 0.14224)
		(layer "In4.Cu")
		(net "M_E_DQ<63>")
	)
	(segment
		(start 314.729114 -133.234684)
		(end 314.884054 -133.389624)
		(width 0.14224)
		(layer "In4.Cu")
		(net "M_E_DQ<63>")
	)
	(segment
		(start 314.762134 -127.62103)
		(end 314.411868 -127.62103)
		(width 0.14224)
		(layer "In4.Cu")
		(net "M_E_DQ<63>")
	)
	(segment
		(start 295.138602 -106.0196)
		(end 307.764434 -118.645432)
		(width 0.14224)
		(layer "In4.Cu")
		(net "M_E_DQ<63>")
	)
	(segment
		(start 313.861196 -141.785848)
		(end 313.861196 -142.059152)
		(width 0.14224)
		(layer "In4.Cu")
		(net "M_E_DQ<63>")
	)
	(segment
		(start 315.159136 -132.576824)
		(end 314.884054 -132.576824)
		(width 0.14224)
		(layer "In4.Cu")
		(net "M_E_DQ<63>")
	)
	(segment
		(start 314.762134 -128.28397)
		(end 314.917074 -128.43891)
		(width 0.14224)
		(layer "In4.Cu")
		(net "M_E_DQ<63>")
	)
	(segment
		(start 314.9854 -136.652)
		(end 314.9854 -138.811)
		(width 0.14224)
		(layer "In4.Cu")
		(net "M_E_DQ<63>")
	)
	(segment
		(start 314.256928 -127.77597)
		(end 314.256928 -128.12903)
		(width 0.14224)
		(layer "In4.Cu")
		(net "M_E_DQ<63>")
	)
	(segment
		(start 314.54979 -139.932156)
		(end 314.527438 -139.932156)
		(width 0.14224)
		(layer "In4.Cu")
		(net "M_E_DQ<63>")
	)
	(segment
		(start 315.314076 -133.544564)
		(end 315.314076 -133.761988)
		(width 0.14224)
		(layer "In4.Cu")
		(net "M_E_DQ<63>")
	)
	(segment
		(start 315.07176 -134.670546)
		(end 315.07176 -136.083294)
		(width 0.14224)
		(layer "In4.Cu")
		(net "M_E_DQ<63>")
	)
	(segment
		(start 314.256928 -126.45009)
		(end 314.256928 -126.80315)
		(width 0.14224)
		(layer "In4.Cu")
		(net "M_E_DQ<63>")
	)
	(segment
		(start 314.762134 -126.95809)
		(end 314.917074 -127.11303)
		(width 0.14224)
		(layer "In4.Cu")
		(net "M_E_DQ<63>")
	)
	(segment
		(start 288.5948 -102.252018)
		(end 288.58845 -102.262686)
		(width 0.0889)
		(layer "In4.Cu")
		(net "M_E_DQ<63>")
	)
	(segment
		(start 314.099194 -140.3604)
		(end 314.099194 -140.790168)
		(width 0.14224)
		(layer "In4.Cu")
		(net "M_E_DQ<63>")
	)
	(arc
		(start 287.73628 -100.196904)
		(mid 287.809078 -100.487667)
		(end 287.72993 -100.776786)
		(width 0.0889)
		(layer "In4.Cu")
		(net "M_E_DQ<63>")
	)
	(arc
		(start 287.72993 -100.776786)
		(mid 287.727182 -101.172253)
		(end 288.065464 -101.376988)
		(width 0.0889)
		(layer "In4.Cu")
		(net "M_E_DQ<63>")
	)
	(arc
		(start 288.583624 -103.261922)
		(mid 288.587371 -103.651178)
		(end 288.920174 -103.853234)
		(width 0.0889)
		(layer "In4.Cu")
		(net "M_E_DQ<63>")
	)
	(arc
		(start 287.72993 -96.814386)
		(mid 287.676431 -97.014284)
		(end 287.72993 -97.214182)
		(width 0.0889)
		(layer "In4.Cu")
		(net "M_E_DQ<63>")
	)
	(arc
		(start 287.72993 -96.223582)
		(mid 287.808993 -96.518984)
		(end 287.72993 -96.814386)
		(width 0.0889)
		(layer "In4.Cu")
		(net "M_E_DQ<63>")
	)
	(arc
		(start 287.655254 -96.008444)
		(mid 287.672806 -96.073907)
		(end 287.693354 -96.138492)
		(width 0.0889)
		(layer "In4.Cu")
		(net "M_E_DQ<63>")
	)
	(arc
		(start 289.81527 -104.348788)
		(mid 290.098487 -104.433069)
		(end 290.30549 -104.643936)
		(width 0.0889)
		(layer "In4.Cu")
		(net "M_E_DQ<63>")
	)
	(arc
		(start 287.73628 -99.206304)
		(mid 287.809078 -99.497067)
		(end 287.72993 -99.786186)
		(width 0.0889)
		(layer "In4.Cu")
		(net "M_E_DQ<63>")
	)
	(arc
		(start 287.72993 -97.804986)
		(mid 287.676431 -98.004884)
		(end 287.72993 -98.204782)
		(width 0.0889)
		(layer "In4.Cu")
		(net "M_E_DQ<63>")
	)
	(arc
		(start 288.09823 -101.376988)
		(mid 288.59062 -101.675921)
		(end 288.5948 -102.252018)
		(width 0.0889)
		(layer "In4.Cu")
		(net "M_E_DQ<63>")
	)
	(arc
		(start 289.44697 -104.148636)
		(mid 289.588653 -104.29244)
		(end 289.782504 -104.348788)
		(width 0.0889)
		(layer "In4.Cu")
		(net "M_E_DQ<63>")
	)
	(arc
		(start 288.58845 -102.662736)
		(mid 288.667672 -102.951854)
		(end 288.5948 -103.242618)
		(width 0.0889)
		(layer "In4.Cu")
		(net "M_E_DQ<63>")
	)
	(arc
		(start 288.95294 -103.853234)
		(mid 289.238364 -103.936701)
		(end 289.44697 -104.148636)
		(width 0.0889)
		(layer "In4.Cu")
		(net "M_E_DQ<63>")
	)
	(arc
		(start 287.72993 -98.795586)
		(mid 287.676351 -99.001837)
		(end 287.73628 -99.206304)
		(width 0.0889)
		(layer "In4.Cu")
		(net "M_E_DQ<63>")
	)
	(arc
		(start 288.583624 -102.271322)
		(mid 288.534869 -102.467674)
		(end 288.58845 -102.662736)
		(width 0.0889)
		(layer "In4.Cu")
		(net "M_E_DQ<63>")
	)
	(arc
		(start 287.72993 -99.786186)
		(mid 287.67646 -99.981249)
		(end 287.725104 -100.1776)
		(width 0.0889)
		(layer "In4.Cu")
		(net "M_E_DQ<63>")
	)
	(arc
		(start 290.30549 -104.643936)
		(mid 290.445569 -104.786672)
		(end 290.637214 -104.843834)
		(width 0.0889)
		(layer "In4.Cu")
		(net "M_E_DQ<63>")
	)
	(arc
		(start 287.72993 -97.214182)
		(mid 287.809061 -97.509584)
		(end 287.72993 -97.804986)
		(width 0.0889)
		(layer "In4.Cu")
		(net "M_E_DQ<63>")
	)
	(arc
		(start 290.67379 -104.843834)
		(mid 290.957007 -104.928115)
		(end 291.16401 -105.138982)
		(width 0.0889)
		(layer "In4.Cu")
		(net "M_E_DQ<63>")
	)
	(arc
		(start 287.72993 -98.204782)
		(mid 287.809061 -98.500184)
		(end 287.72993 -98.795586)
		(width 0.0889)
		(layer "In4.Cu")
		(net "M_E_DQ<63>")
	)
	(arc
		(start 287.693354 -96.138492)
		(mid 287.709157 -96.182106)
		(end 287.72993 -96.223582)
		(width 0.0889)
		(layer "In4.Cu")
		(net "M_E_DQ<63>")
	)
	(segment
		(start 314.550298 -147.27174)
		(end 314.550044 -147.27174)
		(width 0.1651)
		(layer "F.Cu")
		(net "M_E_DQ<62>")
	)
	(segment
		(start 314.550044 -147.27174)
		(end 314.550044 -146.304)
		(width 0.1651)
		(layer "F.Cu")
		(net "M_E_DQ<62>")
	)
	(segment
		(start 314.550044 -146.304)
		(end 314.682124 -146.17192)
		(width 0.1651)
		(layer "F.Cu")
		(net "M_E_DQ<62>")
	)
	(segment
		(start 314.550044 -145.8214)
		(end 314.550044 -145.516854)
		(width 0.1651)
		(layer "F.Cu")
		(net "M_E_DQ<62>")
	)
	(segment
		(start 314.682124 -146.17192)
		(end 314.682124 -145.95348)
		(width 0.1651)
		(layer "F.Cu")
		(net "M_E_DQ<62>")
	)
	(segment
		(start 287.21812 -93.547184)
		(end 286.64662 -93.547184)
		(width 0.1651)
		(layer "F.Cu")
		(net "M_E_DQ<62>")
	)
	(segment
		(start 314.550044 -145.516854)
		(end 314.54979 -145.5166)
		(width 0.1651)
		(layer "F.Cu")
		(net "M_E_DQ<62>")
	)
	(segment
		(start 314.682124 -145.95348)
		(end 314.550044 -145.8214)
		(width 0.1651)
		(layer "F.Cu")
		(net "M_E_DQ<62>")
	)
	(via
		(at 287.21812 -93.547184)
		(size 0.508)
		(drill 0.254)
		(layers "F.Cu" "B.Cu")
		(net "M_E_DQ<62>")
	)
	(via
		(at 314.54979 -145.5166)
		(size 0.508)
		(drill 0.254)
		(layers "F.Cu" "B.Cu")
		(net "M_E_DQ<62>")
	)
	(via
		(at 313.699906 -141.213078)
		(size 0.508)
		(drill 0.254)
		(layers "F.Cu" "B.Cu")
		(net "M_E_DQ<62>")
	)
	(segment
		(start 313.699906 -142.476982)
		(end 313.699906 -141.213078)
		(width 0.1651)
		(layer "B.Cu")
		(net "M_E_DQ<62>")
	)
	(segment
		(start 313.700414 -142.477236)
		(end 313.699906 -142.476982)
		(width 0.1651)
		(layer "B.Cu")
		(net "M_E_DQ<62>")
	)
	(segment
		(start 314.1218 -136.645396)
		(end 314.1218 -138.7348)
		(width 0.14224)
		(layer "In4.Cu")
		(net "M_E_DQ<62>")
	)
	(segment
		(start 287.56483 -99.290886)
		(end 287.569656 -99.299522)
		(width 0.0889)
		(layer "In4.Cu")
		(net "M_E_DQ<62>")
	)
	(segment
		(start 314.267596 -136.256268)
		(end 314.267596 -136.4996)
		(width 0.14224)
		(layer "In4.Cu")
		(net "M_E_DQ<62>")
	)
	(segment
		(start 314.267596 -136.4996)
		(end 314.1218 -136.645396)
		(width 0.14224)
		(layer "In4.Cu")
		(net "M_E_DQ<62>")
	)
	(segment
		(start 290.99891 -105.234486)
		(end 291.125402 -105.453434)
		(width 0.0889)
		(layer "In4.Cu")
		(net "M_E_DQ<62>")
	)
	(segment
		(start 313.798966 -128.856486)
		(end 314.162694 -129.220214)
		(width 0.14224)
		(layer "In4.Cu")
		(net "M_E_DQ<62>")
	)
	(segment
		(start 291.154104 -105.502964)
		(end 291.508434 -105.857294)
		(width 0.0889)
		(layer "In4.Cu")
		(net "M_E_DQ<62>")
	)
	(segment
		(start 288.428176 -103.1494)
		(end 288.42335 -103.158036)
		(width 0.0889)
		(layer "In4.Cu")
		(net "M_E_DQ<62>")
	)
	(segment
		(start 307.726842 -119.31904)
		(end 308.976268 -119.31904)
		(width 0.14224)
		(layer "In4.Cu")
		(net "M_E_DQ<62>")
	)
	(segment
		(start 314.267596 -138.880596)
		(end 314.267596 -139.333478)
		(width 0.14224)
		(layer "In4.Cu")
		(net "M_E_DQ<62>")
	)
	(segment
		(start 288.42335 -102.167436)
		(end 288.417 -102.178104)
		(width 0.0889)
		(layer "In4.Cu")
		(net "M_E_DQ<62>")
	)
	(segment
		(start 313.944254 -135.932926)
		(end 314.267596 -136.256268)
		(width 0.14224)
		(layer "In4.Cu")
		(net "M_E_DQ<62>")
	)
	(segment
		(start 313.266836 -144.233646)
		(end 314.54979 -145.5166)
		(width 0.14224)
		(layer "In4.Cu")
		(net "M_E_DQ<62>")
	)
	(segment
		(start 314.216796 -131.459478)
		(end 314.216796 -131.953)
		(width 0.14224)
		(layer "In4.Cu")
		(net "M_E_DQ<62>")
	)
	(segment
		(start 287.55848 -100.270818)
		(end 287.56483 -100.281486)
		(width 0.0889)
		(layer "In4.Cu")
		(net "M_E_DQ<62>")
	)
	(segment
		(start 314.267596 -139.333478)
		(end 313.530996 -140.070078)
		(width 0.14224)
		(layer "In4.Cu")
		(net "M_E_DQ<62>")
	)
	(segment
		(start 314.1218 -138.7348)
		(end 314.267596 -138.880596)
		(width 0.14224)
		(layer "In4.Cu")
		(net "M_E_DQ<62>")
	)
	(segment
		(start 314.162694 -129.96418)
		(end 314.064396 -130.062478)
		(width 0.14224)
		(layer "In4.Cu")
		(net "M_E_DQ<62>")
	)
	(segment
		(start 287.56483 -100.281486)
		(end 287.569656 -100.290122)
		(width 0.0889)
		(layer "In4.Cu")
		(net "M_E_DQ<62>")
	)
	(segment
		(start 314.162694 -129.220214)
		(end 314.162694 -129.96418)
		(width 0.14224)
		(layer "In4.Cu")
		(net "M_E_DQ<62>")
	)
	(segment
		(start 313.944254 -134.768336)
		(end 313.944254 -135.932926)
		(width 0.14224)
		(layer "In4.Cu")
		(net "M_E_DQ<62>")
	)
	(segment
		(start 287.21812 -93.547184)
		(end 286.866076 -94.347538)
		(width 0.0889)
		(layer "In4.Cu")
		(net "M_E_DQ<62>")
	)
	(segment
		(start 288.428176 -102.1588)
		(end 288.42335 -102.167436)
		(width 0.0889)
		(layer "In4.Cu")
		(net "M_E_DQ<62>")
	)
	(segment
		(start 291.930582 -106.5149)
		(end 294.922702 -106.5149)
		(width 0.14224)
		(layer "In4.Cu")
		(net "M_E_DQ<62>")
	)
	(segment
		(start 288.91357 -104.043734)
		(end 288.946336 -104.043734)
		(width 0.0889)
		(layer "In4.Cu")
		(net "M_E_DQ<62>")
	)
	(segment
		(start 291.125402 -105.453434)
		(end 291.154104 -105.502964)
		(width 0.0889)
		(layer "In4.Cu")
		(net "M_E_DQ<62>")
	)
	(segment
		(start 314.216796 -134.105396)
		(end 314.216796 -134.495794)
		(width 0.14224)
		(layer "In4.Cu")
		(net "M_E_DQ<62>")
	)
	(segment
		(start 288.05886 -101.567488)
		(end 288.091626 -101.567488)
		(width 0.0889)
		(layer "In4.Cu")
		(net "M_E_DQ<62>")
	)
	(segment
		(start 290.63061 -105.034334)
		(end 290.663376 -105.034334)
		(width 0.0889)
		(layer "In4.Cu")
		(net "M_E_DQ<62>")
	)
	(segment
		(start 313.530996 -140.070078)
		(end 313.530996 -141.044168)
		(width 0.14224)
		(layer "In4.Cu")
		(net "M_E_DQ<62>")
	)
	(segment
		(start 294.922702 -106.5149)
		(end 307.726842 -119.31904)
		(width 0.14224)
		(layer "In4.Cu")
		(net "M_E_DQ<62>")
	)
	(segment
		(start 291.508434 -105.857294)
		(end 291.508434 -106.092752)
		(width 0.0889)
		(layer "In4.Cu")
		(net "M_E_DQ<62>")
	)
	(segment
		(start 289.7759 -104.539288)
		(end 289.808666 -104.539288)
		(width 0.0889)
		(layer "In4.Cu")
		(net "M_E_DQ<62>")
	)
	(segment
		(start 314.1218 -134.0104)
		(end 314.216796 -134.105396)
		(width 0.14224)
		(layer "In4.Cu")
		(net "M_E_DQ<62>")
	)
	(segment
		(start 314.216796 -131.953)
		(end 314.1218 -132.047996)
		(width 0.14224)
		(layer "In4.Cu")
		(net "M_E_DQ<62>")
	)
	(segment
		(start 291.508434 -106.092752)
		(end 291.930582 -106.5149)
		(width 0.14224)
		(layer "In4.Cu")
		(net "M_E_DQ<62>")
	)
	(segment
		(start 313.699906 -141.213078)
		(end 313.266836 -141.646148)
		(width 0.14224)
		(layer "In4.Cu")
		(net "M_E_DQ<62>")
	)
	(segment
		(start 314.1218 -132.047996)
		(end 314.1218 -134.0104)
		(width 0.14224)
		(layer "In4.Cu")
		(net "M_E_DQ<62>")
	)
	(segment
		(start 314.216796 -134.495794)
		(end 313.944254 -134.768336)
		(width 0.14224)
		(layer "In4.Cu")
		(net "M_E_DQ<62>")
	)
	(segment
		(start 288.42335 -103.158036)
		(end 288.417 -103.168704)
		(width 0.0889)
		(layer "In4.Cu")
		(net "M_E_DQ<62>")
	)
	(segment
		(start 313.798966 -124.141738)
		(end 313.798966 -128.856486)
		(width 0.14224)
		(layer "In4.Cu")
		(net "M_E_DQ<62>")
	)
	(segment
		(start 314.064396 -131.307078)
		(end 314.216796 -131.459478)
		(width 0.14224)
		(layer "In4.Cu")
		(net "M_E_DQ<62>")
	)
	(segment
		(start 313.530996 -141.044168)
		(end 313.699906 -141.213078)
		(width 0.14224)
		(layer "In4.Cu")
		(net "M_E_DQ<62>")
	)
	(segment
		(start 308.976268 -119.31904)
		(end 313.798966 -124.141738)
		(width 0.14224)
		(layer "In4.Cu")
		(net "M_E_DQ<62>")
	)
	(segment
		(start 314.064396 -130.062478)
		(end 314.064396 -131.307078)
		(width 0.14224)
		(layer "In4.Cu")
		(net "M_E_DQ<62>")
	)
	(segment
		(start 313.266836 -141.646148)
		(end 313.266836 -144.233646)
		(width 0.14224)
		(layer "In4.Cu")
		(net "M_E_DQ<62>")
	)
	(arc
		(start 288.091626 -101.567488)
		(mid 288.424544 -101.769479)
		(end 288.428176 -102.1588)
		(width 0.0889)
		(layer "In4.Cu")
		(net "M_E_DQ<62>")
	)
	(arc
		(start 286.87141 -95.328486)
		(mid 286.822183 -95.5867)
		(end 286.9438 -95.819722)
		(width 0.0889)
		(layer "In4.Cu")
		(net "M_E_DQ<62>")
	)
	(arc
		(start 287.56483 -98.700082)
		(mid 287.485767 -98.995484)
		(end 287.56483 -99.290886)
		(width 0.0889)
		(layer "In4.Cu")
		(net "M_E_DQ<62>")
	)
	(arc
		(start 286.87141 -94.737682)
		(mid 286.950541 -95.033084)
		(end 286.87141 -95.328486)
		(width 0.0889)
		(layer "In4.Cu")
		(net "M_E_DQ<62>")
	)
	(arc
		(start 288.417 -103.168704)
		(mid 288.421031 -103.744886)
		(end 288.91357 -104.043734)
		(width 0.0889)
		(layer "In4.Cu")
		(net "M_E_DQ<62>")
	)
	(arc
		(start 289.28187 -104.243886)
		(mid 289.490478 -104.455818)
		(end 289.7759 -104.539288)
		(width 0.0889)
		(layer "In4.Cu")
		(net "M_E_DQ<62>")
	)
	(arc
		(start 286.866076 -94.347538)
		(mid 286.817997 -94.543298)
		(end 286.87141 -94.737682)
		(width 0.0889)
		(layer "In4.Cu")
		(net "M_E_DQ<62>")
	)
	(arc
		(start 287.56483 -98.300286)
		(mid 287.618329 -98.500184)
		(end 287.56483 -98.700082)
		(width 0.0889)
		(layer "In4.Cu")
		(net "M_E_DQ<62>")
	)
	(arc
		(start 287.56483 -100.681536)
		(mid 287.560501 -101.264708)
		(end 288.05886 -101.567488)
		(width 0.0889)
		(layer "In4.Cu")
		(net "M_E_DQ<62>")
	)
	(arc
		(start 290.14039 -104.739186)
		(mid 290.347394 -104.95005)
		(end 290.63061 -105.034334)
		(width 0.0889)
		(layer "In4.Cu")
		(net "M_E_DQ<62>")
	)
	(arc
		(start 287.56483 -97.709482)
		(mid 287.485699 -98.004884)
		(end 287.56483 -98.300286)
		(width 0.0889)
		(layer "In4.Cu")
		(net "M_E_DQ<62>")
	)
	(arc
		(start 288.417 -102.178104)
		(mid 288.344202 -102.468867)
		(end 288.42335 -102.757986)
		(width 0.0889)
		(layer "In4.Cu")
		(net "M_E_DQ<62>")
	)
	(arc
		(start 288.946336 -104.043734)
		(mid 289.140186 -104.100084)
		(end 289.28187 -104.243886)
		(width 0.0889)
		(layer "In4.Cu")
		(net "M_E_DQ<62>")
	)
	(arc
		(start 286.9438 -95.819722)
		(mid 287.160403 -96.010704)
		(end 287.404556 -96.164908)
		(width 0.0889)
		(layer "In4.Cu")
		(net "M_E_DQ<62>")
	)
	(arc
		(start 287.569656 -100.290122)
		(mid 287.618411 -100.486474)
		(end 287.56483 -100.681536)
		(width 0.0889)
		(layer "In4.Cu")
		(net "M_E_DQ<62>")
	)
	(arc
		(start 287.56483 -96.319086)
		(mid 287.618363 -96.518984)
		(end 287.56483 -96.718882)
		(width 0.0889)
		(layer "In4.Cu")
		(net "M_E_DQ<62>")
	)
	(arc
		(start 289.808666 -104.539288)
		(mid 290.000308 -104.596454)
		(end 290.14039 -104.739186)
		(width 0.0889)
		(layer "In4.Cu")
		(net "M_E_DQ<62>")
	)
	(arc
		(start 287.56483 -97.309686)
		(mid 287.618329 -97.509584)
		(end 287.56483 -97.709482)
		(width 0.0889)
		(layer "In4.Cu")
		(net "M_E_DQ<62>")
	)
	(arc
		(start 287.404556 -96.164908)
		(mid 287.495667 -96.230595)
		(end 287.56483 -96.319086)
		(width 0.0889)
		(layer "In4.Cu")
		(net "M_E_DQ<62>")
	)
	(arc
		(start 287.56483 -96.718882)
		(mid 287.485699 -97.014284)
		(end 287.56483 -97.309686)
		(width 0.0889)
		(layer "In4.Cu")
		(net "M_E_DQ<62>")
	)
	(arc
		(start 287.569656 -99.299522)
		(mid 287.618411 -99.495874)
		(end 287.56483 -99.690936)
		(width 0.0889)
		(layer "In4.Cu")
		(net "M_E_DQ<62>")
	)
	(arc
		(start 290.663376 -105.034334)
		(mid 290.857226 -105.090684)
		(end 290.99891 -105.234486)
		(width 0.0889)
		(layer "In4.Cu")
		(net "M_E_DQ<62>")
	)
	(arc
		(start 287.56483 -99.690936)
		(mid 287.485608 -99.980054)
		(end 287.55848 -100.270818)
		(width 0.0889)
		(layer "In4.Cu")
		(net "M_E_DQ<62>")
	)
	(arc
		(start 288.42335 -102.757986)
		(mid 288.47682 -102.953049)
		(end 288.428176 -103.1494)
		(width 0.0889)
		(layer "In4.Cu")
		(net "M_E_DQ<62>")
	)
	(segment
		(start 307.750464 -142.6718)
		(end 307.749956 -142.677642)
		(width 0.1651)
		(layer "F.Cu")
		(net "M_E_DQ<61>")
	)
	(segment
		(start 307.749956 -142.677642)
		(end 307.749956 -143.941546)
		(width 0.1651)
		(layer "F.Cu")
		(net "M_E_DQ<61>")
	)
	(segment
		(start 284.071314 -95.033084)
		(end 284.642814 -95.033084)
		(width 0.1651)
		(layer "F.Cu")
		(net "M_E_DQ<61>")
	)
	(via
		(at 284.642814 -95.033084)
		(size 0.508)
		(drill 0.254)
		(layers "F.Cu" "B.Cu")
		(net "M_E_DQ<61>")
	)
	(via
		(at 307.749956 -143.941546)
		(size 0.508)
		(drill 0.254)
		(layers "F.Cu" "B.Cu")
		(net "M_E_DQ<61>")
	)
	(via
		(at 308.577996 -139.845796)
		(size 0.508)
		(drill 0.254)
		(layers "F.Cu" "B.Cu")
		(net "M_E_DQ<61>")
	)
	(segment
		(start 308.600348 -137.877296)
		(end 308.59984 -137.877296)
		(width 0.1651)
		(layer "B.Cu")
		(net "M_E_DQ<61>")
	)
	(segment
		(start 308.59984 -137.877296)
		(end 308.59984 -139.823952)
		(width 0.1651)
		(layer "B.Cu")
		(net "M_E_DQ<61>")
	)
	(segment
		(start 308.59984 -139.823952)
		(end 308.577996 -139.845796)
		(width 0.1651)
		(layer "B.Cu")
		(net "M_E_DQ<61>")
	)
	(segment
		(start 308.073044 -140.9192)
		(end 308.200044 -141.0462)
		(width 0.14224)
		(layer "In4.Cu")
		(net "M_E_DQ<61>")
	)
	(segment
		(start 284.296104 -101.176836)
		(end 284.302454 -101.187504)
		(width 0.0889)
		(layer "In4.Cu")
		(net "M_E_DQ<61>")
	)
	(segment
		(start 285.154624 -105.234486)
		(end 285.149798 -105.243122)
		(width 0.0889)
		(layer "In4.Cu")
		(net "M_E_DQ<61>")
	)
	(segment
		(start 309.0164 -129.895346)
		(end 309.0164 -131.351274)
		(width 0.14224)
		(layer "In4.Cu")
		(net "M_E_DQ<61>")
	)
	(segment
		(start 303.323498 -121.770648)
		(end 303.676558 -121.770648)
		(width 0.14224)
		(layer "In4.Cu")
		(net "M_E_DQ<61>")
	)
	(segment
		(start 305.157378 -121.925588)
		(end 305.157378 -122.318272)
		(width 0.14224)
		(layer "In4.Cu")
		(net "M_E_DQ<61>")
	)
	(segment
		(start 308.174644 -143.561054)
		(end 308.174644 -143.789146)
		(width 0.14224)
		(layer "In4.Cu")
		(net "M_E_DQ<61>")
	)
	(segment
		(start 303.168558 -122.318272)
		(end 303.168558 -121.925588)
		(width 0.14224)
		(layer "In4.Cu")
		(net "M_E_DQ<61>")
	)
	(segment
		(start 307.911246 -142.985744)
		(end 307.911246 -143.297656)
		(width 0.14224)
		(layer "In4.Cu")
		(net "M_E_DQ<61>")
	)
	(segment
		(start 308.933596 -134.670038)
		(end 309.060596 -134.797038)
		(width 0.14224)
		(layer "In4.Cu")
		(net "M_E_DQ<61>")
	)
	(segment
		(start 308.908196 -139.5476)
		(end 308.61 -139.845796)
		(width 0.14224)
		(layer "In4.Cu")
		(net "M_E_DQ<61>")
	)
	(segment
		(start 308.149244 -142.747746)
		(end 307.911246 -142.985744)
		(width 0.14224)
		(layer "In4.Cu")
		(net "M_E_DQ<61>")
	)
	(segment
		(start 284.642814 -95.033084)
		(end 284.356048 -95.679006)
		(width 0.0889)
		(layer "In4.Cu")
		(net "M_E_DQ<61>")
	)
	(segment
		(start 303.831498 -122.318272)
		(end 303.986438 -122.473212)
		(width 0.14224)
		(layer "In4.Cu")
		(net "M_E_DQ<61>")
	)
	(segment
		(start 308.908196 -138.944604)
		(end 308.908196 -139.5476)
		(width 0.14224)
		(layer "In4.Cu")
		(net "M_E_DQ<61>")
	)
	(segment
		(start 305.312318 -122.473212)
		(end 306.071524 -122.473212)
		(width 0.14224)
		(layer "In4.Cu")
		(net "M_E_DQ<61>")
	)
	(segment
		(start 308.577996 -139.855448)
		(end 308.073044 -140.3604)
		(width 0.14224)
		(layer "In4.Cu")
		(net "M_E_DQ<61>")
	)
	(segment
		(start 285.486348 -105.834434)
		(end 285.519114 -105.834434)
		(width 0.0889)
		(layer "In4.Cu")
		(net "M_E_DQ<61>")
	)
	(segment
		(start 308.908196 -125.309884)
		(end 308.908196 -129.787142)
		(width 0.14224)
		(layer "In4.Cu")
		(net "M_E_DQ<61>")
	)
	(segment
		(start 304.494438 -122.318272)
		(end 304.494438 -121.925588)
		(width 0.14224)
		(layer "In4.Cu")
		(net "M_E_DQ<61>")
	)
	(segment
		(start 307.911246 -143.297656)
		(end 308.174644 -143.561054)
		(width 0.14224)
		(layer "In4.Cu")
		(net "M_E_DQ<61>")
	)
	(segment
		(start 307.911246 -141.817344)
		(end 307.911246 -142.154656)
		(width 0.14224)
		(layer "In4.Cu")
		(net "M_E_DQ<61>")
	)
	(segment
		(start 284.296104 -102.167436)
		(end 284.302454 -102.178104)
		(width 0.0889)
		(layer "In4.Cu")
		(net "M_E_DQ<61>")
	)
	(segment
		(start 286.871664 -106.624882)
		(end 287.046924 -106.929682)
		(width 0.0889)
		(layer "In4.Cu")
		(net "M_E_DQ<61>")
	)
	(segment
		(start 287.30956 -111.777272)
		(end 290.599622 -115.067334)
		(width 0.14224)
		(layer "In4.Cu")
		(net "M_E_DQ<61>")
	)
	(segment
		(start 290.599622 -115.067334)
		(end 293.65448 -115.067334)
		(width 0.14224)
		(layer "In4.Cu")
		(net "M_E_DQ<61>")
	)
	(segment
		(start 305.002438 -121.770648)
		(end 305.157378 -121.925588)
		(width 0.14224)
		(layer "In4.Cu")
		(net "M_E_DQ<61>")
	)
	(segment
		(start 308.200044 -141.0462)
		(end 308.200044 -141.528546)
		(width 0.14224)
		(layer "In4.Cu")
		(net "M_E_DQ<61>")
	)
	(segment
		(start 308.908196 -136.005824)
		(end 308.908196 -136.5504)
		(width 0.14224)
		(layer "In4.Cu")
		(net "M_E_DQ<61>")
	)
	(segment
		(start 301.060358 -122.473212)
		(end 303.013618 -122.473212)
		(width 0.14224)
		(layer "In4.Cu")
		(net "M_E_DQ<61>")
	)
	(segment
		(start 308.908196 -136.5504)
		(end 309.0164 -136.658604)
		(width 0.14224)
		(layer "In4.Cu")
		(net "M_E_DQ<61>")
	)
	(segment
		(start 286.347408 -106.329734)
		(end 286.3596 -106.329734)
		(width 0.0889)
		(layer "In4.Cu")
		(net "M_E_DQ<61>")
	)
	(segment
		(start 308.61 -139.845796)
		(end 308.577996 -139.845796)
		(width 0.14224)
		(layer "In4.Cu")
		(net "M_E_DQ<61>")
	)
	(segment
		(start 304.494438 -121.925588)
		(end 304.649378 -121.770648)
		(width 0.14224)
		(layer "In4.Cu")
		(net "M_E_DQ<61>")
	)
	(segment
		(start 287.046924 -106.929682)
		(end 287.046924 -107.214924)
		(width 0.0889)
		(layer "In4.Cu")
		(net "M_E_DQ<61>")
	)
	(segment
		(start 308.908196 -129.787142)
		(end 309.0164 -129.895346)
		(width 0.14224)
		(layer "In4.Cu")
		(net "M_E_DQ<61>")
	)
	(segment
		(start 308.022244 -143.941546)
		(end 307.749956 -143.941546)
		(width 0.14224)
		(layer "In4.Cu")
		(net "M_E_DQ<61>")
	)
	(segment
		(start 303.831498 -121.925588)
		(end 303.831498 -122.318272)
		(width 0.14224)
		(layer "In4.Cu")
		(net "M_E_DQ<61>")
	)
	(segment
		(start 284.291278 -100.1776)
		(end 284.296104 -100.186236)
		(width 0.0889)
		(layer "In4.Cu")
		(net "M_E_DQ<61>")
	)
	(segment
		(start 293.65448 -115.067334)
		(end 301.060358 -122.473212)
		(width 0.14224)
		(layer "In4.Cu")
		(net "M_E_DQ<61>")
	)
	(segment
		(start 285.160974 -105.223818)
		(end 285.154624 -105.234486)
		(width 0.0889)
		(layer "In4.Cu")
		(net "M_E_DQ<61>")
	)
	(segment
		(start 306.071524 -122.473212)
		(end 308.908196 -125.309884)
		(width 0.14224)
		(layer "In4.Cu")
		(net "M_E_DQ<61>")
	)
	(segment
		(start 309.060596 -134.797038)
		(end 309.060596 -135.853424)
		(width 0.14224)
		(layer "In4.Cu")
		(net "M_E_DQ<61>")
	)
	(segment
		(start 303.168558 -121.925588)
		(end 303.323498 -121.770648)
		(width 0.14224)
		(layer "In4.Cu")
		(net "M_E_DQ<61>")
	)
	(segment
		(start 303.013618 -122.473212)
		(end 303.168558 -122.318272)
		(width 0.14224)
		(layer "In4.Cu")
		(net "M_E_DQ<61>")
	)
	(segment
		(start 286.3596 -106.329734)
		(end 286.384492 -106.32948)
		(width 0.0889)
		(layer "In4.Cu")
		(net "M_E_DQ<61>")
	)
	(segment
		(start 304.339498 -122.473212)
		(end 304.494438 -122.318272)
		(width 0.14224)
		(layer "In4.Cu")
		(net "M_E_DQ<61>")
	)
	(segment
		(start 308.149244 -142.392654)
		(end 308.149244 -142.747746)
		(width 0.14224)
		(layer "In4.Cu")
		(net "M_E_DQ<61>")
	)
	(segment
		(start 307.911246 -142.154656)
		(end 308.149244 -142.392654)
		(width 0.14224)
		(layer "In4.Cu")
		(net "M_E_DQ<61>")
	)
	(segment
		(start 308.200044 -141.528546)
		(end 307.911246 -141.817344)
		(width 0.14224)
		(layer "In4.Cu")
		(net "M_E_DQ<61>")
	)
	(segment
		(start 284.291278 -102.1588)
		(end 284.296104 -102.167436)
		(width 0.0889)
		(layer "In4.Cu")
		(net "M_E_DQ<61>")
	)
	(segment
		(start 303.676558 -121.770648)
		(end 303.831498 -121.925588)
		(width 0.14224)
		(layer "In4.Cu")
		(net "M_E_DQ<61>")
	)
	(segment
		(start 308.933596 -134.093204)
		(end 308.933596 -134.670038)
		(width 0.14224)
		(layer "In4.Cu")
		(net "M_E_DQ<61>")
	)
	(segment
		(start 303.986438 -122.473212)
		(end 304.339498 -122.473212)
		(width 0.14224)
		(layer "In4.Cu")
		(net "M_E_DQ<61>")
	)
	(segment
		(start 285.160974 -104.233218)
		(end 285.154624 -104.243886)
		(width 0.0889)
		(layer "In4.Cu")
		(net "M_E_DQ<61>")
	)
	(segment
		(start 284.296104 -100.186236)
		(end 284.302454 -100.196904)
		(width 0.0889)
		(layer "In4.Cu")
		(net "M_E_DQ<61>")
	)
	(segment
		(start 308.174644 -143.789146)
		(end 308.022244 -143.941546)
		(width 0.14224)
		(layer "In4.Cu")
		(net "M_E_DQ<61>")
	)
	(segment
		(start 305.157378 -122.318272)
		(end 305.312318 -122.473212)
		(width 0.14224)
		(layer "In4.Cu")
		(net "M_E_DQ<61>")
	)
	(segment
		(start 309.0418 -132.061204)
		(end 309.0418 -133.985)
		(width 0.14224)
		(layer "In4.Cu")
		(net "M_E_DQ<61>")
	)
	(segment
		(start 308.933596 -131.434078)
		(end 308.933596 -131.953)
		(width 0.14224)
		(layer "In4.Cu")
		(net "M_E_DQ<61>")
	)
	(segment
		(start 309.0164 -138.8364)
		(end 308.908196 -138.944604)
		(width 0.14224)
		(layer "In4.Cu")
		(net "M_E_DQ<61>")
	)
	(segment
		(start 308.933596 -131.953)
		(end 309.0418 -132.061204)
		(width 0.14224)
		(layer "In4.Cu")
		(net "M_E_DQ<61>")
	)
	(segment
		(start 309.060596 -135.853424)
		(end 308.908196 -136.005824)
		(width 0.14224)
		(layer "In4.Cu")
		(net "M_E_DQ<61>")
	)
	(segment
		(start 309.0418 -133.985)
		(end 308.933596 -134.093204)
		(width 0.14224)
		(layer "In4.Cu")
		(net "M_E_DQ<61>")
	)
	(segment
		(start 309.0164 -131.351274)
		(end 308.933596 -131.434078)
		(width 0.14224)
		(layer "In4.Cu")
		(net "M_E_DQ<61>")
	)
	(segment
		(start 308.577996 -139.845796)
		(end 308.577996 -139.855448)
		(width 0.14224)
		(layer "In4.Cu")
		(net "M_E_DQ<61>")
	)
	(segment
		(start 304.649378 -121.770648)
		(end 305.002438 -121.770648)
		(width 0.14224)
		(layer "In4.Cu")
		(net "M_E_DQ<61>")
	)
	(segment
		(start 284.631638 -103.358188)
		(end 284.664404 -103.358188)
		(width 0.0889)
		(layer "In4.Cu")
		(net "M_E_DQ<61>")
	)
	(segment
		(start 287.046924 -107.214924)
		(end 287.30956 -107.47756)
		(width 0.0889)
		(layer "In4.Cu")
		(net "M_E_DQ<61>")
	)
	(segment
		(start 285.154624 -104.243886)
		(end 285.149798 -104.252522)
		(width 0.0889)
		(layer "In4.Cu")
		(net "M_E_DQ<61>")
	)
	(segment
		(start 287.30956 -107.47756)
		(end 287.30956 -111.777272)
		(width 0.14224)
		(layer "In4.Cu")
		(net "M_E_DQ<61>")
	)
	(segment
		(start 308.073044 -140.3604)
		(end 308.073044 -140.9192)
		(width 0.14224)
		(layer "In4.Cu")
		(net "M_E_DQ<61>")
	)
	(segment
		(start 309.0164 -136.658604)
		(end 309.0164 -138.8364)
		(width 0.14224)
		(layer "In4.Cu")
		(net "M_E_DQ<61>")
	)
	(segment
		(start 284.291278 -101.1682)
		(end 284.296104 -101.176836)
		(width 0.0889)
		(layer "In4.Cu")
		(net "M_E_DQ<61>")
	)
	(arc
		(start 284.302454 -100.196904)
		(mid 284.375252 -100.487667)
		(end 284.296104 -100.776786)
		(width 0.0889)
		(layer "In4.Cu")
		(net "M_E_DQ<61>")
	)
	(arc
		(start 284.296358 -97.804986)
		(mid 284.242859 -98.004884)
		(end 284.296358 -98.204782)
		(width 0.0889)
		(layer "In4.Cu")
		(net "M_E_DQ<61>")
	)
	(arc
		(start 284.296104 -101.767386)
		(mid 284.242634 -101.962449)
		(end 284.291278 -102.1588)
		(width 0.0889)
		(layer "In4.Cu")
		(net "M_E_DQ<61>")
	)
	(arc
		(start 284.302454 -102.178104)
		(mid 284.375252 -102.468867)
		(end 284.296104 -102.757986)
		(width 0.0889)
		(layer "In4.Cu")
		(net "M_E_DQ<61>")
	)
	(arc
		(start 284.296104 -99.786186)
		(mid 284.242634 -99.981249)
		(end 284.291278 -100.1776)
		(width 0.0889)
		(layer "In4.Cu")
		(net "M_E_DQ<61>")
	)
	(arc
		(start 284.296358 -96.223582)
		(mid 284.375489 -96.518984)
		(end 284.296358 -96.814386)
		(width 0.0889)
		(layer "In4.Cu")
		(net "M_E_DQ<61>")
	)
	(arc
		(start 284.296104 -102.757986)
		(mid 284.293356 -103.153453)
		(end 284.631638 -103.358188)
		(width 0.0889)
		(layer "In4.Cu")
		(net "M_E_DQ<61>")
	)
	(arc
		(start 284.296358 -97.214182)
		(mid 284.375489 -97.509584)
		(end 284.296358 -97.804986)
		(width 0.0889)
		(layer "In4.Cu")
		(net "M_E_DQ<61>")
	)
	(arc
		(start 284.296358 -99.195382)
		(mid 284.299445 -99.200821)
		(end 284.302454 -99.206304)
		(width 0.0889)
		(layer "In4.Cu")
		(net "M_E_DQ<61>")
	)
	(arc
		(start 284.296358 -98.204782)
		(mid 284.375489 -98.500184)
		(end 284.296358 -98.795586)
		(width 0.0889)
		(layer "In4.Cu")
		(net "M_E_DQ<61>")
	)
	(arc
		(start 285.149798 -104.252522)
		(mid 285.101043 -104.448874)
		(end 285.154624 -104.643936)
		(width 0.0889)
		(layer "In4.Cu")
		(net "M_E_DQ<61>")
	)
	(arc
		(start 284.664404 -103.358188)
		(mid 285.156794 -103.657121)
		(end 285.160974 -104.233218)
		(width 0.0889)
		(layer "In4.Cu")
		(net "M_E_DQ<61>")
	)
	(arc
		(start 284.356048 -95.679006)
		(mid 284.331024 -95.753384)
		(end 284.296358 -95.823786)
		(width 0.0889)
		(layer "In4.Cu")
		(net "M_E_DQ<61>")
	)
	(arc
		(start 284.296358 -96.814386)
		(mid 284.242859 -97.014284)
		(end 284.296358 -97.214182)
		(width 0.0889)
		(layer "In4.Cu")
		(net "M_E_DQ<61>")
	)
	(arc
		(start 284.296358 -95.823786)
		(mid 284.242859 -96.023684)
		(end 284.296358 -96.223582)
		(width 0.0889)
		(layer "In4.Cu")
		(net "M_E_DQ<61>")
	)
	(arc
		(start 284.302454 -99.206304)
		(mid 284.375252 -99.497067)
		(end 284.296104 -99.786186)
		(width 0.0889)
		(layer "In4.Cu")
		(net "M_E_DQ<61>")
	)
	(arc
		(start 285.519114 -105.834434)
		(mid 285.804538 -105.917901)
		(end 286.013144 -106.129836)
		(width 0.0889)
		(layer "In4.Cu")
		(net "M_E_DQ<61>")
	)
	(arc
		(start 286.013144 -106.129836)
		(mid 286.154301 -106.273221)
		(end 286.347408 -106.329734)
		(width 0.0889)
		(layer "In4.Cu")
		(net "M_E_DQ<61>")
	)
	(arc
		(start 285.154624 -104.643936)
		(mid 285.233846 -104.933054)
		(end 285.160974 -105.223818)
		(width 0.0889)
		(layer "In4.Cu")
		(net "M_E_DQ<61>")
	)
	(arc
		(start 284.296358 -98.795586)
		(mid 284.242859 -98.995484)
		(end 284.296358 -99.195382)
		(width 0.0889)
		(layer "In4.Cu")
		(net "M_E_DQ<61>")
	)
	(arc
		(start 284.302454 -101.187504)
		(mid 284.375252 -101.478267)
		(end 284.296104 -101.767386)
		(width 0.0889)
		(layer "In4.Cu")
		(net "M_E_DQ<61>")
	)
	(arc
		(start 284.296104 -100.776786)
		(mid 284.242634 -100.971849)
		(end 284.291278 -101.1682)
		(width 0.0889)
		(layer "In4.Cu")
		(net "M_E_DQ<61>")
	)
	(arc
		(start 285.149798 -105.243122)
		(mid 285.153545 -105.632378)
		(end 285.486348 -105.834434)
		(width 0.0889)
		(layer "In4.Cu")
		(net "M_E_DQ<61>")
	)
	(arc
		(start 286.384492 -106.32948)
		(mid 286.666002 -106.414616)
		(end 286.871664 -106.624882)
		(width 0.0889)
		(layer "In4.Cu")
		(net "M_E_DQ<61>")
	)
	(segment
		(start 308.600348 -147.27174)
		(end 308.59984 -147.27174)
		(width 0.1651)
		(layer "F.Cu")
		(net "M_E_DQ<60>")
	)
	(segment
		(start 284.071314 -94.042738)
		(end 284.642814 -94.042738)
		(width 0.1651)
		(layer "F.Cu")
		(net "M_E_DQ<60>")
	)
	(segment
		(start 308.59984 -145.946368)
		(end 308.501796 -145.415)
		(width 0.1651)
		(layer "F.Cu")
		(net "M_E_DQ<60>")
	)
	(segment
		(start 308.59984 -147.27174)
		(end 308.59984 -145.946368)
		(width 0.1651)
		(layer "F.Cu")
		(net "M_E_DQ<60>")
	)
	(via
		(at 307.749956 -141.213078)
		(size 0.508)
		(drill 0.254)
		(layers "F.Cu" "B.Cu")
		(net "M_E_DQ<60>")
	)
	(via
		(at 308.501796 -145.415)
		(size 0.508)
		(drill 0.254)
		(layers "F.Cu" "B.Cu")
		(net "M_E_DQ<60>")
	)
	(via
		(at 284.642814 -94.042738)
		(size 0.508)
		(drill 0.254)
		(layers "F.Cu" "B.Cu")
		(net "M_E_DQ<60>")
	)
	(segment
		(start 307.750464 -142.477236)
		(end 307.749956 -142.476982)
		(width 0.1651)
		(layer "B.Cu")
		(net "M_E_DQ<60>")
	)
	(segment
		(start 307.749956 -142.476982)
		(end 307.749956 -141.213078)
		(width 0.1651)
		(layer "B.Cu")
		(net "M_E_DQ<60>")
	)
	(segment
		(start 286.856424 -106.98099)
		(end 286.856424 -107.186476)
		(width 0.0889)
		(layer "In4.Cu")
		(net "M_E_DQ<60>")
	)
	(segment
		(start 308.1782 -138.7602)
		(end 308.235096 -138.817096)
		(width 0.14224)
		(layer "In4.Cu")
		(net "M_E_DQ<60>")
	)
	(segment
		(start 307.749956 -141.213078)
		(end 307.316886 -141.646148)
		(width 0.14224)
		(layer "In4.Cu")
		(net "M_E_DQ<60>")
	)
	(segment
		(start 286.334962 -106.520488)
		(end 286.359854 -106.520234)
		(width 0.0889)
		(layer "In4.Cu")
		(net "M_E_DQ<60>")
	)
	(segment
		(start 300.86935 -123.144534)
		(end 305.48707 -123.144534)
		(width 0.14224)
		(layer "In4.Cu")
		(net "M_E_DQ<60>")
	)
	(segment
		(start 284.99435 -105.1306)
		(end 284.989524 -105.139236)
		(width 0.0889)
		(layer "In4.Cu")
		(net "M_E_DQ<60>")
	)
	(segment
		(start 308.273196 -125.93066)
		(end 308.273196 -129.732278)
		(width 0.14224)
		(layer "In4.Cu")
		(net "M_E_DQ<60>")
	)
	(segment
		(start 284.625034 -103.548688)
		(end 284.6578 -103.548688)
		(width 0.0889)
		(layer "In4.Cu")
		(net "M_E_DQ<60>")
	)
	(segment
		(start 308.235096 -138.817096)
		(end 308.235096 -139.358878)
		(width 0.14224)
		(layer "In4.Cu")
		(net "M_E_DQ<60>")
	)
	(segment
		(start 307.434996 -140.158978)
		(end 307.434996 -140.898118)
		(width 0.14224)
		(layer "In4.Cu")
		(net "M_E_DQ<60>")
	)
	(segment
		(start 285.844488 -106.219244)
		(end 285.84779 -106.225086)
		(width 0.0889)
		(layer "In4.Cu")
		(net "M_E_DQ<60>")
	)
	(segment
		(start 308.247796 -134.130796)
		(end 308.247796 -134.47395)
		(width 0.14224)
		(layer "In4.Cu")
		(net "M_E_DQ<60>")
	)
	(segment
		(start 307.316886 -141.646148)
		(end 307.316886 -144.17929)
		(width 0.14224)
		(layer "In4.Cu")
		(net "M_E_DQ<60>")
	)
	(segment
		(start 308.247796 -134.47395)
		(end 307.981604 -134.740142)
		(width 0.14224)
		(layer "In4.Cu")
		(net "M_E_DQ<60>")
	)
	(segment
		(start 284.99435 -104.14)
		(end 284.989524 -104.148636)
		(width 0.0889)
		(layer "In4.Cu")
		(net "M_E_DQ<60>")
	)
	(segment
		(start 308.019196 -131.180078)
		(end 308.247796 -131.408678)
		(width 0.14224)
		(layer "In4.Cu")
		(net "M_E_DQ<60>")
	)
	(segment
		(start 284.124654 -101.261418)
		(end 284.131004 -101.272086)
		(width 0.0889)
		(layer "In4.Cu")
		(net "M_E_DQ<60>")
	)
	(segment
		(start 308.247796 -131.408678)
		(end 308.247796 -131.8768)
		(width 0.14224)
		(layer "In4.Cu")
		(net "M_E_DQ<60>")
	)
	(segment
		(start 290.401248 -115.546124)
		(end 293.27094 -115.546124)
		(width 0.14224)
		(layer "In4.Cu")
		(net "M_E_DQ<60>")
	)
	(segment
		(start 286.359854 -106.520234)
		(end 286.372046 -106.520234)
		(width 0.0889)
		(layer "In4.Cu")
		(net "M_E_DQ<60>")
	)
	(segment
		(start 284.989524 -105.139236)
		(end 284.983174 -105.149904)
		(width 0.0889)
		(layer "In4.Cu")
		(net "M_E_DQ<60>")
	)
	(segment
		(start 308.273196 -129.732278)
		(end 308.019196 -129.986278)
		(width 0.14224)
		(layer "In4.Cu")
		(net "M_E_DQ<60>")
	)
	(segment
		(start 284.642814 -94.042738)
		(end 284.099508 -94.801436)
		(width 0.0889)
		(layer "In4.Cu")
		(net "M_E_DQ<60>")
	)
	(segment
		(start 307.434996 -140.898118)
		(end 307.749956 -141.213078)
		(width 0.14224)
		(layer "In4.Cu")
		(net "M_E_DQ<60>")
	)
	(segment
		(start 307.316886 -144.17929)
		(end 307.474874 -144.337278)
		(width 0.14224)
		(layer "In4.Cu")
		(net "M_E_DQ<60>")
	)
	(segment
		(start 308.247796 -131.8768)
		(end 308.1782 -131.946396)
		(width 0.14224)
		(layer "In4.Cu")
		(net "M_E_DQ<60>")
	)
	(segment
		(start 307.981604 -134.740142)
		(end 307.981604 -135.926576)
		(width 0.14224)
		(layer "In4.Cu")
		(net "M_E_DQ<60>")
	)
	(segment
		(start 305.48707 -123.144534)
		(end 308.273196 -125.93066)
		(width 0.14224)
		(layer "In4.Cu")
		(net "M_E_DQ<60>")
	)
	(segment
		(start 284.989524 -104.148636)
		(end 284.983174 -104.159304)
		(width 0.0889)
		(layer "In4.Cu")
		(net "M_E_DQ<60>")
	)
	(segment
		(start 286.67456 -111.819436)
		(end 290.401248 -115.546124)
		(width 0.14224)
		(layer "In4.Cu")
		(net "M_E_DQ<60>")
	)
	(segment
		(start 308.235096 -139.358878)
		(end 307.434996 -140.158978)
		(width 0.14224)
		(layer "In4.Cu")
		(net "M_E_DQ<60>")
	)
	(segment
		(start 307.981604 -135.926576)
		(end 308.235096 -136.180068)
		(width 0.14224)
		(layer "In4.Cu")
		(net "M_E_DQ<60>")
	)
	(segment
		(start 285.479744 -106.024934)
		(end 285.501334 -106.024934)
		(width 0.0889)
		(layer "In4.Cu")
		(net "M_E_DQ<60>")
	)
	(segment
		(start 286.856424 -107.186476)
		(end 286.67456 -107.36834)
		(width 0.0889)
		(layer "In4.Cu")
		(net "M_E_DQ<60>")
	)
	(segment
		(start 293.27094 -115.546124)
		(end 300.86935 -123.144534)
		(width 0.14224)
		(layer "In4.Cu")
		(net "M_E_DQ<60>")
	)
	(segment
		(start 308.235096 -136.6266)
		(end 308.1782 -136.683496)
		(width 0.14224)
		(layer "In4.Cu")
		(net "M_E_DQ<60>")
	)
	(segment
		(start 308.235096 -136.180068)
		(end 308.235096 -136.6266)
		(width 0.14224)
		(layer "In4.Cu")
		(net "M_E_DQ<60>")
	)
	(segment
		(start 307.474874 -144.63903)
		(end 308.250844 -145.415)
		(width 0.14224)
		(layer "In4.Cu")
		(net "M_E_DQ<60>")
	)
	(segment
		(start 308.019196 -129.986278)
		(end 308.019196 -131.180078)
		(width 0.14224)
		(layer "In4.Cu")
		(net "M_E_DQ<60>")
	)
	(segment
		(start 284.124654 -100.270818)
		(end 284.131004 -100.281486)
		(width 0.0889)
		(layer "In4.Cu")
		(net "M_E_DQ<60>")
	)
	(segment
		(start 308.1782 -134.0612)
		(end 308.247796 -134.130796)
		(width 0.14224)
		(layer "In4.Cu")
		(net "M_E_DQ<60>")
	)
	(segment
		(start 308.1782 -131.946396)
		(end 308.1782 -134.0612)
		(width 0.14224)
		(layer "In4.Cu")
		(net "M_E_DQ<60>")
	)
	(segment
		(start 284.124654 -102.252018)
		(end 284.131004 -102.262686)
		(width 0.0889)
		(layer "In4.Cu")
		(net "M_E_DQ<60>")
	)
	(segment
		(start 284.131004 -100.281486)
		(end 284.13583 -100.290122)
		(width 0.0889)
		(layer "In4.Cu")
		(net "M_E_DQ<60>")
	)
	(segment
		(start 286.67456 -107.36834)
		(end 286.67456 -111.819436)
		(width 0.14224)
		(layer "In4.Cu")
		(net "M_E_DQ<60>")
	)
	(segment
		(start 286.70631 -106.720132)
		(end 286.856424 -106.98099)
		(width 0.0889)
		(layer "In4.Cu")
		(net "M_E_DQ<60>")
	)
	(segment
		(start 308.250844 -145.415)
		(end 308.501796 -145.415)
		(width 0.14224)
		(layer "In4.Cu")
		(net "M_E_DQ<60>")
	)
	(segment
		(start 284.131004 -102.262686)
		(end 284.13583 -102.271322)
		(width 0.0889)
		(layer "In4.Cu")
		(net "M_E_DQ<60>")
	)
	(segment
		(start 308.1782 -136.683496)
		(end 308.1782 -138.7602)
		(width 0.14224)
		(layer "In4.Cu")
		(net "M_E_DQ<60>")
	)
	(segment
		(start 307.474874 -144.337278)
		(end 307.474874 -144.63903)
		(width 0.14224)
		(layer "In4.Cu")
		(net "M_E_DQ<60>")
	)
	(segment
		(start 284.131004 -101.272086)
		(end 284.13583 -101.280722)
		(width 0.0889)
		(layer "In4.Cu")
		(net "M_E_DQ<60>")
	)
	(arc
		(start 284.983174 -105.149904)
		(mid 284.987205 -105.726086)
		(end 285.479744 -106.024934)
		(width 0.0889)
		(layer "In4.Cu")
		(net "M_E_DQ<60>")
	)
	(arc
		(start 284.131258 -97.309686)
		(mid 284.184757 -97.509584)
		(end 284.131258 -97.709482)
		(width 0.0889)
		(layer "In4.Cu")
		(net "M_E_DQ<60>")
	)
	(arc
		(start 285.501334 -106.024934)
		(mid 285.698495 -106.076893)
		(end 285.844488 -106.219244)
		(width 0.0889)
		(layer "In4.Cu")
		(net "M_E_DQ<60>")
	)
	(arc
		(start 286.372046 -106.520234)
		(mid 286.565149 -106.576753)
		(end 286.70631 -106.720132)
		(width 0.0889)
		(layer "In4.Cu")
		(net "M_E_DQ<60>")
	)
	(arc
		(start 284.131258 -97.709482)
		(mid 284.052127 -98.004884)
		(end 284.131258 -98.300286)
		(width 0.0889)
		(layer "In4.Cu")
		(net "M_E_DQ<60>")
	)
	(arc
		(start 284.131258 -98.300286)
		(mid 284.184757 -98.500184)
		(end 284.131258 -98.700082)
		(width 0.0889)
		(layer "In4.Cu")
		(net "M_E_DQ<60>")
	)
	(arc
		(start 284.131258 -96.319086)
		(mid 284.184757 -96.518984)
		(end 284.131258 -96.718882)
		(width 0.0889)
		(layer "In4.Cu")
		(net "M_E_DQ<60>")
	)
	(arc
		(start 284.989524 -104.739186)
		(mid 285.042994 -104.934249)
		(end 284.99435 -105.1306)
		(width 0.0889)
		(layer "In4.Cu")
		(net "M_E_DQ<60>")
	)
	(arc
		(start 284.131004 -101.672136)
		(mid 284.051782 -101.961254)
		(end 284.124654 -102.252018)
		(width 0.0889)
		(layer "In4.Cu")
		(net "M_E_DQ<60>")
	)
	(arc
		(start 285.84779 -106.225086)
		(mid 286.053407 -106.435427)
		(end 286.334962 -106.520488)
		(width 0.0889)
		(layer "In4.Cu")
		(net "M_E_DQ<60>")
	)
	(arc
		(start 284.131004 -102.662736)
		(mid 284.126675 -103.245908)
		(end 284.625034 -103.548688)
		(width 0.0889)
		(layer "In4.Cu")
		(net "M_E_DQ<60>")
	)
	(arc
		(start 284.6578 -103.548688)
		(mid 284.990718 -103.750679)
		(end 284.99435 -104.14)
		(width 0.0889)
		(layer "In4.Cu")
		(net "M_E_DQ<60>")
	)
	(arc
		(start 284.13583 -102.271322)
		(mid 284.184585 -102.467674)
		(end 284.131004 -102.662736)
		(width 0.0889)
		(layer "In4.Cu")
		(net "M_E_DQ<60>")
	)
	(arc
		(start 284.983174 -104.159304)
		(mid 284.910376 -104.450067)
		(end 284.989524 -104.739186)
		(width 0.0889)
		(layer "In4.Cu")
		(net "M_E_DQ<60>")
	)
	(arc
		(start 284.131004 -100.681536)
		(mid 284.051782 -100.970654)
		(end 284.124654 -101.261418)
		(width 0.0889)
		(layer "In4.Cu")
		(net "M_E_DQ<60>")
	)
	(arc
		(start 284.13583 -100.290122)
		(mid 284.184585 -100.486474)
		(end 284.131004 -100.681536)
		(width 0.0889)
		(layer "In4.Cu")
		(net "M_E_DQ<60>")
	)
	(arc
		(start 284.131258 -99.290886)
		(mid 284.133622 -99.295163)
		(end 284.13583 -99.299522)
		(width 0.0889)
		(layer "In4.Cu")
		(net "M_E_DQ<60>")
	)
	(arc
		(start 284.099508 -94.801436)
		(mid 284.05328 -95.068693)
		(end 284.131258 -95.328486)
		(width 0.0889)
		(layer "In4.Cu")
		(net "M_E_DQ<60>")
	)
	(arc
		(start 284.13583 -99.299522)
		(mid 284.184585 -99.495874)
		(end 284.131004 -99.690936)
		(width 0.0889)
		(layer "In4.Cu")
		(net "M_E_DQ<60>")
	)
	(arc
		(start 284.131258 -96.718882)
		(mid 284.052127 -97.014284)
		(end 284.131258 -97.309686)
		(width 0.0889)
		(layer "In4.Cu")
		(net "M_E_DQ<60>")
	)
	(arc
		(start 284.131004 -99.690936)
		(mid 284.051782 -99.980054)
		(end 284.124654 -100.270818)
		(width 0.0889)
		(layer "In4.Cu")
		(net "M_E_DQ<60>")
	)
	(arc
		(start 284.131258 -95.728282)
		(mid 284.052127 -96.023684)
		(end 284.131258 -96.319086)
		(width 0.0889)
		(layer "In4.Cu")
		(net "M_E_DQ<60>")
	)
	(arc
		(start 284.131258 -95.328486)
		(mid 284.184757 -95.528384)
		(end 284.131258 -95.728282)
		(width 0.0889)
		(layer "In4.Cu")
		(net "M_E_DQ<60>")
	)
	(arc
		(start 284.131258 -98.700082)
		(mid 284.052127 -98.995484)
		(end 284.131258 -99.290886)
		(width 0.0889)
		(layer "In4.Cu")
		(net "M_E_DQ<60>")
	)
	(arc
		(start 284.13583 -101.280722)
		(mid 284.184585 -101.477074)
		(end 284.131004 -101.672136)
		(width 0.0889)
		(layer "In4.Cu")
		(net "M_E_DQ<60>")
	)
	(segment
		(start 237.900718 -83.32724)
		(end 237.329218 -83.32724)
		(width 0.1651)
		(layer "F.Cu")
		(net "M_E_DQ<5>")
	)
	(segment
		(start 196.399912 -142.677642)
		(end 196.399912 -143.941546)
		(width 0.1651)
		(layer "F.Cu")
		(net "M_E_DQ<5>")
	)
	(segment
		(start 196.40042 -142.6718)
		(end 196.399912 -142.677642)
		(width 0.1651)
		(layer "F.Cu")
		(net "M_E_DQ<5>")
	)
	(via
		(at 196.399912 -143.941546)
		(size 0.508)
		(drill 0.254)
		(layers "F.Cu" "B.Cu")
		(net "M_E_DQ<5>")
	)
	(via
		(at 237.329218 -83.32724)
		(size 0.508)
		(drill 0.254)
		(layers "F.Cu" "B.Cu")
		(net "M_E_DQ<5>")
	)
	(via
		(at 197.173596 -139.932156)
		(size 0.508)
		(drill 0.254)
		(layers "F.Cu" "B.Cu")
		(net "M_E_DQ<5>")
	)
	(segment
		(start 197.249796 -137.877296)
		(end 197.249796 -139.855956)
		(width 0.1651)
		(layer "B.Cu")
		(net "M_E_DQ<5>")
	)
	(segment
		(start 197.250304 -137.877296)
		(end 197.249796 -137.877296)
		(width 0.1651)
		(layer "B.Cu")
		(net "M_E_DQ<5>")
	)
	(segment
		(start 197.249796 -139.855956)
		(end 197.173596 -139.932156)
		(width 0.1651)
		(layer "B.Cu")
		(net "M_E_DQ<5>")
	)
	(segment
		(start 196.85 -141.528546)
		(end 196.561202 -141.817344)
		(width 0.14224)
		(layer "In4.Cu")
		(net "M_E_DQ<5>")
	)
	(segment
		(start 202.07224 -111.261906)
		(end 202.072494 -111.462566)
		(width 0.14224)
		(layer "In4.Cu")
		(net "M_E_DQ<5>")
	)
	(segment
		(start 232.431082 -82.150966)
		(end 231.210358 -82.150966)
		(width 0.0889)
		(layer "In4.Cu")
		(net "M_E_DQ<5>")
	)
	(segment
		(start 236.481874 -82.43189)
		(end 236.457744 -82.43189)
		(width 0.0889)
		(layer "In4.Cu")
		(net "M_E_DQ<5>")
	)
	(segment
		(start 201.292206 -112.702086)
		(end 201.035412 -112.95888)
		(width 0.14224)
		(layer "In4.Cu")
		(net "M_E_DQ<5>")
	)
	(segment
		(start 197.173596 -139.932156)
		(end 197.151244 -139.932156)
		(width 0.14224)
		(layer "In4.Cu")
		(net "M_E_DQ<5>")
	)
	(segment
		(start 197.554596 -138.868404)
		(end 197.554596 -139.551156)
		(width 0.14224)
		(layer "In4.Cu")
		(net "M_E_DQ<5>")
	)
	(segment
		(start 202.072494 -111.462566)
		(end 202.341226 -111.731298)
		(width 0.14224)
		(layer "In4.Cu")
		(net "M_E_DQ<5>")
	)
	(segment
		(start 196.561202 -142.985744)
		(end 196.561202 -143.297656)
		(width 0.14224)
		(layer "In4.Cu")
		(net "M_E_DQ<5>")
	)
	(segment
		(start 201.411332 -111.922814)
		(end 201.152252 -112.181894)
		(width 0.14224)
		(layer "In4.Cu")
		(net "M_E_DQ<5>")
	)
	(segment
		(start 196.8246 -143.561054)
		(end 196.8246 -143.789146)
		(width 0.14224)
		(layer "In4.Cu")
		(net "M_E_DQ<5>")
	)
	(segment
		(start 203.002134 -111.271558)
		(end 202.80122 -111.271558)
		(width 0.14224)
		(layer "In4.Cu")
		(net "M_E_DQ<5>")
	)
	(segment
		(start 196.723 -140.9192)
		(end 196.85 -141.0462)
		(width 0.14224)
		(layer "In4.Cu")
		(net "M_E_DQ<5>")
	)
	(segment
		(start 196.7992 -142.747746)
		(end 196.561202 -142.985744)
		(width 0.14224)
		(layer "In4.Cu")
		(net "M_E_DQ<5>")
	)
	(segment
		(start 202.33132 -111.002826)
		(end 202.07224 -111.261906)
		(width 0.14224)
		(layer "In4.Cu")
		(net "M_E_DQ<5>")
	)
	(segment
		(start 201.881232 -112.191546)
		(end 201.6125 -111.922814)
		(width 0.14224)
		(layer "In4.Cu")
		(net "M_E_DQ<5>")
	)
	(segment
		(start 218.913964 -91.744546)
		(end 218.913964 -96.477582)
		(width 0.14224)
		(layer "In4.Cu")
		(net "M_E_DQ<5>")
	)
	(segment
		(start 197.6882 -136.658604)
		(end 197.6882 -138.7348)
		(width 0.14224)
		(layer "In4.Cu")
		(net "M_E_DQ<5>")
	)
	(segment
		(start 208.051146 -107.3404)
		(end 206.933292 -107.3404)
		(width 0.14224)
		(layer "In4.Cu")
		(net "M_E_DQ<5>")
	)
	(segment
		(start 197.681596 -131.153408)
		(end 197.4342 -131.400804)
		(width 0.14224)
		(layer "In4.Cu")
		(net "M_E_DQ<5>")
	)
	(segment
		(start 231.210358 -82.150966)
		(end 230.994204 -82.36712)
		(width 0.0889)
		(layer "In4.Cu")
		(net "M_E_DQ<5>")
	)
	(segment
		(start 200.808844 -112.959134)
		(end 200.692512 -112.842802)
		(width 0.14224)
		(layer "In4.Cu")
		(net "M_E_DQ<5>")
	)
	(segment
		(start 196.723 -140.3604)
		(end 196.723 -140.9192)
		(width 0.14224)
		(layer "In4.Cu")
		(net "M_E_DQ<5>")
	)
	(segment
		(start 202.0824 -112.191292)
		(end 201.881232 -112.191546)
		(width 0.14224)
		(layer "In4.Cu")
		(net "M_E_DQ<5>")
	)
	(segment
		(start 201.035412 -112.95888)
		(end 200.808844 -112.959134)
		(width 0.14224)
		(layer "In4.Cu")
		(net "M_E_DQ<5>")
	)
	(segment
		(start 230.994204 -82.36712)
		(end 228.29139 -82.36712)
		(width 0.14224)
		(layer "In4.Cu")
		(net "M_E_DQ<5>")
	)
	(segment
		(start 233.912918 -81.93659)
		(end 233.880152 -81.93659)
		(width 0.0889)
		(layer "In4.Cu")
		(net "M_E_DQ<5>")
	)
	(segment
		(start 197.69836 -135.966454)
		(end 197.554596 -136.110218)
		(width 0.14224)
		(layer "In4.Cu")
		(net "M_E_DQ<5>")
	)
	(segment
		(start 197.554596 -136.525)
		(end 197.6882 -136.658604)
		(width 0.14224)
		(layer "In4.Cu")
		(net "M_E_DQ<5>")
	)
	(segment
		(start 201.152252 -112.181894)
		(end 201.152506 -112.382554)
		(width 0.14224)
		(layer "In4.Cu")
		(net "M_E_DQ<5>")
	)
	(segment
		(start 197.4342 -131.400804)
		(end 197.4342 -134.415022)
		(width 0.14224)
		(layer "In4.Cu")
		(net "M_E_DQ<5>")
	)
	(segment
		(start 197.6882 -138.7348)
		(end 197.554596 -138.868404)
		(width 0.14224)
		(layer "In4.Cu")
		(net "M_E_DQ<5>")
	)
	(segment
		(start 201.152506 -112.382554)
		(end 201.292206 -112.522254)
		(width 0.14224)
		(layer "In4.Cu")
		(net "M_E_DQ<5>")
	)
	(segment
		(start 233.054906 -82.431636)
		(end 232.711752 -82.431636)
		(width 0.0889)
		(layer "In4.Cu")
		(net "M_E_DQ<5>")
	)
	(segment
		(start 202.532488 -111.002826)
		(end 202.33132 -111.002826)
		(width 0.14224)
		(layer "In4.Cu")
		(net "M_E_DQ<5>")
	)
	(segment
		(start 196.8246 -143.789146)
		(end 196.6722 -143.941546)
		(width 0.14224)
		(layer "In4.Cu")
		(net "M_E_DQ<5>")
	)
	(segment
		(start 196.561202 -143.297656)
		(end 196.8246 -143.561054)
		(width 0.14224)
		(layer "In4.Cu")
		(net "M_E_DQ<5>")
	)
	(segment
		(start 237.329218 -83.32724)
		(end 236.833918 -82.660744)
		(width 0.0889)
		(layer "In4.Cu")
		(net "M_E_DQ<5>")
	)
	(segment
		(start 197.554596 -139.551156)
		(end 197.173596 -139.932156)
		(width 0.14224)
		(layer "In4.Cu")
		(net "M_E_DQ<5>")
	)
	(segment
		(start 200.692512 -112.842802)
		(end 200.491344 -112.842802)
		(width 0.14224)
		(layer "In4.Cu")
		(net "M_E_DQ<5>")
	)
	(segment
		(start 196.561202 -141.817344)
		(end 196.561202 -142.154656)
		(width 0.14224)
		(layer "In4.Cu")
		(net "M_E_DQ<5>")
	)
	(segment
		(start 218.913964 -96.477582)
		(end 208.051146 -107.3404)
		(width 0.14224)
		(layer "In4.Cu")
		(net "M_E_DQ<5>")
	)
	(segment
		(start 197.151244 -139.932156)
		(end 196.723 -140.3604)
		(width 0.14224)
		(layer "In4.Cu")
		(net "M_E_DQ<5>")
	)
	(segment
		(start 197.4342 -134.415022)
		(end 197.69836 -134.679182)
		(width 0.14224)
		(layer "In4.Cu")
		(net "M_E_DQ<5>")
	)
	(segment
		(start 206.933292 -107.3404)
		(end 203.002134 -111.271558)
		(width 0.14224)
		(layer "In4.Cu")
		(net "M_E_DQ<5>")
	)
	(segment
		(start 197.554596 -136.110218)
		(end 197.554596 -136.525)
		(width 0.14224)
		(layer "In4.Cu")
		(net "M_E_DQ<5>")
	)
	(segment
		(start 196.7992 -142.392654)
		(end 196.7992 -142.747746)
		(width 0.14224)
		(layer "In4.Cu")
		(net "M_E_DQ<5>")
	)
	(segment
		(start 197.69836 -134.679182)
		(end 197.69836 -135.966454)
		(width 0.14224)
		(layer "In4.Cu")
		(net "M_E_DQ<5>")
	)
	(segment
		(start 201.292206 -112.522254)
		(end 201.292206 -112.702086)
		(width 0.14224)
		(layer "In4.Cu")
		(net "M_E_DQ<5>")
	)
	(segment
		(start 197.503796 -129.781808)
		(end 197.681596 -129.959608)
		(width 0.14224)
		(layer "In4.Cu")
		(net "M_E_DQ<5>")
	)
	(segment
		(start 202.80122 -111.271558)
		(end 202.532488 -111.002826)
		(width 0.14224)
		(layer "In4.Cu")
		(net "M_E_DQ<5>")
	)
	(segment
		(start 202.341226 -111.731298)
		(end 202.341226 -111.932466)
		(width 0.14224)
		(layer "In4.Cu")
		(net "M_E_DQ<5>")
	)
	(segment
		(start 201.6125 -111.922814)
		(end 201.411332 -111.922814)
		(width 0.14224)
		(layer "In4.Cu")
		(net "M_E_DQ<5>")
	)
	(segment
		(start 196.561202 -142.154656)
		(end 196.7992 -142.392654)
		(width 0.14224)
		(layer "In4.Cu")
		(net "M_E_DQ<5>")
	)
	(segment
		(start 235.627164 -81.93659)
		(end 235.594398 -81.93659)
		(width 0.0889)
		(layer "In4.Cu")
		(net "M_E_DQ<5>")
	)
	(segment
		(start 196.85 -141.0462)
		(end 196.85 -141.528546)
		(width 0.14224)
		(layer "In4.Cu")
		(net "M_E_DQ<5>")
	)
	(segment
		(start 197.681596 -129.959608)
		(end 197.681596 -131.153408)
		(width 0.14224)
		(layer "In4.Cu")
		(net "M_E_DQ<5>")
	)
	(segment
		(start 200.491344 -112.842802)
		(end 197.503796 -115.83035)
		(width 0.14224)
		(layer "In4.Cu")
		(net "M_E_DQ<5>")
	)
	(segment
		(start 197.503796 -115.83035)
		(end 197.503796 -129.781808)
		(width 0.14224)
		(layer "In4.Cu")
		(net "M_E_DQ<5>")
	)
	(segment
		(start 196.6722 -143.941546)
		(end 196.399912 -143.941546)
		(width 0.14224)
		(layer "In4.Cu")
		(net "M_E_DQ<5>")
	)
	(segment
		(start 202.341226 -111.932466)
		(end 202.0824 -112.191292)
		(width 0.14224)
		(layer "In4.Cu")
		(net "M_E_DQ<5>")
	)
	(segment
		(start 232.711752 -82.431636)
		(end 232.431082 -82.150966)
		(width 0.0889)
		(layer "In4.Cu")
		(net "M_E_DQ<5>")
	)
	(segment
		(start 236.833918 -82.660744)
		(end 236.817408 -82.632042)
		(width 0.0889)
		(layer "In4.Cu")
		(net "M_E_DQ<5>")
	)
	(segment
		(start 228.29139 -82.36712)
		(end 218.913964 -91.744546)
		(width 0.14224)
		(layer "In4.Cu")
		(net "M_E_DQ<5>")
	)
	(arc
		(start 235.594398 -81.93659)
		(mid 235.308974 -81.853123)
		(end 235.100368 -81.641188)
		(width 0.0889)
		(layer "In4.Cu")
		(net "M_E_DQ<5>")
	)
	(arc
		(start 235.958888 -82.136488)
		(mid 235.818809 -81.993752)
		(end 235.627164 -81.93659)
		(width 0.0889)
		(layer "In4.Cu")
		(net "M_E_DQ<5>")
	)
	(arc
		(start 233.880152 -81.93659)
		(mid 233.68851 -81.993756)
		(end 233.548428 -82.136488)
		(width 0.0889)
		(layer "In4.Cu")
		(net "M_E_DQ<5>")
	)
	(arc
		(start 235.100368 -81.641188)
		(mid 234.753658 -81.440877)
		(end 234.406948 -81.641188)
		(width 0.0889)
		(layer "In4.Cu")
		(net "M_E_DQ<5>")
	)
	(arc
		(start 233.548428 -82.136488)
		(mid 233.340009 -82.348201)
		(end 233.054906 -82.431636)
		(width 0.0889)
		(layer "In4.Cu")
		(net "M_E_DQ<5>")
	)
	(arc
		(start 236.457744 -82.43189)
		(mid 236.169599 -82.349571)
		(end 235.958888 -82.136488)
		(width 0.0889)
		(layer "In4.Cu")
		(net "M_E_DQ<5>")
	)
	(arc
		(start 234.406948 -81.641188)
		(mid 234.19834 -81.85312)
		(end 233.912918 -81.93659)
		(width 0.0889)
		(layer "In4.Cu")
		(net "M_E_DQ<5>")
	)
	(arc
		(start 236.817408 -82.632042)
		(mid 236.675725 -82.488238)
		(end 236.481874 -82.43189)
		(width 0.0889)
		(layer "In4.Cu")
		(net "M_E_DQ<5>")
	)
	(segment
		(start 315.399928 -142.677642)
		(end 315.399928 -143.941546)
		(width 0.1651)
		(layer "F.Cu")
		(net "M_E_DQ<59>")
	)
	(segment
		(start 287.50514 -95.033084)
		(end 288.07664 -95.033084)
		(width 0.1651)
		(layer "F.Cu")
		(net "M_E_DQ<59>")
	)
	(segment
		(start 315.400436 -142.6718)
		(end 315.399928 -142.677642)
		(width 0.1651)
		(layer "F.Cu")
		(net "M_E_DQ<59>")
	)
	(via
		(at 315.399928 -143.941546)
		(size 0.508)
		(drill 0.254)
		(layers "F.Cu" "B.Cu")
		(net "M_E_DQ<59>")
	)
	(via
		(at 316.249812 -139.932156)
		(size 0.508)
		(drill 0.254)
		(layers "F.Cu" "B.Cu")
		(net "M_E_DQ<59>")
	)
	(via
		(at 288.07664 -95.033084)
		(size 0.508)
		(drill 0.254)
		(layers "F.Cu" "B.Cu")
		(net "M_E_DQ<59>")
	)
	(segment
		(start 316.25032 -137.877296)
		(end 316.249812 -137.877296)
		(width 0.1651)
		(layer "B.Cu")
		(net "M_E_DQ<59>")
	)
	(segment
		(start 316.249812 -137.877296)
		(end 316.249812 -139.932156)
		(width 0.1651)
		(layer "B.Cu")
		(net "M_E_DQ<59>")
	)
	(segment
		(start 288.571686 -95.699326)
		(end 288.07664 -95.033084)
		(width 0.0889)
		(layer "In4.Cu")
		(net "M_E_DQ<59>")
	)
	(segment
		(start 316.756796 -131.268978)
		(end 316.756796 -130.113278)
		(width 0.14224)
		(layer "In4.Cu")
		(net "M_E_DQ<59>")
	)
	(segment
		(start 315.818266 -142.3162)
		(end 315.561218 -142.059152)
		(width 0.14224)
		(layer "In4.Cu")
		(net "M_E_DQ<59>")
	)
	(segment
		(start 315.843666 -140.834618)
		(end 315.799216 -140.790168)
		(width 0.14224)
		(layer "In4.Cu")
		(net "M_E_DQ<59>")
	)
	(segment
		(start 316.672976 -126.948438)
		(end 316.418976 -126.694438)
		(width 0.14224)
		(layer "In4.Cu")
		(net "M_E_DQ<59>")
	)
	(segment
		(start 288.583624 -99.299522)
		(end 288.58845 -99.290886)
		(width 0.0889)
		(layer "In4.Cu")
		(net "M_E_DQ<59>")
	)
	(segment
		(start 316.418976 -126.694438)
		(end 316.418976 -124.337064)
		(width 0.14224)
		(layer "In4.Cu")
		(net "M_E_DQ<59>")
	)
	(segment
		(start 315.672216 -143.941546)
		(end 315.850016 -143.763746)
		(width 0.14224)
		(layer "In4.Cu")
		(net "M_E_DQ<59>")
	)
	(segment
		(start 316.728856 -136.127744)
		(end 316.728856 -134.653782)
		(width 0.14224)
		(layer "In4.Cu")
		(net "M_E_DQ<59>")
	)
	(segment
		(start 316.402212 -127.752856)
		(end 316.54369 -127.611378)
		(width 0.14224)
		(layer "In4.Cu")
		(net "M_E_DQ<59>")
	)
	(segment
		(start 317.160148 -127.611378)
		(end 317.315088 -127.456438)
		(width 0.14224)
		(layer "In4.Cu")
		(net "M_E_DQ<59>")
	)
	(segment
		(start 292.609524 -104.848914)
		(end 292.109144 -104.348534)
		(width 0.0889)
		(layer "In4.Cu")
		(net "M_E_DQ<59>")
	)
	(segment
		(start 288.58845 -99.290886)
		(end 288.5948 -99.280218)
		(width 0.0889)
		(layer "In4.Cu")
		(net "M_E_DQ<59>")
	)
	(segment
		(start 316.402212 -128.105916)
		(end 316.402212 -127.752856)
		(width 0.14224)
		(layer "In4.Cu")
		(net "M_E_DQ<59>")
	)
	(segment
		(start 316.578996 -136.277604)
		(end 316.728856 -136.127744)
		(width 0.14224)
		(layer "In4.Cu")
		(net "M_E_DQ<59>")
	)
	(segment
		(start 292.959028 -104.848914)
		(end 292.609524 -104.848914)
		(width 0.0889)
		(layer "In4.Cu")
		(net "M_E_DQ<59>")
	)
	(segment
		(start 288.58845 -97.309686)
		(end 288.5948 -97.299018)
		(width 0.0889)
		(layer "In4.Cu")
		(net "M_E_DQ<59>")
	)
	(segment
		(start 316.715648 -128.937258)
		(end 317.160148 -128.937258)
		(width 0.14224)
		(layer "In4.Cu")
		(net "M_E_DQ<59>")
	)
	(segment
		(start 315.561218 -141.785848)
		(end 315.843666 -141.5034)
		(width 0.14224)
		(layer "In4.Cu")
		(net "M_E_DQ<59>")
	)
	(segment
		(start 316.418976 -124.337064)
		(end 309.344568 -117.262656)
		(width 0.14224)
		(layer "In4.Cu")
		(net "M_E_DQ<59>")
	)
	(segment
		(start 292.109144 -104.348534)
		(end 291.499544 -104.348534)
		(width 0.0889)
		(layer "In4.Cu")
		(net "M_E_DQ<59>")
	)
	(segment
		(start 315.850016 -143.44015)
		(end 315.561218 -143.151352)
		(width 0.14224)
		(layer "In4.Cu")
		(net "M_E_DQ<59>")
	)
	(segment
		(start 290.67379 -103.853234)
		(end 290.637214 -103.853234)
		(width 0.0889)
		(layer "In4.Cu")
		(net "M_E_DQ<59>")
	)
	(segment
		(start 315.399928 -143.941546)
		(end 315.672216 -143.941546)
		(width 0.14224)
		(layer "In4.Cu")
		(net "M_E_DQ<59>")
	)
	(segment
		(start 295.390316 -104.848914)
		(end 292.959028 -104.848914)
		(width 0.14224)
		(layer "In4.Cu")
		(net "M_E_DQ<59>")
	)
	(segment
		(start 288.95675 -100.881434)
		(end 288.917126 -100.881434)
		(width 0.0889)
		(layer "In4.Cu")
		(net "M_E_DQ<59>")
	)
	(segment
		(start 315.561218 -143.151352)
		(end 315.561218 -142.878048)
		(width 0.14224)
		(layer "In4.Cu")
		(net "M_E_DQ<59>")
	)
	(segment
		(start 307.804058 -117.262656)
		(end 295.390316 -104.848914)
		(width 0.14224)
		(layer "In4.Cu")
		(net "M_E_DQ<59>")
	)
	(segment
		(start 288.583624 -98.308922)
		(end 288.58845 -98.300286)
		(width 0.0889)
		(layer "In4.Cu")
		(net "M_E_DQ<59>")
	)
	(segment
		(start 316.756796 -130.113278)
		(end 316.500002 -129.856484)
		(width 0.14224)
		(layer "In4.Cu")
		(net "M_E_DQ<59>")
	)
	(segment
		(start 316.500002 -129.152904)
		(end 316.715648 -128.937258)
		(width 0.14224)
		(layer "In4.Cu")
		(net "M_E_DQ<59>")
	)
	(segment
		(start 317.160148 -128.274318)
		(end 316.570614 -128.274318)
		(width 0.14224)
		(layer "In4.Cu")
		(net "M_E_DQ<59>")
	)
	(segment
		(start 315.850016 -143.763746)
		(end 315.850016 -143.44015)
		(width 0.14224)
		(layer "In4.Cu")
		(net "M_E_DQ<59>")
	)
	(segment
		(start 317.315088 -127.103378)
		(end 317.160148 -126.948438)
		(width 0.14224)
		(layer "In4.Cu")
		(net "M_E_DQ<59>")
	)
	(segment
		(start 316.249812 -139.932156)
		(end 316.578996 -139.602972)
		(width 0.14224)
		(layer "In4.Cu")
		(net "M_E_DQ<59>")
	)
	(segment
		(start 317.315088 -127.456438)
		(end 317.315088 -127.103378)
		(width 0.14224)
		(layer "In4.Cu")
		(net "M_E_DQ<59>")
	)
	(segment
		(start 288.58845 -98.300286)
		(end 288.5948 -98.289618)
		(width 0.0889)
		(layer "In4.Cu")
		(net "M_E_DQ<59>")
	)
	(segment
		(start 315.799216 -140.790168)
		(end 315.799216 -140.382752)
		(width 0.14224)
		(layer "In4.Cu")
		(net "M_E_DQ<59>")
	)
	(segment
		(start 316.578996 -139.602972)
		(end 316.578996 -136.277604)
		(width 0.14224)
		(layer "In4.Cu")
		(net "M_E_DQ<59>")
	)
	(segment
		(start 315.799216 -140.382752)
		(end 316.249812 -139.932156)
		(width 0.14224)
		(layer "In4.Cu")
		(net "M_E_DQ<59>")
	)
	(segment
		(start 315.561218 -142.059152)
		(end 315.561218 -141.785848)
		(width 0.14224)
		(layer "In4.Cu")
		(net "M_E_DQ<59>")
	)
	(segment
		(start 289.44697 -102.167436)
		(end 289.442144 -102.1588)
		(width 0.0889)
		(layer "In4.Cu")
		(net "M_E_DQ<59>")
	)
	(segment
		(start 317.160148 -128.937258)
		(end 317.315088 -128.782318)
		(width 0.14224)
		(layer "In4.Cu")
		(net "M_E_DQ<59>")
	)
	(segment
		(start 316.570614 -128.274318)
		(end 316.402212 -128.105916)
		(width 0.14224)
		(layer "In4.Cu")
		(net "M_E_DQ<59>")
	)
	(segment
		(start 316.500002 -129.856484)
		(end 316.500002 -129.152904)
		(width 0.14224)
		(layer "In4.Cu")
		(net "M_E_DQ<59>")
	)
	(segment
		(start 289.81527 -103.358188)
		(end 289.782504 -103.358188)
		(width 0.0889)
		(layer "In4.Cu")
		(net "M_E_DQ<59>")
	)
	(segment
		(start 289.45332 -102.178104)
		(end 289.44697 -102.167436)
		(width 0.0889)
		(layer "In4.Cu")
		(net "M_E_DQ<59>")
	)
	(segment
		(start 288.583624 -97.318322)
		(end 288.58845 -97.309686)
		(width 0.0889)
		(layer "In4.Cu")
		(net "M_E_DQ<59>")
	)
	(segment
		(start 317.160148 -126.948438)
		(end 316.672976 -126.948438)
		(width 0.14224)
		(layer "In4.Cu")
		(net "M_E_DQ<59>")
	)
	(segment
		(start 315.843666 -141.5034)
		(end 315.843666 -140.834618)
		(width 0.14224)
		(layer "In4.Cu")
		(net "M_E_DQ<59>")
	)
	(segment
		(start 315.561218 -142.878048)
		(end 315.818266 -142.621)
		(width 0.14224)
		(layer "In4.Cu")
		(net "M_E_DQ<59>")
	)
	(segment
		(start 316.593982 -134.518908)
		(end 316.593982 -131.431792)
		(width 0.14224)
		(layer "In4.Cu")
		(net "M_E_DQ<59>")
	)
	(segment
		(start 288.58845 -96.319086)
		(end 288.5948 -96.308418)
		(width 0.0889)
		(layer "In4.Cu")
		(net "M_E_DQ<59>")
	)
	(segment
		(start 309.344568 -117.262656)
		(end 307.804058 -117.262656)
		(width 0.14224)
		(layer "In4.Cu")
		(net "M_E_DQ<59>")
	)
	(segment
		(start 316.593982 -131.431792)
		(end 316.756796 -131.268978)
		(width 0.14224)
		(layer "In4.Cu")
		(net "M_E_DQ<59>")
	)
	(segment
		(start 316.54369 -127.611378)
		(end 317.160148 -127.611378)
		(width 0.14224)
		(layer "In4.Cu")
		(net "M_E_DQ<59>")
	)
	(segment
		(start 317.315088 -128.429258)
		(end 317.160148 -128.274318)
		(width 0.14224)
		(layer "In4.Cu")
		(net "M_E_DQ<59>")
	)
	(segment
		(start 288.58845 -95.728536)
		(end 288.571686 -95.699326)
		(width 0.0889)
		(layer "In4.Cu")
		(net "M_E_DQ<59>")
	)
	(segment
		(start 315.818266 -142.621)
		(end 315.818266 -142.3162)
		(width 0.14224)
		(layer "In4.Cu")
		(net "M_E_DQ<59>")
	)
	(segment
		(start 317.315088 -128.782318)
		(end 317.315088 -128.429258)
		(width 0.14224)
		(layer "In4.Cu")
		(net "M_E_DQ<59>")
	)
	(segment
		(start 288.583624 -96.327722)
		(end 288.58845 -96.319086)
		(width 0.0889)
		(layer "In4.Cu")
		(net "M_E_DQ<59>")
	)
	(segment
		(start 316.728856 -134.653782)
		(end 316.593982 -134.518908)
		(width 0.14224)
		(layer "In4.Cu")
		(net "M_E_DQ<59>")
	)
	(arc
		(start 289.44697 -102.757986)
		(mid 289.526192 -102.468868)
		(end 289.45332 -102.178104)
		(width 0.0889)
		(layer "In4.Cu")
		(net "M_E_DQ<59>")
	)
	(arc
		(start 289.442144 -102.1588)
		(mid 289.393389 -101.962448)
		(end 289.44697 -101.767386)
		(width 0.0889)
		(layer "In4.Cu")
		(net "M_E_DQ<59>")
	)
	(arc
		(start 288.58845 -99.690936)
		(mid 288.53498 -99.495873)
		(end 288.583624 -99.299522)
		(width 0.0889)
		(layer "In4.Cu")
		(net "M_E_DQ<59>")
	)
	(arc
		(start 290.637214 -103.853234)
		(mid 290.445572 -103.796068)
		(end 290.30549 -103.653336)
		(width 0.0889)
		(layer "In4.Cu")
		(net "M_E_DQ<59>")
	)
	(arc
		(start 288.58845 -100.28174)
		(mid 288.667581 -99.986338)
		(end 288.58845 -99.690936)
		(width 0.0889)
		(layer "In4.Cu")
		(net "M_E_DQ<59>")
	)
	(arc
		(start 288.917126 -100.881434)
		(mid 288.58421 -100.673982)
		(end 288.58845 -100.28174)
		(width 0.0889)
		(layer "In4.Cu")
		(net "M_E_DQ<59>")
	)
	(arc
		(start 289.44697 -101.767386)
		(mid 289.452224 -101.185878)
		(end 288.95675 -100.881434)
		(width 0.0889)
		(layer "In4.Cu")
		(net "M_E_DQ<59>")
	)
	(arc
		(start 288.5948 -97.299018)
		(mid 288.667598 -97.008255)
		(end 288.58845 -96.719136)
		(width 0.0889)
		(layer "In4.Cu")
		(net "M_E_DQ<59>")
	)
	(arc
		(start 288.5948 -98.289618)
		(mid 288.667598 -97.998855)
		(end 288.58845 -97.709736)
		(width 0.0889)
		(layer "In4.Cu")
		(net "M_E_DQ<59>")
	)
	(arc
		(start 291.16401 -104.148382)
		(mid 290.957006 -103.937518)
		(end 290.67379 -103.853234)
		(width 0.0889)
		(layer "In4.Cu")
		(net "M_E_DQ<59>")
	)
	(arc
		(start 289.782504 -103.358188)
		(mid 289.444335 -103.15339)
		(end 289.44697 -102.757986)
		(width 0.0889)
		(layer "In4.Cu")
		(net "M_E_DQ<59>")
	)
	(arc
		(start 288.58845 -98.700336)
		(mid 288.53498 -98.505273)
		(end 288.583624 -98.308922)
		(width 0.0889)
		(layer "In4.Cu")
		(net "M_E_DQ<59>")
	)
	(arc
		(start 288.58845 -96.719136)
		(mid 288.53498 -96.524073)
		(end 288.583624 -96.327722)
		(width 0.0889)
		(layer "In4.Cu")
		(net "M_E_DQ<59>")
	)
	(arc
		(start 290.30549 -103.653336)
		(mid 290.098486 -103.442472)
		(end 289.81527 -103.358188)
		(width 0.0889)
		(layer "In4.Cu")
		(net "M_E_DQ<59>")
	)
	(arc
		(start 291.499544 -104.348534)
		(mid 291.305694 -104.292184)
		(end 291.16401 -104.148382)
		(width 0.0889)
		(layer "In4.Cu")
		(net "M_E_DQ<59>")
	)
	(arc
		(start 288.58845 -97.709736)
		(mid 288.53498 -97.514673)
		(end 288.583624 -97.318322)
		(width 0.0889)
		(layer "In4.Cu")
		(net "M_E_DQ<59>")
	)
	(arc
		(start 288.5948 -99.280218)
		(mid 288.667598 -98.989455)
		(end 288.58845 -98.700336)
		(width 0.0889)
		(layer "In4.Cu")
		(net "M_E_DQ<59>")
	)
	(arc
		(start 288.5948 -96.308418)
		(mid 288.667598 -96.017655)
		(end 288.58845 -95.728536)
		(width 0.0889)
		(layer "In4.Cu")
		(net "M_E_DQ<59>")
	)
	(segment
		(start 287.21812 -92.556584)
		(end 286.64662 -92.556584)
		(width 0.0889)
		(layer "F.Cu")
		(net "M_E_DQ<58>")
	)
	(segment
		(start 316.249812 -145.5166)
		(end 316.249812 -145.793968)
		(width 0.1651)
		(layer "F.Cu")
		(net "M_E_DQ<58>")
	)
	(segment
		(start 316.381384 -146.14906)
		(end 316.249812 -146.280632)
		(width 0.1651)
		(layer "F.Cu")
		(net "M_E_DQ<58>")
	)
	(segment
		(start 316.249812 -147.27174)
		(end 316.25032 -147.27174)
		(width 0.1651)
		(layer "F.Cu")
		(net "M_E_DQ<58>")
	)
	(segment
		(start 316.249812 -145.793968)
		(end 316.381384 -145.92554)
		(width 0.1651)
		(layer "F.Cu")
		(net "M_E_DQ<58>")
	)
	(segment
		(start 316.381384 -145.92554)
		(end 316.381384 -146.14906)
		(width 0.1651)
		(layer "F.Cu")
		(net "M_E_DQ<58>")
	)
	(segment
		(start 316.249812 -146.280632)
		(end 316.249812 -147.27174)
		(width 0.1651)
		(layer "F.Cu")
		(net "M_E_DQ<58>")
	)
	(via
		(at 287.21812 -92.556584)
		(size 0.508)
		(drill 0.254)
		(layers "F.Cu" "B.Cu")
		(net "M_E_DQ<58>")
	)
	(via
		(at 315.399928 -141.213078)
		(size 0.508)
		(drill 0.254)
		(layers "F.Cu" "B.Cu")
		(net "M_E_DQ<58>")
	)
	(via
		(at 316.249812 -145.5166)
		(size 0.508)
		(drill 0.254)
		(layers "F.Cu" "B.Cu")
		(net "M_E_DQ<58>")
	)
	(segment
		(start 315.400436 -142.477236)
		(end 315.399928 -142.476982)
		(width 0.1651)
		(layer "B.Cu")
		(net "M_E_DQ<58>")
	)
	(segment
		(start 315.399928 -142.476982)
		(end 315.399928 -141.213078)
		(width 0.1651)
		(layer "B.Cu")
		(net "M_E_DQ<58>")
	)
	(segment
		(start 288.42335 -98.205036)
		(end 288.417 -98.215704)
		(width 0.0889)
		(layer "In4.Cu")
		(net "M_E_DQ<58>")
	)
	(segment
		(start 288.428176 -99.187)
		(end 288.42335 -99.195636)
		(width 0.0889)
		(layer "In4.Cu")
		(net "M_E_DQ<58>")
	)
	(segment
		(start 292.69817 -105.4862)
		(end 295.316402 -105.4862)
		(width 0.14224)
		(layer "In4.Cu")
		(net "M_E_DQ<58>")
	)
	(segment
		(start 288.428176 -100.1776)
		(end 288.42335 -100.186236)
		(width 0.0889)
		(layer "In4.Cu")
		(net "M_E_DQ<58>")
	)
	(segment
		(start 292.503606 -105.291636)
		(end 292.69817 -105.4862)
		(width 0.14224)
		(layer "In4.Cu")
		(net "M_E_DQ<58>")
	)
	(segment
		(start 315.689996 -135.976868)
		(end 315.8871 -136.173972)
		(width 0.14224)
		(layer "In4.Cu")
		(net "M_E_DQ<58>")
	)
	(segment
		(start 287.581594 -94.708472)
		(end 287.56483 -94.737936)
		(width 0.0889)
		(layer "In4.Cu")
		(net "M_E_DQ<58>")
	)
	(segment
		(start 315.8871 -139.403074)
		(end 315.307726 -139.982448)
		(width 0.14224)
		(layer "In4.Cu")
		(net "M_E_DQ<58>")
	)
	(segment
		(start 315.766196 -129.960878)
		(end 315.766196 -131.332478)
		(width 0.14224)
		(layer "In4.Cu")
		(net "M_E_DQ<58>")
	)
	(segment
		(start 291.48913 -104.539034)
		(end 292.03015 -104.539034)
		(width 0.0889)
		(layer "In4.Cu")
		(net "M_E_DQ<58>")
	)
	(segment
		(start 288.42335 -99.195636)
		(end 288.417 -99.206304)
		(width 0.0889)
		(layer "In4.Cu")
		(net "M_E_DQ<58>")
	)
	(segment
		(start 315.8871 -136.173972)
		(end 315.8871 -139.403074)
		(width 0.14224)
		(layer "In4.Cu")
		(net "M_E_DQ<58>")
	)
	(segment
		(start 315.86043 -129.866644)
		(end 315.766196 -129.960878)
		(width 0.14224)
		(layer "In4.Cu")
		(net "M_E_DQ<58>")
	)
	(segment
		(start 289.28187 -102.262686)
		(end 289.286696 -102.271322)
		(width 0.0889)
		(layer "In4.Cu")
		(net "M_E_DQ<58>")
	)
	(segment
		(start 315.86043 -124.599954)
		(end 315.86043 -129.866644)
		(width 0.14224)
		(layer "In4.Cu")
		(net "M_E_DQ<58>")
	)
	(segment
		(start 287.21812 -92.556584)
		(end 287.547558 -93.317568)
		(width 0.0889)
		(layer "In4.Cu")
		(net "M_E_DQ<58>")
	)
	(segment
		(start 315.766196 -131.332478)
		(end 315.859922 -131.426204)
		(width 0.14224)
		(layer "In4.Cu")
		(net "M_E_DQ<58>")
	)
	(segment
		(start 288.91357 -101.072188)
		(end 288.953194 -101.072188)
		(width 0.0889)
		(layer "In4.Cu")
		(net "M_E_DQ<58>")
	)
	(segment
		(start 314.966858 -144.233646)
		(end 316.249812 -145.5166)
		(width 0.14224)
		(layer "In4.Cu")
		(net "M_E_DQ<58>")
	)
	(segment
		(start 292.03015 -104.539034)
		(end 292.503606 -105.01249)
		(width 0.0889)
		(layer "In4.Cu")
		(net "M_E_DQ<58>")
	)
	(segment
		(start 315.859922 -134.558024)
		(end 315.689996 -134.72795)
		(width 0.14224)
		(layer "In4.Cu")
		(net "M_E_DQ<58>")
	)
	(segment
		(start 288.42335 -97.214436)
		(end 288.417 -97.225104)
		(width 0.0889)
		(layer "In4.Cu")
		(net "M_E_DQ<58>")
	)
	(segment
		(start 289.7759 -103.548688)
		(end 289.808666 -103.548688)
		(width 0.0889)
		(layer "In4.Cu")
		(net "M_E_DQ<58>")
	)
	(segment
		(start 288.063686 -95.623888)
		(end 288.091626 -95.623888)
		(width 0.0889)
		(layer "In4.Cu")
		(net "M_E_DQ<58>")
	)
	(segment
		(start 289.27552 -102.252018)
		(end 289.28187 -102.262686)
		(width 0.0889)
		(layer "In4.Cu")
		(net "M_E_DQ<58>")
	)
	(segment
		(start 287.547558 -93.317568)
		(end 287.569656 -93.355922)
		(width 0.0889)
		(layer "In4.Cu")
		(net "M_E_DQ<58>")
	)
	(segment
		(start 315.307726 -141.120876)
		(end 315.399928 -141.213078)
		(width 0.14224)
		(layer "In4.Cu")
		(net "M_E_DQ<58>")
	)
	(segment
		(start 295.316402 -105.4862)
		(end 307.753258 -117.923056)
		(width 0.14224)
		(layer "In4.Cu")
		(net "M_E_DQ<58>")
	)
	(segment
		(start 315.689996 -134.72795)
		(end 315.689996 -135.976868)
		(width 0.14224)
		(layer "In4.Cu")
		(net "M_E_DQ<58>")
	)
	(segment
		(start 288.428176 -96.2152)
		(end 288.42335 -96.223836)
		(width 0.0889)
		(layer "In4.Cu")
		(net "M_E_DQ<58>")
	)
	(segment
		(start 288.428176 -98.1964)
		(end 288.42335 -98.205036)
		(width 0.0889)
		(layer "In4.Cu")
		(net "M_E_DQ<58>")
	)
	(segment
		(start 288.428176 -97.2058)
		(end 288.42335 -97.214436)
		(width 0.0889)
		(layer "In4.Cu")
		(net "M_E_DQ<58>")
	)
	(segment
		(start 288.42335 -96.223836)
		(end 288.417 -96.234504)
		(width 0.0889)
		(layer "In4.Cu")
		(net "M_E_DQ<58>")
	)
	(segment
		(start 315.859922 -131.426204)
		(end 315.859922 -134.558024)
		(width 0.14224)
		(layer "In4.Cu")
		(net "M_E_DQ<58>")
	)
	(segment
		(start 309.183532 -117.923056)
		(end 315.86043 -124.599954)
		(width 0.14224)
		(layer "In4.Cu")
		(net "M_E_DQ<58>")
	)
	(segment
		(start 290.63061 -104.043734)
		(end 290.663376 -104.043734)
		(width 0.0889)
		(layer "In4.Cu")
		(net "M_E_DQ<58>")
	)
	(segment
		(start 314.966858 -141.646148)
		(end 314.966858 -144.233646)
		(width 0.14224)
		(layer "In4.Cu")
		(net "M_E_DQ<58>")
	)
	(segment
		(start 292.503606 -105.01249)
		(end 292.503606 -105.291636)
		(width 0.0889)
		(layer "In4.Cu")
		(net "M_E_DQ<58>")
	)
	(segment
		(start 287.56483 -94.737936)
		(end 287.55848 -94.748604)
		(width 0.0889)
		(layer "In4.Cu")
		(net "M_E_DQ<58>")
	)
	(segment
		(start 307.753258 -117.923056)
		(end 309.183532 -117.923056)
		(width 0.14224)
		(layer "In4.Cu")
		(net "M_E_DQ<58>")
	)
	(segment
		(start 315.307726 -139.982448)
		(end 315.307726 -141.120876)
		(width 0.14224)
		(layer "In4.Cu")
		(net "M_E_DQ<58>")
	)
	(segment
		(start 315.399928 -141.213078)
		(end 314.966858 -141.646148)
		(width 0.14224)
		(layer "In4.Cu")
		(net "M_E_DQ<58>")
	)
	(arc
		(start 290.99891 -104.243886)
		(mid 291.205914 -104.45475)
		(end 291.48913 -104.539034)
		(width 0.0889)
		(layer "In4.Cu")
		(net "M_E_DQ<58>")
	)
	(arc
		(start 287.55848 -94.748604)
		(mid 287.564657 -95.328536)
		(end 288.063686 -95.623888)
		(width 0.0889)
		(layer "In4.Cu")
		(net "M_E_DQ<58>")
	)
	(arc
		(start 288.42335 -98.795586)
		(mid 288.47682 -98.990649)
		(end 288.428176 -99.187)
		(width 0.0889)
		(layer "In4.Cu")
		(net "M_E_DQ<58>")
	)
	(arc
		(start 288.417 -99.206304)
		(mid 288.344202 -99.497067)
		(end 288.42335 -99.786186)
		(width 0.0889)
		(layer "In4.Cu")
		(net "M_E_DQ<58>")
	)
	(arc
		(start 288.091626 -95.623888)
		(mid 288.424544 -95.825879)
		(end 288.428176 -96.2152)
		(width 0.0889)
		(layer "In4.Cu")
		(net "M_E_DQ<58>")
	)
	(arc
		(start 288.42335 -100.186236)
		(mid 288.418096 -100.767744)
		(end 288.91357 -101.072188)
		(width 0.0889)
		(layer "In4.Cu")
		(net "M_E_DQ<58>")
	)
	(arc
		(start 289.28187 -102.662736)
		(mid 289.277541 -103.245908)
		(end 289.7759 -103.548688)
		(width 0.0889)
		(layer "In4.Cu")
		(net "M_E_DQ<58>")
	)
	(arc
		(start 287.569656 -93.355922)
		(mid 287.618411 -93.552274)
		(end 287.56483 -93.747336)
		(width 0.0889)
		(layer "In4.Cu")
		(net "M_E_DQ<58>")
	)
	(arc
		(start 288.42335 -96.814386)
		(mid 288.47682 -97.009449)
		(end 288.428176 -97.2058)
		(width 0.0889)
		(layer "In4.Cu")
		(net "M_E_DQ<58>")
	)
	(arc
		(start 288.417 -98.215704)
		(mid 288.344202 -98.506467)
		(end 288.42335 -98.795586)
		(width 0.0889)
		(layer "In4.Cu")
		(net "M_E_DQ<58>")
	)
	(arc
		(start 290.663376 -104.043734)
		(mid 290.857226 -104.100084)
		(end 290.99891 -104.243886)
		(width 0.0889)
		(layer "In4.Cu")
		(net "M_E_DQ<58>")
	)
	(arc
		(start 288.953194 -101.072188)
		(mid 289.286163 -101.279736)
		(end 289.28187 -101.672136)
		(width 0.0889)
		(layer "In4.Cu")
		(net "M_E_DQ<58>")
	)
	(arc
		(start 289.28187 -101.672136)
		(mid 289.202648 -101.961254)
		(end 289.27552 -102.252018)
		(width 0.0889)
		(layer "In4.Cu")
		(net "M_E_DQ<58>")
	)
	(arc
		(start 287.56483 -94.33814)
		(mid 287.626677 -94.520873)
		(end 287.581594 -94.708472)
		(width 0.0889)
		(layer "In4.Cu")
		(net "M_E_DQ<58>")
	)
	(arc
		(start 288.417 -97.225104)
		(mid 288.344202 -97.515867)
		(end 288.42335 -97.804986)
		(width 0.0889)
		(layer "In4.Cu")
		(net "M_E_DQ<58>")
	)
	(arc
		(start 288.42335 -99.786186)
		(mid 288.47682 -99.981249)
		(end 288.428176 -100.1776)
		(width 0.0889)
		(layer "In4.Cu")
		(net "M_E_DQ<58>")
	)
	(arc
		(start 289.286696 -102.271322)
		(mid 289.335451 -102.467674)
		(end 289.28187 -102.662736)
		(width 0.0889)
		(layer "In4.Cu")
		(net "M_E_DQ<58>")
	)
	(arc
		(start 288.417 -96.234504)
		(mid 288.344202 -96.525267)
		(end 288.42335 -96.814386)
		(width 0.0889)
		(layer "In4.Cu")
		(net "M_E_DQ<58>")
	)
	(arc
		(start 288.42335 -97.804986)
		(mid 288.47682 -98.000049)
		(end 288.428176 -98.1964)
		(width 0.0889)
		(layer "In4.Cu")
		(net "M_E_DQ<58>")
	)
	(arc
		(start 290.14039 -103.748586)
		(mid 290.347394 -103.95945)
		(end 290.63061 -104.043734)
		(width 0.0889)
		(layer "In4.Cu")
		(net "M_E_DQ<58>")
	)
	(arc
		(start 287.56483 -93.747336)
		(mid 287.485699 -94.042738)
		(end 287.56483 -94.33814)
		(width 0.0889)
		(layer "In4.Cu")
		(net "M_E_DQ<58>")
	)
	(arc
		(start 289.808666 -103.548688)
		(mid 290.000308 -103.605854)
		(end 290.14039 -103.748586)
		(width 0.0889)
		(layer "In4.Cu")
		(net "M_E_DQ<58>")
	)
	(segment
		(start 309.449978 -142.677642)
		(end 309.449978 -143.941546)
		(width 0.1651)
		(layer "F.Cu")
		(net "M_E_DQ<57>")
	)
	(segment
		(start 309.450486 -142.6718)
		(end 309.449978 -142.677642)
		(width 0.1651)
		(layer "F.Cu")
		(net "M_E_DQ<57>")
	)
	(segment
		(start 284.929834 -95.528384)
		(end 285.501334 -95.528384)
		(width 0.1651)
		(layer "F.Cu")
		(net "M_E_DQ<57>")
	)
	(via
		(at 309.449978 -143.941546)
		(size 0.508)
		(drill 0.254)
		(layers "F.Cu" "B.Cu")
		(net "M_E_DQ<57>")
	)
	(via
		(at 310.122062 -139.932156)
		(size 0.508)
		(drill 0.254)
		(layers "F.Cu" "B.Cu")
		(net "M_E_DQ<57>")
	)
	(via
		(at 285.501334 -95.528384)
		(size 0.508)
		(drill 0.254)
		(layers "F.Cu" "B.Cu")
		(net "M_E_DQ<57>")
	)
	(segment
		(start 310.30037 -137.877296)
		(end 310.299862 -137.877296)
		(width 0.1651)
		(layer "B.Cu")
		(net "M_E_DQ<57>")
	)
	(segment
		(start 310.122062 -139.428982)
		(end 310.122062 -139.932156)
		(width 0.1651)
		(layer "B.Cu")
		(net "M_E_DQ<57>")
	)
	(segment
		(start 310.299862 -137.877296)
		(end 310.299862 -139.251182)
		(width 0.1651)
		(layer "B.Cu")
		(net "M_E_DQ<57>")
	)
	(segment
		(start 310.299862 -139.251182)
		(end 310.122062 -139.428982)
		(width 0.1651)
		(layer "B.Cu")
		(net "M_E_DQ<57>")
	)
	(segment
		(start 303.347628 -119.900446)
		(end 303.597564 -120.150382)
		(width 0.14224)
		(layer "In4.Cu")
		(net "M_E_DQ<57>")
	)
	(segment
		(start 288.342324 -107.18038)
		(end 288.5694 -107.407456)
		(width 0.0889)
		(layer "In4.Cu")
		(net "M_E_DQ<57>")
	)
	(segment
		(start 303.515268 -118.57609)
		(end 303.734216 -118.57609)
		(width 0.14224)
		(layer "In4.Cu")
		(net "M_E_DQ<57>")
	)
	(segment
		(start 303.734216 -118.57609)
		(end 303.984152 -118.826026)
		(width 0.14224)
		(layer "In4.Cu")
		(net "M_E_DQ<57>")
	)
	(segment
		(start 310.609996 -136.5758)
		(end 310.7182 -136.684004)
		(width 0.14224)
		(layer "In4.Cu")
		(net "M_E_DQ<57>")
	)
	(segment
		(start 303.597564 -120.150382)
		(end 303.816512 -120.150382)
		(width 0.14224)
		(layer "In4.Cu")
		(net "M_E_DQ<57>")
	)
	(segment
		(start 310.122062 -139.843256)
		(end 310.122062 -139.932156)
		(width 0.14224)
		(layer "In4.Cu")
		(net "M_E_DQ<57>")
	)
	(segment
		(start 310.609996 -125.45187)
		(end 310.609996 -131.895596)
		(width 0.14224)
		(layer "In4.Cu")
		(net "M_E_DQ<57>")
	)
	(segment
		(start 309.611268 -142.076424)
		(end 309.825644 -142.2908)
		(width 0.14224)
		(layer "In4.Cu")
		(net "M_E_DQ<57>")
	)
	(segment
		(start 309.611268 -141.715744)
		(end 309.611268 -142.076424)
		(width 0.14224)
		(layer "In4.Cu")
		(net "M_E_DQ<57>")
	)
	(segment
		(start 287.730692 -106.130344)
		(end 287.774888 -106.207052)
		(width 0.0889)
		(layer "In4.Cu")
		(net "M_E_DQ<57>")
	)
	(segment
		(start 309.825644 -142.7226)
		(end 309.611268 -142.936976)
		(width 0.14224)
		(layer "In4.Cu")
		(net "M_E_DQ<57>")
	)
	(segment
		(start 285.154624 -100.281486)
		(end 285.149798 -100.290122)
		(width 0.0889)
		(layer "In4.Cu")
		(net "M_E_DQ<57>")
	)
	(segment
		(start 309.698898 -143.941546)
		(end 309.449978 -143.941546)
		(width 0.14224)
		(layer "In4.Cu")
		(net "M_E_DQ<57>")
	)
	(segment
		(start 302.659796 -119.212614)
		(end 302.878744 -119.212614)
		(width 0.14224)
		(layer "In4.Cu")
		(net "M_E_DQ<57>")
	)
	(segment
		(start 310.09971 -139.932156)
		(end 309.671466 -140.3604)
		(width 0.14224)
		(layer "In4.Cu")
		(net "M_E_DQ<57>")
	)
	(segment
		(start 304.671984 -119.513858)
		(end 310.609996 -125.45187)
		(width 0.14224)
		(layer "In4.Cu")
		(net "M_E_DQ<57>")
	)
	(segment
		(start 309.851044 -143.4846)
		(end 309.851044 -143.7894)
		(width 0.14224)
		(layer "In4.Cu")
		(net "M_E_DQ<57>")
	)
	(segment
		(start 310.609996 -138.995404)
		(end 310.609996 -139.355322)
		(width 0.14224)
		(layer "In4.Cu")
		(net "M_E_DQ<57>")
	)
	(segment
		(start 303.046384 -117.888258)
		(end 303.046384 -118.107206)
		(width 0.14224)
		(layer "In4.Cu")
		(net "M_E_DQ<57>")
	)
	(segment
		(start 309.825644 -142.2908)
		(end 309.825644 -142.7226)
		(width 0.14224)
		(layer "In4.Cu")
		(net "M_E_DQ<57>")
	)
	(segment
		(start 285.160974 -101.261418)
		(end 285.154624 -101.272086)
		(width 0.0889)
		(layer "In4.Cu")
		(net "M_E_DQ<57>")
	)
	(segment
		(start 303.347628 -119.681498)
		(end 303.347628 -119.900446)
		(width 0.14224)
		(layer "In4.Cu")
		(net "M_E_DQ<57>")
	)
	(segment
		(start 310.7436 -133.9088)
		(end 310.609996 -134.042404)
		(width 0.14224)
		(layer "In4.Cu")
		(net "M_E_DQ<57>")
	)
	(segment
		(start 288.5694 -107.407456)
		(end 288.5694 -108.458)
		(width 0.14224)
		(layer "In4.Cu")
		(net "M_E_DQ<57>")
	)
	(segment
		(start 310.7436 -132.0292)
		(end 310.7436 -133.9088)
		(width 0.14224)
		(layer "In4.Cu")
		(net "M_E_DQ<57>")
	)
	(segment
		(start 303.046384 -118.107206)
		(end 302.40986 -118.74373)
		(width 0.14224)
		(layer "In4.Cu")
		(net "M_E_DQ<57>")
	)
	(segment
		(start 303.816512 -120.150382)
		(end 304.453036 -119.513858)
		(width 0.14224)
		(layer "In4.Cu")
		(net "M_E_DQ<57>")
	)
	(segment
		(start 310.609996 -139.355322)
		(end 310.122062 -139.843256)
		(width 0.14224)
		(layer "In4.Cu")
		(net "M_E_DQ<57>")
	)
	(segment
		(start 288.342324 -106.774488)
		(end 288.342324 -107.18038)
		(width 0.0889)
		(layer "In4.Cu")
		(net "M_E_DQ<57>")
	)
	(segment
		(start 310.609996 -134.042404)
		(end 310.609996 -136.5758)
		(width 0.14224)
		(layer "In4.Cu")
		(net "M_E_DQ<57>")
	)
	(segment
		(start 302.878744 -119.212614)
		(end 303.515268 -118.57609)
		(width 0.14224)
		(layer "In4.Cu")
		(net "M_E_DQ<57>")
	)
	(segment
		(start 285.154624 -101.272086)
		(end 285.149798 -101.280722)
		(width 0.0889)
		(layer "In4.Cu")
		(net "M_E_DQ<57>")
	)
	(segment
		(start 302.40986 -118.74373)
		(end 302.40986 -118.962678)
		(width 0.14224)
		(layer "In4.Cu")
		(net "M_E_DQ<57>")
	)
	(segment
		(start 302.40986 -118.962678)
		(end 302.659796 -119.212614)
		(width 0.14224)
		(layer "In4.Cu")
		(net "M_E_DQ<57>")
	)
	(segment
		(start 309.611268 -143.244824)
		(end 309.851044 -143.4846)
		(width 0.14224)
		(layer "In4.Cu")
		(net "M_E_DQ<57>")
	)
	(segment
		(start 285.160974 -100.270818)
		(end 285.154624 -100.281486)
		(width 0.0889)
		(layer "In4.Cu")
		(net "M_E_DQ<57>")
	)
	(segment
		(start 285.154624 -102.262686)
		(end 285.149798 -102.271322)
		(width 0.0889)
		(layer "In4.Cu")
		(net "M_E_DQ<57>")
	)
	(segment
		(start 310.7182 -138.8872)
		(end 310.609996 -138.995404)
		(width 0.14224)
		(layer "In4.Cu")
		(net "M_E_DQ<57>")
	)
	(segment
		(start 285.160974 -102.252018)
		(end 285.154624 -102.262686)
		(width 0.0889)
		(layer "In4.Cu")
		(net "M_E_DQ<57>")
	)
	(segment
		(start 285.486348 -102.862634)
		(end 285.519114 -102.862634)
		(width 0.0889)
		(layer "In4.Cu")
		(net "M_E_DQ<57>")
	)
	(segment
		(start 309.851044 -143.7894)
		(end 309.698898 -143.941546)
		(width 0.14224)
		(layer "In4.Cu")
		(net "M_E_DQ<57>")
	)
	(segment
		(start 287.203134 -105.834434)
		(end 287.2359 -105.834434)
		(width 0.0889)
		(layer "In4.Cu")
		(net "M_E_DQ<57>")
	)
	(segment
		(start 286.013144 -104.148636)
		(end 286.022034 -104.163876)
		(width 0.0889)
		(layer "In4.Cu")
		(net "M_E_DQ<57>")
	)
	(segment
		(start 286.3596 -105.339388)
		(end 286.38119 -105.339388)
		(width 0.0889)
		(layer "In4.Cu")
		(net "M_E_DQ<57>")
	)
	(segment
		(start 309.901844 -141.425168)
		(end 309.611268 -141.715744)
		(width 0.14224)
		(layer "In4.Cu")
		(net "M_E_DQ<57>")
	)
	(segment
		(start 304.453036 -119.513858)
		(end 304.671984 -119.513858)
		(width 0.14224)
		(layer "In4.Cu")
		(net "M_E_DQ<57>")
	)
	(segment
		(start 293.908226 -108.7501)
		(end 303.046384 -117.888258)
		(width 0.14224)
		(layer "In4.Cu")
		(net "M_E_DQ<57>")
	)
	(segment
		(start 285.501334 -95.528384)
		(end 285.199328 -96.223328)
		(width 0.0889)
		(layer "In4.Cu")
		(net "M_E_DQ<57>")
	)
	(segment
		(start 303.984152 -118.826026)
		(end 303.984152 -119.044974)
		(width 0.14224)
		(layer "In4.Cu")
		(net "M_E_DQ<57>")
	)
	(segment
		(start 309.671466 -140.3604)
		(end 309.671466 -140.790168)
		(width 0.14224)
		(layer "In4.Cu")
		(net "M_E_DQ<57>")
	)
	(segment
		(start 285.154878 -99.290886)
		(end 285.149798 -99.299522)
		(width 0.0889)
		(layer "In4.Cu")
		(net "M_E_DQ<57>")
	)
	(segment
		(start 310.7182 -136.684004)
		(end 310.7182 -138.8872)
		(width 0.14224)
		(layer "In4.Cu")
		(net "M_E_DQ<57>")
	)
	(segment
		(start 288.8615 -108.7501)
		(end 293.908226 -108.7501)
		(width 0.14224)
		(layer "In4.Cu")
		(net "M_E_DQ<57>")
	)
	(segment
		(start 303.984152 -119.044974)
		(end 303.347628 -119.681498)
		(width 0.14224)
		(layer "In4.Cu")
		(net "M_E_DQ<57>")
	)
	(segment
		(start 310.122062 -139.932156)
		(end 310.09971 -139.932156)
		(width 0.14224)
		(layer "In4.Cu")
		(net "M_E_DQ<57>")
	)
	(segment
		(start 288.5694 -108.458)
		(end 288.8615 -108.7501)
		(width 0.14224)
		(layer "In4.Cu")
		(net "M_E_DQ<57>")
	)
	(segment
		(start 310.609996 -131.895596)
		(end 310.7436 -132.0292)
		(width 0.14224)
		(layer "In4.Cu")
		(net "M_E_DQ<57>")
	)
	(segment
		(start 309.611268 -142.936976)
		(end 309.611268 -143.244824)
		(width 0.14224)
		(layer "In4.Cu")
		(net "M_E_DQ<57>")
	)
	(segment
		(start 309.671466 -140.790168)
		(end 309.901844 -141.020546)
		(width 0.14224)
		(layer "In4.Cu")
		(net "M_E_DQ<57>")
	)
	(segment
		(start 309.901844 -141.020546)
		(end 309.901844 -141.425168)
		(width 0.14224)
		(layer "In4.Cu")
		(net "M_E_DQ<57>")
	)
	(segment
		(start 287.774888 -106.207052)
		(end 288.342324 -106.774488)
		(width 0.0889)
		(layer "In4.Cu")
		(net "M_E_DQ<57>")
	)
	(arc
		(start 285.149798 -99.299522)
		(mid 285.101043 -99.495874)
		(end 285.154624 -99.690936)
		(width 0.0889)
		(layer "In4.Cu")
		(net "M_E_DQ<57>")
	)
	(arc
		(start 285.154878 -96.319086)
		(mid 285.101379 -96.518984)
		(end 285.154878 -96.718882)
		(width 0.0889)
		(layer "In4.Cu")
		(net "M_E_DQ<57>")
	)
	(arc
		(start 285.149798 -100.290122)
		(mid 285.101043 -100.486474)
		(end 285.154624 -100.681536)
		(width 0.0889)
		(layer "In4.Cu")
		(net "M_E_DQ<57>")
	)
	(arc
		(start 285.154878 -98.300286)
		(mid 285.101379 -98.500184)
		(end 285.154878 -98.700082)
		(width 0.0889)
		(layer "In4.Cu")
		(net "M_E_DQ<57>")
	)
	(arc
		(start 285.154878 -97.309686)
		(mid 285.101379 -97.509584)
		(end 285.154878 -97.709482)
		(width 0.0889)
		(layer "In4.Cu")
		(net "M_E_DQ<57>")
	)
	(arc
		(start 285.519114 -102.862634)
		(mid 286.017635 -103.165518)
		(end 286.013144 -103.74884)
		(width 0.0889)
		(layer "In4.Cu")
		(net "M_E_DQ<57>")
	)
	(arc
		(start 286.022034 -104.163876)
		(mid 286.092431 -104.452827)
		(end 286.013144 -104.73944)
		(width 0.0889)
		(layer "In4.Cu")
		(net "M_E_DQ<57>")
	)
	(arc
		(start 285.149798 -101.280722)
		(mid 285.101043 -101.477074)
		(end 285.154624 -101.672136)
		(width 0.0889)
		(layer "In4.Cu")
		(net "M_E_DQ<57>")
	)
	(arc
		(start 287.2359 -105.834434)
		(mid 287.521774 -105.918045)
		(end 287.730692 -106.130344)
		(width 0.0889)
		(layer "In4.Cu")
		(net "M_E_DQ<57>")
	)
	(arc
		(start 285.154624 -99.690936)
		(mid 285.233846 -99.980054)
		(end 285.160974 -100.270818)
		(width 0.0889)
		(layer "In4.Cu")
		(net "M_E_DQ<57>")
	)
	(arc
		(start 286.013144 -103.74884)
		(mid 285.959611 -103.948738)
		(end 286.013144 -104.148636)
		(width 0.0889)
		(layer "In4.Cu")
		(net "M_E_DQ<57>")
	)
	(arc
		(start 286.38119 -105.339388)
		(mid 286.664407 -105.423669)
		(end 286.87141 -105.634536)
		(width 0.0889)
		(layer "In4.Cu")
		(net "M_E_DQ<57>")
	)
	(arc
		(start 285.154624 -101.672136)
		(mid 285.233846 -101.961254)
		(end 285.160974 -102.252018)
		(width 0.0889)
		(layer "In4.Cu")
		(net "M_E_DQ<57>")
	)
	(arc
		(start 285.154878 -96.718882)
		(mid 285.234009 -97.014284)
		(end 285.154878 -97.309686)
		(width 0.0889)
		(layer "In4.Cu")
		(net "M_E_DQ<57>")
	)
	(arc
		(start 285.154878 -97.709482)
		(mid 285.234009 -98.004884)
		(end 285.154878 -98.300286)
		(width 0.0889)
		(layer "In4.Cu")
		(net "M_E_DQ<57>")
	)
	(arc
		(start 286.013144 -104.73944)
		(mid 286.013227 -105.139381)
		(end 286.3596 -105.339388)
		(width 0.0889)
		(layer "In4.Cu")
		(net "M_E_DQ<57>")
	)
	(arc
		(start 285.149798 -102.271322)
		(mid 285.153545 -102.660578)
		(end 285.486348 -102.862634)
		(width 0.0889)
		(layer "In4.Cu")
		(net "M_E_DQ<57>")
	)
	(arc
		(start 285.154878 -98.700082)
		(mid 285.234009 -98.995484)
		(end 285.154878 -99.290886)
		(width 0.0889)
		(layer "In4.Cu")
		(net "M_E_DQ<57>")
	)
	(arc
		(start 286.87141 -105.634536)
		(mid 287.011489 -105.777272)
		(end 287.203134 -105.834434)
		(width 0.0889)
		(layer "In4.Cu")
		(net "M_E_DQ<57>")
	)
	(arc
		(start 285.154624 -100.681536)
		(mid 285.233846 -100.970654)
		(end 285.160974 -101.261418)
		(width 0.0889)
		(layer "In4.Cu")
		(net "M_E_DQ<57>")
	)
	(arc
		(start 285.199328 -96.223328)
		(mid 285.179246 -96.272202)
		(end 285.154878 -96.319086)
		(width 0.0889)
		(layer "In4.Cu")
		(net "M_E_DQ<57>")
	)
	(segment
		(start 310.30037 -147.27174)
		(end 310.299862 -147.277582)
		(width 0.1651)
		(layer "F.Cu")
		(net "M_E_DQ<56>")
	)
	(segment
		(start 310.299862 -147.277582)
		(end 310.122062 -145.415)
		(width 0.1651)
		(layer "F.Cu")
		(net "M_E_DQ<56>")
	)
	(segment
		(start 284.929834 -93.547184)
		(end 285.501334 -93.547184)
		(width 0.1651)
		(layer "F.Cu")
		(net "M_E_DQ<56>")
	)
	(via
		(at 310.122062 -145.415)
		(size 0.508)
		(drill 0.254)
		(layers "F.Cu" "B.Cu")
		(net "M_E_DQ<56>")
	)
	(via
		(at 309.449978 -141.213078)
		(size 0.508)
		(drill 0.254)
		(layers "F.Cu" "B.Cu")
		(net "M_E_DQ<56>")
	)
	(via
		(at 285.501334 -93.547184)
		(size 0.508)
		(drill 0.254)
		(layers "F.Cu" "B.Cu")
		(net "M_E_DQ<56>")
	)
	(segment
		(start 309.449978 -142.476982)
		(end 309.449978 -141.213078)
		(width 0.1651)
		(layer "B.Cu")
		(net "M_E_DQ<56>")
	)
	(segment
		(start 309.450486 -142.477236)
		(end 309.449978 -142.476982)
		(width 0.1651)
		(layer "B.Cu")
		(net "M_E_DQ<56>")
	)
	(segment
		(start 287.94456 -111.26216)
		(end 291.1602 -114.4778)
		(width 0.14224)
		(layer "In4.Cu")
		(net "M_E_DQ<56>")
	)
	(segment
		(start 309.616602 -134.78637)
		(end 309.616602 -135.957056)
		(width 0.14224)
		(layer "In4.Cu")
		(net "M_E_DQ<56>")
	)
	(segment
		(start 287.94456 -107.46867)
		(end 287.94456 -111.26216)
		(width 0.14224)
		(layer "In4.Cu")
		(net "M_E_DQ<56>")
	)
	(segment
		(start 309.632096 -130.062478)
		(end 309.632096 -131.141978)
		(width 0.14224)
		(layer "In4.Cu")
		(net "M_E_DQ<56>")
	)
	(segment
		(start 293.920164 -114.4778)
		(end 299.468032 -120.025668)
		(width 0.14224)
		(layer "In4.Cu")
		(net "M_E_DQ<56>")
	)
	(segment
		(start 309.88 -138.8872)
		(end 309.936896 -138.944096)
		(width 0.14224)
		(layer "In4.Cu")
		(net "M_E_DQ<56>")
	)
	(segment
		(start 287.56483 -106.225086)
		(end 287.621472 -106.32313)
		(width 0.0889)
		(layer "In4.Cu")
		(net "M_E_DQ<56>")
	)
	(segment
		(start 309.016908 -144.60601)
		(end 309.825898 -145.415)
		(width 0.14224)
		(layer "In4.Cu")
		(net "M_E_DQ<56>")
	)
	(segment
		(start 287.19653 -106.024934)
		(end 287.229296 -106.024934)
		(width 0.0889)
		(layer "In4.Cu")
		(net "M_E_DQ<56>")
	)
	(segment
		(start 287.621472 -106.32313)
		(end 288.151824 -106.853482)
		(width 0.0889)
		(layer "In4.Cu")
		(net "M_E_DQ<56>")
	)
	(segment
		(start 309.936896 -139.358878)
		(end 309.2196 -140.076174)
		(width 0.14224)
		(layer "In4.Cu")
		(net "M_E_DQ<56>")
	)
	(segment
		(start 284.99435 -101.1682)
		(end 284.989524 -101.176836)
		(width 0.0889)
		(layer "In4.Cu")
		(net "M_E_DQ<56>")
	)
	(segment
		(start 309.88 -136.632696)
		(end 309.88 -138.8872)
		(width 0.14224)
		(layer "In4.Cu")
		(net "M_E_DQ<56>")
	)
	(segment
		(start 284.989524 -100.186236)
		(end 284.983174 -100.196904)
		(width 0.0889)
		(layer "In4.Cu")
		(net "M_E_DQ<56>")
	)
	(segment
		(start 309.924196 -134.478776)
		(end 309.616602 -134.78637)
		(width 0.14224)
		(layer "In4.Cu")
		(net "M_E_DQ<56>")
	)
	(segment
		(start 309.936896 -136.5758)
		(end 309.88 -136.632696)
		(width 0.14224)
		(layer "In4.Cu")
		(net "M_E_DQ<56>")
	)
	(segment
		(start 309.936896 -136.27735)
		(end 309.936896 -136.5758)
		(width 0.14224)
		(layer "In4.Cu")
		(net "M_E_DQ<56>")
	)
	(segment
		(start 288.151824 -107.261406)
		(end 287.94456 -107.46867)
		(width 0.0889)
		(layer "In4.Cu")
		(net "M_E_DQ<56>")
	)
	(segment
		(start 309.974996 -125.595888)
		(end 309.974996 -129.719578)
		(width 0.14224)
		(layer "In4.Cu")
		(net "M_E_DQ<56>")
	)
	(segment
		(start 285.479744 -103.053134)
		(end 285.501334 -103.053134)
		(width 0.0889)
		(layer "In4.Cu")
		(net "M_E_DQ<56>")
	)
	(segment
		(start 309.924196 -131.9022)
		(end 309.88 -131.946396)
		(width 0.14224)
		(layer "In4.Cu")
		(net "M_E_DQ<56>")
	)
	(segment
		(start 288.151824 -106.853482)
		(end 288.151824 -107.261406)
		(width 0.0889)
		(layer "In4.Cu")
		(net "M_E_DQ<56>")
	)
	(segment
		(start 309.974996 -129.719578)
		(end 309.632096 -130.062478)
		(width 0.14224)
		(layer "In4.Cu")
		(net "M_E_DQ<56>")
	)
	(segment
		(start 286.34182 -105.529888)
		(end 286.374586 -105.529888)
		(width 0.0889)
		(layer "In4.Cu")
		(net "M_E_DQ<56>")
	)
	(segment
		(start 284.989524 -102.167436)
		(end 284.983174 -102.178104)
		(width 0.0889)
		(layer "In4.Cu")
		(net "M_E_DQ<56>")
	)
	(segment
		(start 309.632096 -131.141978)
		(end 309.924196 -131.434078)
		(width 0.14224)
		(layer "In4.Cu")
		(net "M_E_DQ<56>")
	)
	(segment
		(start 309.016908 -141.646148)
		(end 309.016908 -144.60601)
		(width 0.14224)
		(layer "In4.Cu")
		(net "M_E_DQ<56>")
	)
	(segment
		(start 284.989778 -95.232982)
		(end 285.121096 -95.005398)
		(width 0.0889)
		(layer "In4.Cu")
		(net "M_E_DQ<56>")
	)
	(segment
		(start 309.88 -134.0358)
		(end 309.924196 -134.079996)
		(width 0.14224)
		(layer "In4.Cu")
		(net "M_E_DQ<56>")
	)
	(segment
		(start 309.2196 -140.9827)
		(end 309.449978 -141.213078)
		(width 0.14224)
		(layer "In4.Cu")
		(net "M_E_DQ<56>")
	)
	(segment
		(start 309.449978 -141.213078)
		(end 309.016908 -141.646148)
		(width 0.14224)
		(layer "In4.Cu")
		(net "M_E_DQ<56>")
	)
	(segment
		(start 309.924196 -134.079996)
		(end 309.924196 -134.478776)
		(width 0.14224)
		(layer "In4.Cu")
		(net "M_E_DQ<56>")
	)
	(segment
		(start 284.99435 -102.1588)
		(end 284.989524 -102.167436)
		(width 0.0889)
		(layer "In4.Cu")
		(net "M_E_DQ<56>")
	)
	(segment
		(start 309.616602 -135.957056)
		(end 309.936896 -136.27735)
		(width 0.14224)
		(layer "In4.Cu")
		(net "M_E_DQ<56>")
	)
	(segment
		(start 309.825898 -145.415)
		(end 310.122062 -145.415)
		(width 0.14224)
		(layer "In4.Cu")
		(net "M_E_DQ<56>")
	)
	(segment
		(start 309.924196 -131.434078)
		(end 309.924196 -131.9022)
		(width 0.14224)
		(layer "In4.Cu")
		(net "M_E_DQ<56>")
	)
	(segment
		(start 299.468032 -120.025668)
		(end 305.637946 -121.258838)
		(width 0.14224)
		(layer "In4.Cu")
		(net "M_E_DQ<56>")
	)
	(segment
		(start 284.989524 -101.176836)
		(end 284.983174 -101.187504)
		(width 0.0889)
		(layer "In4.Cu")
		(net "M_E_DQ<56>")
	)
	(segment
		(start 291.1602 -114.4778)
		(end 293.920164 -114.4778)
		(width 0.14224)
		(layer "In4.Cu")
		(net "M_E_DQ<56>")
	)
	(segment
		(start 284.99435 -100.1776)
		(end 284.989524 -100.186236)
		(width 0.0889)
		(layer "In4.Cu")
		(net "M_E_DQ<56>")
	)
	(segment
		(start 305.637946 -121.258838)
		(end 309.974996 -125.595888)
		(width 0.14224)
		(layer "In4.Cu")
		(net "M_E_DQ<56>")
	)
	(segment
		(start 309.936896 -138.944096)
		(end 309.936896 -139.358878)
		(width 0.14224)
		(layer "In4.Cu")
		(net "M_E_DQ<56>")
	)
	(segment
		(start 309.2196 -140.076174)
		(end 309.2196 -140.9827)
		(width 0.14224)
		(layer "In4.Cu")
		(net "M_E_DQ<56>")
	)
	(segment
		(start 285.8389 -104.228646)
		(end 285.84779 -104.243886)
		(width 0.0889)
		(layer "In4.Cu")
		(net "M_E_DQ<56>")
	)
	(segment
		(start 309.88 -131.946396)
		(end 309.88 -134.0358)
		(width 0.14224)
		(layer "In4.Cu")
		(net "M_E_DQ<56>")
	)
	(segment
		(start 285.501334 -93.547184)
		(end 285.201868 -94.234762)
		(width 0.0889)
		(layer "In4.Cu")
		(net "M_E_DQ<56>")
	)
	(arc
		(start 284.983174 -100.196904)
		(mid 284.910376 -100.487667)
		(end 284.989524 -100.776786)
		(width 0.0889)
		(layer "In4.Cu")
		(net "M_E_DQ<56>")
	)
	(arc
		(start 284.989778 -99.195382)
		(mid 284.986531 -99.200876)
		(end 284.983174 -99.206304)
		(width 0.0889)
		(layer "In4.Cu")
		(net "M_E_DQ<56>")
	)
	(arc
		(start 285.84779 -104.643682)
		(mid 285.843462 -105.226858)
		(end 286.34182 -105.529888)
		(width 0.0889)
		(layer "In4.Cu")
		(net "M_E_DQ<56>")
	)
	(arc
		(start 284.989778 -95.823786)
		(mid 285.043277 -96.023684)
		(end 284.989778 -96.223582)
		(width 0.0889)
		(layer "In4.Cu")
		(net "M_E_DQ<56>")
	)
	(arc
		(start 284.989778 -96.223582)
		(mid 284.910647 -96.518984)
		(end 284.989778 -96.814386)
		(width 0.0889)
		(layer "In4.Cu")
		(net "M_E_DQ<56>")
	)
	(arc
		(start 284.983174 -102.178104)
		(mid 284.987205 -102.754286)
		(end 285.479744 -103.053134)
		(width 0.0889)
		(layer "In4.Cu")
		(net "M_E_DQ<56>")
	)
	(arc
		(start 284.989778 -97.804986)
		(mid 285.043277 -98.004884)
		(end 284.989778 -98.204782)
		(width 0.0889)
		(layer "In4.Cu")
		(net "M_E_DQ<56>")
	)
	(arc
		(start 285.201868 -94.234762)
		(mid 285.180857 -94.287456)
		(end 285.154878 -94.337886)
		(width 0.0889)
		(layer "In4.Cu")
		(net "M_E_DQ<56>")
	)
	(arc
		(start 284.989778 -97.214182)
		(mid 284.910647 -97.509584)
		(end 284.989778 -97.804986)
		(width 0.0889)
		(layer "In4.Cu")
		(net "M_E_DQ<56>")
	)
	(arc
		(start 287.229296 -106.024934)
		(mid 287.423146 -106.081284)
		(end 287.56483 -106.225086)
		(width 0.0889)
		(layer "In4.Cu")
		(net "M_E_DQ<56>")
	)
	(arc
		(start 285.501334 -103.053134)
		(mid 285.84776 -103.253111)
		(end 285.84779 -103.653082)
		(width 0.0889)
		(layer "In4.Cu")
		(net "M_E_DQ<56>")
	)
	(arc
		(start 284.983174 -101.187504)
		(mid 284.910376 -101.478267)
		(end 284.989524 -101.767386)
		(width 0.0889)
		(layer "In4.Cu")
		(net "M_E_DQ<56>")
	)
	(arc
		(start 285.154878 -94.337886)
		(mid 285.101885 -94.517677)
		(end 285.13659 -94.701868)
		(width 0.0889)
		(layer "In4.Cu")
		(net "M_E_DQ<56>")
	)
	(arc
		(start 284.989524 -99.786186)
		(mid 285.042994 -99.981249)
		(end 284.99435 -100.1776)
		(width 0.0889)
		(layer "In4.Cu")
		(net "M_E_DQ<56>")
	)
	(arc
		(start 285.13659 -94.701868)
		(mid 285.165455 -94.855503)
		(end 285.121096 -95.005398)
		(width 0.0889)
		(layer "In4.Cu")
		(net "M_E_DQ<56>")
	)
	(arc
		(start 284.983174 -99.206304)
		(mid 284.910376 -99.497067)
		(end 284.989524 -99.786186)
		(width 0.0889)
		(layer "In4.Cu")
		(net "M_E_DQ<56>")
	)
	(arc
		(start 284.989524 -100.776786)
		(mid 285.042994 -100.971849)
		(end 284.99435 -101.1682)
		(width 0.0889)
		(layer "In4.Cu")
		(net "M_E_DQ<56>")
	)
	(arc
		(start 285.84779 -104.243886)
		(mid 285.901323 -104.443784)
		(end 285.84779 -104.643682)
		(width 0.0889)
		(layer "In4.Cu")
		(net "M_E_DQ<56>")
	)
	(arc
		(start 284.989778 -95.232982)
		(mid 284.910647 -95.528384)
		(end 284.989778 -95.823786)
		(width 0.0889)
		(layer "In4.Cu")
		(net "M_E_DQ<56>")
	)
	(arc
		(start 284.989524 -101.767386)
		(mid 285.042994 -101.962449)
		(end 284.99435 -102.1588)
		(width 0.0889)
		(layer "In4.Cu")
		(net "M_E_DQ<56>")
	)
	(arc
		(start 284.989778 -98.204782)
		(mid 284.910647 -98.500184)
		(end 284.989778 -98.795586)
		(width 0.0889)
		(layer "In4.Cu")
		(net "M_E_DQ<56>")
	)
	(arc
		(start 285.84779 -103.653082)
		(mid 285.768601 -103.939697)
		(end 285.8389 -104.228646)
		(width 0.0889)
		(layer "In4.Cu")
		(net "M_E_DQ<56>")
	)
	(arc
		(start 284.989778 -98.795586)
		(mid 285.043277 -98.995484)
		(end 284.989778 -99.195382)
		(width 0.0889)
		(layer "In4.Cu")
		(net "M_E_DQ<56>")
	)
	(arc
		(start 284.989778 -96.814386)
		(mid 285.043277 -97.014284)
		(end 284.989778 -97.214182)
		(width 0.0889)
		(layer "In4.Cu")
		(net "M_E_DQ<56>")
	)
	(arc
		(start 286.374586 -105.529888)
		(mid 286.566228 -105.587054)
		(end 286.70631 -105.729786)
		(width 0.0889)
		(layer "In4.Cu")
		(net "M_E_DQ<56>")
	)
	(arc
		(start 286.70631 -105.729786)
		(mid 286.913314 -105.94065)
		(end 287.19653 -106.024934)
		(width 0.0889)
		(layer "In4.Cu")
		(net "M_E_DQ<56>")
	)
	(segment
		(start 303.87163 -111.94923)
		(end 304.30343 -111.94923)
		(width 0.1651)
		(layer "F.Cu")
		(net "M_E_DQ<55>")
	)
	(segment
		(start 302.399446 -110.045246)
		(end 302.659542 -110.305342)
		(width 0.1651)
		(layer "F.Cu")
		(net "M_E_DQ<55>")
	)
	(segment
		(start 304.35042 -142.6718)
		(end 304.349912 -142.677642)
		(width 0.1651)
		(layer "F.Cu")
		(net "M_E_DQ<55>")
	)
	(segment
		(start 303.611534 -111.257334)
		(end 303.611534 -111.689134)
		(width 0.1651)
		(layer "F.Cu")
		(net "M_E_DQ<55>")
	)
	(segment
		(start 305.743864 -121.882408)
		(end 305.938174 -121.882408)
		(width 0.1651)
		(layer "F.Cu")
		(net "M_E_DQ<55>")
	)
	(segment
		(start 287.916366 -105.080054)
		(end 296.036492 -105.080054)
		(width 0.1016)
		(layer "F.Cu")
		(net "M_E_DQ<55>")
	)
	(segment
		(start 304.30343 -111.94923)
		(end 304.877216 -112.523016)
		(width 0.1651)
		(layer "F.Cu")
		(net "M_E_DQ<55>")
	)
	(segment
		(start 301.967646 -110.045246)
		(end 302.399446 -110.045246)
		(width 0.1651)
		(layer "F.Cu")
		(net "M_E_DQ<55>")
	)
	(segment
		(start 305.578764 -121.224548)
		(end 305.578764 -121.717308)
		(width 0.1651)
		(layer "F.Cu")
		(net "M_E_DQ<55>")
	)
	(segment
		(start 305.816 -125.182376)
		(end 305.689 -125.309376)
		(width 0.1651)
		(layer "F.Cu")
		(net "M_E_DQ<55>")
	)
	(segment
		(start 301.032672 -109.0676)
		(end 301.4218 -109.0676)
		(width 0.1651)
		(layer "F.Cu")
		(net "M_E_DQ<55>")
	)
	(segment
		(start 302.919638 -110.997238)
		(end 303.351438 -110.997238)
		(width 0.1651)
		(layer "F.Cu")
		(net "M_E_DQ<55>")
	)
	(segment
		(start 302.659542 -110.305342)
		(end 302.659542 -110.737142)
		(width 0.1651)
		(layer "F.Cu")
		(net "M_E_DQ<55>")
	)
	(segment
		(start 300.270672 -108.3056)
		(end 300.4439 -108.478828)
		(width 0.1016)
		(layer "F.Cu")
		(net "M_E_DQ<55>")
	)
	(segment
		(start 300.4439 -108.478828)
		(end 301.032672 -109.0676)
		(width 0.1651)
		(layer "F.Cu")
		(net "M_E_DQ<55>")
	)
	(segment
		(start 305.943 -124.08408)
		(end 305.816 -124.21108)
		(width 0.1651)
		(layer "F.Cu")
		(net "M_E_DQ<55>")
	)
	(segment
		(start 303.351438 -110.997238)
		(end 303.611534 -111.257334)
		(width 0.1651)
		(layer "F.Cu")
		(net "M_E_DQ<55>")
	)
	(segment
		(start 296.036492 -105.080054)
		(end 299.0215 -108.065062)
		(width 0.1016)
		(layer "F.Cu")
		(net "M_E_DQ<55>")
	)
	(segment
		(start 304.877216 -119.863616)
		(end 305.086512 -120.072912)
		(width 0.1651)
		(layer "F.Cu")
		(net "M_E_DQ<55>")
	)
	(segment
		(start 305.938174 -121.882408)
		(end 306.103274 -122.047508)
		(width 0.1651)
		(layer "F.Cu")
		(net "M_E_DQ<55>")
	)
	(segment
		(start 306.135786 -120.861836)
		(end 305.938174 -121.059448)
		(width 0.1651)
		(layer "F.Cu")
		(net "M_E_DQ<55>")
	)
	(segment
		(start 305.938174 -121.059448)
		(end 305.743864 -121.059448)
		(width 0.1651)
		(layer "F.Cu")
		(net "M_E_DQ<55>")
	)
	(segment
		(start 305.086512 -120.072912)
		(end 305.746912 -120.072912)
		(width 0.1651)
		(layer "F.Cu")
		(net "M_E_DQ<55>")
	)
	(segment
		(start 305.746912 -120.072912)
		(end 306.135786 -120.461786)
		(width 0.1651)
		(layer "F.Cu")
		(net "M_E_DQ<55>")
	)
	(segment
		(start 305.97602 -124.08408)
		(end 305.943 -124.08408)
		(width 0.1651)
		(layer "F.Cu")
		(net "M_E_DQ<55>")
	)
	(segment
		(start 286.64662 -102.462584)
		(end 286.64662 -103.810308)
		(width 0.0889)
		(layer "F.Cu")
		(net "M_E_DQ<55>")
	)
	(segment
		(start 286.64662 -103.810308)
		(end 287.916366 -105.080054)
		(width 0.1016)
		(layer "F.Cu")
		(net "M_E_DQ<55>")
	)
	(segment
		(start 302.659542 -110.737142)
		(end 302.919638 -110.997238)
		(width 0.1651)
		(layer "F.Cu")
		(net "M_E_DQ<55>")
	)
	(segment
		(start 304.349912 -142.677642)
		(end 304.349912 -143.941546)
		(width 0.1651)
		(layer "F.Cu")
		(net "M_E_DQ<55>")
	)
	(segment
		(start 299.0215 -108.065062)
		(end 299.262038 -108.3056)
		(width 0.1016)
		(layer "F.Cu")
		(net "M_E_DQ<55>")
	)
	(segment
		(start 305.689 -125.309376)
		(end 305.047396 -125.309376)
		(width 0.1651)
		(layer "F.Cu")
		(net "M_E_DQ<55>")
	)
	(segment
		(start 305.743864 -121.059448)
		(end 305.578764 -121.224548)
		(width 0.1651)
		(layer "F.Cu")
		(net "M_E_DQ<55>")
	)
	(segment
		(start 305.578764 -121.717308)
		(end 305.743864 -121.882408)
		(width 0.1651)
		(layer "F.Cu")
		(net "M_E_DQ<55>")
	)
	(segment
		(start 304.877216 -112.523016)
		(end 304.877216 -119.863616)
		(width 0.1651)
		(layer "F.Cu")
		(net "M_E_DQ<55>")
	)
	(segment
		(start 306.103274 -123.956826)
		(end 305.97602 -124.08408)
		(width 0.1651)
		(layer "F.Cu")
		(net "M_E_DQ<55>")
	)
	(segment
		(start 301.70755 -109.35335)
		(end 301.70755 -109.78515)
		(width 0.1651)
		(layer "F.Cu")
		(net "M_E_DQ<55>")
	)
	(segment
		(start 306.103274 -122.047508)
		(end 306.103274 -123.956826)
		(width 0.1651)
		(layer "F.Cu")
		(net "M_E_DQ<55>")
	)
	(segment
		(start 301.70755 -109.78515)
		(end 301.967646 -110.045246)
		(width 0.1651)
		(layer "F.Cu")
		(net "M_E_DQ<55>")
	)
	(segment
		(start 299.262038 -108.3056)
		(end 300.270672 -108.3056)
		(width 0.1016)
		(layer "F.Cu")
		(net "M_E_DQ<55>")
	)
	(segment
		(start 306.135786 -120.461786)
		(end 306.135786 -120.861836)
		(width 0.1651)
		(layer "F.Cu")
		(net "M_E_DQ<55>")
	)
	(segment
		(start 301.4218 -109.0676)
		(end 301.70755 -109.35335)
		(width 0.1651)
		(layer "F.Cu")
		(net "M_E_DQ<55>")
	)
	(segment
		(start 303.611534 -111.689134)
		(end 303.87163 -111.94923)
		(width 0.1651)
		(layer "F.Cu")
		(net "M_E_DQ<55>")
	)
	(segment
		(start 305.816 -124.21108)
		(end 305.816 -125.182376)
		(width 0.1651)
		(layer "F.Cu")
		(net "M_E_DQ<55>")
	)
	(via
		(at 305.047396 -125.309376)
		(size 0.508)
		(drill 0.254)
		(layers "F.Cu" "B.Cu")
		(net "M_E_DQ<55>")
	)
	(via
		(at 304.349912 -143.941546)
		(size 0.508)
		(drill 0.254)
		(layers "F.Cu" "B.Cu")
		(net "M_E_DQ<55>")
	)
	(via
		(at 305.199796 -139.932156)
		(size 0.508)
		(drill 0.254)
		(layers "F.Cu" "B.Cu")
		(net "M_E_DQ<55>")
	)
	(segment
		(start 305.199796 -137.877296)
		(end 305.199796 -139.932156)
		(width 0.1651)
		(layer "B.Cu")
		(net "M_E_DQ<55>")
	)
	(segment
		(start 305.200304 -137.877296)
		(end 305.199796 -137.877296)
		(width 0.1651)
		(layer "B.Cu")
		(net "M_E_DQ<55>")
	)
	(segment
		(start 305.54168 -139.590272)
		(end 305.199796 -139.932156)
		(width 0.14224)
		(layer "In4.Cu")
		(net "M_E_DQ<55>")
	)
	(segment
		(start 305.552602 -129.859278)
		(end 305.781202 -130.087878)
		(width 0.14224)
		(layer "In4.Cu")
		(net "M_E_DQ<55>")
	)
	(segment
		(start 305.781202 -130.087878)
		(end 305.781202 -131.205478)
		(width 0.14224)
		(layer "In4.Cu")
		(net "M_E_DQ<55>")
	)
	(segment
		(start 305.047396 -125.309376)
		(end 305.047396 -126.911608)
		(width 0.14224)
		(layer "In4.Cu")
		(net "M_E_DQ<55>")
	)
	(segment
		(start 305.552602 -136.6012)
		(end 305.6382 -136.686798)
		(width 0.14224)
		(layer "In4.Cu")
		(net "M_E_DQ<55>")
	)
	(segment
		(start 305.552602 -138.896598)
		(end 305.552602 -139.590272)
		(width 0.14224)
		(layer "In4.Cu")
		(net "M_E_DQ<55>")
	)
	(segment
		(start 305.6128 -131.962398)
		(end 305.6128 -134.0866)
		(width 0.14224)
		(layer "In4.Cu")
		(net "M_E_DQ<55>")
	)
	(segment
		(start 305.578002 -134.568438)
		(end 305.721766 -134.712202)
		(width 0.14224)
		(layer "In4.Cu")
		(net "M_E_DQ<55>")
	)
	(segment
		(start 305.552602 -136.204198)
		(end 305.552602 -136.6012)
		(width 0.14224)
		(layer "In4.Cu")
		(net "M_E_DQ<55>")
	)
	(segment
		(start 305.552602 -127.416814)
		(end 305.552602 -129.859278)
		(width 0.14224)
		(layer "In4.Cu")
		(net "M_E_DQ<55>")
	)
	(segment
		(start 305.6128 -134.0866)
		(end 305.578002 -134.121398)
		(width 0.14224)
		(layer "In4.Cu")
		(net "M_E_DQ<55>")
	)
	(segment
		(start 305.047396 -126.911608)
		(end 305.552602 -127.416814)
		(width 0.14224)
		(layer "In4.Cu")
		(net "M_E_DQ<55>")
	)
	(segment
		(start 305.721766 -134.712202)
		(end 305.721766 -136.035034)
		(width 0.14224)
		(layer "In4.Cu")
		(net "M_E_DQ<55>")
	)
	(segment
		(start 305.721766 -136.035034)
		(end 305.552602 -136.204198)
		(width 0.14224)
		(layer "In4.Cu")
		(net "M_E_DQ<55>")
	)
	(segment
		(start 305.781202 -131.205478)
		(end 305.578002 -131.408678)
		(width 0.14224)
		(layer "In4.Cu")
		(net "M_E_DQ<55>")
	)
	(segment
		(start 305.552602 -139.590272)
		(end 305.54168 -139.590272)
		(width 0.14224)
		(layer "In4.Cu")
		(net "M_E_DQ<55>")
	)
	(segment
		(start 305.578002 -131.408678)
		(end 305.578002 -131.9276)
		(width 0.14224)
		(layer "In4.Cu")
		(net "M_E_DQ<55>")
	)
	(segment
		(start 305.578002 -131.9276)
		(end 305.6128 -131.962398)
		(width 0.14224)
		(layer "In4.Cu")
		(net "M_E_DQ<55>")
	)
	(segment
		(start 305.6382 -136.686798)
		(end 305.6382 -138.811)
		(width 0.14224)
		(layer "In4.Cu")
		(net "M_E_DQ<55>")
	)
	(segment
		(start 305.6382 -138.811)
		(end 305.552602 -138.896598)
		(width 0.14224)
		(layer "In4.Cu")
		(net "M_E_DQ<55>")
	)
	(segment
		(start 305.578002 -134.121398)
		(end 305.578002 -134.568438)
		(width 0.14224)
		(layer "In4.Cu")
		(net "M_E_DQ<55>")
	)
	(segment
		(start 304.7492 -140.3604)
		(end 305.177444 -139.932156)
		(width 0.14224)
		(layer "In9.Cu")
		(net "M_E_DQ<55>")
	)
	(segment
		(start 304.79365 -141.5034)
		(end 304.79365 -140.834618)
		(width 0.14224)
		(layer "In9.Cu")
		(net "M_E_DQ<55>")
	)
	(segment
		(start 304.79365 -140.834618)
		(end 304.7492 -140.790168)
		(width 0.14224)
		(layer "In9.Cu")
		(net "M_E_DQ<55>")
	)
	(segment
		(start 304.7492 -140.790168)
		(end 304.7492 -140.3604)
		(width 0.14224)
		(layer "In9.Cu")
		(net "M_E_DQ<55>")
	)
	(segment
		(start 304.511202 -142.878048)
		(end 304.76825 -142.621)
		(width 0.14224)
		(layer "In9.Cu")
		(net "M_E_DQ<55>")
	)
	(segment
		(start 304.511202 -141.785848)
		(end 304.79365 -141.5034)
		(width 0.14224)
		(layer "In9.Cu")
		(net "M_E_DQ<55>")
	)
	(segment
		(start 304.511202 -142.059152)
		(end 304.511202 -141.785848)
		(width 0.14224)
		(layer "In9.Cu")
		(net "M_E_DQ<55>")
	)
	(segment
		(start 304.8 -143.763746)
		(end 304.8 -143.44015)
		(width 0.14224)
		(layer "In9.Cu")
		(net "M_E_DQ<55>")
	)
	(segment
		(start 305.177444 -139.932156)
		(end 305.199796 -139.932156)
		(width 0.14224)
		(layer "In9.Cu")
		(net "M_E_DQ<55>")
	)
	(segment
		(start 304.349912 -143.941546)
		(end 304.6222 -143.941546)
		(width 0.14224)
		(layer "In9.Cu")
		(net "M_E_DQ<55>")
	)
	(segment
		(start 304.8 -143.44015)
		(end 304.511202 -143.151352)
		(width 0.14224)
		(layer "In9.Cu")
		(net "M_E_DQ<55>")
	)
	(segment
		(start 304.6222 -143.941546)
		(end 304.8 -143.763746)
		(width 0.14224)
		(layer "In9.Cu")
		(net "M_E_DQ<55>")
	)
	(segment
		(start 304.76825 -142.621)
		(end 304.76825 -142.3162)
		(width 0.14224)
		(layer "In9.Cu")
		(net "M_E_DQ<55>")
	)
	(segment
		(start 304.511202 -143.151352)
		(end 304.511202 -142.878048)
		(width 0.14224)
		(layer "In9.Cu")
		(net "M_E_DQ<55>")
	)
	(segment
		(start 304.76825 -142.3162)
		(end 304.511202 -142.059152)
		(width 0.14224)
		(layer "In9.Cu")
		(net "M_E_DQ<55>")
	)
	(segment
		(start 299.871384 -108.964984)
		(end 304.202338 -113.295938)
		(width 0.1651)
		(layer "F.Cu")
		(net "M_E_DQ<54>")
	)
	(segment
		(start 304.7746 -126.19101)
		(end 304.37201 -126.5936)
		(width 0.1651)
		(layer "F.Cu")
		(net "M_E_DQ<54>")
	)
	(segment
		(start 304.202338 -120.636538)
		(end 304.92446 -121.35866)
		(width 0.1651)
		(layer "F.Cu")
		(net "M_E_DQ<54>")
	)
	(segment
		(start 286.31642 -101.243638)
		(end 286.295084 -101.280722)
		(width 0.0889)
		(layer "F.Cu")
		(net "M_E_DQ<54>")
	)
	(segment
		(start 305.33213 -145.95348)
		(end 305.20005 -145.8214)
		(width 0.1651)
		(layer "F.Cu")
		(net "M_E_DQ<54>")
	)
	(segment
		(start 304.92446 -122.83694)
		(end 304.5206 -123.2408)
		(width 0.1651)
		(layer "F.Cu")
		(net "M_E_DQ<54>")
	)
	(segment
		(start 304.5206 -123.2408)
		(end 304.5206 -125.4506)
		(width 0.1651)
		(layer "F.Cu")
		(net "M_E_DQ<54>")
	)
	(segment
		(start 286.394144 -104.114854)
		(end 287.753044 -105.473754)
		(width 0.1016)
		(layer "F.Cu")
		(net "M_E_DQ<54>")
	)
	(segment
		(start 304.92446 -121.35866)
		(end 304.92446 -122.83694)
		(width 0.1651)
		(layer "F.Cu")
		(net "M_E_DQ<54>")
	)
	(segment
		(start 305.33213 -146.17192)
		(end 305.33213 -145.95348)
		(width 0.1651)
		(layer "F.Cu")
		(net "M_E_DQ<54>")
	)
	(segment
		(start 286.30626 -102.252018)
		(end 286.29991 -102.262686)
		(width 0.0889)
		(layer "F.Cu")
		(net "M_E_DQ<54>")
	)
	(segment
		(start 299.668692 -108.762292)
		(end 299.871384 -108.964984)
		(width 0.1016)
		(layer "F.Cu")
		(net "M_E_DQ<54>")
	)
	(segment
		(start 305.20005 -145.8214)
		(end 305.20005 -145.516854)
		(width 0.1651)
		(layer "F.Cu")
		(net "M_E_DQ<54>")
	)
	(segment
		(start 287.753044 -105.473754)
		(end 295.87317 -105.473754)
		(width 0.1016)
		(layer "F.Cu")
		(net "M_E_DQ<54>")
	)
	(segment
		(start 286.394144 -103.014272)
		(end 286.394144 -104.114854)
		(width 0.0889)
		(layer "F.Cu")
		(net "M_E_DQ<54>")
	)
	(segment
		(start 295.87317 -105.473754)
		(end 299.161708 -108.762292)
		(width 0.1016)
		(layer "F.Cu")
		(net "M_E_DQ<54>")
	)
	(segment
		(start 286.29991 -102.262686)
		(end 286.295084 -102.271322)
		(width 0.0889)
		(layer "F.Cu")
		(net "M_E_DQ<54>")
	)
	(segment
		(start 304.5206 -125.4506)
		(end 304.7746 -125.7046)
		(width 0.1651)
		(layer "F.Cu")
		(net "M_E_DQ<54>")
	)
	(segment
		(start 305.20005 -147.27174)
		(end 305.20005 -146.304)
		(width 0.1651)
		(layer "F.Cu")
		(net "M_E_DQ<54>")
	)
	(segment
		(start 304.202338 -113.295938)
		(end 304.202338 -120.636538)
		(width 0.1651)
		(layer "F.Cu")
		(net "M_E_DQ<54>")
	)
	(segment
		(start 299.161708 -108.762292)
		(end 299.668692 -108.762292)
		(width 0.1016)
		(layer "F.Cu")
		(net "M_E_DQ<54>")
	)
	(segment
		(start 305.20005 -146.304)
		(end 305.33213 -146.17192)
		(width 0.1651)
		(layer "F.Cu")
		(net "M_E_DQ<54>")
	)
	(segment
		(start 286.64662 -100.481638)
		(end 286.31642 -101.243638)
		(width 0.0889)
		(layer "F.Cu")
		(net "M_E_DQ<54>")
	)
	(segment
		(start 304.7746 -125.7046)
		(end 304.7746 -126.19101)
		(width 0.1651)
		(layer "F.Cu")
		(net "M_E_DQ<54>")
	)
	(segment
		(start 305.20005 -145.516854)
		(end 305.199796 -145.5166)
		(width 0.1651)
		(layer "F.Cu")
		(net "M_E_DQ<54>")
	)
	(segment
		(start 304.37201 -126.5936)
		(end 304.3174 -126.5936)
		(width 0.1651)
		(layer "F.Cu")
		(net "M_E_DQ<54>")
	)
	(segment
		(start 305.200304 -147.27174)
		(end 305.20005 -147.27174)
		(width 0.1651)
		(layer "F.Cu")
		(net "M_E_DQ<54>")
	)
	(via
		(at 304.3174 -126.5936)
		(size 0.508)
		(drill 0.254)
		(layers "F.Cu" "B.Cu")
		(net "M_E_DQ<54>")
	)
	(via
		(at 305.199796 -145.5166)
		(size 0.508)
		(drill 0.254)
		(layers "F.Cu" "B.Cu")
		(net "M_E_DQ<54>")
	)
	(via
		(at 304.349912 -141.213078)
		(size 0.508)
		(drill 0.254)
		(layers "F.Cu" "B.Cu")
		(net "M_E_DQ<54>")
	)
	(arc
		(start 286.29991 -101.672136)
		(mid 286.379132 -101.961254)
		(end 286.30626 -102.252018)
		(width 0.0889)
		(layer "F.Cu")
		(net "M_E_DQ<54>")
	)
	(arc
		(start 286.295084 -102.271322)
		(mid 286.246329 -102.467674)
		(end 286.29991 -102.662736)
		(width 0.0889)
		(layer "F.Cu")
		(net "M_E_DQ<54>")
	)
	(arc
		(start 286.29991 -102.662736)
		(mid 286.370151 -102.832303)
		(end 286.394144 -103.014272)
		(width 0.0889)
		(layer "F.Cu")
		(net "M_E_DQ<54>")
	)
	(arc
		(start 286.295084 -101.280722)
		(mid 286.246329 -101.477074)
		(end 286.29991 -101.672136)
		(width 0.0889)
		(layer "F.Cu")
		(net "M_E_DQ<54>")
	)
	(segment
		(start 304.349912 -142.476982)
		(end 304.349912 -141.213078)
		(width 0.1651)
		(layer "B.Cu")
		(net "M_E_DQ<54>")
	)
	(segment
		(start 304.35042 -142.477236)
		(end 304.349912 -142.476982)
		(width 0.1651)
		(layer "B.Cu")
		(net "M_E_DQ<54>")
	)
	(segment
		(start 304.866802 -134.128002)
		(end 304.7746 -134.0358)
		(width 0.14224)
		(layer "In4.Cu")
		(net "M_E_DQ<54>")
	)
	(segment
		(start 304.714402 -131.307078)
		(end 304.714402 -130.062478)
		(width 0.14224)
		(layer "In4.Cu")
		(net "M_E_DQ<54>")
	)
	(segment
		(start 304.714402 -130.062478)
		(end 304.917602 -129.859278)
		(width 0.14224)
		(layer "In4.Cu")
		(net "M_E_DQ<54>")
	)
	(segment
		(start 304.181002 -140.070078)
		(end 304.917602 -139.333478)
		(width 0.14224)
		(layer "In4.Cu")
		(net "M_E_DQ<54>")
	)
	(segment
		(start 304.59426 -135.932926)
		(end 304.59426 -134.79018)
		(width 0.14224)
		(layer "In4.Cu")
		(net "M_E_DQ<54>")
	)
	(segment
		(start 304.349912 -126.626112)
		(end 304.3174 -126.5936)
		(width 0.14224)
		(layer "In4.Cu")
		(net "M_E_DQ<54>")
	)
	(segment
		(start 304.866802 -131.459478)
		(end 304.714402 -131.307078)
		(width 0.14224)
		(layer "In4.Cu")
		(net "M_E_DQ<54>")
	)
	(segment
		(start 304.866802 -131.953)
		(end 304.866802 -131.459478)
		(width 0.14224)
		(layer "In4.Cu")
		(net "M_E_DQ<54>")
	)
	(segment
		(start 304.8508 -136.642602)
		(end 304.8508 -136.189466)
		(width 0.14224)
		(layer "In4.Cu")
		(net "M_E_DQ<54>")
	)
	(segment
		(start 304.917602 -128.229614)
		(end 304.349912 -127.661924)
		(width 0.14224)
		(layer "In4.Cu")
		(net "M_E_DQ<54>")
	)
	(segment
		(start 304.866802 -134.517638)
		(end 304.866802 -134.128002)
		(width 0.14224)
		(layer "In4.Cu")
		(net "M_E_DQ<54>")
	)
	(segment
		(start 304.7746 -136.718802)
		(end 304.8508 -136.642602)
		(width 0.14224)
		(layer "In4.Cu")
		(net "M_E_DQ<54>")
	)
	(segment
		(start 304.917602 -129.859278)
		(end 304.917602 -128.229614)
		(width 0.14224)
		(layer "In4.Cu")
		(net "M_E_DQ<54>")
	)
	(segment
		(start 304.181002 -141.044168)
		(end 304.181002 -140.070078)
		(width 0.14224)
		(layer "In4.Cu")
		(net "M_E_DQ<54>")
	)
	(segment
		(start 304.349912 -127.661924)
		(end 304.349912 -126.626112)
		(width 0.14224)
		(layer "In4.Cu")
		(net "M_E_DQ<54>")
	)
	(segment
		(start 304.7746 -134.0358)
		(end 304.7746 -132.045202)
		(width 0.14224)
		(layer "In4.Cu")
		(net "M_E_DQ<54>")
	)
	(segment
		(start 304.7746 -138.8364)
		(end 304.7746 -136.718802)
		(width 0.14224)
		(layer "In4.Cu")
		(net "M_E_DQ<54>")
	)
	(segment
		(start 304.8508 -136.189466)
		(end 304.59426 -135.932926)
		(width 0.14224)
		(layer "In4.Cu")
		(net "M_E_DQ<54>")
	)
	(segment
		(start 304.917602 -138.979402)
		(end 304.7746 -138.8364)
		(width 0.14224)
		(layer "In4.Cu")
		(net "M_E_DQ<54>")
	)
	(segment
		(start 304.7746 -132.045202)
		(end 304.866802 -131.953)
		(width 0.14224)
		(layer "In4.Cu")
		(net "M_E_DQ<54>")
	)
	(segment
		(start 304.917602 -139.333478)
		(end 304.917602 -138.979402)
		(width 0.14224)
		(layer "In4.Cu")
		(net "M_E_DQ<54>")
	)
	(segment
		(start 304.59426 -134.79018)
		(end 304.866802 -134.517638)
		(width 0.14224)
		(layer "In4.Cu")
		(net "M_E_DQ<54>")
	)
	(segment
		(start 304.349912 -141.213078)
		(end 304.181002 -141.044168)
		(width 0.14224)
		(layer "In4.Cu")
		(net "M_E_DQ<54>")
	)
	(segment
		(start 304.349912 -141.213078)
		(end 303.916842 -141.646148)
		(width 0.14224)
		(layer "In9.Cu")
		(net "M_E_DQ<54>")
	)
	(segment
		(start 303.916842 -141.646148)
		(end 303.916842 -144.233646)
		(width 0.14224)
		(layer "In9.Cu")
		(net "M_E_DQ<54>")
	)
	(segment
		(start 303.916842 -144.233646)
		(end 305.199796 -145.5166)
		(width 0.14224)
		(layer "In9.Cu")
		(net "M_E_DQ<54>")
	)
	(segment
		(start 283.384244 -103.34498)
		(end 283.384244 -103.764334)
		(width 0.0889)
		(layer "F.Cu")
		(net "M_E_DQ<53>")
	)
	(segment
		(start 296.461688 -114.674396)
		(end 296.461688 -114.953288)
		(width 0.1651)
		(layer "F.Cu")
		(net "M_E_DQ<53>")
	)
	(segment
		(start 284.000702 -105.8164)
		(end 286.413956 -108.229654)
		(width 0.1016)
		(layer "F.Cu")
		(net "M_E_DQ<53>")
	)
	(segment
		(start 296.461688 -114.953288)
		(end 298.3738 -116.8654)
		(width 0.1651)
		(layer "F.Cu")
		(net "M_E_DQ<53>")
	)
	(segment
		(start 283.72308 -102.765098)
		(end 283.54909 -103.062786)
		(width 0.0889)
		(layer "F.Cu")
		(net "M_E_DQ<53>")
	)
	(segment
		(start 283.845 -105.8164)
		(end 284.000702 -105.8164)
		(width 0.0889)
		(layer "F.Cu")
		(net "M_E_DQ<53>")
	)
	(segment
		(start 295.7068 -114.1984)
		(end 295.985692 -114.1984)
		(width 0.1651)
		(layer "F.Cu")
		(net "M_E_DQ<53>")
	)
	(segment
		(start 295.3258 -113.2078)
		(end 295.3258 -113.8174)
		(width 0.1651)
		(layer "F.Cu")
		(net "M_E_DQ<53>")
	)
	(segment
		(start 283.54909 -103.062786)
		(end 283.384244 -103.34498)
		(width 0.0889)
		(layer "F.Cu")
		(net "M_E_DQ<53>")
	)
	(segment
		(start 298.40047 -142.6718)
		(end 298.399962 -142.677642)
		(width 0.1651)
		(layer "F.Cu")
		(net "M_E_DQ<53>")
	)
	(segment
		(start 299.649896 -124.871226)
		(end 299.160946 -125.360176)
		(width 0.1651)
		(layer "F.Cu")
		(net "M_E_DQ<53>")
	)
	(segment
		(start 299.531278 -123.890278)
		(end 299.649896 -124.008896)
		(width 0.1651)
		(layer "F.Cu")
		(net "M_E_DQ<53>")
	)
	(segment
		(start 296.672 -113.512092)
		(end 296.950892 -113.512092)
		(width 0.1651)
		(layer "F.Cu")
		(net "M_E_DQ<53>")
	)
	(segment
		(start 283.724604 -101.76764)
		(end 283.719778 -101.776276)
		(width 0.0889)
		(layer "F.Cu")
		(net "M_E_DQ<53>")
	)
	(segment
		(start 295.985692 -114.1984)
		(end 296.672 -113.512092)
		(width 0.1651)
		(layer "F.Cu")
		(net "M_E_DQ<53>")
	)
	(segment
		(start 283.6545 -105.6259)
		(end 283.845 -105.8164)
		(width 0.0889)
		(layer "F.Cu")
		(net "M_E_DQ<53>")
	)
	(segment
		(start 297.147996 -113.988088)
		(end 296.461688 -114.674396)
		(width 0.1651)
		(layer "F.Cu")
		(net "M_E_DQ<53>")
	)
	(segment
		(start 286.413956 -108.229654)
		(end 294.729408 -108.229654)
		(width 0.1016)
		(layer "F.Cu")
		(net "M_E_DQ<53>")
	)
	(segment
		(start 294.729408 -108.229654)
		(end 296.6212 -110.121446)
		(width 0.1016)
		(layer "F.Cu")
		(net "M_E_DQ<53>")
	)
	(segment
		(start 296.6212 -111.9124)
		(end 295.3258 -113.2078)
		(width 0.1651)
		(layer "F.Cu")
		(net "M_E_DQ<53>")
	)
	(segment
		(start 299.649896 -124.008896)
		(end 299.649896 -124.871226)
		(width 0.1651)
		(layer "F.Cu")
		(net "M_E_DQ<53>")
	)
	(segment
		(start 299.531278 -119.572278)
		(end 299.531278 -123.890278)
		(width 0.1651)
		(layer "F.Cu")
		(net "M_E_DQ<53>")
	)
	(segment
		(start 296.950892 -113.512092)
		(end 297.147996 -113.709196)
		(width 0.1651)
		(layer "F.Cu")
		(net "M_E_DQ<53>")
	)
	(segment
		(start 283.6545 -104.03459)
		(end 283.6545 -105.6259)
		(width 0.0889)
		(layer "F.Cu")
		(net "M_E_DQ<53>")
	)
	(segment
		(start 297.147996 -113.709196)
		(end 297.147996 -113.988088)
		(width 0.1651)
		(layer "F.Cu")
		(net "M_E_DQ<53>")
	)
	(segment
		(start 296.6212 -111.1631)
		(end 296.6212 -111.9124)
		(width 0.1651)
		(layer "F.Cu")
		(net "M_E_DQ<53>")
	)
	(segment
		(start 298.3738 -116.8654)
		(end 298.3738 -118.4148)
		(width 0.1651)
		(layer "F.Cu")
		(net "M_E_DQ<53>")
	)
	(segment
		(start 295.3258 -113.8174)
		(end 295.7068 -114.1984)
		(width 0.1651)
		(layer "F.Cu")
		(net "M_E_DQ<53>")
	)
	(segment
		(start 283.384244 -103.764334)
		(end 283.6545 -104.03459)
		(width 0.0889)
		(layer "F.Cu")
		(net "M_E_DQ<53>")
	)
	(segment
		(start 296.6212 -110.121446)
		(end 296.6212 -111.1631)
		(width 0.1016)
		(layer "F.Cu")
		(net "M_E_DQ<53>")
	)
	(segment
		(start 298.3738 -118.4148)
		(end 299.531278 -119.572278)
		(width 0.1651)
		(layer "F.Cu")
		(net "M_E_DQ<53>")
	)
	(segment
		(start 298.399962 -142.677642)
		(end 298.399962 -143.941546)
		(width 0.1651)
		(layer "F.Cu")
		(net "M_E_DQ<53>")
	)
	(via
		(at 299.160946 -125.360176)
		(size 0.508)
		(drill 0.254)
		(layers "F.Cu" "B.Cu")
		(net "M_E_DQ<53>")
	)
	(via
		(at 298.399962 -143.941546)
		(size 0.508)
		(drill 0.254)
		(layers "F.Cu" "B.Cu")
		(net "M_E_DQ<53>")
	)
	(via
		(at 299.173646 -139.932156)
		(size 0.508)
		(drill 0.254)
		(layers "F.Cu" "B.Cu")
		(net "M_E_DQ<53>")
	)
	(arc
		(start 283.719778 -101.776276)
		(mid 283.671023 -101.972628)
		(end 283.724604 -102.16769)
		(width 0.0889)
		(layer "F.Cu")
		(net "M_E_DQ<53>")
	)
	(arc
		(start 284.071314 -100.976684)
		(mid 283.917057 -101.380534)
		(end 283.724604 -101.76764)
		(width 0.0889)
		(layer "F.Cu")
		(net "M_E_DQ<53>")
	)
	(arc
		(start 283.724604 -102.16769)
		(mid 283.804341 -102.466605)
		(end 283.72308 -102.765098)
		(width 0.0889)
		(layer "F.Cu")
		(net "M_E_DQ<53>")
	)
	(segment
		(start 299.250354 -137.877296)
		(end 299.249846 -137.877296)
		(width 0.1651)
		(layer "B.Cu")
		(net "M_E_DQ<53>")
	)
	(segment
		(start 299.249846 -139.855956)
		(end 299.173646 -139.932156)
		(width 0.1651)
		(layer "B.Cu")
		(net "M_E_DQ<53>")
	)
	(segment
		(start 299.249846 -137.877296)
		(end 299.249846 -139.855956)
		(width 0.1651)
		(layer "B.Cu")
		(net "M_E_DQ<53>")
	)
	(segment
		(start 299.6692 -134.0104)
		(end 299.583602 -134.095998)
		(width 0.14224)
		(layer "In4.Cu")
		(net "M_E_DQ<53>")
	)
	(segment
		(start 299.6692 -136.635998)
		(end 299.6692 -138.7856)
		(width 0.14224)
		(layer "In4.Cu")
		(net "M_E_DQ<53>")
	)
	(segment
		(start 299.558202 -138.896598)
		(end 299.558202 -139.5476)
		(width 0.14224)
		(layer "In4.Cu")
		(net "M_E_DQ<53>")
	)
	(segment
		(start 299.6692 -131.962398)
		(end 299.6692 -134.0104)
		(width 0.14224)
		(layer "In4.Cu")
		(net "M_E_DQ<53>")
	)
	(segment
		(start 299.710602 -134.797038)
		(end 299.710602 -135.853424)
		(width 0.14224)
		(layer "In4.Cu")
		(net "M_E_DQ<53>")
	)
	(segment
		(start 299.647102 -131.370578)
		(end 299.583602 -131.434078)
		(width 0.14224)
		(layer "In4.Cu")
		(net "M_E_DQ<53>")
	)
	(segment
		(start 299.558202 -129.906014)
		(end 299.647102 -129.994914)
		(width 0.14224)
		(layer "In4.Cu")
		(net "M_E_DQ<53>")
	)
	(segment
		(start 299.583602 -134.095998)
		(end 299.583602 -134.670038)
		(width 0.14224)
		(layer "In4.Cu")
		(net "M_E_DQ<53>")
	)
	(segment
		(start 299.558202 -136.005824)
		(end 299.558202 -136.525)
		(width 0.14224)
		(layer "In4.Cu")
		(net "M_E_DQ<53>")
	)
	(segment
		(start 299.583602 -131.8768)
		(end 299.6692 -131.962398)
		(width 0.14224)
		(layer "In4.Cu")
		(net "M_E_DQ<53>")
	)
	(segment
		(start 299.160946 -125.360176)
		(end 299.160946 -128.136904)
		(width 0.14224)
		(layer "In4.Cu")
		(net "M_E_DQ<53>")
	)
	(segment
		(start 299.558202 -136.525)
		(end 299.6692 -136.635998)
		(width 0.14224)
		(layer "In4.Cu")
		(net "M_E_DQ<53>")
	)
	(segment
		(start 299.558202 -128.53416)
		(end 299.558202 -129.906014)
		(width 0.14224)
		(layer "In4.Cu")
		(net "M_E_DQ<53>")
	)
	(segment
		(start 299.583602 -131.434078)
		(end 299.583602 -131.8768)
		(width 0.14224)
		(layer "In4.Cu")
		(net "M_E_DQ<53>")
	)
	(segment
		(start 299.647102 -129.994914)
		(end 299.647102 -131.370578)
		(width 0.14224)
		(layer "In4.Cu")
		(net "M_E_DQ<53>")
	)
	(segment
		(start 299.710602 -135.853424)
		(end 299.558202 -136.005824)
		(width 0.14224)
		(layer "In4.Cu")
		(net "M_E_DQ<53>")
	)
	(segment
		(start 299.160946 -128.136904)
		(end 299.558202 -128.53416)
		(width 0.14224)
		(layer "In4.Cu")
		(net "M_E_DQ<53>")
	)
	(segment
		(start 299.583602 -134.670038)
		(end 299.710602 -134.797038)
		(width 0.14224)
		(layer "In4.Cu")
		(net "M_E_DQ<53>")
	)
	(segment
		(start 299.558202 -139.5476)
		(end 299.173646 -139.932156)
		(width 0.14224)
		(layer "In4.Cu")
		(net "M_E_DQ<53>")
	)
	(segment
		(start 299.6692 -138.7856)
		(end 299.558202 -138.896598)
		(width 0.14224)
		(layer "In4.Cu")
		(net "M_E_DQ<53>")
	)
	(segment
		(start 298.85005 -141.528546)
		(end 298.85005 -141.0462)
		(width 0.14224)
		(layer "In9.Cu")
		(net "M_E_DQ<53>")
	)
	(segment
		(start 298.561252 -142.985744)
		(end 298.79925 -142.747746)
		(width 0.14224)
		(layer "In9.Cu")
		(net "M_E_DQ<53>")
	)
	(segment
		(start 298.79925 -142.747746)
		(end 298.79925 -142.392654)
		(width 0.14224)
		(layer "In9.Cu")
		(net "M_E_DQ<53>")
	)
	(segment
		(start 298.67225 -143.941546)
		(end 298.82465 -143.789146)
		(width 0.14224)
		(layer "In9.Cu")
		(net "M_E_DQ<53>")
	)
	(segment
		(start 298.82465 -143.789146)
		(end 298.82465 -143.561054)
		(width 0.14224)
		(layer "In9.Cu")
		(net "M_E_DQ<53>")
	)
	(segment
		(start 298.561252 -141.817344)
		(end 298.85005 -141.528546)
		(width 0.14224)
		(layer "In9.Cu")
		(net "M_E_DQ<53>")
	)
	(segment
		(start 298.399962 -143.941546)
		(end 298.67225 -143.941546)
		(width 0.14224)
		(layer "In9.Cu")
		(net "M_E_DQ<53>")
	)
	(segment
		(start 298.561252 -142.154656)
		(end 298.561252 -141.817344)
		(width 0.14224)
		(layer "In9.Cu")
		(net "M_E_DQ<53>")
	)
	(segment
		(start 298.72305 -140.9192)
		(end 298.72305 -140.3604)
		(width 0.14224)
		(layer "In9.Cu")
		(net "M_E_DQ<53>")
	)
	(segment
		(start 298.79925 -142.392654)
		(end 298.561252 -142.154656)
		(width 0.14224)
		(layer "In9.Cu")
		(net "M_E_DQ<53>")
	)
	(segment
		(start 298.72305 -140.3604)
		(end 299.151294 -139.932156)
		(width 0.14224)
		(layer "In9.Cu")
		(net "M_E_DQ<53>")
	)
	(segment
		(start 298.85005 -141.0462)
		(end 298.72305 -140.9192)
		(width 0.14224)
		(layer "In9.Cu")
		(net "M_E_DQ<53>")
	)
	(segment
		(start 299.151294 -139.932156)
		(end 299.173646 -139.932156)
		(width 0.14224)
		(layer "In9.Cu")
		(net "M_E_DQ<53>")
	)
	(segment
		(start 298.82465 -143.561054)
		(end 298.561252 -143.297656)
		(width 0.14224)
		(layer "In9.Cu")
		(net "M_E_DQ<53>")
	)
	(segment
		(start 298.561252 -143.297656)
		(end 298.561252 -142.985744)
		(width 0.14224)
		(layer "In9.Cu")
		(net "M_E_DQ<53>")
	)
	(segment
		(start 283.1846 -103.860346)
		(end 283.464 -104.139746)
		(width 0.0889)
		(layer "F.Cu")
		(net "M_E_DQ<52>")
	)
	(segment
		(start 294.513 -113.919)
		(end 297.688 -117.094)
		(width 0.1651)
		(layer "F.Cu")
		(net "M_E_DQ<52>")
	)
	(segment
		(start 295.9608 -111.3028)
		(end 295.9608 -111.6076)
		(width 0.1651)
		(layer "F.Cu")
		(net "M_E_DQ<52>")
	)
	(segment
		(start 295.9608 -110.018068)
		(end 295.9608 -111.3028)
		(width 0.1016)
		(layer "F.Cu")
		(net "M_E_DQ<52>")
	)
	(segment
		(start 295.9608 -111.6076)
		(end 294.513 -113.0554)
		(width 0.1651)
		(layer "F.Cu")
		(net "M_E_DQ<52>")
	)
	(segment
		(start 283.6672 -105.918)
		(end 283.6672 -106.03992)
		(width 0.0889)
		(layer "F.Cu")
		(net "M_E_DQ<52>")
	)
	(segment
		(start 299.249846 -147.27174)
		(end 299.250354 -147.27174)
		(width 0.1651)
		(layer "F.Cu")
		(net "M_E_DQ<52>")
	)
	(segment
		(start 283.464 -105.7148)
		(end 283.6672 -105.918)
		(width 0.0889)
		(layer "F.Cu")
		(net "M_E_DQ<52>")
	)
	(segment
		(start 283.464 -104.139746)
		(end 283.464 -105.7148)
		(width 0.0889)
		(layer "F.Cu")
		(net "M_E_DQ<52>")
	)
	(segment
		(start 294.513 -113.0554)
		(end 294.513 -113.919)
		(width 0.1651)
		(layer "F.Cu")
		(net "M_E_DQ<52>")
	)
	(segment
		(start 283.6672 -106.03992)
		(end 286.250634 -108.623354)
		(width 0.1016)
		(layer "F.Cu")
		(net "M_E_DQ<52>")
	)
	(segment
		(start 298.8056 -124.333)
		(end 298.704 -124.4346)
		(width 0.1651)
		(layer "F.Cu")
		(net "M_E_DQ<52>")
	)
	(segment
		(start 298.8056 -119.862346)
		(end 298.8056 -124.333)
		(width 0.1651)
		(layer "F.Cu")
		(net "M_E_DQ<52>")
	)
	(segment
		(start 283.1846 -103.308912)
		(end 283.1846 -103.860346)
		(width 0.0889)
		(layer "F.Cu")
		(net "M_E_DQ<52>")
	)
	(segment
		(start 298.704 -124.4346)
		(end 298.704 -126.13386)
		(width 0.1651)
		(layer "F.Cu")
		(net "M_E_DQ<52>")
	)
	(segment
		(start 297.688 -118.744746)
		(end 298.8056 -119.862346)
		(width 0.1651)
		(layer "F.Cu")
		(net "M_E_DQ<52>")
	)
	(segment
		(start 294.566086 -108.623354)
		(end 295.9608 -110.018068)
		(width 0.1016)
		(layer "F.Cu")
		(net "M_E_DQ<52>")
	)
	(segment
		(start 286.250634 -108.623354)
		(end 294.566086 -108.623354)
		(width 0.1016)
		(layer "F.Cu")
		(net "M_E_DQ<52>")
	)
	(segment
		(start 283.32811 -103.062786)
		(end 283.1846 -103.308912)
		(width 0.0889)
		(layer "F.Cu")
		(net "M_E_DQ<52>")
	)
	(segment
		(start 299.249846 -145.946368)
		(end 299.249846 -147.27174)
		(width 0.1651)
		(layer "F.Cu")
		(net "M_E_DQ<52>")
	)
	(segment
		(start 298.704 -126.13386)
		(end 298.247562 -126.590298)
		(width 0.1651)
		(layer "F.Cu")
		(net "M_E_DQ<52>")
	)
	(segment
		(start 299.151802 -145.415)
		(end 299.249846 -145.946368)
		(width 0.1651)
		(layer "F.Cu")
		(net "M_E_DQ<52>")
	)
	(segment
		(start 283.558488 -102.667816)
		(end 283.32811 -103.062786)
		(width 0.0889)
		(layer "F.Cu")
		(net "M_E_DQ<52>")
	)
	(segment
		(start 297.688 -117.094)
		(end 297.688 -118.744746)
		(width 0.1651)
		(layer "F.Cu")
		(net "M_E_DQ<52>")
	)
	(via
		(at 299.151802 -145.415)
		(size 0.508)
		(drill 0.254)
		(layers "F.Cu" "B.Cu")
		(net "M_E_DQ<52>")
	)
	(via
		(at 298.247562 -126.590298)
		(size 0.508)
		(drill 0.254)
		(layers "F.Cu" "B.Cu")
		(net "M_E_DQ<52>")
	)
	(via
		(at 298.399962 -141.213078)
		(size 0.508)
		(drill 0.254)
		(layers "F.Cu" "B.Cu")
		(net "M_E_DQ<52>")
	)
	(arc
		(start 283.687774 -100.862638)
		(mid 283.673718 -100.931665)
		(end 283.672026 -101.002084)
		(width 0.0889)
		(layer "F.Cu")
		(net "M_E_DQ<52>")
	)
	(arc
		(start 284.060138 -100.576634)
		(mid 283.866288 -100.632984)
		(end 283.724604 -100.776786)
		(width 0.0889)
		(layer "F.Cu")
		(net "M_E_DQ<52>")
	)
	(arc
		(start 283.559504 -101.672136)
		(mid 283.480373 -101.967538)
		(end 283.559504 -102.26294)
		(width 0.0889)
		(layer "F.Cu")
		(net "M_E_DQ<52>")
	)
	(arc
		(start 283.672026 -101.002084)
		(mid 283.65447 -101.343612)
		(end 283.559504 -101.672136)
		(width 0.0889)
		(layer "F.Cu")
		(net "M_E_DQ<52>")
	)
	(arc
		(start 284.929834 -100.481638)
		(mid 284.496907 -100.546721)
		(end 284.060138 -100.576634)
		(width 0.0889)
		(layer "F.Cu")
		(net "M_E_DQ<52>")
	)
	(arc
		(start 283.559504 -102.26294)
		(mid 283.613482 -102.46553)
		(end 283.558488 -102.667816)
		(width 0.0889)
		(layer "F.Cu")
		(net "M_E_DQ<52>")
	)
	(arc
		(start 283.724604 -100.776786)
		(mid 283.703654 -100.818625)
		(end 283.687774 -100.862638)
		(width 0.0889)
		(layer "F.Cu")
		(net "M_E_DQ<52>")
	)
	(segment
		(start 298.399962 -142.476982)
		(end 298.399962 -141.213078)
		(width 0.1651)
		(layer "B.Cu")
		(net "M_E_DQ<52>")
	)
	(segment
		(start 298.40047 -142.477236)
		(end 298.399962 -142.476982)
		(width 0.1651)
		(layer "B.Cu")
		(net "M_E_DQ<52>")
	)
	(segment
		(start 298.897802 -131.421378)
		(end 298.669202 -131.192778)
		(width 0.14224)
		(layer "In4.Cu")
		(net "M_E_DQ<52>")
	)
	(segment
		(start 298.669202 -129.986278)
		(end 298.923202 -129.732278)
		(width 0.14224)
		(layer "In4.Cu")
		(net "M_E_DQ<52>")
	)
	(segment
		(start 298.831 -132.019802)
		(end 298.897802 -131.953)
		(width 0.14224)
		(layer "In4.Cu")
		(net "M_E_DQ<52>")
	)
	(segment
		(start 298.885102 -139.042902)
		(end 298.831 -138.9888)
		(width 0.14224)
		(layer "In4.Cu")
		(net "M_E_DQ<52>")
	)
	(segment
		(start 298.669202 -131.192778)
		(end 298.669202 -129.986278)
		(width 0.14224)
		(layer "In4.Cu")
		(net "M_E_DQ<52>")
	)
	(segment
		(start 298.3738 -139.87018)
		(end 298.885102 -139.358878)
		(width 0.1016)
		(layer "In4.Cu")
		(net "M_E_DQ<52>")
	)
	(segment
		(start 298.831 -136.655302)
		(end 298.885102 -136.6012)
		(width 0.14224)
		(layer "In4.Cu")
		(net "M_E_DQ<52>")
	)
	(segment
		(start 298.923202 -129.732278)
		(end 298.923202 -129.093214)
		(width 0.14224)
		(layer "In4.Cu")
		(net "M_E_DQ<52>")
	)
	(segment
		(start 298.831 -134.0612)
		(end 298.831 -132.019802)
		(width 0.14224)
		(layer "In4.Cu")
		(net "M_E_DQ<52>")
	)
	(segment
		(start 298.885102 -136.6012)
		(end 298.885102 -136.180068)
		(width 0.14224)
		(layer "In4.Cu")
		(net "M_E_DQ<52>")
	)
	(segment
		(start 298.831 -138.9888)
		(end 298.831 -136.655302)
		(width 0.14224)
		(layer "In4.Cu")
		(net "M_E_DQ<52>")
	)
	(segment
		(start 298.897802 -134.476998)
		(end 298.897802 -134.128002)
		(width 0.14224)
		(layer "In4.Cu")
		(net "M_E_DQ<52>")
	)
	(segment
		(start 298.63161 -135.926576)
		(end 298.63161 -134.74319)
		(width 0.14224)
		(layer "In4.Cu")
		(net "M_E_DQ<52>")
	)
	(segment
		(start 298.897802 -134.128002)
		(end 298.831 -134.0612)
		(width 0.14224)
		(layer "In4.Cu")
		(net "M_E_DQ<52>")
	)
	(segment
		(start 298.63161 -134.74319)
		(end 298.897802 -134.476998)
		(width 0.14224)
		(layer "In4.Cu")
		(net "M_E_DQ<52>")
	)
	(segment
		(start 298.885102 -136.180068)
		(end 298.63161 -135.926576)
		(width 0.14224)
		(layer "In4.Cu")
		(net "M_E_DQ<52>")
	)
	(segment
		(start 298.3484 -126.691136)
		(end 298.247562 -126.590298)
		(width 0.14224)
		(layer "In4.Cu")
		(net "M_E_DQ<52>")
	)
	(segment
		(start 298.3738 -141.186916)
		(end 298.3738 -139.87018)
		(width 0.1016)
		(layer "In4.Cu")
		(net "M_E_DQ<52>")
	)
	(segment
		(start 298.923202 -129.093214)
		(end 298.3484 -128.518412)
		(width 0.14224)
		(layer "In4.Cu")
		(net "M_E_DQ<52>")
	)
	(segment
		(start 298.885102 -139.358878)
		(end 298.885102 -139.042902)
		(width 0.14224)
		(layer "In4.Cu")
		(net "M_E_DQ<52>")
	)
	(segment
		(start 298.399962 -141.213078)
		(end 298.3738 -141.186916)
		(width 0.1016)
		(layer "In4.Cu")
		(net "M_E_DQ<52>")
	)
	(segment
		(start 298.897802 -131.953)
		(end 298.897802 -131.421378)
		(width 0.14224)
		(layer "In4.Cu")
		(net "M_E_DQ<52>")
	)
	(segment
		(start 298.3484 -128.518412)
		(end 298.3484 -126.691136)
		(width 0.14224)
		(layer "In4.Cu")
		(net "M_E_DQ<52>")
	)
	(segment
		(start 298.399962 -141.213078)
		(end 297.966892 -141.646148)
		(width 0.14224)
		(layer "In9.Cu")
		(net "M_E_DQ<52>")
	)
	(segment
		(start 297.966892 -144.17929)
		(end 298.12488 -144.337278)
		(width 0.14224)
		(layer "In9.Cu")
		(net "M_E_DQ<52>")
	)
	(segment
		(start 298.90085 -145.415)
		(end 299.151802 -145.415)
		(width 0.14224)
		(layer "In9.Cu")
		(net "M_E_DQ<52>")
	)
	(segment
		(start 298.12488 -144.63903)
		(end 298.90085 -145.415)
		(width 0.14224)
		(layer "In9.Cu")
		(net "M_E_DQ<52>")
	)
	(segment
		(start 298.12488 -144.337278)
		(end 298.12488 -144.63903)
		(width 0.14224)
		(layer "In9.Cu")
		(net "M_E_DQ<52>")
	)
	(segment
		(start 297.966892 -141.646148)
		(end 297.966892 -144.17929)
		(width 0.14224)
		(layer "In9.Cu")
		(net "M_E_DQ<52>")
	)
	(segment
		(start 306.050442 -142.6718)
		(end 306.049934 -142.677642)
		(width 0.1651)
		(layer "F.Cu")
		(net "M_E_DQ<51>")
	)
	(segment
		(start 307.45303 -119.793258)
		(end 307.45303 -124.223272)
		(width 0.1651)
		(layer "F.Cu")
		(net "M_E_DQ<51>")
	)
	(segment
		(start 287.15843 -102.757986)
		(end 287.15843 -102.781608)
		(width 0.0889)
		(layer "F.Cu")
		(net "M_E_DQ<51>")
	)
	(segment
		(start 307.45303 -124.223272)
		(end 307.887116 -124.657358)
		(width 0.1651)
		(layer "F.Cu")
		(net "M_E_DQ<51>")
	)
	(segment
		(start 307.887116 -125.546358)
		(end 307.412898 -126.020576)
		(width 0.1651)
		(layer "F.Cu")
		(net "M_E_DQ<51>")
	)
	(segment
		(start 306.226972 -118.5672)
		(end 307.45303 -119.793258)
		(width 0.1651)
		(layer "F.Cu")
		(net "M_E_DQ<51>")
	)
	(segment
		(start 307.887116 -124.657358)
		(end 307.887116 -125.546358)
		(width 0.1651)
		(layer "F.Cu")
		(net "M_E_DQ<51>")
	)
	(segment
		(start 287.15843 -102.167436)
		(end 287.16478 -102.178104)
		(width 0.0889)
		(layer "F.Cu")
		(net "M_E_DQ<51>")
	)
	(segment
		(start 307.412898 -126.020576)
		(end 306.899818 -126.020576)
		(width 0.1651)
		(layer "F.Cu")
		(net "M_E_DQ<51>")
	)
	(segment
		(start 301.5996 -107.5182)
		(end 301.752 -107.6706)
		(width 0.1016)
		(layer "F.Cu")
		(net "M_E_DQ<51>")
	)
	(segment
		(start 301.752 -107.6706)
		(end 302.514 -107.6706)
		(width 0.1651)
		(layer "F.Cu")
		(net "M_E_DQ<51>")
	)
	(segment
		(start 302.514 -107.6706)
		(end 306.226972 -111.383572)
		(width 0.1651)
		(layer "F.Cu")
		(net "M_E_DQ<51>")
	)
	(segment
		(start 287.15843 -102.781608)
		(end 287.110424 -102.829614)
		(width 0.0889)
		(layer "F.Cu")
		(net "M_E_DQ<51>")
	)
	(segment
		(start 296.363136 -104.292654)
		(end 299.588682 -107.5182)
		(width 0.1016)
		(layer "F.Cu")
		(net "M_E_DQ<51>")
	)
	(segment
		(start 287.50514 -101.635814)
		(end 287.44164 -101.572314)
		(width 0.0889)
		(layer "F.Cu")
		(net "M_E_DQ<51>")
	)
	(segment
		(start 287.153604 -102.1588)
		(end 287.15843 -102.167436)
		(width 0.0889)
		(layer "F.Cu")
		(net "M_E_DQ<51>")
	)
	(segment
		(start 287.110424 -103.159814)
		(end 288.243264 -104.292654)
		(width 0.1016)
		(layer "F.Cu")
		(net "M_E_DQ<51>")
	)
	(segment
		(start 306.049934 -142.677642)
		(end 306.049934 -143.941546)
		(width 0.1651)
		(layer "F.Cu")
		(net "M_E_DQ<51>")
	)
	(segment
		(start 288.243264 -104.292654)
		(end 296.363136 -104.292654)
		(width 0.1016)
		(layer "F.Cu")
		(net "M_E_DQ<51>")
	)
	(segment
		(start 287.50514 -101.967538)
		(end 287.50514 -101.635814)
		(width 0.0889)
		(layer "F.Cu")
		(net "M_E_DQ<51>")
	)
	(segment
		(start 306.226972 -111.383572)
		(end 306.226972 -118.5672)
		(width 0.1651)
		(layer "F.Cu")
		(net "M_E_DQ<51>")
	)
	(segment
		(start 299.588682 -107.5182)
		(end 301.5996 -107.5182)
		(width 0.1016)
		(layer "F.Cu")
		(net "M_E_DQ<51>")
	)
	(segment
		(start 287.110424 -102.829614)
		(end 287.110424 -103.159814)
		(width 0.0889)
		(layer "F.Cu")
		(net "M_E_DQ<51>")
	)
	(via
		(at 306.049934 -143.941546)
		(size 0.508)
		(drill 0.254)
		(layers "F.Cu" "B.Cu")
		(net "M_E_DQ<51>")
	)
	(via
		(at 306.899818 -126.020576)
		(size 0.508)
		(drill 0.254)
		(layers "F.Cu" "B.Cu")
		(net "M_E_DQ<51>")
	)
	(via
		(at 306.899818 -139.932156)
		(size 0.508)
		(drill 0.254)
		(layers "F.Cu" "B.Cu")
		(net "M_E_DQ<51>")
	)
	(arc
		(start 287.16478 -102.178104)
		(mid 287.237578 -102.468867)
		(end 287.15843 -102.757986)
		(width 0.0889)
		(layer "F.Cu")
		(net "M_E_DQ<51>")
	)
	(arc
		(start 287.44164 -101.572314)
		(mid 287.145855 -101.791048)
		(end 287.153604 -102.1588)
		(width 0.0889)
		(layer "F.Cu")
		(net "M_E_DQ<51>")
	)
	(segment
		(start 306.899818 -137.877296)
		(end 306.899818 -139.932156)
		(width 0.1651)
		(layer "B.Cu")
		(net "M_E_DQ<51>")
	)
	(segment
		(start 306.900326 -137.877296)
		(end 306.899818 -137.877296)
		(width 0.1651)
		(layer "B.Cu")
		(net "M_E_DQ<51>")
	)
	(segment
		(start 307.229002 -138.744198)
		(end 307.229002 -139.61618)
		(width 0.14224)
		(layer "In4.Cu")
		(net "M_E_DQ<51>")
	)
	(segment
		(start 307.34 -134.0104)
		(end 307.267102 -134.083298)
		(width 0.14224)
		(layer "In4.Cu")
		(net "M_E_DQ<51>")
	)
	(segment
		(start 307.406802 -130.113278)
		(end 307.406802 -131.268978)
		(width 0.14224)
		(layer "In4.Cu")
		(net "M_E_DQ<51>")
	)
	(segment
		(start 307.254402 -126.37516)
		(end 307.254402 -129.960878)
		(width 0.14224)
		(layer "In4.Cu")
		(net "M_E_DQ<51>")
	)
	(segment
		(start 307.229002 -136.229852)
		(end 307.229002 -136.5504)
		(width 0.14224)
		(layer "In4.Cu")
		(net "M_E_DQ<51>")
	)
	(segment
		(start 307.483002 -135.975852)
		(end 307.229002 -136.229852)
		(width 0.14224)
		(layer "In4.Cu")
		(net "M_E_DQ<51>")
	)
	(segment
		(start 307.229002 -139.61618)
		(end 306.899818 -139.945364)
		(width 0.14224)
		(layer "In4.Cu")
		(net "M_E_DQ<51>")
	)
	(segment
		(start 307.229002 -136.5504)
		(end 307.3146 -136.635998)
		(width 0.14224)
		(layer "In4.Cu")
		(net "M_E_DQ<51>")
	)
	(segment
		(start 307.406802 -131.268978)
		(end 307.267102 -131.408678)
		(width 0.14224)
		(layer "In4.Cu")
		(net "M_E_DQ<51>")
	)
	(segment
		(start 307.267102 -131.408678)
		(end 307.267102 -132.0292)
		(width 0.14224)
		(layer "In4.Cu")
		(net "M_E_DQ<51>")
	)
	(segment
		(start 306.899818 -126.020576)
		(end 307.254402 -126.37516)
		(width 0.14224)
		(layer "In4.Cu")
		(net "M_E_DQ<51>")
	)
	(segment
		(start 307.3146 -138.6586)
		(end 307.229002 -138.744198)
		(width 0.14224)
		(layer "In4.Cu")
		(net "M_E_DQ<51>")
	)
	(segment
		(start 307.34 -132.102098)
		(end 307.34 -134.0104)
		(width 0.14224)
		(layer "In4.Cu")
		(net "M_E_DQ<51>")
	)
	(segment
		(start 307.267102 -134.581138)
		(end 307.483002 -134.797038)
		(width 0.14224)
		(layer "In4.Cu")
		(net "M_E_DQ<51>")
	)
	(segment
		(start 307.267102 -134.083298)
		(end 307.267102 -134.581138)
		(width 0.14224)
		(layer "In4.Cu")
		(net "M_E_DQ<51>")
	)
	(segment
		(start 307.483002 -134.797038)
		(end 307.483002 -135.975852)
		(width 0.14224)
		(layer "In4.Cu")
		(net "M_E_DQ<51>")
	)
	(segment
		(start 307.267102 -132.0292)
		(end 307.34 -132.102098)
		(width 0.14224)
		(layer "In4.Cu")
		(net "M_E_DQ<51>")
	)
	(segment
		(start 307.254402 -129.960878)
		(end 307.406802 -130.113278)
		(width 0.14224)
		(layer "In4.Cu")
		(net "M_E_DQ<51>")
	)
	(segment
		(start 307.3146 -136.635998)
		(end 307.3146 -138.6586)
		(width 0.14224)
		(layer "In4.Cu")
		(net "M_E_DQ<51>")
	)
	(segment
		(start 306.899818 -139.945364)
		(end 306.899818 -139.932156)
		(width 0.14224)
		(layer "In4.Cu")
		(net "M_E_DQ<51>")
	)
	(segment
		(start 306.049934 -143.941546)
		(end 306.322222 -143.941546)
		(width 0.14224)
		(layer "In9.Cu")
		(net "M_E_DQ<51>")
	)
	(segment
		(start 306.500022 -143.763746)
		(end 306.500022 -143.44015)
		(width 0.14224)
		(layer "In9.Cu")
		(net "M_E_DQ<51>")
	)
	(segment
		(start 306.449222 -140.790168)
		(end 306.449222 -140.3604)
		(width 0.14224)
		(layer "In9.Cu")
		(net "M_E_DQ<51>")
	)
	(segment
		(start 306.449222 -140.3604)
		(end 306.877466 -139.932156)
		(width 0.14224)
		(layer "In9.Cu")
		(net "M_E_DQ<51>")
	)
	(segment
		(start 306.493672 -141.5034)
		(end 306.493672 -140.834618)
		(width 0.14224)
		(layer "In9.Cu")
		(net "M_E_DQ<51>")
	)
	(segment
		(start 306.211224 -142.059152)
		(end 306.211224 -141.785848)
		(width 0.14224)
		(layer "In9.Cu")
		(net "M_E_DQ<51>")
	)
	(segment
		(start 306.211224 -141.785848)
		(end 306.493672 -141.5034)
		(width 0.14224)
		(layer "In9.Cu")
		(net "M_E_DQ<51>")
	)
	(segment
		(start 306.468272 -142.3162)
		(end 306.211224 -142.059152)
		(width 0.14224)
		(layer "In9.Cu")
		(net "M_E_DQ<51>")
	)
	(segment
		(start 306.500022 -143.44015)
		(end 306.211224 -143.151352)
		(width 0.14224)
		(layer "In9.Cu")
		(net "M_E_DQ<51>")
	)
	(segment
		(start 306.493672 -140.834618)
		(end 306.449222 -140.790168)
		(width 0.14224)
		(layer "In9.Cu")
		(net "M_E_DQ<51>")
	)
	(segment
		(start 306.877466 -139.932156)
		(end 306.899818 -139.932156)
		(width 0.14224)
		(layer "In9.Cu")
		(net "M_E_DQ<51>")
	)
	(segment
		(start 306.211224 -143.151352)
		(end 306.211224 -142.878048)
		(width 0.14224)
		(layer "In9.Cu")
		(net "M_E_DQ<51>")
	)
	(segment
		(start 306.211224 -142.878048)
		(end 306.468272 -142.621)
		(width 0.14224)
		(layer "In9.Cu")
		(net "M_E_DQ<51>")
	)
	(segment
		(start 306.322222 -143.941546)
		(end 306.500022 -143.763746)
		(width 0.14224)
		(layer "In9.Cu")
		(net "M_E_DQ<51>")
	)
	(segment
		(start 306.468272 -142.621)
		(end 306.468272 -142.3162)
		(width 0.14224)
		(layer "In9.Cu")
		(net "M_E_DQ<51>")
	)
	(segment
		(start 305.552094 -118.912894)
		(end 306.778152 -120.138952)
		(width 0.1651)
		(layer "F.Cu")
		(net "M_E_DQ<50>")
	)
	(segment
		(start 307.03139 -146.14906)
		(end 307.03139 -145.92554)
		(width 0.1651)
		(layer "F.Cu")
		(net "M_E_DQ<50>")
	)
	(segment
		(start 301.0281 -107.9119)
		(end 299.42536 -107.9119)
		(width 0.1016)
		(layer "F.Cu")
		(net "M_E_DQ<50>")
	)
	(segment
		(start 306.899818 -146.280632)
		(end 307.03139 -146.14906)
		(width 0.1651)
		(layer "F.Cu")
		(net "M_E_DQ<50>")
	)
	(segment
		(start 305.552094 -118.109238)
		(end 305.552094 -112.131094)
		(width 0.1651)
		(layer "F.Cu")
		(net "M_E_DQ<50>")
	)
	(segment
		(start 288.079688 -104.686354)
		(end 286.907224 -103.51389)
		(width 0.1016)
		(layer "F.Cu")
		(net "M_E_DQ<50>")
	)
	(segment
		(start 301.4853 -108.3691)
		(end 301.0281 -107.9119)
		(width 0.1016)
		(layer "F.Cu")
		(net "M_E_DQ<50>")
	)
	(segment
		(start 286.998156 -102.271322)
		(end 286.99333 -102.262686)
		(width 0.0889)
		(layer "F.Cu")
		(net "M_E_DQ<50>")
	)
	(segment
		(start 305.552094 -118.109238)
		(end 305.552094 -118.912894)
		(width 0.1651)
		(layer "F.Cu")
		(net "M_E_DQ<50>")
	)
	(segment
		(start 306.899818 -145.793968)
		(end 306.899818 -145.5166)
		(width 0.1651)
		(layer "F.Cu")
		(net "M_E_DQ<50>")
	)
	(segment
		(start 301.7901 -108.3691)
		(end 301.4853 -108.3691)
		(width 0.1651)
		(layer "F.Cu")
		(net "M_E_DQ<50>")
	)
	(segment
		(start 306.778152 -124.723652)
		(end 306.4256 -125.076204)
		(width 0.1651)
		(layer "F.Cu")
		(net "M_E_DQ<50>")
	)
	(segment
		(start 307.03139 -145.92554)
		(end 306.899818 -145.793968)
		(width 0.1651)
		(layer "F.Cu")
		(net "M_E_DQ<50>")
	)
	(segment
		(start 286.99333 -102.262686)
		(end 286.98698 -102.252018)
		(width 0.0889)
		(layer "F.Cu")
		(net "M_E_DQ<50>")
	)
	(segment
		(start 306.900326 -147.27174)
		(end 306.899818 -147.27174)
		(width 0.1651)
		(layer "F.Cu")
		(net "M_E_DQ<50>")
	)
	(segment
		(start 305.552094 -112.131094)
		(end 301.7901 -108.3691)
		(width 0.1651)
		(layer "F.Cu")
		(net "M_E_DQ<50>")
	)
	(segment
		(start 306.4256 -126.138432)
		(end 305.948334 -126.615698)
		(width 0.1651)
		(layer "F.Cu")
		(net "M_E_DQ<50>")
	)
	(segment
		(start 306.4256 -125.076204)
		(end 306.4256 -126.138432)
		(width 0.1651)
		(layer "F.Cu")
		(net "M_E_DQ<50>")
	)
	(segment
		(start 286.907224 -102.748842)
		(end 286.99333 -102.662736)
		(width 0.0889)
		(layer "F.Cu")
		(net "M_E_DQ<50>")
	)
	(segment
		(start 296.199814 -104.686354)
		(end 288.079688 -104.686354)
		(width 0.1016)
		(layer "F.Cu")
		(net "M_E_DQ<50>")
	)
	(segment
		(start 287.50514 -101.308408)
		(end 287.50514 -100.976684)
		(width 0.0889)
		(layer "F.Cu")
		(net "M_E_DQ<50>")
	)
	(segment
		(start 306.778152 -120.138952)
		(end 306.778152 -124.723652)
		(width 0.1651)
		(layer "F.Cu")
		(net "M_E_DQ<50>")
	)
	(segment
		(start 287.432496 -101.381052)
		(end 287.50514 -101.308408)
		(width 0.0889)
		(layer "F.Cu")
		(net "M_E_DQ<50>")
	)
	(segment
		(start 299.42536 -107.9119)
		(end 296.199814 -104.686354)
		(width 0.1016)
		(layer "F.Cu")
		(net "M_E_DQ<50>")
	)
	(segment
		(start 286.907224 -103.51389)
		(end 286.907224 -102.748842)
		(width 0.0889)
		(layer "F.Cu")
		(net "M_E_DQ<50>")
	)
	(segment
		(start 305.948334 -126.615698)
		(end 305.9176 -126.615698)
		(width 0.1651)
		(layer "F.Cu")
		(net "M_E_DQ<50>")
	)
	(segment
		(start 306.899818 -147.27174)
		(end 306.899818 -146.280632)
		(width 0.1651)
		(layer "F.Cu")
		(net "M_E_DQ<50>")
	)
	(via
		(at 306.049934 -141.213078)
		(size 0.508)
		(drill 0.254)
		(layers "F.Cu" "B.Cu")
		(net "M_E_DQ<50>")
	)
	(via
		(at 305.9176 -126.615698)
		(size 0.508)
		(drill 0.254)
		(layers "F.Cu" "B.Cu")
		(net "M_E_DQ<50>")
	)
	(via
		(at 305.552094 -118.109238)
		(size 0.508)
		(drill 0.254)
		(layers "F.Cu" "B.Cu")
		(net "M_E_DQ<50>")
	)
	(via
		(at 306.899818 -145.5166)
		(size 0.508)
		(drill 0.254)
		(layers "F.Cu" "B.Cu")
		(net "M_E_DQ<50>")
	)
	(arc
		(start 286.98698 -102.252018)
		(mid 286.978854 -101.698389)
		(end 287.432496 -101.381052)
		(width 0.0889)
		(layer "F.Cu")
		(net "M_E_DQ<50>")
	)
	(arc
		(start 286.99333 -102.662736)
		(mid 287.0468 -102.467673)
		(end 286.998156 -102.271322)
		(width 0.0889)
		(layer "F.Cu")
		(net "M_E_DQ<50>")
	)
	(segment
		(start 306.049934 -142.476982)
		(end 306.049934 -141.213078)
		(width 0.1651)
		(layer "B.Cu")
		(net "M_E_DQ<50>")
	)
	(segment
		(start 306.050442 -142.477236)
		(end 306.049934 -142.476982)
		(width 0.1651)
		(layer "B.Cu")
		(net "M_E_DQ<50>")
	)
	(segment
		(start 306.049934 -141.213078)
		(end 305.705002 -140.868146)
		(width 0.14224)
		(layer "In4.Cu")
		(net "M_E_DQ<50>")
	)
	(segment
		(start 306.416202 -129.960878)
		(end 306.543202 -129.833878)
		(width 0.14224)
		(layer "In4.Cu")
		(net "M_E_DQ<50>")
	)
	(segment
		(start 306.568602 -139.371578)
		(end 306.568602 -138.852402)
		(width 0.14224)
		(layer "In4.Cu")
		(net "M_E_DQ<50>")
	)
	(segment
		(start 306.568602 -138.852402)
		(end 306.4764 -138.7602)
		(width 0.14224)
		(layer "In4.Cu")
		(net "M_E_DQ<50>")
	)
	(segment
		(start 306.416202 -131.332478)
		(end 306.416202 -129.960878)
		(width 0.14224)
		(layer "In4.Cu")
		(net "M_E_DQ<50>")
	)
	(segment
		(start 306.619402 -131.535678)
		(end 306.416202 -131.332478)
		(width 0.14224)
		(layer "In4.Cu")
		(net "M_E_DQ<50>")
	)
	(segment
		(start 306.340002 -135.976868)
		(end 306.340002 -134.771638)
		(width 0.14224)
		(layer "In4.Cu")
		(net "M_E_DQ<50>")
	)
	(segment
		(start 306.475638 -134.035038)
		(end 306.475638 -132.096764)
		(width 0.14224)
		(layer "In4.Cu")
		(net "M_E_DQ<50>")
	)
	(segment
		(start 305.948334 -126.615698)
		(end 305.9176 -126.615698)
		(width 0.14224)
		(layer "In4.Cu")
		(net "M_E_DQ<50>")
	)
	(segment
		(start 306.4764 -138.7602)
		(end 306.4764 -136.651746)
		(width 0.14224)
		(layer "In4.Cu")
		(net "M_E_DQ<50>")
	)
	(segment
		(start 306.568602 -136.205468)
		(end 306.340002 -135.976868)
		(width 0.14224)
		(layer "In4.Cu")
		(net "M_E_DQ<50>")
	)
	(segment
		(start 305.705002 -140.235178)
		(end 306.568602 -139.371578)
		(width 0.14224)
		(layer "In4.Cu")
		(net "M_E_DQ<50>")
	)
	(segment
		(start 306.543202 -127.210566)
		(end 305.948334 -126.615698)
		(width 0.14224)
		(layer "In4.Cu")
		(net "M_E_DQ<50>")
	)
	(segment
		(start 306.619402 -134.492238)
		(end 306.619402 -134.178802)
		(width 0.14224)
		(layer "In4.Cu")
		(net "M_E_DQ<50>")
	)
	(segment
		(start 306.568602 -136.559544)
		(end 306.568602 -136.205468)
		(width 0.14224)
		(layer "In4.Cu")
		(net "M_E_DQ<50>")
	)
	(segment
		(start 305.705002 -140.868146)
		(end 305.705002 -140.235178)
		(width 0.14224)
		(layer "In4.Cu")
		(net "M_E_DQ<50>")
	)
	(segment
		(start 306.619402 -134.178802)
		(end 306.475638 -134.035038)
		(width 0.14224)
		(layer "In4.Cu")
		(net "M_E_DQ<50>")
	)
	(segment
		(start 306.475638 -132.096764)
		(end 306.619402 -131.953)
		(width 0.14224)
		(layer "In4.Cu")
		(net "M_E_DQ<50>")
	)
	(segment
		(start 306.619402 -131.953)
		(end 306.619402 -131.535678)
		(width 0.14224)
		(layer "In4.Cu")
		(net "M_E_DQ<50>")
	)
	(segment
		(start 306.543202 -129.833878)
		(end 306.543202 -127.210566)
		(width 0.14224)
		(layer "In4.Cu")
		(net "M_E_DQ<50>")
	)
	(segment
		(start 306.340002 -134.771638)
		(end 306.619402 -134.492238)
		(width 0.14224)
		(layer "In4.Cu")
		(net "M_E_DQ<50>")
	)
	(segment
		(start 306.4764 -136.651746)
		(end 306.568602 -136.559544)
		(width 0.14224)
		(layer "In4.Cu")
		(net "M_E_DQ<50>")
	)
	(segment
		(start 305.616864 -144.233646)
		(end 306.899818 -145.5166)
		(width 0.14224)
		(layer "In9.Cu")
		(net "M_E_DQ<50>")
	)
	(segment
		(start 306.049934 -141.213078)
		(end 305.616864 -141.646148)
		(width 0.14224)
		(layer "In9.Cu")
		(net "M_E_DQ<50>")
	)
	(segment
		(start 305.616864 -141.646148)
		(end 305.616864 -144.233646)
		(width 0.14224)
		(layer "In9.Cu")
		(net "M_E_DQ<50>")
	)
	(segment
		(start 197.250304 -147.27174)
		(end 197.249796 -147.27174)
		(width 0.1651)
		(layer "F.Cu")
		(net "M_E_DQ<4>")
	)
	(segment
		(start 197.249796 -145.946368)
		(end 197.151752 -145.415)
		(width 0.1651)
		(layer "F.Cu")
		(net "M_E_DQ<4>")
	)
	(segment
		(start 238.759238 -83.822286)
		(end 238.187738 -83.822286)
		(width 0.1651)
		(layer "F.Cu")
		(net "M_E_DQ<4>")
	)
	(segment
		(start 197.249796 -147.27174)
		(end 197.249796 -145.946368)
		(width 0.1651)
		(layer "F.Cu")
		(net "M_E_DQ<4>")
	)
	(via
		(at 197.151752 -145.415)
		(size 0.508)
		(drill 0.254)
		(layers "F.Cu" "B.Cu")
		(net "M_E_DQ<4>")
	)
	(via
		(at 238.187738 -83.822286)
		(size 0.508)
		(drill 0.254)
		(layers "F.Cu" "B.Cu")
		(net "M_E_DQ<4>")
	)
	(via
		(at 196.399912 -141.213078)
		(size 0.508)
		(drill 0.254)
		(layers "F.Cu" "B.Cu")
		(net "M_E_DQ<4>")
	)
	(segment
		(start 196.399912 -142.476982)
		(end 196.399912 -141.213078)
		(width 0.1651)
		(layer "B.Cu")
		(net "M_E_DQ<4>")
	)
	(segment
		(start 196.40042 -142.477236)
		(end 196.399912 -142.476982)
		(width 0.1651)
		(layer "B.Cu")
		(net "M_E_DQ<4>")
	)
	(segment
		(start 196.877178 -139.226036)
		(end 196.627496 -139.829032)
		(width 0.14224)
		(layer "In4.Cu")
		(net "M_E_DQ<4>")
	)
	(segment
		(start 238.187738 -83.822286)
		(end 237.857538 -83.060286)
		(width 0.0889)
		(layer "In4.Cu")
		(net "M_E_DQ<4>")
	)
	(segment
		(start 237.857538 -83.060286)
		(end 237.841028 -83.031838)
		(width 0.0889)
		(layer "In4.Cu")
		(net "M_E_DQ<4>")
	)
	(segment
		(start 196.627496 -139.829032)
		(end 196.290946 -140.165582)
		(width 0.14224)
		(layer "In4.Cu")
		(net "M_E_DQ<4>")
	)
	(segment
		(start 205.80477 -106.8578)
		(end 196.948044 -115.714526)
		(width 0.14224)
		(layer "In4.Cu")
		(net "M_E_DQ<4>")
	)
	(segment
		(start 196.690996 -130.266694)
		(end 196.690996 -131.09702)
		(width 0.14224)
		(layer "In4.Cu")
		(net "M_E_DQ<4>")
	)
	(segment
		(start 217.725752 -96.954594)
		(end 209.249264 -105.431082)
		(width 0.14224)
		(layer "In4.Cu")
		(net "M_E_DQ<4>")
	)
	(segment
		(start 196.665596 -135.86206)
		(end 196.877178 -136.373108)
		(width 0.14224)
		(layer "In4.Cu")
		(net "M_E_DQ<4>")
	)
	(segment
		(start 196.88683 -129.794)
		(end 196.844666 -129.8956)
		(width 0.14224)
		(layer "In4.Cu")
		(net "M_E_DQ<4>")
	)
	(segment
		(start 233.051604 -82.241136)
		(end 232.790746 -82.241136)
		(width 0.0889)
		(layer "In4.Cu")
		(net "M_E_DQ<4>")
	)
	(segment
		(start 196.857112 -131.498086)
		(end 196.857112 -134.397496)
		(width 0.14224)
		(layer "In4.Cu")
		(net "M_E_DQ<4>")
	)
	(segment
		(start 196.844666 -129.8956)
		(end 196.690996 -130.266694)
		(width 0.14224)
		(layer "In4.Cu")
		(net "M_E_DQ<4>")
	)
	(segment
		(start 230.994204 -81.73212)
		(end 228.028246 -81.73212)
		(width 0.14224)
		(layer "In4.Cu")
		(net "M_E_DQ<4>")
	)
	(segment
		(start 232.510584 -81.960974)
		(end 231.223058 -81.960974)
		(width 0.0889)
		(layer "In4.Cu")
		(net "M_E_DQ<4>")
	)
	(segment
		(start 209.165698 -105.465626)
		(end 205.80477 -106.8578)
		(width 0.14224)
		(layer "In4.Cu")
		(net "M_E_DQ<4>")
	)
	(segment
		(start 235.633768 -81.74609)
		(end 235.601002 -81.74609)
		(width 0.0889)
		(layer "In4.Cu")
		(net "M_E_DQ<4>")
	)
	(segment
		(start 209.249264 -105.431082)
		(end 209.165698 -105.465626)
		(width 0.14224)
		(layer "In4.Cu")
		(net "M_E_DQ<4>")
	)
	(segment
		(start 196.877178 -136.373108)
		(end 196.877178 -139.226036)
		(width 0.14224)
		(layer "In4.Cu")
		(net "M_E_DQ<4>")
	)
	(segment
		(start 218.435174 -95.241618)
		(end 217.725752 -96.954594)
		(width 0.14224)
		(layer "In4.Cu")
		(net "M_E_DQ<4>")
	)
	(segment
		(start 196.948044 -115.714526)
		(end 196.948044 -129.645918)
		(width 0.14224)
		(layer "In4.Cu")
		(net "M_E_DQ<4>")
	)
	(segment
		(start 234.771438 -81.250536)
		(end 234.735878 -81.250536)
		(width 0.0889)
		(layer "In4.Cu")
		(net "M_E_DQ<4>")
	)
	(segment
		(start 195.966842 -141.646148)
		(end 195.966842 -144.23009)
		(width 0.14224)
		(layer "In4.Cu")
		(net "M_E_DQ<4>")
	)
	(segment
		(start 196.690996 -131.09702)
		(end 196.857112 -131.498086)
		(width 0.14224)
		(layer "In4.Cu")
		(net "M_E_DQ<4>")
	)
	(segment
		(start 228.028246 -81.73212)
		(end 218.435174 -91.325192)
		(width 0.14224)
		(layer "In4.Cu")
		(net "M_E_DQ<4>")
	)
	(segment
		(start 218.435174 -91.325192)
		(end 218.435174 -95.241618)
		(width 0.14224)
		(layer "In4.Cu")
		(net "M_E_DQ<4>")
	)
	(segment
		(start 231.223058 -81.960974)
		(end 230.994204 -81.73212)
		(width 0.0889)
		(layer "In4.Cu")
		(net "M_E_DQ<4>")
	)
	(segment
		(start 233.906314 -81.74609)
		(end 233.873548 -81.74609)
		(width 0.0889)
		(layer "In4.Cu")
		(net "M_E_DQ<4>")
	)
	(segment
		(start 195.966842 -144.23009)
		(end 197.151752 -145.415)
		(width 0.14224)
		(layer "In4.Cu")
		(net "M_E_DQ<4>")
	)
	(segment
		(start 237.350808 -82.73669)
		(end 237.318042 -82.73669)
		(width 0.0889)
		(layer "In4.Cu")
		(net "M_E_DQ<4>")
	)
	(segment
		(start 196.948044 -129.645918)
		(end 196.88683 -129.794)
		(width 0.14224)
		(layer "In4.Cu")
		(net "M_E_DQ<4>")
	)
	(segment
		(start 196.290946 -141.104112)
		(end 196.399912 -141.213078)
		(width 0.14224)
		(layer "In4.Cu")
		(net "M_E_DQ<4>")
	)
	(segment
		(start 196.290946 -140.165582)
		(end 196.290946 -141.104112)
		(width 0.14224)
		(layer "In4.Cu")
		(net "M_E_DQ<4>")
	)
	(segment
		(start 236.483652 -82.241136)
		(end 236.455712 -82.241136)
		(width 0.0889)
		(layer "In4.Cu")
		(net "M_E_DQ<4>")
	)
	(segment
		(start 196.399912 -141.213078)
		(end 195.966842 -141.646148)
		(width 0.14224)
		(layer "In4.Cu")
		(net "M_E_DQ<4>")
	)
	(segment
		(start 196.857112 -134.397496)
		(end 196.665596 -134.860284)
		(width 0.14224)
		(layer "In4.Cu")
		(net "M_E_DQ<4>")
	)
	(segment
		(start 232.790746 -82.241136)
		(end 232.510584 -81.960974)
		(width 0.0889)
		(layer "In4.Cu")
		(net "M_E_DQ<4>")
	)
	(segment
		(start 196.665596 -134.860284)
		(end 196.665596 -135.86206)
		(width 0.14224)
		(layer "In4.Cu")
		(net "M_E_DQ<4>")
	)
	(arc
		(start 236.123988 -82.041238)
		(mid 235.916984 -81.830374)
		(end 235.633768 -81.74609)
		(width 0.0889)
		(layer "In4.Cu")
		(net "M_E_DQ<4>")
	)
	(arc
		(start 236.455712 -82.241136)
		(mid 236.26407 -82.18397)
		(end 236.123988 -82.041238)
		(width 0.0889)
		(layer "In4.Cu")
		(net "M_E_DQ<4>")
	)
	(arc
		(start 237.841028 -83.031838)
		(mid 237.634024 -82.820974)
		(end 237.350808 -82.73669)
		(width 0.0889)
		(layer "In4.Cu")
		(net "M_E_DQ<4>")
	)
	(arc
		(start 237.318042 -82.73669)
		(mid 237.124192 -82.68034)
		(end 236.982508 -82.536538)
		(width 0.0889)
		(layer "In4.Cu")
		(net "M_E_DQ<4>")
	)
	(arc
		(start 234.241848 -81.545938)
		(mid 234.100165 -81.689742)
		(end 233.906314 -81.74609)
		(width 0.0889)
		(layer "In4.Cu")
		(net "M_E_DQ<4>")
	)
	(arc
		(start 233.383328 -82.041238)
		(mid 233.243249 -82.183974)
		(end 233.051604 -82.241136)
		(width 0.0889)
		(layer "In4.Cu")
		(net "M_E_DQ<4>")
	)
	(arc
		(start 234.735878 -81.250536)
		(mid 234.450454 -81.334003)
		(end 234.241848 -81.545938)
		(width 0.0889)
		(layer "In4.Cu")
		(net "M_E_DQ<4>")
	)
	(arc
		(start 233.873548 -81.74609)
		(mid 233.590331 -81.830371)
		(end 233.383328 -82.041238)
		(width 0.0889)
		(layer "In4.Cu")
		(net "M_E_DQ<4>")
	)
	(arc
		(start 235.601002 -81.74609)
		(mid 235.407152 -81.68974)
		(end 235.265468 -81.545938)
		(width 0.0889)
		(layer "In4.Cu")
		(net "M_E_DQ<4>")
	)
	(arc
		(start 235.265468 -81.545938)
		(mid 235.05686 -81.334006)
		(end 234.771438 -81.250536)
		(width 0.0889)
		(layer "In4.Cu")
		(net "M_E_DQ<4>")
	)
	(arc
		(start 236.982508 -82.536538)
		(mid 236.771795 -82.323459)
		(end 236.483652 -82.241136)
		(width 0.0889)
		(layer "In4.Cu")
		(net "M_E_DQ<4>")
	)
	(segment
		(start 300.0756 -113.2078)
		(end 300.0756 -117.6401)
		(width 0.1651)
		(layer "F.Cu")
		(net "M_E_DQ<49>")
	)
	(segment
		(start 284.4673 -103.911146)
		(end 284.4673 -105.2957)
		(width 0.0889)
		(layer "F.Cu")
		(net "M_E_DQ<49>")
	)
	(segment
		(start 284.785054 -105.4862)
		(end 286.741108 -107.442254)
		(width 0.1016)
		(layer "F.Cu")
		(net "M_E_DQ<49>")
	)
	(segment
		(start 301.4218 -116.0145)
		(end 301.4218 -124.1806)
		(width 0.1651)
		(layer "F.Cu")
		(net "M_E_DQ<49>")
	)
	(segment
		(start 300.5836 -117.8052)
		(end 300.7487 -117.6401)
		(width 0.1651)
		(layer "F.Cu")
		(net "M_E_DQ<49>")
	)
	(segment
		(start 301.262796 -124.339604)
		(end 301.262796 -125.195076)
		(width 0.1651)
		(layer "F.Cu")
		(net "M_E_DQ<49>")
	)
	(segment
		(start 284.929834 -103.448612)
		(end 284.4673 -103.911146)
		(width 0.0889)
		(layer "F.Cu")
		(net "M_E_DQ<49>")
	)
	(segment
		(start 300.2407 -117.8052)
		(end 300.5836 -117.8052)
		(width 0.1651)
		(layer "F.Cu")
		(net "M_E_DQ<49>")
	)
	(segment
		(start 284.4673 -105.2957)
		(end 284.6578 -105.4862)
		(width 0.0889)
		(layer "F.Cu")
		(net "M_E_DQ<49>")
	)
	(segment
		(start 284.929834 -102.462584)
		(end 284.929834 -103.448612)
		(width 0.0889)
		(layer "F.Cu")
		(net "M_E_DQ<49>")
	)
	(segment
		(start 286.741108 -107.442254)
		(end 295.056052 -107.442254)
		(width 0.1016)
		(layer "F.Cu")
		(net "M_E_DQ<49>")
	)
	(segment
		(start 300.100492 -142.6718)
		(end 300.099984 -142.677642)
		(width 0.1651)
		(layer "F.Cu")
		(net "M_E_DQ<49>")
	)
	(segment
		(start 297.7896 -110.175802)
		(end 297.7896 -110.9218)
		(width 0.1016)
		(layer "F.Cu")
		(net "M_E_DQ<49>")
	)
	(segment
		(start 297.7896 -110.9218)
		(end 300.0756 -113.2078)
		(width 0.1651)
		(layer "F.Cu")
		(net "M_E_DQ<49>")
	)
	(segment
		(start 284.6578 -105.4862)
		(end 284.785054 -105.4862)
		(width 0.0889)
		(layer "F.Cu")
		(net "M_E_DQ<49>")
	)
	(segment
		(start 300.7487 -117.6401)
		(end 300.7487 -116.0145)
		(width 0.1651)
		(layer "F.Cu")
		(net "M_E_DQ<49>")
	)
	(segment
		(start 300.099984 -142.677642)
		(end 300.099984 -143.941546)
		(width 0.1651)
		(layer "F.Cu")
		(net "M_E_DQ<49>")
	)
	(segment
		(start 301.2567 -115.8494)
		(end 301.4218 -116.0145)
		(width 0.1651)
		(layer "F.Cu")
		(net "M_E_DQ<49>")
	)
	(segment
		(start 301.4218 -124.1806)
		(end 301.262796 -124.339604)
		(width 0.1651)
		(layer "F.Cu")
		(net "M_E_DQ<49>")
	)
	(segment
		(start 301.262796 -125.195076)
		(end 301.135796 -125.322076)
		(width 0.1651)
		(layer "F.Cu")
		(net "M_E_DQ<49>")
	)
	(segment
		(start 295.056052 -107.442254)
		(end 297.7896 -110.175802)
		(width 0.1016)
		(layer "F.Cu")
		(net "M_E_DQ<49>")
	)
	(segment
		(start 301.135796 -125.322076)
		(end 300.772068 -125.322076)
		(width 0.1651)
		(layer "F.Cu")
		(net "M_E_DQ<49>")
	)
	(segment
		(start 300.0756 -117.6401)
		(end 300.2407 -117.8052)
		(width 0.1651)
		(layer "F.Cu")
		(net "M_E_DQ<49>")
	)
	(segment
		(start 300.9138 -115.8494)
		(end 301.2567 -115.8494)
		(width 0.1651)
		(layer "F.Cu")
		(net "M_E_DQ<49>")
	)
	(segment
		(start 300.7487 -116.0145)
		(end 300.9138 -115.8494)
		(width 0.1651)
		(layer "F.Cu")
		(net "M_E_DQ<49>")
	)
	(via
		(at 300.772068 -125.322076)
		(size 0.508)
		(drill 0.254)
		(layers "F.Cu" "B.Cu")
		(net "M_E_DQ<49>")
	)
	(via
		(at 300.772068 -139.932156)
		(size 0.508)
		(drill 0.254)
		(layers "F.Cu" "B.Cu")
		(net "M_E_DQ<49>")
	)
	(via
		(at 300.099984 -143.941546)
		(size 0.508)
		(drill 0.254)
		(layers "F.Cu" "B.Cu")
		(net "M_E_DQ<49>")
	)
	(segment
		(start 300.772068 -139.428982)
		(end 300.772068 -139.932156)
		(width 0.1651)
		(layer "B.Cu")
		(net "M_E_DQ<49>")
	)
	(segment
		(start 300.949868 -137.877296)
		(end 300.949868 -139.251182)
		(width 0.1651)
		(layer "B.Cu")
		(net "M_E_DQ<49>")
	)
	(segment
		(start 300.950376 -137.877296)
		(end 300.949868 -137.877296)
		(width 0.1651)
		(layer "B.Cu")
		(net "M_E_DQ<49>")
	)
	(segment
		(start 300.949868 -139.251182)
		(end 300.772068 -139.428982)
		(width 0.1651)
		(layer "B.Cu")
		(net "M_E_DQ<49>")
	)
	(segment
		(start 301.371 -136.686798)
		(end 301.371 -138.7856)
		(width 0.14224)
		(layer "In4.Cu")
		(net "M_E_DQ<49>")
	)
	(segment
		(start 301.260002 -136.5758)
		(end 301.371 -136.686798)
		(width 0.14224)
		(layer "In4.Cu")
		(net "M_E_DQ<49>")
	)
	(segment
		(start 300.772068 -139.843256)
		(end 300.772068 -139.932156)
		(width 0.14224)
		(layer "In4.Cu")
		(net "M_E_DQ<49>")
	)
	(segment
		(start 300.772068 -125.322076)
		(end 300.576996 -125.517148)
		(width 0.14224)
		(layer "In4.Cu")
		(net "M_E_DQ<49>")
	)
	(segment
		(start 300.576996 -125.517148)
		(end 300.576996 -128.257808)
		(width 0.14224)
		(layer "In4.Cu")
		(net "M_E_DQ<49>")
	)
	(segment
		(start 301.260002 -128.940814)
		(end 301.260002 -131.816856)
		(width 0.14224)
		(layer "In4.Cu")
		(net "M_E_DQ<49>")
	)
	(segment
		(start 301.260002 -138.896598)
		(end 301.260002 -139.355322)
		(width 0.14224)
		(layer "In4.Cu")
		(net "M_E_DQ<49>")
	)
	(segment
		(start 301.260002 -131.816856)
		(end 301.371 -131.927854)
		(width 0.14224)
		(layer "In4.Cu")
		(net "M_E_DQ<49>")
	)
	(segment
		(start 301.371 -138.7856)
		(end 301.260002 -138.896598)
		(width 0.14224)
		(layer "In4.Cu")
		(net "M_E_DQ<49>")
	)
	(segment
		(start 301.371 -134.1374)
		(end 301.260002 -134.248398)
		(width 0.14224)
		(layer "In4.Cu")
		(net "M_E_DQ<49>")
	)
	(segment
		(start 301.260002 -139.355322)
		(end 300.772068 -139.843256)
		(width 0.14224)
		(layer "In4.Cu")
		(net "M_E_DQ<49>")
	)
	(segment
		(start 301.260002 -134.248398)
		(end 301.260002 -136.5758)
		(width 0.14224)
		(layer "In4.Cu")
		(net "M_E_DQ<49>")
	)
	(segment
		(start 301.371 -131.927854)
		(end 301.371 -134.1374)
		(width 0.14224)
		(layer "In4.Cu")
		(net "M_E_DQ<49>")
	)
	(segment
		(start 300.576996 -128.257808)
		(end 301.260002 -128.940814)
		(width 0.14224)
		(layer "In4.Cu")
		(net "M_E_DQ<49>")
	)
	(segment
		(start 300.261274 -142.076424)
		(end 300.261274 -141.715744)
		(width 0.14224)
		(layer "In9.Cu")
		(net "M_E_DQ<49>")
	)
	(segment
		(start 300.47565 -142.7226)
		(end 300.47565 -142.2908)
		(width 0.14224)
		(layer "In9.Cu")
		(net "M_E_DQ<49>")
	)
	(segment
		(start 300.749716 -139.932156)
		(end 300.772068 -139.932156)
		(width 0.14224)
		(layer "In9.Cu")
		(net "M_E_DQ<49>")
	)
	(segment
		(start 300.321472 -140.790168)
		(end 300.321472 -140.3604)
		(width 0.14224)
		(layer "In9.Cu")
		(net "M_E_DQ<49>")
	)
	(segment
		(start 300.55185 -141.425168)
		(end 300.55185 -141.020546)
		(width 0.14224)
		(layer "In9.Cu")
		(net "M_E_DQ<49>")
	)
	(segment
		(start 300.261274 -142.936976)
		(end 300.47565 -142.7226)
		(width 0.14224)
		(layer "In9.Cu")
		(net "M_E_DQ<49>")
	)
	(segment
		(start 300.50105 -143.7894)
		(end 300.50105 -143.4846)
		(width 0.14224)
		(layer "In9.Cu")
		(net "M_E_DQ<49>")
	)
	(segment
		(start 300.321472 -140.3604)
		(end 300.749716 -139.932156)
		(width 0.14224)
		(layer "In9.Cu")
		(net "M_E_DQ<49>")
	)
	(segment
		(start 300.099984 -143.941546)
		(end 300.348904 -143.941546)
		(width 0.14224)
		(layer "In9.Cu")
		(net "M_E_DQ<49>")
	)
	(segment
		(start 300.261274 -143.244824)
		(end 300.261274 -142.936976)
		(width 0.14224)
		(layer "In9.Cu")
		(net "M_E_DQ<49>")
	)
	(segment
		(start 300.348904 -143.941546)
		(end 300.50105 -143.7894)
		(width 0.14224)
		(layer "In9.Cu")
		(net "M_E_DQ<49>")
	)
	(segment
		(start 300.261274 -141.715744)
		(end 300.55185 -141.425168)
		(width 0.14224)
		(layer "In9.Cu")
		(net "M_E_DQ<49>")
	)
	(segment
		(start 300.50105 -143.4846)
		(end 300.261274 -143.244824)
		(width 0.14224)
		(layer "In9.Cu")
		(net "M_E_DQ<49>")
	)
	(segment
		(start 300.55185 -141.020546)
		(end 300.321472 -140.790168)
		(width 0.14224)
		(layer "In9.Cu")
		(net "M_E_DQ<49>")
	)
	(segment
		(start 300.47565 -142.2908)
		(end 300.261274 -142.076424)
		(width 0.14224)
		(layer "In9.Cu")
		(net "M_E_DQ<49>")
	)
	(segment
		(start 298.7802 -113.131854)
		(end 298.7802 -113.585752)
		(width 0.1651)
		(layer "F.Cu")
		(net "M_E_DQ<48>")
	)
	(segment
		(start 284.2768 -105.392728)
		(end 284.48 -105.595928)
		(width 0.0889)
		(layer "F.Cu")
		(net "M_E_DQ<48>")
	)
	(segment
		(start 298.7802 -113.585752)
		(end 297.558968 -114.806476)
		(width 0.1651)
		(layer "F.Cu")
		(net "M_E_DQ<48>")
	)
	(segment
		(start 284.511242 -103.524304)
		(end 284.2768 -103.758746)
		(width 0.0889)
		(layer "F.Cu")
		(net "M_E_DQ<48>")
	)
	(segment
		(start 297.2816 -110.224824)
		(end 297.2816 -111.252254)
		(width 0.1016)
		(layer "F.Cu")
		(net "M_E_DQ<48>")
	)
	(segment
		(start 300.125384 -126.590298)
		(end 299.8216 -126.590298)
		(width 0.1651)
		(layer "F.Cu")
		(net "M_E_DQ<48>")
	)
	(segment
		(start 299.1104 -114.681254)
		(end 299.1104 -118.1608)
		(width 0.1651)
		(layer "F.Cu")
		(net "M_E_DQ<48>")
	)
	(segment
		(start 284.071314 -101.967538)
		(end 284.511242 -102.407466)
		(width 0.0889)
		(layer "F.Cu")
		(net "M_E_DQ<48>")
	)
	(segment
		(start 297.2816 -111.252254)
		(end 297.2816 -111.633254)
		(width 0.1651)
		(layer "F.Cu")
		(net "M_E_DQ<48>")
	)
	(segment
		(start 297.558968 -115.08486)
		(end 297.75658 -115.282472)
		(width 0.1651)
		(layer "F.Cu")
		(net "M_E_DQ<48>")
	)
	(segment
		(start 300.950376 -147.27174)
		(end 300.949868 -147.277582)
		(width 0.1651)
		(layer "F.Cu")
		(net "M_E_DQ<48>")
	)
	(segment
		(start 300.297596 -123.679458)
		(end 300.297596 -126.418086)
		(width 0.1651)
		(layer "F.Cu")
		(net "M_E_DQ<48>")
	)
	(segment
		(start 300.949868 -147.277582)
		(end 300.772068 -145.415)
		(width 0.1651)
		(layer "F.Cu")
		(net "M_E_DQ<48>")
	)
	(segment
		(start 284.2768 -103.758746)
		(end 284.2768 -105.392728)
		(width 0.0889)
		(layer "F.Cu")
		(net "M_E_DQ<48>")
	)
	(segment
		(start 297.558968 -114.806476)
		(end 297.558968 -115.08486)
		(width 0.1651)
		(layer "F.Cu")
		(net "M_E_DQ<48>")
	)
	(segment
		(start 300.736 -119.7864)
		(end 300.736 -123.241054)
		(width 0.1651)
		(layer "F.Cu")
		(net "M_E_DQ<48>")
	)
	(segment
		(start 298.734226 -114.583464)
		(end 299.01261 -114.583464)
		(width 0.1651)
		(layer "F.Cu")
		(net "M_E_DQ<48>")
	)
	(segment
		(start 286.577786 -107.835954)
		(end 294.89273 -107.835954)
		(width 0.1016)
		(layer "F.Cu")
		(net "M_E_DQ<48>")
	)
	(segment
		(start 284.48 -105.595928)
		(end 284.48 -105.738168)
		(width 0.0889)
		(layer "F.Cu")
		(net "M_E_DQ<48>")
	)
	(segment
		(start 294.89273 -107.835954)
		(end 297.2816 -110.224824)
		(width 0.1016)
		(layer "F.Cu")
		(net "M_E_DQ<48>")
	)
	(segment
		(start 300.736 -123.241054)
		(end 300.297596 -123.679458)
		(width 0.1651)
		(layer "F.Cu")
		(net "M_E_DQ<48>")
	)
	(segment
		(start 298.034964 -115.282472)
		(end 298.734226 -114.583464)
		(width 0.1651)
		(layer "F.Cu")
		(net "M_E_DQ<48>")
	)
	(segment
		(start 284.48 -105.738168)
		(end 286.577786 -107.835954)
		(width 0.1016)
		(layer "F.Cu")
		(net "M_E_DQ<48>")
	)
	(segment
		(start 284.511242 -102.407466)
		(end 284.511242 -103.524304)
		(width 0.0889)
		(layer "F.Cu")
		(net "M_E_DQ<48>")
	)
	(segment
		(start 297.2816 -111.633254)
		(end 298.7802 -113.131854)
		(width 0.1651)
		(layer "F.Cu")
		(net "M_E_DQ<48>")
	)
	(segment
		(start 299.1104 -118.1608)
		(end 300.736 -119.7864)
		(width 0.1651)
		(layer "F.Cu")
		(net "M_E_DQ<48>")
	)
	(segment
		(start 300.297596 -126.418086)
		(end 300.125384 -126.590298)
		(width 0.1651)
		(layer "F.Cu")
		(net "M_E_DQ<48>")
	)
	(segment
		(start 299.01261 -114.583464)
		(end 299.1104 -114.681254)
		(width 0.1651)
		(layer "F.Cu")
		(net "M_E_DQ<48>")
	)
	(segment
		(start 297.75658 -115.282472)
		(end 298.034964 -115.282472)
		(width 0.1651)
		(layer "F.Cu")
		(net "M_E_DQ<48>")
	)
	(via
		(at 299.8216 -126.590298)
		(size 0.508)
		(drill 0.254)
		(layers "F.Cu" "B.Cu")
		(net "M_E_DQ<48>")
	)
	(via
		(at 300.099984 -141.213078)
		(size 0.508)
		(drill 0.254)
		(layers "F.Cu" "B.Cu")
		(net "M_E_DQ<48>")
	)
	(via
		(at 300.772068 -145.415)
		(size 0.508)
		(drill 0.254)
		(layers "F.Cu" "B.Cu")
		(net "M_E_DQ<48>")
	)
	(segment
		(start 300.100492 -142.477236)
		(end 300.099984 -142.476982)
		(width 0.1651)
		(layer "B.Cu")
		(net "M_E_DQ<48>")
	)
	(segment
		(start 300.099984 -142.476982)
		(end 300.099984 -141.213078)
		(width 0.1651)
		(layer "B.Cu")
		(net "M_E_DQ<48>")
	)
	(segment
		(start 299.736002 -140.209778)
		(end 299.736002 -140.849096)
		(width 0.14224)
		(layer "In4.Cu")
		(net "M_E_DQ<48>")
	)
	(segment
		(start 299.736002 -140.849096)
		(end 300.099984 -141.213078)
		(width 0.14224)
		(layer "In4.Cu")
		(net "M_E_DQ<48>")
	)
	(segment
		(start 300.574202 -131.9784)
		(end 300.5328 -132.019802)
		(width 0.14224)
		(layer "In4.Cu")
		(net "M_E_DQ<48>")
	)
	(segment
		(start 300.294802 -134.764018)
		(end 300.294802 -135.956802)
		(width 0.14224)
		(layer "In4.Cu")
		(net "M_E_DQ<48>")
	)
	(segment
		(start 300.586902 -136.248902)
		(end 300.586902 -136.6266)
		(width 0.14224)
		(layer "In4.Cu")
		(net "M_E_DQ<48>")
	)
	(segment
		(start 300.574202 -134.051802)
		(end 300.574202 -134.484618)
		(width 0.14224)
		(layer "In4.Cu")
		(net "M_E_DQ<48>")
	)
	(segment
		(start 300.574202 -134.484618)
		(end 300.294802 -134.764018)
		(width 0.14224)
		(layer "In4.Cu")
		(net "M_E_DQ<48>")
	)
	(segment
		(start 300.5328 -138.9634)
		(end 300.586902 -139.017502)
		(width 0.14224)
		(layer "In4.Cu")
		(net "M_E_DQ<48>")
	)
	(segment
		(start 300.5328 -136.680702)
		(end 300.5328 -138.9634)
		(width 0.14224)
		(layer "In4.Cu")
		(net "M_E_DQ<48>")
	)
	(segment
		(start 300.586902 -136.6266)
		(end 300.5328 -136.680702)
		(width 0.14224)
		(layer "In4.Cu")
		(net "M_E_DQ<48>")
	)
	(segment
		(start 300.625002 -129.719578)
		(end 300.282102 -130.062478)
		(width 0.14224)
		(layer "In4.Cu")
		(net "M_E_DQ<48>")
	)
	(segment
		(start 300.574202 -131.434078)
		(end 300.574202 -131.9784)
		(width 0.14224)
		(layer "In4.Cu")
		(net "M_E_DQ<48>")
	)
	(segment
		(start 300.294802 -135.956802)
		(end 300.586902 -136.248902)
		(width 0.14224)
		(layer "In4.Cu")
		(net "M_E_DQ<48>")
	)
	(segment
		(start 300.625002 -129.203958)
		(end 300.625002 -129.719578)
		(width 0.14224)
		(layer "In4.Cu")
		(net "M_E_DQ<48>")
	)
	(segment
		(start 300.5328 -134.0104)
		(end 300.574202 -134.051802)
		(width 0.14224)
		(layer "In4.Cu")
		(net "M_E_DQ<48>")
	)
	(segment
		(start 300.586902 -139.017502)
		(end 300.586902 -139.358878)
		(width 0.14224)
		(layer "In4.Cu")
		(net "M_E_DQ<48>")
	)
	(segment
		(start 300.586902 -139.358878)
		(end 299.736002 -140.209778)
		(width 0.14224)
		(layer "In4.Cu")
		(net "M_E_DQ<48>")
	)
	(segment
		(start 300.099984 -126.868682)
		(end 300.099984 -128.67894)
		(width 0.14224)
		(layer "In4.Cu")
		(net "M_E_DQ<48>")
	)
	(segment
		(start 299.8216 -126.590298)
		(end 300.099984 -126.868682)
		(width 0.14224)
		(layer "In4.Cu")
		(net "M_E_DQ<48>")
	)
	(segment
		(start 300.099984 -128.67894)
		(end 300.625002 -129.203958)
		(width 0.14224)
		(layer "In4.Cu")
		(net "M_E_DQ<48>")
	)
	(segment
		(start 300.282102 -131.141978)
		(end 300.574202 -131.434078)
		(width 0.14224)
		(layer "In4.Cu")
		(net "M_E_DQ<48>")
	)
	(segment
		(start 300.5328 -132.019802)
		(end 300.5328 -134.0104)
		(width 0.14224)
		(layer "In4.Cu")
		(net "M_E_DQ<48>")
	)
	(segment
		(start 300.282102 -130.062478)
		(end 300.282102 -131.141978)
		(width 0.14224)
		(layer "In4.Cu")
		(net "M_E_DQ<48>")
	)
	(segment
		(start 299.666914 -144.60601)
		(end 300.475904 -145.415)
		(width 0.14224)
		(layer "In9.Cu")
		(net "M_E_DQ<48>")
	)
	(segment
		(start 299.666914 -141.646148)
		(end 299.666914 -144.60601)
		(width 0.14224)
		(layer "In9.Cu")
		(net "M_E_DQ<48>")
	)
	(segment
		(start 300.099984 -141.213078)
		(end 299.666914 -141.646148)
		(width 0.14224)
		(layer "In9.Cu")
		(net "M_E_DQ<48>")
	)
	(segment
		(start 300.475904 -145.415)
		(end 300.772068 -145.415)
		(width 0.14224)
		(layer "In9.Cu")
		(net "M_E_DQ<48>")
	)
	(segment
		(start 294.999918 -142.677642)
		(end 294.999918 -143.941546)
		(width 0.1651)
		(layer "F.Cu")
		(net "M_E_DQ<47>")
	)
	(segment
		(start 292.530276 -117.023134)
		(end 292.898068 -117.023134)
		(width 0.1651)
		(layer "F.Cu")
		(net "M_E_DQ<47>")
	)
	(segment
		(start 285.467044 -111.9378)
		(end 286.769556 -111.9378)
		(width 0.1016)
		(layer "F.Cu")
		(net "M_E_DQ<47>")
	)
	(segment
		(start 293.374064 -117.49913)
		(end 293.374064 -117.73281)
		(width 0.1651)
		(layer "F.Cu")
		(net "M_E_DQ<47>")
	)
	(segment
		(start 281.737562 -105.775506)
		(end 281.84602 -105.883964)
		(width 0.0889)
		(layer "F.Cu")
		(net "M_E_DQ<47>")
	)
	(segment
		(start 281.84602 -108.316776)
		(end 285.467044 -111.9378)
		(width 0.1016)
		(layer "F.Cu")
		(net "M_E_DQ<47>")
	)
	(segment
		(start 290.976558 -116.351558)
		(end 291.15639 -116.351558)
		(width 0.1651)
		(layer "F.Cu")
		(net "M_E_DQ<47>")
	)
	(segment
		(start 291.306758 -115.758722)
		(end 291.442648 -115.622832)
		(width 0.1651)
		(layer "F.Cu")
		(net "M_E_DQ<47>")
	)
	(segment
		(start 293.349934 -116.571268)
		(end 293.603172 -116.571268)
		(width 0.1651)
		(layer "F.Cu")
		(net "M_E_DQ<47>")
	)
	(segment
		(start 293.845488 -117.027706)
		(end 293.374064 -117.49913)
		(width 0.1651)
		(layer "F.Cu")
		(net "M_E_DQ<47>")
	)
	(segment
		(start 296.2148 -123.9012)
		(end 296.2148 -124.944378)
		(width 0.1651)
		(layer "F.Cu")
		(net "M_E_DQ<47>")
	)
	(segment
		(start 291.306758 -116.20119)
		(end 291.306758 -115.758722)
		(width 0.1651)
		(layer "F.Cu")
		(net "M_E_DQ<47>")
	)
	(segment
		(start 292.049708 -116.542566)
		(end 292.530276 -117.023134)
		(width 0.1651)
		(layer "F.Cu")
		(net "M_E_DQ<47>")
	)
	(segment
		(start 287.8074 -113.1824)
		(end 290.976558 -116.351558)
		(width 0.1651)
		(layer "F.Cu")
		(net "M_E_DQ<47>")
	)
	(segment
		(start 281.495754 -103.695754)
		(end 281.737562 -103.937562)
		(width 0.0889)
		(layer "F.Cu")
		(net "M_E_DQ<47>")
	)
	(segment
		(start 296.2148 -124.944378)
		(end 295.748202 -125.410976)
		(width 0.1651)
		(layer "F.Cu")
		(net "M_E_DQ<47>")
	)
	(segment
		(start 281.495754 -102.462584)
		(end 281.495754 -103.695754)
		(width 0.0889)
		(layer "F.Cu")
		(net "M_E_DQ<47>")
	)
	(segment
		(start 293.845488 -116.813584)
		(end 293.845488 -117.027706)
		(width 0.1651)
		(layer "F.Cu")
		(net "M_E_DQ<47>")
	)
	(segment
		(start 296.648886 -121.007632)
		(end 296.648886 -123.467114)
		(width 0.1651)
		(layer "F.Cu")
		(net "M_E_DQ<47>")
	)
	(segment
		(start 286.769556 -111.9378)
		(end 287.1724 -112.340644)
		(width 0.1016)
		(layer "F.Cu")
		(net "M_E_DQ<47>")
	)
	(segment
		(start 291.442648 -115.622832)
		(end 291.913564 -115.622832)
		(width 0.1651)
		(layer "F.Cu")
		(net "M_E_DQ<47>")
	)
	(segment
		(start 281.84602 -105.883964)
		(end 281.84602 -108.316776)
		(width 0.1016)
		(layer "F.Cu")
		(net "M_E_DQ<47>")
	)
	(segment
		(start 293.374064 -117.73281)
		(end 296.648886 -121.007632)
		(width 0.1651)
		(layer "F.Cu")
		(net "M_E_DQ<47>")
	)
	(segment
		(start 287.1724 -112.340644)
		(end 287.1724 -112.5474)
		(width 0.1016)
		(layer "F.Cu")
		(net "M_E_DQ<47>")
	)
	(segment
		(start 293.603172 -116.571268)
		(end 293.845488 -116.813584)
		(width 0.1651)
		(layer "F.Cu")
		(net "M_E_DQ<47>")
	)
	(segment
		(start 287.1724 -112.5474)
		(end 287.8074 -113.1824)
		(width 0.1016)
		(layer "F.Cu")
		(net "M_E_DQ<47>")
	)
	(segment
		(start 292.049708 -115.758976)
		(end 292.049708 -116.542566)
		(width 0.1651)
		(layer "F.Cu")
		(net "M_E_DQ<47>")
	)
	(segment
		(start 295.000426 -142.6718)
		(end 294.999918 -142.677642)
		(width 0.1651)
		(layer "F.Cu")
		(net "M_E_DQ<47>")
	)
	(segment
		(start 291.15639 -116.351558)
		(end 291.306758 -116.20119)
		(width 0.1651)
		(layer "F.Cu")
		(net "M_E_DQ<47>")
	)
	(segment
		(start 292.898068 -117.023134)
		(end 293.349934 -116.571268)
		(width 0.1651)
		(layer "F.Cu")
		(net "M_E_DQ<47>")
	)
	(segment
		(start 291.913564 -115.622832)
		(end 292.049708 -115.758976)
		(width 0.1651)
		(layer "F.Cu")
		(net "M_E_DQ<47>")
	)
	(segment
		(start 296.648886 -123.467114)
		(end 296.2148 -123.9012)
		(width 0.1651)
		(layer "F.Cu")
		(net "M_E_DQ<47>")
	)
	(segment
		(start 281.737562 -103.937562)
		(end 281.737562 -105.775506)
		(width 0.0889)
		(layer "F.Cu")
		(net "M_E_DQ<47>")
	)
	(via
		(at 294.999918 -143.941546)
		(size 0.508)
		(drill 0.254)
		(layers "F.Cu" "B.Cu")
		(net "M_E_DQ<47>")
	)
	(via
		(at 295.748202 -125.410976)
		(size 0.508)
		(drill 0.254)
		(layers "F.Cu" "B.Cu")
		(net "M_E_DQ<47>")
	)
	(via
		(at 295.849802 -139.932156)
		(size 0.508)
		(drill 0.254)
		(layers "F.Cu" "B.Cu")
		(net "M_E_DQ<47>")
	)
	(segment
		(start 295.85031 -137.877296)
		(end 295.849802 -137.877296)
		(width 0.1651)
		(layer "B.Cu")
		(net "M_E_DQ<47>")
	)
	(segment
		(start 295.849802 -137.877296)
		(end 295.849802 -139.932156)
		(width 0.1651)
		(layer "B.Cu")
		(net "M_E_DQ<47>")
	)
	(segment
		(start 294.999918 -143.941546)
		(end 295.272206 -143.941546)
		(width 0.14224)
		(layer "In9.Cu")
		(net "M_E_DQ<47>")
	)
	(segment
		(start 295.443656 -140.834618)
		(end 295.399206 -140.790168)
		(width 0.14224)
		(layer "In9.Cu")
		(net "M_E_DQ<47>")
	)
	(segment
		(start 295.161208 -141.785848)
		(end 295.443656 -141.5034)
		(width 0.14224)
		(layer "In9.Cu")
		(net "M_E_DQ<47>")
	)
	(segment
		(start 295.161208 -142.059152)
		(end 295.161208 -141.785848)
		(width 0.14224)
		(layer "In9.Cu")
		(net "M_E_DQ<47>")
	)
	(segment
		(start 295.399206 -140.790168)
		(end 295.399206 -140.3604)
		(width 0.14224)
		(layer "In9.Cu")
		(net "M_E_DQ<47>")
	)
	(segment
		(start 295.161208 -143.151352)
		(end 295.161208 -142.878048)
		(width 0.14224)
		(layer "In9.Cu")
		(net "M_E_DQ<47>")
	)
	(segment
		(start 295.418256 -142.621)
		(end 295.418256 -142.3162)
		(width 0.14224)
		(layer "In9.Cu")
		(net "M_E_DQ<47>")
	)
	(segment
		(start 295.418256 -142.3162)
		(end 295.161208 -142.059152)
		(width 0.14224)
		(layer "In9.Cu")
		(net "M_E_DQ<47>")
	)
	(segment
		(start 295.82745 -139.932156)
		(end 295.849802 -139.932156)
		(width 0.14224)
		(layer "In9.Cu")
		(net "M_E_DQ<47>")
	)
	(segment
		(start 295.399206 -140.3604)
		(end 295.82745 -139.932156)
		(width 0.14224)
		(layer "In9.Cu")
		(net "M_E_DQ<47>")
	)
	(segment
		(start 295.443656 -141.5034)
		(end 295.443656 -140.834618)
		(width 0.14224)
		(layer "In9.Cu")
		(net "M_E_DQ<47>")
	)
	(segment
		(start 295.272206 -143.941546)
		(end 295.450006 -143.763746)
		(width 0.14224)
		(layer "In9.Cu")
		(net "M_E_DQ<47>")
	)
	(segment
		(start 295.450006 -143.763746)
		(end 295.450006 -143.44015)
		(width 0.14224)
		(layer "In9.Cu")
		(net "M_E_DQ<47>")
	)
	(segment
		(start 295.450006 -143.44015)
		(end 295.161208 -143.151352)
		(width 0.14224)
		(layer "In9.Cu")
		(net "M_E_DQ<47>")
	)
	(segment
		(start 295.161208 -142.878048)
		(end 295.418256 -142.621)
		(width 0.14224)
		(layer "In9.Cu")
		(net "M_E_DQ<47>")
	)
	(segment
		(start 296.151808 -131.8768)
		(end 296.151808 -131.484878)
		(width 0.14224)
		(layer "In11.Cu")
		(net "M_E_DQ<47>")
	)
	(segment
		(start 296.371772 -136.037574)
		(end 296.371772 -134.712202)
		(width 0.14224)
		(layer "In11.Cu")
		(net "M_E_DQ<47>")
	)
	(segment
		(start 296.202608 -136.206738)
		(end 296.371772 -136.037574)
		(width 0.14224)
		(layer "In11.Cu")
		(net "M_E_DQ<47>")
	)
	(segment
		(start 296.431208 -130.087878)
		(end 296.202608 -129.859278)
		(width 0.14224)
		(layer "In11.Cu")
		(net "M_E_DQ<47>")
	)
	(segment
		(start 296.2656 -138.7348)
		(end 296.2656 -136.664192)
		(width 0.14224)
		(layer "In11.Cu")
		(net "M_E_DQ<47>")
	)
	(segment
		(start 296.202608 -138.797792)
		(end 296.2656 -138.7348)
		(width 0.14224)
		(layer "In11.Cu")
		(net "M_E_DQ<47>")
	)
	(segment
		(start 296.191686 -139.590272)
		(end 296.202608 -139.590272)
		(width 0.14224)
		(layer "In11.Cu")
		(net "M_E_DQ<47>")
	)
	(segment
		(start 296.2656 -136.664192)
		(end 296.202608 -136.6012)
		(width 0.14224)
		(layer "In11.Cu")
		(net "M_E_DQ<47>")
	)
	(segment
		(start 296.202608 -129.348992)
		(end 295.776396 -128.92278)
		(width 0.14224)
		(layer "In11.Cu")
		(net "M_E_DQ<47>")
	)
	(segment
		(start 296.371772 -134.712202)
		(end 296.228008 -134.568438)
		(width 0.14224)
		(layer "In11.Cu")
		(net "M_E_DQ<47>")
	)
	(segment
		(start 295.849802 -139.932156)
		(end 296.191686 -139.590272)
		(width 0.14224)
		(layer "In11.Cu")
		(net "M_E_DQ<47>")
	)
	(segment
		(start 296.202608 -139.590272)
		(end 296.202608 -138.797792)
		(width 0.14224)
		(layer "In11.Cu")
		(net "M_E_DQ<47>")
	)
	(segment
		(start 296.228008 -134.098792)
		(end 296.291 -134.0358)
		(width 0.14224)
		(layer "In11.Cu")
		(net "M_E_DQ<47>")
	)
	(segment
		(start 295.776396 -128.92278)
		(end 295.776396 -125.43917)
		(width 0.14224)
		(layer "In11.Cu")
		(net "M_E_DQ<47>")
	)
	(segment
		(start 296.431208 -131.205478)
		(end 296.431208 -130.087878)
		(width 0.14224)
		(layer "In11.Cu")
		(net "M_E_DQ<47>")
	)
	(segment
		(start 296.291 -132.015992)
		(end 296.151808 -131.8768)
		(width 0.14224)
		(layer "In11.Cu")
		(net "M_E_DQ<47>")
	)
	(segment
		(start 296.291 -134.0358)
		(end 296.291 -132.015992)
		(width 0.14224)
		(layer "In11.Cu")
		(net "M_E_DQ<47>")
	)
	(segment
		(start 296.202608 -129.859278)
		(end 296.202608 -129.348992)
		(width 0.14224)
		(layer "In11.Cu")
		(net "M_E_DQ<47>")
	)
	(segment
		(start 296.202608 -136.6012)
		(end 296.202608 -136.206738)
		(width 0.14224)
		(layer "In11.Cu")
		(net "M_E_DQ<47>")
	)
	(segment
		(start 296.228008 -134.568438)
		(end 296.228008 -134.098792)
		(width 0.14224)
		(layer "In11.Cu")
		(net "M_E_DQ<47>")
	)
	(segment
		(start 295.776396 -125.43917)
		(end 295.748202 -125.410976)
		(width 0.14224)
		(layer "In11.Cu")
		(net "M_E_DQ<47>")
	)
	(segment
		(start 296.151808 -131.484878)
		(end 296.431208 -131.205478)
		(width 0.14224)
		(layer "In11.Cu")
		(net "M_E_DQ<47>")
	)
	(segment
		(start 281.45232 -108.480098)
		(end 285.303722 -112.3315)
		(width 0.1016)
		(layer "F.Cu")
		(net "M_E_DQ<46>")
	)
	(segment
		(start 295.326562 -121.24055)
		(end 295.459658 -121.107454)
		(width 0.1651)
		(layer "F.Cu")
		(net "M_E_DQ<46>")
	)
	(segment
		(start 281.45232 -105.883964)
		(end 281.45232 -108.480098)
		(width 0.1016)
		(layer "F.Cu")
		(net "M_E_DQ<46>")
	)
	(segment
		(start 294.976296 -120.624092)
		(end 294.842946 -120.757442)
		(width 0.1651)
		(layer "F.Cu")
		(net "M_E_DQ<46>")
	)
	(segment
		(start 281.547062 -105.789222)
		(end 281.45232 -105.883964)
		(width 0.0889)
		(layer "F.Cu")
		(net "M_E_DQ<46>")
	)
	(segment
		(start 290.969192 -117.258592)
		(end 291.858446 -117.258592)
		(width 0.1651)
		(layer "F.Cu")
		(net "M_E_DQ<46>")
	)
	(segment
		(start 294.842946 -120.757442)
		(end 294.842946 -121.004838)
		(width 0.1651)
		(layer "F.Cu")
		(net "M_E_DQ<46>")
	)
	(segment
		(start 286.9819 -113.2713)
		(end 290.969192 -117.258592)
		(width 0.1651)
		(layer "F.Cu")
		(net "M_E_DQ<46>")
	)
	(segment
		(start 281.547062 -104.016556)
		(end 281.547062 -105.789222)
		(width 0.0889)
		(layer "F.Cu")
		(net "M_E_DQ<46>")
	)
	(segment
		(start 295.850056 -146.304)
		(end 295.982136 -146.17192)
		(width 0.1651)
		(layer "F.Cu")
		(net "M_E_DQ<46>")
	)
	(segment
		(start 295.850056 -147.27174)
		(end 295.850056 -146.304)
		(width 0.1651)
		(layer "F.Cu")
		(net "M_E_DQ<46>")
	)
	(segment
		(start 286.474154 -112.3315)
		(end 286.7406 -112.597946)
		(width 0.1016)
		(layer "F.Cu")
		(net "M_E_DQ<46>")
	)
	(segment
		(start 295.4274 -126.188216)
		(end 294.999918 -126.615698)
		(width 0.1651)
		(layer "F.Cu")
		(net "M_E_DQ<46>")
	)
	(segment
		(start 294.842946 -121.004838)
		(end 295.078658 -121.24055)
		(width 0.1651)
		(layer "F.Cu")
		(net "M_E_DQ<46>")
	)
	(segment
		(start 285.303722 -112.3315)
		(end 286.474154 -112.3315)
		(width 0.1016)
		(layer "F.Cu")
		(net "M_E_DQ<46>")
	)
	(segment
		(start 295.850056 -145.516854)
		(end 295.849802 -145.5166)
		(width 0.1651)
		(layer "F.Cu")
		(net "M_E_DQ<46>")
	)
	(segment
		(start 295.4274 -125.73)
		(end 295.4274 -126.188216)
		(width 0.1651)
		(layer "F.Cu")
		(net "M_E_DQ<46>")
	)
	(segment
		(start 286.7406 -113.03)
		(end 286.9819 -113.2713)
		(width 0.1016)
		(layer "F.Cu")
		(net "M_E_DQ<46>")
	)
	(segment
		(start 295.982136 -145.95348)
		(end 295.850056 -145.8214)
		(width 0.1651)
		(layer "F.Cu")
		(net "M_E_DQ<46>")
	)
	(segment
		(start 281.232864 -102.97541)
		(end 281.305254 -103.0478)
		(width 0.0889)
		(layer "F.Cu")
		(net "M_E_DQ<46>")
	)
	(segment
		(start 295.982136 -146.17192)
		(end 295.982136 -145.95348)
		(width 0.1651)
		(layer "F.Cu")
		(net "M_E_DQ<46>")
	)
	(segment
		(start 281.149044 -102.26294)
		(end 281.144218 -102.271576)
		(width 0.0889)
		(layer "F.Cu")
		(net "M_E_DQ<46>")
	)
	(segment
		(start 291.858446 -117.258592)
		(end 294.97655 -120.376696)
		(width 0.1651)
		(layer "F.Cu")
		(net "M_E_DQ<46>")
	)
	(segment
		(start 295.1988 -125.5014)
		(end 295.4274 -125.73)
		(width 0.1651)
		(layer "F.Cu")
		(net "M_E_DQ<46>")
	)
	(segment
		(start 281.165808 -101.243638)
		(end 281.149044 -101.272594)
		(width 0.0889)
		(layer "F.Cu")
		(net "M_E_DQ<46>")
	)
	(segment
		(start 295.459658 -121.107454)
		(end 295.707308 -121.107454)
		(width 0.1651)
		(layer "F.Cu")
		(net "M_E_DQ<46>")
	)
	(segment
		(start 295.078658 -121.24055)
		(end 295.326562 -121.24055)
		(width 0.1651)
		(layer "F.Cu")
		(net "M_E_DQ<46>")
	)
	(segment
		(start 295.1988 -124.0028)
		(end 295.1988 -125.5014)
		(width 0.1651)
		(layer "F.Cu")
		(net "M_E_DQ<46>")
	)
	(segment
		(start 295.707308 -121.107454)
		(end 295.974008 -121.374154)
		(width 0.1651)
		(layer "F.Cu")
		(net "M_E_DQ<46>")
	)
	(segment
		(start 294.97655 -120.376696)
		(end 294.976296 -120.624092)
		(width 0.1651)
		(layer "F.Cu")
		(net "M_E_DQ<46>")
	)
	(segment
		(start 295.85031 -147.27174)
		(end 295.850056 -147.27174)
		(width 0.1651)
		(layer "F.Cu")
		(net "M_E_DQ<46>")
	)
	(segment
		(start 286.7406 -112.597946)
		(end 286.7406 -113.03)
		(width 0.1016)
		(layer "F.Cu")
		(net "M_E_DQ<46>")
	)
	(segment
		(start 295.974008 -123.227592)
		(end 295.1988 -124.0028)
		(width 0.1651)
		(layer "F.Cu")
		(net "M_E_DQ<46>")
	)
	(segment
		(start 281.495754 -100.481638)
		(end 281.165808 -101.243638)
		(width 0.0889)
		(layer "F.Cu")
		(net "M_E_DQ<46>")
	)
	(segment
		(start 295.974008 -121.374154)
		(end 295.974008 -123.227592)
		(width 0.1651)
		(layer "F.Cu")
		(net "M_E_DQ<46>")
	)
	(segment
		(start 281.305254 -103.0478)
		(end 281.305254 -103.774748)
		(width 0.0889)
		(layer "F.Cu")
		(net "M_E_DQ<46>")
	)
	(segment
		(start 281.149044 -101.67239)
		(end 281.155394 -101.683058)
		(width 0.0889)
		(layer "F.Cu")
		(net "M_E_DQ<46>")
	)
	(segment
		(start 295.850056 -145.8214)
		(end 295.850056 -145.516854)
		(width 0.1651)
		(layer "F.Cu")
		(net "M_E_DQ<46>")
	)
	(segment
		(start 281.305254 -103.774748)
		(end 281.547062 -104.016556)
		(width 0.0889)
		(layer "F.Cu")
		(net "M_E_DQ<46>")
	)
	(via
		(at 295.849802 -145.5166)
		(size 0.508)
		(drill 0.254)
		(layers "F.Cu" "B.Cu")
		(net "M_E_DQ<46>")
	)
	(via
		(at 294.999918 -126.615698)
		(size 0.508)
		(drill 0.254)
		(layers "F.Cu" "B.Cu")
		(net "M_E_DQ<46>")
	)
	(via
		(at 294.999918 -141.213078)
		(size 0.508)
		(drill 0.254)
		(layers "F.Cu" "B.Cu")
		(net "M_E_DQ<46>")
	)
	(arc
		(start 281.149044 -102.66299)
		(mid 281.211501 -102.813683)
		(end 281.232864 -102.97541)
		(width 0.0889)
		(layer "F.Cu")
		(net "M_E_DQ<46>")
	)
	(arc
		(start 281.149044 -101.272594)
		(mid 281.095545 -101.472492)
		(end 281.149044 -101.67239)
		(width 0.0889)
		(layer "F.Cu")
		(net "M_E_DQ<46>")
	)
	(arc
		(start 281.155394 -101.683058)
		(mid 281.228192 -101.973821)
		(end 281.149044 -102.26294)
		(width 0.0889)
		(layer "F.Cu")
		(net "M_E_DQ<46>")
	)
	(arc
		(start 281.144218 -102.271576)
		(mid 281.095463 -102.467928)
		(end 281.149044 -102.66299)
		(width 0.0889)
		(layer "F.Cu")
		(net "M_E_DQ<46>")
	)
	(segment
		(start 294.999918 -142.476982)
		(end 294.999918 -141.213078)
		(width 0.1651)
		(layer "B.Cu")
		(net "M_E_DQ<46>")
	)
	(segment
		(start 295.000426 -142.477236)
		(end 294.999918 -142.476982)
		(width 0.1651)
		(layer "B.Cu")
		(net "M_E_DQ<46>")
	)
	(segment
		(start 294.566848 -141.646148)
		(end 294.566848 -144.233646)
		(width 0.14224)
		(layer "In9.Cu")
		(net "M_E_DQ<46>")
	)
	(segment
		(start 294.566848 -144.233646)
		(end 295.849802 -145.5166)
		(width 0.14224)
		(layer "In9.Cu")
		(net "M_E_DQ<46>")
	)
	(segment
		(start 294.999918 -141.213078)
		(end 294.566848 -141.646148)
		(width 0.14224)
		(layer "In9.Cu")
		(net "M_E_DQ<46>")
	)
	(segment
		(start 295.4274 -132.042408)
		(end 295.516808 -131.953)
		(width 0.14224)
		(layer "In11.Cu")
		(net "M_E_DQ<46>")
	)
	(segment
		(start 295.567608 -129.859278)
		(end 295.567608 -129.426208)
		(width 0.14224)
		(layer "In11.Cu")
		(net "M_E_DQ<46>")
	)
	(segment
		(start 295.516808 -131.459478)
		(end 295.364408 -131.307078)
		(width 0.14224)
		(layer "In11.Cu")
		(net "M_E_DQ<46>")
	)
	(segment
		(start 294.831008 -141.044168)
		(end 294.831008 -140.070078)
		(width 0.14224)
		(layer "In11.Cu")
		(net "M_E_DQ<46>")
	)
	(segment
		(start 295.567608 -139.333478)
		(end 295.567608 -138.976608)
		(width 0.14224)
		(layer "In11.Cu")
		(net "M_E_DQ<46>")
	)
	(segment
		(start 295.567608 -129.426208)
		(end 295.115996 -128.974596)
		(width 0.14224)
		(layer "In11.Cu")
		(net "M_E_DQ<46>")
	)
	(segment
		(start 295.4274 -138.8364)
		(end 295.4274 -136.690608)
		(width 0.14224)
		(layer "In11.Cu")
		(net "M_E_DQ<46>")
	)
	(segment
		(start 295.244266 -135.932926)
		(end 295.244266 -134.79018)
		(width 0.14224)
		(layer "In11.Cu")
		(net "M_E_DQ<46>")
	)
	(segment
		(start 294.831008 -140.070078)
		(end 295.567608 -139.333478)
		(width 0.14224)
		(layer "In11.Cu")
		(net "M_E_DQ<46>")
	)
	(segment
		(start 295.115996 -128.974596)
		(end 295.115996 -126.731776)
		(width 0.14224)
		(layer "In11.Cu")
		(net "M_E_DQ<46>")
	)
	(segment
		(start 294.999918 -141.213078)
		(end 294.831008 -141.044168)
		(width 0.14224)
		(layer "In11.Cu")
		(net "M_E_DQ<46>")
	)
	(segment
		(start 295.115996 -126.731776)
		(end 294.999918 -126.615698)
		(width 0.14224)
		(layer "In11.Cu")
		(net "M_E_DQ<46>")
	)
	(segment
		(start 295.244266 -134.79018)
		(end 295.516808 -134.517638)
		(width 0.14224)
		(layer "In11.Cu")
		(net "M_E_DQ<46>")
	)
	(segment
		(start 295.364408 -130.062478)
		(end 295.567608 -129.859278)
		(width 0.14224)
		(layer "In11.Cu")
		(net "M_E_DQ<46>")
	)
	(segment
		(start 295.516808 -134.150608)
		(end 295.4274 -134.0612)
		(width 0.14224)
		(layer "In11.Cu")
		(net "M_E_DQ<46>")
	)
	(segment
		(start 295.516808 -131.953)
		(end 295.516808 -131.459478)
		(width 0.14224)
		(layer "In11.Cu")
		(net "M_E_DQ<46>")
	)
	(segment
		(start 295.4274 -134.0612)
		(end 295.4274 -132.042408)
		(width 0.14224)
		(layer "In11.Cu")
		(net "M_E_DQ<46>")
	)
	(segment
		(start 295.567608 -136.256268)
		(end 295.244266 -135.932926)
		(width 0.14224)
		(layer "In11.Cu")
		(net "M_E_DQ<46>")
	)
	(segment
		(start 295.364408 -131.307078)
		(end 295.364408 -130.062478)
		(width 0.14224)
		(layer "In11.Cu")
		(net "M_E_DQ<46>")
	)
	(segment
		(start 295.567608 -138.976608)
		(end 295.4274 -138.8364)
		(width 0.14224)
		(layer "In11.Cu")
		(net "M_E_DQ<46>")
	)
	(segment
		(start 295.567608 -136.5504)
		(end 295.567608 -136.256268)
		(width 0.14224)
		(layer "In11.Cu")
		(net "M_E_DQ<46>")
	)
	(segment
		(start 295.4274 -136.690608)
		(end 295.567608 -136.5504)
		(width 0.14224)
		(layer "In11.Cu")
		(net "M_E_DQ<46>")
	)
	(segment
		(start 295.516808 -134.517638)
		(end 295.516808 -134.150608)
		(width 0.14224)
		(layer "In11.Cu")
		(net "M_E_DQ<46>")
	)
	(segment
		(start 287.776666 -121.116598)
		(end 288.010346 -121.116598)
		(width 0.1651)
		(layer "F.Cu")
		(net "M_E_DQ<45>")
	)
	(segment
		(start 284.011624 -117.742208)
		(end 284.173676 -117.580156)
		(width 0.1651)
		(layer "F.Cu")
		(net "M_E_DQ<45>")
	)
	(segment
		(start 282.745688 -116.152168)
		(end 282.583636 -116.31422)
		(width 0.1651)
		(layer "F.Cu")
		(net "M_E_DQ<45>")
	)
	(segment
		(start 278.39797 -103.062786)
		(end 278.157686 -103.474012)
		(width 0.0889)
		(layer "F.Cu")
		(net "M_E_DQ<45>")
	)
	(segment
		(start 283.69768 -116.87048)
		(end 283.69768 -117.10416)
		(width 0.1651)
		(layer "F.Cu")
		(net "M_E_DQ<45>")
	)
	(segment
		(start 287.12414 -121.050812)
		(end 287.366456 -121.293128)
		(width 0.1651)
		(layer "F.Cu")
		(net "M_E_DQ<45>")
	)
	(segment
		(start 283.69768 -117.10416)
		(end 283.535628 -117.266212)
		(width 0.1651)
		(layer "F.Cu")
		(net "M_E_DQ<45>")
	)
	(segment
		(start 286.414464 -120.341136)
		(end 286.648144 -120.341136)
		(width 0.1651)
		(layer "F.Cu")
		(net "M_E_DQ<45>")
	)
	(segment
		(start 278.69642 -105.87482)
		(end 278.69642 -109.62386)
		(width 0.1016)
		(layer "F.Cu")
		(net "M_E_DQ<45>")
	)
	(segment
		(start 288.252662 -121.592594)
		(end 288.108644 -121.736612)
		(width 0.1651)
		(layer "F.Cu")
		(net "M_E_DQ<45>")
	)
	(segment
		(start 287.600136 -121.293128)
		(end 287.776666 -121.116598)
		(width 0.1651)
		(layer "F.Cu")
		(net "M_E_DQ<45>")
	)
	(segment
		(start 287.058354 -120.164606)
		(end 287.30067 -120.406922)
		(width 0.1651)
		(layer "F.Cu")
		(net "M_E_DQ<45>")
	)
	(segment
		(start 282.825952 -116.790216)
		(end 283.059632 -116.790216)
		(width 0.1651)
		(layer "F.Cu")
		(net "M_E_DQ<45>")
	)
	(segment
		(start 278.157686 -103.474012)
		(end 278.157686 -103.761286)
		(width 0.0889)
		(layer "F.Cu")
		(net "M_E_DQ<45>")
	)
	(segment
		(start 287.30067 -120.406922)
		(end 287.30067 -120.640602)
		(width 0.1651)
		(layer "F.Cu")
		(net "M_E_DQ<45>")
	)
	(segment
		(start 288.108644 -121.736612)
		(end 288.108644 -121.916444)
		(width 0.1651)
		(layer "F.Cu")
		(net "M_E_DQ<45>")
	)
	(segment
		(start 283.455364 -116.628164)
		(end 283.69768 -116.87048)
		(width 0.1651)
		(layer "F.Cu")
		(net "M_E_DQ<45>")
	)
	(segment
		(start 283.535628 -117.266212)
		(end 283.535628 -117.499892)
		(width 0.1651)
		(layer "F.Cu")
		(net "M_E_DQ<45>")
	)
	(segment
		(start 278.573484 -101.76764)
		(end 278.568658 -101.776276)
		(width 0.0889)
		(layer "F.Cu")
		(net "M_E_DQ<45>")
	)
	(segment
		(start 290.230306 -123.103894)
		(end 289.823652 -123.510548)
		(width 0.1651)
		(layer "F.Cu")
		(net "M_E_DQ<45>")
	)
	(segment
		(start 283.535628 -117.499892)
		(end 283.777944 -117.742208)
		(width 0.1651)
		(layer "F.Cu")
		(net "M_E_DQ<45>")
	)
	(segment
		(start 288.108644 -121.916444)
		(end 288.404808 -122.212608)
		(width 0.1651)
		(layer "F.Cu")
		(net "M_E_DQ<45>")
	)
	(segment
		(start 286.648144 -120.341136)
		(end 286.824674 -120.164606)
		(width 0.1651)
		(layer "F.Cu")
		(net "M_E_DQ<45>")
	)
	(segment
		(start 282.745688 -115.918488)
		(end 282.745688 -116.152168)
		(width 0.1651)
		(layer "F.Cu")
		(net "M_E_DQ<45>")
	)
	(segment
		(start 282.0924 -113.01984)
		(end 282.0924 -114.3762)
		(width 0.1016)
		(layer "F.Cu")
		(net "M_E_DQ<45>")
	)
	(segment
		(start 284.407356 -117.580156)
		(end 286.137858 -119.310658)
		(width 0.1651)
		(layer "F.Cu")
		(net "M_E_DQ<45>")
	)
	(segment
		(start 289.156648 -121.6406)
		(end 289.5854 -121.6406)
		(width 0.1651)
		(layer "F.Cu")
		(net "M_E_DQ<45>")
	)
	(segment
		(start 278.57196 -102.765098)
		(end 278.39797 -103.062786)
		(width 0.0889)
		(layer "F.Cu")
		(net "M_E_DQ<45>")
	)
	(segment
		(start 282.194 -115.3668)
		(end 282.745688 -115.918488)
		(width 0.1651)
		(layer "F.Cu")
		(net "M_E_DQ<45>")
	)
	(segment
		(start 283.059632 -116.790216)
		(end 283.221684 -116.628164)
		(width 0.1651)
		(layer "F.Cu")
		(net "M_E_DQ<45>")
	)
	(segment
		(start 282.194 -114.4778)
		(end 282.194 -115.3668)
		(width 0.1651)
		(layer "F.Cu")
		(net "M_E_DQ<45>")
	)
	(segment
		(start 288.010346 -121.116598)
		(end 288.252662 -121.358914)
		(width 0.1651)
		(layer "F.Cu")
		(net "M_E_DQ<45>")
	)
	(segment
		(start 286.137858 -120.06453)
		(end 286.414464 -120.341136)
		(width 0.1651)
		(layer "F.Cu")
		(net "M_E_DQ<45>")
	)
	(segment
		(start 287.30067 -120.640602)
		(end 287.12414 -120.817132)
		(width 0.1651)
		(layer "F.Cu")
		(net "M_E_DQ<45>")
	)
	(segment
		(start 289.050476 -142.6718)
		(end 289.049968 -142.677642)
		(width 0.1651)
		(layer "F.Cu")
		(net "M_E_DQ<45>")
	)
	(segment
		(start 287.366456 -121.293128)
		(end 287.600136 -121.293128)
		(width 0.1651)
		(layer "F.Cu")
		(net "M_E_DQ<45>")
	)
	(segment
		(start 278.59482 -105.77322)
		(end 278.69642 -105.87482)
		(width 0.0889)
		(layer "F.Cu")
		(net "M_E_DQ<45>")
	)
	(segment
		(start 289.5854 -121.6406)
		(end 290.230306 -122.285506)
		(width 0.1651)
		(layer "F.Cu")
		(net "M_E_DQ<45>")
	)
	(segment
		(start 287.12414 -120.817132)
		(end 287.12414 -121.050812)
		(width 0.1651)
		(layer "F.Cu")
		(net "M_E_DQ<45>")
	)
	(segment
		(start 282.0924 -114.3762)
		(end 282.194 -114.4778)
		(width 0.1651)
		(layer "F.Cu")
		(net "M_E_DQ<45>")
	)
	(segment
		(start 286.137858 -119.310658)
		(end 286.137858 -120.06453)
		(width 0.1651)
		(layer "F.Cu")
		(net "M_E_DQ<45>")
	)
	(segment
		(start 278.157686 -103.761286)
		(end 278.59482 -104.19842)
		(width 0.0889)
		(layer "F.Cu")
		(net "M_E_DQ<45>")
	)
	(segment
		(start 278.69642 -109.62386)
		(end 282.0924 -113.01984)
		(width 0.1016)
		(layer "F.Cu")
		(net "M_E_DQ<45>")
	)
	(segment
		(start 288.58464 -122.212608)
		(end 289.156648 -121.6406)
		(width 0.1651)
		(layer "F.Cu")
		(net "M_E_DQ<45>")
	)
	(segment
		(start 290.230306 -122.285506)
		(end 290.230306 -123.103894)
		(width 0.1651)
		(layer "F.Cu")
		(net "M_E_DQ<45>")
	)
	(segment
		(start 283.777944 -117.742208)
		(end 284.011624 -117.742208)
		(width 0.1651)
		(layer "F.Cu")
		(net "M_E_DQ<45>")
	)
	(segment
		(start 284.173676 -117.580156)
		(end 284.407356 -117.580156)
		(width 0.1651)
		(layer "F.Cu")
		(net "M_E_DQ<45>")
	)
	(segment
		(start 282.583636 -116.31422)
		(end 282.583636 -116.5479)
		(width 0.1651)
		(layer "F.Cu")
		(net "M_E_DQ<45>")
	)
	(segment
		(start 288.252662 -121.358914)
		(end 288.252662 -121.592594)
		(width 0.1651)
		(layer "F.Cu")
		(net "M_E_DQ<45>")
	)
	(segment
		(start 289.823652 -123.510548)
		(end 289.823652 -124.750576)
		(width 0.1651)
		(layer "F.Cu")
		(net "M_E_DQ<45>")
	)
	(segment
		(start 282.583636 -116.5479)
		(end 282.825952 -116.790216)
		(width 0.1651)
		(layer "F.Cu")
		(net "M_E_DQ<45>")
	)
	(segment
		(start 286.824674 -120.164606)
		(end 287.058354 -120.164606)
		(width 0.1651)
		(layer "F.Cu")
		(net "M_E_DQ<45>")
	)
	(segment
		(start 278.59482 -104.19842)
		(end 278.59482 -105.77322)
		(width 0.0889)
		(layer "F.Cu")
		(net "M_E_DQ<45>")
	)
	(segment
		(start 288.404808 -122.212608)
		(end 288.58464 -122.212608)
		(width 0.1651)
		(layer "F.Cu")
		(net "M_E_DQ<45>")
	)
	(segment
		(start 289.049968 -142.677642)
		(end 289.049968 -143.941546)
		(width 0.1651)
		(layer "F.Cu")
		(net "M_E_DQ<45>")
	)
	(segment
		(start 283.221684 -116.628164)
		(end 283.455364 -116.628164)
		(width 0.1651)
		(layer "F.Cu")
		(net "M_E_DQ<45>")
	)
	(via
		(at 289.823652 -139.932156)
		(size 0.508)
		(drill 0.254)
		(layers "F.Cu" "B.Cu")
		(net "M_E_DQ<45>")
	)
	(via
		(at 289.049968 -143.941546)
		(size 0.508)
		(drill 0.254)
		(layers "F.Cu" "B.Cu")
		(net "M_E_DQ<45>")
	)
	(via
		(at 289.823652 -124.750576)
		(size 0.508)
		(drill 0.254)
		(layers "F.Cu" "B.Cu")
		(net "M_E_DQ<45>")
	)
	(arc
		(start 278.568658 -101.776276)
		(mid 278.519903 -101.972628)
		(end 278.573484 -102.16769)
		(width 0.0889)
		(layer "F.Cu")
		(net "M_E_DQ<45>")
	)
	(arc
		(start 278.573484 -102.16769)
		(mid 278.653221 -102.466605)
		(end 278.57196 -102.765098)
		(width 0.0889)
		(layer "F.Cu")
		(net "M_E_DQ<45>")
	)
	(arc
		(start 278.920194 -100.976684)
		(mid 278.765937 -101.380534)
		(end 278.573484 -101.76764)
		(width 0.0889)
		(layer "F.Cu")
		(net "M_E_DQ<45>")
	)
	(segment
		(start 289.899852 -137.877296)
		(end 289.899852 -139.855956)
		(width 0.1651)
		(layer "B.Cu")
		(net "M_E_DQ<45>")
	)
	(segment
		(start 289.899852 -139.855956)
		(end 289.823652 -139.932156)
		(width 0.1651)
		(layer "B.Cu")
		(net "M_E_DQ<45>")
	)
	(segment
		(start 289.90036 -137.877296)
		(end 289.899852 -137.877296)
		(width 0.1651)
		(layer "B.Cu")
		(net "M_E_DQ<45>")
	)
	(segment
		(start 289.449256 -142.392654)
		(end 289.211258 -142.154656)
		(width 0.14224)
		(layer "In9.Cu")
		(net "M_E_DQ<45>")
	)
	(segment
		(start 289.500056 -141.528546)
		(end 289.500056 -141.0462)
		(width 0.14224)
		(layer "In9.Cu")
		(net "M_E_DQ<45>")
	)
	(segment
		(start 289.211258 -141.817344)
		(end 289.500056 -141.528546)
		(width 0.14224)
		(layer "In9.Cu")
		(net "M_E_DQ<45>")
	)
	(segment
		(start 289.211258 -142.154656)
		(end 289.211258 -141.817344)
		(width 0.14224)
		(layer "In9.Cu")
		(net "M_E_DQ<45>")
	)
	(segment
		(start 289.211258 -142.985744)
		(end 289.449256 -142.747746)
		(width 0.14224)
		(layer "In9.Cu")
		(net "M_E_DQ<45>")
	)
	(segment
		(start 289.474656 -143.789146)
		(end 289.474656 -143.561054)
		(width 0.14224)
		(layer "In9.Cu")
		(net "M_E_DQ<45>")
	)
	(segment
		(start 289.373056 -140.3604)
		(end 289.8013 -139.932156)
		(width 0.14224)
		(layer "In9.Cu")
		(net "M_E_DQ<45>")
	)
	(segment
		(start 289.474656 -143.561054)
		(end 289.211258 -143.297656)
		(width 0.14224)
		(layer "In9.Cu")
		(net "M_E_DQ<45>")
	)
	(segment
		(start 289.322256 -143.941546)
		(end 289.474656 -143.789146)
		(width 0.14224)
		(layer "In9.Cu")
		(net "M_E_DQ<45>")
	)
	(segment
		(start 289.8013 -139.932156)
		(end 289.823652 -139.932156)
		(width 0.14224)
		(layer "In9.Cu")
		(net "M_E_DQ<45>")
	)
	(segment
		(start 289.500056 -141.0462)
		(end 289.373056 -140.9192)
		(width 0.14224)
		(layer "In9.Cu")
		(net "M_E_DQ<45>")
	)
	(segment
		(start 289.449256 -142.747746)
		(end 289.449256 -142.392654)
		(width 0.14224)
		(layer "In9.Cu")
		(net "M_E_DQ<45>")
	)
	(segment
		(start 289.211258 -143.297656)
		(end 289.211258 -142.985744)
		(width 0.14224)
		(layer "In9.Cu")
		(net "M_E_DQ<45>")
	)
	(segment
		(start 289.373056 -140.9192)
		(end 289.373056 -140.3604)
		(width 0.14224)
		(layer "In9.Cu")
		(net "M_E_DQ<45>")
	)
	(segment
		(start 289.049968 -143.941546)
		(end 289.322256 -143.941546)
		(width 0.14224)
		(layer "In9.Cu")
		(net "M_E_DQ<45>")
	)
	(segment
		(start 290.360608 -134.797038)
		(end 290.233608 -134.670038)
		(width 0.14224)
		(layer "In11.Cu")
		(net "M_E_DQ<45>")
	)
	(segment
		(start 290.208208 -136.005824)
		(end 290.360608 -135.853424)
		(width 0.14224)
		(layer "In11.Cu")
		(net "M_E_DQ<45>")
	)
	(segment
		(start 290.208208 -138.823192)
		(end 290.322 -138.7094)
		(width 0.14224)
		(layer "In11.Cu")
		(net "M_E_DQ<45>")
	)
	(segment
		(start 290.322 -134.0612)
		(end 290.322 -131.939792)
		(width 0.14224)
		(layer "In11.Cu")
		(net "M_E_DQ<45>")
	)
	(segment
		(start 290.322 -136.664192)
		(end 290.208208 -136.5504)
		(width 0.14224)
		(layer "In11.Cu")
		(net "M_E_DQ<45>")
	)
	(segment
		(start 290.208208 -136.5504)
		(end 290.208208 -136.005824)
		(width 0.14224)
		(layer "In11.Cu")
		(net "M_E_DQ<45>")
	)
	(segment
		(start 290.289996 -125.558804)
		(end 290.289996 -125.21692)
		(width 0.14224)
		(layer "In11.Cu")
		(net "M_E_DQ<45>")
	)
	(segment
		(start 290.297108 -131.370578)
		(end 290.297108 -129.795778)
		(width 0.14224)
		(layer "In11.Cu")
		(net "M_E_DQ<45>")
	)
	(segment
		(start 289.823652 -139.932156)
		(end 290.208208 -139.5476)
		(width 0.14224)
		(layer "In11.Cu")
		(net "M_E_DQ<45>")
	)
	(segment
		(start 290.297108 -129.795778)
		(end 290.208208 -129.706878)
		(width 0.14224)
		(layer "In11.Cu")
		(net "M_E_DQ<45>")
	)
	(segment
		(start 290.322 -138.7094)
		(end 290.322 -136.664192)
		(width 0.14224)
		(layer "In11.Cu")
		(net "M_E_DQ<45>")
	)
	(segment
		(start 290.06419 -126.762002)
		(end 290.06419 -125.78461)
		(width 0.14224)
		(layer "In11.Cu")
		(net "M_E_DQ<45>")
	)
	(segment
		(start 290.233608 -134.670038)
		(end 290.233608 -134.149592)
		(width 0.14224)
		(layer "In11.Cu")
		(net "M_E_DQ<45>")
	)
	(segment
		(start 290.233608 -131.434078)
		(end 290.297108 -131.370578)
		(width 0.14224)
		(layer "In11.Cu")
		(net "M_E_DQ<45>")
	)
	(segment
		(start 290.322 -131.939792)
		(end 290.233608 -131.8514)
		(width 0.14224)
		(layer "In11.Cu")
		(net "M_E_DQ<45>")
	)
	(segment
		(start 290.233608 -131.8514)
		(end 290.233608 -131.434078)
		(width 0.14224)
		(layer "In11.Cu")
		(net "M_E_DQ<45>")
	)
	(segment
		(start 290.06419 -125.78461)
		(end 290.289996 -125.558804)
		(width 0.14224)
		(layer "In11.Cu")
		(net "M_E_DQ<45>")
	)
	(segment
		(start 290.233608 -134.149592)
		(end 290.322 -134.0612)
		(width 0.14224)
		(layer "In11.Cu")
		(net "M_E_DQ<45>")
	)
	(segment
		(start 290.208208 -129.706878)
		(end 290.208208 -126.90602)
		(width 0.14224)
		(layer "In11.Cu")
		(net "M_E_DQ<45>")
	)
	(segment
		(start 290.208208 -139.5476)
		(end 290.208208 -138.823192)
		(width 0.14224)
		(layer "In11.Cu")
		(net "M_E_DQ<45>")
	)
	(segment
		(start 290.289996 -125.21692)
		(end 289.823652 -124.750576)
		(width 0.14224)
		(layer "In11.Cu")
		(net "M_E_DQ<45>")
	)
	(segment
		(start 290.360608 -135.853424)
		(end 290.360608 -134.797038)
		(width 0.14224)
		(layer "In11.Cu")
		(net "M_E_DQ<45>")
	)
	(segment
		(start 290.208208 -126.90602)
		(end 290.06419 -126.762002)
		(width 0.14224)
		(layer "In11.Cu")
		(net "M_E_DQ<45>")
	)
	(segment
		(start 278.30272 -105.87228)
		(end 278.30272 -109.787182)
		(width 0.1016)
		(layer "F.Cu")
		(net "M_E_DQ<44>")
	)
	(segment
		(start 285.251652 -119.370348)
		(end 285.493968 -119.612664)
		(width 0.1651)
		(layer "F.Cu")
		(net "M_E_DQ<44>")
	)
	(segment
		(start 278.30272 -109.787182)
		(end 281.6352 -113.119662)
		(width 0.1016)
		(layer "F.Cu")
		(net "M_E_DQ<44>")
	)
	(segment
		(start 289.90036 -147.27174)
		(end 289.899852 -147.27174)
		(width 0.1651)
		(layer "F.Cu")
		(net "M_E_DQ<44>")
	)
	(segment
		(start 284.62732 -119.52732)
		(end 284.861 -119.52732)
		(width 0.1651)
		(layer "F.Cu")
		(net "M_E_DQ<44>")
	)
	(segment
		(start 278.40432 -105.77068)
		(end 278.30272 -105.87228)
		(width 0.0889)
		(layer "F.Cu")
		(net "M_E_DQ<44>")
	)
	(segment
		(start 289.179 -124.9934)
		(end 289.3568 -125.1712)
		(width 0.1651)
		(layer "F.Cu")
		(net "M_E_DQ<44>")
	)
	(segment
		(start 283.918914 -118.565422)
		(end 284.06598 -118.418356)
		(width 0.1651)
		(layer "F.Cu")
		(net "M_E_DQ<44>")
	)
	(segment
		(start 289.3568 -125.603)
		(end 289.5092 -125.7554)
		(width 0.1651)
		(layer "F.Cu")
		(net "M_E_DQ<44>")
	)
	(segment
		(start 285.017972 -119.370348)
		(end 285.251652 -119.370348)
		(width 0.1651)
		(layer "F.Cu")
		(net "M_E_DQ<44>")
	)
	(segment
		(start 284.541976 -118.660672)
		(end 284.541976 -118.894352)
		(width 0.1651)
		(layer "F.Cu")
		(net "M_E_DQ<44>")
	)
	(segment
		(start 284.541976 -118.894352)
		(end 284.385004 -119.051324)
		(width 0.1651)
		(layer "F.Cu")
		(net "M_E_DQ<44>")
	)
	(segment
		(start 288.9758 -122.9614)
		(end 289.179 -123.1646)
		(width 0.1651)
		(layer "F.Cu")
		(net "M_E_DQ<44>")
	)
	(segment
		(start 289.899852 -147.27174)
		(end 289.899852 -145.946368)
		(width 0.1651)
		(layer "F.Cu")
		(net "M_E_DQ<44>")
	)
	(segment
		(start 289.899852 -145.946368)
		(end 289.801808 -145.415)
		(width 0.1651)
		(layer "F.Cu")
		(net "M_E_DQ<44>")
	)
	(segment
		(start 278.177498 -103.062786)
		(end 277.967186 -103.423212)
		(width 0.0889)
		(layer "F.Cu")
		(net "M_E_DQ<44>")
	)
	(segment
		(start 283.685234 -118.565422)
		(end 283.918914 -118.565422)
		(width 0.1651)
		(layer "F.Cu")
		(net "M_E_DQ<44>")
	)
	(segment
		(start 281.432 -116.312188)
		(end 283.685234 -118.565422)
		(width 0.1651)
		(layer "F.Cu")
		(net "M_E_DQ<44>")
	)
	(segment
		(start 277.967186 -103.85044)
		(end 278.40432 -104.287574)
		(width 0.0889)
		(layer "F.Cu")
		(net "M_E_DQ<44>")
	)
	(segment
		(start 278.411178 -102.662228)
		(end 278.177498 -103.062786)
		(width 0.0889)
		(layer "F.Cu")
		(net "M_E_DQ<44>")
	)
	(segment
		(start 284.385004 -119.285004)
		(end 284.62732 -119.52732)
		(width 0.1651)
		(layer "F.Cu")
		(net "M_E_DQ<44>")
	)
	(segment
		(start 285.346902 -119.99341)
		(end 285.346902 -120.22709)
		(width 0.1651)
		(layer "F.Cu")
		(net "M_E_DQ<44>")
	)
	(segment
		(start 285.493968 -119.846344)
		(end 285.346902 -119.99341)
		(width 0.1651)
		(layer "F.Cu")
		(net "M_E_DQ<44>")
	)
	(segment
		(start 289.3568 -125.1712)
		(end 289.3568 -125.603)
		(width 0.1651)
		(layer "F.Cu")
		(net "M_E_DQ<44>")
	)
	(segment
		(start 284.06598 -118.418356)
		(end 284.29966 -118.418356)
		(width 0.1651)
		(layer "F.Cu")
		(net "M_E_DQ<44>")
	)
	(segment
		(start 289.179 -123.1646)
		(end 289.179 -124.9934)
		(width 0.1651)
		(layer "F.Cu")
		(net "M_E_DQ<44>")
	)
	(segment
		(start 284.385004 -119.051324)
		(end 284.385004 -119.285004)
		(width 0.1651)
		(layer "F.Cu")
		(net "M_E_DQ<44>")
	)
	(segment
		(start 289.5092 -126.156466)
		(end 289.049968 -126.615698)
		(width 0.1651)
		(layer "F.Cu")
		(net "M_E_DQ<44>")
	)
	(segment
		(start 278.40432 -104.287574)
		(end 278.40432 -105.77068)
		(width 0.0889)
		(layer "F.Cu")
		(net "M_E_DQ<44>")
	)
	(segment
		(start 288.081212 -122.9614)
		(end 288.9758 -122.9614)
		(width 0.1651)
		(layer "F.Cu")
		(net "M_E_DQ<44>")
	)
	(segment
		(start 285.346902 -120.22709)
		(end 288.081212 -122.9614)
		(width 0.1651)
		(layer "F.Cu")
		(net "M_E_DQ<44>")
	)
	(segment
		(start 281.6352 -114.4524)
		(end 281.432 -114.6556)
		(width 0.1016)
		(layer "F.Cu")
		(net "M_E_DQ<44>")
	)
	(segment
		(start 281.6352 -113.119662)
		(end 281.6352 -114.4524)
		(width 0.1016)
		(layer "F.Cu")
		(net "M_E_DQ<44>")
	)
	(segment
		(start 284.29966 -118.418356)
		(end 284.541976 -118.660672)
		(width 0.1651)
		(layer "F.Cu")
		(net "M_E_DQ<44>")
	)
	(segment
		(start 284.861 -119.52732)
		(end 285.017972 -119.370348)
		(width 0.1651)
		(layer "F.Cu")
		(net "M_E_DQ<44>")
	)
	(segment
		(start 277.967186 -103.423212)
		(end 277.967186 -103.85044)
		(width 0.0889)
		(layer "F.Cu")
		(net "M_E_DQ<44>")
	)
	(segment
		(start 281.432 -114.6556)
		(end 281.432 -116.312188)
		(width 0.1651)
		(layer "F.Cu")
		(net "M_E_DQ<44>")
	)
	(segment
		(start 289.5092 -125.7554)
		(end 289.5092 -126.156466)
		(width 0.1651)
		(layer "F.Cu")
		(net "M_E_DQ<44>")
	)
	(segment
		(start 285.493968 -119.612664)
		(end 285.493968 -119.846344)
		(width 0.1651)
		(layer "F.Cu")
		(net "M_E_DQ<44>")
	)
	(via
		(at 289.801808 -145.415)
		(size 0.508)
		(drill 0.254)
		(layers "F.Cu" "B.Cu")
		(net "M_E_DQ<44>")
	)
	(via
		(at 289.049968 -126.615698)
		(size 0.508)
		(drill 0.254)
		(layers "F.Cu" "B.Cu")
		(net "M_E_DQ<44>")
	)
	(via
		(at 289.049968 -141.213078)
		(size 0.508)
		(drill 0.254)
		(layers "F.Cu" "B.Cu")
		(net "M_E_DQ<44>")
	)
	(arc
		(start 278.408384 -101.672136)
		(mid 278.329253 -101.967538)
		(end 278.408384 -102.26294)
		(width 0.0889)
		(layer "F.Cu")
		(net "M_E_DQ<44>")
	)
	(arc
		(start 278.573484 -100.776786)
		(mid 278.552534 -100.818625)
		(end 278.536654 -100.862638)
		(width 0.0889)
		(layer "F.Cu")
		(net "M_E_DQ<44>")
	)
	(arc
		(start 278.520906 -101.002084)
		(mid 278.50335 -101.343612)
		(end 278.408384 -101.672136)
		(width 0.0889)
		(layer "F.Cu")
		(net "M_E_DQ<44>")
	)
	(arc
		(start 279.778714 -100.481638)
		(mid 279.345787 -100.546721)
		(end 278.909018 -100.576634)
		(width 0.0889)
		(layer "F.Cu")
		(net "M_E_DQ<44>")
	)
	(arc
		(start 278.909018 -100.576634)
		(mid 278.715168 -100.632984)
		(end 278.573484 -100.776786)
		(width 0.0889)
		(layer "F.Cu")
		(net "M_E_DQ<44>")
	)
	(arc
		(start 278.408384 -102.26294)
		(mid 278.462539 -102.462225)
		(end 278.411178 -102.662228)
		(width 0.0889)
		(layer "F.Cu")
		(net "M_E_DQ<44>")
	)
	(arc
		(start 278.536654 -100.862638)
		(mid 278.522598 -100.931665)
		(end 278.520906 -101.002084)
		(width 0.0889)
		(layer "F.Cu")
		(net "M_E_DQ<44>")
	)
	(segment
		(start 289.049968 -142.476982)
		(end 289.049968 -141.213078)
		(width 0.1651)
		(layer "B.Cu")
		(net "M_E_DQ<44>")
	)
	(segment
		(start 289.050476 -142.477236)
		(end 289.049968 -142.476982)
		(width 0.1651)
		(layer "B.Cu")
		(net "M_E_DQ<44>")
	)
	(segment
		(start 289.049968 -141.213078)
		(end 288.616898 -141.646148)
		(width 0.14224)
		(layer "In9.Cu")
		(net "M_E_DQ<44>")
	)
	(segment
		(start 288.616898 -141.646148)
		(end 288.616898 -144.17929)
		(width 0.14224)
		(layer "In9.Cu")
		(net "M_E_DQ<44>")
	)
	(segment
		(start 288.774886 -144.337278)
		(end 288.774886 -144.63903)
		(width 0.14224)
		(layer "In9.Cu")
		(net "M_E_DQ<44>")
	)
	(segment
		(start 288.616898 -144.17929)
		(end 288.774886 -144.337278)
		(width 0.14224)
		(layer "In9.Cu")
		(net "M_E_DQ<44>")
	)
	(segment
		(start 289.550856 -145.415)
		(end 289.801808 -145.415)
		(width 0.14224)
		(layer "In9.Cu")
		(net "M_E_DQ<44>")
	)
	(segment
		(start 288.774886 -144.63903)
		(end 289.550856 -145.415)
		(width 0.14224)
		(layer "In9.Cu")
		(net "M_E_DQ<44>")
	)
	(segment
		(start 289.4838 -138.7856)
		(end 289.4838 -136.652508)
		(width 0.14224)
		(layer "In11.Cu")
		(net "M_E_DQ<44>")
	)
	(segment
		(start 289.4838 -132.042408)
		(end 289.547808 -131.9784)
		(width 0.14224)
		(layer "In11.Cu")
		(net "M_E_DQ<44>")
	)
	(segment
		(start 289.319208 -129.986278)
		(end 289.573208 -129.732278)
		(width 0.14224)
		(layer "In11.Cu")
		(net "M_E_DQ<44>")
	)
	(segment
		(start 289.4838 -129.209546)
		(end 289.4838 -127.04953)
		(width 0.14224)
		(layer "In11.Cu")
		(net "M_E_DQ<44>")
	)
	(segment
		(start 289.573208 -129.298954)
		(end 289.4838 -129.209546)
		(width 0.14224)
		(layer "In11.Cu")
		(net "M_E_DQ<44>")
	)
	(segment
		(start 289.547808 -134.176008)
		(end 289.4838 -134.112)
		(width 0.14224)
		(layer "In11.Cu")
		(net "M_E_DQ<44>")
	)
	(segment
		(start 289.281616 -135.926576)
		(end 289.281616 -134.746238)
		(width 0.14224)
		(layer "In11.Cu")
		(net "M_E_DQ<44>")
	)
	(segment
		(start 289.281616 -134.746238)
		(end 289.547808 -134.480046)
		(width 0.14224)
		(layer "In11.Cu")
		(net "M_E_DQ<44>")
	)
	(segment
		(start 289.4838 -134.112)
		(end 289.4838 -132.042408)
		(width 0.14224)
		(layer "In11.Cu")
		(net "M_E_DQ<44>")
	)
	(segment
		(start 289.048952 -141.212062)
		(end 289.048952 -139.9794)
		(width 0.1016)
		(layer "In11.Cu")
		(net "M_E_DQ<44>")
	)
	(segment
		(start 289.048952 -139.9794)
		(end 289.535108 -139.493244)
		(width 0.14224)
		(layer "In11.Cu")
		(net "M_E_DQ<44>")
	)
	(segment
		(start 289.4838 -136.652508)
		(end 289.535108 -136.6012)
		(width 0.14224)
		(layer "In11.Cu")
		(net "M_E_DQ<44>")
	)
	(segment
		(start 289.535108 -136.6012)
		(end 289.535108 -136.180068)
		(width 0.14224)
		(layer "In11.Cu")
		(net "M_E_DQ<44>")
	)
	(segment
		(start 289.547808 -131.408678)
		(end 289.319208 -131.180078)
		(width 0.14224)
		(layer "In11.Cu")
		(net "M_E_DQ<44>")
	)
	(segment
		(start 289.547808 -131.9784)
		(end 289.547808 -131.408678)
		(width 0.14224)
		(layer "In11.Cu")
		(net "M_E_DQ<44>")
	)
	(segment
		(start 289.535108 -136.180068)
		(end 289.281616 -135.926576)
		(width 0.14224)
		(layer "In11.Cu")
		(net "M_E_DQ<44>")
	)
	(segment
		(start 289.049968 -141.213078)
		(end 289.048952 -141.212062)
		(width 0.1016)
		(layer "In11.Cu")
		(net "M_E_DQ<44>")
	)
	(segment
		(start 289.547808 -134.480046)
		(end 289.547808 -134.176008)
		(width 0.14224)
		(layer "In11.Cu")
		(net "M_E_DQ<44>")
	)
	(segment
		(start 289.319208 -131.180078)
		(end 289.319208 -129.986278)
		(width 0.14224)
		(layer "In11.Cu")
		(net "M_E_DQ<44>")
	)
	(segment
		(start 289.573208 -129.732278)
		(end 289.573208 -129.298954)
		(width 0.14224)
		(layer "In11.Cu")
		(net "M_E_DQ<44>")
	)
	(segment
		(start 289.535108 -139.493244)
		(end 289.535108 -138.836908)
		(width 0.14224)
		(layer "In11.Cu")
		(net "M_E_DQ<44>")
	)
	(segment
		(start 289.535108 -138.836908)
		(end 289.4838 -138.7856)
		(width 0.14224)
		(layer "In11.Cu")
		(net "M_E_DQ<44>")
	)
	(segment
		(start 289.4838 -127.04953)
		(end 289.049968 -126.615698)
		(width 0.14224)
		(layer "In11.Cu")
		(net "M_E_DQ<44>")
	)
	(segment
		(start 295.17467 -116.370862)
		(end 295.33977 -116.535962)
		(width 0.1651)
		(layer "F.Cu")
		(net "M_E_DQ<43>")
	)
	(segment
		(start 290.984432 -114.327432)
		(end 292.486334 -114.327432)
		(width 0.1651)
		(layer "F.Cu")
		(net "M_E_DQ<43>")
	)
	(segment
		(start 295.33977 -117.209062)
		(end 295.17467 -117.374162)
		(width 0.1651)
		(layer "F.Cu")
		(net "M_E_DQ<43>")
	)
	(segment
		(start 295.899586 -116.535962)
		(end 296.064686 -116.701062)
		(width 0.1651)
		(layer "F.Cu")
		(net "M_E_DQ<43>")
	)
	(segment
		(start 285.793688 -111.1504)
		(end 287.0962 -111.1504)
		(width 0.1016)
		(layer "F.Cu")
		(net "M_E_DQ<43>")
	)
	(segment
		(start 281.974544 -103.27894)
		(end 282.53182 -103.836216)
		(width 0.0889)
		(layer "F.Cu")
		(net "M_E_DQ<43>")
	)
	(segment
		(start 296.700448 -142.6718)
		(end 296.69994 -142.677642)
		(width 0.1651)
		(layer "F.Cu")
		(net "M_E_DQ<43>")
	)
	(segment
		(start 297.815 -124.1552)
		(end 297.815 -124.968)
		(width 0.1651)
		(layer "F.Cu")
		(net "M_E_DQ<43>")
	)
	(segment
		(start 282.354274 -101.967538)
		(end 282.041092 -102.690168)
		(width 0.0889)
		(layer "F.Cu")
		(net "M_E_DQ<43>")
	)
	(segment
		(start 282.63342 -105.87228)
		(end 282.63342 -107.990132)
		(width 0.1016)
		(layer "F.Cu")
		(net "M_E_DQ<43>")
	)
	(segment
		(start 288.1376 -112.1918)
		(end 288.8488 -112.1918)
		(width 0.1016)
		(layer "F.Cu")
		(net "M_E_DQ<43>")
	)
	(segment
		(start 282.53182 -103.836216)
		(end 282.53182 -105.77068)
		(width 0.0889)
		(layer "F.Cu")
		(net "M_E_DQ<43>")
	)
	(segment
		(start 282.63342 -107.990132)
		(end 285.793688 -111.1504)
		(width 0.1016)
		(layer "F.Cu")
		(net "M_E_DQ<43>")
	)
	(segment
		(start 288.8488 -112.1918)
		(end 290.984432 -114.327432)
		(width 0.1651)
		(layer "F.Cu")
		(net "M_E_DQ<43>")
	)
	(segment
		(start 295.17467 -117.374162)
		(end 295.17467 -117.675152)
		(width 0.1651)
		(layer "F.Cu")
		(net "M_E_DQ<43>")
	)
	(segment
		(start 297.815 -124.968)
		(end 297.346624 -125.436376)
		(width 0.1651)
		(layer "F.Cu")
		(net "M_E_DQ<43>")
	)
	(segment
		(start 281.974544 -102.88143)
		(end 281.974544 -103.27894)
		(width 0.0889)
		(layer "F.Cu")
		(net "M_E_DQ<43>")
	)
	(segment
		(start 292.486334 -114.327432)
		(end 293.438834 -115.279932)
		(width 0.1651)
		(layer "F.Cu")
		(net "M_E_DQ<43>")
	)
	(segment
		(start 296.064686 -116.701062)
		(end 296.064686 -117.043962)
		(width 0.1651)
		(layer "F.Cu")
		(net "M_E_DQ<43>")
	)
	(segment
		(start 295.899586 -117.209062)
		(end 295.33977 -117.209062)
		(width 0.1651)
		(layer "F.Cu")
		(net "M_E_DQ<43>")
	)
	(segment
		(start 297.942 -124.0282)
		(end 297.815 -124.1552)
		(width 0.1651)
		(layer "F.Cu")
		(net "M_E_DQ<43>")
	)
	(segment
		(start 297.942 -120.442482)
		(end 297.942 -124.0282)
		(width 0.1651)
		(layer "F.Cu")
		(net "M_E_DQ<43>")
	)
	(segment
		(start 287.0962 -111.1504)
		(end 288.1376 -112.1918)
		(width 0.1016)
		(layer "F.Cu")
		(net "M_E_DQ<43>")
	)
	(segment
		(start 296.69994 -142.677642)
		(end 296.69994 -143.941546)
		(width 0.1651)
		(layer "F.Cu")
		(net "M_E_DQ<43>")
	)
	(segment
		(start 295.17467 -117.675152)
		(end 297.942 -120.442482)
		(width 0.1651)
		(layer "F.Cu")
		(net "M_E_DQ<43>")
	)
	(segment
		(start 295.33977 -116.535962)
		(end 295.899586 -116.535962)
		(width 0.1651)
		(layer "F.Cu")
		(net "M_E_DQ<43>")
	)
	(segment
		(start 282.53182 -105.77068)
		(end 282.63342 -105.87228)
		(width 0.0889)
		(layer "F.Cu")
		(net "M_E_DQ<43>")
	)
	(segment
		(start 294.470074 -115.279932)
		(end 295.17467 -115.984528)
		(width 0.1651)
		(layer "F.Cu")
		(net "M_E_DQ<43>")
	)
	(segment
		(start 293.438834 -115.279932)
		(end 294.470074 -115.279932)
		(width 0.1651)
		(layer "F.Cu")
		(net "M_E_DQ<43>")
	)
	(segment
		(start 296.064686 -117.043962)
		(end 295.899586 -117.209062)
		(width 0.1651)
		(layer "F.Cu")
		(net "M_E_DQ<43>")
	)
	(segment
		(start 295.17467 -115.984528)
		(end 295.17467 -116.370862)
		(width 0.1651)
		(layer "F.Cu")
		(net "M_E_DQ<43>")
	)
	(via
		(at 297.549824 -139.932156)
		(size 0.508)
		(drill 0.254)
		(layers "F.Cu" "B.Cu")
		(net "M_E_DQ<43>")
	)
	(via
		(at 296.69994 -143.941546)
		(size 0.508)
		(drill 0.254)
		(layers "F.Cu" "B.Cu")
		(net "M_E_DQ<43>")
	)
	(via
		(at 297.346624 -125.436376)
		(size 0.508)
		(drill 0.254)
		(layers "F.Cu" "B.Cu")
		(net "M_E_DQ<43>")
	)
	(arc
		(start 282.007564 -102.757986)
		(mid 281.982905 -102.817532)
		(end 281.974544 -102.88143)
		(width 0.0889)
		(layer "F.Cu")
		(net "M_E_DQ<43>")
	)
	(arc
		(start 282.041092 -102.690168)
		(mid 282.025406 -102.724609)
		(end 282.007564 -102.757986)
		(width 0.0889)
		(layer "F.Cu")
		(net "M_E_DQ<43>")
	)
	(segment
		(start 297.549824 -137.877296)
		(end 297.549824 -139.932156)
		(width 0.1651)
		(layer "B.Cu")
		(net "M_E_DQ<43>")
	)
	(segment
		(start 297.550332 -137.877296)
		(end 297.549824 -137.877296)
		(width 0.1651)
		(layer "B.Cu")
		(net "M_E_DQ<43>")
	)
	(segment
		(start 297.118278 -142.621)
		(end 297.118278 -142.3162)
		(width 0.14224)
		(layer "In9.Cu")
		(net "M_E_DQ<43>")
	)
	(segment
		(start 297.118278 -142.3162)
		(end 296.86123 -142.059152)
		(width 0.14224)
		(layer "In9.Cu")
		(net "M_E_DQ<43>")
	)
	(segment
		(start 297.150028 -143.763746)
		(end 297.150028 -143.44015)
		(width 0.14224)
		(layer "In9.Cu")
		(net "M_E_DQ<43>")
	)
	(segment
		(start 297.143678 -140.834618)
		(end 297.099228 -140.790168)
		(width 0.14224)
		(layer "In9.Cu")
		(net "M_E_DQ<43>")
	)
	(segment
		(start 296.86123 -142.878048)
		(end 297.118278 -142.621)
		(width 0.14224)
		(layer "In9.Cu")
		(net "M_E_DQ<43>")
	)
	(segment
		(start 297.527472 -139.932156)
		(end 297.549824 -139.932156)
		(width 0.14224)
		(layer "In9.Cu")
		(net "M_E_DQ<43>")
	)
	(segment
		(start 296.69994 -143.941546)
		(end 296.972228 -143.941546)
		(width 0.14224)
		(layer "In9.Cu")
		(net "M_E_DQ<43>")
	)
	(segment
		(start 296.972228 -143.941546)
		(end 297.150028 -143.763746)
		(width 0.14224)
		(layer "In9.Cu")
		(net "M_E_DQ<43>")
	)
	(segment
		(start 296.86123 -143.151352)
		(end 296.86123 -142.878048)
		(width 0.14224)
		(layer "In9.Cu")
		(net "M_E_DQ<43>")
	)
	(segment
		(start 296.86123 -142.059152)
		(end 296.86123 -141.785848)
		(width 0.14224)
		(layer "In9.Cu")
		(net "M_E_DQ<43>")
	)
	(segment
		(start 297.099228 -140.3604)
		(end 297.527472 -139.932156)
		(width 0.14224)
		(layer "In9.Cu")
		(net "M_E_DQ<43>")
	)
	(segment
		(start 297.143678 -141.5034)
		(end 297.143678 -140.834618)
		(width 0.14224)
		(layer "In9.Cu")
		(net "M_E_DQ<43>")
	)
	(segment
		(start 297.150028 -143.44015)
		(end 296.86123 -143.151352)
		(width 0.14224)
		(layer "In9.Cu")
		(net "M_E_DQ<43>")
	)
	(segment
		(start 297.099228 -140.790168)
		(end 297.099228 -140.3604)
		(width 0.14224)
		(layer "In9.Cu")
		(net "M_E_DQ<43>")
	)
	(segment
		(start 296.86123 -141.785848)
		(end 297.143678 -141.5034)
		(width 0.14224)
		(layer "In9.Cu")
		(net "M_E_DQ<43>")
	)
	(segment
		(start 297.879008 -136.5504)
		(end 297.9674 -136.638792)
		(width 0.14224)
		(layer "In11.Cu")
		(net "M_E_DQ<43>")
	)
	(segment
		(start 297.879008 -136.232392)
		(end 297.879008 -136.5504)
		(width 0.14224)
		(layer "In11.Cu")
		(net "M_E_DQ<43>")
	)
	(segment
		(start 297.549824 -139.945364)
		(end 297.549824 -139.932156)
		(width 0.14224)
		(layer "In11.Cu")
		(net "M_E_DQ<43>")
	)
	(segment
		(start 297.917108 -131.9022)
		(end 297.9674 -131.952492)
		(width 0.14224)
		(layer "In11.Cu")
		(net "M_E_DQ<43>")
	)
	(segment
		(start 297.9674 -138.6586)
		(end 297.879008 -138.746992)
		(width 0.14224)
		(layer "In11.Cu")
		(net "M_E_DQ<43>")
	)
	(segment
		(start 297.9674 -134.0612)
		(end 297.917108 -134.111492)
		(width 0.14224)
		(layer "In11.Cu")
		(net "M_E_DQ<43>")
	)
	(segment
		(start 297.879008 -139.61618)
		(end 297.549824 -139.945364)
		(width 0.14224)
		(layer "In11.Cu")
		(net "M_E_DQ<43>")
	)
	(segment
		(start 298.133008 -134.797038)
		(end 298.133008 -135.978392)
		(width 0.14224)
		(layer "In11.Cu")
		(net "M_E_DQ<43>")
	)
	(segment
		(start 297.9928 -129.286)
		(end 297.904408 -129.374392)
		(width 0.14224)
		(layer "In11.Cu")
		(net "M_E_DQ<43>")
	)
	(segment
		(start 297.904408 -129.960878)
		(end 298.056808 -130.113278)
		(width 0.14224)
		(layer "In11.Cu")
		(net "M_E_DQ<43>")
	)
	(segment
		(start 297.917108 -134.111492)
		(end 297.917108 -134.581138)
		(width 0.14224)
		(layer "In11.Cu")
		(net "M_E_DQ<43>")
	)
	(segment
		(start 297.904408 -129.374392)
		(end 297.904408 -129.960878)
		(width 0.14224)
		(layer "In11.Cu")
		(net "M_E_DQ<43>")
	)
	(segment
		(start 297.9674 -131.952492)
		(end 297.9674 -134.0612)
		(width 0.14224)
		(layer "In11.Cu")
		(net "M_E_DQ<43>")
	)
	(segment
		(start 297.917108 -134.581138)
		(end 298.133008 -134.797038)
		(width 0.14224)
		(layer "In11.Cu")
		(net "M_E_DQ<43>")
	)
	(segment
		(start 298.056808 -131.268978)
		(end 297.917108 -131.408678)
		(width 0.14224)
		(layer "In11.Cu")
		(net "M_E_DQ<43>")
	)
	(segment
		(start 297.917108 -131.408678)
		(end 297.917108 -131.9022)
		(width 0.14224)
		(layer "In11.Cu")
		(net "M_E_DQ<43>")
	)
	(segment
		(start 297.879008 -138.746992)
		(end 297.879008 -139.61618)
		(width 0.14224)
		(layer "In11.Cu")
		(net "M_E_DQ<43>")
	)
	(segment
		(start 298.056808 -130.113278)
		(end 298.056808 -131.268978)
		(width 0.14224)
		(layer "In11.Cu")
		(net "M_E_DQ<43>")
	)
	(segment
		(start 297.346624 -125.436376)
		(end 297.346624 -127.369824)
		(width 0.14224)
		(layer "In11.Cu")
		(net "M_E_DQ<43>")
	)
	(segment
		(start 297.9674 -136.638792)
		(end 297.9674 -138.6586)
		(width 0.14224)
		(layer "In11.Cu")
		(net "M_E_DQ<43>")
	)
	(segment
		(start 298.133008 -135.978392)
		(end 297.879008 -136.232392)
		(width 0.14224)
		(layer "In11.Cu")
		(net "M_E_DQ<43>")
	)
	(segment
		(start 297.9928 -128.016)
		(end 297.9928 -129.286)
		(width 0.14224)
		(layer "In11.Cu")
		(net "M_E_DQ<43>")
	)
	(segment
		(start 297.346624 -127.369824)
		(end 297.9928 -128.016)
		(width 0.14224)
		(layer "In11.Cu")
		(net "M_E_DQ<43>")
	)
	(segment
		(start 288.3916 -112.649)
		(end 290.725606 -114.983006)
		(width 0.1651)
		(layer "F.Cu")
		(net "M_E_DQ<42>")
	)
	(segment
		(start 288.037778 -112.649)
		(end 288.3916 -112.649)
		(width 0.1016)
		(layer "F.Cu")
		(net "M_E_DQ<42>")
	)
	(segment
		(start 297.29176 -120.701562)
		(end 297.29176 -123.73864)
		(width 0.1651)
		(layer "F.Cu")
		(net "M_E_DQ<42>")
	)
	(segment
		(start 292.226238 -114.983006)
		(end 293.163752 -115.92052)
		(width 0.1651)
		(layer "F.Cu")
		(net "M_E_DQ<42>")
	)
	(segment
		(start 297.550332 -147.27174)
		(end 297.549824 -147.27174)
		(width 0.1651)
		(layer "F.Cu")
		(net "M_E_DQ<42>")
	)
	(segment
		(start 282.23972 -105.87228)
		(end 282.23972 -108.153454)
		(width 0.1016)
		(layer "F.Cu")
		(net "M_E_DQ<42>")
	)
	(segment
		(start 297.0022 -125.73)
		(end 297.0022 -126.161038)
		(width 0.1651)
		(layer "F.Cu")
		(net "M_E_DQ<42>")
	)
	(segment
		(start 294.521128 -117.93093)
		(end 297.29176 -120.701562)
		(width 0.1651)
		(layer "F.Cu")
		(net "M_E_DQ<42>")
	)
	(segment
		(start 297.681396 -146.14906)
		(end 297.681396 -145.92554)
		(width 0.1651)
		(layer "F.Cu")
		(net "M_E_DQ<42>")
	)
	(segment
		(start 296.8752 -124.1552)
		(end 296.8752 -125.603)
		(width 0.1651)
		(layer "F.Cu")
		(net "M_E_DQ<42>")
	)
	(segment
		(start 297.549824 -147.27174)
		(end 297.549824 -146.280632)
		(width 0.1651)
		(layer "F.Cu")
		(net "M_E_DQ<42>")
	)
	(segment
		(start 297.681396 -145.92554)
		(end 297.549824 -145.793968)
		(width 0.1651)
		(layer "F.Cu")
		(net "M_E_DQ<42>")
	)
	(segment
		(start 293.868602 -115.92052)
		(end 294.521128 -116.573046)
		(width 0.1651)
		(layer "F.Cu")
		(net "M_E_DQ<42>")
	)
	(segment
		(start 293.163752 -115.92052)
		(end 293.868602 -115.92052)
		(width 0.1651)
		(layer "F.Cu")
		(net "M_E_DQ<42>")
	)
	(segment
		(start 281.784044 -102.880668)
		(end 281.784044 -103.357934)
		(width 0.0889)
		(layer "F.Cu")
		(net "M_E_DQ<42>")
	)
	(segment
		(start 297.0022 -126.161038)
		(end 296.54754 -126.615698)
		(width 0.1651)
		(layer "F.Cu")
		(net "M_E_DQ<42>")
	)
	(segment
		(start 294.521128 -116.573046)
		(end 294.521128 -117.93093)
		(width 0.1651)
		(layer "F.Cu")
		(net "M_E_DQ<42>")
	)
	(segment
		(start 296.8752 -125.603)
		(end 297.0022 -125.73)
		(width 0.1651)
		(layer "F.Cu")
		(net "M_E_DQ<42>")
	)
	(segment
		(start 297.29176 -123.73864)
		(end 296.8752 -124.1552)
		(width 0.1651)
		(layer "F.Cu")
		(net "M_E_DQ<42>")
	)
	(segment
		(start 290.725606 -114.983006)
		(end 292.226238 -114.983006)
		(width 0.1651)
		(layer "F.Cu")
		(net "M_E_DQ<42>")
	)
	(segment
		(start 281.784044 -103.357934)
		(end 282.34132 -103.91521)
		(width 0.0889)
		(layer "F.Cu")
		(net "M_E_DQ<42>")
	)
	(segment
		(start 281.842464 -102.262686)
		(end 281.84729 -102.271322)
		(width 0.0889)
		(layer "F.Cu")
		(net "M_E_DQ<42>")
	)
	(segment
		(start 297.549824 -146.280632)
		(end 297.681396 -146.14906)
		(width 0.1651)
		(layer "F.Cu")
		(net "M_E_DQ<42>")
	)
	(segment
		(start 285.630366 -111.5441)
		(end 286.932878 -111.5441)
		(width 0.1016)
		(layer "F.Cu")
		(net "M_E_DQ<42>")
	)
	(segment
		(start 282.354274 -100.976684)
		(end 281.824938 -101.704394)
		(width 0.0889)
		(layer "F.Cu")
		(net "M_E_DQ<42>")
	)
	(segment
		(start 282.23972 -108.153454)
		(end 285.630366 -111.5441)
		(width 0.1016)
		(layer "F.Cu")
		(net "M_E_DQ<42>")
	)
	(segment
		(start 281.836114 -102.252018)
		(end 281.842464 -102.262686)
		(width 0.0889)
		(layer "F.Cu")
		(net "M_E_DQ<42>")
	)
	(segment
		(start 297.549824 -145.793968)
		(end 297.549824 -145.5166)
		(width 0.1651)
		(layer "F.Cu")
		(net "M_E_DQ<42>")
	)
	(segment
		(start 282.34132 -105.77068)
		(end 282.23972 -105.87228)
		(width 0.0889)
		(layer "F.Cu")
		(net "M_E_DQ<42>")
	)
	(segment
		(start 282.34132 -103.91521)
		(end 282.34132 -105.77068)
		(width 0.0889)
		(layer "F.Cu")
		(net "M_E_DQ<42>")
	)
	(segment
		(start 286.932878 -111.5441)
		(end 288.037778 -112.649)
		(width 0.1016)
		(layer "F.Cu")
		(net "M_E_DQ<42>")
	)
	(via
		(at 297.549824 -145.5166)
		(size 0.508)
		(drill 0.254)
		(layers "F.Cu" "B.Cu")
		(net "M_E_DQ<42>")
	)
	(via
		(at 296.69994 -141.213078)
		(size 0.508)
		(drill 0.254)
		(layers "F.Cu" "B.Cu")
		(net "M_E_DQ<42>")
	)
	(via
		(at 296.54754 -126.615698)
		(size 0.508)
		(drill 0.254)
		(layers "F.Cu" "B.Cu")
		(net "M_E_DQ<42>")
	)
	(arc
		(start 281.84729 -102.271322)
		(mid 281.896045 -102.467674)
		(end 281.842464 -102.662736)
		(width 0.0889)
		(layer "F.Cu")
		(net "M_E_DQ<42>")
	)
	(arc
		(start 281.842464 -102.662736)
		(mid 281.798919 -102.767858)
		(end 281.784044 -102.880668)
		(width 0.0889)
		(layer "F.Cu")
		(net "M_E_DQ<42>")
	)
	(arc
		(start 281.824938 -101.704394)
		(mid 281.763261 -101.979581)
		(end 281.836114 -102.252018)
		(width 0.0889)
		(layer "F.Cu")
		(net "M_E_DQ<42>")
	)
	(segment
		(start 296.700448 -142.477236)
		(end 296.69994 -142.476982)
		(width 0.1651)
		(layer "B.Cu")
		(net "M_E_DQ<42>")
	)
	(segment
		(start 296.69994 -142.476982)
		(end 296.69994 -141.213078)
		(width 0.1651)
		(layer "B.Cu")
		(net "M_E_DQ<42>")
	)
	(segment
		(start 296.26687 -141.646148)
		(end 296.26687 -144.233646)
		(width 0.14224)
		(layer "In9.Cu")
		(net "M_E_DQ<42>")
	)
	(segment
		(start 296.26687 -144.233646)
		(end 297.549824 -145.5166)
		(width 0.14224)
		(layer "In9.Cu")
		(net "M_E_DQ<42>")
	)
	(segment
		(start 296.69994 -141.213078)
		(end 296.26687 -141.646148)
		(width 0.14224)
		(layer "In9.Cu")
		(net "M_E_DQ<42>")
	)
	(segment
		(start 296.54754 -128.679194)
		(end 297.193208 -129.324862)
		(width 0.14224)
		(layer "In11.Cu")
		(net "M_E_DQ<42>")
	)
	(segment
		(start 297.1292 -138.7348)
		(end 297.218608 -138.824208)
		(width 0.14224)
		(layer "In11.Cu")
		(net "M_E_DQ<42>")
	)
	(segment
		(start 297.218608 -138.824208)
		(end 297.218608 -139.371578)
		(width 0.14224)
		(layer "In11.Cu")
		(net "M_E_DQ<42>")
	)
	(segment
		(start 297.1292 -134.0612)
		(end 297.269408 -134.201408)
		(width 0.14224)
		(layer "In11.Cu")
		(net "M_E_DQ<42>")
	)
	(segment
		(start 296.54754 -126.615698)
		(end 296.54754 -128.679194)
		(width 0.14224)
		(layer "In11.Cu")
		(net "M_E_DQ<42>")
	)
	(segment
		(start 297.193208 -129.324862)
		(end 297.193208 -129.833878)
		(width 0.14224)
		(layer "In11.Cu")
		(net "M_E_DQ<42>")
	)
	(segment
		(start 297.1292 -132.017008)
		(end 297.1292 -134.0612)
		(width 0.14224)
		(layer "In11.Cu")
		(net "M_E_DQ<42>")
	)
	(segment
		(start 297.269408 -134.492238)
		(end 296.990008 -134.771638)
		(width 0.14224)
		(layer "In11.Cu")
		(net "M_E_DQ<42>")
	)
	(segment
		(start 297.269408 -131.535678)
		(end 297.269408 -131.8768)
		(width 0.14224)
		(layer "In11.Cu")
		(net "M_E_DQ<42>")
	)
	(segment
		(start 296.355008 -140.235178)
		(end 296.355008 -140.868146)
		(width 0.14224)
		(layer "In11.Cu")
		(net "M_E_DQ<42>")
	)
	(segment
		(start 297.066208 -129.960878)
		(end 297.066208 -131.332478)
		(width 0.14224)
		(layer "In11.Cu")
		(net "M_E_DQ<42>")
	)
	(segment
		(start 297.1292 -136.665208)
		(end 297.1292 -138.7348)
		(width 0.14224)
		(layer "In11.Cu")
		(net "M_E_DQ<42>")
	)
	(segment
		(start 296.990008 -135.976868)
		(end 297.218608 -136.205468)
		(width 0.14224)
		(layer "In11.Cu")
		(net "M_E_DQ<42>")
	)
	(segment
		(start 297.066208 -131.332478)
		(end 297.269408 -131.535678)
		(width 0.14224)
		(layer "In11.Cu")
		(net "M_E_DQ<42>")
	)
	(segment
		(start 297.193208 -129.833878)
		(end 297.066208 -129.960878)
		(width 0.14224)
		(layer "In11.Cu")
		(net "M_E_DQ<42>")
	)
	(segment
		(start 296.355008 -140.868146)
		(end 296.69994 -141.213078)
		(width 0.14224)
		(layer "In11.Cu")
		(net "M_E_DQ<42>")
	)
	(segment
		(start 297.218608 -136.5758)
		(end 297.1292 -136.665208)
		(width 0.14224)
		(layer "In11.Cu")
		(net "M_E_DQ<42>")
	)
	(segment
		(start 297.218608 -139.371578)
		(end 296.355008 -140.235178)
		(width 0.14224)
		(layer "In11.Cu")
		(net "M_E_DQ<42>")
	)
	(segment
		(start 297.269408 -131.8768)
		(end 297.1292 -132.017008)
		(width 0.14224)
		(layer "In11.Cu")
		(net "M_E_DQ<42>")
	)
	(segment
		(start 297.269408 -134.201408)
		(end 297.269408 -134.492238)
		(width 0.14224)
		(layer "In11.Cu")
		(net "M_E_DQ<42>")
	)
	(segment
		(start 296.990008 -134.771638)
		(end 296.990008 -135.976868)
		(width 0.14224)
		(layer "In11.Cu")
		(net "M_E_DQ<42>")
	)
	(segment
		(start 297.218608 -136.205468)
		(end 297.218608 -136.5758)
		(width 0.14224)
		(layer "In11.Cu")
		(net "M_E_DQ<42>")
	)
	(segment
		(start 287.730184 -118.233444)
		(end 287.50006 -118.463568)
		(width 0.1651)
		(layer "F.Cu")
		(net "M_E_DQ<41>")
	)
	(segment
		(start 285.596076 -116.559584)
		(end 285.596076 -116.838476)
		(width 0.1651)
		(layer "F.Cu")
		(net "M_E_DQ<41>")
	)
	(segment
		(start 285.8262 -116.32946)
		(end 285.596076 -116.559584)
		(width 0.1651)
		(layer "F.Cu")
		(net "M_E_DQ<41>")
	)
	(segment
		(start 287.024064 -117.987572)
		(end 287.254188 -117.757448)
		(width 0.1651)
		(layer "F.Cu")
		(net "M_E_DQ<41>")
	)
	(segment
		(start 289.865816 -120.013984)
		(end 291.8714 -122.019568)
		(width 0.1651)
		(layer "F.Cu")
		(net "M_E_DQ<41>")
	)
	(segment
		(start 285.320232 -115.5446)
		(end 285.8262 -116.050568)
		(width 0.1651)
		(layer "F.Cu")
		(net "M_E_DQ<41>")
	)
	(segment
		(start 279.38222 -103.73868)
		(end 279.38222 -105.782364)
		(width 0.0889)
		(layer "F.Cu")
		(net "M_E_DQ<41>")
	)
	(segment
		(start 287.697164 -118.939564)
		(end 287.976056 -118.939564)
		(width 0.1651)
		(layer "F.Cu")
		(net "M_E_DQ<41>")
	)
	(segment
		(start 287.50006 -118.74246)
		(end 287.697164 -118.939564)
		(width 0.1651)
		(layer "F.Cu")
		(net "M_E_DQ<41>")
	)
	(segment
		(start 279.578816 -103.542084)
		(end 279.38222 -103.73868)
		(width 0.0889)
		(layer "F.Cu")
		(net "M_E_DQ<41>")
	)
	(segment
		(start 283.4132 -113.226596)
		(end 283.4132 -113.8174)
		(width 0.1016)
		(layer "F.Cu")
		(net "M_E_DQ<41>")
	)
	(segment
		(start 286.745172 -117.987572)
		(end 287.024064 -117.987572)
		(width 0.1651)
		(layer "F.Cu")
		(net "M_E_DQ<41>")
	)
	(segment
		(start 292.08095 -124.206)
		(end 291.599874 -124.687076)
		(width 0.1651)
		(layer "F.Cu")
		(net "M_E_DQ<41>")
	)
	(segment
		(start 285.79318 -117.03558)
		(end 286.072072 -117.03558)
		(width 0.1651)
		(layer "F.Cu")
		(net "M_E_DQ<41>")
	)
	(segment
		(start 287.50006 -118.463568)
		(end 287.50006 -118.74246)
		(width 0.1651)
		(layer "F.Cu")
		(net "M_E_DQ<41>")
	)
	(segment
		(start 289.158172 -119.661432)
		(end 289.437064 -119.661432)
		(width 0.1651)
		(layer "F.Cu")
		(net "M_E_DQ<41>")
	)
	(segment
		(start 288.452052 -119.694452)
		(end 288.649156 -119.891556)
		(width 0.1651)
		(layer "F.Cu")
		(net "M_E_DQ<41>")
	)
	(segment
		(start 286.548068 -117.790468)
		(end 286.745172 -117.987572)
		(width 0.1651)
		(layer "F.Cu")
		(net "M_E_DQ<41>")
	)
	(segment
		(start 279.432004 -102.662736)
		(end 279.578816 -102.917498)
		(width 0.0889)
		(layer "F.Cu")
		(net "M_E_DQ<41>")
	)
	(segment
		(start 291.599874 -124.687076)
		(end 291.422074 -124.687076)
		(width 0.1651)
		(layer "F.Cu")
		(net "M_E_DQ<41>")
	)
	(segment
		(start 287.254188 -117.757448)
		(end 287.53308 -117.757448)
		(width 0.1651)
		(layer "F.Cu")
		(net "M_E_DQ<41>")
	)
	(segment
		(start 283.4132 -113.8174)
		(end 283.718 -114.1222)
		(width 0.1651)
		(layer "F.Cu")
		(net "M_E_DQ<41>")
	)
	(segment
		(start 279.48382 -105.883964)
		(end 279.48382 -109.297216)
		(width 0.1016)
		(layer "F.Cu")
		(net "M_E_DQ<41>")
	)
	(segment
		(start 279.49144 -102.296976)
		(end 279.404572 -102.320344)
		(width 0.0889)
		(layer "F.Cu")
		(net "M_E_DQ<41>")
	)
	(segment
		(start 288.928048 -119.891556)
		(end 289.158172 -119.661432)
		(width 0.1651)
		(layer "F.Cu")
		(net "M_E_DQ<41>")
	)
	(segment
		(start 279.38222 -105.782364)
		(end 279.48382 -105.883964)
		(width 0.0889)
		(layer "F.Cu")
		(net "M_E_DQ<41>")
	)
	(segment
		(start 286.581088 -116.805456)
		(end 286.778192 -117.00256)
		(width 0.1651)
		(layer "F.Cu")
		(net "M_E_DQ<41>")
	)
	(segment
		(start 288.452052 -119.41556)
		(end 288.452052 -119.694452)
		(width 0.1651)
		(layer "F.Cu")
		(net "M_E_DQ<41>")
	)
	(segment
		(start 286.072072 -117.03558)
		(end 286.302196 -116.805456)
		(width 0.1651)
		(layer "F.Cu")
		(net "M_E_DQ<41>")
	)
	(segment
		(start 285.596076 -116.838476)
		(end 285.79318 -117.03558)
		(width 0.1651)
		(layer "F.Cu")
		(net "M_E_DQ<41>")
	)
	(segment
		(start 288.649156 -119.891556)
		(end 288.928048 -119.891556)
		(width 0.1651)
		(layer "F.Cu")
		(net "M_E_DQ<41>")
	)
	(segment
		(start 279.578816 -102.917498)
		(end 279.578816 -103.542084)
		(width 0.0889)
		(layer "F.Cu")
		(net "M_E_DQ<41>")
	)
	(segment
		(start 287.730184 -117.954552)
		(end 287.730184 -118.233444)
		(width 0.1651)
		(layer "F.Cu")
		(net "M_E_DQ<41>")
	)
	(segment
		(start 287.53308 -117.757448)
		(end 287.730184 -117.954552)
		(width 0.1651)
		(layer "F.Cu")
		(net "M_E_DQ<41>")
	)
	(segment
		(start 288.20618 -118.70944)
		(end 288.485072 -118.70944)
		(width 0.1651)
		(layer "F.Cu")
		(net "M_E_DQ<41>")
	)
	(segment
		(start 285.8262 -116.050568)
		(end 285.8262 -116.32946)
		(width 0.1651)
		(layer "F.Cu")
		(net "M_E_DQ<41>")
	)
	(segment
		(start 283.718 -114.1222)
		(end 283.718 -114.935)
		(width 0.1651)
		(layer "F.Cu")
		(net "M_E_DQ<41>")
	)
	(segment
		(start 292.08095 -123.375166)
		(end 292.08095 -124.206)
		(width 0.1651)
		(layer "F.Cu")
		(net "M_E_DQ<41>")
	)
	(segment
		(start 286.548068 -117.511576)
		(end 286.548068 -117.790468)
		(width 0.1651)
		(layer "F.Cu")
		(net "M_E_DQ<41>")
	)
	(segment
		(start 284.3276 -115.5446)
		(end 285.320232 -115.5446)
		(width 0.1651)
		(layer "F.Cu")
		(net "M_E_DQ<41>")
	)
	(segment
		(start 279.778714 -102.462584)
		(end 279.49144 -102.296976)
		(width 0.0889)
		(layer "F.Cu")
		(net "M_E_DQ<41>")
	)
	(segment
		(start 287.976056 -118.939564)
		(end 288.20618 -118.70944)
		(width 0.1651)
		(layer "F.Cu")
		(net "M_E_DQ<41>")
	)
	(segment
		(start 288.485072 -118.70944)
		(end 288.682176 -118.906544)
		(width 0.1651)
		(layer "F.Cu")
		(net "M_E_DQ<41>")
	)
	(segment
		(start 289.789616 -120.013984)
		(end 289.865816 -120.013984)
		(width 0.1651)
		(layer "F.Cu")
		(net "M_E_DQ<41>")
	)
	(segment
		(start 286.302196 -116.805456)
		(end 286.581088 -116.805456)
		(width 0.1651)
		(layer "F.Cu")
		(net "M_E_DQ<41>")
	)
	(segment
		(start 289.437064 -119.661432)
		(end 289.789616 -120.013984)
		(width 0.1651)
		(layer "F.Cu")
		(net "M_E_DQ<41>")
	)
	(segment
		(start 279.48382 -109.297216)
		(end 283.4132 -113.226596)
		(width 0.1016)
		(layer "F.Cu")
		(net "M_E_DQ<41>")
	)
	(segment
		(start 283.718 -114.935)
		(end 284.3276 -115.5446)
		(width 0.1651)
		(layer "F.Cu")
		(net "M_E_DQ<41>")
	)
	(segment
		(start 290.74999 -142.677642)
		(end 290.74999 -143.941546)
		(width 0.1651)
		(layer "F.Cu")
		(net "M_E_DQ<41>")
	)
	(segment
		(start 288.682176 -119.185436)
		(end 288.452052 -119.41556)
		(width 0.1651)
		(layer "F.Cu")
		(net "M_E_DQ<41>")
	)
	(segment
		(start 290.750498 -142.6718)
		(end 290.74999 -142.677642)
		(width 0.1651)
		(layer "F.Cu")
		(net "M_E_DQ<41>")
	)
	(segment
		(start 291.8714 -122.019568)
		(end 291.8714 -123.165616)
		(width 0.1651)
		(layer "F.Cu")
		(net "M_E_DQ<41>")
	)
	(segment
		(start 286.778192 -117.00256)
		(end 286.778192 -117.281452)
		(width 0.1651)
		(layer "F.Cu")
		(net "M_E_DQ<41>")
	)
	(segment
		(start 291.8714 -123.165616)
		(end 292.08095 -123.375166)
		(width 0.1651)
		(layer "F.Cu")
		(net "M_E_DQ<41>")
	)
	(segment
		(start 288.682176 -118.906544)
		(end 288.682176 -119.185436)
		(width 0.1651)
		(layer "F.Cu")
		(net "M_E_DQ<41>")
	)
	(segment
		(start 286.778192 -117.281452)
		(end 286.548068 -117.511576)
		(width 0.1651)
		(layer "F.Cu")
		(net "M_E_DQ<41>")
	)
	(via
		(at 291.422074 -139.932156)
		(size 0.508)
		(drill 0.254)
		(layers "F.Cu" "B.Cu")
		(net "M_E_DQ<41>")
	)
	(via
		(at 291.422074 -124.687076)
		(size 0.508)
		(drill 0.254)
		(layers "F.Cu" "B.Cu")
		(net "M_E_DQ<41>")
	)
	(via
		(at 290.74999 -143.941546)
		(size 0.508)
		(drill 0.254)
		(layers "F.Cu" "B.Cu")
		(net "M_E_DQ<41>")
	)
	(arc
		(start 279.404572 -102.320344)
		(mid 279.37973 -102.494622)
		(end 279.432004 -102.662736)
		(width 0.0889)
		(layer "F.Cu")
		(net "M_E_DQ<41>")
	)
	(segment
		(start 291.599874 -137.877296)
		(end 291.599874 -139.251182)
		(width 0.1651)
		(layer "B.Cu")
		(net "M_E_DQ<41>")
	)
	(segment
		(start 291.600382 -137.877296)
		(end 291.599874 -137.877296)
		(width 0.1651)
		(layer "B.Cu")
		(net "M_E_DQ<41>")
	)
	(segment
		(start 291.422074 -139.428982)
		(end 291.422074 -139.932156)
		(width 0.1651)
		(layer "B.Cu")
		(net "M_E_DQ<41>")
	)
	(segment
		(start 291.599874 -139.251182)
		(end 291.422074 -139.428982)
		(width 0.1651)
		(layer "B.Cu")
		(net "M_E_DQ<41>")
	)
	(segment
		(start 290.91128 -142.076424)
		(end 290.91128 -141.715744)
		(width 0.14224)
		(layer "In9.Cu")
		(net "M_E_DQ<41>")
	)
	(segment
		(start 290.91128 -141.715744)
		(end 291.201856 -141.425168)
		(width 0.14224)
		(layer "In9.Cu")
		(net "M_E_DQ<41>")
	)
	(segment
		(start 291.151056 -143.7894)
		(end 291.151056 -143.4846)
		(width 0.14224)
		(layer "In9.Cu")
		(net "M_E_DQ<41>")
	)
	(segment
		(start 291.399722 -139.932156)
		(end 291.422074 -139.932156)
		(width 0.14224)
		(layer "In9.Cu")
		(net "M_E_DQ<41>")
	)
	(segment
		(start 290.91128 -142.936976)
		(end 291.125656 -142.7226)
		(width 0.14224)
		(layer "In9.Cu")
		(net "M_E_DQ<41>")
	)
	(segment
		(start 290.971478 -140.790168)
		(end 290.971478 -140.3604)
		(width 0.14224)
		(layer "In9.Cu")
		(net "M_E_DQ<41>")
	)
	(segment
		(start 291.151056 -143.4846)
		(end 290.91128 -143.244824)
		(width 0.14224)
		(layer "In9.Cu")
		(net "M_E_DQ<41>")
	)
	(segment
		(start 291.201856 -141.020546)
		(end 290.971478 -140.790168)
		(width 0.14224)
		(layer "In9.Cu")
		(net "M_E_DQ<41>")
	)
	(segment
		(start 290.99891 -143.941546)
		(end 291.151056 -143.7894)
		(width 0.14224)
		(layer "In9.Cu")
		(net "M_E_DQ<41>")
	)
	(segment
		(start 291.125656 -142.7226)
		(end 291.125656 -142.2908)
		(width 0.14224)
		(layer "In9.Cu")
		(net "M_E_DQ<41>")
	)
	(segment
		(start 290.971478 -140.3604)
		(end 291.399722 -139.932156)
		(width 0.14224)
		(layer "In9.Cu")
		(net "M_E_DQ<41>")
	)
	(segment
		(start 291.125656 -142.2908)
		(end 290.91128 -142.076424)
		(width 0.14224)
		(layer "In9.Cu")
		(net "M_E_DQ<41>")
	)
	(segment
		(start 290.74999 -143.941546)
		(end 290.99891 -143.941546)
		(width 0.14224)
		(layer "In9.Cu")
		(net "M_E_DQ<41>")
	)
	(segment
		(start 290.91128 -143.244824)
		(end 290.91128 -142.936976)
		(width 0.14224)
		(layer "In9.Cu")
		(net "M_E_DQ<41>")
	)
	(segment
		(start 291.201856 -141.425168)
		(end 291.201856 -141.020546)
		(width 0.14224)
		(layer "In9.Cu")
		(net "M_E_DQ<41>")
	)
	(segment
		(start 291.255196 -127.953008)
		(end 291.255196 -125.799596)
		(width 0.14224)
		(layer "In11.Cu")
		(net "M_E_DQ<41>")
	)
	(segment
		(start 291.910008 -139.355322)
		(end 291.910008 -138.823192)
		(width 0.14224)
		(layer "In11.Cu")
		(net "M_E_DQ<41>")
	)
	(segment
		(start 291.910008 -136.5758)
		(end 291.910008 -134.200392)
		(width 0.14224)
		(layer "In11.Cu")
		(net "M_E_DQ<41>")
	)
	(segment
		(start 292.0238 -131.838192)
		(end 291.910008 -131.7244)
		(width 0.14224)
		(layer "In11.Cu")
		(net "M_E_DQ<41>")
	)
	(segment
		(start 291.910008 -131.7244)
		(end 291.910008 -128.60782)
		(width 0.14224)
		(layer "In11.Cu")
		(net "M_E_DQ<41>")
	)
	(segment
		(start 292.0238 -136.689592)
		(end 291.910008 -136.5758)
		(width 0.14224)
		(layer "In11.Cu")
		(net "M_E_DQ<41>")
	)
	(segment
		(start 291.910008 -128.60782)
		(end 291.255196 -127.953008)
		(width 0.14224)
		(layer "In11.Cu")
		(net "M_E_DQ<41>")
	)
	(segment
		(start 292.0238 -138.7094)
		(end 292.0238 -136.689592)
		(width 0.14224)
		(layer "In11.Cu")
		(net "M_E_DQ<41>")
	)
	(segment
		(start 292.0238 -134.0866)
		(end 292.0238 -131.838192)
		(width 0.14224)
		(layer "In11.Cu")
		(net "M_E_DQ<41>")
	)
	(segment
		(start 291.910008 -138.823192)
		(end 292.0238 -138.7094)
		(width 0.14224)
		(layer "In11.Cu")
		(net "M_E_DQ<41>")
	)
	(segment
		(start 291.422074 -139.932156)
		(end 291.422074 -139.843256)
		(width 0.14224)
		(layer "In11.Cu")
		(net "M_E_DQ<41>")
	)
	(segment
		(start 291.422074 -139.843256)
		(end 291.910008 -139.355322)
		(width 0.14224)
		(layer "In11.Cu")
		(net "M_E_DQ<41>")
	)
	(segment
		(start 291.910008 -134.200392)
		(end 292.0238 -134.0866)
		(width 0.14224)
		(layer "In11.Cu")
		(net "M_E_DQ<41>")
	)
	(segment
		(start 290.924996 -125.469396)
		(end 290.924996 -125.184154)
		(width 0.14224)
		(layer "In11.Cu")
		(net "M_E_DQ<41>")
	)
	(segment
		(start 291.255196 -125.799596)
		(end 290.924996 -125.469396)
		(width 0.14224)
		(layer "In11.Cu")
		(net "M_E_DQ<41>")
	)
	(segment
		(start 290.924996 -125.184154)
		(end 291.422074 -124.687076)
		(width 0.14224)
		(layer "In11.Cu")
		(net "M_E_DQ<41>")
	)
	(segment
		(start 279.19172 -103.659686)
		(end 279.19172 -105.782364)
		(width 0.0889)
		(layer "F.Cu")
		(net "M_E_DQ<40>")
	)
	(segment
		(start 290.0172 -127.254)
		(end 290.195 -127.4318)
		(width 0.1651)
		(layer "F.Cu")
		(net "M_E_DQ<40>")
	)
	(segment
		(start 279.266904 -102.757986)
		(end 279.388316 -102.968552)
		(width 0.0889)
		(layer "F.Cu")
		(net "M_E_DQ<40>")
	)
	(segment
		(start 291.084 -122.174)
		(end 291.084 -123.317)
		(width 0.1651)
		(layer "F.Cu")
		(net "M_E_DQ<40>")
	)
	(segment
		(start 279.19172 -105.782364)
		(end 279.09012 -105.883964)
		(width 0.0889)
		(layer "F.Cu")
		(net "M_E_DQ<40>")
	)
	(segment
		(start 290.2712 -125.2728)
		(end 290.2712 -125.603)
		(width 0.1651)
		(layer "F.Cu")
		(net "M_E_DQ<40>")
	)
	(segment
		(start 279.388316 -102.968552)
		(end 279.388316 -103.46309)
		(width 0.0889)
		(layer "F.Cu")
		(net "M_E_DQ<40>")
	)
	(segment
		(start 282.956 -114.2746)
		(end 282.956 -115.156488)
		(width 0.1651)
		(layer "F.Cu")
		(net "M_E_DQ<40>")
	)
	(segment
		(start 279.09012 -109.460538)
		(end 282.7528 -113.123218)
		(width 0.1016)
		(layer "F.Cu")
		(net "M_E_DQ<40>")
	)
	(segment
		(start 290.195 -127.4318)
		(end 291.084 -127.4318)
		(width 0.1651)
		(layer "F.Cu")
		(net "M_E_DQ<40>")
	)
	(segment
		(start 291.25799 -126.86919)
		(end 291.004498 -126.615698)
		(width 0.1651)
		(layer "F.Cu")
		(net "M_E_DQ<40>")
	)
	(segment
		(start 291.599874 -147.277582)
		(end 291.422074 -145.415)
		(width 0.1651)
		(layer "F.Cu")
		(net "M_E_DQ<40>")
	)
	(segment
		(start 290.4744 -125.0696)
		(end 290.2712 -125.2728)
		(width 0.1651)
		(layer "F.Cu")
		(net "M_E_DQ<40>")
	)
	(segment
		(start 288.627312 -120.8278)
		(end 289.7378 -120.8278)
		(width 0.1651)
		(layer "F.Cu")
		(net "M_E_DQ<40>")
	)
	(segment
		(start 279.388316 -103.46309)
		(end 279.19172 -103.659686)
		(width 0.0889)
		(layer "F.Cu")
		(net "M_E_DQ<40>")
	)
	(segment
		(start 291.084 -127.4318)
		(end 291.25799 -127.25781)
		(width 0.1651)
		(layer "F.Cu")
		(net "M_E_DQ<40>")
	)
	(segment
		(start 291.600382 -147.27174)
		(end 291.599874 -147.277582)
		(width 0.1651)
		(layer "F.Cu")
		(net "M_E_DQ<40>")
	)
	(segment
		(start 279.09012 -105.883964)
		(end 279.09012 -109.460538)
		(width 0.1016)
		(layer "F.Cu")
		(net "M_E_DQ<40>")
	)
	(segment
		(start 282.7528 -114.0714)
		(end 282.956 -114.2746)
		(width 0.1651)
		(layer "F.Cu")
		(net "M_E_DQ<40>")
	)
	(segment
		(start 278.920194 -101.967538)
		(end 279.207468 -102.133146)
		(width 0.0889)
		(layer "F.Cu")
		(net "M_E_DQ<40>")
	)
	(segment
		(start 291.084 -123.317)
		(end 290.4744 -123.9266)
		(width 0.1651)
		(layer "F.Cu")
		(net "M_E_DQ<40>")
	)
	(segment
		(start 291.004498 -126.615698)
		(end 290.67379 -126.615698)
		(width 0.1651)
		(layer "F.Cu")
		(net "M_E_DQ<40>")
	)
	(segment
		(start 289.7378 -120.8278)
		(end 291.084 -122.174)
		(width 0.1651)
		(layer "F.Cu")
		(net "M_E_DQ<40>")
	)
	(segment
		(start 282.7528 -113.123218)
		(end 282.7528 -114.0714)
		(width 0.1016)
		(layer "F.Cu")
		(net "M_E_DQ<40>")
	)
	(segment
		(start 279.207468 -102.133146)
		(end 279.234138 -102.232714)
		(width 0.0889)
		(layer "F.Cu")
		(net "M_E_DQ<40>")
	)
	(segment
		(start 290.4744 -123.9266)
		(end 290.4744 -125.0696)
		(width 0.1651)
		(layer "F.Cu")
		(net "M_E_DQ<40>")
	)
	(segment
		(start 291.25799 -127.25781)
		(end 291.25799 -126.86919)
		(width 0.1651)
		(layer "F.Cu")
		(net "M_E_DQ<40>")
	)
	(segment
		(start 290.2712 -125.603)
		(end 290.0172 -125.857)
		(width 0.1651)
		(layer "F.Cu")
		(net "M_E_DQ<40>")
	)
	(segment
		(start 290.0172 -125.857)
		(end 290.0172 -127.254)
		(width 0.1651)
		(layer "F.Cu")
		(net "M_E_DQ<40>")
	)
	(segment
		(start 282.956 -115.156488)
		(end 288.627312 -120.8278)
		(width 0.1651)
		(layer "F.Cu")
		(net "M_E_DQ<40>")
	)
	(via
		(at 290.67379 -126.615698)
		(size 0.508)
		(drill 0.254)
		(layers "F.Cu" "B.Cu")
		(net "M_E_DQ<40>")
	)
	(via
		(at 291.422074 -145.415)
		(size 0.508)
		(drill 0.254)
		(layers "F.Cu" "B.Cu")
		(net "M_E_DQ<40>")
	)
	(via
		(at 290.74999 -141.213078)
		(size 0.508)
		(drill 0.254)
		(layers "F.Cu" "B.Cu")
		(net "M_E_DQ<40>")
	)
	(arc
		(start 279.234138 -102.232714)
		(mid 279.18886 -102.499189)
		(end 279.266904 -102.757986)
		(width 0.0889)
		(layer "F.Cu")
		(net "M_E_DQ<40>")
	)
	(segment
		(start 290.750498 -142.477236)
		(end 290.74999 -142.476982)
		(width 0.1651)
		(layer "B.Cu")
		(net "M_E_DQ<40>")
	)
	(segment
		(start 290.74999 -142.476982)
		(end 290.74999 -141.213078)
		(width 0.1651)
		(layer "B.Cu")
		(net "M_E_DQ<40>")
	)
	(segment
		(start 291.12591 -145.415)
		(end 290.31692 -144.60601)
		(width 0.14224)
		(layer "In9.Cu")
		(net "M_E_DQ<40>")
	)
	(segment
		(start 290.31692 -144.60601)
		(end 290.31692 -141.646148)
		(width 0.14224)
		(layer "In9.Cu")
		(net "M_E_DQ<40>")
	)
	(segment
		(start 291.422074 -145.415)
		(end 291.12591 -145.415)
		(width 0.14224)
		(layer "In9.Cu")
		(net "M_E_DQ<40>")
	)
	(segment
		(start 290.31692 -141.646148)
		(end 290.74999 -141.213078)
		(width 0.14224)
		(layer "In9.Cu")
		(net "M_E_DQ<40>")
	)
	(segment
		(start 291.224208 -131.434078)
		(end 291.224208 -131.9276)
		(width 0.14224)
		(layer "In11.Cu")
		(net "M_E_DQ<40>")
	)
	(segment
		(start 290.944808 -134.758938)
		(end 290.944808 -135.979662)
		(width 0.14224)
		(layer "In11.Cu")
		(net "M_E_DQ<40>")
	)
	(segment
		(start 291.224208 -131.9276)
		(end 291.1856 -131.966208)
		(width 0.14224)
		(layer "In11.Cu")
		(net "M_E_DQ<40>")
	)
	(segment
		(start 291.224208 -134.479538)
		(end 290.944808 -134.758938)
		(width 0.14224)
		(layer "In11.Cu")
		(net "M_E_DQ<40>")
	)
	(segment
		(start 291.236908 -138.811508)
		(end 291.236908 -139.358878)
		(width 0.14224)
		(layer "In11.Cu")
		(net "M_E_DQ<40>")
	)
	(segment
		(start 291.1856 -138.7602)
		(end 291.236908 -138.811508)
		(width 0.14224)
		(layer "In11.Cu")
		(net "M_E_DQ<40>")
	)
	(segment
		(start 290.386008 -140.849096)
		(end 290.74999 -141.213078)
		(width 0.14224)
		(layer "In11.Cu")
		(net "M_E_DQ<40>")
	)
	(segment
		(start 291.275008 -128.870964)
		(end 291.275008 -129.719578)
		(width 0.14224)
		(layer "In11.Cu")
		(net "M_E_DQ<40>")
	)
	(segment
		(start 291.1856 -134.0866)
		(end 291.224208 -134.125208)
		(width 0.14224)
		(layer "In11.Cu")
		(net "M_E_DQ<40>")
	)
	(segment
		(start 291.236908 -139.358878)
		(end 290.386008 -140.209778)
		(width 0.14224)
		(layer "In11.Cu")
		(net "M_E_DQ<40>")
	)
	(segment
		(start 290.944808 -135.979662)
		(end 291.236908 -136.271762)
		(width 0.14224)
		(layer "In11.Cu")
		(net "M_E_DQ<40>")
	)
	(segment
		(start 290.932108 -131.141978)
		(end 291.224208 -131.434078)
		(width 0.14224)
		(layer "In11.Cu")
		(net "M_E_DQ<40>")
	)
	(segment
		(start 291.1856 -136.601708)
		(end 291.1856 -138.7602)
		(width 0.14224)
		(layer "In11.Cu")
		(net "M_E_DQ<40>")
	)
	(segment
		(start 291.224208 -134.125208)
		(end 291.224208 -134.479538)
		(width 0.14224)
		(layer "In11.Cu")
		(net "M_E_DQ<40>")
	)
	(segment
		(start 291.1856 -131.966208)
		(end 291.1856 -134.0866)
		(width 0.14224)
		(layer "In11.Cu")
		(net "M_E_DQ<40>")
	)
	(segment
		(start 290.67379 -128.269746)
		(end 291.275008 -128.870964)
		(width 0.14224)
		(layer "In11.Cu")
		(net "M_E_DQ<40>")
	)
	(segment
		(start 290.386008 -140.209778)
		(end 290.386008 -140.849096)
		(width 0.14224)
		(layer "In11.Cu")
		(net "M_E_DQ<40>")
	)
	(segment
		(start 290.932108 -130.062478)
		(end 290.932108 -131.141978)
		(width 0.14224)
		(layer "In11.Cu")
		(net "M_E_DQ<40>")
	)
	(segment
		(start 290.67379 -126.615698)
		(end 290.67379 -128.269746)
		(width 0.14224)
		(layer "In11.Cu")
		(net "M_E_DQ<40>")
	)
	(segment
		(start 291.275008 -129.719578)
		(end 290.932108 -130.062478)
		(width 0.14224)
		(layer "In11.Cu")
		(net "M_E_DQ<40>")
	)
	(segment
		(start 291.236908 -136.5504)
		(end 291.1856 -136.601708)
		(width 0.14224)
		(layer "In11.Cu")
		(net "M_E_DQ<40>")
	)
	(segment
		(start 291.236908 -136.271762)
		(end 291.236908 -136.5504)
		(width 0.14224)
		(layer "In11.Cu")
		(net "M_E_DQ<40>")
	)
	(segment
		(start 204.050392 -142.6718)
		(end 204.049884 -142.677642)
		(width 0.1651)
		(layer "F.Cu")
		(net "M_E_DQ<3>")
	)
	(segment
		(start 204.049884 -142.677642)
		(end 204.049884 -143.941546)
		(width 0.1651)
		(layer "F.Cu")
		(net "M_E_DQ<3>")
	)
	(segment
		(start 236.183678 -86.29904)
		(end 235.612178 -86.29904)
		(width 0.1651)
		(layer "F.Cu")
		(net "M_E_DQ<3>")
	)
	(via
		(at 204.049884 -143.941546)
		(size 0.508)
		(drill 0.254)
		(layers "F.Cu" "B.Cu")
		(net "M_E_DQ<3>")
	)
	(via
		(at 204.899768 -139.932156)
		(size 0.508)
		(drill 0.254)
		(layers "F.Cu" "B.Cu")
		(net "M_E_DQ<3>")
	)
	(via
		(at 235.612178 -86.29904)
		(size 0.508)
		(drill 0.254)
		(layers "F.Cu" "B.Cu")
		(net "M_E_DQ<3>")
	)
	(segment
		(start 204.900276 -137.877296)
		(end 204.899768 -137.877296)
		(width 0.1651)
		(layer "B.Cu")
		(net "M_E_DQ<3>")
	)
	(segment
		(start 204.899768 -137.877296)
		(end 204.899768 -139.932156)
		(width 0.1651)
		(layer "B.Cu")
		(net "M_E_DQ<3>")
	)
	(segment
		(start 214.090758 -107.595924)
		(end 213.734904 -107.951778)
		(width 0.14224)
		(layer "In4.Cu")
		(net "M_E_DQ<3>")
	)
	(segment
		(start 212.251036 -110.13567)
		(end 212.010498 -109.895132)
		(width 0.14224)
		(layer "In4.Cu")
		(net "M_E_DQ<3>")
	)
	(segment
		(start 204.211174 -141.785848)
		(end 204.211174 -142.059152)
		(width 0.14224)
		(layer "In4.Cu")
		(net "M_E_DQ<3>")
	)
	(segment
		(start 206.5528 -125.613922)
		(end 205.2828 -126.883922)
		(width 0.14224)
		(layer "In4.Cu")
		(net "M_E_DQ<3>")
	)
	(segment
		(start 229.4636 -88.730582)
		(end 229.289864 -88.904318)
		(width 0.0889)
		(layer "In4.Cu")
		(net "M_E_DQ<3>")
	)
	(segment
		(start 214.769192 -107.836462)
		(end 214.550244 -107.836462)
		(width 0.14224)
		(layer "In4.Cu")
		(net "M_E_DQ<3>")
	)
	(segment
		(start 213.975442 -108.630212)
		(end 213.619588 -108.986066)
		(width 0.14224)
		(layer "In4.Cu")
		(net "M_E_DQ<3>")
	)
	(segment
		(start 204.211174 -142.878048)
		(end 204.211174 -143.151352)
		(width 0.14224)
		(layer "In4.Cu")
		(net "M_E_DQ<3>")
	)
	(segment
		(start 204.499972 -143.44015)
		(end 204.499972 -143.763746)
		(width 0.14224)
		(layer "In4.Cu")
		(net "M_E_DQ<3>")
	)
	(segment
		(start 207.9752 -124.1298)
		(end 207.5688 -124.1298)
		(width 0.14224)
		(layer "In4.Cu")
		(net "M_E_DQ<3>")
	)
	(segment
		(start 214.550244 -107.836462)
		(end 214.309706 -107.595924)
		(width 0.14224)
		(layer "In4.Cu")
		(net "M_E_DQ<3>")
	)
	(segment
		(start 213.734904 -108.170726)
		(end 213.975442 -108.411264)
		(width 0.14224)
		(layer "In4.Cu")
		(net "M_E_DQ<3>")
	)
	(segment
		(start 211.4042 -110.282482)
		(end 211.4042 -111.186722)
		(width 0.14224)
		(layer "In4.Cu")
		(net "M_E_DQ<3>")
	)
	(segment
		(start 205.482952 -136.045448)
		(end 205.134464 -136.393936)
		(width 0.14224)
		(layer "In4.Cu")
		(net "M_E_DQ<3>")
	)
	(segment
		(start 213.40064 -108.986066)
		(end 213.160102 -108.745528)
		(width 0.14224)
		(layer "In4.Cu")
		(net "M_E_DQ<3>")
	)
	(segment
		(start 211.79155 -109.895132)
		(end 211.4042 -110.282482)
		(width 0.14224)
		(layer "In4.Cu")
		(net "M_E_DQ<3>")
	)
	(segment
		(start 204.493622 -140.834618)
		(end 204.493622 -141.5034)
		(width 0.14224)
		(layer "In4.Cu")
		(net "M_E_DQ<3>")
	)
	(segment
		(start 208.1784 -123.9266)
		(end 207.9752 -124.1298)
		(width 0.14224)
		(layer "In4.Cu")
		(net "M_E_DQ<3>")
	)
	(segment
		(start 231.79278 -87.88019)
		(end 231.334564 -88.338406)
		(width 0.0889)
		(layer "In4.Cu")
		(net "M_E_DQ<3>")
	)
	(segment
		(start 204.449172 -140.790168)
		(end 204.493622 -140.834618)
		(width 0.14224)
		(layer "In4.Cu")
		(net "M_E_DQ<3>")
	)
	(segment
		(start 205.482952 -134.797038)
		(end 205.482952 -136.045448)
		(width 0.14224)
		(layer "In4.Cu")
		(net "M_E_DQ<3>")
	)
	(segment
		(start 205.171548 -134.485634)
		(end 205.482952 -134.797038)
		(width 0.14224)
		(layer "In4.Cu")
		(net "M_E_DQ<3>")
	)
	(segment
		(start 213.975442 -108.411264)
		(end 213.975442 -108.630212)
		(width 0.14224)
		(layer "In4.Cu")
		(net "M_E_DQ<3>")
	)
	(segment
		(start 205.171548 -134.197852)
		(end 205.171548 -134.485634)
		(width 0.14224)
		(layer "In4.Cu")
		(net "M_E_DQ<3>")
	)
	(segment
		(start 214.884508 -107.021122)
		(end 215.125046 -107.26166)
		(width 0.14224)
		(layer "In4.Cu")
		(net "M_E_DQ<3>")
	)
	(segment
		(start 212.469984 -110.13567)
		(end 212.251036 -110.13567)
		(width 0.14224)
		(layer "In4.Cu")
		(net "M_E_DQ<3>")
	)
	(segment
		(start 204.468222 -142.621)
		(end 204.211174 -142.878048)
		(width 0.14224)
		(layer "In4.Cu")
		(net "M_E_DQ<3>")
	)
	(segment
		(start 212.825838 -109.779816)
		(end 212.469984 -110.13567)
		(width 0.14224)
		(layer "In4.Cu")
		(net "M_E_DQ<3>")
	)
	(segment
		(start 205.5114 -131.089146)
		(end 205.1812 -131.419346)
		(width 0.14224)
		(layer "In4.Cu")
		(net "M_E_DQ<3>")
	)
	(segment
		(start 206.5528 -118.9228)
		(end 206.5528 -125.613922)
		(width 0.14224)
		(layer "In4.Cu")
		(net "M_E_DQ<3>")
	)
	(segment
		(start 214.309706 -107.595924)
		(end 214.090758 -107.595924)
		(width 0.14224)
		(layer "In4.Cu")
		(net "M_E_DQ<3>")
	)
	(segment
		(start 205.2066 -139.638532)
		(end 204.899768 -139.945364)
		(width 0.14224)
		(layer "In4.Cu")
		(net "M_E_DQ<3>")
	)
	(segment
		(start 229.720648 -88.338406)
		(end 229.4636 -88.595454)
		(width 0.0889)
		(layer "In4.Cu")
		(net "M_E_DQ<3>")
	)
	(segment
		(start 211.4042 -111.186722)
		(end 208.1784 -114.412522)
		(width 0.14224)
		(layer "In4.Cu")
		(net "M_E_DQ<3>")
	)
	(segment
		(start 204.899768 -139.932156)
		(end 204.877416 -139.932156)
		(width 0.14224)
		(layer "In4.Cu")
		(net "M_E_DQ<3>")
	)
	(segment
		(start 205.2066 -138.8872)
		(end 205.2066 -139.638532)
		(width 0.14224)
		(layer "In4.Cu")
		(net "M_E_DQ<3>")
	)
	(segment
		(start 204.211174 -143.151352)
		(end 204.499972 -143.44015)
		(width 0.14224)
		(layer "In4.Cu")
		(net "M_E_DQ<3>")
	)
	(segment
		(start 233.912918 -86.88959)
		(end 233.880152 -86.88959)
		(width 0.0889)
		(layer "In4.Cu")
		(net "M_E_DQ<3>")
	)
	(segment
		(start 204.499972 -143.763746)
		(end 204.322172 -143.941546)
		(width 0.14224)
		(layer "In4.Cu")
		(net "M_E_DQ<3>")
	)
	(segment
		(start 213.160102 -108.745528)
		(end 212.941154 -108.745528)
		(width 0.14224)
		(layer "In4.Cu")
		(net "M_E_DQ<3>")
	)
	(segment
		(start 214.884508 -106.802174)
		(end 214.884508 -107.021122)
		(width 0.14224)
		(layer "In4.Cu")
		(net "M_E_DQ<3>")
	)
	(segment
		(start 204.468222 -142.3162)
		(end 204.468222 -142.621)
		(width 0.14224)
		(layer "In4.Cu")
		(net "M_E_DQ<3>")
	)
	(segment
		(start 207.5688 -124.1298)
		(end 207.3656 -123.9266)
		(width 0.14224)
		(layer "In4.Cu")
		(net "M_E_DQ<3>")
	)
	(segment
		(start 229.289864 -88.904318)
		(end 223.282764 -94.911418)
		(width 0.14224)
		(layer "In4.Cu")
		(net "M_E_DQ<3>")
	)
	(segment
		(start 207.3656 -123.9266)
		(end 207.3656 -118.9228)
		(width 0.14224)
		(layer "In4.Cu")
		(net "M_E_DQ<3>")
	)
	(segment
		(start 234.790742 -86.394036)
		(end 234.742482 -86.394036)
		(width 0.0889)
		(layer "In4.Cu")
		(net "M_E_DQ<3>")
	)
	(segment
		(start 215.125046 -107.26166)
		(end 215.125046 -107.480608)
		(width 0.14224)
		(layer "In4.Cu")
		(net "M_E_DQ<3>")
	)
	(segment
		(start 205.5114 -130.048254)
		(end 205.5114 -131.089146)
		(width 0.14224)
		(layer "In4.Cu")
		(net "M_E_DQ<3>")
	)
	(segment
		(start 205.2828 -126.883922)
		(end 205.2828 -129.819654)
		(width 0.14224)
		(layer "In4.Cu")
		(net "M_E_DQ<3>")
	)
	(segment
		(start 204.449172 -140.3604)
		(end 204.449172 -140.790168)
		(width 0.14224)
		(layer "In4.Cu")
		(net "M_E_DQ<3>")
	)
	(segment
		(start 212.5853 -109.101382)
		(end 212.5853 -109.32033)
		(width 0.14224)
		(layer "In4.Cu")
		(net "M_E_DQ<3>")
	)
	(segment
		(start 208.1784 -114.412522)
		(end 208.1784 -123.9266)
		(width 0.14224)
		(layer "In4.Cu")
		(net "M_E_DQ<3>")
	)
	(segment
		(start 206.756 -118.7196)
		(end 206.5528 -118.9228)
		(width 0.14224)
		(layer "In4.Cu")
		(net "M_E_DQ<3>")
	)
	(segment
		(start 235.612178 -86.29904)
		(end 234.790742 -86.394036)
		(width 0.0889)
		(layer "In4.Cu")
		(net "M_E_DQ<3>")
	)
	(segment
		(start 207.3656 -118.9228)
		(end 207.1624 -118.7196)
		(width 0.14224)
		(layer "In4.Cu")
		(net "M_E_DQ<3>")
	)
	(segment
		(start 233.058208 -87.384636)
		(end 233.025442 -87.384636)
		(width 0.0889)
		(layer "In4.Cu")
		(net "M_E_DQ<3>")
	)
	(segment
		(start 215.125046 -107.480608)
		(end 214.769192 -107.836462)
		(width 0.14224)
		(layer "In4.Cu")
		(net "M_E_DQ<3>")
	)
	(segment
		(start 212.5853 -109.32033)
		(end 212.825838 -109.560868)
		(width 0.14224)
		(layer "In4.Cu")
		(net "M_E_DQ<3>")
	)
	(segment
		(start 231.334564 -88.338406)
		(end 229.720648 -88.338406)
		(width 0.0889)
		(layer "In4.Cu")
		(net "M_E_DQ<3>")
	)
	(segment
		(start 229.4636 -88.595454)
		(end 229.4636 -88.730582)
		(width 0.0889)
		(layer "In4.Cu")
		(net "M_E_DQ<3>")
	)
	(segment
		(start 205.3336 -136.9314)
		(end 205.3336 -138.7602)
		(width 0.14224)
		(layer "In4.Cu")
		(net "M_E_DQ<3>")
	)
	(segment
		(start 205.3336 -138.7602)
		(end 205.2066 -138.8872)
		(width 0.14224)
		(layer "In4.Cu")
		(net "M_E_DQ<3>")
	)
	(segment
		(start 213.619588 -108.986066)
		(end 213.40064 -108.986066)
		(width 0.14224)
		(layer "In4.Cu")
		(net "M_E_DQ<3>")
	)
	(segment
		(start 204.322172 -143.941546)
		(end 204.049884 -143.941546)
		(width 0.14224)
		(layer "In4.Cu")
		(net "M_E_DQ<3>")
	)
	(segment
		(start 223.282764 -98.403918)
		(end 214.884508 -106.802174)
		(width 0.14224)
		(layer "In4.Cu")
		(net "M_E_DQ<3>")
	)
	(segment
		(start 204.493622 -141.5034)
		(end 204.211174 -141.785848)
		(width 0.14224)
		(layer "In4.Cu")
		(net "M_E_DQ<3>")
	)
	(segment
		(start 205.1812 -131.419346)
		(end 205.1812 -132.0038)
		(width 0.14224)
		(layer "In4.Cu")
		(net "M_E_DQ<3>")
	)
	(segment
		(start 207.1624 -118.7196)
		(end 206.756 -118.7196)
		(width 0.14224)
		(layer "In4.Cu")
		(net "M_E_DQ<3>")
	)
	(segment
		(start 223.282764 -94.911418)
		(end 223.282764 -98.403918)
		(width 0.14224)
		(layer "In4.Cu")
		(net "M_E_DQ<3>")
	)
	(segment
		(start 204.211174 -142.059152)
		(end 204.468222 -142.3162)
		(width 0.14224)
		(layer "In4.Cu")
		(net "M_E_DQ<3>")
	)
	(segment
		(start 212.825838 -109.560868)
		(end 212.825838 -109.779816)
		(width 0.14224)
		(layer "In4.Cu")
		(net "M_E_DQ<3>")
	)
	(segment
		(start 205.2828 -129.819654)
		(end 205.5114 -130.048254)
		(width 0.14224)
		(layer "In4.Cu")
		(net "M_E_DQ<3>")
	)
	(segment
		(start 205.3336 -134.0358)
		(end 205.171548 -134.197852)
		(width 0.14224)
		(layer "In4.Cu")
		(net "M_E_DQ<3>")
	)
	(segment
		(start 205.134464 -136.393936)
		(end 205.134464 -136.732264)
		(width 0.14224)
		(layer "In4.Cu")
		(net "M_E_DQ<3>")
	)
	(segment
		(start 232.191814 -87.88019)
		(end 231.79278 -87.88019)
		(width 0.0889)
		(layer "In4.Cu")
		(net "M_E_DQ<3>")
	)
	(segment
		(start 212.010498 -109.895132)
		(end 211.79155 -109.895132)
		(width 0.14224)
		(layer "In4.Cu")
		(net "M_E_DQ<3>")
	)
	(segment
		(start 212.941154 -108.745528)
		(end 212.5853 -109.101382)
		(width 0.14224)
		(layer "In4.Cu")
		(net "M_E_DQ<3>")
	)
	(segment
		(start 205.3336 -132.1562)
		(end 205.3336 -134.0358)
		(width 0.14224)
		(layer "In4.Cu")
		(net "M_E_DQ<3>")
	)
	(segment
		(start 213.734904 -107.951778)
		(end 213.734904 -108.170726)
		(width 0.14224)
		(layer "In4.Cu")
		(net "M_E_DQ<3>")
	)
	(segment
		(start 205.1812 -132.0038)
		(end 205.3336 -132.1562)
		(width 0.14224)
		(layer "In4.Cu")
		(net "M_E_DQ<3>")
	)
	(segment
		(start 204.877416 -139.932156)
		(end 204.449172 -140.3604)
		(width 0.14224)
		(layer "In4.Cu")
		(net "M_E_DQ<3>")
	)
	(segment
		(start 204.899768 -139.945364)
		(end 204.899768 -139.932156)
		(width 0.14224)
		(layer "In4.Cu")
		(net "M_E_DQ<3>")
	)
	(segment
		(start 205.134464 -136.732264)
		(end 205.3336 -136.9314)
		(width 0.14224)
		(layer "In4.Cu")
		(net "M_E_DQ<3>")
	)
	(arc
		(start 232.689908 -87.584788)
		(mid 232.479555 -87.79776)
		(end 232.191814 -87.88019)
		(width 0.0889)
		(layer "In4.Cu")
		(net "M_E_DQ<3>")
	)
	(arc
		(start 233.880152 -86.88959)
		(mid 233.68851 -86.946756)
		(end 233.548428 -87.089488)
		(width 0.0889)
		(layer "In4.Cu")
		(net "M_E_DQ<3>")
	)
	(arc
		(start 233.025442 -87.384636)
		(mid 232.831592 -87.440986)
		(end 232.689908 -87.584788)
		(width 0.0889)
		(layer "In4.Cu")
		(net "M_E_DQ<3>")
	)
	(arc
		(start 234.742482 -86.394036)
		(mid 234.548632 -86.450386)
		(end 234.406948 -86.594188)
		(width 0.0889)
		(layer "In4.Cu")
		(net "M_E_DQ<3>")
	)
	(arc
		(start 233.548428 -87.089488)
		(mid 233.341424 -87.300352)
		(end 233.058208 -87.384636)
		(width 0.0889)
		(layer "In4.Cu")
		(net "M_E_DQ<3>")
	)
	(arc
		(start 234.406948 -86.594188)
		(mid 234.19834 -86.80612)
		(end 233.912918 -86.88959)
		(width 0.0889)
		(layer "In4.Cu")
		(net "M_E_DQ<3>")
	)
	(segment
		(start 285.650432 -142.6718)
		(end 285.649924 -142.677642)
		(width 0.1651)
		(layer "F.Cu")
		(net "M_E_DQ<39>")
	)
	(segment
		(start 285.649924 -142.677642)
		(end 285.649924 -143.941546)
		(width 0.1651)
		(layer "F.Cu")
		(net "M_E_DQ<39>")
	)
	(segment
		(start 273.769328 -98.995738)
		(end 274.340828 -98.995738)
		(width 0.1651)
		(layer "F.Cu")
		(net "M_E_DQ<39>")
	)
	(via
		(at 286.499808 -139.932156)
		(size 0.508)
		(drill 0.254)
		(layers "F.Cu" "B.Cu")
		(net "M_E_DQ<39>")
	)
	(via
		(at 285.649924 -143.941546)
		(size 0.508)
		(drill 0.254)
		(layers "F.Cu" "B.Cu")
		(net "M_E_DQ<39>")
	)
	(via
		(at 274.340828 -98.995738)
		(size 0.508)
		(drill 0.254)
		(layers "F.Cu" "B.Cu")
		(net "M_E_DQ<39>")
	)
	(segment
		(start 286.499808 -139.932156)
		(end 286.499808 -137.877296)
		(width 0.1651)
		(layer "B.Cu")
		(net "M_E_DQ<39>")
	)
	(segment
		(start 286.499808 -137.877296)
		(end 286.500316 -137.877296)
		(width 0.1651)
		(layer "B.Cu")
		(net "M_E_DQ<39>")
	)
	(segment
		(start 285.811214 -141.785848)
		(end 285.811214 -142.059152)
		(width 0.14224)
		(layer "In4.Cu")
		(net "M_E_DQ<39>")
	)
	(segment
		(start 286.068262 -142.621)
		(end 285.811214 -142.878048)
		(width 0.14224)
		(layer "In4.Cu")
		(net "M_E_DQ<39>")
	)
	(segment
		(start 286.7152 -133.3754)
		(end 286.9946 -133.6548)
		(width 0.14224)
		(layer "In4.Cu")
		(net "M_E_DQ<39>")
	)
	(segment
		(start 286.852614 -138.952986)
		(end 286.852614 -139.590272)
		(width 0.14224)
		(layer "In4.Cu")
		(net "M_E_DQ<39>")
	)
	(segment
		(start 286.878014 -134.53237)
		(end 287.021778 -134.676134)
		(width 0.14224)
		(layer "In4.Cu")
		(net "M_E_DQ<39>")
	)
	(segment
		(start 281.474926 -120.302274)
		(end 281.312874 -120.464326)
		(width 0.14224)
		(layer "In4.Cu")
		(net "M_E_DQ<39>")
	)
	(segment
		(start 287.021778 -134.676134)
		(end 287.021778 -136.015222)
		(width 0.14224)
		(layer "In4.Cu")
		(net "M_E_DQ<39>")
	)
	(segment
		(start 276.584664 -104.52989)
		(end 276.584664 -115.955064)
		(width 0.14224)
		(layer "In4.Cu")
		(net "M_E_DQ<39>")
	)
	(segment
		(start 279.969468 -118.577868)
		(end 280.325322 -118.933722)
		(width 0.14224)
		(layer "In4.Cu")
		(net "M_E_DQ<39>")
	)
	(segment
		(start 286.766 -131.445)
		(end 286.766 -131.917186)
		(width 0.14224)
		(layer "In4.Cu")
		(net "M_E_DQ<39>")
	)
	(segment
		(start 286.093662 -141.5034)
		(end 285.811214 -141.785848)
		(width 0.14224)
		(layer "In4.Cu")
		(net "M_E_DQ<39>")
	)
	(segment
		(start 287.147 -130.153664)
		(end 287.147 -131.064)
		(width 0.14224)
		(layer "In4.Cu")
		(net "M_E_DQ<39>")
	)
	(segment
		(start 281.668728 -121.039128)
		(end 281.887676 -121.039128)
		(width 0.14224)
		(layer "In4.Cu")
		(net "M_E_DQ<39>")
	)
	(segment
		(start 286.049212 -140.790168)
		(end 286.093662 -140.834618)
		(width 0.14224)
		(layer "In4.Cu")
		(net "M_E_DQ<39>")
	)
	(segment
		(start 279.013666 -118.384066)
		(end 279.36952 -118.73992)
		(width 0.14224)
		(layer "In4.Cu")
		(net "M_E_DQ<39>")
	)
	(segment
		(start 280.325322 -118.933722)
		(end 280.325322 -119.15267)
		(width 0.14224)
		(layer "In4.Cu")
		(net "M_E_DQ<39>")
	)
	(segment
		(start 287.02 -136.753346)
		(end 287.02 -137.1854)
		(width 0.14224)
		(layer "In4.Cu")
		(net "M_E_DQ<39>")
	)
	(segment
		(start 282.62453 -121.23293)
		(end 282.62453 -121.451878)
		(width 0.14224)
		(layer "In4.Cu")
		(net "M_E_DQ<39>")
	)
	(segment
		(start 281.312874 -120.464326)
		(end 281.312874 -120.683274)
		(width 0.14224)
		(layer "In4.Cu")
		(net "M_E_DQ<39>")
	)
	(segment
		(start 286.499808 -139.932156)
		(end 286.477456 -139.932156)
		(width 0.14224)
		(layer "In4.Cu")
		(net "M_E_DQ<39>")
	)
	(segment
		(start 286.7914 -126.1618)
		(end 286.7914 -129.798064)
		(width 0.14224)
		(layer "In4.Cu")
		(net "M_E_DQ<39>")
	)
	(segment
		(start 286.100012 -143.763746)
		(end 285.922212 -143.941546)
		(width 0.14224)
		(layer "In4.Cu")
		(net "M_E_DQ<39>")
	)
	(segment
		(start 285.811214 -142.059152)
		(end 286.068262 -142.3162)
		(width 0.14224)
		(layer "In4.Cu")
		(net "M_E_DQ<39>")
	)
	(segment
		(start 286.093662 -140.834618)
		(end 286.093662 -141.5034)
		(width 0.14224)
		(layer "In4.Cu")
		(net "M_E_DQ<39>")
	)
	(segment
		(start 278.219916 -117.590316)
		(end 278.438864 -117.590316)
		(width 0.14224)
		(layer "In4.Cu")
		(net "M_E_DQ<39>")
	)
	(segment
		(start 278.819864 -117.428264)
		(end 279.175718 -117.784118)
		(width 0.14224)
		(layer "In4.Cu")
		(net "M_E_DQ<39>")
	)
	(segment
		(start 279.175718 -117.784118)
		(end 279.175718 -118.003066)
		(width 0.14224)
		(layer "In4.Cu")
		(net "M_E_DQ<39>")
	)
	(segment
		(start 286.766 -131.917186)
		(end 287.02 -132.171186)
		(width 0.14224)
		(layer "In4.Cu")
		(net "M_E_DQ<39>")
	)
	(segment
		(start 280.16327 -119.53367)
		(end 280.519124 -119.889524)
		(width 0.14224)
		(layer "In4.Cu")
		(net "M_E_DQ<39>")
	)
	(segment
		(start 286.100012 -143.44015)
		(end 286.100012 -143.763746)
		(width 0.14224)
		(layer "In4.Cu")
		(net "M_E_DQ<39>")
	)
	(segment
		(start 282.049728 -120.877076)
		(end 282.268676 -120.877076)
		(width 0.14224)
		(layer "In4.Cu")
		(net "M_E_DQ<39>")
	)
	(segment
		(start 280.519124 -119.889524)
		(end 280.738072 -119.889524)
		(width 0.14224)
		(layer "In4.Cu")
		(net "M_E_DQ<39>")
	)
	(segment
		(start 281.119072 -119.727472)
		(end 281.474926 -120.083326)
		(width 0.14224)
		(layer "In4.Cu")
		(net "M_E_DQ<39>")
	)
	(segment
		(start 287.02 -137.1854)
		(end 286.749236 -137.456164)
		(width 0.14224)
		(layer "In4.Cu")
		(net "M_E_DQ<39>")
	)
	(segment
		(start 282.462478 -121.832878)
		(end 286.7914 -126.1618)
		(width 0.14224)
		(layer "In4.Cu")
		(net "M_E_DQ<39>")
	)
	(segment
		(start 286.841692 -139.590272)
		(end 286.499808 -139.932156)
		(width 0.14224)
		(layer "In4.Cu")
		(net "M_E_DQ<39>")
	)
	(segment
		(start 286.852614 -136.184386)
		(end 286.852614 -136.58596)
		(width 0.14224)
		(layer "In4.Cu")
		(net "M_E_DQ<39>")
	)
	(segment
		(start 279.75052 -118.577868)
		(end 279.969468 -118.577868)
		(width 0.14224)
		(layer "In4.Cu")
		(net "M_E_DQ<39>")
	)
	(segment
		(start 275.749512 -102.793292)
		(end 276.298914 -103.342694)
		(width 0.0889)
		(layer "In4.Cu")
		(net "M_E_DQ<39>")
	)
	(segment
		(start 275.184362 -99.890834)
		(end 275.217128 -99.890834)
		(width 0.0889)
		(layer "In4.Cu")
		(net "M_E_DQ<39>")
	)
	(segment
		(start 286.749236 -137.456164)
		(end 286.749236 -138.057636)
		(width 0.14224)
		(layer "In4.Cu")
		(net "M_E_DQ<39>")
	)
	(segment
		(start 282.62453 -121.451878)
		(end 282.462478 -121.61393)
		(width 0.14224)
		(layer "In4.Cu")
		(net "M_E_DQ<39>")
	)
	(segment
		(start 286.049212 -140.3604)
		(end 286.049212 -140.790168)
		(width 0.14224)
		(layer "In4.Cu")
		(net "M_E_DQ<39>")
	)
	(segment
		(start 279.013666 -118.165118)
		(end 279.013666 -118.384066)
		(width 0.14224)
		(layer "In4.Cu")
		(net "M_E_DQ<39>")
	)
	(segment
		(start 274.340828 -99.290378)
		(end 274.412964 -99.362514)
		(width 0.0889)
		(layer "In4.Cu")
		(net "M_E_DQ<39>")
	)
	(segment
		(start 276.298914 -103.342694)
		(end 276.298914 -104.24414)
		(width 0.0889)
		(layer "In4.Cu")
		(net "M_E_DQ<39>")
	)
	(segment
		(start 275.711158 -100.186236)
		(end 275.749512 -100.258372)
		(width 0.0889)
		(layer "In4.Cu")
		(net "M_E_DQ<39>")
	)
	(segment
		(start 285.811214 -142.878048)
		(end 285.811214 -143.151352)
		(width 0.14224)
		(layer "In4.Cu")
		(net "M_E_DQ<39>")
	)
	(segment
		(start 287.02 -138.3284)
		(end 287.02 -138.7856)
		(width 0.14224)
		(layer "In4.Cu")
		(net "M_E_DQ<39>")
	)
	(segment
		(start 286.7914 -129.798064)
		(end 287.147 -130.153664)
		(width 0.14224)
		(layer "In4.Cu")
		(net "M_E_DQ<39>")
	)
	(segment
		(start 278.600916 -117.428264)
		(end 278.819864 -117.428264)
		(width 0.14224)
		(layer "In4.Cu")
		(net "M_E_DQ<39>")
	)
	(segment
		(start 281.474926 -120.083326)
		(end 281.474926 -120.302274)
		(width 0.14224)
		(layer "In4.Cu")
		(net "M_E_DQ<39>")
	)
	(segment
		(start 286.749236 -138.057636)
		(end 287.02 -138.3284)
		(width 0.14224)
		(layer "In4.Cu")
		(net "M_E_DQ<39>")
	)
	(segment
		(start 274.412964 -99.362514)
		(end 274.499578 -99.417124)
		(width 0.0889)
		(layer "In4.Cu")
		(net "M_E_DQ<39>")
	)
	(segment
		(start 287.02 -138.7856)
		(end 286.852614 -138.952986)
		(width 0.14224)
		(layer "In4.Cu")
		(net "M_E_DQ<39>")
	)
	(segment
		(start 279.588468 -118.73992)
		(end 279.75052 -118.577868)
		(width 0.14224)
		(layer "In4.Cu")
		(net "M_E_DQ<39>")
	)
	(segment
		(start 280.16327 -119.314722)
		(end 280.16327 -119.53367)
		(width 0.14224)
		(layer "In4.Cu")
		(net "M_E_DQ<39>")
	)
	(segment
		(start 286.878014 -134.101586)
		(end 286.878014 -134.53237)
		(width 0.14224)
		(layer "In4.Cu")
		(net "M_E_DQ<39>")
	)
	(segment
		(start 279.175718 -118.003066)
		(end 279.013666 -118.165118)
		(width 0.14224)
		(layer "In4.Cu")
		(net "M_E_DQ<39>")
	)
	(segment
		(start 280.900124 -119.727472)
		(end 281.119072 -119.727472)
		(width 0.14224)
		(layer "In4.Cu")
		(net "M_E_DQ<39>")
	)
	(segment
		(start 287.02 -132.171186)
		(end 287.02 -132.6388)
		(width 0.14224)
		(layer "In4.Cu")
		(net "M_E_DQ<39>")
	)
	(segment
		(start 286.852614 -139.590272)
		(end 286.841692 -139.590272)
		(width 0.14224)
		(layer "In4.Cu")
		(net "M_E_DQ<39>")
	)
	(segment
		(start 278.438864 -117.590316)
		(end 278.600916 -117.428264)
		(width 0.14224)
		(layer "In4.Cu")
		(net "M_E_DQ<39>")
	)
	(segment
		(start 286.852614 -136.58596)
		(end 287.02 -136.753346)
		(width 0.14224)
		(layer "In4.Cu")
		(net "M_E_DQ<39>")
	)
	(segment
		(start 274.340828 -98.995738)
		(end 274.340828 -99.290378)
		(width 0.0889)
		(layer "In4.Cu")
		(net "M_E_DQ<39>")
	)
	(segment
		(start 285.811214 -143.151352)
		(end 286.100012 -143.44015)
		(width 0.14224)
		(layer "In4.Cu")
		(net "M_E_DQ<39>")
	)
	(segment
		(start 282.462478 -121.61393)
		(end 282.462478 -121.832878)
		(width 0.14224)
		(layer "In4.Cu")
		(net "M_E_DQ<39>")
	)
	(segment
		(start 287.021778 -136.015222)
		(end 286.852614 -136.184386)
		(width 0.14224)
		(layer "In4.Cu")
		(net "M_E_DQ<39>")
	)
	(segment
		(start 287.147 -131.064)
		(end 286.766 -131.445)
		(width 0.14224)
		(layer "In4.Cu")
		(net "M_E_DQ<39>")
	)
	(segment
		(start 276.298914 -104.24414)
		(end 276.584664 -104.52989)
		(width 0.0889)
		(layer "In4.Cu")
		(net "M_E_DQ<39>")
	)
	(segment
		(start 286.477456 -139.932156)
		(end 286.049212 -140.3604)
		(width 0.14224)
		(layer "In4.Cu")
		(net "M_E_DQ<39>")
	)
	(segment
		(start 286.9946 -133.985)
		(end 286.878014 -134.101586)
		(width 0.14224)
		(layer "In4.Cu")
		(net "M_E_DQ<39>")
	)
	(segment
		(start 286.9946 -133.6548)
		(end 286.9946 -133.985)
		(width 0.14224)
		(layer "In4.Cu")
		(net "M_E_DQ<39>")
	)
	(segment
		(start 285.922212 -143.941546)
		(end 285.649924 -143.941546)
		(width 0.14224)
		(layer "In4.Cu")
		(net "M_E_DQ<39>")
	)
	(segment
		(start 280.738072 -119.889524)
		(end 280.900124 -119.727472)
		(width 0.14224)
		(layer "In4.Cu")
		(net "M_E_DQ<39>")
	)
	(segment
		(start 276.584664 -115.955064)
		(end 278.219916 -117.590316)
		(width 0.14224)
		(layer "In4.Cu")
		(net "M_E_DQ<39>")
	)
	(segment
		(start 281.312874 -120.683274)
		(end 281.668728 -121.039128)
		(width 0.14224)
		(layer "In4.Cu")
		(net "M_E_DQ<39>")
	)
	(segment
		(start 275.749512 -100.258372)
		(end 275.749512 -102.793292)
		(width 0.0889)
		(layer "In4.Cu")
		(net "M_E_DQ<39>")
	)
	(segment
		(start 280.325322 -119.15267)
		(end 280.16327 -119.314722)
		(width 0.14224)
		(layer "In4.Cu")
		(net "M_E_DQ<39>")
	)
	(segment
		(start 286.068262 -142.3162)
		(end 286.068262 -142.621)
		(width 0.14224)
		(layer "In4.Cu")
		(net "M_E_DQ<39>")
	)
	(segment
		(start 287.02 -132.6388)
		(end 286.7152 -132.9436)
		(width 0.14224)
		(layer "In4.Cu")
		(net "M_E_DQ<39>")
	)
	(segment
		(start 281.887676 -121.039128)
		(end 282.049728 -120.877076)
		(width 0.14224)
		(layer "In4.Cu")
		(net "M_E_DQ<39>")
	)
	(segment
		(start 279.36952 -118.73992)
		(end 279.588468 -118.73992)
		(width 0.14224)
		(layer "In4.Cu")
		(net "M_E_DQ<39>")
	)
	(segment
		(start 286.7152 -132.9436)
		(end 286.7152 -133.3754)
		(width 0.14224)
		(layer "In4.Cu")
		(net "M_E_DQ<39>")
	)
	(segment
		(start 282.268676 -120.877076)
		(end 282.62453 -121.23293)
		(width 0.14224)
		(layer "In4.Cu")
		(net "M_E_DQ<39>")
	)
	(arc
		(start 275.217128 -99.890834)
		(mid 275.502552 -99.974301)
		(end 275.711158 -100.186236)
		(width 0.0889)
		(layer "In4.Cu")
		(net "M_E_DQ<39>")
	)
	(arc
		(start 274.852638 -99.690936)
		(mid 274.992717 -99.833672)
		(end 275.184362 -99.890834)
		(width 0.0889)
		(layer "In4.Cu")
		(net "M_E_DQ<39>")
	)
	(arc
		(start 274.499578 -99.417124)
		(mid 274.703033 -99.519309)
		(end 274.852638 -99.690936)
		(width 0.0889)
		(layer "In4.Cu")
		(net "M_E_DQ<39>")
	)
	(segment
		(start 286.632142 -146.17192)
		(end 286.632142 -145.95348)
		(width 0.1651)
		(layer "F.Cu")
		(net "M_E_DQ<38>")
	)
	(segment
		(start 286.500062 -145.516854)
		(end 286.499808 -145.5166)
		(width 0.1651)
		(layer "F.Cu")
		(net "M_E_DQ<38>")
	)
	(segment
		(start 286.500062 -146.304)
		(end 286.632142 -146.17192)
		(width 0.1651)
		(layer "F.Cu")
		(net "M_E_DQ<38>")
	)
	(segment
		(start 286.500316 -147.27174)
		(end 286.500062 -147.27174)
		(width 0.1651)
		(layer "F.Cu")
		(net "M_E_DQ<38>")
	)
	(segment
		(start 286.632142 -145.95348)
		(end 286.500062 -145.8214)
		(width 0.1651)
		(layer "F.Cu")
		(net "M_E_DQ<38>")
	)
	(segment
		(start 286.500062 -145.8214)
		(end 286.500062 -145.516854)
		(width 0.1651)
		(layer "F.Cu")
		(net "M_E_DQ<38>")
	)
	(segment
		(start 273.769328 -97.014538)
		(end 274.340828 -97.014538)
		(width 0.1651)
		(layer "F.Cu")
		(net "M_E_DQ<38>")
	)
	(segment
		(start 286.500062 -147.27174)
		(end 286.500062 -146.304)
		(width 0.1651)
		(layer "F.Cu")
		(net "M_E_DQ<38>")
	)
	(via
		(at 285.649924 -141.213078)
		(size 0.508)
		(drill 0.254)
		(layers "F.Cu" "B.Cu")
		(net "M_E_DQ<38>")
	)
	(via
		(at 286.499808 -145.5166)
		(size 0.508)
		(drill 0.254)
		(layers "F.Cu" "B.Cu")
		(net "M_E_DQ<38>")
	)
	(via
		(at 274.340828 -97.014538)
		(size 0.508)
		(drill 0.254)
		(layers "F.Cu" "B.Cu")
		(net "M_E_DQ<38>")
	)
	(segment
		(start 285.649924 -142.476982)
		(end 285.649924 -141.213078)
		(width 0.1651)
		(layer "B.Cu")
		(net "M_E_DQ<38>")
	)
	(segment
		(start 285.650432 -142.477236)
		(end 285.649924 -142.476982)
		(width 0.1651)
		(layer "B.Cu")
		(net "M_E_DQ<38>")
	)
	(segment
		(start 274.340828 -97.014538)
		(end 274.010882 -97.776284)
		(width 0.0889)
		(layer "In4.Cu")
		(net "M_E_DQ<38>")
	)
	(segment
		(start 275.177758 -100.081334)
		(end 275.199348 -100.081334)
		(width 0.0889)
		(layer "In4.Cu")
		(net "M_E_DQ<38>")
	)
	(segment
		(start 276.108922 -104.24033)
		(end 275.949664 -104.399588)
		(width 0.0889)
		(layer "In4.Cu")
		(net "M_E_DQ<38>")
	)
	(segment
		(start 274.010882 -97.776284)
		(end 273.994118 -97.804986)
		(width 0.0889)
		(layer "In4.Cu")
		(net "M_E_DQ<38>")
	)
	(segment
		(start 285.481014 -140.137134)
		(end 285.481014 -141.044168)
		(width 0.14224)
		(layer "In4.Cu")
		(net "M_E_DQ<38>")
	)
	(segment
		(start 273.989292 -98.1964)
		(end 273.994118 -98.205036)
		(width 0.0889)
		(layer "In4.Cu")
		(net "M_E_DQ<38>")
	)
	(segment
		(start 286.258 -131.861814)
		(end 286.0802 -132.039614)
		(width 0.14224)
		(layer "In4.Cu")
		(net "M_E_DQ<38>")
	)
	(segment
		(start 274.077684 -99.297236)
		(end 274.287996 -99.507548)
		(width 0.0889)
		(layer "In4.Cu")
		(net "M_E_DQ<38>")
	)
	(segment
		(start 285.216854 -141.646148)
		(end 285.216854 -144.233646)
		(width 0.14224)
		(layer "In4.Cu")
		(net "M_E_DQ<38>")
	)
	(segment
		(start 285.216854 -144.233646)
		(end 286.499808 -145.5166)
		(width 0.14224)
		(layer "In4.Cu")
		(net "M_E_DQ<38>")
	)
	(segment
		(start 286.217614 -136.5758)
		(end 286.07385 -136.719564)
		(width 0.14224)
		(layer "In4.Cu")
		(net "M_E_DQ<38>")
	)
	(segment
		(start 276.108922 -103.421434)
		(end 276.108922 -104.24033)
		(width 0.0889)
		(layer "In4.Cu")
		(net "M_E_DQ<38>")
	)
	(segment
		(start 275.949664 -104.399588)
		(end 275.949664 -116.02212)
		(width 0.14224)
		(layer "In4.Cu")
		(net "M_E_DQ<38>")
	)
	(segment
		(start 286.0802 -132.039614)
		(end 286.0802 -134.0612)
		(width 0.14224)
		(layer "In4.Cu")
		(net "M_E_DQ<38>")
	)
	(segment
		(start 275.55952 -100.307394)
		(end 275.55952 -102.872032)
		(width 0.0889)
		(layer "In4.Cu")
		(net "M_E_DQ<38>")
	)
	(segment
		(start 286.1564 -126.228856)
		(end 286.1564 -129.794)
		(width 0.14224)
		(layer "In4.Cu")
		(net "M_E_DQ<38>")
	)
	(segment
		(start 275.949664 -116.02212)
		(end 286.1564 -126.228856)
		(width 0.14224)
		(layer "In4.Cu")
		(net "M_E_DQ<38>")
	)
	(segment
		(start 275.542502 -100.275644)
		(end 275.55952 -100.307394)
		(width 0.0889)
		(layer "In4.Cu")
		(net "M_E_DQ<38>")
	)
	(segment
		(start 273.994118 -98.205036)
		(end 274.000468 -98.215704)
		(width 0.0889)
		(layer "In4.Cu")
		(net "M_E_DQ<38>")
	)
	(segment
		(start 286.07385 -138.80465)
		(end 286.217614 -138.948414)
		(width 0.14224)
		(layer "In4.Cu")
		(net "M_E_DQ<38>")
	)
	(segment
		(start 286.07385 -136.719564)
		(end 286.07385 -138.80465)
		(width 0.14224)
		(layer "In4.Cu")
		(net "M_E_DQ<38>")
	)
	(segment
		(start 286.1564 -129.794)
		(end 285.9024 -130.048)
		(width 0.14224)
		(layer "In4.Cu")
		(net "M_E_DQ<38>")
	)
	(segment
		(start 275.55952 -102.872032)
		(end 276.108922 -103.421434)
		(width 0.0889)
		(layer "In4.Cu")
		(net "M_E_DQ<38>")
	)
	(segment
		(start 286.258 -131.445)
		(end 286.258 -131.861814)
		(width 0.14224)
		(layer "In4.Cu")
		(net "M_E_DQ<38>")
	)
	(segment
		(start 286.203136 -134.184136)
		(end 286.203136 -134.471664)
		(width 0.14224)
		(layer "In4.Cu")
		(net "M_E_DQ<38>")
	)
	(segment
		(start 285.8008 -135.915654)
		(end 286.217614 -136.332468)
		(width 0.14224)
		(layer "In4.Cu")
		(net "M_E_DQ<38>")
	)
	(segment
		(start 285.9024 -131.0894)
		(end 286.258 -131.445)
		(width 0.14224)
		(layer "In4.Cu")
		(net "M_E_DQ<38>")
	)
	(segment
		(start 285.649924 -141.213078)
		(end 285.216854 -141.646148)
		(width 0.14224)
		(layer "In4.Cu")
		(net "M_E_DQ<38>")
	)
	(segment
		(start 286.217614 -138.948414)
		(end 286.217614 -139.400534)
		(width 0.14224)
		(layer "In4.Cu")
		(net "M_E_DQ<38>")
	)
	(segment
		(start 285.481014 -141.044168)
		(end 285.649924 -141.213078)
		(width 0.14224)
		(layer "In4.Cu")
		(net "M_E_DQ<38>")
	)
	(segment
		(start 286.203136 -134.471664)
		(end 285.8008 -134.874)
		(width 0.14224)
		(layer "In4.Cu")
		(net "M_E_DQ<38>")
	)
	(segment
		(start 285.9024 -130.048)
		(end 285.9024 -131.0894)
		(width 0.14224)
		(layer "In4.Cu")
		(net "M_E_DQ<38>")
	)
	(segment
		(start 286.217614 -136.332468)
		(end 286.217614 -136.5758)
		(width 0.14224)
		(layer "In4.Cu")
		(net "M_E_DQ<38>")
	)
	(segment
		(start 285.8008 -134.874)
		(end 285.8008 -135.915654)
		(width 0.14224)
		(layer "In4.Cu")
		(net "M_E_DQ<38>")
	)
	(segment
		(start 286.0802 -134.0612)
		(end 286.203136 -134.184136)
		(width 0.14224)
		(layer "In4.Cu")
		(net "M_E_DQ<38>")
	)
	(segment
		(start 286.217614 -139.400534)
		(end 285.481014 -140.137134)
		(width 0.14224)
		(layer "In4.Cu")
		(net "M_E_DQ<38>")
	)
	(arc
		(start 274.447508 -99.600512)
		(mid 274.585786 -99.669734)
		(end 274.687538 -99.786186)
		(width 0.0889)
		(layer "In4.Cu")
		(net "M_E_DQ<38>")
	)
	(arc
		(start 273.994118 -97.804986)
		(mid 273.940648 -98.000049)
		(end 273.989292 -98.1964)
		(width 0.0889)
		(layer "In4.Cu")
		(net "M_E_DQ<38>")
	)
	(arc
		(start 275.199348 -100.081334)
		(mid 275.396509 -100.133293)
		(end 275.542502 -100.275644)
		(width 0.0889)
		(layer "In4.Cu")
		(net "M_E_DQ<38>")
	)
	(arc
		(start 274.687538 -99.786186)
		(mid 274.894542 -99.99705)
		(end 275.177758 -100.081334)
		(width 0.0889)
		(layer "In4.Cu")
		(net "M_E_DQ<38>")
	)
	(arc
		(start 273.994118 -98.795586)
		(mid 273.945919 -99.061428)
		(end 274.077684 -99.297236)
		(width 0.0889)
		(layer "In4.Cu")
		(net "M_E_DQ<38>")
	)
	(arc
		(start 274.000468 -98.215704)
		(mid 274.073266 -98.506467)
		(end 273.994118 -98.795586)
		(width 0.0889)
		(layer "In4.Cu")
		(net "M_E_DQ<38>")
	)
	(arc
		(start 274.287996 -99.507548)
		(mid 274.361713 -99.564398)
		(end 274.447508 -99.600512)
		(width 0.0889)
		(layer "In4.Cu")
		(net "M_E_DQ<38>")
	)
	(segment
		(start 279.700482 -142.6718)
		(end 279.699974 -142.677642)
		(width 0.1651)
		(layer "F.Cu")
		(net "M_E_DQ<37>")
	)
	(segment
		(start 272.052288 -97.014538)
		(end 272.623788 -97.014538)
		(width 0.1651)
		(layer "F.Cu")
		(net "M_E_DQ<37>")
	)
	(segment
		(start 279.699974 -142.677642)
		(end 279.699974 -143.941546)
		(width 0.1651)
		(layer "F.Cu")
		(net "M_E_DQ<37>")
	)
	(via
		(at 280.473658 -139.932156)
		(size 0.508)
		(drill 0.254)
		(layers "F.Cu" "B.Cu")
		(net "M_E_DQ<37>")
	)
	(via
		(at 272.623788 -97.014538)
		(size 0.508)
		(drill 0.254)
		(layers "F.Cu" "B.Cu")
		(net "M_E_DQ<37>")
	)
	(via
		(at 279.699974 -143.941546)
		(size 0.508)
		(drill 0.254)
		(layers "F.Cu" "B.Cu")
		(net "M_E_DQ<37>")
	)
	(segment
		(start 280.549858 -139.855956)
		(end 280.473658 -139.932156)
		(width 0.1651)
		(layer "B.Cu")
		(net "M_E_DQ<37>")
	)
	(segment
		(start 280.549858 -137.877296)
		(end 280.549858 -139.855956)
		(width 0.1651)
		(layer "B.Cu")
		(net "M_E_DQ<37>")
	)
	(segment
		(start 280.550366 -137.877296)
		(end 280.549858 -137.877296)
		(width 0.1651)
		(layer "B.Cu")
		(net "M_E_DQ<37>")
	)
	(segment
		(start 280.9748 -136.666986)
		(end 280.9748 -138.811)
		(width 0.14224)
		(layer "In4.Cu")
		(net "M_E_DQ<37>")
	)
	(segment
		(start 280.150062 -141.528546)
		(end 279.861264 -141.817344)
		(width 0.14224)
		(layer "In4.Cu")
		(net "M_E_DQ<37>")
	)
	(segment
		(start 275.8694 -121.431558)
		(end 275.8694 -121.744486)
		(width 0.14224)
		(layer "In4.Cu")
		(net "M_E_DQ<37>")
	)
	(segment
		(start 280.947114 -131.370578)
		(end 280.883614 -131.434078)
		(width 0.14224)
		(layer "In4.Cu")
		(net "M_E_DQ<37>")
	)
	(segment
		(start 271.906746 -103.074724)
		(end 271.906746 -105.985056)
		(width 0.0889)
		(layer "In4.Cu")
		(net "M_E_DQ<37>")
	)
	(segment
		(start 276.125432 -122.619262)
		(end 276.476968 -122.267726)
		(width 0.14224)
		(layer "In4.Cu")
		(net "M_E_DQ<37>")
	)
	(segment
		(start 280.124662 -143.561054)
		(end 280.124662 -143.789146)
		(width 0.14224)
		(layer "In4.Cu")
		(net "M_E_DQ<37>")
	)
	(segment
		(start 280.858214 -138.927586)
		(end 280.858214 -139.5476)
		(width 0.14224)
		(layer "In4.Cu")
		(net "M_E_DQ<37>")
	)
	(segment
		(start 275.560028 -122.341386)
		(end 275.837904 -122.619262)
		(width 0.14224)
		(layer "In4.Cu")
		(net "M_E_DQ<37>")
	)
	(segment
		(start 280.473658 -139.932156)
		(end 280.451306 -139.932156)
		(width 0.14224)
		(layer "In4.Cu")
		(net "M_E_DQ<37>")
	)
	(segment
		(start 272.114264 -118.895622)
		(end 274.697698 -121.479056)
		(width 0.14224)
		(layer "In4.Cu")
		(net "M_E_DQ<37>")
	)
	(segment
		(start 275.837904 -122.619262)
		(end 276.125432 -122.619262)
		(width 0.14224)
		(layer "In4.Cu")
		(net "M_E_DQ<37>")
	)
	(segment
		(start 272.623788 -97.014538)
		(end 272.286476 -97.014538)
		(width 0.0889)
		(layer "In4.Cu")
		(net "M_E_DQ<37>")
	)
	(segment
		(start 271.500092 -99.052126)
		(end 271.499838 -99.05238)
		(width 0.0889)
		(layer "In4.Cu")
		(net "M_E_DQ<37>")
	)
	(segment
		(start 272.223738 -98.000312)
		(end 271.500092 -98.723958)
		(width 0.0889)
		(layer "In4.Cu")
		(net "M_E_DQ<37>")
	)
	(segment
		(start 280.124662 -143.789146)
		(end 279.972262 -143.941546)
		(width 0.14224)
		(layer "In4.Cu")
		(net "M_E_DQ<37>")
	)
	(segment
		(start 276.476968 -122.267726)
		(end 276.730714 -122.267726)
		(width 0.14224)
		(layer "In4.Cu")
		(net "M_E_DQ<37>")
	)
	(segment
		(start 280.883614 -134.670038)
		(end 281.010614 -134.797038)
		(width 0.14224)
		(layer "In4.Cu")
		(net "M_E_DQ<37>")
	)
	(segment
		(start 280.883614 -131.8514)
		(end 280.9748 -131.942586)
		(width 0.14224)
		(layer "In4.Cu")
		(net "M_E_DQ<37>")
	)
	(segment
		(start 271.906746 -105.985056)
		(end 272.114264 -106.192574)
		(width 0.0889)
		(layer "In4.Cu")
		(net "M_E_DQ<37>")
	)
	(segment
		(start 280.9748 -138.811)
		(end 280.858214 -138.927586)
		(width 0.14224)
		(layer "In4.Cu")
		(net "M_E_DQ<37>")
	)
	(segment
		(start 280.858214 -139.5476)
		(end 280.473658 -139.932156)
		(width 0.14224)
		(layer "In4.Cu")
		(net "M_E_DQ<37>")
	)
	(segment
		(start 280.947114 -129.994914)
		(end 280.947114 -131.370578)
		(width 0.14224)
		(layer "In4.Cu")
		(net "M_E_DQ<37>")
	)
	(segment
		(start 280.883614 -131.434078)
		(end 280.883614 -131.8514)
		(width 0.14224)
		(layer "In4.Cu")
		(net "M_E_DQ<37>")
	)
	(segment
		(start 280.858214 -136.005824)
		(end 280.858214 -136.5504)
		(width 0.14224)
		(layer "In4.Cu")
		(net "M_E_DQ<37>")
	)
	(segment
		(start 280.6954 -126.232412)
		(end 280.6954 -129.7432)
		(width 0.14224)
		(layer "In4.Cu")
		(net "M_E_DQ<37>")
	)
	(segment
		(start 271.500092 -98.723958)
		(end 271.500092 -99.052126)
		(width 0.0889)
		(layer "In4.Cu")
		(net "M_E_DQ<37>")
	)
	(segment
		(start 280.099262 -142.747746)
		(end 279.861264 -142.985744)
		(width 0.14224)
		(layer "In4.Cu")
		(net "M_E_DQ<37>")
	)
	(segment
		(start 281.010614 -135.853424)
		(end 280.858214 -136.005824)
		(width 0.14224)
		(layer "In4.Cu")
		(net "M_E_DQ<37>")
	)
	(segment
		(start 280.858214 -136.5504)
		(end 280.9748 -136.666986)
		(width 0.14224)
		(layer "In4.Cu")
		(net "M_E_DQ<37>")
	)
	(segment
		(start 275.607526 -121.169684)
		(end 275.8694 -121.431558)
		(width 0.14224)
		(layer "In4.Cu")
		(net "M_E_DQ<37>")
	)
	(segment
		(start 279.861264 -142.985744)
		(end 279.861264 -143.297656)
		(width 0.14224)
		(layer "In4.Cu")
		(net "M_E_DQ<37>")
	)
	(segment
		(start 275.294598 -121.169684)
		(end 275.607526 -121.169684)
		(width 0.14224)
		(layer "In4.Cu")
		(net "M_E_DQ<37>")
	)
	(segment
		(start 274.985226 -121.479056)
		(end 275.294598 -121.169684)
		(width 0.14224)
		(layer "In4.Cu")
		(net "M_E_DQ<37>")
	)
	(segment
		(start 271.499838 -99.05238)
		(end 271.499838 -102.667816)
		(width 0.0889)
		(layer "In4.Cu")
		(net "M_E_DQ<37>")
	)
	(segment
		(start 279.861264 -142.154656)
		(end 280.099262 -142.392654)
		(width 0.14224)
		(layer "In4.Cu")
		(net "M_E_DQ<37>")
	)
	(segment
		(start 272.114264 -106.192574)
		(end 272.114264 -118.895622)
		(width 0.14224)
		(layer "In4.Cu")
		(net "M_E_DQ<37>")
	)
	(segment
		(start 275.560028 -122.053858)
		(end 275.560028 -122.341386)
		(width 0.14224)
		(layer "In4.Cu")
		(net "M_E_DQ<37>")
	)
	(segment
		(start 275.8694 -121.744486)
		(end 275.560028 -122.053858)
		(width 0.14224)
		(layer "In4.Cu")
		(net "M_E_DQ<37>")
	)
	(segment
		(start 280.6954 -129.7432)
		(end 280.947114 -129.994914)
		(width 0.14224)
		(layer "In4.Cu")
		(net "M_E_DQ<37>")
	)
	(segment
		(start 272.286476 -97.014538)
		(end 272.223738 -97.077276)
		(width 0.0889)
		(layer "In4.Cu")
		(net "M_E_DQ<37>")
	)
	(segment
		(start 274.697698 -121.479056)
		(end 274.985226 -121.479056)
		(width 0.14224)
		(layer "In4.Cu")
		(net "M_E_DQ<37>")
	)
	(segment
		(start 279.861264 -141.817344)
		(end 279.861264 -142.154656)
		(width 0.14224)
		(layer "In4.Cu")
		(net "M_E_DQ<37>")
	)
	(segment
		(start 279.861264 -143.297656)
		(end 280.124662 -143.561054)
		(width 0.14224)
		(layer "In4.Cu")
		(net "M_E_DQ<37>")
	)
	(segment
		(start 280.883614 -134.025386)
		(end 280.883614 -134.670038)
		(width 0.14224)
		(layer "In4.Cu")
		(net "M_E_DQ<37>")
	)
	(segment
		(start 280.9748 -133.9342)
		(end 280.883614 -134.025386)
		(width 0.14224)
		(layer "In4.Cu")
		(net "M_E_DQ<37>")
	)
	(segment
		(start 281.010614 -134.797038)
		(end 281.010614 -135.853424)
		(width 0.14224)
		(layer "In4.Cu")
		(net "M_E_DQ<37>")
	)
	(segment
		(start 280.023062 -140.9192)
		(end 280.150062 -141.0462)
		(width 0.14224)
		(layer "In4.Cu")
		(net "M_E_DQ<37>")
	)
	(segment
		(start 279.972262 -143.941546)
		(end 279.699974 -143.941546)
		(width 0.14224)
		(layer "In4.Cu")
		(net "M_E_DQ<37>")
	)
	(segment
		(start 280.150062 -141.0462)
		(end 280.150062 -141.528546)
		(width 0.14224)
		(layer "In4.Cu")
		(net "M_E_DQ<37>")
	)
	(segment
		(start 280.023062 -140.3604)
		(end 280.023062 -140.9192)
		(width 0.14224)
		(layer "In4.Cu")
		(net "M_E_DQ<37>")
	)
	(segment
		(start 280.9748 -131.942586)
		(end 280.9748 -133.9342)
		(width 0.14224)
		(layer "In4.Cu")
		(net "M_E_DQ<37>")
	)
	(segment
		(start 271.499838 -102.667816)
		(end 271.906746 -103.074724)
		(width 0.0889)
		(layer "In4.Cu")
		(net "M_E_DQ<37>")
	)
	(segment
		(start 280.099262 -142.392654)
		(end 280.099262 -142.747746)
		(width 0.14224)
		(layer "In4.Cu")
		(net "M_E_DQ<37>")
	)
	(segment
		(start 272.223738 -97.077276)
		(end 272.223738 -98.000312)
		(width 0.0889)
		(layer "In4.Cu")
		(net "M_E_DQ<37>")
	)
	(segment
		(start 280.451306 -139.932156)
		(end 280.023062 -140.3604)
		(width 0.14224)
		(layer "In4.Cu")
		(net "M_E_DQ<37>")
	)
	(segment
		(start 276.730714 -122.267726)
		(end 280.6954 -126.232412)
		(width 0.14224)
		(layer "In4.Cu")
		(net "M_E_DQ<37>")
	)
	(segment
		(start 280.550366 -147.27174)
		(end 280.549858 -147.27174)
		(width 0.1651)
		(layer "F.Cu")
		(net "M_E_DQ<36>")
	)
	(segment
		(start 280.549858 -147.27174)
		(end 280.549858 -145.946368)
		(width 0.1651)
		(layer "F.Cu")
		(net "M_E_DQ<36>")
	)
	(segment
		(start 280.549858 -145.946368)
		(end 280.451814 -145.415)
		(width 0.1651)
		(layer "F.Cu")
		(net "M_E_DQ<36>")
	)
	(segment
		(start 272.052288 -96.023938)
		(end 272.623788 -96.023938)
		(width 0.1651)
		(layer "F.Cu")
		(net "M_E_DQ<36>")
	)
	(via
		(at 280.451814 -145.415)
		(size 0.508)
		(drill 0.254)
		(layers "F.Cu" "B.Cu")
		(net "M_E_DQ<36>")
	)
	(via
		(at 279.699974 -141.213078)
		(size 0.508)
		(drill 0.254)
		(layers "F.Cu" "B.Cu")
		(net "M_E_DQ<36>")
	)
	(via
		(at 272.623788 -96.023938)
		(size 0.508)
		(drill 0.254)
		(layers "F.Cu" "B.Cu")
		(net "M_E_DQ<36>")
	)
	(segment
		(start 279.699974 -142.476982)
		(end 279.699974 -141.213078)
		(width 0.1651)
		(layer "B.Cu")
		(net "M_E_DQ<36>")
	)
	(segment
		(start 279.700482 -142.477236)
		(end 279.699974 -142.476982)
		(width 0.1651)
		(layer "B.Cu")
		(net "M_E_DQ<36>")
	)
	(segment
		(start 279.699974 -141.213078)
		(end 279.266904 -141.646148)
		(width 0.14224)
		(layer "In4.Cu")
		(net "M_E_DQ<36>")
	)
	(segment
		(start 271.479264 -119.136668)
		(end 280.157428 -127.814832)
		(width 0.14224)
		(layer "In4.Cu")
		(net "M_E_DQ<36>")
	)
	(segment
		(start 280.185114 -139.358878)
		(end 279.562306 -139.981686)
		(width 0.14224)
		(layer "In4.Cu")
		(net "M_E_DQ<36>")
	)
	(segment
		(start 271.716246 -103.152956)
		(end 271.716246 -105.894886)
		(width 0.0889)
		(layer "In4.Cu")
		(net "M_E_DQ<36>")
	)
	(segment
		(start 280.157428 -129.798064)
		(end 279.969214 -129.986278)
		(width 0.14224)
		(layer "In4.Cu")
		(net "M_E_DQ<36>")
	)
	(segment
		(start 279.98674 -134.66826)
		(end 279.98674 -135.981694)
		(width 0.14224)
		(layer "In4.Cu")
		(net "M_E_DQ<36>")
	)
	(segment
		(start 279.266904 -144.17929)
		(end 279.424892 -144.337278)
		(width 0.14224)
		(layer "In4.Cu")
		(net "M_E_DQ<36>")
	)
	(segment
		(start 279.562306 -141.07541)
		(end 279.699974 -141.213078)
		(width 0.14224)
		(layer "In4.Cu")
		(net "M_E_DQ<36>")
	)
	(segment
		(start 271.309338 -98.64598)
		(end 271.309338 -102.746048)
		(width 0.0889)
		(layer "In4.Cu")
		(net "M_E_DQ<36>")
	)
	(segment
		(start 280.200862 -145.415)
		(end 280.451814 -145.415)
		(width 0.14224)
		(layer "In4.Cu")
		(net "M_E_DQ<36>")
	)
	(segment
		(start 280.197814 -134.457186)
		(end 279.98674 -134.66826)
		(width 0.14224)
		(layer "In4.Cu")
		(net "M_E_DQ<36>")
	)
	(segment
		(start 280.185114 -136.180068)
		(end 280.185114 -139.358878)
		(width 0.14224)
		(layer "In4.Cu")
		(net "M_E_DQ<36>")
	)
	(segment
		(start 271.479264 -106.131868)
		(end 271.479264 -119.136668)
		(width 0.14224)
		(layer "In4.Cu")
		(net "M_E_DQ<36>")
	)
	(segment
		(start 272.033746 -96.162876)
		(end 272.033746 -97.921572)
		(width 0.0889)
		(layer "In4.Cu")
		(net "M_E_DQ<36>")
	)
	(segment
		(start 271.309338 -102.746048)
		(end 271.716246 -103.152956)
		(width 0.0889)
		(layer "In4.Cu")
		(net "M_E_DQ<36>")
	)
	(segment
		(start 272.033746 -97.921572)
		(end 271.309338 -98.64598)
		(width 0.0889)
		(layer "In4.Cu")
		(net "M_E_DQ<36>")
	)
	(segment
		(start 272.623788 -96.023938)
		(end 272.172684 -96.023938)
		(width 0.0889)
		(layer "In4.Cu")
		(net "M_E_DQ<36>")
	)
	(segment
		(start 279.266904 -141.646148)
		(end 279.266904 -144.17929)
		(width 0.14224)
		(layer "In4.Cu")
		(net "M_E_DQ<36>")
	)
	(segment
		(start 279.969214 -131.192778)
		(end 280.197814 -131.421378)
		(width 0.14224)
		(layer "In4.Cu")
		(net "M_E_DQ<36>")
	)
	(segment
		(start 279.562306 -139.981686)
		(end 279.562306 -141.07541)
		(width 0.14224)
		(layer "In4.Cu")
		(net "M_E_DQ<36>")
	)
	(segment
		(start 280.197814 -131.421378)
		(end 280.197814 -134.457186)
		(width 0.14224)
		(layer "In4.Cu")
		(net "M_E_DQ<36>")
	)
	(segment
		(start 279.424892 -144.337278)
		(end 279.424892 -144.63903)
		(width 0.14224)
		(layer "In4.Cu")
		(net "M_E_DQ<36>")
	)
	(segment
		(start 279.424892 -144.63903)
		(end 280.200862 -145.415)
		(width 0.14224)
		(layer "In4.Cu")
		(net "M_E_DQ<36>")
	)
	(segment
		(start 280.157428 -127.814832)
		(end 280.157428 -129.798064)
		(width 0.14224)
		(layer "In4.Cu")
		(net "M_E_DQ<36>")
	)
	(segment
		(start 271.716246 -105.894886)
		(end 271.479264 -106.131868)
		(width 0.0889)
		(layer "In4.Cu")
		(net "M_E_DQ<36>")
	)
	(segment
		(start 279.98674 -135.981694)
		(end 280.185114 -136.180068)
		(width 0.14224)
		(layer "In4.Cu")
		(net "M_E_DQ<36>")
	)
	(segment
		(start 279.969214 -129.986278)
		(end 279.969214 -131.192778)
		(width 0.14224)
		(layer "In4.Cu")
		(net "M_E_DQ<36>")
	)
	(segment
		(start 272.172684 -96.023938)
		(end 272.033746 -96.162876)
		(width 0.0889)
		(layer "In4.Cu")
		(net "M_E_DQ<36>")
	)
	(segment
		(start 287.350454 -142.6718)
		(end 287.349946 -142.677642)
		(width 0.1651)
		(layer "F.Cu")
		(net "M_E_DQ<35>")
	)
	(segment
		(start 287.349946 -142.677642)
		(end 287.349946 -143.941546)
		(width 0.1651)
		(layer "F.Cu")
		(net "M_E_DQ<35>")
	)
	(segment
		(start 274.627848 -98.500184)
		(end 275.199348 -98.500184)
		(width 0.1651)
		(layer "F.Cu")
		(net "M_E_DQ<35>")
	)
	(via
		(at 288.19983 -139.932156)
		(size 0.508)
		(drill 0.254)
		(layers "F.Cu" "B.Cu")
		(net "M_E_DQ<35>")
	)
	(via
		(at 287.349946 -143.941546)
		(size 0.508)
		(drill 0.254)
		(layers "F.Cu" "B.Cu")
		(net "M_E_DQ<35>")
	)
	(via
		(at 275.199348 -98.500184)
		(size 0.508)
		(drill 0.254)
		(layers "F.Cu" "B.Cu")
		(net "M_E_DQ<35>")
	)
	(segment
		(start 288.19983 -137.877296)
		(end 288.19983 -139.932156)
		(width 0.1651)
		(layer "B.Cu")
		(net "M_E_DQ<35>")
	)
	(segment
		(start 288.200338 -137.877296)
		(end 288.19983 -137.877296)
		(width 0.1651)
		(layer "B.Cu")
		(net "M_E_DQ<35>")
	)
	(segment
		(start 287.800034 -143.44015)
		(end 287.800034 -143.763746)
		(width 0.14224)
		(layer "In4.Cu")
		(net "M_E_DQ<35>")
	)
	(segment
		(start 288.554414 -129.804414)
		(end 288.706814 -129.956814)
		(width 0.14224)
		(layer "In4.Cu")
		(net "M_E_DQ<35>")
	)
	(segment
		(start 277.857204 -114.862356)
		(end 285.04515 -122.050302)
		(width 0.14224)
		(layer "In4.Cu")
		(net "M_E_DQ<35>")
	)
	(segment
		(start 286.920686 -124.144786)
		(end 286.7025 -124.362972)
		(width 0.14224)
		(layer "In4.Cu")
		(net "M_E_DQ<35>")
	)
	(segment
		(start 288.19983 -139.945364)
		(end 288.19983 -139.932156)
		(width 0.14224)
		(layer "In4.Cu")
		(net "M_E_DQ<35>")
	)
	(segment
		(start 287.749234 -140.3604)
		(end 287.749234 -140.790168)
		(width 0.14224)
		(layer "In4.Cu")
		(net "M_E_DQ<35>")
	)
	(segment
		(start 285.981902 -123.926854)
		(end 286.20085 -123.926854)
		(width 0.14224)
		(layer "In4.Cu")
		(net "M_E_DQ<35>")
	)
	(segment
		(start 287.511236 -142.059152)
		(end 287.768284 -142.3162)
		(width 0.14224)
		(layer "In4.Cu")
		(net "M_E_DQ<35>")
	)
	(segment
		(start 285.04515 -122.050302)
		(end 285.04515 -122.26925)
		(width 0.14224)
		(layer "In4.Cu")
		(net "M_E_DQ<35>")
	)
	(segment
		(start 286.7025 -124.542804)
		(end 286.991552 -124.831856)
		(width 0.14224)
		(layer "In4.Cu")
		(net "M_E_DQ<35>")
	)
	(segment
		(start 285.731966 -123.45797)
		(end 285.731966 -123.676918)
		(width 0.14224)
		(layer "In4.Cu")
		(net "M_E_DQ<35>")
	)
	(segment
		(start 287.793684 -141.5034)
		(end 287.511236 -141.785848)
		(width 0.14224)
		(layer "In4.Cu")
		(net "M_E_DQ<35>")
	)
	(segment
		(start 285.04515 -122.26925)
		(end 284.794198 -122.520202)
		(width 0.14224)
		(layer "In4.Cu")
		(net "M_E_DQ<35>")
	)
	(segment
		(start 284.794198 -122.520202)
		(end 284.794198 -122.73915)
		(width 0.14224)
		(layer "In4.Cu")
		(net "M_E_DQ<35>")
	)
	(segment
		(start 287.511236 -143.151352)
		(end 287.800034 -143.44015)
		(width 0.14224)
		(layer "In4.Cu")
		(net "M_E_DQ<35>")
	)
	(segment
		(start 286.991552 -124.831856)
		(end 287.171384 -124.831856)
		(width 0.14224)
		(layer "In4.Cu")
		(net "M_E_DQ<35>")
	)
	(segment
		(start 285.982918 -122.98807)
		(end 285.982918 -123.207018)
		(width 0.14224)
		(layer "In4.Cu")
		(net "M_E_DQ<35>")
	)
	(segment
		(start 285.044134 -122.989086)
		(end 285.263082 -122.989086)
		(width 0.14224)
		(layer "In4.Cu")
		(net "M_E_DQ<35>")
	)
	(segment
		(start 287.768284 -142.3162)
		(end 287.768284 -142.621)
		(width 0.14224)
		(layer "In4.Cu")
		(net "M_E_DQ<35>")
	)
	(segment
		(start 287.749234 -140.790168)
		(end 287.793684 -140.834618)
		(width 0.14224)
		(layer "In4.Cu")
		(net "M_E_DQ<35>")
	)
	(segment
		(start 288.4678 -131.927854)
		(end 288.6202 -132.080254)
		(width 0.14224)
		(layer "In4.Cu")
		(net "M_E_DQ<35>")
	)
	(segment
		(start 286.20085 -123.926854)
		(end 286.451802 -123.675902)
		(width 0.14224)
		(layer "In4.Cu")
		(net "M_E_DQ<35>")
	)
	(segment
		(start 275.461222 -98.959416)
		(end 275.500084 -98.982276)
		(width 0.0889)
		(layer "In4.Cu")
		(net "M_E_DQ<35>")
	)
	(segment
		(start 277.598886 -103.55834)
		(end 277.598886 -103.800656)
		(width 0.0889)
		(layer "In4.Cu")
		(net "M_E_DQ<35>")
	)
	(segment
		(start 288.529014 -136.53516)
		(end 288.6202 -136.626346)
		(width 0.14224)
		(layer "In4.Cu")
		(net "M_E_DQ<35>")
	)
	(segment
		(start 288.567114 -134.523226)
		(end 288.783014 -134.739126)
		(width 0.14224)
		(layer "In4.Cu")
		(net "M_E_DQ<35>")
	)
	(segment
		(start 288.529014 -138.876786)
		(end 288.529014 -139.61618)
		(width 0.14224)
		(layer "In4.Cu")
		(net "M_E_DQ<35>")
	)
	(segment
		(start 288.6202 -138.7856)
		(end 288.529014 -138.876786)
		(width 0.14224)
		(layer "In4.Cu")
		(net "M_E_DQ<35>")
	)
	(segment
		(start 288.6202 -132.080254)
		(end 288.6202 -134.0866)
		(width 0.14224)
		(layer "In4.Cu")
		(net "M_E_DQ<35>")
	)
	(segment
		(start 277.598886 -103.800656)
		(end 277.857204 -104.058974)
		(width 0.0889)
		(layer "In4.Cu")
		(net "M_E_DQ<35>")
	)
	(segment
		(start 288.783014 -135.955532)
		(end 288.529014 -136.209532)
		(width 0.14224)
		(layer "In4.Cu")
		(net "M_E_DQ<35>")
	)
	(segment
		(start 285.514034 -122.738134)
		(end 285.732982 -122.738134)
		(width 0.14224)
		(layer "In4.Cu")
		(net "M_E_DQ<35>")
	)
	(segment
		(start 284.794198 -122.73915)
		(end 285.044134 -122.989086)
		(width 0.14224)
		(layer "In4.Cu")
		(net "M_E_DQ<35>")
	)
	(segment
		(start 288.6202 -134.0866)
		(end 288.567114 -134.139686)
		(width 0.14224)
		(layer "In4.Cu")
		(net "M_E_DQ<35>")
	)
	(segment
		(start 286.920686 -123.925838)
		(end 286.920686 -124.144786)
		(width 0.14224)
		(layer "In4.Cu")
		(net "M_E_DQ<35>")
	)
	(segment
		(start 287.793684 -140.834618)
		(end 287.793684 -141.5034)
		(width 0.14224)
		(layer "In4.Cu")
		(net "M_E_DQ<35>")
	)
	(segment
		(start 288.706814 -129.956814)
		(end 288.706814 -131.268978)
		(width 0.14224)
		(layer "In4.Cu")
		(net "M_E_DQ<35>")
	)
	(segment
		(start 287.800034 -143.763746)
		(end 287.622234 -143.941546)
		(width 0.14224)
		(layer "In4.Cu")
		(net "M_E_DQ<35>")
	)
	(segment
		(start 287.608518 -124.61367)
		(end 288.1122 -125.117352)
		(width 0.14224)
		(layer "In4.Cu")
		(net "M_E_DQ<35>")
	)
	(segment
		(start 277.857204 -104.058974)
		(end 277.857204 -114.862356)
		(width 0.14224)
		(layer "In4.Cu")
		(net "M_E_DQ<35>")
	)
	(segment
		(start 285.732982 -122.738134)
		(end 285.982918 -122.98807)
		(width 0.14224)
		(layer "In4.Cu")
		(net "M_E_DQ<35>")
	)
	(segment
		(start 287.171384 -124.831856)
		(end 287.38957 -124.61367)
		(width 0.14224)
		(layer "In4.Cu")
		(net "M_E_DQ<35>")
	)
	(segment
		(start 285.731966 -123.676918)
		(end 285.981902 -123.926854)
		(width 0.14224)
		(layer "In4.Cu")
		(net "M_E_DQ<35>")
	)
	(segment
		(start 288.6202 -136.626346)
		(end 288.6202 -138.7856)
		(width 0.14224)
		(layer "In4.Cu")
		(net "M_E_DQ<35>")
	)
	(segment
		(start 276.057614 -99.395788)
		(end 276.079204 -99.395788)
		(width 0.0889)
		(layer "In4.Cu")
		(net "M_E_DQ<35>")
	)
	(segment
		(start 286.451802 -123.675902)
		(end 286.67075 -123.675902)
		(width 0.14224)
		(layer "In4.Cu")
		(net "M_E_DQ<35>")
	)
	(segment
		(start 287.511236 -141.785848)
		(end 287.511236 -142.059152)
		(width 0.14224)
		(layer "In4.Cu")
		(net "M_E_DQ<35>")
	)
	(segment
		(start 287.622234 -143.941546)
		(end 287.349946 -143.941546)
		(width 0.14224)
		(layer "In4.Cu")
		(net "M_E_DQ<35>")
	)
	(segment
		(start 288.706814 -131.268978)
		(end 288.4678 -131.507992)
		(width 0.14224)
		(layer "In4.Cu")
		(net "M_E_DQ<35>")
	)
	(segment
		(start 288.529014 -136.209532)
		(end 288.529014 -136.53516)
		(width 0.14224)
		(layer "In4.Cu")
		(net "M_E_DQ<35>")
	)
	(segment
		(start 288.1122 -127.381)
		(end 288.554414 -127.823214)
		(width 0.14224)
		(layer "In4.Cu")
		(net "M_E_DQ<35>")
	)
	(segment
		(start 288.1122 -125.117352)
		(end 288.1122 -127.381)
		(width 0.14224)
		(layer "In4.Cu")
		(net "M_E_DQ<35>")
	)
	(segment
		(start 276.516084 -102.475538)
		(end 277.598886 -103.55834)
		(width 0.0889)
		(layer "In4.Cu")
		(net "M_E_DQ<35>")
	)
	(segment
		(start 288.19983 -139.932156)
		(end 288.177478 -139.932156)
		(width 0.14224)
		(layer "In4.Cu")
		(net "M_E_DQ<35>")
	)
	(segment
		(start 287.511236 -142.878048)
		(end 287.511236 -143.151352)
		(width 0.14224)
		(layer "In4.Cu")
		(net "M_E_DQ<35>")
	)
	(segment
		(start 288.177478 -139.932156)
		(end 287.749234 -140.3604)
		(width 0.14224)
		(layer "In4.Cu")
		(net "M_E_DQ<35>")
	)
	(segment
		(start 288.529014 -139.61618)
		(end 288.19983 -139.945364)
		(width 0.14224)
		(layer "In4.Cu")
		(net "M_E_DQ<35>")
	)
	(segment
		(start 285.263082 -122.989086)
		(end 285.514034 -122.738134)
		(width 0.14224)
		(layer "In4.Cu")
		(net "M_E_DQ<35>")
	)
	(segment
		(start 286.7025 -124.362972)
		(end 286.7025 -124.542804)
		(width 0.14224)
		(layer "In4.Cu")
		(net "M_E_DQ<35>")
	)
	(segment
		(start 288.4678 -131.507992)
		(end 288.4678 -131.927854)
		(width 0.14224)
		(layer "In4.Cu")
		(net "M_E_DQ<35>")
	)
	(segment
		(start 288.567114 -134.139686)
		(end 288.567114 -134.523226)
		(width 0.14224)
		(layer "In4.Cu")
		(net "M_E_DQ<35>")
	)
	(segment
		(start 275.711158 -99.195636)
		(end 275.71446 -99.201478)
		(width 0.0889)
		(layer "In4.Cu")
		(net "M_E_DQ<35>")
	)
	(segment
		(start 287.768284 -142.621)
		(end 287.511236 -142.878048)
		(width 0.14224)
		(layer "In4.Cu")
		(net "M_E_DQ<35>")
	)
	(segment
		(start 287.38957 -124.61367)
		(end 287.608518 -124.61367)
		(width 0.14224)
		(layer "In4.Cu")
		(net "M_E_DQ<35>")
	)
	(segment
		(start 276.516084 -100.372926)
		(end 276.516084 -102.475538)
		(width 0.0889)
		(layer "In4.Cu")
		(net "M_E_DQ<35>")
	)
	(segment
		(start 285.982918 -123.207018)
		(end 285.731966 -123.45797)
		(width 0.14224)
		(layer "In4.Cu")
		(net "M_E_DQ<35>")
	)
	(segment
		(start 288.783014 -134.739126)
		(end 288.783014 -135.955532)
		(width 0.14224)
		(layer "In4.Cu")
		(net "M_E_DQ<35>")
	)
	(segment
		(start 288.554414 -127.823214)
		(end 288.554414 -129.804414)
		(width 0.14224)
		(layer "In4.Cu")
		(net "M_E_DQ<35>")
	)
	(segment
		(start 276.575774 -100.270818)
		(end 276.516084 -100.372926)
		(width 0.0889)
		(layer "In4.Cu")
		(net "M_E_DQ<35>")
	)
	(segment
		(start 286.67075 -123.675902)
		(end 286.920686 -123.925838)
		(width 0.14224)
		(layer "In4.Cu")
		(net "M_E_DQ<35>")
	)
	(arc
		(start 275.71446 -99.201478)
		(mid 275.860426 -99.343877)
		(end 276.057614 -99.395788)
		(width 0.0889)
		(layer "In4.Cu")
		(net "M_E_DQ<35>")
	)
	(arc
		(start 275.500084 -98.982276)
		(mid 275.619382 -99.07534)
		(end 275.711158 -99.195636)
		(width 0.0889)
		(layer "In4.Cu")
		(net "M_E_DQ<35>")
	)
	(arc
		(start 275.199348 -98.500184)
		(mid 275.269433 -98.764485)
		(end 275.461222 -98.959416)
		(width 0.0889)
		(layer "In4.Cu")
		(net "M_E_DQ<35>")
	)
	(arc
		(start 276.079204 -99.395788)
		(mid 276.571594 -99.694721)
		(end 276.575774 -100.270818)
		(width 0.0889)
		(layer "In4.Cu")
		(net "M_E_DQ<35>")
	)
	(segment
		(start 274.627848 -97.509584)
		(end 275.199348 -97.509584)
		(width 0.1651)
		(layer "F.Cu")
		(net "M_E_DQ<34>")
	)
	(segment
		(start 288.331402 -146.14906)
		(end 288.331402 -145.92554)
		(width 0.1651)
		(layer "F.Cu")
		(net "M_E_DQ<34>")
	)
	(segment
		(start 288.200338 -147.27174)
		(end 288.19983 -147.27174)
		(width 0.1651)
		(layer "F.Cu")
		(net "M_E_DQ<34>")
	)
	(segment
		(start 288.19983 -145.793968)
		(end 288.19983 -145.5166)
		(width 0.1651)
		(layer "F.Cu")
		(net "M_E_DQ<34>")
	)
	(segment
		(start 288.19983 -146.280632)
		(end 288.331402 -146.14906)
		(width 0.1651)
		(layer "F.Cu")
		(net "M_E_DQ<34>")
	)
	(segment
		(start 288.19983 -147.27174)
		(end 288.19983 -146.280632)
		(width 0.1651)
		(layer "F.Cu")
		(net "M_E_DQ<34>")
	)
	(segment
		(start 288.331402 -145.92554)
		(end 288.19983 -145.793968)
		(width 0.1651)
		(layer "F.Cu")
		(net "M_E_DQ<34>")
	)
	(via
		(at 287.349946 -141.213078)
		(size 0.508)
		(drill 0.254)
		(layers "F.Cu" "B.Cu")
		(net "M_E_DQ<34>")
	)
	(via
		(at 288.19983 -145.5166)
		(size 0.508)
		(drill 0.254)
		(layers "F.Cu" "B.Cu")
		(net "M_E_DQ<34>")
	)
	(via
		(at 275.199348 -97.509584)
		(size 0.508)
		(drill 0.254)
		(layers "F.Cu" "B.Cu")
		(net "M_E_DQ<34>")
	)
	(segment
		(start 287.350454 -142.477236)
		(end 287.349946 -142.476982)
		(width 0.1651)
		(layer "B.Cu")
		(net "M_E_DQ<34>")
	)
	(segment
		(start 287.349946 -142.476982)
		(end 287.349946 -141.213078)
		(width 0.1651)
		(layer "B.Cu")
		(net "M_E_DQ<34>")
	)
	(segment
		(start 277.408894 -103.63708)
		(end 277.408894 -103.848154)
		(width 0.0889)
		(layer "In4.Cu")
		(net "M_E_DQ<34>")
	)
	(segment
		(start 283.232352 -121.866152)
		(end 287.4772 -126.111)
		(width 0.14224)
		(layer "In4.Cu")
		(net "M_E_DQ<34>")
	)
	(segment
		(start 287.349946 -141.213078)
		(end 286.916876 -141.646148)
		(width 0.14224)
		(layer "In4.Cu")
		(net "M_E_DQ<34>")
	)
	(segment
		(start 276.325584 -100.721414)
		(end 276.326092 -100.721922)
		(width 0.0889)
		(layer "In4.Cu")
		(net "M_E_DQ<34>")
	)
	(segment
		(start 287.73247 -129.91973)
		(end 287.73247 -131.348734)
		(width 0.14224)
		(layer "In4.Cu")
		(net "M_E_DQ<34>")
	)
	(segment
		(start 287.4772 -128.8796)
		(end 287.786572 -129.188972)
		(width 0.14224)
		(layer "In4.Cu")
		(net "M_E_DQ<34>")
	)
	(segment
		(start 286.916876 -144.233646)
		(end 288.19983 -145.5166)
		(width 0.14224)
		(layer "In4.Cu")
		(net "M_E_DQ<34>")
	)
	(segment
		(start 287.833562 -134.51713)
		(end 287.640014 -134.710678)
		(width 0.14224)
		(layer "In4.Cu")
		(net "M_E_DQ<34>")
	)
	(segment
		(start 287.640014 -135.976868)
		(end 287.800034 -136.136888)
		(width 0.14224)
		(layer "In4.Cu")
		(net "M_E_DQ<34>")
	)
	(segment
		(start 276.326092 -100.721922)
		(end 276.326092 -102.554278)
		(width 0.0889)
		(layer "In4.Cu")
		(net "M_E_DQ<34>")
	)
	(segment
		(start 276.325584 -100.321872)
		(end 276.325584 -100.721414)
		(width 0.0889)
		(layer "In4.Cu")
		(net "M_E_DQ<34>")
	)
	(segment
		(start 287.005014 -140.235178)
		(end 287.005014 -140.868146)
		(width 0.14224)
		(layer "In4.Cu")
		(net "M_E_DQ<34>")
	)
	(segment
		(start 283.232352 -121.135648)
		(end 283.232352 -121.866152)
		(width 0.14224)
		(layer "In4.Cu")
		(net "M_E_DQ<34>")
	)
	(segment
		(start 277.222204 -104.034844)
		(end 277.222204 -104.247696)
		(width 0.0889)
		(layer "In4.Cu")
		(net "M_E_DQ<34>")
	)
	(segment
		(start 275.199348 -97.509584)
		(end 275.154898 -97.509584)
		(width 0.0889)
		(layer "In4.Cu")
		(net "M_E_DQ<34>")
	)
	(segment
		(start 276.039834 -99.586288)
		(end 276.0726 -99.586288)
		(width 0.0889)
		(layer "In4.Cu")
		(net "M_E_DQ<34>")
	)
	(segment
		(start 276.326092 -102.554278)
		(end 277.408894 -103.63708)
		(width 0.0889)
		(layer "In4.Cu")
		(net "M_E_DQ<34>")
	)
	(segment
		(start 287.800034 -136.136888)
		(end 287.800034 -139.440158)
		(width 0.14224)
		(layer "In4.Cu")
		(net "M_E_DQ<34>")
	)
	(segment
		(start 287.005014 -140.868146)
		(end 287.349946 -141.213078)
		(width 0.14224)
		(layer "In4.Cu")
		(net "M_E_DQ<34>")
	)
	(segment
		(start 287.786572 -129.188972)
		(end 287.786572 -129.865628)
		(width 0.14224)
		(layer "In4.Cu")
		(net "M_E_DQ<34>")
	)
	(segment
		(start 287.800034 -139.440158)
		(end 287.005014 -140.235178)
		(width 0.14224)
		(layer "In4.Cu")
		(net "M_E_DQ<34>")
	)
	(segment
		(start 287.640014 -134.710678)
		(end 287.640014 -135.976868)
		(width 0.14224)
		(layer "In4.Cu")
		(net "M_E_DQ<34>")
	)
	(segment
		(start 277.408894 -103.848154)
		(end 277.222204 -104.034844)
		(width 0.0889)
		(layer "In4.Cu")
		(net "M_E_DQ<34>")
	)
	(segment
		(start 277.222204 -115.1255)
		(end 283.232352 -121.135648)
		(width 0.14224)
		(layer "In4.Cu")
		(net "M_E_DQ<34>")
	)
	(segment
		(start 287.4772 -126.111)
		(end 287.4772 -128.8796)
		(width 0.14224)
		(layer "In4.Cu")
		(net "M_E_DQ<34>")
	)
	(segment
		(start 287.833562 -131.449826)
		(end 287.833562 -134.51713)
		(width 0.14224)
		(layer "In4.Cu")
		(net "M_E_DQ<34>")
	)
	(segment
		(start 276.411182 -100.17379)
		(end 276.325584 -100.321872)
		(width 0.0889)
		(layer "In4.Cu")
		(net "M_E_DQ<34>")
	)
	(segment
		(start 287.786572 -129.865628)
		(end 287.73247 -129.91973)
		(width 0.14224)
		(layer "In4.Cu")
		(net "M_E_DQ<34>")
	)
	(segment
		(start 286.916876 -141.646148)
		(end 286.916876 -144.233646)
		(width 0.14224)
		(layer "In4.Cu")
		(net "M_E_DQ<34>")
	)
	(segment
		(start 275.542502 -99.285044)
		(end 275.545804 -99.290886)
		(width 0.0889)
		(layer "In4.Cu")
		(net "M_E_DQ<34>")
	)
	(segment
		(start 275.048726 -98.871024)
		(end 275.255228 -99.077526)
		(width 0.0889)
		(layer "In4.Cu")
		(net "M_E_DQ<34>")
	)
	(segment
		(start 277.222204 -104.247696)
		(end 277.222204 -115.1255)
		(width 0.14224)
		(layer "In4.Cu")
		(net "M_E_DQ<34>")
	)
	(segment
		(start 287.73247 -131.348734)
		(end 287.833562 -131.449826)
		(width 0.14224)
		(layer "In4.Cu")
		(net "M_E_DQ<34>")
	)
	(arc
		(start 275.255228 -99.077526)
		(mid 275.276462 -99.093785)
		(end 275.301202 -99.103942)
		(width 0.0889)
		(layer "In4.Cu")
		(net "M_E_DQ<34>")
	)
	(arc
		(start 275.301202 -99.103942)
		(mid 275.439583 -99.170874)
		(end 275.542502 -99.285044)
		(width 0.0889)
		(layer "In4.Cu")
		(net "M_E_DQ<34>")
	)
	(arc
		(start 274.827492 -98.35261)
		(mid 274.831262 -98.657413)
		(end 275.048726 -98.871024)
		(width 0.0889)
		(layer "In4.Cu")
		(net "M_E_DQ<34>")
	)
	(arc
		(start 275.154898 -97.509584)
		(mid 274.949056 -97.612676)
		(end 274.908264 -97.839276)
		(width 0.0889)
		(layer "In4.Cu")
		(net "M_E_DQ<34>")
	)
	(arc
		(start 274.908264 -97.839276)
		(mid 274.928713 -98.069381)
		(end 274.858988 -98.289618)
		(width 0.0889)
		(layer "In4.Cu")
		(net "M_E_DQ<34>")
	)
	(arc
		(start 276.0726 -99.586288)
		(mid 276.404444 -99.786405)
		(end 276.411182 -100.17379)
		(width 0.0889)
		(layer "In4.Cu")
		(net "M_E_DQ<34>")
	)
	(arc
		(start 274.858988 -98.289618)
		(mid 274.841892 -98.32044)
		(end 274.827492 -98.35261)
		(width 0.0889)
		(layer "In4.Cu")
		(net "M_E_DQ<34>")
	)
	(arc
		(start 275.545804 -99.290886)
		(mid 275.754412 -99.502818)
		(end 276.039834 -99.586288)
		(width 0.0889)
		(layer "In4.Cu")
		(net "M_E_DQ<34>")
	)
	(segment
		(start 272.052288 -99.986338)
		(end 272.623788 -99.986338)
		(width 0.1651)
		(layer "F.Cu")
		(net "M_E_DQ<33>")
	)
	(segment
		(start 281.399996 -142.677642)
		(end 281.399996 -143.941546)
		(width 0.1651)
		(layer "F.Cu")
		(net "M_E_DQ<33>")
	)
	(segment
		(start 281.400504 -142.6718)
		(end 281.399996 -142.677642)
		(width 0.1651)
		(layer "F.Cu")
		(net "M_E_DQ<33>")
	)
	(via
		(at 281.399996 -143.941546)
		(size 0.508)
		(drill 0.254)
		(layers "F.Cu" "B.Cu")
		(net "M_E_DQ<33>")
	)
	(via
		(at 272.623788 -99.986338)
		(size 0.508)
		(drill 0.254)
		(layers "F.Cu" "B.Cu")
		(net "M_E_DQ<33>")
	)
	(via
		(at 282.07208 -139.932156)
		(size 0.508)
		(drill 0.254)
		(layers "F.Cu" "B.Cu")
		(net "M_E_DQ<33>")
	)
	(segment
		(start 282.07208 -139.428982)
		(end 282.07208 -139.932156)
		(width 0.1651)
		(layer "B.Cu")
		(net "M_E_DQ<33>")
	)
	(segment
		(start 282.24988 -137.877296)
		(end 282.24988 -139.251182)
		(width 0.1651)
		(layer "B.Cu")
		(net "M_E_DQ<33>")
	)
	(segment
		(start 282.24988 -139.251182)
		(end 282.07208 -139.428982)
		(width 0.1651)
		(layer "B.Cu")
		(net "M_E_DQ<33>")
	)
	(segment
		(start 282.250388 -137.877296)
		(end 282.24988 -137.877296)
		(width 0.1651)
		(layer "B.Cu")
		(net "M_E_DQ<33>")
	)
	(segment
		(start 281.851862 -141.020546)
		(end 281.851862 -141.425168)
		(width 0.14224)
		(layer "In4.Cu")
		(net "M_E_DQ<33>")
	)
	(segment
		(start 282.250134 -137.434574)
		(end 282.095194 -137.589514)
		(width 0.14224)
		(layer "In4.Cu")
		(net "M_E_DQ<33>")
	)
	(segment
		(start 282.559506 -127.513334)
		(end 282.559506 -127.866394)
		(width 0.14224)
		(layer "In4.Cu")
		(net "M_E_DQ<33>")
	)
	(segment
		(start 282.970732 -132.17017)
		(end 282.970732 -132.443474)
		(width 0.14224)
		(layer "In4.Cu")
		(net "M_E_DQ<33>")
	)
	(segment
		(start 282.991052 -137.279634)
		(end 282.836112 -137.434574)
		(width 0.14224)
		(layer "In4.Cu")
		(net "M_E_DQ<33>")
	)
	(segment
		(start 272.223738 -100.06838)
		(end 272.223738 -102.368604)
		(width 0.0889)
		(layer "In4.Cu")
		(net "M_E_DQ<33>")
	)
	(segment
		(start 282.162504 -133.099556)
		(end 282.324302 -133.261354)
		(width 0.14224)
		(layer "In4.Cu")
		(net "M_E_DQ<33>")
	)
	(segment
		(start 282.07208 -139.932156)
		(end 282.049728 -139.932156)
		(width 0.14224)
		(layer "In4.Cu")
		(net "M_E_DQ<33>")
	)
	(segment
		(start 282.310586 -132.598414)
		(end 282.162504 -132.746496)
		(width 0.14224)
		(layer "In4.Cu")
		(net "M_E_DQ<33>")
	)
	(segment
		(start 282.970732 -132.443474)
		(end 282.815792 -132.598414)
		(width 0.14224)
		(layer "In4.Cu")
		(net "M_E_DQ<33>")
	)
	(segment
		(start 282.404566 -127.358394)
		(end 282.559506 -127.513334)
		(width 0.14224)
		(layer "In4.Cu")
		(net "M_E_DQ<33>")
	)
	(segment
		(start 282.815792 -133.261354)
		(end 282.970732 -133.416294)
		(width 0.14224)
		(layer "In4.Cu")
		(net "M_E_DQ<33>")
	)
	(segment
		(start 282.560014 -131.759452)
		(end 282.970732 -132.17017)
		(width 0.14224)
		(layer "In4.Cu")
		(net "M_E_DQ<33>")
	)
	(segment
		(start 282.560014 -136.58596)
		(end 282.991052 -137.016998)
		(width 0.14224)
		(layer "In4.Cu")
		(net "M_E_DQ<33>")
	)
	(segment
		(start 282.250134 -138.097514)
		(end 282.836112 -138.097514)
		(width 0.14224)
		(layer "In4.Cu")
		(net "M_E_DQ<33>")
	)
	(segment
		(start 282.836112 -137.434574)
		(end 282.250134 -137.434574)
		(width 0.14224)
		(layer "In4.Cu")
		(net "M_E_DQ<33>")
	)
	(segment
		(start 273.384264 -117.106954)
		(end 282.255976 -125.978666)
		(width 0.14224)
		(layer "In4.Cu")
		(net "M_E_DQ<33>")
	)
	(segment
		(start 272.623788 -99.986338)
		(end 272.30578 -99.986338)
		(width 0.0889)
		(layer "In4.Cu")
		(net "M_E_DQ<33>")
	)
	(segment
		(start 282.991052 -137.016998)
		(end 282.991052 -137.279634)
		(width 0.14224)
		(layer "In4.Cu")
		(net "M_E_DQ<33>")
	)
	(segment
		(start 273.168618 -103.313484)
		(end 273.168618 -106.088688)
		(width 0.0889)
		(layer "In4.Cu")
		(net "M_E_DQ<33>")
	)
	(segment
		(start 282.559506 -127.866394)
		(end 282.404566 -128.021334)
		(width 0.14224)
		(layer "In4.Cu")
		(net "M_E_DQ<33>")
	)
	(segment
		(start 282.162504 -132.746496)
		(end 282.162504 -133.099556)
		(width 0.14224)
		(layer "In4.Cu")
		(net "M_E_DQ<33>")
	)
	(segment
		(start 282.560014 -134.130034)
		(end 282.560014 -136.58596)
		(width 0.14224)
		(layer "In4.Cu")
		(net "M_E_DQ<33>")
	)
	(segment
		(start 281.561286 -142.936976)
		(end 281.561286 -143.244824)
		(width 0.14224)
		(layer "In4.Cu")
		(net "M_E_DQ<33>")
	)
	(segment
		(start 282.560014 -139.355322)
		(end 282.07208 -139.843256)
		(width 0.14224)
		(layer "In4.Cu")
		(net "M_E_DQ<33>")
	)
	(segment
		(start 282.970732 -133.416294)
		(end 282.970732 -133.719316)
		(width 0.14224)
		(layer "In4.Cu")
		(net "M_E_DQ<33>")
	)
	(segment
		(start 282.255976 -125.978666)
		(end 282.255976 -127.216154)
		(width 0.14224)
		(layer "In4.Cu")
		(net "M_E_DQ<33>")
	)
	(segment
		(start 272.223738 -102.368604)
		(end 273.168618 -103.313484)
		(width 0.0889)
		(layer "In4.Cu")
		(net "M_E_DQ<33>")
	)
	(segment
		(start 282.991052 -138.252454)
		(end 282.991052 -138.547348)
		(width 0.14224)
		(layer "In4.Cu")
		(net "M_E_DQ<33>")
	)
	(segment
		(start 282.991052 -138.547348)
		(end 282.560014 -138.978386)
		(width 0.14224)
		(layer "In4.Cu")
		(net "M_E_DQ<33>")
	)
	(segment
		(start 282.560014 -129.245614)
		(end 282.560014 -131.759452)
		(width 0.14224)
		(layer "In4.Cu")
		(net "M_E_DQ<33>")
	)
	(segment
		(start 282.324302 -133.261354)
		(end 282.815792 -133.261354)
		(width 0.14224)
		(layer "In4.Cu")
		(net "M_E_DQ<33>")
	)
	(segment
		(start 282.404566 -128.021334)
		(end 281.96032 -128.021334)
		(width 0.14224)
		(layer "In4.Cu")
		(net "M_E_DQ<33>")
	)
	(segment
		(start 282.095194 -137.942574)
		(end 282.250134 -138.097514)
		(width 0.14224)
		(layer "In4.Cu")
		(net "M_E_DQ<33>")
	)
	(segment
		(start 272.30578 -99.986338)
		(end 272.223738 -100.06838)
		(width 0.0889)
		(layer "In4.Cu")
		(net "M_E_DQ<33>")
	)
	(segment
		(start 281.561286 -143.244824)
		(end 281.801062 -143.4846)
		(width 0.14224)
		(layer "In4.Cu")
		(net "M_E_DQ<33>")
	)
	(segment
		(start 282.815792 -132.598414)
		(end 282.310586 -132.598414)
		(width 0.14224)
		(layer "In4.Cu")
		(net "M_E_DQ<33>")
	)
	(segment
		(start 282.560014 -138.978386)
		(end 282.560014 -139.355322)
		(width 0.14224)
		(layer "In4.Cu")
		(net "M_E_DQ<33>")
	)
	(segment
		(start 281.851862 -141.425168)
		(end 281.561286 -141.715744)
		(width 0.14224)
		(layer "In4.Cu")
		(net "M_E_DQ<33>")
	)
	(segment
		(start 281.801062 -143.7894)
		(end 281.648916 -143.941546)
		(width 0.14224)
		(layer "In4.Cu")
		(net "M_E_DQ<33>")
	)
	(segment
		(start 282.398216 -127.358394)
		(end 282.404566 -127.358394)
		(width 0.14224)
		(layer "In4.Cu")
		(net "M_E_DQ<33>")
	)
	(segment
		(start 281.94762 -128.60274)
		(end 282.1813 -128.60274)
		(width 0.14224)
		(layer "In4.Cu")
		(net "M_E_DQ<33>")
	)
	(segment
		(start 281.621484 -140.3604)
		(end 281.621484 -140.790168)
		(width 0.14224)
		(layer "In4.Cu")
		(net "M_E_DQ<33>")
	)
	(segment
		(start 273.168618 -106.088688)
		(end 273.384264 -106.304334)
		(width 0.0889)
		(layer "In4.Cu")
		(net "M_E_DQ<33>")
	)
	(segment
		(start 281.80538 -128.176274)
		(end 281.80538 -128.4605)
		(width 0.14224)
		(layer "In4.Cu")
		(net "M_E_DQ<33>")
	)
	(segment
		(start 281.561286 -141.715744)
		(end 281.561286 -142.076424)
		(width 0.14224)
		(layer "In4.Cu")
		(net "M_E_DQ<33>")
	)
	(segment
		(start 282.255976 -127.216154)
		(end 282.398216 -127.358394)
		(width 0.14224)
		(layer "In4.Cu")
		(net "M_E_DQ<33>")
	)
	(segment
		(start 281.96032 -128.021334)
		(end 281.80538 -128.176274)
		(width 0.14224)
		(layer "In4.Cu")
		(net "M_E_DQ<33>")
	)
	(segment
		(start 281.775662 -142.2908)
		(end 281.775662 -142.7226)
		(width 0.14224)
		(layer "In4.Cu")
		(net "M_E_DQ<33>")
	)
	(segment
		(start 282.836112 -138.097514)
		(end 282.991052 -138.252454)
		(width 0.14224)
		(layer "In4.Cu")
		(net "M_E_DQ<33>")
	)
	(segment
		(start 282.07208 -139.843256)
		(end 282.07208 -139.932156)
		(width 0.14224)
		(layer "In4.Cu")
		(net "M_E_DQ<33>")
	)
	(segment
		(start 282.323794 -129.009394)
		(end 282.560014 -129.245614)
		(width 0.14224)
		(layer "In4.Cu")
		(net "M_E_DQ<33>")
	)
	(segment
		(start 282.095194 -137.589514)
		(end 282.095194 -137.942574)
		(width 0.14224)
		(layer "In4.Cu")
		(net "M_E_DQ<33>")
	)
	(segment
		(start 281.621484 -140.790168)
		(end 281.851862 -141.020546)
		(width 0.14224)
		(layer "In4.Cu")
		(net "M_E_DQ<33>")
	)
	(segment
		(start 282.970732 -133.719316)
		(end 282.560014 -134.130034)
		(width 0.14224)
		(layer "In4.Cu")
		(net "M_E_DQ<33>")
	)
	(segment
		(start 281.801062 -143.4846)
		(end 281.801062 -143.7894)
		(width 0.14224)
		(layer "In4.Cu")
		(net "M_E_DQ<33>")
	)
	(segment
		(start 281.775662 -142.7226)
		(end 281.561286 -142.936976)
		(width 0.14224)
		(layer "In4.Cu")
		(net "M_E_DQ<33>")
	)
	(segment
		(start 281.561286 -142.076424)
		(end 281.775662 -142.2908)
		(width 0.14224)
		(layer "In4.Cu")
		(net "M_E_DQ<33>")
	)
	(segment
		(start 282.323794 -128.745234)
		(end 282.323794 -129.009394)
		(width 0.14224)
		(layer "In4.Cu")
		(net "M_E_DQ<33>")
	)
	(segment
		(start 281.648916 -143.941546)
		(end 281.399996 -143.941546)
		(width 0.14224)
		(layer "In4.Cu")
		(net "M_E_DQ<33>")
	)
	(segment
		(start 282.049728 -139.932156)
		(end 281.621484 -140.3604)
		(width 0.14224)
		(layer "In4.Cu")
		(net "M_E_DQ<33>")
	)
	(segment
		(start 273.384264 -106.304334)
		(end 273.384264 -117.106954)
		(width 0.14224)
		(layer "In4.Cu")
		(net "M_E_DQ<33>")
	)
	(segment
		(start 281.80538 -128.4605)
		(end 281.94762 -128.60274)
		(width 0.14224)
		(layer "In4.Cu")
		(net "M_E_DQ<33>")
	)
	(segment
		(start 282.1813 -128.60274)
		(end 282.323794 -128.745234)
		(width 0.14224)
		(layer "In4.Cu")
		(net "M_E_DQ<33>")
	)
	(segment
		(start 282.24988 -147.277582)
		(end 282.07208 -145.415)
		(width 0.1651)
		(layer "F.Cu")
		(net "M_E_DQ<32>")
	)
	(segment
		(start 272.052288 -98.995738)
		(end 272.623788 -98.995738)
		(width 0.1651)
		(layer "F.Cu")
		(net "M_E_DQ<32>")
	)
	(segment
		(start 282.250388 -147.27174)
		(end 282.24988 -147.277582)
		(width 0.1651)
		(layer "F.Cu")
		(net "M_E_DQ<32>")
	)
	(via
		(at 282.07208 -145.415)
		(size 0.508)
		(drill 0.254)
		(layers "F.Cu" "B.Cu")
		(net "M_E_DQ<32>")
	)
	(via
		(at 272.623788 -98.995738)
		(size 0.508)
		(drill 0.254)
		(layers "F.Cu" "B.Cu")
		(net "M_E_DQ<32>")
	)
	(via
		(at 281.399996 -141.213078)
		(size 0.508)
		(drill 0.254)
		(layers "F.Cu" "B.Cu")
		(net "M_E_DQ<32>")
	)
	(segment
		(start 281.399996 -142.476982)
		(end 281.399996 -141.213078)
		(width 0.1651)
		(layer "B.Cu")
		(net "M_E_DQ<32>")
	)
	(segment
		(start 281.400504 -142.477236)
		(end 281.399996 -142.476982)
		(width 0.1651)
		(layer "B.Cu")
		(net "M_E_DQ<32>")
	)
	(segment
		(start 272.978626 -106.072432)
		(end 272.749264 -106.301794)
		(width 0.0889)
		(layer "In4.Cu")
		(net "M_E_DQ<32>")
	)
	(segment
		(start 281.53614 -138.58494)
		(end 281.886914 -138.935714)
		(width 0.14224)
		(layer "In4.Cu")
		(net "M_E_DQ<32>")
	)
	(segment
		(start 274.610068 -119.519446)
		(end 274.313142 -119.816372)
		(width 0.14224)
		(layer "In4.Cu")
		(net "M_E_DQ<32>")
	)
	(segment
		(start 274.610068 -119.23268)
		(end 274.610068 -119.519446)
		(width 0.14224)
		(layer "In4.Cu")
		(net "M_E_DQ<32>")
	)
	(segment
		(start 275.47189 -120.094502)
		(end 281.259788 -125.8824)
		(width 0.14224)
		(layer "In4.Cu")
		(net "M_E_DQ<32>")
	)
	(segment
		(start 281.036014 -140.849096)
		(end 281.399996 -141.213078)
		(width 0.14224)
		(layer "In4.Cu")
		(net "M_E_DQ<32>")
	)
	(segment
		(start 281.259788 -125.8824)
		(end 281.259788 -128.783588)
		(width 0.14224)
		(layer "In4.Cu")
		(net "M_E_DQ<32>")
	)
	(segment
		(start 274.888198 -120.391174)
		(end 275.18487 -120.094502)
		(width 0.14224)
		(layer "In4.Cu")
		(net "M_E_DQ<32>")
	)
	(segment
		(start 272.033238 -99.10064)
		(end 272.033238 -102.446836)
		(width 0.0889)
		(layer "In4.Cu")
		(net "M_E_DQ<32>")
	)
	(segment
		(start 281.886914 -139.358878)
		(end 281.036014 -140.209778)
		(width 0.14224)
		(layer "In4.Cu")
		(net "M_E_DQ<32>")
	)
	(segment
		(start 281.874214 -131.826)
		(end 281.610054 -132.09016)
		(width 0.14224)
		(layer "In4.Cu")
		(net "M_E_DQ<32>")
	)
	(segment
		(start 273.460464 -118.083076)
		(end 273.460464 -118.369842)
		(width 0.14224)
		(layer "In4.Cu")
		(net "M_E_DQ<32>")
	)
	(segment
		(start 273.237706 -118.5926)
		(end 273.237706 -118.873016)
		(width 0.14224)
		(layer "In4.Cu")
		(net "M_E_DQ<32>")
	)
	(segment
		(start 281.582114 -130.062478)
		(end 281.582114 -131.141978)
		(width 0.14224)
		(layer "In4.Cu")
		(net "M_E_DQ<32>")
	)
	(segment
		(start 281.610054 -133.807454)
		(end 281.874214 -134.071614)
		(width 0.14224)
		(layer "In4.Cu")
		(net "M_E_DQ<32>")
	)
	(segment
		(start 281.874214 -134.482586)
		(end 281.594814 -134.761986)
		(width 0.14224)
		(layer "In4.Cu")
		(net "M_E_DQ<32>")
	)
	(segment
		(start 273.237706 -118.873016)
		(end 273.525488 -119.160798)
		(width 0.14224)
		(layer "In4.Cu")
		(net "M_E_DQ<32>")
	)
	(segment
		(start 280.966926 -144.60601)
		(end 281.775916 -145.415)
		(width 0.14224)
		(layer "In4.Cu")
		(net "M_E_DQ<32>")
	)
	(segment
		(start 281.259788 -128.783588)
		(end 281.925014 -129.448814)
		(width 0.14224)
		(layer "In4.Cu")
		(net "M_E_DQ<32>")
	)
	(segment
		(start 274.313142 -119.816372)
		(end 274.313142 -120.103392)
		(width 0.14224)
		(layer "In4.Cu")
		(net "M_E_DQ<32>")
	)
	(segment
		(start 272.033238 -102.446836)
		(end 272.978626 -103.392224)
		(width 0.0889)
		(layer "In4.Cu")
		(net "M_E_DQ<32>")
	)
	(segment
		(start 274.322286 -118.944898)
		(end 274.610068 -119.23268)
		(width 0.14224)
		(layer "In4.Cu")
		(net "M_E_DQ<32>")
	)
	(segment
		(start 281.775916 -145.415)
		(end 282.07208 -145.415)
		(width 0.14224)
		(layer "In4.Cu")
		(net "M_E_DQ<32>")
	)
	(segment
		(start 281.874214 -134.071614)
		(end 281.874214 -134.482586)
		(width 0.14224)
		(layer "In4.Cu")
		(net "M_E_DQ<32>")
	)
	(segment
		(start 281.874214 -131.434078)
		(end 281.874214 -131.826)
		(width 0.14224)
		(layer "In4.Cu")
		(net "M_E_DQ<32>")
	)
	(segment
		(start 272.13814 -98.995738)
		(end 272.033238 -99.10064)
		(width 0.0889)
		(layer "In4.Cu")
		(net "M_E_DQ<32>")
	)
	(segment
		(start 281.886914 -138.935714)
		(end 281.886914 -139.358878)
		(width 0.14224)
		(layer "In4.Cu")
		(net "M_E_DQ<32>")
	)
	(segment
		(start 281.886914 -136.652)
		(end 281.53614 -137.002774)
		(width 0.14224)
		(layer "In4.Cu")
		(net "M_E_DQ<32>")
	)
	(segment
		(start 272.749264 -106.301794)
		(end 272.749264 -117.371876)
		(width 0.14224)
		(layer "In4.Cu")
		(net "M_E_DQ<32>")
	)
	(segment
		(start 272.978626 -103.392224)
		(end 272.978626 -106.072432)
		(width 0.0889)
		(layer "In4.Cu")
		(net "M_E_DQ<32>")
	)
	(segment
		(start 281.925014 -129.719578)
		(end 281.582114 -130.062478)
		(width 0.14224)
		(layer "In4.Cu")
		(net "M_E_DQ<32>")
	)
	(segment
		(start 274.035266 -118.944898)
		(end 274.322286 -118.944898)
		(width 0.14224)
		(layer "In4.Cu")
		(net "M_E_DQ<32>")
	)
	(segment
		(start 281.594814 -134.761986)
		(end 281.594814 -135.976614)
		(width 0.14224)
		(layer "In4.Cu")
		(net "M_E_DQ<32>")
	)
	(segment
		(start 273.525488 -119.160798)
		(end 273.819366 -119.160798)
		(width 0.14224)
		(layer "In4.Cu")
		(net "M_E_DQ<32>")
	)
	(segment
		(start 273.460464 -118.369842)
		(end 273.237706 -118.5926)
		(width 0.14224)
		(layer "In4.Cu")
		(net "M_E_DQ<32>")
	)
	(segment
		(start 281.886914 -136.268714)
		(end 281.886914 -136.652)
		(width 0.14224)
		(layer "In4.Cu")
		(net "M_E_DQ<32>")
	)
	(segment
		(start 274.313142 -120.103392)
		(end 274.600924 -120.391174)
		(width 0.14224)
		(layer "In4.Cu")
		(net "M_E_DQ<32>")
	)
	(segment
		(start 272.623788 -98.995738)
		(end 272.13814 -98.995738)
		(width 0.0889)
		(layer "In4.Cu")
		(net "M_E_DQ<32>")
	)
	(segment
		(start 281.53614 -137.002774)
		(end 281.53614 -138.58494)
		(width 0.14224)
		(layer "In4.Cu")
		(net "M_E_DQ<32>")
	)
	(segment
		(start 281.610054 -132.09016)
		(end 281.610054 -133.807454)
		(width 0.14224)
		(layer "In4.Cu")
		(net "M_E_DQ<32>")
	)
	(segment
		(start 272.749264 -117.371876)
		(end 273.460464 -118.083076)
		(width 0.14224)
		(layer "In4.Cu")
		(net "M_E_DQ<32>")
	)
	(segment
		(start 275.18487 -120.094502)
		(end 275.47189 -120.094502)
		(width 0.14224)
		(layer "In4.Cu")
		(net "M_E_DQ<32>")
	)
	(segment
		(start 273.819366 -119.160798)
		(end 274.035266 -118.944898)
		(width 0.14224)
		(layer "In4.Cu")
		(net "M_E_DQ<32>")
	)
	(segment
		(start 281.925014 -129.448814)
		(end 281.925014 -129.719578)
		(width 0.14224)
		(layer "In4.Cu")
		(net "M_E_DQ<32>")
	)
	(segment
		(start 274.600924 -120.391174)
		(end 274.888198 -120.391174)
		(width 0.14224)
		(layer "In4.Cu")
		(net "M_E_DQ<32>")
	)
	(segment
		(start 281.036014 -140.209778)
		(end 281.036014 -140.849096)
		(width 0.14224)
		(layer "In4.Cu")
		(net "M_E_DQ<32>")
	)
	(segment
		(start 281.594814 -135.976614)
		(end 281.886914 -136.268714)
		(width 0.14224)
		(layer "In4.Cu")
		(net "M_E_DQ<32>")
	)
	(segment
		(start 281.399996 -141.213078)
		(end 280.966926 -141.646148)
		(width 0.14224)
		(layer "In4.Cu")
		(net "M_E_DQ<32>")
	)
	(segment
		(start 280.966926 -141.646148)
		(end 280.966926 -144.60601)
		(width 0.14224)
		(layer "In4.Cu")
		(net "M_E_DQ<32>")
	)
	(segment
		(start 281.582114 -131.141978)
		(end 281.874214 -131.434078)
		(width 0.14224)
		(layer "In4.Cu")
		(net "M_E_DQ<32>")
	)
	(segment
		(start 230.234998 -119.439944)
		(end 230.066342 -119.6086)
		(width 0.1651)
		(layer "F.Cu")
		(net "M_E_DQ<31>")
	)
	(segment
		(start 231.058466 -121.489724)
		(end 231.24033 -121.671588)
		(width 0.1651)
		(layer "F.Cu")
		(net "M_E_DQ<31>")
	)
	(segment
		(start 244.692424 -103.01605)
		(end 242.74272 -104.965754)
		(width 0.1016)
		(layer "F.Cu")
		(net "M_E_DQ<31>")
	)
	(segment
		(start 230.066342 -119.94134)
		(end 230.248206 -120.123204)
		(width 0.1651)
		(layer "F.Cu")
		(net "M_E_DQ<31>")
	)
	(segment
		(start 231.189022 -117.898164)
		(end 231.013762 -118.073424)
		(width 0.1651)
		(layer "F.Cu")
		(net "M_E_DQ<31>")
	)
	(segment
		(start 230.066342 -119.6086)
		(end 230.066342 -119.94134)
		(width 0.1651)
		(layer "F.Cu")
		(net "M_E_DQ<31>")
	)
	(segment
		(start 231.189022 -112.206532)
		(end 231.189022 -113.065306)
		(width 0.1651)
		(layer "F.Cu")
		(net "M_E_DQ<31>")
	)
	(segment
		(start 231.189022 -123.747022)
		(end 231.7242 -124.2822)
		(width 0.1651)
		(layer "F.Cu")
		(net "M_E_DQ<31>")
	)
	(segment
		(start 231.077516 -120.806464)
		(end 230.83266 -120.806464)
		(width 0.1651)
		(layer "F.Cu")
		(net "M_E_DQ<31>")
	)
	(segment
		(start 231.392476 -115.686332)
		(end 231.189022 -115.889786)
		(width 0.1651)
		(layer "F.Cu")
		(net "M_E_DQ<31>")
	)
	(segment
		(start 230.400352 -142.6718)
		(end 230.399844 -142.677642)
		(width 0.1651)
		(layer "F.Cu")
		(net "M_E_DQ<31>")
	)
	(segment
		(start 230.085646 -118.255034)
		(end 230.085646 -118.587774)
		(width 0.1651)
		(layer "F.Cu")
		(net "M_E_DQ<31>")
	)
	(segment
		(start 230.6574 -122.680984)
		(end 230.83266 -122.856244)
		(width 0.1651)
		(layer "F.Cu")
		(net "M_E_DQ<31>")
	)
	(segment
		(start 231.087422 -118.756684)
		(end 231.24033 -118.909592)
		(width 0.1651)
		(layer "F.Cu")
		(net "M_E_DQ<31>")
	)
	(segment
		(start 231.239822 -120.311418)
		(end 231.239822 -120.644158)
		(width 0.1651)
		(layer "F.Cu")
		(net "M_E_DQ<31>")
	)
	(segment
		(start 231.24033 -122.004328)
		(end 231.071674 -122.172984)
		(width 0.1651)
		(layer "F.Cu")
		(net "M_E_DQ<31>")
	)
	(segment
		(start 231.189022 -113.629186)
		(end 231.189022 -115.210844)
		(width 0.1651)
		(layer "F.Cu")
		(net "M_E_DQ<31>")
	)
	(segment
		(start 231.239822 -120.644158)
		(end 231.077516 -120.806464)
		(width 0.1651)
		(layer "F.Cu")
		(net "M_E_DQ<31>")
	)
	(segment
		(start 230.399844 -142.677642)
		(end 230.399844 -143.941546)
		(width 0.1651)
		(layer "F.Cu")
		(net "M_E_DQ<31>")
	)
	(segment
		(start 230.6574 -120.981724)
		(end 230.6574 -121.314464)
		(width 0.1651)
		(layer "F.Cu")
		(net "M_E_DQ<31>")
	)
	(segment
		(start 230.6574 -121.314464)
		(end 230.83266 -121.489724)
		(width 0.1651)
		(layer "F.Cu")
		(net "M_E_DQ<31>")
	)
	(segment
		(start 231.189022 -115.889786)
		(end 231.189022 -117.898164)
		(width 0.1651)
		(layer "F.Cu")
		(net "M_E_DQ<31>")
	)
	(segment
		(start 230.248206 -120.123204)
		(end 231.051608 -120.123204)
		(width 0.1651)
		(layer "F.Cu")
		(net "M_E_DQ<31>")
	)
	(segment
		(start 231.189022 -123.031504)
		(end 231.189022 -123.747022)
		(width 0.1651)
		(layer "F.Cu")
		(net "M_E_DQ<31>")
	)
	(segment
		(start 230.267256 -118.073424)
		(end 230.085646 -118.255034)
		(width 0.1651)
		(layer "F.Cu")
		(net "M_E_DQ<31>")
	)
	(segment
		(start 231.013762 -122.856244)
		(end 231.189022 -123.031504)
		(width 0.1651)
		(layer "F.Cu")
		(net "M_E_DQ<31>")
	)
	(segment
		(start 231.392476 -115.414298)
		(end 231.392476 -115.686332)
		(width 0.1651)
		(layer "F.Cu")
		(net "M_E_DQ<31>")
	)
	(segment
		(start 231.013762 -118.073424)
		(end 230.267256 -118.073424)
		(width 0.1651)
		(layer "F.Cu")
		(net "M_E_DQ<31>")
	)
	(segment
		(start 231.7242 -125.283976)
		(end 231.5972 -125.410976)
		(width 0.1651)
		(layer "F.Cu")
		(net "M_E_DQ<31>")
	)
	(segment
		(start 244.768624 -102.93985)
		(end 244.692424 -103.01605)
		(width 0.0889)
		(layer "F.Cu")
		(net "M_E_DQ<31>")
	)
	(segment
		(start 230.83266 -120.806464)
		(end 230.6574 -120.981724)
		(width 0.1651)
		(layer "F.Cu")
		(net "M_E_DQ<31>")
	)
	(segment
		(start 231.5972 -125.410976)
		(end 231.249728 -125.410976)
		(width 0.1651)
		(layer "F.Cu")
		(net "M_E_DQ<31>")
	)
	(segment
		(start 231.07777 -119.439944)
		(end 230.234998 -119.439944)
		(width 0.1651)
		(layer "F.Cu")
		(net "M_E_DQ<31>")
	)
	(segment
		(start 230.6574 -122.348244)
		(end 230.6574 -122.680984)
		(width 0.1651)
		(layer "F.Cu")
		(net "M_E_DQ<31>")
	)
	(segment
		(start 231.051608 -120.123204)
		(end 231.239822 -120.311418)
		(width 0.1651)
		(layer "F.Cu")
		(net "M_E_DQ<31>")
	)
	(segment
		(start 231.189022 -115.210844)
		(end 231.392476 -115.414298)
		(width 0.1651)
		(layer "F.Cu")
		(net "M_E_DQ<31>")
	)
	(segment
		(start 230.254556 -118.756684)
		(end 231.087422 -118.756684)
		(width 0.1651)
		(layer "F.Cu")
		(net "M_E_DQ<31>")
	)
	(segment
		(start 237.428024 -107.314746)
		(end 236.080808 -107.314746)
		(width 0.1651)
		(layer "F.Cu")
		(net "M_E_DQ<31>")
	)
	(segment
		(start 230.83266 -122.172984)
		(end 230.6574 -122.348244)
		(width 0.1651)
		(layer "F.Cu")
		(net "M_E_DQ<31>")
	)
	(segment
		(start 242.74272 -104.965754)
		(end 239.98682 -104.965754)
		(width 0.1016)
		(layer "F.Cu")
		(net "M_E_DQ<31>")
	)
	(segment
		(start 237.637828 -107.314746)
		(end 237.428024 -107.314746)
		(width 0.1016)
		(layer "F.Cu")
		(net "M_E_DQ<31>")
	)
	(segment
		(start 230.085646 -118.587774)
		(end 230.254556 -118.756684)
		(width 0.1651)
		(layer "F.Cu")
		(net "M_E_DQ<31>")
	)
	(segment
		(start 231.071674 -122.172984)
		(end 230.83266 -122.172984)
		(width 0.1651)
		(layer "F.Cu")
		(net "M_E_DQ<31>")
	)
	(segment
		(start 231.24033 -118.909592)
		(end 231.24033 -119.277384)
		(width 0.1651)
		(layer "F.Cu")
		(net "M_E_DQ<31>")
	)
	(segment
		(start 231.004872 -113.249456)
		(end 231.004872 -113.445036)
		(width 0.1651)
		(layer "F.Cu")
		(net "M_E_DQ<31>")
	)
	(segment
		(start 230.83266 -121.489724)
		(end 231.058466 -121.489724)
		(width 0.1651)
		(layer "F.Cu")
		(net "M_E_DQ<31>")
	)
	(segment
		(start 239.98682 -104.965754)
		(end 237.637828 -107.314746)
		(width 0.1016)
		(layer "F.Cu")
		(net "M_E_DQ<31>")
	)
	(segment
		(start 244.768624 -101.15804)
		(end 244.768624 -102.93985)
		(width 0.0889)
		(layer "F.Cu")
		(net "M_E_DQ<31>")
	)
	(segment
		(start 231.7242 -124.2822)
		(end 231.7242 -125.283976)
		(width 0.1651)
		(layer "F.Cu")
		(net "M_E_DQ<31>")
	)
	(segment
		(start 231.004872 -113.445036)
		(end 231.189022 -113.629186)
		(width 0.1651)
		(layer "F.Cu")
		(net "M_E_DQ<31>")
	)
	(segment
		(start 236.080808 -107.314746)
		(end 231.189022 -112.206532)
		(width 0.1651)
		(layer "F.Cu")
		(net "M_E_DQ<31>")
	)
	(segment
		(start 231.24033 -121.671588)
		(end 231.24033 -122.004328)
		(width 0.1651)
		(layer "F.Cu")
		(net "M_E_DQ<31>")
	)
	(segment
		(start 231.189022 -113.065306)
		(end 231.004872 -113.249456)
		(width 0.1651)
		(layer "F.Cu")
		(net "M_E_DQ<31>")
	)
	(segment
		(start 231.24033 -119.277384)
		(end 231.07777 -119.439944)
		(width 0.1651)
		(layer "F.Cu")
		(net "M_E_DQ<31>")
	)
	(segment
		(start 230.83266 -122.856244)
		(end 231.013762 -122.856244)
		(width 0.1651)
		(layer "F.Cu")
		(net "M_E_DQ<31>")
	)
	(via
		(at 231.249728 -139.932156)
		(size 0.508)
		(drill 0.254)
		(layers "F.Cu" "B.Cu")
		(net "M_E_DQ<31>")
	)
	(via
		(at 231.249728 -125.410976)
		(size 0.508)
		(drill 0.254)
		(layers "F.Cu" "B.Cu")
		(net "M_E_DQ<31>")
	)
	(via
		(at 230.399844 -143.941546)
		(size 0.508)
		(drill 0.254)
		(layers "F.Cu" "B.Cu")
		(net "M_E_DQ<31>")
	)
	(segment
		(start 231.25049 -139.931394)
		(end 231.249728 -139.932156)
		(width 0.1651)
		(layer "B.Cu")
		(net "M_E_DQ<31>")
	)
	(segment
		(start 231.25049 -137.877296)
		(end 231.25049 -139.931394)
		(width 0.1651)
		(layer "B.Cu")
		(net "M_E_DQ<31>")
	)
	(segment
		(start 230.799132 -140.3604)
		(end 230.799132 -140.790168)
		(width 0.14224)
		(layer "In4.Cu")
		(net "M_E_DQ<31>")
	)
	(segment
		(start 231.551734 -131.484878)
		(end 231.551734 -131.9022)
		(width 0.14224)
		(layer "In4.Cu")
		(net "M_E_DQ<31>")
	)
	(segment
		(start 231.602534 -138.983466)
		(end 231.602534 -139.590272)
		(width 0.14224)
		(layer "In4.Cu")
		(net "M_E_DQ<31>")
	)
	(segment
		(start 231.5972 -133.3246)
		(end 231.8258 -133.5532)
		(width 0.14224)
		(layer "In4.Cu")
		(net "M_E_DQ<31>")
	)
	(segment
		(start 231.5972 -132.9182)
		(end 231.5972 -133.3246)
		(width 0.14224)
		(layer "In4.Cu")
		(net "M_E_DQ<31>")
	)
	(segment
		(start 230.843582 -140.834618)
		(end 230.843582 -141.5034)
		(width 0.14224)
		(layer "In4.Cu")
		(net "M_E_DQ<31>")
	)
	(segment
		(start 231.627934 -134.157466)
		(end 231.627934 -134.568438)
		(width 0.14224)
		(layer "In4.Cu")
		(net "M_E_DQ<31>")
	)
	(segment
		(start 230.693722 -125.211078)
		(end 230.592884 -125.311916)
		(width 0.14224)
		(layer "In4.Cu")
		(net "M_E_DQ<31>")
	)
	(segment
		(start 231.602534 -139.590272)
		(end 231.591612 -139.590272)
		(width 0.14224)
		(layer "In4.Cu")
		(net "M_E_DQ<31>")
	)
	(segment
		(start 231.8258 -133.5532)
		(end 231.8258 -133.9596)
		(width 0.14224)
		(layer "In4.Cu")
		(net "M_E_DQ<31>")
	)
	(segment
		(start 231.771698 -134.712202)
		(end 231.771698 -136.020302)
		(width 0.14224)
		(layer "In4.Cu")
		(net "M_E_DQ<31>")
	)
	(segment
		(start 231.8766 -137.3632)
		(end 231.5464 -137.6934)
		(width 0.14224)
		(layer "In4.Cu")
		(net "M_E_DQ<31>")
	)
	(segment
		(start 230.561134 -143.151352)
		(end 230.849932 -143.44015)
		(width 0.14224)
		(layer "In4.Cu")
		(net "M_E_DQ<31>")
	)
	(segment
		(start 230.561134 -142.059152)
		(end 230.818182 -142.3162)
		(width 0.14224)
		(layer "In4.Cu")
		(net "M_E_DQ<31>")
	)
	(segment
		(start 231.602534 -129.859278)
		(end 231.831134 -130.087878)
		(width 0.14224)
		(layer "In4.Cu")
		(net "M_E_DQ<31>")
	)
	(segment
		(start 231.831134 -130.087878)
		(end 231.831134 -131.205478)
		(width 0.14224)
		(layer "In4.Cu")
		(net "M_E_DQ<31>")
	)
	(segment
		(start 231.8258 -132.6896)
		(end 231.5972 -132.9182)
		(width 0.14224)
		(layer "In4.Cu")
		(net "M_E_DQ<31>")
	)
	(segment
		(start 230.561134 -141.785848)
		(end 230.561134 -142.059152)
		(width 0.14224)
		(layer "In4.Cu")
		(net "M_E_DQ<31>")
	)
	(segment
		(start 230.849932 -143.763746)
		(end 230.672132 -143.941546)
		(width 0.14224)
		(layer "In4.Cu")
		(net "M_E_DQ<31>")
	)
	(segment
		(start 230.818182 -142.3162)
		(end 230.818182 -142.621)
		(width 0.14224)
		(layer "In4.Cu")
		(net "M_E_DQ<31>")
	)
	(segment
		(start 231.831134 -131.205478)
		(end 231.551734 -131.484878)
		(width 0.14224)
		(layer "In4.Cu")
		(net "M_E_DQ<31>")
	)
	(segment
		(start 231.771698 -136.020302)
		(end 231.602534 -136.189466)
		(width 0.14224)
		(layer "In4.Cu")
		(net "M_E_DQ<31>")
	)
	(segment
		(start 230.849932 -143.44015)
		(end 230.849932 -143.763746)
		(width 0.14224)
		(layer "In4.Cu")
		(net "M_E_DQ<31>")
	)
	(segment
		(start 230.818182 -142.621)
		(end 230.561134 -142.878048)
		(width 0.14224)
		(layer "In4.Cu")
		(net "M_E_DQ<31>")
	)
	(segment
		(start 231.551734 -131.9022)
		(end 231.8258 -132.176266)
		(width 0.14224)
		(layer "In4.Cu")
		(net "M_E_DQ<31>")
	)
	(segment
		(start 231.249728 -125.410976)
		(end 231.04983 -125.211078)
		(width 0.14224)
		(layer "In4.Cu")
		(net "M_E_DQ<31>")
	)
	(segment
		(start 230.799132 -140.790168)
		(end 230.843582 -140.834618)
		(width 0.14224)
		(layer "In4.Cu")
		(net "M_E_DQ<31>")
	)
	(segment
		(start 231.602534 -127.61468)
		(end 231.602534 -129.859278)
		(width 0.14224)
		(layer "In4.Cu")
		(net "M_E_DQ<31>")
	)
	(segment
		(start 231.249728 -139.932156)
		(end 231.227376 -139.932156)
		(width 0.14224)
		(layer "In4.Cu")
		(net "M_E_DQ<31>")
	)
	(segment
		(start 231.591612 -139.590272)
		(end 231.249728 -139.932156)
		(width 0.14224)
		(layer "In4.Cu")
		(net "M_E_DQ<31>")
	)
	(segment
		(start 231.8766 -138.7094)
		(end 231.602534 -138.983466)
		(width 0.14224)
		(layer "In4.Cu")
		(net "M_E_DQ<31>")
	)
	(segment
		(start 231.5464 -137.6934)
		(end 231.5464 -138.0236)
		(width 0.14224)
		(layer "In4.Cu")
		(net "M_E_DQ<31>")
	)
	(segment
		(start 230.561134 -142.878048)
		(end 230.561134 -143.151352)
		(width 0.14224)
		(layer "In4.Cu")
		(net "M_E_DQ<31>")
	)
	(segment
		(start 231.8766 -136.849866)
		(end 231.8766 -137.3632)
		(width 0.14224)
		(layer "In4.Cu")
		(net "M_E_DQ<31>")
	)
	(segment
		(start 231.5464 -138.0236)
		(end 231.8766 -138.3538)
		(width 0.14224)
		(layer "In4.Cu")
		(net "M_E_DQ<31>")
	)
	(segment
		(start 231.8258 -133.9596)
		(end 231.627934 -134.157466)
		(width 0.14224)
		(layer "In4.Cu")
		(net "M_E_DQ<31>")
	)
	(segment
		(start 230.672132 -143.941546)
		(end 230.399844 -143.941546)
		(width 0.14224)
		(layer "In4.Cu")
		(net "M_E_DQ<31>")
	)
	(segment
		(start 231.602534 -136.189466)
		(end 231.602534 -136.5758)
		(width 0.14224)
		(layer "In4.Cu")
		(net "M_E_DQ<31>")
	)
	(segment
		(start 231.04983 -125.211078)
		(end 230.693722 -125.211078)
		(width 0.14224)
		(layer "In4.Cu")
		(net "M_E_DQ<31>")
	)
	(segment
		(start 231.602534 -136.5758)
		(end 231.8766 -136.849866)
		(width 0.14224)
		(layer "In4.Cu")
		(net "M_E_DQ<31>")
	)
	(segment
		(start 231.8766 -138.3538)
		(end 231.8766 -138.7094)
		(width 0.14224)
		(layer "In4.Cu")
		(net "M_E_DQ<31>")
	)
	(segment
		(start 231.8258 -132.176266)
		(end 231.8258 -132.6896)
		(width 0.14224)
		(layer "In4.Cu")
		(net "M_E_DQ<31>")
	)
	(segment
		(start 230.592884 -125.513084)
		(end 230.8352 -125.7554)
		(width 0.14224)
		(layer "In4.Cu")
		(net "M_E_DQ<31>")
	)
	(segment
		(start 230.8352 -125.7554)
		(end 230.8352 -126.847346)
		(width 0.14224)
		(layer "In4.Cu")
		(net "M_E_DQ<31>")
	)
	(segment
		(start 230.592884 -125.311916)
		(end 230.592884 -125.513084)
		(width 0.14224)
		(layer "In4.Cu")
		(net "M_E_DQ<31>")
	)
	(segment
		(start 230.8352 -126.847346)
		(end 231.602534 -127.61468)
		(width 0.14224)
		(layer "In4.Cu")
		(net "M_E_DQ<31>")
	)
	(segment
		(start 230.843582 -141.5034)
		(end 230.561134 -141.785848)
		(width 0.14224)
		(layer "In4.Cu")
		(net "M_E_DQ<31>")
	)
	(segment
		(start 231.627934 -134.568438)
		(end 231.771698 -134.712202)
		(width 0.14224)
		(layer "In4.Cu")
		(net "M_E_DQ<31>")
	)
	(segment
		(start 231.227376 -139.932156)
		(end 230.799132 -140.3604)
		(width 0.14224)
		(layer "In4.Cu")
		(net "M_E_DQ<31>")
	)
	(segment
		(start 244.417596 -102.859586)
		(end 242.616228 -104.660954)
		(width 0.1016)
		(layer "F.Cu")
		(net "M_E_DQ<30>")
	)
	(segment
		(start 237.705646 -106.667046)
		(end 235.8136 -106.667046)
		(width 0.1651)
		(layer "F.Cu")
		(net "M_E_DQ<30>")
	)
	(segment
		(start 231.249982 -145.516854)
		(end 231.249982 -145.8214)
		(width 0.1651)
		(layer "F.Cu")
		(net "M_E_DQ<30>")
	)
	(segment
		(start 244.438932 -99.938078)
		(end 244.421914 -99.967288)
		(width 0.0889)
		(layer "F.Cu")
		(net "M_E_DQ<30>")
	)
	(segment
		(start 230.547164 -115.641628)
		(end 230.547164 -117.18798)
		(width 0.1651)
		(layer "F.Cu")
		(net "M_E_DQ<30>")
	)
	(segment
		(start 230.886 -126.129542)
		(end 230.399844 -126.615698)
		(width 0.1651)
		(layer "F.Cu")
		(net "M_E_DQ<30>")
	)
	(segment
		(start 229.98684 -113.006124)
		(end 229.814882 -113.178082)
		(width 0.1651)
		(layer "F.Cu")
		(net "M_E_DQ<30>")
	)
	(segment
		(start 230.886 -125.7554)
		(end 230.886 -126.129542)
		(width 0.1651)
		(layer "F.Cu")
		(net "M_E_DQ<30>")
	)
	(segment
		(start 244.524784 -102.752398)
		(end 244.417596 -102.859586)
		(width 0.0889)
		(layer "F.Cu")
		(net "M_E_DQ<30>")
	)
	(segment
		(start 242.616228 -104.660954)
		(end 239.860328 -104.660954)
		(width 0.1016)
		(layer "F.Cu")
		(net "M_E_DQ<30>")
	)
	(segment
		(start 230.076248 -115.341654)
		(end 230.216202 -115.481608)
		(width 0.1651)
		(layer "F.Cu")
		(net "M_E_DQ<30>")
	)
	(segment
		(start 235.8136 -106.667046)
		(end 230.54056 -111.940086)
		(width 0.1651)
		(layer "F.Cu")
		(net "M_E_DQ<30>")
	)
	(segment
		(start 229.997 -120.788938)
		(end 229.997 -123.4694)
		(width 0.1651)
		(layer "F.Cu")
		(net "M_E_DQ<30>")
	)
	(segment
		(start 229.413562 -118.020846)
		(end 229.413562 -120.2055)
		(width 0.1651)
		(layer "F.Cu")
		(net "M_E_DQ<30>")
	)
	(segment
		(start 231.249982 -146.304)
		(end 231.249982 -147.27174)
		(width 0.1651)
		(layer "F.Cu")
		(net "M_E_DQ<30>")
	)
	(segment
		(start 230.076248 -114.925348)
		(end 230.076248 -115.341654)
		(width 0.1651)
		(layer "F.Cu")
		(net "M_E_DQ<30>")
	)
	(segment
		(start 230.336598 -117.398546)
		(end 230.035862 -117.398546)
		(width 0.1651)
		(layer "F.Cu")
		(net "M_E_DQ<30>")
	)
	(segment
		(start 229.993444 -113.689384)
		(end 230.338884 -113.689384)
		(width 0.1651)
		(layer "F.Cu")
		(net "M_E_DQ<30>")
	)
	(segment
		(start 230.387144 -115.481608)
		(end 230.547164 -115.641628)
		(width 0.1651)
		(layer "F.Cu")
		(net "M_E_DQ<30>")
	)
	(segment
		(start 244.768624 -99.17684)
		(end 244.438932 -99.938078)
		(width 0.0889)
		(layer "F.Cu")
		(net "M_E_DQ<30>")
	)
	(segment
		(start 230.54056 -112.804448)
		(end 230.338884 -113.006124)
		(width 0.1651)
		(layer "F.Cu")
		(net "M_E_DQ<30>")
	)
	(segment
		(start 231.249728 -145.5166)
		(end 231.249982 -145.516854)
		(width 0.1651)
		(layer "F.Cu")
		(net "M_E_DQ<30>")
	)
	(segment
		(start 231.249982 -147.27174)
		(end 231.25049 -147.27174)
		(width 0.1651)
		(layer "F.Cu")
		(net "M_E_DQ<30>")
	)
	(segment
		(start 229.413562 -120.2055)
		(end 229.997 -120.788938)
		(width 0.1651)
		(layer "F.Cu")
		(net "M_E_DQ<30>")
	)
	(segment
		(start 244.417088 -101.349302)
		(end 244.421914 -101.357938)
		(width 0.0889)
		(layer "F.Cu")
		(net "M_E_DQ<30>")
	)
	(segment
		(start 231.382062 -145.95348)
		(end 231.382062 -146.17192)
		(width 0.1651)
		(layer "F.Cu")
		(net "M_E_DQ<30>")
	)
	(segment
		(start 239.860328 -104.660954)
		(end 237.854236 -106.667046)
		(width 0.1016)
		(layer "F.Cu")
		(net "M_E_DQ<30>")
	)
	(segment
		(start 230.216202 -115.481608)
		(end 230.387144 -115.481608)
		(width 0.1651)
		(layer "F.Cu")
		(net "M_E_DQ<30>")
	)
	(segment
		(start 230.338884 -113.006124)
		(end 229.98684 -113.006124)
		(width 0.1651)
		(layer "F.Cu")
		(net "M_E_DQ<30>")
	)
	(segment
		(start 230.7844 -125.6538)
		(end 230.886 -125.7554)
		(width 0.1651)
		(layer "F.Cu")
		(net "M_E_DQ<30>")
	)
	(segment
		(start 230.035862 -117.398546)
		(end 229.413562 -118.020846)
		(width 0.1651)
		(layer "F.Cu")
		(net "M_E_DQ<30>")
	)
	(segment
		(start 237.854236 -106.667046)
		(end 237.705646 -106.667046)
		(width 0.1016)
		(layer "F.Cu")
		(net "M_E_DQ<30>")
	)
	(segment
		(start 229.814882 -113.510822)
		(end 229.993444 -113.689384)
		(width 0.1651)
		(layer "F.Cu")
		(net "M_E_DQ<30>")
	)
	(segment
		(start 244.421914 -101.357938)
		(end 244.430804 -101.373178)
		(width 0.0889)
		(layer "F.Cu")
		(net "M_E_DQ<30>")
	)
	(segment
		(start 230.203248 -114.798348)
		(end 230.076248 -114.925348)
		(width 0.1651)
		(layer "F.Cu")
		(net "M_E_DQ<30>")
	)
	(segment
		(start 231.249982 -145.8214)
		(end 231.382062 -145.95348)
		(width 0.1651)
		(layer "F.Cu")
		(net "M_E_DQ<30>")
	)
	(segment
		(start 230.547164 -117.18798)
		(end 230.336598 -117.398546)
		(width 0.1651)
		(layer "F.Cu")
		(net "M_E_DQ<30>")
	)
	(segment
		(start 230.514144 -113.864644)
		(end 230.514144 -114.671348)
		(width 0.1651)
		(layer "F.Cu")
		(net "M_E_DQ<30>")
	)
	(segment
		(start 230.387144 -114.798348)
		(end 230.203248 -114.798348)
		(width 0.1651)
		(layer "F.Cu")
		(net "M_E_DQ<30>")
	)
	(segment
		(start 230.54056 -111.940086)
		(end 230.54056 -112.804448)
		(width 0.1651)
		(layer "F.Cu")
		(net "M_E_DQ<30>")
	)
	(segment
		(start 230.514144 -114.671348)
		(end 230.387144 -114.798348)
		(width 0.1651)
		(layer "F.Cu")
		(net "M_E_DQ<30>")
	)
	(segment
		(start 230.338884 -113.689384)
		(end 230.514144 -113.864644)
		(width 0.1651)
		(layer "F.Cu")
		(net "M_E_DQ<30>")
	)
	(segment
		(start 231.382062 -146.17192)
		(end 231.249982 -146.304)
		(width 0.1651)
		(layer "F.Cu")
		(net "M_E_DQ<30>")
	)
	(segment
		(start 244.524784 -101.746812)
		(end 244.524784 -102.752398)
		(width 0.0889)
		(layer "F.Cu")
		(net "M_E_DQ<30>")
	)
	(segment
		(start 229.814882 -113.178082)
		(end 229.814882 -113.510822)
		(width 0.1651)
		(layer "F.Cu")
		(net "M_E_DQ<30>")
	)
	(segment
		(start 230.7844 -124.2568)
		(end 230.7844 -125.6538)
		(width 0.1651)
		(layer "F.Cu")
		(net "M_E_DQ<30>")
	)
	(segment
		(start 229.997 -123.4694)
		(end 230.7844 -124.2568)
		(width 0.1651)
		(layer "F.Cu")
		(net "M_E_DQ<30>")
	)
	(via
		(at 231.249728 -145.5166)
		(size 0.508)
		(drill 0.254)
		(layers "F.Cu" "B.Cu")
		(net "M_E_DQ<30>")
	)
	(via
		(at 230.399844 -126.615698)
		(size 0.508)
		(drill 0.254)
		(layers "F.Cu" "B.Cu")
		(net "M_E_DQ<30>")
	)
	(via
		(at 230.399844 -141.213078)
		(size 0.508)
		(drill 0.254)
		(layers "F.Cu" "B.Cu")
		(net "M_E_DQ<30>")
	)
	(arc
		(start 244.421914 -100.367084)
		(mid 244.501045 -100.662486)
		(end 244.421914 -100.957888)
		(width 0.0889)
		(layer "F.Cu")
		(net "M_E_DQ<30>")
	)
	(arc
		(start 244.421914 -100.957888)
		(mid 244.368444 -101.152951)
		(end 244.417088 -101.349302)
		(width 0.0889)
		(layer "F.Cu")
		(net "M_E_DQ<30>")
	)
	(arc
		(start 244.430804 -101.373178)
		(mid 244.500953 -101.554172)
		(end 244.524784 -101.746812)
		(width 0.0889)
		(layer "F.Cu")
		(net "M_E_DQ<30>")
	)
	(arc
		(start 244.421914 -99.967288)
		(mid 244.368415 -100.167186)
		(end 244.421914 -100.367084)
		(width 0.0889)
		(layer "F.Cu")
		(net "M_E_DQ<30>")
	)
	(segment
		(start 230.399844 -142.476982)
		(end 230.399844 -141.213078)
		(width 0.1651)
		(layer "B.Cu")
		(net "M_E_DQ<30>")
	)
	(segment
		(start 230.400352 -142.477236)
		(end 230.399844 -142.476982)
		(width 0.1651)
		(layer "B.Cu")
		(net "M_E_DQ<30>")
	)
	(segment
		(start 230.967534 -136.5504)
		(end 230.8352 -136.682734)
		(width 0.14224)
		(layer "In4.Cu")
		(net "M_E_DQ<30>")
	)
	(segment
		(start 230.764334 -131.307078)
		(end 230.916734 -131.459478)
		(width 0.14224)
		(layer "In4.Cu")
		(net "M_E_DQ<30>")
	)
	(segment
		(start 230.764334 -130.062478)
		(end 230.764334 -131.307078)
		(width 0.14224)
		(layer "In4.Cu")
		(net "M_E_DQ<30>")
	)
	(segment
		(start 229.966774 -144.233646)
		(end 231.249728 -145.5166)
		(width 0.14224)
		(layer "In4.Cu")
		(net "M_E_DQ<30>")
	)
	(segment
		(start 230.399844 -127.199898)
		(end 230.967534 -127.767588)
		(width 0.14224)
		(layer "In4.Cu")
		(net "M_E_DQ<30>")
	)
	(segment
		(start 230.967534 -127.767588)
		(end 230.967534 -129.859278)
		(width 0.14224)
		(layer "In4.Cu")
		(net "M_E_DQ<30>")
	)
	(segment
		(start 230.967534 -139.333478)
		(end 230.230934 -140.070078)
		(width 0.14224)
		(layer "In4.Cu")
		(net "M_E_DQ<30>")
	)
	(segment
		(start 230.8352 -138.7348)
		(end 230.967534 -138.867134)
		(width 0.14224)
		(layer "In4.Cu")
		(net "M_E_DQ<30>")
	)
	(segment
		(start 230.8352 -131.958334)
		(end 230.8352 -133.985)
		(width 0.14224)
		(layer "In4.Cu")
		(net "M_E_DQ<30>")
	)
	(segment
		(start 230.916734 -134.517638)
		(end 230.644192 -134.79018)
		(width 0.14224)
		(layer "In4.Cu")
		(net "M_E_DQ<30>")
	)
	(segment
		(start 230.399844 -126.615698)
		(end 230.399844 -127.199898)
		(width 0.14224)
		(layer "In4.Cu")
		(net "M_E_DQ<30>")
	)
	(segment
		(start 230.644192 -135.932926)
		(end 230.967534 -136.256268)
		(width 0.14224)
		(layer "In4.Cu")
		(net "M_E_DQ<30>")
	)
	(segment
		(start 230.967534 -136.256268)
		(end 230.967534 -136.5504)
		(width 0.14224)
		(layer "In4.Cu")
		(net "M_E_DQ<30>")
	)
	(segment
		(start 230.230934 -140.070078)
		(end 230.230934 -141.044168)
		(width 0.14224)
		(layer "In4.Cu")
		(net "M_E_DQ<30>")
	)
	(segment
		(start 230.916734 -134.066534)
		(end 230.916734 -134.517638)
		(width 0.14224)
		(layer "In4.Cu")
		(net "M_E_DQ<30>")
	)
	(segment
		(start 230.967534 -129.859278)
		(end 230.764334 -130.062478)
		(width 0.14224)
		(layer "In4.Cu")
		(net "M_E_DQ<30>")
	)
	(segment
		(start 230.916734 -131.459478)
		(end 230.916734 -131.8768)
		(width 0.14224)
		(layer "In4.Cu")
		(net "M_E_DQ<30>")
	)
	(segment
		(start 230.967534 -138.867134)
		(end 230.967534 -139.333478)
		(width 0.14224)
		(layer "In4.Cu")
		(net "M_E_DQ<30>")
	)
	(segment
		(start 230.230934 -141.044168)
		(end 230.399844 -141.213078)
		(width 0.14224)
		(layer "In4.Cu")
		(net "M_E_DQ<30>")
	)
	(segment
		(start 230.644192 -134.79018)
		(end 230.644192 -135.932926)
		(width 0.14224)
		(layer "In4.Cu")
		(net "M_E_DQ<30>")
	)
	(segment
		(start 229.966774 -141.646148)
		(end 229.966774 -144.233646)
		(width 0.14224)
		(layer "In4.Cu")
		(net "M_E_DQ<30>")
	)
	(segment
		(start 230.916734 -131.8768)
		(end 230.8352 -131.958334)
		(width 0.14224)
		(layer "In4.Cu")
		(net "M_E_DQ<30>")
	)
	(segment
		(start 230.8352 -136.682734)
		(end 230.8352 -138.7348)
		(width 0.14224)
		(layer "In4.Cu")
		(net "M_E_DQ<30>")
	)
	(segment
		(start 230.8352 -133.985)
		(end 230.916734 -134.066534)
		(width 0.14224)
		(layer "In4.Cu")
		(net "M_E_DQ<30>")
	)
	(segment
		(start 230.399844 -141.213078)
		(end 229.966774 -141.646148)
		(width 0.14224)
		(layer "In4.Cu")
		(net "M_E_DQ<30>")
	)
	(segment
		(start 204.899768 -147.27174)
		(end 204.899768 -146.280632)
		(width 0.1651)
		(layer "F.Cu")
		(net "M_E_DQ<2>")
	)
	(segment
		(start 204.899768 -146.280632)
		(end 205.03134 -146.14906)
		(width 0.1651)
		(layer "F.Cu")
		(net "M_E_DQ<2>")
	)
	(segment
		(start 204.900276 -147.27174)
		(end 204.899768 -147.27174)
		(width 0.1651)
		(layer "F.Cu")
		(net "M_E_DQ<2>")
	)
	(segment
		(start 237.042198 -86.794086)
		(end 236.470698 -86.794086)
		(width 0.1651)
		(layer "F.Cu")
		(net "M_E_DQ<2>")
	)
	(segment
		(start 205.03134 -146.14906)
		(end 205.03134 -145.92554)
		(width 0.1651)
		(layer "F.Cu")
		(net "M_E_DQ<2>")
	)
	(segment
		(start 205.03134 -145.92554)
		(end 204.899768 -145.793968)
		(width 0.1651)
		(layer "F.Cu")
		(net "M_E_DQ<2>")
	)
	(segment
		(start 204.899768 -145.793968)
		(end 204.899768 -145.5166)
		(width 0.1651)
		(layer "F.Cu")
		(net "M_E_DQ<2>")
	)
	(via
		(at 204.899768 -145.5166)
		(size 0.508)
		(drill 0.254)
		(layers "F.Cu" "B.Cu")
		(net "M_E_DQ<2>")
	)
	(via
		(at 236.470698 -86.794086)
		(size 0.508)
		(drill 0.254)
		(layers "F.Cu" "B.Cu")
		(net "M_E_DQ<2>")
	)
	(via
		(at 204.049884 -141.213078)
		(size 0.508)
		(drill 0.254)
		(layers "F.Cu" "B.Cu")
		(net "M_E_DQ<2>")
	)
	(segment
		(start 204.050392 -142.477236)
		(end 204.049884 -142.476982)
		(width 0.1651)
		(layer "B.Cu")
		(net "M_E_DQ<2>")
	)
	(segment
		(start 204.049884 -142.476982)
		(end 204.049884 -141.213078)
		(width 0.1651)
		(layer "B.Cu")
		(net "M_E_DQ<2>")
	)
	(segment
		(start 205.3082 -125.5268)
		(end 205.105 -125.3236)
		(width 0.14224)
		(layer "In4.Cu")
		(net "M_E_DQ<2>")
	)
	(segment
		(start 204.9018 -123.063)
		(end 204.4954 -123.063)
		(width 0.14224)
		(layer "In4.Cu")
		(net "M_E_DQ<2>")
	)
	(segment
		(start 204.339952 -134.701026)
		(end 204.339952 -135.976868)
		(width 0.14224)
		(layer "In4.Cu")
		(net "M_E_DQ<2>")
	)
	(segment
		(start 204.4954 -123.063)
		(end 204.2922 -123.2662)
		(width 0.14224)
		(layer "In4.Cu")
		(net "M_E_DQ<2>")
	)
	(segment
		(start 205.9178 -125.3236)
		(end 205.7146 -125.5268)
		(width 0.14224)
		(layer "In4.Cu")
		(net "M_E_DQ<2>")
	)
	(segment
		(start 231.255824 -88.148414)
		(end 229.616 -88.148414)
		(width 0.0889)
		(layer "In4.Cu")
		(net "M_E_DQ<2>")
	)
	(segment
		(start 204.2922 -123.2662)
		(end 204.2922 -128.933448)
		(width 0.14224)
		(layer "In4.Cu")
		(net "M_E_DQ<2>")
	)
	(segment
		(start 206.7306 -117.8814)
		(end 206.7306 -115.8494)
		(width 0.14224)
		(layer "In4.Cu")
		(net "M_E_DQ<2>")
	)
	(segment
		(start 203.616814 -144.233646)
		(end 204.899768 -145.5166)
		(width 0.14224)
		(layer "In4.Cu")
		(net "M_E_DQ<2>")
	)
	(segment
		(start 229.616 -88.148414)
		(end 229.347014 -88.4174)
		(width 0.0889)
		(layer "In4.Cu")
		(net "M_E_DQ<2>")
	)
	(segment
		(start 231.714548 -87.68969)
		(end 231.255824 -88.148414)
		(width 0.0889)
		(layer "In4.Cu")
		(net "M_E_DQ<2>")
	)
	(segment
		(start 204.049884 -141.213078)
		(end 203.616814 -141.646148)
		(width 0.14224)
		(layer "In4.Cu")
		(net "M_E_DQ<2>")
	)
	(segment
		(start 205.105 -123.2662)
		(end 204.9018 -123.063)
		(width 0.14224)
		(layer "In4.Cu")
		(net "M_E_DQ<2>")
	)
	(segment
		(start 207.5434 -114.149378)
		(end 207.5434 -117.8814)
		(width 0.14224)
		(layer "In4.Cu")
		(net "M_E_DQ<2>")
	)
	(segment
		(start 206.121 -115.6462)
		(end 205.9178 -115.8494)
		(width 0.14224)
		(layer "In4.Cu")
		(net "M_E_DQ<2>")
	)
	(segment
		(start 206.7306 -115.8494)
		(end 206.5274 -115.6462)
		(width 0.14224)
		(layer "In4.Cu")
		(net "M_E_DQ<2>")
	)
	(segment
		(start 205.105 -125.3236)
		(end 205.105 -123.2662)
		(width 0.14224)
		(layer "In4.Cu")
		(net "M_E_DQ<2>")
	)
	(segment
		(start 204.475588 -131.969764)
		(end 204.475588 -133.939788)
		(width 0.14224)
		(layer "In4.Cu")
		(net "M_E_DQ<2>")
	)
	(segment
		(start 204.568552 -136.601708)
		(end 204.47 -136.70026)
		(width 0.14224)
		(layer "In4.Cu")
		(net "M_E_DQ<2>")
	)
	(segment
		(start 203.704952 -140.235178)
		(end 203.704952 -140.868146)
		(width 0.14224)
		(layer "In4.Cu")
		(net "M_E_DQ<2>")
	)
	(segment
		(start 205.7146 -125.5268)
		(end 205.3082 -125.5268)
		(width 0.14224)
		(layer "In4.Cu")
		(net "M_E_DQ<2>")
	)
	(segment
		(start 204.47 -136.70026)
		(end 204.47 -138.938)
		(width 0.14224)
		(layer "In4.Cu")
		(net "M_E_DQ<2>")
	)
	(segment
		(start 204.568552 -139.371578)
		(end 203.704952 -140.235178)
		(width 0.14224)
		(layer "In4.Cu")
		(net "M_E_DQ<2>")
	)
	(segment
		(start 204.543152 -129.833878)
		(end 204.416152 -129.960878)
		(width 0.14224)
		(layer "In4.Cu")
		(net "M_E_DQ<2>")
	)
	(segment
		(start 210.760818 -110.93196)
		(end 207.5434 -114.149378)
		(width 0.14224)
		(layer "In4.Cu")
		(net "M_E_DQ<2>")
	)
	(segment
		(start 204.416152 -131.332478)
		(end 204.619352 -131.535678)
		(width 0.14224)
		(layer "In4.Cu")
		(net "M_E_DQ<2>")
	)
	(segment
		(start 204.619352 -131.826)
		(end 204.475588 -131.969764)
		(width 0.14224)
		(layer "In4.Cu")
		(net "M_E_DQ<2>")
	)
	(segment
		(start 204.568552 -139.036552)
		(end 204.568552 -139.371578)
		(width 0.14224)
		(layer "In4.Cu")
		(net "M_E_DQ<2>")
	)
	(segment
		(start 222.803974 -98.175572)
		(end 210.760818 -110.218728)
		(width 0.14224)
		(layer "In4.Cu")
		(net "M_E_DQ<2>")
	)
	(segment
		(start 236.140752 -86.03234)
		(end 236.123988 -86.003638)
		(width 0.0889)
		(layer "In4.Cu")
		(net "M_E_DQ<2>")
	)
	(segment
		(start 204.543152 -129.1844)
		(end 204.543152 -129.833878)
		(width 0.14224)
		(layer "In4.Cu")
		(net "M_E_DQ<2>")
	)
	(segment
		(start 206.5274 -115.6462)
		(end 206.121 -115.6462)
		(width 0.14224)
		(layer "In4.Cu")
		(net "M_E_DQ<2>")
	)
	(segment
		(start 203.704952 -140.868146)
		(end 204.049884 -141.213078)
		(width 0.14224)
		(layer "In4.Cu")
		(net "M_E_DQ<2>")
	)
	(segment
		(start 236.470698 -86.794086)
		(end 236.140752 -86.03234)
		(width 0.0889)
		(layer "In4.Cu")
		(net "M_E_DQ<2>")
	)
	(segment
		(start 204.619352 -134.421626)
		(end 204.339952 -134.701026)
		(width 0.14224)
		(layer "In4.Cu")
		(net "M_E_DQ<2>")
	)
	(segment
		(start 204.2922 -128.933448)
		(end 204.543152 -129.1844)
		(width 0.14224)
		(layer "In4.Cu")
		(net "M_E_DQ<2>")
	)
	(segment
		(start 204.619352 -131.535678)
		(end 204.619352 -131.826)
		(width 0.14224)
		(layer "In4.Cu")
		(net "M_E_DQ<2>")
	)
	(segment
		(start 229.347014 -88.4174)
		(end 229.099364 -88.4174)
		(width 0.0889)
		(layer "In4.Cu")
		(net "M_E_DQ<2>")
	)
	(segment
		(start 234.768644 -86.203536)
		(end 234.735878 -86.203536)
		(width 0.0889)
		(layer "In4.Cu")
		(net "M_E_DQ<2>")
	)
	(segment
		(start 206.9338 -118.0846)
		(end 206.7306 -117.8814)
		(width 0.14224)
		(layer "In4.Cu")
		(net "M_E_DQ<2>")
	)
	(segment
		(start 207.3402 -118.0846)
		(end 206.9338 -118.0846)
		(width 0.14224)
		(layer "In4.Cu")
		(net "M_E_DQ<2>")
	)
	(segment
		(start 222.803974 -94.71279)
		(end 222.803974 -98.175572)
		(width 0.14224)
		(layer "In4.Cu")
		(net "M_E_DQ<2>")
	)
	(segment
		(start 235.633768 -85.70849)
		(end 235.590588 -85.70849)
		(width 0.0889)
		(layer "In4.Cu")
		(net "M_E_DQ<2>")
	)
	(segment
		(start 204.475588 -133.939788)
		(end 204.619352 -134.083552)
		(width 0.14224)
		(layer "In4.Cu")
		(net "M_E_DQ<2>")
	)
	(segment
		(start 204.619352 -134.083552)
		(end 204.619352 -134.421626)
		(width 0.14224)
		(layer "In4.Cu")
		(net "M_E_DQ<2>")
	)
	(segment
		(start 204.47 -138.938)
		(end 204.568552 -139.036552)
		(width 0.14224)
		(layer "In4.Cu")
		(net "M_E_DQ<2>")
	)
	(segment
		(start 205.9178 -115.8494)
		(end 205.9178 -125.3236)
		(width 0.14224)
		(layer "In4.Cu")
		(net "M_E_DQ<2>")
	)
	(segment
		(start 210.760818 -110.218728)
		(end 210.760818 -110.93196)
		(width 0.14224)
		(layer "In4.Cu")
		(net "M_E_DQ<2>")
	)
	(segment
		(start 204.568552 -136.205468)
		(end 204.568552 -136.601708)
		(width 0.14224)
		(layer "In4.Cu")
		(net "M_E_DQ<2>")
	)
	(segment
		(start 204.339952 -135.976868)
		(end 204.568552 -136.205468)
		(width 0.14224)
		(layer "In4.Cu")
		(net "M_E_DQ<2>")
	)
	(segment
		(start 229.099364 -88.4174)
		(end 222.803974 -94.71279)
		(width 0.14224)
		(layer "In4.Cu")
		(net "M_E_DQ<2>")
	)
	(segment
		(start 233.051604 -87.194136)
		(end 233.018838 -87.194136)
		(width 0.0889)
		(layer "In4.Cu")
		(net "M_E_DQ<2>")
	)
	(segment
		(start 233.906314 -86.69909)
		(end 233.873548 -86.69909)
		(width 0.0889)
		(layer "In4.Cu")
		(net "M_E_DQ<2>")
	)
	(segment
		(start 204.416152 -129.960878)
		(end 204.416152 -131.332478)
		(width 0.14224)
		(layer "In4.Cu")
		(net "M_E_DQ<2>")
	)
	(segment
		(start 207.5434 -117.8814)
		(end 207.3402 -118.0846)
		(width 0.14224)
		(layer "In4.Cu")
		(net "M_E_DQ<2>")
	)
	(segment
		(start 203.616814 -141.646148)
		(end 203.616814 -144.233646)
		(width 0.14224)
		(layer "In4.Cu")
		(net "M_E_DQ<2>")
	)
	(segment
		(start 232.189274 -87.68969)
		(end 231.714548 -87.68969)
		(width 0.0889)
		(layer "In4.Cu")
		(net "M_E_DQ<2>")
	)
	(arc
		(start 236.123988 -86.003638)
		(mid 235.916984 -85.792774)
		(end 235.633768 -85.70849)
		(width 0.0889)
		(layer "In4.Cu")
		(net "M_E_DQ<2>")
	)
	(arc
		(start 235.590588 -85.70849)
		(mid 235.307371 -85.792771)
		(end 235.100368 -86.003638)
		(width 0.0889)
		(layer "In4.Cu")
		(net "M_E_DQ<2>")
	)
	(arc
		(start 233.018838 -87.194136)
		(mid 232.733414 -87.277603)
		(end 232.524808 -87.489538)
		(width 0.0889)
		(layer "In4.Cu")
		(net "M_E_DQ<2>")
	)
	(arc
		(start 233.873548 -86.69909)
		(mid 233.590331 -86.783371)
		(end 233.383328 -86.994238)
		(width 0.0889)
		(layer "In4.Cu")
		(net "M_E_DQ<2>")
	)
	(arc
		(start 234.735878 -86.203536)
		(mid 234.450454 -86.287003)
		(end 234.241848 -86.498938)
		(width 0.0889)
		(layer "In4.Cu")
		(net "M_E_DQ<2>")
	)
	(arc
		(start 235.100368 -86.003638)
		(mid 234.960289 -86.146374)
		(end 234.768644 -86.203536)
		(width 0.0889)
		(layer "In4.Cu")
		(net "M_E_DQ<2>")
	)
	(arc
		(start 232.524808 -87.489538)
		(mid 232.383125 -87.633342)
		(end 232.189274 -87.68969)
		(width 0.0889)
		(layer "In4.Cu")
		(net "M_E_DQ<2>")
	)
	(arc
		(start 234.241848 -86.498938)
		(mid 234.100165 -86.642742)
		(end 233.906314 -86.69909)
		(width 0.0889)
		(layer "In4.Cu")
		(net "M_E_DQ<2>")
	)
	(arc
		(start 233.383328 -86.994238)
		(mid 233.243249 -87.136974)
		(end 233.051604 -87.194136)
		(width 0.0889)
		(layer "In4.Cu")
		(net "M_E_DQ<2>")
	)
	(segment
		(start 224.987866 -118.648734)
		(end 224.4598 -119.1768)
		(width 0.1651)
		(layer "F.Cu")
		(net "M_E_DQ<29>")
	)
	(segment
		(start 238.972852 -102.527354)
		(end 237.97006 -103.530146)
		(width 0.1016)
		(layer "F.Cu")
		(net "M_E_DQ<29>")
	)
	(segment
		(start 236.164628 -102.844346)
		(end 232.988866 -102.844346)
		(width 0.1651)
		(layer "F.Cu")
		(net "M_E_DQ<29>")
	)
	(segment
		(start 241.852958 -101.44252)
		(end 241.645186 -101.812598)
		(width 0.0889)
		(layer "F.Cu")
		(net "M_E_DQ<29>")
	)
	(segment
		(start 224.4598 -117.3734)
		(end 224.4598 -117.7798)
		(width 0.1651)
		(layer "F.Cu")
		(net "M_E_DQ<29>")
	)
	(segment
		(start 224.4598 -122.936254)
		(end 224.8154 -123.291854)
		(width 0.1651)
		(layer "F.Cu")
		(net "M_E_DQ<29>")
	)
	(segment
		(start 224.4598 -120.904)
		(end 224.4598 -121.3104)
		(width 0.1651)
		(layer "F.Cu")
		(net "M_E_DQ<29>")
	)
	(segment
		(start 224.8916 -121.7422)
		(end 224.8916 -122.072654)
		(width 0.1651)
		(layer "F.Cu")
		(net "M_E_DQ<29>")
	)
	(segment
		(start 224.4598 -115.5446)
		(end 224.4598 -115.951)
		(width 0.1651)
		(layer "F.Cu")
		(net "M_E_DQ<29>")
	)
	(segment
		(start 224.4598 -121.3104)
		(end 224.8916 -121.7422)
		(width 0.1651)
		(layer "F.Cu")
		(net "M_E_DQ<29>")
	)
	(segment
		(start 224.987866 -116.479066)
		(end 224.987866 -116.845334)
		(width 0.1651)
		(layer "F.Cu")
		(net "M_E_DQ<29>")
	)
	(segment
		(start 224.8154 -123.291854)
		(end 224.8154 -124.3076)
		(width 0.1651)
		(layer "F.Cu")
		(net "M_E_DQ<29>")
	)
	(segment
		(start 225.830638 -110.002574)
		(end 224.4598 -113.312194)
		(width 0.1651)
		(layer "F.Cu")
		(net "M_E_DQ<29>")
	)
	(segment
		(start 224.8154 -124.3076)
		(end 225.171 -124.6632)
		(width 0.1651)
		(layer "F.Cu")
		(net "M_E_DQ<29>")
	)
	(segment
		(start 224.449894 -142.677642)
		(end 224.449894 -143.941546)
		(width 0.1651)
		(layer "F.Cu")
		(net "M_E_DQ<29>")
	)
	(segment
		(start 224.450402 -142.6718)
		(end 224.449894 -142.677642)
		(width 0.1651)
		(layer "F.Cu")
		(net "M_E_DQ<29>")
	)
	(segment
		(start 241.846608 -100.462588)
		(end 241.841782 -100.471224)
		(width 0.0889)
		(layer "F.Cu")
		(net "M_E_DQ<29>")
	)
	(segment
		(start 232.988866 -102.844346)
		(end 225.830638 -110.002574)
		(width 0.1651)
		(layer "F.Cu")
		(net "M_E_DQ<29>")
	)
	(segment
		(start 224.4598 -113.312194)
		(end 224.4598 -113.8936)
		(width 0.1651)
		(layer "F.Cu")
		(net "M_E_DQ<29>")
	)
	(segment
		(start 224.8916 -122.072654)
		(end 224.4598 -122.504454)
		(width 0.1651)
		(layer "F.Cu")
		(net "M_E_DQ<29>")
	)
	(segment
		(start 224.4598 -119.5578)
		(end 224.987866 -120.085866)
		(width 0.1651)
		(layer "F.Cu")
		(net "M_E_DQ<29>")
	)
	(segment
		(start 224.987866 -118.307866)
		(end 224.987866 -118.648734)
		(width 0.1651)
		(layer "F.Cu")
		(net "M_E_DQ<29>")
	)
	(segment
		(start 224.4598 -113.8936)
		(end 224.9424 -114.3762)
		(width 0.1651)
		(layer "F.Cu")
		(net "M_E_DQ<29>")
	)
	(segment
		(start 224.4598 -119.1768)
		(end 224.4598 -119.5578)
		(width 0.1651)
		(layer "F.Cu")
		(net "M_E_DQ<29>")
	)
	(segment
		(start 224.4598 -117.7798)
		(end 224.987866 -118.307866)
		(width 0.1651)
		(layer "F.Cu")
		(net "M_E_DQ<29>")
	)
	(segment
		(start 224.9424 -114.3762)
		(end 224.9424 -115.062)
		(width 0.1651)
		(layer "F.Cu")
		(net "M_E_DQ<29>")
	)
	(segment
		(start 241.326924 -102.13086)
		(end 241.326924 -102.224586)
		(width 0.0889)
		(layer "F.Cu")
		(net "M_E_DQ<29>")
	)
	(segment
		(start 224.4598 -115.951)
		(end 224.987866 -116.479066)
		(width 0.1651)
		(layer "F.Cu")
		(net "M_E_DQ<29>")
	)
	(segment
		(start 224.9424 -115.062)
		(end 224.4598 -115.5446)
		(width 0.1651)
		(layer "F.Cu")
		(net "M_E_DQ<29>")
	)
	(segment
		(start 237.97006 -103.530146)
		(end 237.171484 -103.530146)
		(width 0.1016)
		(layer "F.Cu")
		(net "M_E_DQ<29>")
	)
	(segment
		(start 236.485684 -102.844346)
		(end 236.164628 -102.844346)
		(width 0.1016)
		(layer "F.Cu")
		(net "M_E_DQ<29>")
	)
	(segment
		(start 242.193318 -99.67214)
		(end 241.903758 -100.327206)
		(width 0.0889)
		(layer "F.Cu")
		(net "M_E_DQ<29>")
	)
	(segment
		(start 241.326924 -102.224586)
		(end 241.024156 -102.527354)
		(width 0.1016)
		(layer "F.Cu")
		(net "M_E_DQ<29>")
	)
	(segment
		(start 241.024156 -102.527354)
		(end 238.972852 -102.527354)
		(width 0.1016)
		(layer "F.Cu")
		(net "M_E_DQ<29>")
	)
	(segment
		(start 224.4598 -122.504454)
		(end 224.4598 -122.936254)
		(width 0.1651)
		(layer "F.Cu")
		(net "M_E_DQ<29>")
	)
	(segment
		(start 224.987866 -116.845334)
		(end 224.4598 -117.3734)
		(width 0.1651)
		(layer "F.Cu")
		(net "M_E_DQ<29>")
	)
	(segment
		(start 241.645186 -101.812598)
		(end 241.326924 -102.13086)
		(width 0.0889)
		(layer "F.Cu")
		(net "M_E_DQ<29>")
	)
	(segment
		(start 224.987866 -120.085866)
		(end 224.987866 -120.375934)
		(width 0.1651)
		(layer "F.Cu")
		(net "M_E_DQ<29>")
	)
	(segment
		(start 224.987866 -120.375934)
		(end 224.4598 -120.904)
		(width 0.1651)
		(layer "F.Cu")
		(net "M_E_DQ<29>")
	)
	(segment
		(start 237.171484 -103.530146)
		(end 236.485684 -102.844346)
		(width 0.1016)
		(layer "F.Cu")
		(net "M_E_DQ<29>")
	)
	(via
		(at 224.449894 -143.941546)
		(size 0.508)
		(drill 0.254)
		(layers "F.Cu" "B.Cu")
		(net "M_E_DQ<29>")
	)
	(via
		(at 225.223578 -139.932156)
		(size 0.508)
		(drill 0.254)
		(layers "F.Cu" "B.Cu")
		(net "M_E_DQ<29>")
	)
	(via
		(at 225.171 -124.6632)
		(size 0.508)
		(drill 0.254)
		(layers "F.Cu" "B.Cu")
		(net "M_E_DQ<29>")
	)
	(arc
		(start 241.841782 -100.471224)
		(mid 241.793027 -100.667576)
		(end 241.846608 -100.862638)
		(width 0.0889)
		(layer "F.Cu")
		(net "M_E_DQ<29>")
	)
	(arc
		(start 241.846608 -100.862638)
		(mid 241.92583 -101.151756)
		(end 241.852958 -101.44252)
		(width 0.0889)
		(layer "F.Cu")
		(net "M_E_DQ<29>")
	)
	(arc
		(start 241.903758 -100.327206)
		(mid 241.879422 -100.396688)
		(end 241.846608 -100.462588)
		(width 0.0889)
		(layer "F.Cu")
		(net "M_E_DQ<29>")
	)
	(segment
		(start 225.299778 -137.877296)
		(end 225.299778 -139.855956)
		(width 0.1651)
		(layer "B.Cu")
		(net "M_E_DQ<29>")
	)
	(segment
		(start 225.299778 -139.855956)
		(end 225.223578 -139.932156)
		(width 0.1651)
		(layer "B.Cu")
		(net "M_E_DQ<29>")
	)
	(segment
		(start 225.300286 -137.877296)
		(end 225.299778 -137.877296)
		(width 0.1651)
		(layer "B.Cu")
		(net "M_E_DQ<29>")
	)
	(segment
		(start 224.772982 -140.3604)
		(end 224.772982 -140.9192)
		(width 0.14224)
		(layer "In4.Cu")
		(net "M_E_DQ<29>")
	)
	(segment
		(start 225.697034 -129.795778)
		(end 225.697034 -131.370578)
		(width 0.14224)
		(layer "In4.Cu")
		(net "M_E_DQ<29>")
	)
	(segment
		(start 224.849182 -142.747746)
		(end 224.611184 -142.985744)
		(width 0.14224)
		(layer "In4.Cu")
		(net "M_E_DQ<29>")
	)
	(segment
		(start 225.7298 -134.0358)
		(end 225.633534 -134.132066)
		(width 0.14224)
		(layer "In4.Cu")
		(net "M_E_DQ<29>")
	)
	(segment
		(start 224.611184 -142.154656)
		(end 224.849182 -142.392654)
		(width 0.14224)
		(layer "In4.Cu")
		(net "M_E_DQ<29>")
	)
	(segment
		(start 224.874582 -143.561054)
		(end 224.874582 -143.789146)
		(width 0.14224)
		(layer "In4.Cu")
		(net "M_E_DQ<29>")
	)
	(segment
		(start 225.633534 -134.132066)
		(end 225.633534 -134.670038)
		(width 0.14224)
		(layer "In4.Cu")
		(net "M_E_DQ<29>")
	)
	(segment
		(start 224.722182 -143.941546)
		(end 224.449894 -143.941546)
		(width 0.14224)
		(layer "In4.Cu")
		(net "M_E_DQ<29>")
	)
	(segment
		(start 224.899982 -141.0462)
		(end 224.899982 -141.528546)
		(width 0.14224)
		(layer "In4.Cu")
		(net "M_E_DQ<29>")
	)
	(segment
		(start 225.1964 -125.908054)
		(end 225.1964 -127.553466)
		(width 0.14224)
		(layer "In4.Cu")
		(net "M_E_DQ<29>")
	)
	(segment
		(start 224.899982 -141.528546)
		(end 224.611184 -141.817344)
		(width 0.14224)
		(layer "In4.Cu")
		(net "M_E_DQ<29>")
	)
	(segment
		(start 225.7298 -138.7856)
		(end 225.608134 -138.907266)
		(width 0.14224)
		(layer "In4.Cu")
		(net "M_E_DQ<29>")
	)
	(segment
		(start 225.7298 -131.973066)
		(end 225.7298 -134.0358)
		(width 0.14224)
		(layer "In4.Cu")
		(net "M_E_DQ<29>")
	)
	(segment
		(start 225.608134 -136.4996)
		(end 225.7298 -136.621266)
		(width 0.14224)
		(layer "In4.Cu")
		(net "M_E_DQ<29>")
	)
	(segment
		(start 225.760534 -135.853424)
		(end 225.608134 -136.005824)
		(width 0.14224)
		(layer "In4.Cu")
		(net "M_E_DQ<29>")
	)
	(segment
		(start 225.171 -124.6632)
		(end 225.608134 -125.100334)
		(width 0.14224)
		(layer "In4.Cu")
		(net "M_E_DQ<29>")
	)
	(segment
		(start 225.760534 -134.797038)
		(end 225.760534 -135.853424)
		(width 0.14224)
		(layer "In4.Cu")
		(net "M_E_DQ<29>")
	)
	(segment
		(start 224.611184 -143.297656)
		(end 224.874582 -143.561054)
		(width 0.14224)
		(layer "In4.Cu")
		(net "M_E_DQ<29>")
	)
	(segment
		(start 224.849182 -142.392654)
		(end 224.849182 -142.747746)
		(width 0.14224)
		(layer "In4.Cu")
		(net "M_E_DQ<29>")
	)
	(segment
		(start 225.697034 -131.370578)
		(end 225.633534 -131.434078)
		(width 0.14224)
		(layer "In4.Cu")
		(net "M_E_DQ<29>")
	)
	(segment
		(start 225.608134 -138.907266)
		(end 225.608134 -139.5476)
		(width 0.14224)
		(layer "In4.Cu")
		(net "M_E_DQ<29>")
	)
	(segment
		(start 225.1964 -127.553466)
		(end 225.608134 -127.9652)
		(width 0.14224)
		(layer "In4.Cu")
		(net "M_E_DQ<29>")
	)
	(segment
		(start 225.223578 -139.932156)
		(end 225.201226 -139.932156)
		(width 0.14224)
		(layer "In4.Cu")
		(net "M_E_DQ<29>")
	)
	(segment
		(start 225.608134 -125.49632)
		(end 225.1964 -125.908054)
		(width 0.14224)
		(layer "In4.Cu")
		(net "M_E_DQ<29>")
	)
	(segment
		(start 224.611184 -142.985744)
		(end 224.611184 -143.297656)
		(width 0.14224)
		(layer "In4.Cu")
		(net "M_E_DQ<29>")
	)
	(segment
		(start 224.772982 -140.9192)
		(end 224.899982 -141.0462)
		(width 0.14224)
		(layer "In4.Cu")
		(net "M_E_DQ<29>")
	)
	(segment
		(start 225.633534 -134.670038)
		(end 225.760534 -134.797038)
		(width 0.14224)
		(layer "In4.Cu")
		(net "M_E_DQ<29>")
	)
	(segment
		(start 225.633534 -131.8768)
		(end 225.7298 -131.973066)
		(width 0.14224)
		(layer "In4.Cu")
		(net "M_E_DQ<29>")
	)
	(segment
		(start 225.608134 -129.706878)
		(end 225.697034 -129.795778)
		(width 0.14224)
		(layer "In4.Cu")
		(net "M_E_DQ<29>")
	)
	(segment
		(start 225.7298 -136.621266)
		(end 225.7298 -138.7856)
		(width 0.14224)
		(layer "In4.Cu")
		(net "M_E_DQ<29>")
	)
	(segment
		(start 224.874582 -143.789146)
		(end 224.722182 -143.941546)
		(width 0.14224)
		(layer "In4.Cu")
		(net "M_E_DQ<29>")
	)
	(segment
		(start 225.608134 -127.9652)
		(end 225.608134 -129.706878)
		(width 0.14224)
		(layer "In4.Cu")
		(net "M_E_DQ<29>")
	)
	(segment
		(start 225.608134 -136.005824)
		(end 225.608134 -136.4996)
		(width 0.14224)
		(layer "In4.Cu")
		(net "M_E_DQ<29>")
	)
	(segment
		(start 225.608134 -139.5476)
		(end 225.223578 -139.932156)
		(width 0.14224)
		(layer "In4.Cu")
		(net "M_E_DQ<29>")
	)
	(segment
		(start 224.611184 -141.817344)
		(end 224.611184 -142.154656)
		(width 0.14224)
		(layer "In4.Cu")
		(net "M_E_DQ<29>")
	)
	(segment
		(start 225.201226 -139.932156)
		(end 224.772982 -140.3604)
		(width 0.14224)
		(layer "In4.Cu")
		(net "M_E_DQ<29>")
	)
	(segment
		(start 225.633534 -131.434078)
		(end 225.633534 -131.8768)
		(width 0.14224)
		(layer "In4.Cu")
		(net "M_E_DQ<29>")
	)
	(segment
		(start 225.608134 -125.100334)
		(end 225.608134 -125.49632)
		(width 0.14224)
		(layer "In4.Cu")
		(net "M_E_DQ<29>")
	)
	(segment
		(start 241.18443 -102.004114)
		(end 241.098324 -102.004114)
		(width 0.0889)
		(layer "F.Cu")
		(net "M_E_DQ<28>")
	)
	(segment
		(start 241.686334 -101.349302)
		(end 241.490754 -101.69779)
		(width 0.0889)
		(layer "F.Cu")
		(net "M_E_DQ<28>")
	)
	(segment
		(start 241.490754 -101.69779)
		(end 241.18443 -102.004114)
		(width 0.0889)
		(layer "F.Cu")
		(net "M_E_DQ<28>")
	)
	(segment
		(start 225.299778 -147.27174)
		(end 225.299778 -145.946368)
		(width 0.1651)
		(layer "F.Cu")
		(net "M_E_DQ<28>")
	)
	(segment
		(start 225.300286 -147.27174)
		(end 225.299778 -147.27174)
		(width 0.1651)
		(layer "F.Cu")
		(net "M_E_DQ<28>")
	)
	(segment
		(start 237.838488 -103.212646)
		(end 237.303056 -103.212646)
		(width 0.127)
		(layer "F.Cu")
		(net "M_E_DQ<28>")
	)
	(segment
		(start 241.675158 -99.95662)
		(end 241.681508 -99.967288)
		(width 0.0889)
		(layer "F.Cu")
		(net "M_E_DQ<28>")
	)
	(segment
		(start 241.098324 -102.004114)
		(end 240.892584 -102.209854)
		(width 0.127)
		(layer "F.Cu")
		(net "M_E_DQ<28>")
	)
	(segment
		(start 238.84128 -102.209854)
		(end 237.838488 -103.212646)
		(width 0.127)
		(layer "F.Cu")
		(net "M_E_DQ<28>")
	)
	(segment
		(start 243.051838 -99.17684)
		(end 242.208812 -99.081336)
		(width 0.0889)
		(layer "F.Cu")
		(net "M_E_DQ<28>")
	)
	(segment
		(start 223.7994 -113.180622)
		(end 223.7994 -126.2634)
		(width 0.1651)
		(layer "F.Cu")
		(net "M_E_DQ<28>")
	)
	(segment
		(start 223.7994 -126.2634)
		(end 224.155 -126.619)
		(width 0.1651)
		(layer "F.Cu")
		(net "M_E_DQ<28>")
	)
	(segment
		(start 225.299778 -145.946368)
		(end 225.201734 -145.415)
		(width 0.1651)
		(layer "F.Cu")
		(net "M_E_DQ<28>")
	)
	(segment
		(start 240.892584 -102.209854)
		(end 238.84128 -102.209854)
		(width 0.127)
		(layer "F.Cu")
		(net "M_E_DQ<28>")
	)
	(segment
		(start 232.514648 -102.196646)
		(end 225.403918 -109.307376)
		(width 0.1651)
		(layer "F.Cu")
		(net "M_E_DQ<28>")
	)
	(segment
		(start 236.287056 -102.196646)
		(end 232.514648 -102.196646)
		(width 0.1651)
		(layer "F.Cu")
		(net "M_E_DQ<28>")
	)
	(segment
		(start 224.155 -126.619)
		(end 224.2566 -126.619)
		(width 0.1651)
		(layer "F.Cu")
		(net "M_E_DQ<28>")
	)
	(segment
		(start 225.403918 -109.307376)
		(end 223.7994 -113.180622)
		(width 0.1651)
		(layer "F.Cu")
		(net "M_E_DQ<28>")
	)
	(segment
		(start 237.303056 -103.212646)
		(end 236.287056 -102.196646)
		(width 0.127)
		(layer "F.Cu")
		(net "M_E_DQ<28>")
	)
	(via
		(at 224.2566 -126.619)
		(size 0.508)
		(drill 0.254)
		(layers "F.Cu" "B.Cu")
		(net "M_E_DQ<28>")
	)
	(via
		(at 225.201734 -145.415)
		(size 0.508)
		(drill 0.254)
		(layers "F.Cu" "B.Cu")
		(net "M_E_DQ<28>")
	)
	(via
		(at 224.449894 -141.213078)
		(size 0.508)
		(drill 0.254)
		(layers "F.Cu" "B.Cu")
		(net "M_E_DQ<28>")
	)
	(arc
		(start 241.681508 -100.957888)
		(mid 241.734978 -101.152951)
		(end 241.686334 -101.349302)
		(width 0.0889)
		(layer "F.Cu")
		(net "M_E_DQ<28>")
	)
	(arc
		(start 241.681508 -99.967288)
		(mid 241.735007 -100.167186)
		(end 241.681508 -100.367084)
		(width 0.0889)
		(layer "F.Cu")
		(net "M_E_DQ<28>")
	)
	(arc
		(start 241.681508 -100.367084)
		(mid 241.602377 -100.662486)
		(end 241.681508 -100.957888)
		(width 0.0889)
		(layer "F.Cu")
		(net "M_E_DQ<28>")
	)
	(arc
		(start 242.208812 -99.081336)
		(mid 241.688688 -99.364508)
		(end 241.675158 -99.95662)
		(width 0.0889)
		(layer "F.Cu")
		(net "M_E_DQ<28>")
	)
	(segment
		(start 224.449894 -142.476982)
		(end 224.449894 -141.213078)
		(width 0.1651)
		(layer "B.Cu")
		(net "M_E_DQ<28>")
	)
	(segment
		(start 224.450402 -142.477236)
		(end 224.449894 -142.476982)
		(width 0.1651)
		(layer "B.Cu")
		(net "M_E_DQ<28>")
	)
	(segment
		(start 224.71253 -134.69747)
		(end 224.71253 -135.957564)
		(width 0.14224)
		(layer "In4.Cu")
		(net "M_E_DQ<28>")
	)
	(segment
		(start 224.016824 -144.17929)
		(end 224.174812 -144.337278)
		(width 0.14224)
		(layer "In4.Cu")
		(net "M_E_DQ<28>")
	)
	(segment
		(start 224.321878 -141.085062)
		(end 224.449894 -141.213078)
		(width 0.14224)
		(layer "In4.Cu")
		(net "M_E_DQ<28>")
	)
	(segment
		(start 224.950782 -145.415)
		(end 225.201734 -145.415)
		(width 0.14224)
		(layer "In4.Cu")
		(net "M_E_DQ<28>")
	)
	(segment
		(start 224.973134 -129.732278)
		(end 224.719134 -129.986278)
		(width 0.14224)
		(layer "In4.Cu")
		(net "M_E_DQ<28>")
	)
	(segment
		(start 224.973134 -128.122934)
		(end 224.973134 -129.732278)
		(width 0.14224)
		(layer "In4.Cu")
		(net "M_E_DQ<28>")
	)
	(segment
		(start 224.2566 -127.4064)
		(end 224.973134 -128.122934)
		(width 0.14224)
		(layer "In4.Cu")
		(net "M_E_DQ<28>")
	)
	(segment
		(start 224.174812 -144.337278)
		(end 224.174812 -144.63903)
		(width 0.14224)
		(layer "In4.Cu")
		(net "M_E_DQ<28>")
	)
	(segment
		(start 224.016824 -141.646148)
		(end 224.016824 -144.17929)
		(width 0.14224)
		(layer "In4.Cu")
		(net "M_E_DQ<28>")
	)
	(segment
		(start 224.911158 -131.372102)
		(end 224.911158 -134.498842)
		(width 0.14224)
		(layer "In4.Cu")
		(net "M_E_DQ<28>")
	)
	(segment
		(start 224.917254 -136.162288)
		(end 224.917254 -139.376658)
		(width 0.14224)
		(layer "In4.Cu")
		(net "M_E_DQ<28>")
	)
	(segment
		(start 224.2566 -126.619)
		(end 224.2566 -127.4064)
		(width 0.14224)
		(layer "In4.Cu")
		(net "M_E_DQ<28>")
	)
	(segment
		(start 224.449894 -141.213078)
		(end 224.016824 -141.646148)
		(width 0.14224)
		(layer "In4.Cu")
		(net "M_E_DQ<28>")
	)
	(segment
		(start 224.321878 -139.972034)
		(end 224.321878 -141.085062)
		(width 0.14224)
		(layer "In4.Cu")
		(net "M_E_DQ<28>")
	)
	(segment
		(start 224.719134 -129.986278)
		(end 224.719134 -131.180078)
		(width 0.14224)
		(layer "In4.Cu")
		(net "M_E_DQ<28>")
	)
	(segment
		(start 224.719134 -131.180078)
		(end 224.911158 -131.372102)
		(width 0.14224)
		(layer "In4.Cu")
		(net "M_E_DQ<28>")
	)
	(segment
		(start 224.917254 -139.376658)
		(end 224.321878 -139.972034)
		(width 0.14224)
		(layer "In4.Cu")
		(net "M_E_DQ<28>")
	)
	(segment
		(start 224.71253 -135.957564)
		(end 224.917254 -136.162288)
		(width 0.14224)
		(layer "In4.Cu")
		(net "M_E_DQ<28>")
	)
	(segment
		(start 224.174812 -144.63903)
		(end 224.950782 -145.415)
		(width 0.14224)
		(layer "In4.Cu")
		(net "M_E_DQ<28>")
	)
	(segment
		(start 224.911158 -134.498842)
		(end 224.71253 -134.69747)
		(width 0.14224)
		(layer "In4.Cu")
		(net "M_E_DQ<28>")
	)
	(segment
		(start 233.2736 -114.223546)
		(end 233.4514 -114.045746)
		(width 0.1651)
		(layer "F.Cu")
		(net "M_E_DQ<27>")
	)
	(segment
		(start 232.537 -119.679974)
		(end 232.537 -119.337074)
		(width 0.1651)
		(layer "F.Cu")
		(net "M_E_DQ<27>")
	)
	(segment
		(start 233.4514 -122.68962)
		(end 233.2736 -122.51182)
		(width 0.1651)
		(layer "F.Cu")
		(net "M_E_DQ<27>")
	)
	(segment
		(start 232.537 -121.026174)
		(end 232.537 -120.683274)
		(width 0.1651)
		(layer "F.Cu")
		(net "M_E_DQ<27>")
	)
	(segment
		(start 232.7021 -121.864374)
		(end 233.2863 -121.864374)
		(width 0.1651)
		(layer "F.Cu")
		(net "M_E_DQ<27>")
	)
	(segment
		(start 232.537 -120.683274)
		(end 232.7021 -120.518174)
		(width 0.1651)
		(layer "F.Cu")
		(net "M_E_DQ<27>")
	)
	(segment
		(start 233.4514 -111.8489)
		(end 236.690154 -108.610146)
		(width 0.1651)
		(layer "F.Cu")
		(net "M_E_DQ<27>")
	)
	(segment
		(start 233.4514 -116.586)
		(end 233.299 -116.4336)
		(width 0.1651)
		(layer "F.Cu")
		(net "M_E_DQ<27>")
	)
	(segment
		(start 232.7021 -119.171974)
		(end 233.2863 -119.171974)
		(width 0.1651)
		(layer "F.Cu")
		(net "M_E_DQ<27>")
	)
	(segment
		(start 233.2863 -118.498874)
		(end 232.7021 -118.498874)
		(width 0.1651)
		(layer "F.Cu")
		(net "M_E_DQ<27>")
	)
	(segment
		(start 233.136694 -123.17222)
		(end 233.299 -123.17222)
		(width 0.1651)
		(layer "F.Cu")
		(net "M_E_DQ<27>")
	)
	(segment
		(start 233.4514 -119.006874)
		(end 233.4514 -118.663974)
		(width 0.1651)
		(layer "F.Cu")
		(net "M_E_DQ<27>")
	)
	(segment
		(start 232.100374 -142.6718)
		(end 232.099866 -142.677642)
		(width 0.1651)
		(layer "F.Cu")
		(net "M_E_DQ<27>")
	)
	(segment
		(start 233.4514 -112.348772)
		(end 233.4514 -111.8489)
		(width 0.1651)
		(layer "F.Cu")
		(net "M_E_DQ<27>")
	)
	(segment
		(start 233.4514 -115.046506)
		(end 233.2736 -114.868706)
		(width 0.1651)
		(layer "F.Cu")
		(net "M_E_DQ<27>")
	)
	(segment
		(start 233.247946 -117.8306)
		(end 233.4514 -117.627146)
		(width 0.1651)
		(layer "F.Cu")
		(net "M_E_DQ<27>")
	)
	(segment
		(start 232.67162 -122.51182)
		(end 232.537 -122.3772)
		(width 0.1651)
		(layer "F.Cu")
		(net "M_E_DQ<27>")
	)
	(segment
		(start 233.4514 -118.663974)
		(end 233.2863 -118.498874)
		(width 0.1651)
		(layer "F.Cu")
		(net "M_E_DQ<27>")
	)
	(segment
		(start 245.164864 -101.632004)
		(end 245.164864 -103.423974)
		(width 0.0889)
		(layer "F.Cu")
		(net "M_E_DQ<27>")
	)
	(segment
		(start 232.537 -122.029474)
		(end 232.7021 -121.864374)
		(width 0.1651)
		(layer "F.Cu")
		(net "M_E_DQ<27>")
	)
	(segment
		(start 245.627144 -100.662486)
		(end 245.339108 -101.326696)
		(width 0.0889)
		(layer "F.Cu")
		(net "M_E_DQ<27>")
	)
	(segment
		(start 233.4514 -114.045746)
		(end 233.4514 -113.352072)
		(width 0.1651)
		(layer "F.Cu")
		(net "M_E_DQ<27>")
	)
	(segment
		(start 232.62844 -112.678972)
		(end 232.79354 -112.513872)
		(width 0.1651)
		(layer "F.Cu")
		(net "M_E_DQ<27>")
	)
	(segment
		(start 233.299 -116.0272)
		(end 233.4514 -115.8748)
		(width 0.1651)
		(layer "F.Cu")
		(net "M_E_DQ<27>")
	)
	(segment
		(start 233.4514 -115.8748)
		(end 233.4514 -115.046506)
		(width 0.1651)
		(layer "F.Cu")
		(net "M_E_DQ<27>")
	)
	(segment
		(start 233.4514 -124.04852)
		(end 233.3244 -123.92152)
		(width 0.1651)
		(layer "F.Cu")
		(net "M_E_DQ<27>")
	)
	(segment
		(start 233.4514 -121.699274)
		(end 233.4514 -121.356374)
		(width 0.1651)
		(layer "F.Cu")
		(net "M_E_DQ<27>")
	)
	(segment
		(start 232.9434 -123.365514)
		(end 233.136694 -123.17222)
		(width 0.1651)
		(layer "F.Cu")
		(net "M_E_DQ<27>")
	)
	(segment
		(start 245.268496 -101.446584)
		(end 245.164864 -101.632004)
		(width 0.0889)
		(layer "F.Cu")
		(net "M_E_DQ<27>")
	)
	(segment
		(start 233.2863 -119.845074)
		(end 232.7021 -119.845074)
		(width 0.1651)
		(layer "F.Cu")
		(net "M_E_DQ<27>")
	)
	(segment
		(start 233.2736 -114.868706)
		(end 233.2736 -114.223546)
		(width 0.1651)
		(layer "F.Cu")
		(net "M_E_DQ<27>")
	)
	(segment
		(start 233.4514 -120.353074)
		(end 233.4514 -120.010174)
		(width 0.1651)
		(layer "F.Cu")
		(net "M_E_DQ<27>")
	)
	(segment
		(start 233.4514 -125.3998)
		(end 233.4514 -124.04852)
		(width 0.1651)
		(layer "F.Cu")
		(net "M_E_DQ<27>")
	)
	(segment
		(start 233.1466 -123.92152)
		(end 232.9434 -123.71832)
		(width 0.1651)
		(layer "F.Cu")
		(net "M_E_DQ<27>")
	)
	(segment
		(start 232.62844 -113.021872)
		(end 232.62844 -112.678972)
		(width 0.1651)
		(layer "F.Cu")
		(net "M_E_DQ<27>")
	)
	(segment
		(start 232.099866 -142.677642)
		(end 232.099866 -143.941546)
		(width 0.1651)
		(layer "F.Cu")
		(net "M_E_DQ<27>")
	)
	(segment
		(start 233.2863 -120.518174)
		(end 233.4514 -120.353074)
		(width 0.1651)
		(layer "F.Cu")
		(net "M_E_DQ<27>")
	)
	(segment
		(start 232.537 -118.333774)
		(end 232.537 -117.9576)
		(width 0.1651)
		(layer "F.Cu")
		(net "M_E_DQ<27>")
	)
	(segment
		(start 233.2863 -121.191274)
		(end 232.7021 -121.191274)
		(width 0.1651)
		(layer "F.Cu")
		(net "M_E_DQ<27>")
	)
	(segment
		(start 233.4514 -117.627146)
		(end 233.4514 -116.586)
		(width 0.1651)
		(layer "F.Cu")
		(net "M_E_DQ<27>")
	)
	(segment
		(start 237.222792 -108.610146)
		(end 240.244884 -105.588054)
		(width 0.127)
		(layer "F.Cu")
		(net "M_E_DQ<27>")
	)
	(segment
		(start 232.79354 -112.513872)
		(end 233.2863 -112.513872)
		(width 0.1651)
		(layer "F.Cu")
		(net "M_E_DQ<27>")
	)
	(segment
		(start 233.3244 -125.5268)
		(end 233.4514 -125.3998)
		(width 0.1651)
		(layer "F.Cu")
		(net "M_E_DQ<27>")
	)
	(segment
		(start 232.7021 -118.498874)
		(end 232.537 -118.333774)
		(width 0.1651)
		(layer "F.Cu")
		(net "M_E_DQ<27>")
	)
	(segment
		(start 233.4514 -123.01982)
		(end 233.4514 -122.68962)
		(width 0.1651)
		(layer "F.Cu")
		(net "M_E_DQ<27>")
	)
	(segment
		(start 233.038142 -125.5268)
		(end 233.3244 -125.5268)
		(width 0.1651)
		(layer "F.Cu")
		(net "M_E_DQ<27>")
	)
	(segment
		(start 232.664 -117.8306)
		(end 233.247946 -117.8306)
		(width 0.1651)
		(layer "F.Cu")
		(net "M_E_DQ<27>")
	)
	(segment
		(start 233.2863 -113.186972)
		(end 232.79354 -113.186972)
		(width 0.1651)
		(layer "F.Cu")
		(net "M_E_DQ<27>")
	)
	(segment
		(start 232.966768 -125.455426)
		(end 233.038142 -125.5268)
		(width 0.1651)
		(layer "F.Cu")
		(net "M_E_DQ<27>")
	)
	(segment
		(start 243.000784 -105.588054)
		(end 240.244884 -105.588054)
		(width 0.127)
		(layer "F.Cu")
		(net "M_E_DQ<27>")
	)
	(segment
		(start 233.2863 -112.513872)
		(end 233.4514 -112.348772)
		(width 0.1651)
		(layer "F.Cu")
		(net "M_E_DQ<27>")
	)
	(segment
		(start 233.299 -116.4336)
		(end 233.299 -116.0272)
		(width 0.1651)
		(layer "F.Cu")
		(net "M_E_DQ<27>")
	)
	(segment
		(start 233.2736 -122.51182)
		(end 232.67162 -122.51182)
		(width 0.1651)
		(layer "F.Cu")
		(net "M_E_DQ<27>")
	)
	(segment
		(start 233.2863 -121.864374)
		(end 233.4514 -121.699274)
		(width 0.1651)
		(layer "F.Cu")
		(net "M_E_DQ<27>")
	)
	(segment
		(start 245.164864 -103.423974)
		(end 245.136924 -103.451914)
		(width 0.0889)
		(layer "F.Cu")
		(net "M_E_DQ<27>")
	)
	(segment
		(start 232.537 -117.9576)
		(end 232.664 -117.8306)
		(width 0.1651)
		(layer "F.Cu")
		(net "M_E_DQ<27>")
	)
	(segment
		(start 245.333774 -101.336856)
		(end 245.268496 -101.446584)
		(width 0.0889)
		(layer "F.Cu")
		(net "M_E_DQ<27>")
	)
	(segment
		(start 232.9434 -123.71832)
		(end 232.9434 -123.365514)
		(width 0.1651)
		(layer "F.Cu")
		(net "M_E_DQ<27>")
	)
	(segment
		(start 232.537 -119.337074)
		(end 232.7021 -119.171974)
		(width 0.1651)
		(layer "F.Cu")
		(net "M_E_DQ<27>")
	)
	(segment
		(start 245.136924 -103.451914)
		(end 243.000784 -105.588054)
		(width 0.127)
		(layer "F.Cu")
		(net "M_E_DQ<27>")
	)
	(segment
		(start 232.7021 -121.191274)
		(end 232.537 -121.026174)
		(width 0.1651)
		(layer "F.Cu")
		(net "M_E_DQ<27>")
	)
	(segment
		(start 237.097824 -108.610146)
		(end 237.222792 -108.610146)
		(width 0.127)
		(layer "F.Cu")
		(net "M_E_DQ<27>")
	)
	(segment
		(start 232.537 -122.3772)
		(end 232.537 -122.029474)
		(width 0.1651)
		(layer "F.Cu")
		(net "M_E_DQ<27>")
	)
	(segment
		(start 233.3244 -123.92152)
		(end 233.1466 -123.92152)
		(width 0.1651)
		(layer "F.Cu")
		(net "M_E_DQ<27>")
	)
	(segment
		(start 233.2863 -119.171974)
		(end 233.4514 -119.006874)
		(width 0.1651)
		(layer "F.Cu")
		(net "M_E_DQ<27>")
	)
	(segment
		(start 233.4514 -121.356374)
		(end 233.2863 -121.191274)
		(width 0.1651)
		(layer "F.Cu")
		(net "M_E_DQ<27>")
	)
	(segment
		(start 233.299 -123.17222)
		(end 233.4514 -123.01982)
		(width 0.1651)
		(layer "F.Cu")
		(net "M_E_DQ<27>")
	)
	(segment
		(start 233.4514 -120.010174)
		(end 233.2863 -119.845074)
		(width 0.1651)
		(layer "F.Cu")
		(net "M_E_DQ<27>")
	)
	(segment
		(start 236.690154 -108.610146)
		(end 237.097824 -108.610146)
		(width 0.1651)
		(layer "F.Cu")
		(net "M_E_DQ<27>")
	)
	(segment
		(start 232.7021 -119.845074)
		(end 232.537 -119.679974)
		(width 0.1651)
		(layer "F.Cu")
		(net "M_E_DQ<27>")
	)
	(segment
		(start 232.79354 -113.186972)
		(end 232.62844 -113.021872)
		(width 0.1651)
		(layer "F.Cu")
		(net "M_E_DQ<27>")
	)
	(segment
		(start 233.4514 -113.352072)
		(end 233.2863 -113.186972)
		(width 0.1651)
		(layer "F.Cu")
		(net "M_E_DQ<27>")
	)
	(segment
		(start 232.7021 -120.518174)
		(end 233.2863 -120.518174)
		(width 0.1651)
		(layer "F.Cu")
		(net "M_E_DQ<27>")
	)
	(via
		(at 232.94975 -139.932156)
		(size 0.508)
		(drill 0.254)
		(layers "F.Cu" "B.Cu")
		(net "M_E_DQ<27>")
	)
	(via
		(at 232.099866 -143.941546)
		(size 0.508)
		(drill 0.254)
		(layers "F.Cu" "B.Cu")
		(net "M_E_DQ<27>")
	)
	(via
		(at 232.966768 -125.455426)
		(size 0.508)
		(drill 0.254)
		(layers "F.Cu" "B.Cu")
		(net "M_E_DQ<27>")
	)
	(arc
		(start 245.339108 -101.326696)
		(mid 245.336604 -101.331862)
		(end 245.333774 -101.336856)
		(width 0.0889)
		(layer "F.Cu")
		(net "M_E_DQ<27>")
	)
	(segment
		(start 232.94975 -139.932156)
		(end 232.94975 -137.877296)
		(width 0.1651)
		(layer "B.Cu")
		(net "M_E_DQ<27>")
	)
	(segment
		(start 232.94975 -137.877296)
		(end 232.950512 -137.877296)
		(width 0.1651)
		(layer "B.Cu")
		(net "M_E_DQ<27>")
	)
	(segment
		(start 232.499154 -140.790168)
		(end 232.543604 -140.834618)
		(width 0.14224)
		(layer "In4.Cu")
		(net "M_E_DQ<27>")
	)
	(segment
		(start 233.2736 -137.922)
		(end 233.046016 -138.149584)
		(width 0.14224)
		(layer "In4.Cu")
		(net "M_E_DQ<27>")
	)
	(segment
		(start 232.927398 -139.932156)
		(end 232.499154 -140.3604)
		(width 0.14224)
		(layer "In4.Cu")
		(net "M_E_DQ<27>")
	)
	(segment
		(start 233.2736 -139.621514)
		(end 232.94975 -139.945364)
		(width 0.14224)
		(layer "In4.Cu")
		(net "M_E_DQ<27>")
	)
	(segment
		(start 232.94975 -139.932156)
		(end 232.927398 -139.932156)
		(width 0.14224)
		(layer "In4.Cu")
		(net "M_E_DQ<27>")
	)
	(segment
		(start 233.046016 -138.149584)
		(end 233.046016 -138.532616)
		(width 0.14224)
		(layer "In4.Cu")
		(net "M_E_DQ<27>")
	)
	(segment
		(start 233.317034 -134.581138)
		(end 233.532934 -134.797038)
		(width 0.14224)
		(layer "In4.Cu")
		(net "M_E_DQ<27>")
	)
	(segment
		(start 233.317034 -134.119366)
		(end 233.317034 -134.581138)
		(width 0.14224)
		(layer "In4.Cu")
		(net "M_E_DQ<27>")
	)
	(segment
		(start 233.278934 -136.72312)
		(end 232.9942 -137.007854)
		(width 0.14224)
		(layer "In4.Cu")
		(net "M_E_DQ<27>")
	)
	(segment
		(start 233.2736 -137.642346)
		(end 233.2736 -137.922)
		(width 0.14224)
		(layer "In4.Cu")
		(net "M_E_DQ<27>")
	)
	(segment
		(start 233.317034 -131.8768)
		(end 233.3752 -131.934966)
		(width 0.14224)
		(layer "In4.Cu")
		(net "M_E_DQ<27>")
	)
	(segment
		(start 232.261156 -142.059152)
		(end 232.518204 -142.3162)
		(width 0.14224)
		(layer "In4.Cu")
		(net "M_E_DQ<27>")
	)
	(segment
		(start 233.278934 -136.265412)
		(end 233.278934 -136.72312)
		(width 0.14224)
		(layer "In4.Cu")
		(net "M_E_DQ<27>")
	)
	(segment
		(start 233.456734 -131.268978)
		(end 233.317034 -131.408678)
		(width 0.14224)
		(layer "In4.Cu")
		(net "M_E_DQ<27>")
	)
	(segment
		(start 233.532934 -136.011412)
		(end 233.278934 -136.265412)
		(width 0.14224)
		(layer "In4.Cu")
		(net "M_E_DQ<27>")
	)
	(segment
		(start 233.3752 -134.0612)
		(end 233.317034 -134.119366)
		(width 0.14224)
		(layer "In4.Cu")
		(net "M_E_DQ<27>")
	)
	(segment
		(start 232.499154 -140.3604)
		(end 232.499154 -140.790168)
		(width 0.14224)
		(layer "In4.Cu")
		(net "M_E_DQ<27>")
	)
	(segment
		(start 232.543604 -140.834618)
		(end 232.543604 -141.5034)
		(width 0.14224)
		(layer "In4.Cu")
		(net "M_E_DQ<27>")
	)
	(segment
		(start 232.94975 -139.945364)
		(end 232.94975 -139.932156)
		(width 0.14224)
		(layer "In4.Cu")
		(net "M_E_DQ<27>")
	)
	(segment
		(start 232.549954 -143.44015)
		(end 232.549954 -143.763746)
		(width 0.14224)
		(layer "In4.Cu")
		(net "M_E_DQ<27>")
	)
	(segment
		(start 233.304334 -129.960878)
		(end 233.456734 -130.113278)
		(width 0.14224)
		(layer "In4.Cu")
		(net "M_E_DQ<27>")
	)
	(segment
		(start 232.518204 -142.3162)
		(end 232.518204 -142.621)
		(width 0.14224)
		(layer "In4.Cu")
		(net "M_E_DQ<27>")
	)
	(segment
		(start 233.317034 -131.408678)
		(end 233.317034 -131.8768)
		(width 0.14224)
		(layer "In4.Cu")
		(net "M_E_DQ<27>")
	)
	(segment
		(start 233.3752 -131.934966)
		(end 233.3752 -134.0612)
		(width 0.14224)
		(layer "In4.Cu")
		(net "M_E_DQ<27>")
	)
	(segment
		(start 232.9942 -137.007854)
		(end 232.9942 -137.362946)
		(width 0.14224)
		(layer "In4.Cu")
		(net "M_E_DQ<27>")
	)
	(segment
		(start 232.549954 -143.763746)
		(end 232.372154 -143.941546)
		(width 0.14224)
		(layer "In4.Cu")
		(net "M_E_DQ<27>")
	)
	(segment
		(start 232.9942 -137.362946)
		(end 233.2736 -137.642346)
		(width 0.14224)
		(layer "In4.Cu")
		(net "M_E_DQ<27>")
	)
	(segment
		(start 233.304334 -125.792992)
		(end 233.304334 -129.960878)
		(width 0.14224)
		(layer "In4.Cu")
		(net "M_E_DQ<27>")
	)
	(segment
		(start 233.456734 -130.113278)
		(end 233.456734 -131.268978)
		(width 0.14224)
		(layer "In4.Cu")
		(net "M_E_DQ<27>")
	)
	(segment
		(start 232.261156 -142.878048)
		(end 232.261156 -143.151352)
		(width 0.14224)
		(layer "In4.Cu")
		(net "M_E_DQ<27>")
	)
	(segment
		(start 232.518204 -142.621)
		(end 232.261156 -142.878048)
		(width 0.14224)
		(layer "In4.Cu")
		(net "M_E_DQ<27>")
	)
	(segment
		(start 232.372154 -143.941546)
		(end 232.099866 -143.941546)
		(width 0.14224)
		(layer "In4.Cu")
		(net "M_E_DQ<27>")
	)
	(segment
		(start 233.532934 -134.797038)
		(end 233.532934 -136.011412)
		(width 0.14224)
		(layer "In4.Cu")
		(net "M_E_DQ<27>")
	)
	(segment
		(start 233.046016 -138.532616)
		(end 233.2736 -138.7602)
		(width 0.14224)
		(layer "In4.Cu")
		(net "M_E_DQ<27>")
	)
	(segment
		(start 232.261156 -141.785848)
		(end 232.261156 -142.059152)
		(width 0.14224)
		(layer "In4.Cu")
		(net "M_E_DQ<27>")
	)
	(segment
		(start 232.966768 -125.455426)
		(end 233.304334 -125.792992)
		(width 0.14224)
		(layer "In4.Cu")
		(net "M_E_DQ<27>")
	)
	(segment
		(start 232.261156 -143.151352)
		(end 232.549954 -143.44015)
		(width 0.14224)
		(layer "In4.Cu")
		(net "M_E_DQ<27>")
	)
	(segment
		(start 232.543604 -141.5034)
		(end 232.261156 -141.785848)
		(width 0.14224)
		(layer "In4.Cu")
		(net "M_E_DQ<27>")
	)
	(segment
		(start 233.2736 -138.7602)
		(end 233.2736 -139.621514)
		(width 0.14224)
		(layer "In4.Cu")
		(net "M_E_DQ<27>")
	)
	(segment
		(start 231.88549 -123.531122)
		(end 232.3846 -124.030232)
		(width 0.1651)
		(layer "F.Cu")
		(net "M_E_DQ<26>")
	)
	(segment
		(start 232.5497 -117.196362)
		(end 232.0925 -117.196362)
		(width 0.1651)
		(layer "F.Cu")
		(net "M_E_DQ<26>")
	)
	(segment
		(start 231.88549 -117.403372)
		(end 231.88549 -123.531122)
		(width 0.1651)
		(layer "F.Cu")
		(net "M_E_DQ<26>")
	)
	(segment
		(start 237.275624 -107.962446)
		(end 236.398308 -107.962446)
		(width 0.1651)
		(layer "F.Cu")
		(net "M_E_DQ<26>")
	)
	(segment
		(start 232.3846 -124.030232)
		(end 232.3846 -125.1458)
		(width 0.1651)
		(layer "F.Cu")
		(net "M_E_DQ<26>")
	)
	(segment
		(start 232.4862 -125.6792)
		(end 232.918 -126.111)
		(width 0.1651)
		(layer "F.Cu")
		(net "M_E_DQ<26>")
	)
	(segment
		(start 232.6894 -126.8476)
		(end 232.331768 -126.8476)
		(width 0.1651)
		(layer "F.Cu")
		(net "M_E_DQ<26>")
	)
	(segment
		(start 232.7148 -115.710462)
		(end 232.5497 -115.875562)
		(width 0.1651)
		(layer "F.Cu")
		(net "M_E_DQ<26>")
	)
	(segment
		(start 231.9274 -116.370862)
		(end 232.0925 -116.535962)
		(width 0.1651)
		(layer "F.Cu")
		(net "M_E_DQ<26>")
	)
	(segment
		(start 233.081322 -145.92554)
		(end 232.94975 -145.793968)
		(width 0.1651)
		(layer "F.Cu")
		(net "M_E_DQ<26>")
	)
	(segment
		(start 232.950512 -147.27174)
		(end 232.94975 -147.27174)
		(width 0.1651)
		(layer "F.Cu")
		(net "M_E_DQ<26>")
	)
	(segment
		(start 231.9274 -116.040662)
		(end 231.9274 -116.370862)
		(width 0.1651)
		(layer "F.Cu")
		(net "M_E_DQ<26>")
	)
	(segment
		(start 232.6132 -114.389662)
		(end 232.4481 -114.554762)
		(width 0.1651)
		(layer "F.Cu")
		(net "M_E_DQ<26>")
	)
	(segment
		(start 232.331768 -126.8476)
		(end 232.099866 -126.615698)
		(width 0.1651)
		(layer "F.Cu")
		(net "M_E_DQ<26>")
	)
	(segment
		(start 245.627144 -99.67214)
		(end 245.162578 -100.297234)
		(width 0.0889)
		(layer "F.Cu")
		(net "M_E_DQ<26>")
	)
	(segment
		(start 242.869212 -105.270554)
		(end 240.113312 -105.270554)
		(width 0.1016)
		(layer "F.Cu")
		(net "M_E_DQ<26>")
	)
	(segment
		(start 232.0925 -116.535962)
		(end 232.5497 -116.535962)
		(width 0.1651)
		(layer "F.Cu")
		(net "M_E_DQ<26>")
	)
	(segment
		(start 232.7148 -115.380262)
		(end 232.7148 -115.710462)
		(width 0.1651)
		(layer "F.Cu")
		(net "M_E_DQ<26>")
	)
	(segment
		(start 232.918 -126.619)
		(end 232.6894 -126.8476)
		(width 0.1651)
		(layer "F.Cu")
		(net "M_E_DQ<26>")
	)
	(segment
		(start 232.6132 -114.059462)
		(end 232.6132 -114.389662)
		(width 0.1651)
		(layer "F.Cu")
		(net "M_E_DQ<26>")
	)
	(segment
		(start 244.974364 -103.165402)
		(end 244.937788 -103.201978)
		(width 0.0889)
		(layer "F.Cu")
		(net "M_E_DQ<26>")
	)
	(segment
		(start 232.4481 -114.554762)
		(end 232.0925 -114.554762)
		(width 0.1651)
		(layer "F.Cu")
		(net "M_E_DQ<26>")
	)
	(segment
		(start 245.11762 -101.30409)
		(end 245.094506 -101.345492)
		(width 0.0889)
		(layer "F.Cu")
		(net "M_E_DQ<26>")
	)
	(segment
		(start 240.113312 -105.270554)
		(end 237.42142 -107.962446)
		(width 0.1016)
		(layer "F.Cu")
		(net "M_E_DQ<26>")
	)
	(segment
		(start 232.5497 -115.875562)
		(end 232.0925 -115.875562)
		(width 0.1651)
		(layer "F.Cu")
		(net "M_E_DQ<26>")
	)
	(segment
		(start 232.0925 -115.215162)
		(end 232.5497 -115.215162)
		(width 0.1651)
		(layer "F.Cu")
		(net "M_E_DQ<26>")
	)
	(segment
		(start 232.918 -126.111)
		(end 232.918 -126.619)
		(width 0.1651)
		(layer "F.Cu")
		(net "M_E_DQ<26>")
	)
	(segment
		(start 231.9274 -114.719862)
		(end 231.9274 -115.050062)
		(width 0.1651)
		(layer "F.Cu")
		(net "M_E_DQ<26>")
	)
	(segment
		(start 244.974364 -101.621082)
		(end 244.974364 -103.165402)
		(width 0.0889)
		(layer "F.Cu")
		(net "M_E_DQ<26>")
	)
	(segment
		(start 231.9274 -115.050062)
		(end 232.0925 -115.215162)
		(width 0.1651)
		(layer "F.Cu")
		(net "M_E_DQ<26>")
	)
	(segment
		(start 232.5497 -116.535962)
		(end 232.7148 -116.701062)
		(width 0.1651)
		(layer "F.Cu")
		(net "M_E_DQ<26>")
	)
	(segment
		(start 232.94975 -147.27174)
		(end 232.94975 -146.280632)
		(width 0.1651)
		(layer "F.Cu")
		(net "M_E_DQ<26>")
	)
	(segment
		(start 232.0925 -117.196362)
		(end 231.88549 -117.403372)
		(width 0.1651)
		(layer "F.Cu")
		(net "M_E_DQ<26>")
	)
	(segment
		(start 232.94975 -146.280632)
		(end 233.081322 -146.14906)
		(width 0.1651)
		(layer "F.Cu")
		(net "M_E_DQ<26>")
	)
	(segment
		(start 232.3846 -125.1458)
		(end 232.4862 -125.2474)
		(width 0.1651)
		(layer "F.Cu")
		(net "M_E_DQ<26>")
	)
	(segment
		(start 236.398308 -107.962446)
		(end 231.917494 -112.44326)
		(width 0.1651)
		(layer "F.Cu")
		(net "M_E_DQ<26>")
	)
	(segment
		(start 232.0925 -114.554762)
		(end 231.9274 -114.719862)
		(width 0.1651)
		(layer "F.Cu")
		(net "M_E_DQ<26>")
	)
	(segment
		(start 231.917494 -112.44326)
		(end 231.917494 -113.693956)
		(width 0.1651)
		(layer "F.Cu")
		(net "M_E_DQ<26>")
	)
	(segment
		(start 232.4862 -125.2474)
		(end 232.4862 -125.6792)
		(width 0.1651)
		(layer "F.Cu")
		(net "M_E_DQ<26>")
	)
	(segment
		(start 245.094506 -101.345492)
		(end 245.011956 -101.484176)
		(width 0.0889)
		(layer "F.Cu")
		(net "M_E_DQ<26>")
	)
	(segment
		(start 232.94975 -145.793968)
		(end 232.94975 -145.5166)
		(width 0.1651)
		(layer "F.Cu")
		(net "M_E_DQ<26>")
	)
	(segment
		(start 233.081322 -146.14906)
		(end 233.081322 -145.92554)
		(width 0.1651)
		(layer "F.Cu")
		(net "M_E_DQ<26>")
	)
	(segment
		(start 232.7148 -117.031262)
		(end 232.5497 -117.196362)
		(width 0.1651)
		(layer "F.Cu")
		(net "M_E_DQ<26>")
	)
	(segment
		(start 231.917494 -113.693956)
		(end 232.1179 -113.894362)
		(width 0.1651)
		(layer "F.Cu")
		(net "M_E_DQ<26>")
	)
	(segment
		(start 232.0925 -115.875562)
		(end 231.9274 -116.040662)
		(width 0.1651)
		(layer "F.Cu")
		(net "M_E_DQ<26>")
	)
	(segment
		(start 232.1179 -113.894362)
		(end 232.4481 -113.894362)
		(width 0.1651)
		(layer "F.Cu")
		(net "M_E_DQ<26>")
	)
	(segment
		(start 232.4481 -113.894362)
		(end 232.6132 -114.059462)
		(width 0.1651)
		(layer "F.Cu")
		(net "M_E_DQ<26>")
	)
	(segment
		(start 237.42142 -107.962446)
		(end 237.275624 -107.962446)
		(width 0.1016)
		(layer "F.Cu")
		(net "M_E_DQ<26>")
	)
	(segment
		(start 232.5497 -115.215162)
		(end 232.7148 -115.380262)
		(width 0.1651)
		(layer "F.Cu")
		(net "M_E_DQ<26>")
	)
	(segment
		(start 244.937788 -103.201978)
		(end 242.869212 -105.270554)
		(width 0.1016)
		(layer "F.Cu")
		(net "M_E_DQ<26>")
	)
	(segment
		(start 232.7148 -116.701062)
		(end 232.7148 -117.031262)
		(width 0.1651)
		(layer "F.Cu")
		(net "M_E_DQ<26>")
	)
	(via
		(at 232.94975 -145.5166)
		(size 0.508)
		(drill 0.254)
		(layers "F.Cu" "B.Cu")
		(net "M_E_DQ<26>")
	)
	(via
		(at 232.099866 -141.213078)
		(size 0.508)
		(drill 0.254)
		(layers "F.Cu" "B.Cu")
		(net "M_E_DQ<26>")
	)
	(via
		(at 232.099866 -126.615698)
		(size 0.508)
		(drill 0.254)
		(layers "F.Cu" "B.Cu")
		(net "M_E_DQ<26>")
	)
	(arc
		(start 245.115334 -100.957888)
		(mid 245.162165 -101.130673)
		(end 245.11762 -101.30409)
		(width 0.0889)
		(layer "F.Cu")
		(net "M_E_DQ<26>")
	)
	(arc
		(start 245.162578 -100.297234)
		(mid 245.037693 -100.620322)
		(end 245.115334 -100.957888)
		(width 0.0889)
		(layer "F.Cu")
		(net "M_E_DQ<26>")
	)
	(arc
		(start 245.011956 -101.484176)
		(mid 244.983894 -101.550088)
		(end 244.974364 -101.621082)
		(width 0.0889)
		(layer "F.Cu")
		(net "M_E_DQ<26>")
	)
	(segment
		(start 232.100374 -142.477236)
		(end 232.099866 -142.476982)
		(width 0.1651)
		(layer "B.Cu")
		(net "M_E_DQ<26>")
	)
	(segment
		(start 232.099866 -142.476982)
		(end 232.099866 -141.213078)
		(width 0.1651)
		(layer "B.Cu")
		(net "M_E_DQ<26>")
	)
	(segment
		(start 232.618534 -136.5504)
		(end 232.537 -136.631934)
		(width 0.14224)
		(layer "In4.Cu")
		(net "M_E_DQ<26>")
	)
	(segment
		(start 232.618534 -136.205468)
		(end 232.618534 -136.5504)
		(width 0.14224)
		(layer "In4.Cu")
		(net "M_E_DQ<26>")
	)
	(segment
		(start 232.669334 -134.193534)
		(end 232.669334 -134.492238)
		(width 0.14224)
		(layer "In4.Cu")
		(net "M_E_DQ<26>")
	)
	(segment
		(start 231.754934 -140.235178)
		(end 231.754934 -140.868146)
		(width 0.14224)
		(layer "In4.Cu")
		(net "M_E_DQ<26>")
	)
	(segment
		(start 232.537 -132.009134)
		(end 232.537 -134.0612)
		(width 0.14224)
		(layer "In4.Cu")
		(net "M_E_DQ<26>")
	)
	(segment
		(start 232.389934 -134.771638)
		(end 232.389934 -135.976868)
		(width 0.14224)
		(layer "In4.Cu")
		(net "M_E_DQ<26>")
	)
	(segment
		(start 232.537 -134.0612)
		(end 232.669334 -134.193534)
		(width 0.14224)
		(layer "In4.Cu")
		(net "M_E_DQ<26>")
	)
	(segment
		(start 232.466134 -131.332478)
		(end 232.664 -131.530344)
		(width 0.14224)
		(layer "In4.Cu")
		(net "M_E_DQ<26>")
	)
	(segment
		(start 232.618534 -139.371578)
		(end 231.754934 -140.235178)
		(width 0.14224)
		(layer "In4.Cu")
		(net "M_E_DQ<26>")
	)
	(segment
		(start 231.666796 -141.646148)
		(end 231.666796 -144.233646)
		(width 0.14224)
		(layer "In4.Cu")
		(net "M_E_DQ<26>")
	)
	(segment
		(start 232.669334 -134.492238)
		(end 232.389934 -134.771638)
		(width 0.14224)
		(layer "In4.Cu")
		(net "M_E_DQ<26>")
	)
	(segment
		(start 232.537 -138.8872)
		(end 232.618534 -138.968734)
		(width 0.14224)
		(layer "In4.Cu")
		(net "M_E_DQ<26>")
	)
	(segment
		(start 232.099866 -141.213078)
		(end 231.666796 -141.646148)
		(width 0.14224)
		(layer "In4.Cu")
		(net "M_E_DQ<26>")
	)
	(segment
		(start 232.537 -136.631934)
		(end 232.537 -138.8872)
		(width 0.14224)
		(layer "In4.Cu")
		(net "M_E_DQ<26>")
	)
	(segment
		(start 232.099866 -126.615698)
		(end 232.593134 -127.108966)
		(width 0.14224)
		(layer "In4.Cu")
		(net "M_E_DQ<26>")
	)
	(segment
		(start 232.618534 -138.968734)
		(end 232.618534 -139.371578)
		(width 0.14224)
		(layer "In4.Cu")
		(net "M_E_DQ<26>")
	)
	(segment
		(start 231.666796 -144.233646)
		(end 232.94975 -145.5166)
		(width 0.14224)
		(layer "In4.Cu")
		(net "M_E_DQ<26>")
	)
	(segment
		(start 231.754934 -140.868146)
		(end 232.099866 -141.213078)
		(width 0.14224)
		(layer "In4.Cu")
		(net "M_E_DQ<26>")
	)
	(segment
		(start 232.593134 -129.833878)
		(end 232.466134 -129.960878)
		(width 0.14224)
		(layer "In4.Cu")
		(net "M_E_DQ<26>")
	)
	(segment
		(start 232.466134 -129.960878)
		(end 232.466134 -131.332478)
		(width 0.14224)
		(layer "In4.Cu")
		(net "M_E_DQ<26>")
	)
	(segment
		(start 232.593134 -127.108966)
		(end 232.593134 -129.833878)
		(width 0.14224)
		(layer "In4.Cu")
		(net "M_E_DQ<26>")
	)
	(segment
		(start 232.664 -131.530344)
		(end 232.664 -131.882134)
		(width 0.14224)
		(layer "In4.Cu")
		(net "M_E_DQ<26>")
	)
	(segment
		(start 232.389934 -135.976868)
		(end 232.618534 -136.205468)
		(width 0.14224)
		(layer "In4.Cu")
		(net "M_E_DQ<26>")
	)
	(segment
		(start 232.664 -131.882134)
		(end 232.537 -132.009134)
		(width 0.14224)
		(layer "In4.Cu")
		(net "M_E_DQ<26>")
	)
	(segment
		(start 226.7966 -118.721124)
		(end 226.6315 -118.886224)
		(width 0.1651)
		(layer "F.Cu")
		(net "M_E_DQ<25>")
	)
	(segment
		(start 226.834954 -122.670824)
		(end 226.657154 -122.848624)
		(width 0.1651)
		(layer "F.Cu")
		(net "M_E_DQ<25>")
	)
	(segment
		(start 226.7966 -115.632992)
		(end 226.614736 -115.814856)
		(width 0.1651)
		(layer "F.Cu")
		(net "M_E_DQ<25>")
	)
	(segment
		(start 226.268788 -112.384332)
		(end 226.268788 -112.727232)
		(width 0.1651)
		(layer "F.Cu")
		(net "M_E_DQ<25>")
	)
	(segment
		(start 236.434122 -104.139746)
		(end 233.78414 -104.139746)
		(width 0.1651)
		(layer "F.Cu")
		(net "M_E_DQ<25>")
	)
	(segment
		(start 226.841558 -121.032524)
		(end 226.841558 -121.362724)
		(width 0.1651)
		(layer "F.Cu")
		(net "M_E_DQ<25>")
	)
	(segment
		(start 239.225836 -103.136954)
		(end 238.223044 -104.139746)
		(width 0.1016)
		(layer "F.Cu")
		(net "M_E_DQ<25>")
	)
	(segment
		(start 226.2886 -123.3424)
		(end 226.441 -123.4948)
		(width 0.1651)
		(layer "F.Cu")
		(net "M_E_DQ<25>")
	)
	(segment
		(start 242.996466 -102.124256)
		(end 241.983768 -103.136954)
		(width 0.1016)
		(layer "F.Cu")
		(net "M_E_DQ<25>")
	)
	(segment
		(start 226.7966 -113.057432)
		(end 226.7966 -115.632992)
		(width 0.1651)
		(layer "F.Cu")
		(net "M_E_DQ<25>")
	)
	(segment
		(start 226.2886 -122.994166)
		(end 226.2886 -123.3424)
		(width 0.1651)
		(layer "F.Cu")
		(net "M_E_DQ<25>")
	)
	(segment
		(start 241.983768 -103.136954)
		(end 239.225836 -103.136954)
		(width 0.1016)
		(layer "F.Cu")
		(net "M_E_DQ<25>")
	)
	(segment
		(start 226.676204 -120.207024)
		(end 226.434396 -120.207024)
		(width 0.1651)
		(layer "F.Cu")
		(net "M_E_DQ<25>")
	)
	(segment
		(start 226.834954 -122.340624)
		(end 226.834954 -122.670824)
		(width 0.1651)
		(layer "F.Cu")
		(net "M_E_DQ<25>")
	)
	(segment
		(start 226.614736 -115.814856)
		(end 226.614736 -116.07038)
		(width 0.1651)
		(layer "F.Cu")
		(net "M_E_DQ<25>")
	)
	(segment
		(start 226.441 -123.4948)
		(end 226.70516 -123.4948)
		(width 0.1651)
		(layer "F.Cu")
		(net "M_E_DQ<25>")
	)
	(segment
		(start 226.149916 -142.677642)
		(end 226.149916 -143.941546)
		(width 0.1651)
		(layer "F.Cu")
		(net "M_E_DQ<25>")
	)
	(segment
		(start 233.78414 -104.139746)
		(end 226.7966 -111.127286)
		(width 0.1651)
		(layer "F.Cu")
		(net "M_E_DQ<25>")
	)
	(segment
		(start 226.614736 -116.07038)
		(end 226.7966 -116.252244)
		(width 0.1651)
		(layer "F.Cu")
		(net "M_E_DQ<25>")
	)
	(segment
		(start 226.269296 -119.381524)
		(end 226.434396 -119.546624)
		(width 0.1651)
		(layer "F.Cu")
		(net "M_E_DQ<25>")
	)
	(segment
		(start 226.841558 -121.362724)
		(end 226.676458 -121.527824)
		(width 0.1651)
		(layer "F.Cu")
		(net "M_E_DQ<25>")
	)
	(segment
		(start 226.676458 -120.867424)
		(end 226.841558 -121.032524)
		(width 0.1651)
		(layer "F.Cu")
		(net "M_E_DQ<25>")
	)
	(segment
		(start 226.657154 -122.848624)
		(end 226.434142 -122.848624)
		(width 0.1651)
		(layer "F.Cu")
		(net "M_E_DQ<25>")
	)
	(segment
		(start 227.33 -124.914914)
		(end 227.33 -125.759464)
		(width 0.1651)
		(layer "F.Cu")
		(net "M_E_DQ<25>")
	)
	(segment
		(start 226.6315 -112.219232)
		(end 226.433888 -112.219232)
		(width 0.1651)
		(layer "F.Cu")
		(net "M_E_DQ<25>")
	)
	(segment
		(start 238.223044 -104.139746)
		(end 236.434122 -104.139746)
		(width 0.1016)
		(layer "F.Cu")
		(net "M_E_DQ<25>")
	)
	(segment
		(start 226.70516 -123.4948)
		(end 226.83216 -123.6218)
		(width 0.1651)
		(layer "F.Cu")
		(net "M_E_DQ<25>")
	)
	(segment
		(start 226.269042 -122.023124)
		(end 226.434142 -122.188224)
		(width 0.1651)
		(layer "F.Cu")
		(net "M_E_DQ<25>")
	)
	(segment
		(start 226.2886 -124.579888)
		(end 226.496626 -124.787914)
		(width 0.1651)
		(layer "F.Cu")
		(net "M_E_DQ<25>")
	)
	(segment
		(start 227.203 -124.787914)
		(end 227.33 -124.914914)
		(width 0.1651)
		(layer "F.Cu")
		(net "M_E_DQ<25>")
	)
	(segment
		(start 226.434396 -120.867424)
		(end 226.676458 -120.867424)
		(width 0.1651)
		(layer "F.Cu")
		(net "M_E_DQ<25>")
	)
	(segment
		(start 226.83216 -123.97994)
		(end 226.6696 -124.1425)
		(width 0.1651)
		(layer "F.Cu")
		(net "M_E_DQ<25>")
	)
	(segment
		(start 226.269296 -120.372124)
		(end 226.269296 -120.702324)
		(width 0.1651)
		(layer "F.Cu")
		(net "M_E_DQ<25>")
	)
	(segment
		(start 227.33 -125.759464)
		(end 227.183188 -125.906276)
		(width 0.1651)
		(layer "F.Cu")
		(net "M_E_DQ<25>")
	)
	(segment
		(start 226.434396 -118.886224)
		(end 226.269296 -119.051324)
		(width 0.1651)
		(layer "F.Cu")
		(net "M_E_DQ<25>")
	)
	(segment
		(start 226.6315 -118.886224)
		(end 226.434396 -118.886224)
		(width 0.1651)
		(layer "F.Cu")
		(net "M_E_DQ<25>")
	)
	(segment
		(start 227.183188 -125.906276)
		(end 226.822 -125.906276)
		(width 0.1651)
		(layer "F.Cu")
		(net "M_E_DQ<25>")
	)
	(segment
		(start 226.4156 -124.1425)
		(end 226.2886 -124.2695)
		(width 0.1651)
		(layer "F.Cu")
		(net "M_E_DQ<25>")
	)
	(segment
		(start 226.7966 -116.252244)
		(end 226.7966 -118.721124)
		(width 0.1651)
		(layer "F.Cu")
		(net "M_E_DQ<25>")
	)
	(segment
		(start 226.7966 -112.054132)
		(end 226.6315 -112.219232)
		(width 0.1651)
		(layer "F.Cu")
		(net "M_E_DQ<25>")
	)
	(segment
		(start 243.051838 -102.068884)
		(end 242.996466 -102.124256)
		(width 0.0889)
		(layer "F.Cu")
		(net "M_E_DQ<25>")
	)
	(segment
		(start 226.6315 -112.892332)
		(end 226.7966 -113.057432)
		(width 0.1651)
		(layer "F.Cu")
		(net "M_E_DQ<25>")
	)
	(segment
		(start 226.434396 -119.546624)
		(end 226.676204 -119.546624)
		(width 0.1651)
		(layer "F.Cu")
		(net "M_E_DQ<25>")
	)
	(segment
		(start 226.434142 -121.527824)
		(end 226.269042 -121.692924)
		(width 0.1651)
		(layer "F.Cu")
		(net "M_E_DQ<25>")
	)
	(segment
		(start 226.496626 -124.787914)
		(end 227.203 -124.787914)
		(width 0.1651)
		(layer "F.Cu")
		(net "M_E_DQ<25>")
	)
	(segment
		(start 226.433888 -112.892332)
		(end 226.6315 -112.892332)
		(width 0.1651)
		(layer "F.Cu")
		(net "M_E_DQ<25>")
	)
	(segment
		(start 226.268788 -112.727232)
		(end 226.433888 -112.892332)
		(width 0.1651)
		(layer "F.Cu")
		(net "M_E_DQ<25>")
	)
	(segment
		(start 226.269296 -120.702324)
		(end 226.434396 -120.867424)
		(width 0.1651)
		(layer "F.Cu")
		(net "M_E_DQ<25>")
	)
	(segment
		(start 226.150424 -142.6718)
		(end 226.149916 -142.677642)
		(width 0.1651)
		(layer "F.Cu")
		(net "M_E_DQ<25>")
	)
	(segment
		(start 243.051838 -101.15804)
		(end 243.051838 -102.068884)
		(width 0.0889)
		(layer "F.Cu")
		(net "M_E_DQ<25>")
	)
	(segment
		(start 226.434396 -120.207024)
		(end 226.269296 -120.372124)
		(width 0.1651)
		(layer "F.Cu")
		(net "M_E_DQ<25>")
	)
	(segment
		(start 226.269042 -121.692924)
		(end 226.269042 -122.023124)
		(width 0.1651)
		(layer "F.Cu")
		(net "M_E_DQ<25>")
	)
	(segment
		(start 226.269296 -119.051324)
		(end 226.269296 -119.381524)
		(width 0.1651)
		(layer "F.Cu")
		(net "M_E_DQ<25>")
	)
	(segment
		(start 226.6696 -124.1425)
		(end 226.4156 -124.1425)
		(width 0.1651)
		(layer "F.Cu")
		(net "M_E_DQ<25>")
	)
	(segment
		(start 226.434142 -122.188224)
		(end 226.682554 -122.188224)
		(width 0.1651)
		(layer "F.Cu")
		(net "M_E_DQ<25>")
	)
	(segment
		(start 226.682554 -122.188224)
		(end 226.834954 -122.340624)
		(width 0.1651)
		(layer "F.Cu")
		(net "M_E_DQ<25>")
	)
	(segment
		(start 226.434142 -122.848624)
		(end 226.2886 -122.994166)
		(width 0.1651)
		(layer "F.Cu")
		(net "M_E_DQ<25>")
	)
	(segment
		(start 226.676204 -119.546624)
		(end 226.841304 -119.711724)
		(width 0.1651)
		(layer "F.Cu")
		(net "M_E_DQ<25>")
	)
	(segment
		(start 226.676458 -121.527824)
		(end 226.434142 -121.527824)
		(width 0.1651)
		(layer "F.Cu")
		(net "M_E_DQ<25>")
	)
	(segment
		(start 226.841304 -119.711724)
		(end 226.841304 -120.041924)
		(width 0.1651)
		(layer "F.Cu")
		(net "M_E_DQ<25>")
	)
	(segment
		(start 226.841304 -120.041924)
		(end 226.676204 -120.207024)
		(width 0.1651)
		(layer "F.Cu")
		(net "M_E_DQ<25>")
	)
	(segment
		(start 226.7966 -111.127286)
		(end 226.7966 -112.054132)
		(width 0.1651)
		(layer "F.Cu")
		(net "M_E_DQ<25>")
	)
	(segment
		(start 226.2886 -124.2695)
		(end 226.2886 -124.579888)
		(width 0.1651)
		(layer "F.Cu")
		(net "M_E_DQ<25>")
	)
	(segment
		(start 226.433888 -112.219232)
		(end 226.268788 -112.384332)
		(width 0.1651)
		(layer "F.Cu")
		(net "M_E_DQ<25>")
	)
	(segment
		(start 226.83216 -123.6218)
		(end 226.83216 -123.97994)
		(width 0.1651)
		(layer "F.Cu")
		(net "M_E_DQ<25>")
	)
	(via
		(at 226.822 -125.906276)
		(size 0.508)
		(drill 0.254)
		(layers "F.Cu" "B.Cu")
		(net "M_E_DQ<25>")
	)
	(via
		(at 226.822 -139.932156)
		(size 0.508)
		(drill 0.254)
		(layers "F.Cu" "B.Cu")
		(net "M_E_DQ<25>")
	)
	(via
		(at 226.149916 -143.941546)
		(size 0.508)
		(drill 0.254)
		(layers "F.Cu" "B.Cu")
		(net "M_E_DQ<25>")
	)
	(segment
		(start 226.9998 -139.251182)
		(end 226.822 -139.428982)
		(width 0.1651)
		(layer "B.Cu")
		(net "M_E_DQ<25>")
	)
	(segment
		(start 226.822 -139.428982)
		(end 226.822 -139.932156)
		(width 0.1651)
		(layer "B.Cu")
		(net "M_E_DQ<25>")
	)
	(segment
		(start 226.9998 -137.877296)
		(end 226.9998 -139.251182)
		(width 0.1651)
		(layer "B.Cu")
		(net "M_E_DQ<25>")
	)
	(segment
		(start 227.000308 -137.877296)
		(end 226.9998 -137.877296)
		(width 0.1651)
		(layer "B.Cu")
		(net "M_E_DQ<25>")
	)
	(segment
		(start 226.799648 -139.932156)
		(end 226.371404 -140.3604)
		(width 0.14224)
		(layer "In4.Cu")
		(net "M_E_DQ<25>")
	)
	(segment
		(start 226.822 -139.843256)
		(end 226.822 -139.932156)
		(width 0.14224)
		(layer "In4.Cu")
		(net "M_E_DQ<25>")
	)
	(segment
		(start 226.550982 -143.4846)
		(end 226.550982 -143.7894)
		(width 0.14224)
		(layer "In4.Cu")
		(net "M_E_DQ<25>")
	)
	(segment
		(start 226.601782 -141.020546)
		(end 226.601782 -141.425168)
		(width 0.14224)
		(layer "In4.Cu")
		(net "M_E_DQ<25>")
	)
	(segment
		(start 227.4316 -138.811)
		(end 227.309934 -138.932666)
		(width 0.14224)
		(layer "In4.Cu")
		(net "M_E_DQ<25>")
	)
	(segment
		(start 226.311206 -143.244824)
		(end 226.550982 -143.4846)
		(width 0.14224)
		(layer "In4.Cu")
		(net "M_E_DQ<25>")
	)
	(segment
		(start 226.371404 -140.790168)
		(end 226.601782 -141.020546)
		(width 0.14224)
		(layer "In4.Cu")
		(net "M_E_DQ<25>")
	)
	(segment
		(start 226.822 -128.035812)
		(end 227.309934 -128.523746)
		(width 0.14224)
		(layer "In4.Cu")
		(net "M_E_DQ<25>")
	)
	(segment
		(start 226.311206 -141.715744)
		(end 226.311206 -142.076424)
		(width 0.14224)
		(layer "In4.Cu")
		(net "M_E_DQ<25>")
	)
	(segment
		(start 227.309934 -136.5758)
		(end 227.4316 -136.697466)
		(width 0.14224)
		(layer "In4.Cu")
		(net "M_E_DQ<25>")
	)
	(segment
		(start 227.4316 -131.978146)
		(end 227.4316 -134.4422)
		(width 0.14224)
		(layer "In4.Cu")
		(net "M_E_DQ<25>")
	)
	(segment
		(start 226.822 -139.932156)
		(end 226.799648 -139.932156)
		(width 0.14224)
		(layer "In4.Cu")
		(net "M_E_DQ<25>")
	)
	(segment
		(start 227.309934 -131.85648)
		(end 227.4316 -131.978146)
		(width 0.14224)
		(layer "In4.Cu")
		(net "M_E_DQ<25>")
	)
	(segment
		(start 226.398836 -143.941546)
		(end 226.149916 -143.941546)
		(width 0.14224)
		(layer "In4.Cu")
		(net "M_E_DQ<25>")
	)
	(segment
		(start 226.311206 -142.076424)
		(end 226.525582 -142.2908)
		(width 0.14224)
		(layer "In4.Cu")
		(net "M_E_DQ<25>")
	)
	(segment
		(start 227.309934 -138.932666)
		(end 227.309934 -139.355322)
		(width 0.14224)
		(layer "In4.Cu")
		(net "M_E_DQ<25>")
	)
	(segment
		(start 227.309934 -134.563866)
		(end 227.309934 -136.5758)
		(width 0.14224)
		(layer "In4.Cu")
		(net "M_E_DQ<25>")
	)
	(segment
		(start 226.525582 -142.2908)
		(end 226.525582 -142.7226)
		(width 0.14224)
		(layer "In4.Cu")
		(net "M_E_DQ<25>")
	)
	(segment
		(start 226.371404 -140.3604)
		(end 226.371404 -140.790168)
		(width 0.14224)
		(layer "In4.Cu")
		(net "M_E_DQ<25>")
	)
	(segment
		(start 227.309934 -139.355322)
		(end 226.822 -139.843256)
		(width 0.14224)
		(layer "In4.Cu")
		(net "M_E_DQ<25>")
	)
	(segment
		(start 226.525582 -142.7226)
		(end 226.311206 -142.936976)
		(width 0.14224)
		(layer "In4.Cu")
		(net "M_E_DQ<25>")
	)
	(segment
		(start 226.311206 -142.936976)
		(end 226.311206 -143.244824)
		(width 0.14224)
		(layer "In4.Cu")
		(net "M_E_DQ<25>")
	)
	(segment
		(start 227.4316 -134.4422)
		(end 227.309934 -134.563866)
		(width 0.14224)
		(layer "In4.Cu")
		(net "M_E_DQ<25>")
	)
	(segment
		(start 227.4316 -136.697466)
		(end 227.4316 -138.811)
		(width 0.14224)
		(layer "In4.Cu")
		(net "M_E_DQ<25>")
	)
	(segment
		(start 226.550982 -143.7894)
		(end 226.398836 -143.941546)
		(width 0.14224)
		(layer "In4.Cu")
		(net "M_E_DQ<25>")
	)
	(segment
		(start 226.822 -125.906276)
		(end 226.822 -128.035812)
		(width 0.14224)
		(layer "In4.Cu")
		(net "M_E_DQ<25>")
	)
	(segment
		(start 226.601782 -141.425168)
		(end 226.311206 -141.715744)
		(width 0.14224)
		(layer "In4.Cu")
		(net "M_E_DQ<25>")
	)
	(segment
		(start 227.309934 -128.523746)
		(end 227.309934 -131.85648)
		(width 0.14224)
		(layer "In4.Cu")
		(net "M_E_DQ<25>")
	)
	(segment
		(start 242.633246 -101.102414)
		(end 242.633246 -102.056184)
		(width 0.0889)
		(layer "F.Cu")
		(net "M_E_DQ<24>")
	)
	(segment
		(start 226.0854 -116.764562)
		(end 225.9203 -116.929662)
		(width 0.1651)
		(layer "F.Cu")
		(net "M_E_DQ<24>")
	)
	(segment
		(start 225.9203 -113.627662)
		(end 226.0854 -113.792762)
		(width 0.1651)
		(layer "F.Cu")
		(net "M_E_DQ<24>")
	)
	(segment
		(start 226.0854 -116.434362)
		(end 226.0854 -116.764562)
		(width 0.1651)
		(layer "F.Cu")
		(net "M_E_DQ<24>")
	)
	(segment
		(start 226.149408 -118.091966)
		(end 225.990912 -118.250462)
		(width 0.1651)
		(layer "F.Cu")
		(net "M_E_DQ<24>")
	)
	(segment
		(start 233.526584 -103.492046)
		(end 226.191318 -110.827312)
		(width 0.1651)
		(layer "F.Cu")
		(net "M_E_DQ<24>")
	)
	(segment
		(start 225.7933 -113.627662)
		(end 225.9203 -113.627662)
		(width 0.1651)
		(layer "F.Cu")
		(net "M_E_DQ<24>")
	)
	(segment
		(start 225.6282 -116.104162)
		(end 225.7933 -116.269262)
		(width 0.1651)
		(layer "F.Cu")
		(net "M_E_DQ<24>")
	)
	(segment
		(start 225.6282 -115.773962)
		(end 225.6282 -116.104162)
		(width 0.1651)
		(layer "F.Cu")
		(net "M_E_DQ<24>")
	)
	(segment
		(start 242.633246 -102.056184)
		(end 242.59032 -102.09911)
		(width 0.0889)
		(layer "F.Cu")
		(net "M_E_DQ<24>")
	)
	(segment
		(start 226.0854 -115.443762)
		(end 225.9203 -115.608862)
		(width 0.1651)
		(layer "F.Cu")
		(net "M_E_DQ<24>")
	)
	(segment
		(start 226.149408 -117.761766)
		(end 226.149408 -118.091966)
		(width 0.1651)
		(layer "F.Cu")
		(net "M_E_DQ<24>")
	)
	(segment
		(start 225.6282 -114.453162)
		(end 225.6282 -114.783362)
		(width 0.1651)
		(layer "F.Cu")
		(net "M_E_DQ<24>")
	)
	(segment
		(start 225.6282 -113.462562)
		(end 225.7933 -113.627662)
		(width 0.1651)
		(layer "F.Cu")
		(net "M_E_DQ<24>")
	)
	(segment
		(start 225.9203 -116.929662)
		(end 225.7933 -116.929662)
		(width 0.1651)
		(layer "F.Cu")
		(net "M_E_DQ<24>")
	)
	(segment
		(start 225.9203 -116.269262)
		(end 226.0854 -116.434362)
		(width 0.1651)
		(layer "F.Cu")
		(net "M_E_DQ<24>")
	)
	(segment
		(start 225.7933 -118.250462)
		(end 225.6282 -118.415562)
		(width 0.1651)
		(layer "F.Cu")
		(net "M_E_DQ<24>")
	)
	(segment
		(start 225.9203 -114.948462)
		(end 226.0854 -115.113562)
		(width 0.1651)
		(layer "F.Cu")
		(net "M_E_DQ<24>")
	)
	(segment
		(start 225.7933 -117.590062)
		(end 225.977704 -117.590062)
		(width 0.1651)
		(layer "F.Cu")
		(net "M_E_DQ<24>")
	)
	(segment
		(start 225.7933 -114.288062)
		(end 225.6282 -114.453162)
		(width 0.1651)
		(layer "F.Cu")
		(net "M_E_DQ<24>")
	)
	(segment
		(start 238.096552 -103.834946)
		(end 237.044992 -103.834946)
		(width 0.1016)
		(layer "F.Cu")
		(net "M_E_DQ<24>")
	)
	(segment
		(start 225.6282 -112.186466)
		(end 225.6282 -113.462562)
		(width 0.1651)
		(layer "F.Cu")
		(net "M_E_DQ<24>")
	)
	(segment
		(start 237.044992 -103.834946)
		(end 236.702092 -103.492046)
		(width 0.1016)
		(layer "F.Cu")
		(net "M_E_DQ<24>")
	)
	(segment
		(start 226.0854 -115.113562)
		(end 226.0854 -115.443762)
		(width 0.1651)
		(layer "F.Cu")
		(net "M_E_DQ<24>")
	)
	(segment
		(start 242.59032 -102.09911)
		(end 241.857276 -102.832154)
		(width 0.1016)
		(layer "F.Cu")
		(net "M_E_DQ<24>")
	)
	(segment
		(start 225.9203 -114.288062)
		(end 225.7933 -114.288062)
		(width 0.1651)
		(layer "F.Cu")
		(net "M_E_DQ<24>")
	)
	(segment
		(start 225.6282 -117.424962)
		(end 225.7933 -117.590062)
		(width 0.1651)
		(layer "F.Cu")
		(net "M_E_DQ<24>")
	)
	(segment
		(start 226.0854 -113.792762)
		(end 226.0854 -114.122962)
		(width 0.1651)
		(layer "F.Cu")
		(net "M_E_DQ<24>")
	)
	(segment
		(start 239.099344 -102.832154)
		(end 238.096552 -103.834946)
		(width 0.1016)
		(layer "F.Cu")
		(net "M_E_DQ<24>")
	)
	(segment
		(start 226.9998 -147.277582)
		(end 226.822 -145.415)
		(width 0.1651)
		(layer "F.Cu")
		(net "M_E_DQ<24>")
	)
	(segment
		(start 241.857276 -102.832154)
		(end 239.099344 -102.832154)
		(width 0.1016)
		(layer "F.Cu")
		(net "M_E_DQ<24>")
	)
	(segment
		(start 225.7933 -114.948462)
		(end 225.9203 -114.948462)
		(width 0.1651)
		(layer "F.Cu")
		(net "M_E_DQ<24>")
	)
	(segment
		(start 225.7933 -116.929662)
		(end 225.6282 -117.094762)
		(width 0.1651)
		(layer "F.Cu")
		(net "M_E_DQ<24>")
	)
	(segment
		(start 225.6282 -114.783362)
		(end 225.7933 -114.948462)
		(width 0.1651)
		(layer "F.Cu")
		(net "M_E_DQ<24>")
	)
	(segment
		(start 225.6282 -117.094762)
		(end 225.6282 -117.424962)
		(width 0.1651)
		(layer "F.Cu")
		(net "M_E_DQ<24>")
	)
	(segment
		(start 225.977704 -117.590062)
		(end 226.149408 -117.761766)
		(width 0.1651)
		(layer "F.Cu")
		(net "M_E_DQ<24>")
	)
	(segment
		(start 242.193318 -100.662486)
		(end 242.633246 -101.102414)
		(width 0.0889)
		(layer "F.Cu")
		(net "M_E_DQ<24>")
	)
	(segment
		(start 225.7933 -116.269262)
		(end 225.9203 -116.269262)
		(width 0.1651)
		(layer "F.Cu")
		(net "M_E_DQ<24>")
	)
	(segment
		(start 225.9203 -115.608862)
		(end 225.7933 -115.608862)
		(width 0.1651)
		(layer "F.Cu")
		(net "M_E_DQ<24>")
	)
	(segment
		(start 236.702092 -103.492046)
		(end 236.434122 -103.492046)
		(width 0.1016)
		(layer "F.Cu")
		(net "M_E_DQ<24>")
	)
	(segment
		(start 225.7933 -115.608862)
		(end 225.6282 -115.773962)
		(width 0.1651)
		(layer "F.Cu")
		(net "M_E_DQ<24>")
	)
	(segment
		(start 225.6282 -125.73)
		(end 225.8568 -125.9586)
		(width 0.1651)
		(layer "F.Cu")
		(net "M_E_DQ<24>")
	)
	(segment
		(start 227.000308 -147.27174)
		(end 226.9998 -147.277582)
		(width 0.1651)
		(layer "F.Cu")
		(net "M_E_DQ<24>")
	)
	(segment
		(start 236.434122 -103.492046)
		(end 233.526584 -103.492046)
		(width 0.1651)
		(layer "F.Cu")
		(net "M_E_DQ<24>")
	)
	(segment
		(start 225.6282 -118.415562)
		(end 225.6282 -125.73)
		(width 0.1651)
		(layer "F.Cu")
		(net "M_E_DQ<24>")
	)
	(segment
		(start 226.191318 -110.827312)
		(end 225.6282 -112.186466)
		(width 0.1651)
		(layer "F.Cu")
		(net "M_E_DQ<24>")
	)
	(segment
		(start 226.0854 -114.122962)
		(end 225.9203 -114.288062)
		(width 0.1651)
		(layer "F.Cu")
		(net "M_E_DQ<24>")
	)
	(segment
		(start 225.990912 -118.250462)
		(end 225.7933 -118.250462)
		(width 0.1651)
		(layer "F.Cu")
		(net "M_E_DQ<24>")
	)
	(via
		(at 225.8568 -125.9586)
		(size 0.508)
		(drill 0.254)
		(layers "F.Cu" "B.Cu")
		(net "M_E_DQ<24>")
	)
	(via
		(at 226.822 -145.415)
		(size 0.508)
		(drill 0.254)
		(layers "F.Cu" "B.Cu")
		(net "M_E_DQ<24>")
	)
	(via
		(at 226.149916 -141.213078)
		(size 0.508)
		(drill 0.254)
		(layers "F.Cu" "B.Cu")
		(net "M_E_DQ<24>")
	)
	(segment
		(start 226.149916 -142.476982)
		(end 226.149916 -141.213078)
		(width 0.1651)
		(layer "B.Cu")
		(net "M_E_DQ<24>")
	)
	(segment
		(start 226.150424 -142.477236)
		(end 226.149916 -142.476982)
		(width 0.1651)
		(layer "B.Cu")
		(net "M_E_DQ<24>")
	)
	(segment
		(start 225.716846 -141.646148)
		(end 225.716846 -144.60601)
		(width 0.14224)
		(layer "In4.Cu")
		(net "M_E_DQ<24>")
	)
	(segment
		(start 225.785934 -140.849096)
		(end 226.149916 -141.213078)
		(width 0.14224)
		(layer "In4.Cu")
		(net "M_E_DQ<24>")
	)
	(segment
		(start 226.568 -136.670034)
		(end 226.568 -138.8872)
		(width 0.14224)
		(layer "In4.Cu")
		(net "M_E_DQ<24>")
	)
	(segment
		(start 225.785934 -140.209778)
		(end 225.785934 -140.849096)
		(width 0.14224)
		(layer "In4.Cu")
		(net "M_E_DQ<24>")
	)
	(segment
		(start 226.636834 -136.263634)
		(end 226.636834 -136.6012)
		(width 0.14224)
		(layer "In4.Cu")
		(net "M_E_DQ<24>")
	)
	(segment
		(start 226.332034 -131.141978)
		(end 226.624134 -131.434078)
		(width 0.14224)
		(layer "In4.Cu")
		(net "M_E_DQ<24>")
	)
	(segment
		(start 226.149916 -141.213078)
		(end 225.716846 -141.646148)
		(width 0.14224)
		(layer "In4.Cu")
		(net "M_E_DQ<24>")
	)
	(segment
		(start 226.344734 -134.764018)
		(end 226.344734 -135.971534)
		(width 0.14224)
		(layer "In4.Cu")
		(net "M_E_DQ<24>")
	)
	(segment
		(start 226.624134 -134.484618)
		(end 226.344734 -134.764018)
		(width 0.14224)
		(layer "In4.Cu")
		(net "M_E_DQ<24>")
	)
	(segment
		(start 225.8568 -125.9586)
		(end 226.2886 -126.3904)
		(width 0.14224)
		(layer "In4.Cu")
		(net "M_E_DQ<24>")
	)
	(segment
		(start 226.674934 -129.158492)
		(end 226.674934 -129.719578)
		(width 0.14224)
		(layer "In4.Cu")
		(net "M_E_DQ<24>")
	)
	(segment
		(start 226.344734 -135.971534)
		(end 226.636834 -136.263634)
		(width 0.14224)
		(layer "In4.Cu")
		(net "M_E_DQ<24>")
	)
	(segment
		(start 225.716846 -144.60601)
		(end 226.525836 -145.415)
		(width 0.14224)
		(layer "In4.Cu")
		(net "M_E_DQ<24>")
	)
	(segment
		(start 226.332034 -130.062478)
		(end 226.332034 -131.141978)
		(width 0.14224)
		(layer "In4.Cu")
		(net "M_E_DQ<24>")
	)
	(segment
		(start 226.568 -131.907534)
		(end 226.568 -134.0866)
		(width 0.14224)
		(layer "In4.Cu")
		(net "M_E_DQ<24>")
	)
	(segment
		(start 226.624134 -131.434078)
		(end 226.624134 -131.8514)
		(width 0.14224)
		(layer "In4.Cu")
		(net "M_E_DQ<24>")
	)
	(segment
		(start 226.674934 -129.719578)
		(end 226.332034 -130.062478)
		(width 0.14224)
		(layer "In4.Cu")
		(net "M_E_DQ<24>")
	)
	(segment
		(start 226.624134 -131.8514)
		(end 226.568 -131.907534)
		(width 0.14224)
		(layer "In4.Cu")
		(net "M_E_DQ<24>")
	)
	(segment
		(start 226.568 -134.0866)
		(end 226.624134 -134.142734)
		(width 0.14224)
		(layer "In4.Cu")
		(net "M_E_DQ<24>")
	)
	(segment
		(start 226.636834 -139.358878)
		(end 225.785934 -140.209778)
		(width 0.14224)
		(layer "In4.Cu")
		(net "M_E_DQ<24>")
	)
	(segment
		(start 226.2886 -126.3904)
		(end 226.2886 -128.772158)
		(width 0.14224)
		(layer "In4.Cu")
		(net "M_E_DQ<24>")
	)
	(segment
		(start 226.2886 -128.772158)
		(end 226.674934 -129.158492)
		(width 0.14224)
		(layer "In4.Cu")
		(net "M_E_DQ<24>")
	)
	(segment
		(start 226.636834 -136.6012)
		(end 226.568 -136.670034)
		(width 0.14224)
		(layer "In4.Cu")
		(net "M_E_DQ<24>")
	)
	(segment
		(start 226.525836 -145.415)
		(end 226.822 -145.415)
		(width 0.14224)
		(layer "In4.Cu")
		(net "M_E_DQ<24>")
	)
	(segment
		(start 226.636834 -138.956034)
		(end 226.636834 -139.358878)
		(width 0.14224)
		(layer "In4.Cu")
		(net "M_E_DQ<24>")
	)
	(segment
		(start 226.568 -138.8872)
		(end 226.636834 -138.956034)
		(width 0.14224)
		(layer "In4.Cu")
		(net "M_E_DQ<24>")
	)
	(segment
		(start 226.624134 -134.142734)
		(end 226.624134 -134.484618)
		(width 0.14224)
		(layer "In4.Cu")
		(net "M_E_DQ<24>")
	)
	(segment
		(start 221.04985 -142.677642)
		(end 221.04985 -143.941546)
		(width 0.1651)
		(layer "F.Cu")
		(net "M_E_DQ<23>")
	)
	(segment
		(start 239.617758 -100.167186)
		(end 239.046258 -100.167186)
		(width 0.1651)
		(layer "F.Cu")
		(net "M_E_DQ<23>")
	)
	(segment
		(start 221.050358 -142.6718)
		(end 221.04985 -142.677642)
		(width 0.1651)
		(layer "F.Cu")
		(net "M_E_DQ<23>")
	)
	(via
		(at 221.899734 -139.932156)
		(size 0.508)
		(drill 0.254)
		(layers "F.Cu" "B.Cu")
		(net "M_E_DQ<23>")
	)
	(via
		(at 221.04985 -143.941546)
		(size 0.508)
		(drill 0.254)
		(layers "F.Cu" "B.Cu")
		(net "M_E_DQ<23>")
	)
	(via
		(at 239.046258 -100.167186)
		(size 0.508)
		(drill 0.254)
		(layers "F.Cu" "B.Cu")
		(net "M_E_DQ<23>")
	)
	(segment
		(start 221.899734 -137.877296)
		(end 221.899734 -139.932156)
		(width 0.1651)
		(layer "B.Cu")
		(net "M_E_DQ<23>")
	)
	(segment
		(start 221.900496 -137.877296)
		(end 221.899734 -137.877296)
		(width 0.1651)
		(layer "B.Cu")
		(net "M_E_DQ<23>")
	)
	(segment
		(start 222.241618 -139.590272)
		(end 221.899734 -139.932156)
		(width 0.14224)
		(layer "In4.Cu")
		(net "M_E_DQ<23>")
	)
	(segment
		(start 222.6818 -128.905)
		(end 222.25254 -129.33426)
		(width 0.14224)
		(layer "In4.Cu")
		(net "M_E_DQ<23>")
	)
	(segment
		(start 230.817166 -117.880892)
		(end 225.917252 -122.780806)
		(width 0.14224)
		(layer "In4.Cu")
		(net "M_E_DQ<23>")
	)
	(segment
		(start 221.21114 -142.878048)
		(end 221.21114 -143.151352)
		(width 0.14224)
		(layer "In4.Cu")
		(net "M_E_DQ<23>")
	)
	(segment
		(start 222.25254 -136.167114)
		(end 222.25254 -136.57834)
		(width 0.14224)
		(layer "In4.Cu")
		(net "M_E_DQ<23>")
	)
	(segment
		(start 222.25254 -129.859278)
		(end 222.48114 -130.087878)
		(width 0.14224)
		(layer "In4.Cu")
		(net "M_E_DQ<23>")
	)
	(segment
		(start 222.3262 -134.0866)
		(end 222.27794 -134.13486)
		(width 0.14224)
		(layer "In4.Cu")
		(net "M_E_DQ<23>")
	)
	(segment
		(start 225.917252 -122.780806)
		(end 224.532952 -122.780806)
		(width 0.14224)
		(layer "In4.Cu")
		(net "M_E_DQ<23>")
	)
	(segment
		(start 232.0036 -114.818922)
		(end 228.778054 -118.044468)
		(width 0.14224)
		(layer "In4.Cu")
		(net "M_E_DQ<23>")
	)
	(segment
		(start 222.27794 -134.13486)
		(end 222.27794 -134.568438)
		(width 0.14224)
		(layer "In4.Cu")
		(net "M_E_DQ<23>")
	)
	(segment
		(start 221.21114 -141.785848)
		(end 221.21114 -142.059152)
		(width 0.14224)
		(layer "In4.Cu")
		(net "M_E_DQ<23>")
	)
	(segment
		(start 239.564418 -101.44252)
		(end 239.5474 -101.471222)
		(width 0.0889)
		(layer "In4.Cu")
		(net "M_E_DQ<23>")
	)
	(segment
		(start 222.48114 -130.087878)
		(end 222.48114 -131.188206)
		(width 0.14224)
		(layer "In4.Cu")
		(net "M_E_DQ<23>")
	)
	(segment
		(start 221.449138 -140.790168)
		(end 221.493588 -140.834618)
		(width 0.14224)
		(layer "In4.Cu")
		(net "M_E_DQ<23>")
	)
	(segment
		(start 236.870494 -104.088184)
		(end 236.870494 -105.487216)
		(width 0.14224)
		(layer "In4.Cu")
		(net "M_E_DQ<23>")
	)
	(segment
		(start 222.3262 -138.8364)
		(end 222.25254 -138.91006)
		(width 0.14224)
		(layer "In4.Cu")
		(net "M_E_DQ<23>")
	)
	(segment
		(start 221.468188 -142.3162)
		(end 221.468188 -142.621)
		(width 0.14224)
		(layer "In4.Cu")
		(net "M_E_DQ<23>")
	)
	(segment
		(start 239.499394 -101.557074)
		(end 238.620554 -102.435914)
		(width 0.0889)
		(layer "In4.Cu")
		(net "M_E_DQ<23>")
	)
	(segment
		(start 238.620554 -102.435914)
		(end 237.861856 -102.435914)
		(width 0.0889)
		(layer "In4.Cu")
		(net "M_E_DQ<23>")
	)
	(segment
		(start 221.322138 -143.941546)
		(end 221.04985 -143.941546)
		(width 0.14224)
		(layer "In4.Cu")
		(net "M_E_DQ<23>")
	)
	(segment
		(start 222.25254 -138.91006)
		(end 222.25254 -139.590272)
		(width 0.14224)
		(layer "In4.Cu")
		(net "M_E_DQ<23>")
	)
	(segment
		(start 221.899734 -139.932156)
		(end 221.877382 -139.932156)
		(width 0.14224)
		(layer "In4.Cu")
		(net "M_E_DQ<23>")
	)
	(segment
		(start 229.02799 -118.513352)
		(end 229.246938 -118.513352)
		(width 0.14224)
		(layer "In4.Cu")
		(net "M_E_DQ<23>")
	)
	(segment
		(start 222.3262 -136.652)
		(end 222.3262 -138.8364)
		(width 0.14224)
		(layer "In4.Cu")
		(net "M_E_DQ<23>")
	)
	(segment
		(start 222.25254 -139.590272)
		(end 222.241618 -139.590272)
		(width 0.14224)
		(layer "In4.Cu")
		(net "M_E_DQ<23>")
	)
	(segment
		(start 222.27794 -134.568438)
		(end 222.421704 -134.712202)
		(width 0.14224)
		(layer "In4.Cu")
		(net "M_E_DQ<23>")
	)
	(segment
		(start 230.348282 -117.412008)
		(end 230.56723 -117.412008)
		(width 0.14224)
		(layer "In4.Cu")
		(net "M_E_DQ<23>")
	)
	(segment
		(start 230.56723 -117.412008)
		(end 230.817166 -117.661944)
		(width 0.14224)
		(layer "In4.Cu")
		(net "M_E_DQ<23>")
	)
	(segment
		(start 222.25254 -136.57834)
		(end 222.3262 -136.652)
		(width 0.14224)
		(layer "In4.Cu")
		(net "M_E_DQ<23>")
	)
	(segment
		(start 221.493588 -141.5034)
		(end 221.21114 -141.785848)
		(width 0.14224)
		(layer "In4.Cu")
		(net "M_E_DQ<23>")
	)
	(segment
		(start 239.5474 -101.471222)
		(end 239.499394 -101.557074)
		(width 0.0889)
		(layer "In4.Cu")
		(net "M_E_DQ<23>")
	)
	(segment
		(start 230.817166 -117.661944)
		(end 230.817166 -117.880892)
		(width 0.14224)
		(layer "In4.Cu")
		(net "M_E_DQ<23>")
	)
	(segment
		(start 228.778054 -118.044468)
		(end 228.778054 -118.263416)
		(width 0.14224)
		(layer "In4.Cu")
		(net "M_E_DQ<23>")
	)
	(segment
		(start 222.20174 -131.467606)
		(end 222.20174 -131.953)
		(width 0.14224)
		(layer "In4.Cu")
		(net "M_E_DQ<23>")
	)
	(segment
		(start 229.246938 -118.513352)
		(end 230.348282 -117.412008)
		(width 0.14224)
		(layer "In4.Cu")
		(net "M_E_DQ<23>")
	)
	(segment
		(start 224.532952 -122.780806)
		(end 222.6818 -124.631958)
		(width 0.14224)
		(layer "In4.Cu")
		(net "M_E_DQ<23>")
	)
	(segment
		(start 236.870494 -105.487216)
		(end 232.0036 -110.35411)
		(width 0.14224)
		(layer "In4.Cu")
		(net "M_E_DQ<23>")
	)
	(segment
		(start 222.421704 -135.99795)
		(end 222.25254 -136.167114)
		(width 0.14224)
		(layer "In4.Cu")
		(net "M_E_DQ<23>")
	)
	(segment
		(start 221.21114 -143.151352)
		(end 221.499938 -143.44015)
		(width 0.14224)
		(layer "In4.Cu")
		(net "M_E_DQ<23>")
	)
	(segment
		(start 222.48114 -131.188206)
		(end 222.20174 -131.467606)
		(width 0.14224)
		(layer "In4.Cu")
		(net "M_E_DQ<23>")
	)
	(segment
		(start 237.861856 -102.435914)
		(end 236.870494 -103.427276)
		(width 0.0889)
		(layer "In4.Cu")
		(net "M_E_DQ<23>")
	)
	(segment
		(start 222.25254 -129.33426)
		(end 222.25254 -129.859278)
		(width 0.14224)
		(layer "In4.Cu")
		(net "M_E_DQ<23>")
	)
	(segment
		(start 222.3262 -132.07746)
		(end 222.3262 -134.0866)
		(width 0.14224)
		(layer "In4.Cu")
		(net "M_E_DQ<23>")
	)
	(segment
		(start 221.449138 -140.3604)
		(end 221.449138 -140.790168)
		(width 0.14224)
		(layer "In4.Cu")
		(net "M_E_DQ<23>")
	)
	(segment
		(start 221.21114 -142.059152)
		(end 221.468188 -142.3162)
		(width 0.14224)
		(layer "In4.Cu")
		(net "M_E_DQ<23>")
	)
	(segment
		(start 221.499938 -143.44015)
		(end 221.499938 -143.763746)
		(width 0.14224)
		(layer "In4.Cu")
		(net "M_E_DQ<23>")
	)
	(segment
		(start 221.499938 -143.763746)
		(end 221.322138 -143.941546)
		(width 0.14224)
		(layer "In4.Cu")
		(net "M_E_DQ<23>")
	)
	(segment
		(start 222.20174 -131.953)
		(end 222.3262 -132.07746)
		(width 0.14224)
		(layer "In4.Cu")
		(net "M_E_DQ<23>")
	)
	(segment
		(start 222.6818 -124.631958)
		(end 222.6818 -128.905)
		(width 0.14224)
		(layer "In4.Cu")
		(net "M_E_DQ<23>")
	)
	(segment
		(start 228.778054 -118.263416)
		(end 229.02799 -118.513352)
		(width 0.14224)
		(layer "In4.Cu")
		(net "M_E_DQ<23>")
	)
	(segment
		(start 221.468188 -142.621)
		(end 221.21114 -142.878048)
		(width 0.14224)
		(layer "In4.Cu")
		(net "M_E_DQ<23>")
	)
	(segment
		(start 232.0036 -110.35411)
		(end 232.0036 -114.818922)
		(width 0.14224)
		(layer "In4.Cu")
		(net "M_E_DQ<23>")
	)
	(segment
		(start 236.870494 -103.427276)
		(end 236.870494 -104.088184)
		(width 0.0889)
		(layer "In4.Cu")
		(net "M_E_DQ<23>")
	)
	(segment
		(start 221.493588 -140.834618)
		(end 221.493588 -141.5034)
		(width 0.14224)
		(layer "In4.Cu")
		(net "M_E_DQ<23>")
	)
	(segment
		(start 239.541304 -100.833428)
		(end 239.558068 -100.862638)
		(width 0.0889)
		(layer "In4.Cu")
		(net "M_E_DQ<23>")
	)
	(segment
		(start 221.877382 -139.932156)
		(end 221.449138 -140.3604)
		(width 0.14224)
		(layer "In4.Cu")
		(net "M_E_DQ<23>")
	)
	(segment
		(start 222.421704 -134.712202)
		(end 222.421704 -135.99795)
		(width 0.14224)
		(layer "In4.Cu")
		(net "M_E_DQ<23>")
	)
	(arc
		(start 239.366044 -100.589334)
		(mid 239.459875 -100.706928)
		(end 239.541304 -100.833428)
		(width 0.0889)
		(layer "In4.Cu")
		(net "M_E_DQ<23>")
	)
	(arc
		(start 239.046258 -100.167186)
		(mid 239.198134 -100.384333)
		(end 239.366044 -100.589334)
		(width 0.0889)
		(layer "In4.Cu")
		(net "M_E_DQ<23>")
	)
	(arc
		(start 239.558068 -100.862638)
		(mid 239.63729 -101.151756)
		(end 239.564418 -101.44252)
		(width 0.0889)
		(layer "In4.Cu")
		(net "M_E_DQ<23>")
	)
	(segment
		(start 221.899988 -147.27174)
		(end 221.899988 -146.304)
		(width 0.1651)
		(layer "F.Cu")
		(net "M_E_DQ<22>")
	)
	(segment
		(start 222.032068 -146.17192)
		(end 222.032068 -145.95348)
		(width 0.1651)
		(layer "F.Cu")
		(net "M_E_DQ<22>")
	)
	(segment
		(start 221.899988 -145.8214)
		(end 221.899988 -145.516854)
		(width 0.1651)
		(layer "F.Cu")
		(net "M_E_DQ<22>")
	)
	(segment
		(start 221.899988 -145.516854)
		(end 221.899734 -145.5166)
		(width 0.1651)
		(layer "F.Cu")
		(net "M_E_DQ<22>")
	)
	(segment
		(start 222.032068 -145.95348)
		(end 221.899988 -145.8214)
		(width 0.1651)
		(layer "F.Cu")
		(net "M_E_DQ<22>")
	)
	(segment
		(start 239.617758 -98.18624)
		(end 239.046258 -98.18624)
		(width 0.1651)
		(layer "F.Cu")
		(net "M_E_DQ<22>")
	)
	(segment
		(start 221.900496 -147.27174)
		(end 221.899988 -147.27174)
		(width 0.1651)
		(layer "F.Cu")
		(net "M_E_DQ<22>")
	)
	(segment
		(start 221.899988 -146.304)
		(end 222.032068 -146.17192)
		(width 0.1651)
		(layer "F.Cu")
		(net "M_E_DQ<22>")
	)
	(via
		(at 239.046258 -98.18624)
		(size 0.508)
		(drill 0.254)
		(layers "F.Cu" "B.Cu")
		(net "M_E_DQ<22>")
	)
	(via
		(at 221.04985 -141.214094)
		(size 0.508)
		(drill 0.254)
		(layers "F.Cu" "B.Cu")
		(net "M_E_DQ<22>")
	)
	(via
		(at 221.899734 -145.5166)
		(size 0.508)
		(drill 0.254)
		(layers "F.Cu" "B.Cu")
		(net "M_E_DQ<22>")
	)
	(segment
		(start 221.050358 -142.477236)
		(end 221.04985 -142.476982)
		(width 0.1651)
		(layer "B.Cu")
		(net "M_E_DQ<22>")
	)
	(segment
		(start 221.04985 -142.476982)
		(end 221.04985 -141.214094)
		(width 0.1651)
		(layer "B.Cu")
		(net "M_E_DQ<22>")
	)
	(segment
		(start 221.4626 -138.8872)
		(end 221.61754 -139.04214)
		(width 0.14224)
		(layer "In4.Cu")
		(net "M_E_DQ<22>")
	)
	(segment
		(start 238.694722 -99.368102)
		(end 238.699548 -99.376738)
		(width 0.0889)
		(layer "In4.Cu")
		(net "M_E_DQ<22>")
	)
	(segment
		(start 221.61754 -139.333478)
		(end 220.88094 -140.070078)
		(width 0.14224)
		(layer "In4.Cu")
		(net "M_E_DQ<22>")
	)
	(segment
		(start 224.202752 -122.145806)
		(end 222.0468 -124.301758)
		(width 0.14224)
		(layer "In4.Cu")
		(net "M_E_DQ<22>")
	)
	(segment
		(start 239.346486 -101.440996)
		(end 238.54156 -102.245922)
		(width 0.0889)
		(layer "In4.Cu")
		(net "M_E_DQ<22>")
	)
	(segment
		(start 220.61678 -141.646148)
		(end 221.04985 -141.213078)
		(width 0.14224)
		(layer "In4.Cu")
		(net "M_E_DQ<22>")
	)
	(segment
		(start 222.0468 -128.752854)
		(end 221.61754 -129.182114)
		(width 0.14224)
		(layer "In4.Cu")
		(net "M_E_DQ<22>")
	)
	(segment
		(start 221.41434 -131.307078)
		(end 221.56674 -131.459478)
		(width 0.14224)
		(layer "In4.Cu")
		(net "M_E_DQ<22>")
	)
	(segment
		(start 222.0468 -124.301758)
		(end 222.0468 -128.752854)
		(width 0.14224)
		(layer "In4.Cu")
		(net "M_E_DQ<22>")
	)
	(segment
		(start 231.3686 -110.077504)
		(end 231.3686 -114.68608)
		(width 0.14224)
		(layer "In4.Cu")
		(net "M_E_DQ<22>")
	)
	(segment
		(start 239.046258 -98.18624)
		(end 238.716312 -98.947986)
		(width 0.0889)
		(layer "In4.Cu")
		(net "M_E_DQ<22>")
	)
	(segment
		(start 231.3686 -114.68608)
		(end 228.258116 -117.796564)
		(width 0.14224)
		(layer "In4.Cu")
		(net "M_E_DQ<22>")
	)
	(segment
		(start 221.61754 -136.5504)
		(end 221.4626 -136.70534)
		(width 0.14224)
		(layer "In4.Cu")
		(net "M_E_DQ<22>")
	)
	(segment
		(start 228.258116 -117.796564)
		(end 228.258116 -119.538242)
		(width 0.14224)
		(layer "In4.Cu")
		(net "M_E_DQ<22>")
	)
	(segment
		(start 236.617764 -103.683054)
		(end 236.373924 -103.683054)
		(width 0.0889)
		(layer "In4.Cu")
		(net "M_E_DQ<22>")
	)
	(segment
		(start 236.680502 -103.620316)
		(end 236.617764 -103.683054)
		(width 0.0889)
		(layer "In4.Cu")
		(net "M_E_DQ<22>")
	)
	(segment
		(start 221.61754 -136.256268)
		(end 221.61754 -136.5504)
		(width 0.14224)
		(layer "In4.Cu")
		(net "M_E_DQ<22>")
	)
	(segment
		(start 221.4626 -134.0612)
		(end 221.56674 -134.16534)
		(width 0.14224)
		(layer "In4.Cu")
		(net "M_E_DQ<22>")
	)
	(segment
		(start 221.56674 -131.459478)
		(end 221.56674 -131.9784)
		(width 0.14224)
		(layer "In4.Cu")
		(net "M_E_DQ<22>")
	)
	(segment
		(start 221.899734 -145.5166)
		(end 220.61678 -144.233646)
		(width 0.14224)
		(layer "In4.Cu")
		(net "M_E_DQ<22>")
	)
	(segment
		(start 236.373924 -103.683054)
		(end 236.1692 -103.887778)
		(width 0.14224)
		(layer "In4.Cu")
		(net "M_E_DQ<22>")
	)
	(segment
		(start 221.4626 -132.08254)
		(end 221.4626 -134.0612)
		(width 0.14224)
		(layer "In4.Cu")
		(net "M_E_DQ<22>")
	)
	(segment
		(start 221.61754 -129.182114)
		(end 221.61754 -129.859278)
		(width 0.14224)
		(layer "In4.Cu")
		(net "M_E_DQ<22>")
	)
	(segment
		(start 221.56674 -134.16534)
		(end 221.56674 -134.517638)
		(width 0.14224)
		(layer "In4.Cu")
		(net "M_E_DQ<22>")
	)
	(segment
		(start 225.650552 -122.145806)
		(end 224.202752 -122.145806)
		(width 0.14224)
		(layer "In4.Cu")
		(net "M_E_DQ<22>")
	)
	(segment
		(start 239.397794 -101.349302)
		(end 239.346486 -101.440996)
		(width 0.0889)
		(layer "In4.Cu")
		(net "M_E_DQ<22>")
	)
	(segment
		(start 221.56674 -134.517638)
		(end 221.294198 -134.79018)
		(width 0.14224)
		(layer "In4.Cu")
		(net "M_E_DQ<22>")
	)
	(segment
		(start 228.258116 -119.538242)
		(end 225.650552 -122.145806)
		(width 0.14224)
		(layer "In4.Cu")
		(net "M_E_DQ<22>")
	)
	(segment
		(start 237.783116 -102.245922)
		(end 236.680502 -103.348536)
		(width 0.0889)
		(layer "In4.Cu")
		(net "M_E_DQ<22>")
	)
	(segment
		(start 238.705898 -99.95662)
		(end 238.699548 -99.967288)
		(width 0.0889)
		(layer "In4.Cu")
		(net "M_E_DQ<22>")
	)
	(segment
		(start 220.61678 -144.233646)
		(end 220.61678 -141.646148)
		(width 0.14224)
		(layer "In4.Cu")
		(net "M_E_DQ<22>")
	)
	(segment
		(start 221.61754 -129.859278)
		(end 221.41434 -130.062478)
		(width 0.14224)
		(layer "In4.Cu")
		(net "M_E_DQ<22>")
	)
	(segment
		(start 220.88094 -140.070078)
		(end 220.88094 -141.044168)
		(width 0.14224)
		(layer "In4.Cu")
		(net "M_E_DQ<22>")
	)
	(segment
		(start 221.4626 -136.70534)
		(end 221.4626 -138.8872)
		(width 0.14224)
		(layer "In4.Cu")
		(net "M_E_DQ<22>")
	)
	(segment
		(start 221.56674 -131.9784)
		(end 221.4626 -132.08254)
		(width 0.14224)
		(layer "In4.Cu")
		(net "M_E_DQ<22>")
	)
	(segment
		(start 238.716312 -98.947986)
		(end 238.699548 -98.976688)
		(width 0.0889)
		(layer "In4.Cu")
		(net "M_E_DQ<22>")
	)
	(segment
		(start 236.1692 -103.887778)
		(end 236.1692 -105.276904)
		(width 0.14224)
		(layer "In4.Cu")
		(net "M_E_DQ<22>")
	)
	(segment
		(start 221.61754 -139.04214)
		(end 221.61754 -139.333478)
		(width 0.14224)
		(layer "In4.Cu")
		(net "M_E_DQ<22>")
	)
	(segment
		(start 236.680502 -103.348536)
		(end 236.680502 -103.620316)
		(width 0.0889)
		(layer "In4.Cu")
		(net "M_E_DQ<22>")
	)
	(segment
		(start 221.41434 -130.062478)
		(end 221.41434 -131.307078)
		(width 0.14224)
		(layer "In4.Cu")
		(net "M_E_DQ<22>")
	)
	(segment
		(start 221.04985 -141.213078)
		(end 221.04985 -141.214094)
		(width 0.14224)
		(layer "In4.Cu")
		(net "M_E_DQ<22>")
	)
	(segment
		(start 221.294198 -135.932926)
		(end 221.61754 -136.256268)
		(width 0.14224)
		(layer "In4.Cu")
		(net "M_E_DQ<22>")
	)
	(segment
		(start 238.54156 -102.245922)
		(end 237.783116 -102.245922)
		(width 0.0889)
		(layer "In4.Cu")
		(net "M_E_DQ<22>")
	)
	(segment
		(start 220.88094 -141.044168)
		(end 221.04985 -141.213078)
		(width 0.14224)
		(layer "In4.Cu")
		(net "M_E_DQ<22>")
	)
	(segment
		(start 221.294198 -134.79018)
		(end 221.294198 -135.932926)
		(width 0.14224)
		(layer "In4.Cu")
		(net "M_E_DQ<22>")
	)
	(segment
		(start 236.1692 -105.276904)
		(end 231.3686 -110.077504)
		(width 0.14224)
		(layer "In4.Cu")
		(net "M_E_DQ<22>")
	)
	(arc
		(start 238.699548 -99.376738)
		(mid 238.77877 -99.665856)
		(end 238.705898 -99.95662)
		(width 0.0889)
		(layer "In4.Cu")
		(net "M_E_DQ<22>")
	)
	(arc
		(start 238.699548 -98.976688)
		(mid 238.646078 -99.171751)
		(end 238.694722 -99.368102)
		(width 0.0889)
		(layer "In4.Cu")
		(net "M_E_DQ<22>")
	)
	(arc
		(start 239.392968 -100.957888)
		(mid 239.446438 -101.152951)
		(end 239.397794 -101.349302)
		(width 0.0889)
		(layer "In4.Cu")
		(net "M_E_DQ<22>")
	)
	(arc
		(start 238.699548 -99.967288)
		(mid 238.668537 -100.299452)
		(end 238.899954 -100.539804)
		(width 0.0889)
		(layer "In4.Cu")
		(net "M_E_DQ<22>")
	)
	(arc
		(start 238.899954 -100.539804)
		(mid 239.181166 -100.707917)
		(end 239.392968 -100.957888)
		(width 0.0889)
		(layer "In4.Cu")
		(net "M_E_DQ<22>")
	)
	(segment
		(start 215.0999 -142.677642)
		(end 215.0999 -143.941546)
		(width 0.1651)
		(layer "F.Cu")
		(net "M_E_DQ<21>")
	)
	(segment
		(start 237.042198 -99.67214)
		(end 236.470698 -99.67214)
		(width 0.1651)
		(layer "F.Cu")
		(net "M_E_DQ<21>")
	)
	(segment
		(start 215.100408 -142.6718)
		(end 215.0999 -142.677642)
		(width 0.1651)
		(layer "F.Cu")
		(net "M_E_DQ<21>")
	)
	(via
		(at 236.470698 -99.67214)
		(size 0.508)
		(drill 0.254)
		(layers "F.Cu" "B.Cu")
		(net "M_E_DQ<21>")
	)
	(via
		(at 215.873584 -139.932156)
		(size 0.508)
		(drill 0.254)
		(layers "F.Cu" "B.Cu")
		(net "M_E_DQ<21>")
	)
	(via
		(at 215.0999 -143.941546)
		(size 0.508)
		(drill 0.254)
		(layers "F.Cu" "B.Cu")
		(net "M_E_DQ<21>")
	)
	(segment
		(start 215.949784 -137.877296)
		(end 215.949784 -139.855956)
		(width 0.1651)
		(layer "B.Cu")
		(net "M_E_DQ<21>")
	)
	(segment
		(start 215.950292 -137.877296)
		(end 215.949784 -137.877296)
		(width 0.1651)
		(layer "B.Cu")
		(net "M_E_DQ<21>")
	)
	(segment
		(start 215.949784 -139.855956)
		(end 215.873584 -139.932156)
		(width 0.1651)
		(layer "B.Cu")
		(net "M_E_DQ<21>")
	)
	(segment
		(start 232.111804 -101.679248)
		(end 229.591362 -104.19969)
		(width 0.14224)
		(layer "In4.Cu")
		(net "M_E_DQ<21>")
	)
	(segment
		(start 229.591362 -104.49814)
		(end 229.746302 -104.65308)
		(width 0.14224)
		(layer "In4.Cu")
		(net "M_E_DQ<21>")
	)
	(segment
		(start 228.706934 -107.021122)
		(end 228.487986 -107.021122)
		(width 0.14224)
		(layer "In4.Cu")
		(net "M_E_DQ<21>")
	)
	(segment
		(start 216.41054 -134.797038)
		(end 216.41054 -135.853424)
		(width 0.14224)
		(layer "In4.Cu")
		(net "M_E_DQ<21>")
	)
	(segment
		(start 232.111804 -101.354636)
		(end 232.111804 -101.679248)
		(width 0.0889)
		(layer "In4.Cu")
		(net "M_E_DQ<21>")
	)
	(segment
		(start 232.70845 -100.75799)
		(end 232.111804 -101.354636)
		(width 0.0889)
		(layer "In4.Cu")
		(net "M_E_DQ<21>")
	)
	(segment
		(start 216.3826 -131.97586)
		(end 216.3826 -134.0104)
		(width 0.14224)
		(layer "In4.Cu")
		(net "M_E_DQ<21>")
	)
	(segment
		(start 235.648754 -99.76739)
		(end 235.594144 -99.76739)
		(width 0.0889)
		(layer "In4.Cu")
		(net "M_E_DQ<21>")
	)
	(segment
		(start 228.487986 -107.021122)
		(end 228.132132 -107.376976)
		(width 0.14224)
		(layer "In4.Cu")
		(net "M_E_DQ<21>")
	)
	(segment
		(start 230.150416 -104.65308)
		(end 230.305356 -104.80802)
		(width 0.14224)
		(layer "In4.Cu")
		(net "M_E_DQ<21>")
	)
	(segment
		(start 229.281482 -106.226864)
		(end 229.281482 -106.445812)
		(width 0.14224)
		(layer "In4.Cu")
		(net "M_E_DQ<21>")
	)
	(segment
		(start 216.3826 -136.64946)
		(end 216.3826 -138.7602)
		(width 0.14224)
		(layer "In4.Cu")
		(net "M_E_DQ<21>")
	)
	(segment
		(start 215.422988 -140.3604)
		(end 215.422988 -140.9192)
		(width 0.14224)
		(layer "In4.Cu")
		(net "M_E_DQ<21>")
	)
	(segment
		(start 215.873584 -139.932156)
		(end 215.851232 -139.932156)
		(width 0.14224)
		(layer "In4.Cu")
		(net "M_E_DQ<21>")
	)
	(segment
		(start 236.470698 -99.67214)
		(end 235.648754 -99.76739)
		(width 0.0889)
		(layer "In4.Cu")
		(net "M_E_DQ<21>")
	)
	(segment
		(start 216.3826 -138.7602)
		(end 216.0524 -139.0904)
		(width 0.14224)
		(layer "In4.Cu")
		(net "M_E_DQ<21>")
	)
	(segment
		(start 230.150416 -105.31602)
		(end 229.746302 -105.31602)
		(width 0.14224)
		(layer "In4.Cu")
		(net "M_E_DQ<21>")
	)
	(segment
		(start 215.524588 -143.789146)
		(end 215.372188 -143.941546)
		(width 0.14224)
		(layer "In4.Cu")
		(net "M_E_DQ<21>")
	)
	(segment
		(start 216.28354 -134.670038)
		(end 216.41054 -134.797038)
		(width 0.14224)
		(layer "In4.Cu")
		(net "M_E_DQ<21>")
	)
	(segment
		(start 229.03688 -107.131866)
		(end 228.817932 -107.131866)
		(width 0.14224)
		(layer "In4.Cu")
		(net "M_E_DQ<21>")
	)
	(segment
		(start 230.305356 -104.80802)
		(end 230.305356 -105.16108)
		(width 0.14224)
		(layer "In4.Cu")
		(net "M_E_DQ<21>")
	)
	(segment
		(start 216.0524 -139.0904)
		(end 216.0524 -139.75334)
		(width 0.14224)
		(layer "In4.Cu")
		(net "M_E_DQ<21>")
	)
	(segment
		(start 229.392734 -106.776012)
		(end 229.03688 -107.131866)
		(width 0.14224)
		(layer "In4.Cu")
		(net "M_E_DQ<21>")
	)
	(segment
		(start 217.8304 -127.6096)
		(end 216.2302 -129.2098)
		(width 0.14224)
		(layer "In4.Cu")
		(net "M_E_DQ<21>")
	)
	(segment
		(start 229.591362 -105.47096)
		(end 229.591362 -105.916984)
		(width 0.14224)
		(layer "In4.Cu")
		(net "M_E_DQ<21>")
	)
	(segment
		(start 229.281482 -106.445812)
		(end 229.392734 -106.557064)
		(width 0.14224)
		(layer "In4.Cu")
		(net "M_E_DQ<21>")
	)
	(segment
		(start 228.132132 -107.376976)
		(end 228.132132 -107.59567)
		(width 0.14224)
		(layer "In4.Cu")
		(net "M_E_DQ<21>")
	)
	(segment
		(start 215.549988 -141.0462)
		(end 215.549988 -141.528546)
		(width 0.14224)
		(layer "In4.Cu")
		(net "M_E_DQ<21>")
	)
	(segment
		(start 215.524588 -143.561054)
		(end 215.524588 -143.789146)
		(width 0.14224)
		(layer "In4.Cu")
		(net "M_E_DQ<21>")
	)
	(segment
		(start 216.2302 -129.742946)
		(end 216.4842 -129.996946)
		(width 0.14224)
		(layer "In4.Cu")
		(net "M_E_DQ<21>")
	)
	(segment
		(start 227.5332 -113.174526)
		(end 217.8304 -122.877326)
		(width 0.14224)
		(layer "In4.Cu")
		(net "M_E_DQ<21>")
	)
	(segment
		(start 227.5332 -108.635546)
		(end 227.5332 -113.174526)
		(width 0.14224)
		(layer "In4.Cu")
		(net "M_E_DQ<21>")
	)
	(segment
		(start 216.4842 -131.089146)
		(end 216.20607 -131.367276)
		(width 0.14224)
		(layer "In4.Cu")
		(net "M_E_DQ<21>")
	)
	(segment
		(start 215.549988 -141.528546)
		(end 215.26119 -141.817344)
		(width 0.14224)
		(layer "In4.Cu")
		(net "M_E_DQ<21>")
	)
	(segment
		(start 215.499188 -142.747746)
		(end 215.26119 -142.985744)
		(width 0.14224)
		(layer "In4.Cu")
		(net "M_E_DQ<21>")
	)
	(segment
		(start 217.8304 -122.877326)
		(end 217.8304 -127.6096)
		(width 0.14224)
		(layer "In4.Cu")
		(net "M_E_DQ<21>")
	)
	(segment
		(start 215.26119 -142.154656)
		(end 215.499188 -142.392654)
		(width 0.14224)
		(layer "In4.Cu")
		(net "M_E_DQ<21>")
	)
	(segment
		(start 216.28354 -134.10946)
		(end 216.28354 -134.670038)
		(width 0.14224)
		(layer "In4.Cu")
		(net "M_E_DQ<21>")
	)
	(segment
		(start 229.591362 -105.916984)
		(end 229.281482 -106.226864)
		(width 0.14224)
		(layer "In4.Cu")
		(net "M_E_DQ<21>")
	)
	(segment
		(start 230.305356 -105.16108)
		(end 230.150416 -105.31602)
		(width 0.14224)
		(layer "In4.Cu")
		(net "M_E_DQ<21>")
	)
	(segment
		(start 216.3826 -134.0104)
		(end 216.28354 -134.10946)
		(width 0.14224)
		(layer "In4.Cu")
		(net "M_E_DQ<21>")
	)
	(segment
		(start 234.771438 -100.26269)
		(end 234.735624 -100.26269)
		(width 0.0889)
		(layer "In4.Cu")
		(net "M_E_DQ<21>")
	)
	(segment
		(start 215.26119 -143.297656)
		(end 215.524588 -143.561054)
		(width 0.14224)
		(layer "In4.Cu")
		(net "M_E_DQ<21>")
	)
	(segment
		(start 216.25814 -136.525)
		(end 216.3826 -136.64946)
		(width 0.14224)
		(layer "In4.Cu")
		(net "M_E_DQ<21>")
	)
	(segment
		(start 215.422988 -140.9192)
		(end 215.549988 -141.0462)
		(width 0.14224)
		(layer "In4.Cu")
		(net "M_E_DQ<21>")
	)
	(segment
		(start 228.132132 -107.59567)
		(end 228.24313 -107.706668)
		(width 0.14224)
		(layer "In4.Cu")
		(net "M_E_DQ<21>")
	)
	(segment
		(start 216.4842 -129.996946)
		(end 216.4842 -131.089146)
		(width 0.14224)
		(layer "In4.Cu")
		(net "M_E_DQ<21>")
	)
	(segment
		(start 228.24313 -107.706668)
		(end 228.24313 -107.925616)
		(width 0.14224)
		(layer "In4.Cu")
		(net "M_E_DQ<21>")
	)
	(segment
		(start 229.746302 -104.65308)
		(end 230.150416 -104.65308)
		(width 0.14224)
		(layer "In4.Cu")
		(net "M_E_DQ<21>")
	)
	(segment
		(start 216.41054 -135.853424)
		(end 216.25814 -136.005824)
		(width 0.14224)
		(layer "In4.Cu")
		(net "M_E_DQ<21>")
	)
	(segment
		(start 215.26119 -141.817344)
		(end 215.26119 -142.154656)
		(width 0.14224)
		(layer "In4.Cu")
		(net "M_E_DQ<21>")
	)
	(segment
		(start 216.20607 -131.367276)
		(end 216.20607 -131.79933)
		(width 0.14224)
		(layer "In4.Cu")
		(net "M_E_DQ<21>")
	)
	(segment
		(start 215.26119 -142.985744)
		(end 215.26119 -143.297656)
		(width 0.14224)
		(layer "In4.Cu")
		(net "M_E_DQ<21>")
	)
	(segment
		(start 233.908092 -100.75799)
		(end 232.70845 -100.75799)
		(width 0.0889)
		(layer "In4.Cu")
		(net "M_E_DQ<21>")
	)
	(segment
		(start 215.851232 -139.932156)
		(end 215.422988 -140.3604)
		(width 0.14224)
		(layer "In4.Cu")
		(net "M_E_DQ<21>")
	)
	(segment
		(start 228.817932 -107.131866)
		(end 228.706934 -107.021122)
		(width 0.14224)
		(layer "In4.Cu")
		(net "M_E_DQ<21>")
	)
	(segment
		(start 228.24313 -107.925616)
		(end 227.5332 -108.635546)
		(width 0.14224)
		(layer "In4.Cu")
		(net "M_E_DQ<21>")
	)
	(segment
		(start 216.2302 -129.2098)
		(end 216.2302 -129.742946)
		(width 0.14224)
		(layer "In4.Cu")
		(net "M_E_DQ<21>")
	)
	(segment
		(start 216.20607 -131.79933)
		(end 216.3826 -131.97586)
		(width 0.14224)
		(layer "In4.Cu")
		(net "M_E_DQ<21>")
	)
	(segment
		(start 229.746302 -105.31602)
		(end 229.591362 -105.47096)
		(width 0.14224)
		(layer "In4.Cu")
		(net "M_E_DQ<21>")
	)
	(segment
		(start 229.591362 -104.19969)
		(end 229.591362 -104.49814)
		(width 0.14224)
		(layer "In4.Cu")
		(net "M_E_DQ<21>")
	)
	(segment
		(start 215.372188 -143.941546)
		(end 215.0999 -143.941546)
		(width 0.14224)
		(layer "In4.Cu")
		(net "M_E_DQ<21>")
	)
	(segment
		(start 229.392734 -106.557064)
		(end 229.392734 -106.776012)
		(width 0.14224)
		(layer "In4.Cu")
		(net "M_E_DQ<21>")
	)
	(segment
		(start 216.25814 -136.005824)
		(end 216.25814 -136.525)
		(width 0.14224)
		(layer "In4.Cu")
		(net "M_E_DQ<21>")
	)
	(segment
		(start 216.0524 -139.75334)
		(end 215.873584 -139.932156)
		(width 0.14224)
		(layer "In4.Cu")
		(net "M_E_DQ<21>")
	)
	(segment
		(start 215.499188 -142.392654)
		(end 215.499188 -142.747746)
		(width 0.14224)
		(layer "In4.Cu")
		(net "M_E_DQ<21>")
	)
	(arc
		(start 234.406948 -100.462588)
		(mid 234.196235 -100.675667)
		(end 233.908092 -100.75799)
		(width 0.0889)
		(layer "In4.Cu")
		(net "M_E_DQ<21>")
	)
	(arc
		(start 235.265468 -99.967288)
		(mid 235.05686 -100.17922)
		(end 234.771438 -100.26269)
		(width 0.0889)
		(layer "In4.Cu")
		(net "M_E_DQ<21>")
	)
	(arc
		(start 234.735624 -100.26269)
		(mid 234.545695 -100.32056)
		(end 234.406948 -100.462588)
		(width 0.0889)
		(layer "In4.Cu")
		(net "M_E_DQ<21>")
	)
	(arc
		(start 235.594144 -99.76739)
		(mid 235.404215 -99.82526)
		(end 235.265468 -99.967288)
		(width 0.0889)
		(layer "In4.Cu")
		(net "M_E_DQ<21>")
	)
	(segment
		(start 237.042198 -98.681286)
		(end 236.470698 -98.681286)
		(width 0.1651)
		(layer "F.Cu")
		(net "M_E_DQ<20>")
	)
	(segment
		(start 215.950292 -147.27174)
		(end 215.949784 -147.27174)
		(width 0.1651)
		(layer "F.Cu")
		(net "M_E_DQ<20>")
	)
	(segment
		(start 215.949784 -145.946368)
		(end 215.85174 -145.415)
		(width 0.1651)
		(layer "F.Cu")
		(net "M_E_DQ<20>")
	)
	(segment
		(start 215.949784 -147.27174)
		(end 215.949784 -145.946368)
		(width 0.1651)
		(layer "F.Cu")
		(net "M_E_DQ<20>")
	)
	(via
		(at 236.470698 -98.681286)
		(size 0.508)
		(drill 0.254)
		(layers "F.Cu" "B.Cu")
		(net "M_E_DQ<20>")
	)
	(via
		(at 215.85174 -145.415)
		(size 0.508)
		(drill 0.254)
		(layers "F.Cu" "B.Cu")
		(net "M_E_DQ<20>")
	)
	(via
		(at 215.0999 -141.213078)
		(size 0.508)
		(drill 0.254)
		(layers "F.Cu" "B.Cu")
		(net "M_E_DQ<20>")
	)
	(segment
		(start 215.0999 -142.476982)
		(end 215.0999 -141.213078)
		(width 0.1651)
		(layer "B.Cu")
		(net "M_E_DQ<20>")
	)
	(segment
		(start 215.100408 -142.477236)
		(end 215.0999 -142.476982)
		(width 0.1651)
		(layer "B.Cu")
		(net "M_E_DQ<20>")
	)
	(segment
		(start 226.8982 -112.911382)
		(end 217.1954 -122.614182)
		(width 0.14224)
		(layer "In4.Cu")
		(net "M_E_DQ<20>")
	)
	(segment
		(start 215.588596 -129.766822)
		(end 215.386412 -129.969006)
		(width 0.14224)
		(layer "In4.Cu")
		(net "M_E_DQ<20>")
	)
	(segment
		(start 215.331548 -134.756398)
		(end 215.331548 -135.926576)
		(width 0.14224)
		(layer "In4.Cu")
		(net "M_E_DQ<20>")
	)
	(segment
		(start 235.630212 -99.576636)
		(end 235.594398 -99.576636)
		(width 0.0889)
		(layer "In4.Cu")
		(net "M_E_DQ<20>")
	)
	(segment
		(start 215.386412 -131.205478)
		(end 215.59774 -131.416806)
		(width 0.14224)
		(layer "In4.Cu")
		(net "M_E_DQ<20>")
	)
	(segment
		(start 215.386412 -129.969006)
		(end 215.386412 -131.205478)
		(width 0.14224)
		(layer "In4.Cu")
		(net "M_E_DQ<20>")
	)
	(segment
		(start 228.9302 -103.962708)
		(end 228.9302 -105.892346)
		(width 0.14224)
		(layer "In4.Cu")
		(net "M_E_DQ<20>")
	)
	(segment
		(start 214.961978 -141.075156)
		(end 215.0999 -141.213078)
		(width 0.14224)
		(layer "In4.Cu")
		(net "M_E_DQ<20>")
	)
	(segment
		(start 234.771692 -100.071936)
		(end 234.732068 -100.071936)
		(width 0.0889)
		(layer "In4.Cu")
		(net "M_E_DQ<20>")
	)
	(segment
		(start 215.59774 -131.416806)
		(end 215.59774 -134.490206)
		(width 0.14224)
		(layer "In4.Cu")
		(net "M_E_DQ<20>")
	)
	(segment
		(start 231.637332 -101.255576)
		(end 228.9302 -103.962708)
		(width 0.14224)
		(layer "In4.Cu")
		(net "M_E_DQ<20>")
	)
	(segment
		(start 214.66683 -144.17929)
		(end 214.824818 -144.337278)
		(width 0.14224)
		(layer "In4.Cu")
		(net "M_E_DQ<20>")
	)
	(segment
		(start 215.588596 -129.089404)
		(end 215.588596 -129.766822)
		(width 0.14224)
		(layer "In4.Cu")
		(net "M_E_DQ<20>")
	)
	(segment
		(start 215.59774 -134.490206)
		(end 215.331548 -134.756398)
		(width 0.14224)
		(layer "In4.Cu")
		(net "M_E_DQ<20>")
	)
	(segment
		(start 233.906314 -100.567236)
		(end 232.629202 -100.567236)
		(width 0.0889)
		(layer "In4.Cu")
		(net "M_E_DQ<20>")
	)
	(segment
		(start 215.58504 -139.304014)
		(end 214.961978 -139.927076)
		(width 0.14224)
		(layer "In4.Cu")
		(net "M_E_DQ<20>")
	)
	(segment
		(start 235.975398 -99.348036)
		(end 235.958888 -99.376738)
		(width 0.0889)
		(layer "In4.Cu")
		(net "M_E_DQ<20>")
	)
	(segment
		(start 217.1954 -127.4826)
		(end 215.588596 -129.089404)
		(width 0.14224)
		(layer "In4.Cu")
		(net "M_E_DQ<20>")
	)
	(segment
		(start 214.66683 -141.646148)
		(end 214.66683 -144.17929)
		(width 0.14224)
		(layer "In4.Cu")
		(net "M_E_DQ<20>")
	)
	(segment
		(start 231.940862 -101.255576)
		(end 231.637332 -101.255576)
		(width 0.0889)
		(layer "In4.Cu")
		(net "M_E_DQ<20>")
	)
	(segment
		(start 215.600788 -145.415)
		(end 215.85174 -145.415)
		(width 0.14224)
		(layer "In4.Cu")
		(net "M_E_DQ<20>")
	)
	(segment
		(start 236.470698 -98.681286)
		(end 235.975398 -99.348036)
		(width 0.0889)
		(layer "In4.Cu")
		(net "M_E_DQ<20>")
	)
	(segment
		(start 214.824818 -144.63903)
		(end 215.600788 -145.415)
		(width 0.14224)
		(layer "In4.Cu")
		(net "M_E_DQ<20>")
	)
	(segment
		(start 215.331548 -135.926576)
		(end 215.58504 -136.180068)
		(width 0.14224)
		(layer "In4.Cu")
		(net "M_E_DQ<20>")
	)
	(segment
		(start 214.961978 -139.927076)
		(end 214.961978 -141.075156)
		(width 0.14224)
		(layer "In4.Cu")
		(net "M_E_DQ<20>")
	)
	(segment
		(start 232.629202 -100.567236)
		(end 231.940862 -101.255576)
		(width 0.0889)
		(layer "In4.Cu")
		(net "M_E_DQ<20>")
	)
	(segment
		(start 226.8982 -107.924346)
		(end 226.8982 -112.911382)
		(width 0.14224)
		(layer "In4.Cu")
		(net "M_E_DQ<20>")
	)
	(segment
		(start 215.0999 -141.213078)
		(end 214.66683 -141.646148)
		(width 0.14224)
		(layer "In4.Cu")
		(net "M_E_DQ<20>")
	)
	(segment
		(start 215.58504 -136.180068)
		(end 215.58504 -139.304014)
		(width 0.14224)
		(layer "In4.Cu")
		(net "M_E_DQ<20>")
	)
	(segment
		(start 217.1954 -122.614182)
		(end 217.1954 -127.4826)
		(width 0.14224)
		(layer "In4.Cu")
		(net "M_E_DQ<20>")
	)
	(segment
		(start 228.9302 -105.892346)
		(end 226.8982 -107.924346)
		(width 0.14224)
		(layer "In4.Cu")
		(net "M_E_DQ<20>")
	)
	(segment
		(start 214.824818 -144.337278)
		(end 214.824818 -144.63903)
		(width 0.14224)
		(layer "In4.Cu")
		(net "M_E_DQ<20>")
	)
	(arc
		(start 235.958888 -99.376738)
		(mid 235.820144 -99.518771)
		(end 235.630212 -99.576636)
		(width 0.0889)
		(layer "In4.Cu")
		(net "M_E_DQ<20>")
	)
	(arc
		(start 235.594398 -99.576636)
		(mid 235.308974 -99.660103)
		(end 235.100368 -99.872038)
		(width 0.0889)
		(layer "In4.Cu")
		(net "M_E_DQ<20>")
	)
	(arc
		(start 234.241848 -100.367084)
		(mid 234.100165 -100.510888)
		(end 233.906314 -100.567236)
		(width 0.0889)
		(layer "In4.Cu")
		(net "M_E_DQ<20>")
	)
	(arc
		(start 235.100368 -99.872038)
		(mid 234.961624 -100.014071)
		(end 234.771692 -100.071936)
		(width 0.0889)
		(layer "In4.Cu")
		(net "M_E_DQ<20>")
	)
	(arc
		(start 234.732068 -100.071936)
		(mid 234.448851 -100.156217)
		(end 234.241848 -100.367084)
		(width 0.0889)
		(layer "In4.Cu")
		(net "M_E_DQ<20>")
	)
	(segment
		(start 237.042198 -83.822286)
		(end 236.470698 -83.822286)
		(width 0.1651)
		(layer "F.Cu")
		(net "M_E_DQ<1>")
	)
	(segment
		(start 198.100442 -142.6718)
		(end 198.099934 -142.677642)
		(width 0.1651)
		(layer "F.Cu")
		(net "M_E_DQ<1>")
	)
	(segment
		(start 198.099934 -142.677642)
		(end 198.099934 -143.941546)
		(width 0.1651)
		(layer "F.Cu")
		(net "M_E_DQ<1>")
	)
	(via
		(at 198.099934 -143.941546)
		(size 0.508)
		(drill 0.254)
		(layers "F.Cu" "B.Cu")
		(net "M_E_DQ<1>")
	)
	(via
		(at 236.470698 -83.822286)
		(size 0.508)
		(drill 0.254)
		(layers "F.Cu" "B.Cu")
		(net "M_E_DQ<1>")
	)
	(via
		(at 198.772018 -139.932156)
		(size 0.508)
		(drill 0.254)
		(layers "F.Cu" "B.Cu")
		(net "M_E_DQ<1>")
	)
	(segment
		(start 198.950326 -137.877296)
		(end 198.949818 -137.877296)
		(width 0.1651)
		(layer "B.Cu")
		(net "M_E_DQ<1>")
	)
	(segment
		(start 198.949818 -137.877296)
		(end 198.949818 -139.251182)
		(width 0.1651)
		(layer "B.Cu")
		(net "M_E_DQ<1>")
	)
	(segment
		(start 198.949818 -139.251182)
		(end 198.772018 -139.428982)
		(width 0.1651)
		(layer "B.Cu")
		(net "M_E_DQ<1>")
	)
	(segment
		(start 198.772018 -139.428982)
		(end 198.772018 -139.932156)
		(width 0.1651)
		(layer "B.Cu")
		(net "M_E_DQ<1>")
	)
	(segment
		(start 200.718166 -115.513358)
		(end 200.068434 -114.863626)
		(width 0.14224)
		(layer "In4.Cu")
		(net "M_E_DQ<1>")
	)
	(segment
		(start 199.08774 -133.385052)
		(end 199.53986 -133.385052)
		(width 0.14224)
		(layer "In4.Cu")
		(net "M_E_DQ<1>")
	)
	(segment
		(start 199.798178 -116.433346)
		(end 199.148446 -115.783614)
		(width 0.14224)
		(layer "In4.Cu")
		(net "M_E_DQ<1>")
	)
	(segment
		(start 198.261224 -143.244824)
		(end 198.501 -143.4846)
		(width 0.14224)
		(layer "In4.Cu")
		(net "M_E_DQ<1>")
	)
	(segment
		(start 198.947786 -115.78336)
		(end 198.7804 -115.950746)
		(width 0.14224)
		(layer "In4.Cu")
		(net "M_E_DQ<1>")
	)
	(segment
		(start 199.39 -136.709404)
		(end 199.39 -138.7602)
		(width 0.14224)
		(layer "In4.Cu")
		(net "M_E_DQ<1>")
	)
	(segment
		(start 236.470698 -83.822286)
		(end 235.975398 -83.156298)
		(width 0.0889)
		(layer "In4.Cu")
		(net "M_E_DQ<1>")
	)
	(segment
		(start 233.058208 -83.42249)
		(end 232.833926 -83.42249)
		(width 0.0889)
		(layer "In4.Cu")
		(net "M_E_DQ<1>")
	)
	(segment
		(start 228.665278 -83.78952)
		(end 219.871544 -92.583254)
		(width 0.14224)
		(layer "In4.Cu")
		(net "M_E_DQ<1>")
	)
	(segment
		(start 199.608694 -115.122452)
		(end 199.608694 -115.32362)
		(width 0.14224)
		(layer "In4.Cu")
		(net "M_E_DQ<1>")
	)
	(segment
		(start 198.321422 -140.3604)
		(end 198.321422 -140.790168)
		(width 0.14224)
		(layer "In4.Cu")
		(net "M_E_DQ<1>")
	)
	(segment
		(start 231.89438 -82.92719)
		(end 231.258364 -83.563206)
		(width 0.0889)
		(layer "In4.Cu")
		(net "M_E_DQ<1>")
	)
	(segment
		(start 198.772018 -139.932156)
		(end 198.749666 -139.932156)
		(width 0.14224)
		(layer "In4.Cu")
		(net "M_E_DQ<1>")
	)
	(segment
		(start 230.839264 -83.78952)
		(end 228.665278 -83.78952)
		(width 0.14224)
		(layer "In4.Cu")
		(net "M_E_DQ<1>")
	)
	(segment
		(start 198.4756 -142.7226)
		(end 198.261224 -142.936976)
		(width 0.14224)
		(layer "In4.Cu")
		(net "M_E_DQ<1>")
	)
	(segment
		(start 201.168 -114.452146)
		(end 201.168 -115.264692)
		(width 0.14224)
		(layer "In4.Cu")
		(net "M_E_DQ<1>")
	)
	(segment
		(start 231.065578 -83.563206)
		(end 230.839264 -83.78952)
		(width 0.0889)
		(layer "In4.Cu")
		(net "M_E_DQ<1>")
	)
	(segment
		(start 198.321422 -140.790168)
		(end 198.5518 -141.020546)
		(width 0.14224)
		(layer "In4.Cu")
		(net "M_E_DQ<1>")
	)
	(segment
		(start 207.238346 -108.3818)
		(end 201.168 -114.452146)
		(width 0.14224)
		(layer "In4.Cu")
		(net "M_E_DQ<1>")
	)
	(segment
		(start 198.7804 -115.950746)
		(end 198.7804 -128.853184)
		(width 0.14224)
		(layer "In4.Cu")
		(net "M_E_DQ<1>")
	)
	(segment
		(start 200.258172 -116.17452)
		(end 199.999346 -116.433346)
		(width 0.14224)
		(layer "In4.Cu")
		(net "M_E_DQ<1>")
	)
	(segment
		(start 198.7804 -128.853184)
		(end 199.256396 -129.32918)
		(width 0.14224)
		(layer "In4.Cu")
		(net "M_E_DQ<1>")
	)
	(segment
		(start 235.623354 -82.92719)
		(end 235.590588 -82.92719)
		(width 0.0889)
		(layer "In4.Cu")
		(net "M_E_DQ<1>")
	)
	(segment
		(start 199.256396 -129.32918)
		(end 199.256396 -131.743196)
		(width 0.14224)
		(layer "In4.Cu")
		(net "M_E_DQ<1>")
	)
	(segment
		(start 232.48493 -83.124294)
		(end 232.376218 -83.00466)
		(width 0.0889)
		(layer "In4.Cu")
		(net "M_E_DQ<1>")
	)
	(segment
		(start 219.871544 -92.583254)
		(end 219.871544 -96.891602)
		(width 0.14224)
		(layer "In4.Cu")
		(net "M_E_DQ<1>")
	)
	(segment
		(start 200.919334 -115.513358)
		(end 200.718166 -115.513358)
		(width 0.14224)
		(layer "In4.Cu")
		(net "M_E_DQ<1>")
	)
	(segment
		(start 199.6948 -132.1816)
		(end 199.6948 -132.417312)
		(width 0.14224)
		(layer "In4.Cu")
		(net "M_E_DQ<1>")
	)
	(segment
		(start 232.376218 -83.00466)
		(end 232.298748 -82.92719)
		(width 0.0889)
		(layer "In4.Cu")
		(net "M_E_DQ<1>")
	)
	(segment
		(start 199.03694 -132.572252)
		(end 198.9074 -132.701792)
		(width 0.14224)
		(layer "In4.Cu")
		(net "M_E_DQ<1>")
	)
	(segment
		(start 199.867774 -114.863372)
		(end 199.608694 -115.122452)
		(width 0.14224)
		(layer "In4.Cu")
		(net "M_E_DQ<1>")
	)
	(segment
		(start 232.298748 -82.92719)
		(end 231.89438 -82.92719)
		(width 0.0889)
		(layer "In4.Cu")
		(net "M_E_DQ<1>")
	)
	(segment
		(start 198.9074 -132.701792)
		(end 198.9074 -133.204712)
		(width 0.14224)
		(layer "In4.Cu")
		(net "M_E_DQ<1>")
	)
	(segment
		(start 199.256396 -136.5758)
		(end 199.39 -136.709404)
		(width 0.14224)
		(layer "In4.Cu")
		(net "M_E_DQ<1>")
	)
	(segment
		(start 198.5518 -141.020546)
		(end 198.5518 -141.425168)
		(width 0.14224)
		(layer "In4.Cu")
		(net "M_E_DQ<1>")
	)
	(segment
		(start 219.871544 -96.891602)
		(end 208.381346 -108.3818)
		(width 0.14224)
		(layer "In4.Cu")
		(net "M_E_DQ<1>")
	)
	(segment
		(start 199.256396 -139.358878)
		(end 198.772018 -139.843256)
		(width 0.14224)
		(layer "In4.Cu")
		(net "M_E_DQ<1>")
	)
	(segment
		(start 198.261224 -142.076424)
		(end 198.4756 -142.2908)
		(width 0.14224)
		(layer "In4.Cu")
		(net "M_E_DQ<1>")
	)
	(segment
		(start 198.501 -143.7894)
		(end 198.348854 -143.941546)
		(width 0.14224)
		(layer "In4.Cu")
		(net "M_E_DQ<1>")
	)
	(segment
		(start 233.916728 -82.92719)
		(end 233.883962 -82.92719)
		(width 0.0889)
		(layer "In4.Cu")
		(net "M_E_DQ<1>")
	)
	(segment
		(start 199.39 -138.7602)
		(end 199.256396 -138.893804)
		(width 0.14224)
		(layer "In4.Cu")
		(net "M_E_DQ<1>")
	)
	(segment
		(start 199.256396 -131.743196)
		(end 199.6948 -132.1816)
		(width 0.14224)
		(layer "In4.Cu")
		(net "M_E_DQ<1>")
	)
	(segment
		(start 199.6948 -133.8326)
		(end 199.256396 -134.271004)
		(width 0.14224)
		(layer "In4.Cu")
		(net "M_E_DQ<1>")
	)
	(segment
		(start 199.6948 -132.417312)
		(end 199.53986 -132.572252)
		(width 0.14224)
		(layer "In4.Cu")
		(net "M_E_DQ<1>")
	)
	(segment
		(start 200.068434 -114.863626)
		(end 199.867774 -114.863372)
		(width 0.14224)
		(layer "In4.Cu")
		(net "M_E_DQ<1>")
	)
	(segment
		(start 199.6948 -133.539992)
		(end 199.6948 -133.8326)
		(width 0.14224)
		(layer "In4.Cu")
		(net "M_E_DQ<1>")
	)
	(segment
		(start 198.4756 -142.2908)
		(end 198.4756 -142.7226)
		(width 0.14224)
		(layer "In4.Cu")
		(net "M_E_DQ<1>")
	)
	(segment
		(start 231.258364 -83.563206)
		(end 231.065578 -83.563206)
		(width 0.0889)
		(layer "In4.Cu")
		(net "M_E_DQ<1>")
	)
	(segment
		(start 198.261224 -141.715744)
		(end 198.261224 -142.076424)
		(width 0.14224)
		(layer "In4.Cu")
		(net "M_E_DQ<1>")
	)
	(segment
		(start 235.975398 -83.156298)
		(end 235.958888 -83.127342)
		(width 0.0889)
		(layer "In4.Cu")
		(net "M_E_DQ<1>")
	)
	(segment
		(start 201.168 -115.264692)
		(end 200.919334 -115.513358)
		(width 0.14224)
		(layer "In4.Cu")
		(net "M_E_DQ<1>")
	)
	(segment
		(start 199.999346 -116.433346)
		(end 199.798178 -116.433346)
		(width 0.14224)
		(layer "In4.Cu")
		(net "M_E_DQ<1>")
	)
	(segment
		(start 199.256396 -138.893804)
		(end 199.256396 -139.358878)
		(width 0.14224)
		(layer "In4.Cu")
		(net "M_E_DQ<1>")
	)
	(segment
		(start 199.53986 -132.572252)
		(end 199.03694 -132.572252)
		(width 0.14224)
		(layer "In4.Cu")
		(net "M_E_DQ<1>")
	)
	(segment
		(start 198.772018 -139.843256)
		(end 198.772018 -139.932156)
		(width 0.14224)
		(layer "In4.Cu")
		(net "M_E_DQ<1>")
	)
	(segment
		(start 198.348854 -143.941546)
		(end 198.099934 -143.941546)
		(width 0.14224)
		(layer "In4.Cu")
		(net "M_E_DQ<1>")
	)
	(segment
		(start 200.258426 -115.973352)
		(end 200.258172 -116.17452)
		(width 0.14224)
		(layer "In4.Cu")
		(net "M_E_DQ<1>")
	)
	(segment
		(start 199.256396 -134.271004)
		(end 199.256396 -136.5758)
		(width 0.14224)
		(layer "In4.Cu")
		(net "M_E_DQ<1>")
	)
	(segment
		(start 198.501 -143.4846)
		(end 198.501 -143.7894)
		(width 0.14224)
		(layer "In4.Cu")
		(net "M_E_DQ<1>")
	)
	(segment
		(start 199.148446 -115.783614)
		(end 198.947786 -115.78336)
		(width 0.14224)
		(layer "In4.Cu")
		(net "M_E_DQ<1>")
	)
	(segment
		(start 198.5518 -141.425168)
		(end 198.261224 -141.715744)
		(width 0.14224)
		(layer "In4.Cu")
		(net "M_E_DQ<1>")
	)
	(segment
		(start 198.749666 -139.932156)
		(end 198.321422 -140.3604)
		(width 0.14224)
		(layer "In4.Cu")
		(net "M_E_DQ<1>")
	)
	(segment
		(start 198.261224 -142.936976)
		(end 198.261224 -143.244824)
		(width 0.14224)
		(layer "In4.Cu")
		(net "M_E_DQ<1>")
	)
	(segment
		(start 199.53986 -133.385052)
		(end 199.6948 -133.539992)
		(width 0.14224)
		(layer "In4.Cu")
		(net "M_E_DQ<1>")
	)
	(segment
		(start 198.9074 -133.204712)
		(end 199.08774 -133.385052)
		(width 0.14224)
		(layer "In4.Cu")
		(net "M_E_DQ<1>")
	)
	(segment
		(start 208.381346 -108.3818)
		(end 207.238346 -108.3818)
		(width 0.14224)
		(layer "In4.Cu")
		(net "M_E_DQ<1>")
	)
	(segment
		(start 199.608694 -115.32362)
		(end 200.258426 -115.973352)
		(width 0.14224)
		(layer "In4.Cu")
		(net "M_E_DQ<1>")
	)
	(arc
		(start 235.590588 -82.92719)
		(mid 235.307371 -82.842909)
		(end 235.100368 -82.632042)
		(width 0.0889)
		(layer "In4.Cu")
		(net "M_E_DQ<1>")
	)
	(arc
		(start 234.406948 -82.632042)
		(mid 234.199944 -82.842906)
		(end 233.916728 -82.92719)
		(width 0.0889)
		(layer "In4.Cu")
		(net "M_E_DQ<1>")
	)
	(arc
		(start 232.833926 -83.42249)
		(mid 232.631028 -83.30663)
		(end 232.48493 -83.124294)
		(width 0.0889)
		(layer "In4.Cu")
		(net "M_E_DQ<1>")
	)
	(arc
		(start 233.548428 -83.127342)
		(mid 233.341424 -83.338206)
		(end 233.058208 -83.42249)
		(width 0.0889)
		(layer "In4.Cu")
		(net "M_E_DQ<1>")
	)
	(arc
		(start 235.958888 -83.127342)
		(mid 235.817205 -82.983538)
		(end 235.623354 -82.92719)
		(width 0.0889)
		(layer "In4.Cu")
		(net "M_E_DQ<1>")
	)
	(arc
		(start 235.100368 -82.632042)
		(mid 234.753658 -82.431731)
		(end 234.406948 -82.632042)
		(width 0.0889)
		(layer "In4.Cu")
		(net "M_E_DQ<1>")
	)
	(arc
		(start 233.883962 -82.92719)
		(mid 233.690112 -82.98354)
		(end 233.548428 -83.127342)
		(width 0.0889)
		(layer "In4.Cu")
		(net "M_E_DQ<1>")
	)
	(segment
		(start 222.75038 -142.6718)
		(end 222.749872 -142.677642)
		(width 0.1651)
		(layer "F.Cu")
		(net "M_E_DQ<19>")
	)
	(segment
		(start 240.476278 -99.67214)
		(end 239.904778 -99.67214)
		(width 0.1651)
		(layer "F.Cu")
		(net "M_E_DQ<19>")
	)
	(segment
		(start 222.749872 -142.677642)
		(end 222.749872 -143.941546)
		(width 0.1651)
		(layer "F.Cu")
		(net "M_E_DQ<19>")
	)
	(via
		(at 239.904778 -99.67214)
		(size 0.508)
		(drill 0.254)
		(layers "F.Cu" "B.Cu")
		(net "M_E_DQ<19>")
	)
	(via
		(at 223.599756 -139.932156)
		(size 0.508)
		(drill 0.254)
		(layers "F.Cu" "B.Cu")
		(net "M_E_DQ<19>")
	)
	(via
		(at 222.749872 -143.941546)
		(size 0.508)
		(drill 0.254)
		(layers "F.Cu" "B.Cu")
		(net "M_E_DQ<19>")
	)
	(segment
		(start 223.600518 -137.877296)
		(end 223.600518 -139.931394)
		(width 0.1651)
		(layer "B.Cu")
		(net "M_E_DQ<19>")
	)
	(segment
		(start 223.600518 -139.931394)
		(end 223.599756 -139.932156)
		(width 0.1651)
		(layer "B.Cu")
		(net "M_E_DQ<19>")
	)
	(segment
		(start 223.19996 -143.44015)
		(end 223.19996 -143.763746)
		(width 0.14224)
		(layer "In4.Cu")
		(net "M_E_DQ<19>")
	)
	(segment
		(start 239.974374 -104.179624)
		(end 233.2736 -110.880398)
		(width 0.14224)
		(layer "In4.Cu")
		(net "M_E_DQ<19>")
	)
	(segment
		(start 240.576608 -102.540562)
		(end 239.974374 -103.142796)
		(width 0.0889)
		(layer "In4.Cu")
		(net "M_E_DQ<19>")
	)
	(segment
		(start 232.61066 -117.520466)
		(end 232.61066 -116.314982)
		(width 0.14224)
		(layer "In4.Cu")
		(net "M_E_DQ<19>")
	)
	(segment
		(start 224.028 -138.7856)
		(end 223.92894 -138.88466)
		(width 0.14224)
		(layer "In4.Cu")
		(net "M_E_DQ<19>")
	)
	(segment
		(start 227.60559 -122.870976)
		(end 228.026468 -123.291854)
		(width 0.14224)
		(layer "In4.Cu")
		(net "M_E_DQ<19>")
	)
	(segment
		(start 223.599756 -139.945364)
		(end 223.599756 -139.932156)
		(width 0.14224)
		(layer "In4.Cu")
		(net "M_E_DQ<19>")
	)
	(segment
		(start 224.18294 -135.98906)
		(end 223.92894 -136.24306)
		(width 0.14224)
		(layer "In4.Cu")
		(net "M_E_DQ<19>")
	)
	(segment
		(start 228.026468 -123.510802)
		(end 227.776532 -123.760738)
		(width 0.14224)
		(layer "In4.Cu")
		(net "M_E_DQ<19>")
	)
	(segment
		(start 223.96704 -134.581138)
		(end 224.18294 -134.797038)
		(width 0.14224)
		(layer "In4.Cu")
		(net "M_E_DQ<19>")
	)
	(segment
		(start 223.19361 -141.5034)
		(end 222.911162 -141.785848)
		(width 0.14224)
		(layer "In4.Cu")
		(net "M_E_DQ<19>")
	)
	(segment
		(start 224.10674 -130.113278)
		(end 224.10674 -131.268978)
		(width 0.14224)
		(layer "In4.Cu")
		(net "M_E_DQ<19>")
	)
	(segment
		(start 223.96704 -131.9022)
		(end 224.028 -131.96316)
		(width 0.14224)
		(layer "In4.Cu")
		(net "M_E_DQ<19>")
	)
	(segment
		(start 223.14916 -140.3604)
		(end 223.14916 -140.790168)
		(width 0.14224)
		(layer "In4.Cu")
		(net "M_E_DQ<19>")
	)
	(segment
		(start 240.576608 -101.64445)
		(end 240.576608 -102.540562)
		(width 0.0889)
		(layer "In4.Cu")
		(net "M_E_DQ<19>")
	)
	(segment
		(start 222.911162 -143.151352)
		(end 223.19996 -143.44015)
		(width 0.14224)
		(layer "In4.Cu")
		(net "M_E_DQ<19>")
	)
	(segment
		(start 231.94772 -116.314982)
		(end 231.94772 -118.309898)
		(width 0.14224)
		(layer "In4.Cu")
		(net "M_E_DQ<19>")
	)
	(segment
		(start 223.02216 -143.941546)
		(end 222.749872 -143.941546)
		(width 0.14224)
		(layer "In4.Cu")
		(net "M_E_DQ<19>")
	)
	(segment
		(start 228.026468 -123.291854)
		(end 228.026468 -123.510802)
		(width 0.14224)
		(layer "In4.Cu")
		(net "M_E_DQ<19>")
	)
	(segment
		(start 223.19361 -140.834618)
		(end 223.19361 -141.5034)
		(width 0.14224)
		(layer "In4.Cu")
		(net "M_E_DQ<19>")
	)
	(segment
		(start 224.028 -131.96316)
		(end 224.028 -134.0104)
		(width 0.14224)
		(layer "In4.Cu")
		(net "M_E_DQ<19>")
	)
	(segment
		(start 223.599756 -139.932156)
		(end 223.577404 -139.932156)
		(width 0.14224)
		(layer "In4.Cu")
		(net "M_E_DQ<19>")
	)
	(segment
		(start 239.904778 -99.67214)
		(end 240.400078 -100.338128)
		(width 0.0889)
		(layer "In4.Cu")
		(net "M_E_DQ<19>")
	)
	(segment
		(start 223.92894 -136.52754)
		(end 224.028 -136.6266)
		(width 0.14224)
		(layer "In4.Cu")
		(net "M_E_DQ<19>")
	)
	(segment
		(start 227.557584 -123.760738)
		(end 227.136706 -123.33986)
		(width 0.14224)
		(layer "In4.Cu")
		(net "M_E_DQ<19>")
	)
	(segment
		(start 223.92894 -136.24306)
		(end 223.92894 -136.52754)
		(width 0.14224)
		(layer "In4.Cu")
		(net "M_E_DQ<19>")
	)
	(segment
		(start 222.911162 -141.785848)
		(end 222.911162 -142.059152)
		(width 0.14224)
		(layer "In4.Cu")
		(net "M_E_DQ<19>")
	)
	(segment
		(start 233.2736 -117.520466)
		(end 233.11866 -117.675406)
		(width 0.14224)
		(layer "In4.Cu")
		(net "M_E_DQ<19>")
	)
	(segment
		(start 223.16821 -142.3162)
		(end 223.16821 -142.621)
		(width 0.14224)
		(layer "In4.Cu")
		(net "M_E_DQ<19>")
	)
	(segment
		(start 240.400078 -100.338128)
		(end 240.416588 -100.367084)
		(width 0.0889)
		(layer "In4.Cu")
		(net "M_E_DQ<19>")
	)
	(segment
		(start 223.577404 -139.932156)
		(end 223.14916 -140.3604)
		(width 0.14224)
		(layer "In4.Cu")
		(net "M_E_DQ<19>")
	)
	(segment
		(start 226.178618 -124.079)
		(end 224.917 -124.079)
		(width 0.14224)
		(layer "In4.Cu")
		(net "M_E_DQ<19>")
	)
	(segment
		(start 223.96704 -134.07136)
		(end 223.96704 -134.581138)
		(width 0.14224)
		(layer "In4.Cu")
		(net "M_E_DQ<19>")
	)
	(segment
		(start 232.7656 -117.675406)
		(end 232.61066 -117.520466)
		(width 0.14224)
		(layer "In4.Cu")
		(net "M_E_DQ<19>")
	)
	(segment
		(start 223.7994 -129.805938)
		(end 224.10674 -130.113278)
		(width 0.14224)
		(layer "In4.Cu")
		(net "M_E_DQ<19>")
	)
	(segment
		(start 240.411762 -101.349302)
		(end 240.576608 -101.64445)
		(width 0.0889)
		(layer "In4.Cu")
		(net "M_E_DQ<19>")
	)
	(segment
		(start 223.92894 -139.61618)
		(end 223.599756 -139.945364)
		(width 0.14224)
		(layer "In4.Cu")
		(net "M_E_DQ<19>")
	)
	(segment
		(start 233.11866 -117.675406)
		(end 232.7656 -117.675406)
		(width 0.14224)
		(layer "In4.Cu")
		(net "M_E_DQ<19>")
	)
	(segment
		(start 224.10674 -131.268978)
		(end 223.96704 -131.408678)
		(width 0.14224)
		(layer "In4.Cu")
		(net "M_E_DQ<19>")
	)
	(segment
		(start 224.028 -136.6266)
		(end 224.028 -138.7856)
		(width 0.14224)
		(layer "In4.Cu")
		(net "M_E_DQ<19>")
	)
	(segment
		(start 223.96704 -131.408678)
		(end 223.96704 -131.9022)
		(width 0.14224)
		(layer "In4.Cu")
		(net "M_E_DQ<19>")
	)
	(segment
		(start 239.974374 -103.445564)
		(end 239.974374 -104.179624)
		(width 0.14224)
		(layer "In4.Cu")
		(net "M_E_DQ<19>")
	)
	(segment
		(start 224.028 -134.0104)
		(end 223.96704 -134.07136)
		(width 0.14224)
		(layer "In4.Cu")
		(net "M_E_DQ<19>")
	)
	(segment
		(start 231.94772 -118.309898)
		(end 227.60559 -122.652028)
		(width 0.14224)
		(layer "In4.Cu")
		(net "M_E_DQ<19>")
	)
	(segment
		(start 223.14916 -140.790168)
		(end 223.19361 -140.834618)
		(width 0.14224)
		(layer "In4.Cu")
		(net "M_E_DQ<19>")
	)
	(segment
		(start 232.10266 -116.160042)
		(end 231.94772 -116.314982)
		(width 0.14224)
		(layer "In4.Cu")
		(net "M_E_DQ<19>")
	)
	(segment
		(start 226.917758 -123.33986)
		(end 226.178618 -124.079)
		(width 0.14224)
		(layer "In4.Cu")
		(net "M_E_DQ<19>")
	)
	(segment
		(start 223.92894 -138.88466)
		(end 223.92894 -139.61618)
		(width 0.14224)
		(layer "In4.Cu")
		(net "M_E_DQ<19>")
	)
	(segment
		(start 222.911162 -142.059152)
		(end 223.16821 -142.3162)
		(width 0.14224)
		(layer "In4.Cu")
		(net "M_E_DQ<19>")
	)
	(segment
		(start 224.18294 -134.797038)
		(end 224.18294 -135.98906)
		(width 0.14224)
		(layer "In4.Cu")
		(net "M_E_DQ<19>")
	)
	(segment
		(start 233.2736 -110.880398)
		(end 233.2736 -117.520466)
		(width 0.14224)
		(layer "In4.Cu")
		(net "M_E_DQ<19>")
	)
	(segment
		(start 222.911162 -142.878048)
		(end 222.911162 -143.151352)
		(width 0.14224)
		(layer "In4.Cu")
		(net "M_E_DQ<19>")
	)
	(segment
		(start 239.974374 -103.142796)
		(end 239.974374 -103.445564)
		(width 0.0889)
		(layer "In4.Cu")
		(net "M_E_DQ<19>")
	)
	(segment
		(start 223.16821 -142.621)
		(end 222.911162 -142.878048)
		(width 0.14224)
		(layer "In4.Cu")
		(net "M_E_DQ<19>")
	)
	(segment
		(start 223.7994 -125.1966)
		(end 223.7994 -129.805938)
		(width 0.14224)
		(layer "In4.Cu")
		(net "M_E_DQ<19>")
	)
	(segment
		(start 227.136706 -123.33986)
		(end 226.917758 -123.33986)
		(width 0.14224)
		(layer "In4.Cu")
		(net "M_E_DQ<19>")
	)
	(segment
		(start 224.917 -124.079)
		(end 223.7994 -125.1966)
		(width 0.14224)
		(layer "In4.Cu")
		(net "M_E_DQ<19>")
	)
	(segment
		(start 232.45572 -116.160042)
		(end 232.10266 -116.160042)
		(width 0.14224)
		(layer "In4.Cu")
		(net "M_E_DQ<19>")
	)
	(segment
		(start 232.61066 -116.314982)
		(end 232.45572 -116.160042)
		(width 0.14224)
		(layer "In4.Cu")
		(net "M_E_DQ<19>")
	)
	(segment
		(start 227.776532 -123.760738)
		(end 227.557584 -123.760738)
		(width 0.14224)
		(layer "In4.Cu")
		(net "M_E_DQ<19>")
	)
	(segment
		(start 227.60559 -122.652028)
		(end 227.60559 -122.870976)
		(width 0.14224)
		(layer "In4.Cu")
		(net "M_E_DQ<19>")
	)
	(segment
		(start 223.19996 -143.763746)
		(end 223.02216 -143.941546)
		(width 0.14224)
		(layer "In4.Cu")
		(net "M_E_DQ<19>")
	)
	(arc
		(start 240.416588 -100.367084)
		(mid 240.495719 -100.662486)
		(end 240.416588 -100.957888)
		(width 0.0889)
		(layer "In4.Cu")
		(net "M_E_DQ<19>")
	)
	(arc
		(start 240.416588 -100.957888)
		(mid 240.363118 -101.152951)
		(end 240.411762 -101.349302)
		(width 0.0889)
		(layer "In4.Cu")
		(net "M_E_DQ<19>")
	)
	(segment
		(start 223.599756 -146.280632)
		(end 223.731328 -146.14906)
		(width 0.1651)
		(layer "F.Cu")
		(net "M_E_DQ<18>")
	)
	(segment
		(start 223.599756 -147.27174)
		(end 223.599756 -146.280632)
		(width 0.1651)
		(layer "F.Cu")
		(net "M_E_DQ<18>")
	)
	(segment
		(start 223.731328 -145.92554)
		(end 223.599756 -145.793968)
		(width 0.1651)
		(layer "F.Cu")
		(net "M_E_DQ<18>")
	)
	(segment
		(start 223.731328 -146.14906)
		(end 223.731328 -145.92554)
		(width 0.1651)
		(layer "F.Cu")
		(net "M_E_DQ<18>")
	)
	(segment
		(start 240.476278 -98.681286)
		(end 239.904778 -98.681286)
		(width 0.1651)
		(layer "F.Cu")
		(net "M_E_DQ<18>")
	)
	(segment
		(start 223.599756 -145.793968)
		(end 223.599756 -145.5166)
		(width 0.1651)
		(layer "F.Cu")
		(net "M_E_DQ<18>")
	)
	(segment
		(start 223.600518 -147.27174)
		(end 223.599756 -147.27174)
		(width 0.1651)
		(layer "F.Cu")
		(net "M_E_DQ<18>")
	)
	(via
		(at 222.749872 -141.213078)
		(size 0.508)
		(drill 0.254)
		(layers "F.Cu" "B.Cu")
		(net "M_E_DQ<18>")
	)
	(via
		(at 239.904778 -98.681286)
		(size 0.508)
		(drill 0.254)
		(layers "F.Cu" "B.Cu")
		(net "M_E_DQ<18>")
	)
	(via
		(at 223.599756 -145.5166)
		(size 0.508)
		(drill 0.254)
		(layers "F.Cu" "B.Cu")
		(net "M_E_DQ<18>")
	)
	(segment
		(start 222.749872 -142.476982)
		(end 222.749872 -141.213078)
		(width 0.1651)
		(layer "B.Cu")
		(net "M_E_DQ<18>")
	)
	(segment
		(start 222.75038 -142.477236)
		(end 222.749872 -142.476982)
		(width 0.1651)
		(layer "B.Cu")
		(net "M_E_DQ<18>")
	)
	(segment
		(start 223.31934 -131.523486)
		(end 223.31934 -131.9276)
		(width 0.14224)
		(layer "In4.Cu")
		(net "M_E_DQ<18>")
	)
	(segment
		(start 240.245138 -101.44252)
		(end 240.261902 -101.470968)
		(width 0.0889)
		(layer "In4.Cu")
		(net "M_E_DQ<18>")
	)
	(segment
		(start 223.26854 -138.96594)
		(end 223.26854 -139.371578)
		(width 0.14224)
		(layer "In4.Cu")
		(net "M_E_DQ<18>")
	)
	(segment
		(start 231.356408 -116.207286)
		(end 231.356408 -118.06555)
		(width 0.14224)
		(layer "In4.Cu")
		(net "M_E_DQ<18>")
	)
	(segment
		(start 223.175576 -134.072376)
		(end 223.284542 -134.181342)
		(width 0.14224)
		(layer "In4.Cu")
		(net "M_E_DQ<18>")
	)
	(segment
		(start 240.386616 -102.461822)
		(end 239.88141 -102.967028)
		(width 0.0889)
		(layer "In4.Cu")
		(net "M_E_DQ<18>")
	)
	(segment
		(start 222.316802 -144.233646)
		(end 223.599756 -145.5166)
		(width 0.14224)
		(layer "In4.Cu")
		(net "M_E_DQ<18>")
	)
	(segment
		(start 224.863152 -123.415806)
		(end 223.3168 -124.962158)
		(width 0.14224)
		(layer "In4.Cu")
		(net "M_E_DQ<18>")
	)
	(segment
		(start 226.006152 -123.415806)
		(end 224.863152 -123.415806)
		(width 0.14224)
		(layer "In4.Cu")
		(net "M_E_DQ<18>")
	)
	(segment
		(start 223.26854 -136.5504)
		(end 223.1898 -136.62914)
		(width 0.14224)
		(layer "In4.Cu")
		(net "M_E_DQ<18>")
	)
	(segment
		(start 223.3168 -124.962158)
		(end 223.3168 -129.760218)
		(width 0.14224)
		(layer "In4.Cu")
		(net "M_E_DQ<18>")
	)
	(segment
		(start 223.03994 -134.713726)
		(end 223.03994 -135.976868)
		(width 0.14224)
		(layer "In4.Cu")
		(net "M_E_DQ<18>")
	)
	(segment
		(start 223.284542 -134.181342)
		(end 223.284542 -134.469124)
		(width 0.14224)
		(layer "In4.Cu")
		(net "M_E_DQ<18>")
	)
	(segment
		(start 223.3168 -129.760218)
		(end 223.11614 -129.960878)
		(width 0.14224)
		(layer "In4.Cu")
		(net "M_E_DQ<18>")
	)
	(segment
		(start 232.6386 -114.925094)
		(end 231.356408 -116.207286)
		(width 0.14224)
		(layer "In4.Cu")
		(net "M_E_DQ<18>")
	)
	(segment
		(start 223.175576 -132.071364)
		(end 223.175576 -134.072376)
		(width 0.14224)
		(layer "In4.Cu")
		(net "M_E_DQ<18>")
	)
	(segment
		(start 223.1898 -136.62914)
		(end 223.1898 -138.8872)
		(width 0.14224)
		(layer "In4.Cu")
		(net "M_E_DQ<18>")
	)
	(segment
		(start 223.284542 -134.469124)
		(end 223.03994 -134.713726)
		(width 0.14224)
		(layer "In4.Cu")
		(net "M_E_DQ<18>")
	)
	(segment
		(start 223.11614 -131.320286)
		(end 223.31934 -131.523486)
		(width 0.14224)
		(layer "In4.Cu")
		(net "M_E_DQ<18>")
	)
	(segment
		(start 239.88141 -102.967028)
		(end 239.60201 -102.967028)
		(width 0.0889)
		(layer "In4.Cu")
		(net "M_E_DQ<18>")
	)
	(segment
		(start 223.26854 -136.205468)
		(end 223.26854 -136.5504)
		(width 0.14224)
		(layer "In4.Cu")
		(net "M_E_DQ<18>")
	)
	(segment
		(start 238.9632 -103.605838)
		(end 238.9632 -104.292654)
		(width 0.14224)
		(layer "In4.Cu")
		(net "M_E_DQ<18>")
	)
	(segment
		(start 232.6386 -110.617254)
		(end 232.6386 -114.925094)
		(width 0.14224)
		(layer "In4.Cu")
		(net "M_E_DQ<18>")
	)
	(segment
		(start 223.03994 -135.976868)
		(end 223.26854 -136.205468)
		(width 0.14224)
		(layer "In4.Cu")
		(net "M_E_DQ<18>")
	)
	(segment
		(start 240.261902 -101.470968)
		(end 240.386616 -101.69398)
		(width 0.0889)
		(layer "In4.Cu")
		(net "M_E_DQ<18>")
	)
	(segment
		(start 239.886998 -100.26269)
		(end 239.922812 -100.26269)
		(width 0.0889)
		(layer "In4.Cu")
		(net "M_E_DQ<18>")
	)
	(segment
		(start 240.386616 -101.69398)
		(end 240.386616 -102.461822)
		(width 0.0889)
		(layer "In4.Cu")
		(net "M_E_DQ<18>")
	)
	(segment
		(start 239.60201 -102.967028)
		(end 238.9632 -103.605838)
		(width 0.14224)
		(layer "In4.Cu")
		(net "M_E_DQ<18>")
	)
	(segment
		(start 222.40494 -140.235178)
		(end 222.40494 -140.868146)
		(width 0.14224)
		(layer "In4.Cu")
		(net "M_E_DQ<18>")
	)
	(segment
		(start 222.749872 -141.213078)
		(end 222.316802 -141.646148)
		(width 0.14224)
		(layer "In4.Cu")
		(net "M_E_DQ<18>")
	)
	(segment
		(start 231.356408 -118.06555)
		(end 226.006152 -123.415806)
		(width 0.14224)
		(layer "In4.Cu")
		(net "M_E_DQ<18>")
	)
	(segment
		(start 239.904778 -98.681286)
		(end 239.409478 -99.348036)
		(width 0.0889)
		(layer "In4.Cu")
		(net "M_E_DQ<18>")
	)
	(segment
		(start 238.9632 -104.292654)
		(end 232.6386 -110.617254)
		(width 0.14224)
		(layer "In4.Cu")
		(net "M_E_DQ<18>")
	)
	(segment
		(start 239.409478 -99.348036)
		(end 239.392968 -99.376738)
		(width 0.0889)
		(layer "In4.Cu")
		(net "M_E_DQ<18>")
	)
	(segment
		(start 222.40494 -140.868146)
		(end 222.749872 -141.213078)
		(width 0.14224)
		(layer "In4.Cu")
		(net "M_E_DQ<18>")
	)
	(segment
		(start 223.26854 -139.371578)
		(end 222.40494 -140.235178)
		(width 0.14224)
		(layer "In4.Cu")
		(net "M_E_DQ<18>")
	)
	(segment
		(start 223.11614 -129.960878)
		(end 223.11614 -131.320286)
		(width 0.14224)
		(layer "In4.Cu")
		(net "M_E_DQ<18>")
	)
	(segment
		(start 223.31934 -131.9276)
		(end 223.175576 -132.071364)
		(width 0.14224)
		(layer "In4.Cu")
		(net "M_E_DQ<18>")
	)
	(segment
		(start 223.1898 -138.8872)
		(end 223.26854 -138.96594)
		(width 0.14224)
		(layer "In4.Cu")
		(net "M_E_DQ<18>")
	)
	(segment
		(start 222.316802 -141.646148)
		(end 222.316802 -144.233646)
		(width 0.14224)
		(layer "In4.Cu")
		(net "M_E_DQ<18>")
	)
	(arc
		(start 239.392968 -99.376738)
		(mid 239.388639 -99.95991)
		(end 239.886998 -100.26269)
		(width 0.0889)
		(layer "In4.Cu")
		(net "M_E_DQ<18>")
	)
	(arc
		(start 240.251488 -100.862638)
		(mid 240.172266 -101.151756)
		(end 240.245138 -101.44252)
		(width 0.0889)
		(layer "In4.Cu")
		(net "M_E_DQ<18>")
	)
	(arc
		(start 239.922812 -100.26269)
		(mid 240.255781 -100.470238)
		(end 240.251488 -100.862638)
		(width 0.0889)
		(layer "In4.Cu")
		(net "M_E_DQ<18>")
	)
	(segment
		(start 216.799922 -142.677642)
		(end 216.799922 -143.941546)
		(width 0.1651)
		(layer "F.Cu")
		(net "M_E_DQ<17>")
	)
	(segment
		(start 216.80043 -142.6718)
		(end 216.799922 -142.677642)
		(width 0.1651)
		(layer "F.Cu")
		(net "M_E_DQ<17>")
	)
	(segment
		(start 237.900718 -100.167186)
		(end 237.329218 -100.167186)
		(width 0.1651)
		(layer "F.Cu")
		(net "M_E_DQ<17>")
	)
	(via
		(at 237.329218 -100.167186)
		(size 0.508)
		(drill 0.254)
		(layers "F.Cu" "B.Cu")
		(net "M_E_DQ<17>")
	)
	(via
		(at 217.472006 -139.932156)
		(size 0.508)
		(drill 0.254)
		(layers "F.Cu" "B.Cu")
		(net "M_E_DQ<17>")
	)
	(via
		(at 216.799922 -143.941546)
		(size 0.508)
		(drill 0.254)
		(layers "F.Cu" "B.Cu")
		(net "M_E_DQ<17>")
	)
	(segment
		(start 217.649806 -137.877296)
		(end 217.649806 -139.251182)
		(width 0.1651)
		(layer "B.Cu")
		(net "M_E_DQ<17>")
	)
	(segment
		(start 217.649806 -139.251182)
		(end 217.472006 -139.428982)
		(width 0.1651)
		(layer "B.Cu")
		(net "M_E_DQ<17>")
	)
	(segment
		(start 217.472006 -139.428982)
		(end 217.472006 -139.932156)
		(width 0.1651)
		(layer "B.Cu")
		(net "M_E_DQ<17>")
	)
	(segment
		(start 217.650314 -137.877296)
		(end 217.649806 -137.877296)
		(width 0.1651)
		(layer "B.Cu")
		(net "M_E_DQ<17>")
	)
	(segment
		(start 234.74299 -101.253036)
		(end 234.742482 -101.252528)
		(width 0.0889)
		(layer "In4.Cu")
		(net "M_E_DQ<17>")
	)
	(segment
		(start 231.847898 -105.27538)
		(end 232.002838 -105.43032)
		(width 0.14224)
		(layer "In4.Cu")
		(net "M_E_DQ<17>")
	)
	(segment
		(start 217.6526 -133.26491)
		(end 217.80754 -133.41985)
		(width 0.14224)
		(layer "In4.Cu")
		(net "M_E_DQ<17>")
	)
	(segment
		(start 228.8032 -113.700814)
		(end 219.1004 -123.403614)
		(width 0.14224)
		(layer "In4.Cu")
		(net "M_E_DQ<17>")
	)
	(segment
		(start 219.1004 -125.374654)
		(end 219.4814 -125.755654)
		(width 0.14224)
		(layer "In4.Cu")
		(net "M_E_DQ<17>")
	)
	(segment
		(start 219.4814 -125.755654)
		(end 219.4814 -126.045214)
		(width 0.14224)
		(layer "In4.Cu")
		(net "M_E_DQ<17>")
	)
	(segment
		(start 228.8032 -108.966254)
		(end 228.8032 -113.700814)
		(width 0.14224)
		(layer "In4.Cu")
		(net "M_E_DQ<17>")
	)
	(segment
		(start 217.73134 -137.397998)
		(end 217.5764 -137.552938)
		(width 0.14224)
		(layer "In4.Cu")
		(net "M_E_DQ<17>")
	)
	(segment
		(start 217.73134 -138.210798)
		(end 218.00566 -138.210798)
		(width 0.14224)
		(layer "In4.Cu")
		(net "M_E_DQ<17>")
	)
	(segment
		(start 217.200988 -143.7894)
		(end 217.048842 -143.941546)
		(width 0.14224)
		(layer "In4.Cu")
		(net "M_E_DQ<17>")
	)
	(segment
		(start 217.251788 -141.020546)
		(end 217.251788 -141.425168)
		(width 0.14224)
		(layer "In4.Cu")
		(net "M_E_DQ<17>")
	)
	(segment
		(start 219.4814 -127.7112)
		(end 217.95994 -129.23266)
		(width 0.14224)
		(layer "In4.Cu")
		(net "M_E_DQ<17>")
	)
	(segment
		(start 232.002838 -105.43032)
		(end 232.002838 -105.766616)
		(width 0.14224)
		(layer "In4.Cu")
		(net "M_E_DQ<17>")
	)
	(segment
		(start 218.1606 -138.365738)
		(end 218.1606 -138.7094)
		(width 0.14224)
		(layer "In4.Cu")
		(net "M_E_DQ<17>")
	)
	(segment
		(start 217.95994 -138.91006)
		(end 217.95994 -139.444222)
		(width 0.14224)
		(layer "In4.Cu")
		(net "M_E_DQ<17>")
	)
	(segment
		(start 216.961212 -142.936976)
		(end 216.961212 -143.244824)
		(width 0.14224)
		(layer "In4.Cu")
		(net "M_E_DQ<17>")
	)
	(segment
		(start 217.02141 -140.790168)
		(end 217.251788 -141.020546)
		(width 0.14224)
		(layer "In4.Cu")
		(net "M_E_DQ<17>")
	)
	(segment
		(start 235.625132 -100.75799)
		(end 235.597192 -100.75799)
		(width 0.0889)
		(layer "In4.Cu")
		(net "M_E_DQ<17>")
	)
	(segment
		(start 218.18346 -132.60705)
		(end 217.80754 -132.60705)
		(width 0.14224)
		(layer "In4.Cu")
		(net "M_E_DQ<17>")
	)
	(segment
		(start 217.200988 -143.4846)
		(end 217.200988 -143.7894)
		(width 0.14224)
		(layer "In4.Cu")
		(net "M_E_DQ<17>")
	)
	(segment
		(start 218.00566 -137.397998)
		(end 217.73134 -137.397998)
		(width 0.14224)
		(layer "In4.Cu")
		(net "M_E_DQ<17>")
	)
	(segment
		(start 218.3384 -132.1816)
		(end 218.3384 -132.45211)
		(width 0.14224)
		(layer "In4.Cu")
		(net "M_E_DQ<17>")
	)
	(segment
		(start 217.95994 -139.444222)
		(end 217.472006 -139.932156)
		(width 0.14224)
		(layer "In4.Cu")
		(net "M_E_DQ<17>")
	)
	(segment
		(start 219.4814 -127.239014)
		(end 219.4814 -127.7112)
		(width 0.14224)
		(layer "In4.Cu")
		(net "M_E_DQ<17>")
	)
	(segment
		(start 218.3384 -132.45211)
		(end 218.18346 -132.60705)
		(width 0.14224)
		(layer "In4.Cu")
		(net "M_E_DQ<17>")
	)
	(segment
		(start 218.1606 -138.7094)
		(end 217.95994 -138.91006)
		(width 0.14224)
		(layer "In4.Cu")
		(net "M_E_DQ<17>")
	)
	(segment
		(start 219.4814 -124.663454)
		(end 219.1004 -125.044454)
		(width 0.14224)
		(layer "In4.Cu")
		(net "M_E_DQ<17>")
	)
	(segment
		(start 217.80754 -133.41985)
		(end 218.18346 -133.41985)
		(width 0.14224)
		(layer "In4.Cu")
		(net "M_E_DQ<17>")
	)
	(segment
		(start 219.4814 -124.485654)
		(end 219.4814 -124.663454)
		(width 0.14224)
		(layer "In4.Cu")
		(net "M_E_DQ<17>")
	)
	(segment
		(start 233.262424 -102.856792)
		(end 231.975914 -104.143302)
		(width 0.14224)
		(layer "In4.Cu")
		(net "M_E_DQ<17>")
	)
	(segment
		(start 234.775248 -101.253036)
		(end 234.74299 -101.253036)
		(width 0.0889)
		(layer "In4.Cu")
		(net "M_E_DQ<17>")
	)
	(segment
		(start 231.975914 -104.4575)
		(end 231.820974 -104.61244)
		(width 0.14224)
		(layer "In4.Cu")
		(net "M_E_DQ<17>")
	)
	(segment
		(start 237.329218 -100.167186)
		(end 236.506766 -100.26269)
		(width 0.0889)
		(layer "In4.Cu")
		(net "M_E_DQ<17>")
	)
	(segment
		(start 218.3384 -133.8834)
		(end 217.95994 -134.26186)
		(width 0.14224)
		(layer "In4.Cu")
		(net "M_E_DQ<17>")
	)
	(segment
		(start 231.336088 -105.12044)
		(end 231.491028 -105.27538)
		(width 0.14224)
		(layer "In4.Cu")
		(net "M_E_DQ<17>")
	)
	(segment
		(start 218.1606 -136.8044)
		(end 218.1606 -137.243058)
		(width 0.14224)
		(layer "In4.Cu")
		(net "M_E_DQ<17>")
	)
	(segment
		(start 217.472006 -139.932156)
		(end 217.449654 -139.932156)
		(width 0.14224)
		(layer "In4.Cu")
		(net "M_E_DQ<17>")
	)
	(segment
		(start 219.1004 -125.044454)
		(end 219.1004 -125.374654)
		(width 0.14224)
		(layer "In4.Cu")
		(net "M_E_DQ<17>")
	)
	(segment
		(start 217.251788 -141.425168)
		(end 216.961212 -141.715744)
		(width 0.14224)
		(layer "In4.Cu")
		(net "M_E_DQ<17>")
	)
	(segment
		(start 231.491028 -104.61244)
		(end 231.336088 -104.76738)
		(width 0.14224)
		(layer "In4.Cu")
		(net "M_E_DQ<17>")
	)
	(segment
		(start 217.95994 -136.60374)
		(end 218.1606 -136.8044)
		(width 0.14224)
		(layer "In4.Cu")
		(net "M_E_DQ<17>")
	)
	(segment
		(start 231.336088 -104.76738)
		(end 231.336088 -105.12044)
		(width 0.14224)
		(layer "In4.Cu")
		(net "M_E_DQ<17>")
	)
	(segment
		(start 218.3384 -133.57479)
		(end 218.3384 -133.8834)
		(width 0.14224)
		(layer "In4.Cu")
		(net "M_E_DQ<17>")
	)
	(segment
		(start 217.95994 -134.26186)
		(end 217.95994 -136.60374)
		(width 0.14224)
		(layer "In4.Cu")
		(net "M_E_DQ<17>")
	)
	(segment
		(start 217.5764 -138.055858)
		(end 217.73134 -138.210798)
		(width 0.14224)
		(layer "In4.Cu")
		(net "M_E_DQ<17>")
	)
	(segment
		(start 217.6526 -132.76199)
		(end 217.6526 -133.26491)
		(width 0.14224)
		(layer "In4.Cu")
		(net "M_E_DQ<17>")
	)
	(segment
		(start 233.262424 -102.638606)
		(end 233.262424 -102.856792)
		(width 0.0889)
		(layer "In4.Cu")
		(net "M_E_DQ<17>")
	)
	(segment
		(start 217.175588 -142.7226)
		(end 216.961212 -142.936976)
		(width 0.14224)
		(layer "In4.Cu")
		(net "M_E_DQ<17>")
	)
	(segment
		(start 231.975914 -104.143302)
		(end 231.975914 -104.4575)
		(width 0.14224)
		(layer "In4.Cu")
		(net "M_E_DQ<17>")
	)
	(segment
		(start 219.4814 -126.045214)
		(end 219.1004 -126.426214)
		(width 0.14224)
		(layer "In4.Cu")
		(net "M_E_DQ<17>")
	)
	(segment
		(start 219.1004 -123.403614)
		(end 219.1004 -124.104654)
		(width 0.14224)
		(layer "In4.Cu")
		(net "M_E_DQ<17>")
	)
	(segment
		(start 218.18346 -133.41985)
		(end 218.3384 -133.57479)
		(width 0.14224)
		(layer "In4.Cu")
		(net "M_E_DQ<17>")
	)
	(segment
		(start 231.491028 -105.27538)
		(end 231.847898 -105.27538)
		(width 0.14224)
		(layer "In4.Cu")
		(net "M_E_DQ<17>")
	)
	(segment
		(start 217.02141 -140.3604)
		(end 217.02141 -140.790168)
		(width 0.14224)
		(layer "In4.Cu")
		(net "M_E_DQ<17>")
	)
	(segment
		(start 217.80754 -132.60705)
		(end 217.6526 -132.76199)
		(width 0.14224)
		(layer "In4.Cu")
		(net "M_E_DQ<17>")
	)
	(segment
		(start 217.175588 -142.2908)
		(end 217.175588 -142.7226)
		(width 0.14224)
		(layer "In4.Cu")
		(net "M_E_DQ<17>")
	)
	(segment
		(start 232.002838 -105.766616)
		(end 228.8032 -108.966254)
		(width 0.14224)
		(layer "In4.Cu")
		(net "M_E_DQ<17>")
	)
	(segment
		(start 236.506766 -100.26269)
		(end 236.452664 -100.26269)
		(width 0.0889)
		(layer "In4.Cu")
		(net "M_E_DQ<17>")
	)
	(segment
		(start 217.95994 -129.23266)
		(end 217.95994 -131.80314)
		(width 0.14224)
		(layer "In4.Cu")
		(net "M_E_DQ<17>")
	)
	(segment
		(start 231.820974 -104.61244)
		(end 231.491028 -104.61244)
		(width 0.14224)
		(layer "In4.Cu")
		(net "M_E_DQ<17>")
	)
	(segment
		(start 217.95994 -131.80314)
		(end 218.3384 -132.1816)
		(width 0.14224)
		(layer "In4.Cu")
		(net "M_E_DQ<17>")
	)
	(segment
		(start 217.449654 -139.932156)
		(end 217.02141 -140.3604)
		(width 0.14224)
		(layer "In4.Cu")
		(net "M_E_DQ<17>")
	)
	(segment
		(start 234.742482 -101.252528)
		(end 234.73918 -101.252528)
		(width 0.0889)
		(layer "In4.Cu")
		(net "M_E_DQ<17>")
	)
	(segment
		(start 219.1004 -124.104654)
		(end 219.4814 -124.485654)
		(width 0.14224)
		(layer "In4.Cu")
		(net "M_E_DQ<17>")
	)
	(segment
		(start 218.1606 -137.243058)
		(end 218.00566 -137.397998)
		(width 0.14224)
		(layer "In4.Cu")
		(net "M_E_DQ<17>")
	)
	(segment
		(start 234.40644 -101.452934)
		(end 234.349544 -101.551486)
		(width 0.0889)
		(layer "In4.Cu")
		(net "M_E_DQ<17>")
	)
	(segment
		(start 216.961212 -142.076424)
		(end 217.175588 -142.2908)
		(width 0.14224)
		(layer "In4.Cu")
		(net "M_E_DQ<17>")
	)
	(segment
		(start 217.5764 -137.552938)
		(end 217.5764 -138.055858)
		(width 0.14224)
		(layer "In4.Cu")
		(net "M_E_DQ<17>")
	)
	(segment
		(start 217.048842 -143.941546)
		(end 216.799922 -143.941546)
		(width 0.14224)
		(layer "In4.Cu")
		(net "M_E_DQ<17>")
	)
	(segment
		(start 218.00566 -138.210798)
		(end 218.1606 -138.365738)
		(width 0.14224)
		(layer "In4.Cu")
		(net "M_E_DQ<17>")
	)
	(segment
		(start 219.1004 -126.858014)
		(end 219.4814 -127.239014)
		(width 0.14224)
		(layer "In4.Cu")
		(net "M_E_DQ<17>")
	)
	(segment
		(start 216.961212 -141.715744)
		(end 216.961212 -142.076424)
		(width 0.14224)
		(layer "In4.Cu")
		(net "M_E_DQ<17>")
	)
	(segment
		(start 216.961212 -143.244824)
		(end 217.200988 -143.4846)
		(width 0.14224)
		(layer "In4.Cu")
		(net "M_E_DQ<17>")
	)
	(segment
		(start 219.1004 -126.426214)
		(end 219.1004 -126.858014)
		(width 0.14224)
		(layer "In4.Cu")
		(net "M_E_DQ<17>")
	)
	(segment
		(start 234.349544 -101.551486)
		(end 233.262424 -102.638606)
		(width 0.0889)
		(layer "In4.Cu")
		(net "M_E_DQ<17>")
	)
	(arc
		(start 236.452664 -100.26269)
		(mid 236.262735 -100.32056)
		(end 236.123988 -100.462588)
		(width 0.0889)
		(layer "In4.Cu")
		(net "M_E_DQ<17>")
	)
	(arc
		(start 235.265468 -100.957888)
		(mid 235.058464 -101.168752)
		(end 234.775248 -101.253036)
		(width 0.0889)
		(layer "In4.Cu")
		(net "M_E_DQ<17>")
	)
	(arc
		(start 235.597192 -100.75799)
		(mid 235.40555 -100.815156)
		(end 235.265468 -100.957888)
		(width 0.0889)
		(layer "In4.Cu")
		(net "M_E_DQ<17>")
	)
	(arc
		(start 234.73918 -101.252528)
		(mid 234.546894 -101.309713)
		(end 234.40644 -101.452934)
		(width 0.0889)
		(layer "In4.Cu")
		(net "M_E_DQ<17>")
	)
	(arc
		(start 236.123988 -100.462588)
		(mid 235.913275 -100.675667)
		(end 235.625132 -100.75799)
		(width 0.0889)
		(layer "In4.Cu")
		(net "M_E_DQ<17>")
	)
	(segment
		(start 217.650314 -147.27174)
		(end 217.649806 -147.277582)
		(width 0.1651)
		(layer "F.Cu")
		(net "M_E_DQ<16>")
	)
	(segment
		(start 217.649806 -147.277582)
		(end 217.472006 -145.415)
		(width 0.1651)
		(layer "F.Cu")
		(net "M_E_DQ<16>")
	)
	(segment
		(start 237.900718 -98.18624)
		(end 237.329218 -98.18624)
		(width 0.1651)
		(layer "F.Cu")
		(net "M_E_DQ<16>")
	)
	(via
		(at 217.472006 -145.415)
		(size 0.508)
		(drill 0.254)
		(layers "F.Cu" "B.Cu")
		(net "M_E_DQ<16>")
	)
	(via
		(at 216.799922 -141.213078)
		(size 0.508)
		(drill 0.254)
		(layers "F.Cu" "B.Cu")
		(net "M_E_DQ<16>")
	)
	(via
		(at 237.329218 -98.18624)
		(size 0.508)
		(drill 0.254)
		(layers "F.Cu" "B.Cu")
		(net "M_E_DQ<16>")
	)
	(segment
		(start 216.80043 -142.477236)
		(end 216.799922 -142.476982)
		(width 0.1651)
		(layer "B.Cu")
		(net "M_E_DQ<16>")
	)
	(segment
		(start 216.799922 -142.476982)
		(end 216.799922 -141.213078)
		(width 0.1651)
		(layer "B.Cu")
		(net "M_E_DQ<16>")
	)
	(segment
		(start 217.27414 -134.484618)
		(end 216.98204 -134.776718)
		(width 0.14224)
		(layer "In4.Cu")
		(net "M_E_DQ<16>")
	)
	(segment
		(start 217.097102 -138.560302)
		(end 217.231722 -138.694922)
		(width 0.14224)
		(layer "In4.Cu")
		(net "M_E_DQ<16>")
	)
	(segment
		(start 216.9414 -130.103118)
		(end 216.9414 -131.139946)
		(width 0.14224)
		(layer "In4.Cu")
		(net "M_E_DQ<16>")
	)
	(segment
		(start 216.98204 -135.979916)
		(end 217.28557 -136.283446)
		(width 0.14224)
		(layer "In4.Cu")
		(net "M_E_DQ<16>")
	)
	(segment
		(start 236.488732 -100.071936)
		(end 236.449108 -100.071936)
		(width 0.0889)
		(layer "In4.Cu")
		(net "M_E_DQ<16>")
	)
	(segment
		(start 235.623354 -100.567236)
		(end 235.599224 -100.567236)
		(width 0.0889)
		(layer "In4.Cu")
		(net "M_E_DQ<16>")
	)
	(segment
		(start 216.9414 -131.139946)
		(end 217.265504 -131.46405)
		(width 0.14224)
		(layer "In4.Cu")
		(net "M_E_DQ<16>")
	)
	(segment
		(start 234.197398 -101.4349)
		(end 233.210608 -102.42169)
		(width 0.0889)
		(layer "In4.Cu")
		(net "M_E_DQ<16>")
	)
	(segment
		(start 217.28557 -136.60247)
		(end 217.097102 -136.790938)
		(width 0.14224)
		(layer "In4.Cu")
		(net "M_E_DQ<16>")
	)
	(segment
		(start 217.320368 -129.72415)
		(end 216.9414 -130.103118)
		(width 0.14224)
		(layer "In4.Cu")
		(net "M_E_DQ<16>")
	)
	(segment
		(start 234.241848 -101.357938)
		(end 234.197398 -101.4349)
		(width 0.0889)
		(layer "In4.Cu")
		(net "M_E_DQ<16>")
	)
	(segment
		(start 217.27414 -134.11454)
		(end 217.27414 -134.484618)
		(width 0.14224)
		(layer "In4.Cu")
		(net "M_E_DQ<16>")
	)
	(segment
		(start 217.28557 -136.283446)
		(end 217.28557 -136.60247)
		(width 0.14224)
		(layer "In4.Cu")
		(net "M_E_DQ<16>")
	)
	(segment
		(start 237.329218 -98.18624)
		(end 236.834172 -98.851974)
		(width 0.0889)
		(layer "In4.Cu")
		(net "M_E_DQ<16>")
	)
	(segment
		(start 217.320368 -129.034032)
		(end 217.320368 -129.72415)
		(width 0.14224)
		(layer "In4.Cu")
		(net "M_E_DQ<16>")
	)
	(segment
		(start 217.144346 -132.082794)
		(end 217.144346 -133.984746)
		(width 0.14224)
		(layer "In4.Cu")
		(net "M_E_DQ<16>")
	)
	(segment
		(start 217.265504 -131.961636)
		(end 217.144346 -132.082794)
		(width 0.14224)
		(layer "In4.Cu")
		(net "M_E_DQ<16>")
	)
	(segment
		(start 234.768644 -101.062536)
		(end 234.735878 -101.062536)
		(width 0.0889)
		(layer "In4.Cu")
		(net "M_E_DQ<16>")
	)
	(segment
		(start 218.4654 -123.14047)
		(end 218.4654 -127.889)
		(width 0.14224)
		(layer "In4.Cu")
		(net "M_E_DQ<16>")
	)
	(segment
		(start 232.799382 -102.42169)
		(end 230.790496 -104.430576)
		(width 0.14224)
		(layer "In4.Cu")
		(net "M_E_DQ<16>")
	)
	(segment
		(start 216.5985 -141.011656)
		(end 216.799922 -141.213078)
		(width 0.14224)
		(layer "In4.Cu")
		(net "M_E_DQ<16>")
	)
	(segment
		(start 236.834172 -98.851974)
		(end 236.817408 -98.881438)
		(width 0.0889)
		(layer "In4.Cu")
		(net "M_E_DQ<16>")
	)
	(segment
		(start 233.210608 -102.42169)
		(end 232.799382 -102.42169)
		(width 0.0889)
		(layer "In4.Cu")
		(net "M_E_DQ<16>")
	)
	(segment
		(start 217.265504 -131.46405)
		(end 217.265504 -131.961636)
		(width 0.14224)
		(layer "In4.Cu")
		(net "M_E_DQ<16>")
	)
	(segment
		(start 228.1682 -113.43767)
		(end 218.4654 -123.14047)
		(width 0.14224)
		(layer "In4.Cu")
		(net "M_E_DQ<16>")
	)
	(segment
		(start 216.799922 -141.213078)
		(end 216.366852 -141.646148)
		(width 0.14224)
		(layer "In4.Cu")
		(net "M_E_DQ<16>")
	)
	(segment
		(start 216.366852 -141.646148)
		(end 216.366852 -144.60601)
		(width 0.14224)
		(layer "In4.Cu")
		(net "M_E_DQ<16>")
	)
	(segment
		(start 216.5985 -140.047218)
		(end 216.5985 -141.011656)
		(width 0.14224)
		(layer "In4.Cu")
		(net "M_E_DQ<16>")
	)
	(segment
		(start 217.175842 -145.415)
		(end 217.472006 -145.415)
		(width 0.14224)
		(layer "In4.Cu")
		(net "M_E_DQ<16>")
	)
	(segment
		(start 217.097102 -136.790938)
		(end 217.097102 -138.560302)
		(width 0.14224)
		(layer "In4.Cu")
		(net "M_E_DQ<16>")
	)
	(segment
		(start 216.98204 -134.776718)
		(end 216.98204 -135.979916)
		(width 0.14224)
		(layer "In4.Cu")
		(net "M_E_DQ<16>")
	)
	(segment
		(start 217.231722 -139.413996)
		(end 216.5985 -140.047218)
		(width 0.14224)
		(layer "In4.Cu")
		(net "M_E_DQ<16>")
	)
	(segment
		(start 230.790496 -104.430576)
		(end 230.790496 -106.064558)
		(width 0.14224)
		(layer "In4.Cu")
		(net "M_E_DQ<16>")
	)
	(segment
		(start 228.1682 -108.686854)
		(end 228.1682 -113.43767)
		(width 0.14224)
		(layer "In4.Cu")
		(net "M_E_DQ<16>")
	)
	(segment
		(start 230.790496 -106.064558)
		(end 228.1682 -108.686854)
		(width 0.14224)
		(layer "In4.Cu")
		(net "M_E_DQ<16>")
	)
	(segment
		(start 216.366852 -144.60601)
		(end 217.175842 -145.415)
		(width 0.14224)
		(layer "In4.Cu")
		(net "M_E_DQ<16>")
	)
	(segment
		(start 217.144346 -133.984746)
		(end 217.27414 -134.11454)
		(width 0.14224)
		(layer "In4.Cu")
		(net "M_E_DQ<16>")
	)
	(segment
		(start 217.231722 -138.694922)
		(end 217.231722 -139.413996)
		(width 0.14224)
		(layer "In4.Cu")
		(net "M_E_DQ<16>")
	)
	(segment
		(start 218.4654 -127.889)
		(end 217.320368 -129.034032)
		(width 0.14224)
		(layer "In4.Cu")
		(net "M_E_DQ<16>")
	)
	(arc
		(start 235.100368 -100.862638)
		(mid 234.960289 -101.005374)
		(end 234.768644 -101.062536)
		(width 0.0889)
		(layer "In4.Cu")
		(net "M_E_DQ<16>")
	)
	(arc
		(start 236.817408 -98.881438)
		(mid 236.738277 -99.17684)
		(end 236.817408 -99.472242)
		(width 0.0889)
		(layer "In4.Cu")
		(net "M_E_DQ<16>")
	)
	(arc
		(start 234.735878 -101.062536)
		(mid 234.450454 -101.146003)
		(end 234.241848 -101.357938)
		(width 0.0889)
		(layer "In4.Cu")
		(net "M_E_DQ<16>")
	)
	(arc
		(start 235.599224 -100.567236)
		(mid 235.311079 -100.649555)
		(end 235.100368 -100.862638)
		(width 0.0889)
		(layer "In4.Cu")
		(net "M_E_DQ<16>")
	)
	(arc
		(start 236.449108 -100.071936)
		(mid 236.165891 -100.156217)
		(end 235.958888 -100.367084)
		(width 0.0889)
		(layer "In4.Cu")
		(net "M_E_DQ<16>")
	)
	(arc
		(start 236.817408 -99.472242)
		(mid 236.821653 -99.864487)
		(end 236.488732 -100.071936)
		(width 0.0889)
		(layer "In4.Cu")
		(net "M_E_DQ<16>")
	)
	(arc
		(start 235.958888 -100.367084)
		(mid 235.817205 -100.510888)
		(end 235.623354 -100.567236)
		(width 0.0889)
		(layer "In4.Cu")
		(net "M_E_DQ<16>")
	)
	(segment
		(start 211.700364 -142.6718)
		(end 211.699856 -142.677642)
		(width 0.1651)
		(layer "F.Cu")
		(net "M_E_DQ<15>")
	)
	(segment
		(start 211.699856 -142.677642)
		(end 211.699856 -143.941546)
		(width 0.1651)
		(layer "F.Cu")
		(net "M_E_DQ<15>")
	)
	(segment
		(start 236.183678 -91.25204)
		(end 235.612178 -91.25204)
		(width 0.1651)
		(layer "F.Cu")
		(net "M_E_DQ<15>")
	)
	(via
		(at 212.54974 -139.932156)
		(size 0.508)
		(drill 0.254)
		(layers "F.Cu" "B.Cu")
		(net "M_E_DQ<15>")
	)
	(via
		(at 211.699856 -143.941546)
		(size 0.508)
		(drill 0.254)
		(layers "F.Cu" "B.Cu")
		(net "M_E_DQ<15>")
	)
	(via
		(at 235.612178 -91.25204)
		(size 0.508)
		(drill 0.254)
		(layers "F.Cu" "B.Cu")
		(net "M_E_DQ<15>")
	)
	(segment
		(start 212.550502 -137.877296)
		(end 212.550502 -139.931394)
		(width 0.1651)
		(layer "B.Cu")
		(net "M_E_DQ<15>")
	)
	(segment
		(start 212.550502 -139.931394)
		(end 212.54974 -139.932156)
		(width 0.1651)
		(layer "B.Cu")
		(net "M_E_DQ<15>")
	)
	(segment
		(start 214.79129 -121.333514)
		(end 214.79129 -121.552462)
		(width 0.14224)
		(layer "In4.Cu")
		(net "M_E_DQ<15>")
	)
	(segment
		(start 222.640398 -109.539024)
		(end 222.795338 -109.693964)
		(width 0.14224)
		(layer "In4.Cu")
		(net "M_E_DQ<15>")
	)
	(segment
		(start 212.902546 -128.455166)
		(end 212.902546 -129.859278)
		(width 0.14224)
		(layer "In4.Cu")
		(net "M_E_DQ<15>")
	)
	(segment
		(start 223.6216 -110.422944)
		(end 216.6874 -117.357144)
		(width 0.14224)
		(layer "In4.Cu")
		(net "M_E_DQ<15>")
	)
	(segment
		(start 235.265468 -92.442538)
		(end 235.271818 -92.453206)
		(width 0.0889)
		(layer "In4.Cu")
		(net "M_E_DQ<15>")
	)
	(segment
		(start 234.300014 -93.603826)
		(end 234.298998 -93.603826)
		(width 0.0889)
		(layer "In4.Cu")
		(net "M_E_DQ<15>")
	)
	(segment
		(start 216.516204 -119.6086)
		(end 216.516204 -119.827548)
		(width 0.14224)
		(layer "In4.Cu")
		(net "M_E_DQ<15>")
	)
	(segment
		(start 219.818712 -116.52504)
		(end 217.309954 -119.033798)
		(width 0.14224)
		(layer "In4.Cu")
		(net "M_E_DQ<15>")
	)
	(segment
		(start 223.6216 -104.893364)
		(end 223.6216 -108.876084)
		(width 0.14224)
		(layer "In4.Cu")
		(net "M_E_DQ<15>")
	)
	(segment
		(start 222.795338 -109.693964)
		(end 223.46666 -109.693964)
		(width 0.14224)
		(layer "In4.Cu")
		(net "M_E_DQ<15>")
	)
	(segment
		(start 212.902546 -139.590272)
		(end 212.891624 -139.590272)
		(width 0.14224)
		(layer "In4.Cu")
		(net "M_E_DQ<15>")
	)
	(segment
		(start 223.46666 -109.031024)
		(end 222.795338 -109.031024)
		(width 0.14224)
		(layer "In4.Cu")
		(net "M_E_DQ<15>")
	)
	(segment
		(start 217.091006 -119.033798)
		(end 216.701878 -118.64467)
		(width 0.14224)
		(layer "In4.Cu")
		(net "M_E_DQ<15>")
	)
	(segment
		(start 213.07171 -136.05129)
		(end 212.902546 -136.220454)
		(width 0.14224)
		(layer "In4.Cu")
		(net "M_E_DQ<15>")
	)
	(segment
		(start 216.974674 -117.931946)
		(end 217.262202 -117.931946)
		(width 0.14224)
		(layer "In4.Cu")
		(net "M_E_DQ<15>")
	)
	(segment
		(start 217.262202 -117.931946)
		(end 219.24391 -115.950238)
		(width 0.14224)
		(layer "In4.Cu")
		(net "M_E_DQ<15>")
	)
	(segment
		(start 232.680764 -94.713806)
		(end 230.798624 -96.595946)
		(width 0.0889)
		(layer "In4.Cu")
		(net "M_E_DQ<15>")
	)
	(segment
		(start 212.54974 -139.932156)
		(end 212.527388 -139.932156)
		(width 0.14224)
		(layer "In4.Cu")
		(net "M_E_DQ<15>")
	)
	(segment
		(start 222.795338 -109.031024)
		(end 222.640398 -109.185964)
		(width 0.14224)
		(layer "In4.Cu")
		(net "M_E_DQ<15>")
	)
	(segment
		(start 214.224362 -120.547638)
		(end 214.224362 -120.766586)
		(width 0.14224)
		(layer "In4.Cu")
		(net "M_E_DQ<15>")
	)
	(segment
		(start 212.927946 -134.543038)
		(end 213.07171 -134.686802)
		(width 0.14224)
		(layer "In4.Cu")
		(net "M_E_DQ<15>")
	)
	(segment
		(start 211.972144 -143.941546)
		(end 211.699856 -143.941546)
		(width 0.14224)
		(layer "In4.Cu")
		(net "M_E_DQ<15>")
	)
	(segment
		(start 211.861146 -142.059152)
		(end 212.118194 -142.3162)
		(width 0.14224)
		(layer "In4.Cu")
		(net "M_E_DQ<15>")
	)
	(segment
		(start 233.189018 -94.713806)
		(end 232.680764 -94.713806)
		(width 0.0889)
		(layer "In4.Cu")
		(net "M_E_DQ<15>")
	)
	(segment
		(start 230.798624 -96.892872)
		(end 228.62159 -99.069906)
		(width 0.14224)
		(layer "In4.Cu")
		(net "M_E_DQ<15>")
	)
	(segment
		(start 214.3252 -127.032512)
		(end 212.902546 -128.455166)
		(width 0.14224)
		(layer "In4.Cu")
		(net "M_E_DQ<15>")
	)
	(segment
		(start 235.392722 -91.822016)
		(end 235.265468 -92.042488)
		(width 0.0889)
		(layer "In4.Cu")
		(net "M_E_DQ<15>")
	)
	(segment
		(start 212.979 -132.080254)
		(end 212.979 -134.112)
		(width 0.14224)
		(layer "In4.Cu")
		(net "M_E_DQ<15>")
	)
	(segment
		(start 215.58504 -120.758712)
		(end 215.366092 -120.758712)
		(width 0.14224)
		(layer "In4.Cu")
		(net "M_E_DQ<15>")
	)
	(segment
		(start 212.149944 -143.763746)
		(end 211.972144 -143.941546)
		(width 0.14224)
		(layer "In4.Cu")
		(net "M_E_DQ<15>")
	)
	(segment
		(start 216.127076 -119.219472)
		(end 216.516204 -119.6086)
		(width 0.14224)
		(layer "In4.Cu")
		(net "M_E_DQ<15>")
	)
	(segment
		(start 212.927946 -134.163054)
		(end 212.927946 -134.543038)
		(width 0.14224)
		(layer "In4.Cu")
		(net "M_E_DQ<15>")
	)
	(segment
		(start 234.57535 -93.32849)
		(end 234.300014 -93.603826)
		(width 0.0889)
		(layer "In4.Cu")
		(net "M_E_DQ<15>")
	)
	(segment
		(start 216.48293 -118.64467)
		(end 216.127076 -119.000524)
		(width 0.14224)
		(layer "In4.Cu")
		(net "M_E_DQ<15>")
	)
	(segment
		(start 211.861146 -141.785848)
		(end 211.861146 -142.059152)
		(width 0.14224)
		(layer "In4.Cu")
		(net "M_E_DQ<15>")
	)
	(segment
		(start 228.62159 -99.893374)
		(end 223.6216 -104.893364)
		(width 0.14224)
		(layer "In4.Cu")
		(net "M_E_DQ<15>")
	)
	(segment
		(start 213.131146 -131.140454)
		(end 212.851746 -131.419854)
		(width 0.14224)
		(layer "In4.Cu")
		(net "M_E_DQ<15>")
	)
	(segment
		(start 212.143594 -141.5034)
		(end 211.861146 -141.785848)
		(width 0.14224)
		(layer "In4.Cu")
		(net "M_E_DQ<15>")
	)
	(segment
		(start 212.979 -134.112)
		(end 212.927946 -134.163054)
		(width 0.14224)
		(layer "In4.Cu")
		(net "M_E_DQ<15>")
	)
	(segment
		(start 212.118194 -142.3162)
		(end 212.118194 -142.621)
		(width 0.14224)
		(layer "In4.Cu")
		(net "M_E_DQ<15>")
	)
	(segment
		(start 212.851746 -131.419854)
		(end 212.851746 -131.953)
		(width 0.14224)
		(layer "In4.Cu")
		(net "M_E_DQ<15>")
	)
	(segment
		(start 215.366092 -120.758712)
		(end 214.799164 -120.191784)
		(width 0.14224)
		(layer "In4.Cu")
		(net "M_E_DQ<15>")
	)
	(segment
		(start 216.516204 -119.827548)
		(end 215.58504 -120.758712)
		(width 0.14224)
		(layer "In4.Cu")
		(net "M_E_DQ<15>")
	)
	(segment
		(start 214.580216 -120.191784)
		(end 214.224362 -120.547638)
		(width 0.14224)
		(layer "In4.Cu")
		(net "M_E_DQ<15>")
	)
	(segment
		(start 212.851746 -131.953)
		(end 212.979 -132.080254)
		(width 0.14224)
		(layer "In4.Cu")
		(net "M_E_DQ<15>")
	)
	(segment
		(start 235.260642 -92.433902)
		(end 235.265468 -92.442538)
		(width 0.0889)
		(layer "In4.Cu")
		(net "M_E_DQ<15>")
	)
	(segment
		(start 212.118194 -142.621)
		(end 211.861146 -142.878048)
		(width 0.14224)
		(layer "In4.Cu")
		(net "M_E_DQ<15>")
	)
	(segment
		(start 212.099144 -140.790168)
		(end 212.143594 -140.834618)
		(width 0.14224)
		(layer "In4.Cu")
		(net "M_E_DQ<15>")
	)
	(segment
		(start 212.902546 -136.220454)
		(end 212.902546 -136.575546)
		(width 0.14224)
		(layer "In4.Cu")
		(net "M_E_DQ<15>")
	)
	(segment
		(start 212.979 -136.652)
		(end 212.979 -138.785346)
		(width 0.14224)
		(layer "In4.Cu")
		(net "M_E_DQ<15>")
	)
	(segment
		(start 213.131146 -130.087878)
		(end 213.131146 -131.140454)
		(width 0.14224)
		(layer "In4.Cu")
		(net "M_E_DQ<15>")
	)
	(segment
		(start 214.79129 -121.552462)
		(end 214.3252 -122.018552)
		(width 0.14224)
		(layer "In4.Cu")
		(net "M_E_DQ<15>")
	)
	(segment
		(start 212.902546 -138.8618)
		(end 212.902546 -139.590272)
		(width 0.14224)
		(layer "In4.Cu")
		(net "M_E_DQ<15>")
	)
	(segment
		(start 217.309954 -119.033798)
		(end 217.091006 -119.033798)
		(width 0.14224)
		(layer "In4.Cu")
		(net "M_E_DQ<15>")
	)
	(segment
		(start 219.818712 -116.237512)
		(end 219.818712 -116.52504)
		(width 0.14224)
		(layer "In4.Cu")
		(net "M_E_DQ<15>")
	)
	(segment
		(start 230.798624 -96.595946)
		(end 230.798624 -96.892872)
		(width 0.0889)
		(layer "In4.Cu")
		(net "M_E_DQ<15>")
	)
	(segment
		(start 216.701878 -118.64467)
		(end 216.48293 -118.64467)
		(width 0.14224)
		(layer "In4.Cu")
		(net "M_E_DQ<15>")
	)
	(segment
		(start 214.799164 -120.191784)
		(end 214.580216 -120.191784)
		(width 0.14224)
		(layer "In4.Cu")
		(net "M_E_DQ<15>")
	)
	(segment
		(start 234.298998 -93.603826)
		(end 233.189018 -94.713806)
		(width 0.0889)
		(layer "In4.Cu")
		(net "M_E_DQ<15>")
	)
	(segment
		(start 212.902546 -136.575546)
		(end 212.979 -136.652)
		(width 0.14224)
		(layer "In4.Cu")
		(net "M_E_DQ<15>")
	)
	(segment
		(start 211.861146 -142.878048)
		(end 211.861146 -143.151352)
		(width 0.14224)
		(layer "In4.Cu")
		(net "M_E_DQ<15>")
	)
	(segment
		(start 212.149944 -143.44015)
		(end 212.149944 -143.763746)
		(width 0.14224)
		(layer "In4.Cu")
		(net "M_E_DQ<15>")
	)
	(segment
		(start 212.099144 -140.3604)
		(end 212.099144 -140.790168)
		(width 0.14224)
		(layer "In4.Cu")
		(net "M_E_DQ<15>")
	)
	(segment
		(start 216.6874 -117.357144)
		(end 216.6874 -117.644672)
		(width 0.14224)
		(layer "In4.Cu")
		(net "M_E_DQ<15>")
	)
	(segment
		(start 234.766612 -93.32849)
		(end 234.57535 -93.32849)
		(width 0.0889)
		(layer "In4.Cu")
		(net "M_E_DQ<15>")
	)
	(segment
		(start 223.6216 -108.876084)
		(end 223.46666 -109.031024)
		(width 0.14224)
		(layer "In4.Cu")
		(net "M_E_DQ<15>")
	)
	(segment
		(start 219.24391 -115.950238)
		(end 219.531438 -115.950238)
		(width 0.14224)
		(layer "In4.Cu")
		(net "M_E_DQ<15>")
	)
	(segment
		(start 216.6874 -117.644672)
		(end 216.974674 -117.931946)
		(width 0.14224)
		(layer "In4.Cu")
		(net "M_E_DQ<15>")
	)
	(segment
		(start 212.979 -138.785346)
		(end 212.902546 -138.8618)
		(width 0.14224)
		(layer "In4.Cu")
		(net "M_E_DQ<15>")
	)
	(segment
		(start 212.527388 -139.932156)
		(end 212.099144 -140.3604)
		(width 0.14224)
		(layer "In4.Cu")
		(net "M_E_DQ<15>")
	)
	(segment
		(start 222.640398 -109.185964)
		(end 222.640398 -109.539024)
		(width 0.14224)
		(layer "In4.Cu")
		(net "M_E_DQ<15>")
	)
	(segment
		(start 228.62159 -99.069906)
		(end 228.62159 -99.893374)
		(width 0.14224)
		(layer "In4.Cu")
		(net "M_E_DQ<15>")
	)
	(segment
		(start 219.531438 -115.950238)
		(end 219.818712 -116.237512)
		(width 0.14224)
		(layer "In4.Cu")
		(net "M_E_DQ<15>")
	)
	(segment
		(start 214.3252 -122.018552)
		(end 214.3252 -127.032512)
		(width 0.14224)
		(layer "In4.Cu")
		(net "M_E_DQ<15>")
	)
	(segment
		(start 223.46666 -109.693964)
		(end 223.6216 -109.848904)
		(width 0.14224)
		(layer "In4.Cu")
		(net "M_E_DQ<15>")
	)
	(segment
		(start 212.143594 -140.834618)
		(end 212.143594 -141.5034)
		(width 0.14224)
		(layer "In4.Cu")
		(net "M_E_DQ<15>")
	)
	(segment
		(start 212.902546 -129.859278)
		(end 213.131146 -130.087878)
		(width 0.14224)
		(layer "In4.Cu")
		(net "M_E_DQ<15>")
	)
	(segment
		(start 214.224362 -120.766586)
		(end 214.79129 -121.333514)
		(width 0.14224)
		(layer "In4.Cu")
		(net "M_E_DQ<15>")
	)
	(segment
		(start 212.891624 -139.590272)
		(end 212.54974 -139.932156)
		(width 0.14224)
		(layer "In4.Cu")
		(net "M_E_DQ<15>")
	)
	(segment
		(start 211.861146 -143.151352)
		(end 212.149944 -143.44015)
		(width 0.14224)
		(layer "In4.Cu")
		(net "M_E_DQ<15>")
	)
	(segment
		(start 213.07171 -134.686802)
		(end 213.07171 -136.05129)
		(width 0.14224)
		(layer "In4.Cu")
		(net "M_E_DQ<15>")
	)
	(segment
		(start 216.127076 -119.000524)
		(end 216.127076 -119.219472)
		(width 0.14224)
		(layer "In4.Cu")
		(net "M_E_DQ<15>")
	)
	(segment
		(start 223.6216 -109.848904)
		(end 223.6216 -110.422944)
		(width 0.14224)
		(layer "In4.Cu")
		(net "M_E_DQ<15>")
	)
	(arc
		(start 235.265468 -92.042488)
		(mid 235.211998 -92.237551)
		(end 235.260642 -92.433902)
		(width 0.0889)
		(layer "In4.Cu")
		(net "M_E_DQ<15>")
	)
	(arc
		(start 235.612178 -91.25204)
		(mid 235.524702 -91.545594)
		(end 235.392722 -91.822016)
		(width 0.0889)
		(layer "In4.Cu")
		(net "M_E_DQ<15>")
	)
	(arc
		(start 235.271818 -92.453206)
		(mid 235.265641 -93.033138)
		(end 234.766612 -93.32849)
		(width 0.0889)
		(layer "In4.Cu")
		(net "M_E_DQ<15>")
	)
	(segment
		(start 212.549994 -146.304)
		(end 212.682074 -146.17192)
		(width 0.1651)
		(layer "F.Cu")
		(net "M_E_DQ<14>")
	)
	(segment
		(start 212.549994 -147.27174)
		(end 212.549994 -146.304)
		(width 0.1651)
		(layer "F.Cu")
		(net "M_E_DQ<14>")
	)
	(segment
		(start 212.682074 -145.95348)
		(end 212.549994 -145.8214)
		(width 0.1651)
		(layer "F.Cu")
		(net "M_E_DQ<14>")
	)
	(segment
		(start 236.183678 -90.26144)
		(end 235.612178 -90.26144)
		(width 0.1651)
		(layer "F.Cu")
		(net "M_E_DQ<14>")
	)
	(segment
		(start 212.549994 -145.516854)
		(end 212.54974 -145.5166)
		(width 0.1651)
		(layer "F.Cu")
		(net "M_E_DQ<14>")
	)
	(segment
		(start 212.550502 -147.27174)
		(end 212.549994 -147.27174)
		(width 0.1651)
		(layer "F.Cu")
		(net "M_E_DQ<14>")
	)
	(segment
		(start 212.682074 -146.17192)
		(end 212.682074 -145.95348)
		(width 0.1651)
		(layer "F.Cu")
		(net "M_E_DQ<14>")
	)
	(segment
		(start 212.549994 -145.8214)
		(end 212.549994 -145.516854)
		(width 0.1651)
		(layer "F.Cu")
		(net "M_E_DQ<14>")
	)
	(via
		(at 212.54974 -145.5166)
		(size 0.508)
		(drill 0.254)
		(layers "F.Cu" "B.Cu")
		(net "M_E_DQ<14>")
	)
	(via
		(at 211.699856 -141.213078)
		(size 0.508)
		(drill 0.254)
		(layers "F.Cu" "B.Cu")
		(net "M_E_DQ<14>")
	)
	(via
		(at 235.612178 -90.26144)
		(size 0.508)
		(drill 0.254)
		(layers "F.Cu" "B.Cu")
		(net "M_E_DQ<14>")
	)
	(segment
		(start 211.700364 -142.477236)
		(end 211.699856 -142.476982)
		(width 0.1651)
		(layer "B.Cu")
		(net "M_E_DQ<14>")
	)
	(segment
		(start 211.699856 -142.476982)
		(end 211.699856 -141.213078)
		(width 0.1651)
		(layer "B.Cu")
		(net "M_E_DQ<14>")
	)
	(segment
		(start 215.305132 -119.593868)
		(end 215.017604 -119.593868)
		(width 0.14224)
		(layer "In4.Cu")
		(net "M_E_DQ<14>")
	)
	(segment
		(start 214.437976 -119.276368)
		(end 213.6902 -120.024144)
		(width 0.14224)
		(layer "In4.Cu")
		(net "M_E_DQ<14>")
	)
	(segment
		(start 234.496356 -93.137736)
		(end 233.110278 -94.523814)
		(width 0.0889)
		(layer "In4.Cu")
		(net "M_E_DQ<14>")
	)
	(segment
		(start 235.100368 -92.537788)
		(end 235.105194 -92.546424)
		(width 0.0889)
		(layer "In4.Cu")
		(net "M_E_DQ<14>")
	)
	(segment
		(start 235.612178 -90.26144)
		(end 235.282232 -91.023186)
		(width 0.0889)
		(layer "In4.Cu")
		(net "M_E_DQ<14>")
	)
	(segment
		(start 215.017604 -119.593868)
		(end 214.700104 -119.276368)
		(width 0.14224)
		(layer "In4.Cu")
		(net "M_E_DQ<14>")
	)
	(segment
		(start 212.216746 -134.492238)
		(end 211.944204 -134.76478)
		(width 0.14224)
		(layer "In4.Cu")
		(net "M_E_DQ<14>")
	)
	(segment
		(start 230.364538 -96.428814)
		(end 228.1428 -98.650552)
		(width 0.14224)
		(layer "In4.Cu")
		(net "M_E_DQ<14>")
	)
	(segment
		(start 214.700104 -119.276368)
		(end 214.437976 -119.276368)
		(width 0.14224)
		(layer "In4.Cu")
		(net "M_E_DQ<14>")
	)
	(segment
		(start 235.094018 -92.52712)
		(end 235.100368 -92.537788)
		(width 0.0889)
		(layer "In4.Cu")
		(net "M_E_DQ<14>")
	)
	(segment
		(start 211.530946 -140.070078)
		(end 211.530946 -141.044168)
		(width 0.14224)
		(layer "In4.Cu")
		(net "M_E_DQ<14>")
	)
	(segment
		(start 219.255848 -112.307878)
		(end 219.517976 -112.307878)
		(width 0.14224)
		(layer "In4.Cu")
		(net "M_E_DQ<14>")
	)
	(segment
		(start 212.1154 -136.677146)
		(end 212.1154 -138.811)
		(width 0.14224)
		(layer "In4.Cu")
		(net "M_E_DQ<14>")
	)
	(segment
		(start 235.227622 -91.726766)
		(end 235.100368 -91.947238)
		(width 0.0889)
		(layer "In4.Cu")
		(net "M_E_DQ<14>")
	)
	(segment
		(start 212.1916 -129.935224)
		(end 211.963 -130.163824)
		(width 0.14224)
		(layer "In4.Cu")
		(net "M_E_DQ<14>")
	)
	(segment
		(start 234.768644 -93.137736)
		(end 234.496356 -93.137736)
		(width 0.0889)
		(layer "In4.Cu")
		(net "M_E_DQ<14>")
	)
	(segment
		(start 219.517976 -112.307878)
		(end 221.636082 -110.189772)
		(width 0.14224)
		(layer "In4.Cu")
		(net "M_E_DQ<14>")
	)
	(segment
		(start 215.274906 -118.701566)
		(end 215.592406 -119.019066)
		(width 0.14224)
		(layer "In4.Cu")
		(net "M_E_DQ<14>")
	)
	(segment
		(start 212.1154 -131.978146)
		(end 212.1154 -134.0358)
		(width 0.14224)
		(layer "In4.Cu")
		(net "M_E_DQ<14>")
	)
	(segment
		(start 211.530946 -141.044168)
		(end 211.699856 -141.213078)
		(width 0.14224)
		(layer "In4.Cu")
		(net "M_E_DQ<14>")
	)
	(segment
		(start 222.210884 -110.935516)
		(end 216.0524 -117.094)
		(width 0.14224)
		(layer "In4.Cu")
		(net "M_E_DQ<14>")
	)
	(segment
		(start 212.1916 -128.267968)
		(end 212.1916 -129.935224)
		(width 0.14224)
		(layer "In4.Cu")
		(net "M_E_DQ<14>")
	)
	(segment
		(start 212.267546 -136.525)
		(end 212.1154 -136.677146)
		(width 0.14224)
		(layer "In4.Cu")
		(net "M_E_DQ<14>")
	)
	(segment
		(start 213.6902 -120.024144)
		(end 213.6902 -126.769368)
		(width 0.14224)
		(layer "In4.Cu")
		(net "M_E_DQ<14>")
	)
	(segment
		(start 215.592406 -119.019066)
		(end 215.592406 -119.306594)
		(width 0.14224)
		(layer "In4.Cu")
		(net "M_E_DQ<14>")
	)
	(segment
		(start 222.210884 -110.477046)
		(end 222.210884 -110.935516)
		(width 0.14224)
		(layer "In4.Cu")
		(net "M_E_DQ<14>")
	)
	(segment
		(start 216.0524 -117.094)
		(end 216.0524 -117.661944)
		(width 0.14224)
		(layer "In4.Cu")
		(net "M_E_DQ<14>")
	)
	(segment
		(start 221.636082 -110.189772)
		(end 221.92361 -110.189772)
		(width 0.14224)
		(layer "In4.Cu")
		(net "M_E_DQ<14>")
	)
	(segment
		(start 211.266786 -144.233646)
		(end 212.54974 -145.5166)
		(width 0.14224)
		(layer "In4.Cu")
		(net "M_E_DQ<14>")
	)
	(segment
		(start 212.216746 -131.459478)
		(end 212.216746 -131.8768)
		(width 0.14224)
		(layer "In4.Cu")
		(net "M_E_DQ<14>")
	)
	(segment
		(start 235.282232 -91.023186)
		(end 235.265468 -91.051888)
		(width 0.0889)
		(layer "In4.Cu")
		(net "M_E_DQ<14>")
	)
	(segment
		(start 222.9358 -107.74045)
		(end 218.968574 -111.707676)
		(width 0.14224)
		(layer "In4.Cu")
		(net "M_E_DQ<14>")
	)
	(segment
		(start 230.697024 -96.428814)
		(end 230.364538 -96.428814)
		(width 0.0889)
		(layer "In4.Cu")
		(net "M_E_DQ<14>")
	)
	(segment
		(start 222.9358 -104.902)
		(end 222.9358 -107.74045)
		(width 0.14224)
		(layer "In4.Cu")
		(net "M_E_DQ<14>")
	)
	(segment
		(start 218.968574 -112.020604)
		(end 219.255848 -112.307878)
		(width 0.14224)
		(layer "In4.Cu")
		(net "M_E_DQ<14>")
	)
	(segment
		(start 216.0524 -117.661944)
		(end 215.274906 -118.439438)
		(width 0.14224)
		(layer "In4.Cu")
		(net "M_E_DQ<14>")
	)
	(segment
		(start 211.266786 -141.646148)
		(end 211.266786 -144.233646)
		(width 0.14224)
		(layer "In4.Cu")
		(net "M_E_DQ<14>")
	)
	(segment
		(start 212.1154 -138.811)
		(end 212.267546 -138.963146)
		(width 0.14224)
		(layer "In4.Cu")
		(net "M_E_DQ<14>")
	)
	(segment
		(start 212.1154 -134.0358)
		(end 212.216746 -134.137146)
		(width 0.14224)
		(layer "In4.Cu")
		(net "M_E_DQ<14>")
	)
	(segment
		(start 211.963 -130.163824)
		(end 211.963 -131.205732)
		(width 0.14224)
		(layer "In4.Cu")
		(net "M_E_DQ<14>")
	)
	(segment
		(start 215.592406 -119.306594)
		(end 215.305132 -119.593868)
		(width 0.14224)
		(layer "In4.Cu")
		(net "M_E_DQ<14>")
	)
	(segment
		(start 213.6902 -126.769368)
		(end 212.1916 -128.267968)
		(width 0.14224)
		(layer "In4.Cu")
		(net "M_E_DQ<14>")
	)
	(segment
		(start 211.699856 -141.213078)
		(end 211.266786 -141.646148)
		(width 0.14224)
		(layer "In4.Cu")
		(net "M_E_DQ<14>")
	)
	(segment
		(start 212.267546 -138.963146)
		(end 212.267546 -139.333478)
		(width 0.14224)
		(layer "In4.Cu")
		(net "M_E_DQ<14>")
	)
	(segment
		(start 211.944204 -135.932926)
		(end 212.267546 -136.256268)
		(width 0.14224)
		(layer "In4.Cu")
		(net "M_E_DQ<14>")
	)
	(segment
		(start 221.92361 -110.189772)
		(end 222.210884 -110.477046)
		(width 0.14224)
		(layer "In4.Cu")
		(net "M_E_DQ<14>")
	)
	(segment
		(start 211.963 -131.205732)
		(end 212.216746 -131.459478)
		(width 0.14224)
		(layer "In4.Cu")
		(net "M_E_DQ<14>")
	)
	(segment
		(start 212.216746 -134.137146)
		(end 212.216746 -134.492238)
		(width 0.14224)
		(layer "In4.Cu")
		(net "M_E_DQ<14>")
	)
	(segment
		(start 212.267546 -136.256268)
		(end 212.267546 -136.525)
		(width 0.14224)
		(layer "In4.Cu")
		(net "M_E_DQ<14>")
	)
	(segment
		(start 232.602024 -94.523814)
		(end 230.697024 -96.428814)
		(width 0.0889)
		(layer "In4.Cu")
		(net "M_E_DQ<14>")
	)
	(segment
		(start 212.267546 -139.333478)
		(end 211.530946 -140.070078)
		(width 0.14224)
		(layer "In4.Cu")
		(net "M_E_DQ<14>")
	)
	(segment
		(start 233.110278 -94.523814)
		(end 232.602024 -94.523814)
		(width 0.0889)
		(layer "In4.Cu")
		(net "M_E_DQ<14>")
	)
	(segment
		(start 218.968574 -111.707676)
		(end 218.968574 -112.020604)
		(width 0.14224)
		(layer "In4.Cu")
		(net "M_E_DQ<14>")
	)
	(segment
		(start 228.1428 -98.650552)
		(end 228.1428 -99.695)
		(width 0.14224)
		(layer "In4.Cu")
		(net "M_E_DQ<14>")
	)
	(segment
		(start 215.274906 -118.439438)
		(end 215.274906 -118.701566)
		(width 0.14224)
		(layer "In4.Cu")
		(net "M_E_DQ<14>")
	)
	(segment
		(start 211.944204 -134.76478)
		(end 211.944204 -135.932926)
		(width 0.14224)
		(layer "In4.Cu")
		(net "M_E_DQ<14>")
	)
	(segment
		(start 228.1428 -99.695)
		(end 222.9358 -104.902)
		(width 0.14224)
		(layer "In4.Cu")
		(net "M_E_DQ<14>")
	)
	(segment
		(start 212.216746 -131.8768)
		(end 212.1154 -131.978146)
		(width 0.14224)
		(layer "In4.Cu")
		(net "M_E_DQ<14>")
	)
	(arc
		(start 235.100368 -91.947238)
		(mid 235.021146 -92.236356)
		(end 235.094018 -92.52712)
		(width 0.0889)
		(layer "In4.Cu")
		(net "M_E_DQ<14>")
	)
	(arc
		(start 235.105194 -92.546424)
		(mid 235.101447 -92.93568)
		(end 234.768644 -93.137736)
		(width 0.0889)
		(layer "In4.Cu")
		(net "M_E_DQ<14>")
	)
	(arc
		(start 235.265468 -91.051888)
		(mid 235.212554 -91.228185)
		(end 235.244132 -91.40952)
		(width 0.0889)
		(layer "In4.Cu")
		(net "M_E_DQ<14>")
	)
	(arc
		(start 235.244132 -91.40952)
		(mid 235.272672 -91.570051)
		(end 235.227622 -91.726766)
		(width 0.0889)
		(layer "In4.Cu")
		(net "M_E_DQ<14>")
	)
	(segment
		(start 205.749906 -142.677642)
		(end 205.749906 -143.941546)
		(width 0.1651)
		(layer "F.Cu")
		(net "M_E_DQ<13>")
	)
	(segment
		(start 205.750414 -142.6718)
		(end 205.749906 -142.677642)
		(width 0.1651)
		(layer "F.Cu")
		(net "M_E_DQ<13>")
	)
	(segment
		(start 237.900718 -88.28024)
		(end 237.329218 -88.28024)
		(width 0.1651)
		(layer "F.Cu")
		(net "M_E_DQ<13>")
	)
	(via
		(at 205.749906 -143.941546)
		(size 0.508)
		(drill 0.254)
		(layers "F.Cu" "B.Cu")
		(net "M_E_DQ<13>")
	)
	(via
		(at 206.52359 -139.932156)
		(size 0.508)
		(drill 0.254)
		(layers "F.Cu" "B.Cu")
		(net "M_E_DQ<13>")
	)
	(via
		(at 237.329218 -88.28024)
		(size 0.508)
		(drill 0.254)
		(layers "F.Cu" "B.Cu")
		(net "M_E_DQ<13>")
	)
	(segment
		(start 206.59979 -137.877296)
		(end 206.59979 -139.855956)
		(width 0.1651)
		(layer "B.Cu")
		(net "M_E_DQ<13>")
	)
	(segment
		(start 206.600298 -137.877296)
		(end 206.59979 -137.877296)
		(width 0.1651)
		(layer "B.Cu")
		(net "M_E_DQ<13>")
	)
	(segment
		(start 206.59979 -139.855956)
		(end 206.52359 -139.932156)
		(width 0.1651)
		(layer "B.Cu")
		(net "M_E_DQ<13>")
	)
	(segment
		(start 206.987394 -133.376162)
		(end 207.283812 -133.376162)
		(width 0.14224)
		(layer "In4.Cu")
		(net "M_E_DQ<13>")
	)
	(segment
		(start 235.597192 -86.88959)
		(end 235.627164 -86.88959)
		(width 0.0889)
		(layer "In4.Cu")
		(net "M_E_DQ<13>")
	)
	(segment
		(start 206.9084 -127.6858)
		(end 209.8548 -124.7394)
		(width 0.14224)
		(layer "In4.Cu")
		(net "M_E_DQ<13>")
	)
	(segment
		(start 206.832454 -133.531102)
		(end 206.987394 -133.376162)
		(width 0.14224)
		(layer "In4.Cu")
		(net "M_E_DQ<13>")
	)
	(segment
		(start 206.9084 -129.03835)
		(end 207.06334 -128.88341)
		(width 0.14224)
		(layer "In4.Cu")
		(net "M_E_DQ<13>")
	)
	(segment
		(start 206.908146 -138.938254)
		(end 207.2894 -138.557)
		(width 0.14224)
		(layer "In4.Cu")
		(net "M_E_DQ<13>")
	)
	(segment
		(start 207.2894 -136.906254)
		(end 206.908146 -136.525)
		(width 0.14224)
		(layer "In4.Cu")
		(net "M_E_DQ<13>")
	)
	(segment
		(start 207.06334 -128.22047)
		(end 206.9084 -128.06553)
		(width 0.14224)
		(layer "In4.Cu")
		(net "M_E_DQ<13>")
	)
	(segment
		(start 207.438752 -132.868162)
		(end 207.283812 -132.713222)
		(width 0.14224)
		(layer "In4.Cu")
		(net "M_E_DQ<13>")
	)
	(segment
		(start 206.199994 -141.0462)
		(end 206.072994 -140.9192)
		(width 0.14224)
		(layer "In4.Cu")
		(net "M_E_DQ<13>")
	)
	(segment
		(start 206.072994 -140.3604)
		(end 206.501238 -139.932156)
		(width 0.14224)
		(layer "In4.Cu")
		(net "M_E_DQ<13>")
	)
	(segment
		(start 206.908146 -136.005824)
		(end 207.060546 -135.853424)
		(width 0.14224)
		(layer "In4.Cu")
		(net "M_E_DQ<13>")
	)
	(segment
		(start 205.911196 -143.297656)
		(end 205.911196 -142.985744)
		(width 0.14224)
		(layer "In4.Cu")
		(net "M_E_DQ<13>")
	)
	(segment
		(start 206.832454 -132.558282)
		(end 206.832454 -131.53517)
		(width 0.14224)
		(layer "In4.Cu")
		(net "M_E_DQ<13>")
	)
	(segment
		(start 205.911196 -142.154656)
		(end 205.911196 -141.817344)
		(width 0.14224)
		(layer "In4.Cu")
		(net "M_E_DQ<13>")
	)
	(segment
		(start 206.149194 -142.747746)
		(end 206.149194 -142.392654)
		(width 0.14224)
		(layer "In4.Cu")
		(net "M_E_DQ<13>")
	)
	(segment
		(start 206.9846 -129.8956)
		(end 206.9084 -129.8194)
		(width 0.14224)
		(layer "In4.Cu")
		(net "M_E_DQ<13>")
	)
	(segment
		(start 234.742482 -87.384636)
		(end 234.775248 -87.384636)
		(width 0.0889)
		(layer "In4.Cu")
		(net "M_E_DQ<13>")
	)
	(segment
		(start 207.445102 -128.22047)
		(end 207.06334 -128.22047)
		(width 0.14224)
		(layer "In4.Cu")
		(net "M_E_DQ<13>")
	)
	(segment
		(start 233.880152 -87.88019)
		(end 233.912918 -87.88019)
		(width 0.0889)
		(layer "In4.Cu")
		(net "M_E_DQ<13>")
	)
	(segment
		(start 231.547416 -89.17686)
		(end 231.853486 -88.87079)
		(width 0.0889)
		(layer "In4.Cu")
		(net "M_E_DQ<13>")
	)
	(segment
		(start 206.022194 -143.941546)
		(end 206.174594 -143.789146)
		(width 0.14224)
		(layer "In4.Cu")
		(net "M_E_DQ<13>")
	)
	(segment
		(start 233.025442 -88.375236)
		(end 233.058208 -88.375236)
		(width 0.0889)
		(layer "In4.Cu")
		(net "M_E_DQ<13>")
	)
	(segment
		(start 207.283812 -132.713222)
		(end 206.987394 -132.713222)
		(width 0.14224)
		(layer "In4.Cu")
		(net "M_E_DQ<13>")
	)
	(segment
		(start 205.911196 -141.817344)
		(end 206.199994 -141.528546)
		(width 0.14224)
		(layer "In4.Cu")
		(net "M_E_DQ<13>")
	)
	(segment
		(start 207.600042 -128.72847)
		(end 207.600042 -128.37541)
		(width 0.14224)
		(layer "In4.Cu")
		(net "M_E_DQ<13>")
	)
	(segment
		(start 206.908146 -136.525)
		(end 206.908146 -136.005824)
		(width 0.14224)
		(layer "In4.Cu")
		(net "M_E_DQ<13>")
	)
	(segment
		(start 224.78619 -98.658934)
		(end 224.78619 -96.567498)
		(width 0.14224)
		(layer "In4.Cu")
		(net "M_E_DQ<13>")
	)
	(segment
		(start 206.832454 -131.53517)
		(end 206.9846 -131.383024)
		(width 0.14224)
		(layer "In4.Cu")
		(net "M_E_DQ<13>")
	)
	(segment
		(start 206.174594 -143.561054)
		(end 205.911196 -143.297656)
		(width 0.14224)
		(layer "In4.Cu")
		(net "M_E_DQ<13>")
	)
	(segment
		(start 209.8548 -114.8588)
		(end 218.63939 -106.07421)
		(width 0.14224)
		(layer "In4.Cu")
		(net "M_E_DQ<13>")
	)
	(segment
		(start 207.060546 -134.797038)
		(end 206.832454 -134.568946)
		(width 0.14224)
		(layer "In4.Cu")
		(net "M_E_DQ<13>")
	)
	(segment
		(start 206.9084 -129.8194)
		(end 206.9084 -129.03835)
		(width 0.14224)
		(layer "In4.Cu")
		(net "M_E_DQ<13>")
	)
	(segment
		(start 206.501238 -139.932156)
		(end 206.52359 -139.932156)
		(width 0.14224)
		(layer "In4.Cu")
		(net "M_E_DQ<13>")
	)
	(segment
		(start 224.78619 -96.567498)
		(end 230.265224 -91.088464)
		(width 0.14224)
		(layer "In4.Cu")
		(net "M_E_DQ<13>")
	)
	(segment
		(start 231.547416 -89.522554)
		(end 231.547416 -89.17686)
		(width 0.0889)
		(layer "In4.Cu")
		(net "M_E_DQ<13>")
	)
	(segment
		(start 206.987394 -132.713222)
		(end 206.832454 -132.558282)
		(width 0.14224)
		(layer "In4.Cu")
		(net "M_E_DQ<13>")
	)
	(segment
		(start 236.940344 -87.734394)
		(end 237.329218 -88.28024)
		(width 0.0889)
		(layer "In4.Cu")
		(net "M_E_DQ<13>")
	)
	(segment
		(start 206.832454 -134.568946)
		(end 206.832454 -133.531102)
		(width 0.14224)
		(layer "In4.Cu")
		(net "M_E_DQ<13>")
	)
	(segment
		(start 205.911196 -142.985744)
		(end 206.149194 -142.747746)
		(width 0.14224)
		(layer "In4.Cu")
		(net "M_E_DQ<13>")
	)
	(segment
		(start 207.600042 -128.37541)
		(end 207.445102 -128.22047)
		(width 0.14224)
		(layer "In4.Cu")
		(net "M_E_DQ<13>")
	)
	(segment
		(start 230.265224 -91.088464)
		(end 230.265224 -90.804746)
		(width 0.0889)
		(layer "In4.Cu")
		(net "M_E_DQ<13>")
	)
	(segment
		(start 209.8548 -124.7394)
		(end 209.8548 -114.8588)
		(width 0.14224)
		(layer "In4.Cu")
		(net "M_E_DQ<13>")
	)
	(segment
		(start 206.072994 -140.9192)
		(end 206.072994 -140.3604)
		(width 0.14224)
		(layer "In4.Cu")
		(net "M_E_DQ<13>")
	)
	(segment
		(start 207.060546 -135.853424)
		(end 207.060546 -134.797038)
		(width 0.14224)
		(layer "In4.Cu")
		(net "M_E_DQ<13>")
	)
	(segment
		(start 207.283812 -133.376162)
		(end 207.438752 -133.221222)
		(width 0.14224)
		(layer "In4.Cu")
		(net "M_E_DQ<13>")
	)
	(segment
		(start 206.199994 -141.528546)
		(end 206.199994 -141.0462)
		(width 0.14224)
		(layer "In4.Cu")
		(net "M_E_DQ<13>")
	)
	(segment
		(start 206.9846 -131.383024)
		(end 206.9846 -129.8956)
		(width 0.14224)
		(layer "In4.Cu")
		(net "M_E_DQ<13>")
	)
	(segment
		(start 218.63939 -106.07421)
		(end 218.63939 -104.805734)
		(width 0.14224)
		(layer "In4.Cu")
		(net "M_E_DQ<13>")
	)
	(segment
		(start 206.52359 -139.932156)
		(end 206.908146 -139.5476)
		(width 0.14224)
		(layer "In4.Cu")
		(net "M_E_DQ<13>")
	)
	(segment
		(start 206.908146 -139.5476)
		(end 206.908146 -138.938254)
		(width 0.14224)
		(layer "In4.Cu")
		(net "M_E_DQ<13>")
	)
	(segment
		(start 206.149194 -142.392654)
		(end 205.911196 -142.154656)
		(width 0.14224)
		(layer "In4.Cu")
		(net "M_E_DQ<13>")
	)
	(segment
		(start 207.06334 -128.88341)
		(end 207.445102 -128.88341)
		(width 0.14224)
		(layer "In4.Cu")
		(net "M_E_DQ<13>")
	)
	(segment
		(start 231.853486 -88.87079)
		(end 232.195878 -88.87079)
		(width 0.0889)
		(layer "In4.Cu")
		(net "M_E_DQ<13>")
	)
	(segment
		(start 230.265224 -90.804746)
		(end 231.547416 -89.522554)
		(width 0.0889)
		(layer "In4.Cu")
		(net "M_E_DQ<13>")
	)
	(segment
		(start 206.174594 -143.789146)
		(end 206.174594 -143.561054)
		(width 0.14224)
		(layer "In4.Cu")
		(net "M_E_DQ<13>")
	)
	(segment
		(start 205.749906 -143.941546)
		(end 206.022194 -143.941546)
		(width 0.14224)
		(layer "In4.Cu")
		(net "M_E_DQ<13>")
	)
	(segment
		(start 206.9084 -128.06553)
		(end 206.9084 -127.6858)
		(width 0.14224)
		(layer "In4.Cu")
		(net "M_E_DQ<13>")
	)
	(segment
		(start 236.449108 -87.384636)
		(end 236.481874 -87.384636)
		(width 0.0889)
		(layer "In4.Cu")
		(net "M_E_DQ<13>")
	)
	(segment
		(start 207.445102 -128.88341)
		(end 207.600042 -128.72847)
		(width 0.14224)
		(layer "In4.Cu")
		(net "M_E_DQ<13>")
	)
	(segment
		(start 218.63939 -104.805734)
		(end 224.78619 -98.658934)
		(width 0.14224)
		(layer "In4.Cu")
		(net "M_E_DQ<13>")
	)
	(segment
		(start 207.2894 -138.557)
		(end 207.2894 -136.906254)
		(width 0.14224)
		(layer "In4.Cu")
		(net "M_E_DQ<13>")
	)
	(segment
		(start 207.438752 -133.221222)
		(end 207.438752 -132.868162)
		(width 0.14224)
		(layer "In4.Cu")
		(net "M_E_DQ<13>")
	)
	(arc
		(start 232.195878 -88.87079)
		(mid 232.481302 -88.787323)
		(end 232.689908 -88.575388)
		(width 0.0889)
		(layer "In4.Cu")
		(net "M_E_DQ<13>")
	)
	(arc
		(start 236.817408 -87.584788)
		(mid 236.872695 -87.664672)
		(end 236.940344 -87.734394)
		(width 0.0889)
		(layer "In4.Cu")
		(net "M_E_DQ<13>")
	)
	(arc
		(start 233.548428 -88.080088)
		(mid 233.688507 -87.937352)
		(end 233.880152 -87.88019)
		(width 0.0889)
		(layer "In4.Cu")
		(net "M_E_DQ<13>")
	)
	(arc
		(start 236.481874 -87.384636)
		(mid 236.675724 -87.440986)
		(end 236.817408 -87.584788)
		(width 0.0889)
		(layer "In4.Cu")
		(net "M_E_DQ<13>")
	)
	(arc
		(start 235.265468 -87.089488)
		(mid 235.405547 -86.946752)
		(end 235.597192 -86.88959)
		(width 0.0889)
		(layer "In4.Cu")
		(net "M_E_DQ<13>")
	)
	(arc
		(start 235.627164 -86.88959)
		(mid 235.818806 -86.946756)
		(end 235.958888 -87.089488)
		(width 0.0889)
		(layer "In4.Cu")
		(net "M_E_DQ<13>")
	)
	(arc
		(start 233.912918 -87.88019)
		(mid 234.198342 -87.796723)
		(end 234.406948 -87.584788)
		(width 0.0889)
		(layer "In4.Cu")
		(net "M_E_DQ<13>")
	)
	(arc
		(start 233.058208 -88.375236)
		(mid 233.341425 -88.290955)
		(end 233.548428 -88.080088)
		(width 0.0889)
		(layer "In4.Cu")
		(net "M_E_DQ<13>")
	)
	(arc
		(start 232.689908 -88.575388)
		(mid 232.831591 -88.431584)
		(end 233.025442 -88.375236)
		(width 0.0889)
		(layer "In4.Cu")
		(net "M_E_DQ<13>")
	)
	(arc
		(start 234.775248 -87.384636)
		(mid 235.058465 -87.300355)
		(end 235.265468 -87.089488)
		(width 0.0889)
		(layer "In4.Cu")
		(net "M_E_DQ<13>")
	)
	(arc
		(start 235.958888 -87.089488)
		(mid 236.165892 -87.300352)
		(end 236.449108 -87.384636)
		(width 0.0889)
		(layer "In4.Cu")
		(net "M_E_DQ<13>")
	)
	(arc
		(start 234.406948 -87.584788)
		(mid 234.548631 -87.440984)
		(end 234.742482 -87.384636)
		(width 0.0889)
		(layer "In4.Cu")
		(net "M_E_DQ<13>")
	)
	(segment
		(start 206.600298 -147.27174)
		(end 206.59979 -147.27174)
		(width 0.1651)
		(layer "F.Cu")
		(net "M_E_DQ<12>")
	)
	(segment
		(start 206.59979 -145.946368)
		(end 206.501746 -145.415)
		(width 0.1651)
		(layer "F.Cu")
		(net "M_E_DQ<12>")
	)
	(segment
		(start 238.759238 -88.775286)
		(end 238.187738 -88.775286)
		(width 0.1651)
		(layer "F.Cu")
		(net "M_E_DQ<12>")
	)
	(segment
		(start 206.59979 -147.27174)
		(end 206.59979 -145.946368)
		(width 0.1651)
		(layer "F.Cu")
		(net "M_E_DQ<12>")
	)
	(via
		(at 206.501746 -145.415)
		(size 0.508)
		(drill 0.254)
		(layers "F.Cu" "B.Cu")
		(net "M_E_DQ<12>")
	)
	(via
		(at 238.187738 -88.775286)
		(size 0.508)
		(drill 0.254)
		(layers "F.Cu" "B.Cu")
		(net "M_E_DQ<12>")
	)
	(via
		(at 205.749906 -141.213078)
		(size 0.508)
		(drill 0.254)
		(layers "F.Cu" "B.Cu")
		(net "M_E_DQ<12>")
	)
	(segment
		(start 205.749906 -142.476982)
		(end 205.749906 -141.213078)
		(width 0.1651)
		(layer "B.Cu")
		(net "M_E_DQ<12>")
	)
	(segment
		(start 205.750414 -142.477236)
		(end 205.749906 -142.476982)
		(width 0.1651)
		(layer "B.Cu")
		(net "M_E_DQ<12>")
	)
	(segment
		(start 233.906314 -87.68969)
		(end 233.873548 -87.68969)
		(width 0.0889)
		(layer "In4.Cu")
		(net "M_E_DQ<12>")
	)
	(segment
		(start 206.064358 -129.941066)
		(end 206.064358 -131.249166)
		(width 0.14224)
		(layer "In4.Cu")
		(net "M_E_DQ<12>")
	)
	(segment
		(start 233.051604 -88.184736)
		(end 233.018838 -88.184736)
		(width 0.0889)
		(layer "In4.Cu")
		(net "M_E_DQ<12>")
	)
	(segment
		(start 206.064358 -131.249166)
		(end 206.247746 -131.432554)
		(width 0.14224)
		(layer "In4.Cu")
		(net "M_E_DQ<12>")
	)
	(segment
		(start 206.0575 -136.002522)
		(end 206.235046 -136.180068)
		(width 0.14224)
		(layer "In4.Cu")
		(net "M_E_DQ<12>")
	)
	(segment
		(start 235.633768 -86.69909)
		(end 235.590588 -86.69909)
		(width 0.0889)
		(layer "In4.Cu")
		(net "M_E_DQ<12>")
	)
	(segment
		(start 206.0575 -134.6581)
		(end 206.0575 -136.002522)
		(width 0.14224)
		(layer "In4.Cu")
		(net "M_E_DQ<12>")
	)
	(segment
		(start 234.768644 -87.194136)
		(end 234.735878 -87.194136)
		(width 0.0889)
		(layer "In4.Cu")
		(net "M_E_DQ<12>")
	)
	(segment
		(start 230.189024 -90.612214)
		(end 229.84333 -90.612214)
		(width 0.0889)
		(layer "In4.Cu")
		(net "M_E_DQ<12>")
	)
	(segment
		(start 224.3074 -95.9358)
		(end 224.3074 -98.46056)
		(width 0.14224)
		(layer "In4.Cu")
		(net "M_E_DQ<12>")
	)
	(segment
		(start 218.1606 -104.60736)
		(end 218.1606 -105.8672)
		(width 0.14224)
		(layer "In4.Cu")
		(net "M_E_DQ<12>")
	)
	(segment
		(start 206.300324 -127.303276)
		(end 206.300324 -129.7051)
		(width 0.14224)
		(layer "In4.Cu")
		(net "M_E_DQ<12>")
	)
	(segment
		(start 209.1944 -124.4092)
		(end 206.300324 -127.303276)
		(width 0.14224)
		(layer "In4.Cu")
		(net "M_E_DQ<12>")
	)
	(segment
		(start 206.250794 -145.415)
		(end 206.501746 -145.415)
		(width 0.14224)
		(layer "In4.Cu")
		(net "M_E_DQ<12>")
	)
	(segment
		(start 206.247746 -131.432554)
		(end 206.247746 -134.467854)
		(width 0.14224)
		(layer "In4.Cu")
		(net "M_E_DQ<12>")
	)
	(segment
		(start 209.1944 -114.8334)
		(end 209.1944 -124.4092)
		(width 0.14224)
		(layer "In4.Cu")
		(net "M_E_DQ<12>")
	)
	(segment
		(start 224.3074 -98.46056)
		(end 218.1606 -104.60736)
		(width 0.14224)
		(layer "In4.Cu")
		(net "M_E_DQ<12>")
	)
	(segment
		(start 231.357424 -89.09812)
		(end 231.357424 -89.443814)
		(width 0.0889)
		(layer "In4.Cu")
		(net "M_E_DQ<12>")
	)
	(segment
		(start 206.247746 -134.467854)
		(end 206.0575 -134.6581)
		(width 0.14224)
		(layer "In4.Cu")
		(net "M_E_DQ<12>")
	)
	(segment
		(start 237.350808 -87.68969)
		(end 237.318042 -87.68969)
		(width 0.0889)
		(layer "In4.Cu")
		(net "M_E_DQ<12>")
	)
	(segment
		(start 218.1606 -105.8672)
		(end 209.1944 -114.8334)
		(width 0.14224)
		(layer "In4.Cu")
		(net "M_E_DQ<12>")
	)
	(segment
		(start 205.653386 -139.940538)
		(end 205.653386 -141.116558)
		(width 0.14224)
		(layer "In4.Cu")
		(net "M_E_DQ<12>")
	)
	(segment
		(start 205.474824 -144.337278)
		(end 205.474824 -144.63903)
		(width 0.14224)
		(layer "In4.Cu")
		(net "M_E_DQ<12>")
	)
	(segment
		(start 231.357424 -89.443814)
		(end 230.189024 -90.612214)
		(width 0.0889)
		(layer "In4.Cu")
		(net "M_E_DQ<12>")
	)
	(segment
		(start 229.117144 -91.3384)
		(end 228.9048 -91.3384)
		(width 0.14224)
		(layer "In4.Cu")
		(net "M_E_DQ<12>")
	)
	(segment
		(start 205.316836 -141.646148)
		(end 205.316836 -144.17929)
		(width 0.14224)
		(layer "In4.Cu")
		(net "M_E_DQ<12>")
	)
	(segment
		(start 206.300324 -129.7051)
		(end 206.064358 -129.941066)
		(width 0.14224)
		(layer "In4.Cu")
		(net "M_E_DQ<12>")
	)
	(segment
		(start 229.84333 -90.612214)
		(end 229.117144 -91.3384)
		(width 0.14224)
		(layer "In4.Cu")
		(net "M_E_DQ<12>")
	)
	(segment
		(start 232.189274 -88.68029)
		(end 231.775254 -88.68029)
		(width 0.0889)
		(layer "In4.Cu")
		(net "M_E_DQ<12>")
	)
	(segment
		(start 228.9048 -91.3384)
		(end 224.3074 -95.9358)
		(width 0.14224)
		(layer "In4.Cu")
		(net "M_E_DQ<12>")
	)
	(segment
		(start 206.235046 -136.180068)
		(end 206.235046 -139.358878)
		(width 0.14224)
		(layer "In4.Cu")
		(net "M_E_DQ<12>")
	)
	(segment
		(start 205.749906 -141.213078)
		(end 205.316836 -141.646148)
		(width 0.14224)
		(layer "In4.Cu")
		(net "M_E_DQ<12>")
	)
	(segment
		(start 206.235046 -139.358878)
		(end 205.653386 -139.940538)
		(width 0.14224)
		(layer "In4.Cu")
		(net "M_E_DQ<12>")
	)
	(segment
		(start 205.474824 -144.63903)
		(end 206.250794 -145.415)
		(width 0.14224)
		(layer "In4.Cu")
		(net "M_E_DQ<12>")
	)
	(segment
		(start 236.488478 -87.194136)
		(end 236.455712 -87.194136)
		(width 0.0889)
		(layer "In4.Cu")
		(net "M_E_DQ<12>")
	)
	(segment
		(start 205.653386 -141.116558)
		(end 205.749906 -141.213078)
		(width 0.14224)
		(layer "In4.Cu")
		(net "M_E_DQ<12>")
	)
	(segment
		(start 238.187738 -88.775286)
		(end 237.841028 -87.984838)
		(width 0.0889)
		(layer "In4.Cu")
		(net "M_E_DQ<12>")
	)
	(segment
		(start 205.316836 -144.17929)
		(end 205.474824 -144.337278)
		(width 0.14224)
		(layer "In4.Cu")
		(net "M_E_DQ<12>")
	)
	(segment
		(start 231.775254 -88.68029)
		(end 231.357424 -89.09812)
		(width 0.0889)
		(layer "In4.Cu")
		(net "M_E_DQ<12>")
	)
	(arc
		(start 233.873548 -87.68969)
		(mid 233.590331 -87.773971)
		(end 233.383328 -87.984838)
		(width 0.0889)
		(layer "In4.Cu")
		(net "M_E_DQ<12>")
	)
	(arc
		(start 233.383328 -87.984838)
		(mid 233.243249 -88.127574)
		(end 233.051604 -88.184736)
		(width 0.0889)
		(layer "In4.Cu")
		(net "M_E_DQ<12>")
	)
	(arc
		(start 236.123988 -86.994238)
		(mid 235.916984 -86.783374)
		(end 235.633768 -86.69909)
		(width 0.0889)
		(layer "In4.Cu")
		(net "M_E_DQ<12>")
	)
	(arc
		(start 237.841028 -87.984838)
		(mid 237.634024 -87.773974)
		(end 237.350808 -87.68969)
		(width 0.0889)
		(layer "In4.Cu")
		(net "M_E_DQ<12>")
	)
	(arc
		(start 237.318042 -87.68969)
		(mid 237.124192 -87.63334)
		(end 236.982508 -87.489538)
		(width 0.0889)
		(layer "In4.Cu")
		(net "M_E_DQ<12>")
	)
	(arc
		(start 236.455712 -87.194136)
		(mid 236.26407 -87.13697)
		(end 236.123988 -86.994238)
		(width 0.0889)
		(layer "In4.Cu")
		(net "M_E_DQ<12>")
	)
	(arc
		(start 232.524808 -88.480138)
		(mid 232.383125 -88.623942)
		(end 232.189274 -88.68029)
		(width 0.0889)
		(layer "In4.Cu")
		(net "M_E_DQ<12>")
	)
	(arc
		(start 233.018838 -88.184736)
		(mid 232.733414 -88.268203)
		(end 232.524808 -88.480138)
		(width 0.0889)
		(layer "In4.Cu")
		(net "M_E_DQ<12>")
	)
	(arc
		(start 234.241848 -87.489538)
		(mid 234.100165 -87.633342)
		(end 233.906314 -87.68969)
		(width 0.0889)
		(layer "In4.Cu")
		(net "M_E_DQ<12>")
	)
	(arc
		(start 235.590588 -86.69909)
		(mid 235.307371 -86.783371)
		(end 235.100368 -86.994238)
		(width 0.0889)
		(layer "In4.Cu")
		(net "M_E_DQ<12>")
	)
	(arc
		(start 234.735878 -87.194136)
		(mid 234.450454 -87.277603)
		(end 234.241848 -87.489538)
		(width 0.0889)
		(layer "In4.Cu")
		(net "M_E_DQ<12>")
	)
	(arc
		(start 236.982508 -87.489538)
		(mid 236.7739 -87.277606)
		(end 236.488478 -87.194136)
		(width 0.0889)
		(layer "In4.Cu")
		(net "M_E_DQ<12>")
	)
	(arc
		(start 235.100368 -86.994238)
		(mid 234.960289 -87.136974)
		(end 234.768644 -87.194136)
		(width 0.0889)
		(layer "In4.Cu")
		(net "M_E_DQ<12>")
	)
	(segment
		(start 237.042198 -91.747086)
		(end 236.470698 -91.747086)
		(width 0.1651)
		(layer "F.Cu")
		(net "M_E_DQ<11>")
	)
	(segment
		(start 213.399878 -142.677642)
		(end 213.399878 -143.941546)
		(width 0.1651)
		(layer "F.Cu")
		(net "M_E_DQ<11>")
	)
	(segment
		(start 213.400386 -142.6718)
		(end 213.399878 -142.677642)
		(width 0.1651)
		(layer "F.Cu")
		(net "M_E_DQ<11>")
	)
	(via
		(at 214.249762 -139.932156)
		(size 0.508)
		(drill 0.254)
		(layers "F.Cu" "B.Cu")
		(net "M_E_DQ<11>")
	)
	(via
		(at 213.399878 -143.941546)
		(size 0.508)
		(drill 0.254)
		(layers "F.Cu" "B.Cu")
		(net "M_E_DQ<11>")
	)
	(via
		(at 236.470698 -91.747086)
		(size 0.508)
		(drill 0.254)
		(layers "F.Cu" "B.Cu")
		(net "M_E_DQ<11>")
	)
	(segment
		(start 214.250524 -137.877296)
		(end 214.249762 -137.877296)
		(width 0.1651)
		(layer "B.Cu")
		(net "M_E_DQ<11>")
	)
	(segment
		(start 214.249762 -137.877296)
		(end 214.249762 -139.932156)
		(width 0.1651)
		(layer "B.Cu")
		(net "M_E_DQ<11>")
	)
	(segment
		(start 231.3686 -98.8822)
		(end 225.8822 -104.3686)
		(width 0.14224)
		(layer "In4.Cu")
		(net "M_E_DQ<11>")
	)
	(segment
		(start 225.72726 -105.687368)
		(end 225.8822 -105.842308)
		(width 0.14224)
		(layer "In4.Cu")
		(net "M_E_DQ<11>")
	)
	(segment
		(start 236.470698 -91.747086)
		(end 236.14126 -92.50807)
		(width 0.0889)
		(layer "In4.Cu")
		(net "M_E_DQ<11>")
	)
	(segment
		(start 214.617046 -131.9022)
		(end 214.6808 -131.965954)
		(width 0.14224)
		(layer "In4.Cu")
		(net "M_E_DQ<11>")
	)
	(segment
		(start 225.8822 -110.171738)
		(end 223.118426 -112.935512)
		(width 0.14224)
		(layer "In4.Cu")
		(net "M_E_DQ<11>")
	)
	(segment
		(start 213.843616 -141.5034)
		(end 213.561168 -141.785848)
		(width 0.14224)
		(layer "In4.Cu")
		(net "M_E_DQ<11>")
	)
	(segment
		(start 215.9762 -125.042422)
		(end 216.1794 -125.245622)
		(width 0.14224)
		(layer "In4.Cu")
		(net "M_E_DQ<11>")
	)
	(segment
		(start 214.617046 -131.305554)
		(end 214.617046 -131.9022)
		(width 0.14224)
		(layer "In4.Cu")
		(net "M_E_DQ<11>")
	)
	(segment
		(start 214.5792 -128.5748)
		(end 214.5792 -129.935732)
		(width 0.14224)
		(layer "In4.Cu")
		(net "M_E_DQ<11>")
	)
	(segment
		(start 225.673412 -111.817658)
		(end 225.960686 -112.104932)
		(width 0.14224)
		(layer "In4.Cu")
		(net "M_E_DQ<11>")
	)
	(segment
		(start 223.693228 -113.510314)
		(end 225.385884 -111.817658)
		(width 0.14224)
		(layer "In4.Cu")
		(net "M_E_DQ<11>")
	)
	(segment
		(start 236.123988 -93.928438)
		(end 236.130338 -93.939106)
		(width 0.0889)
		(layer "In4.Cu")
		(net "M_E_DQ<11>")
	)
	(segment
		(start 216.1794 -122.173746)
		(end 216.1794 -122.400822)
		(width 0.14224)
		(layer "In4.Cu")
		(net "M_E_DQ<11>")
	)
	(segment
		(start 213.561168 -142.878048)
		(end 213.561168 -143.151352)
		(width 0.14224)
		(layer "In4.Cu")
		(net "M_E_DQ<11>")
	)
	(segment
		(start 214.22741 -139.932156)
		(end 213.799166 -140.3604)
		(width 0.14224)
		(layer "In4.Cu")
		(net "M_E_DQ<11>")
	)
	(segment
		(start 225.8822 -105.842308)
		(end 225.8822 -106.195368)
		(width 0.14224)
		(layer "In4.Cu")
		(net "M_E_DQ<11>")
	)
	(segment
		(start 225.8822 -104.3686)
		(end 225.8822 -104.869488)
		(width 0.14224)
		(layer "In4.Cu")
		(net "M_E_DQ<11>")
	)
	(segment
		(start 214.6808 -134.0612)
		(end 214.617046 -134.124954)
		(width 0.14224)
		(layer "In4.Cu")
		(net "M_E_DQ<11>")
	)
	(segment
		(start 215.37295 -126.014734)
		(end 215.37295 -126.421134)
		(width 0.14224)
		(layer "In4.Cu")
		(net "M_E_DQ<11>")
	)
	(segment
		(start 224.930716 -106.858308)
		(end 225.085656 -107.013248)
		(width 0.14224)
		(layer "In4.Cu")
		(net "M_E_DQ<11>")
	)
	(segment
		(start 215.676988 -124.229622)
		(end 215.473788 -124.432822)
		(width 0.14224)
		(layer "In4.Cu")
		(net "M_E_DQ<11>")
	)
	(segment
		(start 213.818216 -142.3162)
		(end 213.818216 -142.621)
		(width 0.14224)
		(layer "In4.Cu")
		(net "M_E_DQ<11>")
	)
	(segment
		(start 215.55202 -126.600204)
		(end 215.932258 -126.600204)
		(width 0.14224)
		(layer "In4.Cu")
		(net "M_E_DQ<11>")
	)
	(segment
		(start 225.8822 -107.168188)
		(end 225.8822 -110.171738)
		(width 0.14224)
		(layer "In4.Cu")
		(net "M_E_DQ<11>")
	)
	(segment
		(start 215.676988 -125.042422)
		(end 215.9762 -125.042422)
		(width 0.14224)
		(layer "In4.Cu")
		(net "M_E_DQ<11>")
	)
	(segment
		(start 213.799166 -140.3604)
		(end 213.799166 -140.790168)
		(width 0.14224)
		(layer "In4.Cu")
		(net "M_E_DQ<11>")
	)
	(segment
		(start 223.4057 -113.510314)
		(end 223.693228 -113.510314)
		(width 0.14224)
		(layer "In4.Cu")
		(net "M_E_DQ<11>")
	)
	(segment
		(start 213.561168 -142.059152)
		(end 213.818216 -142.3162)
		(width 0.14224)
		(layer "In4.Cu")
		(net "M_E_DQ<11>")
	)
	(segment
		(start 216.1794 -125.652022)
		(end 215.9762 -125.855222)
		(width 0.14224)
		(layer "In4.Cu")
		(net "M_E_DQ<11>")
	)
	(segment
		(start 225.8822 -104.869488)
		(end 225.72726 -105.024428)
		(width 0.14224)
		(layer "In4.Cu")
		(net "M_E_DQ<11>")
	)
	(segment
		(start 215.9762 -123.416822)
		(end 216.1794 -123.620022)
		(width 0.14224)
		(layer "In4.Cu")
		(net "M_E_DQ<11>")
	)
	(segment
		(start 215.9762 -124.229622)
		(end 215.676988 -124.229622)
		(width 0.14224)
		(layer "In4.Cu")
		(net "M_E_DQ<11>")
	)
	(segment
		(start 216.07018 -126.738126)
		(end 216.07018 -127.08382)
		(width 0.14224)
		(layer "In4.Cu")
		(net "M_E_DQ<11>")
	)
	(segment
		(start 214.756746 -131.165854)
		(end 214.617046 -131.305554)
		(width 0.14224)
		(layer "In4.Cu")
		(net "M_E_DQ<11>")
	)
	(segment
		(start 214.617046 -134.124954)
		(end 214.617046 -134.543038)
		(width 0.14224)
		(layer "In4.Cu")
		(net "M_E_DQ<11>")
	)
	(segment
		(start 236.14126 -92.50807)
		(end 236.119162 -92.546424)
		(width 0.0889)
		(layer "In4.Cu")
		(net "M_E_DQ<11>")
	)
	(segment
		(start 214.832946 -134.758938)
		(end 214.832946 -135.966708)
		(width 0.14224)
		(layer "In4.Cu")
		(net "M_E_DQ<11>")
	)
	(segment
		(start 214.617046 -134.543038)
		(end 214.832946 -134.758938)
		(width 0.14224)
		(layer "In4.Cu")
		(net "M_E_DQ<11>")
	)
	(segment
		(start 215.9762 -125.855222)
		(end 215.532462 -125.855222)
		(width 0.14224)
		(layer "In4.Cu")
		(net "M_E_DQ<11>")
	)
	(segment
		(start 216.1794 -123.620022)
		(end 216.1794 -124.026422)
		(width 0.14224)
		(layer "In4.Cu")
		(net "M_E_DQ<11>")
	)
	(segment
		(start 215.663526 -122.604022)
		(end 215.453722 -122.813826)
		(width 0.14224)
		(layer "In4.Cu")
		(net "M_E_DQ<11>")
	)
	(segment
		(start 213.843616 -140.834618)
		(end 213.843616 -141.5034)
		(width 0.14224)
		(layer "In4.Cu")
		(net "M_E_DQ<11>")
	)
	(segment
		(start 225.085656 -107.013248)
		(end 225.72726 -107.013248)
		(width 0.14224)
		(layer "In4.Cu")
		(net "M_E_DQ<11>")
	)
	(segment
		(start 235.625132 -94.81439)
		(end 235.597192 -94.81439)
		(width 0.0889)
		(layer "In4.Cu")
		(net "M_E_DQ<11>")
	)
	(segment
		(start 215.9762 -122.604022)
		(end 215.663526 -122.604022)
		(width 0.14224)
		(layer "In4.Cu")
		(net "M_E_DQ<11>")
	)
	(segment
		(start 215.453722 -123.220226)
		(end 215.650318 -123.416822)
		(width 0.14224)
		(layer "In4.Cu")
		(net "M_E_DQ<11>")
	)
	(segment
		(start 232.299764 -96.771206)
		(end 232.299764 -97.193608)
		(width 0.0889)
		(layer "In4.Cu")
		(net "M_E_DQ<11>")
	)
	(segment
		(start 223.118426 -113.22304)
		(end 223.4057 -113.510314)
		(width 0.14224)
		(layer "In4.Cu")
		(net "M_E_DQ<11>")
	)
	(segment
		(start 224.930716 -105.532428)
		(end 225.085656 -105.687368)
		(width 0.14224)
		(layer "In4.Cu")
		(net "M_E_DQ<11>")
	)
	(segment
		(start 225.085656 -105.687368)
		(end 225.72726 -105.687368)
		(width 0.14224)
		(layer "In4.Cu")
		(net "M_E_DQ<11>")
	)
	(segment
		(start 232.299764 -97.193608)
		(end 231.3686 -98.124772)
		(width 0.14224)
		(layer "In4.Cu")
		(net "M_E_DQ<11>")
	)
	(segment
		(start 213.849966 -143.44015)
		(end 213.849966 -143.763746)
		(width 0.14224)
		(layer "In4.Cu")
		(net "M_E_DQ<11>")
	)
	(segment
		(start 213.561168 -143.151352)
		(end 213.849966 -143.44015)
		(width 0.14224)
		(layer "In4.Cu")
		(net "M_E_DQ<11>")
	)
	(segment
		(start 215.453722 -122.813826)
		(end 215.453722 -123.220226)
		(width 0.14224)
		(layer "In4.Cu")
		(net "M_E_DQ<11>")
	)
	(segment
		(start 225.960686 -112.39246)
		(end 216.1794 -122.173746)
		(width 0.14224)
		(layer "In4.Cu")
		(net "M_E_DQ<11>")
	)
	(segment
		(start 215.932258 -126.600204)
		(end 216.07018 -126.738126)
		(width 0.14224)
		(layer "In4.Cu")
		(net "M_E_DQ<11>")
	)
	(segment
		(start 223.118426 -112.935512)
		(end 223.118426 -113.22304)
		(width 0.14224)
		(layer "In4.Cu")
		(net "M_E_DQ<11>")
	)
	(segment
		(start 214.756746 -130.113278)
		(end 214.756746 -131.165854)
		(width 0.14224)
		(layer "In4.Cu")
		(net "M_E_DQ<11>")
	)
	(segment
		(start 225.72726 -107.013248)
		(end 225.8822 -107.168188)
		(width 0.14224)
		(layer "In4.Cu")
		(net "M_E_DQ<11>")
	)
	(segment
		(start 234.775248 -95.309436)
		(end 233.761534 -95.309436)
		(width 0.0889)
		(layer "In4.Cu")
		(net "M_E_DQ<11>")
	)
	(segment
		(start 213.799166 -140.790168)
		(end 213.843616 -140.834618)
		(width 0.14224)
		(layer "In4.Cu")
		(net "M_E_DQ<11>")
	)
	(segment
		(start 214.6808 -136.626854)
		(end 214.6808 -138.7856)
		(width 0.14224)
		(layer "In4.Cu")
		(net "M_E_DQ<11>")
	)
	(segment
		(start 214.578946 -136.220708)
		(end 214.578946 -136.525)
		(width 0.14224)
		(layer "In4.Cu")
		(net "M_E_DQ<11>")
	)
	(segment
		(start 225.8822 -106.195368)
		(end 225.72726 -106.350308)
		(width 0.14224)
		(layer "In4.Cu")
		(net "M_E_DQ<11>")
	)
	(segment
		(start 214.832946 -135.966708)
		(end 214.578946 -136.220708)
		(width 0.14224)
		(layer "In4.Cu")
		(net "M_E_DQ<11>")
	)
	(segment
		(start 214.6808 -131.965954)
		(end 214.6808 -134.0612)
		(width 0.14224)
		(layer "In4.Cu")
		(net "M_E_DQ<11>")
	)
	(segment
		(start 214.249762 -139.945364)
		(end 214.249762 -139.932156)
		(width 0.14224)
		(layer "In4.Cu")
		(net "M_E_DQ<11>")
	)
	(segment
		(start 214.578946 -138.887454)
		(end 214.578946 -139.61618)
		(width 0.14224)
		(layer "In4.Cu")
		(net "M_E_DQ<11>")
	)
	(segment
		(start 225.385884 -111.817658)
		(end 225.673412 -111.817658)
		(width 0.14224)
		(layer "In4.Cu")
		(net "M_E_DQ<11>")
	)
	(segment
		(start 216.1794 -124.026422)
		(end 215.9762 -124.229622)
		(width 0.14224)
		(layer "In4.Cu")
		(net "M_E_DQ<11>")
	)
	(segment
		(start 214.249762 -139.932156)
		(end 214.22741 -139.932156)
		(width 0.14224)
		(layer "In4.Cu")
		(net "M_E_DQ<11>")
	)
	(segment
		(start 215.473788 -124.839222)
		(end 215.676988 -125.042422)
		(width 0.14224)
		(layer "In4.Cu")
		(net "M_E_DQ<11>")
	)
	(segment
		(start 225.085656 -105.024428)
		(end 224.930716 -105.179368)
		(width 0.14224)
		(layer "In4.Cu")
		(net "M_E_DQ<11>")
	)
	(segment
		(start 213.672166 -143.941546)
		(end 213.399878 -143.941546)
		(width 0.14224)
		(layer "In4.Cu")
		(net "M_E_DQ<11>")
	)
	(segment
		(start 213.561168 -141.785848)
		(end 213.561168 -142.059152)
		(width 0.14224)
		(layer "In4.Cu")
		(net "M_E_DQ<11>")
	)
	(segment
		(start 216.1794 -125.245622)
		(end 216.1794 -125.652022)
		(width 0.14224)
		(layer "In4.Cu")
		(net "M_E_DQ<11>")
	)
	(segment
		(start 225.72726 -105.024428)
		(end 225.085656 -105.024428)
		(width 0.14224)
		(layer "In4.Cu")
		(net "M_E_DQ<11>")
	)
	(segment
		(start 213.849966 -143.763746)
		(end 213.672166 -143.941546)
		(width 0.14224)
		(layer "In4.Cu")
		(net "M_E_DQ<11>")
	)
	(segment
		(start 215.532462 -125.855222)
		(end 215.37295 -126.014734)
		(width 0.14224)
		(layer "In4.Cu")
		(net "M_E_DQ<11>")
	)
	(segment
		(start 216.1794 -122.400822)
		(end 215.9762 -122.604022)
		(width 0.14224)
		(layer "In4.Cu")
		(net "M_E_DQ<11>")
	)
	(segment
		(start 214.578946 -136.525)
		(end 214.6808 -136.626854)
		(width 0.14224)
		(layer "In4.Cu")
		(net "M_E_DQ<11>")
	)
	(segment
		(start 224.930716 -106.505248)
		(end 224.930716 -106.858308)
		(width 0.14224)
		(layer "In4.Cu")
		(net "M_E_DQ<11>")
	)
	(segment
		(start 224.930716 -105.179368)
		(end 224.930716 -105.532428)
		(width 0.14224)
		(layer "In4.Cu")
		(net "M_E_DQ<11>")
	)
	(segment
		(start 213.818216 -142.621)
		(end 213.561168 -142.878048)
		(width 0.14224)
		(layer "In4.Cu")
		(net "M_E_DQ<11>")
	)
	(segment
		(start 214.5792 -129.935732)
		(end 214.756746 -130.113278)
		(width 0.14224)
		(layer "In4.Cu")
		(net "M_E_DQ<11>")
	)
	(segment
		(start 231.3686 -98.124772)
		(end 231.3686 -98.8822)
		(width 0.14224)
		(layer "In4.Cu")
		(net "M_E_DQ<11>")
	)
	(segment
		(start 225.085656 -106.350308)
		(end 224.930716 -106.505248)
		(width 0.14224)
		(layer "In4.Cu")
		(net "M_E_DQ<11>")
	)
	(segment
		(start 225.72726 -106.350308)
		(end 225.085656 -106.350308)
		(width 0.14224)
		(layer "In4.Cu")
		(net "M_E_DQ<11>")
	)
	(segment
		(start 216.07018 -127.08382)
		(end 214.5792 -128.5748)
		(width 0.14224)
		(layer "In4.Cu")
		(net "M_E_DQ<11>")
	)
	(segment
		(start 214.6808 -138.7856)
		(end 214.578946 -138.887454)
		(width 0.14224)
		(layer "In4.Cu")
		(net "M_E_DQ<11>")
	)
	(segment
		(start 215.37295 -126.421134)
		(end 215.55202 -126.600204)
		(width 0.14224)
		(layer "In4.Cu")
		(net "M_E_DQ<11>")
	)
	(segment
		(start 214.578946 -139.61618)
		(end 214.249762 -139.945364)
		(width 0.14224)
		(layer "In4.Cu")
		(net "M_E_DQ<11>")
	)
	(segment
		(start 225.960686 -112.104932)
		(end 225.960686 -112.39246)
		(width 0.14224)
		(layer "In4.Cu")
		(net "M_E_DQ<11>")
	)
	(segment
		(start 215.650318 -123.416822)
		(end 215.9762 -123.416822)
		(width 0.14224)
		(layer "In4.Cu")
		(net "M_E_DQ<11>")
	)
	(segment
		(start 215.473788 -124.432822)
		(end 215.473788 -124.839222)
		(width 0.14224)
		(layer "In4.Cu")
		(net "M_E_DQ<11>")
	)
	(segment
		(start 233.761534 -95.309436)
		(end 232.299764 -96.771206)
		(width 0.0889)
		(layer "In4.Cu")
		(net "M_E_DQ<11>")
	)
	(arc
		(start 236.130338 -93.939106)
		(mid 236.124161 -94.519038)
		(end 235.625132 -94.81439)
		(width 0.0889)
		(layer "In4.Cu")
		(net "M_E_DQ<11>")
	)
	(arc
		(start 236.123988 -92.937838)
		(mid 236.203119 -93.23324)
		(end 236.123988 -93.528642)
		(width 0.0889)
		(layer "In4.Cu")
		(net "M_E_DQ<11>")
	)
	(arc
		(start 235.265468 -95.014288)
		(mid 235.058464 -95.225152)
		(end 234.775248 -95.309436)
		(width 0.0889)
		(layer "In4.Cu")
		(net "M_E_DQ<11>")
	)
	(arc
		(start 236.119162 -92.546424)
		(mid 236.070407 -92.742776)
		(end 236.123988 -92.937838)
		(width 0.0889)
		(layer "In4.Cu")
		(net "M_E_DQ<11>")
	)
	(arc
		(start 235.597192 -94.81439)
		(mid 235.40555 -94.871556)
		(end 235.265468 -95.014288)
		(width 0.0889)
		(layer "In4.Cu")
		(net "M_E_DQ<11>")
	)
	(arc
		(start 236.123988 -93.528642)
		(mid 236.070489 -93.72854)
		(end 236.123988 -93.928438)
		(width 0.0889)
		(layer "In4.Cu")
		(net "M_E_DQ<11>")
	)
	(segment
		(start 214.250524 -147.27174)
		(end 214.249762 -147.27174)
		(width 0.1651)
		(layer "F.Cu")
		(net "M_E_DQ<10>")
	)
	(segment
		(start 214.249762 -147.27174)
		(end 214.249762 -146.280632)
		(width 0.1651)
		(layer "F.Cu")
		(net "M_E_DQ<10>")
	)
	(segment
		(start 214.249762 -145.793968)
		(end 214.249762 -145.5166)
		(width 0.1651)
		(layer "F.Cu")
		(net "M_E_DQ<10>")
	)
	(segment
		(start 214.381334 -145.92554)
		(end 214.249762 -145.793968)
		(width 0.1651)
		(layer "F.Cu")
		(net "M_E_DQ<10>")
	)
	(segment
		(start 214.381334 -146.14906)
		(end 214.381334 -145.92554)
		(width 0.1651)
		(layer "F.Cu")
		(net "M_E_DQ<10>")
	)
	(segment
		(start 237.900718 -91.25204)
		(end 237.329218 -91.25204)
		(width 0.1651)
		(layer "F.Cu")
		(net "M_E_DQ<10>")
	)
	(segment
		(start 214.249762 -146.280632)
		(end 214.381334 -146.14906)
		(width 0.1651)
		(layer "F.Cu")
		(net "M_E_DQ<10>")
	)
	(via
		(at 213.399878 -141.213078)
		(size 0.508)
		(drill 0.254)
		(layers "F.Cu" "B.Cu")
		(net "M_E_DQ<10>")
	)
	(via
		(at 214.249762 -145.5166)
		(size 0.508)
		(drill 0.254)
		(layers "F.Cu" "B.Cu")
		(net "M_E_DQ<10>")
	)
	(via
		(at 237.329218 -91.25204)
		(size 0.508)
		(drill 0.254)
		(layers "F.Cu" "B.Cu")
		(net "M_E_DQ<10>")
	)
	(segment
		(start 213.400386 -142.477236)
		(end 213.399878 -142.476982)
		(width 0.1651)
		(layer "B.Cu")
		(net "M_E_DQ<10>")
	)
	(segment
		(start 213.399878 -142.476982)
		(end 213.399878 -141.213078)
		(width 0.1651)
		(layer "B.Cu")
		(net "M_E_DQ<10>")
	)
	(segment
		(start 224.149158 -108.84916)
		(end 224.149158 -109.20222)
		(width 0.14224)
		(layer "In4.Cu")
		(net "M_E_DQ<10>")
	)
	(segment
		(start 213.054946 -140.235178)
		(end 213.054946 -140.868146)
		(width 0.14224)
		(layer "In4.Cu")
		(net "M_E_DQ<10>")
	)
	(segment
		(start 224.149158 -109.20222)
		(end 224.304098 -109.35716)
		(width 0.14224)
		(layer "In4.Cu")
		(net "M_E_DQ<10>")
	)
	(segment
		(start 213.918546 -136.205468)
		(end 213.918546 -136.5758)
		(width 0.14224)
		(layer "In4.Cu")
		(net "M_E_DQ<10>")
	)
	(segment
		(start 224.304098 -108.69422)
		(end 224.149158 -108.84916)
		(width 0.14224)
		(layer "In4.Cu")
		(net "M_E_DQ<10>")
	)
	(segment
		(start 213.9442 -129.782824)
		(end 213.5886 -130.138424)
		(width 0.14224)
		(layer "In4.Cu")
		(net "M_E_DQ<10>")
	)
	(segment
		(start 213.5886 -130.138424)
		(end 213.5886 -131.0386)
		(width 0.14224)
		(layer "In4.Cu")
		(net "M_E_DQ<10>")
	)
	(segment
		(start 233.683302 -95.118936)
		(end 232.060496 -96.741742)
		(width 0.0889)
		(layer "In4.Cu")
		(net "M_E_DQ<10>")
	)
	(segment
		(start 213.918546 -139.371578)
		(end 213.054946 -140.235178)
		(width 0.14224)
		(layer "In4.Cu")
		(net "M_E_DQ<10>")
	)
	(segment
		(start 235.623354 -94.623636)
		(end 235.599224 -94.623636)
		(width 0.0889)
		(layer "In4.Cu")
		(net "M_E_DQ<10>")
	)
	(segment
		(start 232.060496 -96.741742)
		(end 231.847898 -96.741742)
		(width 0.0889)
		(layer "In4.Cu")
		(net "M_E_DQ<10>")
	)
	(segment
		(start 225.146362 -109.5121)
		(end 225.146362 -110.134146)
		(width 0.14224)
		(layer "In4.Cu")
		(net "M_E_DQ<10>")
	)
	(segment
		(start 225.146362 -110.134146)
		(end 220.04147 -115.239038)
		(width 0.14224)
		(layer "In4.Cu")
		(net "M_E_DQ<10>")
	)
	(segment
		(start 220.04147 -115.41887)
		(end 220.213682 -115.591082)
		(width 0.14224)
		(layer "In4.Cu")
		(net "M_E_DQ<10>")
	)
	(segment
		(start 235.952538 -94.01302)
		(end 235.958888 -94.023688)
		(width 0.0889)
		(layer "In4.Cu")
		(net "M_E_DQ<10>")
	)
	(segment
		(start 234.768644 -95.118936)
		(end 233.683302 -95.118936)
		(width 0.0889)
		(layer "In4.Cu")
		(net "M_E_DQ<10>")
	)
	(segment
		(start 213.689946 -134.733538)
		(end 213.689946 -135.976868)
		(width 0.14224)
		(layer "In4.Cu")
		(net "M_E_DQ<10>")
	)
	(segment
		(start 213.5886 -131.0386)
		(end 214.0712 -131.5212)
		(width 0.14224)
		(layer "In4.Cu")
		(net "M_E_DQ<10>")
	)
	(segment
		(start 213.689946 -135.976868)
		(end 213.918546 -136.205468)
		(width 0.14224)
		(layer "In4.Cu")
		(net "M_E_DQ<10>")
	)
	(segment
		(start 224.991422 -109.35716)
		(end 225.146362 -109.5121)
		(width 0.14224)
		(layer "In4.Cu")
		(net "M_E_DQ<10>")
	)
	(segment
		(start 213.969346 -134.454138)
		(end 213.689946 -134.733538)
		(width 0.14224)
		(layer "In4.Cu")
		(net "M_E_DQ<10>")
	)
	(segment
		(start 213.825328 -132.097018)
		(end 213.825328 -134.069328)
		(width 0.14224)
		(layer "In4.Cu")
		(net "M_E_DQ<10>")
	)
	(segment
		(start 212.966808 -144.233646)
		(end 214.249762 -145.5166)
		(width 0.14224)
		(layer "In4.Cu")
		(net "M_E_DQ<10>")
	)
	(segment
		(start 222.50781 -113.87201)
		(end 222.795084 -114.159284)
		(width 0.14224)
		(layer "In4.Cu")
		(net "M_E_DQ<10>")
	)
	(segment
		(start 224.310956 -104.881172)
		(end 224.310956 -107.101132)
		(width 0.14224)
		(layer "In4.Cu")
		(net "M_E_DQ<10>")
	)
	(segment
		(start 213.9442 -128.311656)
		(end 213.9442 -129.782824)
		(width 0.14224)
		(layer "In4.Cu")
		(net "M_E_DQ<10>")
	)
	(segment
		(start 230.7336 -97.85604)
		(end 230.7336 -98.458528)
		(width 0.14224)
		(layer "In4.Cu")
		(net "M_E_DQ<10>")
	)
	(segment
		(start 236.507782 -91.347036)
		(end 236.459522 -91.347036)
		(width 0.0889)
		(layer "In4.Cu")
		(net "M_E_DQ<10>")
	)
	(segment
		(start 213.399878 -141.213078)
		(end 212.966808 -141.646148)
		(width 0.14224)
		(layer "In4.Cu")
		(net "M_E_DQ<10>")
	)
	(segment
		(start 213.8172 -138.8618)
		(end 213.918546 -138.963146)
		(width 0.14224)
		(layer "In4.Cu")
		(net "M_E_DQ<10>")
	)
	(segment
		(start 231.847898 -96.741742)
		(end 230.7336 -97.85604)
		(width 0.14224)
		(layer "In4.Cu")
		(net "M_E_DQ<10>")
	)
	(segment
		(start 220.04147 -115.239038)
		(end 220.04147 -115.41887)
		(width 0.14224)
		(layer "In4.Cu")
		(net "M_E_DQ<10>")
	)
	(segment
		(start 237.329218 -91.25204)
		(end 236.507782 -91.347036)
		(width 0.0889)
		(layer "In4.Cu")
		(net "M_E_DQ<10>")
	)
	(segment
		(start 230.7336 -98.458528)
		(end 224.310956 -104.881172)
		(width 0.14224)
		(layer "In4.Cu")
		(net "M_E_DQ<10>")
	)
	(segment
		(start 213.054946 -140.868146)
		(end 213.399878 -141.213078)
		(width 0.14224)
		(layer "In4.Cu")
		(net "M_E_DQ<10>")
	)
	(segment
		(start 213.969346 -134.213346)
		(end 213.969346 -134.454138)
		(width 0.14224)
		(layer "In4.Cu")
		(net "M_E_DQ<10>")
	)
	(segment
		(start 214.9602 -127.295656)
		(end 213.9442 -128.311656)
		(width 0.14224)
		(layer "In4.Cu")
		(net "M_E_DQ<10>")
	)
	(segment
		(start 213.918546 -138.963146)
		(end 213.918546 -139.371578)
		(width 0.14224)
		(layer "In4.Cu")
		(net "M_E_DQ<10>")
	)
	(segment
		(start 213.918546 -136.5758)
		(end 213.8172 -136.677146)
		(width 0.14224)
		(layer "In4.Cu")
		(net "M_E_DQ<10>")
	)
	(segment
		(start 236.123988 -91.547188)
		(end 235.958888 -91.8337)
		(width 0.0889)
		(layer "In4.Cu")
		(net "M_E_DQ<10>")
	)
	(segment
		(start 214.0712 -131.851146)
		(end 213.825328 -132.097018)
		(width 0.14224)
		(layer "In4.Cu")
		(net "M_E_DQ<10>")
	)
	(segment
		(start 222.795084 -114.159284)
		(end 222.795084 -114.446812)
		(width 0.14224)
		(layer "In4.Cu")
		(net "M_E_DQ<10>")
	)
	(segment
		(start 235.963714 -92.433902)
		(end 235.958888 -92.442538)
		(width 0.0889)
		(layer "In4.Cu")
		(net "M_E_DQ<10>")
	)
	(segment
		(start 213.8172 -136.677146)
		(end 213.8172 -138.8618)
		(width 0.14224)
		(layer "In4.Cu")
		(net "M_E_DQ<10>")
	)
	(segment
		(start 235.958888 -92.442538)
		(end 235.952538 -92.453206)
		(width 0.0889)
		(layer "In4.Cu")
		(net "M_E_DQ<10>")
	)
	(segment
		(start 213.825328 -134.069328)
		(end 213.969346 -134.213346)
		(width 0.14224)
		(layer "In4.Cu")
		(net "M_E_DQ<10>")
	)
	(segment
		(start 224.991422 -108.69422)
		(end 224.304098 -108.69422)
		(width 0.14224)
		(layer "In4.Cu")
		(net "M_E_DQ<10>")
	)
	(segment
		(start 235.963714 -93.424502)
		(end 235.958888 -93.433138)
		(width 0.0889)
		(layer "In4.Cu")
		(net "M_E_DQ<10>")
	)
	(segment
		(start 220.50121 -115.591082)
		(end 222.220282 -113.87201)
		(width 0.14224)
		(layer "In4.Cu")
		(net "M_E_DQ<10>")
	)
	(segment
		(start 214.9602 -122.281696)
		(end 214.9602 -127.295656)
		(width 0.14224)
		(layer "In4.Cu")
		(net "M_E_DQ<10>")
	)
	(segment
		(start 214.0712 -131.5212)
		(end 214.0712 -131.851146)
		(width 0.14224)
		(layer "In4.Cu")
		(net "M_E_DQ<10>")
	)
	(segment
		(start 225.146362 -108.53928)
		(end 224.991422 -108.69422)
		(width 0.14224)
		(layer "In4.Cu")
		(net "M_E_DQ<10>")
	)
	(segment
		(start 224.304098 -109.35716)
		(end 224.991422 -109.35716)
		(width 0.14224)
		(layer "In4.Cu")
		(net "M_E_DQ<10>")
	)
	(segment
		(start 225.146362 -107.936538)
		(end 225.146362 -108.53928)
		(width 0.14224)
		(layer "In4.Cu")
		(net "M_E_DQ<10>")
	)
	(segment
		(start 222.795084 -114.446812)
		(end 214.9602 -122.281696)
		(width 0.14224)
		(layer "In4.Cu")
		(net "M_E_DQ<10>")
	)
	(segment
		(start 224.310956 -107.101132)
		(end 225.146362 -107.936538)
		(width 0.14224)
		(layer "In4.Cu")
		(net "M_E_DQ<10>")
	)
	(segment
		(start 220.213682 -115.591082)
		(end 220.50121 -115.591082)
		(width 0.14224)
		(layer "In4.Cu")
		(net "M_E_DQ<10>")
	)
	(segment
		(start 212.966808 -141.646148)
		(end 212.966808 -144.233646)
		(width 0.14224)
		(layer "In4.Cu")
		(net "M_E_DQ<10>")
	)
	(segment
		(start 222.220282 -113.87201)
		(end 222.50781 -113.87201)
		(width 0.14224)
		(layer "In4.Cu")
		(net "M_E_DQ<10>")
	)
	(arc
		(start 236.459522 -91.347036)
		(mid 236.265672 -91.403386)
		(end 236.123988 -91.547188)
		(width 0.0889)
		(layer "In4.Cu")
		(net "M_E_DQ<10>")
	)
	(arc
		(start 235.952538 -92.453206)
		(mid 235.87974 -92.743969)
		(end 235.958888 -93.033088)
		(width 0.0889)
		(layer "In4.Cu")
		(net "M_E_DQ<10>")
	)
	(arc
		(start 235.599224 -94.623636)
		(mid 235.311079 -94.705955)
		(end 235.100368 -94.919038)
		(width 0.0889)
		(layer "In4.Cu")
		(net "M_E_DQ<10>")
	)
	(arc
		(start 235.958888 -93.433138)
		(mid 235.879666 -93.722256)
		(end 235.952538 -94.01302)
		(width 0.0889)
		(layer "In4.Cu")
		(net "M_E_DQ<10>")
	)
	(arc
		(start 235.958888 -94.023688)
		(mid 235.961471 -94.418935)
		(end 235.623354 -94.623636)
		(width 0.0889)
		(layer "In4.Cu")
		(net "M_E_DQ<10>")
	)
	(arc
		(start 235.100368 -94.919038)
		(mid 234.960289 -95.061774)
		(end 234.768644 -95.118936)
		(width 0.0889)
		(layer "In4.Cu")
		(net "M_E_DQ<10>")
	)
	(arc
		(start 235.958888 -93.033088)
		(mid 236.012358 -93.228151)
		(end 235.963714 -93.424502)
		(width 0.0889)
		(layer "In4.Cu")
		(net "M_E_DQ<10>")
	)
	(arc
		(start 235.958888 -92.042488)
		(mid 236.012358 -92.237551)
		(end 235.963714 -92.433902)
		(width 0.0889)
		(layer "In4.Cu")
		(net "M_E_DQ<10>")
	)
	(arc
		(start 235.958888 -91.8337)
		(mid 235.93092 -91.938094)
		(end 235.958888 -92.042488)
		(width 0.0889)
		(layer "In4.Cu")
		(net "M_E_DQ<10>")
	)
	(segment
		(start 198.950326 -147.27174)
		(end 198.949818 -147.277582)
		(width 0.1651)
		(layer "F.Cu")
		(net "M_E_DQ<0>")
	)
	(segment
		(start 238.759238 -84.812886)
		(end 238.187738 -84.812886)
		(width 0.1651)
		(layer "F.Cu")
		(net "M_E_DQ<0>")
	)
	(segment
		(start 198.949818 -147.277582)
		(end 198.772018 -145.415)
		(width 0.1651)
		(layer "F.Cu")
		(net "M_E_DQ<0>")
	)
	(via
		(at 198.099934 -141.213078)
		(size 0.508)
		(drill 0.254)
		(layers "F.Cu" "B.Cu")
		(net "M_E_DQ<0>")
	)
	(via
		(at 238.187738 -84.812886)
		(size 0.508)
		(drill 0.254)
		(layers "F.Cu" "B.Cu")
		(net "M_E_DQ<0>")
	)
	(via
		(at 198.772018 -145.415)
		(size 0.508)
		(drill 0.254)
		(layers "F.Cu" "B.Cu")
		(net "M_E_DQ<0>")
	)
	(segment
		(start 198.099934 -142.476982)
		(end 198.099934 -141.213078)
		(width 0.1651)
		(layer "B.Cu")
		(net "M_E_DQ<0>")
	)
	(segment
		(start 198.100442 -142.477236)
		(end 198.099934 -142.476982)
		(width 0.1651)
		(layer "B.Cu")
		(net "M_E_DQ<0>")
	)
	(segment
		(start 197.666864 -141.646148)
		(end 197.666864 -144.60601)
		(width 0.14224)
		(layer "In4.Cu")
		(net "M_E_DQ<0>")
	)
	(segment
		(start 198.475854 -145.415)
		(end 198.772018 -145.415)
		(width 0.14224)
		(layer "In4.Cu")
		(net "M_E_DQ<0>")
	)
	(segment
		(start 228.402134 -83.15452)
		(end 219.392754 -92.1639)
		(width 0.14224)
		(layer "In4.Cu")
		(net "M_E_DQ<0>")
	)
	(segment
		(start 231.81564 -82.737198)
		(end 231.179624 -83.373214)
		(width 0.0889)
		(layer "In4.Cu")
		(net "M_E_DQ<0>")
	)
	(segment
		(start 198.621396 -131.953)
		(end 198.3232 -132.251196)
		(width 0.14224)
		(layer "In4.Cu")
		(net "M_E_DQ<0>")
	)
	(segment
		(start 198.138796 -115.90655)
		(end 198.138796 -128.97485)
		(width 0.14224)
		(layer "In4.Cu")
		(net "M_E_DQ<0>")
	)
	(segment
		(start 238.187738 -84.812886)
		(end 237.857792 -84.05114)
		(width 0.0889)
		(layer "In4.Cu")
		(net "M_E_DQ<0>")
	)
	(segment
		(start 207.111346 -107.8484)
		(end 201.523346 -113.4364)
		(width 0.14224)
		(layer "In4.Cu")
		(net "M_E_DQ<0>")
	)
	(segment
		(start 198.099934 -141.213078)
		(end 197.666864 -141.646148)
		(width 0.14224)
		(layer "In4.Cu")
		(net "M_E_DQ<0>")
	)
	(segment
		(start 198.621396 -131.514596)
		(end 198.621396 -131.953)
		(width 0.14224)
		(layer "In4.Cu")
		(net "M_E_DQ<0>")
	)
	(segment
		(start 197.666864 -144.60601)
		(end 198.475854 -145.415)
		(width 0.14224)
		(layer "In4.Cu")
		(net "M_E_DQ<0>")
	)
	(segment
		(start 198.621396 -134.181596)
		(end 198.621396 -134.437374)
		(width 0.14224)
		(layer "In4.Cu")
		(net "M_E_DQ<0>")
	)
	(segment
		(start 198.5264 -136.670796)
		(end 198.5264 -138.8872)
		(width 0.14224)
		(layer "In4.Cu")
		(net "M_E_DQ<0>")
	)
	(segment
		(start 198.519034 -129.80797)
		(end 198.291196 -130.035808)
		(width 0.14224)
		(layer "In4.Cu")
		(net "M_E_DQ<0>")
	)
	(segment
		(start 198.570596 -138.931396)
		(end 198.570596 -139.339828)
		(width 0.14224)
		(layer "In4.Cu")
		(net "M_E_DQ<0>")
	)
	(segment
		(start 237.857792 -84.05114)
		(end 237.841028 -84.022438)
		(width 0.0889)
		(layer "In4.Cu")
		(net "M_E_DQ<0>")
	)
	(segment
		(start 231.027478 -83.373214)
		(end 230.808784 -83.15452)
		(width 0.0889)
		(layer "In4.Cu")
		(net "M_E_DQ<0>")
	)
	(segment
		(start 198.138796 -128.97485)
		(end 198.519034 -129.355088)
		(width 0.14224)
		(layer "In4.Cu")
		(net "M_E_DQ<0>")
	)
	(segment
		(start 230.808784 -83.15452)
		(end 228.402134 -83.15452)
		(width 0.14224)
		(layer "In4.Cu")
		(net "M_E_DQ<0>")
	)
	(segment
		(start 219.392754 -96.684592)
		(end 208.228946 -107.8484)
		(width 0.14224)
		(layer "In4.Cu")
		(net "M_E_DQ<0>")
	)
	(segment
		(start 235.633768 -82.73669)
		(end 235.601002 -82.73669)
		(width 0.0889)
		(layer "In4.Cu")
		(net "M_E_DQ<0>")
	)
	(segment
		(start 236.488478 -83.231736)
		(end 236.452664 -83.231736)
		(width 0.0889)
		(layer "In4.Cu")
		(net "M_E_DQ<0>")
	)
	(segment
		(start 231.179624 -83.373214)
		(end 231.027478 -83.373214)
		(width 0.0889)
		(layer "In4.Cu")
		(net "M_E_DQ<0>")
	)
	(segment
		(start 237.350808 -83.72729)
		(end 237.318042 -83.72729)
		(width 0.0889)
		(layer "In4.Cu")
		(net "M_E_DQ<0>")
	)
	(segment
		(start 219.392754 -92.1639)
		(end 219.392754 -96.684592)
		(width 0.14224)
		(layer "In4.Cu")
		(net "M_E_DQ<0>")
	)
	(segment
		(start 198.291196 -131.184396)
		(end 198.621396 -131.514596)
		(width 0.14224)
		(layer "In4.Cu")
		(net "M_E_DQ<0>")
	)
	(segment
		(start 208.228946 -107.8484)
		(end 207.111346 -107.8484)
		(width 0.14224)
		(layer "In4.Cu")
		(net "M_E_DQ<0>")
	)
	(segment
		(start 197.855332 -140.055092)
		(end 197.855332 -140.951712)
		(width 0.14224)
		(layer "In4.Cu")
		(net "M_E_DQ<0>")
	)
	(segment
		(start 198.570596 -136.26465)
		(end 198.570596 -136.6266)
		(width 0.14224)
		(layer "In4.Cu")
		(net "M_E_DQ<0>")
	)
	(segment
		(start 232.380028 -82.737198)
		(end 231.81564 -82.737198)
		(width 0.0889)
		(layer "In4.Cu")
		(net "M_E_DQ<0>")
	)
	(segment
		(start 198.570596 -139.339828)
		(end 197.855332 -140.055092)
		(width 0.14224)
		(layer "In4.Cu")
		(net "M_E_DQ<0>")
	)
	(segment
		(start 198.3232 -133.8834)
		(end 198.621396 -134.181596)
		(width 0.14224)
		(layer "In4.Cu")
		(net "M_E_DQ<0>")
	)
	(segment
		(start 232.767378 -83.158076)
		(end 232.54462 -82.90179)
		(width 0.0889)
		(layer "In4.Cu")
		(net "M_E_DQ<0>")
	)
	(segment
		(start 198.519034 -129.355088)
		(end 198.519034 -129.80797)
		(width 0.14224)
		(layer "In4.Cu")
		(net "M_E_DQ<0>")
	)
	(segment
		(start 198.621396 -134.437374)
		(end 198.291196 -134.767574)
		(width 0.14224)
		(layer "In4.Cu")
		(net "M_E_DQ<0>")
	)
	(segment
		(start 198.5264 -138.8872)
		(end 198.570596 -138.931396)
		(width 0.14224)
		(layer "In4.Cu")
		(net "M_E_DQ<0>")
	)
	(segment
		(start 200.608946 -113.4364)
		(end 198.138796 -115.90655)
		(width 0.14224)
		(layer "In4.Cu")
		(net "M_E_DQ<0>")
	)
	(segment
		(start 198.291196 -135.98525)
		(end 198.570596 -136.26465)
		(width 0.14224)
		(layer "In4.Cu")
		(net "M_E_DQ<0>")
	)
	(segment
		(start 201.523346 -113.4364)
		(end 200.608946 -113.4364)
		(width 0.14224)
		(layer "In4.Cu")
		(net "M_E_DQ<0>")
	)
	(segment
		(start 198.099934 -141.196314)
		(end 198.099934 -141.213078)
		(width 0.14224)
		(layer "In4.Cu")
		(net "M_E_DQ<0>")
	)
	(segment
		(start 233.054652 -83.231736)
		(end 232.869232 -83.231736)
		(width 0.0889)
		(layer "In4.Cu")
		(net "M_E_DQ<0>")
	)
	(segment
		(start 198.570596 -136.6266)
		(end 198.5264 -136.670796)
		(width 0.14224)
		(layer "In4.Cu")
		(net "M_E_DQ<0>")
	)
	(segment
		(start 198.291196 -130.035808)
		(end 198.291196 -131.184396)
		(width 0.14224)
		(layer "In4.Cu")
		(net "M_E_DQ<0>")
	)
	(segment
		(start 232.54462 -82.90179)
		(end 232.380028 -82.737198)
		(width 0.0889)
		(layer "In4.Cu")
		(net "M_E_DQ<0>")
	)
	(segment
		(start 198.291196 -134.767574)
		(end 198.291196 -135.98525)
		(width 0.14224)
		(layer "In4.Cu")
		(net "M_E_DQ<0>")
	)
	(segment
		(start 198.3232 -132.251196)
		(end 198.3232 -133.8834)
		(width 0.14224)
		(layer "In4.Cu")
		(net "M_E_DQ<0>")
	)
	(segment
		(start 233.906314 -82.73669)
		(end 233.873548 -82.73669)
		(width 0.0889)
		(layer "In4.Cu")
		(net "M_E_DQ<0>")
	)
	(segment
		(start 197.855332 -140.951712)
		(end 198.099934 -141.196314)
		(width 0.14224)
		(layer "In4.Cu")
		(net "M_E_DQ<0>")
	)
	(arc
		(start 235.265468 -82.536538)
		(mid 234.753658 -82.240999)
		(end 234.241848 -82.536538)
		(width 0.0889)
		(layer "In4.Cu")
		(net "M_E_DQ<0>")
	)
	(arc
		(start 233.383328 -83.031838)
		(mid 233.244584 -83.173871)
		(end 233.054652 -83.231736)
		(width 0.0889)
		(layer "In4.Cu")
		(net "M_E_DQ<0>")
	)
	(arc
		(start 237.841028 -84.022438)
		(mid 237.634024 -83.811574)
		(end 237.350808 -83.72729)
		(width 0.0889)
		(layer "In4.Cu")
		(net "M_E_DQ<0>")
	)
	(arc
		(start 236.982508 -83.527138)
		(mid 236.7739 -83.315206)
		(end 236.488478 -83.231736)
		(width 0.0889)
		(layer "In4.Cu")
		(net "M_E_DQ<0>")
	)
	(arc
		(start 236.123988 -83.031838)
		(mid 235.916984 -82.820974)
		(end 235.633768 -82.73669)
		(width 0.0889)
		(layer "In4.Cu")
		(net "M_E_DQ<0>")
	)
	(arc
		(start 236.452664 -83.231736)
		(mid 236.262735 -83.173866)
		(end 236.123988 -83.031838)
		(width 0.0889)
		(layer "In4.Cu")
		(net "M_E_DQ<0>")
	)
	(arc
		(start 233.873548 -82.73669)
		(mid 233.590331 -82.820971)
		(end 233.383328 -83.031838)
		(width 0.0889)
		(layer "In4.Cu")
		(net "M_E_DQ<0>")
	)
	(arc
		(start 234.241848 -82.536538)
		(mid 234.100165 -82.680342)
		(end 233.906314 -82.73669)
		(width 0.0889)
		(layer "In4.Cu")
		(net "M_E_DQ<0>")
	)
	(arc
		(start 232.869232 -83.231736)
		(mid 232.814039 -83.200798)
		(end 232.767378 -83.158076)
		(width 0.0889)
		(layer "In4.Cu")
		(net "M_E_DQ<0>")
	)
	(arc
		(start 237.318042 -83.72729)
		(mid 237.124192 -83.67094)
		(end 236.982508 -83.527138)
		(width 0.0889)
		(layer "In4.Cu")
		(net "M_E_DQ<0>")
	)
	(arc
		(start 235.601002 -82.73669)
		(mid 235.407152 -82.68034)
		(end 235.265468 -82.536538)
		(width 0.0889)
		(layer "In4.Cu")
		(net "M_E_DQ<0>")
	)
	(segment
		(start 267.089636 -95.21444)
		(end 266.518136 -95.21444)
		(width 0.1016)
		(layer "F.Cu")
		(net "M_E_CS_N<7>")
	)
	(via
		(at 266.518136 -95.21444)
		(size 0.508)
		(drill 0.254)
		(layers "F.Cu" "B.Cu")
		(net "M_E_CS_N<7>")
	)
	(via
		(at 277.999952 -139.172188)
		(size 0.4572)
		(drill 0.2032)
		(layers "F.Cu" "B.Cu")
		(net "M_E_CS_N<7>")
	)
	(segment
		(start 278.00046 -137.877296)
		(end 277.999952 -137.877296)
		(width 0.1651)
		(layer "B.Cu")
		(net "M_E_CS_N<7>")
	)
	(segment
		(start 277.999952 -137.877296)
		(end 277.999952 -139.172188)
		(width 0.1651)
		(layer "B.Cu")
		(net "M_E_CS_N<7>")
	)
	(segment
		(start 277.4188 -128.090168)
		(end 277.4188 -129.7686)
		(width 0.14224)
		(layer "In4.Cu")
		(net "M_E_CS_N<7>")
	)
	(segment
		(start 277.4188 -129.7686)
		(end 277.607014 -129.956814)
		(width 0.14224)
		(layer "In4.Cu")
		(net "M_E_CS_N<7>")
	)
	(segment
		(start 277.589234 -138.117834)
		(end 277.999952 -138.528552)
		(width 0.14224)
		(layer "In4.Cu")
		(net "M_E_CS_N<7>")
	)
	(segment
		(start 277.583392 -131.966208)
		(end 277.583392 -134.759192)
		(width 0.14224)
		(layer "In4.Cu")
		(net "M_E_CS_N<7>")
	)
	(segment
		(start 267.9954 -95.75292)
		(end 267.9954 -96.89084)
		(width 0.0889)
		(layer "In4.Cu")
		(net "M_E_CS_N<7>")
	)
	(segment
		(start 267.45692 -95.21444)
		(end 267.9954 -95.75292)
		(width 0.0889)
		(layer "In4.Cu")
		(net "M_E_CS_N<7>")
	)
	(segment
		(start 277.542752 -131.238752)
		(end 277.607014 -131.303014)
		(width 0.14224)
		(layer "In4.Cu")
		(net "M_E_CS_N<7>")
	)
	(segment
		(start 277.607014 -129.956814)
		(end 277.607014 -130.520186)
		(width 0.14224)
		(layer "In4.Cu")
		(net "M_E_CS_N<7>")
	)
	(segment
		(start 266.518136 -95.21444)
		(end 267.45692 -95.21444)
		(width 0.0889)
		(layer "In4.Cu")
		(net "M_E_CS_N<7>")
	)
	(segment
		(start 277.542752 -130.584448)
		(end 277.542752 -131.238752)
		(width 0.14224)
		(layer "In4.Cu")
		(net "M_E_CS_N<7>")
	)
	(segment
		(start 277.607014 -131.303014)
		(end 277.607014 -131.942586)
		(width 0.14224)
		(layer "In4.Cu")
		(net "M_E_CS_N<7>")
	)
	(segment
		(start 267.9954 -96.89084)
		(end 268.7574 -97.65284)
		(width 0.0889)
		(layer "In4.Cu")
		(net "M_E_CS_N<7>")
	)
	(segment
		(start 269.6972 -120.368568)
		(end 277.4188 -128.090168)
		(width 0.14224)
		(layer "In4.Cu")
		(net "M_E_CS_N<7>")
	)
	(segment
		(start 268.7574 -97.65284)
		(end 268.7574 -100.9396)
		(width 0.0889)
		(layer "In4.Cu")
		(net "M_E_CS_N<7>")
	)
	(segment
		(start 277.607014 -131.942586)
		(end 277.583392 -131.966208)
		(width 0.14224)
		(layer "In4.Cu")
		(net "M_E_CS_N<7>")
	)
	(segment
		(start 268.7574 -100.9396)
		(end 269.6972 -101.8794)
		(width 0.0889)
		(layer "In4.Cu")
		(net "M_E_CS_N<7>")
	)
	(segment
		(start 269.6972 -103.1494)
		(end 269.6972 -120.368568)
		(width 0.14224)
		(layer "In4.Cu")
		(net "M_E_CS_N<7>")
	)
	(segment
		(start 277.589234 -134.765034)
		(end 277.589234 -138.117834)
		(width 0.14224)
		(layer "In4.Cu")
		(net "M_E_CS_N<7>")
	)
	(segment
		(start 277.999952 -138.528552)
		(end 277.999952 -139.172188)
		(width 0.14224)
		(layer "In4.Cu")
		(net "M_E_CS_N<7>")
	)
	(segment
		(start 277.607014 -130.520186)
		(end 277.542752 -130.584448)
		(width 0.14224)
		(layer "In4.Cu")
		(net "M_E_CS_N<7>")
	)
	(segment
		(start 269.6972 -101.8794)
		(end 269.6972 -103.1494)
		(width 0.0889)
		(layer "In4.Cu")
		(net "M_E_CS_N<7>")
	)
	(segment
		(start 277.583392 -134.759192)
		(end 277.589234 -134.765034)
		(width 0.14224)
		(layer "In4.Cu")
		(net "M_E_CS_N<7>")
	)
	(segment
		(start 267.948156 -96.700086)
		(end 267.376656 -96.700086)
		(width 0.1016)
		(layer "F.Cu")
		(net "M_E_CS_N<6>")
	)
	(via
		(at 277.999952 -141.188186)
		(size 0.4572)
		(drill 0.2032)
		(layers "F.Cu" "B.Cu")
		(net "M_E_CS_N<6>")
	)
	(via
		(at 267.376656 -96.700086)
		(size 0.508)
		(drill 0.254)
		(layers "F.Cu" "B.Cu")
		(net "M_E_CS_N<6>")
	)
	(segment
		(start 277.999952 -142.476982)
		(end 277.999952 -141.188186)
		(width 0.1651)
		(layer "B.Cu")
		(net "M_E_CS_N<6>")
	)
	(segment
		(start 278.00046 -142.477236)
		(end 277.999952 -142.476982)
		(width 0.1651)
		(layer "B.Cu")
		(net "M_E_CS_N<6>")
	)
	(segment
		(start 276.712172 -131.237228)
		(end 276.712172 -134.793228)
		(width 0.14224)
		(layer "In4.Cu")
		(net "M_E_CS_N<6>")
	)
	(segment
		(start 276.8346 -130.6576)
		(end 276.8346 -131.1148)
		(width 0.14224)
		(layer "In4.Cu")
		(net "M_E_CS_N<6>")
	)
	(segment
		(start 269.3162 -102.0318)
		(end 269.3162 -102.70871)
		(width 0.0889)
		(layer "In4.Cu")
		(net "M_E_CS_N<6>")
	)
	(segment
		(start 269.1892 -120.677686)
		(end 272.24482 -123.733306)
		(width 0.14224)
		(layer "In4.Cu")
		(net "M_E_CS_N<6>")
	)
	(segment
		(start 276.85492 -129.77368)
		(end 276.575774 -130.052826)
		(width 0.14224)
		(layer "In4.Cu")
		(net "M_E_CS_N<6>")
	)
	(segment
		(start 276.575774 -130.398774)
		(end 276.8346 -130.6576)
		(width 0.14224)
		(layer "In4.Cu")
		(net "M_E_CS_N<6>")
	)
	(segment
		(start 272.24482 -123.733306)
		(end 272.24482 -124.650246)
		(width 0.14224)
		(layer "In4.Cu")
		(net "M_E_CS_N<6>")
	)
	(segment
		(start 276.708362 -137.998962)
		(end 277.589234 -138.879834)
		(width 0.14224)
		(layer "In4.Cu")
		(net "M_E_CS_N<6>")
	)
	(segment
		(start 276.712172 -134.793228)
		(end 276.708362 -134.797038)
		(width 0.14224)
		(layer "In4.Cu")
		(net "M_E_CS_N<6>")
	)
	(segment
		(start 277.999952 -140.503656)
		(end 277.999952 -141.188186)
		(width 0.14224)
		(layer "In4.Cu")
		(net "M_E_CS_N<6>")
	)
	(segment
		(start 276.575774 -130.052826)
		(end 276.575774 -130.398774)
		(width 0.14224)
		(layer "In4.Cu")
		(net "M_E_CS_N<6>")
	)
	(segment
		(start 267.376656 -96.700086)
		(end 268.478 -97.80143)
		(width 0.0889)
		(layer "In4.Cu")
		(net "M_E_CS_N<6>")
	)
	(segment
		(start 277.589234 -140.092938)
		(end 277.999952 -140.503656)
		(width 0.14224)
		(layer "In4.Cu")
		(net "M_E_CS_N<6>")
	)
	(segment
		(start 277.589234 -138.879834)
		(end 277.589234 -140.092938)
		(width 0.14224)
		(layer "In4.Cu")
		(net "M_E_CS_N<6>")
	)
	(segment
		(start 276.85492 -129.260346)
		(end 276.85492 -129.77368)
		(width 0.14224)
		(layer "In4.Cu")
		(net "M_E_CS_N<6>")
	)
	(segment
		(start 269.1892 -103.07447)
		(end 269.1892 -120.677686)
		(width 0.14224)
		(layer "In4.Cu")
		(net "M_E_CS_N<6>")
	)
	(segment
		(start 269.1892 -102.83571)
		(end 269.1892 -103.07447)
		(width 0.0889)
		(layer "In4.Cu")
		(net "M_E_CS_N<6>")
	)
	(segment
		(start 276.708362 -134.797038)
		(end 276.708362 -137.998962)
		(width 0.14224)
		(layer "In4.Cu")
		(net "M_E_CS_N<6>")
	)
	(segment
		(start 268.478 -97.80143)
		(end 268.478 -101.1936)
		(width 0.0889)
		(layer "In4.Cu")
		(net "M_E_CS_N<6>")
	)
	(segment
		(start 276.8346 -131.1148)
		(end 276.712172 -131.237228)
		(width 0.14224)
		(layer "In4.Cu")
		(net "M_E_CS_N<6>")
	)
	(segment
		(start 272.24482 -124.650246)
		(end 276.85492 -129.260346)
		(width 0.14224)
		(layer "In4.Cu")
		(net "M_E_CS_N<6>")
	)
	(segment
		(start 269.3162 -102.70871)
		(end 269.1892 -102.83571)
		(width 0.0889)
		(layer "In4.Cu")
		(net "M_E_CS_N<6>")
	)
	(segment
		(start 268.478 -101.1936)
		(end 269.3162 -102.0318)
		(width 0.0889)
		(layer "In4.Cu")
		(net "M_E_CS_N<6>")
	)
	(segment
		(start 264.51433 -94.718886)
		(end 263.94283 -94.718886)
		(width 0.1016)
		(layer "F.Cu")
		(net "M_E_CS_N<5>")
	)
	(via
		(at 274.599908 -141.183868)
		(size 0.4572)
		(drill 0.2032)
		(layers "F.Cu" "B.Cu")
		(net "M_E_CS_N<5>")
	)
	(via
		(at 263.94283 -94.718886)
		(size 0.508)
		(drill 0.254)
		(layers "F.Cu" "B.Cu")
		(net "M_E_CS_N<5>")
	)
	(segment
		(start 274.600416 -142.477236)
		(end 274.599908 -142.476982)
		(width 0.1651)
		(layer "B.Cu")
		(net "M_E_CS_N<5>")
	)
	(segment
		(start 274.599908 -142.476982)
		(end 274.599908 -141.183868)
		(width 0.1651)
		(layer "B.Cu")
		(net "M_E_CS_N<5>")
	)
	(segment
		(start 265.319256 -97.48012)
		(end 265.312906 -97.490788)
		(width 0.0889)
		(layer "In4.Cu")
		(net "M_E_CS_N<5>")
	)
	(segment
		(start 265.312906 -98.481388)
		(end 265.30808 -98.490024)
		(width 0.0889)
		(layer "In4.Cu")
		(net "M_E_CS_N<5>")
	)
	(segment
		(start 264.801096 -95.61449)
		(end 264.822686 -95.61449)
		(width 0.0889)
		(layer "In4.Cu")
		(net "M_E_CS_N<5>")
	)
	(segment
		(start 263.94283 -94.718886)
		(end 264.438384 -95.385636)
		(width 0.0889)
		(layer "In4.Cu")
		(net "M_E_CS_N<5>")
	)
	(segment
		(start 270.21282 -124.434092)
		(end 270.21282 -125.49251)
		(width 0.14224)
		(layer "In4.Cu")
		(net "M_E_CS_N<5>")
	)
	(segment
		(start 273.18208 -130.32486)
		(end 273.545554 -130.688334)
		(width 0.14224)
		(layer "In4.Cu")
		(net "M_E_CS_N<5>")
	)
	(segment
		(start 273.46148 -134.861046)
		(end 273.46148 -135.800338)
		(width 0.14224)
		(layer "In4.Cu")
		(net "M_E_CS_N<5>")
	)
	(segment
		(start 266.6492 -102.1842)
		(end 266.6492 -102.7938)
		(width 0.0889)
		(layer "In4.Cu")
		(net "M_E_CS_N<5>")
	)
	(segment
		(start 274.163536 -140.067284)
		(end 274.599908 -140.503656)
		(width 0.14224)
		(layer "In4.Cu")
		(net "M_E_CS_N<5>")
	)
	(segment
		(start 273.133312 -131.514088)
		(end 273.133312 -132.44576)
		(width 0.14224)
		(layer "In4.Cu")
		(net "M_E_CS_N<5>")
	)
	(segment
		(start 266.6492 -102.7938)
		(end 267.1572 -103.3018)
		(width 0.0889)
		(layer "In4.Cu")
		(net "M_E_CS_N<5>")
	)
	(segment
		(start 265.319256 -98.47072)
		(end 265.312906 -98.481388)
		(width 0.0889)
		(layer "In4.Cu")
		(net "M_E_CS_N<5>")
	)
	(segment
		(start 265.557 -99.5426)
		(end 266.1158 -100.1014)
		(width 0.0889)
		(layer "In4.Cu")
		(net "M_E_CS_N<5>")
	)
	(segment
		(start 273.334988 -134.734554)
		(end 273.46148 -134.861046)
		(width 0.14224)
		(layer "In4.Cu")
		(net "M_E_CS_N<5>")
	)
	(segment
		(start 265.319256 -96.48952)
		(end 265.312906 -96.500188)
		(width 0.0889)
		(layer "In4.Cu")
		(net "M_E_CS_N<5>")
	)
	(segment
		(start 273.334988 -138.156188)
		(end 274.163536 -138.984736)
		(width 0.14224)
		(layer "In4.Cu")
		(net "M_E_CS_N<5>")
	)
	(segment
		(start 264.438384 -95.385636)
		(end 264.457942 -95.42018)
		(width 0.0889)
		(layer "In4.Cu")
		(net "M_E_CS_N<5>")
	)
	(segment
		(start 274.599908 -140.503656)
		(end 274.599908 -141.183868)
		(width 0.14224)
		(layer "In4.Cu")
		(net "M_E_CS_N<5>")
	)
	(segment
		(start 273.334988 -132.647436)
		(end 273.334988 -134.734554)
		(width 0.14224)
		(layer "In4.Cu")
		(net "M_E_CS_N<5>")
	)
	(segment
		(start 273.334988 -135.92683)
		(end 273.334988 -138.156188)
		(width 0.14224)
		(layer "In4.Cu")
		(net "M_E_CS_N<5>")
	)
	(segment
		(start 273.46148 -135.800338)
		(end 273.334988 -135.92683)
		(width 0.14224)
		(layer "In4.Cu")
		(net "M_E_CS_N<5>")
	)
	(segment
		(start 266.1158 -101.6508)
		(end 266.6492 -102.1842)
		(width 0.0889)
		(layer "In4.Cu")
		(net "M_E_CS_N<5>")
	)
	(segment
		(start 273.18208 -130.00482)
		(end 273.18208 -130.32486)
		(width 0.14224)
		(layer "In4.Cu")
		(net "M_E_CS_N<5>")
	)
	(segment
		(start 265.549126 -99.17049)
		(end 265.557 -99.178364)
		(width 0.0889)
		(layer "In4.Cu")
		(net "M_E_CS_N<5>")
	)
	(segment
		(start 273.431 -129.7559)
		(end 273.18208 -130.00482)
		(width 0.14224)
		(layer "In4.Cu")
		(net "M_E_CS_N<5>")
	)
	(segment
		(start 273.545554 -130.688334)
		(end 273.545554 -131.101846)
		(width 0.14224)
		(layer "In4.Cu")
		(net "M_E_CS_N<5>")
	)
	(segment
		(start 267.1572 -121.378472)
		(end 270.21282 -124.434092)
		(width 0.14224)
		(layer "In4.Cu")
		(net "M_E_CS_N<5>")
	)
	(segment
		(start 266.1158 -100.1014)
		(end 266.1158 -101.6508)
		(width 0.0889)
		(layer "In4.Cu")
		(net "M_E_CS_N<5>")
	)
	(segment
		(start 265.312906 -96.500188)
		(end 265.30808 -96.508824)
		(width 0.0889)
		(layer "In4.Cu")
		(net "M_E_CS_N<5>")
	)
	(segment
		(start 274.163536 -138.984736)
		(end 274.163536 -140.067284)
		(width 0.14224)
		(layer "In4.Cu")
		(net "M_E_CS_N<5>")
	)
	(segment
		(start 267.1572 -103.552498)
		(end 267.1572 -121.378472)
		(width 0.14224)
		(layer "In4.Cu")
		(net "M_E_CS_N<5>")
	)
	(segment
		(start 265.557 -99.178364)
		(end 265.557 -99.5426)
		(width 0.0889)
		(layer "In4.Cu")
		(net "M_E_CS_N<5>")
	)
	(segment
		(start 267.1572 -103.3018)
		(end 267.1572 -103.552498)
		(width 0.0889)
		(layer "In4.Cu")
		(net "M_E_CS_N<5>")
	)
	(segment
		(start 265.312906 -97.490788)
		(end 265.30808 -97.499424)
		(width 0.0889)
		(layer "In4.Cu")
		(net "M_E_CS_N<5>")
	)
	(segment
		(start 273.431 -128.71069)
		(end 273.431 -129.7559)
		(width 0.14224)
		(layer "In4.Cu")
		(net "M_E_CS_N<5>")
	)
	(segment
		(start 273.133312 -132.44576)
		(end 273.334988 -132.647436)
		(width 0.14224)
		(layer "In4.Cu")
		(net "M_E_CS_N<5>")
	)
	(segment
		(start 273.545554 -131.101846)
		(end 273.133312 -131.514088)
		(width 0.14224)
		(layer "In4.Cu")
		(net "M_E_CS_N<5>")
	)
	(segment
		(start 270.21282 -125.49251)
		(end 273.431 -128.71069)
		(width 0.14224)
		(layer "In4.Cu")
		(net "M_E_CS_N<5>")
	)
	(arc
		(start 265.312906 -98.881438)
		(mid 265.419259 -99.035571)
		(end 265.549126 -99.17049)
		(width 0.0889)
		(layer "In4.Cu")
		(net "M_E_CS_N<5>")
	)
	(arc
		(start 265.30808 -97.499424)
		(mid 265.259325 -97.695776)
		(end 265.312906 -97.890838)
		(width 0.0889)
		(layer "In4.Cu")
		(net "M_E_CS_N<5>")
	)
	(arc
		(start 265.312906 -96.900238)
		(mid 265.392128 -97.189356)
		(end 265.319256 -97.48012)
		(width 0.0889)
		(layer "In4.Cu")
		(net "M_E_CS_N<5>")
	)
	(arc
		(start 265.30808 -98.490024)
		(mid 265.259325 -98.686376)
		(end 265.312906 -98.881438)
		(width 0.0889)
		(layer "In4.Cu")
		(net "M_E_CS_N<5>")
	)
	(arc
		(start 264.822686 -95.61449)
		(mid 265.315076 -95.913423)
		(end 265.319256 -96.48952)
		(width 0.0889)
		(layer "In4.Cu")
		(net "M_E_CS_N<5>")
	)
	(arc
		(start 265.312906 -97.890838)
		(mid 265.392128 -98.179956)
		(end 265.319256 -98.47072)
		(width 0.0889)
		(layer "In4.Cu")
		(net "M_E_CS_N<5>")
	)
	(arc
		(start 265.30808 -96.508824)
		(mid 265.259325 -96.705176)
		(end 265.312906 -96.900238)
		(width 0.0889)
		(layer "In4.Cu")
		(net "M_E_CS_N<5>")
	)
	(arc
		(start 264.457942 -95.42018)
		(mid 264.603908 -95.562579)
		(end 264.801096 -95.61449)
		(width 0.0889)
		(layer "In4.Cu")
		(net "M_E_CS_N<5>")
	)
	(segment
		(start 263.65581 -98.18624)
		(end 263.08431 -98.18624)
		(width 0.1016)
		(layer "F.Cu")
		(net "M_E_CS_N<4>")
	)
	(via
		(at 263.08431 -98.18624)
		(size 0.508)
		(drill 0.254)
		(layers "F.Cu" "B.Cu")
		(net "M_E_CS_N<4>")
	)
	(via
		(at 270.350234 -141.187678)
		(size 0.4572)
		(drill 0.2032)
		(layers "F.Cu" "B.Cu")
		(net "M_E_CS_N<4>")
	)
	(segment
		(start 270.34998 -142.476982)
		(end 270.34998 -141.187932)
		(width 0.1651)
		(layer "B.Cu")
		(net "M_E_CS_N<4>")
	)
	(segment
		(start 270.350488 -142.477236)
		(end 270.34998 -142.476982)
		(width 0.1651)
		(layer "B.Cu")
		(net "M_E_CS_N<4>")
	)
	(segment
		(start 270.34998 -141.187932)
		(end 270.350234 -141.187678)
		(width 0.1651)
		(layer "B.Cu")
		(net "M_E_CS_N<4>")
	)
	(segment
		(start 264.0838 -102.5398)
		(end 264.6172 -103.0732)
		(width 0.0889)
		(layer "In4.Cu")
		(net "M_E_CS_N<4>")
	)
	(segment
		(start 269.034006 -129.387854)
		(end 269.034006 -129.816606)
		(width 0.14224)
		(layer "In4.Cu")
		(net "M_E_CS_N<4>")
	)
	(segment
		(start 269.1892 -133.8072)
		(end 269.084298 -133.912102)
		(width 0.14224)
		(layer "In4.Cu")
		(net "M_E_CS_N<4>")
	)
	(segment
		(start 269.0114 -131.2164)
		(end 269.1892 -131.3942)
		(width 0.14224)
		(layer "In4.Cu")
		(net "M_E_CS_N<4>")
	)
	(segment
		(start 269.084298 -133.912102)
		(end 269.084298 -134.743698)
		(width 0.14224)
		(layer "In4.Cu")
		(net "M_E_CS_N<4>")
	)
	(segment
		(start 268.37005 -127.530098)
		(end 268.236954 -127.663194)
		(width 0.14224)
		(layer "In4.Cu")
		(net "M_E_CS_N<4>")
	)
	(segment
		(start 268.539976 -128.315212)
		(end 269.018766 -128.315212)
		(width 0.14224)
		(layer "In4.Cu")
		(net "M_E_CS_N<4>")
	)
	(segment
		(start 269.087854 -136.092946)
		(end 269.087854 -138.074654)
		(width 0.14224)
		(layer "In4.Cu")
		(net "M_E_CS_N<4>")
	)
	(segment
		(start 266.093702 -123.81103)
		(end 265.65987 -124.244862)
		(width 0.14224)
		(layer "In4.Cu")
		(net "M_E_CS_N<4>")
	)
	(segment
		(start 264.79754 -123.67006)
		(end 265.085068 -123.67006)
		(width 0.14224)
		(layer "In4.Cu")
		(net "M_E_CS_N<4>")
	)
	(segment
		(start 268.236954 -128.01219)
		(end 268.539976 -128.315212)
		(width 0.14224)
		(layer "In4.Cu")
		(net "M_E_CS_N<4>")
	)
	(segment
		(start 269.084298 -134.743698)
		(end 269.1384 -134.7978)
		(width 0.14224)
		(layer "In4.Cu")
		(net "M_E_CS_N<4>")
	)
	(segment
		(start 269.1384 -136.0424)
		(end 269.087854 -136.092946)
		(width 0.14224)
		(layer "In4.Cu")
		(net "M_E_CS_N<4>")
	)
	(segment
		(start 265.65987 -124.244862)
		(end 265.65987 -124.53239)
		(width 0.14224)
		(layer "In4.Cu")
		(net "M_E_CS_N<4>")
	)
	(segment
		(start 264.6172 -123.48972)
		(end 264.79754 -123.67006)
		(width 0.14224)
		(layer "In4.Cu")
		(net "M_E_CS_N<4>")
	)
	(segment
		(start 269.1384 -129.921)
		(end 269.1384 -130.4798)
		(width 0.14224)
		(layer "In4.Cu")
		(net "M_E_CS_N<4>")
	)
	(segment
		(start 265.806428 -123.236228)
		(end 266.093702 -123.523502)
		(width 0.14224)
		(layer "In4.Cu")
		(net "M_E_CS_N<4>")
	)
	(segment
		(start 269.018766 -128.315212)
		(end 269.343378 -128.639824)
		(width 0.14224)
		(layer "In4.Cu")
		(net "M_E_CS_N<4>")
	)
	(segment
		(start 268.236954 -127.663194)
		(end 268.236954 -128.01219)
		(width 0.14224)
		(layer "In4.Cu")
		(net "M_E_CS_N<4>")
	)
	(segment
		(start 268.37005 -127.24257)
		(end 268.37005 -127.530098)
		(width 0.14224)
		(layer "In4.Cu")
		(net "M_E_CS_N<4>")
	)
	(segment
		(start 269.034006 -129.816606)
		(end 269.1384 -129.921)
		(width 0.14224)
		(layer "In4.Cu")
		(net "M_E_CS_N<4>")
	)
	(segment
		(start 269.343378 -128.639824)
		(end 269.343378 -129.078482)
		(width 0.14224)
		(layer "In4.Cu")
		(net "M_E_CS_N<4>")
	)
	(segment
		(start 269.927832 -140.765276)
		(end 270.350234 -141.187678)
		(width 0.14224)
		(layer "In4.Cu")
		(net "M_E_CS_N<4>")
	)
	(segment
		(start 265.5189 -123.236228)
		(end 265.806428 -123.236228)
		(width 0.14224)
		(layer "In4.Cu")
		(net "M_E_CS_N<4>")
	)
	(segment
		(start 266.093702 -123.523502)
		(end 266.093702 -123.81103)
		(width 0.14224)
		(layer "In4.Cu")
		(net "M_E_CS_N<4>")
	)
	(segment
		(start 264.0838 -102.2096)
		(end 264.0838 -102.5398)
		(width 0.0889)
		(layer "In4.Cu")
		(net "M_E_CS_N<4>")
	)
	(segment
		(start 269.087854 -138.074654)
		(end 269.927832 -138.914632)
		(width 0.14224)
		(layer "In4.Cu")
		(net "M_E_CS_N<4>")
	)
	(segment
		(start 263.4615 -99.2505)
		(end 263.4615 -101.5873)
		(width 0.0889)
		(layer "In4.Cu")
		(net "M_E_CS_N<4>")
	)
	(segment
		(start 264.6172 -103.0732)
		(end 264.6172 -103.279448)
		(width 0.0889)
		(layer "In4.Cu")
		(net "M_E_CS_N<4>")
	)
	(segment
		(start 265.65987 -124.53239)
		(end 268.37005 -127.24257)
		(width 0.14224)
		(layer "In4.Cu")
		(net "M_E_CS_N<4>")
	)
	(segment
		(start 263.08431 -98.87331)
		(end 263.4615 -99.2505)
		(width 0.0889)
		(layer "In4.Cu")
		(net "M_E_CS_N<4>")
	)
	(segment
		(start 269.1384 -134.7978)
		(end 269.1384 -136.0424)
		(width 0.14224)
		(layer "In4.Cu")
		(net "M_E_CS_N<4>")
	)
	(segment
		(start 269.0114 -130.6068)
		(end 269.0114 -131.2164)
		(width 0.14224)
		(layer "In4.Cu")
		(net "M_E_CS_N<4>")
	)
	(segment
		(start 269.343378 -129.078482)
		(end 269.034006 -129.387854)
		(width 0.14224)
		(layer "In4.Cu")
		(net "M_E_CS_N<4>")
	)
	(segment
		(start 265.085068 -123.67006)
		(end 265.5189 -123.236228)
		(width 0.14224)
		(layer "In4.Cu")
		(net "M_E_CS_N<4>")
	)
	(segment
		(start 269.1892 -131.3942)
		(end 269.1892 -133.8072)
		(width 0.14224)
		(layer "In4.Cu")
		(net "M_E_CS_N<4>")
	)
	(segment
		(start 263.4615 -101.5873)
		(end 264.0838 -102.2096)
		(width 0.0889)
		(layer "In4.Cu")
		(net "M_E_CS_N<4>")
	)
	(segment
		(start 269.927832 -138.914632)
		(end 269.927832 -140.765276)
		(width 0.14224)
		(layer "In4.Cu")
		(net "M_E_CS_N<4>")
	)
	(segment
		(start 263.08431 -98.18624)
		(end 263.08431 -98.87331)
		(width 0.0889)
		(layer "In4.Cu")
		(net "M_E_CS_N<4>")
	)
	(segment
		(start 269.1384 -130.4798)
		(end 269.0114 -130.6068)
		(width 0.14224)
		(layer "In4.Cu")
		(net "M_E_CS_N<4>")
	)
	(segment
		(start 264.6172 -103.279448)
		(end 264.6172 -123.48972)
		(width 0.14224)
		(layer "In4.Cu")
		(net "M_E_CS_N<4>")
	)
	(segment
		(start 277.999952 -147.27174)
		(end 278.00046 -147.27174)
		(width 0.1651)
		(layer "F.Cu")
		(net "M_E_CS_N<3>")
	)
	(segment
		(start 278.00046 -145.988278)
		(end 277.999952 -145.988786)
		(width 0.1651)
		(layer "F.Cu")
		(net "M_E_CS_N<3>")
	)
	(segment
		(start 277.999952 -145.988786)
		(end 277.999952 -147.27174)
		(width 0.1651)
		(layer "F.Cu")
		(net "M_E_CS_N<3>")
	)
	(segment
		(start 266.231116 -93.72854)
		(end 265.659616 -93.72854)
		(width 0.1016)
		(layer "F.Cu")
		(net "M_E_CS_N<3>")
	)
	(via
		(at 278.00046 -145.988278)
		(size 0.4572)
		(drill 0.2032)
		(layers "F.Cu" "B.Cu")
		(net "M_E_CS_N<3>")
	)
	(via
		(at 265.659616 -93.72854)
		(size 0.508)
		(drill 0.254)
		(layers "F.Cu" "B.Cu")
		(net "M_E_CS_N<3>")
	)
	(segment
		(start 277.999952 -144.706848)
		(end 277.999952 -145.98777)
		(width 0.14224)
		(layer "In4.Cu")
		(net "M_E_CS_N<3>")
	)
	(segment
		(start 278.2316 -139.6238)
		(end 278.2316 -140.0048)
		(width 0.14224)
		(layer "In4.Cu")
		(net "M_E_CS_N<3>")
	)
	(segment
		(start 278.407622 -132.095748)
		(end 278.407622 -134.697978)
		(width 0.14224)
		(layer "In4.Cu")
		(net "M_E_CS_N<3>")
	)
	(segment
		(start 278.5364 -136.9568)
		(end 278.5364 -139.319)
		(width 0.14224)
		(layer "In4.Cu")
		(net "M_E_CS_N<3>")
	)
	(segment
		(start 268.605 -96.974152)
		(end 269.0114 -97.380552)
		(width 0.0889)
		(layer "In4.Cu")
		(net "M_E_CS_N<3>")
	)
	(segment
		(start 278.48687 -128.48209)
		(end 278.48687 -129.76733)
		(width 0.14224)
		(layer "In4.Cu")
		(net "M_E_CS_N<3>")
	)
	(segment
		(start 278.5745 -144.1323)
		(end 277.999952 -144.706848)
		(width 0.14224)
		(layer "In4.Cu")
		(net "M_E_CS_N<3>")
	)
	(segment
		(start 278.5364 -139.319)
		(end 278.2316 -139.6238)
		(width 0.14224)
		(layer "In4.Cu")
		(net "M_E_CS_N<3>")
	)
	(segment
		(start 278.2316 -140.0048)
		(end 278.4856 -140.2588)
		(width 0.14224)
		(layer "In4.Cu")
		(net "M_E_CS_N<3>")
	)
	(segment
		(start 278.48687 -129.76733)
		(end 278.257 -129.9972)
		(width 0.14224)
		(layer "In4.Cu")
		(net "M_E_CS_N<3>")
	)
	(segment
		(start 270.2052 -120.20042)
		(end 278.48687 -128.48209)
		(width 0.14224)
		(layer "In4.Cu")
		(net "M_E_CS_N<3>")
	)
	(segment
		(start 278.257 -130.4544)
		(end 278.48687 -130.68427)
		(width 0.14224)
		(layer "In4.Cu")
		(net "M_E_CS_N<3>")
	)
	(segment
		(start 278.5745 -141.6431)
		(end 278.5745 -144.1323)
		(width 0.14224)
		(layer "In4.Cu")
		(net "M_E_CS_N<3>")
	)
	(segment
		(start 270.2052 -103.333804)
		(end 270.2052 -120.20042)
		(width 0.14224)
		(layer "In4.Cu")
		(net "M_E_CS_N<3>")
	)
	(segment
		(start 267.208 -94.234)
		(end 267.7922 -94.234)
		(width 0.0889)
		(layer "In4.Cu")
		(net "M_E_CS_N<3>")
	)
	(segment
		(start 277.999952 -145.98777)
		(end 278.00046 -145.988278)
		(width 0.14224)
		(layer "In4.Cu")
		(net "M_E_CS_N<3>")
	)
	(segment
		(start 270.2052 -103.096568)
		(end 270.2052 -103.333804)
		(width 0.0889)
		(layer "In4.Cu")
		(net "M_E_CS_N<3>")
	)
	(segment
		(start 270.0528 -102.944168)
		(end 270.2052 -103.096568)
		(width 0.0889)
		(layer "In4.Cu")
		(net "M_E_CS_N<3>")
	)
	(segment
		(start 278.429212 -134.719568)
		(end 278.429212 -136.849612)
		(width 0.14224)
		(layer "In4.Cu")
		(net "M_E_CS_N<3>")
	)
	(segment
		(start 268.605 -95.0468)
		(end 268.605 -96.974152)
		(width 0.0889)
		(layer "In4.Cu")
		(net "M_E_CS_N<3>")
	)
	(segment
		(start 265.659616 -93.72854)
		(end 266.70254 -93.72854)
		(width 0.0889)
		(layer "In4.Cu")
		(net "M_E_CS_N<3>")
	)
	(segment
		(start 278.257 -129.9972)
		(end 278.257 -130.4544)
		(width 0.14224)
		(layer "In4.Cu")
		(net "M_E_CS_N<3>")
	)
	(segment
		(start 278.4856 -141.5542)
		(end 278.5745 -141.6431)
		(width 0.14224)
		(layer "In4.Cu")
		(net "M_E_CS_N<3>")
	)
	(segment
		(start 278.429212 -136.849612)
		(end 278.5364 -136.9568)
		(width 0.14224)
		(layer "In4.Cu")
		(net "M_E_CS_N<3>")
	)
	(segment
		(start 267.7922 -94.234)
		(end 268.605 -95.0468)
		(width 0.0889)
		(layer "In4.Cu")
		(net "M_E_CS_N<3>")
	)
	(segment
		(start 278.4856 -140.2588)
		(end 278.4856 -141.5542)
		(width 0.14224)
		(layer "In4.Cu")
		(net "M_E_CS_N<3>")
	)
	(segment
		(start 270.0528 -101.6762)
		(end 270.0528 -102.944168)
		(width 0.0889)
		(layer "In4.Cu")
		(net "M_E_CS_N<3>")
	)
	(segment
		(start 278.407622 -134.697978)
		(end 278.429212 -134.719568)
		(width 0.14224)
		(layer "In4.Cu")
		(net "M_E_CS_N<3>")
	)
	(segment
		(start 278.48687 -130.68427)
		(end 278.48687 -132.0165)
		(width 0.14224)
		(layer "In4.Cu")
		(net "M_E_CS_N<3>")
	)
	(segment
		(start 266.70254 -93.72854)
		(end 267.208 -94.234)
		(width 0.0889)
		(layer "In4.Cu")
		(net "M_E_CS_N<3>")
	)
	(segment
		(start 269.0114 -100.6348)
		(end 270.0528 -101.6762)
		(width 0.0889)
		(layer "In4.Cu")
		(net "M_E_CS_N<3>")
	)
	(segment
		(start 269.0114 -97.380552)
		(end 269.0114 -100.6348)
		(width 0.0889)
		(layer "In4.Cu")
		(net "M_E_CS_N<3>")
	)
	(segment
		(start 278.48687 -132.0165)
		(end 278.407622 -132.095748)
		(width 0.14224)
		(layer "In4.Cu")
		(net "M_E_CS_N<3>")
	)
	(segment
		(start 277.999952 -142.677642)
		(end 277.999952 -143.972788)
		(width 0.1651)
		(layer "F.Cu")
		(net "M_E_CS_N<2>")
	)
	(segment
		(start 267.089636 -96.20504)
		(end 266.518136 -96.20504)
		(width 0.1016)
		(layer "F.Cu")
		(net "M_E_CS_N<2>")
	)
	(segment
		(start 278.00046 -142.6718)
		(end 277.999952 -142.677642)
		(width 0.1651)
		(layer "F.Cu")
		(net "M_E_CS_N<2>")
	)
	(via
		(at 266.518136 -96.20504)
		(size 0.508)
		(drill 0.254)
		(layers "F.Cu" "B.Cu")
		(net "M_E_CS_N<2>")
	)
	(via
		(at 277.999952 -143.972788)
		(size 0.4572)
		(drill 0.2032)
		(layers "F.Cu" "B.Cu")
		(net "M_E_CS_N<2>")
	)
	(segment
		(start 275.8186 -131.191)
		(end 275.9202 -131.2926)
		(width 0.14224)
		(layer "In4.Cu")
		(net "M_E_CS_N<2>")
	)
	(segment
		(start 268.1224 -98.0948)
		(end 268.1224 -101.3714)
		(width 0.0889)
		(layer "In4.Cu")
		(net "M_E_CS_N<2>")
	)
	(segment
		(start 275.827744 -128.951736)
		(end 275.827744 -129.879344)
		(width 0.14224)
		(layer "In4.Cu")
		(net "M_E_CS_N<2>")
	)
	(segment
		(start 266.827 -96.513904)
		(end 266.827 -96.7994)
		(width 0.0889)
		(layer "In4.Cu")
		(net "M_E_CS_N<2>")
	)
	(segment
		(start 275.9202 -131.2926)
		(end 275.9202 -131.953)
		(width 0.14224)
		(layer "In4.Cu")
		(net "M_E_CS_N<2>")
	)
	(segment
		(start 275.865082 -138.044682)
		(end 276.712172 -138.891772)
		(width 0.14224)
		(layer "In4.Cu")
		(net "M_E_CS_N<2>")
	)
	(segment
		(start 275.876258 -135.349742)
		(end 275.865082 -135.360918)
		(width 0.14224)
		(layer "In4.Cu")
		(net "M_E_CS_N<2>")
	)
	(segment
		(start 275.9202 -131.953)
		(end 275.876258 -131.996942)
		(width 0.14224)
		(layer "In4.Cu")
		(net "M_E_CS_N<2>")
	)
	(segment
		(start 276.712172 -140.060172)
		(end 277.585424 -140.933424)
		(width 0.14224)
		(layer "In4.Cu")
		(net "M_E_CS_N<2>")
	)
	(segment
		(start 268.6812 -102.960932)
		(end 268.6812 -120.859804)
		(width 0.14224)
		(layer "In4.Cu")
		(net "M_E_CS_N<2>")
	)
	(segment
		(start 268.8082 -102.0572)
		(end 268.8082 -102.543864)
		(width 0.0889)
		(layer "In4.Cu")
		(net "M_E_CS_N<2>")
	)
	(segment
		(start 271.73682 -124.860812)
		(end 275.827744 -128.951736)
		(width 0.14224)
		(layer "In4.Cu")
		(net "M_E_CS_N<2>")
	)
	(segment
		(start 266.827 -96.7994)
		(end 268.1224 -98.0948)
		(width 0.0889)
		(layer "In4.Cu")
		(net "M_E_CS_N<2>")
	)
	(segment
		(start 275.876258 -131.996942)
		(end 275.876258 -135.349742)
		(width 0.14224)
		(layer "In4.Cu")
		(net "M_E_CS_N<2>")
	)
	(segment
		(start 275.9202 -130.556)
		(end 275.8186 -130.6576)
		(width 0.14224)
		(layer "In4.Cu")
		(net "M_E_CS_N<2>")
	)
	(segment
		(start 277.585424 -141.539976)
		(end 277.5458 -141.5796)
		(width 0.14224)
		(layer "In4.Cu")
		(net "M_E_CS_N<2>")
	)
	(segment
		(start 277.585424 -140.933424)
		(end 277.585424 -141.539976)
		(width 0.14224)
		(layer "In4.Cu")
		(net "M_E_CS_N<2>")
	)
	(segment
		(start 268.6812 -120.859804)
		(end 271.73682 -123.915424)
		(width 0.14224)
		(layer "In4.Cu")
		(net "M_E_CS_N<2>")
	)
	(segment
		(start 268.8082 -102.543864)
		(end 268.6812 -102.670864)
		(width 0.0889)
		(layer "In4.Cu")
		(net "M_E_CS_N<2>")
	)
	(segment
		(start 276.712172 -138.891772)
		(end 276.712172 -140.060172)
		(width 0.14224)
		(layer "In4.Cu")
		(net "M_E_CS_N<2>")
	)
	(segment
		(start 271.73682 -123.915424)
		(end 271.73682 -124.860812)
		(width 0.14224)
		(layer "In4.Cu")
		(net "M_E_CS_N<2>")
	)
	(segment
		(start 275.8186 -130.6576)
		(end 275.8186 -131.191)
		(width 0.14224)
		(layer "In4.Cu")
		(net "M_E_CS_N<2>")
	)
	(segment
		(start 277.5458 -141.5796)
		(end 277.5458 -143.518636)
		(width 0.14224)
		(layer "In4.Cu")
		(net "M_E_CS_N<2>")
	)
	(segment
		(start 268.6812 -102.670864)
		(end 268.6812 -102.960932)
		(width 0.0889)
		(layer "In4.Cu")
		(net "M_E_CS_N<2>")
	)
	(segment
		(start 275.865082 -135.360918)
		(end 275.865082 -138.044682)
		(width 0.14224)
		(layer "In4.Cu")
		(net "M_E_CS_N<2>")
	)
	(segment
		(start 268.1224 -101.3714)
		(end 268.8082 -102.0572)
		(width 0.0889)
		(layer "In4.Cu")
		(net "M_E_CS_N<2>")
	)
	(segment
		(start 277.5458 -143.518636)
		(end 277.999952 -143.972788)
		(width 0.14224)
		(layer "In4.Cu")
		(net "M_E_CS_N<2>")
	)
	(segment
		(start 275.9202 -129.9718)
		(end 275.9202 -130.556)
		(width 0.14224)
		(layer "In4.Cu")
		(net "M_E_CS_N<2>")
	)
	(segment
		(start 275.827744 -129.879344)
		(end 275.9202 -129.9718)
		(width 0.14224)
		(layer "In4.Cu")
		(net "M_E_CS_N<2>")
	)
	(segment
		(start 266.518136 -96.20504)
		(end 266.827 -96.513904)
		(width 0.0889)
		(layer "In4.Cu")
		(net "M_E_CS_N<2>")
	)
	(segment
		(start 274.600416 -142.6718)
		(end 274.599908 -142.677642)
		(width 0.1651)
		(layer "F.Cu")
		(net "M_E_CS_N<1>")
	)
	(segment
		(start 263.65581 -95.21444)
		(end 263.08431 -95.21444)
		(width 0.1016)
		(layer "F.Cu")
		(net "M_E_CS_N<1>")
	)
	(segment
		(start 274.599908 -142.677642)
		(end 274.599908 -143.968978)
		(width 0.1651)
		(layer "F.Cu")
		(net "M_E_CS_N<1>")
	)
	(via
		(at 274.599908 -143.968978)
		(size 0.508)
		(drill 0.254)
		(layers "F.Cu" "B.Cu")
		(net "M_E_CS_N<1>")
	)
	(via
		(at 263.08431 -95.21444)
		(size 0.508)
		(drill 0.254)
		(layers "F.Cu" "B.Cu")
		(net "M_E_CS_N<1>")
	)
	(segment
		(start 265.147806 -97.395538)
		(end 265.141456 -97.406206)
		(width 0.0889)
		(layer "In4.Cu")
		(net "M_E_CS_N<1>")
	)
	(segment
		(start 263.92124 -96.300036)
		(end 263.94283 -96.300036)
		(width 0.0889)
		(layer "In4.Cu")
		(net "M_E_CS_N<1>")
	)
	(segment
		(start 272.4658 -131.9784)
		(end 272.4658 -134.7216)
		(width 0.14224)
		(layer "In4.Cu")
		(net "M_E_CS_N<1>")
	)
	(segment
		(start 274.187666 -143.556736)
		(end 274.599908 -143.968978)
		(width 0.14224)
		(layer "In4.Cu")
		(net "M_E_CS_N<1>")
	)
	(segment
		(start 272.4658 -134.7216)
		(end 272.5674 -134.8232)
		(width 0.14224)
		(layer "In4.Cu")
		(net "M_E_CS_N<1>")
	)
	(segment
		(start 272.542 -131.2672)
		(end 272.542 -131.9022)
		(width 0.14224)
		(layer "In4.Cu")
		(net "M_E_CS_N<1>")
	)
	(segment
		(start 264.285984 -96.494346)
		(end 264.289286 -96.500188)
		(width 0.0889)
		(layer "In4.Cu")
		(net "M_E_CS_N<1>")
	)
	(segment
		(start 263.414256 -95.976186)
		(end 263.43102 -96.004888)
		(width 0.0889)
		(layer "In4.Cu")
		(net "M_E_CS_N<1>")
	)
	(segment
		(start 272.461736 -136.043924)
		(end 272.461736 -138.019536)
		(width 0.14224)
		(layer "In4.Cu")
		(net "M_E_CS_N<1>")
	)
	(segment
		(start 273.2278 -140.015976)
		(end 274.187666 -140.975842)
		(width 0.14224)
		(layer "In4.Cu")
		(net "M_E_CS_N<1>")
	)
	(segment
		(start 273.2278 -139.5476)
		(end 273.2278 -140.015976)
		(width 0.14224)
		(layer "In4.Cu")
		(net "M_E_CS_N<1>")
	)
	(segment
		(start 265.811 -102.489)
		(end 266.6492 -103.3272)
		(width 0.0889)
		(layer "In4.Cu")
		(net "M_E_CS_N<1>")
	)
	(segment
		(start 266.6492 -103.53421)
		(end 266.6492 -121.532904)
		(width 0.14224)
		(layer "In4.Cu")
		(net "M_E_CS_N<1>")
	)
	(segment
		(start 272.461736 -138.019536)
		(end 273.338544 -138.896344)
		(width 0.14224)
		(layer "In4.Cu")
		(net "M_E_CS_N<1>")
	)
	(segment
		(start 272.542 -131.9022)
		(end 272.4658 -131.9784)
		(width 0.14224)
		(layer "In4.Cu")
		(net "M_E_CS_N<1>")
	)
	(segment
		(start 274.187666 -140.975842)
		(end 274.187666 -143.556736)
		(width 0.14224)
		(layer "In4.Cu")
		(net "M_E_CS_N<1>")
	)
	(segment
		(start 269.70482 -125.703076)
		(end 272.35277 -128.351026)
		(width 0.14224)
		(layer "In4.Cu")
		(net "M_E_CS_N<1>")
	)
	(segment
		(start 272.415 -131.1402)
		(end 272.542 -131.2672)
		(width 0.14224)
		(layer "In4.Cu")
		(net "M_E_CS_N<1>")
	)
	(segment
		(start 266.6492 -121.532904)
		(end 269.70482 -124.588524)
		(width 0.14224)
		(layer "In4.Cu")
		(net "M_E_CS_N<1>")
	)
	(segment
		(start 272.35277 -128.351026)
		(end 272.35277 -129.85877)
		(width 0.14224)
		(layer "In4.Cu")
		(net "M_E_CS_N<1>")
	)
	(segment
		(start 272.5674 -135.93826)
		(end 272.461736 -136.043924)
		(width 0.14224)
		(layer "In4.Cu")
		(net "M_E_CS_N<1>")
	)
	(segment
		(start 272.5928 -130.0988)
		(end 272.5928 -130.4798)
		(width 0.14224)
		(layer "In4.Cu")
		(net "M_E_CS_N<1>")
	)
	(segment
		(start 263.08431 -95.21444)
		(end 263.414256 -95.976186)
		(width 0.0889)
		(layer "In4.Cu")
		(net "M_E_CS_N<1>")
	)
	(segment
		(start 272.5674 -134.8232)
		(end 272.5674 -135.93826)
		(width 0.14224)
		(layer "In4.Cu")
		(net "M_E_CS_N<1>")
	)
	(segment
		(start 265.152632 -97.386902)
		(end 265.147806 -97.395538)
		(width 0.0889)
		(layer "In4.Cu")
		(net "M_E_CS_N<1>")
	)
	(segment
		(start 265.147806 -98.386138)
		(end 265.141456 -98.396806)
		(width 0.0889)
		(layer "In4.Cu")
		(net "M_E_CS_N<1>")
	)
	(segment
		(start 265.2014 -99.176586)
		(end 265.2014 -99.695)
		(width 0.0889)
		(layer "In4.Cu")
		(net "M_E_CS_N<1>")
	)
	(segment
		(start 264.783316 -96.79559)
		(end 264.816082 -96.79559)
		(width 0.0889)
		(layer "In4.Cu")
		(net "M_E_CS_N<1>")
	)
	(segment
		(start 273.338544 -138.896344)
		(end 273.338544 -139.436856)
		(width 0.14224)
		(layer "In4.Cu")
		(net "M_E_CS_N<1>")
	)
	(segment
		(start 266.6492 -103.3272)
		(end 266.6492 -103.53421)
		(width 0.0889)
		(layer "In4.Cu")
		(net "M_E_CS_N<1>")
	)
	(segment
		(start 265.152632 -98.377502)
		(end 265.147806 -98.386138)
		(width 0.0889)
		(layer "In4.Cu")
		(net "M_E_CS_N<1>")
	)
	(segment
		(start 265.2014 -99.695)
		(end 265.811 -100.3046)
		(width 0.0889)
		(layer "In4.Cu")
		(net "M_E_CS_N<1>")
	)
	(segment
		(start 269.70482 -124.588524)
		(end 269.70482 -125.703076)
		(width 0.14224)
		(layer "In4.Cu")
		(net "M_E_CS_N<1>")
	)
	(segment
		(start 272.415 -130.6576)
		(end 272.415 -131.1402)
		(width 0.14224)
		(layer "In4.Cu")
		(net "M_E_CS_N<1>")
	)
	(segment
		(start 272.35277 -129.85877)
		(end 272.5928 -130.0988)
		(width 0.14224)
		(layer "In4.Cu")
		(net "M_E_CS_N<1>")
	)
	(segment
		(start 273.338544 -139.436856)
		(end 273.2278 -139.5476)
		(width 0.14224)
		(layer "In4.Cu")
		(net "M_E_CS_N<1>")
	)
	(segment
		(start 272.5928 -130.4798)
		(end 272.415 -130.6576)
		(width 0.14224)
		(layer "In4.Cu")
		(net "M_E_CS_N<1>")
	)
	(segment
		(start 265.811 -100.3046)
		(end 265.811 -102.489)
		(width 0.0889)
		(layer "In4.Cu")
		(net "M_E_CS_N<1>")
	)
	(arc
		(start 263.94283 -96.300036)
		(mid 264.139991 -96.351995)
		(end 264.285984 -96.494346)
		(width 0.0889)
		(layer "In4.Cu")
		(net "M_E_CS_N<1>")
	)
	(arc
		(start 263.43102 -96.004888)
		(mid 263.638024 -96.215752)
		(end 263.92124 -96.300036)
		(width 0.0889)
		(layer "In4.Cu")
		(net "M_E_CS_N<1>")
	)
	(arc
		(start 264.289286 -96.500188)
		(mid 264.497894 -96.71212)
		(end 264.783316 -96.79559)
		(width 0.0889)
		(layer "In4.Cu")
		(net "M_E_CS_N<1>")
	)
	(arc
		(start 265.141456 -98.396806)
		(mid 265.068658 -98.687569)
		(end 265.147806 -98.976688)
		(width 0.0889)
		(layer "In4.Cu")
		(net "M_E_CS_N<1>")
	)
	(arc
		(start 265.147806 -97.986088)
		(mid 265.201276 -98.181151)
		(end 265.152632 -98.377502)
		(width 0.0889)
		(layer "In4.Cu")
		(net "M_E_CS_N<1>")
	)
	(arc
		(start 264.816082 -96.79559)
		(mid 265.149 -96.997581)
		(end 265.152632 -97.386902)
		(width 0.0889)
		(layer "In4.Cu")
		(net "M_E_CS_N<1>")
	)
	(arc
		(start 265.141456 -97.406206)
		(mid 265.068658 -97.696969)
		(end 265.147806 -97.986088)
		(width 0.0889)
		(layer "In4.Cu")
		(net "M_E_CS_N<1>")
	)
	(arc
		(start 265.147806 -98.976688)
		(mid 265.187749 -99.073111)
		(end 265.2014 -99.176586)
		(width 0.0889)
		(layer "In4.Cu")
		(net "M_E_CS_N<1>")
	)
	(segment
		(start 270.34998 -143.972534)
		(end 270.350234 -143.972788)
		(width 0.1651)
		(layer "F.Cu")
		(net "M_E_CS_N<0>")
	)
	(segment
		(start 270.350488 -142.6718)
		(end 270.34998 -142.677642)
		(width 0.1651)
		(layer "F.Cu")
		(net "M_E_CS_N<0>")
	)
	(segment
		(start 262.79729 -97.690686)
		(end 262.22579 -97.690686)
		(width 0.1016)
		(layer "F.Cu")
		(net "M_E_CS_N<0>")
	)
	(segment
		(start 270.34998 -142.677642)
		(end 270.34998 -143.972534)
		(width 0.1651)
		(layer "F.Cu")
		(net "M_E_CS_N<0>")
	)
	(via
		(at 270.350234 -143.972788)
		(size 0.4572)
		(drill 0.2032)
		(layers "F.Cu" "B.Cu")
		(net "M_E_CS_N<0>")
	)
	(via
		(at 262.22579 -97.690686)
		(size 0.508)
		(drill 0.254)
		(layers "F.Cu" "B.Cu")
		(net "M_E_CS_N<0>")
	)
	(segment
		(start 267.4366 -127.028194)
		(end 267.4366 -127.79502)
		(width 0.14224)
		(layer "In4.Cu")
		(net "M_E_CS_N<0>")
	)
	(segment
		(start 268.213078 -133.859524)
		(end 268.213078 -134.783322)
		(width 0.14224)
		(layer "In4.Cu")
		(net "M_E_CS_N<0>")
	)
	(segment
		(start 267.081508 -128.43764)
		(end 267.447268 -128.8034)
		(width 0.14224)
		(layer "In4.Cu")
		(net "M_E_CS_N<0>")
	)
	(segment
		(start 267.905738 -133.144006)
		(end 267.905738 -133.552184)
		(width 0.14224)
		(layer "In4.Cu")
		(net "M_E_CS_N<0>")
	)
	(segment
		(start 268.593062 -132.93979)
		(end 268.109954 -132.93979)
		(width 0.14224)
		(layer "In4.Cu")
		(net "M_E_CS_N<0>")
	)
	(segment
		(start 269.059914 -141.389608)
		(end 269.390876 -141.72057)
		(width 0.14224)
		(layer "In4.Cu")
		(net "M_E_CS_N<0>")
	)
	(segment
		(start 268.3764 -136.8298)
		(end 268.3764 -138.1252)
		(width 0.14224)
		(layer "In4.Cu")
		(net "M_E_CS_N<0>")
	)
	(segment
		(start 268.109954 -132.93979)
		(end 267.905738 -133.144006)
		(width 0.14224)
		(layer "In4.Cu")
		(net "M_E_CS_N<0>")
	)
	(segment
		(start 269.084298 -138.833098)
		(end 269.084298 -139.468098)
		(width 0.14224)
		(layer "In4.Cu")
		(net "M_E_CS_N<0>")
	)
	(segment
		(start 268.1732 -130.5306)
		(end 268.2748 -130.6322)
		(width 0.14224)
		(layer "In4.Cu")
		(net "M_E_CS_N<0>")
	)
	(segment
		(start 263.0678 -101.7524)
		(end 263.8044 -102.489)
		(width 0.0889)
		(layer "In4.Cu")
		(net "M_E_CS_N<0>")
	)
	(segment
		(start 268.748002 -132.78485)
		(end 268.593062 -132.93979)
		(width 0.14224)
		(layer "In4.Cu")
		(net "M_E_CS_N<0>")
	)
	(segment
		(start 264.1092 -123.70054)
		(end 266.44473 -126.03607)
		(width 0.14224)
		(layer "In4.Cu")
		(net "M_E_CS_N<0>")
	)
	(segment
		(start 269.390876 -141.72057)
		(end 269.922244 -141.72057)
		(width 0.14224)
		(layer "In4.Cu")
		(net "M_E_CS_N<0>")
	)
	(segment
		(start 267.081508 -128.150112)
		(end 267.081508 -128.43764)
		(width 0.14224)
		(layer "In4.Cu")
		(net "M_E_CS_N<0>")
	)
	(segment
		(start 268.5034 -129.6162)
		(end 268.1732 -129.9464)
		(width 0.14224)
		(layer "In4.Cu")
		(net "M_E_CS_N<0>")
	)
	(segment
		(start 268.593062 -132.27685)
		(end 268.748002 -132.43179)
		(width 0.14224)
		(layer "In4.Cu")
		(net "M_E_CS_N<0>")
	)
	(segment
		(start 268.110462 -134.885938)
		(end 268.110462 -136.005062)
		(width 0.14224)
		(layer "In4.Cu")
		(net "M_E_CS_N<0>")
	)
	(segment
		(start 268.110462 -136.005062)
		(end 268.214856 -136.109456)
		(width 0.14224)
		(layer "In4.Cu")
		(net "M_E_CS_N<0>")
	)
	(segment
		(start 267.447268 -128.8034)
		(end 268.201648 -128.8034)
		(width 0.14224)
		(layer "In4.Cu")
		(net "M_E_CS_N<0>")
	)
	(segment
		(start 269.084298 -139.468098)
		(end 269.113 -139.4968)
		(width 0.14224)
		(layer "In4.Cu")
		(net "M_E_CS_N<0>")
	)
	(segment
		(start 262.6614 -99.0346)
		(end 263.0678 -99.441)
		(width 0.0889)
		(layer "In4.Cu")
		(net "M_E_CS_N<0>")
	)
	(segment
		(start 268.02461 -131.44119)
		(end 268.02461 -132.12191)
		(width 0.14224)
		(layer "In4.Cu")
		(net "M_E_CS_N<0>")
	)
	(segment
		(start 268.02461 -132.12191)
		(end 268.17955 -132.27685)
		(width 0.14224)
		(layer "In4.Cu")
		(net "M_E_CS_N<0>")
	)
	(segment
		(start 268.213078 -134.783322)
		(end 268.110462 -134.885938)
		(width 0.14224)
		(layer "In4.Cu")
		(net "M_E_CS_N<0>")
	)
	(segment
		(start 267.4366 -127.79502)
		(end 267.081508 -128.150112)
		(width 0.14224)
		(layer "In4.Cu")
		(net "M_E_CS_N<0>")
	)
	(segment
		(start 268.2748 -131.191)
		(end 268.02461 -131.44119)
		(width 0.14224)
		(layer "In4.Cu")
		(net "M_E_CS_N<0>")
	)
	(segment
		(start 270.350234 -142.14856)
		(end 270.350234 -143.972788)
		(width 0.14224)
		(layer "In4.Cu")
		(net "M_E_CS_N<0>")
	)
	(segment
		(start 268.2748 -130.6322)
		(end 268.2748 -131.191)
		(width 0.14224)
		(layer "In4.Cu")
		(net "M_E_CS_N<0>")
	)
	(segment
		(start 269.113 -139.4968)
		(end 269.113 -140.699236)
		(width 0.14224)
		(layer "In4.Cu")
		(net "M_E_CS_N<0>")
	)
	(segment
		(start 268.748002 -132.43179)
		(end 268.748002 -132.78485)
		(width 0.14224)
		(layer "In4.Cu")
		(net "M_E_CS_N<0>")
	)
	(segment
		(start 266.444476 -126.03607)
		(end 267.4366 -127.028194)
		(width 0.14224)
		(layer "In4.Cu")
		(net "M_E_CS_N<0>")
	)
	(segment
		(start 266.44473 -126.03607)
		(end 266.444476 -126.03607)
		(width 0.14224)
		(layer "In4.Cu")
		(net "M_E_CS_N<0>")
	)
	(segment
		(start 262.6614 -98.126296)
		(end 262.6614 -99.0346)
		(width 0.0889)
		(layer "In4.Cu")
		(net "M_E_CS_N<0>")
	)
	(segment
		(start 268.201648 -128.8034)
		(end 268.5034 -129.105152)
		(width 0.14224)
		(layer "In4.Cu")
		(net "M_E_CS_N<0>")
	)
	(segment
		(start 264.1092 -103.26116)
		(end 264.1092 -123.70054)
		(width 0.14224)
		(layer "In4.Cu")
		(net "M_E_CS_N<0>")
	)
	(segment
		(start 268.1732 -129.9464)
		(end 268.1732 -130.5306)
		(width 0.14224)
		(layer "In4.Cu")
		(net "M_E_CS_N<0>")
	)
	(segment
		(start 267.905738 -133.552184)
		(end 268.213078 -133.859524)
		(width 0.14224)
		(layer "In4.Cu")
		(net "M_E_CS_N<0>")
	)
	(segment
		(start 269.113 -140.699236)
		(end 269.059914 -140.752322)
		(width 0.14224)
		(layer "In4.Cu")
		(net "M_E_CS_N<0>")
	)
	(segment
		(start 263.8044 -102.489)
		(end 263.8044 -102.759764)
		(width 0.0889)
		(layer "In4.Cu")
		(net "M_E_CS_N<0>")
	)
	(segment
		(start 268.3764 -138.1252)
		(end 269.084298 -138.833098)
		(width 0.14224)
		(layer "In4.Cu")
		(net "M_E_CS_N<0>")
	)
	(segment
		(start 268.17955 -132.27685)
		(end 268.593062 -132.27685)
		(width 0.14224)
		(layer "In4.Cu")
		(net "M_E_CS_N<0>")
	)
	(segment
		(start 268.5034 -129.105152)
		(end 268.5034 -129.6162)
		(width 0.14224)
		(layer "In4.Cu")
		(net "M_E_CS_N<0>")
	)
	(segment
		(start 268.214856 -136.109456)
		(end 268.214856 -136.668256)
		(width 0.14224)
		(layer "In4.Cu")
		(net "M_E_CS_N<0>")
	)
	(segment
		(start 264.1092 -103.064564)
		(end 264.1092 -103.26116)
		(width 0.0889)
		(layer "In4.Cu")
		(net "M_E_CS_N<0>")
	)
	(segment
		(start 263.0678 -99.441)
		(end 263.0678 -101.7524)
		(width 0.0889)
		(layer "In4.Cu")
		(net "M_E_CS_N<0>")
	)
	(segment
		(start 263.8044 -102.759764)
		(end 264.1092 -103.064564)
		(width 0.0889)
		(layer "In4.Cu")
		(net "M_E_CS_N<0>")
	)
	(segment
		(start 262.22579 -97.690686)
		(end 262.6614 -98.126296)
		(width 0.0889)
		(layer "In4.Cu")
		(net "M_E_CS_N<0>")
	)
	(segment
		(start 268.214856 -136.668256)
		(end 268.3764 -136.8298)
		(width 0.14224)
		(layer "In4.Cu")
		(net "M_E_CS_N<0>")
	)
	(segment
		(start 269.922244 -141.72057)
		(end 270.350234 -142.14856)
		(width 0.14224)
		(layer "In4.Cu")
		(net "M_E_CS_N<0>")
	)
	(segment
		(start 269.059914 -140.752322)
		(end 269.059914 -141.389608)
		(width 0.14224)
		(layer "In4.Cu")
		(net "M_E_CS_N<0>")
	)
	(segment
		(start 258.50469 -96.20504)
		(end 257.93319 -96.20504)
		(width 0.1016)
		(layer "F.Cu")
		(net "M_E_CLK_DP<3>")
	)
	(via
		(at 256.826004 -139.170156)
		(size 0.508)
		(drill 0.254)
		(layers "F.Cu" "B.Cu")
		(net "M_E_CLK_DP<3>")
	)
	(via
		(at 257.93319 -96.20504)
		(size 0.508)
		(drill 0.254)
		(layers "F.Cu" "B.Cu")
		(net "M_E_CLK_DP<3>")
	)
	(segment
		(start 256.749804 -137.877296)
		(end 256.749804 -139.093956)
		(width 0.1651)
		(layer "B.Cu")
		(net "M_E_CLK_DP<3>")
	)
	(segment
		(start 256.749804 -139.093956)
		(end 256.826004 -139.170156)
		(width 0.1651)
		(layer "B.Cu")
		(net "M_E_CLK_DP<3>")
	)
	(segment
		(start 256.750312 -137.877296)
		(end 256.749804 -137.877296)
		(width 0.1651)
		(layer "B.Cu")
		(net "M_E_CLK_DP<3>")
	)
	(segment
		(start 257.531362 -137.707624)
		(end 257.531362 -137.354564)
		(width 0.14224)
		(layer "In4.Cu")
		(net "M_E_CLK_DP<3>")
	)
	(segment
		(start 258.972812 -131.166616)
		(end 258.972812 -104.015794)
		(width 0.14224)
		(layer "In4.Cu")
		(net "M_E_CLK_DP<3>")
	)
	(segment
		(start 257.695446 -137.19048)
		(end 258.9657 -137.19048)
		(width 0.14224)
		(layer "In4.Cu")
		(net "M_E_CLK_DP<3>")
	)
	(segment
		(start 259.27812 -133.045962)
		(end 258.900168 -132.66801)
		(width 0.14224)
		(layer "In4.Cu")
		(net "M_E_CLK_DP<3>")
	)
	(segment
		(start 256.95148 -139.295632)
		(end 256.95148 -139.934696)
		(width 0.14224)
		(layer "In4.Cu")
		(net "M_E_CLK_DP<3>")
	)
	(segment
		(start 259.27812 -139.34948)
		(end 259.27812 -138.16584)
		(width 0.14224)
		(layer "In4.Cu")
		(net "M_E_CLK_DP<3>")
	)
	(segment
		(start 258.900168 -132.66801)
		(end 257.760724 -132.66801)
		(width 0.14224)
		(layer "In4.Cu")
		(net "M_E_CLK_DP<3>")
	)
	(segment
		(start 258.470654 -131.668774)
		(end 258.972812 -131.166616)
		(width 0.14224)
		(layer "In4.Cu")
		(net "M_E_CLK_DP<3>")
	)
	(segment
		(start 257.531362 -137.354564)
		(end 257.695446 -137.19048)
		(width 0.14224)
		(layer "In4.Cu")
		(net "M_E_CLK_DP<3>")
	)
	(segment
		(start 258.9657 -137.19048)
		(end 259.27812 -136.87806)
		(width 0.14224)
		(layer "In4.Cu")
		(net "M_E_CLK_DP<3>")
	)
	(segment
		(start 257.677158 -137.85342)
		(end 257.531362 -137.707624)
		(width 0.14224)
		(layer "In4.Cu")
		(net "M_E_CLK_DP<3>")
	)
	(segment
		(start 257.760724 -132.66801)
		(end 257.581654 -132.48894)
		(width 0.14224)
		(layer "In4.Cu")
		(net "M_E_CLK_DP<3>")
	)
	(segment
		(start 258.0894 -100.5078)
		(end 257.694176 -100.112576)
		(width 0.0889)
		(layer "In4.Cu")
		(net "M_E_CLK_DP<3>")
	)
	(segment
		(start 258.2926 -140.335)
		(end 259.27812 -139.34948)
		(width 0.14224)
		(layer "In4.Cu")
		(net "M_E_CLK_DP<3>")
	)
	(segment
		(start 257.585972 -97.394268)
		(end 257.581654 -97.386902)
		(width 0.0889)
		(layer "In4.Cu")
		(net "M_E_CLK_DP<3>")
	)
	(segment
		(start 257.581654 -131.87553)
		(end 257.78841 -131.668774)
		(width 0.14224)
		(layer "In4.Cu")
		(net "M_E_CLK_DP<3>")
	)
	(segment
		(start 256.826004 -139.170156)
		(end 256.95148 -139.295632)
		(width 0.14224)
		(layer "In4.Cu")
		(net "M_E_CLK_DP<3>")
	)
	(segment
		(start 256.95148 -139.934696)
		(end 257.351784 -140.335)
		(width 0.14224)
		(layer "In4.Cu")
		(net "M_E_CLK_DP<3>")
	)
	(segment
		(start 258.0894 -102.641146)
		(end 258.0894 -100.5078)
		(width 0.0889)
		(layer "In4.Cu")
		(net "M_E_CLK_DP<3>")
	)
	(segment
		(start 259.27812 -138.16584)
		(end 258.9657 -137.85342)
		(width 0.14224)
		(layer "In4.Cu")
		(net "M_E_CLK_DP<3>")
	)
	(segment
		(start 258.9276 -103.479346)
		(end 258.0894 -102.641146)
		(width 0.0889)
		(layer "In4.Cu")
		(net "M_E_CLK_DP<3>")
	)
	(segment
		(start 258.972812 -104.015794)
		(end 258.972812 -103.98633)
		(width 0.0889)
		(layer "In4.Cu")
		(net "M_E_CLK_DP<3>")
	)
	(segment
		(start 258.9657 -137.85342)
		(end 257.677158 -137.85342)
		(width 0.14224)
		(layer "In4.Cu")
		(net "M_E_CLK_DP<3>")
	)
	(segment
		(start 257.581654 -132.48894)
		(end 257.581654 -131.87553)
		(width 0.14224)
		(layer "In4.Cu")
		(net "M_E_CLK_DP<3>")
	)
	(segment
		(start 257.351784 -140.335)
		(end 258.2926 -140.335)
		(width 0.14224)
		(layer "In4.Cu")
		(net "M_E_CLK_DP<3>")
	)
	(segment
		(start 257.78841 -131.668774)
		(end 258.470654 -131.668774)
		(width 0.14224)
		(layer "In4.Cu")
		(net "M_E_CLK_DP<3>")
	)
	(segment
		(start 258.9276 -103.941118)
		(end 258.9276 -103.479346)
		(width 0.0889)
		(layer "In4.Cu")
		(net "M_E_CLK_DP<3>")
	)
	(segment
		(start 259.27812 -136.87806)
		(end 259.27812 -133.045962)
		(width 0.14224)
		(layer "In4.Cu")
		(net "M_E_CLK_DP<3>")
	)
	(segment
		(start 258.972812 -103.98633)
		(end 258.9276 -103.941118)
		(width 0.0889)
		(layer "In4.Cu")
		(net "M_E_CLK_DP<3>")
	)
	(segment
		(start 257.694176 -100.112576)
		(end 257.694176 -97.71507)
		(width 0.0889)
		(layer "In4.Cu")
		(net "M_E_CLK_DP<3>")
	)
	(segment
		(start 257.76047 -96.37776)
		(end 257.93319 -96.20504)
		(width 0.0889)
		(layer "In4.Cu")
		(net "M_E_CLK_DP<3>")
	)
	(arc
		(start 257.58648 -96.995488)
		(mid 257.651838 -96.826926)
		(end 257.663188 -96.646492)
		(width 0.0889)
		(layer "In4.Cu")
		(net "M_E_CLK_DP<3>")
	)
	(arc
		(start 257.663188 -96.646492)
		(mid 257.681934 -96.501307)
		(end 257.76047 -96.37776)
		(width 0.0889)
		(layer "In4.Cu")
		(net "M_E_CLK_DP<3>")
	)
	(arc
		(start 257.581654 -97.386902)
		(mid 257.575898 -97.376066)
		(end 257.570478 -97.365058)
		(width 0.0889)
		(layer "In4.Cu")
		(net "M_E_CLK_DP<3>")
	)
	(arc
		(start 257.694176 -97.71507)
		(mid 257.656075 -97.549271)
		(end 257.585972 -97.394268)
		(width 0.0889)
		(layer "In4.Cu")
		(net "M_E_CLK_DP<3>")
	)
	(arc
		(start 257.570478 -97.365058)
		(mid 257.533237 -97.178315)
		(end 257.58648 -96.995488)
		(width 0.0889)
		(layer "In4.Cu")
		(net "M_E_CLK_DP<3>")
	)
	(segment
		(start 256.749804 -147.27174)
		(end 256.749804 -145.984468)
		(width 0.1651)
		(layer "F.Cu")
		(net "M_E_CLK_DP<1>")
	)
	(segment
		(start 260.50875 -96.700086)
		(end 261.08025 -96.700086)
		(width 0.1016)
		(layer "F.Cu")
		(net "M_E_CLK_DP<1>")
	)
	(segment
		(start 256.750312 -147.27174)
		(end 256.749804 -147.27174)
		(width 0.1651)
		(layer "F.Cu")
		(net "M_E_CLK_DP<1>")
	)
	(via
		(at 260.50875 -96.700086)
		(size 0.508)
		(drill 0.254)
		(layers "F.Cu" "B.Cu")
		(net "M_E_CLK_DP<1>")
	)
	(via
		(at 256.749804 -145.984468)
		(size 0.508)
		(drill 0.254)
		(layers "F.Cu" "B.Cu")
		(net "M_E_CLK_DP<1>")
	)
	(segment
		(start 260.16204 -98.481388)
		(end 260.157214 -98.490024)
		(width 0.0889)
		(layer "In4.Cu")
		(net "M_E_CLK_DP<1>")
	)
	(segment
		(start 260.215634 -96.531176)
		(end 260.136894 -96.552512)
		(width 0.0889)
		(layer "In4.Cu")
		(net "M_E_CLK_DP<1>")
	)
	(segment
		(start 261.9502 -141.677136)
		(end 261.9502 -144.798288)
		(width 0.14224)
		(layer "In4.Cu")
		(net "M_E_CLK_DP<1>")
	)
	(segment
		(start 257.061208 -146.295872)
		(end 256.749804 -145.984468)
		(width 0.14224)
		(layer "In4.Cu")
		(net "M_E_CLK_DP<1>")
	)
	(segment
		(start 260.50875 -96.700086)
		(end 260.215634 -96.531176)
		(width 0.0889)
		(layer "In4.Cu")
		(net "M_E_CLK_DP<1>")
	)
	(segment
		(start 260.107684 -101.95179)
		(end 261.417054 -103.26116)
		(width 0.0889)
		(layer "In4.Cu")
		(net "M_E_CLK_DP<1>")
	)
	(segment
		(start 261.417054 -103.26116)
		(end 261.417054 -103.899462)
		(width 0.0889)
		(layer "In4.Cu")
		(net "M_E_CLK_DP<1>")
	)
	(segment
		(start 261.417054 -103.899462)
		(end 261.450836 -103.933244)
		(width 0.0889)
		(layer "In4.Cu")
		(net "M_E_CLK_DP<1>")
	)
	(segment
		(start 260.16839 -97.48012)
		(end 260.16204 -97.490788)
		(width 0.0889)
		(layer "In4.Cu")
		(net "M_E_CLK_DP<1>")
	)
	(segment
		(start 257.54711 -147.26412)
		(end 257.061208 -146.778218)
		(width 0.14224)
		(layer "In4.Cu")
		(net "M_E_CLK_DP<1>")
	)
	(segment
		(start 257.061208 -146.778218)
		(end 257.061208 -146.295872)
		(width 0.14224)
		(layer "In4.Cu")
		(net "M_E_CLK_DP<1>")
	)
	(segment
		(start 259.484368 -147.26412)
		(end 257.54711 -147.26412)
		(width 0.14224)
		(layer "In4.Cu")
		(net "M_E_CLK_DP<1>")
	)
	(segment
		(start 261.9502 -144.798288)
		(end 259.484368 -147.26412)
		(width 0.14224)
		(layer "In4.Cu")
		(net "M_E_CLK_DP<1>")
	)
	(segment
		(start 260.16839 -99.461066)
		(end 260.107684 -99.569778)
		(width 0.0889)
		(layer "In4.Cu")
		(net "M_E_CLK_DP<1>")
	)
	(segment
		(start 261.450836 -103.933244)
		(end 261.450836 -126.785878)
		(width 0.14224)
		(layer "In4.Cu")
		(net "M_E_CLK_DP<1>")
	)
	(segment
		(start 262.250936 -127.585978)
		(end 262.250936 -141.3764)
		(width 0.14224)
		(layer "In4.Cu")
		(net "M_E_CLK_DP<1>")
	)
	(segment
		(start 262.250936 -141.3764)
		(end 261.9502 -141.677136)
		(width 0.14224)
		(layer "In4.Cu")
		(net "M_E_CLK_DP<1>")
	)
	(segment
		(start 260.16839 -98.47072)
		(end 260.16204 -98.481388)
		(width 0.0889)
		(layer "In4.Cu")
		(net "M_E_CLK_DP<1>")
	)
	(segment
		(start 261.450836 -126.785878)
		(end 262.250936 -127.585978)
		(width 0.14224)
		(layer "In4.Cu")
		(net "M_E_CLK_DP<1>")
	)
	(segment
		(start 260.107684 -99.569778)
		(end 260.107684 -101.95179)
		(width 0.0889)
		(layer "In4.Cu")
		(net "M_E_CLK_DP<1>")
	)
	(segment
		(start 260.16204 -97.490788)
		(end 260.157214 -97.499424)
		(width 0.0889)
		(layer "In4.Cu")
		(net "M_E_CLK_DP<1>")
	)
	(arc
		(start 260.16204 -96.900238)
		(mid 260.241262 -97.189356)
		(end 260.16839 -97.48012)
		(width 0.0889)
		(layer "In4.Cu")
		(net "M_E_CLK_DP<1>")
	)
	(arc
		(start 260.136894 -96.552512)
		(mid 260.115692 -96.625588)
		(end 260.1087 -96.701356)
		(width 0.0889)
		(layer "In4.Cu")
		(net "M_E_CLK_DP<1>")
	)
	(arc
		(start 260.157214 -98.490024)
		(mid 260.108459 -98.686376)
		(end 260.16204 -98.881438)
		(width 0.0889)
		(layer "In4.Cu")
		(net "M_E_CLK_DP<1>")
	)
	(arc
		(start 260.16204 -98.881438)
		(mid 260.214598 -99.001203)
		(end 260.23951 -99.129596)
		(width 0.0889)
		(layer "In4.Cu")
		(net "M_E_CLK_DP<1>")
	)
	(arc
		(start 260.16204 -97.890838)
		(mid 260.241262 -98.179956)
		(end 260.16839 -98.47072)
		(width 0.0889)
		(layer "In4.Cu")
		(net "M_E_CLK_DP<1>")
	)
	(arc
		(start 260.1087 -96.701356)
		(mid 260.122362 -96.804286)
		(end 260.16204 -96.900238)
		(width 0.0889)
		(layer "In4.Cu")
		(net "M_E_CLK_DP<1>")
	)
	(arc
		(start 260.23951 -99.129596)
		(mid 260.228238 -99.300545)
		(end 260.16839 -99.461066)
		(width 0.0889)
		(layer "In4.Cu")
		(net "M_E_CLK_DP<1>")
	)
	(arc
		(start 260.157214 -97.499424)
		(mid 260.108459 -97.695776)
		(end 260.16204 -97.890838)
		(width 0.0889)
		(layer "In4.Cu")
		(net "M_E_CLK_DP<1>")
	)
	(segment
		(start 258.50469 -95.21444)
		(end 257.93319 -95.21444)
		(width 0.1016)
		(layer "F.Cu")
		(net "M_E_CLK_DP<2>")
	)
	(via
		(at 257.93319 -95.21444)
		(size 0.508)
		(drill 0.254)
		(layers "F.Cu" "B.Cu")
		(net "M_E_CLK_DP<2>")
	)
	(via
		(at 256.775712 -141.183868)
		(size 0.508)
		(drill 0.254)
		(layers "F.Cu" "B.Cu")
		(net "M_E_CLK_DP<2>")
	)
	(segment
		(start 256.750312 -142.477236)
		(end 256.749804 -142.476982)
		(width 0.1651)
		(layer "B.Cu")
		(net "M_E_CLK_DP<2>")
	)
	(segment
		(start 256.749804 -142.476982)
		(end 256.749804 -141.209776)
		(width 0.1651)
		(layer "B.Cu")
		(net "M_E_CLK_DP<2>")
	)
	(segment
		(start 256.749804 -141.209776)
		(end 256.775712 -141.183868)
		(width 0.1651)
		(layer "B.Cu")
		(net "M_E_CLK_DP<2>")
	)
	(segment
		(start 256.775712 -141.209776)
		(end 256.775712 -141.183868)
		(width 0.14224)
		(layer "In4.Cu")
		(net "M_E_CLK_DP<2>")
	)
	(segment
		(start 258.7244 -102.3874)
		(end 259.7658 -103.4288)
		(width 0.0889)
		(layer "In4.Cu")
		(net "M_E_CLK_DP<2>")
	)
	(segment
		(start 257.93319 -95.21444)
		(end 257.640074 -95.045276)
		(width 0.0889)
		(layer "In4.Cu")
		(net "M_E_CLK_DP<2>")
	)
	(segment
		(start 257.640074 -95.045276)
		(end 257.561334 -95.066612)
		(width 0.0889)
		(layer "In4.Cu")
		(net "M_E_CLK_DP<2>")
	)
	(segment
		(start 260.249416 -141.419072)
		(end 259.281168 -142.38732)
		(width 0.14224)
		(layer "In4.Cu")
		(net "M_E_CLK_DP<2>")
	)
	(segment
		(start 257.008122 -141.937232)
		(end 257.008122 -141.442186)
		(width 0.14224)
		(layer "In4.Cu")
		(net "M_E_CLK_DP<2>")
	)
	(segment
		(start 258.358894 -98.015806)
		(end 258.3688 -98.065336)
		(width 0.0889)
		(layer "In4.Cu")
		(net "M_E_CLK_DP<2>")
	)
	(segment
		(start 259.81152 -132.023866)
		(end 260.249416 -132.461762)
		(width 0.14224)
		(layer "In4.Cu")
		(net "M_E_CLK_DP<2>")
	)
	(segment
		(start 258.45135 -96.48952)
		(end 258.445 -96.500188)
		(width 0.0889)
		(layer "In4.Cu")
		(net "M_E_CLK_DP<2>")
	)
	(segment
		(start 257.922014 -95.61449)
		(end 257.95478 -95.61449)
		(width 0.0889)
		(layer "In4.Cu")
		(net "M_E_CLK_DP<2>")
	)
	(segment
		(start 259.7658 -103.4288)
		(end 259.7658 -103.928164)
		(width 0.0889)
		(layer "In4.Cu")
		(net "M_E_CLK_DP<2>")
	)
	(segment
		(start 259.81152 -104.004364)
		(end 259.81152 -132.023866)
		(width 0.14224)
		(layer "In4.Cu")
		(net "M_E_CLK_DP<2>")
	)
	(segment
		(start 258.3688 -99.865434)
		(end 258.7244 -100.221034)
		(width 0.0889)
		(layer "In4.Cu")
		(net "M_E_CLK_DP<2>")
	)
	(segment
		(start 258.7244 -100.221034)
		(end 258.7244 -102.3874)
		(width 0.0889)
		(layer "In4.Cu")
		(net "M_E_CLK_DP<2>")
	)
	(segment
		(start 257.008122 -141.442186)
		(end 256.775712 -141.209776)
		(width 0.14224)
		(layer "In4.Cu")
		(net "M_E_CLK_DP<2>")
	)
	(segment
		(start 259.7658 -103.928164)
		(end 259.81152 -103.973884)
		(width 0.0889)
		(layer "In4.Cu")
		(net "M_E_CLK_DP<2>")
	)
	(segment
		(start 257.45821 -142.38732)
		(end 257.008122 -141.937232)
		(width 0.14224)
		(layer "In4.Cu")
		(net "M_E_CLK_DP<2>")
	)
	(segment
		(start 259.281168 -142.38732)
		(end 257.45821 -142.38732)
		(width 0.14224)
		(layer "In4.Cu")
		(net "M_E_CLK_DP<2>")
	)
	(segment
		(start 258.445 -96.500188)
		(end 258.440174 -96.508824)
		(width 0.0889)
		(layer "In4.Cu")
		(net "M_E_CLK_DP<2>")
	)
	(segment
		(start 260.249416 -132.461762)
		(end 260.249416 -141.419072)
		(width 0.14224)
		(layer "In4.Cu")
		(net "M_E_CLK_DP<2>")
	)
	(segment
		(start 258.45135 -97.48012)
		(end 258.445 -97.490788)
		(width 0.0889)
		(layer "In4.Cu")
		(net "M_E_CLK_DP<2>")
	)
	(segment
		(start 258.3688 -98.065336)
		(end 258.3688 -99.865434)
		(width 0.0889)
		(layer "In4.Cu")
		(net "M_E_CLK_DP<2>")
	)
	(segment
		(start 259.81152 -103.973884)
		(end 259.81152 -104.004364)
		(width 0.0889)
		(layer "In4.Cu")
		(net "M_E_CLK_DP<2>")
	)
	(arc
		(start 257.537458 -95.15475)
		(mid 257.626214 -95.471213)
		(end 257.922014 -95.61449)
		(width 0.0889)
		(layer "In4.Cu")
		(net "M_E_CLK_DP<2>")
	)
	(arc
		(start 257.561334 -95.066612)
		(mid 257.546869 -95.109997)
		(end 257.537458 -95.15475)
		(width 0.0889)
		(layer "In4.Cu")
		(net "M_E_CLK_DP<2>")
	)
	(arc
		(start 257.95478 -95.61449)
		(mid 258.44717 -95.913423)
		(end 258.45135 -96.48952)
		(width 0.0889)
		(layer "In4.Cu")
		(net "M_E_CLK_DP<2>")
	)
	(arc
		(start 258.445 -96.900238)
		(mid 258.524222 -97.189356)
		(end 258.45135 -97.48012)
		(width 0.0889)
		(layer "In4.Cu")
		(net "M_E_CLK_DP<2>")
	)
	(arc
		(start 258.445 -97.490788)
		(mid 258.354186 -97.745465)
		(end 258.358894 -98.015806)
		(width 0.0889)
		(layer "In4.Cu")
		(net "M_E_CLK_DP<2>")
	)
	(arc
		(start 258.440174 -96.508824)
		(mid 258.391419 -96.705176)
		(end 258.445 -96.900238)
		(width 0.0889)
		(layer "In4.Cu")
		(net "M_E_CLK_DP<2>")
	)
	(segment
		(start 259.65023 -95.21444)
		(end 260.22173 -95.21444)
		(width 0.1016)
		(layer "F.Cu")
		(net "M_E_CLK_DP<0>")
	)
	(segment
		(start 256.749804 -142.677642)
		(end 256.749804 -143.970756)
		(width 0.1651)
		(layer "F.Cu")
		(net "M_E_CLK_DP<0>")
	)
	(segment
		(start 256.750312 -142.6718)
		(end 256.749804 -142.677642)
		(width 0.1651)
		(layer "F.Cu")
		(net "M_E_CLK_DP<0>")
	)
	(via
		(at 256.749804 -143.970756)
		(size 0.508)
		(drill 0.254)
		(layers "F.Cu" "B.Cu")
		(net "M_E_CLK_DP<0>")
	)
	(via
		(at 259.65023 -95.21444)
		(size 0.508)
		(drill 0.254)
		(layers "F.Cu" "B.Cu")
		(net "M_E_CLK_DP<0>")
	)
	(segment
		(start 259.30352 -96.404938)
		(end 259.30987 -96.415606)
		(width 0.0889)
		(layer "In4.Cu")
		(net "M_E_CLK_DP<0>")
	)
	(segment
		(start 259.3848 -102.117906)
		(end 260.535928 -103.269034)
		(width 0.0889)
		(layer "In4.Cu")
		(net "M_E_CLK_DP<0>")
	)
	(segment
		(start 260.999986 -129.848356)
		(end 260.7691 -129.848356)
		(width 0.14224)
		(layer "In4.Cu")
		(net "M_E_CLK_DP<0>")
	)
	(segment
		(start 260.986524 -130.511296)
		(end 261.43712 -130.961892)
		(width 0.14224)
		(layer "In4.Cu")
		(net "M_E_CLK_DP<0>")
	)
	(segment
		(start 259.30352 -97.395538)
		(end 259.30987 -97.406206)
		(width 0.0889)
		(layer "In4.Cu")
		(net "M_E_CLK_DP<0>")
	)
	(segment
		(start 260.6421 -130.384296)
		(end 260.7691 -130.511296)
		(width 0.14224)
		(layer "In4.Cu")
		(net "M_E_CLK_DP<0>")
	)
	(segment
		(start 261.2136 -139.94892)
		(end 261.2136 -143.350488)
		(width 0.14224)
		(layer "In4.Cu")
		(net "M_E_CLK_DP<0>")
	)
	(segment
		(start 259.3848 -99.514914)
		(end 259.3848 -102.117906)
		(width 0.0889)
		(layer "In4.Cu")
		(net "M_E_CLK_DP<0>")
	)
	(segment
		(start 260.6421 -129.975356)
		(end 260.6421 -130.384296)
		(width 0.14224)
		(layer "In4.Cu")
		(net "M_E_CLK_DP<0>")
	)
	(segment
		(start 259.298694 -96.396302)
		(end 259.30352 -96.404938)
		(width 0.0889)
		(layer "In4.Cu")
		(net "M_E_CLK_DP<0>")
	)
	(segment
		(start 260.535928 -103.269034)
		(end 260.535928 -103.942388)
		(width 0.0889)
		(layer "In4.Cu")
		(net "M_E_CLK_DP<0>")
	)
	(segment
		(start 259.357368 -145.20672)
		(end 257.396996 -145.20672)
		(width 0.14224)
		(layer "In4.Cu")
		(net "M_E_CLK_DP<0>")
	)
	(segment
		(start 260.581648 -103.988108)
		(end 260.581648 -128.150366)
		(width 0.14224)
		(layer "In4.Cu")
		(net "M_E_CLK_DP<0>")
	)
	(segment
		(start 259.65023 -95.21444)
		(end 259.357114 -95.045276)
		(width 0.0889)
		(layer "In4.Cu")
		(net "M_E_CLK_DP<0>")
	)
	(segment
		(start 261.43712 -130.961892)
		(end 261.43712 -139.7254)
		(width 0.14224)
		(layer "In4.Cu")
		(net "M_E_CLK_DP<0>")
	)
	(segment
		(start 259.298694 -95.405702)
		(end 259.30352 -95.414338)
		(width 0.0889)
		(layer "In4.Cu")
		(net "M_E_CLK_DP<0>")
	)
	(segment
		(start 259.329936 -99.42322)
		(end 259.3848 -99.514914)
		(width 0.0889)
		(layer "In4.Cu")
		(net "M_E_CLK_DP<0>")
	)
	(segment
		(start 259.29844 -99.367594)
		(end 259.329936 -99.42322)
		(width 0.0889)
		(layer "In4.Cu")
		(net "M_E_CLK_DP<0>")
	)
	(segment
		(start 261.362698 -128.931416)
		(end 261.362698 -129.485644)
		(width 0.14224)
		(layer "In4.Cu")
		(net "M_E_CLK_DP<0>")
	)
	(segment
		(start 259.30352 -98.386138)
		(end 259.30987 -98.396806)
		(width 0.0889)
		(layer "In4.Cu")
		(net "M_E_CLK_DP<0>")
	)
	(segment
		(start 260.7691 -129.848356)
		(end 260.6421 -129.975356)
		(width 0.14224)
		(layer "In4.Cu")
		(net "M_E_CLK_DP<0>")
	)
	(segment
		(start 257.396996 -145.20672)
		(end 257.017774 -144.827498)
		(width 0.14224)
		(layer "In4.Cu")
		(net "M_E_CLK_DP<0>")
	)
	(segment
		(start 261.362698 -129.485644)
		(end 260.999986 -129.848356)
		(width 0.14224)
		(layer "In4.Cu")
		(net "M_E_CLK_DP<0>")
	)
	(segment
		(start 259.298694 -98.377502)
		(end 259.30352 -98.386138)
		(width 0.0889)
		(layer "In4.Cu")
		(net "M_E_CLK_DP<0>")
	)
	(segment
		(start 259.30352 -95.414338)
		(end 259.30987 -95.425006)
		(width 0.0889)
		(layer "In4.Cu")
		(net "M_E_CLK_DP<0>")
	)
	(segment
		(start 261.2136 -143.350488)
		(end 259.357368 -145.20672)
		(width 0.14224)
		(layer "In4.Cu")
		(net "M_E_CLK_DP<0>")
	)
	(segment
		(start 259.357114 -95.045276)
		(end 259.278374 -95.066612)
		(width 0.0889)
		(layer "In4.Cu")
		(net "M_E_CLK_DP<0>")
	)
	(segment
		(start 260.7691 -130.511296)
		(end 260.986524 -130.511296)
		(width 0.14224)
		(layer "In4.Cu")
		(net "M_E_CLK_DP<0>")
	)
	(segment
		(start 260.535928 -103.942388)
		(end 260.581648 -103.988108)
		(width 0.0889)
		(layer "In4.Cu")
		(net "M_E_CLK_DP<0>")
	)
	(segment
		(start 261.43712 -139.7254)
		(end 261.2136 -139.94892)
		(width 0.14224)
		(layer "In4.Cu")
		(net "M_E_CLK_DP<0>")
	)
	(segment
		(start 260.581648 -128.150366)
		(end 261.362698 -128.931416)
		(width 0.14224)
		(layer "In4.Cu")
		(net "M_E_CLK_DP<0>")
	)
	(segment
		(start 257.017774 -144.827498)
		(end 257.017774 -144.238726)
		(width 0.14224)
		(layer "In4.Cu")
		(net "M_E_CLK_DP<0>")
	)
	(segment
		(start 257.017774 -144.238726)
		(end 256.749804 -143.970756)
		(width 0.14224)
		(layer "In4.Cu")
		(net "M_E_CLK_DP<0>")
	)
	(segment
		(start 259.298694 -97.386902)
		(end 259.30352 -97.395538)
		(width 0.0889)
		(layer "In4.Cu")
		(net "M_E_CLK_DP<0>")
	)
	(arc
		(start 259.30987 -98.396806)
		(mid 259.382668 -98.687569)
		(end 259.30352 -98.976688)
		(width 0.0889)
		(layer "In4.Cu")
		(net "M_E_CLK_DP<0>")
	)
	(arc
		(start 259.30352 -96.995488)
		(mid 259.25005 -97.190551)
		(end 259.298694 -97.386902)
		(width 0.0889)
		(layer "In4.Cu")
		(net "M_E_CLK_DP<0>")
	)
	(arc
		(start 259.278374 -95.066612)
		(mid 259.262199 -95.116695)
		(end 259.25272 -95.168466)
		(width 0.0889)
		(layer "In4.Cu")
		(net "M_E_CLK_DP<0>")
	)
	(arc
		(start 259.30352 -96.004888)
		(mid 259.25005 -96.199951)
		(end 259.298694 -96.396302)
		(width 0.0889)
		(layer "In4.Cu")
		(net "M_E_CLK_DP<0>")
	)
	(arc
		(start 259.30987 -95.425006)
		(mid 259.382668 -95.715769)
		(end 259.30352 -96.004888)
		(width 0.0889)
		(layer "In4.Cu")
		(net "M_E_CLK_DP<0>")
	)
	(arc
		(start 259.30987 -97.406206)
		(mid 259.382668 -97.696969)
		(end 259.30352 -97.986088)
		(width 0.0889)
		(layer "In4.Cu")
		(net "M_E_CLK_DP<0>")
	)
	(arc
		(start 259.30987 -96.415606)
		(mid 259.382668 -96.706369)
		(end 259.30352 -96.995488)
		(width 0.0889)
		(layer "In4.Cu")
		(net "M_E_CLK_DP<0>")
	)
	(arc
		(start 259.30352 -97.986088)
		(mid 259.25005 -98.181151)
		(end 259.298694 -98.377502)
		(width 0.0889)
		(layer "In4.Cu")
		(net "M_E_CLK_DP<0>")
	)
	(arc
		(start 259.30352 -98.976688)
		(mid 259.250054 -99.171467)
		(end 259.29844 -99.367594)
		(width 0.0889)
		(layer "In4.Cu")
		(net "M_E_CLK_DP<0>")
	)
	(arc
		(start 259.25272 -95.168466)
		(mid 259.257388 -95.290633)
		(end 259.298694 -95.405702)
		(width 0.0889)
		(layer "In4.Cu")
		(net "M_E_CLK_DP<0>")
	)
	(segment
		(start 257.64617 -96.700086)
		(end 257.07467 -96.700086)
		(width 0.1016)
		(layer "F.Cu")
		(net "M_E_CLK_DN<3>")
	)
	(via
		(at 257.07467 -96.700086)
		(size 0.508)
		(drill 0.254)
		(layers "F.Cu" "B.Cu")
		(net "M_E_CLK_DN<3>")
	)
	(via
		(at 257.523742 -139.170156)
		(size 0.508)
		(drill 0.254)
		(layers "F.Cu" "B.Cu")
		(net "M_E_CLK_DN<3>")
	)
	(segment
		(start 257.599942 -139.093956)
		(end 257.599942 -137.877296)
		(width 0.1651)
		(layer "B.Cu")
		(net "M_E_CLK_DN<3>")
	)
	(segment
		(start 257.599942 -137.877296)
		(end 257.60045 -137.877296)
		(width 0.1651)
		(layer "B.Cu")
		(net "M_E_CLK_DN<3>")
	)
	(segment
		(start 257.523742 -139.170156)
		(end 257.599942 -139.093956)
		(width 0.1651)
		(layer "B.Cu")
		(net "M_E_CLK_DN<3>")
	)
	(segment
		(start 258.458208 -138.235944)
		(end 258.571492 -138.12266)
		(width 0.14224)
		(layer "In4.Cu")
		(net "M_E_CLK_DN<3>")
	)
	(segment
		(start 257.22072 -139.473178)
		(end 257.523742 -139.170156)
		(width 0.14224)
		(layer "In4.Cu")
		(net "M_E_CLK_DN<3>")
	)
	(segment
		(start 257.565398 -138.12266)
		(end 257.880104 -138.12266)
		(width 0.14224)
		(layer "In4.Cu")
		(net "M_E_CLK_DN<3>")
	)
	(segment
		(start 258.895088 -135.850376)
		(end 258.895088 -136.315196)
		(width 0.14224)
		(layer "In4.Cu")
		(net "M_E_CLK_DN<3>")
	)
	(segment
		(start 258.007612 -136.807702)
		(end 257.894074 -136.92124)
		(width 0.14224)
		(layer "In4.Cu")
		(net "M_E_CLK_DN<3>")
	)
	(segment
		(start 259.00888 -133.157722)
		(end 259.00888 -133.48716)
		(width 0.14224)
		(layer "In4.Cu")
		(net "M_E_CLK_DN<3>")
	)
	(segment
		(start 257.41503 -97.48012)
		(end 257.42138 -97.490788)
		(width 0.0889)
		(layer "In4.Cu")
		(net "M_E_CLK_DN<3>")
	)
	(segment
		(start 259.00888 -136.7663)
		(end 258.85394 -136.92124)
		(width 0.14224)
		(layer "In4.Cu")
		(net "M_E_CLK_DN<3>")
	)
	(segment
		(start 258.450334 -133.04393)
		(end 258.557014 -132.93725)
		(width 0.14224)
		(layer "In4.Cu")
		(net "M_E_CLK_DN<3>")
	)
	(segment
		(start 258.18084 -140.06576)
		(end 257.463544 -140.06576)
		(width 0.14224)
		(layer "In4.Cu")
		(net "M_E_CLK_DN<3>")
	)
	(segment
		(start 259.00888 -134.179056)
		(end 259.00888 -134.57936)
		(width 0.14224)
		(layer "In4.Cu")
		(net "M_E_CLK_DN<3>")
	)
	(segment
		(start 258.703572 -103.994712)
		(end 258.703572 -104.005888)
		(width 0.0889)
		(layer "In4.Cu")
		(net "M_E_CLK_DN<3>")
	)
	(segment
		(start 257.648964 -132.93725)
		(end 257.878834 -132.93725)
		(width 0.14224)
		(layer "In4.Cu")
		(net "M_E_CLK_DN<3>")
	)
	(segment
		(start 258.85394 -138.12266)
		(end 259.00888 -138.2776)
		(width 0.14224)
		(layer "In4.Cu")
		(net "M_E_CLK_DN<3>")
	)
	(segment
		(start 257.312414 -131.76377)
		(end 257.312414 -132.6007)
		(width 0.14224)
		(layer "In4.Cu")
		(net "M_E_CLK_DN<3>")
	)
	(segment
		(start 258.703572 -128.740408)
		(end 258.58978 -128.8542)
		(width 0.14224)
		(layer "In4.Cu")
		(net "M_E_CLK_DN<3>")
	)
	(segment
		(start 258.85394 -136.92124)
		(end 258.58597 -136.92124)
		(width 0.14224)
		(layer "In4.Cu")
		(net "M_E_CLK_DN<3>")
	)
	(segment
		(start 257.22072 -139.822936)
		(end 257.22072 -139.473178)
		(width 0.14224)
		(layer "In4.Cu")
		(net "M_E_CLK_DN<3>")
	)
	(segment
		(start 258.788408 -132.93725)
		(end 259.00888 -133.157722)
		(width 0.14224)
		(layer "In4.Cu")
		(net "M_E_CLK_DN<3>")
	)
	(segment
		(start 259.00888 -138.2776)
		(end 259.00888 -139.23772)
		(width 0.14224)
		(layer "In4.Cu")
		(net "M_E_CLK_DN<3>")
	)
	(segment
		(start 258.895088 -136.315196)
		(end 259.00888 -136.428988)
		(width 0.14224)
		(layer "In4.Cu")
		(net "M_E_CLK_DN<3>")
	)
	(segment
		(start 257.07467 -96.700086)
		(end 257.367786 -96.531176)
		(width 0.0889)
		(layer "In4.Cu")
		(net "M_E_CLK_DN<3>")
	)
	(segment
		(start 257.262122 -137.819384)
		(end 257.565398 -138.12266)
		(width 0.14224)
		(layer "In4.Cu")
		(net "M_E_CLK_DN<3>")
	)
	(segment
		(start 257.67665 -131.399534)
		(end 257.312414 -131.76377)
		(width 0.14224)
		(layer "In4.Cu")
		(net "M_E_CLK_DN<3>")
	)
	(segment
		(start 258.58978 -128.8542)
		(end 258.58978 -129.31902)
		(width 0.14224)
		(layer "In4.Cu")
		(net "M_E_CLK_DN<3>")
	)
	(segment
		(start 258.7371 -103.55834)
		(end 258.7371 -103.961184)
		(width 0.0889)
		(layer "In4.Cu")
		(net "M_E_CLK_DN<3>")
	)
	(segment
		(start 259.00888 -135.271764)
		(end 259.00888 -135.736584)
		(width 0.14224)
		(layer "In4.Cu")
		(net "M_E_CLK_DN<3>")
	)
	(segment
		(start 257.8989 -100.586794)
		(end 257.8989 -102.72014)
		(width 0.0889)
		(layer "In4.Cu")
		(net "M_E_CLK_DN<3>")
	)
	(segment
		(start 258.58978 -130.476244)
		(end 258.703572 -130.590036)
		(width 0.14224)
		(layer "In4.Cu")
		(net "M_E_CLK_DN<3>")
	)
	(segment
		(start 258.358894 -131.399534)
		(end 257.67665 -131.399534)
		(width 0.14224)
		(layer "In4.Cu")
		(net "M_E_CLK_DN<3>")
	)
	(segment
		(start 258.58978 -129.31902)
		(end 258.703572 -129.432812)
		(width 0.14224)
		(layer "In4.Cu")
		(net "M_E_CLK_DN<3>")
	)
	(segment
		(start 259.00888 -139.23772)
		(end 258.18084 -140.06576)
		(width 0.14224)
		(layer "In4.Cu")
		(net "M_E_CLK_DN<3>")
	)
	(segment
		(start 258.895342 -134.065518)
		(end 259.00888 -134.179056)
		(width 0.14224)
		(layer "In4.Cu")
		(net "M_E_CLK_DN<3>")
	)
	(segment
		(start 258.703572 -131.054856)
		(end 258.358894 -131.399534)
		(width 0.14224)
		(layer "In4.Cu")
		(net "M_E_CLK_DN<3>")
	)
	(segment
		(start 258.703572 -128.275588)
		(end 258.703572 -128.740408)
		(width 0.14224)
		(layer "In4.Cu")
		(net "M_E_CLK_DN<3>")
	)
	(segment
		(start 257.8989 -102.72014)
		(end 258.7371 -103.55834)
		(width 0.0889)
		(layer "In4.Cu")
		(net "M_E_CLK_DN<3>")
	)
	(segment
		(start 259.00888 -135.736584)
		(end 258.895088 -135.850376)
		(width 0.14224)
		(layer "In4.Cu")
		(net "M_E_CLK_DN<3>")
	)
	(segment
		(start 258.703572 -127.583184)
		(end 258.58978 -127.696976)
		(width 0.14224)
		(layer "In4.Cu")
		(net "M_E_CLK_DN<3>")
	)
	(segment
		(start 258.895088 -135.157972)
		(end 259.00888 -135.271764)
		(width 0.14224)
		(layer "In4.Cu")
		(net "M_E_CLK_DN<3>")
	)
	(segment
		(start 258.703572 -129.432812)
		(end 258.703572 -129.897632)
		(width 0.14224)
		(layer "In4.Cu")
		(net "M_E_CLK_DN<3>")
	)
	(segment
		(start 258.7371 -103.961184)
		(end 258.703572 -103.994712)
		(width 0.0889)
		(layer "In4.Cu")
		(net "M_E_CLK_DN<3>")
	)
	(segment
		(start 258.58978 -127.696976)
		(end 258.58978 -128.161796)
		(width 0.14224)
		(layer "In4.Cu")
		(net "M_E_CLK_DN<3>")
	)
	(segment
		(start 258.895088 -134.693152)
		(end 258.895088 -135.157972)
		(width 0.14224)
		(layer "In4.Cu")
		(net "M_E_CLK_DN<3>")
	)
	(segment
		(start 257.463544 -140.06576)
		(end 257.22072 -139.822936)
		(width 0.14224)
		(layer "In4.Cu")
		(net "M_E_CLK_DN<3>")
	)
	(segment
		(start 258.472432 -136.807702)
		(end 258.007612 -136.807702)
		(width 0.14224)
		(layer "In4.Cu")
		(net "M_E_CLK_DN<3>")
	)
	(segment
		(start 259.00888 -133.48716)
		(end 258.895342 -133.600698)
		(width 0.14224)
		(layer "In4.Cu")
		(net "M_E_CLK_DN<3>")
	)
	(segment
		(start 257.312414 -132.6007)
		(end 257.648964 -132.93725)
		(width 0.14224)
		(layer "In4.Cu")
		(net "M_E_CLK_DN<3>")
	)
	(segment
		(start 258.703572 -129.897632)
		(end 258.58978 -130.011424)
		(width 0.14224)
		(layer "In4.Cu")
		(net "M_E_CLK_DN<3>")
	)
	(segment
		(start 258.58978 -128.161796)
		(end 258.703572 -128.275588)
		(width 0.14224)
		(layer "In4.Cu")
		(net "M_E_CLK_DN<3>")
	)
	(segment
		(start 257.367786 -96.531176)
		(end 257.446526 -96.552512)
		(width 0.0889)
		(layer "In4.Cu")
		(net "M_E_CLK_DN<3>")
	)
	(segment
		(start 258.703572 -130.590036)
		(end 258.703572 -131.054856)
		(width 0.14224)
		(layer "In4.Cu")
		(net "M_E_CLK_DN<3>")
	)
	(segment
		(start 257.985514 -133.04393)
		(end 258.450334 -133.04393)
		(width 0.14224)
		(layer "In4.Cu")
		(net "M_E_CLK_DN<3>")
	)
	(segment
		(start 257.993388 -138.235944)
		(end 258.458208 -138.235944)
		(width 0.14224)
		(layer "In4.Cu")
		(net "M_E_CLK_DN<3>")
	)
	(segment
		(start 257.262122 -137.242804)
		(end 257.262122 -137.819384)
		(width 0.14224)
		(layer "In4.Cu")
		(net "M_E_CLK_DN<3>")
	)
	(segment
		(start 257.878834 -132.93725)
		(end 257.985514 -133.04393)
		(width 0.14224)
		(layer "In4.Cu")
		(net "M_E_CLK_DN<3>")
	)
	(segment
		(start 257.503676 -100.19157)
		(end 257.8989 -100.586794)
		(width 0.0889)
		(layer "In4.Cu")
		(net "M_E_CLK_DN<3>")
	)
	(segment
		(start 257.503676 -97.728024)
		(end 257.503676 -100.19157)
		(width 0.0889)
		(layer "In4.Cu")
		(net "M_E_CLK_DN<3>")
	)
	(segment
		(start 258.703572 -104.005888)
		(end 258.703572 -127.583184)
		(width 0.14224)
		(layer "In4.Cu")
		(net "M_E_CLK_DN<3>")
	)
	(segment
		(start 258.58597 -136.92124)
		(end 258.472432 -136.807702)
		(width 0.14224)
		(layer "In4.Cu")
		(net "M_E_CLK_DN<3>")
	)
	(segment
		(start 259.00888 -136.428988)
		(end 259.00888 -136.7663)
		(width 0.14224)
		(layer "In4.Cu")
		(net "M_E_CLK_DN<3>")
	)
	(segment
		(start 258.895342 -133.600698)
		(end 258.895342 -134.065518)
		(width 0.14224)
		(layer "In4.Cu")
		(net "M_E_CLK_DN<3>")
	)
	(segment
		(start 258.58978 -130.011424)
		(end 258.58978 -130.476244)
		(width 0.14224)
		(layer "In4.Cu")
		(net "M_E_CLK_DN<3>")
	)
	(segment
		(start 258.571492 -138.12266)
		(end 258.85394 -138.12266)
		(width 0.14224)
		(layer "In4.Cu")
		(net "M_E_CLK_DN<3>")
	)
	(segment
		(start 257.583686 -136.92124)
		(end 257.262122 -137.242804)
		(width 0.14224)
		(layer "In4.Cu")
		(net "M_E_CLK_DN<3>")
	)
	(segment
		(start 257.894074 -136.92124)
		(end 257.583686 -136.92124)
		(width 0.14224)
		(layer "In4.Cu")
		(net "M_E_CLK_DN<3>")
	)
	(segment
		(start 258.557014 -132.93725)
		(end 258.788408 -132.93725)
		(width 0.14224)
		(layer "In4.Cu")
		(net "M_E_CLK_DN<3>")
	)
	(segment
		(start 259.00888 -134.57936)
		(end 258.895088 -134.693152)
		(width 0.14224)
		(layer "In4.Cu")
		(net "M_E_CLK_DN<3>")
	)
	(segment
		(start 257.880104 -138.12266)
		(end 257.993388 -138.235944)
		(width 0.14224)
		(layer "In4.Cu")
		(net "M_E_CLK_DN<3>")
	)
	(arc
		(start 257.473196 -96.663764)
		(mid 257.465598 -96.786015)
		(end 257.42138 -96.900238)
		(width 0.0889)
		(layer "In4.Cu")
		(net "M_E_CLK_DN<3>")
	)
	(arc
		(start 257.42138 -97.490788)
		(mid 257.473794 -97.605498)
		(end 257.503676 -97.728024)
		(width 0.0889)
		(layer "In4.Cu")
		(net "M_E_CLK_DN<3>")
	)
	(arc
		(start 257.446526 -96.552512)
		(mid 257.463862 -96.60718)
		(end 257.473196 -96.663764)
		(width 0.0889)
		(layer "In4.Cu")
		(net "M_E_CLK_DN<3>")
	)
	(arc
		(start 257.42138 -96.900238)
		(mid 257.342684 -97.170106)
		(end 257.397504 -97.44583)
		(width 0.0889)
		(layer "In4.Cu")
		(net "M_E_CLK_DN<3>")
	)
	(arc
		(start 257.397504 -97.44583)
		(mid 257.405989 -97.463117)
		(end 257.41503 -97.48012)
		(width 0.0889)
		(layer "In4.Cu")
		(net "M_E_CLK_DN<3>")
	)
	(segment
		(start 257.60045 -147.27174)
		(end 257.599942 -147.27174)
		(width 0.1651)
		(layer "F.Cu")
		(net "M_E_CLK_DN<1>")
	)
	(segment
		(start 257.599942 -147.27174)
		(end 257.599942 -145.984468)
		(width 0.1651)
		(layer "F.Cu")
		(net "M_E_CLK_DN<1>")
	)
	(segment
		(start 259.65023 -96.20504)
		(end 260.22173 -96.20504)
		(width 0.1016)
		(layer "F.Cu")
		(net "M_E_CLK_DN<1>")
	)
	(via
		(at 257.599942 -145.984468)
		(size 0.508)
		(drill 0.254)
		(layers "F.Cu" "B.Cu")
		(net "M_E_CLK_DN<1>")
	)
	(via
		(at 259.65023 -96.20504)
		(size 0.508)
		(drill 0.254)
		(layers "F.Cu" "B.Cu")
		(net "M_E_CLK_DN<1>")
	)
	(segment
		(start 259.65023 -96.20504)
		(end 259.755386 -96.31045)
		(width 0.0889)
		(layer "In4.Cu")
		(net "M_E_CLK_DN<1>")
	)
	(segment
		(start 261.181596 -125.740414)
		(end 261.067804 -125.854206)
		(width 0.14224)
		(layer "In4.Cu")
		(net "M_E_CLK_DN<1>")
	)
	(segment
		(start 261.981696 -140.813536)
		(end 261.981696 -141.26464)
		(width 0.14224)
		(layer "In4.Cu")
		(net "M_E_CLK_DN<1>")
	)
	(segment
		(start 259.917184 -99.520248)
		(end 259.917184 -102.030784)
		(width 0.0889)
		(layer "In4.Cu")
		(net "M_E_CLK_DN<1>")
	)
	(segment
		(start 259.700522 -146.666204)
		(end 259.371846 -146.99488)
		(width 0.14224)
		(layer "In4.Cu")
		(net "M_E_CLK_DN<1>")
	)
	(segment
		(start 260.029452 -146.176492)
		(end 259.700522 -146.505422)
		(width 0.14224)
		(layer "In4.Cu")
		(net "M_E_CLK_DN<1>")
	)
	(segment
		(start 261.181596 -126.897638)
		(end 261.981696 -127.697738)
		(width 0.14224)
		(layer "In4.Cu")
		(net "M_E_CLK_DN<1>")
	)
	(segment
		(start 261.981696 -127.697738)
		(end 261.981696 -128.171702)
		(width 0.14224)
		(layer "In4.Cu")
		(net "M_E_CLK_DN<1>")
	)
	(segment
		(start 261.598918 -144.18437)
		(end 261.68096 -144.266412)
		(width 0.14224)
		(layer "In4.Cu")
		(net "M_E_CLK_DN<1>")
	)
	(segment
		(start 261.981696 -129.933954)
		(end 261.885938 -130.029712)
		(width 0.14224)
		(layer "In4.Cu")
		(net "M_E_CLK_DN<1>")
	)
	(segment
		(start 260.001766 -98.377502)
		(end 259.99694 -98.386138)
		(width 0.0889)
		(layer "In4.Cu")
		(net "M_E_CLK_DN<1>")
	)
	(segment
		(start 260.190234 -146.176492)
		(end 260.029452 -146.176492)
		(width 0.14224)
		(layer "In4.Cu")
		(net "M_E_CLK_DN<1>")
	)
	(segment
		(start 261.067804 -125.854206)
		(end 261.067804 -126.319026)
		(width 0.14224)
		(layer "In4.Cu")
		(net "M_E_CLK_DN<1>")
	)
	(segment
		(start 261.877048 -140.244068)
		(end 261.877048 -140.708888)
		(width 0.14224)
		(layer "In4.Cu")
		(net "M_E_CLK_DN<1>")
	)
	(segment
		(start 258.237482 -146.881088)
		(end 258.12369 -146.99488)
		(width 0.14224)
		(layer "In4.Cu")
		(net "M_E_CLK_DN<1>")
	)
	(segment
		(start 261.981696 -141.26464)
		(end 261.68096 -141.565376)
		(width 0.14224)
		(layer "In4.Cu")
		(net "M_E_CLK_DN<1>")
	)
	(segment
		(start 261.181596 -124.58319)
		(end 261.067804 -124.696982)
		(width 0.14224)
		(layer "In4.Cu")
		(net "M_E_CLK_DN<1>")
	)
	(segment
		(start 261.877048 -128.74117)
		(end 261.981696 -128.845818)
		(width 0.14224)
		(layer "In4.Cu")
		(net "M_E_CLK_DN<1>")
	)
	(segment
		(start 259.371846 -146.99488)
		(end 258.816094 -146.99488)
		(width 0.14224)
		(layer "In4.Cu")
		(net "M_E_CLK_DN<1>")
	)
	(segment
		(start 257.330448 -146.253962)
		(end 257.599942 -145.984468)
		(width 0.14224)
		(layer "In4.Cu")
		(net "M_E_CLK_DN<1>")
	)
	(segment
		(start 261.181596 -103.963724)
		(end 261.181596 -123.425966)
		(width 0.14224)
		(layer "In4.Cu")
		(net "M_E_CLK_DN<1>")
	)
	(segment
		(start 260.001766 -97.386902)
		(end 259.99694 -97.395538)
		(width 0.0889)
		(layer "In4.Cu")
		(net "M_E_CLK_DN<1>")
	)
	(segment
		(start 260.001512 -99.368864)
		(end 259.917184 -99.520248)
		(width 0.0889)
		(layer "In4.Cu")
		(net "M_E_CLK_DN<1>")
	)
	(segment
		(start 261.067804 -126.319026)
		(end 261.181596 -126.432818)
		(width 0.14224)
		(layer "In4.Cu")
		(net "M_E_CLK_DN<1>")
	)
	(segment
		(start 261.68096 -144.266412)
		(end 261.68096 -144.685766)
		(width 0.14224)
		(layer "In4.Cu")
		(net "M_E_CLK_DN<1>")
	)
	(segment
		(start 261.181596 -125.275594)
		(end 261.181596 -125.740414)
		(width 0.14224)
		(layer "In4.Cu")
		(net "M_E_CLK_DN<1>")
	)
	(segment
		(start 260.51891 -145.687034)
		(end 260.51891 -145.847816)
		(width 0.14224)
		(layer "In4.Cu")
		(net "M_E_CLK_DN<1>")
	)
	(segment
		(start 261.68096 -141.565376)
		(end 261.68096 -143.637508)
		(width 0.14224)
		(layer "In4.Cu")
		(net "M_E_CLK_DN<1>")
	)
	(segment
		(start 257.330448 -146.666458)
		(end 257.330448 -146.253962)
		(width 0.14224)
		(layer "In4.Cu")
		(net "M_E_CLK_DN<1>")
	)
	(segment
		(start 261.226554 -103.340154)
		(end 261.226554 -103.896668)
		(width 0.0889)
		(layer "In4.Cu")
		(net "M_E_CLK_DN<1>")
	)
	(segment
		(start 260.84784 -145.358104)
		(end 260.51891 -145.687034)
		(width 0.14224)
		(layer "In4.Cu")
		(net "M_E_CLK_DN<1>")
	)
	(segment
		(start 257.65887 -146.99488)
		(end 257.330448 -146.666458)
		(width 0.14224)
		(layer "In4.Cu")
		(net "M_E_CLK_DN<1>")
	)
	(segment
		(start 260.51891 -145.847816)
		(end 260.190234 -146.176492)
		(width 0.14224)
		(layer "In4.Cu")
		(net "M_E_CLK_DN<1>")
	)
	(segment
		(start 261.181596 -126.432818)
		(end 261.181596 -126.897638)
		(width 0.14224)
		(layer "In4.Cu")
		(net "M_E_CLK_DN<1>")
	)
	(segment
		(start 259.99694 -98.976688)
		(end 259.997194 -98.976942)
		(width 0.0889)
		(layer "In4.Cu")
		(net "M_E_CLK_DN<1>")
	)
	(segment
		(start 259.700522 -146.505422)
		(end 259.700522 -146.666204)
		(width 0.14224)
		(layer "In4.Cu")
		(net "M_E_CLK_DN<1>")
	)
	(segment
		(start 261.68096 -143.637508)
		(end 261.598918 -143.71955)
		(width 0.14224)
		(layer "In4.Cu")
		(net "M_E_CLK_DN<1>")
	)
	(segment
		(start 261.981696 -140.13942)
		(end 261.877048 -140.244068)
		(width 0.14224)
		(layer "In4.Cu")
		(net "M_E_CLK_DN<1>")
	)
	(segment
		(start 258.816094 -146.99488)
		(end 258.702302 -146.881088)
		(width 0.14224)
		(layer "In4.Cu")
		(net "M_E_CLK_DN<1>")
	)
	(segment
		(start 261.067804 -125.161802)
		(end 261.181596 -125.275594)
		(width 0.14224)
		(layer "In4.Cu")
		(net "M_E_CLK_DN<1>")
	)
	(segment
		(start 261.885938 -130.494532)
		(end 261.981696 -130.59029)
		(width 0.14224)
		(layer "In4.Cu")
		(net "M_E_CLK_DN<1>")
	)
	(segment
		(start 261.008622 -145.358104)
		(end 260.84784 -145.358104)
		(width 0.14224)
		(layer "In4.Cu")
		(net "M_E_CLK_DN<1>")
	)
	(segment
		(start 261.181596 -124.11837)
		(end 261.181596 -124.58319)
		(width 0.14224)
		(layer "In4.Cu")
		(net "M_E_CLK_DN<1>")
	)
	(segment
		(start 261.981696 -130.59029)
		(end 261.981696 -140.13942)
		(width 0.14224)
		(layer "In4.Cu")
		(net "M_E_CLK_DN<1>")
	)
	(segment
		(start 258.702302 -146.881088)
		(end 258.237482 -146.881088)
		(width 0.14224)
		(layer "In4.Cu")
		(net "M_E_CLK_DN<1>")
	)
	(segment
		(start 261.598918 -143.71955)
		(end 261.598918 -144.18437)
		(width 0.14224)
		(layer "In4.Cu")
		(net "M_E_CLK_DN<1>")
	)
	(segment
		(start 261.226554 -103.896668)
		(end 261.181596 -103.941626)
		(width 0.0889)
		(layer "In4.Cu")
		(net "M_E_CLK_DN<1>")
	)
	(segment
		(start 259.917184 -102.030784)
		(end 261.226554 -103.340154)
		(width 0.0889)
		(layer "In4.Cu")
		(net "M_E_CLK_DN<1>")
	)
	(segment
		(start 259.99694 -97.395538)
		(end 259.99059 -97.406206)
		(width 0.0889)
		(layer "In4.Cu")
		(net "M_E_CLK_DN<1>")
	)
	(segment
		(start 261.877048 -128.27635)
		(end 261.877048 -128.74117)
		(width 0.14224)
		(layer "In4.Cu")
		(net "M_E_CLK_DN<1>")
	)
	(segment
		(start 261.885938 -130.029712)
		(end 261.885938 -130.494532)
		(width 0.14224)
		(layer "In4.Cu")
		(net "M_E_CLK_DN<1>")
	)
	(segment
		(start 261.067804 -123.539758)
		(end 261.067804 -124.004578)
		(width 0.14224)
		(layer "In4.Cu")
		(net "M_E_CLK_DN<1>")
	)
	(segment
		(start 261.067804 -124.696982)
		(end 261.067804 -125.161802)
		(width 0.14224)
		(layer "In4.Cu")
		(net "M_E_CLK_DN<1>")
	)
	(segment
		(start 261.877048 -140.708888)
		(end 261.981696 -140.813536)
		(width 0.14224)
		(layer "In4.Cu")
		(net "M_E_CLK_DN<1>")
	)
	(segment
		(start 258.12369 -146.99488)
		(end 257.65887 -146.99488)
		(width 0.14224)
		(layer "In4.Cu")
		(net "M_E_CLK_DN<1>")
	)
	(segment
		(start 261.981696 -128.171702)
		(end 261.877048 -128.27635)
		(width 0.14224)
		(layer "In4.Cu")
		(net "M_E_CLK_DN<1>")
	)
	(segment
		(start 261.68096 -144.685766)
		(end 261.008622 -145.358104)
		(width 0.14224)
		(layer "In4.Cu")
		(net "M_E_CLK_DN<1>")
	)
	(segment
		(start 259.99694 -98.386138)
		(end 259.99059 -98.396806)
		(width 0.0889)
		(layer "In4.Cu")
		(net "M_E_CLK_DN<1>")
	)
	(segment
		(start 261.981696 -128.845818)
		(end 261.981696 -129.933954)
		(width 0.14224)
		(layer "In4.Cu")
		(net "M_E_CLK_DN<1>")
	)
	(segment
		(start 261.181596 -103.941626)
		(end 261.181596 -103.963724)
		(width 0.0889)
		(layer "In4.Cu")
		(net "M_E_CLK_DN<1>")
	)
	(segment
		(start 261.067804 -124.004578)
		(end 261.181596 -124.11837)
		(width 0.14224)
		(layer "In4.Cu")
		(net "M_E_CLK_DN<1>")
	)
	(segment
		(start 261.181596 -123.425966)
		(end 261.067804 -123.539758)
		(width 0.14224)
		(layer "In4.Cu")
		(net "M_E_CLK_DN<1>")
	)
	(arc
		(start 259.99694 -96.995488)
		(mid 260.05041 -97.190551)
		(end 260.001766 -97.386902)
		(width 0.0889)
		(layer "In4.Cu")
		(net "M_E_CLK_DN<1>")
	)
	(arc
		(start 259.99694 -97.986088)
		(mid 260.05041 -98.181151)
		(end 260.001766 -98.377502)
		(width 0.0889)
		(layer "In4.Cu")
		(net "M_E_CLK_DN<1>")
	)
	(arc
		(start 259.997194 -98.976942)
		(mid 260.032562 -99.057995)
		(end 260.049264 -99.144836)
		(width 0.0889)
		(layer "In4.Cu")
		(net "M_E_CLK_DN<1>")
	)
	(arc
		(start 260.049264 -99.144836)
		(mid 260.041741 -99.260334)
		(end 260.001512 -99.368864)
		(width 0.0889)
		(layer "In4.Cu")
		(net "M_E_CLK_DN<1>")
	)
	(arc
		(start 259.99059 -98.396806)
		(mid 259.917792 -98.687569)
		(end 259.99694 -98.976688)
		(width 0.0889)
		(layer "In4.Cu")
		(net "M_E_CLK_DN<1>")
	)
	(arc
		(start 259.917692 -96.701864)
		(mid 259.938111 -96.853859)
		(end 259.99694 -96.995488)
		(width 0.0889)
		(layer "In4.Cu")
		(net "M_E_CLK_DN<1>")
	)
	(arc
		(start 259.99059 -97.406206)
		(mid 259.917792 -97.696969)
		(end 259.99694 -97.986088)
		(width 0.0889)
		(layer "In4.Cu")
		(net "M_E_CLK_DN<1>")
	)
	(arc
		(start 259.755386 -96.31045)
		(mid 259.875462 -96.490017)
		(end 259.917692 -96.701864)
		(width 0.0889)
		(layer "In4.Cu")
		(net "M_E_CLK_DN<1>")
	)
	(segment
		(start 257.64617 -94.718886)
		(end 257.07467 -94.718886)
		(width 0.1016)
		(layer "F.Cu")
		(net "M_E_CLK_DN<2>")
	)
	(via
		(at 257.599942 -141.183868)
		(size 0.508)
		(drill 0.254)
		(layers "F.Cu" "B.Cu")
		(net "M_E_CLK_DN<2>")
	)
	(via
		(at 257.07467 -94.718886)
		(size 0.508)
		(drill 0.254)
		(layers "F.Cu" "B.Cu")
		(net "M_E_CLK_DN<2>")
	)
	(segment
		(start 257.60045 -142.477236)
		(end 257.599942 -142.476982)
		(width 0.1651)
		(layer "B.Cu")
		(net "M_E_CLK_DN<2>")
	)
	(segment
		(start 257.599942 -142.476982)
		(end 257.599942 -141.183868)
		(width 0.1651)
		(layer "B.Cu")
		(net "M_E_CLK_DN<2>")
	)
	(segment
		(start 259.866384 -135.634222)
		(end 259.866384 -136.099042)
		(width 0.14224)
		(layer "In4.Cu")
		(net "M_E_CLK_DN<2>")
	)
	(segment
		(start 259.54228 -103.982266)
		(end 259.54228 -104.004364)
		(width 0.0889)
		(layer "In4.Cu")
		(net "M_E_CLK_DN<2>")
	)
	(segment
		(start 259.980176 -140.149326)
		(end 259.866384 -140.263118)
		(width 0.14224)
		(layer "In4.Cu")
		(net "M_E_CLK_DN<2>")
	)
	(segment
		(start 259.980176 -141.30655)
		(end 259.771896 -141.51483)
		(width 0.14224)
		(layer "In4.Cu")
		(net "M_E_CLK_DN<2>")
	)
	(segment
		(start 259.354574 -141.802104)
		(end 259.354574 -141.932152)
		(width 0.14224)
		(layer "In4.Cu")
		(net "M_E_CLK_DN<2>")
	)
	(segment
		(start 259.980176 -137.370058)
		(end 259.980176 -137.834878)
		(width 0.14224)
		(layer "In4.Cu")
		(net "M_E_CLK_DN<2>")
	)
	(segment
		(start 258.284726 -97.386902)
		(end 258.2799 -97.395538)
		(width 0.0889)
		(layer "In4.Cu")
		(net "M_E_CLK_DN<2>")
	)
	(segment
		(start 258.106926 -142.11808)
		(end 257.56997 -142.11808)
		(width 0.14224)
		(layer "In4.Cu")
		(net "M_E_CLK_DN<2>")
	)
	(segment
		(start 257.91541 -95.80499)
		(end 257.948176 -95.80499)
		(width 0.0889)
		(layer "In4.Cu")
		(net "M_E_CLK_DN<2>")
	)
	(segment
		(start 259.980176 -136.212834)
		(end 259.980176 -136.677654)
		(width 0.14224)
		(layer "In4.Cu")
		(net "M_E_CLK_DN<2>")
	)
	(segment
		(start 259.980176 -134.363206)
		(end 259.866384 -134.476998)
		(width 0.14224)
		(layer "In4.Cu")
		(net "M_E_CLK_DN<2>")
	)
	(segment
		(start 259.866384 -134.476998)
		(end 259.866384 -134.941818)
		(width 0.14224)
		(layer "In4.Cu")
		(net "M_E_CLK_DN<2>")
	)
	(segment
		(start 259.168646 -142.11808)
		(end 258.798314 -142.11808)
		(width 0.14224)
		(layer "In4.Cu")
		(net "M_E_CLK_DN<2>")
	)
	(segment
		(start 258.1783 -99.944428)
		(end 258.5339 -100.300028)
		(width 0.0889)
		(layer "In4.Cu")
		(net "M_E_CLK_DN<2>")
	)
	(segment
		(start 259.866384 -139.105894)
		(end 259.866384 -139.570714)
		(width 0.14224)
		(layer "In4.Cu")
		(net "M_E_CLK_DN<2>")
	)
	(segment
		(start 259.980176 -136.677654)
		(end 259.866384 -136.791446)
		(width 0.14224)
		(layer "In4.Cu")
		(net "M_E_CLK_DN<2>")
	)
	(segment
		(start 259.866384 -133.319774)
		(end 259.866384 -133.784594)
		(width 0.14224)
		(layer "In4.Cu")
		(net "M_E_CLK_DN<2>")
	)
	(segment
		(start 259.5753 -103.949246)
		(end 259.54228 -103.982266)
		(width 0.0889)
		(layer "In4.Cu")
		(net "M_E_CLK_DN<2>")
	)
	(segment
		(start 259.866384 -134.941818)
		(end 259.980176 -135.05561)
		(width 0.14224)
		(layer "In4.Cu")
		(net "M_E_CLK_DN<2>")
	)
	(segment
		(start 258.5339 -102.466394)
		(end 259.5753 -103.507794)
		(width 0.0889)
		(layer "In4.Cu")
		(net "M_E_CLK_DN<2>")
	)
	(segment
		(start 258.5339 -100.300028)
		(end 258.5339 -102.466394)
		(width 0.0889)
		(layer "In4.Cu")
		(net "M_E_CLK_DN<2>")
	)
	(segment
		(start 259.866384 -137.94867)
		(end 259.866384 -138.41349)
		(width 0.14224)
		(layer "In4.Cu")
		(net "M_E_CLK_DN<2>")
	)
	(segment
		(start 259.980176 -132.573522)
		(end 259.980176 -133.205982)
		(width 0.14224)
		(layer "In4.Cu")
		(net "M_E_CLK_DN<2>")
	)
	(segment
		(start 258.798314 -142.11808)
		(end 258.68503 -142.004796)
		(width 0.14224)
		(layer "In4.Cu")
		(net "M_E_CLK_DN<2>")
	)
	(segment
		(start 259.641594 -141.515084)
		(end 259.354574 -141.802104)
		(width 0.14224)
		(layer "In4.Cu")
		(net "M_E_CLK_DN<2>")
	)
	(segment
		(start 259.866384 -136.791446)
		(end 259.866384 -137.256266)
		(width 0.14224)
		(layer "In4.Cu")
		(net "M_E_CLK_DN<2>")
	)
	(segment
		(start 259.980176 -137.834878)
		(end 259.866384 -137.94867)
		(width 0.14224)
		(layer "In4.Cu")
		(net "M_E_CLK_DN<2>")
	)
	(segment
		(start 258.1783 -98.08464)
		(end 258.1783 -99.944428)
		(width 0.0889)
		(layer "In4.Cu")
		(net "M_E_CLK_DN<2>")
	)
	(segment
		(start 257.07467 -94.718886)
		(end 257.283458 -94.92742)
		(width 0.0889)
		(layer "In4.Cu")
		(net "M_E_CLK_DN<2>")
	)
	(segment
		(start 259.54228 -132.135626)
		(end 259.980176 -132.573522)
		(width 0.14224)
		(layer "In4.Cu")
		(net "M_E_CLK_DN<2>")
	)
	(segment
		(start 259.980176 -135.52043)
		(end 259.866384 -135.634222)
		(width 0.14224)
		(layer "In4.Cu")
		(net "M_E_CLK_DN<2>")
	)
	(segment
		(start 257.56997 -142.11808)
		(end 257.277362 -141.825472)
		(width 0.14224)
		(layer "In4.Cu")
		(net "M_E_CLK_DN<2>")
	)
	(segment
		(start 259.866384 -140.727938)
		(end 259.980176 -140.84173)
		(width 0.14224)
		(layer "In4.Cu")
		(net "M_E_CLK_DN<2>")
	)
	(segment
		(start 259.771896 -141.51483)
		(end 259.641594 -141.515084)
		(width 0.14224)
		(layer "In4.Cu")
		(net "M_E_CLK_DN<2>")
	)
	(segment
		(start 259.980176 -138.527282)
		(end 259.980176 -138.992102)
		(width 0.14224)
		(layer "In4.Cu")
		(net "M_E_CLK_DN<2>")
	)
	(segment
		(start 258.22021 -142.004796)
		(end 258.106926 -142.11808)
		(width 0.14224)
		(layer "In4.Cu")
		(net "M_E_CLK_DN<2>")
	)
	(segment
		(start 259.980176 -138.992102)
		(end 259.866384 -139.105894)
		(width 0.14224)
		(layer "In4.Cu")
		(net "M_E_CLK_DN<2>")
	)
	(segment
		(start 259.980176 -139.684506)
		(end 259.980176 -140.149326)
		(width 0.14224)
		(layer "In4.Cu")
		(net "M_E_CLK_DN<2>")
	)
	(segment
		(start 259.980176 -140.84173)
		(end 259.980176 -141.30655)
		(width 0.14224)
		(layer "In4.Cu")
		(net "M_E_CLK_DN<2>")
	)
	(segment
		(start 259.354574 -141.932152)
		(end 259.168646 -142.11808)
		(width 0.14224)
		(layer "In4.Cu")
		(net "M_E_CLK_DN<2>")
	)
	(segment
		(start 259.980176 -133.898386)
		(end 259.980176 -134.363206)
		(width 0.14224)
		(layer "In4.Cu")
		(net "M_E_CLK_DN<2>")
	)
	(segment
		(start 259.866384 -140.263118)
		(end 259.866384 -140.727938)
		(width 0.14224)
		(layer "In4.Cu")
		(net "M_E_CLK_DN<2>")
	)
	(segment
		(start 259.980176 -135.05561)
		(end 259.980176 -135.52043)
		(width 0.14224)
		(layer "In4.Cu")
		(net "M_E_CLK_DN<2>")
	)
	(segment
		(start 259.980176 -133.205982)
		(end 259.866384 -133.319774)
		(width 0.14224)
		(layer "In4.Cu")
		(net "M_E_CLK_DN<2>")
	)
	(segment
		(start 259.866384 -138.41349)
		(end 259.980176 -138.527282)
		(width 0.14224)
		(layer "In4.Cu")
		(net "M_E_CLK_DN<2>")
	)
	(segment
		(start 258.68503 -142.004796)
		(end 258.22021 -142.004796)
		(width 0.14224)
		(layer "In4.Cu")
		(net "M_E_CLK_DN<2>")
	)
	(segment
		(start 259.866384 -139.570714)
		(end 259.980176 -139.684506)
		(width 0.14224)
		(layer "In4.Cu")
		(net "M_E_CLK_DN<2>")
	)
	(segment
		(start 259.5753 -103.507794)
		(end 259.5753 -103.949246)
		(width 0.0889)
		(layer "In4.Cu")
		(net "M_E_CLK_DN<2>")
	)
	(segment
		(start 258.17195 -98.053398)
		(end 258.1783 -98.08464)
		(width 0.0889)
		(layer "In4.Cu")
		(net "M_E_CLK_DN<2>")
	)
	(segment
		(start 259.866384 -133.784594)
		(end 259.980176 -133.898386)
		(width 0.14224)
		(layer "In4.Cu")
		(net "M_E_CLK_DN<2>")
	)
	(segment
		(start 259.54228 -104.004364)
		(end 259.54228 -132.135626)
		(width 0.14224)
		(layer "In4.Cu")
		(net "M_E_CLK_DN<2>")
	)
	(segment
		(start 258.284726 -96.396302)
		(end 258.2799 -96.404938)
		(width 0.0889)
		(layer "In4.Cu")
		(net "M_E_CLK_DN<2>")
	)
	(segment
		(start 258.2799 -96.404938)
		(end 258.27355 -96.415606)
		(width 0.0889)
		(layer "In4.Cu")
		(net "M_E_CLK_DN<2>")
	)
	(segment
		(start 257.277362 -141.825472)
		(end 257.277362 -141.506448)
		(width 0.14224)
		(layer "In4.Cu")
		(net "M_E_CLK_DN<2>")
	)
	(segment
		(start 259.866384 -136.099042)
		(end 259.980176 -136.212834)
		(width 0.14224)
		(layer "In4.Cu")
		(net "M_E_CLK_DN<2>")
	)
	(segment
		(start 257.277362 -141.506448)
		(end 257.599942 -141.183868)
		(width 0.14224)
		(layer "In4.Cu")
		(net "M_E_CLK_DN<2>")
	)
	(segment
		(start 259.866384 -137.256266)
		(end 259.980176 -137.370058)
		(width 0.14224)
		(layer "In4.Cu")
		(net "M_E_CLK_DN<2>")
	)
	(arc
		(start 258.2799 -96.995488)
		(mid 258.33337 -97.190551)
		(end 258.284726 -97.386902)
		(width 0.0889)
		(layer "In4.Cu")
		(net "M_E_CLK_DN<2>")
	)
	(arc
		(start 258.27355 -96.415606)
		(mid 258.200752 -96.706369)
		(end 258.2799 -96.995488)
		(width 0.0889)
		(layer "In4.Cu")
		(net "M_E_CLK_DN<2>")
	)
	(arc
		(start 257.948176 -95.80499)
		(mid 258.281094 -96.006981)
		(end 258.284726 -96.396302)
		(width 0.0889)
		(layer "In4.Cu")
		(net "M_E_CLK_DN<2>")
	)
	(arc
		(start 257.283458 -94.92742)
		(mid 257.339771 -95.01909)
		(end 257.348736 -95.126302)
		(width 0.0889)
		(layer "In4.Cu")
		(net "M_E_CLK_DN<2>")
	)
	(arc
		(start 257.348736 -95.126302)
		(mid 257.479424 -95.593102)
		(end 257.91541 -95.80499)
		(width 0.0889)
		(layer "In4.Cu")
		(net "M_E_CLK_DN<2>")
	)
	(arc
		(start 258.2799 -97.395538)
		(mid 258.166089 -97.714643)
		(end 258.17195 -98.053398)
		(width 0.0889)
		(layer "In4.Cu")
		(net "M_E_CLK_DN<2>")
	)
	(segment
		(start 257.60045 -142.6718)
		(end 257.599942 -142.677642)
		(width 0.1651)
		(layer "F.Cu")
		(net "M_E_CLK_DN<0>")
	)
	(segment
		(start 259.36321 -94.718886)
		(end 258.79171 -94.718886)
		(width 0.1016)
		(layer "F.Cu")
		(net "M_E_CLK_DN<0>")
	)
	(segment
		(start 257.599942 -142.677642)
		(end 257.599942 -143.970756)
		(width 0.1651)
		(layer "F.Cu")
		(net "M_E_CLK_DN<0>")
	)
	(via
		(at 258.79171 -94.718886)
		(size 0.508)
		(drill 0.254)
		(layers "F.Cu" "B.Cu")
		(net "M_E_CLK_DN<0>")
	)
	(via
		(at 257.599942 -143.970756)
		(size 0.508)
		(drill 0.254)
		(layers "F.Cu" "B.Cu")
		(net "M_E_CLK_DN<0>")
	)
	(segment
		(start 261.16788 -133.433312)
		(end 261.054088 -133.547104)
		(width 0.14224)
		(layer "In4.Cu")
		(net "M_E_CLK_DN<0>")
	)
	(segment
		(start 261.16788 -134.125716)
		(end 261.16788 -134.590536)
		(width 0.14224)
		(layer "In4.Cu")
		(net "M_E_CLK_DN<0>")
	)
	(segment
		(start 260.65734 -129.579116)
		(end 260.37286 -129.863596)
		(width 0.14224)
		(layer "In4.Cu")
		(net "M_E_CLK_DN<0>")
	)
	(segment
		(start 258.142486 -144.823942)
		(end 258.028948 -144.93748)
		(width 0.14224)
		(layer "In4.Cu")
		(net "M_E_CLK_DN<0>")
	)
	(segment
		(start 261.054088 -135.169148)
		(end 261.16788 -135.28294)
		(width 0.14224)
		(layer "In4.Cu")
		(net "M_E_CLK_DN<0>")
	)
	(segment
		(start 260.94436 -142.081504)
		(end 260.830568 -142.195296)
		(width 0.14224)
		(layer "In4.Cu")
		(net "M_E_CLK_DN<0>")
	)
	(segment
		(start 260.94436 -143.238728)
		(end 260.742938 -143.44015)
		(width 0.14224)
		(layer "In4.Cu")
		(net "M_E_CLK_DN<0>")
	)
	(segment
		(start 259.13207 -97.48012)
		(end 259.13842 -97.490788)
		(width 0.0889)
		(layer "In4.Cu")
		(net "M_E_CLK_DN<0>")
	)
	(segment
		(start 260.874764 -130.780536)
		(end 261.16788 -131.073652)
		(width 0.14224)
		(layer "In4.Cu")
		(net "M_E_CLK_DN<0>")
	)
	(segment
		(start 261.093458 -129.043176)
		(end 261.093458 -129.373884)
		(width 0.14224)
		(layer "In4.Cu")
		(net "M_E_CLK_DN<0>")
	)
	(segment
		(start 260.742938 -143.44015)
		(end 260.583426 -143.44015)
		(width 0.14224)
		(layer "In4.Cu")
		(net "M_E_CLK_DN<0>")
	)
	(segment
		(start 259.446014 -144.582896)
		(end 259.446014 -144.737074)
		(width 0.14224)
		(layer "In4.Cu")
		(net "M_E_CLK_DN<0>")
	)
	(segment
		(start 259.77469 -144.25422)
		(end 259.446014 -144.582896)
		(width 0.14224)
		(layer "In4.Cu")
		(net "M_E_CLK_DN<0>")
	)
	(segment
		(start 260.94436 -142.773908)
		(end 260.94436 -143.238728)
		(width 0.14224)
		(layer "In4.Cu")
		(net "M_E_CLK_DN<0>")
	)
	(segment
		(start 259.928868 -144.25422)
		(end 259.77469 -144.25422)
		(width 0.14224)
		(layer "In4.Cu")
		(net "M_E_CLK_DN<0>")
	)
	(segment
		(start 257.508756 -144.93748)
		(end 257.287014 -144.715738)
		(width 0.14224)
		(layer "In4.Cu")
		(net "M_E_CLK_DN<0>")
	)
	(segment
		(start 259.446014 -144.737074)
		(end 259.245608 -144.93748)
		(width 0.14224)
		(layer "In4.Cu")
		(net "M_E_CLK_DN<0>")
	)
	(segment
		(start 259.13207 -99.460558)
		(end 259.132578 -99.46132)
		(width 0.0889)
		(layer "In4.Cu")
		(net "M_E_CLK_DN<0>")
	)
	(segment
		(start 260.888226 -129.579116)
		(end 260.65734 -129.579116)
		(width 0.14224)
		(layer "In4.Cu")
		(net "M_E_CLK_DN<0>")
	)
	(segment
		(start 260.312408 -103.976932)
		(end 260.312408 -103.988108)
		(width 0.0889)
		(layer "In4.Cu")
		(net "M_E_CLK_DN<0>")
	)
	(segment
		(start 261.16788 -135.74776)
		(end 261.054088 -135.861552)
		(width 0.14224)
		(layer "In4.Cu")
		(net "M_E_CLK_DN<0>")
	)
	(segment
		(start 260.94436 -139.83716)
		(end 260.94436 -140.92428)
		(width 0.14224)
		(layer "In4.Cu")
		(net "M_E_CLK_DN<0>")
	)
	(segment
		(start 260.830568 -141.038072)
		(end 260.830568 -141.502892)
		(width 0.14224)
		(layer "In4.Cu")
		(net "M_E_CLK_DN<0>")
	)
	(segment
		(start 260.345428 -103.348028)
		(end 260.345428 -103.943912)
		(width 0.0889)
		(layer "In4.Cu")
		(net "M_E_CLK_DN<0>")
	)
	(segment
		(start 261.16788 -139.61364)
		(end 260.94436 -139.83716)
		(width 0.14224)
		(layer "In4.Cu")
		(net "M_E_CLK_DN<0>")
	)
	(segment
		(start 261.16788 -132.276088)
		(end 261.054088 -132.38988)
		(width 0.14224)
		(layer "In4.Cu")
		(net "M_E_CLK_DN<0>")
	)
	(segment
		(start 261.054088 -133.547104)
		(end 261.054088 -134.011924)
		(width 0.14224)
		(layer "In4.Cu")
		(net "M_E_CLK_DN<0>")
	)
	(segment
		(start 261.054088 -136.326372)
		(end 261.16788 -136.440164)
		(width 0.14224)
		(layer "In4.Cu")
		(net "M_E_CLK_DN<0>")
	)
	(segment
		(start 260.830568 -142.195296)
		(end 260.830568 -142.660116)
		(width 0.14224)
		(layer "In4.Cu")
		(net "M_E_CLK_DN<0>")
	)
	(segment
		(start 261.16788 -134.590536)
		(end 261.054088 -134.704328)
		(width 0.14224)
		(layer "In4.Cu")
		(net "M_E_CLK_DN<0>")
	)
	(segment
		(start 259.13842 -98.481388)
		(end 259.143246 -98.490024)
		(width 0.0889)
		(layer "In4.Cu")
		(net "M_E_CLK_DN<0>")
	)
	(segment
		(start 261.16788 -131.073652)
		(end 261.16788 -132.276088)
		(width 0.14224)
		(layer "In4.Cu")
		(net "M_E_CLK_DN<0>")
	)
	(segment
		(start 260.312408 -103.988108)
		(end 260.312408 -128.262126)
		(width 0.14224)
		(layer "In4.Cu")
		(net "M_E_CLK_DN<0>")
	)
	(segment
		(start 259.16509 -99.519232)
		(end 259.1943 -99.567746)
		(width 0.0889)
		(layer "In4.Cu")
		(net "M_E_CLK_DN<0>")
	)
	(segment
		(start 260.345428 -103.943912)
		(end 260.312408 -103.976932)
		(width 0.0889)
		(layer "In4.Cu")
		(net "M_E_CLK_DN<0>")
	)
	(segment
		(start 260.94436 -141.616684)
		(end 260.94436 -142.081504)
		(width 0.14224)
		(layer "In4.Cu")
		(net "M_E_CLK_DN<0>")
	)
	(segment
		(start 260.37286 -130.496056)
		(end 260.65734 -130.780536)
		(width 0.14224)
		(layer "In4.Cu")
		(net "M_E_CLK_DN<0>")
	)
	(segment
		(start 258.028948 -144.93748)
		(end 257.508756 -144.93748)
		(width 0.14224)
		(layer "In4.Cu")
		(net "M_E_CLK_DN<0>")
	)
	(segment
		(start 260.37286 -129.863596)
		(end 260.37286 -130.496056)
		(width 0.14224)
		(layer "In4.Cu")
		(net "M_E_CLK_DN<0>")
	)
	(segment
		(start 259.13842 -96.500188)
		(end 259.143246 -96.508824)
		(width 0.0889)
		(layer "In4.Cu")
		(net "M_E_CLK_DN<0>")
	)
	(segment
		(start 261.054088 -134.011924)
		(end 261.16788 -134.125716)
		(width 0.14224)
		(layer "In4.Cu")
		(net "M_E_CLK_DN<0>")
	)
	(segment
		(start 258.79171 -94.718886)
		(end 258.97967 -94.906846)
		(width 0.0889)
		(layer "In4.Cu")
		(net "M_E_CLK_DN<0>")
	)
	(segment
		(start 259.13207 -98.47072)
		(end 259.13842 -98.481388)
		(width 0.0889)
		(layer "In4.Cu")
		(net "M_E_CLK_DN<0>")
	)
	(segment
		(start 261.093458 -129.373884)
		(end 260.888226 -129.579116)
		(width 0.14224)
		(layer "In4.Cu")
		(net "M_E_CLK_DN<0>")
	)
	(segment
		(start 259.1943 -99.567746)
		(end 259.1943 -102.1969)
		(width 0.0889)
		(layer "In4.Cu")
		(net "M_E_CLK_DN<0>")
	)
	(segment
		(start 259.245608 -144.93748)
		(end 258.720844 -144.93748)
		(width 0.14224)
		(layer "In4.Cu")
		(net "M_E_CLK_DN<0>")
	)
	(segment
		(start 261.054088 -132.8547)
		(end 261.16788 -132.968492)
		(width 0.14224)
		(layer "In4.Cu")
		(net "M_E_CLK_DN<0>")
	)
	(segment
		(start 260.830568 -142.660116)
		(end 260.94436 -142.773908)
		(width 0.14224)
		(layer "In4.Cu")
		(net "M_E_CLK_DN<0>")
	)
	(segment
		(start 259.13207 -96.48952)
		(end 259.13842 -96.500188)
		(width 0.0889)
		(layer "In4.Cu")
		(net "M_E_CLK_DN<0>")
	)
	(segment
		(start 260.94436 -140.92428)
		(end 260.830568 -141.038072)
		(width 0.14224)
		(layer "In4.Cu")
		(net "M_E_CLK_DN<0>")
	)
	(segment
		(start 260.312408 -128.262126)
		(end 261.093458 -129.043176)
		(width 0.14224)
		(layer "In4.Cu")
		(net "M_E_CLK_DN<0>")
	)
	(segment
		(start 261.16788 -135.28294)
		(end 261.16788 -135.74776)
		(width 0.14224)
		(layer "In4.Cu")
		(net "M_E_CLK_DN<0>")
	)
	(segment
		(start 257.287014 -144.715738)
		(end 257.287014 -144.283684)
		(width 0.14224)
		(layer "In4.Cu")
		(net "M_E_CLK_DN<0>")
	)
	(segment
		(start 261.16788 -136.440164)
		(end 261.16788 -139.61364)
		(width 0.14224)
		(layer "In4.Cu")
		(net "M_E_CLK_DN<0>")
	)
	(segment
		(start 258.607306 -144.823942)
		(end 258.142486 -144.823942)
		(width 0.14224)
		(layer "In4.Cu")
		(net "M_E_CLK_DN<0>")
	)
	(segment
		(start 260.65734 -130.780536)
		(end 260.874764 -130.780536)
		(width 0.14224)
		(layer "In4.Cu")
		(net "M_E_CLK_DN<0>")
	)
	(segment
		(start 261.054088 -134.704328)
		(end 261.054088 -135.169148)
		(width 0.14224)
		(layer "In4.Cu")
		(net "M_E_CLK_DN<0>")
	)
	(segment
		(start 259.132578 -99.46132)
		(end 259.16509 -99.519232)
		(width 0.0889)
		(layer "In4.Cu")
		(net "M_E_CLK_DN<0>")
	)
	(segment
		(start 260.25475 -143.768826)
		(end 260.25475 -143.928338)
		(width 0.14224)
		(layer "In4.Cu")
		(net "M_E_CLK_DN<0>")
	)
	(segment
		(start 259.13842 -95.509588)
		(end 259.143246 -95.518224)
		(width 0.0889)
		(layer "In4.Cu")
		(net "M_E_CLK_DN<0>")
	)
	(segment
		(start 260.25475 -143.928338)
		(end 259.928868 -144.25422)
		(width 0.14224)
		(layer "In4.Cu")
		(net "M_E_CLK_DN<0>")
	)
	(segment
		(start 261.16788 -132.968492)
		(end 261.16788 -133.433312)
		(width 0.14224)
		(layer "In4.Cu")
		(net "M_E_CLK_DN<0>")
	)
	(segment
		(start 259.1943 -102.1969)
		(end 260.345428 -103.348028)
		(width 0.0889)
		(layer "In4.Cu")
		(net "M_E_CLK_DN<0>")
	)
	(segment
		(start 257.287014 -144.283684)
		(end 257.599942 -143.970756)
		(width 0.14224)
		(layer "In4.Cu")
		(net "M_E_CLK_DN<0>")
	)
	(segment
		(start 258.720844 -144.93748)
		(end 258.607306 -144.823942)
		(width 0.14224)
		(layer "In4.Cu")
		(net "M_E_CLK_DN<0>")
	)
	(segment
		(start 259.13842 -97.490788)
		(end 259.143246 -97.499424)
		(width 0.0889)
		(layer "In4.Cu")
		(net "M_E_CLK_DN<0>")
	)
	(segment
		(start 261.054088 -132.38988)
		(end 261.054088 -132.8547)
		(width 0.14224)
		(layer "In4.Cu")
		(net "M_E_CLK_DN<0>")
	)
	(segment
		(start 261.054088 -135.861552)
		(end 261.054088 -136.326372)
		(width 0.14224)
		(layer "In4.Cu")
		(net "M_E_CLK_DN<0>")
	)
	(segment
		(start 260.830568 -141.502892)
		(end 260.94436 -141.616684)
		(width 0.14224)
		(layer "In4.Cu")
		(net "M_E_CLK_DN<0>")
	)
	(segment
		(start 259.13207 -95.49892)
		(end 259.13842 -95.509588)
		(width 0.0889)
		(layer "In4.Cu")
		(net "M_E_CLK_DN<0>")
	)
	(segment
		(start 260.583426 -143.44015)
		(end 260.25475 -143.768826)
		(width 0.14224)
		(layer "In4.Cu")
		(net "M_E_CLK_DN<0>")
	)
	(arc
		(start 259.143246 -97.499424)
		(mid 259.192001 -97.695776)
		(end 259.13842 -97.890838)
		(width 0.0889)
		(layer "In4.Cu")
		(net "M_E_CLK_DN<0>")
	)
	(arc
		(start 258.97967 -94.906846)
		(mid 259.0488 -95.01706)
		(end 259.062982 -95.146368)
		(width 0.0889)
		(layer "In4.Cu")
		(net "M_E_CLK_DN<0>")
	)
	(arc
		(start 259.143246 -96.508824)
		(mid 259.192001 -96.705176)
		(end 259.13842 -96.900238)
		(width 0.0889)
		(layer "In4.Cu")
		(net "M_E_CLK_DN<0>")
	)
	(arc
		(start 259.13842 -98.881438)
		(mid 259.05945 -99.170159)
		(end 259.13207 -99.460558)
		(width 0.0889)
		(layer "In4.Cu")
		(net "M_E_CLK_DN<0>")
	)
	(arc
		(start 259.143246 -98.490024)
		(mid 259.192001 -98.686376)
		(end 259.13842 -98.881438)
		(width 0.0889)
		(layer "In4.Cu")
		(net "M_E_CLK_DN<0>")
	)
	(arc
		(start 259.13842 -97.890838)
		(mid 259.059198 -98.179956)
		(end 259.13207 -98.47072)
		(width 0.0889)
		(layer "In4.Cu")
		(net "M_E_CLK_DN<0>")
	)
	(arc
		(start 259.13842 -95.909638)
		(mid 259.059198 -96.198756)
		(end 259.13207 -96.48952)
		(width 0.0889)
		(layer "In4.Cu")
		(net "M_E_CLK_DN<0>")
	)
	(arc
		(start 259.13842 -96.900238)
		(mid 259.059198 -97.189356)
		(end 259.13207 -97.48012)
		(width 0.0889)
		(layer "In4.Cu")
		(net "M_E_CLK_DN<0>")
	)
	(arc
		(start 259.143246 -95.518224)
		(mid 259.192001 -95.714576)
		(end 259.13842 -95.909638)
		(width 0.0889)
		(layer "In4.Cu")
		(net "M_E_CLK_DN<0>")
	)
	(arc
		(start 259.062982 -95.146368)
		(mid 259.070068 -95.328028)
		(end 259.13207 -95.49892)
		(width 0.0889)
		(layer "In4.Cu")
		(net "M_E_CLK_DN<0>")
	)
	(segment
		(start 251.636784 -96.20504)
		(end 251.065284 -96.20504)
		(width 0.1016)
		(layer "F.Cu")
		(net "M_E_CKE<3>")
	)
	(via
		(at 251.065284 -96.20504)
		(size 0.508)
		(drill 0.254)
		(layers "F.Cu" "B.Cu")
		(net "M_E_CKE<3>")
	)
	(via
		(at 243.999766 -139.170156)
		(size 0.4572)
		(drill 0.2032)
		(layers "F.Cu" "B.Cu")
		(net "M_E_CKE<3>")
	)
	(segment
		(start 243.999766 -137.877296)
		(end 243.999766 -139.170156)
		(width 0.1651)
		(layer "B.Cu")
		(net "M_E_CKE<3>")
	)
	(segment
		(start 244.000274 -137.877296)
		(end 243.999766 -137.877296)
		(width 0.1651)
		(layer "B.Cu")
		(net "M_E_CKE<3>")
	)
	(segment
		(start 244.6274 -126.6952)
		(end 244.6274 -129.7686)
		(width 0.14224)
		(layer "In4.Cu")
		(net "M_E_CKE<3>")
	)
	(segment
		(start 250.665488 -98.351848)
		(end 251.041916 -98.728276)
		(width 0.0889)
		(layer "In4.Cu")
		(net "M_E_CKE<3>")
	)
	(segment
		(start 250.665488 -98.114104)
		(end 250.665488 -98.351848)
		(width 0.0889)
		(layer "In4.Cu")
		(net "M_E_CKE<3>")
	)
	(segment
		(start 250.718574 -97.395538)
		(end 250.724924 -97.406206)
		(width 0.0889)
		(layer "In4.Cu")
		(net "M_E_CKE<3>")
	)
	(segment
		(start 244.5004 -130.6068)
		(end 244.5004 -131.2164)
		(width 0.14224)
		(layer "In4.Cu")
		(net "M_E_CKE<3>")
	)
	(segment
		(start 250.735338 -96.966786)
		(end 250.718574 -96.995488)
		(width 0.0889)
		(layer "In4.Cu")
		(net "M_E_CKE<3>")
	)
	(segment
		(start 244.2083 -133.8707)
		(end 244.436138 -134.098538)
		(width 0.14224)
		(layer "In4.Cu")
		(net "M_E_CKE<3>")
	)
	(segment
		(start 244.6274 -129.7686)
		(end 244.348 -130.048)
		(width 0.14224)
		(layer "In4.Cu")
		(net "M_E_CKE<3>")
	)
	(segment
		(start 243.999766 -138.524488)
		(end 243.999766 -139.170156)
		(width 0.14224)
		(layer "In4.Cu")
		(net "M_E_CKE<3>")
	)
	(segment
		(start 244.348 -130.4544)
		(end 244.5004 -130.6068)
		(width 0.14224)
		(layer "In4.Cu")
		(net "M_E_CKE<3>")
	)
	(segment
		(start 244.5004 -131.2164)
		(end 244.2083 -131.5085)
		(width 0.14224)
		(layer "In4.Cu")
		(net "M_E_CKE<3>")
	)
	(segment
		(start 251.041916 -101.715316)
		(end 251.041916 -120.280684)
		(width 0.14224)
		(layer "In4.Cu")
		(net "M_E_CKE<3>")
	)
	(segment
		(start 251.065284 -96.20504)
		(end 250.735338 -96.966786)
		(width 0.0889)
		(layer "In4.Cu")
		(net "M_E_CKE<3>")
	)
	(segment
		(start 244.409468 -136.006332)
		(end 244.409468 -138.114786)
		(width 0.14224)
		(layer "In4.Cu")
		(net "M_E_CKE<3>")
	)
	(segment
		(start 244.436138 -135.979662)
		(end 244.409468 -136.006332)
		(width 0.14224)
		(layer "In4.Cu")
		(net "M_E_CKE<3>")
	)
	(segment
		(start 251.041916 -98.728276)
		(end 251.041916 -101.715316)
		(width 0.0889)
		(layer "In4.Cu")
		(net "M_E_CKE<3>")
	)
	(segment
		(start 244.409468 -138.114786)
		(end 243.999766 -138.524488)
		(width 0.14224)
		(layer "In4.Cu")
		(net "M_E_CKE<3>")
	)
	(segment
		(start 244.436138 -134.098538)
		(end 244.436138 -135.979662)
		(width 0.14224)
		(layer "In4.Cu")
		(net "M_E_CKE<3>")
	)
	(segment
		(start 250.743466 -97.938082)
		(end 250.73483 -97.946718)
		(width 0.0889)
		(layer "In4.Cu")
		(net "M_E_CKE<3>")
	)
	(segment
		(start 250.713748 -97.386902)
		(end 250.718574 -97.395538)
		(width 0.0889)
		(layer "In4.Cu")
		(net "M_E_CKE<3>")
	)
	(segment
		(start 251.041916 -120.280684)
		(end 244.6274 -126.6952)
		(width 0.14224)
		(layer "In4.Cu")
		(net "M_E_CKE<3>")
	)
	(segment
		(start 244.2083 -131.5085)
		(end 244.2083 -133.8707)
		(width 0.14224)
		(layer "In4.Cu")
		(net "M_E_CKE<3>")
	)
	(segment
		(start 244.348 -130.048)
		(end 244.348 -130.4544)
		(width 0.14224)
		(layer "In4.Cu")
		(net "M_E_CKE<3>")
	)
	(arc
		(start 250.73483 -97.946718)
		(mid 250.683516 -98.023515)
		(end 250.665488 -98.114104)
		(width 0.0889)
		(layer "In4.Cu")
		(net "M_E_CKE<3>")
	)
	(arc
		(start 250.724924 -97.406206)
		(mid 250.797403 -97.66993)
		(end 250.743466 -97.938082)
		(width 0.0889)
		(layer "In4.Cu")
		(net "M_E_CKE<3>")
	)
	(arc
		(start 250.718574 -96.995488)
		(mid 250.665104 -97.190551)
		(end 250.713748 -97.386902)
		(width 0.0889)
		(layer "In4.Cu")
		(net "M_E_CKE<3>")
	)
	(segment
		(start 251.636784 -94.223586)
		(end 251.065284 -94.223586)
		(width 0.1016)
		(layer "F.Cu")
		(net "M_E_CKE<2>")
	)
	(via
		(at 244.849904 -141.187678)
		(size 0.4572)
		(drill 0.2032)
		(layers "F.Cu" "B.Cu")
		(net "M_E_CKE<2>")
	)
	(via
		(at 251.065284 -94.223586)
		(size 0.508)
		(drill 0.254)
		(layers "F.Cu" "B.Cu")
		(net "M_E_CKE<2>")
	)
	(segment
		(start 244.850412 -142.477236)
		(end 244.849904 -142.476982)
		(width 0.1651)
		(layer "B.Cu")
		(net "M_E_CKE<2>")
	)
	(segment
		(start 244.849904 -142.476982)
		(end 244.849904 -141.187678)
		(width 0.1651)
		(layer "B.Cu")
		(net "M_E_CKE<2>")
	)
	(segment
		(start 246.13743 -134.07263)
		(end 246.13743 -134.76097)
		(width 0.14224)
		(layer "In4.Cu")
		(net "M_E_CKE<2>")
	)
	(segment
		(start 251.577094 -98.481388)
		(end 251.572268 -98.490024)
		(width 0.0889)
		(layer "In4.Cu")
		(net "M_E_CKE<2>")
	)
	(segment
		(start 251.583444 -98.47072)
		(end 251.577094 -98.481388)
		(width 0.0889)
		(layer "In4.Cu")
		(net "M_E_CKE<2>")
	)
	(segment
		(start 251.065284 -94.223586)
		(end 251.56033 -94.889828)
		(width 0.0889)
		(layer "In4.Cu")
		(net "M_E_CKE<2>")
	)
	(segment
		(start 251.583444 -96.48952)
		(end 251.577094 -96.500188)
		(width 0.0889)
		(layer "In4.Cu")
		(net "M_E_CKE<2>")
	)
	(segment
		(start 246.0752 -129.9972)
		(end 246.0752 -130.5052)
		(width 0.14224)
		(layer "In4.Cu")
		(net "M_E_CKE<2>")
	)
	(segment
		(start 245.3386 -139.6238)
		(end 245.3386 -140.0556)
		(width 0.14224)
		(layer "In4.Cu")
		(net "M_E_CKE<2>")
	)
	(segment
		(start 246.253 -129.8194)
		(end 246.0752 -129.9972)
		(width 0.14224)
		(layer "In4.Cu")
		(net "M_E_CKE<2>")
	)
	(segment
		(start 246.253 -126.5682)
		(end 246.253 -129.8194)
		(width 0.14224)
		(layer "In4.Cu")
		(net "M_E_CKE<2>")
	)
	(segment
		(start 245.3386 -140.0556)
		(end 245.1608 -140.2334)
		(width 0.14224)
		(layer "In4.Cu")
		(net "M_E_CKE<2>")
	)
	(segment
		(start 246.0498 -131.318)
		(end 246.0498 -133.985)
		(width 0.14224)
		(layer "In4.Cu")
		(net "M_E_CKE<2>")
	)
	(segment
		(start 252.057916 -120.763284)
		(end 246.253 -126.5682)
		(width 0.14224)
		(layer "In4.Cu")
		(net "M_E_CKE<2>")
	)
	(segment
		(start 245.1608 -140.876782)
		(end 244.849904 -141.187678)
		(width 0.14224)
		(layer "In4.Cu")
		(net "M_E_CKE<2>")
	)
	(segment
		(start 246.115078 -134.783322)
		(end 246.115078 -138.034522)
		(width 0.14224)
		(layer "In4.Cu")
		(net "M_E_CKE<2>")
	)
	(segment
		(start 245.1608 -140.2334)
		(end 245.1608 -140.876782)
		(width 0.14224)
		(layer "In4.Cu")
		(net "M_E_CKE<2>")
	)
	(segment
		(start 246.0498 -133.985)
		(end 246.13743 -134.07263)
		(width 0.14224)
		(layer "In4.Cu")
		(net "M_E_CKE<2>")
	)
	(segment
		(start 246.13743 -134.76097)
		(end 246.115078 -134.783322)
		(width 0.14224)
		(layer "In4.Cu")
		(net "M_E_CKE<2>")
	)
	(segment
		(start 251.583444 -95.49892)
		(end 251.577094 -95.509588)
		(width 0.0889)
		(layer "In4.Cu")
		(net "M_E_CKE<2>")
	)
	(segment
		(start 246.1768 -131.191)
		(end 246.0498 -131.318)
		(width 0.14224)
		(layer "In4.Cu")
		(net "M_E_CKE<2>")
	)
	(segment
		(start 251.4346 -98.887534)
		(end 251.4346 -100.9396)
		(width 0.0889)
		(layer "In4.Cu")
		(net "M_E_CKE<2>")
	)
	(segment
		(start 245.29034 -138.85926)
		(end 245.29034 -139.57554)
		(width 0.14224)
		(layer "In4.Cu")
		(net "M_E_CKE<2>")
	)
	(segment
		(start 245.29034 -139.57554)
		(end 245.3386 -139.6238)
		(width 0.14224)
		(layer "In4.Cu")
		(net "M_E_CKE<2>")
	)
	(segment
		(start 251.56033 -94.889828)
		(end 251.577094 -94.919038)
		(width 0.0889)
		(layer "In4.Cu")
		(net "M_E_CKE<2>")
	)
	(segment
		(start 251.526294 -98.63328)
		(end 251.4346 -98.887534)
		(width 0.0889)
		(layer "In4.Cu")
		(net "M_E_CKE<2>")
	)
	(segment
		(start 246.115078 -138.034522)
		(end 245.29034 -138.85926)
		(width 0.14224)
		(layer "In4.Cu")
		(net "M_E_CKE<2>")
	)
	(segment
		(start 246.1768 -130.6068)
		(end 246.1768 -131.191)
		(width 0.14224)
		(layer "In4.Cu")
		(net "M_E_CKE<2>")
	)
	(segment
		(start 246.0752 -130.5052)
		(end 246.1768 -130.6068)
		(width 0.14224)
		(layer "In4.Cu")
		(net "M_E_CKE<2>")
	)
	(segment
		(start 251.577094 -97.490788)
		(end 251.572268 -97.499424)
		(width 0.0889)
		(layer "In4.Cu")
		(net "M_E_CKE<2>")
	)
	(segment
		(start 251.577094 -96.500188)
		(end 251.572268 -96.508824)
		(width 0.0889)
		(layer "In4.Cu")
		(net "M_E_CKE<2>")
	)
	(segment
		(start 252.057916 -101.800152)
		(end 252.057916 -120.763284)
		(width 0.14224)
		(layer "In4.Cu")
		(net "M_E_CKE<2>")
	)
	(segment
		(start 252.057916 -101.562916)
		(end 252.057916 -101.800152)
		(width 0.0889)
		(layer "In4.Cu")
		(net "M_E_CKE<2>")
	)
	(segment
		(start 251.4346 -100.9396)
		(end 252.057916 -101.562916)
		(width 0.0889)
		(layer "In4.Cu")
		(net "M_E_CKE<2>")
	)
	(segment
		(start 251.577094 -95.509588)
		(end 251.572268 -95.518224)
		(width 0.0889)
		(layer "In4.Cu")
		(net "M_E_CKE<2>")
	)
	(segment
		(start 251.583444 -97.48012)
		(end 251.577094 -97.490788)
		(width 0.0889)
		(layer "In4.Cu")
		(net "M_E_CKE<2>")
	)
	(arc
		(start 251.577094 -96.900238)
		(mid 251.656316 -97.189356)
		(end 251.583444 -97.48012)
		(width 0.0889)
		(layer "In4.Cu")
		(net "M_E_CKE<2>")
	)
	(arc
		(start 251.577094 -94.919038)
		(mid 251.656316 -95.208156)
		(end 251.583444 -95.49892)
		(width 0.0889)
		(layer "In4.Cu")
		(net "M_E_CKE<2>")
	)
	(arc
		(start 251.577094 -95.909638)
		(mid 251.656316 -96.198756)
		(end 251.583444 -96.48952)
		(width 0.0889)
		(layer "In4.Cu")
		(net "M_E_CKE<2>")
	)
	(arc
		(start 251.572268 -98.490024)
		(mid 251.542502 -98.559475)
		(end 251.526294 -98.63328)
		(width 0.0889)
		(layer "In4.Cu")
		(net "M_E_CKE<2>")
	)
	(arc
		(start 251.572268 -95.518224)
		(mid 251.523513 -95.714576)
		(end 251.577094 -95.909638)
		(width 0.0889)
		(layer "In4.Cu")
		(net "M_E_CKE<2>")
	)
	(arc
		(start 251.572268 -96.508824)
		(mid 251.523513 -96.705176)
		(end 251.577094 -96.900238)
		(width 0.0889)
		(layer "In4.Cu")
		(net "M_E_CKE<2>")
	)
	(arc
		(start 251.577094 -97.890838)
		(mid 251.656316 -98.179956)
		(end 251.583444 -98.47072)
		(width 0.0889)
		(layer "In4.Cu")
		(net "M_E_CKE<2>")
	)
	(arc
		(start 251.572268 -97.499424)
		(mid 251.523513 -97.695776)
		(end 251.577094 -97.890838)
		(width 0.0889)
		(layer "In4.Cu")
		(net "M_E_CKE<2>")
	)
	(segment
		(start 243.999766 -147.27174)
		(end 243.999766 -145.988278)
		(width 0.1651)
		(layer "F.Cu")
		(net "M_E_CKE<1>")
	)
	(segment
		(start 244.000274 -147.27174)
		(end 243.999766 -147.27174)
		(width 0.1651)
		(layer "F.Cu")
		(net "M_E_CKE<1>")
	)
	(segment
		(start 251.636784 -95.21444)
		(end 251.065284 -95.21444)
		(width 0.1016)
		(layer "F.Cu")
		(net "M_E_CKE<1>")
	)
	(via
		(at 251.065284 -95.21444)
		(size 0.508)
		(drill 0.254)
		(layers "F.Cu" "B.Cu")
		(net "M_E_CKE<1>")
	)
	(via
		(at 243.999766 -145.988278)
		(size 0.4572)
		(drill 0.2032)
		(layers "F.Cu" "B.Cu")
		(net "M_E_CKE<1>")
	)
	(segment
		(start 245.28653 -136.11733)
		(end 245.28653 -138.02487)
		(width 0.14224)
		(layer "In4.Cu")
		(net "M_E_CKE<1>")
	)
	(segment
		(start 243.999766 -144.671034)
		(end 243.999766 -145.988278)
		(width 0.14224)
		(layer "In4.Cu")
		(net "M_E_CKE<1>")
	)
	(segment
		(start 251.411994 -97.395538)
		(end 251.405644 -97.406206)
		(width 0.0889)
		(layer "In4.Cu")
		(net "M_E_CKE<1>")
	)
	(segment
		(start 251.39523 -95.976186)
		(end 251.411994 -96.004888)
		(width 0.0889)
		(layer "In4.Cu")
		(net "M_E_CKE<1>")
	)
	(segment
		(start 245.2116 -129.8702)
		(end 245.3386 -129.9972)
		(width 0.14224)
		(layer "In4.Cu")
		(net "M_E_CKE<1>")
	)
	(segment
		(start 251.41682 -96.396302)
		(end 251.411994 -96.404938)
		(width 0.0889)
		(layer "In4.Cu")
		(net "M_E_CKE<1>")
	)
	(segment
		(start 244.43944 -140.17244)
		(end 244.43944 -144.23136)
		(width 0.14224)
		(layer "In4.Cu")
		(net "M_E_CKE<1>")
	)
	(segment
		(start 251.411994 -96.404938)
		(end 251.405644 -96.415606)
		(width 0.0889)
		(layer "In4.Cu")
		(net "M_E_CKE<1>")
	)
	(segment
		(start 245.28653 -138.02487)
		(end 244.413278 -138.898122)
		(width 0.14224)
		(layer "In4.Cu")
		(net "M_E_CKE<1>")
	)
	(segment
		(start 245.3386 -130.5052)
		(end 245.2116 -130.6322)
		(width 0.14224)
		(layer "In4.Cu")
		(net "M_E_CKE<1>")
	)
	(segment
		(start 245.3132 -134.0358)
		(end 245.264178 -134.084822)
		(width 0.14224)
		(layer "In4.Cu")
		(net "M_E_CKE<1>")
	)
	(segment
		(start 245.3132 -131.2926)
		(end 245.3132 -134.0358)
		(width 0.14224)
		(layer "In4.Cu")
		(net "M_E_CKE<1>")
	)
	(segment
		(start 245.264178 -134.084822)
		(end 245.264178 -136.094978)
		(width 0.14224)
		(layer "In4.Cu")
		(net "M_E_CKE<1>")
	)
	(segment
		(start 245.2116 -130.6322)
		(end 245.2116 -131.191)
		(width 0.14224)
		(layer "In4.Cu")
		(net "M_E_CKE<1>")
	)
	(segment
		(start 251.41682 -97.386902)
		(end 251.411994 -97.395538)
		(width 0.0889)
		(layer "In4.Cu")
		(net "M_E_CKE<1>")
	)
	(segment
		(start 251.2441 -98.6155)
		(end 251.2441 -101.240844)
		(width 0.0889)
		(layer "In4.Cu")
		(net "M_E_CKE<1>")
	)
	(segment
		(start 251.549916 -120.534684)
		(end 245.2116 -126.873)
		(width 0.14224)
		(layer "In4.Cu")
		(net "M_E_CKE<1>")
	)
	(segment
		(start 244.413278 -138.898122)
		(end 244.413278 -140.146278)
		(width 0.14224)
		(layer "In4.Cu")
		(net "M_E_CKE<1>")
	)
	(segment
		(start 251.065284 -95.21444)
		(end 251.39523 -95.976186)
		(width 0.0889)
		(layer "In4.Cu")
		(net "M_E_CKE<1>")
	)
	(segment
		(start 251.549916 -101.54666)
		(end 251.549916 -101.854762)
		(width 0.0889)
		(layer "In4.Cu")
		(net "M_E_CKE<1>")
	)
	(segment
		(start 251.41682 -98.377502)
		(end 251.411994 -98.386138)
		(width 0.0889)
		(layer "In4.Cu")
		(net "M_E_CKE<1>")
	)
	(segment
		(start 251.411994 -98.386138)
		(end 251.405644 -98.396806)
		(width 0.0889)
		(layer "In4.Cu")
		(net "M_E_CKE<1>")
	)
	(segment
		(start 244.43944 -144.23136)
		(end 243.999766 -144.671034)
		(width 0.14224)
		(layer "In4.Cu")
		(net "M_E_CKE<1>")
	)
	(segment
		(start 251.549916 -101.854762)
		(end 251.549916 -120.534684)
		(width 0.14224)
		(layer "In4.Cu")
		(net "M_E_CKE<1>")
	)
	(segment
		(start 245.3386 -129.9972)
		(end 245.3386 -130.5052)
		(width 0.14224)
		(layer "In4.Cu")
		(net "M_E_CKE<1>")
	)
	(segment
		(start 245.2116 -131.191)
		(end 245.3132 -131.2926)
		(width 0.14224)
		(layer "In4.Cu")
		(net "M_E_CKE<1>")
	)
	(segment
		(start 251.2441 -101.240844)
		(end 251.549916 -101.54666)
		(width 0.0889)
		(layer "In4.Cu")
		(net "M_E_CKE<1>")
	)
	(segment
		(start 251.27204 -98.58756)
		(end 251.2441 -98.6155)
		(width 0.0889)
		(layer "In4.Cu")
		(net "M_E_CKE<1>")
	)
	(segment
		(start 245.2116 -126.873)
		(end 245.2116 -129.8702)
		(width 0.14224)
		(layer "In4.Cu")
		(net "M_E_CKE<1>")
	)
	(segment
		(start 244.413278 -140.146278)
		(end 244.43944 -140.17244)
		(width 0.14224)
		(layer "In4.Cu")
		(net "M_E_CKE<1>")
	)
	(segment
		(start 251.368306 -98.479356)
		(end 251.27204 -98.58756)
		(width 0.0889)
		(layer "In4.Cu")
		(net "M_E_CKE<1>")
	)
	(segment
		(start 245.264178 -136.094978)
		(end 245.28653 -136.11733)
		(width 0.14224)
		(layer "In4.Cu")
		(net "M_E_CKE<1>")
	)
	(arc
		(start 251.405644 -97.406206)
		(mid 251.332846 -97.696969)
		(end 251.411994 -97.986088)
		(width 0.0889)
		(layer "In4.Cu")
		(net "M_E_CKE<1>")
	)
	(arc
		(start 251.411994 -96.995488)
		(mid 251.465464 -97.190551)
		(end 251.41682 -97.386902)
		(width 0.0889)
		(layer "In4.Cu")
		(net "M_E_CKE<1>")
	)
	(arc
		(start 251.411994 -96.004888)
		(mid 251.465464 -96.199951)
		(end 251.41682 -96.396302)
		(width 0.0889)
		(layer "In4.Cu")
		(net "M_E_CKE<1>")
	)
	(arc
		(start 251.411994 -97.986088)
		(mid 251.465464 -98.181151)
		(end 251.41682 -98.377502)
		(width 0.0889)
		(layer "In4.Cu")
		(net "M_E_CKE<1>")
	)
	(arc
		(start 251.405644 -98.396806)
		(mid 251.385382 -98.437361)
		(end 251.368306 -98.479356)
		(width 0.0889)
		(layer "In4.Cu")
		(net "M_E_CKE<1>")
	)
	(arc
		(start 251.405644 -96.415606)
		(mid 251.332846 -96.706369)
		(end 251.411994 -96.995488)
		(width 0.0889)
		(layer "In4.Cu")
		(net "M_E_CKE<1>")
	)
	(segment
		(start 244.850412 -142.6718)
		(end 244.849904 -142.677642)
		(width 0.1651)
		(layer "F.Cu")
		(net "M_E_CKE<0>")
	)
	(segment
		(start 252.495304 -94.718886)
		(end 251.923804 -94.718886)
		(width 0.1016)
		(layer "F.Cu")
		(net "M_E_CKE<0>")
	)
	(segment
		(start 244.849904 -142.677642)
		(end 244.849904 -143.970756)
		(width 0.1651)
		(layer "F.Cu")
		(net "M_E_CKE<0>")
	)
	(via
		(at 244.849904 -143.970756)
		(size 0.4572)
		(drill 0.2032)
		(layers "F.Cu" "B.Cu")
		(net "M_E_CKE<0>")
	)
	(via
		(at 251.923804 -94.718886)
		(size 0.508)
		(drill 0.254)
		(layers "F.Cu" "B.Cu")
		(net "M_E_CKE<0>")
	)
	(segment
		(start 252.577092 -121.031508)
		(end 246.9134 -126.6952)
		(width 0.14224)
		(layer "In4.Cu")
		(net "M_E_CKE<0>")
	)
	(segment
		(start 247.015 -130.5306)
		(end 246.888 -130.6576)
		(width 0.14224)
		(layer "In4.Cu")
		(net "M_E_CKE<0>")
	)
	(segment
		(start 252.577092 -100.478336)
		(end 252.577092 -100.821998)
		(width 0.0889)
		(layer "In4.Cu")
		(net "M_E_CKE<0>")
	)
	(segment
		(start 246.9896 -131.953)
		(end 246.9896 -134.7978)
		(width 0.14224)
		(layer "In4.Cu")
		(net "M_E_CKE<0>")
	)
	(segment
		(start 246.8118 -136.8552)
		(end 246.8118 -138.038332)
		(width 0.14224)
		(layer "In4.Cu")
		(net "M_E_CKE<0>")
	)
	(segment
		(start 246.98833 -136.14273)
		(end 246.98833 -136.67867)
		(width 0.14224)
		(layer "In4.Cu")
		(net "M_E_CKE<0>")
	)
	(segment
		(start 247.0404 -131.9022)
		(end 246.9896 -131.953)
		(width 0.14224)
		(layer "In4.Cu")
		(net "M_E_CKE<0>")
	)
	(segment
		(start 246.98833 -136.67867)
		(end 246.8118 -136.8552)
		(width 0.14224)
		(layer "In4.Cu")
		(net "M_E_CKE<0>")
	)
	(segment
		(start 247.015 -129.9464)
		(end 247.015 -130.5306)
		(width 0.14224)
		(layer "In4.Cu")
		(net "M_E_CKE<0>")
	)
	(segment
		(start 246.140986 -140.477494)
		(end 246.140986 -142.127478)
		(width 0.14224)
		(layer "In4.Cu")
		(net "M_E_CKE<0>")
	)
	(segment
		(start 252.253242 -95.47987)
		(end 252.27534 -95.518224)
		(width 0.0889)
		(layer "In4.Cu")
		(net "M_E_CKE<0>")
	)
	(segment
		(start 252.225048 -99.394518)
		(end 252.338332 -99.590606)
		(width 0.0889)
		(layer "In4.Cu")
		(net "M_E_CKE<0>")
	)
	(segment
		(start 246.115078 -139.583922)
		(end 246.0244 -139.6746)
		(width 0.14224)
		(layer "In4.Cu")
		(net "M_E_CKE<0>")
	)
	(segment
		(start 246.140986 -142.127478)
		(end 244.849904 -143.41856)
		(width 0.14224)
		(layer "In4.Cu")
		(net "M_E_CKE<0>")
	)
	(segment
		(start 247.10009 -136.03097)
		(end 246.98833 -136.14273)
		(width 0.14224)
		(layer "In4.Cu")
		(net "M_E_CKE<0>")
	)
	(segment
		(start 246.9134 -129.8448)
		(end 247.015 -129.9464)
		(width 0.14224)
		(layer "In4.Cu")
		(net "M_E_CKE<0>")
	)
	(segment
		(start 251.923804 -94.718886)
		(end 252.253242 -95.47987)
		(width 0.0889)
		(layer "In4.Cu")
		(net "M_E_CKE<0>")
	)
	(segment
		(start 247.10009 -134.90829)
		(end 247.10009 -136.03097)
		(width 0.14224)
		(layer "In4.Cu")
		(net "M_E_CKE<0>")
	)
	(segment
		(start 252.270514 -96.500188)
		(end 252.27534 -96.508824)
		(width 0.0889)
		(layer "In4.Cu")
		(net "M_E_CKE<0>")
	)
	(segment
		(start 252.270514 -98.481388)
		(end 252.27534 -98.490024)
		(width 0.0889)
		(layer "In4.Cu")
		(net "M_E_CKE<0>")
	)
	(segment
		(start 252.577092 -100.821998)
		(end 252.577092 -121.031508)
		(width 0.14224)
		(layer "In4.Cu")
		(net "M_E_CKE<0>")
	)
	(segment
		(start 247.0404 -131.2926)
		(end 247.0404 -131.9022)
		(width 0.14224)
		(layer "In4.Cu")
		(net "M_E_CKE<0>")
	)
	(segment
		(start 252.338332 -100.239576)
		(end 252.577092 -100.478336)
		(width 0.0889)
		(layer "In4.Cu")
		(net "M_E_CKE<0>")
	)
	(segment
		(start 246.115078 -138.735054)
		(end 246.115078 -139.583922)
		(width 0.14224)
		(layer "In4.Cu")
		(net "M_E_CKE<0>")
	)
	(segment
		(start 246.9134 -126.6952)
		(end 246.9134 -129.8448)
		(width 0.14224)
		(layer "In4.Cu")
		(net "M_E_CKE<0>")
	)
	(segment
		(start 246.888 -130.6576)
		(end 246.888 -131.1402)
		(width 0.14224)
		(layer "In4.Cu")
		(net "M_E_CKE<0>")
	)
	(segment
		(start 252.264164 -97.48012)
		(end 252.270514 -97.490788)
		(width 0.0889)
		(layer "In4.Cu")
		(net "M_E_CKE<0>")
	)
	(segment
		(start 246.9896 -134.7978)
		(end 247.10009 -134.90829)
		(width 0.14224)
		(layer "In4.Cu")
		(net "M_E_CKE<0>")
	)
	(segment
		(start 252.270514 -97.490788)
		(end 252.27534 -97.499424)
		(width 0.0889)
		(layer "In4.Cu")
		(net "M_E_CKE<0>")
	)
	(segment
		(start 246.0244 -140.360908)
		(end 246.140986 -140.477494)
		(width 0.14224)
		(layer "In4.Cu")
		(net "M_E_CKE<0>")
	)
	(segment
		(start 246.0244 -139.6746)
		(end 246.0244 -140.360908)
		(width 0.14224)
		(layer "In4.Cu")
		(net "M_E_CKE<0>")
	)
	(segment
		(start 252.338332 -99.590606)
		(end 252.338332 -100.239576)
		(width 0.0889)
		(layer "In4.Cu")
		(net "M_E_CKE<0>")
	)
	(segment
		(start 246.888 -131.1402)
		(end 247.0404 -131.2926)
		(width 0.14224)
		(layer "In4.Cu")
		(net "M_E_CKE<0>")
	)
	(segment
		(start 246.8118 -138.038332)
		(end 246.115078 -138.735054)
		(width 0.14224)
		(layer "In4.Cu")
		(net "M_E_CKE<0>")
	)
	(segment
		(start 244.849904 -143.41856)
		(end 244.849904 -143.970756)
		(width 0.14224)
		(layer "In4.Cu")
		(net "M_E_CKE<0>")
	)
	(segment
		(start 252.264164 -98.47072)
		(end 252.270514 -98.481388)
		(width 0.0889)
		(layer "In4.Cu")
		(net "M_E_CKE<0>")
	)
	(segment
		(start 252.264164 -96.48952)
		(end 252.270514 -96.500188)
		(width 0.0889)
		(layer "In4.Cu")
		(net "M_E_CKE<0>")
	)
	(arc
		(start 252.270514 -97.890838)
		(mid 252.191292 -98.179956)
		(end 252.264164 -98.47072)
		(width 0.0889)
		(layer "In4.Cu")
		(net "M_E_CKE<0>")
	)
	(arc
		(start 252.27534 -96.508824)
		(mid 252.324095 -96.705176)
		(end 252.270514 -96.900238)
		(width 0.0889)
		(layer "In4.Cu")
		(net "M_E_CKE<0>")
	)
	(arc
		(start 252.270514 -98.881438)
		(mid 252.193556 -99.127447)
		(end 252.228604 -99.382834)
		(width 0.0889)
		(layer "In4.Cu")
		(net "M_E_CKE<0>")
	)
	(arc
		(start 252.27534 -95.518224)
		(mid 252.324095 -95.714576)
		(end 252.270514 -95.909638)
		(width 0.0889)
		(layer "In4.Cu")
		(net "M_E_CKE<0>")
	)
	(arc
		(start 252.27534 -98.490024)
		(mid 252.324095 -98.686376)
		(end 252.270514 -98.881438)
		(width 0.0889)
		(layer "In4.Cu")
		(net "M_E_CKE<0>")
	)
	(arc
		(start 252.27534 -97.499424)
		(mid 252.324095 -97.695776)
		(end 252.270514 -97.890838)
		(width 0.0889)
		(layer "In4.Cu")
		(net "M_E_CKE<0>")
	)
	(arc
		(start 252.228604 -99.382834)
		(mid 252.226795 -99.388666)
		(end 252.225048 -99.394518)
		(width 0.0889)
		(layer "In4.Cu")
		(net "M_E_CKE<0>")
	)
	(arc
		(start 252.270514 -96.900238)
		(mid 252.191292 -97.189356)
		(end 252.264164 -97.48012)
		(width 0.0889)
		(layer "In4.Cu")
		(net "M_E_CKE<0>")
	)
	(arc
		(start 252.270514 -95.909638)
		(mid 252.191292 -96.198756)
		(end 252.264164 -96.48952)
		(width 0.0889)
		(layer "In4.Cu")
		(net "M_E_CKE<0>")
	)
	(segment
		(start 276.300438 -147.27174)
		(end 276.300438 -145.988278)
		(width 0.10795)
		(layer "F.Cu")
		(net "M_E_C<2>")
	)
	(segment
		(start 266.231116 -96.700086)
		(end 265.659616 -96.700086)
		(width 0.1016)
		(layer "F.Cu")
		(net "M_E_C<2>")
	)
	(via
		(at 276.300438 -145.988278)
		(size 0.4572)
		(drill 0.2032)
		(layers "F.Cu" "B.Cu")
		(net "M_E_C<2>")
	)
	(via
		(at 265.659616 -96.700086)
		(size 0.508)
		(drill 0.254)
		(layers "F.Cu" "B.Cu")
		(net "M_E_C<2>")
	)
	(via
		(at 276.300438 -139.172188)
		(size 0.4572)
		(drill 0.2032)
		(layers "F.Cu" "B.Cu")
		(net "M_E_C<2>")
	)
	(segment
		(start 276.300438 -137.877296)
		(end 276.29993 -137.877296)
		(width 0.1651)
		(layer "B.Cu")
		(net "M_E_C<2>")
	)
	(segment
		(start 276.29993 -137.877296)
		(end 276.29993 -139.17168)
		(width 0.1651)
		(layer "B.Cu")
		(net "M_E_C<2>")
	)
	(segment
		(start 276.29993 -139.17168)
		(end 276.300438 -139.172188)
		(width 0.1651)
		(layer "B.Cu")
		(net "M_E_C<2>")
	)
	(segment
		(start 266.1158 -99.4664)
		(end 266.1158 -100.0506)
		(width 0.14224)
		(layer "In11.Cu")
		(net "M_E_C<2>")
	)
	(segment
		(start 274.973288 -129.877312)
		(end 274.973288 -130.523488)
		(width 0.14224)
		(layer "In11.Cu")
		(net "M_E_C<2>")
	)
	(segment
		(start 275.891244 -143.680942)
		(end 275.891244 -144.24914)
		(width 0.14224)
		(layer "In11.Cu")
		(net "M_E_C<2>")
	)
	(segment
		(start 266.1158 -98.5266)
		(end 266.1158 -99.4664)
		(width 0.0889)
		(layer "In11.Cu")
		(net "M_E_C<2>")
	)
	(segment
		(start 274.069556 -126.411482)
		(end 274.069556 -126.411736)
		(width 0.14224)
		(layer "In11.Cu")
		(net "M_E_C<2>")
	)
	(segment
		(start 276.105366 -142.574772)
		(end 276.105366 -143.46682)
		(width 0.14224)
		(layer "In11.Cu")
		(net "M_E_C<2>")
	)
	(segment
		(start 274.99056 -131.83616)
		(end 275.036788 -131.882388)
		(width 0.14224)
		(layer "In11.Cu")
		(net "M_E_C<2>")
	)
	(segment
		(start 275.891244 -140.918184)
		(end 275.891244 -142.36065)
		(width 0.14224)
		(layer "In11.Cu")
		(net "M_E_C<2>")
	)
	(segment
		(start 267.7922 -102.4636)
		(end 268.1478 -102.8192)
		(width 0.14224)
		(layer "In11.Cu")
		(net "M_E_C<2>")
	)
	(segment
		(start 275.081746 -131.089654)
		(end 274.99056 -131.18084)
		(width 0.14224)
		(layer "In11.Cu")
		(net "M_E_C<2>")
	)
	(segment
		(start 268.1478 -120.489726)
		(end 274.069556 -126.411482)
		(width 0.14224)
		(layer "In11.Cu")
		(net "M_E_C<2>")
	)
	(segment
		(start 275.082 -127.42418)
		(end 275.082 -129.7686)
		(width 0.14224)
		(layer "In11.Cu")
		(net "M_E_C<2>")
	)
	(segment
		(start 265.329416 -97.462086)
		(end 265.312906 -97.490534)
		(width 0.0889)
		(layer "In11.Cu")
		(net "M_E_C<2>")
	)
	(segment
		(start 265.659616 -96.700086)
		(end 265.329416 -97.462086)
		(width 0.0889)
		(layer "In11.Cu")
		(net "M_E_C<2>")
	)
	(segment
		(start 268.1478 -102.8192)
		(end 268.1478 -120.489726)
		(width 0.14224)
		(layer "In11.Cu")
		(net "M_E_C<2>")
	)
	(segment
		(start 274.674584 -135.052816)
		(end 274.674584 -135.692896)
		(width 0.14224)
		(layer "In11.Cu")
		(net "M_E_C<2>")
	)
	(segment
		(start 275.040344 -137.467594)
		(end 276.300438 -138.727688)
		(width 0.14224)
		(layer "In11.Cu")
		(net "M_E_C<2>")
	)
	(segment
		(start 274.99056 -131.18084)
		(end 274.99056 -131.83616)
		(width 0.14224)
		(layer "In11.Cu")
		(net "M_E_C<2>")
	)
	(segment
		(start 275.891244 -144.24914)
		(end 276.29993 -144.657826)
		(width 0.14224)
		(layer "In11.Cu")
		(net "M_E_C<2>")
	)
	(segment
		(start 266.1158 -100.0506)
		(end 267.2842 -101.219)
		(width 0.14224)
		(layer "In11.Cu")
		(net "M_E_C<2>")
	)
	(segment
		(start 267.7922 -101.4984)
		(end 267.7922 -102.4636)
		(width 0.14224)
		(layer "In11.Cu")
		(net "M_E_C<2>")
	)
	(segment
		(start 275.036788 -134.690612)
		(end 274.674584 -135.052816)
		(width 0.14224)
		(layer "In11.Cu")
		(net "M_E_C<2>")
	)
	(segment
		(start 267.2842 -101.219)
		(end 267.5128 -101.219)
		(width 0.14224)
		(layer "In11.Cu")
		(net "M_E_C<2>")
	)
	(segment
		(start 276.105366 -143.46682)
		(end 275.891244 -143.680942)
		(width 0.14224)
		(layer "In11.Cu")
		(net "M_E_C<2>")
	)
	(segment
		(start 274.674584 -135.692896)
		(end 275.040344 -136.058656)
		(width 0.14224)
		(layer "In11.Cu")
		(net "M_E_C<2>")
	)
	(segment
		(start 265.312906 -97.89033)
		(end 265.369294 -97.98812)
		(width 0.0889)
		(layer "In11.Cu")
		(net "M_E_C<2>")
	)
	(segment
		(start 275.081746 -130.631946)
		(end 275.081746 -131.089654)
		(width 0.14224)
		(layer "In11.Cu")
		(net "M_E_C<2>")
	)
	(segment
		(start 276.29993 -145.98777)
		(end 276.300438 -145.988278)
		(width 0.14224)
		(layer "In11.Cu")
		(net "M_E_C<2>")
	)
	(segment
		(start 274.973288 -130.523488)
		(end 275.081746 -130.631946)
		(width 0.14224)
		(layer "In11.Cu")
		(net "M_E_C<2>")
	)
	(segment
		(start 275.082 -129.7686)
		(end 274.973288 -129.877312)
		(width 0.14224)
		(layer "In11.Cu")
		(net "M_E_C<2>")
	)
	(segment
		(start 276.300438 -139.172188)
		(end 276.29993 -139.172696)
		(width 0.14224)
		(layer "In11.Cu")
		(net "M_E_C<2>")
	)
	(segment
		(start 275.040344 -136.058656)
		(end 275.040344 -137.467594)
		(width 0.14224)
		(layer "In11.Cu")
		(net "M_E_C<2>")
	)
	(segment
		(start 276.300438 -138.727688)
		(end 276.300438 -139.172188)
		(width 0.14224)
		(layer "In11.Cu")
		(net "M_E_C<2>")
	)
	(segment
		(start 275.036788 -131.882388)
		(end 275.036788 -134.690612)
		(width 0.14224)
		(layer "In11.Cu")
		(net "M_E_C<2>")
	)
	(segment
		(start 276.29993 -144.657826)
		(end 276.29993 -145.98777)
		(width 0.14224)
		(layer "In11.Cu")
		(net "M_E_C<2>")
	)
	(segment
		(start 275.891244 -142.36065)
		(end 276.105366 -142.574772)
		(width 0.14224)
		(layer "In11.Cu")
		(net "M_E_C<2>")
	)
	(segment
		(start 267.5128 -101.219)
		(end 267.7922 -101.4984)
		(width 0.14224)
		(layer "In11.Cu")
		(net "M_E_C<2>")
	)
	(segment
		(start 276.29993 -139.172696)
		(end 276.29993 -140.509498)
		(width 0.14224)
		(layer "In11.Cu")
		(net "M_E_C<2>")
	)
	(segment
		(start 274.069556 -126.411736)
		(end 275.082 -127.42418)
		(width 0.14224)
		(layer "In11.Cu")
		(net "M_E_C<2>")
	)
	(segment
		(start 276.29993 -140.509498)
		(end 275.891244 -140.918184)
		(width 0.14224)
		(layer "In11.Cu")
		(net "M_E_C<2>")
	)
	(arc
		(start 265.369294 -97.98812)
		(mid 265.577404 -98.19641)
		(end 265.8618 -98.2726)
		(width 0.0889)
		(layer "In11.Cu")
		(net "M_E_C<2>")
	)
	(arc
		(start 265.312906 -97.490534)
		(mid 265.259407 -97.690432)
		(end 265.312906 -97.89033)
		(width 0.0889)
		(layer "In11.Cu")
		(net "M_E_C<2>")
	)
	(arc
		(start 265.8618 -98.2726)
		(mid 266.041405 -98.346995)
		(end 266.1158 -98.5266)
		(width 0.0889)
		(layer "In11.Cu")
		(net "M_E_C<2>")
	)
	(segment
		(start 247.39981 -147.27174)
		(end 247.39981 -145.988278)
		(width 0.1651)
		(layer "F.Cu")
		(net "M_E_BG<1>")
	)
	(segment
		(start 247.400318 -147.27174)
		(end 247.39981 -147.27174)
		(width 0.1651)
		(layer "F.Cu")
		(net "M_E_BG<1>")
	)
	(segment
		(start 254.212344 -94.718886)
		(end 253.640844 -94.718886)
		(width 0.1016)
		(layer "F.Cu")
		(net "M_E_BG<1>")
	)
	(via
		(at 253.640844 -94.718886)
		(size 0.508)
		(drill 0.254)
		(layers "F.Cu" "B.Cu")
		(net "M_E_BG<1>")
	)
	(via
		(at 247.39981 -139.170156)
		(size 0.4572)
		(drill 0.2032)
		(layers "F.Cu" "B.Cu")
		(net "M_E_BG<1>")
	)
	(via
		(at 247.39981 -145.988278)
		(size 0.4572)
		(drill 0.2032)
		(layers "F.Cu" "B.Cu")
		(net "M_E_BG<1>")
	)
	(segment
		(start 247.39981 -137.877296)
		(end 247.39981 -139.170156)
		(width 0.1651)
		(layer "B.Cu")
		(net "M_E_BG<1>")
	)
	(segment
		(start 247.400318 -137.877296)
		(end 247.39981 -137.877296)
		(width 0.1651)
		(layer "B.Cu")
		(net "M_E_BG<1>")
	)
	(segment
		(start 251.238766 -134.587234)
		(end 250.634246 -135.191754)
		(width 0.14224)
		(layer "In11.Cu")
		(net "M_E_BG<1>")
	)
	(segment
		(start 251.1806 -129.921)
		(end 251.1806 -130.5306)
		(width 0.14224)
		(layer "In11.Cu")
		(net "M_E_BG<1>")
	)
	(segment
		(start 251.2822 -129.8194)
		(end 251.1806 -129.921)
		(width 0.14224)
		(layer "In11.Cu")
		(net "M_E_BG<1>")
	)
	(segment
		(start 251.1806 -130.5306)
		(end 251.333 -130.683)
		(width 0.14224)
		(layer "In11.Cu")
		(net "M_E_BG<1>")
	)
	(segment
		(start 254.057404 -98.95332)
		(end 254.057404 -100.274374)
		(width 0.0889)
		(layer "In11.Cu")
		(net "M_E_BG<1>")
	)
	(segment
		(start 251.1044 -131.7498)
		(end 251.238766 -131.884166)
		(width 0.14224)
		(layer "In11.Cu")
		(net "M_E_BG<1>")
	)
	(segment
		(start 251.968 -128.3462)
		(end 251.2822 -129.032)
		(width 0.14224)
		(layer "In11.Cu")
		(net "M_E_BG<1>")
	)
	(segment
		(start 251.333 -131.1656)
		(end 251.1044 -131.3942)
		(width 0.14224)
		(layer "In11.Cu")
		(net "M_E_BG<1>")
	)
	(segment
		(start 247.39981 -144.69999)
		(end 247.39981 -145.988278)
		(width 0.14224)
		(layer "In11.Cu")
		(net "M_E_BG<1>")
	)
	(segment
		(start 254.803148 -123.377452)
		(end 251.968 -126.2126)
		(width 0.14224)
		(layer "In11.Cu")
		(net "M_E_BG<1>")
	)
	(segment
		(start 250.373134 -135.996934)
		(end 250.373134 -136.589262)
		(width 0.14224)
		(layer "In11.Cu")
		(net "M_E_BG<1>")
	)
	(segment
		(start 251.1044 -131.3942)
		(end 251.1044 -131.7498)
		(width 0.14224)
		(layer "In11.Cu")
		(net "M_E_BG<1>")
	)
	(segment
		(start 251.968 -126.2126)
		(end 251.968 -128.3462)
		(width 0.14224)
		(layer "In11.Cu")
		(net "M_E_BG<1>")
	)
	(segment
		(start 247.39981 -139.170156)
		(end 247.39981 -140.341096)
		(width 0.14224)
		(layer "In11.Cu")
		(net "M_E_BG<1>")
	)
	(segment
		(start 251.238766 -131.884166)
		(end 251.238766 -134.587234)
		(width 0.14224)
		(layer "In11.Cu")
		(net "M_E_BG<1>")
	)
	(segment
		(start 251.333 -130.683)
		(end 251.333 -131.1656)
		(width 0.14224)
		(layer "In11.Cu")
		(net "M_E_BG<1>")
	)
	(segment
		(start 254.803148 -103.586534)
		(end 254.803148 -123.377452)
		(width 0.14224)
		(layer "In11.Cu")
		(net "M_E_BG<1>")
	)
	(segment
		(start 254.641604 -100.858574)
		(end 254.641604 -103.023924)
		(width 0.0889)
		(layer "In11.Cu")
		(net "M_E_BG<1>")
	)
	(segment
		(start 253.97841 -97.475548)
		(end 253.9873 -97.490788)
		(width 0.0889)
		(layer "In11.Cu")
		(net "M_E_BG<1>")
	)
	(segment
		(start 247.813068 -141.635988)
		(end 248.019062 -141.841982)
		(width 0.14224)
		(layer "In11.Cu")
		(net "M_E_BG<1>")
	)
	(segment
		(start 250.634246 -135.735822)
		(end 250.373134 -135.996934)
		(width 0.14224)
		(layer "In11.Cu")
		(net "M_E_BG<1>")
	)
	(segment
		(start 253.97841 -96.484948)
		(end 253.9873 -96.500188)
		(width 0.0889)
		(layer "In11.Cu")
		(net "M_E_BG<1>")
	)
	(segment
		(start 250.634246 -135.191754)
		(end 250.634246 -135.735822)
		(width 0.14224)
		(layer "In11.Cu")
		(net "M_E_BG<1>")
	)
	(segment
		(start 250.373134 -136.589262)
		(end 249.980196 -136.9822)
		(width 0.14224)
		(layer "In11.Cu")
		(net "M_E_BG<1>")
	)
	(segment
		(start 247.39981 -140.341096)
		(end 247.813068 -140.754354)
		(width 0.14224)
		(layer "In11.Cu")
		(net "M_E_BG<1>")
	)
	(segment
		(start 254.641604 -103.023924)
		(end 254.803148 -103.185468)
		(width 0.0889)
		(layer "In11.Cu")
		(net "M_E_BG<1>")
	)
	(segment
		(start 251.2822 -129.032)
		(end 251.2822 -129.8194)
		(width 0.14224)
		(layer "In11.Cu")
		(net "M_E_BG<1>")
	)
	(segment
		(start 248.019062 -141.841982)
		(end 248.019062 -143.137128)
		(width 0.14224)
		(layer "In11.Cu")
		(net "M_E_BG<1>")
	)
	(segment
		(start 254.803148 -103.185468)
		(end 254.803148 -103.586534)
		(width 0.0889)
		(layer "In11.Cu")
		(net "M_E_BG<1>")
	)
	(segment
		(start 248.019062 -143.137128)
		(end 247.813068 -143.343122)
		(width 0.14224)
		(layer "In11.Cu")
		(net "M_E_BG<1>")
	)
	(segment
		(start 254.057404 -100.274374)
		(end 254.641604 -100.858574)
		(width 0.0889)
		(layer "In11.Cu")
		(net "M_E_BG<1>")
	)
	(segment
		(start 249.587766 -136.9822)
		(end 247.39981 -139.170156)
		(width 0.14224)
		(layer "In11.Cu")
		(net "M_E_BG<1>")
	)
	(segment
		(start 247.813068 -140.754354)
		(end 247.813068 -141.635988)
		(width 0.14224)
		(layer "In11.Cu")
		(net "M_E_BG<1>")
	)
	(segment
		(start 249.980196 -136.9822)
		(end 249.587766 -136.9822)
		(width 0.14224)
		(layer "In11.Cu")
		(net "M_E_BG<1>")
	)
	(segment
		(start 253.640844 -94.718886)
		(end 253.665482 -94.743524)
		(width 0.0889)
		(layer "In11.Cu")
		(net "M_E_BG<1>")
	)
	(segment
		(start 247.813068 -143.343122)
		(end 247.813068 -144.286732)
		(width 0.14224)
		(layer "In11.Cu")
		(net "M_E_BG<1>")
	)
	(segment
		(start 247.813068 -144.286732)
		(end 247.39981 -144.69999)
		(width 0.14224)
		(layer "In11.Cu")
		(net "M_E_BG<1>")
	)
	(segment
		(start 253.97841 -95.494348)
		(end 253.9873 -95.509588)
		(width 0.0889)
		(layer "In11.Cu")
		(net "M_E_BG<1>")
	)
	(segment
		(start 253.97841 -98.466148)
		(end 253.9873 -98.481388)
		(width 0.0889)
		(layer "In11.Cu")
		(net "M_E_BG<1>")
	)
	(arc
		(start 253.9873 -96.500188)
		(mid 254.040833 -96.700086)
		(end 253.9873 -96.899984)
		(width 0.0889)
		(layer "In11.Cu")
		(net "M_E_BG<1>")
	)
	(arc
		(start 253.9873 -98.481388)
		(mid 254.067811 -98.710603)
		(end 254.057404 -98.95332)
		(width 0.0889)
		(layer "In11.Cu")
		(net "M_E_BG<1>")
	)
	(arc
		(start 253.9873 -97.490788)
		(mid 254.040833 -97.690686)
		(end 253.9873 -97.890584)
		(width 0.0889)
		(layer "In11.Cu")
		(net "M_E_BG<1>")
	)
	(arc
		(start 253.665482 -94.743524)
		(mid 253.868481 -95.047334)
		(end 253.939802 -95.405702)
		(width 0.0889)
		(layer "In11.Cu")
		(net "M_E_BG<1>")
	)
	(arc
		(start 253.9873 -95.509588)
		(mid 254.040833 -95.709486)
		(end 253.9873 -95.909384)
		(width 0.0889)
		(layer "In11.Cu")
		(net "M_E_BG<1>")
	)
	(arc
		(start 253.9873 -96.899984)
		(mid 253.908111 -97.186599)
		(end 253.97841 -97.475548)
		(width 0.0889)
		(layer "In11.Cu")
		(net "M_E_BG<1>")
	)
	(arc
		(start 253.9873 -95.909384)
		(mid 253.908111 -96.195999)
		(end 253.97841 -96.484948)
		(width 0.0889)
		(layer "In11.Cu")
		(net "M_E_BG<1>")
	)
	(arc
		(start 253.9873 -97.890584)
		(mid 253.908111 -98.177199)
		(end 253.97841 -98.466148)
		(width 0.0889)
		(layer "In11.Cu")
		(net "M_E_BG<1>")
	)
	(arc
		(start 253.939802 -95.405702)
		(mid 253.9573 -95.450811)
		(end 253.97841 -95.494348)
		(width 0.0889)
		(layer "In11.Cu")
		(net "M_E_BG<1>")
	)
	(segment
		(start 253.353824 -93.23324)
		(end 252.782324 -93.23324)
		(width 0.1016)
		(layer "F.Cu")
		(net "M_E_BG<0>")
	)
	(segment
		(start 247.39981 -142.677642)
		(end 247.39981 -143.970756)
		(width 0.1651)
		(layer "F.Cu")
		(net "M_E_BG<0>")
	)
	(segment
		(start 247.400318 -142.6718)
		(end 247.39981 -142.677642)
		(width 0.1651)
		(layer "F.Cu")
		(net "M_E_BG<0>")
	)
	(via
		(at 252.782324 -93.23324)
		(size 0.508)
		(drill 0.254)
		(layers "F.Cu" "B.Cu")
		(net "M_E_BG<0>")
	)
	(via
		(at 247.39981 -143.970756)
		(size 0.4572)
		(drill 0.2032)
		(layers "F.Cu" "B.Cu")
		(net "M_E_BG<0>")
	)
	(via
		(at 247.39981 -141.187678)
		(size 0.4572)
		(drill 0.2032)
		(layers "F.Cu" "B.Cu")
		(net "M_E_BG<0>")
	)
	(segment
		(start 247.400318 -142.477236)
		(end 247.39981 -142.476982)
		(width 0.1651)
		(layer "B.Cu")
		(net "M_E_BG<0>")
	)
	(segment
		(start 247.39981 -142.476982)
		(end 247.39981 -141.187678)
		(width 0.1651)
		(layer "B.Cu")
		(net "M_E_BG<0>")
	)
	(segment
		(start 249.301 -126.864872)
		(end 249.301 -128.721104)
		(width 0.14224)
		(layer "In4.Cu")
		(net "M_E_BG<0>")
	)
	(segment
		(start 253.18212 -94.222062)
		(end 253.18212 -97.178368)
		(width 0.0889)
		(layer "In4.Cu")
		(net "M_E_BG<0>")
	)
	(segment
		(start 247.6754 -140.72362)
		(end 247.39981 -140.99921)
		(width 0.14224)
		(layer "In4.Cu")
		(net "M_E_BG<0>")
	)
	(segment
		(start 247.39981 -141.187678)
		(end 247.39981 -143.970756)
		(width 0.14224)
		(layer "In4.Cu")
		(net "M_E_BG<0>")
	)
	(segment
		(start 248.7676 -131.8006)
		(end 248.689876 -131.878324)
		(width 0.14224)
		(layer "In4.Cu")
		(net "M_E_BG<0>")
	)
	(segment
		(start 253.0094 -99.9998)
		(end 253.593092 -100.583492)
		(width 0.0889)
		(layer "In4.Cu")
		(net "M_E_BG<0>")
	)
	(segment
		(start 247.39981 -140.99921)
		(end 247.39981 -141.187678)
		(width 0.14224)
		(layer "In4.Cu")
		(net "M_E_BG<0>")
	)
	(segment
		(start 248.5898 -131.1656)
		(end 248.7676 -131.3434)
		(width 0.14224)
		(layer "In4.Cu")
		(net "M_E_BG<0>")
	)
	(segment
		(start 248.7422 -130.5814)
		(end 248.5898 -130.7338)
		(width 0.14224)
		(layer "In4.Cu")
		(net "M_E_BG<0>")
	)
	(segment
		(start 253.13386 -98.377502)
		(end 253.129034 -98.386138)
		(width 0.0889)
		(layer "In4.Cu")
		(net "M_E_BG<0>")
	)
	(segment
		(start 248.689876 -134.718552)
		(end 248.663714 -134.744714)
		(width 0.14224)
		(layer "In4.Cu")
		(net "M_E_BG<0>")
	)
	(segment
		(start 248.5898 -129.432304)
		(end 248.5898 -129.7686)
		(width 0.14224)
		(layer "In4.Cu")
		(net "M_E_BG<0>")
	)
	(segment
		(start 247.6754 -139.573)
		(end 247.6754 -140.72362)
		(width 0.14224)
		(layer "In4.Cu")
		(net "M_E_BG<0>")
	)
	(segment
		(start 253.129034 -97.395538)
		(end 253.122684 -97.406206)
		(width 0.0889)
		(layer "In4.Cu")
		(net "M_E_BG<0>")
	)
	(segment
		(start 248.663714 -134.744714)
		(end 248.663714 -138.051286)
		(width 0.14224)
		(layer "In4.Cu")
		(net "M_E_BG<0>")
	)
	(segment
		(start 253.593092 -122.57278)
		(end 249.301 -126.864872)
		(width 0.14224)
		(layer "In4.Cu")
		(net "M_E_BG<0>")
	)
	(segment
		(start 248.5898 -130.7338)
		(end 248.5898 -131.1656)
		(width 0.14224)
		(layer "In4.Cu")
		(net "M_E_BG<0>")
	)
	(segment
		(start 249.301 -128.721104)
		(end 248.5898 -129.432304)
		(width 0.14224)
		(layer "In4.Cu")
		(net "M_E_BG<0>")
	)
	(segment
		(start 248.7422 -129.921)
		(end 248.7422 -130.5814)
		(width 0.14224)
		(layer "In4.Cu")
		(net "M_E_BG<0>")
	)
	(segment
		(start 248.5898 -129.7686)
		(end 248.7422 -129.921)
		(width 0.14224)
		(layer "In4.Cu")
		(net "M_E_BG<0>")
	)
	(segment
		(start 248.689876 -131.878324)
		(end 248.689876 -134.718552)
		(width 0.14224)
		(layer "In4.Cu")
		(net "M_E_BG<0>")
	)
	(segment
		(start 247.8278 -138.8872)
		(end 247.8278 -139.4206)
		(width 0.14224)
		(layer "In4.Cu")
		(net "M_E_BG<0>")
	)
	(segment
		(start 248.663714 -138.051286)
		(end 247.8278 -138.8872)
		(width 0.14224)
		(layer "In4.Cu")
		(net "M_E_BG<0>")
	)
	(segment
		(start 247.8278 -139.4206)
		(end 247.6754 -139.573)
		(width 0.14224)
		(layer "In4.Cu")
		(net "M_E_BG<0>")
	)
	(segment
		(start 248.7676 -131.3434)
		(end 248.7676 -131.8006)
		(width 0.14224)
		(layer "In4.Cu")
		(net "M_E_BG<0>")
	)
	(segment
		(start 253.593092 -100.93071)
		(end 253.593092 -122.57278)
		(width 0.14224)
		(layer "In4.Cu")
		(net "M_E_BG<0>")
	)
	(segment
		(start 253.112016 -93.994478)
		(end 253.129034 -94.023688)
		(width 0.0889)
		(layer "In4.Cu")
		(net "M_E_BG<0>")
	)
	(segment
		(start 253.129034 -99.376738)
		(end 253.0094 -99.584256)
		(width 0.0889)
		(layer "In4.Cu")
		(net "M_E_BG<0>")
	)
	(segment
		(start 253.0094 -99.584256)
		(end 253.0094 -99.9998)
		(width 0.0889)
		(layer "In4.Cu")
		(net "M_E_BG<0>")
	)
	(segment
		(start 253.593092 -100.583492)
		(end 253.593092 -100.93071)
		(width 0.0889)
		(layer "In4.Cu")
		(net "M_E_BG<0>")
	)
	(segment
		(start 252.782324 -93.23324)
		(end 253.112016 -93.994478)
		(width 0.0889)
		(layer "In4.Cu")
		(net "M_E_BG<0>")
	)
	(segment
		(start 253.13386 -97.386902)
		(end 253.129034 -97.395538)
		(width 0.0889)
		(layer "In4.Cu")
		(net "M_E_BG<0>")
	)
	(arc
		(start 253.129034 -98.386138)
		(mid 253.049903 -98.68154)
		(end 253.129034 -98.976942)
		(width 0.0889)
		(layer "In4.Cu")
		(net "M_E_BG<0>")
	)
	(arc
		(start 253.129034 -98.976942)
		(mid 253.182533 -99.17684)
		(end 253.129034 -99.376738)
		(width 0.0889)
		(layer "In4.Cu")
		(net "M_E_BG<0>")
	)
	(arc
		(start 253.122684 -97.406206)
		(mid 253.049886 -97.696969)
		(end 253.129034 -97.986088)
		(width 0.0889)
		(layer "In4.Cu")
		(net "M_E_BG<0>")
	)
	(arc
		(start 253.129034 -97.986088)
		(mid 253.182504 -98.181151)
		(end 253.13386 -98.377502)
		(width 0.0889)
		(layer "In4.Cu")
		(net "M_E_BG<0>")
	)
	(arc
		(start 253.129034 -94.023688)
		(mid 253.168637 -94.119382)
		(end 253.18212 -94.222062)
		(width 0.0889)
		(layer "In4.Cu")
		(net "M_E_BG<0>")
	)
	(arc
		(start 253.18212 -97.178368)
		(mid 253.172177 -97.285916)
		(end 253.13386 -97.386902)
		(width 0.0889)
		(layer "In4.Cu")
		(net "M_E_BG<0>")
	)
	(segment
		(start 266.949936 -147.27174)
		(end 266.950444 -147.27174)
		(width 0.1651)
		(layer "F.Cu")
		(net "M_E_BA<1>")
	)
	(segment
		(start 266.949936 -145.988532)
		(end 266.949936 -147.27174)
		(width 0.1651)
		(layer "F.Cu")
		(net "M_E_BA<1>")
	)
	(segment
		(start 266.95019 -145.988278)
		(end 266.949936 -145.988532)
		(width 0.1651)
		(layer "F.Cu")
		(net "M_E_BA<1>")
	)
	(segment
		(start 259.36321 -97.690686)
		(end 258.79171 -97.690686)
		(width 0.1016)
		(layer "F.Cu")
		(net "M_E_BA<1>")
	)
	(via
		(at 266.95019 -145.988278)
		(size 0.4572)
		(drill 0.2032)
		(layers "F.Cu" "B.Cu")
		(net "M_E_BA<1>")
	)
	(via
		(at 258.79171 -97.690686)
		(size 0.508)
		(drill 0.254)
		(layers "F.Cu" "B.Cu")
		(net "M_E_BA<1>")
	)
	(via
		(at 266.949936 -139.172188)
		(size 0.4572)
		(drill 0.2032)
		(layers "F.Cu" "B.Cu")
		(net "M_E_BA<1>")
	)
	(segment
		(start 266.949936 -137.877296)
		(end 266.949936 -139.172188)
		(width 0.1651)
		(layer "B.Cu")
		(net "M_E_BA<1>")
	)
	(segment
		(start 266.950444 -137.877296)
		(end 266.949936 -137.877296)
		(width 0.1651)
		(layer "B.Cu")
		(net "M_E_BA<1>")
	)
	(segment
		(start 258.79171 -97.690686)
		(end 259.121148 -98.45167)
		(width 0.0889)
		(layer "In11.Cu")
		(net "M_E_BA<1>")
	)
	(segment
		(start 259.207 -99.822)
		(end 261.493 -102.108)
		(width 0.0889)
		(layer "In11.Cu")
		(net "M_E_BA<1>")
	)
	(segment
		(start 266.513056 -140.297916)
		(end 266.513056 -142.556484)
		(width 0.14224)
		(layer "In11.Cu")
		(net "M_E_BA<1>")
	)
	(segment
		(start 264.420858 -138.327638)
		(end 264.705338 -138.612118)
		(width 0.14224)
		(layer "In11.Cu")
		(net "M_E_BA<1>")
	)
	(segment
		(start 264.420858 -137.904728)
		(end 264.420858 -138.327638)
		(width 0.14224)
		(layer "In11.Cu")
		(net "M_E_BA<1>")
	)
	(segment
		(start 261.9502 -126.746)
		(end 261.9502 -135.9408)
		(width 0.14224)
		(layer "In11.Cu")
		(net "M_E_BA<1>")
	)
	(segment
		(start 261.000748 -104.353614)
		(end 261.000748 -125.796548)
		(width 0.14224)
		(layer "In11.Cu")
		(net "M_E_BA<1>")
	)
	(segment
		(start 259.121148 -98.45167)
		(end 259.143246 -98.490024)
		(width 0.0889)
		(layer "In11.Cu")
		(net "M_E_BA<1>")
	)
	(segment
		(start 261.493 -102.784148)
		(end 261.000748 -103.2764)
		(width 0.0889)
		(layer "In11.Cu")
		(net "M_E_BA<1>")
	)
	(segment
		(start 261.9502 -135.9408)
		(end 263.613138 -137.603738)
		(width 0.14224)
		(layer "In11.Cu")
		(net "M_E_BA<1>")
	)
	(segment
		(start 266.389866 -138.612118)
		(end 266.949936 -139.172188)
		(width 0.14224)
		(layer "In11.Cu")
		(net "M_E_BA<1>")
	)
	(segment
		(start 266.535662 -142.57909)
		(end 266.535662 -144.431512)
		(width 0.14224)
		(layer "In11.Cu")
		(net "M_E_BA<1>")
	)
	(segment
		(start 261.000748 -125.796548)
		(end 261.9502 -126.746)
		(width 0.14224)
		(layer "In11.Cu")
		(net "M_E_BA<1>")
	)
	(segment
		(start 263.613138 -137.603738)
		(end 264.119868 -137.603738)
		(width 0.14224)
		(layer "In11.Cu")
		(net "M_E_BA<1>")
	)
	(segment
		(start 266.949936 -139.861036)
		(end 266.513056 -140.297916)
		(width 0.14224)
		(layer "In11.Cu")
		(net "M_E_BA<1>")
	)
	(segment
		(start 261.000748 -103.2764)
		(end 261.000748 -104.353614)
		(width 0.0889)
		(layer "In11.Cu")
		(net "M_E_BA<1>")
	)
	(segment
		(start 259.207 -99.7458)
		(end 259.207 -99.822)
		(width 0.0889)
		(layer "In11.Cu")
		(net "M_E_BA<1>")
	)
	(segment
		(start 266.95019 -144.84604)
		(end 266.95019 -145.988278)
		(width 0.14224)
		(layer "In11.Cu")
		(net "M_E_BA<1>")
	)
	(segment
		(start 264.119868 -137.603738)
		(end 264.420858 -137.904728)
		(width 0.14224)
		(layer "In11.Cu")
		(net "M_E_BA<1>")
	)
	(segment
		(start 266.513056 -142.556484)
		(end 266.535662 -142.57909)
		(width 0.14224)
		(layer "In11.Cu")
		(net "M_E_BA<1>")
	)
	(segment
		(start 266.949936 -139.172188)
		(end 266.949936 -139.861036)
		(width 0.14224)
		(layer "In11.Cu")
		(net "M_E_BA<1>")
	)
	(segment
		(start 266.535662 -144.431512)
		(end 266.95019 -144.84604)
		(width 0.14224)
		(layer "In11.Cu")
		(net "M_E_BA<1>")
	)
	(segment
		(start 264.705338 -138.612118)
		(end 266.389866 -138.612118)
		(width 0.14224)
		(layer "In11.Cu")
		(net "M_E_BA<1>")
	)
	(segment
		(start 261.493 -102.108)
		(end 261.493 -102.784148)
		(width 0.0889)
		(layer "In11.Cu")
		(net "M_E_BA<1>")
	)
	(arc
		(start 259.143246 -98.490024)
		(mid 259.192001 -98.686376)
		(end 259.13842 -98.881438)
		(width 0.0889)
		(layer "In11.Cu")
		(net "M_E_BA<1>")
	)
	(arc
		(start 259.13842 -99.472242)
		(mid 259.191847 -99.604225)
		(end 259.207 -99.7458)
		(width 0.0889)
		(layer "In11.Cu")
		(net "M_E_BA<1>")
	)
	(arc
		(start 259.13842 -98.881438)
		(mid 259.059289 -99.17684)
		(end 259.13842 -99.472242)
		(width 0.0889)
		(layer "In11.Cu")
		(net "M_E_BA<1>")
	)
	(segment
		(start 267.800328 -142.6718)
		(end 267.79982 -142.677642)
		(width 0.1651)
		(layer "F.Cu")
		(net "M_E_BA<0>")
	)
	(segment
		(start 267.79982 -142.677642)
		(end 267.79982 -143.972534)
		(width 0.1651)
		(layer "F.Cu")
		(net "M_E_BA<0>")
	)
	(segment
		(start 267.79982 -143.972534)
		(end 267.800074 -143.972788)
		(width 0.1651)
		(layer "F.Cu")
		(net "M_E_BA<0>")
	)
	(segment
		(start 260.50875 -94.718886)
		(end 261.08025 -94.718886)
		(width 0.1016)
		(layer "F.Cu")
		(net "M_E_BA<0>")
	)
	(via
		(at 267.800074 -143.972788)
		(size 0.4572)
		(drill 0.2032)
		(layers "F.Cu" "B.Cu")
		(net "M_E_BA<0>")
	)
	(via
		(at 260.50875 -94.718886)
		(size 0.508)
		(drill 0.254)
		(layers "F.Cu" "B.Cu")
		(net "M_E_BA<0>")
	)
	(via
		(at 267.800074 -141.187678)
		(size 0.4572)
		(drill 0.2032)
		(layers "F.Cu" "B.Cu")
		(net "M_E_BA<0>")
	)
	(segment
		(start 267.79982 -142.476982)
		(end 267.79982 -141.187932)
		(width 0.1651)
		(layer "B.Cu")
		(net "M_E_BA<0>")
	)
	(segment
		(start 267.800328 -142.477236)
		(end 267.79982 -142.476982)
		(width 0.1651)
		(layer "B.Cu")
		(net "M_E_BA<0>")
	)
	(segment
		(start 267.79982 -141.187932)
		(end 267.800074 -141.187678)
		(width 0.1651)
		(layer "B.Cu")
		(net "M_E_BA<0>")
	)
	(segment
		(start 265.995912 -127.024892)
		(end 265.995912 -128.789176)
		(width 0.14224)
		(layer "In4.Cu")
		(net "M_E_BA<0>")
	)
	(segment
		(start 263.0932 -124.12218)
		(end 265.995912 -127.024892)
		(width 0.14224)
		(layer "In4.Cu")
		(net "M_E_BA<0>")
	)
	(segment
		(start 267.378942 -140.407898)
		(end 267.800074 -140.82903)
		(width 0.14224)
		(layer "In4.Cu")
		(net "M_E_BA<0>")
	)
	(segment
		(start 265.995912 -128.789176)
		(end 266.5984 -129.391664)
		(width 0.14224)
		(layer "In4.Cu")
		(net "M_E_BA<0>")
	)
	(segment
		(start 262.9916 -103.020368)
		(end 263.0932 -103.121968)
		(width 0.0889)
		(layer "In4.Cu")
		(net "M_E_BA<0>")
	)
	(segment
		(start 261.718806 -97.386902)
		(end 261.71398 -97.395538)
		(width 0.0889)
		(layer "In4.Cu")
		(net "M_E_BA<0>")
	)
	(segment
		(start 266.7254 -131.0386)
		(end 266.4714 -131.2926)
		(width 0.14224)
		(layer "In4.Cu")
		(net "M_E_BA<0>")
	)
	(segment
		(start 267.378942 -138.68273)
		(end 267.378942 -140.407898)
		(width 0.14224)
		(layer "In4.Cu")
		(net "M_E_BA<0>")
	)
	(segment
		(start 266.5984 -129.8448)
		(end 266.4714 -129.9718)
		(width 0.14224)
		(layer "In4.Cu")
		(net "M_E_BA<0>")
	)
	(segment
		(start 260.50875 -94.718886)
		(end 260.838188 -95.47987)
		(width 0.0889)
		(layer "In4.Cu")
		(net "M_E_BA<0>")
	)
	(segment
		(start 266.4714 -131.9022)
		(end 266.535408 -131.966208)
		(width 0.14224)
		(layer "In4.Cu")
		(net "M_E_BA<0>")
	)
	(segment
		(start 267.800074 -140.82903)
		(end 267.800074 -141.187678)
		(width 0.14224)
		(layer "In4.Cu")
		(net "M_E_BA<0>")
	)
	(segment
		(start 266.535408 -131.966208)
		(end 266.535408 -137.839196)
		(width 0.14224)
		(layer "In4.Cu")
		(net "M_E_BA<0>")
	)
	(segment
		(start 261.71398 -97.395538)
		(end 261.70763 -97.406206)
		(width 0.0889)
		(layer "In4.Cu")
		(net "M_E_BA<0>")
	)
	(segment
		(start 261.34949 -95.80499)
		(end 261.382256 -95.80499)
		(width 0.0889)
		(layer "In4.Cu")
		(net "M_E_BA<0>")
	)
	(segment
		(start 266.5984 -129.391664)
		(end 266.5984 -129.8448)
		(width 0.14224)
		(layer "In4.Cu")
		(net "M_E_BA<0>")
	)
	(segment
		(start 261.71398 -98.386138)
		(end 261.70763 -98.396806)
		(width 0.0889)
		(layer "In4.Cu")
		(net "M_E_BA<0>")
	)
	(segment
		(start 266.7254 -130.7338)
		(end 266.7254 -131.0386)
		(width 0.14224)
		(layer "In4.Cu")
		(net "M_E_BA<0>")
	)
	(segment
		(start 266.4714 -131.2926)
		(end 266.4714 -131.9022)
		(width 0.14224)
		(layer "In4.Cu")
		(net "M_E_BA<0>")
	)
	(segment
		(start 263.0932 -103.311198)
		(end 263.0932 -124.12218)
		(width 0.14224)
		(layer "In4.Cu")
		(net "M_E_BA<0>")
	)
	(segment
		(start 267.800074 -141.187678)
		(end 267.800074 -143.972788)
		(width 0.14224)
		(layer "In4.Cu")
		(net "M_E_BA<0>")
	)
	(segment
		(start 261.7978 -101.448616)
		(end 262.9916 -102.642416)
		(width 0.0889)
		(layer "In4.Cu")
		(net "M_E_BA<0>")
	)
	(segment
		(start 261.7978 -99.314)
		(end 261.7978 -101.448616)
		(width 0.0889)
		(layer "In4.Cu")
		(net "M_E_BA<0>")
	)
	(segment
		(start 266.535408 -137.839196)
		(end 267.378942 -138.68273)
		(width 0.14224)
		(layer "In4.Cu")
		(net "M_E_BA<0>")
	)
	(segment
		(start 261.71398 -96.404938)
		(end 261.70763 -96.415606)
		(width 0.0889)
		(layer "In4.Cu")
		(net "M_E_BA<0>")
	)
	(segment
		(start 266.4714 -130.4798)
		(end 266.7254 -130.7338)
		(width 0.14224)
		(layer "In4.Cu")
		(net "M_E_BA<0>")
	)
	(segment
		(start 261.718806 -98.377502)
		(end 261.71398 -98.386138)
		(width 0.0889)
		(layer "In4.Cu")
		(net "M_E_BA<0>")
	)
	(segment
		(start 266.4714 -129.9718)
		(end 266.4714 -130.4798)
		(width 0.14224)
		(layer "In4.Cu")
		(net "M_E_BA<0>")
	)
	(segment
		(start 263.0932 -103.121968)
		(end 263.0932 -103.311198)
		(width 0.0889)
		(layer "In4.Cu")
		(net "M_E_BA<0>")
	)
	(segment
		(start 261.718806 -96.396302)
		(end 261.71398 -96.404938)
		(width 0.0889)
		(layer "In4.Cu")
		(net "M_E_BA<0>")
	)
	(segment
		(start 262.9916 -102.642416)
		(end 262.9916 -103.020368)
		(width 0.0889)
		(layer "In4.Cu")
		(net "M_E_BA<0>")
	)
	(segment
		(start 260.838188 -95.47987)
		(end 260.85546 -95.509588)
		(width 0.0889)
		(layer "In4.Cu")
		(net "M_E_BA<0>")
	)
	(arc
		(start 261.70763 -97.406206)
		(mid 261.634832 -97.696969)
		(end 261.71398 -97.986088)
		(width 0.0889)
		(layer "In4.Cu")
		(net "M_E_BA<0>")
	)
	(arc
		(start 261.70763 -96.415606)
		(mid 261.634832 -96.706369)
		(end 261.71398 -96.995488)
		(width 0.0889)
		(layer "In4.Cu")
		(net "M_E_BA<0>")
	)
	(arc
		(start 261.70763 -98.396806)
		(mid 261.634832 -98.687569)
		(end 261.71398 -98.976688)
		(width 0.0889)
		(layer "In4.Cu")
		(net "M_E_BA<0>")
	)
	(arc
		(start 261.71398 -97.986088)
		(mid 261.76745 -98.181151)
		(end 261.718806 -98.377502)
		(width 0.0889)
		(layer "In4.Cu")
		(net "M_E_BA<0>")
	)
	(arc
		(start 261.382256 -95.80499)
		(mid 261.715174 -96.006981)
		(end 261.718806 -96.396302)
		(width 0.0889)
		(layer "In4.Cu")
		(net "M_E_BA<0>")
	)
	(arc
		(start 261.71398 -96.995488)
		(mid 261.76745 -97.190551)
		(end 261.718806 -97.386902)
		(width 0.0889)
		(layer "In4.Cu")
		(net "M_E_BA<0>")
	)
	(arc
		(start 260.85546 -95.509588)
		(mid 261.064068 -95.72152)
		(end 261.34949 -95.80499)
		(width 0.0889)
		(layer "In4.Cu")
		(net "M_E_BA<0>")
	)
	(arc
		(start 261.71398 -98.976688)
		(mid 261.77966 -99.139435)
		(end 261.7978 -99.314)
		(width 0.0889)
		(layer "In4.Cu")
		(net "M_E_BA<0>")
	)
	(segment
		(start 254.212344 -96.700086)
		(end 253.640844 -96.700086)
		(width 0.1651)
		(layer "F.Cu")
		(net "M_E_ALERT_N")
	)
	(segment
		(start 248.249948 -147.27174)
		(end 248.249948 -145.988278)
		(width 0.1651)
		(layer "F.Cu")
		(net "M_E_ALERT_N")
	)
	(segment
		(start 248.250456 -147.27174)
		(end 248.249948 -147.27174)
		(width 0.1651)
		(layer "F.Cu")
		(net "M_E_ALERT_N")
	)
	(via
		(at 248.249948 -145.988278)
		(size 0.4572)
		(drill 0.2032)
		(layers "F.Cu" "B.Cu")
		(net "M_E_ALERT_N")
	)
	(via
		(at 253.640844 -96.700086)
		(size 0.508)
		(drill 0.254)
		(layers "F.Cu" "B.Cu")
		(net "M_E_ALERT_N")
	)
	(via
		(at 248.249948 -139.170156)
		(size 0.4572)
		(drill 0.2032)
		(layers "F.Cu" "B.Cu")
		(net "M_E_ALERT_N")
	)
	(segment
		(start 248.250456 -137.877296)
		(end 248.249948 -137.877296)
		(width 0.1651)
		(layer "B.Cu")
		(net "M_E_ALERT_N")
	)
	(segment
		(start 248.249948 -137.877296)
		(end 248.249948 -139.170156)
		(width 0.1651)
		(layer "B.Cu")
		(net "M_E_ALERT_N")
	)
	(segment
		(start 249.451368 -136.065768)
		(end 249.540776 -136.155176)
		(width 0.14224)
		(layer "In4.Cu")
		(net "M_E_ALERT_N")
	)
	(segment
		(start 249.5804 -131.191)
		(end 249.4534 -131.318)
		(width 0.14224)
		(layer "In4.Cu")
		(net "M_E_ALERT_N")
	)
	(segment
		(start 253.311406 -97.46107)
		(end 253.289308 -97.499424)
		(width 0.0889)
		(layer "In4.Cu")
		(net "M_E_ALERT_N")
	)
	(segment
		(start 248.249948 -139.170156)
		(end 248.249948 -140.325348)
		(width 0.14224)
		(layer "In4.Cu")
		(net "M_E_ALERT_N")
	)
	(segment
		(start 249.5296 -134.7216)
		(end 249.451368 -134.799832)
		(width 0.14224)
		(layer "In4.Cu")
		(net "M_E_ALERT_N")
	)
	(segment
		(start 254.101092 -103.38181)
		(end 254.101092 -122.668792)
		(width 0.14224)
		(layer "In4.Cu")
		(net "M_E_ALERT_N")
	)
	(segment
		(start 253.294134 -99.472242)
		(end 253.236984 -99.571302)
		(width 0.0889)
		(layer "In4.Cu")
		(net "M_E_ALERT_N")
	)
	(segment
		(start 249.809 -129.6162)
		(end 249.4788 -129.9464)
		(width 0.14224)
		(layer "In4.Cu")
		(net "M_E_ALERT_N")
	)
	(segment
		(start 254.635 -102.616)
		(end 254.101092 -103.149908)
		(width 0.0889)
		(layer "In4.Cu")
		(net "M_E_ALERT_N")
	)
	(segment
		(start 249.4788 -130.556)
		(end 249.5804 -130.6576)
		(width 0.14224)
		(layer "In4.Cu")
		(net "M_E_ALERT_N")
	)
	(segment
		(start 249.809 -126.960884)
		(end 249.809 -129.6162)
		(width 0.14224)
		(layer "In4.Cu")
		(net "M_E_ALERT_N")
	)
	(segment
		(start 253.640844 -96.700086)
		(end 253.311406 -97.46107)
		(width 0.0889)
		(layer "In4.Cu")
		(net "M_E_ALERT_N")
	)
	(segment
		(start 249.4788 -129.9464)
		(end 249.4788 -130.556)
		(width 0.14224)
		(layer "In4.Cu")
		(net "M_E_ALERT_N")
	)
	(segment
		(start 249.5804 -130.6576)
		(end 249.5804 -131.191)
		(width 0.14224)
		(layer "In4.Cu")
		(net "M_E_ALERT_N")
	)
	(segment
		(start 248.686066 -144.886934)
		(end 248.249948 -145.323052)
		(width 0.14224)
		(layer "In4.Cu")
		(net "M_E_ALERT_N")
	)
	(segment
		(start 249.451368 -134.799832)
		(end 249.451368 -136.065768)
		(width 0.14224)
		(layer "In4.Cu")
		(net "M_E_ALERT_N")
	)
	(segment
		(start 254.101092 -103.149908)
		(end 254.101092 -103.38181)
		(width 0.0889)
		(layer "In4.Cu")
		(net "M_E_ALERT_N")
	)
	(segment
		(start 249.540776 -137.879328)
		(end 248.249948 -139.170156)
		(width 0.14224)
		(layer "In4.Cu")
		(net "M_E_ALERT_N")
	)
	(segment
		(start 254.635 -101.298756)
		(end 254.635 -102.616)
		(width 0.0889)
		(layer "In4.Cu")
		(net "M_E_ALERT_N")
	)
	(segment
		(start 253.236984 -99.571302)
		(end 253.236984 -99.90074)
		(width 0.0889)
		(layer "In4.Cu")
		(net "M_E_ALERT_N")
	)
	(segment
		(start 249.4534 -131.318)
		(end 249.4534 -131.8768)
		(width 0.14224)
		(layer "In4.Cu")
		(net "M_E_ALERT_N")
	)
	(segment
		(start 254.101092 -122.668792)
		(end 249.809 -126.960884)
		(width 0.14224)
		(layer "In4.Cu")
		(net "M_E_ALERT_N")
	)
	(segment
		(start 248.686066 -140.761466)
		(end 248.686066 -144.886934)
		(width 0.14224)
		(layer "In4.Cu")
		(net "M_E_ALERT_N")
	)
	(segment
		(start 253.236984 -99.90074)
		(end 254.635 -101.298756)
		(width 0.0889)
		(layer "In4.Cu")
		(net "M_E_ALERT_N")
	)
	(segment
		(start 249.5296 -131.953)
		(end 249.5296 -134.7216)
		(width 0.14224)
		(layer "In4.Cu")
		(net "M_E_ALERT_N")
	)
	(segment
		(start 249.4534 -131.8768)
		(end 249.5296 -131.953)
		(width 0.14224)
		(layer "In4.Cu")
		(net "M_E_ALERT_N")
	)
	(segment
		(start 248.249948 -145.323052)
		(end 248.249948 -145.988278)
		(width 0.14224)
		(layer "In4.Cu")
		(net "M_E_ALERT_N")
	)
	(segment
		(start 249.540776 -136.155176)
		(end 249.540776 -137.879328)
		(width 0.14224)
		(layer "In4.Cu")
		(net "M_E_ALERT_N")
	)
	(segment
		(start 248.249948 -140.325348)
		(end 248.686066 -140.761466)
		(width 0.14224)
		(layer "In4.Cu")
		(net "M_E_ALERT_N")
	)
	(arc
		(start 253.294134 -98.881438)
		(mid 253.373265 -99.17684)
		(end 253.294134 -99.472242)
		(width 0.0889)
		(layer "In4.Cu")
		(net "M_E_ALERT_N")
	)
	(arc
		(start 253.294134 -97.890838)
		(mid 253.373265 -98.18624)
		(end 253.294134 -98.481642)
		(width 0.0889)
		(layer "In4.Cu")
		(net "M_E_ALERT_N")
	)
	(arc
		(start 253.289308 -97.499424)
		(mid 253.240553 -97.695776)
		(end 253.294134 -97.890838)
		(width 0.0889)
		(layer "In4.Cu")
		(net "M_E_ALERT_N")
	)
	(arc
		(start 253.294134 -98.481642)
		(mid 253.240635 -98.68154)
		(end 253.294134 -98.881438)
		(width 0.0889)
		(layer "In4.Cu")
		(net "M_E_ALERT_N")
	)
	(segment
		(start 246.550434 -142.6718)
		(end 246.549926 -142.677642)
		(width 0.1651)
		(layer "F.Cu")
		(net "M_E_ACT_N")
	)
	(segment
		(start 246.549926 -142.677642)
		(end 246.549926 -143.970756)
		(width 0.1651)
		(layer "F.Cu")
		(net "M_E_ACT_N")
	)
	(segment
		(start 253.353824 -96.20504)
		(end 252.782324 -96.20504)
		(width 0.1651)
		(layer "F.Cu")
		(net "M_E_ACT_N")
	)
	(via
		(at 246.549926 -143.970756)
		(size 0.4572)
		(drill 0.2032)
		(layers "F.Cu" "B.Cu")
		(net "M_E_ACT_N")
	)
	(via
		(at 246.549926 -141.187678)
		(size 0.4572)
		(drill 0.2032)
		(layers "F.Cu" "B.Cu")
		(net "M_E_ACT_N")
	)
	(via
		(at 252.782324 -96.20504)
		(size 0.508)
		(drill 0.254)
		(layers "F.Cu" "B.Cu")
		(net "M_E_ACT_N")
	)
	(segment
		(start 246.550434 -142.477236)
		(end 246.549926 -142.476982)
		(width 0.1651)
		(layer "B.Cu")
		(net "M_E_ACT_N")
	)
	(segment
		(start 246.549926 -142.476982)
		(end 246.549926 -141.187678)
		(width 0.1651)
		(layer "B.Cu")
		(net "M_E_ACT_N")
	)
	(segment
		(start 250.082558 -124.485146)
		(end 249.832622 -124.735082)
		(width 0.14224)
		(layer "In4.Cu")
		(net "M_E_ACT_N")
	)
	(segment
		(start 249.855482 -125.69571)
		(end 249.636534 -125.69571)
		(width 0.14224)
		(layer "In4.Cu")
		(net "M_E_ACT_N")
	)
	(segment
		(start 250.574302 -124.757942)
		(end 250.301506 -124.485146)
		(width 0.14224)
		(layer "In4.Cu")
		(net "M_E_ACT_N")
	)
	(segment
		(start 249.16765 -126.383542)
		(end 248.7422 -126.808992)
		(width 0.14224)
		(layer "In4.Cu")
		(net "M_E_ACT_N")
	)
	(segment
		(start 252.43536 -99.377246)
		(end 252.621796 -99.70008)
		(width 0.0889)
		(layer "In4.Cu")
		(net "M_E_ACT_N")
	)
	(segment
		(start 253.085092 -100.867972)
		(end 253.085092 -122.4661)
		(width 0.14224)
		(layer "In4.Cu")
		(net "M_E_ACT_N")
	)
	(segment
		(start 246.988076 -138.863324)
		(end 246.988076 -139.520676)
		(width 0.14224)
		(layer "In4.Cu")
		(net "M_E_ACT_N")
	)
	(segment
		(start 252.621796 -99.70008)
		(end 252.622304 -99.700588)
		(width 0.0889)
		(layer "In4.Cu")
		(net "M_E_ACT_N")
	)
	(segment
		(start 250.301506 -124.485146)
		(end 250.082558 -124.485146)
		(width 0.14224)
		(layer "In4.Cu")
		(net "M_E_ACT_N")
	)
	(segment
		(start 247.777 -132.306568)
		(end 247.816878 -132.346446)
		(width 0.14224)
		(layer "In4.Cu")
		(net "M_E_ACT_N")
	)
	(segment
		(start 248.883678 -125.880622)
		(end 249.16765 -126.164594)
		(width 0.14224)
		(layer "In4.Cu")
		(net "M_E_ACT_N")
	)
	(segment
		(start 249.832622 -124.95403)
		(end 250.105418 -125.226826)
		(width 0.14224)
		(layer "In4.Cu")
		(net "M_E_ACT_N")
	)
	(segment
		(start 249.366532 -125.425708)
		(end 249.133614 -125.425708)
		(width 0.14224)
		(layer "In4.Cu")
		(net "M_E_ACT_N")
	)
	(segment
		(start 247.7516 -130.5052)
		(end 247.904 -130.6576)
		(width 0.14224)
		(layer "In4.Cu")
		(net "M_E_ACT_N")
	)
	(segment
		(start 251.043186 -124.508006)
		(end 250.79325 -124.757942)
		(width 0.14224)
		(layer "In4.Cu")
		(net "M_E_ACT_N")
	)
	(segment
		(start 252.452378 -96.966786)
		(end 252.435614 -96.995488)
		(width 0.0889)
		(layer "In4.Cu")
		(net "M_E_ACT_N")
	)
	(segment
		(start 250.105418 -125.226826)
		(end 250.105418 -125.445774)
		(width 0.14224)
		(layer "In4.Cu")
		(net "M_E_ACT_N")
	)
	(segment
		(start 250.79325 -124.757942)
		(end 250.574302 -124.757942)
		(width 0.14224)
		(layer "In4.Cu")
		(net "M_E_ACT_N")
	)
	(segment
		(start 246.549926 -141.187678)
		(end 246.549926 -143.970756)
		(width 0.14224)
		(layer "In4.Cu")
		(net "M_E_ACT_N")
	)
	(segment
		(start 251.043186 -124.289058)
		(end 251.043186 -124.508006)
		(width 0.14224)
		(layer "In4.Cu")
		(net "M_E_ACT_N")
	)
	(segment
		(start 247.904 -129.399284)
		(end 247.904 -129.7686)
		(width 0.14224)
		(layer "In4.Cu")
		(net "M_E_ACT_N")
	)
	(segment
		(start 248.883678 -125.675644)
		(end 248.883678 -125.880622)
		(width 0.14224)
		(layer "In4.Cu")
		(net "M_E_ACT_N")
	)
	(segment
		(start 247.040654 -139.573254)
		(end 247.040654 -140.69695)
		(width 0.14224)
		(layer "In4.Cu")
		(net "M_E_ACT_N")
	)
	(segment
		(start 247.7516 -129.921)
		(end 247.7516 -130.5052)
		(width 0.14224)
		(layer "In4.Cu")
		(net "M_E_ACT_N")
	)
	(segment
		(start 252.622304 -99.700588)
		(end 252.622304 -100.044504)
		(width 0.0889)
		(layer "In4.Cu")
		(net "M_E_ACT_N")
	)
	(segment
		(start 247.904 -130.6576)
		(end 247.904 -131.1656)
		(width 0.14224)
		(layer "In4.Cu")
		(net "M_E_ACT_N")
	)
	(segment
		(start 250.843034 -123.853194)
		(end 250.843034 -124.088906)
		(width 0.14224)
		(layer "In4.Cu")
		(net "M_E_ACT_N")
	)
	(segment
		(start 252.430788 -98.377502)
		(end 252.435614 -98.386138)
		(width 0.0889)
		(layer "In4.Cu")
		(net "M_E_ACT_N")
	)
	(segment
		(start 250.843034 -124.088906)
		(end 251.043186 -124.289058)
		(width 0.14224)
		(layer "In4.Cu")
		(net "M_E_ACT_N")
	)
	(segment
		(start 249.133614 -125.425708)
		(end 248.883678 -125.675644)
		(width 0.14224)
		(layer "In4.Cu")
		(net "M_E_ACT_N")
	)
	(segment
		(start 249.832622 -124.735082)
		(end 249.832622 -124.95403)
		(width 0.14224)
		(layer "In4.Cu")
		(net "M_E_ACT_N")
	)
	(segment
		(start 251.731018 -123.820174)
		(end 251.51207 -123.820174)
		(width 0.14224)
		(layer "In4.Cu")
		(net "M_E_ACT_N")
	)
	(segment
		(start 248.7422 -126.808992)
		(end 248.7422 -128.561084)
		(width 0.14224)
		(layer "In4.Cu")
		(net "M_E_ACT_N")
	)
	(segment
		(start 249.16765 -126.164594)
		(end 249.16765 -126.383542)
		(width 0.14224)
		(layer "In4.Cu")
		(net "M_E_ACT_N")
	)
	(segment
		(start 247.8278 -135.382)
		(end 247.8278 -138.0236)
		(width 0.14224)
		(layer "In4.Cu")
		(net "M_E_ACT_N")
	)
	(segment
		(start 251.09297 -123.603258)
		(end 250.843034 -123.853194)
		(width 0.14224)
		(layer "In4.Cu")
		(net "M_E_ACT_N")
	)
	(segment
		(start 252.435614 -98.386138)
		(end 252.441964 -98.396806)
		(width 0.0889)
		(layer "In4.Cu")
		(net "M_E_ACT_N")
	)
	(segment
		(start 249.636534 -125.69571)
		(end 249.366532 -125.425708)
		(width 0.14224)
		(layer "In4.Cu")
		(net "M_E_ACT_N")
	)
	(segment
		(start 247.816878 -132.346446)
		(end 247.816878 -135.371078)
		(width 0.14224)
		(layer "In4.Cu")
		(net "M_E_ACT_N")
	)
	(segment
		(start 251.295154 -123.603258)
		(end 251.09297 -123.603258)
		(width 0.14224)
		(layer "In4.Cu")
		(net "M_E_ACT_N")
	)
	(segment
		(start 247.8278 -138.0236)
		(end 246.988076 -138.863324)
		(width 0.14224)
		(layer "In4.Cu")
		(net "M_E_ACT_N")
	)
	(segment
		(start 247.777 -131.2926)
		(end 247.777 -132.306568)
		(width 0.14224)
		(layer "In4.Cu")
		(net "M_E_ACT_N")
	)
	(segment
		(start 247.904 -129.7686)
		(end 247.7516 -129.921)
		(width 0.14224)
		(layer "In4.Cu")
		(net "M_E_ACT_N")
	)
	(segment
		(start 248.7422 -128.561084)
		(end 247.904 -129.399284)
		(width 0.14224)
		(layer "In4.Cu")
		(net "M_E_ACT_N")
	)
	(segment
		(start 247.904 -131.1656)
		(end 247.777 -131.2926)
		(width 0.14224)
		(layer "In4.Cu")
		(net "M_E_ACT_N")
	)
	(segment
		(start 250.105418 -125.445774)
		(end 249.855482 -125.69571)
		(width 0.14224)
		(layer "In4.Cu")
		(net "M_E_ACT_N")
	)
	(segment
		(start 252.430788 -99.368102)
		(end 252.43536 -99.376992)
		(width 0.0889)
		(layer "In4.Cu")
		(net "M_E_ACT_N")
	)
	(segment
		(start 252.782324 -96.20504)
		(end 252.452378 -96.966786)
		(width 0.0889)
		(layer "In4.Cu")
		(net "M_E_ACT_N")
	)
	(segment
		(start 252.43536 -99.376992)
		(end 252.435614 -99.376738)
		(width 0.0889)
		(layer "In4.Cu")
		(net "M_E_ACT_N")
	)
	(segment
		(start 253.085092 -122.4661)
		(end 251.731018 -123.820174)
		(width 0.14224)
		(layer "In4.Cu")
		(net "M_E_ACT_N")
	)
	(segment
		(start 246.988076 -139.520676)
		(end 247.040654 -139.573254)
		(width 0.14224)
		(layer "In4.Cu")
		(net "M_E_ACT_N")
	)
	(segment
		(start 247.816878 -135.371078)
		(end 247.8278 -135.382)
		(width 0.14224)
		(layer "In4.Cu")
		(net "M_E_ACT_N")
	)
	(segment
		(start 253.085092 -100.507292)
		(end 253.085092 -100.867972)
		(width 0.0889)
		(layer "In4.Cu")
		(net "M_E_ACT_N")
	)
	(segment
		(start 252.435614 -97.395538)
		(end 252.441964 -97.406206)
		(width 0.0889)
		(layer "In4.Cu")
		(net "M_E_ACT_N")
	)
	(segment
		(start 247.040654 -140.69695)
		(end 246.549926 -141.187678)
		(width 0.14224)
		(layer "In4.Cu")
		(net "M_E_ACT_N")
	)
	(segment
		(start 252.622304 -100.044504)
		(end 253.085092 -100.507292)
		(width 0.0889)
		(layer "In4.Cu")
		(net "M_E_ACT_N")
	)
	(segment
		(start 251.51207 -123.820174)
		(end 251.295154 -123.603258)
		(width 0.14224)
		(layer "In4.Cu")
		(net "M_E_ACT_N")
	)
	(segment
		(start 252.430788 -97.386902)
		(end 252.435614 -97.395538)
		(width 0.0889)
		(layer "In4.Cu")
		(net "M_E_ACT_N")
	)
	(arc
		(start 252.435614 -98.976688)
		(mid 252.382144 -99.171751)
		(end 252.430788 -99.368102)
		(width 0.0889)
		(layer "In4.Cu")
		(net "M_E_ACT_N")
	)
	(arc
		(start 252.435614 -97.986088)
		(mid 252.382144 -98.181151)
		(end 252.430788 -98.377502)
		(width 0.0889)
		(layer "In4.Cu")
		(net "M_E_ACT_N")
	)
	(arc
		(start 252.441964 -98.396806)
		(mid 252.514762 -98.687569)
		(end 252.435614 -98.976688)
		(width 0.0889)
		(layer "In4.Cu")
		(net "M_E_ACT_N")
	)
	(arc
		(start 252.441964 -97.406206)
		(mid 252.514762 -97.696969)
		(end 252.435614 -97.986088)
		(width 0.0889)
		(layer "In4.Cu")
		(net "M_E_ACT_N")
	)
	(arc
		(start 252.435614 -99.376738)
		(mid 252.435487 -99.376992)
		(end 252.43536 -99.377246)
		(width 0.0889)
		(layer "In4.Cu")
		(net "M_E_ACT_N")
	)
	(arc
		(start 252.435614 -96.995488)
		(mid 252.382144 -97.190551)
		(end 252.430788 -97.386902)
		(width 0.0889)
		(layer "In4.Cu")
		(net "M_E_ACT_N")
	)
	(segment
		(start 261.480554 -101.654356)
		(end 261.480554 -102.6414)
		(width 0.0889)
		(layer "F.Cu")
		(net "M_D_PAR")
	)
	(segment
		(start 261.42696 -101.453188)
		(end 261.431786 -101.461824)
		(width 0.0889)
		(layer "F.Cu")
		(net "M_D_PAR")
	)
	(segment
		(start 265.249914 -137.67054)
		(end 265.249914 -136.435084)
		(width 0.1651)
		(layer "F.Cu")
		(net "M_D_PAR")
	)
	(segment
		(start 261.480554 -102.6414)
		(end 262.47725 -103.638096)
		(width 0.0889)
		(layer "F.Cu")
		(net "M_D_PAR")
	)
	(segment
		(start 265.250422 -137.67054)
		(end 265.249914 -137.67054)
		(width 0.1651)
		(layer "F.Cu")
		(net "M_D_PAR")
	)
	(segment
		(start 261.42061 -101.44252)
		(end 261.42696 -101.453188)
		(width 0.0889)
		(layer "F.Cu")
		(net "M_D_PAR")
	)
	(segment
		(start 263.808972 -128.49606)
		(end 265.24966 -129.936748)
		(width 0.1651)
		(layer "F.Cu")
		(net "M_D_PAR")
	)
	(segment
		(start 262.47725 -104.28859)
		(end 262.47725 -126.446534)
		(width 0.1651)
		(layer "F.Cu")
		(net "M_D_PAR")
	)
	(segment
		(start 263.808972 -127.778256)
		(end 263.808972 -128.49606)
		(width 0.1651)
		(layer "F.Cu")
		(net "M_D_PAR")
	)
	(segment
		(start 262.47725 -126.446534)
		(end 263.808972 -127.778256)
		(width 0.1651)
		(layer "F.Cu")
		(net "M_D_PAR")
	)
	(segment
		(start 262.47725 -103.638096)
		(end 262.47725 -104.28859)
		(width 0.0889)
		(layer "F.Cu")
		(net "M_D_PAR")
	)
	(segment
		(start 261.08025 -100.662486)
		(end 261.387082 -101.37013)
		(width 0.0889)
		(layer "F.Cu")
		(net "M_D_PAR")
	)
	(segment
		(start 265.249914 -136.435084)
		(end 265.227562 -136.412732)
		(width 0.1651)
		(layer "F.Cu")
		(net "M_D_PAR")
	)
	(segment
		(start 265.24966 -129.936748)
		(end 265.24966 -130.249168)
		(width 0.1651)
		(layer "F.Cu")
		(net "M_D_PAR")
	)
	(via
		(at 265.24966 -130.249168)
		(size 0.508)
		(drill 0.254)
		(layers "F.Cu" "B.Cu")
		(net "M_D_PAR")
	)
	(via
		(at 265.227562 -136.412732)
		(size 0.508)
		(drill 0.254)
		(layers "F.Cu" "B.Cu")
		(net "M_D_PAR")
	)
	(arc
		(start 261.431786 -101.461824)
		(mid 261.468307 -101.555017)
		(end 261.480554 -101.654356)
		(width 0.0889)
		(layer "F.Cu")
		(net "M_D_PAR")
	)
	(arc
		(start 261.387082 -101.37013)
		(mid 261.402624 -101.406891)
		(end 261.42061 -101.44252)
		(width 0.0889)
		(layer "F.Cu")
		(net "M_D_PAR")
	)
	(segment
		(start 265.249914 -128.276096)
		(end 265.249914 -130.248914)
		(width 0.1651)
		(layer "B.Cu")
		(net "M_D_PAR")
	)
	(segment
		(start 265.250422 -128.276096)
		(end 265.249914 -128.276096)
		(width 0.1651)
		(layer "B.Cu")
		(net "M_D_PAR")
	)
	(segment
		(start 265.249914 -130.248914)
		(end 265.24966 -130.249168)
		(width 0.1651)
		(layer "B.Cu")
		(net "M_D_PAR")
	)
	(segment
		(start 265.757914 -134.636256)
		(end 265.757914 -135.269732)
		(width 0.14224)
		(layer "In9.Cu")
		(net "M_D_PAR")
	)
	(segment
		(start 265.66241 -134.540752)
		(end 265.757914 -134.636256)
		(width 0.14224)
		(layer "In9.Cu")
		(net "M_D_PAR")
	)
	(segment
		(start 265.24966 -130.896868)
		(end 265.66241 -131.309618)
		(width 0.14224)
		(layer "In9.Cu")
		(net "M_D_PAR")
	)
	(segment
		(start 265.757914 -135.269732)
		(end 265.227308 -135.800338)
		(width 0.14224)
		(layer "In9.Cu")
		(net "M_D_PAR")
	)
	(segment
		(start 265.24966 -130.249168)
		(end 265.24966 -130.896868)
		(width 0.14224)
		(layer "In9.Cu")
		(net "M_D_PAR")
	)
	(segment
		(start 265.227308 -135.800338)
		(end 265.227308 -136.412478)
		(width 0.14224)
		(layer "In9.Cu")
		(net "M_D_PAR")
	)
	(segment
		(start 265.66241 -131.309618)
		(end 265.66241 -134.540752)
		(width 0.14224)
		(layer "In9.Cu")
		(net "M_D_PAR")
	)
	(segment
		(start 265.227308 -136.412478)
		(end 265.227562 -136.412732)
		(width 0.14224)
		(layer "In9.Cu")
		(net "M_D_PAR")
	)
	(segment
		(start 265.372596 -99.17684)
		(end 265.631676 -99.774502)
		(width 0.0889)
		(layer "F.Cu")
		(net "M_D_ODT<3>")
	)
	(segment
		(start 276.7584 -129.795524)
		(end 276.29993 -130.902456)
		(width 0.1651)
		(layer "F.Cu")
		(net "M_D_ODT<3>")
	)
	(segment
		(start 268.64437 -106.239564)
		(end 268.64437 -121.42597)
		(width 0.1651)
		(layer "F.Cu")
		(net "M_D_ODT<3>")
	)
	(segment
		(start 276.58695 -129.19075)
		(end 276.7584 -129.3622)
		(width 0.1651)
		(layer "F.Cu")
		(net "M_D_ODT<3>")
	)
	(segment
		(start 265.8237 -100.69957)
		(end 265.8237 -102.501446)
		(width 0.0889)
		(layer "F.Cu")
		(net "M_D_ODT<3>")
	)
	(segment
		(start 268.64437 -105.322116)
		(end 268.64437 -106.239564)
		(width 0.0889)
		(layer "F.Cu")
		(net "M_D_ODT<3>")
	)
	(segment
		(start 268.64437 -121.42597)
		(end 276.28342 -129.06502)
		(width 0.1651)
		(layer "F.Cu")
		(net "M_D_ODT<3>")
	)
	(segment
		(start 276.28342 -129.06502)
		(end 276.58695 -129.19075)
		(width 0.1651)
		(layer "F.Cu")
		(net "M_D_ODT<3>")
	)
	(segment
		(start 265.8237 -102.501446)
		(end 268.64437 -105.322116)
		(width 0.0889)
		(layer "F.Cu")
		(net "M_D_ODT<3>")
	)
	(segment
		(start 276.7584 -129.3622)
		(end 276.7584 -129.795524)
		(width 0.1651)
		(layer "F.Cu")
		(net "M_D_ODT<3>")
	)
	(via
		(at 276.29993 -130.902456)
		(size 0.508)
		(drill 0.254)
		(layers "F.Cu" "B.Cu")
		(net "M_D_ODT<3>")
	)
	(arc
		(start 265.631676 -99.774502)
		(mid 265.775184 -100.227178)
		(end 265.8237 -100.69957)
		(width 0.0889)
		(layer "F.Cu")
		(net "M_D_ODT<3>")
	)
	(segment
		(start 276.29993 -132.875782)
		(end 276.29993 -130.902456)
		(width 0.1651)
		(layer "B.Cu")
		(net "M_D_ODT<3>")
	)
	(segment
		(start 276.300438 -132.876036)
		(end 276.29993 -132.875782)
		(width 0.1651)
		(layer "B.Cu")
		(net "M_D_ODT<3>")
	)
	(segment
		(start 273.2024 -130.175254)
		(end 273.3548 -130.022854)
		(width 0.1651)
		(layer "F.Cu")
		(net "M_D_ODT<2>")
	)
	(segment
		(start 263.28116 -100.31476)
		(end 263.259824 -100.293424)
		(width 0.0889)
		(layer "F.Cu")
		(net "M_D_ODT<2>")
	)
	(segment
		(start 273.3548 -129.362454)
		(end 271.157954 -127.165608)
		(width 0.1651)
		(layer "F.Cu")
		(net "M_D_ODT<2>")
	)
	(segment
		(start 263.65581 -99.360736)
		(end 263.65581 -99.17684)
		(width 0.0889)
		(layer "F.Cu")
		(net "M_D_ODT<2>")
	)
	(segment
		(start 271.157954 -127.165608)
		(end 270.655542 -127.165608)
		(width 0.1651)
		(layer "F.Cu")
		(net "M_D_ODT<2>")
	)
	(segment
		(start 269.789656 -125.79731)
		(end 266.62761 -122.635264)
		(width 0.1651)
		(layer "F.Cu")
		(net "M_D_ODT<2>")
	)
	(segment
		(start 264.090404 -102.470204)
		(end 264.090404 -100.920804)
		(width 0.0889)
		(layer "F.Cu")
		(net "M_D_ODT<2>")
	)
	(segment
		(start 264.3886 -102.7684)
		(end 264.090404 -102.470204)
		(width 0.0889)
		(layer "F.Cu")
		(net "M_D_ODT<2>")
	)
	(segment
		(start 266.62761 -122.635264)
		(end 266.62761 -105.540302)
		(width 0.1651)
		(layer "F.Cu")
		(net "M_D_ODT<2>")
	)
	(segment
		(start 266.62761 -105.540302)
		(end 266.62761 -104.763316)
		(width 0.0889)
		(layer "F.Cu")
		(net "M_D_ODT<2>")
	)
	(segment
		(start 263.28116 -100.322634)
		(end 263.28116 -100.31476)
		(width 0.0889)
		(layer "F.Cu")
		(net "M_D_ODT<2>")
	)
	(segment
		(start 266.62761 -104.763316)
		(end 264.632694 -102.7684)
		(width 0.0889)
		(layer "F.Cu")
		(net "M_D_ODT<2>")
	)
	(segment
		(start 270.655542 -127.165608)
		(end 269.789656 -126.299722)
		(width 0.1651)
		(layer "F.Cu")
		(net "M_D_ODT<2>")
	)
	(segment
		(start 263.508236 -100.541836)
		(end 263.500362 -100.541836)
		(width 0.0889)
		(layer "F.Cu")
		(net "M_D_ODT<2>")
	)
	(segment
		(start 273.2024 -130.599942)
		(end 273.2024 -130.175254)
		(width 0.1651)
		(layer "F.Cu")
		(net "M_D_ODT<2>")
	)
	(segment
		(start 273.3548 -130.022854)
		(end 273.3548 -129.362454)
		(width 0.1651)
		(layer "F.Cu")
		(net "M_D_ODT<2>")
	)
	(segment
		(start 264.632694 -102.7684)
		(end 264.3886 -102.7684)
		(width 0.0889)
		(layer "F.Cu")
		(net "M_D_ODT<2>")
	)
	(segment
		(start 263.8044 -100.6348)
		(end 263.6012 -100.6348)
		(width 0.0889)
		(layer "F.Cu")
		(net "M_D_ODT<2>")
	)
	(segment
		(start 269.789656 -126.299722)
		(end 269.789656 -125.79731)
		(width 0.1651)
		(layer "F.Cu")
		(net "M_D_ODT<2>")
	)
	(segment
		(start 263.6012 -100.6348)
		(end 263.508236 -100.541836)
		(width 0.0889)
		(layer "F.Cu")
		(net "M_D_ODT<2>")
	)
	(segment
		(start 263.259824 -100.293424)
		(end 263.259824 -99.756722)
		(width 0.0889)
		(layer "F.Cu")
		(net "M_D_ODT<2>")
	)
	(segment
		(start 264.090404 -100.920804)
		(end 263.8044 -100.6348)
		(width 0.0889)
		(layer "F.Cu")
		(net "M_D_ODT<2>")
	)
	(segment
		(start 263.259824 -99.756722)
		(end 263.65581 -99.360736)
		(width 0.0889)
		(layer "F.Cu")
		(net "M_D_ODT<2>")
	)
	(segment
		(start 272.899886 -130.902456)
		(end 273.2024 -130.599942)
		(width 0.1651)
		(layer "F.Cu")
		(net "M_D_ODT<2>")
	)
	(segment
		(start 263.500362 -100.541836)
		(end 263.28116 -100.322634)
		(width 0.0889)
		(layer "F.Cu")
		(net "M_D_ODT<2>")
	)
	(via
		(at 272.899886 -130.902456)
		(size 0.508)
		(drill 0.254)
		(layers "F.Cu" "B.Cu")
		(net "M_D_ODT<2>")
	)
	(segment
		(start 272.900394 -132.876036)
		(end 272.899886 -132.875782)
		(width 0.1651)
		(layer "B.Cu")
		(net "M_D_ODT<2>")
	)
	(segment
		(start 272.899886 -132.875782)
		(end 272.899886 -130.902456)
		(width 0.1651)
		(layer "B.Cu")
		(net "M_D_ODT<2>")
	)
	(segment
		(start 276.29993 -133.0706)
		(end 276.29993 -131.57073)
		(width 0.1651)
		(layer "F.Cu")
		(net "M_D_ODT<1>")
	)
	(segment
		(start 275.971 -130.445764)
		(end 275.971 -129.921)
		(width 0.1651)
		(layer "F.Cu")
		(net "M_D_ODT<1>")
	)
	(segment
		(start 275.844 -129.3876)
		(end 268.14018 -121.68378)
		(width 0.1651)
		(layer "F.Cu")
		(net "M_D_ODT<1>")
	)
	(segment
		(start 276.29993 -131.57073)
		(end 275.77669 -131.04749)
		(width 0.1651)
		(layer "F.Cu")
		(net "M_D_ODT<1>")
	)
	(segment
		(start 265.521694 -101.541834)
		(end 265.372596 -101.15804)
		(width 0.0889)
		(layer "F.Cu")
		(net "M_D_ODT<1>")
	)
	(segment
		(start 268.14018 -121.68378)
		(end 268.14018 -118.07698)
		(width 0.1651)
		(layer "F.Cu")
		(net "M_D_ODT<1>")
	)
	(segment
		(start 275.77669 -131.04749)
		(end 275.77669 -130.640074)
		(width 0.1651)
		(layer "F.Cu")
		(net "M_D_ODT<1>")
	)
	(segment
		(start 275.844 -129.794)
		(end 275.844 -129.3876)
		(width 0.1651)
		(layer "F.Cu")
		(net "M_D_ODT<1>")
	)
	(segment
		(start 268.14018 -105.148126)
		(end 265.521694 -102.52964)
		(width 0.0889)
		(layer "F.Cu")
		(net "M_D_ODT<1>")
	)
	(segment
		(start 276.300438 -133.0706)
		(end 276.29993 -133.0706)
		(width 0.1651)
		(layer "F.Cu")
		(net "M_D_ODT<1>")
	)
	(segment
		(start 268.14018 -118.07698)
		(end 268.14018 -106.09326)
		(width 0.1651)
		(layer "F.Cu")
		(net "M_D_ODT<1>")
	)
	(segment
		(start 275.971 -129.921)
		(end 275.844 -129.794)
		(width 0.1651)
		(layer "F.Cu")
		(net "M_D_ODT<1>")
	)
	(segment
		(start 268.14018 -106.09326)
		(end 268.14018 -105.148126)
		(width 0.0889)
		(layer "F.Cu")
		(net "M_D_ODT<1>")
	)
	(segment
		(start 265.521694 -102.52964)
		(end 265.521694 -101.541834)
		(width 0.0889)
		(layer "F.Cu")
		(net "M_D_ODT<1>")
	)
	(segment
		(start 275.77669 -130.640074)
		(end 275.971 -130.445764)
		(width 0.1651)
		(layer "F.Cu")
		(net "M_D_ODT<1>")
	)
	(via
		(at 268.14018 -118.07698)
		(size 0.508)
		(drill 0.254)
		(layers "F.Cu" "B.Cu")
		(net "M_D_ODT<1>")
	)
	(segment
		(start 270.988536 -127.986536)
		(end 272.3642 -129.3622)
		(width 0.1651)
		(layer "F.Cu")
		(net "M_D_ODT<0>")
	)
	(segment
		(start 272.2626 -131.0894)
		(end 272.7706 -131.5974)
		(width 0.1651)
		(layer "F.Cu")
		(net "M_D_ODT<0>")
	)
	(segment
		(start 266.12342 -122.907044)
		(end 269.009114 -125.792738)
		(width 0.1651)
		(layer "F.Cu")
		(net "M_D_ODT<0>")
	)
	(segment
		(start 263.769348 -102.428548)
		(end 263.769348 -101.271578)
		(width 0.0889)
		(layer "F.Cu")
		(net "M_D_ODT<0>")
	)
	(segment
		(start 269.899384 -127.986536)
		(end 270.988536 -127.986536)
		(width 0.1651)
		(layer "F.Cu")
		(net "M_D_ODT<0>")
	)
	(segment
		(start 266.12342 -119.622316)
		(end 266.12342 -122.907044)
		(width 0.1651)
		(layer "F.Cu")
		(net "M_D_ODT<0>")
	)
	(segment
		(start 263.769348 -101.271578)
		(end 263.65581 -101.15804)
		(width 0.0889)
		(layer "F.Cu")
		(net "M_D_ODT<0>")
	)
	(segment
		(start 266.12342 -105.333292)
		(end 266.22629 -105.230422)
		(width 0.0889)
		(layer "F.Cu")
		(net "M_D_ODT<0>")
	)
	(segment
		(start 272.7706 -132.947156)
		(end 272.899886 -133.076442)
		(width 0.1651)
		(layer "F.Cu")
		(net "M_D_ODT<0>")
	)
	(segment
		(start 272.3642 -129.3622)
		(end 272.3642 -129.921)
		(width 0.1651)
		(layer "F.Cu")
		(net "M_D_ODT<0>")
	)
	(segment
		(start 272.7706 -131.5974)
		(end 272.7706 -132.947156)
		(width 0.1651)
		(layer "F.Cu")
		(net "M_D_ODT<0>")
	)
	(segment
		(start 272.3642 -129.921)
		(end 272.5166 -130.0734)
		(width 0.1651)
		(layer "F.Cu")
		(net "M_D_ODT<0>")
	)
	(segment
		(start 272.5166 -130.0734)
		(end 272.5166 -130.4798)
		(width 0.1651)
		(layer "F.Cu")
		(net "M_D_ODT<0>")
	)
	(segment
		(start 272.2626 -130.7338)
		(end 272.2626 -131.0894)
		(width 0.1651)
		(layer "F.Cu")
		(net "M_D_ODT<0>")
	)
	(segment
		(start 272.899886 -133.076442)
		(end 272.900394 -133.0706)
		(width 0.1651)
		(layer "F.Cu")
		(net "M_D_ODT<0>")
	)
	(segment
		(start 266.22629 -104.88549)
		(end 263.769348 -102.428548)
		(width 0.0889)
		(layer "F.Cu")
		(net "M_D_ODT<0>")
	)
	(segment
		(start 266.22629 -105.230422)
		(end 266.22629 -104.88549)
		(width 0.0889)
		(layer "F.Cu")
		(net "M_D_ODT<0>")
	)
	(segment
		(start 266.12342 -119.622316)
		(end 266.12342 -105.333292)
		(width 0.1651)
		(layer "F.Cu")
		(net "M_D_ODT<0>")
	)
	(segment
		(start 272.5166 -130.4798)
		(end 272.2626 -130.7338)
		(width 0.1651)
		(layer "F.Cu")
		(net "M_D_ODT<0>")
	)
	(segment
		(start 269.009114 -125.792738)
		(end 269.009114 -127.096266)
		(width 0.1651)
		(layer "F.Cu")
		(net "M_D_ODT<0>")
	)
	(segment
		(start 269.009114 -127.096266)
		(end 269.899384 -127.986536)
		(width 0.1651)
		(layer "F.Cu")
		(net "M_D_ODT<0>")
	)
	(via
		(at 266.12342 -119.622316)
		(size 0.508)
		(drill 0.254)
		(layers "F.Cu" "B.Cu")
		(net "M_D_ODT<0>")
	)
	(segment
		(start 254.212344 -102.302056)
		(end 254.2032 -102.3112)
		(width 0.1651)
		(layer "F.Cu")
		(net "M_D_MA<9>")
	)
	(segment
		(start 249.950478 -133.0706)
		(end 249.94997 -133.076442)
		(width 0.1651)
		(layer "F.Cu")
		(net "M_D_MA<9>")
	)
	(segment
		(start 249.94997 -133.076442)
		(end 249.94997 -134.369302)
		(width 0.1651)
		(layer "F.Cu")
		(net "M_D_MA<9>")
	)
	(segment
		(start 254.212344 -101.653086)
		(end 254.212344 -102.302056)
		(width 0.1651)
		(layer "F.Cu")
		(net "M_D_MA<9>")
	)
	(segment
		(start 249.94997 -134.369302)
		(end 249.949716 -134.369556)
		(width 0.1651)
		(layer "F.Cu")
		(net "M_D_MA<9>")
	)
	(via
		(at 249.94997 -131.611878)
		(size 0.508)
		(drill 0.254)
		(layers "F.Cu" "B.Cu")
		(net "M_D_MA<9>")
	)
	(via
		(at 254.2032 -102.3112)
		(size 0.508)
		(drill 0.254)
		(layers "F.Cu" "B.Cu")
		(net "M_D_MA<9>")
	)
	(via
		(at 249.949716 -134.369556)
		(size 0.4572)
		(drill 0.2032)
		(layers "F.Cu" "B.Cu")
		(net "M_D_MA<9>")
	)
	(segment
		(start 249.950478 -132.876036)
		(end 249.94997 -132.875782)
		(width 0.1651)
		(layer "B.Cu")
		(net "M_D_MA<9>")
	)
	(segment
		(start 249.94997 -132.875782)
		(end 249.94997 -131.611878)
		(width 0.1651)
		(layer "B.Cu")
		(net "M_D_MA<9>")
	)
	(segment
		(start 250.2916 -130.6576)
		(end 250.2916 -131.270248)
		(width 0.14224)
		(layer "In11.Cu")
		(net "M_D_MA<9>")
	)
	(segment
		(start 251.25426 -124.290328)
		(end 251.986034 -125.022102)
		(width 0.14224)
		(layer "In11.Cu")
		(net "M_D_MA<9>")
	)
	(segment
		(start 254.1778 -122.923554)
		(end 253.915672 -123.185682)
		(width 0.14224)
		(layer "In11.Cu")
		(net "M_D_MA<9>")
	)
	(segment
		(start 251.986034 -125.022102)
		(end 251.986034 -125.345698)
		(width 0.14224)
		(layer "In11.Cu")
		(net "M_D_MA<9>")
	)
	(segment
		(start 252.557534 -124.443998)
		(end 251.837444 -123.723908)
		(width 0.14224)
		(layer "In11.Cu")
		(net "M_D_MA<9>")
	)
	(segment
		(start 249.94997 -134.369302)
		(end 249.949716 -134.369556)
		(width 0.14224)
		(layer "In11.Cu")
		(net "M_D_MA<9>")
	)
	(segment
		(start 251.541534 -123.723908)
		(end 251.25426 -124.011182)
		(width 0.14224)
		(layer "In11.Cu")
		(net "M_D_MA<9>")
	)
	(segment
		(start 252.35916 -122.838464)
		(end 252.35916 -123.09602)
		(width 0.14224)
		(layer "In11.Cu")
		(net "M_D_MA<9>")
	)
	(segment
		(start 253.915418 -122.265948)
		(end 254.1778 -122.52833)
		(width 0.14224)
		(layer "In11.Cu")
		(net "M_D_MA<9>")
	)
	(segment
		(start 253.169674 -123.906534)
		(end 253.169674 -124.156724)
		(width 0.14224)
		(layer "In11.Cu")
		(net "M_D_MA<9>")
	)
	(segment
		(start 254.1778 -121.5263)
		(end 253.915418 -121.788682)
		(width 0.14224)
		(layer "In11.Cu")
		(net "M_D_MA<9>")
	)
	(segment
		(start 254.1778 -122.52833)
		(end 254.1778 -122.923554)
		(width 0.14224)
		(layer "In11.Cu")
		(net "M_D_MA<9>")
	)
	(segment
		(start 251.132086 -125.345698)
		(end 250.930918 -125.345698)
		(width 0.14224)
		(layer "In11.Cu")
		(net "M_D_MA<9>")
	)
	(segment
		(start 253.169674 -124.156724)
		(end 252.8824 -124.443998)
		(width 0.14224)
		(layer "In11.Cu")
		(net "M_D_MA<9>")
	)
	(segment
		(start 251.41936 -125.632972)
		(end 251.132086 -125.345698)
		(width 0.14224)
		(layer "In11.Cu")
		(net "M_D_MA<9>")
	)
	(segment
		(start 254.2032 -102.3112)
		(end 254.1778 -102.3366)
		(width 0.14224)
		(layer "In11.Cu")
		(net "M_D_MA<9>")
	)
	(segment
		(start 250.634246 -126.04877)
		(end 251.472446 -126.88697)
		(width 0.14224)
		(layer "In11.Cu")
		(net "M_D_MA<9>")
	)
	(segment
		(start 254.1778 -102.3366)
		(end 254.1778 -121.5263)
		(width 0.14224)
		(layer "In11.Cu")
		(net "M_D_MA<9>")
	)
	(segment
		(start 249.94997 -131.611878)
		(end 249.94997 -134.369302)
		(width 0.14224)
		(layer "In11.Cu")
		(net "M_D_MA<9>")
	)
	(segment
		(start 250.4186 -129.9464)
		(end 250.4186 -130.5306)
		(width 0.14224)
		(layer "In11.Cu")
		(net "M_D_MA<9>")
	)
	(segment
		(start 250.2916 -131.270248)
		(end 249.94997 -131.611878)
		(width 0.14224)
		(layer "In11.Cu")
		(net "M_D_MA<9>")
	)
	(segment
		(start 253.915672 -123.185682)
		(end 253.598426 -123.185682)
		(width 0.14224)
		(layer "In11.Cu")
		(net "M_D_MA<9>")
	)
	(segment
		(start 252.35916 -123.09602)
		(end 253.169674 -123.906534)
		(width 0.14224)
		(layer "In11.Cu")
		(net "M_D_MA<9>")
	)
	(segment
		(start 250.930918 -125.345698)
		(end 250.634246 -125.64237)
		(width 0.14224)
		(layer "In11.Cu")
		(net "M_D_MA<9>")
	)
	(segment
		(start 251.472446 -126.88697)
		(end 251.472446 -128.206754)
		(width 0.14224)
		(layer "In11.Cu")
		(net "M_D_MA<9>")
	)
	(segment
		(start 250.634246 -125.64237)
		(end 250.634246 -126.04877)
		(width 0.14224)
		(layer "In11.Cu")
		(net "M_D_MA<9>")
	)
	(segment
		(start 250.2662 -129.413)
		(end 250.2662 -129.794)
		(width 0.14224)
		(layer "In11.Cu")
		(net "M_D_MA<9>")
	)
	(segment
		(start 251.69876 -125.632972)
		(end 251.41936 -125.632972)
		(width 0.14224)
		(layer "In11.Cu")
		(net "M_D_MA<9>")
	)
	(segment
		(start 251.25426 -124.011182)
		(end 251.25426 -124.290328)
		(width 0.14224)
		(layer "In11.Cu")
		(net "M_D_MA<9>")
	)
	(segment
		(start 252.8824 -124.443998)
		(end 252.557534 -124.443998)
		(width 0.14224)
		(layer "In11.Cu")
		(net "M_D_MA<9>")
	)
	(segment
		(start 250.2662 -129.794)
		(end 250.4186 -129.9464)
		(width 0.14224)
		(layer "In11.Cu")
		(net "M_D_MA<9>")
	)
	(segment
		(start 250.4186 -130.5306)
		(end 250.2916 -130.6576)
		(width 0.14224)
		(layer "In11.Cu")
		(net "M_D_MA<9>")
	)
	(segment
		(start 251.472446 -128.206754)
		(end 250.2662 -129.413)
		(width 0.14224)
		(layer "In11.Cu")
		(net "M_D_MA<9>")
	)
	(segment
		(start 251.837444 -123.723908)
		(end 251.541534 -123.723908)
		(width 0.14224)
		(layer "In11.Cu")
		(net "M_D_MA<9>")
	)
	(segment
		(start 252.646434 -122.55119)
		(end 252.35916 -122.838464)
		(width 0.14224)
		(layer "In11.Cu")
		(net "M_D_MA<9>")
	)
	(segment
		(start 251.986034 -125.345698)
		(end 251.69876 -125.632972)
		(width 0.14224)
		(layer "In11.Cu")
		(net "M_D_MA<9>")
	)
	(segment
		(start 253.598426 -123.185682)
		(end 252.963934 -122.55119)
		(width 0.14224)
		(layer "In11.Cu")
		(net "M_D_MA<9>")
	)
	(segment
		(start 252.963934 -122.55119)
		(end 252.646434 -122.55119)
		(width 0.14224)
		(layer "In11.Cu")
		(net "M_D_MA<9>")
	)
	(segment
		(start 253.915418 -121.788682)
		(end 253.915418 -122.265948)
		(width 0.14224)
		(layer "In11.Cu")
		(net "M_D_MA<9>")
	)
	(segment
		(start 251.4092 -129.667)
		(end 251.1806 -129.8956)
		(width 0.1651)
		(layer "F.Cu")
		(net "M_D_MA<8>")
	)
	(segment
		(start 251.4092 -126.0856)
		(end 251.4092 -129.667)
		(width 0.1651)
		(layer "F.Cu")
		(net "M_D_MA<8>")
	)
	(segment
		(start 251.1806 -130.474466)
		(end 251.649992 -130.943858)
		(width 0.1651)
		(layer "F.Cu")
		(net "M_D_MA<8>")
	)
	(segment
		(start 254.803402 -101.654356)
		(end 254.803402 -102.961694)
		(width 0.0889)
		(layer "F.Cu")
		(net "M_D_MA<8>")
	)
	(segment
		(start 251.6505 -133.0706)
		(end 251.649992 -133.076442)
		(width 0.1651)
		(layer "F.Cu")
		(net "M_D_MA<8>")
	)
	(segment
		(start 251.1806 -129.8956)
		(end 251.1806 -130.474466)
		(width 0.1651)
		(layer "F.Cu")
		(net "M_D_MA<8>")
	)
	(segment
		(start 255.388618 -115.409218)
		(end 251.619766 -119.17807)
		(width 0.1651)
		(layer "F.Cu")
		(net "M_D_MA<8>")
	)
	(segment
		(start 251.649992 -130.943858)
		(end 251.649992 -131.611878)
		(width 0.1651)
		(layer "F.Cu")
		(net "M_D_MA<8>")
	)
	(segment
		(start 251.649992 -133.076442)
		(end 251.649992 -134.371588)
		(width 0.1651)
		(layer "F.Cu")
		(net "M_D_MA<8>")
	)
	(segment
		(start 255.388618 -103.54691)
		(end 255.388618 -103.828596)
		(width 0.0889)
		(layer "F.Cu")
		(net "M_D_MA<8>")
	)
	(segment
		(start 255.388618 -103.828596)
		(end 255.388618 -115.409218)
		(width 0.1651)
		(layer "F.Cu")
		(net "M_D_MA<8>")
	)
	(segment
		(start 254.803402 -102.961694)
		(end 255.388618 -103.54691)
		(width 0.0889)
		(layer "F.Cu")
		(net "M_D_MA<8>")
	)
	(segment
		(start 251.619766 -125.875034)
		(end 251.4092 -126.0856)
		(width 0.1651)
		(layer "F.Cu")
		(net "M_D_MA<8>")
	)
	(segment
		(start 251.619766 -119.17807)
		(end 251.619766 -125.875034)
		(width 0.1651)
		(layer "F.Cu")
		(net "M_D_MA<8>")
	)
	(via
		(at 251.649992 -134.371588)
		(size 0.4572)
		(drill 0.2032)
		(layers "F.Cu" "B.Cu")
		(net "M_D_MA<8>")
	)
	(via
		(at 251.649992 -131.611878)
		(size 0.508)
		(drill 0.254)
		(layers "F.Cu" "B.Cu")
		(net "M_D_MA<8>")
	)
	(arc
		(start 255.92913 -99.67214)
		(mid 255.653785 -100.005294)
		(end 255.41732 -100.367084)
		(width 0.0889)
		(layer "F.Cu")
		(net "M_D_MA<8>")
	)
	(arc
		(start 255.213358 -100.541074)
		(mid 254.932825 -100.707464)
		(end 254.724154 -100.958142)
		(width 0.0889)
		(layer "F.Cu")
		(net "M_D_MA<8>")
	)
	(arc
		(start 254.724154 -100.958142)
		(mid 254.676406 -101.164039)
		(end 254.730504 -101.368352)
		(width 0.0889)
		(layer "F.Cu")
		(net "M_D_MA<8>")
	)
	(arc
		(start 254.730504 -101.368352)
		(mid 254.78512 -101.506727)
		(end 254.803402 -101.654356)
		(width 0.0889)
		(layer "F.Cu")
		(net "M_D_MA<8>")
	)
	(arc
		(start 255.41732 -100.367084)
		(mid 255.330341 -100.471664)
		(end 255.213358 -100.541074)
		(width 0.0889)
		(layer "F.Cu")
		(net "M_D_MA<8>")
	)
	(segment
		(start 251.6505 -132.876036)
		(end 251.649992 -132.875782)
		(width 0.1651)
		(layer "B.Cu")
		(net "M_D_MA<8>")
	)
	(segment
		(start 251.649992 -132.875782)
		(end 251.649992 -131.611878)
		(width 0.1651)
		(layer "B.Cu")
		(net "M_D_MA<8>")
	)
	(segment
		(start 251.156978 -132.649214)
		(end 251.311918 -132.804154)
		(width 0.14224)
		(layer "In9.Cu")
		(net "M_D_MA<8>")
	)
	(segment
		(start 250.407424 -131.94157)
		(end 250.26112 -132.087874)
		(width 0.14224)
		(layer "In9.Cu")
		(net "M_D_MA<8>")
	)
	(segment
		(start 250.53925 -133.771894)
		(end 251.050298 -133.771894)
		(width 0.14224)
		(layer "In9.Cu")
		(net "M_D_MA<8>")
	)
	(segment
		(start 250.129802 -132.649214)
		(end 251.156978 -132.649214)
		(width 0.14224)
		(layer "In9.Cu")
		(net "M_D_MA<8>")
	)
	(segment
		(start 249.944128 -132.46354)
		(end 250.129802 -132.649214)
		(width 0.14224)
		(layer "In9.Cu")
		(net "M_D_MA<8>")
	)
	(segment
		(start 251.649992 -131.926584)
		(end 251.488702 -132.087874)
		(width 0.14224)
		(layer "In9.Cu")
		(net "M_D_MA<8>")
	)
	(segment
		(start 250.811538 -131.479798)
		(end 250.560078 -131.479798)
		(width 0.14224)
		(layer "In9.Cu")
		(net "M_D_MA<8>")
	)
	(segment
		(start 249.944128 -132.214874)
		(end 249.944128 -132.46354)
		(width 0.14224)
		(layer "In9.Cu")
		(net "M_D_MA<8>")
	)
	(segment
		(start 251.115068 -132.087874)
		(end 250.968764 -131.94157)
		(width 0.14224)
		(layer "In9.Cu")
		(net "M_D_MA<8>")
	)
	(segment
		(start 250.26112 -132.087874)
		(end 250.071128 -132.087874)
		(width 0.14224)
		(layer "In9.Cu")
		(net "M_D_MA<8>")
	)
	(segment
		(start 250.370848 -133.603492)
		(end 250.53925 -133.771894)
		(width 0.14224)
		(layer "In9.Cu")
		(net "M_D_MA<8>")
	)
	(segment
		(start 250.968764 -131.637024)
		(end 250.811538 -131.479798)
		(width 0.14224)
		(layer "In9.Cu")
		(net "M_D_MA<8>")
	)
	(segment
		(start 251.311918 -133.055614)
		(end 251.156978 -133.210554)
		(width 0.14224)
		(layer "In9.Cu")
		(net "M_D_MA<8>")
	)
	(segment
		(start 251.050298 -133.771894)
		(end 251.649992 -134.371588)
		(width 0.14224)
		(layer "In9.Cu")
		(net "M_D_MA<8>")
	)
	(segment
		(start 250.560078 -131.479798)
		(end 250.407424 -131.632452)
		(width 0.14224)
		(layer "In9.Cu")
		(net "M_D_MA<8>")
	)
	(segment
		(start 251.156978 -133.210554)
		(end 250.512326 -133.210554)
		(width 0.14224)
		(layer "In9.Cu")
		(net "M_D_MA<8>")
	)
	(segment
		(start 251.649992 -131.611878)
		(end 251.649992 -131.926584)
		(width 0.14224)
		(layer "In9.Cu")
		(net "M_D_MA<8>")
	)
	(segment
		(start 250.071128 -132.087874)
		(end 249.944128 -132.214874)
		(width 0.14224)
		(layer "In9.Cu")
		(net "M_D_MA<8>")
	)
	(segment
		(start 251.488702 -132.087874)
		(end 251.115068 -132.087874)
		(width 0.14224)
		(layer "In9.Cu")
		(net "M_D_MA<8>")
	)
	(segment
		(start 251.311918 -132.804154)
		(end 251.311918 -133.055614)
		(width 0.14224)
		(layer "In9.Cu")
		(net "M_D_MA<8>")
	)
	(segment
		(start 250.512326 -133.210554)
		(end 250.370848 -133.352032)
		(width 0.14224)
		(layer "In9.Cu")
		(net "M_D_MA<8>")
	)
	(segment
		(start 250.370848 -133.352032)
		(end 250.370848 -133.603492)
		(width 0.14224)
		(layer "In9.Cu")
		(net "M_D_MA<8>")
	)
	(segment
		(start 250.968764 -131.94157)
		(end 250.968764 -131.637024)
		(width 0.14224)
		(layer "In9.Cu")
		(net "M_D_MA<8>")
	)
	(segment
		(start 250.407424 -131.632452)
		(end 250.407424 -131.94157)
		(width 0.14224)
		(layer "In9.Cu")
		(net "M_D_MA<8>")
	)
	(segment
		(start 254.856488 -115.197128)
		(end 250.964446 -119.08917)
		(width 0.1651)
		(layer "F.Cu")
		(net "M_D_MA<7>")
	)
	(segment
		(start 251.109734 -120.943116)
		(end 250.944634 -121.108216)
		(width 0.1651)
		(layer "F.Cu")
		(net "M_D_MA<7>")
	)
	(segment
		(start 254.612394 -101.658166)
		(end 254.612394 -103.260906)
		(width 0.0889)
		(layer "F.Cu")
		(net "M_D_MA<7>")
	)
	(segment
		(start 250.595384 -121.273316)
		(end 250.595384 -121.616216)
		(width 0.1651)
		(layer "F.Cu")
		(net "M_D_MA<7>")
	)
	(segment
		(start 251.102114 -124.74829)
		(end 251.102114 -125.51156)
		(width 0.1651)
		(layer "F.Cu")
		(net "M_D_MA<7>")
	)
	(segment
		(start 254.730504 -99.95662)
		(end 254.724154 -99.967288)
		(width 0.0889)
		(layer "F.Cu")
		(net "M_D_MA<7>")
	)
	(segment
		(start 250.760484 -121.781316)
		(end 250.944634 -121.781316)
		(width 0.1651)
		(layer "F.Cu")
		(net "M_D_MA<7>")
	)
	(segment
		(start 254.612394 -103.260906)
		(end 254.856488 -103.505)
		(width 0.0889)
		(layer "F.Cu")
		(net "M_D_MA<7>")
	)
	(segment
		(start 250.944634 -121.781316)
		(end 251.109734 -121.946416)
		(width 0.1651)
		(layer "F.Cu")
		(net "M_D_MA<7>")
	)
	(segment
		(start 251.102114 -125.51156)
		(end 250.799854 -125.81382)
		(width 0.1651)
		(layer "F.Cu")
		(net "M_D_MA<7>")
	)
	(segment
		(start 250.538234 -124.327666)
		(end 250.703334 -124.492766)
		(width 0.1651)
		(layer "F.Cu")
		(net "M_D_MA<7>")
	)
	(segment
		(start 251.109734 -123.311666)
		(end 251.109734 -123.654566)
		(width 0.1651)
		(layer "F.Cu")
		(net "M_D_MA<7>")
	)
	(segment
		(start 250.64085 -122.473466)
		(end 250.475496 -122.63882)
		(width 0.1651)
		(layer "F.Cu")
		(net "M_D_MA<7>")
	)
	(segment
		(start 250.799854 -136.387078)
		(end 250.799854 -137.67054)
		(width 0.1651)
		(layer "F.Cu")
		(net "M_D_MA<7>")
	)
	(segment
		(start 250.475496 -122.63882)
		(end 250.475496 -122.981466)
		(width 0.1651)
		(layer "F.Cu")
		(net "M_D_MA<7>")
	)
	(segment
		(start 250.944634 -123.146566)
		(end 251.109734 -123.311666)
		(width 0.1651)
		(layer "F.Cu")
		(net "M_D_MA<7>")
	)
	(segment
		(start 250.475496 -122.981466)
		(end 250.640596 -123.146566)
		(width 0.1651)
		(layer "F.Cu")
		(net "M_D_MA<7>")
	)
	(segment
		(start 250.640596 -123.146566)
		(end 250.944634 -123.146566)
		(width 0.1651)
		(layer "F.Cu")
		(net "M_D_MA<7>")
	)
	(segment
		(start 250.944634 -123.819666)
		(end 250.703334 -123.819666)
		(width 0.1651)
		(layer "F.Cu")
		(net "M_D_MA<7>")
	)
	(segment
		(start 250.703334 -124.492766)
		(end 250.84659 -124.492766)
		(width 0.1651)
		(layer "F.Cu")
		(net "M_D_MA<7>")
	)
	(segment
		(start 250.944634 -122.473466)
		(end 250.64085 -122.473466)
		(width 0.1651)
		(layer "F.Cu")
		(net "M_D_MA<7>")
	)
	(segment
		(start 254.856488 -103.726488)
		(end 254.856488 -115.197128)
		(width 0.1651)
		(layer "F.Cu")
		(net "M_D_MA<7>")
	)
	(segment
		(start 250.964446 -120.454928)
		(end 251.109734 -120.600216)
		(width 0.1651)
		(layer "F.Cu")
		(net "M_D_MA<7>")
	)
	(segment
		(start 250.595384 -121.616216)
		(end 250.760484 -121.781316)
		(width 0.1651)
		(layer "F.Cu")
		(net "M_D_MA<7>")
	)
	(segment
		(start 250.964446 -119.08917)
		(end 250.964446 -120.454928)
		(width 0.1651)
		(layer "F.Cu")
		(net "M_D_MA<7>")
	)
	(segment
		(start 254.54991 -101.437948)
		(end 254.5588 -101.453188)
		(width 0.0889)
		(layer "F.Cu")
		(net "M_D_MA<7>")
	)
	(segment
		(start 254.856488 -103.505)
		(end 254.856488 -103.726488)
		(width 0.0889)
		(layer "F.Cu")
		(net "M_D_MA<7>")
	)
	(segment
		(start 250.538234 -123.984766)
		(end 250.538234 -124.327666)
		(width 0.1651)
		(layer "F.Cu")
		(net "M_D_MA<7>")
	)
	(segment
		(start 251.109734 -122.308366)
		(end 250.944634 -122.473466)
		(width 0.1651)
		(layer "F.Cu")
		(net "M_D_MA<7>")
	)
	(segment
		(start 250.944634 -121.108216)
		(end 250.760484 -121.108216)
		(width 0.1651)
		(layer "F.Cu")
		(net "M_D_MA<7>")
	)
	(segment
		(start 250.703334 -123.819666)
		(end 250.538234 -123.984766)
		(width 0.1651)
		(layer "F.Cu")
		(net "M_D_MA<7>")
	)
	(segment
		(start 250.799854 -125.81382)
		(end 250.799854 -129.539746)
		(width 0.1651)
		(layer "F.Cu")
		(net "M_D_MA<7>")
	)
	(segment
		(start 250.799854 -137.67054)
		(end 250.800362 -137.67054)
		(width 0.1651)
		(layer "F.Cu")
		(net "M_D_MA<7>")
	)
	(segment
		(start 250.760484 -121.108216)
		(end 250.595384 -121.273316)
		(width 0.1651)
		(layer "F.Cu")
		(net "M_D_MA<7>")
	)
	(segment
		(start 251.109734 -123.654566)
		(end 250.944634 -123.819666)
		(width 0.1651)
		(layer "F.Cu")
		(net "M_D_MA<7>")
	)
	(segment
		(start 251.109734 -120.600216)
		(end 251.109734 -120.943116)
		(width 0.1651)
		(layer "F.Cu")
		(net "M_D_MA<7>")
	)
	(segment
		(start 251.109734 -121.946416)
		(end 251.109734 -122.308366)
		(width 0.1651)
		(layer "F.Cu")
		(net "M_D_MA<7>")
	)
	(segment
		(start 250.84659 -124.492766)
		(end 251.102114 -124.74829)
		(width 0.1651)
		(layer "F.Cu")
		(net "M_D_MA<7>")
	)
	(via
		(at 250.799854 -129.539746)
		(size 0.508)
		(drill 0.254)
		(layers "F.Cu" "B.Cu")
		(net "M_D_MA<7>")
	)
	(via
		(at 250.799854 -136.387078)
		(size 0.4572)
		(drill 0.2032)
		(layers "F.Cu" "B.Cu")
		(net "M_D_MA<7>")
	)
	(arc
		(start 254.724154 -99.967288)
		(mid 254.676497 -100.098876)
		(end 254.677164 -100.238814)
		(width 0.0889)
		(layer "F.Cu")
		(net "M_D_MA<7>")
	)
	(arc
		(start 254.5588 -101.453188)
		(mid 254.59943 -101.552063)
		(end 254.612394 -101.658166)
		(width 0.0889)
		(layer "F.Cu")
		(net "M_D_MA<7>")
	)
	(arc
		(start 254.5588 -100.862384)
		(mid 254.479611 -101.148999)
		(end 254.54991 -101.437948)
		(width 0.0889)
		(layer "F.Cu")
		(net "M_D_MA<7>")
	)
	(arc
		(start 255.07061 -99.17684)
		(mid 254.925086 -99.577429)
		(end 254.730504 -99.95662)
		(width 0.0889)
		(layer "F.Cu")
		(net "M_D_MA<7>")
	)
	(arc
		(start 254.677164 -100.238814)
		(mid 254.675989 -100.561617)
		(end 254.5588 -100.862384)
		(width 0.0889)
		(layer "F.Cu")
		(net "M_D_MA<7>")
	)
	(segment
		(start 250.800362 -128.276096)
		(end 250.799854 -128.276096)
		(width 0.1651)
		(layer "B.Cu")
		(net "M_D_MA<7>")
	)
	(segment
		(start 250.799854 -128.276096)
		(end 250.799854 -129.539746)
		(width 0.1651)
		(layer "B.Cu")
		(net "M_D_MA<7>")
	)
	(segment
		(start 249.487182 -133.308598)
		(end 250.358402 -134.179818)
		(width 0.14224)
		(layer "In9.Cu")
		(net "M_D_MA<7>")
	)
	(segment
		(start 250.358402 -135.945626)
		(end 250.799854 -136.387078)
		(width 0.14224)
		(layer "In9.Cu")
		(net "M_D_MA<7>")
	)
	(segment
		(start 249.487182 -131.437126)
		(end 249.487182 -133.308598)
		(width 0.14224)
		(layer "In9.Cu")
		(net "M_D_MA<7>")
	)
	(segment
		(start 250.799854 -130.124454)
		(end 249.487182 -131.437126)
		(width 0.14224)
		(layer "In9.Cu")
		(net "M_D_MA<7>")
	)
	(segment
		(start 250.358402 -134.179818)
		(end 250.358402 -135.945626)
		(width 0.14224)
		(layer "In9.Cu")
		(net "M_D_MA<7>")
	)
	(segment
		(start 250.799854 -129.539746)
		(end 250.799854 -130.124454)
		(width 0.14224)
		(layer "In9.Cu")
		(net "M_D_MA<7>")
	)
	(segment
		(start 252.61697 -130.785362)
		(end 252.499876 -130.902456)
		(width 0.1651)
		(layer "F.Cu")
		(net "M_D_MA<6>")
	)
	(segment
		(start 255.920748 -103.648002)
		(end 255.920748 -103.879904)
		(width 0.0889)
		(layer "F.Cu")
		(net "M_D_MA<6>")
	)
	(segment
		(start 251.925836 -126.400814)
		(end 251.925836 -126.891796)
		(width 0.1651)
		(layer "F.Cu")
		(net "M_D_MA<6>")
	)
	(segment
		(start 251.958856 -129.759456)
		(end 252.61697 -130.41757)
		(width 0.1651)
		(layer "F.Cu")
		(net "M_D_MA<6>")
	)
	(segment
		(start 252.136656 -127.536194)
		(end 251.897134 -127.775716)
		(width 0.1651)
		(layer "F.Cu")
		(net "M_D_MA<6>")
	)
	(segment
		(start 252.136656 -128.448816)
		(end 252.136656 -128.989836)
		(width 0.1651)
		(layer "F.Cu")
		(net "M_D_MA<6>")
	)
	(segment
		(start 252.136656 -119.493538)
		(end 252.136656 -126.189994)
		(width 0.1651)
		(layer "F.Cu")
		(net "M_D_MA<6>")
	)
	(segment
		(start 252.499876 -133.076442)
		(end 252.499876 -134.371588)
		(width 0.1651)
		(layer "F.Cu")
		(net "M_D_MA<6>")
	)
	(segment
		(start 252.136656 -128.989836)
		(end 251.958856 -129.167636)
		(width 0.1651)
		(layer "F.Cu")
		(net "M_D_MA<6>")
	)
	(segment
		(start 251.897134 -127.775716)
		(end 251.897134 -128.209294)
		(width 0.1651)
		(layer "F.Cu")
		(net "M_D_MA<6>")
	)
	(segment
		(start 251.897134 -128.209294)
		(end 252.136656 -128.448816)
		(width 0.1651)
		(layer "F.Cu")
		(net "M_D_MA<6>")
	)
	(segment
		(start 251.925836 -126.891796)
		(end 252.136656 -127.102616)
		(width 0.1651)
		(layer "F.Cu")
		(net "M_D_MA<6>")
	)
	(segment
		(start 255.07061 -102.797864)
		(end 255.920748 -103.648002)
		(width 0.0889)
		(layer "F.Cu")
		(net "M_D_MA<6>")
	)
	(segment
		(start 252.136656 -127.102616)
		(end 252.136656 -127.536194)
		(width 0.1651)
		(layer "F.Cu")
		(net "M_D_MA<6>")
	)
	(segment
		(start 252.500384 -133.0706)
		(end 252.499876 -133.076442)
		(width 0.1651)
		(layer "F.Cu")
		(net "M_D_MA<6>")
	)
	(segment
		(start 252.61697 -130.41757)
		(end 252.61697 -130.785362)
		(width 0.1651)
		(layer "F.Cu")
		(net "M_D_MA<6>")
	)
	(segment
		(start 255.920748 -103.879904)
		(end 255.920748 -115.709446)
		(width 0.1651)
		(layer "F.Cu")
		(net "M_D_MA<6>")
	)
	(segment
		(start 251.958856 -129.167636)
		(end 251.958856 -129.759456)
		(width 0.1651)
		(layer "F.Cu")
		(net "M_D_MA<6>")
	)
	(segment
		(start 255.920748 -115.709446)
		(end 252.136656 -119.493538)
		(width 0.1651)
		(layer "F.Cu")
		(net "M_D_MA<6>")
	)
	(segment
		(start 252.136656 -126.189994)
		(end 251.925836 -126.400814)
		(width 0.1651)
		(layer "F.Cu")
		(net "M_D_MA<6>")
	)
	(segment
		(start 255.07061 -101.15804)
		(end 255.07061 -102.797864)
		(width 0.0889)
		(layer "F.Cu")
		(net "M_D_MA<6>")
	)
	(via
		(at 252.499876 -130.902456)
		(size 0.508)
		(drill 0.254)
		(layers "F.Cu" "B.Cu")
		(net "M_D_MA<6>")
	)
	(via
		(at 252.499876 -134.371588)
		(size 0.4572)
		(drill 0.2032)
		(layers "F.Cu" "B.Cu")
		(net "M_D_MA<6>")
	)
	(segment
		(start 252.499876 -132.875782)
		(end 252.499876 -130.902456)
		(width 0.1651)
		(layer "B.Cu")
		(net "M_D_MA<6>")
	)
	(segment
		(start 252.500384 -132.876036)
		(end 252.499876 -132.875782)
		(width 0.1651)
		(layer "B.Cu")
		(net "M_D_MA<6>")
	)
	(segment
		(start 252.499876 -134.371588)
		(end 252.499876 -133.956298)
		(width 0.14224)
		(layer "In9.Cu")
		(net "M_D_MA<6>")
	)
	(segment
		(start 252.499876 -133.956298)
		(end 252.6284 -133.827774)
		(width 0.14224)
		(layer "In9.Cu")
		(net "M_D_MA<6>")
	)
	(segment
		(start 252.654816 -132.143754)
		(end 252.499876 -131.988814)
		(width 0.14224)
		(layer "In9.Cu")
		(net "M_D_MA<6>")
	)
	(segment
		(start 253.613158 -132.298694)
		(end 253.458218 -132.143754)
		(width 0.14224)
		(layer "In9.Cu")
		(net "M_D_MA<6>")
	)
	(segment
		(start 253.458218 -132.705094)
		(end 253.613158 -132.550154)
		(width 0.14224)
		(layer "In9.Cu")
		(net "M_D_MA<6>")
	)
	(segment
		(start 252.206252 -133.100064)
		(end 252.206252 -132.848604)
		(width 0.14224)
		(layer "In9.Cu")
		(net "M_D_MA<6>")
	)
	(segment
		(start 252.6284 -133.827774)
		(end 253.438914 -133.827774)
		(width 0.14224)
		(layer "In9.Cu")
		(net "M_D_MA<6>")
	)
	(segment
		(start 252.206252 -132.848604)
		(end 252.349762 -132.705094)
		(width 0.14224)
		(layer "In9.Cu")
		(net "M_D_MA<6>")
	)
	(segment
		(start 252.813058 -131.428236)
		(end 252.813058 -131.215638)
		(width 0.14224)
		(layer "In9.Cu")
		(net "M_D_MA<6>")
	)
	(segment
		(start 253.597664 -133.669024)
		(end 253.597664 -133.417564)
		(width 0.14224)
		(layer "In9.Cu")
		(net "M_D_MA<6>")
	)
	(segment
		(start 253.597664 -133.417564)
		(end 253.446534 -133.266434)
		(width 0.14224)
		(layer "In9.Cu")
		(net "M_D_MA<6>")
	)
	(segment
		(start 253.613158 -132.550154)
		(end 253.613158 -132.298694)
		(width 0.14224)
		(layer "In9.Cu")
		(net "M_D_MA<6>")
	)
	(segment
		(start 252.499876 -131.741418)
		(end 252.813058 -131.428236)
		(width 0.14224)
		(layer "In9.Cu")
		(net "M_D_MA<6>")
	)
	(segment
		(start 252.499876 -131.988814)
		(end 252.499876 -131.741418)
		(width 0.14224)
		(layer "In9.Cu")
		(net "M_D_MA<6>")
	)
	(segment
		(start 252.349762 -132.705094)
		(end 253.458218 -132.705094)
		(width 0.14224)
		(layer "In9.Cu")
		(net "M_D_MA<6>")
	)
	(segment
		(start 252.813058 -131.215638)
		(end 252.499876 -130.902456)
		(width 0.14224)
		(layer "In9.Cu")
		(net "M_D_MA<6>")
	)
	(segment
		(start 253.458218 -132.143754)
		(end 252.654816 -132.143754)
		(width 0.14224)
		(layer "In9.Cu")
		(net "M_D_MA<6>")
	)
	(segment
		(start 252.372622 -133.266434)
		(end 252.206252 -133.100064)
		(width 0.14224)
		(layer "In9.Cu")
		(net "M_D_MA<6>")
	)
	(segment
		(start 253.446534 -133.266434)
		(end 252.372622 -133.266434)
		(width 0.14224)
		(layer "In9.Cu")
		(net "M_D_MA<6>")
	)
	(segment
		(start 253.438914 -133.827774)
		(end 253.597664 -133.669024)
		(width 0.14224)
		(layer "In9.Cu")
		(net "M_D_MA<6>")
	)
	(segment
		(start 255.528826 -100.6602)
		(end 255.450594 -101.271324)
		(width 0.0889)
		(layer "F.Cu")
		(net "M_D_MA<5>")
	)
	(segment
		(start 256.452878 -104.029764)
		(end 256.452878 -115.938554)
		(width 0.1651)
		(layer "F.Cu")
		(net "M_D_MA<5>")
	)
	(segment
		(start 255.3462 -101.4222)
		(end 255.3208 -101.4984)
		(width 0.0889)
		(layer "F.Cu")
		(net "M_D_MA<5>")
	)
	(segment
		(start 252.500384 -137.67054)
		(end 252.499876 -137.67054)
		(width 0.1651)
		(layer "F.Cu")
		(net "M_D_MA<5>")
	)
	(segment
		(start 252.499876 -137.67054)
		(end 252.499876 -136.387078)
		(width 0.1651)
		(layer "F.Cu")
		(net "M_D_MA<5>")
	)
	(segment
		(start 256.0574 -100.076)
		(end 255.7145 -100.324666)
		(width 0.0889)
		(layer "F.Cu")
		(net "M_D_MA<5>")
	)
	(segment
		(start 252.662436 -129.406396)
		(end 252.499876 -129.568956)
		(width 0.1651)
		(layer "F.Cu")
		(net "M_D_MA<5>")
	)
	(segment
		(start 256.452878 -115.938554)
		(end 252.662436 -119.728996)
		(width 0.1651)
		(layer "F.Cu")
		(net "M_D_MA<5>")
	)
	(segment
		(start 255.3208 -101.4984)
		(end 255.3208 -102.6922)
		(width 0.0889)
		(layer "F.Cu")
		(net "M_D_MA<5>")
	)
	(segment
		(start 256.286 -99.8474)
		(end 256.0574 -100.076)
		(width 0.0889)
		(layer "F.Cu")
		(net "M_D_MA<5>")
	)
	(segment
		(start 252.662436 -119.728996)
		(end 252.662436 -129.406396)
		(width 0.1651)
		(layer "F.Cu")
		(net "M_D_MA<5>")
	)
	(segment
		(start 256.452878 -103.824278)
		(end 256.452878 -104.029764)
		(width 0.0889)
		(layer "F.Cu")
		(net "M_D_MA<5>")
	)
	(segment
		(start 256.78765 -99.17684)
		(end 256.286 -99.8474)
		(width 0.0889)
		(layer "F.Cu")
		(net "M_D_MA<5>")
	)
	(segment
		(start 255.3208 -102.6922)
		(end 256.452878 -103.824278)
		(width 0.0889)
		(layer "F.Cu")
		(net "M_D_MA<5>")
	)
	(via
		(at 252.499876 -129.568956)
		(size 0.508)
		(drill 0.254)
		(layers "F.Cu" "B.Cu")
		(net "M_D_MA<5>")
	)
	(via
		(at 252.499876 -136.387078)
		(size 0.4572)
		(drill 0.2032)
		(layers "F.Cu" "B.Cu")
		(net "M_D_MA<5>")
	)
	(arc
		(start 255.450594 -101.271324)
		(mid 255.402623 -101.349686)
		(end 255.3462 -101.4222)
		(width 0.0889)
		(layer "F.Cu")
		(net "M_D_MA<5>")
	)
	(arc
		(start 255.7145 -100.324666)
		(mid 255.578903 -100.46876)
		(end 255.528826 -100.6602)
		(width 0.0889)
		(layer "F.Cu")
		(net "M_D_MA<5>")
	)
	(segment
		(start 252.500384 -128.276096)
		(end 252.499876 -128.276096)
		(width 0.1651)
		(layer "B.Cu")
		(net "M_D_MA<5>")
	)
	(segment
		(start 252.499876 -128.276096)
		(end 252.499876 -129.568956)
		(width 0.1651)
		(layer "B.Cu")
		(net "M_D_MA<5>")
	)
	(segment
		(start 252.499876 -136.387078)
		(end 252.499876 -135.177276)
		(width 0.14224)
		(layer "In9.Cu")
		(net "M_D_MA<5>")
	)
	(segment
		(start 252.0188 -131.2164)
		(end 252.0188 -130.730244)
		(width 0.14224)
		(layer "In9.Cu")
		(net "M_D_MA<5>")
	)
	(segment
		(start 252.499876 -135.177276)
		(end 252.071378 -134.748778)
		(width 0.14224)
		(layer "In9.Cu")
		(net "M_D_MA<5>")
	)
	(segment
		(start 252.090428 -132.243068)
		(end 252.090428 -131.288028)
		(width 0.14224)
		(layer "In9.Cu")
		(net "M_D_MA<5>")
	)
	(segment
		(start 252.0188 -130.730244)
		(end 252.499876 -129.568956)
		(width 0.14224)
		(layer "In9.Cu")
		(net "M_D_MA<5>")
	)
	(segment
		(start 252.090428 -131.288028)
		(end 252.0188 -131.2164)
		(width 0.14224)
		(layer "In9.Cu")
		(net "M_D_MA<5>")
	)
	(segment
		(start 252.071378 -134.748778)
		(end 252.071378 -134.024878)
		(width 0.14224)
		(layer "In9.Cu")
		(net "M_D_MA<5>")
	)
	(segment
		(start 251.7902 -133.7437)
		(end 251.7902 -132.543296)
		(width 0.14224)
		(layer "In9.Cu")
		(net "M_D_MA<5>")
	)
	(segment
		(start 252.071378 -134.024878)
		(end 251.7902 -133.7437)
		(width 0.14224)
		(layer "In9.Cu")
		(net "M_D_MA<5>")
	)
	(segment
		(start 251.7902 -132.543296)
		(end 252.090428 -132.243068)
		(width 0.14224)
		(layer "In9.Cu")
		(net "M_D_MA<5>")
	)
	(segment
		(start 253.209298 -119.934736)
		(end 253.209298 -130.108452)
		(width 0.1651)
		(layer "F.Cu")
		(net "M_D_MA<4>")
	)
	(segment
		(start 255.528318 -101.652324)
		(end 255.528318 -102.493318)
		(width 0.0889)
		(layer "F.Cu")
		(net "M_D_MA<4>")
	)
	(segment
		(start 253.350014 -136.387078)
		(end 253.350014 -137.67054)
		(width 0.1651)
		(layer "F.Cu")
		(net "M_D_MA<4>")
	)
	(segment
		(start 255.528318 -102.493318)
		(end 256.985008 -103.950008)
		(width 0.0889)
		(layer "F.Cu")
		(net "M_D_MA<4>")
	)
	(segment
		(start 255.599692 -101.42347)
		(end 255.58242 -101.453188)
		(width 0.0889)
		(layer "F.Cu")
		(net "M_D_MA<4>")
	)
	(segment
		(start 253.209298 -130.108452)
		(end 253.350014 -130.249168)
		(width 0.1651)
		(layer "F.Cu")
		(net "M_D_MA<4>")
	)
	(segment
		(start 256.985008 -116.159026)
		(end 253.209298 -119.934736)
		(width 0.1651)
		(layer "F.Cu")
		(net "M_D_MA<4>")
	)
	(segment
		(start 256.985008 -103.950008)
		(end 256.985008 -104.142286)
		(width 0.0889)
		(layer "F.Cu")
		(net "M_D_MA<4>")
	)
	(segment
		(start 255.92913 -100.662486)
		(end 255.599692 -101.42347)
		(width 0.0889)
		(layer "F.Cu")
		(net "M_D_MA<4>")
	)
	(segment
		(start 256.985008 -104.142286)
		(end 256.985008 -116.159026)
		(width 0.1651)
		(layer "F.Cu")
		(net "M_D_MA<4>")
	)
	(segment
		(start 253.350014 -137.67054)
		(end 253.350522 -137.67054)
		(width 0.1651)
		(layer "F.Cu")
		(net "M_D_MA<4>")
	)
	(via
		(at 253.350014 -130.249168)
		(size 0.508)
		(drill 0.254)
		(layers "F.Cu" "B.Cu")
		(net "M_D_MA<4>")
	)
	(via
		(at 253.350014 -136.387078)
		(size 0.4572)
		(drill 0.2032)
		(layers "F.Cu" "B.Cu")
		(net "M_D_MA<4>")
	)
	(arc
		(start 255.58242 -101.453188)
		(mid 255.542317 -101.549206)
		(end 255.528318 -101.652324)
		(width 0.0889)
		(layer "F.Cu")
		(net "M_D_MA<4>")
	)
	(segment
		(start 253.350522 -128.276096)
		(end 253.350014 -128.276096)
		(width 0.1651)
		(layer "B.Cu")
		(net "M_D_MA<4>")
	)
	(segment
		(start 253.350014 -128.276096)
		(end 253.350014 -130.249168)
		(width 0.1651)
		(layer "B.Cu")
		(net "M_D_MA<4>")
	)
	(segment
		(start 253.7206 -131.1148)
		(end 254.034036 -131.428236)
		(width 0.14224)
		(layer "In9.Cu")
		(net "M_D_MA<4>")
	)
	(segment
		(start 253.350014 -135.752586)
		(end 253.350014 -136.387078)
		(width 0.14224)
		(layer "In9.Cu")
		(net "M_D_MA<4>")
	)
	(segment
		(start 254.034036 -131.428236)
		(end 254.034036 -133.940042)
		(width 0.14224)
		(layer "In9.Cu")
		(net "M_D_MA<4>")
	)
	(segment
		(start 253.7841 -135.3185)
		(end 253.350014 -135.752586)
		(width 0.14224)
		(layer "In9.Cu")
		(net "M_D_MA<4>")
	)
	(segment
		(start 253.350014 -130.249168)
		(end 253.7206 -130.619754)
		(width 0.14224)
		(layer "In9.Cu")
		(net "M_D_MA<4>")
	)
	(segment
		(start 253.7206 -130.619754)
		(end 253.7206 -131.1148)
		(width 0.14224)
		(layer "In9.Cu")
		(net "M_D_MA<4>")
	)
	(segment
		(start 253.7841 -134.189978)
		(end 253.7841 -135.3185)
		(width 0.14224)
		(layer "In9.Cu")
		(net "M_D_MA<4>")
	)
	(segment
		(start 254.034036 -133.940042)
		(end 253.7841 -134.189978)
		(width 0.14224)
		(layer "In9.Cu")
		(net "M_D_MA<4>")
	)
	(segment
		(start 254.200406 -133.0706)
		(end 254.199898 -133.076442)
		(width 0.1651)
		(layer "F.Cu")
		(net "M_D_MA<3>")
	)
	(segment
		(start 257.517138 -116.355876)
		(end 257.517138 -104.176322)
		(width 0.1651)
		(layer "F.Cu")
		(net "M_D_MA<3>")
	)
	(segment
		(start 253.912116 -130.122676)
		(end 253.65329 -129.86385)
		(width 0.1651)
		(layer "F.Cu")
		(net "M_D_MA<3>")
	)
	(segment
		(start 254.199898 -130.902456)
		(end 253.912116 -130.614674)
		(width 0.1651)
		(layer "F.Cu")
		(net "M_D_MA<3>")
	)
	(segment
		(start 253.65329 -129.86385)
		(end 253.65329 -129.269236)
		(width 0.1651)
		(layer "F.Cu")
		(net "M_D_MA<3>")
	)
	(segment
		(start 256.329434 -102.761034)
		(end 256.329434 -101.653848)
		(width 0.0889)
		(layer "F.Cu")
		(net "M_D_MA<3>")
	)
	(segment
		(start 253.713488 -120.159526)
		(end 257.517138 -116.355876)
		(width 0.1651)
		(layer "F.Cu")
		(net "M_D_MA<3>")
	)
	(segment
		(start 257.517138 -104.176322)
		(end 257.517138 -103.948738)
		(width 0.0889)
		(layer "F.Cu")
		(net "M_D_MA<3>")
	)
	(segment
		(start 254.199898 -133.076442)
		(end 254.199898 -134.371588)
		(width 0.1651)
		(layer "F.Cu")
		(net "M_D_MA<3>")
	)
	(segment
		(start 253.713488 -129.209038)
		(end 253.713488 -120.159526)
		(width 0.1651)
		(layer "F.Cu")
		(net "M_D_MA<3>")
	)
	(segment
		(start 256.280666 -101.461824)
		(end 256.27584 -101.453188)
		(width 0.0889)
		(layer "F.Cu")
		(net "M_D_MA<3>")
	)
	(segment
		(start 256.27584 -101.453188)
		(end 256.26949 -101.44252)
		(width 0.0889)
		(layer "F.Cu")
		(net "M_D_MA<3>")
	)
	(segment
		(start 253.65329 -129.269236)
		(end 253.713488 -129.209038)
		(width 0.1651)
		(layer "F.Cu")
		(net "M_D_MA<3>")
	)
	(segment
		(start 256.774696 -100.567236)
		(end 256.798826 -100.567236)
		(width 0.0889)
		(layer "F.Cu")
		(net "M_D_MA<3>")
	)
	(segment
		(start 253.912116 -130.614674)
		(end 253.912116 -130.122676)
		(width 0.1651)
		(layer "F.Cu")
		(net "M_D_MA<3>")
	)
	(segment
		(start 257.517138 -103.948738)
		(end 256.329434 -102.761034)
		(width 0.0889)
		(layer "F.Cu")
		(net "M_D_MA<3>")
	)
	(segment
		(start 257.13436 -100.367084)
		(end 257.64617 -99.67214)
		(width 0.0889)
		(layer "F.Cu")
		(net "M_D_MA<3>")
	)
	(via
		(at 254.199898 -134.371588)
		(size 0.4572)
		(drill 0.2032)
		(layers "F.Cu" "B.Cu")
		(net "M_D_MA<3>")
	)
	(via
		(at 254.199898 -130.902456)
		(size 0.508)
		(drill 0.254)
		(layers "F.Cu" "B.Cu")
		(net "M_D_MA<3>")
	)
	(arc
		(start 256.26949 -101.44252)
		(mid 256.275667 -100.862588)
		(end 256.774696 -100.567236)
		(width 0.0889)
		(layer "F.Cu")
		(net "M_D_MA<3>")
	)
	(arc
		(start 256.329434 -101.653848)
		(mid 256.31711 -101.554774)
		(end 256.280666 -101.461824)
		(width 0.0889)
		(layer "F.Cu")
		(net "M_D_MA<3>")
	)
	(arc
		(start 256.798826 -100.567236)
		(mid 256.992676 -100.510886)
		(end 257.13436 -100.367084)
		(width 0.0889)
		(layer "F.Cu")
		(net "M_D_MA<3>")
	)
	(segment
		(start 254.199898 -132.875782)
		(end 254.199898 -130.902456)
		(width 0.1651)
		(layer "B.Cu")
		(net "M_D_MA<3>")
	)
	(segment
		(start 254.200406 -132.876036)
		(end 254.199898 -132.875782)
		(width 0.1651)
		(layer "B.Cu")
		(net "M_D_MA<3>")
	)
	(segment
		(start 254.199898 -130.902456)
		(end 254.464312 -131.16687)
		(width 0.14224)
		(layer "In9.Cu")
		(net "M_D_MA<3>")
	)
	(segment
		(start 254.464312 -131.16687)
		(end 254.464312 -134.107174)
		(width 0.14224)
		(layer "In9.Cu")
		(net "M_D_MA<3>")
	)
	(segment
		(start 254.464312 -134.107174)
		(end 254.199898 -134.371588)
		(width 0.14224)
		(layer "In9.Cu")
		(net "M_D_MA<3>")
	)
	(segment
		(start 255.050036 -136.412478)
		(end 255.050036 -136.387078)
		(width 0.1651)
		(layer "F.Cu")
		(net "M_D_MA<2>")
	)
	(segment
		(start 254.850138 -123.005342)
		(end 254.850138 -123.929902)
		(width 0.1651)
		(layer "F.Cu")
		(net "M_D_MA<2>")
	)
	(segment
		(start 254.850138 -123.929902)
		(end 255.168908 -124.248672)
		(width 0.1651)
		(layer "F.Cu")
		(net "M_D_MA<2>")
	)
	(segment
		(start 254.99441 -128.718564)
		(end 254.99441 -130.249168)
		(width 0.1651)
		(layer "F.Cu")
		(net "M_D_MA<2>")
	)
	(segment
		(start 258.581398 -116.838476)
		(end 255.265174 -120.1547)
		(width 0.1651)
		(layer "F.Cu")
		(net "M_D_MA<2>")
	)
	(segment
		(start 256.78765 -101.15804)
		(end 256.78765 -102.33025)
		(width 0.0889)
		(layer "F.Cu")
		(net "M_D_MA<2>")
	)
	(segment
		(start 255.121664 -128.59131)
		(end 254.99441 -128.718564)
		(width 0.1651)
		(layer "F.Cu")
		(net "M_D_MA<2>")
	)
	(segment
		(start 255.05029 -137.67054)
		(end 255.049782 -137.67054)
		(width 0.1651)
		(layer "F.Cu")
		(net "M_D_MA<2>")
	)
	(segment
		(start 255.265174 -122.590306)
		(end 254.850138 -123.005342)
		(width 0.1651)
		(layer "F.Cu")
		(net "M_D_MA<2>")
	)
	(segment
		(start 256.78765 -102.33025)
		(end 258.581398 -104.123998)
		(width 0.0889)
		(layer "F.Cu")
		(net "M_D_MA<2>")
	)
	(segment
		(start 255.049782 -136.412732)
		(end 255.050036 -136.412478)
		(width 0.1651)
		(layer "F.Cu")
		(net "M_D_MA<2>")
	)
	(segment
		(start 255.168908 -124.248672)
		(end 255.168908 -125.295152)
		(width 0.1651)
		(layer "F.Cu")
		(net "M_D_MA<2>")
	)
	(segment
		(start 258.581398 -104.336596)
		(end 258.581398 -116.838476)
		(width 0.1651)
		(layer "F.Cu")
		(net "M_D_MA<2>")
	)
	(segment
		(start 258.581398 -104.123998)
		(end 258.581398 -104.336596)
		(width 0.0889)
		(layer "F.Cu")
		(net "M_D_MA<2>")
	)
	(segment
		(start 255.049782 -137.67054)
		(end 255.049782 -136.412732)
		(width 0.1651)
		(layer "F.Cu")
		(net "M_D_MA<2>")
	)
	(segment
		(start 254.850138 -126.670054)
		(end 255.121664 -126.94158)
		(width 0.1651)
		(layer "F.Cu")
		(net "M_D_MA<2>")
	)
	(segment
		(start 255.121664 -126.94158)
		(end 255.121664 -128.59131)
		(width 0.1651)
		(layer "F.Cu")
		(net "M_D_MA<2>")
	)
	(segment
		(start 254.850138 -125.613922)
		(end 254.850138 -126.670054)
		(width 0.1651)
		(layer "F.Cu")
		(net "M_D_MA<2>")
	)
	(segment
		(start 255.265174 -120.1547)
		(end 255.265174 -122.590306)
		(width 0.1651)
		(layer "F.Cu")
		(net "M_D_MA<2>")
	)
	(segment
		(start 255.168908 -125.295152)
		(end 254.850138 -125.613922)
		(width 0.1651)
		(layer "F.Cu")
		(net "M_D_MA<2>")
	)
	(via
		(at 254.99441 -130.249168)
		(size 0.508)
		(drill 0.254)
		(layers "F.Cu" "B.Cu")
		(net "M_D_MA<2>")
	)
	(via
		(at 255.050036 -136.387078)
		(size 0.4572)
		(drill 0.2032)
		(layers "F.Cu" "B.Cu")
		(net "M_D_MA<2>")
	)
	(segment
		(start 255.049782 -128.276096)
		(end 255.049782 -130.193796)
		(width 0.1651)
		(layer "B.Cu")
		(net "M_D_MA<2>")
	)
	(segment
		(start 255.05029 -128.276096)
		(end 255.049782 -128.276096)
		(width 0.1651)
		(layer "B.Cu")
		(net "M_D_MA<2>")
	)
	(segment
		(start 255.049782 -130.193796)
		(end 254.99441 -130.249168)
		(width 0.1651)
		(layer "B.Cu")
		(net "M_D_MA<2>")
	)
	(segment
		(start 255.717548 -130.91668)
		(end 255.050036 -130.249168)
		(width 0.14224)
		(layer "In9.Cu")
		(net "M_D_MA<2>")
	)
	(segment
		(start 255.050036 -130.249168)
		(end 254.99441 -130.249168)
		(width 0.14224)
		(layer "In9.Cu")
		(net "M_D_MA<2>")
	)
	(segment
		(start 255.464564 -134.763764)
		(end 255.464564 -134.077964)
		(width 0.14224)
		(layer "In9.Cu")
		(net "M_D_MA<2>")
	)
	(segment
		(start 255.717548 -133.82498)
		(end 255.717548 -130.91668)
		(width 0.14224)
		(layer "In9.Cu")
		(net "M_D_MA<2>")
	)
	(segment
		(start 255.050036 -136.387078)
		(end 255.049782 -136.386824)
		(width 0.14224)
		(layer "In9.Cu")
		(net "M_D_MA<2>")
	)
	(segment
		(start 255.464564 -134.077964)
		(end 255.717548 -133.82498)
		(width 0.14224)
		(layer "In9.Cu")
		(net "M_D_MA<2>")
	)
	(segment
		(start 255.049782 -136.386824)
		(end 255.049782 -135.178546)
		(width 0.14224)
		(layer "In9.Cu")
		(net "M_D_MA<2>")
	)
	(segment
		(start 255.049782 -135.178546)
		(end 255.464564 -134.763764)
		(width 0.14224)
		(layer "In9.Cu")
		(net "M_D_MA<2>")
	)
	(segment
		(start 255.05029 -133.0706)
		(end 255.049782 -133.076442)
		(width 0.1651)
		(layer "F.Cu")
		(net "M_D_MA<1>")
	)
	(segment
		(start 255.049782 -133.076442)
		(end 255.049782 -134.371588)
		(width 0.1651)
		(layer "F.Cu")
		(net "M_D_MA<1>")
	)
	(segment
		(start 254.57531 -129.115058)
		(end 254.57531 -129.92989)
		(width 0.1651)
		(layer "F.Cu")
		(net "M_D_MA<1>")
	)
	(segment
		(start 254.330962 -128.234948)
		(end 254.330962 -128.87071)
		(width 0.1651)
		(layer "F.Cu")
		(net "M_D_MA<1>")
	)
	(segment
		(start 256.5654 -101.714808)
		(end 256.5654 -102.5398)
		(width 0.0889)
		(layer "F.Cu")
		(net "M_D_MA<1>")
	)
	(segment
		(start 254.46482 -130.04038)
		(end 254.46482 -130.468116)
		(width 0.1651)
		(layer "F.Cu")
		(net "M_D_MA<1>")
	)
	(segment
		(start 256.5654 -102.5398)
		(end 258.049268 -104.023668)
		(width 0.0889)
		(layer "F.Cu")
		(net "M_D_MA<1>")
	)
	(segment
		(start 258.049268 -104.271826)
		(end 258.049268 -116.569236)
		(width 0.1651)
		(layer "F.Cu")
		(net "M_D_MA<1>")
	)
	(segment
		(start 254.323342 -126.93523)
		(end 254.6858 -127.297688)
		(width 0.1651)
		(layer "F.Cu")
		(net "M_D_MA<1>")
	)
	(segment
		(start 254.57531 -129.92989)
		(end 254.46482 -130.04038)
		(width 0.1651)
		(layer "F.Cu")
		(net "M_D_MA<1>")
	)
	(segment
		(start 256.800604 -100.75799)
		(end 256.772664 -100.75799)
		(width 0.0889)
		(layer "F.Cu")
		(net "M_D_MA<1>")
	)
	(segment
		(start 254.706628 -131.26847)
		(end 255.050036 -131.611878)
		(width 0.1651)
		(layer "F.Cu")
		(net "M_D_MA<1>")
	)
	(segment
		(start 254.323342 -120.295162)
		(end 254.323342 -126.93523)
		(width 0.1651)
		(layer "F.Cu")
		(net "M_D_MA<1>")
	)
	(segment
		(start 254.330962 -128.87071)
		(end 254.57531 -129.115058)
		(width 0.1651)
		(layer "F.Cu")
		(net "M_D_MA<1>")
	)
	(segment
		(start 254.46482 -130.468116)
		(end 254.706628 -130.709924)
		(width 0.1651)
		(layer "F.Cu")
		(net "M_D_MA<1>")
	)
	(segment
		(start 254.706628 -130.709924)
		(end 254.706628 -131.26847)
		(width 0.1651)
		(layer "F.Cu")
		(net "M_D_MA<1>")
	)
	(segment
		(start 254.6858 -127.297688)
		(end 254.6858 -127.88011)
		(width 0.1651)
		(layer "F.Cu")
		(net "M_D_MA<1>")
	)
	(segment
		(start 257.64617 -100.662486)
		(end 256.860802 -100.753672)
		(width 0.0889)
		(layer "F.Cu")
		(net "M_D_MA<1>")
	)
	(segment
		(start 254.6858 -127.88011)
		(end 254.330962 -128.234948)
		(width 0.1651)
		(layer "F.Cu")
		(net "M_D_MA<1>")
	)
	(segment
		(start 258.049268 -104.023668)
		(end 258.049268 -104.271826)
		(width 0.0889)
		(layer "F.Cu")
		(net "M_D_MA<1>")
	)
	(segment
		(start 258.049268 -116.569236)
		(end 254.323342 -120.295162)
		(width 0.1651)
		(layer "F.Cu")
		(net "M_D_MA<1>")
	)
	(via
		(at 255.049782 -134.371588)
		(size 0.4572)
		(drill 0.2032)
		(layers "F.Cu" "B.Cu")
		(net "M_D_MA<1>")
	)
	(via
		(at 255.050036 -131.611878)
		(size 0.508)
		(drill 0.254)
		(layers "F.Cu" "B.Cu")
		(net "M_D_MA<1>")
	)
	(arc
		(start 256.860802 -100.753672)
		(mid 256.830758 -100.756603)
		(end 256.800604 -100.75799)
		(width 0.0889)
		(layer "F.Cu")
		(net "M_D_MA<1>")
	)
	(arc
		(start 256.436114 -101.349302)
		(mid 256.532151 -101.520953)
		(end 256.5654 -101.714808)
		(width 0.0889)
		(layer "F.Cu")
		(net "M_D_MA<1>")
	)
	(arc
		(start 256.772664 -100.75799)
		(mid 256.439746 -100.959981)
		(end 256.436114 -101.349302)
		(width 0.0889)
		(layer "F.Cu")
		(net "M_D_MA<1>")
	)
	(segment
		(start 255.049782 -131.612132)
		(end 255.050036 -131.611878)
		(width 0.1651)
		(layer "B.Cu")
		(net "M_D_MA<1>")
	)
	(segment
		(start 255.049782 -132.875782)
		(end 255.049782 -131.612132)
		(width 0.1651)
		(layer "B.Cu")
		(net "M_D_MA<1>")
	)
	(segment
		(start 255.05029 -132.876036)
		(end 255.049782 -132.875782)
		(width 0.1651)
		(layer "B.Cu")
		(net "M_D_MA<1>")
	)
	(segment
		(start 255.085342 -133.511036)
		(end 254.951992 -133.644386)
		(width 0.14224)
		(layer "In9.Cu")
		(net "M_D_MA<1>")
	)
	(segment
		(start 254.902208 -131.759706)
		(end 254.902208 -132.382514)
		(width 0.14224)
		(layer "In9.Cu")
		(net "M_D_MA<1>")
	)
	(segment
		(start 254.951992 -133.644386)
		(end 254.951992 -134.273798)
		(width 0.14224)
		(layer "In9.Cu")
		(net "M_D_MA<1>")
	)
	(segment
		(start 254.902208 -132.382514)
		(end 255.085342 -132.565648)
		(width 0.14224)
		(layer "In9.Cu")
		(net "M_D_MA<1>")
	)
	(segment
		(start 255.050036 -131.611878)
		(end 254.902208 -131.759706)
		(width 0.14224)
		(layer "In9.Cu")
		(net "M_D_MA<1>")
	)
	(segment
		(start 255.085342 -132.565648)
		(end 255.085342 -133.511036)
		(width 0.14224)
		(layer "In9.Cu")
		(net "M_D_MA<1>")
	)
	(segment
		(start 254.951992 -134.273798)
		(end 255.049782 -134.371588)
		(width 0.14224)
		(layer "In9.Cu")
		(net "M_D_MA<1>")
	)
	(segment
		(start 275.4503 -137.67054)
		(end 275.449792 -137.67054)
		(width 0.1651)
		(layer "F.Cu")
		(net "M_D_MA<17>")
	)
	(segment
		(start 275.449792 -137.67054)
		(end 275.449792 -136.387586)
		(width 0.1651)
		(layer "F.Cu")
		(net "M_D_MA<17>")
	)
	(segment
		(start 275.449792 -136.387586)
		(end 275.4503 -136.387078)
		(width 0.1651)
		(layer "F.Cu")
		(net "M_D_MA<17>")
	)
	(segment
		(start 267.089636 -99.17684)
		(end 266.518136 -99.17684)
		(width 0.1651)
		(layer "F.Cu")
		(net "M_D_MA<17>")
	)
	(via
		(at 275.4503 -136.387078)
		(size 0.4572)
		(drill 0.2032)
		(layers "F.Cu" "B.Cu")
		(net "M_D_MA<17>")
	)
	(via
		(at 275.449792 -130.249168)
		(size 0.508)
		(drill 0.254)
		(layers "F.Cu" "B.Cu")
		(net "M_D_MA<17>")
	)
	(via
		(at 266.518136 -99.17684)
		(size 0.508)
		(drill 0.254)
		(layers "F.Cu" "B.Cu")
		(net "M_D_MA<17>")
	)
	(segment
		(start 275.449792 -128.276096)
		(end 275.449792 -130.249168)
		(width 0.1651)
		(layer "B.Cu")
		(net "M_D_MA<17>")
	)
	(segment
		(start 275.4503 -128.276096)
		(end 275.449792 -128.276096)
		(width 0.1651)
		(layer "B.Cu")
		(net "M_D_MA<17>")
	)
	(segment
		(start 276.216618 -131.836414)
		(end 276.062186 -131.990846)
		(width 0.14224)
		(layer "In11.Cu")
		(net "M_D_MA<17>")
	)
	(segment
		(start 275.7678 -133.195568)
		(end 275.61286 -133.350508)
		(width 0.14224)
		(layer "In11.Cu")
		(net "M_D_MA<17>")
	)
	(segment
		(start 276.216618 -131.566158)
		(end 276.216618 -131.836414)
		(width 0.14224)
		(layer "In11.Cu")
		(net "M_D_MA<17>")
	)
	(segment
		(start 266.954 -99.612704)
		(end 266.954 -100.0506)
		(width 0.0889)
		(layer "In11.Cu")
		(net "M_D_MA<17>")
	)
	(segment
		(start 267.5382 -100.1522)
		(end 268.986 -101.6)
		(width 0.0889)
		(layer "In11.Cu")
		(net "M_D_MA<17>")
	)
	(segment
		(start 275.61286 -133.81609)
		(end 275.865082 -134.068312)
		(width 0.14224)
		(layer "In11.Cu")
		(net "M_D_MA<17>")
	)
	(segment
		(start 275.662898 -130.654298)
		(end 275.662898 -131.012438)
		(width 0.14224)
		(layer "In11.Cu")
		(net "M_D_MA<17>")
	)
	(segment
		(start 273.419824 -124.473716)
		(end 273.600164 -124.473462)
		(width 0.14224)
		(layer "In11.Cu")
		(net "M_D_MA<17>")
	)
	(segment
		(start 276.186392 -133.03377)
		(end 276.024594 -133.195568)
		(width 0.14224)
		(layer "In11.Cu")
		(net "M_D_MA<17>")
	)
	(segment
		(start 275.8186 -128.511808)
		(end 275.8186 -129.88036)
		(width 0.14224)
		(layer "In11.Cu")
		(net "M_D_MA<17>")
	)
	(segment
		(start 274.228306 -124.814584)
		(end 274.228306 -125.32995)
		(width 0.14224)
		(layer "In11.Cu")
		(net "M_D_MA<17>")
	)
	(segment
		(start 276.020784 -126.607062)
		(end 276.020784 -128.309624)
		(width 0.14224)
		(layer "In11.Cu")
		(net "M_D_MA<17>")
	)
	(segment
		(start 275.78558 -132.634228)
		(end 276.03831 -132.634228)
		(width 0.14224)
		(layer "In11.Cu")
		(net "M_D_MA<17>")
	)
	(segment
		(start 274.228306 -125.32995)
		(end 274.780756 -125.8824)
		(width 0.14224)
		(layer "In11.Cu")
		(net "M_D_MA<17>")
	)
	(segment
		(start 275.449792 -130.249168)
		(end 275.449792 -130.441192)
		(width 0.14224)
		(layer "In11.Cu")
		(net "M_D_MA<17>")
	)
	(segment
		(start 273.078702 -123.66498)
		(end 273.078702 -124.132594)
		(width 0.14224)
		(layer "In11.Cu")
		(net "M_D_MA<17>")
	)
	(segment
		(start 268.986 -101.6)
		(end 268.986 -101.994462)
		(width 0.0889)
		(layer "In11.Cu")
		(net "M_D_MA<17>")
	)
	(segment
		(start 276.020784 -128.309624)
		(end 275.8186 -128.511808)
		(width 0.14224)
		(layer "In11.Cu")
		(net "M_D_MA<17>")
	)
	(segment
		(start 271.300956 -122.174254)
		(end 271.587976 -122.174254)
		(width 0.14224)
		(layer "In11.Cu")
		(net "M_D_MA<17>")
	)
	(segment
		(start 275.623528 -132.472176)
		(end 275.78558 -132.634228)
		(width 0.14224)
		(layer "In11.Cu")
		(net "M_D_MA<17>")
	)
	(segment
		(start 276.03831 -132.634228)
		(end 276.186392 -132.78231)
		(width 0.14224)
		(layer "In11.Cu")
		(net "M_D_MA<17>")
	)
	(segment
		(start 266.518136 -99.17684)
		(end 266.954 -99.612704)
		(width 0.0889)
		(layer "In11.Cu")
		(net "M_D_MA<17>")
	)
	(segment
		(start 272.377154 -123.323858)
		(end 272.73758 -123.323858)
		(width 0.14224)
		(layer "In11.Cu")
		(net "M_D_MA<17>")
	)
	(segment
		(start 276.062186 -131.990846)
		(end 275.779992 -131.990846)
		(width 0.14224)
		(layer "In11.Cu")
		(net "M_D_MA<17>")
	)
	(segment
		(start 266.954 -100.0506)
		(end 267.0556 -100.1522)
		(width 0.0889)
		(layer "In11.Cu")
		(net "M_D_MA<17>")
	)
	(segment
		(start 275.779992 -131.990846)
		(end 275.623528 -132.14731)
		(width 0.14224)
		(layer "In11.Cu")
		(net "M_D_MA<17>")
	)
	(segment
		(start 276.186392 -132.78231)
		(end 276.186392 -133.03377)
		(width 0.14224)
		(layer "In11.Cu")
		(net "M_D_MA<17>")
	)
	(segment
		(start 275.623528 -132.14731)
		(end 275.623528 -132.472176)
		(width 0.14224)
		(layer "In11.Cu")
		(net "M_D_MA<17>")
	)
	(segment
		(start 275.296122 -125.8824)
		(end 276.020784 -126.607062)
		(width 0.14224)
		(layer "In11.Cu")
		(net "M_D_MA<17>")
	)
	(segment
		(start 271.120616 -122.174508)
		(end 271.300956 -122.174254)
		(width 0.14224)
		(layer "In11.Cu")
		(net "M_D_MA<17>")
	)
	(segment
		(start 268.986 -119.572278)
		(end 269.62989 -120.216168)
		(width 0.14224)
		(layer "In11.Cu")
		(net "M_D_MA<17>")
	)
	(segment
		(start 276.024594 -133.195568)
		(end 275.7678 -133.195568)
		(width 0.14224)
		(layer "In11.Cu")
		(net "M_D_MA<17>")
	)
	(segment
		(start 269.62989 -120.216168)
		(end 269.62989 -120.683782)
		(width 0.14224)
		(layer "In11.Cu")
		(net "M_D_MA<17>")
	)
	(segment
		(start 269.62989 -120.683782)
		(end 269.971012 -121.024904)
		(width 0.14224)
		(layer "In11.Cu")
		(net "M_D_MA<17>")
	)
	(segment
		(start 273.600164 -124.473462)
		(end 273.887184 -124.473462)
		(width 0.14224)
		(layer "In11.Cu")
		(net "M_D_MA<17>")
	)
	(segment
		(start 270.779494 -121.365772)
		(end 270.779494 -121.833386)
		(width 0.14224)
		(layer "In11.Cu")
		(net "M_D_MA<17>")
	)
	(segment
		(start 272.73758 -123.323858)
		(end 273.078702 -123.66498)
		(width 0.14224)
		(layer "In11.Cu")
		(net "M_D_MA<17>")
	)
	(segment
		(start 270.438372 -121.02465)
		(end 270.779494 -121.365772)
		(width 0.14224)
		(layer "In11.Cu")
		(net "M_D_MA<17>")
	)
	(segment
		(start 269.971012 -121.024904)
		(end 270.151352 -121.02465)
		(width 0.14224)
		(layer "In11.Cu")
		(net "M_D_MA<17>")
	)
	(segment
		(start 275.61286 -133.350508)
		(end 275.61286 -133.81609)
		(width 0.14224)
		(layer "In11.Cu")
		(net "M_D_MA<17>")
	)
	(segment
		(start 267.0556 -100.1522)
		(end 267.5382 -100.1522)
		(width 0.0889)
		(layer "In11.Cu")
		(net "M_D_MA<17>")
	)
	(segment
		(start 273.887184 -124.473462)
		(end 274.228306 -124.814584)
		(width 0.14224)
		(layer "In11.Cu")
		(net "M_D_MA<17>")
	)
	(segment
		(start 275.449792 -130.441192)
		(end 275.662898 -130.654298)
		(width 0.14224)
		(layer "In11.Cu")
		(net "M_D_MA<17>")
	)
	(segment
		(start 270.151352 -121.02465)
		(end 270.438372 -121.02465)
		(width 0.14224)
		(layer "In11.Cu")
		(net "M_D_MA<17>")
	)
	(segment
		(start 273.078702 -124.132594)
		(end 273.419824 -124.473716)
		(width 0.14224)
		(layer "In11.Cu")
		(net "M_D_MA<17>")
	)
	(segment
		(start 268.986 -101.994462)
		(end 268.986 -119.572278)
		(width 0.14224)
		(layer "In11.Cu")
		(net "M_D_MA<17>")
	)
	(segment
		(start 275.662898 -131.012438)
		(end 276.216618 -131.566158)
		(width 0.14224)
		(layer "In11.Cu")
		(net "M_D_MA<17>")
	)
	(segment
		(start 275.8186 -129.88036)
		(end 275.449792 -130.249168)
		(width 0.14224)
		(layer "In11.Cu")
		(net "M_D_MA<17>")
	)
	(segment
		(start 274.780756 -125.8824)
		(end 275.296122 -125.8824)
		(width 0.14224)
		(layer "In11.Cu")
		(net "M_D_MA<17>")
	)
	(segment
		(start 270.779494 -121.833386)
		(end 271.120616 -122.174508)
		(width 0.14224)
		(layer "In11.Cu")
		(net "M_D_MA<17>")
	)
	(segment
		(start 275.865082 -134.068312)
		(end 275.865082 -135.972296)
		(width 0.14224)
		(layer "In11.Cu")
		(net "M_D_MA<17>")
	)
	(segment
		(start 271.929098 -122.515376)
		(end 271.929098 -122.875802)
		(width 0.14224)
		(layer "In11.Cu")
		(net "M_D_MA<17>")
	)
	(segment
		(start 275.865082 -135.972296)
		(end 275.4503 -136.387078)
		(width 0.14224)
		(layer "In11.Cu")
		(net "M_D_MA<17>")
	)
	(segment
		(start 271.587976 -122.174254)
		(end 271.929098 -122.515376)
		(width 0.14224)
		(layer "In11.Cu")
		(net "M_D_MA<17>")
	)
	(segment
		(start 271.929098 -122.875802)
		(end 272.377154 -123.323858)
		(width 0.14224)
		(layer "In11.Cu")
		(net "M_D_MA<17>")
	)
	(segment
		(start 268.649704 -131.611878)
		(end 268.649704 -131.083304)
		(width 0.1651)
		(layer "F.Cu")
		(net "M_D_MA<16>")
	)
	(segment
		(start 267.335 -129.116836)
		(end 265.227816 -127.009652)
		(width 0.1651)
		(layer "F.Cu")
		(net "M_D_MA<16>")
	)
	(segment
		(start 262.206486 -102.161086)
		(end 262.206486 -101.653594)
		(width 0.0889)
		(layer "F.Cu")
		(net "M_D_MA<16>")
	)
	(segment
		(start 264.07745 -125.693678)
		(end 264.07745 -104.375458)
		(width 0.1651)
		(layer "F.Cu")
		(net "M_D_MA<16>")
	)
	(segment
		(start 265.227816 -126.844044)
		(end 264.07745 -125.693678)
		(width 0.1651)
		(layer "F.Cu")
		(net "M_D_MA<16>")
	)
	(segment
		(start 264.07745 -104.375458)
		(end 264.07745 -104.03205)
		(width 0.0889)
		(layer "F.Cu")
		(net "M_D_MA<16>")
	)
	(segment
		(start 267.335 -129.7686)
		(end 267.335 -129.116836)
		(width 0.1651)
		(layer "F.Cu")
		(net "M_D_MA<16>")
	)
	(segment
		(start 264.07745 -104.03205)
		(end 262.206486 -102.161086)
		(width 0.0889)
		(layer "F.Cu")
		(net "M_D_MA<16>")
	)
	(segment
		(start 268.649958 -133.076442)
		(end 268.649958 -134.367778)
		(width 0.1651)
		(layer "F.Cu")
		(net "M_D_MA<16>")
	)
	(segment
		(start 262.28548 -99.967288)
		(end 262.27913 -99.95662)
		(width 0.0889)
		(layer "F.Cu")
		(net "M_D_MA<16>")
	)
	(segment
		(start 265.227816 -127.009652)
		(end 265.227816 -126.844044)
		(width 0.1651)
		(layer "F.Cu")
		(net "M_D_MA<16>")
	)
	(segment
		(start 262.28548 -101.357938)
		(end 262.290306 -101.349302)
		(width 0.0889)
		(layer "F.Cu")
		(net "M_D_MA<16>")
	)
	(segment
		(start 268.650466 -133.0706)
		(end 268.649958 -133.076442)
		(width 0.1651)
		(layer "F.Cu")
		(net "M_D_MA<16>")
	)
	(segment
		(start 262.27913 -99.95662)
		(end 261.93877 -99.17684)
		(width 0.0889)
		(layer "F.Cu")
		(net "M_D_MA<16>")
	)
	(segment
		(start 268.649704 -131.083304)
		(end 267.335 -129.7686)
		(width 0.1651)
		(layer "F.Cu")
		(net "M_D_MA<16>")
	)
	(via
		(at 268.649704 -131.611878)
		(size 0.508)
		(drill 0.254)
		(layers "F.Cu" "B.Cu")
		(net "M_D_MA<16>")
	)
	(via
		(at 268.649958 -134.367778)
		(size 0.508)
		(drill 0.254)
		(layers "F.Cu" "B.Cu")
		(net "M_D_MA<16>")
	)
	(arc
		(start 262.28548 -100.367084)
		(mid 262.338979 -100.167186)
		(end 262.28548 -99.967288)
		(width 0.0889)
		(layer "F.Cu")
		(net "M_D_MA<16>")
	)
	(arc
		(start 262.28548 -100.957888)
		(mid 262.206349 -100.662486)
		(end 262.28548 -100.367084)
		(width 0.0889)
		(layer "F.Cu")
		(net "M_D_MA<16>")
	)
	(arc
		(start 262.290306 -101.349302)
		(mid 262.339061 -101.15295)
		(end 262.28548 -100.957888)
		(width 0.0889)
		(layer "F.Cu")
		(net "M_D_MA<16>")
	)
	(arc
		(start 262.206486 -101.653594)
		(mid 262.226513 -101.500565)
		(end 262.28548 -101.357938)
		(width 0.0889)
		(layer "F.Cu")
		(net "M_D_MA<16>")
	)
	(segment
		(start 268.649958 -132.875782)
		(end 268.649958 -131.612132)
		(width 0.1651)
		(layer "B.Cu")
		(net "M_D_MA<16>")
	)
	(segment
		(start 268.650466 -132.876036)
		(end 268.649958 -132.875782)
		(width 0.1651)
		(layer "B.Cu")
		(net "M_D_MA<16>")
	)
	(segment
		(start 268.649958 -131.612132)
		(end 268.649704 -131.611878)
		(width 0.1651)
		(layer "B.Cu")
		(net "M_D_MA<16>")
	)
	(segment
		(start 269.244572 -132.674106)
		(end 269.399512 -132.519166)
		(width 0.14224)
		(layer "In9.Cu")
		(net "M_D_MA<16>")
	)
	(segment
		(start 269.90167 -133.235446)
		(end 268.897354 -133.235446)
		(width 0.14224)
		(layer "In9.Cu")
		(net "M_D_MA<16>")
	)
	(segment
		(start 268.804644 -133.796786)
		(end 269.885922 -133.796786)
		(width 0.14224)
		(layer "In9.Cu")
		(net "M_D_MA<16>")
	)
	(segment
		(start 268.889734 -132.674106)
		(end 269.244572 -132.674106)
		(width 0.14224)
		(layer "In9.Cu")
		(net "M_D_MA<16>")
	)
	(segment
		(start 270.048736 -133.382512)
		(end 269.90167 -133.235446)
		(width 0.14224)
		(layer "In9.Cu")
		(net "M_D_MA<16>")
	)
	(segment
		(start 269.885922 -133.796786)
		(end 270.048736 -133.633972)
		(width 0.14224)
		(layer "In9.Cu")
		(net "M_D_MA<16>")
	)
	(segment
		(start 268.804644 -132.112766)
		(end 268.649704 -131.957826)
		(width 0.14224)
		(layer "In9.Cu")
		(net "M_D_MA<16>")
	)
	(segment
		(start 269.399512 -132.267706)
		(end 269.244572 -132.112766)
		(width 0.14224)
		(layer "In9.Cu")
		(net "M_D_MA<16>")
	)
	(segment
		(start 268.738604 -133.076696)
		(end 268.738604 -132.825236)
		(width 0.14224)
		(layer "In9.Cu")
		(net "M_D_MA<16>")
	)
	(segment
		(start 270.048736 -133.633972)
		(end 270.048736 -133.382512)
		(width 0.14224)
		(layer "In9.Cu")
		(net "M_D_MA<16>")
	)
	(segment
		(start 268.649704 -133.951726)
		(end 268.804644 -133.796786)
		(width 0.14224)
		(layer "In9.Cu")
		(net "M_D_MA<16>")
	)
	(segment
		(start 268.649704 -131.957826)
		(end 268.649704 -131.611878)
		(width 0.14224)
		(layer "In9.Cu")
		(net "M_D_MA<16>")
	)
	(segment
		(start 268.649958 -134.367778)
		(end 268.649704 -134.367524)
		(width 0.14224)
		(layer "In9.Cu")
		(net "M_D_MA<16>")
	)
	(segment
		(start 268.897354 -133.235446)
		(end 268.738604 -133.076696)
		(width 0.14224)
		(layer "In9.Cu")
		(net "M_D_MA<16>")
	)
	(segment
		(start 269.399512 -132.519166)
		(end 269.399512 -132.267706)
		(width 0.14224)
		(layer "In9.Cu")
		(net "M_D_MA<16>")
	)
	(segment
		(start 268.738604 -132.825236)
		(end 268.889734 -132.674106)
		(width 0.14224)
		(layer "In9.Cu")
		(net "M_D_MA<16>")
	)
	(segment
		(start 268.649704 -134.367524)
		(end 268.649704 -133.951726)
		(width 0.14224)
		(layer "In9.Cu")
		(net "M_D_MA<16>")
	)
	(segment
		(start 269.244572 -132.112766)
		(end 268.804644 -132.112766)
		(width 0.14224)
		(layer "In9.Cu")
		(net "M_D_MA<16>")
	)
	(segment
		(start 264.51433 -97.690686)
		(end 263.94283 -97.690686)
		(width 0.1651)
		(layer "F.Cu")
		(net "M_D_MA<15>")
	)
	(segment
		(start 272.050002 -133.076442)
		(end 272.050002 -134.371334)
		(width 0.1651)
		(layer "F.Cu")
		(net "M_D_MA<15>")
	)
	(segment
		(start 272.050002 -134.371334)
		(end 272.050256 -134.371588)
		(width 0.1651)
		(layer "F.Cu")
		(net "M_D_MA<15>")
	)
	(segment
		(start 272.05051 -133.0706)
		(end 272.050002 -133.076442)
		(width 0.1651)
		(layer "F.Cu")
		(net "M_D_MA<15>")
	)
	(via
		(at 272.049748 -131.611878)
		(size 0.508)
		(drill 0.254)
		(layers "F.Cu" "B.Cu")
		(net "M_D_MA<15>")
	)
	(via
		(at 272.050256 -134.371588)
		(size 0.4572)
		(drill 0.2032)
		(layers "F.Cu" "B.Cu")
		(net "M_D_MA<15>")
	)
	(via
		(at 263.94283 -97.690686)
		(size 0.508)
		(drill 0.254)
		(layers "F.Cu" "B.Cu")
		(net "M_D_MA<15>")
	)
	(segment
		(start 272.05051 -132.876036)
		(end 272.050002 -132.875782)
		(width 0.1651)
		(layer "B.Cu")
		(net "M_D_MA<15>")
	)
	(segment
		(start 272.050002 -132.875782)
		(end 272.050002 -131.612132)
		(width 0.1651)
		(layer "B.Cu")
		(net "M_D_MA<15>")
	)
	(segment
		(start 272.050002 -131.612132)
		(end 272.049748 -131.611878)
		(width 0.1651)
		(layer "B.Cu")
		(net "M_D_MA<15>")
	)
	(segment
		(start 263.94283 -98.10877)
		(end 263.525 -98.5266)
		(width 0.0889)
		(layer "In11.Cu")
		(net "M_D_MA<15>")
	)
	(segment
		(start 271.849596 -126.806198)
		(end 271.849596 -129.380996)
		(width 0.14224)
		(layer "In11.Cu")
		(net "M_D_MA<15>")
	)
	(segment
		(start 266.3063 -121.262902)
		(end 271.849596 -126.806198)
		(width 0.14224)
		(layer "In11.Cu")
		(net "M_D_MA<15>")
	)
	(segment
		(start 272.494248 -130.552952)
		(end 272.049748 -130.997452)
		(width 0.14224)
		(layer "In11.Cu")
		(net "M_D_MA<15>")
	)
	(segment
		(start 272.529046 -132.44195)
		(end 272.877026 -132.78993)
		(width 0.14224)
		(layer "In11.Cu")
		(net "M_D_MA<15>")
	)
	(segment
		(start 272.627344 -133.571996)
		(end 272.320766 -133.571996)
		(width 0.14224)
		(layer "In11.Cu")
		(net "M_D_MA<15>")
	)
	(segment
		(start 271.871948 -132.44195)
		(end 272.529046 -132.44195)
		(width 0.14224)
		(layer "In11.Cu")
		(net "M_D_MA<15>")
	)
	(segment
		(start 263.525 -98.8314)
		(end 264.7188 -100.0252)
		(width 0.0889)
		(layer "In11.Cu")
		(net "M_D_MA<15>")
	)
	(segment
		(start 272.00352 -133.25475)
		(end 271.71142 -133.25475)
		(width 0.14224)
		(layer "In11.Cu")
		(net "M_D_MA<15>")
	)
	(segment
		(start 271.43456 -133.755892)
		(end 272.050256 -134.371588)
		(width 0.14224)
		(layer "In11.Cu")
		(net "M_D_MA<15>")
	)
	(segment
		(start 272.049748 -130.997452)
		(end 272.049748 -131.611878)
		(width 0.14224)
		(layer "In11.Cu")
		(net "M_D_MA<15>")
	)
	(segment
		(start 272.049748 -131.611878)
		(end 271.831054 -131.611878)
		(width 0.14224)
		(layer "In11.Cu")
		(net "M_D_MA<15>")
	)
	(segment
		(start 271.71142 -133.25475)
		(end 271.43456 -133.53161)
		(width 0.14224)
		(layer "In11.Cu")
		(net "M_D_MA<15>")
	)
	(segment
		(start 271.61998 -132.189982)
		(end 271.871948 -132.44195)
		(width 0.14224)
		(layer "In11.Cu")
		(net "M_D_MA<15>")
	)
	(segment
		(start 271.43456 -133.53161)
		(end 271.43456 -133.755892)
		(width 0.14224)
		(layer "In11.Cu")
		(net "M_D_MA<15>")
	)
	(segment
		(start 265.1506 -101.432868)
		(end 265.1506 -102.6414)
		(width 0.14224)
		(layer "In11.Cu")
		(net "M_D_MA<15>")
	)
	(segment
		(start 264.7188 -101.001068)
		(end 265.1506 -101.432868)
		(width 0.14224)
		(layer "In11.Cu")
		(net "M_D_MA<15>")
	)
	(segment
		(start 266.3063 -103.7971)
		(end 266.3063 -121.262902)
		(width 0.14224)
		(layer "In11.Cu")
		(net "M_D_MA<15>")
	)
	(segment
		(start 271.831054 -131.611878)
		(end 271.61998 -131.822952)
		(width 0.14224)
		(layer "In11.Cu")
		(net "M_D_MA<15>")
	)
	(segment
		(start 271.61998 -131.822952)
		(end 271.61998 -132.189982)
		(width 0.14224)
		(layer "In11.Cu")
		(net "M_D_MA<15>")
	)
	(segment
		(start 271.849596 -129.380996)
		(end 272.494248 -130.025648)
		(width 0.14224)
		(layer "In11.Cu")
		(net "M_D_MA<15>")
	)
	(segment
		(start 272.320766 -133.571996)
		(end 272.00352 -133.25475)
		(width 0.14224)
		(layer "In11.Cu")
		(net "M_D_MA<15>")
	)
	(segment
		(start 263.525 -98.5266)
		(end 263.525 -98.8314)
		(width 0.0889)
		(layer "In11.Cu")
		(net "M_D_MA<15>")
	)
	(segment
		(start 272.494248 -130.025648)
		(end 272.494248 -130.552952)
		(width 0.14224)
		(layer "In11.Cu")
		(net "M_D_MA<15>")
	)
	(segment
		(start 263.94283 -97.690686)
		(end 263.94283 -98.10877)
		(width 0.0889)
		(layer "In11.Cu")
		(net "M_D_MA<15>")
	)
	(segment
		(start 264.7188 -100.0252)
		(end 264.7188 -101.001068)
		(width 0.14224)
		(layer "In11.Cu")
		(net "M_D_MA<15>")
	)
	(segment
		(start 272.877026 -133.322314)
		(end 272.627344 -133.571996)
		(width 0.14224)
		(layer "In11.Cu")
		(net "M_D_MA<15>")
	)
	(segment
		(start 265.1506 -102.6414)
		(end 266.3063 -103.7971)
		(width 0.14224)
		(layer "In11.Cu")
		(net "M_D_MA<15>")
	)
	(segment
		(start 272.877026 -132.78993)
		(end 272.877026 -133.322314)
		(width 0.14224)
		(layer "In11.Cu")
		(net "M_D_MA<15>")
	)
	(segment
		(start 270.34998 -136.387332)
		(end 270.350234 -136.387078)
		(width 0.1651)
		(layer "F.Cu")
		(net "M_D_MA<14>")
	)
	(segment
		(start 264.61085 -104.610662)
		(end 264.61085 -104.210866)
		(width 0.0889)
		(layer "F.Cu")
		(net "M_D_MA<14>")
	)
	(segment
		(start 264.61085 -104.210866)
		(end 262.475472 -102.075488)
		(width 0.0889)
		(layer "F.Cu")
		(net "M_D_MA<14>")
	)
	(segment
		(start 265.871198 -126.746254)
		(end 266.08151 -126.535942)
		(width 0.1651)
		(layer "F.Cu")
		(net "M_D_MA<14>")
	)
	(segment
		(start 262.475472 -102.075488)
		(end 262.39724 -101.652832)
		(width 0.0889)
		(layer "F.Cu")
		(net "M_D_MA<14>")
	)
	(segment
		(start 270.350488 -137.67054)
		(end 270.34998 -137.67054)
		(width 0.1651)
		(layer "F.Cu")
		(net "M_D_MA<14>")
	)
	(segment
		(start 265.523472 -125.63856)
		(end 265.173968 -125.63856)
		(width 0.1651)
		(layer "F.Cu")
		(net "M_D_MA<14>")
	)
	(segment
		(start 265.871198 -126.979934)
		(end 265.871198 -126.746254)
		(width 0.1651)
		(layer "F.Cu")
		(net "M_D_MA<14>")
	)
	(segment
		(start 265.173968 -125.63856)
		(end 264.675112 -125.139704)
		(width 0.1651)
		(layer "F.Cu")
		(net "M_D_MA<14>")
	)
	(segment
		(start 270.349726 -130.249168)
		(end 269.390368 -130.249168)
		(width 0.1651)
		(layer "F.Cu")
		(net "M_D_MA<14>")
	)
	(segment
		(start 269.390368 -130.249168)
		(end 266.604496 -127.463296)
		(width 0.1651)
		(layer "F.Cu")
		(net "M_D_MA<14>")
	)
	(segment
		(start 264.96137 -124.1552)
		(end 264.61085 -123.80468)
		(width 0.1651)
		(layer "F.Cu")
		(net "M_D_MA<14>")
	)
	(segment
		(start 266.08151 -126.196598)
		(end 265.523472 -125.63856)
		(width 0.1651)
		(layer "F.Cu")
		(net "M_D_MA<14>")
	)
	(segment
		(start 262.45693 -101.44252)
		(end 262.79729 -101.10216)
		(width 0.0889)
		(layer "F.Cu")
		(net "M_D_MA<14>")
	)
	(segment
		(start 270.34998 -137.67054)
		(end 270.34998 -136.387332)
		(width 0.1651)
		(layer "F.Cu")
		(net "M_D_MA<14>")
	)
	(segment
		(start 264.675112 -125.139704)
		(end 264.675112 -124.762514)
		(width 0.1651)
		(layer "F.Cu")
		(net "M_D_MA<14>")
	)
	(segment
		(start 264.96137 -124.476256)
		(end 264.96137 -124.1552)
		(width 0.1651)
		(layer "F.Cu")
		(net "M_D_MA<14>")
	)
	(segment
		(start 262.79729 -101.10216)
		(end 262.79729 -100.662486)
		(width 0.0889)
		(layer "F.Cu")
		(net "M_D_MA<14>")
	)
	(segment
		(start 266.35456 -127.463296)
		(end 265.871198 -126.979934)
		(width 0.1651)
		(layer "F.Cu")
		(net "M_D_MA<14>")
	)
	(segment
		(start 262.45058 -101.453188)
		(end 262.45693 -101.44252)
		(width 0.0889)
		(layer "F.Cu")
		(net "M_D_MA<14>")
	)
	(segment
		(start 266.604496 -127.463296)
		(end 266.35456 -127.463296)
		(width 0.1651)
		(layer "F.Cu")
		(net "M_D_MA<14>")
	)
	(segment
		(start 266.08151 -126.535942)
		(end 266.08151 -126.196598)
		(width 0.1651)
		(layer "F.Cu")
		(net "M_D_MA<14>")
	)
	(segment
		(start 264.61085 -123.80468)
		(end 264.61085 -104.610662)
		(width 0.1651)
		(layer "F.Cu")
		(net "M_D_MA<14>")
	)
	(segment
		(start 264.675112 -124.762514)
		(end 264.96137 -124.476256)
		(width 0.1651)
		(layer "F.Cu")
		(net "M_D_MA<14>")
	)
	(via
		(at 270.350234 -136.387078)
		(size 0.4572)
		(drill 0.2032)
		(layers "F.Cu" "B.Cu")
		(net "M_D_MA<14>")
	)
	(via
		(at 270.349726 -130.249168)
		(size 0.508)
		(drill 0.254)
		(layers "F.Cu" "B.Cu")
		(net "M_D_MA<14>")
	)
	(arc
		(start 262.39724 -101.652832)
		(mid 262.410812 -101.549513)
		(end 262.45058 -101.453188)
		(width 0.0889)
		(layer "F.Cu")
		(net "M_D_MA<14>")
	)
	(segment
		(start 270.349726 -128.276096)
		(end 270.350488 -128.276096)
		(width 0.1651)
		(layer "B.Cu")
		(net "M_D_MA<14>")
	)
	(segment
		(start 270.349726 -130.249168)
		(end 270.349726 -128.276096)
		(width 0.1651)
		(layer "B.Cu")
		(net "M_D_MA<14>")
	)
	(segment
		(start 269.875 -131.369308)
		(end 270.349726 -130.894582)
		(width 0.14224)
		(layer "In9.Cu")
		(net "M_D_MA<14>")
	)
	(segment
		(start 270.350234 -135.779002)
		(end 270.760698 -135.368538)
		(width 0.14224)
		(layer "In9.Cu")
		(net "M_D_MA<14>")
	)
	(segment
		(start 270.760698 -132.736844)
		(end 269.875 -131.851146)
		(width 0.14224)
		(layer "In9.Cu")
		(net "M_D_MA<14>")
	)
	(segment
		(start 270.350234 -136.387078)
		(end 270.350234 -135.779002)
		(width 0.14224)
		(layer "In9.Cu")
		(net "M_D_MA<14>")
	)
	(segment
		(start 269.875 -131.851146)
		(end 269.875 -131.369308)
		(width 0.14224)
		(layer "In9.Cu")
		(net "M_D_MA<14>")
	)
	(segment
		(start 270.349726 -130.894582)
		(end 270.349726 -130.249168)
		(width 0.14224)
		(layer "In9.Cu")
		(net "M_D_MA<14>")
	)
	(segment
		(start 270.760698 -135.368538)
		(end 270.760698 -132.736844)
		(width 0.14224)
		(layer "In9.Cu")
		(net "M_D_MA<14>")
	)
	(segment
		(start 273.750278 -137.67054)
		(end 273.74977 -137.67054)
		(width 0.1651)
		(layer "F.Cu")
		(net "M_D_MA<13>")
	)
	(segment
		(start 265.372596 -98.18624)
		(end 264.801096 -98.18624)
		(width 0.1651)
		(layer "F.Cu")
		(net "M_D_MA<13>")
	)
	(segment
		(start 273.74977 -136.387586)
		(end 273.750278 -136.387078)
		(width 0.1651)
		(layer "F.Cu")
		(net "M_D_MA<13>")
	)
	(segment
		(start 273.74977 -137.67054)
		(end 273.74977 -136.387586)
		(width 0.1651)
		(layer "F.Cu")
		(net "M_D_MA<13>")
	)
	(via
		(at 273.74977 -130.249168)
		(size 0.508)
		(drill 0.254)
		(layers "F.Cu" "B.Cu")
		(net "M_D_MA<13>")
	)
	(via
		(at 273.750278 -136.387078)
		(size 0.4572)
		(drill 0.2032)
		(layers "F.Cu" "B.Cu")
		(net "M_D_MA<13>")
	)
	(via
		(at 264.801096 -98.18624)
		(size 0.508)
		(drill 0.254)
		(layers "F.Cu" "B.Cu")
		(net "M_D_MA<13>")
	)
	(segment
		(start 273.74977 -130.249168)
		(end 273.74977 -128.276096)
		(width 0.1651)
		(layer "B.Cu")
		(net "M_D_MA<13>")
	)
	(segment
		(start 273.74977 -128.276096)
		(end 273.750278 -128.276096)
		(width 0.1651)
		(layer "B.Cu")
		(net "M_D_MA<13>")
	)
	(segment
		(start 273.013932 -128.029208)
		(end 272.578576 -128.029208)
		(width 0.14224)
		(layer "In11.Cu")
		(net "M_D_MA<13>")
	)
	(segment
		(start 273.188938 -127.426974)
		(end 273.188938 -127.854202)
		(width 0.14224)
		(layer "In11.Cu")
		(net "M_D_MA<13>")
	)
	(segment
		(start 266.8143 -121.052336)
		(end 273.188938 -127.426974)
		(width 0.14224)
		(layer "In11.Cu")
		(net "M_D_MA<13>")
	)
	(segment
		(start 272.578576 -128.842008)
		(end 273.014948 -128.842008)
		(width 0.14224)
		(layer "In11.Cu")
		(net "M_D_MA<13>")
	)
	(segment
		(start 264.3886 -98.598736)
		(end 264.3886 -99.3648)
		(width 0.0889)
		(layer "In11.Cu")
		(net "M_D_MA<13>")
	)
	(segment
		(start 264.9728 -100.6348)
		(end 265.6332 -101.2952)
		(width 0.14224)
		(layer "In11.Cu")
		(net "M_D_MA<13>")
	)
	(segment
		(start 265.6332 -101.2952)
		(end 265.6332 -102.387654)
		(width 0.14224)
		(layer "In11.Cu")
		(net "M_D_MA<13>")
	)
	(segment
		(start 273.188938 -127.854202)
		(end 273.013932 -128.029208)
		(width 0.14224)
		(layer "In11.Cu")
		(net "M_D_MA<13>")
	)
	(segment
		(start 264.3886 -99.3648)
		(end 264.9728 -99.949)
		(width 0.0889)
		(layer "In11.Cu")
		(net "M_D_MA<13>")
	)
	(segment
		(start 265.6332 -102.387654)
		(end 266.8143 -103.568754)
		(width 0.14224)
		(layer "In11.Cu")
		(net "M_D_MA<13>")
	)
	(segment
		(start 273.342354 -135.979154)
		(end 273.750278 -136.387078)
		(width 0.14224)
		(layer "In11.Cu")
		(net "M_D_MA<13>")
	)
	(segment
		(start 272.578576 -128.029208)
		(end 272.40484 -128.202944)
		(width 0.14224)
		(layer "In11.Cu")
		(net "M_D_MA<13>")
	)
	(segment
		(start 266.8143 -103.568754)
		(end 266.8143 -121.052336)
		(width 0.14224)
		(layer "In11.Cu")
		(net "M_D_MA<13>")
	)
	(segment
		(start 273.74977 -130.249168)
		(end 273.3802 -130.618738)
		(width 0.14224)
		(layer "In11.Cu")
		(net "M_D_MA<13>")
	)
	(segment
		(start 264.9728 -99.949)
		(end 264.9728 -100.6348)
		(width 0.14224)
		(layer "In11.Cu")
		(net "M_D_MA<13>")
	)
	(segment
		(start 264.801096 -98.18624)
		(end 264.3886 -98.598736)
		(width 0.0889)
		(layer "In11.Cu")
		(net "M_D_MA<13>")
	)
	(segment
		(start 273.3802 -130.618738)
		(end 273.3802 -131.21894)
		(width 0.14224)
		(layer "In11.Cu")
		(net "M_D_MA<13>")
	)
	(segment
		(start 272.40484 -128.668272)
		(end 272.578576 -128.842008)
		(width 0.14224)
		(layer "In11.Cu")
		(net "M_D_MA<13>")
	)
	(segment
		(start 273.74977 -129.57683)
		(end 273.74977 -130.249168)
		(width 0.14224)
		(layer "In11.Cu")
		(net "M_D_MA<13>")
	)
	(segment
		(start 273.3802 -131.21894)
		(end 273.2532 -131.34594)
		(width 0.14224)
		(layer "In11.Cu")
		(net "M_D_MA<13>")
	)
	(segment
		(start 272.40484 -128.202944)
		(end 272.40484 -128.668272)
		(width 0.14224)
		(layer "In11.Cu")
		(net "M_D_MA<13>")
	)
	(segment
		(start 273.342354 -131.915154)
		(end 273.342354 -135.979154)
		(width 0.14224)
		(layer "In11.Cu")
		(net "M_D_MA<13>")
	)
	(segment
		(start 273.014948 -128.842008)
		(end 273.74977 -129.57683)
		(width 0.14224)
		(layer "In11.Cu")
		(net "M_D_MA<13>")
	)
	(segment
		(start 273.2532 -131.34594)
		(end 273.2532 -131.826)
		(width 0.14224)
		(layer "In11.Cu")
		(net "M_D_MA<13>")
	)
	(segment
		(start 273.2532 -131.826)
		(end 273.342354 -131.915154)
		(width 0.14224)
		(layer "In11.Cu")
		(net "M_D_MA<13>")
	)
	(segment
		(start 252.495304 -96.700086)
		(end 251.923804 -96.700086)
		(width 0.1651)
		(layer "F.Cu")
		(net "M_D_MA<12>")
	)
	(segment
		(start 249.10034 -133.0706)
		(end 249.099832 -133.076442)
		(width 0.1651)
		(layer "F.Cu")
		(net "M_D_MA<12>")
	)
	(segment
		(start 249.099832 -133.076442)
		(end 249.099832 -134.369556)
		(width 0.1651)
		(layer "F.Cu")
		(net "M_D_MA<12>")
	)
	(via
		(at 249.099832 -134.369556)
		(size 0.4572)
		(drill 0.2032)
		(layers "F.Cu" "B.Cu")
		(net "M_D_MA<12>")
	)
	(via
		(at 249.099832 -130.902456)
		(size 0.508)
		(drill 0.254)
		(layers "F.Cu" "B.Cu")
		(net "M_D_MA<12>")
	)
	(via
		(at 251.923804 -96.700086)
		(size 0.508)
		(drill 0.254)
		(layers "F.Cu" "B.Cu")
		(net "M_D_MA<12>")
	)
	(segment
		(start 249.099832 -132.875782)
		(end 249.099832 -130.902456)
		(width 0.1651)
		(layer "B.Cu")
		(net "M_D_MA<12>")
	)
	(segment
		(start 249.10034 -132.876036)
		(end 249.099832 -132.875782)
		(width 0.1651)
		(layer "B.Cu")
		(net "M_D_MA<12>")
	)
	(segment
		(start 249.555 -124.354336)
		(end 249.555 -128.4732)
		(width 0.14224)
		(layer "In11.Cu")
		(net "M_D_MA<12>")
	)
	(segment
		(start 249.00763 -134.277354)
		(end 249.099832 -134.369556)
		(width 0.14224)
		(layer "In11.Cu")
		(net "M_D_MA<12>")
	)
	(segment
		(start 248.6152 -129.8448)
		(end 249.099832 -130.329432)
		(width 0.14224)
		(layer "In11.Cu")
		(net "M_D_MA<12>")
	)
	(segment
		(start 253.129034 -98.386138)
		(end 253.122684 -98.396806)
		(width 0.0889)
		(layer "In11.Cu")
		(net "M_D_MA<12>")
	)
	(segment
		(start 253.13386 -99.368102)
		(end 253.129034 -99.376738)
		(width 0.0889)
		(layer "In11.Cu")
		(net "M_D_MA<12>")
	)
	(segment
		(start 252.974348 -99.831398)
		(end 252.974348 -100.575872)
		(width 0.0889)
		(layer "In11.Cu")
		(net "M_D_MA<12>")
	)
	(segment
		(start 249.099832 -130.329432)
		(end 249.099832 -130.902456)
		(width 0.14224)
		(layer "In11.Cu")
		(net "M_D_MA<12>")
	)
	(segment
		(start 248.6152 -129.413)
		(end 248.6152 -129.8448)
		(width 0.14224)
		(layer "In11.Cu")
		(net "M_D_MA<12>")
	)
	(segment
		(start 252.974348 -100.575872)
		(end 252.974348 -120.934988)
		(width 0.14224)
		(layer "In11.Cu")
		(net "M_D_MA<12>")
	)
	(segment
		(start 251.923804 -96.700086)
		(end 252.253242 -97.46107)
		(width 0.0889)
		(layer "In11.Cu")
		(net "M_D_MA<12>")
	)
	(segment
		(start 249.555 -128.4732)
		(end 248.6152 -129.413)
		(width 0.14224)
		(layer "In11.Cu")
		(net "M_D_MA<12>")
	)
	(segment
		(start 249.099832 -130.902456)
		(end 249.00763 -130.994658)
		(width 0.14224)
		(layer "In11.Cu")
		(net "M_D_MA<12>")
	)
	(segment
		(start 253.008638 -99.631754)
		(end 252.974348 -99.831398)
		(width 0.0889)
		(layer "In11.Cu")
		(net "M_D_MA<12>")
	)
	(segment
		(start 249.00763 -130.994658)
		(end 249.00763 -134.277354)
		(width 0.14224)
		(layer "In11.Cu")
		(net "M_D_MA<12>")
	)
	(segment
		(start 253.13386 -98.377502)
		(end 253.129034 -98.386138)
		(width 0.0889)
		(layer "In11.Cu")
		(net "M_D_MA<12>")
	)
	(segment
		(start 252.253242 -97.46107)
		(end 252.270514 -97.490788)
		(width 0.0889)
		(layer "In11.Cu")
		(net "M_D_MA<12>")
	)
	(segment
		(start 252.974348 -120.934988)
		(end 249.555 -124.354336)
		(width 0.14224)
		(layer "In11.Cu")
		(net "M_D_MA<12>")
	)
	(segment
		(start 252.764544 -97.78619)
		(end 252.79731 -97.78619)
		(width 0.0889)
		(layer "In11.Cu")
		(net "M_D_MA<12>")
	)
	(arc
		(start 253.129034 -98.976688)
		(mid 253.182504 -99.171751)
		(end 253.13386 -99.368102)
		(width 0.0889)
		(layer "In11.Cu")
		(net "M_D_MA<12>")
	)
	(arc
		(start 252.79731 -97.78619)
		(mid 253.130228 -97.988181)
		(end 253.13386 -98.377502)
		(width 0.0889)
		(layer "In11.Cu")
		(net "M_D_MA<12>")
	)
	(arc
		(start 252.270514 -97.490788)
		(mid 252.479122 -97.70272)
		(end 252.764544 -97.78619)
		(width 0.0889)
		(layer "In11.Cu")
		(net "M_D_MA<12>")
	)
	(arc
		(start 253.129034 -99.376738)
		(mid 253.064468 -99.502184)
		(end 253.008638 -99.631754)
		(width 0.0889)
		(layer "In11.Cu")
		(net "M_D_MA<12>")
	)
	(arc
		(start 253.122684 -98.396806)
		(mid 253.049886 -98.687569)
		(end 253.129034 -98.976688)
		(width 0.0889)
		(layer "In11.Cu")
		(net "M_D_MA<12>")
	)
	(segment
		(start 249.94997 -136.387078)
		(end 249.94997 -137.67054)
		(width 0.1651)
		(layer "F.Cu")
		(net "M_D_MA<11>")
	)
	(segment
		(start 254.212344 -99.67214)
		(end 253.640844 -98.681286)
		(width 0.1651)
		(layer "F.Cu")
		(net "M_D_MA<11>")
	)
	(segment
		(start 249.94997 -137.67054)
		(end 249.950478 -137.67054)
		(width 0.1651)
		(layer "F.Cu")
		(net "M_D_MA<11>")
	)
	(via
		(at 249.94997 -136.387078)
		(size 0.4572)
		(drill 0.2032)
		(layers "F.Cu" "B.Cu")
		(net "M_D_MA<11>")
	)
	(via
		(at 249.94997 -130.249168)
		(size 0.508)
		(drill 0.254)
		(layers "F.Cu" "B.Cu")
		(net "M_D_MA<11>")
	)
	(via
		(at 253.640844 -98.681286)
		(size 0.508)
		(drill 0.254)
		(layers "F.Cu" "B.Cu")
		(net "M_D_MA<11>")
	)
	(segment
		(start 249.94997 -128.276096)
		(end 249.94997 -130.249168)
		(width 0.1651)
		(layer "B.Cu")
		(net "M_D_MA<11>")
	)
	(segment
		(start 249.950478 -128.276096)
		(end 249.94997 -128.276096)
		(width 0.1651)
		(layer "B.Cu")
		(net "M_D_MA<11>")
	)
	(segment
		(start 253.241048 -99.988116)
		(end 253.482348 -100.229416)
		(width 0.0889)
		(layer "In11.Cu")
		(net "M_D_MA<11>")
	)
	(segment
		(start 249.94997 -130.249168)
		(end 249.7074 -130.491738)
		(width 0.14224)
		(layer "In11.Cu")
		(net "M_D_MA<11>")
	)
	(segment
		(start 253.482348 -100.585778)
		(end 253.482348 -101.031548)
		(width 0.14224)
		(layer "In11.Cu")
		(net "M_D_MA<11>")
	)
	(segment
		(start 249.465592 -135.9027)
		(end 249.94997 -136.387078)
		(width 0.14224)
		(layer "In11.Cu")
		(net "M_D_MA<11>")
	)
	(segment
		(start 253.482348 -101.031548)
		(end 253.873 -101.4222)
		(width 0.14224)
		(layer "In11.Cu")
		(net "M_D_MA<11>")
	)
	(segment
		(start 250.063 -129.032)
		(end 249.7328 -129.3622)
		(width 0.14224)
		(layer "In11.Cu")
		(net "M_D_MA<11>")
	)
	(segment
		(start 253.873 -101.7524)
		(end 253.482348 -102.143052)
		(width 0.14224)
		(layer "In11.Cu")
		(net "M_D_MA<11>")
	)
	(segment
		(start 249.2629 -135.502396)
		(end 249.465592 -135.705088)
		(width 0.14224)
		(layer "In11.Cu")
		(net "M_D_MA<11>")
	)
	(segment
		(start 249.7328 -129.3622)
		(end 249.7328 -130.031998)
		(width 0.14224)
		(layer "In11.Cu")
		(net "M_D_MA<11>")
	)
	(segment
		(start 250.063 -124.536708)
		(end 250.063 -129.032)
		(width 0.14224)
		(layer "In11.Cu")
		(net "M_D_MA<11>")
	)
	(segment
		(start 249.465592 -135.705088)
		(end 249.465592 -135.9027)
		(width 0.14224)
		(layer "In11.Cu")
		(net "M_D_MA<11>")
	)
	(segment
		(start 249.5296 -131.9276)
		(end 249.5296 -134.722108)
		(width 0.14224)
		(layer "In11.Cu")
		(net "M_D_MA<11>")
	)
	(segment
		(start 248.595642 -135.347456)
		(end 248.750582 -135.502396)
		(width 0.14224)
		(layer "In11.Cu")
		(net "M_D_MA<11>")
	)
	(segment
		(start 249.5296 -134.722108)
		(end 249.310652 -134.941056)
		(width 0.14224)
		(layer "In11.Cu")
		(net "M_D_MA<11>")
	)
	(segment
		(start 249.310652 -134.941056)
		(end 248.750582 -134.941056)
		(width 0.14224)
		(layer "In11.Cu")
		(net "M_D_MA<11>")
	)
	(segment
		(start 253.241048 -99.670362)
		(end 253.241048 -99.988116)
		(width 0.0889)
		(layer "In11.Cu")
		(net "M_D_MA<11>")
	)
	(segment
		(start 253.482348 -121.11736)
		(end 250.063 -124.536708)
		(width 0.14224)
		(layer "In11.Cu")
		(net "M_D_MA<11>")
	)
	(segment
		(start 248.750582 -135.502396)
		(end 249.2629 -135.502396)
		(width 0.14224)
		(layer "In11.Cu")
		(net "M_D_MA<11>")
	)
	(segment
		(start 248.595642 -135.095996)
		(end 248.595642 -135.347456)
		(width 0.14224)
		(layer "In11.Cu")
		(net "M_D_MA<11>")
	)
	(segment
		(start 253.640844 -98.681286)
		(end 253.640844 -98.871786)
		(width 0.0889)
		(layer "In11.Cu")
		(net "M_D_MA<11>")
	)
	(segment
		(start 249.7074 -130.491738)
		(end 249.7074 -131.0386)
		(width 0.14224)
		(layer "In11.Cu")
		(net "M_D_MA<11>")
	)
	(segment
		(start 249.7328 -130.031998)
		(end 249.94997 -130.249168)
		(width 0.14224)
		(layer "In11.Cu")
		(net "M_D_MA<11>")
	)
	(segment
		(start 253.640844 -98.871786)
		(end 253.372112 -99.140518)
		(width 0.0889)
		(layer "In11.Cu")
		(net "M_D_MA<11>")
	)
	(segment
		(start 253.482348 -102.143052)
		(end 253.482348 -121.11736)
		(width 0.14224)
		(layer "In11.Cu")
		(net "M_D_MA<11>")
	)
	(segment
		(start 249.7074 -131.0386)
		(end 249.440446 -131.305554)
		(width 0.14224)
		(layer "In11.Cu")
		(net "M_D_MA<11>")
	)
	(segment
		(start 249.440446 -131.838446)
		(end 249.5296 -131.9276)
		(width 0.14224)
		(layer "In11.Cu")
		(net "M_D_MA<11>")
	)
	(segment
		(start 249.440446 -131.305554)
		(end 249.440446 -131.838446)
		(width 0.14224)
		(layer "In11.Cu")
		(net "M_D_MA<11>")
	)
	(segment
		(start 253.873 -101.4222)
		(end 253.873 -101.7524)
		(width 0.14224)
		(layer "In11.Cu")
		(net "M_D_MA<11>")
	)
	(segment
		(start 248.750582 -134.941056)
		(end 248.595642 -135.095996)
		(width 0.14224)
		(layer "In11.Cu")
		(net "M_D_MA<11>")
	)
	(segment
		(start 253.482348 -100.229416)
		(end 253.482348 -100.585778)
		(width 0.0889)
		(layer "In11.Cu")
		(net "M_D_MA<11>")
	)
	(arc
		(start 253.294134 -99.472242)
		(mid 253.254575 -99.567812)
		(end 253.241048 -99.670362)
		(width 0.0889)
		(layer "In11.Cu")
		(net "M_D_MA<11>")
	)
	(arc
		(start 253.372112 -99.140518)
		(mid 253.357537 -99.312116)
		(end 253.294134 -99.472242)
		(width 0.0889)
		(layer "In11.Cu")
		(net "M_D_MA<11>")
	)
	(segment
		(start 259.65023 -98.18624)
		(end 260.22173 -98.18624)
		(width 0.1651)
		(layer "F.Cu")
		(net "M_D_MA<10>")
	)
	(segment
		(start 267.800328 -137.67054)
		(end 267.79982 -137.67054)
		(width 0.1651)
		(layer "F.Cu")
		(net "M_D_MA<10>")
	)
	(segment
		(start 267.79982 -136.387332)
		(end 267.800074 -136.387078)
		(width 0.1651)
		(layer "F.Cu")
		(net "M_D_MA<10>")
	)
	(segment
		(start 267.79982 -137.67054)
		(end 267.79982 -136.387332)
		(width 0.1651)
		(layer "F.Cu")
		(net "M_D_MA<10>")
	)
	(via
		(at 259.65023 -98.18624)
		(size 0.508)
		(drill 0.254)
		(layers "F.Cu" "B.Cu")
		(net "M_D_MA<10>")
	)
	(via
		(at 267.79982 -129.539746)
		(size 0.508)
		(drill 0.254)
		(layers "F.Cu" "B.Cu")
		(net "M_D_MA<10>")
	)
	(via
		(at 267.800074 -136.387078)
		(size 0.4572)
		(drill 0.2032)
		(layers "F.Cu" "B.Cu")
		(net "M_D_MA<10>")
	)
	(segment
		(start 267.800328 -128.276096)
		(end 267.79982 -128.276096)
		(width 0.1651)
		(layer "B.Cu")
		(net "M_D_MA<10>")
	)
	(segment
		(start 267.79982 -128.276096)
		(end 267.79982 -129.539746)
		(width 0.1651)
		(layer "B.Cu")
		(net "M_D_MA<10>")
	)
	(segment
		(start 262.128 -103.43896)
		(end 262.829548 -104.140508)
		(width 0.0889)
		(layer "In11.Cu")
		(net "M_D_MA<10>")
	)
	(segment
		(start 260.102604 -98.638614)
		(end 260.102604 -99.854004)
		(width 0.0889)
		(layer "In11.Cu")
		(net "M_D_MA<10>")
	)
	(segment
		(start 267.79982 -135.703056)
		(end 267.79982 -136.386824)
		(width 0.14224)
		(layer "In11.Cu")
		(net "M_D_MA<10>")
	)
	(segment
		(start 267.361924 -130.579876)
		(end 267.361924 -131.243324)
		(width 0.14224)
		(layer "In11.Cu")
		(net "M_D_MA<10>")
	)
	(segment
		(start 267.42771 -131.30911)
		(end 267.42771 -131.88569)
		(width 0.14224)
		(layer "In11.Cu")
		(net "M_D_MA<10>")
	)
	(segment
		(start 267.79982 -136.386824)
		(end 267.800074 -136.387078)
		(width 0.14224)
		(layer "In11.Cu")
		(net "M_D_MA<10>")
	)
	(segment
		(start 267.367512 -131.945888)
		(end 267.367512 -134.728712)
		(width 0.14224)
		(layer "In11.Cu")
		(net "M_D_MA<10>")
	)
	(segment
		(start 267.4874 -134.8486)
		(end 267.4874 -135.390636)
		(width 0.14224)
		(layer "In11.Cu")
		(net "M_D_MA<10>")
	)
	(segment
		(start 260.102604 -99.854004)
		(end 262.128 -101.8794)
		(width 0.0889)
		(layer "In11.Cu")
		(net "M_D_MA<10>")
	)
	(segment
		(start 267.367512 -134.728712)
		(end 267.4874 -134.8486)
		(width 0.14224)
		(layer "In11.Cu")
		(net "M_D_MA<10>")
	)
	(segment
		(start 267.4874 -135.390636)
		(end 267.79982 -135.703056)
		(width 0.14224)
		(layer "In11.Cu")
		(net "M_D_MA<10>")
	)
	(segment
		(start 262.829548 -104.140508)
		(end 262.829548 -104.466136)
		(width 0.0889)
		(layer "In11.Cu")
		(net "M_D_MA<10>")
	)
	(segment
		(start 262.829548 -104.466136)
		(end 262.829548 -122.697748)
		(width 0.14224)
		(layer "In11.Cu")
		(net "M_D_MA<10>")
	)
	(segment
		(start 259.65023 -98.18624)
		(end 260.102604 -98.638614)
		(width 0.0889)
		(layer "In11.Cu")
		(net "M_D_MA<10>")
	)
	(segment
		(start 267.79982 -127.66802)
		(end 267.79982 -129.539746)
		(width 0.14224)
		(layer "In11.Cu")
		(net "M_D_MA<10>")
	)
	(segment
		(start 267.4874 -130.4544)
		(end 267.361924 -130.579876)
		(width 0.14224)
		(layer "In11.Cu")
		(net "M_D_MA<10>")
	)
	(segment
		(start 267.4874 -129.852166)
		(end 267.4874 -130.4544)
		(width 0.14224)
		(layer "In11.Cu")
		(net "M_D_MA<10>")
	)
	(segment
		(start 267.79982 -129.539746)
		(end 267.4874 -129.852166)
		(width 0.14224)
		(layer "In11.Cu")
		(net "M_D_MA<10>")
	)
	(segment
		(start 267.361924 -131.243324)
		(end 267.42771 -131.30911)
		(width 0.14224)
		(layer "In11.Cu")
		(net "M_D_MA<10>")
	)
	(segment
		(start 262.829548 -122.697748)
		(end 267.79982 -127.66802)
		(width 0.14224)
		(layer "In11.Cu")
		(net "M_D_MA<10>")
	)
	(segment
		(start 267.42771 -131.88569)
		(end 267.367512 -131.945888)
		(width 0.14224)
		(layer "In11.Cu")
		(net "M_D_MA<10>")
	)
	(segment
		(start 262.128 -101.8794)
		(end 262.128 -103.43896)
		(width 0.0889)
		(layer "In11.Cu")
		(net "M_D_MA<10>")
	)
	(segment
		(start 266.099798 -133.076442)
		(end 266.099798 -134.367778)
		(width 0.1651)
		(layer "F.Cu")
		(net "M_D_MA<0>")
	)
	(segment
		(start 265.811 -130.613658)
		(end 265.811 -129.896616)
		(width 0.1651)
		(layer "F.Cu")
		(net "M_D_MA<0>")
	)
	(segment
		(start 264.250932 -127.431038)
		(end 263.01065 -126.190756)
		(width 0.1651)
		(layer "F.Cu")
		(net "M_D_MA<0>")
	)
	(segment
		(start 266.100306 -133.0706)
		(end 266.099798 -133.076442)
		(width 0.1651)
		(layer "F.Cu")
		(net "M_D_MA<0>")
	)
	(segment
		(start 266.099798 -130.902456)
		(end 265.811 -130.613658)
		(width 0.1651)
		(layer "F.Cu")
		(net "M_D_MA<0>")
	)
	(segment
		(start 261.60095 -101.373178)
		(end 261.59206 -101.357938)
		(width 0.0889)
		(layer "F.Cu")
		(net "M_D_MA<0>")
	)
	(segment
		(start 263.01065 -103.75265)
		(end 261.7216 -102.4636)
		(width 0.0889)
		(layer "F.Cu")
		(net "M_D_MA<0>")
	)
	(segment
		(start 265.811 -129.896616)
		(end 264.250932 -128.336548)
		(width 0.1651)
		(layer "F.Cu")
		(net "M_D_MA<0>")
	)
	(segment
		(start 263.01065 -104.28859)
		(end 263.01065 -103.75265)
		(width 0.0889)
		(layer "F.Cu")
		(net "M_D_MA<0>")
	)
	(segment
		(start 261.56412 -100.322888)
		(end 261.08025 -99.67214)
		(width 0.0889)
		(layer "F.Cu")
		(net "M_D_MA<0>")
	)
	(segment
		(start 261.7216 -102.4636)
		(end 261.7216 -101.704648)
		(width 0.0889)
		(layer "F.Cu")
		(net "M_D_MA<0>")
	)
	(segment
		(start 263.01065 -126.190756)
		(end 263.01065 -104.28859)
		(width 0.1651)
		(layer "F.Cu")
		(net "M_D_MA<0>")
	)
	(segment
		(start 261.59206 -101.357938)
		(end 261.587234 -101.349302)
		(width 0.0889)
		(layer "F.Cu")
		(net "M_D_MA<0>")
	)
	(segment
		(start 264.250932 -128.336548)
		(end 264.250932 -127.431038)
		(width 0.1651)
		(layer "F.Cu")
		(net "M_D_MA<0>")
	)
	(via
		(at 266.099798 -130.902456)
		(size 0.508)
		(drill 0.254)
		(layers "F.Cu" "B.Cu")
		(net "M_D_MA<0>")
	)
	(via
		(at 266.099798 -134.367778)
		(size 0.508)
		(drill 0.254)
		(layers "F.Cu" "B.Cu")
		(net "M_D_MA<0>")
	)
	(arc
		(start 261.7216 -101.704648)
		(mid 261.690498 -101.528277)
		(end 261.60095 -101.373178)
		(width 0.0889)
		(layer "F.Cu")
		(net "M_D_MA<0>")
	)
	(arc
		(start 261.587234 -101.349302)
		(mid 261.538479 -101.15295)
		(end 261.59206 -100.957888)
		(width 0.0889)
		(layer "F.Cu")
		(net "M_D_MA<0>")
	)
	(arc
		(start 261.59206 -100.957888)
		(mid 261.670749 -100.636301)
		(end 261.56412 -100.322888)
		(width 0.0889)
		(layer "F.Cu")
		(net "M_D_MA<0>")
	)
	(segment
		(start 266.099798 -132.875782)
		(end 266.099798 -130.902456)
		(width 0.1651)
		(layer "B.Cu")
		(net "M_D_MA<0>")
	)
	(segment
		(start 266.100306 -132.876036)
		(end 266.099798 -132.875782)
		(width 0.1651)
		(layer "B.Cu")
		(net "M_D_MA<0>")
	)
	(segment
		(start 266.099798 -130.902456)
		(end 266.099798 -134.367778)
		(width 0.14224)
		(layer "In9.Cu")
		(net "M_D_MA<0>")
	)
	(segment
		(start 249.919744 -91.25204)
		(end 249.348244 -91.25204)
		(width 0.1651)
		(layer "F.Cu")
		(net "M_D_ECC<7>")
	)
	(segment
		(start 239.749838 -133.076442)
		(end 239.749838 -134.340346)
		(width 0.1651)
		(layer "F.Cu")
		(net "M_D_ECC<7>")
	)
	(segment
		(start 239.750346 -133.0706)
		(end 239.749838 -133.076442)
		(width 0.1651)
		(layer "F.Cu")
		(net "M_D_ECC<7>")
	)
	(via
		(at 240.599722 -130.330956)
		(size 0.508)
		(drill 0.254)
		(layers "F.Cu" "B.Cu")
		(net "M_D_ECC<7>")
	)
	(via
		(at 249.348244 -91.25204)
		(size 0.508)
		(drill 0.254)
		(layers "F.Cu" "B.Cu")
		(net "M_D_ECC<7>")
	)
	(via
		(at 239.749838 -134.340346)
		(size 0.508)
		(drill 0.254)
		(layers "F.Cu" "B.Cu")
		(net "M_D_ECC<7>")
	)
	(segment
		(start 240.600484 -128.276096)
		(end 240.599722 -128.276096)
		(width 0.1651)
		(layer "B.Cu")
		(net "M_D_ECC<7>")
	)
	(segment
		(start 240.599722 -128.276096)
		(end 240.599722 -130.330956)
		(width 0.1651)
		(layer "B.Cu")
		(net "M_D_ECC<7>")
	)
	(segment
		(start 248.883678 -96.208596)
		(end 248.883678 -96.42348)
		(width 0.0889)
		(layer "In2.Cu")
		(net "M_D_ECC<7>")
	)
	(segment
		(start 240.149126 -130.7592)
		(end 240.149126 -131.188968)
		(width 0.14224)
		(layer "In2.Cu")
		(net "M_D_ECC<7>")
	)
	(segment
		(start 243.509292 -116.907818)
		(end 243.676424 -117.07495)
		(width 0.14224)
		(layer "In2.Cu")
		(net "M_D_ECC<7>")
	)
	(segment
		(start 242.14074 -119.071644)
		(end 241.9858 -119.226584)
		(width 0.14224)
		(layer "In2.Cu")
		(net "M_D_ECC<7>")
	)
	(segment
		(start 249.005344 -100.71354)
		(end 248.949718 -100.769166)
		(width 0.0889)
		(layer "In2.Cu")
		(net "M_D_ECC<7>")
	)
	(segment
		(start 240.599722 -130.330956)
		(end 240.57737 -130.330956)
		(width 0.14224)
		(layer "In2.Cu")
		(net "M_D_ECC<7>")
	)
	(segment
		(start 242.89258 -118.383304)
		(end 243.034058 -118.524782)
		(width 0.14224)
		(layer "In2.Cu")
		(net "M_D_ECC<7>")
	)
	(segment
		(start 240.149126 -131.188968)
		(end 240.193576 -131.233418)
		(width 0.14224)
		(layer "In2.Cu")
		(net "M_D_ECC<7>")
	)
	(segment
		(start 243.034058 -118.524782)
		(end 243.034058 -118.903242)
		(width 0.14224)
		(layer "In2.Cu")
		(net "M_D_ECC<7>")
	)
	(segment
		(start 249.369834 -93.82379)
		(end 249.33021 -93.82379)
		(width 0.0889)
		(layer "In2.Cu")
		(net "M_D_ECC<7>")
	)
	(segment
		(start 248.464832 -105.408222)
		(end 243.6114 -110.261654)
		(width 0.14224)
		(layer "In2.Cu")
		(net "M_D_ECC<7>")
	)
	(segment
		(start 241.9858 -123.0122)
		(end 240.952528 -124.045472)
		(width 0.14224)
		(layer "In2.Cu")
		(net "M_D_ECC<7>")
	)
	(segment
		(start 242.865656 -119.071644)
		(end 242.14074 -119.071644)
		(width 0.14224)
		(layer "In2.Cu")
		(net "M_D_ECC<7>")
	)
	(segment
		(start 243.676424 -117.07495)
		(end 243.676424 -117.405404)
		(width 0.14224)
		(layer "In2.Cu")
		(net "M_D_ECC<7>")
	)
	(segment
		(start 240.193576 -131.9022)
		(end 239.911128 -132.184648)
		(width 0.14224)
		(layer "In2.Cu")
		(net "M_D_ECC<7>")
	)
	(segment
		(start 248.883678 -96.42348)
		(end 249.005344 -96.545146)
		(width 0.0889)
		(layer "In2.Cu")
		(net "M_D_ECC<7>")
	)
	(segment
		(start 243.479828 -117.602)
		(end 242.1128 -117.602)
		(width 0.14224)
		(layer "In2.Cu")
		(net "M_D_ECC<7>")
	)
	(segment
		(start 249.001534 -96.004888)
		(end 248.883678 -96.208596)
		(width 0.0889)
		(layer "In2.Cu")
		(net "M_D_ECC<7>")
	)
	(segment
		(start 249.005344 -96.545146)
		(end 249.005344 -100.71354)
		(width 0.0889)
		(layer "In2.Cu")
		(net "M_D_ECC<7>")
	)
	(segment
		(start 240.022126 -134.340346)
		(end 239.749838 -134.340346)
		(width 0.14224)
		(layer "In2.Cu")
		(net "M_D_ECC<7>")
	)
	(segment
		(start 249.866404 -92.52712)
		(end 249.860054 -92.537788)
		(width 0.0889)
		(layer "In2.Cu")
		(net "M_D_ECC<7>")
	)
	(segment
		(start 248.256044 -103.090726)
		(end 248.464832 -103.299514)
		(width 0.0889)
		(layer "In2.Cu")
		(net "M_D_ECC<7>")
	)
	(segment
		(start 241.935 -116.704618)
		(end 242.1382 -116.907818)
		(width 0.14224)
		(layer "In2.Cu")
		(net "M_D_ECC<7>")
	)
	(segment
		(start 240.199926 -133.83895)
		(end 240.199926 -134.162546)
		(width 0.14224)
		(layer "In2.Cu")
		(net "M_D_ECC<7>")
	)
	(segment
		(start 240.57737 -130.330956)
		(end 240.149126 -130.7592)
		(width 0.14224)
		(layer "In2.Cu")
		(net "M_D_ECC<7>")
	)
	(segment
		(start 249.001534 -95.414338)
		(end 249.007884 -95.425006)
		(width 0.0889)
		(layer "In2.Cu")
		(net "M_D_ECC<7>")
	)
	(segment
		(start 240.168176 -133.0198)
		(end 239.911128 -133.276848)
		(width 0.14224)
		(layer "In2.Cu")
		(net "M_D_ECC<7>")
	)
	(segment
		(start 241.9858 -117.729)
		(end 241.9858 -118.228364)
		(width 0.14224)
		(layer "In2.Cu")
		(net "M_D_ECC<7>")
	)
	(segment
		(start 241.9858 -118.228364)
		(end 242.14074 -118.383304)
		(width 0.14224)
		(layer "In2.Cu")
		(net "M_D_ECC<7>")
	)
	(segment
		(start 242.1128 -117.602)
		(end 241.9858 -117.729)
		(width 0.14224)
		(layer "In2.Cu")
		(net "M_D_ECC<7>")
	)
	(segment
		(start 241.9858 -119.226584)
		(end 241.9858 -123.0122)
		(width 0.14224)
		(layer "In2.Cu")
		(net "M_D_ECC<7>")
	)
	(segment
		(start 248.256044 -101.462586)
		(end 248.256044 -103.090726)
		(width 0.0889)
		(layer "In2.Cu")
		(net "M_D_ECC<7>")
	)
	(segment
		(start 242.1382 -116.222018)
		(end 241.935 -116.425218)
		(width 0.14224)
		(layer "In2.Cu")
		(net "M_D_ECC<7>")
	)
	(segment
		(start 248.996708 -95.405702)
		(end 249.001534 -95.414338)
		(width 0.0889)
		(layer "In2.Cu")
		(net "M_D_ECC<7>")
	)
	(segment
		(start 240.952528 -124.045472)
		(end 240.952528 -125.407928)
		(width 0.14224)
		(layer "In2.Cu")
		(net "M_D_ECC<7>")
	)
	(segment
		(start 243.256816 -116.222018)
		(end 242.1382 -116.222018)
		(width 0.14224)
		(layer "In2.Cu")
		(net "M_D_ECC<7>")
	)
	(segment
		(start 239.911128 -133.550152)
		(end 240.199926 -133.83895)
		(width 0.14224)
		(layer "In2.Cu")
		(net "M_D_ECC<7>")
	)
	(segment
		(start 240.193576 -131.233418)
		(end 240.193576 -131.9022)
		(width 0.14224)
		(layer "In2.Cu")
		(net "M_D_ECC<7>")
	)
	(segment
		(start 242.14074 -118.383304)
		(end 242.89258 -118.383304)
		(width 0.14224)
		(layer "In2.Cu")
		(net "M_D_ECC<7>")
	)
	(segment
		(start 241.2492 -125.7046)
		(end 241.2492 -126.5428)
		(width 0.14224)
		(layer "In2.Cu")
		(net "M_D_ECC<7>")
	)
	(segment
		(start 240.952528 -126.839472)
		(end 240.952528 -129.989072)
		(width 0.14224)
		(layer "In2.Cu")
		(net "M_D_ECC<7>")
	)
	(segment
		(start 240.168176 -132.715)
		(end 240.168176 -133.0198)
		(width 0.14224)
		(layer "In2.Cu")
		(net "M_D_ECC<7>")
	)
	(segment
		(start 248.949718 -100.768912)
		(end 248.256044 -101.462586)
		(width 0.0889)
		(layer "In2.Cu")
		(net "M_D_ECC<7>")
	)
	(segment
		(start 243.6114 -110.261654)
		(end 243.6114 -115.867434)
		(width 0.14224)
		(layer "In2.Cu")
		(net "M_D_ECC<7>")
	)
	(segment
		(start 243.6114 -115.867434)
		(end 243.256816 -116.222018)
		(width 0.14224)
		(layer "In2.Cu")
		(net "M_D_ECC<7>")
	)
	(segment
		(start 241.935 -116.425218)
		(end 241.935 -116.704618)
		(width 0.14224)
		(layer "In2.Cu")
		(net "M_D_ECC<7>")
	)
	(segment
		(start 240.952528 -129.989072)
		(end 240.941606 -129.989072)
		(width 0.14224)
		(layer "In2.Cu")
		(net "M_D_ECC<7>")
	)
	(segment
		(start 239.911128 -132.457952)
		(end 240.168176 -132.715)
		(width 0.14224)
		(layer "In2.Cu")
		(net "M_D_ECC<7>")
	)
	(segment
		(start 248.949718 -100.769166)
		(end 248.949718 -100.768912)
		(width 0.0889)
		(layer "In2.Cu")
		(net "M_D_ECC<7>")
	)
	(segment
		(start 241.2492 -126.5428)
		(end 240.952528 -126.839472)
		(width 0.14224)
		(layer "In2.Cu")
		(net "M_D_ECC<7>")
	)
	(segment
		(start 239.911128 -133.276848)
		(end 239.911128 -133.550152)
		(width 0.14224)
		(layer "In2.Cu")
		(net "M_D_ECC<7>")
	)
	(segment
		(start 248.464832 -103.299514)
		(end 248.464832 -105.408222)
		(width 0.14224)
		(layer "In2.Cu")
		(net "M_D_ECC<7>")
	)
	(segment
		(start 243.034058 -118.903242)
		(end 242.865656 -119.071644)
		(width 0.14224)
		(layer "In2.Cu")
		(net "M_D_ECC<7>")
	)
	(segment
		(start 243.676424 -117.405404)
		(end 243.479828 -117.602)
		(width 0.14224)
		(layer "In2.Cu")
		(net "M_D_ECC<7>")
	)
	(segment
		(start 249.860054 -92.537788)
		(end 249.855228 -92.546424)
		(width 0.0889)
		(layer "In2.Cu")
		(net "M_D_ECC<7>")
	)
	(segment
		(start 240.199926 -134.162546)
		(end 240.022126 -134.340346)
		(width 0.14224)
		(layer "In2.Cu")
		(net "M_D_ECC<7>")
	)
	(segment
		(start 242.1382 -116.907818)
		(end 243.509292 -116.907818)
		(width 0.14224)
		(layer "In2.Cu")
		(net "M_D_ECC<7>")
	)
	(segment
		(start 240.952528 -125.407928)
		(end 241.2492 -125.7046)
		(width 0.14224)
		(layer "In2.Cu")
		(net "M_D_ECC<7>")
	)
	(segment
		(start 239.911128 -132.184648)
		(end 239.911128 -132.457952)
		(width 0.14224)
		(layer "In2.Cu")
		(net "M_D_ECC<7>")
	)
	(segment
		(start 240.941606 -129.989072)
		(end 240.599722 -130.330956)
		(width 0.14224)
		(layer "In2.Cu")
		(net "M_D_ECC<7>")
	)
	(arc
		(start 249.001534 -94.423484)
		(mid 249.080665 -94.718886)
		(end 249.001534 -95.014288)
		(width 0.0889)
		(layer "In2.Cu")
		(net "M_D_ECC<7>")
	)
	(arc
		(start 249.33021 -93.82379)
		(mid 248.997294 -94.031242)
		(end 249.001534 -94.423484)
		(width 0.0889)
		(layer "In2.Cu")
		(net "M_D_ECC<7>")
	)
	(arc
		(start 249.007884 -95.425006)
		(mid 249.080682 -95.715769)
		(end 249.001534 -96.004888)
		(width 0.0889)
		(layer "In2.Cu")
		(net "M_D_ECC<7>")
	)
	(arc
		(start 249.860054 -92.937838)
		(mid 249.865308 -93.519346)
		(end 249.369834 -93.82379)
		(width 0.0889)
		(layer "In2.Cu")
		(net "M_D_ECC<7>")
	)
	(arc
		(start 249.855228 -92.546424)
		(mid 249.806473 -92.742776)
		(end 249.860054 -92.937838)
		(width 0.0889)
		(layer "In2.Cu")
		(net "M_D_ECC<7>")
	)
	(arc
		(start 249.860054 -91.947238)
		(mid 249.939276 -92.236356)
		(end 249.866404 -92.52712)
		(width 0.0889)
		(layer "In2.Cu")
		(net "M_D_ECC<7>")
	)
	(arc
		(start 249.001534 -95.014288)
		(mid 248.948064 -95.209351)
		(end 248.996708 -95.405702)
		(width 0.0889)
		(layer "In2.Cu")
		(net "M_D_ECC<7>")
	)
	(arc
		(start 249.348244 -91.25204)
		(mid 249.623428 -91.585446)
		(end 249.860054 -91.947238)
		(width 0.0889)
		(layer "In2.Cu")
		(net "M_D_ECC<7>")
	)
	(segment
		(start 249.919744 -89.27084)
		(end 249.348244 -89.27084)
		(width 0.1651)
		(layer "F.Cu")
		(net "M_D_ECC<6>")
	)
	(segment
		(start 240.599976 -136.7028)
		(end 240.732056 -136.57072)
		(width 0.1651)
		(layer "F.Cu")
		(net "M_D_ECC<6>")
	)
	(segment
		(start 240.732056 -136.57072)
		(end 240.732056 -136.35228)
		(width 0.1651)
		(layer "F.Cu")
		(net "M_D_ECC<6>")
	)
	(segment
		(start 240.600484 -137.67054)
		(end 240.599976 -137.67054)
		(width 0.1651)
		(layer "F.Cu")
		(net "M_D_ECC<6>")
	)
	(segment
		(start 240.732056 -136.35228)
		(end 240.599976 -136.2202)
		(width 0.1651)
		(layer "F.Cu")
		(net "M_D_ECC<6>")
	)
	(segment
		(start 240.599976 -136.2202)
		(end 240.599976 -135.915654)
		(width 0.1651)
		(layer "F.Cu")
		(net "M_D_ECC<6>")
	)
	(segment
		(start 240.599976 -137.67054)
		(end 240.599976 -136.7028)
		(width 0.1651)
		(layer "F.Cu")
		(net "M_D_ECC<6>")
	)
	(segment
		(start 240.599976 -135.915654)
		(end 240.599722 -135.9154)
		(width 0.1651)
		(layer "F.Cu")
		(net "M_D_ECC<6>")
	)
	(via
		(at 239.749838 -131.611878)
		(size 0.508)
		(drill 0.254)
		(layers "F.Cu" "B.Cu")
		(net "M_D_ECC<6>")
	)
	(via
		(at 240.599722 -135.9154)
		(size 0.508)
		(drill 0.254)
		(layers "F.Cu" "B.Cu")
		(net "M_D_ECC<6>")
	)
	(via
		(at 249.348244 -89.27084)
		(size 0.508)
		(drill 0.254)
		(layers "F.Cu" "B.Cu")
		(net "M_D_ECC<6>")
	)
	(segment
		(start 239.750346 -132.876036)
		(end 239.749838 -132.875782)
		(width 0.1651)
		(layer "B.Cu")
		(net "M_D_ECC<6>")
	)
	(segment
		(start 239.749838 -132.875782)
		(end 239.749838 -131.611878)
		(width 0.1651)
		(layer "B.Cu")
		(net "M_D_ECC<6>")
	)
	(segment
		(start 248.830084 -95.49892)
		(end 248.836434 -95.509588)
		(width 0.0889)
		(layer "In2.Cu")
		(net "M_D_ECC<6>")
	)
	(segment
		(start 241.870992 -114.732054)
		(end 242.074192 -114.935254)
		(width 0.14224)
		(layer "In2.Cu")
		(net "M_D_ECC<6>")
	)
	(segment
		(start 242.975384 -109.980984)
		(end 242.975384 -113.690654)
		(width 0.14224)
		(layer "In2.Cu")
		(net "M_D_ECC<6>")
	)
	(segment
		(start 249.69978 -92.433902)
		(end 249.694954 -92.442538)
		(width 0.0889)
		(layer "In2.Cu")
		(net "M_D_ECC<6>")
	)
	(segment
		(start 248.693686 -96.15678)
		(end 248.693686 -96.50222)
		(width 0.0889)
		(layer "In2.Cu")
		(net "M_D_ECC<6>")
	)
	(segment
		(start 249.348244 -89.27084)
		(end 248.97969 -90.105738)
		(width 0.0889)
		(layer "In2.Cu")
		(net "M_D_ECC<6>")
	)
	(segment
		(start 241.4016 -114.528854)
		(end 241.6048 -114.732054)
		(width 0.14224)
		(layer "In2.Cu")
		(net "M_D_ECC<6>")
	)
	(segment
		(start 248.815352 -100.634546)
		(end 248.066052 -101.383846)
		(width 0.0889)
		(layer "In2.Cu")
		(net "M_D_ECC<6>")
	)
	(segment
		(start 248.815352 -96.623886)
		(end 248.815352 -100.634546)
		(width 0.0889)
		(layer "In2.Cu")
		(net "M_D_ECC<6>")
	)
	(segment
		(start 239.316768 -132.044948)
		(end 239.316768 -134.632446)
		(width 0.14224)
		(layer "In2.Cu")
		(net "M_D_ECC<6>")
	)
	(segment
		(start 239.749838 -131.611878)
		(end 239.316768 -132.044948)
		(width 0.14224)
		(layer "In2.Cu")
		(net "M_D_ECC<6>")
	)
	(segment
		(start 239.580928 -131.442968)
		(end 239.749838 -131.611878)
		(width 0.14224)
		(layer "In2.Cu")
		(net "M_D_ECC<6>")
	)
	(segment
		(start 239.316768 -134.632446)
		(end 240.599722 -135.9154)
		(width 0.14224)
		(layer "In2.Cu")
		(net "M_D_ECC<6>")
	)
	(segment
		(start 248.836434 -94.518988)
		(end 248.84126 -94.527624)
		(width 0.0889)
		(layer "In2.Cu")
		(net "M_D_ECC<6>")
	)
	(segment
		(start 242.074192 -115.317016)
		(end 241.821208 -115.57)
		(width 0.14224)
		(layer "In2.Cu")
		(net "M_D_ECC<6>")
	)
	(segment
		(start 240.317528 -127.008128)
		(end 240.317528 -129.732278)
		(width 0.14224)
		(layer "In2.Cu")
		(net "M_D_ECC<6>")
	)
	(segment
		(start 240.1824 -125.5776)
		(end 240.1824 -126.873)
		(width 0.14224)
		(layer "In2.Cu")
		(net "M_D_ECC<6>")
	)
	(segment
		(start 248.066052 -103.050594)
		(end 247.817132 -103.299514)
		(width 0.0889)
		(layer "In2.Cu")
		(net "M_D_ECC<6>")
	)
	(segment
		(start 241.6048 -113.919254)
		(end 241.4016 -114.122454)
		(width 0.14224)
		(layer "In2.Cu")
		(net "M_D_ECC<6>")
	)
	(segment
		(start 247.817132 -103.299514)
		(end 247.817132 -105.139236)
		(width 0.14224)
		(layer "In2.Cu")
		(net "M_D_ECC<6>")
	)
	(segment
		(start 239.580928 -130.468878)
		(end 239.580928 -131.442968)
		(width 0.14224)
		(layer "In2.Cu")
		(net "M_D_ECC<6>")
	)
	(segment
		(start 249.366278 -93.633036)
		(end 249.330464 -93.633036)
		(width 0.0889)
		(layer "In2.Cu")
		(net "M_D_ECC<6>")
	)
	(segment
		(start 249.694954 -92.442538)
		(end 249.688604 -92.453206)
		(width 0.0889)
		(layer "In2.Cu")
		(net "M_D_ECC<6>")
	)
	(segment
		(start 240.4364 -125.3236)
		(end 240.1824 -125.5776)
		(width 0.14224)
		(layer "In2.Cu")
		(net "M_D_ECC<6>")
	)
	(segment
		(start 241.6048 -114.732054)
		(end 241.870992 -114.732054)
		(width 0.14224)
		(layer "In2.Cu")
		(net "M_D_ECC<6>")
	)
	(segment
		(start 242.746784 -113.919254)
		(end 241.6048 -113.919254)
		(width 0.14224)
		(layer "In2.Cu")
		(net "M_D_ECC<6>")
	)
	(segment
		(start 241.3254 -115.7732)
		(end 241.3254 -122.7328)
		(width 0.14224)
		(layer "In2.Cu")
		(net "M_D_ECC<6>")
	)
	(segment
		(start 248.066052 -101.383846)
		(end 248.066052 -103.050594)
		(width 0.0889)
		(layer "In2.Cu")
		(net "M_D_ECC<6>")
	)
	(segment
		(start 242.975384 -113.690654)
		(end 242.746784 -113.919254)
		(width 0.14224)
		(layer "In2.Cu")
		(net "M_D_ECC<6>")
	)
	(segment
		(start 248.836434 -95.509588)
		(end 248.84126 -95.518224)
		(width 0.0889)
		(layer "In2.Cu")
		(net "M_D_ECC<6>")
	)
	(segment
		(start 242.074192 -114.935254)
		(end 242.074192 -115.317016)
		(width 0.14224)
		(layer "In2.Cu")
		(net "M_D_ECC<6>")
	)
	(segment
		(start 247.817132 -105.139236)
		(end 242.975384 -109.980984)
		(width 0.14224)
		(layer "In2.Cu")
		(net "M_D_ECC<6>")
	)
	(segment
		(start 241.3254 -122.7328)
		(end 240.4364 -123.6218)
		(width 0.14224)
		(layer "In2.Cu")
		(net "M_D_ECC<6>")
	)
	(segment
		(start 240.317528 -129.732278)
		(end 239.580928 -130.468878)
		(width 0.14224)
		(layer "In2.Cu")
		(net "M_D_ECC<6>")
	)
	(segment
		(start 248.693686 -96.50222)
		(end 248.815352 -96.623886)
		(width 0.0889)
		(layer "In2.Cu")
		(net "M_D_ECC<6>")
	)
	(segment
		(start 248.948956 -90.290396)
		(end 248.948448 -91.232736)
		(width 0.0889)
		(layer "In2.Cu")
		(net "M_D_ECC<6>")
	)
	(segment
		(start 240.1824 -126.873)
		(end 240.317528 -127.008128)
		(width 0.14224)
		(layer "In2.Cu")
		(net "M_D_ECC<6>")
	)
	(segment
		(start 240.4364 -123.6218)
		(end 240.4364 -125.3236)
		(width 0.14224)
		(layer "In2.Cu")
		(net "M_D_ECC<6>")
	)
	(segment
		(start 241.5286 -115.57)
		(end 241.3254 -115.7732)
		(width 0.14224)
		(layer "In2.Cu")
		(net "M_D_ECC<6>")
	)
	(segment
		(start 241.4016 -114.122454)
		(end 241.4016 -114.528854)
		(width 0.14224)
		(layer "In2.Cu")
		(net "M_D_ECC<6>")
	)
	(segment
		(start 248.836434 -95.909638)
		(end 248.693686 -96.15678)
		(width 0.0889)
		(layer "In2.Cu")
		(net "M_D_ECC<6>")
	)
	(segment
		(start 241.821208 -115.57)
		(end 241.5286 -115.57)
		(width 0.14224)
		(layer "In2.Cu")
		(net "M_D_ECC<6>")
	)
	(arc
		(start 249.694954 -92.042488)
		(mid 249.748424 -92.237551)
		(end 249.69978 -92.433902)
		(width 0.0889)
		(layer "In2.Cu")
		(net "M_D_ECC<6>")
	)
	(arc
		(start 249.073924 -91.543632)
		(mid 249.290527 -91.734614)
		(end 249.53468 -91.888818)
		(width 0.0889)
		(layer "In2.Cu")
		(net "M_D_ECC<6>")
	)
	(arc
		(start 248.836434 -94.919038)
		(mid 248.757212 -95.208156)
		(end 248.830084 -95.49892)
		(width 0.0889)
		(layer "In2.Cu")
		(net "M_D_ECC<6>")
	)
	(arc
		(start 248.84126 -95.518224)
		(mid 248.890015 -95.714576)
		(end 248.836434 -95.909638)
		(width 0.0889)
		(layer "In2.Cu")
		(net "M_D_ECC<6>")
	)
	(arc
		(start 249.688604 -92.453206)
		(mid 249.615806 -92.743969)
		(end 249.694954 -93.033088)
		(width 0.0889)
		(layer "In2.Cu")
		(net "M_D_ECC<6>")
	)
	(arc
		(start 248.84126 -94.527624)
		(mid 248.890015 -94.723976)
		(end 248.836434 -94.919038)
		(width 0.0889)
		(layer "In2.Cu")
		(net "M_D_ECC<6>")
	)
	(arc
		(start 249.694954 -93.033088)
		(mid 249.699364 -93.425551)
		(end 249.366278 -93.633036)
		(width 0.0889)
		(layer "In2.Cu")
		(net "M_D_ECC<6>")
	)
	(arc
		(start 249.53468 -91.888818)
		(mid 249.625792 -91.95421)
		(end 249.694954 -92.042488)
		(width 0.0889)
		(layer "In2.Cu")
		(net "M_D_ECC<6>")
	)
	(arc
		(start 249.330464 -93.633036)
		(mid 248.832213 -93.935876)
		(end 248.836434 -94.518988)
		(width 0.0889)
		(layer "In2.Cu")
		(net "M_D_ECC<6>")
	)
	(arc
		(start 248.948448 -91.232736)
		(mid 248.977015 -91.401989)
		(end 249.073924 -91.543632)
		(width 0.0889)
		(layer "In2.Cu")
		(net "M_D_ECC<6>")
	)
	(arc
		(start 248.97969 -90.105738)
		(mid 248.953381 -90.196245)
		(end 248.948956 -90.290396)
		(width 0.0889)
		(layer "In2.Cu")
		(net "M_D_ECC<6>")
	)
	(segment
		(start 233.799888 -133.076442)
		(end 233.799888 -134.340346)
		(width 0.1651)
		(layer "F.Cu")
		(net "M_D_ECC<5>")
	)
	(segment
		(start 247.344184 -90.756486)
		(end 246.772684 -90.756486)
		(width 0.1651)
		(layer "F.Cu")
		(net "M_D_ECC<5>")
	)
	(segment
		(start 233.800396 -133.0706)
		(end 233.799888 -133.076442)
		(width 0.1651)
		(layer "F.Cu")
		(net "M_D_ECC<5>")
	)
	(via
		(at 233.799888 -134.340346)
		(size 0.508)
		(drill 0.254)
		(layers "F.Cu" "B.Cu")
		(net "M_D_ECC<5>")
	)
	(via
		(at 234.573572 -130.330956)
		(size 0.508)
		(drill 0.254)
		(layers "F.Cu" "B.Cu")
		(net "M_D_ECC<5>")
	)
	(via
		(at 246.772684 -90.756486)
		(size 0.508)
		(drill 0.254)
		(layers "F.Cu" "B.Cu")
		(net "M_D_ECC<5>")
	)
	(segment
		(start 234.649772 -130.254756)
		(end 234.573572 -130.330956)
		(width 0.1651)
		(layer "B.Cu")
		(net "M_D_ECC<5>")
	)
	(segment
		(start 234.649772 -128.276096)
		(end 234.649772 -130.254756)
		(width 0.1651)
		(layer "B.Cu")
		(net "M_D_ECC<5>")
	)
	(segment
		(start 234.65028 -128.276096)
		(end 234.649772 -128.276096)
		(width 0.1651)
		(layer "B.Cu")
		(net "M_D_ECC<5>")
	)
	(segment
		(start 234.249976 -131.445)
		(end 234.249976 -131.927346)
		(width 0.14224)
		(layer "In2.Cu")
		(net "M_D_ECC<5>")
	)
	(segment
		(start 234.224576 -133.959854)
		(end 234.224576 -134.187946)
		(width 0.14224)
		(layer "In2.Cu")
		(net "M_D_ECC<5>")
	)
	(segment
		(start 244.73535 -99.27209)
		(end 243.802662 -100.204778)
		(width 0.0889)
		(layer "In2.Cu")
		(net "M_D_ECC<5>")
	)
	(segment
		(start 243.879878 -103.585518)
		(end 237.1598 -110.305596)
		(width 0.14224)
		(layer "In2.Cu")
		(net "M_D_ECC<5>")
	)
	(segment
		(start 235.808012 -120.829578)
		(end 235.808012 -121.182638)
		(width 0.14224)
		(layer "In2.Cu")
		(net "M_D_ECC<5>")
	)
	(segment
		(start 235.646214 -122.67692)
		(end 235.3818 -122.67692)
		(width 0.14224)
		(layer "In2.Cu")
		(net "M_D_ECC<5>")
	)
	(segment
		(start 234.84586 -127.78994)
		(end 234.696 -127.78994)
		(width 0.14224)
		(layer "In2.Cu")
		(net "M_D_ECC<5>")
	)
	(segment
		(start 235.801154 -122.52198)
		(end 235.646214 -122.67692)
		(width 0.14224)
		(layer "In2.Cu")
		(net "M_D_ECC<5>")
	)
	(segment
		(start 234.249976 -131.927346)
		(end 233.961178 -132.216144)
		(width 0.14224)
		(layer "In2.Cu")
		(net "M_D_ECC<5>")
	)
	(segment
		(start 245.567454 -96.404938)
		(end 245.573804 -96.415606)
		(width 0.0889)
		(layer "In2.Cu")
		(net "M_D_ECC<5>")
	)
	(segment
		(start 235.808012 -121.182638)
		(end 235.63961 -121.35104)
		(width 0.14224)
		(layer "In2.Cu")
		(net "M_D_ECC<5>")
	)
	(segment
		(start 243.802662 -101.623622)
		(end 243.879878 -101.700838)
		(width 0.0889)
		(layer "In2.Cu")
		(net "M_D_ECC<5>")
	)
	(segment
		(start 234.55122 -130.330956)
		(end 234.122976 -130.7592)
		(width 0.14224)
		(layer "In2.Cu")
		(net "M_D_ECC<5>")
	)
	(segment
		(start 234.573572 -130.330956)
		(end 234.55122 -130.330956)
		(width 0.14224)
		(layer "In2.Cu")
		(net "M_D_ECC<5>")
	)
	(segment
		(start 235.2294 -125.603)
		(end 235.0516 -125.7808)
		(width 0.14224)
		(layer "In2.Cu")
		(net "M_D_ECC<5>")
	)
	(segment
		(start 245.562628 -95.405702)
		(end 245.567454 -95.414338)
		(width 0.0889)
		(layer "In2.Cu")
		(net "M_D_ECC<5>")
	)
	(segment
		(start 235.230924 -121.35104)
		(end 235.082842 -121.499122)
		(width 0.14224)
		(layer "In2.Cu")
		(net "M_D_ECC<5>")
	)
	(segment
		(start 245.562628 -96.396302)
		(end 245.567454 -96.404938)
		(width 0.0889)
		(layer "In2.Cu")
		(net "M_D_ECC<5>")
	)
	(segment
		(start 235.082842 -121.852182)
		(end 235.24464 -122.01398)
		(width 0.14224)
		(layer "In2.Cu")
		(net "M_D_ECC<5>")
	)
	(segment
		(start 245.562628 -93.424502)
		(end 245.567454 -93.433138)
		(width 0.0889)
		(layer "In2.Cu")
		(net "M_D_ECC<5>")
	)
	(segment
		(start 233.961178 -132.216144)
		(end 233.961178 -132.553456)
		(width 0.14224)
		(layer "In2.Cu")
		(net "M_D_ECC<5>")
	)
	(segment
		(start 235.0516 -125.7808)
		(end 235.0516 -127.5842)
		(width 0.14224)
		(layer "In2.Cu")
		(net "M_D_ECC<5>")
	)
	(segment
		(start 233.961178 -132.553456)
		(end 234.199176 -132.791454)
		(width 0.14224)
		(layer "In2.Cu")
		(net "M_D_ECC<5>")
	)
	(segment
		(start 234.199176 -133.146546)
		(end 233.961178 -133.384544)
		(width 0.14224)
		(layer "In2.Cu")
		(net "M_D_ECC<5>")
	)
	(segment
		(start 234.696 -127.78994)
		(end 234.4928 -127.99314)
		(width 0.14224)
		(layer "In2.Cu")
		(net "M_D_ECC<5>")
	)
	(segment
		(start 245.567454 -97.395538)
		(end 245.573804 -97.406206)
		(width 0.0889)
		(layer "In2.Cu")
		(net "M_D_ECC<5>")
	)
	(segment
		(start 235.3818 -122.67692)
		(end 235.2294 -122.82932)
		(width 0.14224)
		(layer "In2.Cu")
		(net "M_D_ECC<5>")
	)
	(segment
		(start 234.4928 -127.99314)
		(end 234.4928 -128.39954)
		(width 0.14224)
		(layer "In2.Cu")
		(net "M_D_ECC<5>")
	)
	(segment
		(start 234.958128 -128.709928)
		(end 234.958128 -129.9464)
		(width 0.14224)
		(layer "In2.Cu")
		(net "M_D_ECC<5>")
	)
	(segment
		(start 245.562628 -98.377502)
		(end 245.567454 -98.386138)
		(width 0.0889)
		(layer "In2.Cu")
		(net "M_D_ECC<5>")
	)
	(segment
		(start 245.562628 -92.433902)
		(end 245.567454 -92.442538)
		(width 0.0889)
		(layer "In2.Cu")
		(net "M_D_ECC<5>")
	)
	(segment
		(start 235.237528 -120.6881)
		(end 235.666534 -120.6881)
		(width 0.14224)
		(layer "In2.Cu")
		(net "M_D_ECC<5>")
	)
	(segment
		(start 243.802662 -100.204778)
		(end 243.802662 -101.623622)
		(width 0.0889)
		(layer "In2.Cu")
		(net "M_D_ECC<5>")
	)
	(segment
		(start 235.101384 -120.346216)
		(end 235.101384 -120.551956)
		(width 0.14224)
		(layer "In2.Cu")
		(net "M_D_ECC<5>")
	)
	(segment
		(start 245.073932 -99.27209)
		(end 244.73535 -99.27209)
		(width 0.0889)
		(layer "In2.Cu")
		(net "M_D_ECC<5>")
	)
	(segment
		(start 235.082842 -121.499122)
		(end 235.082842 -121.852182)
		(width 0.14224)
		(layer "In2.Cu")
		(net "M_D_ECC<5>")
	)
	(segment
		(start 234.85094 -128.60274)
		(end 234.958128 -128.709928)
		(width 0.14224)
		(layer "In2.Cu")
		(net "M_D_ECC<5>")
	)
	(segment
		(start 234.122976 -130.7592)
		(end 234.122976 -131.318)
		(width 0.14224)
		(layer "In2.Cu")
		(net "M_D_ECC<5>")
	)
	(segment
		(start 246.772684 -90.418412)
		(end 246.714772 -90.3605)
		(width 0.0889)
		(layer "In2.Cu")
		(net "M_D_ECC<5>")
	)
	(segment
		(start 246.772684 -90.756486)
		(end 246.772684 -90.418412)
		(width 0.0889)
		(layer "In2.Cu")
		(net "M_D_ECC<5>")
	)
	(segment
		(start 235.101384 -120.551956)
		(end 235.237528 -120.6881)
		(width 0.14224)
		(layer "In2.Cu")
		(net "M_D_ECC<5>")
	)
	(segment
		(start 234.072176 -134.340346)
		(end 233.799888 -134.340346)
		(width 0.14224)
		(layer "In2.Cu")
		(net "M_D_ECC<5>")
	)
	(segment
		(start 234.224576 -134.187946)
		(end 234.072176 -134.340346)
		(width 0.14224)
		(layer "In2.Cu")
		(net "M_D_ECC<5>")
	)
	(segment
		(start 234.696 -128.60274)
		(end 234.85094 -128.60274)
		(width 0.14224)
		(layer "In2.Cu")
		(net "M_D_ECC<5>")
	)
	(segment
		(start 237.1598 -118.2878)
		(end 235.101384 -120.346216)
		(width 0.14224)
		(layer "In2.Cu")
		(net "M_D_ECC<5>")
	)
	(segment
		(start 245.567454 -92.442538)
		(end 245.573804 -92.453206)
		(width 0.0889)
		(layer "In2.Cu")
		(net "M_D_ECC<5>")
	)
	(segment
		(start 234.4928 -128.39954)
		(end 234.696 -128.60274)
		(width 0.14224)
		(layer "In2.Cu")
		(net "M_D_ECC<5>")
	)
	(segment
		(start 233.961178 -133.696456)
		(end 234.224576 -133.959854)
		(width 0.14224)
		(layer "In2.Cu")
		(net "M_D_ECC<5>")
	)
	(segment
		(start 245.573804 -94.01302)
		(end 245.567454 -94.023688)
		(width 0.0889)
		(layer "In2.Cu")
		(net "M_D_ECC<5>")
	)
	(segment
		(start 235.63961 -121.35104)
		(end 235.230924 -121.35104)
		(width 0.14224)
		(layer "In2.Cu")
		(net "M_D_ECC<5>")
	)
	(segment
		(start 237.1598 -110.305596)
		(end 237.1598 -118.2878)
		(width 0.14224)
		(layer "In2.Cu")
		(net "M_D_ECC<5>")
	)
	(segment
		(start 235.801154 -122.16892)
		(end 235.801154 -122.52198)
		(width 0.14224)
		(layer "In2.Cu")
		(net "M_D_ECC<5>")
	)
	(segment
		(start 234.199176 -132.791454)
		(end 234.199176 -133.146546)
		(width 0.14224)
		(layer "In2.Cu")
		(net "M_D_ECC<5>")
	)
	(segment
		(start 234.122976 -131.318)
		(end 234.249976 -131.445)
		(width 0.14224)
		(layer "In2.Cu")
		(net "M_D_ECC<5>")
	)
	(segment
		(start 245.567454 -95.414338)
		(end 245.573804 -95.425006)
		(width 0.0889)
		(layer "In2.Cu")
		(net "M_D_ECC<5>")
	)
	(segment
		(start 245.567454 -98.386138)
		(end 245.573804 -98.396806)
		(width 0.0889)
		(layer "In2.Cu")
		(net "M_D_ECC<5>")
	)
	(segment
		(start 245.931944 -91.84259)
		(end 245.899178 -91.84259)
		(width 0.0889)
		(layer "In2.Cu")
		(net "M_D_ECC<5>")
	)
	(segment
		(start 235.24464 -122.01398)
		(end 235.646214 -122.01398)
		(width 0.14224)
		(layer "In2.Cu")
		(net "M_D_ECC<5>")
	)
	(segment
		(start 245.562628 -97.386902)
		(end 245.567454 -97.395538)
		(width 0.0889)
		(layer "In2.Cu")
		(net "M_D_ECC<5>")
	)
	(segment
		(start 233.961178 -133.384544)
		(end 233.961178 -133.696456)
		(width 0.14224)
		(layer "In2.Cu")
		(net "M_D_ECC<5>")
	)
	(segment
		(start 235.2294 -122.82932)
		(end 235.2294 -125.603)
		(width 0.14224)
		(layer "In2.Cu")
		(net "M_D_ECC<5>")
	)
	(segment
		(start 235.646214 -122.01398)
		(end 235.801154 -122.16892)
		(width 0.14224)
		(layer "In2.Cu")
		(net "M_D_ECC<5>")
	)
	(segment
		(start 243.879878 -101.700838)
		(end 243.879878 -103.585518)
		(width 0.14224)
		(layer "In2.Cu")
		(net "M_D_ECC<5>")
	)
	(segment
		(start 235.666534 -120.6881)
		(end 235.808012 -120.829578)
		(width 0.14224)
		(layer "In2.Cu")
		(net "M_D_ECC<5>")
	)
	(segment
		(start 235.0516 -127.5842)
		(end 234.84586 -127.78994)
		(width 0.14224)
		(layer "In2.Cu")
		(net "M_D_ECC<5>")
	)
	(segment
		(start 234.958128 -129.9464)
		(end 234.573572 -130.330956)
		(width 0.14224)
		(layer "In2.Cu")
		(net "M_D_ECC<5>")
	)
	(arc
		(start 246.714772 -90.3605)
		(mid 246.412503 -90.582049)
		(end 246.425974 -90.956638)
		(width 0.0889)
		(layer "In2.Cu")
		(net "M_D_ECC<5>")
	)
	(arc
		(start 245.899178 -91.84259)
		(mid 245.56626 -92.044581)
		(end 245.562628 -92.433902)
		(width 0.0889)
		(layer "In2.Cu")
		(net "M_D_ECC<5>")
	)
	(arc
		(start 245.573804 -96.415606)
		(mid 245.646602 -96.706369)
		(end 245.567454 -96.995488)
		(width 0.0889)
		(layer "In2.Cu")
		(net "M_D_ECC<5>")
	)
	(arc
		(start 245.573804 -95.425006)
		(mid 245.646602 -95.715769)
		(end 245.567454 -96.004888)
		(width 0.0889)
		(layer "In2.Cu")
		(net "M_D_ECC<5>")
	)
	(arc
		(start 245.567454 -96.995488)
		(mid 245.513984 -97.190551)
		(end 245.562628 -97.386902)
		(width 0.0889)
		(layer "In2.Cu")
		(net "M_D_ECC<5>")
	)
	(arc
		(start 245.567454 -94.423484)
		(mid 245.646585 -94.718886)
		(end 245.567454 -95.014288)
		(width 0.0889)
		(layer "In2.Cu")
		(net "M_D_ECC<5>")
	)
	(arc
		(start 245.573804 -97.406206)
		(mid 245.646602 -97.696969)
		(end 245.567454 -97.986088)
		(width 0.0889)
		(layer "In2.Cu")
		(net "M_D_ECC<5>")
	)
	(arc
		(start 245.573804 -98.396806)
		(mid 245.568955 -98.974426)
		(end 245.073932 -99.27209)
		(width 0.0889)
		(layer "In2.Cu")
		(net "M_D_ECC<5>")
	)
	(arc
		(start 245.567454 -93.033088)
		(mid 245.513984 -93.228151)
		(end 245.562628 -93.424502)
		(width 0.0889)
		(layer "In2.Cu")
		(net "M_D_ECC<5>")
	)
	(arc
		(start 245.567454 -96.004888)
		(mid 245.513984 -96.199951)
		(end 245.562628 -96.396302)
		(width 0.0889)
		(layer "In2.Cu")
		(net "M_D_ECC<5>")
	)
	(arc
		(start 245.567454 -94.023688)
		(mid 245.513955 -94.223586)
		(end 245.567454 -94.423484)
		(width 0.0889)
		(layer "In2.Cu")
		(net "M_D_ECC<5>")
	)
	(arc
		(start 245.567454 -93.433138)
		(mid 245.646676 -93.722256)
		(end 245.573804 -94.01302)
		(width 0.0889)
		(layer "In2.Cu")
		(net "M_D_ECC<5>")
	)
	(arc
		(start 245.567454 -95.014288)
		(mid 245.513984 -95.209351)
		(end 245.562628 -95.405702)
		(width 0.0889)
		(layer "In2.Cu")
		(net "M_D_ECC<5>")
	)
	(arc
		(start 246.425974 -90.956638)
		(mid 246.430303 -91.53981)
		(end 245.931944 -91.84259)
		(width 0.0889)
		(layer "In2.Cu")
		(net "M_D_ECC<5>")
	)
	(arc
		(start 245.573804 -92.453206)
		(mid 245.646602 -92.743969)
		(end 245.567454 -93.033088)
		(width 0.0889)
		(layer "In2.Cu")
		(net "M_D_ECC<5>")
	)
	(arc
		(start 245.567454 -97.986088)
		(mid 245.513984 -98.181151)
		(end 245.562628 -98.377502)
		(width 0.0889)
		(layer "In2.Cu")
		(net "M_D_ECC<5>")
	)
	(segment
		(start 234.65028 -137.67054)
		(end 234.649772 -137.67054)
		(width 0.1651)
		(layer "F.Cu")
		(net "M_D_ECC<4>")
	)
	(segment
		(start 247.344184 -89.765886)
		(end 246.772684 -89.765886)
		(width 0.1651)
		(layer "F.Cu")
		(net "M_D_ECC<4>")
	)
	(segment
		(start 234.649772 -136.345168)
		(end 234.551728 -135.8138)
		(width 0.1651)
		(layer "F.Cu")
		(net "M_D_ECC<4>")
	)
	(segment
		(start 234.649772 -137.67054)
		(end 234.649772 -136.345168)
		(width 0.1651)
		(layer "F.Cu")
		(net "M_D_ECC<4>")
	)
	(via
		(at 233.799888 -131.611878)
		(size 0.508)
		(drill 0.254)
		(layers "F.Cu" "B.Cu")
		(net "M_D_ECC<4>")
	)
	(via
		(at 246.772684 -89.765886)
		(size 0.508)
		(drill 0.254)
		(layers "F.Cu" "B.Cu")
		(net "M_D_ECC<4>")
	)
	(via
		(at 234.551728 -135.8138)
		(size 0.508)
		(drill 0.254)
		(layers "F.Cu" "B.Cu")
		(net "M_D_ECC<4>")
	)
	(segment
		(start 233.799888 -132.875782)
		(end 233.799888 -131.611878)
		(width 0.1651)
		(layer "B.Cu")
		(net "M_D_ECC<4>")
	)
	(segment
		(start 233.800396 -132.876036)
		(end 233.799888 -132.875782)
		(width 0.1651)
		(layer "B.Cu")
		(net "M_D_ECC<4>")
	)
	(segment
		(start 234.079796 -125.570996)
		(end 234.2896 -125.7808)
		(width 0.14224)
		(layer "In2.Cu")
		(net "M_D_ECC<4>")
	)
	(segment
		(start 245.396004 -92.52712)
		(end 245.402354 -92.537788)
		(width 0.0889)
		(layer "In2.Cu")
		(net "M_D_ECC<4>")
	)
	(segment
		(start 245.402354 -93.928438)
		(end 245.396004 -93.939106)
		(width 0.0889)
		(layer "In2.Cu")
		(net "M_D_ECC<4>")
	)
	(segment
		(start 245.396004 -98.47072)
		(end 245.402354 -98.481388)
		(width 0.0889)
		(layer "In2.Cu")
		(net "M_D_ECC<4>")
	)
	(segment
		(start 245.396004 -97.48012)
		(end 245.402354 -97.490788)
		(width 0.0889)
		(layer "In2.Cu")
		(net "M_D_ECC<4>")
	)
	(segment
		(start 233.484928 -130.557778)
		(end 233.484928 -131.296918)
		(width 0.14224)
		(layer "In2.Cu")
		(net "M_D_ECC<4>")
	)
	(segment
		(start 246.772684 -90.10396)
		(end 246.707406 -90.169238)
		(width 0.0889)
		(layer "In2.Cu")
		(net "M_D_ECC<4>")
	)
	(segment
		(start 245.402354 -94.518988)
		(end 245.40718 -94.527624)
		(width 0.0889)
		(layer "In2.Cu")
		(net "M_D_ECC<4>")
	)
	(segment
		(start 233.366818 -134.57809)
		(end 233.524806 -134.736078)
		(width 0.14224)
		(layer "In2.Cu")
		(net "M_D_ECC<4>")
	)
	(segment
		(start 245.07063 -99.081336)
		(end 244.656102 -99.081336)
		(width 0.0889)
		(layer "In2.Cu")
		(net "M_D_ECC<4>")
	)
	(segment
		(start 235.4326 -118.8212)
		(end 235.2548 -118.6434)
		(width 0.14224)
		(layer "In2.Cu")
		(net "M_D_ECC<4>")
	)
	(segment
		(start 235.1024 -118.1354)
		(end 234.7468 -118.1354)
		(width 0.14224)
		(layer "In2.Cu")
		(net "M_D_ECC<4>")
	)
	(segment
		(start 245.402354 -98.481388)
		(end 245.40718 -98.490024)
		(width 0.0889)
		(layer "In2.Cu")
		(net "M_D_ECC<4>")
	)
	(segment
		(start 234.7468 -118.1354)
		(end 234.5944 -118.2878)
		(width 0.14224)
		(layer "In2.Cu")
		(net "M_D_ECC<4>")
	)
	(segment
		(start 245.402354 -92.537788)
		(end 245.40718 -92.546424)
		(width 0.0889)
		(layer "In2.Cu")
		(net "M_D_ECC<4>")
	)
	(segment
		(start 235.2548 -118.6434)
		(end 235.2548 -118.2878)
		(width 0.14224)
		(layer "In2.Cu")
		(net "M_D_ECC<4>")
	)
	(segment
		(start 234.5944 -118.2878)
		(end 234.5944 -124.1298)
		(width 0.14224)
		(layer "In2.Cu")
		(net "M_D_ECC<4>")
	)
	(segment
		(start 234.5944 -124.1298)
		(end 234.079796 -124.644404)
		(width 0.14224)
		(layer "In2.Cu")
		(net "M_D_ECC<4>")
	)
	(segment
		(start 243.225066 -101.487478)
		(end 243.225066 -103.342186)
		(width 0.14224)
		(layer "In2.Cu")
		(net "M_D_ECC<4>")
	)
	(segment
		(start 234.2896 -127.6096)
		(end 234.0102 -127.889)
		(width 0.14224)
		(layer "In2.Cu")
		(net "M_D_ECC<4>")
	)
	(segment
		(start 234.0102 -127.889)
		(end 234.0102 -129.0066)
		(width 0.14224)
		(layer "In2.Cu")
		(net "M_D_ECC<4>")
	)
	(segment
		(start 234.285028 -129.757678)
		(end 233.484928 -130.557778)
		(width 0.14224)
		(layer "In2.Cu")
		(net "M_D_ECC<4>")
	)
	(segment
		(start 234.079796 -124.644404)
		(end 234.079796 -125.570996)
		(width 0.14224)
		(layer "In2.Cu")
		(net "M_D_ECC<4>")
	)
	(segment
		(start 235.2548 -118.2878)
		(end 235.1024 -118.1354)
		(width 0.14224)
		(layer "In2.Cu")
		(net "M_D_ECC<4>")
	)
	(segment
		(start 236.4994 -118.2116)
		(end 235.8898 -118.8212)
		(width 0.14224)
		(layer "In2.Cu")
		(net "M_D_ECC<4>")
	)
	(segment
		(start 243.611908 -101.100636)
		(end 243.225066 -101.487478)
		(width 0.0889)
		(layer "In2.Cu")
		(net "M_D_ECC<4>")
	)
	(segment
		(start 245.402354 -97.490788)
		(end 245.40718 -97.499424)
		(width 0.0889)
		(layer "In2.Cu")
		(net "M_D_ECC<4>")
	)
	(segment
		(start 245.402354 -95.509588)
		(end 245.40718 -95.518224)
		(width 0.0889)
		(layer "In2.Cu")
		(net "M_D_ECC<4>")
	)
	(segment
		(start 233.524806 -135.03783)
		(end 234.300776 -135.8138)
		(width 0.14224)
		(layer "In2.Cu")
		(net "M_D_ECC<4>")
	)
	(segment
		(start 243.611908 -100.12553)
		(end 243.611908 -101.100636)
		(width 0.0889)
		(layer "In2.Cu")
		(net "M_D_ECC<4>")
	)
	(segment
		(start 244.656102 -99.081336)
		(end 243.611908 -100.12553)
		(width 0.0889)
		(layer "In2.Cu")
		(net "M_D_ECC<4>")
	)
	(segment
		(start 245.402354 -96.500188)
		(end 245.40718 -96.508824)
		(width 0.0889)
		(layer "In2.Cu")
		(net "M_D_ECC<4>")
	)
	(segment
		(start 236.4994 -110.067852)
		(end 236.4994 -118.2116)
		(width 0.14224)
		(layer "In2.Cu")
		(net "M_D_ECC<4>")
	)
	(segment
		(start 233.366818 -132.044948)
		(end 233.366818 -134.57809)
		(width 0.14224)
		(layer "In2.Cu")
		(net "M_D_ECC<4>")
	)
	(segment
		(start 245.396004 -96.48952)
		(end 245.402354 -96.500188)
		(width 0.0889)
		(layer "In2.Cu")
		(net "M_D_ECC<4>")
	)
	(segment
		(start 235.8898 -118.8212)
		(end 235.4326 -118.8212)
		(width 0.14224)
		(layer "In2.Cu")
		(net "M_D_ECC<4>")
	)
	(segment
		(start 246.772684 -89.765886)
		(end 246.772684 -90.10396)
		(width 0.0889)
		(layer "In2.Cu")
		(net "M_D_ECC<4>")
	)
	(segment
		(start 234.285028 -129.281428)
		(end 234.285028 -129.757678)
		(width 0.14224)
		(layer "In2.Cu")
		(net "M_D_ECC<4>")
	)
	(segment
		(start 234.0102 -129.0066)
		(end 234.285028 -129.281428)
		(width 0.14224)
		(layer "In2.Cu")
		(net "M_D_ECC<4>")
	)
	(segment
		(start 234.300776 -135.8138)
		(end 234.551728 -135.8138)
		(width 0.14224)
		(layer "In2.Cu")
		(net "M_D_ECC<4>")
	)
	(segment
		(start 245.396004 -95.49892)
		(end 245.402354 -95.509588)
		(width 0.0889)
		(layer "In2.Cu")
		(net "M_D_ECC<4>")
	)
	(segment
		(start 233.524806 -134.736078)
		(end 233.524806 -135.03783)
		(width 0.14224)
		(layer "In2.Cu")
		(net "M_D_ECC<4>")
	)
	(segment
		(start 234.2896 -125.7808)
		(end 234.2896 -127.6096)
		(width 0.14224)
		(layer "In2.Cu")
		(net "M_D_ECC<4>")
	)
	(segment
		(start 245.92534 -91.65209)
		(end 245.892574 -91.65209)
		(width 0.0889)
		(layer "In2.Cu")
		(net "M_D_ECC<4>")
	)
	(segment
		(start 243.225066 -103.342186)
		(end 236.4994 -110.067852)
		(width 0.14224)
		(layer "In2.Cu")
		(net "M_D_ECC<4>")
	)
	(segment
		(start 233.799888 -131.611878)
		(end 233.366818 -132.044948)
		(width 0.14224)
		(layer "In2.Cu")
		(net "M_D_ECC<4>")
	)
	(segment
		(start 233.484928 -131.296918)
		(end 233.799888 -131.611878)
		(width 0.14224)
		(layer "In2.Cu")
		(net "M_D_ECC<4>")
	)
	(arc
		(start 245.40718 -95.518224)
		(mid 245.455935 -95.714576)
		(end 245.402354 -95.909638)
		(width 0.0889)
		(layer "In2.Cu")
		(net "M_D_ECC<4>")
	)
	(arc
		(start 245.402354 -92.937838)
		(mid 245.323223 -93.23324)
		(end 245.402354 -93.528642)
		(width 0.0889)
		(layer "In2.Cu")
		(net "M_D_ECC<4>")
	)
	(arc
		(start 246.260874 -91.051888)
		(mid 246.263622 -91.447355)
		(end 245.92534 -91.65209)
		(width 0.0889)
		(layer "In2.Cu")
		(net "M_D_ECC<4>")
	)
	(arc
		(start 245.40718 -98.490024)
		(mid 245.403433 -98.87928)
		(end 245.07063 -99.081336)
		(width 0.0889)
		(layer "In2.Cu")
		(net "M_D_ECC<4>")
	)
	(arc
		(start 245.396004 -93.939106)
		(mid 245.323206 -94.229869)
		(end 245.402354 -94.518988)
		(width 0.0889)
		(layer "In2.Cu")
		(net "M_D_ECC<4>")
	)
	(arc
		(start 245.40718 -96.508824)
		(mid 245.455935 -96.705176)
		(end 245.402354 -96.900238)
		(width 0.0889)
		(layer "In2.Cu")
		(net "M_D_ECC<4>")
	)
	(arc
		(start 245.40718 -92.546424)
		(mid 245.455935 -92.742776)
		(end 245.402354 -92.937838)
		(width 0.0889)
		(layer "In2.Cu")
		(net "M_D_ECC<4>")
	)
	(arc
		(start 245.40718 -97.499424)
		(mid 245.455935 -97.695776)
		(end 245.402354 -97.890838)
		(width 0.0889)
		(layer "In2.Cu")
		(net "M_D_ECC<4>")
	)
	(arc
		(start 245.40718 -94.527624)
		(mid 245.455935 -94.723976)
		(end 245.402354 -94.919038)
		(width 0.0889)
		(layer "In2.Cu")
		(net "M_D_ECC<4>")
	)
	(arc
		(start 246.707406 -90.169238)
		(mid 246.245437 -90.48978)
		(end 246.260874 -91.051888)
		(width 0.0889)
		(layer "In2.Cu")
		(net "M_D_ECC<4>")
	)
	(arc
		(start 245.402354 -96.900238)
		(mid 245.323132 -97.189356)
		(end 245.396004 -97.48012)
		(width 0.0889)
		(layer "In2.Cu")
		(net "M_D_ECC<4>")
	)
	(arc
		(start 245.402354 -95.909638)
		(mid 245.323132 -96.198756)
		(end 245.396004 -96.48952)
		(width 0.0889)
		(layer "In2.Cu")
		(net "M_D_ECC<4>")
	)
	(arc
		(start 245.402354 -97.890838)
		(mid 245.323132 -98.179956)
		(end 245.396004 -98.47072)
		(width 0.0889)
		(layer "In2.Cu")
		(net "M_D_ECC<4>")
	)
	(arc
		(start 245.402354 -93.528642)
		(mid 245.455853 -93.72854)
		(end 245.402354 -93.928438)
		(width 0.0889)
		(layer "In2.Cu")
		(net "M_D_ECC<4>")
	)
	(arc
		(start 245.892574 -91.65209)
		(mid 245.400184 -91.951023)
		(end 245.396004 -92.52712)
		(width 0.0889)
		(layer "In2.Cu")
		(net "M_D_ECC<4>")
	)
	(arc
		(start 245.402354 -94.919038)
		(mid 245.323132 -95.208156)
		(end 245.396004 -95.49892)
		(width 0.0889)
		(layer "In2.Cu")
		(net "M_D_ECC<4>")
	)
	(segment
		(start 241.44986 -133.076442)
		(end 241.44986 -134.340346)
		(width 0.1651)
		(layer "F.Cu")
		(net "M_D_ECC<3>")
	)
	(segment
		(start 241.450368 -133.0706)
		(end 241.44986 -133.076442)
		(width 0.1651)
		(layer "F.Cu")
		(net "M_D_ECC<3>")
	)
	(segment
		(start 250.778264 -90.756486)
		(end 250.206764 -90.756486)
		(width 0.1651)
		(layer "F.Cu")
		(net "M_D_ECC<3>")
	)
	(via
		(at 250.206764 -90.756486)
		(size 0.508)
		(drill 0.254)
		(layers "F.Cu" "B.Cu")
		(net "M_D_ECC<3>")
	)
	(via
		(at 241.44986 -134.340346)
		(size 0.508)
		(drill 0.254)
		(layers "F.Cu" "B.Cu")
		(net "M_D_ECC<3>")
	)
	(via
		(at 242.299744 -130.330956)
		(size 0.508)
		(drill 0.254)
		(layers "F.Cu" "B.Cu")
		(net "M_D_ECC<3>")
	)
	(segment
		(start 242.299998 -129.025142)
		(end 242.299998 -128.276096)
		(width 0.1651)
		(layer "B.Cu")
		(net "M_D_ECC<3>")
	)
	(segment
		(start 242.299998 -128.276096)
		(end 242.300506 -128.276096)
		(width 0.1651)
		(layer "B.Cu")
		(net "M_D_ECC<3>")
	)
	(segment
		(start 242.299744 -129.025396)
		(end 242.299998 -129.025142)
		(width 0.1651)
		(layer "B.Cu")
		(net "M_D_ECC<3>")
	)
	(segment
		(start 242.299744 -130.330956)
		(end 242.299744 -129.025396)
		(width 0.1651)
		(layer "B.Cu")
		(net "M_D_ECC<3>")
	)
	(segment
		(start 243.511578 -121.9454)
		(end 243.308378 -122.1486)
		(width 0.14224)
		(layer "In2.Cu")
		(net "M_D_ECC<3>")
	)
	(segment
		(start 243.161058 -124.830078)
		(end 242.9002 -125.090936)
		(width 0.14224)
		(layer "In2.Cu")
		(net "M_D_ECC<3>")
	)
	(segment
		(start 249.530616 -103.069898)
		(end 249.760232 -103.299514)
		(width 0.0889)
		(layer "In2.Cu")
		(net "M_D_ECC<3>")
	)
	(segment
		(start 249.760232 -105.814368)
		(end 244.933978 -110.640622)
		(width 0.14224)
		(layer "In2.Cu")
		(net "M_D_ECC<3>")
	)
	(segment
		(start 241.899948 -134.162546)
		(end 241.722148 -134.340346)
		(width 0.14224)
		(layer "In2.Cu")
		(net "M_D_ECC<3>")
	)
	(segment
		(start 242.766596 -129.877312)
		(end 242.299744 -130.344164)
		(width 0.14224)
		(layer "In2.Cu")
		(net "M_D_ECC<3>")
	)
	(segment
		(start 241.893598 -131.233418)
		(end 241.893598 -131.9022)
		(width 0.14224)
		(layer "In2.Cu")
		(net "M_D_ECC<3>")
	)
	(segment
		(start 244.41023 -121.9454)
		(end 243.511578 -121.9454)
		(width 0.14224)
		(layer "In2.Cu")
		(net "M_D_ECC<3>")
	)
	(segment
		(start 244.616478 -122.989594)
		(end 244.616478 -123.342654)
		(width 0.14224)
		(layer "In2.Cu")
		(net "M_D_ECC<3>")
	)
	(segment
		(start 244.933978 -121.421652)
		(end 244.41023 -121.9454)
		(width 0.14224)
		(layer "In2.Cu")
		(net "M_D_ECC<3>")
	)
	(segment
		(start 241.893598 -131.9022)
		(end 241.61115 -132.184648)
		(width 0.14224)
		(layer "In2.Cu")
		(net "M_D_ECC<3>")
	)
	(segment
		(start 250.718574 -92.442538)
		(end 250.724924 -92.453206)
		(width 0.0889)
		(layer "In2.Cu")
		(net "M_D_ECC<3>")
	)
	(segment
		(start 243.308378 -123.659138)
		(end 243.308378 -124.012198)
		(width 0.14224)
		(layer "In2.Cu")
		(net "M_D_ECC<3>")
	)
	(segment
		(start 242.277392 -130.330956)
		(end 241.849148 -130.7592)
		(width 0.14224)
		(layer "In2.Cu")
		(net "M_D_ECC<3>")
	)
	(segment
		(start 244.454934 -123.504198)
		(end 243.463318 -123.504198)
		(width 0.14224)
		(layer "In2.Cu")
		(net "M_D_ECC<3>")
	)
	(segment
		(start 243.463318 -124.167138)
		(end 244.284246 -124.167138)
		(width 0.14224)
		(layer "In2.Cu")
		(net "M_D_ECC<3>")
	)
	(segment
		(start 249.792744 -101.706426)
		(end 249.530616 -101.968554)
		(width 0.0889)
		(layer "In2.Cu")
		(net "M_D_ECC<3>")
	)
	(segment
		(start 250.224544 -94.31909)
		(end 250.18873 -94.31909)
		(width 0.0889)
		(layer "In2.Cu")
		(net "M_D_ECC<3>")
	)
	(segment
		(start 250.66498 -91.01201)
		(end 250.66498 -91.372944)
		(width 0.0889)
		(layer "In2.Cu")
		(net "M_D_ECC<3>")
	)
	(segment
		(start 244.284246 -124.167138)
		(end 244.428772 -124.311664)
		(width 0.14224)
		(layer "In2.Cu")
		(net "M_D_ECC<3>")
	)
	(segment
		(start 241.868198 -133.0198)
		(end 241.61115 -133.276848)
		(width 0.14224)
		(layer "In2.Cu")
		(net "M_D_ECC<3>")
	)
	(segment
		(start 241.849148 -131.188968)
		(end 241.893598 -131.233418)
		(width 0.14224)
		(layer "In2.Cu")
		(net "M_D_ECC<3>")
	)
	(segment
		(start 244.428772 -124.664724)
		(end 244.263418 -124.830078)
		(width 0.14224)
		(layer "In2.Cu")
		(net "M_D_ECC<3>")
	)
	(segment
		(start 241.868198 -132.715)
		(end 241.868198 -133.0198)
		(width 0.14224)
		(layer "In2.Cu")
		(net "M_D_ECC<3>")
	)
	(segment
		(start 250.713748 -93.424502)
		(end 250.718574 -93.433138)
		(width 0.0889)
		(layer "In2.Cu")
		(net "M_D_ECC<3>")
	)
	(segment
		(start 250.206764 -90.756486)
		(end 250.282456 -90.832178)
		(width 0.0889)
		(layer "In2.Cu")
		(net "M_D_ECC<3>")
	)
	(segment
		(start 242.9002 -126.866396)
		(end 242.766596 -127)
		(width 0.14224)
		(layer "In2.Cu")
		(net "M_D_ECC<3>")
	)
	(segment
		(start 250.66498 -91.372944)
		(end 250.70181 -91.422474)
		(width 0.0889)
		(layer "In2.Cu")
		(net "M_D_ECC<3>")
	)
	(segment
		(start 244.616478 -123.342654)
		(end 244.454934 -123.504198)
		(width 0.14224)
		(layer "In2.Cu")
		(net "M_D_ECC<3>")
	)
	(segment
		(start 243.308378 -122.1486)
		(end 243.308378 -122.686318)
		(width 0.14224)
		(layer "In2.Cu")
		(net "M_D_ECC<3>")
	)
	(segment
		(start 242.299744 -130.330956)
		(end 242.277392 -130.330956)
		(width 0.14224)
		(layer "In2.Cu")
		(net "M_D_ECC<3>")
	)
	(segment
		(start 249.866404 -95.49892)
		(end 249.860054 -95.509588)
		(width 0.0889)
		(layer "In2.Cu")
		(net "M_D_ECC<3>")
	)
	(segment
		(start 250.713748 -92.433902)
		(end 250.718574 -92.442538)
		(width 0.0889)
		(layer "In2.Cu")
		(net "M_D_ECC<3>")
	)
	(segment
		(start 244.263418 -124.830078)
		(end 243.161058 -124.830078)
		(width 0.14224)
		(layer "In2.Cu")
		(net "M_D_ECC<3>")
	)
	(segment
		(start 250.718574 -91.451938)
		(end 250.724924 -91.462606)
		(width 0.0889)
		(layer "In2.Cu")
		(net "M_D_ECC<3>")
	)
	(segment
		(start 242.766596 -127)
		(end 242.766596 -129.877312)
		(width 0.14224)
		(layer "In2.Cu")
		(net "M_D_ECC<3>")
	)
	(segment
		(start 241.61115 -133.550152)
		(end 241.899948 -133.83895)
		(width 0.14224)
		(layer "In2.Cu")
		(net "M_D_ECC<3>")
	)
	(segment
		(start 244.933978 -110.640622)
		(end 244.933978 -121.421652)
		(width 0.14224)
		(layer "In2.Cu")
		(net "M_D_ECC<3>")
	)
	(segment
		(start 249.860054 -95.509588)
		(end 249.855228 -95.518224)
		(width 0.0889)
		(layer "In2.Cu")
		(net "M_D_ECC<3>")
	)
	(segment
		(start 242.299744 -130.344164)
		(end 242.299744 -130.330956)
		(width 0.14224)
		(layer "In2.Cu")
		(net "M_D_ECC<3>")
	)
	(segment
		(start 249.760232 -103.299514)
		(end 249.760232 -105.814368)
		(width 0.14224)
		(layer "In2.Cu")
		(net "M_D_ECC<3>")
	)
	(segment
		(start 250.70181 -91.422474)
		(end 250.718574 -91.451938)
		(width 0.0889)
		(layer "In2.Cu")
		(net "M_D_ECC<3>")
	)
	(segment
		(start 243.308378 -122.686318)
		(end 243.463318 -122.841258)
		(width 0.14224)
		(layer "In2.Cu")
		(net "M_D_ECC<3>")
	)
	(segment
		(start 243.463318 -123.504198)
		(end 243.308378 -123.659138)
		(width 0.14224)
		(layer "In2.Cu")
		(net "M_D_ECC<3>")
	)
	(segment
		(start 241.899948 -133.83895)
		(end 241.899948 -134.162546)
		(width 0.14224)
		(layer "In2.Cu")
		(net "M_D_ECC<3>")
	)
	(segment
		(start 249.866404 -96.48952)
		(end 249.792744 -96.620584)
		(width 0.0889)
		(layer "In2.Cu")
		(net "M_D_ECC<3>")
	)
	(segment
		(start 241.61115 -133.276848)
		(end 241.61115 -133.550152)
		(width 0.14224)
		(layer "In2.Cu")
		(net "M_D_ECC<3>")
	)
	(segment
		(start 244.428772 -124.311664)
		(end 244.428772 -124.664724)
		(width 0.14224)
		(layer "In2.Cu")
		(net "M_D_ECC<3>")
	)
	(segment
		(start 249.792744 -96.620584)
		(end 249.792744 -101.706426)
		(width 0.0889)
		(layer "In2.Cu")
		(net "M_D_ECC<3>")
	)
	(segment
		(start 243.463318 -122.841258)
		(end 244.468142 -122.841258)
		(width 0.14224)
		(layer "In2.Cu")
		(net "M_D_ECC<3>")
	)
	(segment
		(start 250.485148 -90.832178)
		(end 250.66498 -91.01201)
		(width 0.0889)
		(layer "In2.Cu")
		(net "M_D_ECC<3>")
	)
	(segment
		(start 249.530616 -101.968554)
		(end 249.530616 -103.069898)
		(width 0.0889)
		(layer "In2.Cu")
		(net "M_D_ECC<3>")
	)
	(segment
		(start 242.9002 -125.090936)
		(end 242.9002 -126.866396)
		(width 0.14224)
		(layer "In2.Cu")
		(net "M_D_ECC<3>")
	)
	(segment
		(start 241.849148 -130.7592)
		(end 241.849148 -131.188968)
		(width 0.14224)
		(layer "In2.Cu")
		(net "M_D_ECC<3>")
	)
	(segment
		(start 241.722148 -134.340346)
		(end 241.44986 -134.340346)
		(width 0.14224)
		(layer "In2.Cu")
		(net "M_D_ECC<3>")
	)
	(segment
		(start 250.282456 -90.832178)
		(end 250.485148 -90.832178)
		(width 0.0889)
		(layer "In2.Cu")
		(net "M_D_ECC<3>")
	)
	(segment
		(start 243.308378 -124.012198)
		(end 243.463318 -124.167138)
		(width 0.14224)
		(layer "In2.Cu")
		(net "M_D_ECC<3>")
	)
	(segment
		(start 244.468142 -122.841258)
		(end 244.616478 -122.989594)
		(width 0.14224)
		(layer "In2.Cu")
		(net "M_D_ECC<3>")
	)
	(segment
		(start 241.61115 -132.457952)
		(end 241.868198 -132.715)
		(width 0.14224)
		(layer "In2.Cu")
		(net "M_D_ECC<3>")
	)
	(segment
		(start 241.61115 -132.184648)
		(end 241.61115 -132.457952)
		(width 0.14224)
		(layer "In2.Cu")
		(net "M_D_ECC<3>")
	)
	(arc
		(start 250.718574 -92.042488)
		(mid 250.665104 -92.237551)
		(end 250.713748 -92.433902)
		(width 0.0889)
		(layer "In2.Cu")
		(net "M_D_ECC<3>")
	)
	(arc
		(start 249.860054 -95.909638)
		(mid 249.939276 -96.198756)
		(end 249.866404 -96.48952)
		(width 0.0889)
		(layer "In2.Cu")
		(net "M_D_ECC<3>")
	)
	(arc
		(start 250.718574 -93.033088)
		(mid 250.665104 -93.228151)
		(end 250.713748 -93.424502)
		(width 0.0889)
		(layer "In2.Cu")
		(net "M_D_ECC<3>")
	)
	(arc
		(start 249.855228 -95.518224)
		(mid 249.806473 -95.714576)
		(end 249.860054 -95.909638)
		(width 0.0889)
		(layer "In2.Cu")
		(net "M_D_ECC<3>")
	)
	(arc
		(start 250.718574 -93.433138)
		(mid 250.722903 -94.01631)
		(end 250.224544 -94.31909)
		(width 0.0889)
		(layer "In2.Cu")
		(net "M_D_ECC<3>")
	)
	(arc
		(start 250.724924 -91.462606)
		(mid 250.797722 -91.753369)
		(end 250.718574 -92.042488)
		(width 0.0889)
		(layer "In2.Cu")
		(net "M_D_ECC<3>")
	)
	(arc
		(start 250.724924 -92.453206)
		(mid 250.797722 -92.743969)
		(end 250.718574 -93.033088)
		(width 0.0889)
		(layer "In2.Cu")
		(net "M_D_ECC<3>")
	)
	(arc
		(start 249.860054 -94.919038)
		(mid 249.939276 -95.208156)
		(end 249.866404 -95.49892)
		(width 0.0889)
		(layer "In2.Cu")
		(net "M_D_ECC<3>")
	)
	(arc
		(start 250.18873 -94.31909)
		(mid 249.855761 -94.526638)
		(end 249.860054 -94.919038)
		(width 0.0889)
		(layer "In2.Cu")
		(net "M_D_ECC<3>")
	)
	(segment
		(start 242.299744 -136.679432)
		(end 242.299744 -137.67054)
		(width 0.1651)
		(layer "F.Cu")
		(net "M_D_ECC<2>")
	)
	(segment
		(start 242.299744 -136.192768)
		(end 242.431316 -136.32434)
		(width 0.1651)
		(layer "F.Cu")
		(net "M_D_ECC<2>")
	)
	(segment
		(start 242.431316 -136.54786)
		(end 242.299744 -136.679432)
		(width 0.1651)
		(layer "F.Cu")
		(net "M_D_ECC<2>")
	)
	(segment
		(start 250.778264 -89.765886)
		(end 250.206764 -89.765886)
		(width 0.1651)
		(layer "F.Cu")
		(net "M_D_ECC<2>")
	)
	(segment
		(start 242.299744 -137.67054)
		(end 242.300506 -137.67054)
		(width 0.1651)
		(layer "F.Cu")
		(net "M_D_ECC<2>")
	)
	(segment
		(start 242.431316 -136.32434)
		(end 242.431316 -136.54786)
		(width 0.1651)
		(layer "F.Cu")
		(net "M_D_ECC<2>")
	)
	(segment
		(start 242.299744 -135.9154)
		(end 242.299744 -136.192768)
		(width 0.1651)
		(layer "F.Cu")
		(net "M_D_ECC<2>")
	)
	(via
		(at 250.206764 -89.765886)
		(size 0.508)
		(drill 0.254)
		(layers "F.Cu" "B.Cu")
		(net "M_D_ECC<2>")
	)
	(via
		(at 241.44986 -131.611878)
		(size 0.508)
		(drill 0.254)
		(layers "F.Cu" "B.Cu")
		(net "M_D_ECC<2>")
	)
	(via
		(at 242.299744 -135.9154)
		(size 0.508)
		(drill 0.254)
		(layers "F.Cu" "B.Cu")
		(net "M_D_ECC<2>")
	)
	(segment
		(start 241.450368 -132.876036)
		(end 241.44986 -132.875782)
		(width 0.1651)
		(layer "B.Cu")
		(net "M_D_ECC<2>")
	)
	(segment
		(start 241.44986 -132.875782)
		(end 241.44986 -131.611878)
		(width 0.1651)
		(layer "B.Cu")
		(net "M_D_ECC<2>")
	)
	(segment
		(start 250.553474 -92.537788)
		(end 250.5583 -92.546424)
		(width 0.0889)
		(layer "In2.Cu")
		(net "M_D_ECC<2>")
	)
	(segment
		(start 249.985784 -90.210894)
		(end 249.985784 -90.365834)
		(width 0.0889)
		(layer "In2.Cu")
		(net "M_D_ECC<2>")
	)
	(segment
		(start 243.297964 -120.508776)
		(end 243.456206 -120.667018)
		(width 0.14224)
		(layer "In2.Cu")
		(net "M_D_ECC<2>")
	)
	(segment
		(start 250.417076 -91.310714)
		(end 250.417076 -91.35872)
		(width 0.0889)
		(layer "In2.Cu")
		(net "M_D_ECC<2>")
	)
	(segment
		(start 241.968528 -126.9238)
		(end 241.968528 -129.770378)
		(width 0.14224)
		(layer "In2.Cu")
		(net "M_D_ECC<2>")
	)
	(segment
		(start 249.340624 -103.071422)
		(end 249.112532 -103.299514)
		(width 0.0889)
		(layer "In2.Cu")
		(net "M_D_ECC<2>")
	)
	(segment
		(start 244.259862 -110.476538)
		(end 244.259862 -118.397274)
		(width 0.14224)
		(layer "In2.Cu")
		(net "M_D_ECC<2>")
	)
	(segment
		(start 241.968528 -129.770378)
		(end 241.104928 -130.633978)
		(width 0.14224)
		(layer "In2.Cu")
		(net "M_D_ECC<2>")
	)
	(segment
		(start 241.104928 -131.266946)
		(end 241.44986 -131.611878)
		(width 0.14224)
		(layer "In2.Cu")
		(net "M_D_ECC<2>")
	)
	(segment
		(start 241.8842 -125.476)
		(end 241.8842 -126.839472)
		(width 0.14224)
		(layer "In2.Cu")
		(net "M_D_ECC<2>")
	)
	(segment
		(start 241.01679 -134.632446)
		(end 242.299744 -135.9154)
		(width 0.14224)
		(layer "In2.Cu")
		(net "M_D_ECC<2>")
	)
	(segment
		(start 249.69978 -96.396302)
		(end 249.602752 -96.570038)
		(width 0.0889)
		(layer "In2.Cu")
		(net "M_D_ECC<2>")
	)
	(segment
		(start 249.694954 -95.414338)
		(end 249.688604 -95.425006)
		(width 0.0889)
		(layer "In2.Cu")
		(net "M_D_ECC<2>")
	)
	(segment
		(start 243.456206 -121.175018)
		(end 243.309648 -121.321576)
		(width 0.14224)
		(layer "In2.Cu")
		(net "M_D_ECC<2>")
	)
	(segment
		(start 242.90528 -121.321576)
		(end 242.6716 -121.555256)
		(width 0.14224)
		(layer "In2.Cu")
		(net "M_D_ECC<2>")
	)
	(segment
		(start 242.6716 -121.555256)
		(end 242.6716 -123.5202)
		(width 0.14224)
		(layer "In2.Cu")
		(net "M_D_ECC<2>")
	)
	(segment
		(start 249.711464 -89.936574)
		(end 249.985784 -90.210894)
		(width 0.0889)
		(layer "In2.Cu")
		(net "M_D_ECC<2>")
	)
	(segment
		(start 250.54052 -91.524836)
		(end 250.5583 -91.555824)
		(width 0.0889)
		(layer "In2.Cu")
		(net "M_D_ECC<2>")
	)
	(segment
		(start 242.2906 -125.0696)
		(end 241.8842 -125.476)
		(width 0.14224)
		(layer "In2.Cu")
		(net "M_D_ECC<2>")
	)
	(segment
		(start 249.602752 -101.627686)
		(end 249.340624 -101.889814)
		(width 0.0889)
		(layer "In2.Cu")
		(net "M_D_ECC<2>")
	)
	(segment
		(start 249.769884 -90.866468)
		(end 249.860054 -90.956638)
		(width 0.0889)
		(layer "In2.Cu")
		(net "M_D_ECC<2>")
	)
	(segment
		(start 249.884692 -89.278206)
		(end 249.711464 -89.451434)
		(width 0.0889)
		(layer "In2.Cu")
		(net "M_D_ECC<2>")
	)
	(segment
		(start 242.772692 -119.884444)
		(end 242.772692 -120.305576)
		(width 0.14224)
		(layer "In2.Cu")
		(net "M_D_ECC<2>")
	)
	(segment
		(start 249.602752 -96.570038)
		(end 249.602752 -101.627686)
		(width 0.0889)
		(layer "In2.Cu")
		(net "M_D_ECC<2>")
	)
	(segment
		(start 250.224798 -94.128336)
		(end 250.185174 -94.128336)
		(width 0.0889)
		(layer "In2.Cu")
		(net "M_D_ECC<2>")
	)
	(segment
		(start 242.2906 -123.9012)
		(end 242.2906 -125.0696)
		(width 0.14224)
		(layer "In2.Cu")
		(net "M_D_ECC<2>")
	)
	(segment
		(start 250.417076 -91.35872)
		(end 250.54052 -91.524836)
		(width 0.0889)
		(layer "In2.Cu")
		(net "M_D_ECC<2>")
	)
	(segment
		(start 249.112532 -105.623868)
		(end 244.259862 -110.476538)
		(width 0.14224)
		(layer "In2.Cu")
		(net "M_D_ECC<2>")
	)
	(segment
		(start 242.772692 -120.305576)
		(end 242.975892 -120.508776)
		(width 0.14224)
		(layer "In2.Cu")
		(net "M_D_ECC<2>")
	)
	(segment
		(start 242.975892 -120.508776)
		(end 243.297964 -120.508776)
		(width 0.14224)
		(layer "In2.Cu")
		(net "M_D_ECC<2>")
	)
	(segment
		(start 250.023884 -89.278206)
		(end 249.884692 -89.278206)
		(width 0.0889)
		(layer "In2.Cu")
		(net "M_D_ECC<2>")
	)
	(segment
		(start 242.6716 -123.5202)
		(end 242.2906 -123.9012)
		(width 0.14224)
		(layer "In2.Cu")
		(net "M_D_ECC<2>")
	)
	(segment
		(start 250.547124 -92.52712)
		(end 250.553474 -92.537788)
		(width 0.0889)
		(layer "In2.Cu")
		(net "M_D_ECC<2>")
	)
	(segment
		(start 243.309648 -121.321576)
		(end 242.90528 -121.321576)
		(width 0.14224)
		(layer "In2.Cu")
		(net "M_D_ECC<2>")
	)
	(segment
		(start 249.340624 -101.889814)
		(end 249.340624 -103.071422)
		(width 0.0889)
		(layer "In2.Cu")
		(net "M_D_ECC<2>")
	)
	(segment
		(start 250.396248 -91.274646)
		(end 250.417076 -91.310714)
		(width 0.0889)
		(layer "In2.Cu")
		(net "M_D_ECC<2>")
	)
	(segment
		(start 249.769884 -90.581734)
		(end 249.769884 -90.866468)
		(width 0.0889)
		(layer "In2.Cu")
		(net "M_D_ECC<2>")
	)
	(segment
		(start 241.8842 -126.839472)
		(end 241.968528 -126.9238)
		(width 0.14224)
		(layer "In2.Cu")
		(net "M_D_ECC<2>")
	)
	(segment
		(start 241.01679 -132.044948)
		(end 241.01679 -134.632446)
		(width 0.14224)
		(layer "In2.Cu")
		(net "M_D_ECC<2>")
	)
	(segment
		(start 244.259862 -118.397274)
		(end 242.772692 -119.884444)
		(width 0.14224)
		(layer "In2.Cu")
		(net "M_D_ECC<2>")
	)
	(segment
		(start 249.711464 -89.451434)
		(end 249.711464 -89.936574)
		(width 0.0889)
		(layer "In2.Cu")
		(net "M_D_ECC<2>")
	)
	(segment
		(start 243.456206 -120.667018)
		(end 243.456206 -121.175018)
		(width 0.14224)
		(layer "In2.Cu")
		(net "M_D_ECC<2>")
	)
	(segment
		(start 241.104928 -130.633978)
		(end 241.104928 -131.266946)
		(width 0.14224)
		(layer "In2.Cu")
		(net "M_D_ECC<2>")
	)
	(segment
		(start 250.206764 -89.765886)
		(end 250.206764 -89.461086)
		(width 0.0889)
		(layer "In2.Cu")
		(net "M_D_ECC<2>")
	)
	(segment
		(start 241.44986 -131.611878)
		(end 241.01679 -132.044948)
		(width 0.14224)
		(layer "In2.Cu")
		(net "M_D_ECC<2>")
	)
	(segment
		(start 250.206764 -89.461086)
		(end 250.023884 -89.278206)
		(width 0.0889)
		(layer "In2.Cu")
		(net "M_D_ECC<2>")
	)
	(segment
		(start 250.191778 -91.156536)
		(end 250.192032 -91.156536)
		(width 0.0889)
		(layer "In2.Cu")
		(net "M_D_ECC<2>")
	)
	(segment
		(start 249.985784 -90.365834)
		(end 249.769884 -90.581734)
		(width 0.0889)
		(layer "In2.Cu")
		(net "M_D_ECC<2>")
	)
	(segment
		(start 249.69978 -95.405702)
		(end 249.694954 -95.414338)
		(width 0.0889)
		(layer "In2.Cu")
		(net "M_D_ECC<2>")
	)
	(segment
		(start 249.112532 -103.299514)
		(end 249.112532 -105.623868)
		(width 0.14224)
		(layer "In2.Cu")
		(net "M_D_ECC<2>")
	)
	(arc
		(start 249.694954 -96.004888)
		(mid 249.748424 -96.199951)
		(end 249.69978 -96.396302)
		(width 0.0889)
		(layer "In2.Cu")
		(net "M_D_ECC<2>")
	)
	(arc
		(start 250.5583 -92.546424)
		(mid 250.607055 -92.742776)
		(end 250.553474 -92.937838)
		(width 0.0889)
		(layer "In2.Cu")
		(net "M_D_ECC<2>")
	)
	(arc
		(start 249.688604 -95.425006)
		(mid 249.615806 -95.715769)
		(end 249.694954 -96.004888)
		(width 0.0889)
		(layer "In2.Cu")
		(net "M_D_ECC<2>")
	)
	(arc
		(start 250.553474 -93.528642)
		(mid 250.557719 -93.920887)
		(end 250.224798 -94.128336)
		(width 0.0889)
		(layer "In2.Cu")
		(net "M_D_ECC<2>")
	)
	(arc
		(start 249.860054 -90.956638)
		(mid 250.000133 -91.099374)
		(end 250.191778 -91.156536)
		(width 0.0889)
		(layer "In2.Cu")
		(net "M_D_ECC<2>")
	)
	(arc
		(start 250.553474 -91.947238)
		(mid 250.474252 -92.236356)
		(end 250.547124 -92.52712)
		(width 0.0889)
		(layer "In2.Cu")
		(net "M_D_ECC<2>")
	)
	(arc
		(start 250.5583 -91.555824)
		(mid 250.607055 -91.752176)
		(end 250.553474 -91.947238)
		(width 0.0889)
		(layer "In2.Cu")
		(net "M_D_ECC<2>")
	)
	(arc
		(start 250.185174 -94.128336)
		(mid 249.689697 -94.432779)
		(end 249.694954 -95.014288)
		(width 0.0889)
		(layer "In2.Cu")
		(net "M_D_ECC<2>")
	)
	(arc
		(start 250.192032 -91.156536)
		(mid 250.310001 -91.188181)
		(end 250.396248 -91.274646)
		(width 0.0889)
		(layer "In2.Cu")
		(net "M_D_ECC<2>")
	)
	(arc
		(start 249.694954 -95.014288)
		(mid 249.748424 -95.209351)
		(end 249.69978 -95.405702)
		(width 0.0889)
		(layer "In2.Cu")
		(net "M_D_ECC<2>")
	)
	(arc
		(start 250.553474 -92.937838)
		(mid 250.474343 -93.23324)
		(end 250.553474 -93.528642)
		(width 0.0889)
		(layer "In2.Cu")
		(net "M_D_ECC<2>")
	)
	(segment
		(start 235.49991 -133.076442)
		(end 235.49991 -134.340346)
		(width 0.1651)
		(layer "F.Cu")
		(net "M_D_ECC<1>")
	)
	(segment
		(start 248.202704 -91.25204)
		(end 247.631204 -91.25204)
		(width 0.1651)
		(layer "F.Cu")
		(net "M_D_ECC<1>")
	)
	(segment
		(start 235.500418 -133.0706)
		(end 235.49991 -133.076442)
		(width 0.1651)
		(layer "F.Cu")
		(net "M_D_ECC<1>")
	)
	(via
		(at 247.631204 -91.25204)
		(size 0.508)
		(drill 0.254)
		(layers "F.Cu" "B.Cu")
		(net "M_D_ECC<1>")
	)
	(via
		(at 236.171994 -130.330956)
		(size 0.508)
		(drill 0.254)
		(layers "F.Cu" "B.Cu")
		(net "M_D_ECC<1>")
	)
	(via
		(at 235.49991 -134.340346)
		(size 0.508)
		(drill 0.254)
		(layers "F.Cu" "B.Cu")
		(net "M_D_ECC<1>")
	)
	(segment
		(start 236.349794 -129.649982)
		(end 236.171994 -129.827782)
		(width 0.1651)
		(layer "B.Cu")
		(net "M_D_ECC<1>")
	)
	(segment
		(start 236.349794 -128.276096)
		(end 236.349794 -129.649982)
		(width 0.1651)
		(layer "B.Cu")
		(net "M_D_ECC<1>")
	)
	(segment
		(start 236.350302 -128.276096)
		(end 236.349794 -128.276096)
		(width 0.1651)
		(layer "B.Cu")
		(net "M_D_ECC<1>")
	)
	(segment
		(start 236.171994 -129.827782)
		(end 236.171994 -130.330956)
		(width 0.1651)
		(layer "B.Cu")
		(net "M_D_ECC<1>")
	)
	(segment
		(start 235.721398 -130.7592)
		(end 235.721398 -131.188968)
		(width 0.14224)
		(layer "In2.Cu")
		(net "M_D_ECC<1>")
	)
	(segment
		(start 236.171994 -130.330956)
		(end 236.149642 -130.330956)
		(width 0.14224)
		(layer "In2.Cu")
		(net "M_D_ECC<1>")
	)
	(segment
		(start 245.471696 -100.132134)
		(end 244.9703 -100.63353)
		(width 0.0889)
		(layer "In2.Cu")
		(net "M_D_ECC<1>")
	)
	(segment
		(start 246.425974 -96.900238)
		(end 246.432324 -96.910906)
		(width 0.0889)
		(layer "In2.Cu")
		(net "M_D_ECC<1>")
	)
	(segment
		(start 235.74883 -134.340346)
		(end 235.49991 -134.340346)
		(width 0.14224)
		(layer "In2.Cu")
		(net "M_D_ECC<1>")
	)
	(segment
		(start 236.8296 -121.9454)
		(end 236.98708 -122.10288)
		(width 0.14224)
		(layer "In2.Cu")
		(net "M_D_ECC<1>")
	)
	(segment
		(start 238.4552 -121.20753)
		(end 238.2774 -121.38533)
		(width 0.14224)
		(layer "In2.Cu")
		(net "M_D_ECC<1>")
	)
	(segment
		(start 247.631204 -91.25204)
		(end 247.301258 -92.013786)
		(width 0.0889)
		(layer "In2.Cu")
		(net "M_D_ECC<1>")
	)
	(segment
		(start 237.617 -122.555)
		(end 237.40618 -122.76582)
		(width 0.14224)
		(layer "In2.Cu")
		(net "M_D_ECC<1>")
	)
	(segment
		(start 236.659928 -129.843022)
		(end 236.171994 -130.330956)
		(width 0.14224)
		(layer "In2.Cu")
		(net "M_D_ECC<1>")
	)
	(segment
		(start 237.6932 -121.18213)
		(end 237.6932 -120.233186)
		(width 0.14224)
		(layer "In2.Cu")
		(net "M_D_ECC<1>")
	)
	(segment
		(start 237.6932 -120.233186)
		(end 237.44428 -119.984266)
		(width 0.14224)
		(layer "In2.Cu")
		(net "M_D_ECC<1>")
	)
	(segment
		(start 236.149642 -130.330956)
		(end 235.721398 -130.7592)
		(width 0.14224)
		(layer "In2.Cu")
		(net "M_D_ECC<1>")
	)
	(segment
		(start 235.875576 -133.1214)
		(end 235.6612 -133.335776)
		(width 0.14224)
		(layer "In2.Cu")
		(net "M_D_ECC<1>")
	)
	(segment
		(start 235.6612 -133.643624)
		(end 235.900976 -133.8834)
		(width 0.14224)
		(layer "In2.Cu")
		(net "M_D_ECC<1>")
	)
	(segment
		(start 236.8296 -120.192546)
		(end 236.8296 -121.9454)
		(width 0.14224)
		(layer "In2.Cu")
		(net "M_D_ECC<1>")
	)
	(segment
		(start 237.46206 -122.10288)
		(end 237.617 -122.25782)
		(width 0.14224)
		(layer "In2.Cu")
		(net "M_D_ECC<1>")
	)
	(segment
		(start 237.8964 -121.38533)
		(end 237.6932 -121.18213)
		(width 0.14224)
		(layer "In2.Cu")
		(net "M_D_ECC<1>")
	)
	(segment
		(start 246.432324 -95.49892)
		(end 246.425974 -95.509588)
		(width 0.0889)
		(layer "In2.Cu")
		(net "M_D_ECC<1>")
	)
	(segment
		(start 246.425974 -94.518988)
		(end 246.421148 -94.527624)
		(width 0.0889)
		(layer "In2.Cu")
		(net "M_D_ECC<1>")
	)
	(segment
		(start 237.40618 -122.76582)
		(end 236.97438 -122.76582)
		(width 0.14224)
		(layer "In2.Cu")
		(net "M_D_ECC<1>")
	)
	(segment
		(start 235.6612 -132.475224)
		(end 235.875576 -132.6896)
		(width 0.14224)
		(layer "In2.Cu")
		(net "M_D_ECC<1>")
	)
	(segment
		(start 245.567454 -99.967288)
		(end 245.566946 -99.967034)
		(width 0.0889)
		(layer "In2.Cu")
		(net "M_D_ECC<1>")
	)
	(segment
		(start 246.425974 -95.509588)
		(end 246.421148 -95.518224)
		(width 0.0889)
		(layer "In2.Cu")
		(net "M_D_ECC<1>")
	)
	(segment
		(start 235.951776 -131.419346)
		(end 235.951776 -131.823968)
		(width 0.14224)
		(layer "In2.Cu")
		(net "M_D_ECC<1>")
	)
	(segment
		(start 245.566946 -99.967034)
		(end 245.471696 -100.132134)
		(width 0.0889)
		(layer "In2.Cu")
		(net "M_D_ECC<1>")
	)
	(segment
		(start 235.900976 -134.1882)
		(end 235.74883 -134.340346)
		(width 0.14224)
		(layer "In2.Cu")
		(net "M_D_ECC<1>")
	)
	(segment
		(start 246.425974 -93.928438)
		(end 246.432324 -93.939106)
		(width 0.0889)
		(layer "In2.Cu")
		(net "M_D_ECC<1>")
	)
	(segment
		(start 238.2774 -121.38533)
		(end 237.8964 -121.38533)
		(width 0.14224)
		(layer "In2.Cu")
		(net "M_D_ECC<1>")
	)
	(segment
		(start 235.6612 -132.114544)
		(end 235.6612 -132.475224)
		(width 0.14224)
		(layer "In2.Cu")
		(net "M_D_ECC<1>")
	)
	(segment
		(start 247.301258 -92.013786)
		(end 247.284494 -92.042488)
		(width 0.0889)
		(layer "In2.Cu")
		(net "M_D_ECC<1>")
	)
	(segment
		(start 236.8296 -122.9106)
		(end 236.8296 -124.0536)
		(width 0.14224)
		(layer "In2.Cu")
		(net "M_D_ECC<1>")
	)
	(segment
		(start 246.432324 -98.47072)
		(end 246.425974 -98.481388)
		(width 0.0889)
		(layer "In2.Cu")
		(net "M_D_ECC<1>")
	)
	(segment
		(start 236.97438 -122.76582)
		(end 236.8296 -122.9106)
		(width 0.14224)
		(layer "In2.Cu")
		(net "M_D_ECC<1>")
	)
	(segment
		(start 235.6612 -133.335776)
		(end 235.6612 -133.643624)
		(width 0.14224)
		(layer "In2.Cu")
		(net "M_D_ECC<1>")
	)
	(segment
		(start 237.44428 -119.984266)
		(end 237.03788 -119.984266)
		(width 0.14224)
		(layer "In2.Cu")
		(net "M_D_ECC<1>")
	)
	(segment
		(start 236.8296 -124.0536)
		(end 236.659928 -124.223272)
		(width 0.14224)
		(layer "In2.Cu")
		(net "M_D_ECC<1>")
	)
	(segment
		(start 237.03788 -119.984266)
		(end 236.8296 -120.192546)
		(width 0.14224)
		(layer "In2.Cu")
		(net "M_D_ECC<1>")
	)
	(segment
		(start 238.4552 -110.824518)
		(end 238.4552 -121.20753)
		(width 0.14224)
		(layer "In2.Cu")
		(net "M_D_ECC<1>")
	)
	(segment
		(start 235.900976 -133.8834)
		(end 235.900976 -134.1882)
		(width 0.14224)
		(layer "In2.Cu")
		(net "M_D_ECC<1>")
	)
	(segment
		(start 246.425974 -97.490788)
		(end 246.421148 -97.499424)
		(width 0.0889)
		(layer "In2.Cu")
		(net "M_D_ECC<1>")
	)
	(segment
		(start 236.98708 -122.10288)
		(end 237.46206 -122.10288)
		(width 0.14224)
		(layer "In2.Cu")
		(net "M_D_ECC<1>")
	)
	(segment
		(start 246.425974 -98.881438)
		(end 246.427498 -98.883724)
		(width 0.0889)
		(layer "In2.Cu")
		(net "M_D_ECC<1>")
	)
	(segment
		(start 246.432324 -96.48952)
		(end 246.425974 -96.500188)
		(width 0.0889)
		(layer "In2.Cu")
		(net "M_D_ECC<1>")
	)
	(segment
		(start 244.9703 -101.850952)
		(end 245.180104 -102.060756)
		(width 0.0889)
		(layer "In2.Cu")
		(net "M_D_ECC<1>")
	)
	(segment
		(start 245.180104 -102.060756)
		(end 245.180104 -104.099614)
		(width 0.14224)
		(layer "In2.Cu")
		(net "M_D_ECC<1>")
	)
	(segment
		(start 246.794274 -92.337636)
		(end 246.761508 -92.337636)
		(width 0.0889)
		(layer "In2.Cu")
		(net "M_D_ECC<1>")
	)
	(segment
		(start 246.425974 -96.500188)
		(end 246.421148 -96.508824)
		(width 0.0889)
		(layer "In2.Cu")
		(net "M_D_ECC<1>")
	)
	(segment
		(start 236.659928 -124.223272)
		(end 236.659928 -129.843022)
		(width 0.14224)
		(layer "In2.Cu")
		(net "M_D_ECC<1>")
	)
	(segment
		(start 235.875576 -132.6896)
		(end 235.875576 -133.1214)
		(width 0.14224)
		(layer "In2.Cu")
		(net "M_D_ECC<1>")
	)
	(segment
		(start 237.617 -122.25782)
		(end 237.617 -122.555)
		(width 0.14224)
		(layer "In2.Cu")
		(net "M_D_ECC<1>")
	)
	(segment
		(start 245.180104 -104.099614)
		(end 238.4552 -110.824518)
		(width 0.14224)
		(layer "In2.Cu")
		(net "M_D_ECC<1>")
	)
	(segment
		(start 244.9703 -100.63353)
		(end 244.9703 -101.850952)
		(width 0.0889)
		(layer "In2.Cu")
		(net "M_D_ECC<1>")
	)
	(segment
		(start 246.425974 -98.481388)
		(end 246.421148 -98.490024)
		(width 0.0889)
		(layer "In2.Cu")
		(net "M_D_ECC<1>")
	)
	(segment
		(start 245.937532 -99.76739)
		(end 245.89613 -99.76739)
		(width 0.0889)
		(layer "In2.Cu")
		(net "M_D_ECC<1>")
	)
	(segment
		(start 235.721398 -131.188968)
		(end 235.951776 -131.419346)
		(width 0.14224)
		(layer "In2.Cu")
		(net "M_D_ECC<1>")
	)
	(segment
		(start 235.951776 -131.823968)
		(end 235.6612 -132.114544)
		(width 0.14224)
		(layer "In2.Cu")
		(net "M_D_ECC<1>")
	)
	(arc
		(start 247.284494 -92.042488)
		(mid 247.07749 -92.253352)
		(end 246.794274 -92.337636)
		(width 0.0889)
		(layer "In2.Cu")
		(net "M_D_ECC<1>")
	)
	(arc
		(start 246.761508 -92.337636)
		(mid 246.423339 -92.542434)
		(end 246.425974 -92.937838)
		(width 0.0889)
		(layer "In2.Cu")
		(net "M_D_ECC<1>")
	)
	(arc
		(start 246.425974 -94.919038)
		(mid 246.505196 -95.208156)
		(end 246.432324 -95.49892)
		(width 0.0889)
		(layer "In2.Cu")
		(net "M_D_ECC<1>")
	)
	(arc
		(start 246.421148 -97.499424)
		(mid 246.372393 -97.695776)
		(end 246.425974 -97.890838)
		(width 0.0889)
		(layer "In2.Cu")
		(net "M_D_ECC<1>")
	)
	(arc
		(start 246.425974 -93.528642)
		(mid 246.372475 -93.72854)
		(end 246.425974 -93.928438)
		(width 0.0889)
		(layer "In2.Cu")
		(net "M_D_ECC<1>")
	)
	(arc
		(start 246.427498 -98.883724)
		(mid 246.442787 -99.469907)
		(end 245.937532 -99.76739)
		(width 0.0889)
		(layer "In2.Cu")
		(net "M_D_ECC<1>")
	)
	(arc
		(start 246.421148 -95.518224)
		(mid 246.372393 -95.714576)
		(end 246.425974 -95.909638)
		(width 0.0889)
		(layer "In2.Cu")
		(net "M_D_ECC<1>")
	)
	(arc
		(start 246.425974 -97.890838)
		(mid 246.505196 -98.179956)
		(end 246.432324 -98.47072)
		(width 0.0889)
		(layer "In2.Cu")
		(net "M_D_ECC<1>")
	)
	(arc
		(start 246.432324 -96.910906)
		(mid 246.505122 -97.201669)
		(end 246.425974 -97.490788)
		(width 0.0889)
		(layer "In2.Cu")
		(net "M_D_ECC<1>")
	)
	(arc
		(start 246.432324 -93.939106)
		(mid 246.505122 -94.229869)
		(end 246.425974 -94.518988)
		(width 0.0889)
		(layer "In2.Cu")
		(net "M_D_ECC<1>")
	)
	(arc
		(start 246.425974 -95.909638)
		(mid 246.505196 -96.198756)
		(end 246.432324 -96.48952)
		(width 0.0889)
		(layer "In2.Cu")
		(net "M_D_ECC<1>")
	)
	(arc
		(start 246.421148 -94.527624)
		(mid 246.372393 -94.723976)
		(end 246.425974 -94.919038)
		(width 0.0889)
		(layer "In2.Cu")
		(net "M_D_ECC<1>")
	)
	(arc
		(start 246.421148 -98.490024)
		(mid 246.372393 -98.686376)
		(end 246.425974 -98.881438)
		(width 0.0889)
		(layer "In2.Cu")
		(net "M_D_ECC<1>")
	)
	(arc
		(start 246.425974 -92.937838)
		(mid 246.505105 -93.23324)
		(end 246.425974 -93.528642)
		(width 0.0889)
		(layer "In2.Cu")
		(net "M_D_ECC<1>")
	)
	(arc
		(start 246.421148 -96.508824)
		(mid 246.372393 -96.705176)
		(end 246.425974 -96.900238)
		(width 0.0889)
		(layer "In2.Cu")
		(net "M_D_ECC<1>")
	)
	(arc
		(start 245.89613 -99.76739)
		(mid 245.706201 -99.82526)
		(end 245.567454 -99.967288)
		(width 0.0889)
		(layer "In2.Cu")
		(net "M_D_ECC<1>")
	)
	(segment
		(start 236.349794 -137.676382)
		(end 236.171994 -135.8138)
		(width 0.1651)
		(layer "F.Cu")
		(net "M_D_ECC<0>")
	)
	(segment
		(start 248.202704 -89.27084)
		(end 247.631204 -89.27084)
		(width 0.1651)
		(layer "F.Cu")
		(net "M_D_ECC<0>")
	)
	(segment
		(start 236.350302 -137.67054)
		(end 236.349794 -137.676382)
		(width 0.1651)
		(layer "F.Cu")
		(net "M_D_ECC<0>")
	)
	(via
		(at 247.631204 -89.27084)
		(size 0.508)
		(drill 0.254)
		(layers "F.Cu" "B.Cu")
		(net "M_D_ECC<0>")
	)
	(via
		(at 235.49991 -131.611878)
		(size 0.508)
		(drill 0.254)
		(layers "F.Cu" "B.Cu")
		(net "M_D_ECC<0>")
	)
	(via
		(at 236.171994 -135.8138)
		(size 0.508)
		(drill 0.254)
		(layers "F.Cu" "B.Cu")
		(net "M_D_ECC<0>")
	)
	(segment
		(start 235.500418 -132.876036)
		(end 235.49991 -132.875782)
		(width 0.1651)
		(layer "B.Cu")
		(net "M_D_ECC<0>")
	)
	(segment
		(start 235.49991 -132.875782)
		(end 235.49991 -131.611878)
		(width 0.1651)
		(layer "B.Cu")
		(net "M_D_ECC<0>")
	)
	(segment
		(start 247.631204 -89.27084)
		(end 247.136158 -89.936574)
		(width 0.0889)
		(layer "In2.Cu")
		(net "M_D_ECC<0>")
	)
	(segment
		(start 246.2657 -93.424502)
		(end 246.260874 -93.433138)
		(width 0.0889)
		(layer "In2.Cu")
		(net "M_D_ECC<0>")
	)
	(segment
		(start 235.783628 -127.863092)
		(end 235.712 -127.863092)
		(width 0.14224)
		(layer "In2.Cu")
		(net "M_D_ECC<0>")
	)
	(segment
		(start 235.49991 -131.611878)
		(end 235.06684 -132.044948)
		(width 0.14224)
		(layer "In2.Cu")
		(net "M_D_ECC<0>")
	)
	(segment
		(start 235.705396 -124.238004)
		(end 235.705396 -125.443996)
		(width 0.14224)
		(layer "In2.Cu")
		(net "M_D_ECC<0>")
	)
	(segment
		(start 244.780308 -100.55479)
		(end 244.780308 -101.839522)
		(width 0.0889)
		(layer "In2.Cu")
		(net "M_D_ECC<0>")
	)
	(segment
		(start 235.986828 -127.659892)
		(end 235.783628 -127.863092)
		(width 0.14224)
		(layer "In2.Cu")
		(net "M_D_ECC<0>")
	)
	(segment
		(start 235.705396 -125.443996)
		(end 235.986828 -125.725428)
		(width 0.14224)
		(layer "In2.Cu")
		(net "M_D_ECC<0>")
	)
	(segment
		(start 235.135928 -130.608578)
		(end 235.135928 -131.247896)
		(width 0.14224)
		(layer "In2.Cu")
		(net "M_D_ECC<0>")
	)
	(segment
		(start 246.260874 -95.414338)
		(end 246.254524 -95.425006)
		(width 0.0889)
		(layer "In2.Cu")
		(net "M_D_ECC<0>")
	)
	(segment
		(start 237.7948 -110.56874)
		(end 237.7948 -118.5164)
		(width 0.14224)
		(layer "In2.Cu")
		(net "M_D_ECC<0>")
	)
	(segment
		(start 246.2657 -96.396302)
		(end 246.260874 -96.404938)
		(width 0.0889)
		(layer "In2.Cu")
		(net "M_D_ECC<0>")
	)
	(segment
		(start 235.06684 -132.044948)
		(end 235.06684 -135.00481)
		(width 0.14224)
		(layer "In2.Cu")
		(net "M_D_ECC<0>")
	)
	(segment
		(start 247.113044 -90.54592)
		(end 247.119394 -90.556588)
		(width 0.0889)
		(layer "In2.Cu")
		(net "M_D_ECC<0>")
	)
	(segment
		(start 247.113044 -91.53652)
		(end 247.119394 -91.547188)
		(width 0.0889)
		(layer "In2.Cu")
		(net "M_D_ECC<0>")
	)
	(segment
		(start 235.5088 -128.472692)
		(end 235.712 -128.675892)
		(width 0.14224)
		(layer "In2.Cu")
		(net "M_D_ECC<0>")
	)
	(segment
		(start 244.527578 -102.092252)
		(end 244.527578 -103.835962)
		(width 0.14224)
		(layer "In2.Cu")
		(net "M_D_ECC<0>")
	)
	(segment
		(start 235.135928 -131.247896)
		(end 235.49991 -131.611878)
		(width 0.14224)
		(layer "In2.Cu")
		(net "M_D_ECC<0>")
	)
	(segment
		(start 246.254524 -94.01302)
		(end 246.260874 -94.023688)
		(width 0.0889)
		(layer "In2.Cu")
		(net "M_D_ECC<0>")
	)
	(segment
		(start 235.986828 -125.725428)
		(end 235.986828 -127.659892)
		(width 0.14224)
		(layer "In2.Cu")
		(net "M_D_ECC<0>")
	)
	(segment
		(start 236.300264 -120.010936)
		(end 236.300264 -123.643136)
		(width 0.14224)
		(layer "In2.Cu")
		(net "M_D_ECC<0>")
	)
	(segment
		(start 246.260874 -98.386138)
		(end 246.254524 -98.396806)
		(width 0.0889)
		(layer "In2.Cu")
		(net "M_D_ECC<0>")
	)
	(segment
		(start 246.2657 -98.377502)
		(end 246.260874 -98.386138)
		(width 0.0889)
		(layer "In2.Cu")
		(net "M_D_ECC<0>")
	)
	(segment
		(start 245.31955 -100.015548)
		(end 244.780308 -100.55479)
		(width 0.0889)
		(layer "In2.Cu")
		(net "M_D_ECC<0>")
	)
	(segment
		(start 244.527578 -103.835962)
		(end 237.7948 -110.56874)
		(width 0.14224)
		(layer "In2.Cu")
		(net "M_D_ECC<0>")
	)
	(segment
		(start 247.119394 -91.547188)
		(end 247.12422 -91.555824)
		(width 0.0889)
		(layer "In2.Cu")
		(net "M_D_ECC<0>")
	)
	(segment
		(start 235.986828 -128.879092)
		(end 235.986828 -129.757678)
		(width 0.14224)
		(layer "In2.Cu")
		(net "M_D_ECC<0>")
	)
	(segment
		(start 235.5088 -128.066292)
		(end 235.5088 -128.472692)
		(width 0.14224)
		(layer "In2.Cu")
		(net "M_D_ECC<0>")
	)
	(segment
		(start 235.783628 -128.675892)
		(end 235.986828 -128.879092)
		(width 0.14224)
		(layer "In2.Cu")
		(net "M_D_ECC<0>")
	)
	(segment
		(start 235.986828 -129.757678)
		(end 235.135928 -130.608578)
		(width 0.14224)
		(layer "In2.Cu")
		(net "M_D_ECC<0>")
	)
	(segment
		(start 235.06684 -135.00481)
		(end 235.87583 -135.8138)
		(width 0.14224)
		(layer "In2.Cu")
		(net "M_D_ECC<0>")
	)
	(segment
		(start 235.712 -127.863092)
		(end 235.5088 -128.066292)
		(width 0.14224)
		(layer "In2.Cu")
		(net "M_D_ECC<0>")
	)
	(segment
		(start 237.7948 -118.5164)
		(end 236.300264 -120.010936)
		(width 0.14224)
		(layer "In2.Cu")
		(net "M_D_ECC<0>")
	)
	(segment
		(start 244.780308 -101.839522)
		(end 244.527578 -102.092252)
		(width 0.0889)
		(layer "In2.Cu")
		(net "M_D_ECC<0>")
	)
	(segment
		(start 247.136158 -89.936574)
		(end 247.119394 -89.966038)
		(width 0.0889)
		(layer "In2.Cu")
		(net "M_D_ECC<0>")
	)
	(segment
		(start 235.87583 -135.8138)
		(end 236.171994 -135.8138)
		(width 0.14224)
		(layer "In2.Cu")
		(net "M_D_ECC<0>")
	)
	(segment
		(start 246.260874 -96.404938)
		(end 246.254524 -96.415606)
		(width 0.0889)
		(layer "In2.Cu")
		(net "M_D_ECC<0>")
	)
	(segment
		(start 245.920514 -99.576636)
		(end 245.896384 -99.576636)
		(width 0.0889)
		(layer "In2.Cu")
		(net "M_D_ECC<0>")
	)
	(segment
		(start 246.260874 -98.976688)
		(end 246.261636 -98.977704)
		(width 0.0889)
		(layer "In2.Cu")
		(net "M_D_ECC<0>")
	)
	(segment
		(start 246.78767 -92.147136)
		(end 246.754904 -92.147136)
		(width 0.0889)
		(layer "In2.Cu")
		(net "M_D_ECC<0>")
	)
	(segment
		(start 245.402354 -99.872038)
		(end 245.31955 -100.015548)
		(width 0.0889)
		(layer "In2.Cu")
		(net "M_D_ECC<0>")
	)
	(segment
		(start 235.712 -128.675892)
		(end 235.783628 -128.675892)
		(width 0.14224)
		(layer "In2.Cu")
		(net "M_D_ECC<0>")
	)
	(segment
		(start 236.300264 -123.643136)
		(end 235.705396 -124.238004)
		(width 0.14224)
		(layer "In2.Cu")
		(net "M_D_ECC<0>")
	)
	(segment
		(start 246.2657 -95.405702)
		(end 246.260874 -95.414338)
		(width 0.0889)
		(layer "In2.Cu")
		(net "M_D_ECC<0>")
	)
	(segment
		(start 247.119394 -90.556588)
		(end 247.12422 -90.565224)
		(width 0.0889)
		(layer "In2.Cu")
		(net "M_D_ECC<0>")
	)
	(arc
		(start 246.254524 -95.425006)
		(mid 246.181726 -95.715769)
		(end 246.260874 -96.004888)
		(width 0.0889)
		(layer "In2.Cu")
		(net "M_D_ECC<0>")
	)
	(arc
		(start 245.896384 -99.576636)
		(mid 245.61096 -99.660103)
		(end 245.402354 -99.872038)
		(width 0.0889)
		(layer "In2.Cu")
		(net "M_D_ECC<0>")
	)
	(arc
		(start 246.754904 -92.147136)
		(mid 246.256653 -92.449976)
		(end 246.260874 -93.033088)
		(width 0.0889)
		(layer "In2.Cu")
		(net "M_D_ECC<0>")
	)
	(arc
		(start 246.260874 -95.014288)
		(mid 246.314344 -95.209351)
		(end 246.2657 -95.405702)
		(width 0.0889)
		(layer "In2.Cu")
		(net "M_D_ECC<0>")
	)
	(arc
		(start 246.260874 -97.986088)
		(mid 246.314344 -98.181151)
		(end 246.2657 -98.377502)
		(width 0.0889)
		(layer "In2.Cu")
		(net "M_D_ECC<0>")
	)
	(arc
		(start 246.260874 -97.395284)
		(mid 246.181743 -97.690686)
		(end 246.260874 -97.986088)
		(width 0.0889)
		(layer "In2.Cu")
		(net "M_D_ECC<0>")
	)
	(arc
		(start 246.260874 -96.004888)
		(mid 246.314344 -96.199951)
		(end 246.2657 -96.396302)
		(width 0.0889)
		(layer "In2.Cu")
		(net "M_D_ECC<0>")
	)
	(arc
		(start 246.260874 -96.995488)
		(mid 246.314373 -97.195386)
		(end 246.260874 -97.395284)
		(width 0.0889)
		(layer "In2.Cu")
		(net "M_D_ECC<0>")
	)
	(arc
		(start 247.119394 -90.956638)
		(mid 247.040172 -91.245756)
		(end 247.113044 -91.53652)
		(width 0.0889)
		(layer "In2.Cu")
		(net "M_D_ECC<0>")
	)
	(arc
		(start 247.12422 -91.555824)
		(mid 247.120473 -91.94508)
		(end 246.78767 -92.147136)
		(width 0.0889)
		(layer "In2.Cu")
		(net "M_D_ECC<0>")
	)
	(arc
		(start 247.12422 -90.565224)
		(mid 247.172975 -90.761576)
		(end 247.119394 -90.956638)
		(width 0.0889)
		(layer "In2.Cu")
		(net "M_D_ECC<0>")
	)
	(arc
		(start 246.254524 -98.396806)
		(mid 246.181726 -98.687569)
		(end 246.260874 -98.976688)
		(width 0.0889)
		(layer "In2.Cu")
		(net "M_D_ECC<0>")
	)
	(arc
		(start 246.260874 -94.423484)
		(mid 246.181743 -94.718886)
		(end 246.260874 -95.014288)
		(width 0.0889)
		(layer "In2.Cu")
		(net "M_D_ECC<0>")
	)
	(arc
		(start 246.260874 -93.433138)
		(mid 246.181652 -93.722256)
		(end 246.254524 -94.01302)
		(width 0.0889)
		(layer "In2.Cu")
		(net "M_D_ECC<0>")
	)
	(arc
		(start 246.260874 -94.023688)
		(mid 246.314373 -94.223586)
		(end 246.260874 -94.423484)
		(width 0.0889)
		(layer "In2.Cu")
		(net "M_D_ECC<0>")
	)
	(arc
		(start 246.260874 -93.033088)
		(mid 246.314344 -93.228151)
		(end 246.2657 -93.424502)
		(width 0.0889)
		(layer "In2.Cu")
		(net "M_D_ECC<0>")
	)
	(arc
		(start 246.261636 -98.977704)
		(mid 246.265221 -99.376413)
		(end 245.920514 -99.576636)
		(width 0.0889)
		(layer "In2.Cu")
		(net "M_D_ECC<0>")
	)
	(arc
		(start 246.254524 -96.415606)
		(mid 246.181726 -96.706369)
		(end 246.260874 -96.995488)
		(width 0.0889)
		(layer "In2.Cu")
		(net "M_D_ECC<0>")
	)
	(arc
		(start 247.119394 -89.966038)
		(mid 247.040172 -90.255156)
		(end 247.113044 -90.54592)
		(width 0.0889)
		(layer "In2.Cu")
		(net "M_D_ECC<0>")
	)
	(segment
		(start 199.279256 -134.313168)
		(end 199.279256 -135.131302)
		(width 0.1651)
		(layer "F.Cu")
		(net "M_D_DQS_DP<9>")
	)
	(segment
		(start 199.799956 -133.693154)
		(end 199.363838 -134.129272)
		(width 0.1651)
		(layer "F.Cu")
		(net "M_D_DQS_DP<9>")
	)
	(segment
		(start 199.279256 -135.131302)
		(end 199.36079 -135.355584)
		(width 0.1651)
		(layer "F.Cu")
		(net "M_D_DQS_DP<9>")
	)
	(segment
		(start 199.799956 -133.076442)
		(end 199.799956 -133.693154)
		(width 0.1651)
		(layer "F.Cu")
		(net "M_D_DQS_DP<9>")
	)
	(segment
		(start 199.800464 -133.0706)
		(end 199.799956 -133.076442)
		(width 0.1651)
		(layer "F.Cu")
		(net "M_D_DQS_DP<9>")
	)
	(segment
		(start 233.608118 -85.803486)
		(end 233.036618 -85.803486)
		(width 0.1651)
		(layer "F.Cu")
		(net "M_D_DQS_DP<9>")
	)
	(segment
		(start 199.363838 -134.129272)
		(end 199.300592 -134.26694)
		(width 0.1651)
		(layer "F.Cu")
		(net "M_D_DQS_DP<9>")
	)
	(segment
		(start 199.36079 -135.355584)
		(end 199.742552 -135.737346)
		(width 0.1651)
		(layer "F.Cu")
		(net "M_D_DQS_DP<9>")
	)
	(segment
		(start 199.300592 -134.26694)
		(end 199.279256 -134.313168)
		(width 0.1651)
		(layer "F.Cu")
		(net "M_D_DQS_DP<9>")
	)
	(via
		(at 199.742552 -130.2258)
		(size 0.508)
		(drill 0.254)
		(layers "F.Cu" "B.Cu")
		(net "M_D_DQS_DP<9>")
	)
	(via
		(at 199.742552 -135.737346)
		(size 0.508)
		(drill 0.254)
		(layers "F.Cu" "B.Cu")
		(net "M_D_DQS_DP<9>")
	)
	(via
		(at 233.036618 -85.803486)
		(size 0.508)
		(drill 0.254)
		(layers "F.Cu" "B.Cu")
		(net "M_D_DQS_DP<9>")
	)
	(segment
		(start 199.343772 -131.80187)
		(end 199.266556 -131.669536)
		(width 0.1651)
		(layer "B.Cu")
		(net "M_D_DQS_DP<9>")
	)
	(segment
		(start 199.266556 -131.669536)
		(end 199.266556 -130.773932)
		(width 0.1651)
		(layer "B.Cu")
		(net "M_D_DQS_DP<9>")
	)
	(segment
		(start 199.266556 -130.773932)
		(end 199.353932 -130.61442)
		(width 0.1651)
		(layer "B.Cu")
		(net "M_D_DQS_DP<9>")
	)
	(segment
		(start 199.799956 -132.875782)
		(end 199.799956 -132.258054)
		(width 0.1651)
		(layer "B.Cu")
		(net "M_D_DQS_DP<9>")
	)
	(segment
		(start 199.353932 -130.61442)
		(end 199.742552 -130.2258)
		(width 0.1651)
		(layer "B.Cu")
		(net "M_D_DQS_DP<9>")
	)
	(segment
		(start 199.799956 -132.258054)
		(end 199.343772 -131.80187)
		(width 0.1651)
		(layer "B.Cu")
		(net "M_D_DQS_DP<9>")
	)
	(segment
		(start 199.800464 -132.876036)
		(end 199.799956 -132.875782)
		(width 0.1651)
		(layer "B.Cu")
		(net "M_D_DQS_DP<9>")
	)
	(segment
		(start 199.6694 -130.2258)
		(end 199.2376 -130.6576)
		(width 0.14224)
		(layer "In2.Cu")
		(net "M_D_DQS_DP<9>")
	)
	(segment
		(start 199.2376 -130.6576)
		(end 199.2376 -135.232394)
		(width 0.14224)
		(layer "In2.Cu")
		(net "M_D_DQS_DP<9>")
	)
	(segment
		(start 201.323448 -119.706644)
		(end 201.102722 -119.92737)
		(width 0.14224)
		(layer "In2.Cu")
		(net "M_D_DQS_DP<9>")
	)
	(segment
		(start 233.3498 -86.04758)
		(end 233.350816 -86.05139)
		(width 0.0889)
		(layer "In2.Cu")
		(net "M_D_DQS_DP<9>")
	)
	(segment
		(start 201.078592 -117.64137)
		(end 200.790048 -117.64137)
		(width 0.14224)
		(layer "In2.Cu")
		(net "M_D_DQS_DP<9>")
	)
	(segment
		(start 231.92867 -86.69909)
		(end 231.64546 -86.41588)
		(width 0.0889)
		(layer "In2.Cu")
		(net "M_D_DQS_DP<9>")
	)
	(segment
		(start 200.840848 -116.76761)
		(end 201.103992 -116.76761)
		(width 0.14224)
		(layer "In2.Cu")
		(net "M_D_DQS_DP<9>")
	)
	(segment
		(start 200.30948 -129.938272)
		(end 199.991726 -130.256026)
		(width 0.14224)
		(layer "In2.Cu")
		(net "M_D_DQS_DP<9>")
	)
	(segment
		(start 200.790048 -117.64137)
		(end 200.46188 -117.969538)
		(width 0.14224)
		(layer "In2.Cu")
		(net "M_D_DQS_DP<9>")
	)
	(segment
		(start 201.323448 -119.198136)
		(end 201.323448 -119.706644)
		(width 0.14224)
		(layer "In2.Cu")
		(net "M_D_DQS_DP<9>")
	)
	(segment
		(start 231.64546 -86.41588)
		(end 231.46766 -86.41588)
		(width 0.0889)
		(layer "In2.Cu")
		(net "M_D_DQS_DP<9>")
	)
	(segment
		(start 230.801164 -86.41588)
		(end 230.769668 -86.384384)
		(width 0.0889)
		(layer "In2.Cu")
		(net "M_D_DQS_DP<9>")
	)
	(segment
		(start 201.178922 -119.05361)
		(end 201.323448 -119.198136)
		(width 0.14224)
		(layer "In2.Cu")
		(net "M_D_DQS_DP<9>")
	)
	(segment
		(start 200.152 -128.8542)
		(end 200.152 -129.159)
		(width 0.14224)
		(layer "In2.Cu")
		(net "M_D_DQS_DP<9>")
	)
	(segment
		(start 201.102722 -119.92737)
		(end 200.713848 -119.92737)
		(width 0.14224)
		(layer "In2.Cu")
		(net "M_D_DQS_DP<9>")
	)
	(segment
		(start 216.77376 -99.268026)
		(end 216.77376 -100.827586)
		(width 0.14224)
		(layer "In2.Cu")
		(net "M_D_DQS_DP<9>")
	)
	(segment
		(start 199.742552 -130.2258)
		(end 199.6694 -130.2258)
		(width 0.14224)
		(layer "In2.Cu")
		(net "M_D_DQS_DP<9>")
	)
	(segment
		(start 201.27468 -117.445282)
		(end 201.078592 -117.64137)
		(width 0.14224)
		(layer "In2.Cu")
		(net "M_D_DQS_DP<9>")
	)
	(segment
		(start 201.103992 -116.76761)
		(end 201.27468 -116.938298)
		(width 0.14224)
		(layer "In2.Cu")
		(net "M_D_DQS_DP<9>")
	)
	(segment
		(start 200.30948 -120.331738)
		(end 200.30948 -128.69672)
		(width 0.14224)
		(layer "In2.Cu")
		(net "M_D_DQS_DP<9>")
	)
	(segment
		(start 203.037186 -113.57356)
		(end 200.56348 -116.047266)
		(width 0.14224)
		(layer "In2.Cu")
		(net "M_D_DQS_DP<9>")
	)
	(segment
		(start 231.36606 -86.31428)
		(end 231.18826 -86.31428)
		(width 0.0889)
		(layer "In2.Cu")
		(net "M_D_DQS_DP<9>")
	)
	(segment
		(start 200.56348 -116.047266)
		(end 200.56348 -116.490242)
		(width 0.14224)
		(layer "In2.Cu")
		(net "M_D_DQS_DP<9>")
	)
	(segment
		(start 200.840848 -119.05361)
		(end 201.178922 -119.05361)
		(width 0.14224)
		(layer "In2.Cu")
		(net "M_D_DQS_DP<9>")
	)
	(segment
		(start 230.769668 -86.384384)
		(end 230.74757 -86.384384)
		(width 0.0889)
		(layer "In2.Cu")
		(net "M_D_DQS_DP<9>")
	)
	(segment
		(start 231.18826 -86.31428)
		(end 231.08666 -86.41588)
		(width 0.0889)
		(layer "In2.Cu")
		(net "M_D_DQS_DP<9>")
	)
	(segment
		(start 200.30948 -129.31648)
		(end 200.30948 -129.938272)
		(width 0.14224)
		(layer "In2.Cu")
		(net "M_D_DQS_DP<9>")
	)
	(segment
		(start 200.30948 -128.69672)
		(end 200.152 -128.8542)
		(width 0.14224)
		(layer "In2.Cu")
		(net "M_D_DQS_DP<9>")
	)
	(segment
		(start 230.74757 -86.384384)
		(end 229.657402 -86.384384)
		(width 0.14224)
		(layer "In2.Cu")
		(net "M_D_DQS_DP<9>")
	)
	(segment
		(start 233.051604 -86.203536)
		(end 233.018838 -86.203536)
		(width 0.0889)
		(layer "In2.Cu")
		(net "M_D_DQS_DP<9>")
	)
	(segment
		(start 229.657402 -86.384384)
		(end 216.77376 -99.268026)
		(width 0.14224)
		(layer "In2.Cu")
		(net "M_D_DQS_DP<9>")
	)
	(segment
		(start 232.189274 -86.69909)
		(end 231.92867 -86.69909)
		(width 0.0889)
		(layer "In2.Cu")
		(net "M_D_DQS_DP<9>")
	)
	(segment
		(start 201.27468 -116.938298)
		(end 201.27468 -117.445282)
		(width 0.14224)
		(layer "In2.Cu")
		(net "M_D_DQS_DP<9>")
	)
	(segment
		(start 216.77376 -100.827586)
		(end 204.027786 -113.57356)
		(width 0.14224)
		(layer "In2.Cu")
		(net "M_D_DQS_DP<9>")
	)
	(segment
		(start 204.027786 -113.57356)
		(end 203.037186 -113.57356)
		(width 0.14224)
		(layer "In2.Cu")
		(net "M_D_DQS_DP<9>")
	)
	(segment
		(start 231.46766 -86.41588)
		(end 231.36606 -86.31428)
		(width 0.0889)
		(layer "In2.Cu")
		(net "M_D_DQS_DP<9>")
	)
	(segment
		(start 231.08666 -86.41588)
		(end 230.801164 -86.41588)
		(width 0.0889)
		(layer "In2.Cu")
		(net "M_D_DQS_DP<9>")
	)
	(segment
		(start 200.56348 -116.490242)
		(end 200.840848 -116.76761)
		(width 0.14224)
		(layer "In2.Cu")
		(net "M_D_DQS_DP<9>")
	)
	(segment
		(start 199.991726 -130.256026)
		(end 199.772778 -130.256026)
		(width 0.14224)
		(layer "In2.Cu")
		(net "M_D_DQS_DP<9>")
	)
	(segment
		(start 233.036618 -85.803486)
		(end 233.329734 -85.97265)
		(width 0.0889)
		(layer "In2.Cu")
		(net "M_D_DQS_DP<9>")
	)
	(segment
		(start 199.772778 -130.256026)
		(end 199.742552 -130.2258)
		(width 0.14224)
		(layer "In2.Cu")
		(net "M_D_DQS_DP<9>")
	)
	(segment
		(start 200.46188 -117.969538)
		(end 200.46188 -118.674642)
		(width 0.14224)
		(layer "In2.Cu")
		(net "M_D_DQS_DP<9>")
	)
	(segment
		(start 200.46188 -118.674642)
		(end 200.840848 -119.05361)
		(width 0.14224)
		(layer "In2.Cu")
		(net "M_D_DQS_DP<9>")
	)
	(segment
		(start 233.329734 -85.97265)
		(end 233.3498 -86.04758)
		(width 0.0889)
		(layer "In2.Cu")
		(net "M_D_DQS_DP<9>")
	)
	(segment
		(start 200.152 -129.159)
		(end 200.30948 -129.31648)
		(width 0.14224)
		(layer "In2.Cu")
		(net "M_D_DQS_DP<9>")
	)
	(segment
		(start 200.713848 -119.92737)
		(end 200.30948 -120.331738)
		(width 0.14224)
		(layer "In2.Cu")
		(net "M_D_DQS_DP<9>")
	)
	(segment
		(start 199.2376 -135.232394)
		(end 199.742552 -135.737346)
		(width 0.14224)
		(layer "In2.Cu")
		(net "M_D_DQS_DP<9>")
	)
	(arc
		(start 233.350816 -86.05139)
		(mid 233.259916 -86.135622)
		(end 233.147616 -86.188042)
		(width 0.0889)
		(layer "In2.Cu")
		(net "M_D_DQS_DP<9>")
	)
	(arc
		(start 232.524808 -86.498938)
		(mid 232.383125 -86.642742)
		(end 232.189274 -86.69909)
		(width 0.0889)
		(layer "In2.Cu")
		(net "M_D_DQS_DP<9>")
	)
	(arc
		(start 233.018838 -86.203536)
		(mid 232.733414 -86.287003)
		(end 232.524808 -86.498938)
		(width 0.0889)
		(layer "In2.Cu")
		(net "M_D_DQS_DP<9>")
	)
	(arc
		(start 233.147616 -86.188042)
		(mid 233.100082 -86.198708)
		(end 233.051604 -86.203536)
		(width 0.0889)
		(layer "In2.Cu")
		(net "M_D_DQS_DP<9>")
	)
	(segment
		(start 238.437928 -135.01116)
		(end 238.69396 -135.01116)
		(width 0.1651)
		(layer "F.Cu")
		(net "M_D_DQS_DP<8>")
	)
	(segment
		(start 238.69396 -135.01116)
		(end 238.9378 -135.255)
		(width 0.1651)
		(layer "F.Cu")
		(net "M_D_DQS_DP<8>")
	)
	(segment
		(start 238.9378 -135.255)
		(end 238.9378 -136.6266)
		(width 0.1651)
		(layer "F.Cu")
		(net "M_D_DQS_DP<8>")
	)
	(segment
		(start 238.9378 -136.6266)
		(end 238.899954 -136.664446)
		(width 0.1651)
		(layer "F.Cu")
		(net "M_D_DQS_DP<8>")
	)
	(segment
		(start 238.899954 -136.664446)
		(end 238.899954 -137.67054)
		(width 0.1651)
		(layer "F.Cu")
		(net "M_D_DQS_DP<8>")
	)
	(segment
		(start 238.899954 -137.67054)
		(end 238.900462 -137.67054)
		(width 0.1651)
		(layer "F.Cu")
		(net "M_D_DQS_DP<8>")
	)
	(segment
		(start 249.061224 -90.756486)
		(end 248.489724 -90.756486)
		(width 0.1651)
		(layer "F.Cu")
		(net "M_D_DQS_DP<8>")
	)
	(via
		(at 248.489724 -90.756486)
		(size 0.508)
		(drill 0.254)
		(layers "F.Cu" "B.Cu")
		(net "M_D_DQS_DP<8>")
	)
	(via
		(at 238.437928 -130.940556)
		(size 0.508)
		(drill 0.254)
		(layers "F.Cu" "B.Cu")
		(net "M_D_DQS_DP<8>")
	)
	(via
		(at 238.437928 -135.01116)
		(size 0.508)
		(drill 0.254)
		(layers "F.Cu" "B.Cu")
		(net "M_D_DQS_DP<8>")
	)
	(segment
		(start 238.9378 -130.683)
		(end 238.9378 -129.4638)
		(width 0.1651)
		(layer "B.Cu")
		(net "M_D_DQS_DP<8>")
	)
	(segment
		(start 238.680244 -130.940556)
		(end 238.9378 -130.683)
		(width 0.1651)
		(layer "B.Cu")
		(net "M_D_DQS_DP<8>")
	)
	(segment
		(start 238.899954 -129.425954)
		(end 238.899954 -128.276096)
		(width 0.1651)
		(layer "B.Cu")
		(net "M_D_DQS_DP<8>")
	)
	(segment
		(start 238.899954 -128.276096)
		(end 238.900462 -128.276096)
		(width 0.1651)
		(layer "B.Cu")
		(net "M_D_DQS_DP<8>")
	)
	(segment
		(start 238.437928 -130.940556)
		(end 238.680244 -130.940556)
		(width 0.1651)
		(layer "B.Cu")
		(net "M_D_DQS_DP<8>")
	)
	(segment
		(start 238.9378 -129.4638)
		(end 238.899954 -129.425954)
		(width 0.1651)
		(layer "B.Cu")
		(net "M_D_DQS_DP<8>")
	)
	(segment
		(start 249.007376 -92.45219)
		(end 249.007884 -92.453206)
		(width 0.0889)
		(layer "In2.Cu")
		(net "M_D_DQS_DP<8>")
	)
	(segment
		(start 238.618776 -132.0546)
		(end 238.233712 -132.0546)
		(width 0.14224)
		(layer "In2.Cu")
		(net "M_D_DQS_DP<8>")
	)
	(segment
		(start 238.644176 -133.858)
		(end 238.898176 -134.112)
		(width 0.14224)
		(layer "In2.Cu")
		(net "M_D_DQS_DP<8>")
	)
	(segment
		(start 249.00636 -92.450412)
		(end 249.007376 -92.45219)
		(width 0.0889)
		(layer "In2.Cu")
		(net "M_D_DQS_DP<8>")
	)
	(segment
		(start 241.2492 -110.945422)
		(end 241.028474 -111.166148)
		(width 0.14224)
		(layer "In2.Cu")
		(net "M_D_DQS_DP<8>")
	)
	(segment
		(start 238.898176 -134.112)
		(end 238.898176 -134.550912)
		(width 0.14224)
		(layer "In2.Cu")
		(net "M_D_DQS_DP<8>")
	)
	(segment
		(start 249.00382 -92.446094)
		(end 249.004328 -92.44711)
		(width 0.0889)
		(layer "In2.Cu")
		(net "M_D_DQS_DP<8>")
	)
	(segment
		(start 241.703352 -111.819182)
		(end 242.08232 -112.19815)
		(width 0.14224)
		(layer "In2.Cu")
		(net "M_D_DQS_DP<8>")
	)
	(segment
		(start 238.440976 -133.118352)
		(end 238.260636 -133.298692)
		(width 0.14224)
		(layer "In2.Cu")
		(net "M_D_DQS_DP<8>")
	)
	(segment
		(start 239.296448 -130.082036)
		(end 238.437928 -130.940556)
		(width 0.14224)
		(layer "In2.Cu")
		(net "M_D_DQS_DP<8>")
	)
	(segment
		(start 238.898176 -134.550912)
		(end 238.437928 -135.01116)
		(width 0.14224)
		(layer "In2.Cu")
		(net "M_D_DQS_DP<8>")
	)
	(segment
		(start 238.259112 -133.858)
		(end 238.644176 -133.858)
		(width 0.14224)
		(layer "In2.Cu")
		(net "M_D_DQS_DP<8>")
	)
	(segment
		(start 247.065546 -101.261164)
		(end 246.985536 -101.422708)
		(width 0.0889)
		(layer "In2.Cu")
		(net "M_D_DQS_DP<8>")
	)
	(segment
		(start 247.072658 -101.246686)
		(end 247.065546 -101.261164)
		(width 0.0889)
		(layer "In2.Cu")
		(net "M_D_DQS_DP<8>")
	)
	(segment
		(start 242.08232 -112.856772)
		(end 241.710972 -113.22812)
		(width 0.14224)
		(layer "In2.Cu")
		(net "M_D_DQS_DP<8>")
	)
	(segment
		(start 238.063278 -132.225034)
		(end 238.063278 -132.549392)
		(width 0.14224)
		(layer "In2.Cu")
		(net "M_D_DQS_DP<8>")
	)
	(segment
		(start 238.063278 -133.662166)
		(end 238.259112 -133.858)
		(width 0.14224)
		(layer "In2.Cu")
		(net "M_D_DQS_DP<8>")
	)
	(segment
		(start 241.710972 -113.22812)
		(end 240.856008 -113.22812)
		(width 0.14224)
		(layer "In2.Cu")
		(net "M_D_DQS_DP<8>")
	)
	(segment
		(start 239.296448 -123.727718)
		(end 239.296448 -130.082036)
		(width 0.14224)
		(layer "In2.Cu")
		(net "M_D_DQS_DP<8>")
	)
	(segment
		(start 241.249962 -111.819182)
		(end 241.703352 -111.819182)
		(width 0.14224)
		(layer "In2.Cu")
		(net "M_D_DQS_DP<8>")
	)
	(segment
		(start 248.143014 -95.909384)
		(end 248.2342 -96.067372)
		(width 0.0889)
		(layer "In2.Cu")
		(net "M_D_DQS_DP<8>")
	)
	(segment
		(start 247.115076 -104.87025)
		(end 242.292632 -109.692694)
		(width 0.14224)
		(layer "In2.Cu")
		(net "M_D_DQS_DP<8>")
	)
	(segment
		(start 238.872776 -131.375404)
		(end 238.872776 -131.8006)
		(width 0.14224)
		(layer "In2.Cu")
		(net "M_D_DQS_DP<8>")
	)
	(segment
		(start 242.292632 -109.692694)
		(end 242.292632 -110.567216)
		(width 0.14224)
		(layer "In2.Cu")
		(net "M_D_DQS_DP<8>")
	)
	(segment
		(start 238.063278 -132.549392)
		(end 238.178086 -132.6642)
		(width 0.14224)
		(layer "In2.Cu")
		(net "M_D_DQS_DP<8>")
	)
	(segment
		(start 247.075706 -103.46563)
		(end 247.115076 -103.505)
		(width 0.0889)
		(layer "In2.Cu")
		(net "M_D_DQS_DP<8>")
	)
	(segment
		(start 248.149364 -95.49892)
		(end 248.143014 -95.509588)
		(width 0.0889)
		(layer "In2.Cu")
		(net "M_D_DQS_DP<8>")
	)
	(segment
		(start 249.001534 -92.442284)
		(end 249.00382 -92.446094)
		(width 0.0889)
		(layer "In2.Cu")
		(net "M_D_DQS_DP<8>")
	)
	(segment
		(start 248.2342 -100.085144)
		(end 247.072658 -101.246686)
		(width 0.0889)
		(layer "In2.Cu")
		(net "M_D_DQS_DP<8>")
	)
	(segment
		(start 240.688368 -122.335798)
		(end 239.296448 -123.727718)
		(width 0.14224)
		(layer "In2.Cu")
		(net "M_D_DQS_DP<8>")
	)
	(segment
		(start 240.856008 -113.22812)
		(end 240.688368 -113.39576)
		(width 0.14224)
		(layer "In2.Cu")
		(net "M_D_DQS_DP<8>")
	)
	(segment
		(start 248.489724 -90.756486)
		(end 248.491502 -90.760296)
		(width 0.0889)
		(layer "In2.Cu")
		(net "M_D_DQS_DP<8>")
	)
	(segment
		(start 246.99722 -101.795834)
		(end 247.075706 -101.931978)
		(width 0.0889)
		(layer "In2.Cu")
		(net "M_D_DQS_DP<8>")
	)
	(segment
		(start 238.440976 -132.842)
		(end 238.440976 -133.118352)
		(width 0.14224)
		(layer "In2.Cu")
		(net "M_D_DQS_DP<8>")
	)
	(segment
		(start 248.2342 -96.067372)
		(end 248.2342 -100.085144)
		(width 0.0889)
		(layer "In2.Cu")
		(net "M_D_DQS_DP<8>")
	)
	(segment
		(start 238.178086 -132.6642)
		(end 238.263176 -132.6642)
		(width 0.14224)
		(layer "In2.Cu")
		(net "M_D_DQS_DP<8>")
	)
	(segment
		(start 238.233712 -132.0546)
		(end 238.063278 -132.225034)
		(width 0.14224)
		(layer "In2.Cu")
		(net "M_D_DQS_DP<8>")
	)
	(segment
		(start 248.502678 -93.32849)
		(end 248.478548 -93.32849)
		(width 0.0889)
		(layer "In2.Cu")
		(net "M_D_DQS_DP<8>")
	)
	(segment
		(start 248.143014 -93.928438)
		(end 248.149364 -93.939106)
		(width 0.0889)
		(layer "In2.Cu")
		(net "M_D_DQS_DP<8>")
	)
	(segment
		(start 248.143014 -94.518988)
		(end 248.138188 -94.527624)
		(width 0.0889)
		(layer "In2.Cu")
		(net "M_D_DQS_DP<8>")
	)
	(segment
		(start 238.437928 -130.940556)
		(end 238.872776 -131.375404)
		(width 0.14224)
		(layer "In2.Cu")
		(net "M_D_DQS_DP<8>")
	)
	(segment
		(start 242.08232 -112.19815)
		(end 242.08232 -112.856772)
		(width 0.14224)
		(layer "In2.Cu")
		(net "M_D_DQS_DP<8>")
	)
	(segment
		(start 238.063278 -133.435852)
		(end 238.063278 -133.662166)
		(width 0.14224)
		(layer "In2.Cu")
		(net "M_D_DQS_DP<8>")
	)
	(segment
		(start 249.004836 -92.447872)
		(end 249.00636 -92.450412)
		(width 0.0889)
		(layer "In2.Cu")
		(net "M_D_DQS_DP<8>")
	)
	(segment
		(start 242.292632 -110.567216)
		(end 241.914426 -110.945422)
		(width 0.14224)
		(layer "In2.Cu")
		(net "M_D_DQS_DP<8>")
	)
	(segment
		(start 241.028474 -111.166148)
		(end 241.028474 -111.597694)
		(width 0.14224)
		(layer "In2.Cu")
		(net "M_D_DQS_DP<8>")
	)
	(segment
		(start 240.688368 -113.39576)
		(end 240.688368 -122.335798)
		(width 0.14224)
		(layer "In2.Cu")
		(net "M_D_DQS_DP<8>")
	)
	(segment
		(start 249.004328 -92.44711)
		(end 249.004836 -92.447872)
		(width 0.0889)
		(layer "In2.Cu")
		(net "M_D_DQS_DP<8>")
	)
	(segment
		(start 247.115076 -103.505)
		(end 247.115076 -103.527098)
		(width 0.0889)
		(layer "In2.Cu")
		(net "M_D_DQS_DP<8>")
	)
	(segment
		(start 241.028474 -111.597694)
		(end 241.249962 -111.819182)
		(width 0.14224)
		(layer "In2.Cu")
		(net "M_D_DQS_DP<8>")
	)
	(segment
		(start 238.263176 -132.6642)
		(end 238.440976 -132.842)
		(width 0.14224)
		(layer "In2.Cu")
		(net "M_D_DQS_DP<8>")
	)
	(segment
		(start 241.914426 -110.945422)
		(end 241.2492 -110.945422)
		(width 0.14224)
		(layer "In2.Cu")
		(net "M_D_DQS_DP<8>")
	)
	(segment
		(start 247.115076 -103.527098)
		(end 247.115076 -104.87025)
		(width 0.14224)
		(layer "In2.Cu")
		(net "M_D_DQS_DP<8>")
	)
	(segment
		(start 238.260636 -133.298692)
		(end 238.200438 -133.298692)
		(width 0.14224)
		(layer "In2.Cu")
		(net "M_D_DQS_DP<8>")
	)
	(segment
		(start 238.872776 -131.8006)
		(end 238.618776 -132.0546)
		(width 0.14224)
		(layer "In2.Cu")
		(net "M_D_DQS_DP<8>")
	)
	(segment
		(start 238.200438 -133.298692)
		(end 238.063278 -133.435852)
		(width 0.14224)
		(layer "In2.Cu")
		(net "M_D_DQS_DP<8>")
	)
	(segment
		(start 247.075706 -101.931978)
		(end 247.075706 -103.46563)
		(width 0.0889)
		(layer "In2.Cu")
		(net "M_D_DQS_DP<8>")
	)
	(arc
		(start 248.143014 -95.509588)
		(mid 248.089515 -95.709486)
		(end 248.143014 -95.909384)
		(width 0.0889)
		(layer "In2.Cu")
		(net "M_D_DQS_DP<8>")
	)
	(arc
		(start 248.149364 -93.939106)
		(mid 248.222162 -94.229869)
		(end 248.143014 -94.518988)
		(width 0.0889)
		(layer "In2.Cu")
		(net "M_D_DQS_DP<8>")
	)
	(arc
		(start 248.138188 -94.527624)
		(mid 248.089433 -94.723976)
		(end 248.143014 -94.919038)
		(width 0.0889)
		(layer "In2.Cu")
		(net "M_D_DQS_DP<8>")
	)
	(arc
		(start 248.143014 -94.919038)
		(mid 248.222236 -95.208156)
		(end 248.149364 -95.49892)
		(width 0.0889)
		(layer "In2.Cu")
		(net "M_D_DQS_DP<8>")
	)
	(arc
		(start 246.985536 -101.422708)
		(mid 246.944699 -101.610718)
		(end 246.99722 -101.795834)
		(width 0.0889)
		(layer "In2.Cu")
		(net "M_D_DQS_DP<8>")
	)
	(arc
		(start 249.007884 -92.453206)
		(mid 249.001707 -93.033138)
		(end 248.502678 -93.32849)
		(width 0.0889)
		(layer "In2.Cu")
		(net "M_D_DQS_DP<8>")
	)
	(arc
		(start 248.877328 -91.846654)
		(mid 248.891726 -92.154412)
		(end 249.001534 -92.442284)
		(width 0.0889)
		(layer "In2.Cu")
		(net "M_D_DQS_DP<8>")
	)
	(arc
		(start 248.836434 -91.547188)
		(mid 248.886249 -91.692913)
		(end 248.877328 -91.846654)
		(width 0.0889)
		(layer "In2.Cu")
		(net "M_D_DQS_DP<8>")
	)
	(arc
		(start 248.478548 -93.32849)
		(mid 248.140433 -93.533192)
		(end 248.143014 -93.928438)
		(width 0.0889)
		(layer "In2.Cu")
		(net "M_D_DQS_DP<8>")
	)
	(arc
		(start 248.491502 -90.760296)
		(mid 248.64232 -91.163232)
		(end 248.836434 -91.547188)
		(width 0.0889)
		(layer "In2.Cu")
		(net "M_D_DQS_DP<8>")
	)
	(segment
		(start 288.36366 -98.500184)
		(end 288.93516 -98.500184)
		(width 0.1651)
		(layer "F.Cu")
		(net "M_D_DQS_DP<7>")
	)
	(segment
		(start 312.850022 -137.67054)
		(end 312.850022 -136.664446)
		(width 0.1651)
		(layer "F.Cu")
		(net "M_D_DQS_DP<7>")
	)
	(segment
		(start 312.887868 -135.255)
		(end 312.644028 -135.01116)
		(width 0.1651)
		(layer "F.Cu")
		(net "M_D_DQS_DP<7>")
	)
	(segment
		(start 312.644028 -135.01116)
		(end 312.387996 -135.01116)
		(width 0.1651)
		(layer "F.Cu")
		(net "M_D_DQS_DP<7>")
	)
	(segment
		(start 312.850022 -136.664446)
		(end 312.887868 -136.6266)
		(width 0.1651)
		(layer "F.Cu")
		(net "M_D_DQS_DP<7>")
	)
	(segment
		(start 312.887868 -136.6266)
		(end 312.887868 -135.255)
		(width 0.1651)
		(layer "F.Cu")
		(net "M_D_DQS_DP<7>")
	)
	(segment
		(start 312.850276 -137.67054)
		(end 312.850022 -137.67054)
		(width 0.1651)
		(layer "F.Cu")
		(net "M_D_DQS_DP<7>")
	)
	(via
		(at 312.387996 -130.940556)
		(size 0.508)
		(drill 0.254)
		(layers "F.Cu" "B.Cu")
		(net "M_D_DQS_DP<7>")
	)
	(via
		(at 312.387996 -135.01116)
		(size 0.508)
		(drill 0.254)
		(layers "F.Cu" "B.Cu")
		(net "M_D_DQS_DP<7>")
	)
	(via
		(at 288.93516 -98.500184)
		(size 0.508)
		(drill 0.254)
		(layers "F.Cu" "B.Cu")
		(net "M_D_DQS_DP<7>")
	)
	(segment
		(start 312.387996 -130.940556)
		(end 312.630312 -130.940556)
		(width 0.1651)
		(layer "B.Cu")
		(net "M_D_DQS_DP<7>")
	)
	(segment
		(start 312.850022 -128.276096)
		(end 312.850276 -128.276096)
		(width 0.1651)
		(layer "B.Cu")
		(net "M_D_DQS_DP<7>")
	)
	(segment
		(start 312.850022 -129.425954)
		(end 312.850022 -128.276096)
		(width 0.1651)
		(layer "B.Cu")
		(net "M_D_DQS_DP<7>")
	)
	(segment
		(start 312.887868 -129.4638)
		(end 312.850022 -129.425954)
		(width 0.1651)
		(layer "B.Cu")
		(net "M_D_DQS_DP<7>")
	)
	(segment
		(start 312.887868 -130.683)
		(end 312.887868 -129.4638)
		(width 0.1651)
		(layer "B.Cu")
		(net "M_D_DQS_DP<7>")
	)
	(segment
		(start 312.630312 -130.940556)
		(end 312.887868 -130.683)
		(width 0.1651)
		(layer "B.Cu")
		(net "M_D_DQS_DP<7>")
	)
	(segment
		(start 313.00547 -117.466618)
		(end 313.541664 -117.466618)
		(width 0.14224)
		(layer "In2.Cu")
		(net "M_D_DQS_DP<7>")
	)
	(segment
		(start 312.128154 -132.6642)
		(end 312.213244 -132.6642)
		(width 0.14224)
		(layer "In2.Cu")
		(net "M_D_DQS_DP<7>")
	)
	(segment
		(start 312.391044 -132.842)
		(end 312.391044 -133.118352)
		(width 0.14224)
		(layer "In2.Cu")
		(net "M_D_DQS_DP<7>")
	)
	(segment
		(start 312.228992 -116.18341)
		(end 312.228992 -116.719858)
		(width 0.14224)
		(layer "In2.Cu")
		(net "M_D_DQS_DP<7>")
	)
	(segment
		(start 289.44697 -102.167436)
		(end 289.45332 -102.178104)
		(width 0.0889)
		(layer "In2.Cu")
		(net "M_D_DQS_DP<7>")
	)
	(segment
		(start 312.213244 -132.6642)
		(end 312.391044 -132.842)
		(width 0.14224)
		(layer "In2.Cu")
		(net "M_D_DQS_DP<7>")
	)
	(segment
		(start 314.24372 -128.204722)
		(end 313.266836 -129.181606)
		(width 0.14224)
		(layer "In2.Cu")
		(net "M_D_DQS_DP<7>")
	)
	(segment
		(start 312.387996 -130.940556)
		(end 312.822844 -131.375404)
		(width 0.14224)
		(layer "In2.Cu")
		(net "M_D_DQS_DP<7>")
	)
	(segment
		(start 313.266836 -130.061716)
		(end 312.387996 -130.940556)
		(width 0.14224)
		(layer "In2.Cu")
		(net "M_D_DQS_DP<7>")
	)
	(segment
		(start 312.721498 -117.75059)
		(end 313.00547 -117.466618)
		(width 0.14224)
		(layer "In2.Cu")
		(net "M_D_DQS_DP<7>")
	)
	(segment
		(start 294.96258 -106.3371)
		(end 298.8437 -106.3371)
		(width 0.14224)
		(layer "In2.Cu")
		(net "M_D_DQS_DP<7>")
	)
	(segment
		(start 312.408824 -117.75059)
		(end 312.721498 -117.75059)
		(width 0.14224)
		(layer "In2.Cu")
		(net "M_D_DQS_DP<7>")
	)
	(segment
		(start 293.90848 -105.283)
		(end 294.96258 -106.3371)
		(width 0.14224)
		(layer "In2.Cu")
		(net "M_D_DQS_DP<7>")
	)
	(segment
		(start 312.013346 -132.549392)
		(end 312.128154 -132.6642)
		(width 0.14224)
		(layer "In2.Cu")
		(net "M_D_DQS_DP<7>")
	)
	(segment
		(start 312.150506 -133.298692)
		(end 312.013346 -133.435852)
		(width 0.14224)
		(layer "In2.Cu")
		(net "M_D_DQS_DP<7>")
	)
	(segment
		(start 312.822844 -131.8006)
		(end 312.568844 -132.0546)
		(width 0.14224)
		(layer "In2.Cu")
		(net "M_D_DQS_DP<7>")
	)
	(segment
		(start 291.039042 -104.222804)
		(end 292.792404 -104.222804)
		(width 0.0889)
		(layer "In2.Cu")
		(net "M_D_DQS_DP<7>")
	)
	(segment
		(start 292.792404 -104.222804)
		(end 293.8526 -105.283)
		(width 0.0889)
		(layer "In2.Cu")
		(net "M_D_DQS_DP<7>")
	)
	(segment
		(start 299.6946 -107.188)
		(end 301.845472 -107.188)
		(width 0.14224)
		(layer "In2.Cu")
		(net "M_D_DQS_DP<7>")
	)
	(segment
		(start 312.013346 -132.225034)
		(end 312.013346 -132.549392)
		(width 0.14224)
		(layer "In2.Cu")
		(net "M_D_DQS_DP<7>")
	)
	(segment
		(start 289.582098 -102.76586)
		(end 291.039042 -104.222804)
		(width 0.0889)
		(layer "In2.Cu")
		(net "M_D_DQS_DP<7>")
	)
	(segment
		(start 312.568844 -132.0546)
		(end 312.18378 -132.0546)
		(width 0.14224)
		(layer "In2.Cu")
		(net "M_D_DQS_DP<7>")
	)
	(segment
		(start 312.013346 -133.662166)
		(end 312.20918 -133.858)
		(width 0.14224)
		(layer "In2.Cu")
		(net "M_D_DQS_DP<7>")
	)
	(segment
		(start 289.45332 -100.766118)
		(end 289.44697 -100.776786)
		(width 0.0889)
		(layer "In2.Cu")
		(net "M_D_DQS_DP<7>")
	)
	(segment
		(start 312.013346 -133.435852)
		(end 312.013346 -133.662166)
		(width 0.14224)
		(layer "In2.Cu")
		(net "M_D_DQS_DP<7>")
	)
	(segment
		(start 312.20918 -133.858)
		(end 312.594244 -133.858)
		(width 0.14224)
		(layer "In2.Cu")
		(net "M_D_DQS_DP<7>")
	)
	(segment
		(start 311.98312 -116.96573)
		(end 311.98312 -117.324886)
		(width 0.14224)
		(layer "In2.Cu")
		(net "M_D_DQS_DP<7>")
	)
	(segment
		(start 313.541664 -117.466618)
		(end 314.24372 -118.168674)
		(width 0.14224)
		(layer "In2.Cu")
		(net "M_D_DQS_DP<7>")
	)
	(segment
		(start 301.845472 -107.188)
		(end 310.503062 -115.84559)
		(width 0.14224)
		(layer "In2.Cu")
		(net "M_D_DQS_DP<7>")
	)
	(segment
		(start 289.442144 -100.1776)
		(end 289.44697 -100.186236)
		(width 0.0889)
		(layer "In2.Cu")
		(net "M_D_DQS_DP<7>")
	)
	(segment
		(start 313.266836 -129.181606)
		(end 313.266836 -130.061716)
		(width 0.14224)
		(layer "In2.Cu")
		(net "M_D_DQS_DP<7>")
	)
	(segment
		(start 312.391044 -133.118352)
		(end 312.210704 -133.298692)
		(width 0.14224)
		(layer "In2.Cu")
		(net "M_D_DQS_DP<7>")
	)
	(segment
		(start 312.848244 -134.112)
		(end 312.848244 -134.550912)
		(width 0.14224)
		(layer "In2.Cu")
		(net "M_D_DQS_DP<7>")
	)
	(segment
		(start 312.848244 -134.550912)
		(end 312.387996 -135.01116)
		(width 0.14224)
		(layer "In2.Cu")
		(net "M_D_DQS_DP<7>")
	)
	(segment
		(start 312.228992 -116.719858)
		(end 311.98312 -116.96573)
		(width 0.14224)
		(layer "In2.Cu")
		(net "M_D_DQS_DP<7>")
	)
	(segment
		(start 312.210704 -133.298692)
		(end 312.150506 -133.298692)
		(width 0.14224)
		(layer "In2.Cu")
		(net "M_D_DQS_DP<7>")
	)
	(segment
		(start 314.24372 -118.168674)
		(end 314.24372 -128.204722)
		(width 0.14224)
		(layer "In2.Cu")
		(net "M_D_DQS_DP<7>")
	)
	(segment
		(start 310.815736 -115.84559)
		(end 311.08523 -115.576096)
		(width 0.14224)
		(layer "In2.Cu")
		(net "M_D_DQS_DP<7>")
	)
	(segment
		(start 312.18378 -132.0546)
		(end 312.013346 -132.225034)
		(width 0.14224)
		(layer "In2.Cu")
		(net "M_D_DQS_DP<7>")
	)
	(segment
		(start 298.8437 -106.3371)
		(end 299.6946 -107.188)
		(width 0.14224)
		(layer "In2.Cu")
		(net "M_D_DQS_DP<7>")
	)
	(segment
		(start 289.582098 -102.680516)
		(end 289.582098 -102.76586)
		(width 0.0889)
		(layer "In2.Cu")
		(net "M_D_DQS_DP<7>")
	)
	(segment
		(start 289.442144 -102.1588)
		(end 289.44697 -102.167436)
		(width 0.0889)
		(layer "In2.Cu")
		(net "M_D_DQS_DP<7>")
	)
	(segment
		(start 312.822844 -131.375404)
		(end 312.822844 -131.8006)
		(width 0.14224)
		(layer "In2.Cu")
		(net "M_D_DQS_DP<7>")
	)
	(segment
		(start 311.08523 -115.576096)
		(end 311.621678 -115.576096)
		(width 0.14224)
		(layer "In2.Cu")
		(net "M_D_DQS_DP<7>")
	)
	(segment
		(start 311.98312 -117.324886)
		(end 312.408824 -117.75059)
		(width 0.14224)
		(layer "In2.Cu")
		(net "M_D_DQS_DP<7>")
	)
	(segment
		(start 293.8526 -105.283)
		(end 293.90848 -105.283)
		(width 0.0889)
		(layer "In2.Cu")
		(net "M_D_DQS_DP<7>")
	)
	(segment
		(start 311.621678 -115.576096)
		(end 312.228992 -116.18341)
		(width 0.14224)
		(layer "In2.Cu")
		(net "M_D_DQS_DP<7>")
	)
	(segment
		(start 312.594244 -133.858)
		(end 312.848244 -134.112)
		(width 0.14224)
		(layer "In2.Cu")
		(net "M_D_DQS_DP<7>")
	)
	(segment
		(start 310.503062 -115.84559)
		(end 310.815736 -115.84559)
		(width 0.14224)
		(layer "In2.Cu")
		(net "M_D_DQS_DP<7>")
	)
	(arc
		(start 289.42538 -99.160584)
		(mid 289.525862 -99.470306)
		(end 289.44697 -99.786186)
		(width 0.0889)
		(layer "In2.Cu")
		(net "M_D_DQS_DP<7>")
	)
	(arc
		(start 289.44697 -100.776786)
		(mid 289.393471 -100.976684)
		(end 289.44697 -101.176582)
		(width 0.0889)
		(layer "In2.Cu")
		(net "M_D_DQS_DP<7>")
	)
	(arc
		(start 289.44697 -101.767386)
		(mid 289.3935 -101.962449)
		(end 289.442144 -102.1588)
		(width 0.0889)
		(layer "In2.Cu")
		(net "M_D_DQS_DP<7>")
	)
	(arc
		(start 289.45332 -102.178104)
		(mid 289.549391 -102.421189)
		(end 289.582098 -102.680516)
		(width 0.0889)
		(layer "In2.Cu")
		(net "M_D_DQS_DP<7>")
	)
	(arc
		(start 288.93516 -98.500184)
		(mid 289.187831 -98.824771)
		(end 289.42538 -99.160584)
		(width 0.0889)
		(layer "In2.Cu")
		(net "M_D_DQS_DP<7>")
	)
	(arc
		(start 289.44697 -100.186236)
		(mid 289.526192 -100.475354)
		(end 289.45332 -100.766118)
		(width 0.0889)
		(layer "In2.Cu")
		(net "M_D_DQS_DP<7>")
	)
	(arc
		(start 289.44697 -101.176582)
		(mid 289.526101 -101.471984)
		(end 289.44697 -101.767386)
		(width 0.0889)
		(layer "In2.Cu")
		(net "M_D_DQS_DP<7>")
	)
	(arc
		(start 289.44697 -99.786186)
		(mid 289.3935 -99.981249)
		(end 289.442144 -100.1776)
		(width 0.0889)
		(layer "In2.Cu")
		(net "M_D_DQS_DP<7>")
	)
	(segment
		(start 283.212794 -98.500184)
		(end 283.784294 -98.500184)
		(width 0.1651)
		(layer "F.Cu")
		(net "M_D_DQS_DP<6>")
	)
	(segment
		(start 303.500028 -136.664446)
		(end 303.537874 -136.6266)
		(width 0.1651)
		(layer "F.Cu")
		(net "M_D_DQS_DP<6>")
	)
	(segment
		(start 303.294034 -135.01116)
		(end 303.038002 -135.01116)
		(width 0.1651)
		(layer "F.Cu")
		(net "M_D_DQS_DP<6>")
	)
	(segment
		(start 303.500028 -137.67054)
		(end 303.500028 -136.664446)
		(width 0.1651)
		(layer "F.Cu")
		(net "M_D_DQS_DP<6>")
	)
	(segment
		(start 303.537874 -136.6266)
		(end 303.537874 -135.255)
		(width 0.1651)
		(layer "F.Cu")
		(net "M_D_DQS_DP<6>")
	)
	(segment
		(start 303.537874 -135.255)
		(end 303.294034 -135.01116)
		(width 0.1651)
		(layer "F.Cu")
		(net "M_D_DQS_DP<6>")
	)
	(segment
		(start 303.500282 -137.67054)
		(end 303.500028 -137.67054)
		(width 0.1651)
		(layer "F.Cu")
		(net "M_D_DQS_DP<6>")
	)
	(via
		(at 283.784294 -98.500184)
		(size 0.508)
		(drill 0.254)
		(layers "F.Cu" "B.Cu")
		(net "M_D_DQS_DP<6>")
	)
	(via
		(at 303.038002 -130.940556)
		(size 0.508)
		(drill 0.254)
		(layers "F.Cu" "B.Cu")
		(net "M_D_DQS_DP<6>")
	)
	(via
		(at 303.038002 -135.01116)
		(size 0.508)
		(drill 0.254)
		(layers "F.Cu" "B.Cu")
		(net "M_D_DQS_DP<6>")
	)
	(segment
		(start 303.537874 -130.683)
		(end 303.537874 -129.4638)
		(width 0.1651)
		(layer "B.Cu")
		(net "M_D_DQS_DP<6>")
	)
	(segment
		(start 303.500028 -129.425954)
		(end 303.500028 -128.276096)
		(width 0.1651)
		(layer "B.Cu")
		(net "M_D_DQS_DP<6>")
	)
	(segment
		(start 303.537874 -129.4638)
		(end 303.500028 -129.425954)
		(width 0.1651)
		(layer "B.Cu")
		(net "M_D_DQS_DP<6>")
	)
	(segment
		(start 303.038002 -130.940556)
		(end 303.280318 -130.940556)
		(width 0.1651)
		(layer "B.Cu")
		(net "M_D_DQS_DP<6>")
	)
	(segment
		(start 303.500028 -128.276096)
		(end 303.500282 -128.276096)
		(width 0.1651)
		(layer "B.Cu")
		(net "M_D_DQS_DP<6>")
	)
	(segment
		(start 303.280318 -130.940556)
		(end 303.537874 -130.683)
		(width 0.1651)
		(layer "B.Cu")
		(net "M_D_DQS_DP<6>")
	)
	(segment
		(start 302.663352 -132.549392)
		(end 302.77816 -132.6642)
		(width 0.14224)
		(layer "In2.Cu")
		(net "M_D_DQS_DP<6>")
	)
	(segment
		(start 284.242256 -103.948738)
		(end 284.242256 -106.019346)
		(width 0.0889)
		(layer "In2.Cu")
		(net "M_D_DQS_DP<6>")
	)
	(segment
		(start 284.291278 -101.1682)
		(end 284.296104 -101.176836)
		(width 0.0889)
		(layer "In2.Cu")
		(net "M_D_DQS_DP<6>")
	)
	(segment
		(start 284.242256 -106.019346)
		(end 284.109414 -106.152188)
		(width 0.0889)
		(layer "In2.Cu")
		(net "M_D_DQS_DP<6>")
	)
	(segment
		(start 303.47285 -131.375404)
		(end 303.47285 -131.8006)
		(width 0.14224)
		(layer "In2.Cu")
		(net "M_D_DQS_DP<6>")
	)
	(segment
		(start 284.148784 -106.6292)
		(end 284.148784 -106.651298)
		(width 0.0889)
		(layer "In2.Cu")
		(net "M_D_DQS_DP<6>")
	)
	(segment
		(start 302.86071 -133.298692)
		(end 302.800512 -133.298692)
		(width 0.14224)
		(layer "In2.Cu")
		(net "M_D_DQS_DP<6>")
	)
	(segment
		(start 296.270426 -115.37188)
		(end 296.925492 -115.37188)
		(width 0.14224)
		(layer "In2.Cu")
		(net "M_D_DQS_DP<6>")
	)
	(segment
		(start 302.663352 -133.435852)
		(end 302.663352 -133.662166)
		(width 0.14224)
		(layer "In2.Cu")
		(net "M_D_DQS_DP<6>")
	)
	(segment
		(start 284.298644 -103.162354)
		(end 284.302454 -103.169466)
		(width 0.0889)
		(layer "In2.Cu")
		(net "M_D_DQS_DP<6>")
	)
	(segment
		(start 303.24425 -133.858)
		(end 303.49825 -134.112)
		(width 0.14224)
		(layer "In2.Cu")
		(net "M_D_DQS_DP<6>")
	)
	(segment
		(start 284.109414 -106.58983)
		(end 284.148784 -106.6292)
		(width 0.0889)
		(layer "In2.Cu")
		(net "M_D_DQS_DP<6>")
	)
	(segment
		(start 298.17822 -115.750848)
		(end 298.557188 -115.37188)
		(width 0.14224)
		(layer "In2.Cu")
		(net "M_D_DQS_DP<6>")
	)
	(segment
		(start 303.04105 -132.842)
		(end 303.04105 -133.118352)
		(width 0.14224)
		(layer "In2.Cu")
		(net "M_D_DQS_DP<6>")
	)
	(segment
		(start 302.663352 -133.662166)
		(end 302.859186 -133.858)
		(width 0.14224)
		(layer "In2.Cu")
		(net "M_D_DQS_DP<6>")
	)
	(segment
		(start 303.49825 -134.550912)
		(end 303.038002 -135.01116)
		(width 0.14224)
		(layer "In2.Cu")
		(net "M_D_DQS_DP<6>")
	)
	(segment
		(start 295.89222 -116.198396)
		(end 295.89222 -115.750086)
		(width 0.14224)
		(layer "In2.Cu")
		(net "M_D_DQS_DP<6>")
	)
	(segment
		(start 296.925492 -115.37188)
		(end 297.30446 -115.750848)
		(width 0.14224)
		(layer "In2.Cu")
		(net "M_D_DQS_DP<6>")
	)
	(segment
		(start 303.21885 -132.0546)
		(end 302.833786 -132.0546)
		(width 0.14224)
		(layer "In2.Cu")
		(net "M_D_DQS_DP<6>")
	)
	(segment
		(start 286.1564 -112.808766)
		(end 289.767518 -116.419884)
		(width 0.14224)
		(layer "In2.Cu")
		(net "M_D_DQS_DP<6>")
	)
	(segment
		(start 284.291278 -103.1494)
		(end 284.298644 -103.162354)
		(width 0.0889)
		(layer "In2.Cu")
		(net "M_D_DQS_DP<6>")
	)
	(segment
		(start 302.800512 -133.298692)
		(end 302.663352 -133.435852)
		(width 0.14224)
		(layer "In2.Cu")
		(net "M_D_DQS_DP<6>")
	)
	(segment
		(start 284.302454 -103.169466)
		(end 284.303216 -103.170736)
		(width 0.0889)
		(layer "In2.Cu")
		(net "M_D_DQS_DP<6>")
	)
	(segment
		(start 297.98518 -116.354352)
		(end 298.17822 -116.161312)
		(width 0.14224)
		(layer "In2.Cu")
		(net "M_D_DQS_DP<6>")
	)
	(segment
		(start 295.670732 -116.419884)
		(end 295.89222 -116.198396)
		(width 0.14224)
		(layer "In2.Cu")
		(net "M_D_DQS_DP<6>")
	)
	(segment
		(start 303.820322 -130.158236)
		(end 303.038002 -130.940556)
		(width 0.14224)
		(layer "In2.Cu")
		(net "M_D_DQS_DP<6>")
	)
	(segment
		(start 284.291278 -102.1588)
		(end 284.296104 -102.167436)
		(width 0.0889)
		(layer "In2.Cu")
		(net "M_D_DQS_DP<6>")
	)
	(segment
		(start 289.767518 -116.419884)
		(end 295.670732 -116.419884)
		(width 0.14224)
		(layer "In2.Cu")
		(net "M_D_DQS_DP<6>")
	)
	(segment
		(start 298.557188 -115.37188)
		(end 299.186092 -115.37188)
		(width 0.14224)
		(layer "In2.Cu")
		(net "M_D_DQS_DP<6>")
	)
	(segment
		(start 297.30446 -115.750848)
		(end 297.30446 -116.161312)
		(width 0.14224)
		(layer "In2.Cu")
		(net "M_D_DQS_DP<6>")
	)
	(segment
		(start 297.30446 -116.161312)
		(end 297.4975 -116.354352)
		(width 0.14224)
		(layer "In2.Cu")
		(net "M_D_DQS_DP<6>")
	)
	(segment
		(start 299.186092 -115.37188)
		(end 303.820322 -120.00611)
		(width 0.14224)
		(layer "In2.Cu")
		(net "M_D_DQS_DP<6>")
	)
	(segment
		(start 298.17822 -116.161312)
		(end 298.17822 -115.750848)
		(width 0.14224)
		(layer "In2.Cu")
		(net "M_D_DQS_DP<6>")
	)
	(segment
		(start 295.89222 -115.750086)
		(end 296.270426 -115.37188)
		(width 0.14224)
		(layer "In2.Cu")
		(net "M_D_DQS_DP<6>")
	)
	(segment
		(start 303.49825 -134.112)
		(end 303.49825 -134.550912)
		(width 0.14224)
		(layer "In2.Cu")
		(net "M_D_DQS_DP<6>")
	)
	(segment
		(start 284.109414 -106.152188)
		(end 284.109414 -106.58983)
		(width 0.0889)
		(layer "In2.Cu")
		(net "M_D_DQS_DP<6>")
	)
	(segment
		(start 302.833786 -132.0546)
		(end 302.663352 -132.225034)
		(width 0.14224)
		(layer "In2.Cu")
		(net "M_D_DQS_DP<6>")
	)
	(segment
		(start 297.4975 -116.354352)
		(end 297.98518 -116.354352)
		(width 0.14224)
		(layer "In2.Cu")
		(net "M_D_DQS_DP<6>")
	)
	(segment
		(start 284.296104 -101.176836)
		(end 284.302454 -101.187504)
		(width 0.0889)
		(layer "In2.Cu")
		(net "M_D_DQS_DP<6>")
	)
	(segment
		(start 303.47285 -131.8006)
		(end 303.21885 -132.0546)
		(width 0.14224)
		(layer "In2.Cu")
		(net "M_D_DQS_DP<6>")
	)
	(segment
		(start 302.859186 -133.858)
		(end 303.24425 -133.858)
		(width 0.14224)
		(layer "In2.Cu")
		(net "M_D_DQS_DP<6>")
	)
	(segment
		(start 302.77816 -132.6642)
		(end 302.86325 -132.6642)
		(width 0.14224)
		(layer "In2.Cu")
		(net "M_D_DQS_DP<6>")
	)
	(segment
		(start 302.86325 -132.6642)
		(end 303.04105 -132.842)
		(width 0.14224)
		(layer "In2.Cu")
		(net "M_D_DQS_DP<6>")
	)
	(segment
		(start 302.663352 -132.225034)
		(end 302.663352 -132.549392)
		(width 0.14224)
		(layer "In2.Cu")
		(net "M_D_DQS_DP<6>")
	)
	(segment
		(start 303.820322 -120.00611)
		(end 303.820322 -130.158236)
		(width 0.14224)
		(layer "In2.Cu")
		(net "M_D_DQS_DP<6>")
	)
	(segment
		(start 284.148784 -110.031784)
		(end 286.1564 -112.0394)
		(width 0.14224)
		(layer "In2.Cu")
		(net "M_D_DQS_DP<6>")
	)
	(segment
		(start 284.148784 -106.651298)
		(end 284.148784 -110.031784)
		(width 0.14224)
		(layer "In2.Cu")
		(net "M_D_DQS_DP<6>")
	)
	(segment
		(start 286.1564 -112.0394)
		(end 286.1564 -112.808766)
		(width 0.14224)
		(layer "In2.Cu")
		(net "M_D_DQS_DP<6>")
	)
	(segment
		(start 303.04105 -133.118352)
		(end 302.86071 -133.298692)
		(width 0.14224)
		(layer "In2.Cu")
		(net "M_D_DQS_DP<6>")
	)
	(segment
		(start 284.296104 -102.167436)
		(end 284.302454 -102.178104)
		(width 0.0889)
		(layer "In2.Cu")
		(net "M_D_DQS_DP<6>")
	)
	(segment
		(start 303.038002 -130.940556)
		(end 303.47285 -131.375404)
		(width 0.14224)
		(layer "In2.Cu")
		(net "M_D_DQS_DP<6>")
	)
	(arc
		(start 284.302454 -102.178104)
		(mid 284.375252 -102.468867)
		(end 284.296104 -102.757986)
		(width 0.0889)
		(layer "In2.Cu")
		(net "M_D_DQS_DP<6>")
	)
	(arc
		(start 284.296104 -100.776786)
		(mid 284.242634 -100.971849)
		(end 284.291278 -101.1682)
		(width 0.0889)
		(layer "In2.Cu")
		(net "M_D_DQS_DP<6>")
	)
	(arc
		(start 284.267148 -100.127562)
		(mid 284.28397 -100.162656)
		(end 284.302454 -100.196904)
		(width 0.0889)
		(layer "In2.Cu")
		(net "M_D_DQS_DP<6>")
	)
	(arc
		(start 284.296104 -103.748586)
		(mid 284.255969 -103.845112)
		(end 284.242256 -103.948738)
		(width 0.0889)
		(layer "In2.Cu")
		(net "M_D_DQS_DP<6>")
	)
	(arc
		(start 284.303216 -103.170736)
		(mid 284.375182 -103.460606)
		(end 284.296104 -103.748586)
		(width 0.0889)
		(layer "In2.Cu")
		(net "M_D_DQS_DP<6>")
	)
	(arc
		(start 284.296104 -101.767386)
		(mid 284.242634 -101.962449)
		(end 284.291278 -102.1588)
		(width 0.0889)
		(layer "In2.Cu")
		(net "M_D_DQS_DP<6>")
	)
	(arc
		(start 284.181042 -99.543362)
		(mid 284.183366 -99.841468)
		(end 284.267148 -100.127562)
		(width 0.0889)
		(layer "In2.Cu")
		(net "M_D_DQS_DP<6>")
	)
	(arc
		(start 284.302454 -100.196904)
		(mid 284.375252 -100.487667)
		(end 284.296104 -100.776786)
		(width 0.0889)
		(layer "In2.Cu")
		(net "M_D_DQS_DP<6>")
	)
	(arc
		(start 284.296104 -102.757986)
		(mid 284.242634 -102.953049)
		(end 284.291278 -103.1494)
		(width 0.0889)
		(layer "In2.Cu")
		(net "M_D_DQS_DP<6>")
	)
	(arc
		(start 284.302454 -101.187504)
		(mid 284.375252 -101.478267)
		(end 284.296104 -101.767386)
		(width 0.0889)
		(layer "In2.Cu")
		(net "M_D_DQS_DP<6>")
	)
	(arc
		(start 283.784294 -98.500184)
		(mid 283.935946 -98.905423)
		(end 284.131004 -99.291648)
		(width 0.0889)
		(layer "In2.Cu")
		(net "M_D_DQS_DP<6>")
	)
	(arc
		(start 284.131004 -99.291648)
		(mid 284.176717 -99.413385)
		(end 284.181042 -99.543362)
		(width 0.0889)
		(layer "In2.Cu")
		(net "M_D_DQS_DP<6>")
	)
	(segment
		(start 294.150034 -137.67054)
		(end 294.150034 -136.664446)
		(width 0.1651)
		(layer "F.Cu")
		(net "M_D_DQS_DP<5>")
	)
	(segment
		(start 293.94404 -135.01116)
		(end 293.688008 -135.01116)
		(width 0.1651)
		(layer "F.Cu")
		(net "M_D_DQS_DP<5>")
	)
	(segment
		(start 294.18788 -135.255)
		(end 293.94404 -135.01116)
		(width 0.1651)
		(layer "F.Cu")
		(net "M_D_DQS_DP<5>")
	)
	(segment
		(start 294.18788 -136.6266)
		(end 294.18788 -135.255)
		(width 0.1651)
		(layer "F.Cu")
		(net "M_D_DQS_DP<5>")
	)
	(segment
		(start 278.061674 -98.500184)
		(end 278.633174 -98.500184)
		(width 0.1651)
		(layer "F.Cu")
		(net "M_D_DQS_DP<5>")
	)
	(segment
		(start 294.150034 -136.664446)
		(end 294.18788 -136.6266)
		(width 0.1651)
		(layer "F.Cu")
		(net "M_D_DQS_DP<5>")
	)
	(segment
		(start 294.150288 -137.67054)
		(end 294.150034 -137.67054)
		(width 0.1651)
		(layer "F.Cu")
		(net "M_D_DQS_DP<5>")
	)
	(via
		(at 278.633174 -98.500184)
		(size 0.508)
		(drill 0.254)
		(layers "F.Cu" "B.Cu")
		(net "M_D_DQS_DP<5>")
	)
	(via
		(at 293.688008 -135.01116)
		(size 0.508)
		(drill 0.254)
		(layers "F.Cu" "B.Cu")
		(net "M_D_DQS_DP<5>")
	)
	(via
		(at 293.688008 -130.940556)
		(size 0.508)
		(drill 0.254)
		(layers "F.Cu" "B.Cu")
		(net "M_D_DQS_DP<5>")
	)
	(segment
		(start 293.930324 -130.940556)
		(end 294.18788 -130.683)
		(width 0.1651)
		(layer "B.Cu")
		(net "M_D_DQS_DP<5>")
	)
	(segment
		(start 294.18788 -130.683)
		(end 294.18788 -129.4638)
		(width 0.1651)
		(layer "B.Cu")
		(net "M_D_DQS_DP<5>")
	)
	(segment
		(start 294.150034 -129.425954)
		(end 294.150034 -128.276096)
		(width 0.1651)
		(layer "B.Cu")
		(net "M_D_DQS_DP<5>")
	)
	(segment
		(start 293.688008 -130.940556)
		(end 293.930324 -130.940556)
		(width 0.1651)
		(layer "B.Cu")
		(net "M_D_DQS_DP<5>")
	)
	(segment
		(start 294.150034 -128.276096)
		(end 294.150288 -128.276096)
		(width 0.1651)
		(layer "B.Cu")
		(net "M_D_DQS_DP<5>")
	)
	(segment
		(start 294.18788 -129.4638)
		(end 294.150034 -129.425954)
		(width 0.1651)
		(layer "B.Cu")
		(net "M_D_DQS_DP<5>")
	)
	(segment
		(start 294.546528 -124.237242)
		(end 294.546528 -130.082036)
		(width 0.14224)
		(layer "In2.Cu")
		(net "M_D_DQS_DP<5>")
	)
	(segment
		(start 293.450518 -133.298692)
		(end 293.313358 -133.435852)
		(width 0.14224)
		(layer "In2.Cu")
		(net "M_D_DQS_DP<5>")
	)
	(segment
		(start 276.136862 -113.901728)
		(end 276.423374 -113.901728)
		(width 0.14224)
		(layer "In2.Cu")
		(net "M_D_DQS_DP<5>")
	)
	(segment
		(start 276.125686 -113.238788)
		(end 275.976334 -113.38814)
		(width 0.14224)
		(layer "In2.Cu")
		(net "M_D_DQS_DP<5>")
	)
	(segment
		(start 276.735794 -106.295698)
		(end 276.735794 -112.926368)
		(width 0.14224)
		(layer "In2.Cu")
		(net "M_D_DQS_DP<5>")
	)
	(segment
		(start 293.428166 -132.6642)
		(end 293.513256 -132.6642)
		(width 0.14224)
		(layer "In2.Cu")
		(net "M_D_DQS_DP<5>")
	)
	(segment
		(start 276.735794 -112.926368)
		(end 276.423374 -113.238788)
		(width 0.14224)
		(layer "In2.Cu")
		(net "M_D_DQS_DP<5>")
	)
	(segment
		(start 293.313358 -132.225034)
		(end 293.313358 -132.549392)
		(width 0.14224)
		(layer "In2.Cu")
		(net "M_D_DQS_DP<5>")
	)
	(segment
		(start 276.735794 -114.214148)
		(end 276.735794 -115.80749)
		(width 0.14224)
		(layer "In2.Cu")
		(net "M_D_DQS_DP<5>")
	)
	(segment
		(start 276.423374 -113.238788)
		(end 276.125686 -113.238788)
		(width 0.14224)
		(layer "In2.Cu")
		(net "M_D_DQS_DP<5>")
	)
	(segment
		(start 278.690324 -101.918008)
		(end 278.050498 -102.557834)
		(width 0.0889)
		(layer "In2.Cu")
		(net "M_D_DQS_DP<5>")
	)
	(segment
		(start 293.509192 -133.858)
		(end 293.894256 -133.858)
		(width 0.14224)
		(layer "In2.Cu")
		(net "M_D_DQS_DP<5>")
	)
	(segment
		(start 294.148256 -134.112)
		(end 294.148256 -134.550912)
		(width 0.14224)
		(layer "In2.Cu")
		(net "M_D_DQS_DP<5>")
	)
	(segment
		(start 294.122856 -131.375404)
		(end 294.122856 -131.8006)
		(width 0.14224)
		(layer "In2.Cu")
		(net "M_D_DQS_DP<5>")
	)
	(segment
		(start 293.510716 -133.298692)
		(end 293.450518 -133.298692)
		(width 0.14224)
		(layer "In2.Cu")
		(net "M_D_DQS_DP<5>")
	)
	(segment
		(start 284.74416 -123.815856)
		(end 294.125142 -123.815856)
		(width 0.14224)
		(layer "In2.Cu")
		(net "M_D_DQS_DP<5>")
	)
	(segment
		(start 293.483792 -132.0546)
		(end 293.313358 -132.225034)
		(width 0.14224)
		(layer "In2.Cu")
		(net "M_D_DQS_DP<5>")
	)
	(segment
		(start 277.608792 -102.557834)
		(end 277.353522 -102.813104)
		(width 0.0889)
		(layer "In2.Cu")
		(net "M_D_DQS_DP<5>")
	)
	(segment
		(start 293.313358 -132.549392)
		(end 293.428166 -132.6642)
		(width 0.14224)
		(layer "In2.Cu")
		(net "M_D_DQS_DP<5>")
	)
	(segment
		(start 276.696424 -106.23423)
		(end 276.735794 -106.2736)
		(width 0.0889)
		(layer "In2.Cu")
		(net "M_D_DQS_DP<5>")
	)
	(segment
		(start 278.050498 -102.557834)
		(end 277.608792 -102.557834)
		(width 0.0889)
		(layer "In2.Cu")
		(net "M_D_DQS_DP<5>")
	)
	(segment
		(start 293.868856 -132.0546)
		(end 293.483792 -132.0546)
		(width 0.14224)
		(layer "In2.Cu")
		(net "M_D_DQS_DP<5>")
	)
	(segment
		(start 293.894256 -133.858)
		(end 294.148256 -134.112)
		(width 0.14224)
		(layer "In2.Cu")
		(net "M_D_DQS_DP<5>")
	)
	(segment
		(start 277.353522 -104.04221)
		(end 276.696424 -104.699308)
		(width 0.0889)
		(layer "In2.Cu")
		(net "M_D_DQS_DP<5>")
	)
	(segment
		(start 293.513256 -132.6642)
		(end 293.691056 -132.842)
		(width 0.14224)
		(layer "In2.Cu")
		(net "M_D_DQS_DP<5>")
	)
	(segment
		(start 293.691056 -132.842)
		(end 293.691056 -133.118352)
		(width 0.14224)
		(layer "In2.Cu")
		(net "M_D_DQS_DP<5>")
	)
	(segment
		(start 277.353522 -102.813104)
		(end 277.353522 -104.04221)
		(width 0.0889)
		(layer "In2.Cu")
		(net "M_D_DQS_DP<5>")
	)
	(segment
		(start 276.735794 -106.2736)
		(end 276.735794 -106.295698)
		(width 0.0889)
		(layer "In2.Cu")
		(net "M_D_DQS_DP<5>")
	)
	(segment
		(start 279.223978 -100.673154)
		(end 278.690324 -101.206808)
		(width 0.0889)
		(layer "In2.Cu")
		(net "M_D_DQS_DP<5>")
	)
	(segment
		(start 294.148256 -134.550912)
		(end 293.688008 -135.01116)
		(width 0.14224)
		(layer "In2.Cu")
		(net "M_D_DQS_DP<5>")
	)
	(segment
		(start 278.690324 -101.206808)
		(end 278.690324 -101.918008)
		(width 0.0889)
		(layer "In2.Cu")
		(net "M_D_DQS_DP<5>")
	)
	(segment
		(start 293.313358 -133.435852)
		(end 293.313358 -133.662166)
		(width 0.14224)
		(layer "In2.Cu")
		(net "M_D_DQS_DP<5>")
	)
	(segment
		(start 294.546528 -130.082036)
		(end 293.688008 -130.940556)
		(width 0.14224)
		(layer "In2.Cu")
		(net "M_D_DQS_DP<5>")
	)
	(segment
		(start 275.976334 -113.7412)
		(end 276.136862 -113.901728)
		(width 0.14224)
		(layer "In2.Cu")
		(net "M_D_DQS_DP<5>")
	)
	(segment
		(start 276.423374 -113.901728)
		(end 276.735794 -114.214148)
		(width 0.14224)
		(layer "In2.Cu")
		(net "M_D_DQS_DP<5>")
	)
	(segment
		(start 279.223978 -100.481638)
		(end 279.223978 -100.673154)
		(width 0.0889)
		(layer "In2.Cu")
		(net "M_D_DQS_DP<5>")
	)
	(segment
		(start 293.691056 -133.118352)
		(end 293.510716 -133.298692)
		(width 0.14224)
		(layer "In2.Cu")
		(net "M_D_DQS_DP<5>")
	)
	(segment
		(start 293.688008 -130.940556)
		(end 294.122856 -131.375404)
		(width 0.14224)
		(layer "In2.Cu")
		(net "M_D_DQS_DP<5>")
	)
	(segment
		(start 294.122856 -131.8006)
		(end 293.868856 -132.0546)
		(width 0.14224)
		(layer "In2.Cu")
		(net "M_D_DQS_DP<5>")
	)
	(segment
		(start 294.125142 -123.815856)
		(end 294.546528 -124.237242)
		(width 0.14224)
		(layer "In2.Cu")
		(net "M_D_DQS_DP<5>")
	)
	(segment
		(start 276.696424 -104.699308)
		(end 276.696424 -106.23423)
		(width 0.0889)
		(layer "In2.Cu")
		(net "M_D_DQS_DP<5>")
	)
	(segment
		(start 275.976334 -113.38814)
		(end 275.976334 -113.7412)
		(width 0.14224)
		(layer "In2.Cu")
		(net "M_D_DQS_DP<5>")
	)
	(segment
		(start 293.313358 -133.662166)
		(end 293.509192 -133.858)
		(width 0.14224)
		(layer "In2.Cu")
		(net "M_D_DQS_DP<5>")
	)
	(segment
		(start 276.735794 -115.80749)
		(end 284.74416 -123.815856)
		(width 0.14224)
		(layer "In2.Cu")
		(net "M_D_DQS_DP<5>")
	)
	(arc
		(start 279.029922 -99.543362)
		(mid 279.03762 -99.873963)
		(end 279.144984 -100.186744)
		(width 0.0889)
		(layer "In2.Cu")
		(net "M_D_DQS_DP<5>")
	)
	(arc
		(start 278.979884 -99.291648)
		(mid 279.025597 -99.413385)
		(end 279.029922 -99.543362)
		(width 0.0889)
		(layer "In2.Cu")
		(net "M_D_DQS_DP<5>")
	)
	(arc
		(start 279.144984 -100.186744)
		(mid 279.203863 -100.329)
		(end 279.223978 -100.481638)
		(width 0.0889)
		(layer "In2.Cu")
		(net "M_D_DQS_DP<5>")
	)
	(arc
		(start 278.633174 -98.500184)
		(mid 278.784826 -98.905423)
		(end 278.979884 -99.291648)
		(width 0.0889)
		(layer "In2.Cu")
		(net "M_D_DQS_DP<5>")
	)
	(segment
		(start 284.837632 -136.6266)
		(end 284.799786 -136.664446)
		(width 0.1651)
		(layer "F.Cu")
		(net "M_D_DQS_DP<4>")
	)
	(segment
		(start 277.612602 -118.368572)
		(end 277.398988 -118.582186)
		(width 0.1651)
		(layer "F.Cu")
		(net "M_D_DQS_DP<4>")
	)
	(segment
		(start 279.078182 -119.953786)
		(end 278.89073 -120.141238)
		(width 0.1651)
		(layer "F.Cu")
		(net "M_D_DQS_DP<4>")
	)
	(segment
		(start 279.201626 -120.704102)
		(end 279.491948 -120.704102)
		(width 0.1651)
		(layer "F.Cu")
		(net "M_D_DQS_DP<4>")
	)
	(segment
		(start 284.593792 -135.01116)
		(end 284.837632 -135.255)
		(width 0.1651)
		(layer "F.Cu")
		(net "M_D_DQS_DP<4>")
	)
	(segment
		(start 277.398988 -118.582186)
		(end 277.398988 -118.841266)
		(width 0.1651)
		(layer "F.Cu")
		(net "M_D_DQS_DP<4>")
	)
	(segment
		(start 284.33776 -135.01116)
		(end 284.593792 -135.01116)
		(width 0.1651)
		(layer "F.Cu")
		(net "M_D_DQS_DP<4>")
	)
	(segment
		(start 275.718524 -103.40086)
		(end 275.718524 -104.86517)
		(width 0.0889)
		(layer "F.Cu")
		(net "M_D_DQS_DP<4>")
	)
	(segment
		(start 275.051774 -105.53192)
		(end 275.051774 -106.471974)
		(width 0.0889)
		(layer "F.Cu")
		(net "M_D_DQS_DP<4>")
	)
	(segment
		(start 275.516594 -113.357406)
		(end 275.516594 -113.66754)
		(width 0.1651)
		(layer "F.Cu")
		(net "M_D_DQS_DP<4>")
	)
	(segment
		(start 275.5519 -112.9157)
		(end 275.5519 -113.3221)
		(width 0.1016)
		(layer "F.Cu")
		(net "M_D_DQS_DP<4>")
	)
	(segment
		(start 279.7175 -120.47855)
		(end 280.16073 -120.47855)
		(width 0.1651)
		(layer "F.Cu")
		(net "M_D_DQS_DP<4>")
	)
	(segment
		(start 277.64232 -119.084598)
		(end 277.849584 -119.084598)
		(width 0.1651)
		(layer "F.Cu")
		(net "M_D_DQS_DP<4>")
	)
	(segment
		(start 280.617422 -121.429526)
		(end 280.47061 -121.576338)
		(width 0.1651)
		(layer "F.Cu")
		(net "M_D_DQS_DP<4>")
	)
	(segment
		(start 277.849584 -119.084598)
		(end 278.050498 -118.883684)
		(width 0.1651)
		(layer "F.Cu")
		(net "M_D_DQS_DP<4>")
	)
	(segment
		(start 278.565102 -118.883684)
		(end 279.078182 -119.396764)
		(width 0.1651)
		(layer "F.Cu")
		(net "M_D_DQS_DP<4>")
	)
	(segment
		(start 275.876004 -102.920292)
		(end 275.876004 -103.24338)
		(width 0.0889)
		(layer "F.Cu")
		(net "M_D_DQS_DP<4>")
	)
	(segment
		(start 275.051774 -106.471974)
		(end 275.153374 -106.573574)
		(width 0.0889)
		(layer "F.Cu")
		(net "M_D_DQS_DP<4>")
	)
	(segment
		(start 278.050498 -118.883684)
		(end 278.565102 -118.883684)
		(width 0.1651)
		(layer "F.Cu")
		(net "M_D_DQS_DP<4>")
	)
	(segment
		(start 284.338014 -130.940556)
		(end 284.33776 -130.940556)
		(width 0.1651)
		(layer "F.Cu")
		(net "M_D_DQS_DP<4>")
	)
	(segment
		(start 275.153374 -106.573574)
		(end 275.153374 -112.517174)
		(width 0.1016)
		(layer "F.Cu")
		(net "M_D_DQS_DP<4>")
	)
	(segment
		(start 277.612602 -115.763548)
		(end 277.612602 -118.368572)
		(width 0.1651)
		(layer "F.Cu")
		(net "M_D_DQS_DP<4>")
	)
	(segment
		(start 280.47061 -121.576338)
		(end 280.47061 -121.833386)
		(width 0.1651)
		(layer "F.Cu")
		(net "M_D_DQS_DP<4>")
	)
	(segment
		(start 278.89073 -120.141238)
		(end 278.89073 -120.393206)
		(width 0.1651)
		(layer "F.Cu")
		(net "M_D_DQS_DP<4>")
	)
	(segment
		(start 275.486114 -101.967538)
		(end 275.81606 -102.729538)
		(width 0.0889)
		(layer "F.Cu")
		(net "M_D_DQS_DP<4>")
	)
	(segment
		(start 275.718524 -104.86517)
		(end 275.051774 -105.53192)
		(width 0.0889)
		(layer "F.Cu")
		(net "M_D_DQS_DP<4>")
	)
	(segment
		(start 279.078182 -119.396764)
		(end 279.078182 -119.953786)
		(width 0.1651)
		(layer "F.Cu")
		(net "M_D_DQS_DP<4>")
	)
	(segment
		(start 284.799786 -137.67054)
		(end 284.800294 -137.67054)
		(width 0.1651)
		(layer "F.Cu")
		(net "M_D_DQS_DP<4>")
	)
	(segment
		(start 284.837632 -135.255)
		(end 284.837632 -136.6266)
		(width 0.1651)
		(layer "F.Cu")
		(net "M_D_DQS_DP<4>")
	)
	(segment
		(start 279.491948 -120.704102)
		(end 279.7175 -120.47855)
		(width 0.1651)
		(layer "F.Cu")
		(net "M_D_DQS_DP<4>")
	)
	(segment
		(start 275.5519 -113.3221)
		(end 275.516594 -113.357406)
		(width 0.1016)
		(layer "F.Cu")
		(net "M_D_DQS_DP<4>")
	)
	(segment
		(start 278.89073 -120.393206)
		(end 279.201626 -120.704102)
		(width 0.1651)
		(layer "F.Cu")
		(net "M_D_DQS_DP<4>")
	)
	(segment
		(start 285.11754 -130.16103)
		(end 284.338014 -130.940556)
		(width 0.1651)
		(layer "F.Cu")
		(net "M_D_DQS_DP<4>")
	)
	(segment
		(start 275.516594 -113.66754)
		(end 277.612602 -115.763548)
		(width 0.1651)
		(layer "F.Cu")
		(net "M_D_DQS_DP<4>")
	)
	(segment
		(start 280.47061 -121.833386)
		(end 285.11754 -126.480316)
		(width 0.1651)
		(layer "F.Cu")
		(net "M_D_DQS_DP<4>")
	)
	(segment
		(start 275.81606 -102.729538)
		(end 275.83257 -102.757986)
		(width 0.0889)
		(layer "F.Cu")
		(net "M_D_DQS_DP<4>")
	)
	(segment
		(start 280.617422 -120.935242)
		(end 280.617422 -121.429526)
		(width 0.1651)
		(layer "F.Cu")
		(net "M_D_DQS_DP<4>")
	)
	(segment
		(start 275.876004 -103.24338)
		(end 275.718524 -103.40086)
		(width 0.0889)
		(layer "F.Cu")
		(net "M_D_DQS_DP<4>")
	)
	(segment
		(start 280.16073 -120.47855)
		(end 280.617422 -120.935242)
		(width 0.1651)
		(layer "F.Cu")
		(net "M_D_DQS_DP<4>")
	)
	(segment
		(start 285.11754 -126.480316)
		(end 285.11754 -130.16103)
		(width 0.1651)
		(layer "F.Cu")
		(net "M_D_DQS_DP<4>")
	)
	(segment
		(start 277.398988 -118.841266)
		(end 277.64232 -119.084598)
		(width 0.1651)
		(layer "F.Cu")
		(net "M_D_DQS_DP<4>")
	)
	(segment
		(start 275.153374 -112.517174)
		(end 275.5519 -112.9157)
		(width 0.1016)
		(layer "F.Cu")
		(net "M_D_DQS_DP<4>")
	)
	(segment
		(start 284.799786 -136.664446)
		(end 284.799786 -137.67054)
		(width 0.1651)
		(layer "F.Cu")
		(net "M_D_DQS_DP<4>")
	)
	(via
		(at 284.33776 -135.01116)
		(size 0.508)
		(drill 0.254)
		(layers "F.Cu" "B.Cu")
		(net "M_D_DQS_DP<4>")
	)
	(via
		(at 284.33776 -130.940556)
		(size 0.508)
		(drill 0.254)
		(layers "F.Cu" "B.Cu")
		(net "M_D_DQS_DP<4>")
	)
	(arc
		(start 275.83257 -102.757986)
		(mid 275.864993 -102.836277)
		(end 275.876004 -102.920292)
		(width 0.0889)
		(layer "F.Cu")
		(net "M_D_DQS_DP<4>")
	)
	(segment
		(start 284.837632 -130.683)
		(end 284.837632 -129.4638)
		(width 0.1651)
		(layer "B.Cu")
		(net "M_D_DQS_DP<4>")
	)
	(segment
		(start 284.799786 -128.276096)
		(end 284.800294 -128.276096)
		(width 0.1651)
		(layer "B.Cu")
		(net "M_D_DQS_DP<4>")
	)
	(segment
		(start 284.580076 -130.940556)
		(end 284.837632 -130.683)
		(width 0.1651)
		(layer "B.Cu")
		(net "M_D_DQS_DP<4>")
	)
	(segment
		(start 284.799786 -129.425954)
		(end 284.799786 -128.276096)
		(width 0.1651)
		(layer "B.Cu")
		(net "M_D_DQS_DP<4>")
	)
	(segment
		(start 284.33776 -130.940556)
		(end 284.580076 -130.940556)
		(width 0.1651)
		(layer "B.Cu")
		(net "M_D_DQS_DP<4>")
	)
	(segment
		(start 284.837632 -129.4638)
		(end 284.799786 -129.425954)
		(width 0.1651)
		(layer "B.Cu")
		(net "M_D_DQS_DP<4>")
	)
	(segment
		(start 284.133798 -132.0546)
		(end 284.518862 -132.0546)
		(width 0.14224)
		(layer "In2.Cu")
		(net "M_D_DQS_DP<4>")
	)
	(segment
		(start 284.338014 -135.01116)
		(end 284.798262 -134.550912)
		(width 0.14224)
		(layer "In2.Cu")
		(net "M_D_DQS_DP<4>")
	)
	(segment
		(start 284.078172 -132.6642)
		(end 283.963364 -132.549392)
		(width 0.14224)
		(layer "In2.Cu")
		(net "M_D_DQS_DP<4>")
	)
	(segment
		(start 284.338014 -130.940556)
		(end 284.33776 -130.940556)
		(width 0.14224)
		(layer "In2.Cu")
		(net "M_D_DQS_DP<4>")
	)
	(segment
		(start 283.963364 -133.435852)
		(end 284.100524 -133.298692)
		(width 0.14224)
		(layer "In2.Cu")
		(net "M_D_DQS_DP<4>")
	)
	(segment
		(start 284.341062 -132.842)
		(end 284.163262 -132.6642)
		(width 0.14224)
		(layer "In2.Cu")
		(net "M_D_DQS_DP<4>")
	)
	(segment
		(start 284.544262 -133.858)
		(end 284.159198 -133.858)
		(width 0.14224)
		(layer "In2.Cu")
		(net "M_D_DQS_DP<4>")
	)
	(segment
		(start 284.160722 -133.298692)
		(end 284.341062 -133.118352)
		(width 0.14224)
		(layer "In2.Cu")
		(net "M_D_DQS_DP<4>")
	)
	(segment
		(start 283.963364 -133.662166)
		(end 283.963364 -133.435852)
		(width 0.14224)
		(layer "In2.Cu")
		(net "M_D_DQS_DP<4>")
	)
	(segment
		(start 284.33776 -135.01116)
		(end 284.338014 -135.01116)
		(width 0.14224)
		(layer "In2.Cu")
		(net "M_D_DQS_DP<4>")
	)
	(segment
		(start 284.772862 -131.8006)
		(end 284.772862 -131.375404)
		(width 0.14224)
		(layer "In2.Cu")
		(net "M_D_DQS_DP<4>")
	)
	(segment
		(start 284.518862 -132.0546)
		(end 284.772862 -131.8006)
		(width 0.14224)
		(layer "In2.Cu")
		(net "M_D_DQS_DP<4>")
	)
	(segment
		(start 284.100524 -133.298692)
		(end 284.160722 -133.298692)
		(width 0.14224)
		(layer "In2.Cu")
		(net "M_D_DQS_DP<4>")
	)
	(segment
		(start 284.798262 -134.550912)
		(end 284.798262 -134.112)
		(width 0.14224)
		(layer "In2.Cu")
		(net "M_D_DQS_DP<4>")
	)
	(segment
		(start 283.963364 -132.225034)
		(end 284.133798 -132.0546)
		(width 0.14224)
		(layer "In2.Cu")
		(net "M_D_DQS_DP<4>")
	)
	(segment
		(start 284.341062 -133.118352)
		(end 284.341062 -132.842)
		(width 0.14224)
		(layer "In2.Cu")
		(net "M_D_DQS_DP<4>")
	)
	(segment
		(start 283.963364 -132.549392)
		(end 283.963364 -132.225034)
		(width 0.14224)
		(layer "In2.Cu")
		(net "M_D_DQS_DP<4>")
	)
	(segment
		(start 284.159198 -133.858)
		(end 283.963364 -133.662166)
		(width 0.14224)
		(layer "In2.Cu")
		(net "M_D_DQS_DP<4>")
	)
	(segment
		(start 284.798262 -134.112)
		(end 284.544262 -133.858)
		(width 0.14224)
		(layer "In2.Cu")
		(net "M_D_DQS_DP<4>")
	)
	(segment
		(start 284.163262 -132.6642)
		(end 284.078172 -132.6642)
		(width 0.14224)
		(layer "In2.Cu")
		(net "M_D_DQS_DP<4>")
	)
	(segment
		(start 284.772862 -131.375404)
		(end 284.338014 -130.940556)
		(width 0.14224)
		(layer "In2.Cu")
		(net "M_D_DQS_DP<4>")
	)
	(segment
		(start 229.343966 -135.01116)
		(end 229.087934 -135.01116)
		(width 0.1651)
		(layer "F.Cu")
		(net "M_D_DQS_DP<3>")
	)
	(segment
		(start 242.193318 -96.700086)
		(end 241.621818 -96.700086)
		(width 0.1651)
		(layer "F.Cu")
		(net "M_D_DQS_DP<3>")
	)
	(segment
		(start 229.587806 -136.6266)
		(end 229.587806 -135.255)
		(width 0.1651)
		(layer "F.Cu")
		(net "M_D_DQS_DP<3>")
	)
	(segment
		(start 229.587806 -135.255)
		(end 229.343966 -135.01116)
		(width 0.1651)
		(layer "F.Cu")
		(net "M_D_DQS_DP<3>")
	)
	(segment
		(start 229.550468 -137.67054)
		(end 229.54996 -137.67054)
		(width 0.1651)
		(layer "F.Cu")
		(net "M_D_DQS_DP<3>")
	)
	(segment
		(start 229.54996 -137.67054)
		(end 229.54996 -136.664446)
		(width 0.1651)
		(layer "F.Cu")
		(net "M_D_DQS_DP<3>")
	)
	(segment
		(start 229.54996 -136.664446)
		(end 229.587806 -136.6266)
		(width 0.1651)
		(layer "F.Cu")
		(net "M_D_DQS_DP<3>")
	)
	(via
		(at 241.621818 -96.700086)
		(size 0.508)
		(drill 0.254)
		(layers "F.Cu" "B.Cu")
		(net "M_D_DQS_DP<3>")
	)
	(via
		(at 229.087934 -130.940556)
		(size 0.508)
		(drill 0.254)
		(layers "F.Cu" "B.Cu")
		(net "M_D_DQS_DP<3>")
	)
	(via
		(at 229.087934 -135.01116)
		(size 0.508)
		(drill 0.254)
		(layers "F.Cu" "B.Cu")
		(net "M_D_DQS_DP<3>")
	)
	(segment
		(start 229.54996 -129.425954)
		(end 229.587806 -129.4638)
		(width 0.1651)
		(layer "B.Cu")
		(net "M_D_DQS_DP<3>")
	)
	(segment
		(start 229.587806 -129.4638)
		(end 229.587806 -130.683)
		(width 0.1651)
		(layer "B.Cu")
		(net "M_D_DQS_DP<3>")
	)
	(segment
		(start 229.550468 -128.276096)
		(end 229.54996 -128.276096)
		(width 0.1651)
		(layer "B.Cu")
		(net "M_D_DQS_DP<3>")
	)
	(segment
		(start 229.33025 -130.940556)
		(end 229.087934 -130.940556)
		(width 0.1651)
		(layer "B.Cu")
		(net "M_D_DQS_DP<3>")
	)
	(segment
		(start 229.54996 -128.276096)
		(end 229.54996 -129.425954)
		(width 0.1651)
		(layer "B.Cu")
		(net "M_D_DQS_DP<3>")
	)
	(segment
		(start 229.587806 -130.683)
		(end 229.33025 -130.940556)
		(width 0.1651)
		(layer "B.Cu")
		(net "M_D_DQS_DP<3>")
	)
	(segment
		(start 229.946454 -130.082036)
		(end 229.087934 -130.940556)
		(width 0.14224)
		(layer "In2.Cu")
		(net "M_D_DQS_DP<3>")
	)
	(segment
		(start 236.123988 -101.453188)
		(end 235.844588 -101.937566)
		(width 0.0889)
		(layer "In2.Cu")
		(net "M_D_DQS_DP<3>")
	)
	(segment
		(start 229.090982 -133.118352)
		(end 228.910642 -133.298692)
		(width 0.14224)
		(layer "In2.Cu")
		(net "M_D_DQS_DP<3>")
	)
	(segment
		(start 229.294182 -133.858)
		(end 229.548182 -134.112)
		(width 0.14224)
		(layer "In2.Cu")
		(net "M_D_DQS_DP<3>")
	)
	(segment
		(start 228.883718 -132.0546)
		(end 228.713284 -132.225034)
		(width 0.14224)
		(layer "In2.Cu")
		(net "M_D_DQS_DP<3>")
	)
	(segment
		(start 231.98074 -105.86974)
		(end 231.98074 -109.336586)
		(width 0.14224)
		(layer "In2.Cu")
		(net "M_D_DQS_DP<3>")
	)
	(segment
		(start 228.850444 -133.298692)
		(end 228.713284 -133.435852)
		(width 0.14224)
		(layer "In2.Cu")
		(net "M_D_DQS_DP<3>")
	)
	(segment
		(start 230.42372 -118.46179)
		(end 229.946454 -118.939056)
		(width 0.14224)
		(layer "In2.Cu")
		(net "M_D_DQS_DP<3>")
	)
	(segment
		(start 229.522782 -131.375404)
		(end 229.522782 -131.8006)
		(width 0.14224)
		(layer "In2.Cu")
		(net "M_D_DQS_DP<3>")
	)
	(segment
		(start 229.548182 -134.550912)
		(end 229.087934 -135.01116)
		(width 0.14224)
		(layer "In2.Cu")
		(net "M_D_DQS_DP<3>")
	)
	(segment
		(start 230.39832 -114.836702)
		(end 230.39832 -115.491768)
		(width 0.14224)
		(layer "In2.Cu")
		(net "M_D_DQS_DP<3>")
	)
	(segment
		(start 229.522782 -131.8006)
		(end 229.268782 -132.0546)
		(width 0.14224)
		(layer "In2.Cu")
		(net "M_D_DQS_DP<3>")
	)
	(segment
		(start 229.385368 -116.475764)
		(end 229.653338 -116.743734)
		(width 0.14224)
		(layer "In2.Cu")
		(net "M_D_DQS_DP<3>")
	)
	(segment
		(start 236.492288 -101.253036)
		(end 236.45622 -101.253036)
		(width 0.0889)
		(layer "In2.Cu")
		(net "M_D_DQS_DP<3>")
	)
	(segment
		(start 235.844588 -101.937566)
		(end 234.724194 -103.062786)
		(width 0.0889)
		(layer "In2.Cu")
		(net "M_D_DQS_DP<3>")
	)
	(segment
		(start 229.946454 -118.939056)
		(end 229.946454 -130.082036)
		(width 0.14224)
		(layer "In2.Cu")
		(net "M_D_DQS_DP<3>")
	)
	(segment
		(start 230.39832 -115.491768)
		(end 230.020114 -115.869974)
		(width 0.14224)
		(layer "In2.Cu")
		(net "M_D_DQS_DP<3>")
	)
	(segment
		(start 232.92181 -104.873044)
		(end 232.922064 -104.928416)
		(width 0.0889)
		(layer "In2.Cu")
		(net "M_D_DQS_DP<3>")
	)
	(segment
		(start 229.685088 -113.9444)
		(end 229.685088 -114.12347)
		(width 0.14224)
		(layer "In2.Cu")
		(net "M_D_DQS_DP<3>")
	)
	(segment
		(start 230.42372 -117.102636)
		(end 230.42372 -118.46179)
		(width 0.14224)
		(layer "In2.Cu")
		(net "M_D_DQS_DP<3>")
	)
	(segment
		(start 228.913182 -132.6642)
		(end 229.090982 -132.842)
		(width 0.14224)
		(layer "In2.Cu")
		(net "M_D_DQS_DP<3>")
	)
	(segment
		(start 229.829868 -111.487458)
		(end 229.829868 -112.118394)
		(width 0.14224)
		(layer "In2.Cu")
		(net "M_D_DQS_DP<3>")
	)
	(segment
		(start 229.685088 -114.12347)
		(end 230.39832 -114.836702)
		(width 0.14224)
		(layer "In2.Cu")
		(net "M_D_DQS_DP<3>")
	)
	(segment
		(start 228.910642 -133.298692)
		(end 228.850444 -133.298692)
		(width 0.14224)
		(layer "In2.Cu")
		(net "M_D_DQS_DP<3>")
	)
	(segment
		(start 230.020114 -115.869974)
		(end 229.55885 -115.869974)
		(width 0.14224)
		(layer "In2.Cu")
		(net "M_D_DQS_DP<3>")
	)
	(segment
		(start 228.909118 -133.858)
		(end 229.294182 -133.858)
		(width 0.14224)
		(layer "In2.Cu")
		(net "M_D_DQS_DP<3>")
	)
	(segment
		(start 228.713284 -132.549392)
		(end 228.828092 -132.6642)
		(width 0.14224)
		(layer "In2.Cu")
		(net "M_D_DQS_DP<3>")
	)
	(segment
		(start 229.548182 -134.112)
		(end 229.548182 -134.550912)
		(width 0.14224)
		(layer "In2.Cu")
		(net "M_D_DQS_DP<3>")
	)
	(segment
		(start 240.781078 -98.77679)
		(end 240.748312 -98.77679)
		(width 0.0889)
		(layer "In2.Cu")
		(net "M_D_DQS_DP<3>")
	)
	(segment
		(start 229.268782 -132.0546)
		(end 228.883718 -132.0546)
		(width 0.14224)
		(layer "In2.Cu")
		(net "M_D_DQS_DP<3>")
	)
	(segment
		(start 230.42372 -113.205768)
		(end 229.685088 -113.9444)
		(width 0.14224)
		(layer "In2.Cu")
		(net "M_D_DQS_DP<3>")
	)
	(segment
		(start 229.087934 -130.940556)
		(end 229.522782 -131.375404)
		(width 0.14224)
		(layer "In2.Cu")
		(net "M_D_DQS_DP<3>")
	)
	(segment
		(start 239.067848 -99.76739)
		(end 239.028224 -99.76739)
		(width 0.0889)
		(layer "In2.Cu")
		(net "M_D_DQS_DP<3>")
	)
	(segment
		(start 230.064818 -116.743734)
		(end 230.42372 -117.102636)
		(width 0.14224)
		(layer "In2.Cu")
		(net "M_D_DQS_DP<3>")
	)
	(segment
		(start 238.205518 -100.26269)
		(end 238.169704 -100.26269)
		(width 0.0889)
		(layer "In2.Cu")
		(net "M_D_DQS_DP<3>")
	)
	(segment
		(start 228.828092 -132.6642)
		(end 228.913182 -132.6642)
		(width 0.14224)
		(layer "In2.Cu")
		(net "M_D_DQS_DP<3>")
	)
	(segment
		(start 229.55885 -115.869974)
		(end 229.385368 -116.043456)
		(width 0.14224)
		(layer "In2.Cu")
		(net "M_D_DQS_DP<3>")
	)
	(segment
		(start 237.342172 -100.75799)
		(end 237.314232 -100.75799)
		(width 0.0889)
		(layer "In2.Cu")
		(net "M_D_DQS_DP<3>")
	)
	(segment
		(start 229.829868 -112.118394)
		(end 230.42372 -112.712246)
		(width 0.14224)
		(layer "In2.Cu")
		(net "M_D_DQS_DP<3>")
	)
	(segment
		(start 229.385368 -116.043456)
		(end 229.385368 -116.475764)
		(width 0.14224)
		(layer "In2.Cu")
		(net "M_D_DQS_DP<3>")
	)
	(segment
		(start 230.42372 -112.712246)
		(end 230.42372 -113.205768)
		(width 0.14224)
		(layer "In2.Cu")
		(net "M_D_DQS_DP<3>")
	)
	(segment
		(start 231.98074 -109.336586)
		(end 229.829868 -111.487458)
		(width 0.14224)
		(layer "In2.Cu")
		(net "M_D_DQS_DP<3>")
	)
	(segment
		(start 229.090982 -132.842)
		(end 229.090982 -133.118352)
		(width 0.14224)
		(layer "In2.Cu")
		(net "M_D_DQS_DP<3>")
	)
	(segment
		(start 228.713284 -133.435852)
		(end 228.713284 -133.662166)
		(width 0.14224)
		(layer "In2.Cu")
		(net "M_D_DQS_DP<3>")
	)
	(segment
		(start 228.713284 -132.225034)
		(end 228.713284 -132.549392)
		(width 0.14224)
		(layer "In2.Cu")
		(net "M_D_DQS_DP<3>")
	)
	(segment
		(start 232.922064 -104.928416)
		(end 232.90657 -104.94391)
		(width 0.0889)
		(layer "In2.Cu")
		(net "M_D_DQS_DP<3>")
	)
	(segment
		(start 232.90657 -104.94391)
		(end 231.98074 -105.86974)
		(width 0.14224)
		(layer "In2.Cu")
		(net "M_D_DQS_DP<3>")
	)
	(segment
		(start 239.917732 -99.27209)
		(end 239.893602 -99.27209)
		(width 0.0889)
		(layer "In2.Cu")
		(net "M_D_DQS_DP<3>")
	)
	(segment
		(start 241.621818 -96.700086)
		(end 241.621818 -97.03816)
		(width 0.0889)
		(layer "In2.Cu")
		(net "M_D_DQS_DP<3>")
	)
	(segment
		(start 228.713284 -133.662166)
		(end 228.909118 -133.858)
		(width 0.14224)
		(layer "In2.Cu")
		(net "M_D_DQS_DP<3>")
	)
	(segment
		(start 234.724194 -103.062786)
		(end 232.92181 -104.873044)
		(width 0.0889)
		(layer "In2.Cu")
		(net "M_D_DQS_DP<3>")
	)
	(segment
		(start 229.653338 -116.743734)
		(end 230.064818 -116.743734)
		(width 0.14224)
		(layer "In2.Cu")
		(net "M_D_DQS_DP<3>")
	)
	(arc
		(start 237.841028 -100.462588)
		(mid 237.630315 -100.675667)
		(end 237.342172 -100.75799)
		(width 0.0889)
		(layer "In2.Cu")
		(net "M_D_DQS_DP<3>")
	)
	(arc
		(start 241.378232 -98.363532)
		(mid 241.320839 -98.41736)
		(end 241.275108 -98.481388)
		(width 0.0889)
		(layer "In2.Cu")
		(net "M_D_DQS_DP<3>")
	)
	(arc
		(start 240.748312 -98.77679)
		(mid 240.55667 -98.833956)
		(end 240.416588 -98.976688)
		(width 0.0889)
		(layer "In2.Cu")
		(net "M_D_DQS_DP<3>")
	)
	(arc
		(start 239.028224 -99.76739)
		(mid 238.838295 -99.82526)
		(end 238.699548 -99.967288)
		(width 0.0889)
		(layer "In2.Cu")
		(net "M_D_DQS_DP<3>")
	)
	(arc
		(start 239.893602 -99.27209)
		(mid 239.699752 -99.32844)
		(end 239.558068 -99.472242)
		(width 0.0889)
		(layer "In2.Cu")
		(net "M_D_DQS_DP<3>")
	)
	(arc
		(start 239.558068 -99.472242)
		(mid 239.351064 -99.683106)
		(end 239.067848 -99.76739)
		(width 0.0889)
		(layer "In2.Cu")
		(net "M_D_DQS_DP<3>")
	)
	(arc
		(start 238.699548 -99.967288)
		(mid 238.49094 -100.17922)
		(end 238.205518 -100.26269)
		(width 0.0889)
		(layer "In2.Cu")
		(net "M_D_DQS_DP<3>")
	)
	(arc
		(start 241.813334 -97.33915)
		(mid 242.022206 -97.703236)
		(end 241.790982 -98.053652)
		(width 0.0889)
		(layer "In2.Cu")
		(net "M_D_DQS_DP<3>")
	)
	(arc
		(start 240.416588 -98.976688)
		(mid 240.205875 -99.189767)
		(end 239.917732 -99.27209)
		(width 0.0889)
		(layer "In2.Cu")
		(net "M_D_DQS_DP<3>")
	)
	(arc
		(start 238.169704 -100.26269)
		(mid 237.979775 -100.32056)
		(end 237.841028 -100.462588)
		(width 0.0889)
		(layer "In2.Cu")
		(net "M_D_DQS_DP<3>")
	)
	(arc
		(start 241.61115 -98.20021)
		(mid 241.547132 -98.265551)
		(end 241.468148 -98.311716)
		(width 0.0889)
		(layer "In2.Cu")
		(net "M_D_DQS_DP<3>")
	)
	(arc
		(start 236.982508 -100.957888)
		(mid 236.775504 -101.168752)
		(end 236.492288 -101.253036)
		(width 0.0889)
		(layer "In2.Cu")
		(net "M_D_DQS_DP<3>")
	)
	(arc
		(start 237.314232 -100.75799)
		(mid 237.12259 -100.815156)
		(end 236.982508 -100.957888)
		(width 0.0889)
		(layer "In2.Cu")
		(net "M_D_DQS_DP<3>")
	)
	(arc
		(start 236.45622 -101.253036)
		(mid 236.264203 -101.310144)
		(end 236.123988 -101.453188)
		(width 0.0889)
		(layer "In2.Cu")
		(net "M_D_DQS_DP<3>")
	)
	(arc
		(start 241.621818 -97.03816)
		(mid 241.678662 -97.213426)
		(end 241.813334 -97.33915)
		(width 0.0889)
		(layer "In2.Cu")
		(net "M_D_DQS_DP<3>")
	)
	(arc
		(start 241.790982 -98.053652)
		(mid 241.692018 -98.11583)
		(end 241.61115 -98.20021)
		(width 0.0889)
		(layer "In2.Cu")
		(net "M_D_DQS_DP<3>")
	)
	(arc
		(start 241.275108 -98.481388)
		(mid 241.0665 -98.69332)
		(end 240.781078 -98.77679)
		(width 0.0889)
		(layer "In2.Cu")
		(net "M_D_DQS_DP<3>")
	)
	(arc
		(start 241.468148 -98.311716)
		(mid 241.421499 -98.334691)
		(end 241.378232 -98.363532)
		(width 0.0889)
		(layer "In2.Cu")
		(net "M_D_DQS_DP<3>")
	)
	(segment
		(start 237.042198 -94.718886)
		(end 236.470698 -94.718886)
		(width 0.1651)
		(layer "F.Cu")
		(net "M_D_DQS_DP<2>")
	)
	(segment
		(start 220.237812 -135.255)
		(end 219.993972 -135.01116)
		(width 0.1651)
		(layer "F.Cu")
		(net "M_D_DQS_DP<2>")
	)
	(segment
		(start 220.237812 -136.6266)
		(end 220.237812 -135.255)
		(width 0.1651)
		(layer "F.Cu")
		(net "M_D_DQS_DP<2>")
	)
	(segment
		(start 220.200474 -137.67054)
		(end 220.199966 -137.67054)
		(width 0.1651)
		(layer "F.Cu")
		(net "M_D_DQS_DP<2>")
	)
	(segment
		(start 220.199966 -136.664446)
		(end 220.237812 -136.6266)
		(width 0.1651)
		(layer "F.Cu")
		(net "M_D_DQS_DP<2>")
	)
	(segment
		(start 220.199966 -137.67054)
		(end 220.199966 -136.664446)
		(width 0.1651)
		(layer "F.Cu")
		(net "M_D_DQS_DP<2>")
	)
	(segment
		(start 219.993972 -135.01116)
		(end 219.73794 -135.01116)
		(width 0.1651)
		(layer "F.Cu")
		(net "M_D_DQS_DP<2>")
	)
	(via
		(at 236.470698 -94.718886)
		(size 0.508)
		(drill 0.254)
		(layers "F.Cu" "B.Cu")
		(net "M_D_DQS_DP<2>")
	)
	(via
		(at 219.73794 -130.940556)
		(size 0.508)
		(drill 0.254)
		(layers "F.Cu" "B.Cu")
		(net "M_D_DQS_DP<2>")
	)
	(via
		(at 219.73794 -135.01116)
		(size 0.508)
		(drill 0.254)
		(layers "F.Cu" "B.Cu")
		(net "M_D_DQS_DP<2>")
	)
	(segment
		(start 220.237812 -130.683)
		(end 220.237812 -129.4638)
		(width 0.1651)
		(layer "B.Cu")
		(net "M_D_DQS_DP<2>")
	)
	(segment
		(start 219.980256 -130.940556)
		(end 220.237812 -130.683)
		(width 0.1651)
		(layer "B.Cu")
		(net "M_D_DQS_DP<2>")
	)
	(segment
		(start 220.199966 -129.425954)
		(end 220.199966 -128.276096)
		(width 0.1651)
		(layer "B.Cu")
		(net "M_D_DQS_DP<2>")
	)
	(segment
		(start 220.237812 -129.4638)
		(end 220.199966 -129.425954)
		(width 0.1651)
		(layer "B.Cu")
		(net "M_D_DQS_DP<2>")
	)
	(segment
		(start 220.199966 -128.276096)
		(end 220.200474 -128.276096)
		(width 0.1651)
		(layer "B.Cu")
		(net "M_D_DQS_DP<2>")
	)
	(segment
		(start 219.73794 -130.940556)
		(end 219.980256 -130.940556)
		(width 0.1651)
		(layer "B.Cu")
		(net "M_D_DQS_DP<2>")
	)
	(segment
		(start 220.41612 -108.356908)
		(end 220.41612 -109.939836)
		(width 0.14224)
		(layer "In2.Cu")
		(net "M_D_DQS_DP<2>")
	)
	(segment
		(start 236.470698 -94.718886)
		(end 235.767626 -94.624144)
		(width 0.0889)
		(layer "In2.Cu")
		(net "M_D_DQS_DP<2>")
	)
	(segment
		(start 220.41612 -112.18926)
		(end 220.03766 -112.56772)
		(width 0.14224)
		(layer "In2.Cu")
		(net "M_D_DQS_DP<2>")
	)
	(segment
		(start 220.41612 -109.939836)
		(end 220.037152 -110.318804)
		(width 0.14224)
		(layer "In2.Cu")
		(net "M_D_DQS_DP<2>")
	)
	(segment
		(start 220.41612 -111.571532)
		(end 220.41612 -112.18926)
		(width 0.14224)
		(layer "In2.Cu")
		(net "M_D_DQS_DP<2>")
	)
	(segment
		(start 234.774232 -94.31909)
		(end 233.965242 -94.31909)
		(width 0.0889)
		(layer "In2.Cu")
		(net "M_D_DQS_DP<2>")
	)
	(segment
		(start 220.52026 -128.808226)
		(end 220.52026 -130.158236)
		(width 0.14224)
		(layer "In2.Cu")
		(net "M_D_DQS_DP<2>")
	)
	(segment
		(start 219.740988 -133.118352)
		(end 219.560648 -133.298692)
		(width 0.14224)
		(layer "In2.Cu")
		(net "M_D_DQS_DP<2>")
	)
	(segment
		(start 220.037152 -110.318804)
		(end 218.398598 -110.318804)
		(width 0.14224)
		(layer "In2.Cu")
		(net "M_D_DQS_DP<2>")
	)
	(segment
		(start 219.918788 -132.0546)
		(end 219.533724 -132.0546)
		(width 0.14224)
		(layer "In2.Cu")
		(net "M_D_DQS_DP<2>")
	)
	(segment
		(start 218.13012 -112.830864)
		(end 218.13012 -113.41608)
		(width 0.14224)
		(layer "In2.Cu")
		(net "M_D_DQS_DP<2>")
	)
	(segment
		(start 235.507276 -94.624144)
		(end 235.014008 -94.414848)
		(width 0.0889)
		(layer "In2.Cu")
		(net "M_D_DQS_DP<2>")
	)
	(segment
		(start 219.533724 -132.0546)
		(end 219.36329 -132.225034)
		(width 0.14224)
		(layer "In2.Cu")
		(net "M_D_DQS_DP<2>")
	)
	(segment
		(start 229.673404 -96.651064)
		(end 229.657656 -96.666812)
		(width 0.0889)
		(layer "In2.Cu")
		(net "M_D_DQS_DP<2>")
	)
	(segment
		(start 219.944188 -133.858)
		(end 220.198188 -134.112)
		(width 0.14224)
		(layer "In2.Cu")
		(net "M_D_DQS_DP<2>")
	)
	(segment
		(start 219.50045 -133.298692)
		(end 219.36329 -133.435852)
		(width 0.14224)
		(layer "In2.Cu")
		(net "M_D_DQS_DP<2>")
	)
	(segment
		(start 220.03766 -112.56772)
		(end 218.393264 -112.56772)
		(width 0.14224)
		(layer "In2.Cu")
		(net "M_D_DQS_DP<2>")
	)
	(segment
		(start 218.177872 -110.53953)
		(end 218.177872 -110.971838)
		(width 0.14224)
		(layer "In2.Cu")
		(net "M_D_DQS_DP<2>")
	)
	(segment
		(start 220.198188 -134.112)
		(end 220.198188 -134.550912)
		(width 0.14224)
		(layer "In2.Cu")
		(net "M_D_DQS_DP<2>")
	)
	(segment
		(start 218.393264 -112.56772)
		(end 218.13012 -112.830864)
		(width 0.14224)
		(layer "In2.Cu")
		(net "M_D_DQS_DP<2>")
	)
	(segment
		(start 218.177872 -110.971838)
		(end 218.398598 -111.192564)
		(width 0.14224)
		(layer "In2.Cu")
		(net "M_D_DQS_DP<2>")
	)
	(segment
		(start 229.998524 -96.270064)
		(end 229.673404 -96.595184)
		(width 0.0889)
		(layer "In2.Cu")
		(net "M_D_DQS_DP<2>")
	)
	(segment
		(start 218.81592 -114.10188)
		(end 218.81592 -127.103886)
		(width 0.14224)
		(layer "In2.Cu")
		(net "M_D_DQS_DP<2>")
	)
	(segment
		(start 229.657656 -96.666812)
		(end 223.47936 -102.845616)
		(width 0.14224)
		(layer "In2.Cu")
		(net "M_D_DQS_DP<2>")
	)
	(segment
		(start 219.36329 -132.549392)
		(end 219.478098 -132.6642)
		(width 0.14224)
		(layer "In2.Cu")
		(net "M_D_DQS_DP<2>")
	)
	(segment
		(start 219.36329 -132.225034)
		(end 219.36329 -132.549392)
		(width 0.14224)
		(layer "In2.Cu")
		(net "M_D_DQS_DP<2>")
	)
	(segment
		(start 229.673404 -96.595184)
		(end 229.673404 -96.651064)
		(width 0.0889)
		(layer "In2.Cu")
		(net "M_D_DQS_DP<2>")
	)
	(segment
		(start 218.13012 -113.41608)
		(end 218.81592 -114.10188)
		(width 0.14224)
		(layer "In2.Cu")
		(net "M_D_DQS_DP<2>")
	)
	(segment
		(start 218.398598 -111.192564)
		(end 220.037152 -111.192564)
		(width 0.14224)
		(layer "In2.Cu")
		(net "M_D_DQS_DP<2>")
	)
	(segment
		(start 219.36329 -133.435852)
		(end 219.36329 -133.662166)
		(width 0.14224)
		(layer "In2.Cu")
		(net "M_D_DQS_DP<2>")
	)
	(segment
		(start 229.998524 -96.177608)
		(end 229.998524 -96.270064)
		(width 0.0889)
		(layer "In2.Cu")
		(net "M_D_DQS_DP<2>")
	)
	(segment
		(start 220.198188 -134.550912)
		(end 219.73794 -135.01116)
		(width 0.14224)
		(layer "In2.Cu")
		(net "M_D_DQS_DP<2>")
	)
	(segment
		(start 233.646218 -94.638114)
		(end 231.538018 -94.638114)
		(width 0.0889)
		(layer "In2.Cu")
		(net "M_D_DQS_DP<2>")
	)
	(segment
		(start 218.81592 -127.103886)
		(end 220.52026 -128.808226)
		(width 0.14224)
		(layer "In2.Cu")
		(net "M_D_DQS_DP<2>")
	)
	(segment
		(start 219.563188 -132.6642)
		(end 219.740988 -132.842)
		(width 0.14224)
		(layer "In2.Cu")
		(net "M_D_DQS_DP<2>")
	)
	(segment
		(start 219.73794 -130.940556)
		(end 220.172788 -131.375404)
		(width 0.14224)
		(layer "In2.Cu")
		(net "M_D_DQS_DP<2>")
	)
	(segment
		(start 220.037152 -111.192564)
		(end 220.41612 -111.571532)
		(width 0.14224)
		(layer "In2.Cu")
		(net "M_D_DQS_DP<2>")
	)
	(segment
		(start 219.560648 -133.298692)
		(end 219.50045 -133.298692)
		(width 0.14224)
		(layer "In2.Cu")
		(net "M_D_DQS_DP<2>")
	)
	(segment
		(start 219.559124 -133.858)
		(end 219.944188 -133.858)
		(width 0.14224)
		(layer "In2.Cu")
		(net "M_D_DQS_DP<2>")
	)
	(segment
		(start 219.740988 -132.842)
		(end 219.740988 -133.118352)
		(width 0.14224)
		(layer "In2.Cu")
		(net "M_D_DQS_DP<2>")
	)
	(segment
		(start 219.36329 -133.662166)
		(end 219.559124 -133.858)
		(width 0.14224)
		(layer "In2.Cu")
		(net "M_D_DQS_DP<2>")
	)
	(segment
		(start 231.538018 -94.638114)
		(end 229.998524 -96.177608)
		(width 0.0889)
		(layer "In2.Cu")
		(net "M_D_DQS_DP<2>")
	)
	(segment
		(start 220.172788 -131.375404)
		(end 220.172788 -131.8006)
		(width 0.14224)
		(layer "In2.Cu")
		(net "M_D_DQS_DP<2>")
	)
	(segment
		(start 218.398598 -110.318804)
		(end 218.177872 -110.53953)
		(width 0.14224)
		(layer "In2.Cu")
		(net "M_D_DQS_DP<2>")
	)
	(segment
		(start 219.478098 -132.6642)
		(end 219.563188 -132.6642)
		(width 0.14224)
		(layer "In2.Cu")
		(net "M_D_DQS_DP<2>")
	)
	(segment
		(start 223.47936 -102.845616)
		(end 223.47936 -105.293668)
		(width 0.14224)
		(layer "In2.Cu")
		(net "M_D_DQS_DP<2>")
	)
	(segment
		(start 223.47936 -105.293668)
		(end 220.41612 -108.356908)
		(width 0.14224)
		(layer "In2.Cu")
		(net "M_D_DQS_DP<2>")
	)
	(segment
		(start 220.172788 -131.8006)
		(end 219.918788 -132.0546)
		(width 0.14224)
		(layer "In2.Cu")
		(net "M_D_DQS_DP<2>")
	)
	(segment
		(start 235.767626 -94.624144)
		(end 235.507276 -94.624144)
		(width 0.0889)
		(layer "In2.Cu")
		(net "M_D_DQS_DP<2>")
	)
	(segment
		(start 220.52026 -130.158236)
		(end 219.73794 -130.940556)
		(width 0.14224)
		(layer "In2.Cu")
		(net "M_D_DQS_DP<2>")
	)
	(segment
		(start 233.965242 -94.31909)
		(end 233.646218 -94.638114)
		(width 0.0889)
		(layer "In2.Cu")
		(net "M_D_DQS_DP<2>")
	)
	(arc
		(start 234.985814 -94.39275)
		(mid 234.885281 -94.340817)
		(end 234.774232 -94.31909)
		(width 0.0889)
		(layer "In2.Cu")
		(net "M_D_DQS_DP<2>")
	)
	(arc
		(start 235.014008 -94.414848)
		(mid 235.000158 -94.403484)
		(end 234.985814 -94.39275)
		(width 0.0889)
		(layer "In2.Cu")
		(net "M_D_DQS_DP<2>")
	)
	(segment
		(start 211.117688 -122.89409)
		(end 210.93938 -123.072398)
		(width 0.1651)
		(layer "F.Cu")
		(net "M_D_DQS_DP<1>")
	)
	(segment
		(start 233.5022 -95.309436)
		(end 233.1974 -95.309436)
		(width 0.0889)
		(layer "F.Cu")
		(net "M_D_DQS_DP<1>")
	)
	(segment
		(start 210.93938 -123.602242)
		(end 211.117688 -123.78055)
		(width 0.1651)
		(layer "F.Cu")
		(net "M_D_DQS_DP<1>")
	)
	(segment
		(start 211.78012 -122.54484)
		(end 211.43087 -122.89409)
		(width 0.1651)
		(layer "F.Cu")
		(net "M_D_DQS_DP<1>")
	)
	(segment
		(start 211.78012 -127.083312)
		(end 210.922362 -127.94107)
		(width 0.1651)
		(layer "F.Cu")
		(net "M_D_DQS_DP<1>")
	)
	(segment
		(start 232.9434 -95.411036)
		(end 232.8418 -95.309436)
		(width 0.0889)
		(layer "F.Cu")
		(net "M_D_DQS_DP<1>")
	)
	(segment
		(start 210.887818 -136.6266)
		(end 210.887818 -135.255)
		(width 0.1651)
		(layer "F.Cu")
		(net "M_D_DQS_DP<1>")
	)
	(segment
		(start 211.78012 -114.978434)
		(end 211.78012 -119.75592)
		(width 0.1651)
		(layer "F.Cu")
		(net "M_D_DQS_DP<1>")
	)
	(segment
		(start 211.117688 -125.25121)
		(end 210.93938 -125.429518)
		(width 0.1651)
		(layer "F.Cu")
		(net "M_D_DQS_DP<1>")
	)
	(segment
		(start 211.117688 -123.78055)
		(end 211.43087 -123.78055)
		(width 0.1651)
		(layer "F.Cu")
		(net "M_D_DQS_DP<1>")
	)
	(segment
		(start 233.0958 -95.411036)
		(end 232.9434 -95.411036)
		(width 0.0889)
		(layer "F.Cu")
		(net "M_D_DQS_DP<1>")
	)
	(segment
		(start 210.99272 -120.98528)
		(end 211.78012 -121.77268)
		(width 0.1651)
		(layer "F.Cu")
		(net "M_D_DQS_DP<1>")
	)
	(segment
		(start 210.93938 -125.959362)
		(end 211.117688 -126.13767)
		(width 0.1651)
		(layer "F.Cu")
		(net "M_D_DQS_DP<1>")
	)
	(segment
		(start 211.43087 -123.78055)
		(end 211.78012 -124.1298)
		(width 0.1651)
		(layer "F.Cu")
		(net "M_D_DQS_DP<1>")
	)
	(segment
		(start 233.608118 -95.709486)
		(end 233.895392 -95.543878)
		(width 0.0889)
		(layer "F.Cu")
		(net "M_D_DQS_DP<1>")
	)
	(segment
		(start 210.643978 -135.01116)
		(end 210.387946 -135.01116)
		(width 0.1651)
		(layer "F.Cu")
		(net "M_D_DQS_DP<1>")
	)
	(segment
		(start 232.41 -95.359474)
		(end 231.39908 -95.359474)
		(width 0.1651)
		(layer "F.Cu")
		(net "M_D_DQS_DP<1>")
	)
	(segment
		(start 211.78012 -124.90196)
		(end 211.43087 -125.25121)
		(width 0.1651)
		(layer "F.Cu")
		(net "M_D_DQS_DP<1>")
	)
	(segment
		(start 210.85048 -137.67054)
		(end 210.849972 -137.67054)
		(width 0.1651)
		(layer "F.Cu")
		(net "M_D_DQS_DP<1>")
	)
	(segment
		(start 211.117688 -126.13767)
		(end 211.43087 -126.13767)
		(width 0.1651)
		(layer "F.Cu")
		(net "M_D_DQS_DP<1>")
	)
	(segment
		(start 210.887818 -135.255)
		(end 210.643978 -135.01116)
		(width 0.1651)
		(layer "F.Cu")
		(net "M_D_DQS_DP<1>")
	)
	(segment
		(start 233.1974 -95.309436)
		(end 233.0958 -95.411036)
		(width 0.0889)
		(layer "F.Cu")
		(net "M_D_DQS_DP<1>")
	)
	(segment
		(start 231.39908 -95.359474)
		(end 211.78012 -114.978434)
		(width 0.1651)
		(layer "F.Cu")
		(net "M_D_DQS_DP<1>")
	)
	(segment
		(start 211.43087 -126.13767)
		(end 211.78012 -126.48692)
		(width 0.1651)
		(layer "F.Cu")
		(net "M_D_DQS_DP<1>")
	)
	(segment
		(start 210.922362 -130.406394)
		(end 210.3882 -130.940556)
		(width 0.1651)
		(layer "F.Cu")
		(net "M_D_DQS_DP<1>")
	)
	(segment
		(start 232.460038 -95.309436)
		(end 232.41 -95.359474)
		(width 0.0889)
		(layer "F.Cu")
		(net "M_D_DQS_DP<1>")
	)
	(segment
		(start 210.922362 -127.94107)
		(end 210.922362 -130.406394)
		(width 0.1651)
		(layer "F.Cu")
		(net "M_D_DQS_DP<1>")
	)
	(segment
		(start 233.895392 -95.543878)
		(end 233.918506 -95.457264)
		(width 0.0889)
		(layer "F.Cu")
		(net "M_D_DQS_DP<1>")
	)
	(segment
		(start 211.43087 -125.25121)
		(end 211.117688 -125.25121)
		(width 0.1651)
		(layer "F.Cu")
		(net "M_D_DQS_DP<1>")
	)
	(segment
		(start 232.8418 -95.309436)
		(end 232.460038 -95.309436)
		(width 0.0889)
		(layer "F.Cu")
		(net "M_D_DQS_DP<1>")
	)
	(segment
		(start 233.619802 -95.30969)
		(end 233.5022 -95.309436)
		(width 0.0889)
		(layer "F.Cu")
		(net "M_D_DQS_DP<1>")
	)
	(segment
		(start 211.78012 -119.75592)
		(end 210.99272 -120.54332)
		(width 0.1651)
		(layer "F.Cu")
		(net "M_D_DQS_DP<1>")
	)
	(segment
		(start 210.99272 -120.54332)
		(end 210.99272 -120.98528)
		(width 0.1651)
		(layer "F.Cu")
		(net "M_D_DQS_DP<1>")
	)
	(segment
		(start 211.78012 -121.77268)
		(end 211.78012 -122.54484)
		(width 0.1651)
		(layer "F.Cu")
		(net "M_D_DQS_DP<1>")
	)
	(segment
		(start 210.93938 -125.429518)
		(end 210.93938 -125.959362)
		(width 0.1651)
		(layer "F.Cu")
		(net "M_D_DQS_DP<1>")
	)
	(segment
		(start 210.93938 -123.072398)
		(end 210.93938 -123.602242)
		(width 0.1651)
		(layer "F.Cu")
		(net "M_D_DQS_DP<1>")
	)
	(segment
		(start 210.849972 -137.67054)
		(end 210.849972 -136.664446)
		(width 0.1651)
		(layer "F.Cu")
		(net "M_D_DQS_DP<1>")
	)
	(segment
		(start 211.43087 -122.89409)
		(end 211.117688 -122.89409)
		(width 0.1651)
		(layer "F.Cu")
		(net "M_D_DQS_DP<1>")
	)
	(segment
		(start 210.849972 -136.664446)
		(end 210.887818 -136.6266)
		(width 0.1651)
		(layer "F.Cu")
		(net "M_D_DQS_DP<1>")
	)
	(segment
		(start 210.3882 -130.940556)
		(end 210.387946 -130.940556)
		(width 0.1651)
		(layer "F.Cu")
		(net "M_D_DQS_DP<1>")
	)
	(segment
		(start 211.78012 -126.48692)
		(end 211.78012 -127.083312)
		(width 0.1651)
		(layer "F.Cu")
		(net "M_D_DQS_DP<1>")
	)
	(segment
		(start 211.78012 -124.1298)
		(end 211.78012 -124.90196)
		(width 0.1651)
		(layer "F.Cu")
		(net "M_D_DQS_DP<1>")
	)
	(via
		(at 210.387946 -130.940556)
		(size 0.508)
		(drill 0.254)
		(layers "F.Cu" "B.Cu")
		(net "M_D_DQS_DP<1>")
	)
	(via
		(at 210.387946 -135.01116)
		(size 0.508)
		(drill 0.254)
		(layers "F.Cu" "B.Cu")
		(net "M_D_DQS_DP<1>")
	)
	(arc
		(start 233.918506 -95.457264)
		(mid 233.785229 -95.350969)
		(end 233.619802 -95.30969)
		(width 0.0889)
		(layer "F.Cu")
		(net "M_D_DQS_DP<1>")
	)
	(segment
		(start 210.85048 -128.276096)
		(end 210.849972 -128.276096)
		(width 0.1651)
		(layer "B.Cu")
		(net "M_D_DQS_DP<1>")
	)
	(segment
		(start 210.630262 -130.940556)
		(end 210.387946 -130.940556)
		(width 0.1651)
		(layer "B.Cu")
		(net "M_D_DQS_DP<1>")
	)
	(segment
		(start 210.887818 -130.683)
		(end 210.630262 -130.940556)
		(width 0.1651)
		(layer "B.Cu")
		(net "M_D_DQS_DP<1>")
	)
	(segment
		(start 210.849972 -129.425954)
		(end 210.887818 -129.4638)
		(width 0.1651)
		(layer "B.Cu")
		(net "M_D_DQS_DP<1>")
	)
	(segment
		(start 210.887818 -129.4638)
		(end 210.887818 -130.683)
		(width 0.1651)
		(layer "B.Cu")
		(net "M_D_DQS_DP<1>")
	)
	(segment
		(start 210.849972 -128.276096)
		(end 210.849972 -129.425954)
		(width 0.1651)
		(layer "B.Cu")
		(net "M_D_DQS_DP<1>")
	)
	(segment
		(start 210.013296 -132.225034)
		(end 210.18373 -132.0546)
		(width 0.14224)
		(layer "In2.Cu")
		(net "M_D_DQS_DP<1>")
	)
	(segment
		(start 210.18373 -132.0546)
		(end 210.568794 -132.0546)
		(width 0.14224)
		(layer "In2.Cu")
		(net "M_D_DQS_DP<1>")
	)
	(segment
		(start 210.128104 -132.6642)
		(end 210.013296 -132.549392)
		(width 0.14224)
		(layer "In2.Cu")
		(net "M_D_DQS_DP<1>")
	)
	(segment
		(start 210.568794 -132.0546)
		(end 210.822794 -131.8006)
		(width 0.14224)
		(layer "In2.Cu")
		(net "M_D_DQS_DP<1>")
	)
	(segment
		(start 210.390994 -133.118352)
		(end 210.390994 -132.842)
		(width 0.14224)
		(layer "In2.Cu")
		(net "M_D_DQS_DP<1>")
	)
	(segment
		(start 210.848194 -134.112)
		(end 210.594194 -133.858)
		(width 0.14224)
		(layer "In2.Cu")
		(net "M_D_DQS_DP<1>")
	)
	(segment
		(start 210.013296 -133.435852)
		(end 210.150456 -133.298692)
		(width 0.14224)
		(layer "In2.Cu")
		(net "M_D_DQS_DP<1>")
	)
	(segment
		(start 210.210654 -133.298692)
		(end 210.390994 -133.118352)
		(width 0.14224)
		(layer "In2.Cu")
		(net "M_D_DQS_DP<1>")
	)
	(segment
		(start 210.013296 -133.662166)
		(end 210.013296 -133.435852)
		(width 0.14224)
		(layer "In2.Cu")
		(net "M_D_DQS_DP<1>")
	)
	(segment
		(start 210.594194 -133.858)
		(end 210.20913 -133.858)
		(width 0.14224)
		(layer "In2.Cu")
		(net "M_D_DQS_DP<1>")
	)
	(segment
		(start 210.150456 -133.298692)
		(end 210.210654 -133.298692)
		(width 0.14224)
		(layer "In2.Cu")
		(net "M_D_DQS_DP<1>")
	)
	(segment
		(start 210.20913 -133.858)
		(end 210.013296 -133.662166)
		(width 0.14224)
		(layer "In2.Cu")
		(net "M_D_DQS_DP<1>")
	)
	(segment
		(start 210.822794 -131.375404)
		(end 210.387946 -130.940556)
		(width 0.14224)
		(layer "In2.Cu")
		(net "M_D_DQS_DP<1>")
	)
	(segment
		(start 210.822794 -131.8006)
		(end 210.822794 -131.375404)
		(width 0.14224)
		(layer "In2.Cu")
		(net "M_D_DQS_DP<1>")
	)
	(segment
		(start 210.013296 -132.549392)
		(end 210.013296 -132.225034)
		(width 0.14224)
		(layer "In2.Cu")
		(net "M_D_DQS_DP<1>")
	)
	(segment
		(start 210.390994 -132.842)
		(end 210.213194 -132.6642)
		(width 0.14224)
		(layer "In2.Cu")
		(net "M_D_DQS_DP<1>")
	)
	(segment
		(start 210.387946 -135.01116)
		(end 210.848194 -134.550912)
		(width 0.14224)
		(layer "In2.Cu")
		(net "M_D_DQS_DP<1>")
	)
	(segment
		(start 210.213194 -132.6642)
		(end 210.128104 -132.6642)
		(width 0.14224)
		(layer "In2.Cu")
		(net "M_D_DQS_DP<1>")
	)
	(segment
		(start 210.848194 -134.550912)
		(end 210.848194 -134.112)
		(width 0.14224)
		(layer "In2.Cu")
		(net "M_D_DQS_DP<1>")
	)
	(segment
		(start 237.20044 -133.0706)
		(end 237.199932 -133.076442)
		(width 0.1651)
		(layer "F.Cu")
		(net "M_D_DQS_DP<17>")
	)
	(segment
		(start 236.700568 -134.26694)
		(end 236.679232 -134.313168)
		(width 0.1651)
		(layer "F.Cu")
		(net "M_D_DQS_DP<17>")
	)
	(segment
		(start 237.199932 -133.693154)
		(end 236.763814 -134.129272)
		(width 0.1651)
		(layer "F.Cu")
		(net "M_D_DQS_DP<17>")
	)
	(segment
		(start 236.760766 -135.355584)
		(end 237.142528 -135.737346)
		(width 0.1651)
		(layer "F.Cu")
		(net "M_D_DQS_DP<17>")
	)
	(segment
		(start 236.679232 -135.131302)
		(end 236.760766 -135.355584)
		(width 0.1651)
		(layer "F.Cu")
		(net "M_D_DQS_DP<17>")
	)
	(segment
		(start 237.199932 -133.076442)
		(end 237.199932 -133.693154)
		(width 0.1651)
		(layer "F.Cu")
		(net "M_D_DQS_DP<17>")
	)
	(segment
		(start 249.061224 -88.775286)
		(end 248.489724 -88.775286)
		(width 0.1651)
		(layer "F.Cu")
		(net "M_D_DQS_DP<17>")
	)
	(segment
		(start 236.679232 -134.313168)
		(end 236.679232 -135.131302)
		(width 0.1651)
		(layer "F.Cu")
		(net "M_D_DQS_DP<17>")
	)
	(segment
		(start 236.763814 -134.129272)
		(end 236.700568 -134.26694)
		(width 0.1651)
		(layer "F.Cu")
		(net "M_D_DQS_DP<17>")
	)
	(via
		(at 237.142528 -135.737346)
		(size 0.508)
		(drill 0.254)
		(layers "F.Cu" "B.Cu")
		(net "M_D_DQS_DP<17>")
	)
	(via
		(at 237.142528 -130.2258)
		(size 0.508)
		(drill 0.254)
		(layers "F.Cu" "B.Cu")
		(net "M_D_DQS_DP<17>")
	)
	(via
		(at 248.489724 -88.775286)
		(size 0.508)
		(drill 0.254)
		(layers "F.Cu" "B.Cu")
		(net "M_D_DQS_DP<17>")
	)
	(segment
		(start 236.666532 -131.669536)
		(end 236.666532 -130.773932)
		(width 0.1651)
		(layer "B.Cu")
		(net "M_D_DQS_DP<17>")
	)
	(segment
		(start 237.20044 -132.876036)
		(end 237.199932 -132.875782)
		(width 0.1651)
		(layer "B.Cu")
		(net "M_D_DQS_DP<17>")
	)
	(segment
		(start 236.753908 -130.61442)
		(end 237.142528 -130.2258)
		(width 0.1651)
		(layer "B.Cu")
		(net "M_D_DQS_DP<17>")
	)
	(segment
		(start 236.666532 -130.773932)
		(end 236.753908 -130.61442)
		(width 0.1651)
		(layer "B.Cu")
		(net "M_D_DQS_DP<17>")
	)
	(segment
		(start 237.199932 -132.258054)
		(end 236.743748 -131.80187)
		(width 0.1651)
		(layer "B.Cu")
		(net "M_D_DQS_DP<17>")
	)
	(segment
		(start 237.199932 -132.875782)
		(end 237.199932 -132.258054)
		(width 0.1651)
		(layer "B.Cu")
		(net "M_D_DQS_DP<17>")
	)
	(segment
		(start 236.743748 -131.80187)
		(end 236.666532 -131.669536)
		(width 0.1651)
		(layer "B.Cu")
		(net "M_D_DQS_DP<17>")
	)
	(segment
		(start 245.839234 -102.726998)
		(end 245.839234 -102.7049)
		(width 0.0889)
		(layer "In2.Cu")
		(net "M_D_DQS_DP<17>")
	)
	(segment
		(start 237.42904 -130.2258)
		(end 237.655608 -129.999232)
		(width 0.14224)
		(layer "In2.Cu")
		(net "M_D_DQS_DP<17>")
	)
	(segment
		(start 245.878604 -102.66553)
		(end 245.878604 -100.997512)
		(width 0.0889)
		(layer "In2.Cu")
		(net "M_D_DQS_DP<17>")
	)
	(segment
		(start 237.485428 -129.071116)
		(end 237.485428 -128.817116)
		(width 0.14224)
		(layer "In2.Cu")
		(net "M_D_DQS_DP<17>")
	)
	(segment
		(start 237.655608 -128.392936)
		(end 237.485428 -128.222756)
		(width 0.14224)
		(layer "In2.Cu")
		(net "M_D_DQS_DP<17>")
	)
	(segment
		(start 237.655608 -129.999232)
		(end 237.655608 -129.241296)
		(width 0.14224)
		(layer "In2.Cu")
		(net "M_D_DQS_DP<17>")
	)
	(segment
		(start 247.12422 -95.518224)
		(end 247.119394 -95.509588)
		(width 0.0889)
		(layer "In2.Cu")
		(net "M_D_DQS_DP<17>")
	)
	(segment
		(start 247.971564 -91.462606)
		(end 247.977914 -91.451938)
		(width 0.0889)
		(layer "In2.Cu")
		(net "M_D_DQS_DP<17>")
	)
	(segment
		(start 245.839234 -102.7049)
		(end 245.878604 -102.66553)
		(width 0.0889)
		(layer "In2.Cu")
		(net "M_D_DQS_DP<17>")
	)
	(segment
		(start 236.637576 -130.6576)
		(end 237.069376 -130.2258)
		(width 0.14224)
		(layer "In2.Cu")
		(net "M_D_DQS_DP<17>")
	)
	(segment
		(start 246.939816 -97.147634)
		(end 247.09247 -96.943926)
		(width 0.0889)
		(layer "In2.Cu")
		(net "M_D_DQS_DP<17>")
	)
	(segment
		(start 245.839234 -104.392984)
		(end 245.839234 -102.726998)
		(width 0.14224)
		(layer "In2.Cu")
		(net "M_D_DQS_DP<17>")
	)
	(segment
		(start 236.637576 -135.232394)
		(end 236.637576 -130.6576)
		(width 0.14224)
		(layer "In2.Cu")
		(net "M_D_DQS_DP<17>")
	)
	(segment
		(start 248.424446 -89.178638)
		(end 248.489724 -89.11336)
		(width 0.0889)
		(layer "In2.Cu")
		(net "M_D_DQS_DP<17>")
	)
	(segment
		(start 247.113044 -93.939106)
		(end 247.119394 -93.928438)
		(width 0.0889)
		(layer "In2.Cu")
		(net "M_D_DQS_DP<17>")
	)
	(segment
		(start 237.069376 -130.2258)
		(end 237.142528 -130.2258)
		(width 0.14224)
		(layer "In2.Cu")
		(net "M_D_DQS_DP<17>")
	)
	(segment
		(start 247.609614 -92.64269)
		(end 247.64238 -92.64269)
		(width 0.0889)
		(layer "In2.Cu")
		(net "M_D_DQS_DP<17>")
	)
	(segment
		(start 239.24768 -110.984538)
		(end 245.839234 -104.392984)
		(width 0.14224)
		(layer "In2.Cu")
		(net "M_D_DQS_DP<17>")
	)
	(segment
		(start 237.142528 -130.2258)
		(end 237.42904 -130.2258)
		(width 0.14224)
		(layer "In2.Cu")
		(net "M_D_DQS_DP<17>")
	)
	(segment
		(start 237.655608 -127.798576)
		(end 237.655608 -123.438158)
		(width 0.14224)
		(layer "In2.Cu")
		(net "M_D_DQS_DP<17>")
	)
	(segment
		(start 247.977914 -90.461338)
		(end 247.98274 -90.452702)
		(width 0.0889)
		(layer "In2.Cu")
		(net "M_D_DQS_DP<17>")
	)
	(segment
		(start 237.142528 -135.737346)
		(end 236.637576 -135.232394)
		(width 0.14224)
		(layer "In2.Cu")
		(net "M_D_DQS_DP<17>")
	)
	(segment
		(start 237.485428 -128.817116)
		(end 237.655608 -128.646936)
		(width 0.14224)
		(layer "In2.Cu")
		(net "M_D_DQS_DP<17>")
	)
	(segment
		(start 237.485428 -127.968756)
		(end 237.655608 -127.798576)
		(width 0.14224)
		(layer "In2.Cu")
		(net "M_D_DQS_DP<17>")
	)
	(segment
		(start 247.12422 -94.527624)
		(end 247.119394 -94.518988)
		(width 0.0889)
		(layer "In2.Cu")
		(net "M_D_DQS_DP<17>")
	)
	(segment
		(start 247.977914 -91.451938)
		(end 247.98274 -91.443302)
		(width 0.0889)
		(layer "In2.Cu")
		(net "M_D_DQS_DP<17>")
	)
	(segment
		(start 237.485428 -128.222756)
		(end 237.485428 -127.968756)
		(width 0.14224)
		(layer "In2.Cu")
		(net "M_D_DQS_DP<17>")
	)
	(segment
		(start 247.119394 -95.509588)
		(end 247.113044 -95.49892)
		(width 0.0889)
		(layer "In2.Cu")
		(net "M_D_DQS_DP<17>")
	)
	(segment
		(start 237.655608 -129.241296)
		(end 237.485428 -129.071116)
		(width 0.14224)
		(layer "In2.Cu")
		(net "M_D_DQS_DP<17>")
	)
	(segment
		(start 237.655608 -128.646936)
		(end 237.655608 -128.392936)
		(width 0.14224)
		(layer "In2.Cu")
		(net "M_D_DQS_DP<17>")
	)
	(segment
		(start 239.24768 -121.846086)
		(end 239.24768 -110.984538)
		(width 0.14224)
		(layer "In2.Cu")
		(net "M_D_DQS_DP<17>")
	)
	(segment
		(start 247.971564 -90.472006)
		(end 247.977914 -90.461338)
		(width 0.0889)
		(layer "In2.Cu")
		(net "M_D_DQS_DP<17>")
	)
	(segment
		(start 248.489724 -89.11336)
		(end 248.489724 -88.775286)
		(width 0.0889)
		(layer "In2.Cu")
		(net "M_D_DQS_DP<17>")
	)
	(segment
		(start 245.878604 -100.997512)
		(end 246.939816 -99.9363)
		(width 0.0889)
		(layer "In2.Cu")
		(net "M_D_DQS_DP<17>")
	)
	(segment
		(start 237.655608 -123.438158)
		(end 239.24768 -121.846086)
		(width 0.14224)
		(layer "In2.Cu")
		(net "M_D_DQS_DP<17>")
	)
	(segment
		(start 246.939816 -99.9363)
		(end 246.939816 -97.147634)
		(width 0.0889)
		(layer "In2.Cu")
		(net "M_D_DQS_DP<17>")
	)
	(segment
		(start 247.119394 -96.500188)
		(end 247.113044 -96.48952)
		(width 0.0889)
		(layer "In2.Cu")
		(net "M_D_DQS_DP<17>")
	)
	(arc
		(start 247.98274 -90.452702)
		(mid 248.031495 -90.25635)
		(end 247.977914 -90.061288)
		(width 0.0889)
		(layer "In2.Cu")
		(net "M_D_DQS_DP<17>")
	)
	(arc
		(start 247.64238 -92.64269)
		(mid 247.980549 -92.437892)
		(end 247.977914 -92.042488)
		(width 0.0889)
		(layer "In2.Cu")
		(net "M_D_DQS_DP<17>")
	)
	(arc
		(start 247.98274 -91.443302)
		(mid 248.031495 -91.24695)
		(end 247.977914 -91.051888)
		(width 0.0889)
		(layer "In2.Cu")
		(net "M_D_DQS_DP<17>")
	)
	(arc
		(start 247.977914 -90.061288)
		(mid 247.962409 -89.499146)
		(end 248.424446 -89.178638)
		(width 0.0889)
		(layer "In2.Cu")
		(net "M_D_DQS_DP<17>")
	)
	(arc
		(start 247.977914 -91.051888)
		(mid 247.898692 -90.76277)
		(end 247.971564 -90.472006)
		(width 0.0889)
		(layer "In2.Cu")
		(net "M_D_DQS_DP<17>")
	)
	(arc
		(start 247.113044 -96.48952)
		(mid 247.040246 -96.198757)
		(end 247.119394 -95.909638)
		(width 0.0889)
		(layer "In2.Cu")
		(net "M_D_DQS_DP<17>")
	)
	(arc
		(start 247.119394 -93.928438)
		(mid 247.172893 -93.72854)
		(end 247.119394 -93.528642)
		(width 0.0889)
		(layer "In2.Cu")
		(net "M_D_DQS_DP<17>")
	)
	(arc
		(start 247.119394 -94.518988)
		(mid 247.040172 -94.22987)
		(end 247.113044 -93.939106)
		(width 0.0889)
		(layer "In2.Cu")
		(net "M_D_DQS_DP<17>")
	)
	(arc
		(start 247.146064 -96.555814)
		(mid 247.133797 -96.527489)
		(end 247.119394 -96.500188)
		(width 0.0889)
		(layer "In2.Cu")
		(net "M_D_DQS_DP<17>")
	)
	(arc
		(start 247.113044 -95.49892)
		(mid 247.040246 -95.208157)
		(end 247.119394 -94.919038)
		(width 0.0889)
		(layer "In2.Cu")
		(net "M_D_DQS_DP<17>")
	)
	(arc
		(start 247.977914 -92.042488)
		(mid 247.898692 -91.75337)
		(end 247.971564 -91.462606)
		(width 0.0889)
		(layer "In2.Cu")
		(net "M_D_DQS_DP<17>")
	)
	(arc
		(start 247.119394 -93.528642)
		(mid 247.11414 -92.947134)
		(end 247.609614 -92.64269)
		(width 0.0889)
		(layer "In2.Cu")
		(net "M_D_DQS_DP<17>")
	)
	(arc
		(start 247.119394 -95.909638)
		(mid 247.172864 -95.714575)
		(end 247.12422 -95.518224)
		(width 0.0889)
		(layer "In2.Cu")
		(net "M_D_DQS_DP<17>")
	)
	(arc
		(start 247.119394 -94.919038)
		(mid 247.172864 -94.723975)
		(end 247.12422 -94.527624)
		(width 0.0889)
		(layer "In2.Cu")
		(net "M_D_DQS_DP<17>")
	)
	(arc
		(start 247.09247 -96.943926)
		(mid 247.169476 -96.756787)
		(end 247.146064 -96.555814)
		(width 0.0889)
		(layer "In2.Cu")
		(net "M_D_DQS_DP<17>")
	)
	(segment
		(start 310.650636 -134.26694)
		(end 310.6293 -134.313168)
		(width 0.1651)
		(layer "F.Cu")
		(net "M_D_DQS_DP<16>")
	)
	(segment
		(start 310.713882 -134.129272)
		(end 310.650636 -134.26694)
		(width 0.1651)
		(layer "F.Cu")
		(net "M_D_DQS_DP<16>")
	)
	(segment
		(start 310.710834 -135.355584)
		(end 311.092596 -135.737346)
		(width 0.1651)
		(layer "F.Cu")
		(net "M_D_DQS_DP<16>")
	)
	(segment
		(start 311.150508 -133.0706)
		(end 311.15 -133.076442)
		(width 0.1651)
		(layer "F.Cu")
		(net "M_D_DQS_DP<16>")
	)
	(segment
		(start 288.36366 -97.509584)
		(end 288.93516 -97.509584)
		(width 0.1651)
		(layer "F.Cu")
		(net "M_D_DQS_DP<16>")
	)
	(segment
		(start 310.6293 -134.313168)
		(end 310.6293 -135.131302)
		(width 0.1651)
		(layer "F.Cu")
		(net "M_D_DQS_DP<16>")
	)
	(segment
		(start 310.6293 -135.131302)
		(end 310.710834 -135.355584)
		(width 0.1651)
		(layer "F.Cu")
		(net "M_D_DQS_DP<16>")
	)
	(segment
		(start 311.15 -133.693154)
		(end 310.713882 -134.129272)
		(width 0.1651)
		(layer "F.Cu")
		(net "M_D_DQS_DP<16>")
	)
	(segment
		(start 311.15 -133.076442)
		(end 311.15 -133.693154)
		(width 0.1651)
		(layer "F.Cu")
		(net "M_D_DQS_DP<16>")
	)
	(via
		(at 311.092596 -135.737346)
		(size 0.508)
		(drill 0.254)
		(layers "F.Cu" "B.Cu")
		(net "M_D_DQS_DP<16>")
	)
	(via
		(at 288.93516 -97.509584)
		(size 0.508)
		(drill 0.254)
		(layers "F.Cu" "B.Cu")
		(net "M_D_DQS_DP<16>")
	)
	(via
		(at 311.092596 -130.2258)
		(size 0.508)
		(drill 0.254)
		(layers "F.Cu" "B.Cu")
		(net "M_D_DQS_DP<16>")
	)
	(segment
		(start 311.150508 -132.876036)
		(end 311.15 -132.875782)
		(width 0.1651)
		(layer "B.Cu")
		(net "M_D_DQS_DP<16>")
	)
	(segment
		(start 311.15 -132.875782)
		(end 311.15 -132.258054)
		(width 0.1651)
		(layer "B.Cu")
		(net "M_D_DQS_DP<16>")
	)
	(segment
		(start 311.15 -132.258054)
		(end 310.693816 -131.80187)
		(width 0.1651)
		(layer "B.Cu")
		(net "M_D_DQS_DP<16>")
	)
	(segment
		(start 310.6166 -131.669536)
		(end 310.6166 -130.773932)
		(width 0.1651)
		(layer "B.Cu")
		(net "M_D_DQS_DP<16>")
	)
	(segment
		(start 310.6166 -130.773932)
		(end 310.703976 -130.61442)
		(width 0.1651)
		(layer "B.Cu")
		(net "M_D_DQS_DP<16>")
	)
	(segment
		(start 310.693816 -131.80187)
		(end 310.6166 -131.669536)
		(width 0.1651)
		(layer "B.Cu")
		(net "M_D_DQS_DP<16>")
	)
	(segment
		(start 310.703976 -130.61442)
		(end 311.092596 -130.2258)
		(width 0.1651)
		(layer "B.Cu")
		(net "M_D_DQS_DP<16>")
	)
	(segment
		(start 312.71464 -125.734826)
		(end 312.71464 -125.988826)
		(width 0.14224)
		(layer "In2.Cu")
		(net "M_D_DQS_DP<16>")
	)
	(segment
		(start 293.33698 -106.1974)
		(end 294.52062 -107.38104)
		(width 0.14224)
		(layer "In2.Cu")
		(net "M_D_DQS_DP<16>")
	)
	(segment
		(start 312.71464 -122.398282)
		(end 312.71464 -122.696986)
		(width 0.14224)
		(layer "In2.Cu")
		(net "M_D_DQS_DP<16>")
	)
	(segment
		(start 312.71464 -124.088906)
		(end 312.71464 -124.342906)
		(width 0.14224)
		(layer "In2.Cu")
		(net "M_D_DQS_DP<16>")
	)
	(segment
		(start 311.631076 -129.96672)
		(end 311.371996 -130.2258)
		(width 0.14224)
		(layer "In2.Cu")
		(net "M_D_DQS_DP<16>")
	)
	(segment
		(start 288.417 -100.766118)
		(end 288.42335 -100.776786)
		(width 0.0889)
		(layer "In2.Cu")
		(net "M_D_DQS_DP<16>")
	)
	(segment
		(start 288.599372 -103.062786)
		(end 288.667698 -103.181404)
		(width 0.0889)
		(layer "In2.Cu")
		(net "M_D_DQS_DP<16>")
	)
	(segment
		(start 312.55716 -123.931426)
		(end 312.71464 -124.088906)
		(width 0.14224)
		(layer "In2.Cu")
		(net "M_D_DQS_DP<16>")
	)
	(segment
		(start 312.55716 -124.500386)
		(end 312.55716 -124.754386)
		(width 0.14224)
		(layer "In2.Cu")
		(net "M_D_DQS_DP<16>")
	)
	(segment
		(start 299.26534 -108.27004)
		(end 301.098712 -108.27004)
		(width 0.14224)
		(layer "In2.Cu")
		(net "M_D_DQS_DP<16>")
	)
	(segment
		(start 288.93516 -97.509584)
		(end 288.93516 -97.17151)
		(width 0.0889)
		(layer "In2.Cu")
		(net "M_D_DQS_DP<16>")
	)
	(segment
		(start 312.71464 -123.265946)
		(end 312.71464 -123.519946)
		(width 0.14224)
		(layer "In2.Cu")
		(net "M_D_DQS_DP<16>")
	)
	(segment
		(start 312.55716 -123.108466)
		(end 312.71464 -123.265946)
		(width 0.14224)
		(layer "In2.Cu")
		(net "M_D_DQS_DP<16>")
	)
	(segment
		(start 312.596276 -122.025918)
		(end 312.596276 -122.279918)
		(width 0.14224)
		(layer "In2.Cu")
		(net "M_D_DQS_DP<16>")
	)
	(segment
		(start 312.596276 -122.279918)
		(end 312.71464 -122.398282)
		(width 0.14224)
		(layer "In2.Cu")
		(net "M_D_DQS_DP<16>")
	)
	(segment
		(start 312.55716 -126.146306)
		(end 312.55716 -126.400306)
		(width 0.14224)
		(layer "In2.Cu")
		(net "M_D_DQS_DP<16>")
	)
	(segment
		(start 312.55716 -126.969266)
		(end 312.55716 -127.223266)
		(width 0.14224)
		(layer "In2.Cu")
		(net "M_D_DQS_DP<16>")
	)
	(segment
		(start 312.71464 -125.165866)
		(end 312.55716 -125.323346)
		(width 0.14224)
		(layer "In2.Cu")
		(net "M_D_DQS_DP<16>")
	)
	(segment
		(start 288.42335 -102.167436)
		(end 288.417 -102.178104)
		(width 0.0889)
		(layer "In2.Cu")
		(net "M_D_DQS_DP<16>")
	)
	(segment
		(start 288.42335 -99.195636)
		(end 288.417 -99.206304)
		(width 0.0889)
		(layer "In2.Cu")
		(net "M_D_DQS_DP<16>")
	)
	(segment
		(start 312.71464 -122.696986)
		(end 312.55716 -122.854466)
		(width 0.14224)
		(layer "In2.Cu")
		(net "M_D_DQS_DP<16>")
	)
	(segment
		(start 311.019444 -130.2258)
		(end 310.587644 -130.6576)
		(width 0.14224)
		(layer "In2.Cu")
		(net "M_D_DQS_DP<16>")
	)
	(segment
		(start 288.42335 -102.757986)
		(end 288.599372 -103.062786)
		(width 0.0889)
		(layer "In2.Cu")
		(net "M_D_DQS_DP<16>")
	)
	(segment
		(start 288.428176 -100.1776)
		(end 288.42335 -100.186236)
		(width 0.0889)
		(layer "In2.Cu")
		(net "M_D_DQS_DP<16>")
	)
	(segment
		(start 312.71464 -126.557786)
		(end 312.71464 -126.811786)
		(width 0.14224)
		(layer "In2.Cu")
		(net "M_D_DQS_DP<16>")
	)
	(segment
		(start 312.71464 -119.885968)
		(end 312.71464 -121.907554)
		(width 0.14224)
		(layer "In2.Cu")
		(net "M_D_DQS_DP<16>")
	)
	(segment
		(start 290.6141 -105.156)
		(end 292.351206 -105.156)
		(width 0.0889)
		(layer "In2.Cu")
		(net "M_D_DQS_DP<16>")
	)
	(segment
		(start 312.71464 -126.811786)
		(end 312.55716 -126.969266)
		(width 0.14224)
		(layer "In2.Cu")
		(net "M_D_DQS_DP<16>")
	)
	(segment
		(start 293.321486 -106.181906)
		(end 293.33698 -106.1974)
		(width 0.0889)
		(layer "In2.Cu")
		(net "M_D_DQS_DP<16>")
	)
	(segment
		(start 298.37634 -107.38104)
		(end 299.26534 -108.27004)
		(width 0.14224)
		(layer "In2.Cu")
		(net "M_D_DQS_DP<16>")
	)
	(segment
		(start 301.098712 -108.27004)
		(end 312.71464 -119.885968)
		(width 0.14224)
		(layer "In2.Cu")
		(net "M_D_DQS_DP<16>")
	)
	(segment
		(start 310.587644 -135.232394)
		(end 311.092596 -135.737346)
		(width 0.14224)
		(layer "In2.Cu")
		(net "M_D_DQS_DP<16>")
	)
	(segment
		(start 312.042048 -128.213866)
		(end 312.042048 -128.361186)
		(width 0.14224)
		(layer "In2.Cu")
		(net "M_D_DQS_DP<16>")
	)
	(segment
		(start 312.55716 -127.223266)
		(end 312.71464 -127.380746)
		(width 0.14224)
		(layer "In2.Cu")
		(net "M_D_DQS_DP<16>")
	)
	(segment
		(start 288.667698 -103.181404)
		(end 288.667698 -103.209598)
		(width 0.0889)
		(layer "In2.Cu")
		(net "M_D_DQS_DP<16>")
	)
	(segment
		(start 310.587644 -130.6576)
		(end 310.587644 -135.232394)
		(width 0.14224)
		(layer "In2.Cu")
		(net "M_D_DQS_DP<16>")
	)
	(segment
		(start 312.221626 -128.034288)
		(end 312.042048 -128.213866)
		(width 0.14224)
		(layer "In2.Cu")
		(net "M_D_DQS_DP<16>")
	)
	(segment
		(start 312.55716 -123.677426)
		(end 312.55716 -123.931426)
		(width 0.14224)
		(layer "In2.Cu")
		(net "M_D_DQS_DP<16>")
	)
	(segment
		(start 312.368946 -128.034288)
		(end 312.221626 -128.034288)
		(width 0.14224)
		(layer "In2.Cu")
		(net "M_D_DQS_DP<16>")
	)
	(segment
		(start 312.71464 -123.519946)
		(end 312.55716 -123.677426)
		(width 0.14224)
		(layer "In2.Cu")
		(net "M_D_DQS_DP<16>")
	)
	(segment
		(start 312.71464 -124.911866)
		(end 312.71464 -125.165866)
		(width 0.14224)
		(layer "In2.Cu")
		(net "M_D_DQS_DP<16>")
	)
	(segment
		(start 294.52062 -107.38104)
		(end 298.37634 -107.38104)
		(width 0.14224)
		(layer "In2.Cu")
		(net "M_D_DQS_DP<16>")
	)
	(segment
		(start 311.631076 -128.772158)
		(end 311.631076 -129.96672)
		(width 0.14224)
		(layer "In2.Cu")
		(net "M_D_DQS_DP<16>")
	)
	(segment
		(start 288.950146 -97.909634)
		(end 288.91738 -97.909634)
		(width 0.0889)
		(layer "In2.Cu")
		(net "M_D_DQS_DP<16>")
	)
	(segment
		(start 288.428176 -102.1588)
		(end 288.42335 -102.167436)
		(width 0.0889)
		(layer "In2.Cu")
		(net "M_D_DQS_DP<16>")
	)
	(segment
		(start 288.667698 -103.209598)
		(end 290.6141 -105.156)
		(width 0.0889)
		(layer "In2.Cu")
		(net "M_D_DQS_DP<16>")
	)
	(segment
		(start 312.55716 -125.323346)
		(end 312.55716 -125.577346)
		(width 0.14224)
		(layer "In2.Cu")
		(net "M_D_DQS_DP<16>")
	)
	(segment
		(start 292.351206 -105.156)
		(end 293.32174 -106.126534)
		(width 0.0889)
		(layer "In2.Cu")
		(net "M_D_DQS_DP<16>")
	)
	(segment
		(start 293.32174 -106.126534)
		(end 293.321486 -106.181906)
		(width 0.0889)
		(layer "In2.Cu")
		(net "M_D_DQS_DP<16>")
	)
	(segment
		(start 288.428176 -99.187)
		(end 288.42335 -99.195636)
		(width 0.0889)
		(layer "In2.Cu")
		(net "M_D_DQS_DP<16>")
	)
	(segment
		(start 312.042048 -128.361186)
		(end 311.631076 -128.772158)
		(width 0.14224)
		(layer "In2.Cu")
		(net "M_D_DQS_DP<16>")
	)
	(segment
		(start 311.092596 -130.2258)
		(end 311.019444 -130.2258)
		(width 0.14224)
		(layer "In2.Cu")
		(net "M_D_DQS_DP<16>")
	)
	(segment
		(start 312.71464 -121.907554)
		(end 312.596276 -122.025918)
		(width 0.14224)
		(layer "In2.Cu")
		(net "M_D_DQS_DP<16>")
	)
	(segment
		(start 311.371996 -130.2258)
		(end 311.092596 -130.2258)
		(width 0.14224)
		(layer "In2.Cu")
		(net "M_D_DQS_DP<16>")
	)
	(segment
		(start 312.55716 -122.854466)
		(end 312.55716 -123.108466)
		(width 0.14224)
		(layer "In2.Cu")
		(net "M_D_DQS_DP<16>")
	)
	(segment
		(start 312.71464 -124.342906)
		(end 312.55716 -124.500386)
		(width 0.14224)
		(layer "In2.Cu")
		(net "M_D_DQS_DP<16>")
	)
	(segment
		(start 312.55716 -124.754386)
		(end 312.71464 -124.911866)
		(width 0.14224)
		(layer "In2.Cu")
		(net "M_D_DQS_DP<16>")
	)
	(segment
		(start 312.71464 -127.380746)
		(end 312.71464 -127.688594)
		(width 0.14224)
		(layer "In2.Cu")
		(net "M_D_DQS_DP<16>")
	)
	(segment
		(start 312.71464 -125.988826)
		(end 312.55716 -126.146306)
		(width 0.14224)
		(layer "In2.Cu")
		(net "M_D_DQS_DP<16>")
	)
	(segment
		(start 312.55716 -126.400306)
		(end 312.71464 -126.557786)
		(width 0.14224)
		(layer "In2.Cu")
		(net "M_D_DQS_DP<16>")
	)
	(segment
		(start 288.93516 -97.17151)
		(end 288.993072 -97.113598)
		(width 0.0889)
		(layer "In2.Cu")
		(net "M_D_DQS_DP<16>")
	)
	(segment
		(start 312.55716 -125.577346)
		(end 312.71464 -125.734826)
		(width 0.14224)
		(layer "In2.Cu")
		(net "M_D_DQS_DP<16>")
	)
	(segment
		(start 312.71464 -127.688594)
		(end 312.368946 -128.034288)
		(width 0.14224)
		(layer "In2.Cu")
		(net "M_D_DQS_DP<16>")
	)
	(arc
		(start 288.91738 -97.909634)
		(mid 288.419129 -98.212474)
		(end 288.42335 -98.795586)
		(width 0.0889)
		(layer "In2.Cu")
		(net "M_D_DQS_DP<16>")
	)
	(arc
		(start 288.42335 -98.795586)
		(mid 288.47682 -98.990649)
		(end 288.428176 -99.187)
		(width 0.0889)
		(layer "In2.Cu")
		(net "M_D_DQS_DP<16>")
	)
	(arc
		(start 288.993072 -97.113598)
		(mid 289.334995 -97.531139)
		(end 288.950146 -97.909634)
		(width 0.0889)
		(layer "In2.Cu")
		(net "M_D_DQS_DP<16>")
	)
	(arc
		(start 288.417 -102.178104)
		(mid 288.344202 -102.468867)
		(end 288.42335 -102.757986)
		(width 0.0889)
		(layer "In2.Cu")
		(net "M_D_DQS_DP<16>")
	)
	(arc
		(start 288.42335 -100.186236)
		(mid 288.344128 -100.475354)
		(end 288.417 -100.766118)
		(width 0.0889)
		(layer "In2.Cu")
		(net "M_D_DQS_DP<16>")
	)
	(arc
		(start 288.42335 -101.767386)
		(mid 288.47682 -101.962449)
		(end 288.428176 -102.1588)
		(width 0.0889)
		(layer "In2.Cu")
		(net "M_D_DQS_DP<16>")
	)
	(arc
		(start 288.42335 -99.786186)
		(mid 288.47682 -99.981249)
		(end 288.428176 -100.1776)
		(width 0.0889)
		(layer "In2.Cu")
		(net "M_D_DQS_DP<16>")
	)
	(arc
		(start 288.42335 -100.776786)
		(mid 288.476849 -100.976684)
		(end 288.42335 -101.176582)
		(width 0.0889)
		(layer "In2.Cu")
		(net "M_D_DQS_DP<16>")
	)
	(arc
		(start 288.417 -99.206304)
		(mid 288.344202 -99.497067)
		(end 288.42335 -99.786186)
		(width 0.0889)
		(layer "In2.Cu")
		(net "M_D_DQS_DP<16>")
	)
	(arc
		(start 288.42335 -101.176582)
		(mid 288.344219 -101.471984)
		(end 288.42335 -101.767386)
		(width 0.0889)
		(layer "In2.Cu")
		(net "M_D_DQS_DP<16>")
	)
	(segment
		(start 283.212794 -97.509584)
		(end 283.784294 -97.509584)
		(width 0.1651)
		(layer "F.Cu")
		(net "M_D_DQS_DP<15>")
	)
	(segment
		(start 301.800006 -133.076442)
		(end 301.800006 -133.693154)
		(width 0.1651)
		(layer "F.Cu")
		(net "M_D_DQS_DP<15>")
	)
	(segment
		(start 301.279306 -135.131302)
		(end 301.36084 -135.355584)
		(width 0.1651)
		(layer "F.Cu")
		(net "M_D_DQS_DP<15>")
	)
	(segment
		(start 301.800514 -133.0706)
		(end 301.800006 -133.076442)
		(width 0.1651)
		(layer "F.Cu")
		(net "M_D_DQS_DP<15>")
	)
	(segment
		(start 301.279306 -134.313168)
		(end 301.279306 -135.131302)
		(width 0.1651)
		(layer "F.Cu")
		(net "M_D_DQS_DP<15>")
	)
	(segment
		(start 301.36084 -135.355584)
		(end 301.742602 -135.737346)
		(width 0.1651)
		(layer "F.Cu")
		(net "M_D_DQS_DP<15>")
	)
	(segment
		(start 301.363888 -134.129272)
		(end 301.300642 -134.26694)
		(width 0.1651)
		(layer "F.Cu")
		(net "M_D_DQS_DP<15>")
	)
	(segment
		(start 301.300642 -134.26694)
		(end 301.279306 -134.313168)
		(width 0.1651)
		(layer "F.Cu")
		(net "M_D_DQS_DP<15>")
	)
	(segment
		(start 301.800006 -133.693154)
		(end 301.363888 -134.129272)
		(width 0.1651)
		(layer "F.Cu")
		(net "M_D_DQS_DP<15>")
	)
	(via
		(at 283.784294 -97.509584)
		(size 0.508)
		(drill 0.254)
		(layers "F.Cu" "B.Cu")
		(net "M_D_DQS_DP<15>")
	)
	(via
		(at 301.742602 -135.737346)
		(size 0.508)
		(drill 0.254)
		(layers "F.Cu" "B.Cu")
		(net "M_D_DQS_DP<15>")
	)
	(via
		(at 301.742602 -130.2258)
		(size 0.508)
		(drill 0.254)
		(layers "F.Cu" "B.Cu")
		(net "M_D_DQS_DP<15>")
	)
	(segment
		(start 301.343822 -131.80187)
		(end 301.266606 -131.669536)
		(width 0.1651)
		(layer "B.Cu")
		(net "M_D_DQS_DP<15>")
	)
	(segment
		(start 301.353982 -130.61442)
		(end 301.742602 -130.2258)
		(width 0.1651)
		(layer "B.Cu")
		(net "M_D_DQS_DP<15>")
	)
	(segment
		(start 301.800006 -132.875782)
		(end 301.800006 -132.258054)
		(width 0.1651)
		(layer "B.Cu")
		(net "M_D_DQS_DP<15>")
	)
	(segment
		(start 301.266606 -130.773932)
		(end 301.353982 -130.61442)
		(width 0.1651)
		(layer "B.Cu")
		(net "M_D_DQS_DP<15>")
	)
	(segment
		(start 301.800514 -132.876036)
		(end 301.800006 -132.875782)
		(width 0.1651)
		(layer "B.Cu")
		(net "M_D_DQS_DP<15>")
	)
	(segment
		(start 301.800006 -132.258054)
		(end 301.343822 -131.80187)
		(width 0.1651)
		(layer "B.Cu")
		(net "M_D_DQS_DP<15>")
	)
	(segment
		(start 301.266606 -131.669536)
		(end 301.266606 -130.773932)
		(width 0.1651)
		(layer "B.Cu")
		(net "M_D_DQS_DP<15>")
	)
	(segment
		(start 301.742602 -130.2258)
		(end 301.66945 -130.2258)
		(width 0.14224)
		(layer "In2.Cu")
		(net "M_D_DQS_DP<15>")
	)
	(segment
		(start 282.942284 -105.7402)
		(end 282.942284 -105.762298)
		(width 0.0889)
		(layer "In2.Cu")
		(net "M_D_DQS_DP<15>")
	)
	(segment
		(start 301.66945 -130.2258)
		(end 301.23765 -130.6576)
		(width 0.14224)
		(layer "In2.Cu")
		(net "M_D_DQS_DP<15>")
	)
	(segment
		(start 302.26254 -128.629664)
		(end 302.10506 -128.787144)
		(width 0.14224)
		(layer "In2.Cu")
		(net "M_D_DQS_DP<15>")
	)
	(segment
		(start 289.08883 -117.656102)
		(end 299.423074 -117.656102)
		(width 0.14224)
		(layer "In2.Cu")
		(net "M_D_DQS_DP<15>")
	)
	(segment
		(start 283.263594 -101.751892)
		(end 283.272484 -101.767132)
		(width 0.0889)
		(layer "In2.Cu")
		(net "M_D_DQS_DP<15>")
	)
	(segment
		(start 283.79928 -97.909634)
		(end 283.766514 -97.909634)
		(width 0.0889)
		(layer "In2.Cu")
		(net "M_D_DQS_DP<15>")
	)
	(segment
		(start 283.27731 -103.1494)
		(end 283.121862 -103.427276)
		(width 0.0889)
		(layer "In2.Cu")
		(net "M_D_DQS_DP<15>")
	)
	(segment
		(start 283.266134 -100.765864)
		(end 283.272484 -100.776532)
		(width 0.0889)
		(layer "In2.Cu")
		(net "M_D_DQS_DP<15>")
	)
	(segment
		(start 302.10506 -129.041144)
		(end 302.26254 -129.198624)
		(width 0.14224)
		(layer "In2.Cu")
		(net "M_D_DQS_DP<15>")
	)
	(segment
		(start 282.981654 -104.880664)
		(end 282.981654 -105.70083)
		(width 0.0889)
		(layer "In2.Cu")
		(net "M_D_DQS_DP<15>")
	)
	(segment
		(start 283.44622 -97.509584)
		(end 283.388308 -97.451672)
		(width 0.0889)
		(layer "In2.Cu")
		(net "M_D_DQS_DP<15>")
	)
	(segment
		(start 301.23765 -130.6576)
		(end 301.23765 -135.232394)
		(width 0.14224)
		(layer "In2.Cu")
		(net "M_D_DQS_DP<15>")
	)
	(segment
		(start 282.942284 -105.762298)
		(end 282.942284 -110.450884)
		(width 0.14224)
		(layer "In2.Cu")
		(net "M_D_DQS_DP<15>")
	)
	(segment
		(start 283.121862 -104.740456)
		(end 282.981654 -104.880664)
		(width 0.0889)
		(layer "In2.Cu")
		(net "M_D_DQS_DP<15>")
	)
	(segment
		(start 299.423074 -117.656102)
		(end 302.26254 -120.495568)
		(width 0.14224)
		(layer "In2.Cu")
		(net "M_D_DQS_DP<15>")
	)
	(segment
		(start 283.272484 -99.785932)
		(end 283.27731 -99.794568)
		(width 0.0889)
		(layer "In2.Cu")
		(net "M_D_DQS_DP<15>")
	)
	(segment
		(start 282.981654 -105.70083)
		(end 282.942284 -105.7402)
		(width 0.0889)
		(layer "In2.Cu")
		(net "M_D_DQS_DP<15>")
	)
	(segment
		(start 301.23765 -135.232394)
		(end 301.742602 -135.737346)
		(width 0.14224)
		(layer "In2.Cu")
		(net "M_D_DQS_DP<15>")
	)
	(segment
		(start 283.272484 -100.776532)
		(end 283.279342 -100.788724)
		(width 0.0889)
		(layer "In2.Cu")
		(net "M_D_DQS_DP<15>")
	)
	(segment
		(start 302.10506 -128.787144)
		(end 302.10506 -129.041144)
		(width 0.14224)
		(layer "In2.Cu")
		(net "M_D_DQS_DP<15>")
	)
	(segment
		(start 283.272484 -98.205036)
		(end 283.266134 -98.215704)
		(width 0.0889)
		(layer "In2.Cu")
		(net "M_D_DQS_DP<15>")
	)
	(segment
		(start 282.942284 -110.450884)
		(end 284.99816 -112.50676)
		(width 0.14224)
		(layer "In2.Cu")
		(net "M_D_DQS_DP<15>")
	)
	(segment
		(start 283.784294 -97.509584)
		(end 283.44622 -97.509584)
		(width 0.0889)
		(layer "In2.Cu")
		(net "M_D_DQS_DP<15>")
	)
	(segment
		(start 302.022002 -130.2258)
		(end 301.742602 -130.2258)
		(width 0.14224)
		(layer "In2.Cu")
		(net "M_D_DQS_DP<15>")
	)
	(segment
		(start 302.26254 -120.495568)
		(end 302.26254 -128.629664)
		(width 0.14224)
		(layer "In2.Cu")
		(net "M_D_DQS_DP<15>")
	)
	(segment
		(start 302.26254 -129.985262)
		(end 302.022002 -130.2258)
		(width 0.14224)
		(layer "In2.Cu")
		(net "M_D_DQS_DP<15>")
	)
	(segment
		(start 283.272484 -101.767132)
		(end 283.27731 -101.775768)
		(width 0.0889)
		(layer "In2.Cu")
		(net "M_D_DQS_DP<15>")
	)
	(segment
		(start 283.27731 -99.187)
		(end 283.272484 -99.195636)
		(width 0.0889)
		(layer "In2.Cu")
		(net "M_D_DQS_DP<15>")
	)
	(segment
		(start 284.99816 -113.565432)
		(end 289.08883 -117.656102)
		(width 0.14224)
		(layer "In2.Cu")
		(net "M_D_DQS_DP<15>")
	)
	(segment
		(start 284.99816 -112.50676)
		(end 284.99816 -113.565432)
		(width 0.14224)
		(layer "In2.Cu")
		(net "M_D_DQS_DP<15>")
	)
	(segment
		(start 283.27731 -98.1964)
		(end 283.272484 -98.205036)
		(width 0.0889)
		(layer "In2.Cu")
		(net "M_D_DQS_DP<15>")
	)
	(segment
		(start 302.26254 -129.198624)
		(end 302.26254 -129.985262)
		(width 0.14224)
		(layer "In2.Cu")
		(net "M_D_DQS_DP<15>")
	)
	(segment
		(start 283.121862 -103.427276)
		(end 283.121862 -104.740456)
		(width 0.0889)
		(layer "In2.Cu")
		(net "M_D_DQS_DP<15>")
	)
	(arc
		(start 284.077156 -97.236534)
		(mid 284.154408 -97.66236)
		(end 283.79928 -97.909634)
		(width 0.0889)
		(layer "In2.Cu")
		(net "M_D_DQS_DP<15>")
	)
	(arc
		(start 283.766514 -97.909634)
		(mid 283.482912 -97.986488)
		(end 283.27731 -98.1964)
		(width 0.0889)
		(layer "In2.Cu")
		(net "M_D_DQS_DP<15>")
	)
	(arc
		(start 283.272484 -101.176328)
		(mid 283.193295 -101.462943)
		(end 283.263594 -101.751892)
		(width 0.0889)
		(layer "In2.Cu")
		(net "M_D_DQS_DP<15>")
	)
	(arc
		(start 283.266134 -98.215704)
		(mid 283.193336 -98.506467)
		(end 283.272484 -98.795586)
		(width 0.0889)
		(layer "In2.Cu")
		(net "M_D_DQS_DP<15>")
	)
	(arc
		(start 283.272484 -99.195636)
		(mid 283.193479 -99.490784)
		(end 283.272484 -99.785932)
		(width 0.0889)
		(layer "In2.Cu")
		(net "M_D_DQS_DP<15>")
	)
	(arc
		(start 283.272484 -102.167182)
		(mid 283.193353 -102.462584)
		(end 283.272484 -102.757986)
		(width 0.0889)
		(layer "In2.Cu")
		(net "M_D_DQS_DP<15>")
	)
	(arc
		(start 283.272484 -98.795586)
		(mid 283.325954 -98.990649)
		(end 283.27731 -99.187)
		(width 0.0889)
		(layer "In2.Cu")
		(net "M_D_DQS_DP<15>")
	)
	(arc
		(start 283.27731 -101.775768)
		(mid 283.326065 -101.97212)
		(end 283.272484 -102.167182)
		(width 0.0889)
		(layer "In2.Cu")
		(net "M_D_DQS_DP<15>")
	)
	(arc
		(start 283.27731 -99.794568)
		(mid 283.326065 -99.99092)
		(end 283.272484 -100.185982)
		(width 0.0889)
		(layer "In2.Cu")
		(net "M_D_DQS_DP<15>")
	)
	(arc
		(start 283.279342 -100.788724)
		(mid 283.326018 -100.983425)
		(end 283.272484 -101.176328)
		(width 0.0889)
		(layer "In2.Cu")
		(net "M_D_DQS_DP<15>")
	)
	(arc
		(start 283.388308 -97.451672)
		(mid 283.665036 -97.127568)
		(end 284.077156 -97.236534)
		(width 0.0889)
		(layer "In2.Cu")
		(net "M_D_DQS_DP<15>")
	)
	(arc
		(start 283.272484 -102.757986)
		(mid 283.325954 -102.953049)
		(end 283.27731 -103.1494)
		(width 0.0889)
		(layer "In2.Cu")
		(net "M_D_DQS_DP<15>")
	)
	(arc
		(start 283.272484 -100.185982)
		(mid 283.193262 -100.4751)
		(end 283.266134 -100.765864)
		(width 0.0889)
		(layer "In2.Cu")
		(net "M_D_DQS_DP<15>")
	)
	(segment
		(start 278.061674 -96.518984)
		(end 278.633174 -96.518984)
		(width 0.1651)
		(layer "F.Cu")
		(net "M_D_DQS_DP<14>")
	)
	(segment
		(start 292.010846 -135.355584)
		(end 292.392608 -135.737346)
		(width 0.1651)
		(layer "F.Cu")
		(net "M_D_DQS_DP<14>")
	)
	(segment
		(start 292.450012 -133.693154)
		(end 292.013894 -134.129272)
		(width 0.1651)
		(layer "F.Cu")
		(net "M_D_DQS_DP<14>")
	)
	(segment
		(start 292.45052 -133.0706)
		(end 292.450012 -133.076442)
		(width 0.1651)
		(layer "F.Cu")
		(net "M_D_DQS_DP<14>")
	)
	(segment
		(start 291.950648 -134.26694)
		(end 291.929312 -134.313168)
		(width 0.1651)
		(layer "F.Cu")
		(net "M_D_DQS_DP<14>")
	)
	(segment
		(start 292.013894 -134.129272)
		(end 291.950648 -134.26694)
		(width 0.1651)
		(layer "F.Cu")
		(net "M_D_DQS_DP<14>")
	)
	(segment
		(start 292.450012 -133.076442)
		(end 292.450012 -133.693154)
		(width 0.1651)
		(layer "F.Cu")
		(net "M_D_DQS_DP<14>")
	)
	(segment
		(start 291.929312 -135.131302)
		(end 292.010846 -135.355584)
		(width 0.1651)
		(layer "F.Cu")
		(net "M_D_DQS_DP<14>")
	)
	(segment
		(start 291.929312 -134.313168)
		(end 291.929312 -135.131302)
		(width 0.1651)
		(layer "F.Cu")
		(net "M_D_DQS_DP<14>")
	)
	(via
		(at 292.392608 -135.737346)
		(size 0.508)
		(drill 0.254)
		(layers "F.Cu" "B.Cu")
		(net "M_D_DQS_DP<14>")
	)
	(via
		(at 292.392608 -130.2258)
		(size 0.508)
		(drill 0.254)
		(layers "F.Cu" "B.Cu")
		(net "M_D_DQS_DP<14>")
	)
	(via
		(at 278.633174 -96.518984)
		(size 0.508)
		(drill 0.254)
		(layers "F.Cu" "B.Cu")
		(net "M_D_DQS_DP<14>")
	)
	(segment
		(start 292.45052 -132.876036)
		(end 292.450012 -132.875782)
		(width 0.1651)
		(layer "B.Cu")
		(net "M_D_DQS_DP<14>")
	)
	(segment
		(start 292.003988 -130.61442)
		(end 292.392608 -130.2258)
		(width 0.1651)
		(layer "B.Cu")
		(net "M_D_DQS_DP<14>")
	)
	(segment
		(start 291.993828 -131.80187)
		(end 291.916612 -131.669536)
		(width 0.1651)
		(layer "B.Cu")
		(net "M_D_DQS_DP<14>")
	)
	(segment
		(start 291.916612 -130.773932)
		(end 292.003988 -130.61442)
		(width 0.1651)
		(layer "B.Cu")
		(net "M_D_DQS_DP<14>")
	)
	(segment
		(start 292.450012 -132.258054)
		(end 291.993828 -131.80187)
		(width 0.1651)
		(layer "B.Cu")
		(net "M_D_DQS_DP<14>")
	)
	(segment
		(start 291.916612 -131.669536)
		(end 291.916612 -130.773932)
		(width 0.1651)
		(layer "B.Cu")
		(net "M_D_DQS_DP<14>")
	)
	(segment
		(start 292.450012 -132.875782)
		(end 292.450012 -132.258054)
		(width 0.1651)
		(layer "B.Cu")
		(net "M_D_DQS_DP<14>")
	)
	(segment
		(start 274.637754 -115.549426)
		(end 284.232096 -125.143768)
		(width 0.14224)
		(layer "In2.Cu")
		(net "M_D_DQS_DP<14>")
	)
	(segment
		(start 292.748208 -128.915668)
		(end 292.748208 -129.169668)
		(width 0.14224)
		(layer "In2.Cu")
		(net "M_D_DQS_DP<14>")
	)
	(segment
		(start 292.905688 -129.99212)
		(end 292.672008 -130.2258)
		(width 0.14224)
		(layer "In2.Cu")
		(net "M_D_DQS_DP<14>")
	)
	(segment
		(start 291.5666 -127.576326)
		(end 291.8206 -127.576326)
		(width 0.14224)
		(layer "In2.Cu")
		(net "M_D_DQS_DP<14>")
	)
	(segment
		(start 274.677124 -105.00106)
		(end 274.677124 -106.15803)
		(width 0.0889)
		(layer "In2.Cu")
		(net "M_D_DQS_DP<14>")
	)
	(segment
		(start 289.7632 -127.418846)
		(end 289.92068 -127.576326)
		(width 0.14224)
		(layer "In2.Cu")
		(net "M_D_DQS_DP<14>")
	)
	(segment
		(start 287.441132 -125.842522)
		(end 287.633156 -125.842522)
		(width 0.14224)
		(layer "In2.Cu")
		(net "M_D_DQS_DP<14>")
	)
	(segment
		(start 284.232096 -125.143768)
		(end 286.934402 -125.143768)
		(width 0.14224)
		(layer "In2.Cu")
		(net "M_D_DQS_DP<14>")
	)
	(segment
		(start 290.33216 -127.418846)
		(end 290.58616 -127.418846)
		(width 0.14224)
		(layer "In2.Cu")
		(net "M_D_DQS_DP<14>")
	)
	(segment
		(start 286.934402 -125.143768)
		(end 287.261554 -125.47092)
		(width 0.14224)
		(layer "In2.Cu")
		(net "M_D_DQS_DP<14>")
	)
	(segment
		(start 292.905688 -129.327148)
		(end 292.905688 -129.99212)
		(width 0.14224)
		(layer "In2.Cu")
		(net "M_D_DQS_DP<14>")
	)
	(segment
		(start 291.887656 -135.232394)
		(end 292.392608 -135.737346)
		(width 0.14224)
		(layer "In2.Cu")
		(net "M_D_DQS_DP<14>")
	)
	(segment
		(start 288.94024 -127.418846)
		(end 289.09772 -127.576326)
		(width 0.14224)
		(layer "In2.Cu")
		(net "M_D_DQS_DP<14>")
	)
	(segment
		(start 289.5092 -127.418846)
		(end 289.7632 -127.418846)
		(width 0.14224)
		(layer "In2.Cu")
		(net "M_D_DQS_DP<14>")
	)
	(segment
		(start 291.8206 -127.576326)
		(end 291.97808 -127.418846)
		(width 0.14224)
		(layer "In2.Cu")
		(net "M_D_DQS_DP<14>")
	)
	(segment
		(start 292.672008 -130.2258)
		(end 292.392608 -130.2258)
		(width 0.14224)
		(layer "In2.Cu")
		(net "M_D_DQS_DP<14>")
	)
	(segment
		(start 278.12619 -98.1964)
		(end 278.121364 -98.205036)
		(width 0.0889)
		(layer "In2.Cu")
		(net "M_D_DQS_DP<14>")
	)
	(segment
		(start 278.12619 -99.187)
		(end 278.121364 -99.195636)
		(width 0.0889)
		(layer "In2.Cu")
		(net "M_D_DQS_DP<14>")
	)
	(segment
		(start 287.261554 -125.47092)
		(end 287.261554 -125.662944)
		(width 0.14224)
		(layer "In2.Cu")
		(net "M_D_DQS_DP<14>")
	)
	(segment
		(start 289.35172 -127.576326)
		(end 289.5092 -127.418846)
		(width 0.14224)
		(layer "In2.Cu")
		(net "M_D_DQS_DP<14>")
	)
	(segment
		(start 291.40912 -127.418846)
		(end 291.5666 -127.576326)
		(width 0.14224)
		(layer "In2.Cu")
		(net "M_D_DQS_DP<14>")
	)
	(segment
		(start 291.887656 -130.641344)
		(end 291.887656 -135.232394)
		(width 0.14224)
		(layer "In2.Cu")
		(net "M_D_DQS_DP<14>")
	)
	(segment
		(start 276.32533 -103.352854)
		(end 274.677124 -105.00106)
		(width 0.0889)
		(layer "In2.Cu")
		(net "M_D_DQS_DP<14>")
	)
	(segment
		(start 292.748208 -129.169668)
		(end 292.905688 -129.327148)
		(width 0.14224)
		(layer "In2.Cu")
		(net "M_D_DQS_DP<14>")
	)
	(segment
		(start 287.86328 -126.807214)
		(end 288.474912 -127.418846)
		(width 0.14224)
		(layer "In2.Cu")
		(net "M_D_DQS_DP<14>")
	)
	(segment
		(start 290.99764 -127.576326)
		(end 291.15512 -127.418846)
		(width 0.14224)
		(layer "In2.Cu")
		(net "M_D_DQS_DP<14>")
	)
	(segment
		(start 277.795228 -100.385626)
		(end 277.790402 -100.38588)
		(width 0.0889)
		(layer "In2.Cu")
		(net "M_D_DQS_DP<14>")
	)
	(segment
		(start 291.97808 -127.418846)
		(end 292.25748 -127.418846)
		(width 0.14224)
		(layer "In2.Cu")
		(net "M_D_DQS_DP<14>")
	)
	(segment
		(start 289.92068 -127.576326)
		(end 290.17468 -127.576326)
		(width 0.14224)
		(layer "In2.Cu")
		(net "M_D_DQS_DP<14>")
	)
	(segment
		(start 289.09772 -127.576326)
		(end 289.35172 -127.576326)
		(width 0.14224)
		(layer "In2.Cu")
		(net "M_D_DQS_DP<14>")
	)
	(segment
		(start 292.905688 -128.758188)
		(end 292.748208 -128.915668)
		(width 0.14224)
		(layer "In2.Cu")
		(net "M_D_DQS_DP<14>")
	)
	(segment
		(start 278.633174 -96.518984)
		(end 278.480012 -96.938846)
		(width 0.0889)
		(layer "In2.Cu")
		(net "M_D_DQS_DP<14>")
	)
	(segment
		(start 278.121364 -99.786186)
		(end 278.12619 -99.794568)
		(width 0.0889)
		(layer "In2.Cu")
		(net "M_D_DQS_DP<14>")
	)
	(segment
		(start 290.17468 -127.576326)
		(end 290.33216 -127.418846)
		(width 0.14224)
		(layer "In2.Cu")
		(net "M_D_DQS_DP<14>")
	)
	(segment
		(start 277.790402 -100.38588)
		(end 277.752556 -100.38588)
		(width 0.0889)
		(layer "In2.Cu")
		(net "M_D_DQS_DP<14>")
	)
	(segment
		(start 290.74364 -127.576326)
		(end 290.99764 -127.576326)
		(width 0.14224)
		(layer "In2.Cu")
		(net "M_D_DQS_DP<14>")
	)
	(segment
		(start 278.121364 -98.205036)
		(end 278.115014 -98.215704)
		(width 0.0889)
		(layer "In2.Cu")
		(net "M_D_DQS_DP<14>")
	)
	(segment
		(start 287.261554 -125.662944)
		(end 287.441132 -125.842522)
		(width 0.14224)
		(layer "In2.Cu")
		(net "M_D_DQS_DP<14>")
	)
	(segment
		(start 292.905688 -128.067054)
		(end 292.905688 -128.758188)
		(width 0.14224)
		(layer "In2.Cu")
		(net "M_D_DQS_DP<14>")
	)
	(segment
		(start 274.637754 -106.1974)
		(end 274.637754 -106.219498)
		(width 0.0889)
		(layer "In2.Cu")
		(net "M_D_DQS_DP<14>")
	)
	(segment
		(start 274.677124 -106.15803)
		(end 274.637754 -106.1974)
		(width 0.0889)
		(layer "In2.Cu")
		(net "M_D_DQS_DP<14>")
	)
	(segment
		(start 292.3032 -130.2258)
		(end 291.887656 -130.641344)
		(width 0.14224)
		(layer "In2.Cu")
		(net "M_D_DQS_DP<14>")
	)
	(segment
		(start 287.86328 -126.072646)
		(end 287.86328 -126.807214)
		(width 0.14224)
		(layer "In2.Cu")
		(net "M_D_DQS_DP<14>")
	)
	(segment
		(start 276.32533 -102.305866)
		(end 276.32533 -103.352854)
		(width 0.0889)
		(layer "In2.Cu")
		(net "M_D_DQS_DP<14>")
	)
	(segment
		(start 277.262844 -100.681028)
		(end 276.32533 -102.305866)
		(width 0.0889)
		(layer "In2.Cu")
		(net "M_D_DQS_DP<14>")
	)
	(segment
		(start 278.121364 -99.195636)
		(end 278.115014 -99.206304)
		(width 0.0889)
		(layer "In2.Cu")
		(net "M_D_DQS_DP<14>")
	)
	(segment
		(start 292.25748 -127.418846)
		(end 292.905688 -128.067054)
		(width 0.14224)
		(layer "In2.Cu")
		(net "M_D_DQS_DP<14>")
	)
	(segment
		(start 290.58616 -127.418846)
		(end 290.74364 -127.576326)
		(width 0.14224)
		(layer "In2.Cu")
		(net "M_D_DQS_DP<14>")
	)
	(segment
		(start 287.633156 -125.842522)
		(end 287.86328 -126.072646)
		(width 0.14224)
		(layer "In2.Cu")
		(net "M_D_DQS_DP<14>")
	)
	(segment
		(start 291.15512 -127.418846)
		(end 291.40912 -127.418846)
		(width 0.14224)
		(layer "In2.Cu")
		(net "M_D_DQS_DP<14>")
	)
	(segment
		(start 274.637754 -106.219498)
		(end 274.637754 -115.549426)
		(width 0.14224)
		(layer "In2.Cu")
		(net "M_D_DQS_DP<14>")
	)
	(segment
		(start 292.392608 -130.2258)
		(end 292.3032 -130.2258)
		(width 0.14224)
		(layer "In2.Cu")
		(net "M_D_DQS_DP<14>")
	)
	(segment
		(start 288.474912 -127.418846)
		(end 288.94024 -127.418846)
		(width 0.14224)
		(layer "In2.Cu")
		(net "M_D_DQS_DP<14>")
	)
	(arc
		(start 278.121364 -97.804986)
		(mid 278.174834 -98.000049)
		(end 278.12619 -98.1964)
		(width 0.0889)
		(layer "In2.Cu")
		(net "M_D_DQS_DP<14>")
	)
	(arc
		(start 278.115014 -99.206304)
		(mid 278.042216 -99.497067)
		(end 278.121364 -99.786186)
		(width 0.0889)
		(layer "In2.Cu")
		(net "M_D_DQS_DP<14>")
	)
	(arc
		(start 278.121364 -98.795586)
		(mid 278.174834 -98.990649)
		(end 278.12619 -99.187)
		(width 0.0889)
		(layer "In2.Cu")
		(net "M_D_DQS_DP<14>")
	)
	(arc
		(start 278.12619 -99.794568)
		(mid 278.123818 -100.181389)
		(end 277.795228 -100.385626)
		(width 0.0889)
		(layer "In2.Cu")
		(net "M_D_DQS_DP<14>")
	)
	(arc
		(start 277.752556 -100.38588)
		(mid 277.469652 -100.470299)
		(end 277.262844 -100.681028)
		(width 0.0889)
		(layer "In2.Cu")
		(net "M_D_DQS_DP<14>")
	)
	(arc
		(start 278.480012 -96.938846)
		(mid 278.087196 -97.283512)
		(end 278.121364 -97.804986)
		(width 0.0889)
		(layer "In2.Cu")
		(net "M_D_DQS_DP<14>")
	)
	(arc
		(start 278.115014 -98.215704)
		(mid 278.042216 -98.506467)
		(end 278.121364 -98.795586)
		(width 0.0889)
		(layer "In2.Cu")
		(net "M_D_DQS_DP<14>")
	)
	(segment
		(start 274.1803 -113.7666)
		(end 274.2311 -113.8174)
		(width 0.1016)
		(layer "F.Cu")
		(net "M_D_DQS_DP<13>")
	)
	(segment
		(start 283.100272 -133.0706)
		(end 283.099764 -133.076442)
		(width 0.1651)
		(layer "F.Cu")
		(net "M_D_DQS_DP<13>")
	)
	(segment
		(start 276.02688 -117.2337)
		(end 276.02688 -117.5639)
		(width 0.1651)
		(layer "F.Cu")
		(net "M_D_DQS_DP<13>")
	)
	(segment
		(start 282.579064 -135.131302)
		(end 282.660598 -135.355584)
		(width 0.1651)
		(layer "F.Cu")
		(net "M_D_DQS_DP<13>")
	)
	(segment
		(start 283.311854 -130.2258)
		(end 283.04236 -130.2258)
		(width 0.1651)
		(layer "F.Cu")
		(net "M_D_DQS_DP<13>")
	)
	(segment
		(start 276.15388 -116.267738)
		(end 276.15388 -117.1067)
		(width 0.1651)
		(layer "F.Cu")
		(net "M_D_DQS_DP<13>")
	)
	(segment
		(start 279.235154 -122.560588)
		(end 279.235154 -122.740166)
		(width 0.1651)
		(layer "F.Cu")
		(net "M_D_DQS_DP<13>")
	)
	(segment
		(start 283.7815 -127.386842)
		(end 283.591 -127.577342)
		(width 0.1651)
		(layer "F.Cu")
		(net "M_D_DQS_DP<13>")
	)
	(segment
		(start 283.099764 -133.076442)
		(end 283.099764 -133.693408)
		(width 0.1651)
		(layer "F.Cu")
		(net "M_D_DQS_DP<13>")
	)
	(segment
		(start 279.648412 -122.973846)
		(end 283.7815 -127.106934)
		(width 0.1651)
		(layer "F.Cu")
		(net "M_D_DQS_DP<13>")
	)
	(segment
		(start 276.15388 -119.0879)
		(end 276.15388 -119.479314)
		(width 0.1651)
		(layer "F.Cu")
		(net "M_D_DQS_DP<13>")
	)
	(segment
		(start 274.073874 -105.147618)
		(end 274.073874 -106.484674)
		(width 0.0889)
		(layer "F.Cu")
		(net "M_D_DQS_DP<13>")
	)
	(segment
		(start 276.02688 -118.9609)
		(end 276.15388 -119.0879)
		(width 0.1651)
		(layer "F.Cu")
		(net "M_D_DQS_DP<13>")
	)
	(segment
		(start 276.15388 -119.479314)
		(end 279.235154 -122.560588)
		(width 0.1651)
		(layer "F.Cu")
		(net "M_D_DQS_DP<13>")
	)
	(segment
		(start 275.486114 -100.29952)
		(end 275.392388 -100.393246)
		(width 0.0889)
		(layer "F.Cu")
		(net "M_D_DQS_DP<13>")
	)
	(segment
		(start 283.591 -127.577342)
		(end 283.591 -128.403858)
		(width 0.1651)
		(layer "F.Cu")
		(net "M_D_DQS_DP<13>")
	)
	(segment
		(start 274.903184 -104.318308)
		(end 274.073874 -105.147618)
		(width 0.0889)
		(layer "F.Cu")
		(net "M_D_DQS_DP<13>")
	)
	(segment
		(start 274.2311 -114.344958)
		(end 276.15388 -116.267738)
		(width 0.1651)
		(layer "F.Cu")
		(net "M_D_DQS_DP<13>")
	)
	(segment
		(start 282.660598 -135.355584)
		(end 283.04236 -135.737346)
		(width 0.1651)
		(layer "F.Cu")
		(net "M_D_DQS_DP<13>")
	)
	(segment
		(start 273.972274 -106.586274)
		(end 273.972274 -113.012474)
		(width 0.1016)
		(layer "F.Cu")
		(net "M_D_DQS_DP<13>")
	)
	(segment
		(start 283.7815 -128.594358)
		(end 283.7815 -129.756154)
		(width 0.1651)
		(layer "F.Cu")
		(net "M_D_DQS_DP<13>")
	)
	(segment
		(start 276.02688 -118.6307)
		(end 276.02688 -118.9609)
		(width 0.1651)
		(layer "F.Cu")
		(net "M_D_DQS_DP<13>")
	)
	(segment
		(start 274.073874 -106.484674)
		(end 273.972274 -106.586274)
		(width 0.0889)
		(layer "F.Cu")
		(net "M_D_DQS_DP<13>")
	)
	(segment
		(start 276.15388 -117.1067)
		(end 276.02688 -117.2337)
		(width 0.1651)
		(layer "F.Cu")
		(net "M_D_DQS_DP<13>")
	)
	(segment
		(start 274.903184 -102.92842)
		(end 274.903184 -104.318308)
		(width 0.0889)
		(layer "F.Cu")
		(net "M_D_DQS_DP<13>")
	)
	(segment
		(start 276.02688 -117.5639)
		(end 276.15388 -117.6909)
		(width 0.1651)
		(layer "F.Cu")
		(net "M_D_DQS_DP<13>")
	)
	(segment
		(start 279.235154 -122.740166)
		(end 279.468834 -122.973846)
		(width 0.1651)
		(layer "F.Cu")
		(net "M_D_DQS_DP<13>")
	)
	(segment
		(start 283.099764 -133.693408)
		(end 282.663646 -134.129526)
		(width 0.1651)
		(layer "F.Cu")
		(net "M_D_DQS_DP<13>")
	)
	(segment
		(start 274.967954 -102.252018)
		(end 274.974304 -102.262686)
		(width 0.0889)
		(layer "F.Cu")
		(net "M_D_DQS_DP<13>")
	)
	(segment
		(start 274.974304 -101.272086)
		(end 274.97913 -101.280722)
		(width 0.0889)
		(layer "F.Cu")
		(net "M_D_DQS_DP<13>")
	)
	(segment
		(start 273.972274 -113.012474)
		(end 274.1803 -113.2205)
		(width 0.1016)
		(layer "F.Cu")
		(net "M_D_DQS_DP<13>")
	)
	(segment
		(start 274.1803 -113.2205)
		(end 274.1803 -113.7666)
		(width 0.1016)
		(layer "F.Cu")
		(net "M_D_DQS_DP<13>")
	)
	(segment
		(start 282.6004 -134.26694)
		(end 282.579064 -134.313168)
		(width 0.1651)
		(layer "F.Cu")
		(net "M_D_DQS_DP<13>")
	)
	(segment
		(start 282.663646 -134.129526)
		(end 282.6004 -134.26694)
		(width 0.1651)
		(layer "F.Cu")
		(net "M_D_DQS_DP<13>")
	)
	(segment
		(start 274.2311 -113.8174)
		(end 274.2311 -114.344958)
		(width 0.1651)
		(layer "F.Cu")
		(net "M_D_DQS_DP<13>")
	)
	(segment
		(start 276.15388 -117.6909)
		(end 276.15388 -118.5037)
		(width 0.1651)
		(layer "F.Cu")
		(net "M_D_DQS_DP<13>")
	)
	(segment
		(start 276.15388 -118.5037)
		(end 276.02688 -118.6307)
		(width 0.1651)
		(layer "F.Cu")
		(net "M_D_DQS_DP<13>")
	)
	(segment
		(start 282.579064 -134.313168)
		(end 282.579064 -135.131302)
		(width 0.1651)
		(layer "F.Cu")
		(net "M_D_DQS_DP<13>")
	)
	(segment
		(start 275.486114 -99.986338)
		(end 275.486114 -100.29952)
		(width 0.0889)
		(layer "F.Cu")
		(net "M_D_DQS_DP<13>")
	)
	(segment
		(start 279.468834 -122.973846)
		(end 279.648412 -122.973846)
		(width 0.1651)
		(layer "F.Cu")
		(net "M_D_DQS_DP<13>")
	)
	(segment
		(start 283.7815 -129.756154)
		(end 283.311854 -130.2258)
		(width 0.1651)
		(layer "F.Cu")
		(net "M_D_DQS_DP<13>")
	)
	(segment
		(start 274.974304 -102.262686)
		(end 274.97913 -102.271322)
		(width 0.0889)
		(layer "F.Cu")
		(net "M_D_DQS_DP<13>")
	)
	(segment
		(start 283.591 -128.403858)
		(end 283.7815 -128.594358)
		(width 0.1651)
		(layer "F.Cu")
		(net "M_D_DQS_DP<13>")
	)
	(segment
		(start 283.7815 -127.106934)
		(end 283.7815 -127.386842)
		(width 0.1651)
		(layer "F.Cu")
		(net "M_D_DQS_DP<13>")
	)
	(via
		(at 283.04236 -135.737346)
		(size 0.508)
		(drill 0.254)
		(layers "F.Cu" "B.Cu")
		(net "M_D_DQS_DP<13>")
	)
	(via
		(at 283.04236 -130.2258)
		(size 0.508)
		(drill 0.254)
		(layers "F.Cu" "B.Cu")
		(net "M_D_DQS_DP<13>")
	)
	(arc
		(start 274.97913 -102.271322)
		(mid 275.027885 -102.467674)
		(end 274.974304 -102.662736)
		(width 0.0889)
		(layer "F.Cu")
		(net "M_D_DQS_DP<13>")
	)
	(arc
		(start 274.974304 -101.672136)
		(mid 274.895082 -101.961254)
		(end 274.967954 -102.252018)
		(width 0.0889)
		(layer "F.Cu")
		(net "M_D_DQS_DP<13>")
	)
	(arc
		(start 275.392388 -100.393246)
		(mid 274.952497 -100.722839)
		(end 274.974304 -101.272086)
		(width 0.0889)
		(layer "F.Cu")
		(net "M_D_DQS_DP<13>")
	)
	(arc
		(start 274.974304 -102.662736)
		(mid 274.921238 -102.790892)
		(end 274.903184 -102.92842)
		(width 0.0889)
		(layer "F.Cu")
		(net "M_D_DQS_DP<13>")
	)
	(arc
		(start 274.97913 -101.280722)
		(mid 275.027885 -101.477074)
		(end 274.974304 -101.672136)
		(width 0.0889)
		(layer "F.Cu")
		(net "M_D_DQS_DP<13>")
	)
	(segment
		(start 283.099764 -132.875782)
		(end 283.099764 -132.258054)
		(width 0.1651)
		(layer "B.Cu")
		(net "M_D_DQS_DP<13>")
	)
	(segment
		(start 283.099764 -132.258054)
		(end 282.64358 -131.80187)
		(width 0.1651)
		(layer "B.Cu")
		(net "M_D_DQS_DP<13>")
	)
	(segment
		(start 283.100272 -132.876036)
		(end 283.099764 -132.875782)
		(width 0.1651)
		(layer "B.Cu")
		(net "M_D_DQS_DP<13>")
	)
	(segment
		(start 282.65374 -130.61442)
		(end 283.04236 -130.2258)
		(width 0.1651)
		(layer "B.Cu")
		(net "M_D_DQS_DP<13>")
	)
	(segment
		(start 282.566364 -131.669536)
		(end 282.566364 -130.773932)
		(width 0.1651)
		(layer "B.Cu")
		(net "M_D_DQS_DP<13>")
	)
	(segment
		(start 282.64358 -131.80187)
		(end 282.566364 -131.669536)
		(width 0.1651)
		(layer "B.Cu")
		(net "M_D_DQS_DP<13>")
	)
	(segment
		(start 282.566364 -130.773932)
		(end 282.65374 -130.61442)
		(width 0.1651)
		(layer "B.Cu")
		(net "M_D_DQS_DP<13>")
	)
	(segment
		(start 283.04236 -135.737346)
		(end 282.537662 -135.232648)
		(width 0.14224)
		(layer "In2.Cu")
		(net "M_D_DQS_DP<13>")
	)
	(segment
		(start 282.537662 -130.644138)
		(end 282.956 -130.2258)
		(width 0.14224)
		(layer "In2.Cu")
		(net "M_D_DQS_DP<13>")
	)
	(segment
		(start 282.537662 -135.232648)
		(end 282.537662 -130.644138)
		(width 0.14224)
		(layer "In2.Cu")
		(net "M_D_DQS_DP<13>")
	)
	(segment
		(start 282.956 -130.2258)
		(end 283.04236 -130.2258)
		(width 0.14224)
		(layer "In2.Cu")
		(net "M_D_DQS_DP<13>")
	)
	(segment
		(start 227.329238 -135.131302)
		(end 227.410772 -135.355584)
		(width 0.1651)
		(layer "F.Cu")
		(net "M_D_DQS_DP<12>")
	)
	(segment
		(start 227.849938 -133.076442)
		(end 227.849938 -133.693154)
		(width 0.1651)
		(layer "F.Cu")
		(net "M_D_DQS_DP<12>")
	)
	(segment
		(start 227.849938 -133.693154)
		(end 227.41382 -134.129272)
		(width 0.1651)
		(layer "F.Cu")
		(net "M_D_DQS_DP<12>")
	)
	(segment
		(start 227.329238 -134.313168)
		(end 227.329238 -135.131302)
		(width 0.1651)
		(layer "F.Cu")
		(net "M_D_DQS_DP<12>")
	)
	(segment
		(start 227.850446 -133.0706)
		(end 227.849938 -133.076442)
		(width 0.1651)
		(layer "F.Cu")
		(net "M_D_DQS_DP<12>")
	)
	(segment
		(start 227.41382 -134.129272)
		(end 227.350574 -134.26694)
		(width 0.1651)
		(layer "F.Cu")
		(net "M_D_DQS_DP<12>")
	)
	(segment
		(start 227.350574 -134.26694)
		(end 227.329238 -134.313168)
		(width 0.1651)
		(layer "F.Cu")
		(net "M_D_DQS_DP<12>")
	)
	(segment
		(start 227.410772 -135.355584)
		(end 227.792534 -135.737346)
		(width 0.1651)
		(layer "F.Cu")
		(net "M_D_DQS_DP<12>")
	)
	(segment
		(start 242.193318 -94.718886)
		(end 241.621818 -94.718886)
		(width 0.1651)
		(layer "F.Cu")
		(net "M_D_DQS_DP<12>")
	)
	(via
		(at 227.792534 -130.2258)
		(size 0.508)
		(drill 0.254)
		(layers "F.Cu" "B.Cu")
		(net "M_D_DQS_DP<12>")
	)
	(via
		(at 241.621818 -94.718886)
		(size 0.508)
		(drill 0.254)
		(layers "F.Cu" "B.Cu")
		(net "M_D_DQS_DP<12>")
	)
	(via
		(at 227.792534 -135.737346)
		(size 0.508)
		(drill 0.254)
		(layers "F.Cu" "B.Cu")
		(net "M_D_DQS_DP<12>")
	)
	(segment
		(start 227.849938 -132.875782)
		(end 227.849938 -132.258054)
		(width 0.1651)
		(layer "B.Cu")
		(net "M_D_DQS_DP<12>")
	)
	(segment
		(start 227.403914 -130.61442)
		(end 227.792534 -130.2258)
		(width 0.1651)
		(layer "B.Cu")
		(net "M_D_DQS_DP<12>")
	)
	(segment
		(start 227.849938 -132.258054)
		(end 227.393754 -131.80187)
		(width 0.1651)
		(layer "B.Cu")
		(net "M_D_DQS_DP<12>")
	)
	(segment
		(start 227.393754 -131.80187)
		(end 227.316538 -131.669536)
		(width 0.1651)
		(layer "B.Cu")
		(net "M_D_DQS_DP<12>")
	)
	(segment
		(start 227.316538 -130.773932)
		(end 227.403914 -130.61442)
		(width 0.1651)
		(layer "B.Cu")
		(net "M_D_DQS_DP<12>")
	)
	(segment
		(start 227.850446 -132.876036)
		(end 227.849938 -132.875782)
		(width 0.1651)
		(layer "B.Cu")
		(net "M_D_DQS_DP<12>")
	)
	(segment
		(start 227.316538 -131.669536)
		(end 227.316538 -130.773932)
		(width 0.1651)
		(layer "B.Cu")
		(net "M_D_DQS_DP<12>")
	)
	(segment
		(start 241.621818 -95.05696)
		(end 241.55654 -95.122238)
		(width 0.0889)
		(layer "In2.Cu")
		(net "M_D_DQS_DP<12>")
	)
	(segment
		(start 234.185968 -101.454458)
		(end 233.656124 -101.984302)
		(width 0.0889)
		(layer "In2.Cu")
		(net "M_D_DQS_DP<12>")
	)
	(segment
		(start 233.364786 -102.826312)
		(end 233.308906 -102.826312)
		(width 0.0889)
		(layer "In2.Cu")
		(net "M_D_DQS_DP<12>")
	)
	(segment
		(start 241.110008 -96.404938)
		(end 241.103658 -96.415606)
		(width 0.0889)
		(layer "In2.Cu")
		(net "M_D_DQS_DP<12>")
	)
	(segment
		(start 235.623354 -100.567236)
		(end 235.599224 -100.567236)
		(width 0.0889)
		(layer "In2.Cu")
		(net "M_D_DQS_DP<12>")
	)
	(segment
		(start 233.656124 -102.534974)
		(end 233.364786 -102.826312)
		(width 0.0889)
		(layer "In2.Cu")
		(net "M_D_DQS_DP<12>")
	)
	(segment
		(start 228.0412 -130.2258)
		(end 227.792534 -130.2258)
		(width 0.14224)
		(layer "In2.Cu")
		(net "M_D_DQS_DP<12>")
	)
	(segment
		(start 241.114834 -96.396302)
		(end 241.110008 -96.404938)
		(width 0.0889)
		(layer "In2.Cu")
		(net "M_D_DQS_DP<12>")
	)
	(segment
		(start 239.919764 -98.090736)
		(end 239.886998 -98.090736)
		(width 0.0889)
		(layer "In2.Cu")
		(net "M_D_DQS_DP<12>")
	)
	(segment
		(start 227.287582 -135.232394)
		(end 227.792534 -135.737346)
		(width 0.14224)
		(layer "In2.Cu")
		(net "M_D_DQS_DP<12>")
	)
	(segment
		(start 237.347252 -99.576636)
		(end 237.311438 -99.576636)
		(width 0.0889)
		(layer "In2.Cu")
		(net "M_D_DQS_DP<12>")
	)
	(segment
		(start 228.126544 -128.884426)
		(end 228.126544 -129.138426)
		(width 0.14224)
		(layer "In2.Cu")
		(net "M_D_DQS_DP<12>")
	)
	(segment
		(start 227.719382 -130.2258)
		(end 227.287582 -130.6576)
		(width 0.14224)
		(layer "In2.Cu")
		(net "M_D_DQS_DP<12>")
	)
	(segment
		(start 228.284024 -129.982976)
		(end 228.0412 -130.2258)
		(width 0.14224)
		(layer "In2.Cu")
		(net "M_D_DQS_DP<12>")
	)
	(segment
		(start 238.202724 -99.081336)
		(end 238.174784 -99.081336)
		(width 0.0889)
		(layer "In2.Cu")
		(net "M_D_DQS_DP<12>")
	)
	(segment
		(start 227.792534 -130.2258)
		(end 227.719382 -130.2258)
		(width 0.14224)
		(layer "In2.Cu")
		(net "M_D_DQS_DP<12>")
	)
	(segment
		(start 230.545386 -105.589832)
		(end 230.545386 -108.99394)
		(width 0.14224)
		(layer "In2.Cu")
		(net "M_D_DQS_DP<12>")
	)
	(segment
		(start 228.284024 -111.255302)
		(end 228.284024 -127.927608)
		(width 0.14224)
		(layer "In2.Cu")
		(net "M_D_DQS_DP<12>")
	)
	(segment
		(start 239.057434 -98.58629)
		(end 239.024668 -98.58629)
		(width 0.0889)
		(layer "In2.Cu")
		(net "M_D_DQS_DP<12>")
	)
	(segment
		(start 230.545386 -108.99394)
		(end 228.284024 -111.255302)
		(width 0.14224)
		(layer "In2.Cu")
		(net "M_D_DQS_DP<12>")
	)
	(segment
		(start 233.308906 -102.826312)
		(end 233.293158 -102.84206)
		(width 0.0889)
		(layer "In2.Cu")
		(net "M_D_DQS_DP<12>")
	)
	(segment
		(start 241.621818 -94.718886)
		(end 241.621818 -95.05696)
		(width 0.0889)
		(layer "In2.Cu")
		(net "M_D_DQS_DP<12>")
	)
	(segment
		(start 240.774474 -97.59569)
		(end 240.741708 -97.59569)
		(width 0.0889)
		(layer "In2.Cu")
		(net "M_D_DQS_DP<12>")
	)
	(segment
		(start 228.126544 -129.138426)
		(end 228.284024 -129.295906)
		(width 0.14224)
		(layer "In2.Cu")
		(net "M_D_DQS_DP<12>")
	)
	(segment
		(start 228.284024 -128.726946)
		(end 228.126544 -128.884426)
		(width 0.14224)
		(layer "In2.Cu")
		(net "M_D_DQS_DP<12>")
	)
	(segment
		(start 228.284024 -129.295906)
		(end 228.284024 -129.982976)
		(width 0.14224)
		(layer "In2.Cu")
		(net "M_D_DQS_DP<12>")
	)
	(segment
		(start 228.284024 -127.927608)
		(end 228.150166 -128.061466)
		(width 0.14224)
		(layer "In2.Cu")
		(net "M_D_DQS_DP<12>")
	)
	(segment
		(start 234.241848 -101.357938)
		(end 234.185968 -101.454458)
		(width 0.0889)
		(layer "In2.Cu")
		(net "M_D_DQS_DP<12>")
	)
	(segment
		(start 228.150166 -128.315466)
		(end 228.284024 -128.449324)
		(width 0.14224)
		(layer "In2.Cu")
		(net "M_D_DQS_DP<12>")
	)
	(segment
		(start 233.293158 -102.84206)
		(end 230.545386 -105.589832)
		(width 0.14224)
		(layer "In2.Cu")
		(net "M_D_DQS_DP<12>")
	)
	(segment
		(start 234.768644 -101.062536)
		(end 234.735878 -101.062536)
		(width 0.0889)
		(layer "In2.Cu")
		(net "M_D_DQS_DP<12>")
	)
	(segment
		(start 236.488732 -100.071936)
		(end 236.449108 -100.071936)
		(width 0.0889)
		(layer "In2.Cu")
		(net "M_D_DQS_DP<12>")
	)
	(segment
		(start 227.287582 -130.6576)
		(end 227.287582 -135.232394)
		(width 0.14224)
		(layer "In2.Cu")
		(net "M_D_DQS_DP<12>")
	)
	(segment
		(start 228.150166 -128.061466)
		(end 228.150166 -128.315466)
		(width 0.14224)
		(layer "In2.Cu")
		(net "M_D_DQS_DP<12>")
	)
	(segment
		(start 228.284024 -128.449324)
		(end 228.284024 -128.726946)
		(width 0.14224)
		(layer "In2.Cu")
		(net "M_D_DQS_DP<12>")
	)
	(segment
		(start 233.656124 -101.984302)
		(end 233.656124 -102.534974)
		(width 0.0889)
		(layer "In2.Cu")
		(net "M_D_DQS_DP<12>")
	)
	(arc
		(start 241.110008 -96.004888)
		(mid 241.163478 -96.199951)
		(end 241.114834 -96.396302)
		(width 0.0889)
		(layer "In2.Cu")
		(net "M_D_DQS_DP<12>")
	)
	(arc
		(start 240.251488 -97.890838)
		(mid 240.111409 -98.033574)
		(end 239.919764 -98.090736)
		(width 0.0889)
		(layer "In2.Cu")
		(net "M_D_DQS_DP<12>")
	)
	(arc
		(start 239.024668 -98.58629)
		(mid 238.741451 -98.670571)
		(end 238.534448 -98.881438)
		(width 0.0889)
		(layer "In2.Cu")
		(net "M_D_DQS_DP<12>")
	)
	(arc
		(start 241.103658 -96.415606)
		(mid 241.03086 -96.706369)
		(end 241.110008 -96.995488)
		(width 0.0889)
		(layer "In2.Cu")
		(net "M_D_DQS_DP<12>")
	)
	(arc
		(start 235.599224 -100.567236)
		(mid 235.311079 -100.649555)
		(end 235.100368 -100.862638)
		(width 0.0889)
		(layer "In2.Cu")
		(net "M_D_DQS_DP<12>")
	)
	(arc
		(start 241.110008 -96.995488)
		(mid 241.112756 -97.390955)
		(end 240.774474 -97.59569)
		(width 0.0889)
		(layer "In2.Cu")
		(net "M_D_DQS_DP<12>")
	)
	(arc
		(start 236.449108 -100.071936)
		(mid 236.165891 -100.156217)
		(end 235.958888 -100.367084)
		(width 0.0889)
		(layer "In2.Cu")
		(net "M_D_DQS_DP<12>")
	)
	(arc
		(start 238.534448 -98.881438)
		(mid 238.394369 -99.024174)
		(end 238.202724 -99.081336)
		(width 0.0889)
		(layer "In2.Cu")
		(net "M_D_DQS_DP<12>")
	)
	(arc
		(start 239.886998 -98.090736)
		(mid 239.601574 -98.174203)
		(end 239.392968 -98.386138)
		(width 0.0889)
		(layer "In2.Cu")
		(net "M_D_DQS_DP<12>")
	)
	(arc
		(start 240.741708 -97.59569)
		(mid 240.458491 -97.679971)
		(end 240.251488 -97.890838)
		(width 0.0889)
		(layer "In2.Cu")
		(net "M_D_DQS_DP<12>")
	)
	(arc
		(start 234.735878 -101.062536)
		(mid 234.450454 -101.146003)
		(end 234.241848 -101.357938)
		(width 0.0889)
		(layer "In2.Cu")
		(net "M_D_DQS_DP<12>")
	)
	(arc
		(start 235.100368 -100.862638)
		(mid 234.960289 -101.005374)
		(end 234.768644 -101.062536)
		(width 0.0889)
		(layer "In2.Cu")
		(net "M_D_DQS_DP<12>")
	)
	(arc
		(start 238.174784 -99.081336)
		(mid 237.886639 -99.163655)
		(end 237.675928 -99.376738)
		(width 0.0889)
		(layer "In2.Cu")
		(net "M_D_DQS_DP<12>")
	)
	(arc
		(start 239.392968 -98.386138)
		(mid 239.251285 -98.529942)
		(end 239.057434 -98.58629)
		(width 0.0889)
		(layer "In2.Cu")
		(net "M_D_DQS_DP<12>")
	)
	(arc
		(start 235.958888 -100.367084)
		(mid 235.817205 -100.510888)
		(end 235.623354 -100.567236)
		(width 0.0889)
		(layer "In2.Cu")
		(net "M_D_DQS_DP<12>")
	)
	(arc
		(start 237.311438 -99.576636)
		(mid 237.026014 -99.660103)
		(end 236.817408 -99.872038)
		(width 0.0889)
		(layer "In2.Cu")
		(net "M_D_DQS_DP<12>")
	)
	(arc
		(start 236.817408 -99.872038)
		(mid 236.678664 -100.014071)
		(end 236.488732 -100.071936)
		(width 0.0889)
		(layer "In2.Cu")
		(net "M_D_DQS_DP<12>")
	)
	(arc
		(start 241.55654 -95.122238)
		(mid 241.094571 -95.44278)
		(end 241.110008 -96.004888)
		(width 0.0889)
		(layer "In2.Cu")
		(net "M_D_DQS_DP<12>")
	)
	(arc
		(start 237.675928 -99.376738)
		(mid 237.537184 -99.518771)
		(end 237.347252 -99.576636)
		(width 0.0889)
		(layer "In2.Cu")
		(net "M_D_DQS_DP<12>")
	)
	(segment
		(start 218.060778 -135.355584)
		(end 218.44254 -135.737346)
		(width 0.1651)
		(layer "F.Cu")
		(net "M_D_DQS_DP<11>")
	)
	(segment
		(start 217.979244 -135.131302)
		(end 218.060778 -135.355584)
		(width 0.1651)
		(layer "F.Cu")
		(net "M_D_DQS_DP<11>")
	)
	(segment
		(start 218.500452 -133.0706)
		(end 218.499944 -133.076442)
		(width 0.1651)
		(layer "F.Cu")
		(net "M_D_DQS_DP<11>")
	)
	(segment
		(start 218.00058 -134.26694)
		(end 217.979244 -134.313168)
		(width 0.1651)
		(layer "F.Cu")
		(net "M_D_DQS_DP<11>")
	)
	(segment
		(start 217.979244 -134.313168)
		(end 217.979244 -135.131302)
		(width 0.1651)
		(layer "F.Cu")
		(net "M_D_DQS_DP<11>")
	)
	(segment
		(start 238.759238 -95.709486)
		(end 238.187738 -95.709486)
		(width 0.1651)
		(layer "F.Cu")
		(net "M_D_DQS_DP<11>")
	)
	(segment
		(start 218.499944 -133.693154)
		(end 218.063826 -134.129272)
		(width 0.1651)
		(layer "F.Cu")
		(net "M_D_DQS_DP<11>")
	)
	(segment
		(start 218.063826 -134.129272)
		(end 218.00058 -134.26694)
		(width 0.1651)
		(layer "F.Cu")
		(net "M_D_DQS_DP<11>")
	)
	(segment
		(start 218.499944 -133.076442)
		(end 218.499944 -133.693154)
		(width 0.1651)
		(layer "F.Cu")
		(net "M_D_DQS_DP<11>")
	)
	(via
		(at 238.187738 -95.709486)
		(size 0.508)
		(drill 0.254)
		(layers "F.Cu" "B.Cu")
		(net "M_D_DQS_DP<11>")
	)
	(via
		(at 218.44254 -135.737346)
		(size 0.508)
		(drill 0.254)
		(layers "F.Cu" "B.Cu")
		(net "M_D_DQS_DP<11>")
	)
	(via
		(at 218.44254 -130.2258)
		(size 0.508)
		(drill 0.254)
		(layers "F.Cu" "B.Cu")
		(net "M_D_DQS_DP<11>")
	)
	(segment
		(start 218.05392 -130.61442)
		(end 218.44254 -130.2258)
		(width 0.1651)
		(layer "B.Cu")
		(net "M_D_DQS_DP<11>")
	)
	(segment
		(start 218.499944 -132.258054)
		(end 218.04376 -131.80187)
		(width 0.1651)
		(layer "B.Cu")
		(net "M_D_DQS_DP<11>")
	)
	(segment
		(start 218.500452 -132.876036)
		(end 218.499944 -132.875782)
		(width 0.1651)
		(layer "B.Cu")
		(net "M_D_DQS_DP<11>")
	)
	(segment
		(start 218.04376 -131.80187)
		(end 217.966544 -131.669536)
		(width 0.1651)
		(layer "B.Cu")
		(net "M_D_DQS_DP<11>")
	)
	(segment
		(start 218.499944 -132.875782)
		(end 218.499944 -132.258054)
		(width 0.1651)
		(layer "B.Cu")
		(net "M_D_DQS_DP<11>")
	)
	(segment
		(start 217.966544 -130.773932)
		(end 218.05392 -130.61442)
		(width 0.1651)
		(layer "B.Cu")
		(net "M_D_DQS_DP<11>")
	)
	(segment
		(start 217.966544 -131.669536)
		(end 217.966544 -130.773932)
		(width 0.1651)
		(layer "B.Cu")
		(net "M_D_DQS_DP<11>")
	)
	(segment
		(start 217.55608 -127.853948)
		(end 217.55608 -116.965222)
		(width 0.14224)
		(layer "In2.Cu")
		(net "M_D_DQS_DP<11>")
	)
	(segment
		(start 216.69248 -112.77981)
		(end 216.59088 -112.67821)
		(width 0.14224)
		(layer "In2.Cu")
		(net "M_D_DQS_DP<11>")
	)
	(segment
		(start 222.46209 -102.14737)
		(end 230.426006 -94.183454)
		(width 0.14224)
		(layer "In2.Cu")
		(net "M_D_DQS_DP<11>")
	)
	(segment
		(start 237.318042 -94.623636)
		(end 237.342172 -94.623636)
		(width 0.0889)
		(layer "In2.Cu")
		(net "M_D_DQS_DP<11>")
	)
	(segment
		(start 216.69248 -113.865914)
		(end 216.69248 -112.77981)
		(width 0.14224)
		(layer "In2.Cu")
		(net "M_D_DQS_DP<11>")
	)
	(segment
		(start 234.364022 -93.03385)
		(end 234.467908 -93.137736)
		(width 0.0889)
		(layer "In2.Cu")
		(net "M_D_DQS_DP<11>")
	)
	(segment
		(start 218.72194 -130.2258)
		(end 218.95562 -129.99212)
		(width 0.14224)
		(layer "In2.Cu")
		(net "M_D_DQS_DP<11>")
	)
	(segment
		(start 232.696004 -93.03385)
		(end 234.364022 -93.03385)
		(width 0.0889)
		(layer "In2.Cu")
		(net "M_D_DQS_DP<11>")
	)
	(segment
		(start 216.59088 -112.67821)
		(end 216.59088 -112.21339)
		(width 0.14224)
		(layer "In2.Cu")
		(net "M_D_DQS_DP<11>")
	)
	(segment
		(start 216.69248 -110.324392)
		(end 222.46209 -104.554782)
		(width 0.14224)
		(layer "In2.Cu")
		(net "M_D_DQS_DP<11>")
	)
	(segment
		(start 217.55608 -116.965222)
		(end 217.070432 -116.479574)
		(width 0.14224)
		(layer "In2.Cu")
		(net "M_D_DQS_DP<11>")
	)
	(segment
		(start 234.467908 -93.137736)
		(end 234.766358 -93.137736)
		(width 0.0889)
		(layer "In2.Cu")
		(net "M_D_DQS_DP<11>")
	)
	(segment
		(start 230.497634 -94.167706)
		(end 231.055926 -93.609414)
		(width 0.0889)
		(layer "In2.Cu")
		(net "M_D_DQS_DP<11>")
	)
	(segment
		(start 222.46209 -104.554782)
		(end 222.46209 -102.14737)
		(width 0.14224)
		(layer "In2.Cu")
		(net "M_D_DQS_DP<11>")
	)
	(segment
		(start 218.95562 -129.253488)
		(end 217.55608 -127.853948)
		(width 0.14224)
		(layer "In2.Cu")
		(net "M_D_DQS_DP<11>")
	)
	(segment
		(start 216.59088 -112.21339)
		(end 216.69248 -112.11179)
		(width 0.14224)
		(layer "In2.Cu")
		(net "M_D_DQS_DP<11>")
	)
	(segment
		(start 218.44254 -135.737346)
		(end 217.937588 -135.232394)
		(width 0.14224)
		(layer "In2.Cu")
		(net "M_D_DQS_DP<11>")
	)
	(segment
		(start 230.426006 -94.183454)
		(end 230.441754 -94.167706)
		(width 0.0889)
		(layer "In2.Cu")
		(net "M_D_DQS_DP<11>")
	)
	(segment
		(start 218.369388 -130.2258)
		(end 218.44254 -130.2258)
		(width 0.14224)
		(layer "In2.Cu")
		(net "M_D_DQS_DP<11>")
	)
	(segment
		(start 237.894622 -95.540576)
		(end 238.187738 -95.709486)
		(width 0.0889)
		(layer "In2.Cu")
		(net "M_D_DQS_DP<11>")
	)
	(segment
		(start 217.070432 -116.479574)
		(end 217.070432 -115.78971)
		(width 0.14224)
		(layer "In2.Cu")
		(net "M_D_DQS_DP<11>")
	)
	(segment
		(start 232.12044 -93.609414)
		(end 232.696004 -93.03385)
		(width 0.0889)
		(layer "In2.Cu")
		(net "M_D_DQS_DP<11>")
	)
	(segment
		(start 217.504518 -114.677952)
		(end 216.69248 -113.865914)
		(width 0.14224)
		(layer "In2.Cu")
		(net "M_D_DQS_DP<11>")
	)
	(segment
		(start 236.452664 -94.128336)
		(end 236.492288 -94.128336)
		(width 0.0889)
		(layer "In2.Cu")
		(net "M_D_DQS_DP<11>")
	)
	(segment
		(start 217.504518 -115.355624)
		(end 217.504518 -114.677952)
		(width 0.14224)
		(layer "In2.Cu")
		(net "M_D_DQS_DP<11>")
	)
	(segment
		(start 217.937588 -135.232394)
		(end 217.937588 -130.6576)
		(width 0.14224)
		(layer "In2.Cu")
		(net "M_D_DQS_DP<11>")
	)
	(segment
		(start 218.95562 -129.99212)
		(end 218.95562 -129.253488)
		(width 0.14224)
		(layer "In2.Cu")
		(net "M_D_DQS_DP<11>")
	)
	(segment
		(start 230.441754 -94.167706)
		(end 230.497634 -94.167706)
		(width 0.0889)
		(layer "In2.Cu")
		(net "M_D_DQS_DP<11>")
	)
	(segment
		(start 231.055926 -93.609414)
		(end 232.12044 -93.609414)
		(width 0.0889)
		(layer "In2.Cu")
		(net "M_D_DQS_DP<11>")
	)
	(segment
		(start 217.070432 -115.78971)
		(end 217.504518 -115.355624)
		(width 0.14224)
		(layer "In2.Cu")
		(net "M_D_DQS_DP<11>")
	)
	(segment
		(start 216.69248 -112.11179)
		(end 216.69248 -110.324392)
		(width 0.14224)
		(layer "In2.Cu")
		(net "M_D_DQS_DP<11>")
	)
	(segment
		(start 235.594144 -93.633036)
		(end 235.629958 -93.633036)
		(width 0.0889)
		(layer "In2.Cu")
		(net "M_D_DQS_DP<11>")
	)
	(segment
		(start 218.44254 -130.2258)
		(end 218.72194 -130.2258)
		(width 0.14224)
		(layer "In2.Cu")
		(net "M_D_DQS_DP<11>")
	)
	(segment
		(start 217.937588 -130.6576)
		(end 218.369388 -130.2258)
		(width 0.14224)
		(layer "In2.Cu")
		(net "M_D_DQS_DP<11>")
	)
	(segment
		(start 237.870746 -95.451422)
		(end 237.894622 -95.540576)
		(width 0.0889)
		(layer "In2.Cu")
		(net "M_D_DQS_DP<11>")
	)
	(arc
		(start 236.123988 -93.928438)
		(mid 236.262732 -94.070471)
		(end 236.452664 -94.128336)
		(width 0.0889)
		(layer "In2.Cu")
		(net "M_D_DQS_DP<11>")
	)
	(arc
		(start 236.492288 -94.128336)
		(mid 236.775505 -94.212617)
		(end 236.982508 -94.423484)
		(width 0.0889)
		(layer "In2.Cu")
		(net "M_D_DQS_DP<11>")
	)
	(arc
		(start 235.265468 -93.433138)
		(mid 235.404212 -93.575171)
		(end 235.594144 -93.633036)
		(width 0.0889)
		(layer "In2.Cu")
		(net "M_D_DQS_DP<11>")
	)
	(arc
		(start 235.629958 -93.633036)
		(mid 235.915382 -93.716503)
		(end 236.123988 -93.928438)
		(width 0.0889)
		(layer "In2.Cu")
		(net "M_D_DQS_DP<11>")
	)
	(arc
		(start 234.766358 -93.137736)
		(mid 235.054645 -93.219995)
		(end 235.265468 -93.433138)
		(width 0.0889)
		(layer "In2.Cu")
		(net "M_D_DQS_DP<11>")
	)
	(arc
		(start 236.982508 -94.423484)
		(mid 237.124191 -94.567288)
		(end 237.318042 -94.623636)
		(width 0.0889)
		(layer "In2.Cu")
		(net "M_D_DQS_DP<11>")
	)
	(arc
		(start 237.342172 -94.623636)
		(mid 237.827315 -94.896451)
		(end 237.870746 -95.451422)
		(width 0.0889)
		(layer "In2.Cu")
		(net "M_D_DQS_DP<11>")
	)
	(segment
		(start 234.061 -94.17685)
		(end 233.704892 -94.135956)
		(width 0.0889)
		(layer "F.Cu")
		(net "M_D_DQS_DP<10>")
	)
	(segment
		(start 208.650586 -134.26694)
		(end 208.62925 -134.313168)
		(width 0.1651)
		(layer "F.Cu")
		(net "M_D_DQS_DP<10>")
	)
	(segment
		(start 210.54822 -116.516912)
		(end 210.54822 -119.154956)
		(width 0.1651)
		(layer "F.Cu")
		(net "M_D_DQS_DP<10>")
	)
	(segment
		(start 209.644996 -119.733314)
		(end 209.644996 -128.120902)
		(width 0.1651)
		(layer "F.Cu")
		(net "M_D_DQS_DP<10>")
	)
	(segment
		(start 209.55 -128.215898)
		(end 209.55 -128.469898)
		(width 0.1651)
		(layer "F.Cu")
		(net "M_D_DQS_DP<10>")
	)
	(segment
		(start 209.553048 -129.238502)
		(end 209.644996 -129.33045)
		(width 0.1651)
		(layer "F.Cu")
		(net "M_D_DQS_DP<10>")
	)
	(segment
		(start 234.466638 -94.223586)
		(end 234.061 -94.17685)
		(width 0.0889)
		(layer "F.Cu")
		(net "M_D_DQS_DP<10>")
	)
	(segment
		(start 209.553048 -128.984502)
		(end 209.553048 -129.238502)
		(width 0.1651)
		(layer "F.Cu")
		(net "M_D_DQS_DP<10>")
	)
	(segment
		(start 209.699098 -115.992656)
		(end 210.045046 -116.338604)
		(width 0.1651)
		(layer "F.Cu")
		(net "M_D_DQS_DP<10>")
	)
	(segment
		(start 209.644996 -128.564894)
		(end 209.644996 -128.892554)
		(width 0.1651)
		(layer "F.Cu")
		(net "M_D_DQS_DP<10>")
	)
	(segment
		(start 209.14995 -133.076442)
		(end 209.14995 -133.693154)
		(width 0.1651)
		(layer "F.Cu")
		(net "M_D_DQS_DP<10>")
	)
	(segment
		(start 210.369912 -116.338604)
		(end 210.54822 -116.516912)
		(width 0.1651)
		(layer "F.Cu")
		(net "M_D_DQS_DP<10>")
	)
	(segment
		(start 209.699098 -115.240308)
		(end 209.699098 -115.992656)
		(width 0.1651)
		(layer "F.Cu")
		(net "M_D_DQS_DP<10>")
	)
	(segment
		(start 233.629708 -94.128336)
		(end 232.582466 -94.128336)
		(width 0.0889)
		(layer "F.Cu")
		(net "M_D_DQS_DP<10>")
	)
	(segment
		(start 210.319112 -119.384064)
		(end 209.994246 -119.384064)
		(width 0.1651)
		(layer "F.Cu")
		(net "M_D_DQS_DP<10>")
	)
	(segment
		(start 210.54822 -119.154956)
		(end 210.319112 -119.384064)
		(width 0.1651)
		(layer "F.Cu")
		(net "M_D_DQS_DP<10>")
	)
	(segment
		(start 208.62925 -134.313168)
		(end 208.62925 -135.131302)
		(width 0.1651)
		(layer "F.Cu")
		(net "M_D_DQS_DP<10>")
	)
	(segment
		(start 209.644996 -128.120902)
		(end 209.55 -128.215898)
		(width 0.1651)
		(layer "F.Cu")
		(net "M_D_DQS_DP<10>")
	)
	(segment
		(start 208.710784 -135.355584)
		(end 209.092546 -135.737346)
		(width 0.1651)
		(layer "F.Cu")
		(net "M_D_DQS_DP<10>")
	)
	(segment
		(start 209.644996 -128.892554)
		(end 209.553048 -128.984502)
		(width 0.1651)
		(layer "F.Cu")
		(net "M_D_DQS_DP<10>")
	)
	(segment
		(start 209.994246 -119.384064)
		(end 209.644996 -119.733314)
		(width 0.1651)
		(layer "F.Cu")
		(net "M_D_DQS_DP<10>")
	)
	(segment
		(start 209.644996 -129.920492)
		(end 209.339688 -130.2258)
		(width 0.1651)
		(layer "F.Cu")
		(net "M_D_DQS_DP<10>")
	)
	(segment
		(start 208.62925 -135.131302)
		(end 208.710784 -135.355584)
		(width 0.1651)
		(layer "F.Cu")
		(net "M_D_DQS_DP<10>")
	)
	(segment
		(start 232.582466 -94.128336)
		(end 232.537 -94.08287)
		(width 0.0889)
		(layer "F.Cu")
		(net "M_D_DQS_DP<10>")
	)
	(segment
		(start 209.55 -128.469898)
		(end 209.644996 -128.564894)
		(width 0.1651)
		(layer "F.Cu")
		(net "M_D_DQS_DP<10>")
	)
	(segment
		(start 230.856536 -94.08287)
		(end 209.699098 -115.240308)
		(width 0.1651)
		(layer "F.Cu")
		(net "M_D_DQS_DP<10>")
	)
	(segment
		(start 209.339688 -130.2258)
		(end 209.092546 -130.2258)
		(width 0.1651)
		(layer "F.Cu")
		(net "M_D_DQS_DP<10>")
	)
	(segment
		(start 208.713832 -134.129272)
		(end 208.650586 -134.26694)
		(width 0.1651)
		(layer "F.Cu")
		(net "M_D_DQS_DP<10>")
	)
	(segment
		(start 209.150458 -133.0706)
		(end 209.14995 -133.076442)
		(width 0.1651)
		(layer "F.Cu")
		(net "M_D_DQS_DP<10>")
	)
	(segment
		(start 209.14995 -133.693154)
		(end 208.713832 -134.129272)
		(width 0.1651)
		(layer "F.Cu")
		(net "M_D_DQS_DP<10>")
	)
	(segment
		(start 210.045046 -116.338604)
		(end 210.369912 -116.338604)
		(width 0.1651)
		(layer "F.Cu")
		(net "M_D_DQS_DP<10>")
	)
	(segment
		(start 209.644996 -129.33045)
		(end 209.644996 -129.920492)
		(width 0.1651)
		(layer "F.Cu")
		(net "M_D_DQS_DP<10>")
	)
	(segment
		(start 232.537 -94.08287)
		(end 230.856536 -94.08287)
		(width 0.1651)
		(layer "F.Cu")
		(net "M_D_DQS_DP<10>")
	)
	(via
		(at 209.092546 -130.2258)
		(size 0.508)
		(drill 0.254)
		(layers "F.Cu" "B.Cu")
		(net "M_D_DQS_DP<10>")
	)
	(via
		(at 209.092546 -135.737346)
		(size 0.508)
		(drill 0.254)
		(layers "F.Cu" "B.Cu")
		(net "M_D_DQS_DP<10>")
	)
	(arc
		(start 233.704892 -94.135956)
		(mid 233.667422 -94.130945)
		(end 233.629708 -94.128336)
		(width 0.0889)
		(layer "F.Cu")
		(net "M_D_DQS_DP<10>")
	)
	(segment
		(start 208.61655 -130.773932)
		(end 208.703926 -130.61442)
		(width 0.1651)
		(layer "B.Cu")
		(net "M_D_DQS_DP<10>")
	)
	(segment
		(start 208.703926 -130.61442)
		(end 209.092546 -130.2258)
		(width 0.1651)
		(layer "B.Cu")
		(net "M_D_DQS_DP<10>")
	)
	(segment
		(start 209.14995 -132.258054)
		(end 208.693766 -131.80187)
		(width 0.1651)
		(layer "B.Cu")
		(net "M_D_DQS_DP<10>")
	)
	(segment
		(start 208.61655 -131.669536)
		(end 208.61655 -130.773932)
		(width 0.1651)
		(layer "B.Cu")
		(net "M_D_DQS_DP<10>")
	)
	(segment
		(start 208.693766 -131.80187)
		(end 208.61655 -131.669536)
		(width 0.1651)
		(layer "B.Cu")
		(net "M_D_DQS_DP<10>")
	)
	(segment
		(start 209.150458 -132.876036)
		(end 209.14995 -132.875782)
		(width 0.1651)
		(layer "B.Cu")
		(net "M_D_DQS_DP<10>")
	)
	(segment
		(start 209.14995 -132.875782)
		(end 209.14995 -132.258054)
		(width 0.1651)
		(layer "B.Cu")
		(net "M_D_DQS_DP<10>")
	)
	(segment
		(start 209.092546 -135.737346)
		(end 208.587594 -135.232394)
		(width 0.14224)
		(layer "In2.Cu")
		(net "M_D_DQS_DP<10>")
	)
	(segment
		(start 209.019394 -130.2258)
		(end 209.092546 -130.2258)
		(width 0.14224)
		(layer "In2.Cu")
		(net "M_D_DQS_DP<10>")
	)
	(segment
		(start 208.587594 -130.6576)
		(end 209.019394 -130.2258)
		(width 0.14224)
		(layer "In2.Cu")
		(net "M_D_DQS_DP<10>")
	)
	(segment
		(start 208.587594 -135.232394)
		(end 208.587594 -130.6576)
		(width 0.14224)
		(layer "In2.Cu")
		(net "M_D_DQS_DP<10>")
	)
	(segment
		(start 201.537824 -136.6266)
		(end 201.537824 -135.255)
		(width 0.1651)
		(layer "F.Cu")
		(net "M_D_DQS_DP<0>")
	)
	(segment
		(start 201.537824 -135.255)
		(end 201.293984 -135.01116)
		(width 0.1651)
		(layer "F.Cu")
		(net "M_D_DQS_DP<0>")
	)
	(segment
		(start 201.293984 -135.01116)
		(end 201.037952 -135.01116)
		(width 0.1651)
		(layer "F.Cu")
		(net "M_D_DQS_DP<0>")
	)
	(segment
		(start 201.499978 -136.664446)
		(end 201.537824 -136.6266)
		(width 0.1651)
		(layer "F.Cu")
		(net "M_D_DQS_DP<0>")
	)
	(segment
		(start 233.608118 -87.784686)
		(end 233.036618 -87.784686)
		(width 0.1651)
		(layer "F.Cu")
		(net "M_D_DQS_DP<0>")
	)
	(segment
		(start 201.500486 -137.67054)
		(end 201.499978 -137.67054)
		(width 0.1651)
		(layer "F.Cu")
		(net "M_D_DQS_DP<0>")
	)
	(segment
		(start 201.499978 -137.67054)
		(end 201.499978 -136.664446)
		(width 0.1651)
		(layer "F.Cu")
		(net "M_D_DQS_DP<0>")
	)
	(via
		(at 201.037952 -130.940556)
		(size 0.508)
		(drill 0.254)
		(layers "F.Cu" "B.Cu")
		(net "M_D_DQS_DP<0>")
	)
	(via
		(at 201.037952 -135.01116)
		(size 0.508)
		(drill 0.254)
		(layers "F.Cu" "B.Cu")
		(net "M_D_DQS_DP<0>")
	)
	(via
		(at 233.036618 -87.784686)
		(size 0.508)
		(drill 0.254)
		(layers "F.Cu" "B.Cu")
		(net "M_D_DQS_DP<0>")
	)
	(segment
		(start 201.537824 -129.4638)
		(end 201.537824 -130.683)
		(width 0.1651)
		(layer "B.Cu")
		(net "M_D_DQS_DP<0>")
	)
	(segment
		(start 201.499978 -128.276096)
		(end 201.499978 -129.425954)
		(width 0.1651)
		(layer "B.Cu")
		(net "M_D_DQS_DP<0>")
	)
	(segment
		(start 201.537824 -130.683)
		(end 201.280268 -130.940556)
		(width 0.1651)
		(layer "B.Cu")
		(net "M_D_DQS_DP<0>")
	)
	(segment
		(start 201.499978 -129.425954)
		(end 201.537824 -129.4638)
		(width 0.1651)
		(layer "B.Cu")
		(net "M_D_DQS_DP<0>")
	)
	(segment
		(start 201.280268 -130.940556)
		(end 201.037952 -130.940556)
		(width 0.1651)
		(layer "B.Cu")
		(net "M_D_DQS_DP<0>")
	)
	(segment
		(start 201.500486 -128.276096)
		(end 201.499978 -128.276096)
		(width 0.1651)
		(layer "B.Cu")
		(net "M_D_DQS_DP<0>")
	)
	(segment
		(start 201.62012 -124.21108)
		(end 201.841608 -124.432568)
		(width 0.14224)
		(layer "In2.Cu")
		(net "M_D_DQS_DP<0>")
	)
	(segment
		(start 201.56932 -126.49708)
		(end 201.790808 -126.718568)
		(width 0.14224)
		(layer "In2.Cu")
		(net "M_D_DQS_DP<0>")
	)
	(segment
		(start 202.180952 -121.272808)
		(end 201.892408 -121.272808)
		(width 0.14224)
		(layer "In2.Cu")
		(net "M_D_DQS_DP<0>")
	)
	(segment
		(start 200.663302 -133.435852)
		(end 200.663302 -133.662166)
		(width 0.14224)
		(layer "In2.Cu")
		(net "M_D_DQS_DP<0>")
	)
	(segment
		(start 200.800462 -133.298692)
		(end 200.663302 -133.435852)
		(width 0.14224)
		(layer "In2.Cu")
		(net "M_D_DQS_DP<0>")
	)
	(segment
		(start 231.3178 -87.563198)
		(end 231.250998 -87.63)
		(width 0.0889)
		(layer "In2.Cu")
		(net "M_D_DQS_DP<0>")
	)
	(segment
		(start 202.181714 -125.844808)
		(end 201.790808 -125.844808)
		(width 0.14224)
		(layer "In2.Cu")
		(net "M_D_DQS_DP<0>")
	)
	(segment
		(start 202.181714 -124.432568)
		(end 202.55992 -124.810774)
		(width 0.14224)
		(layer "In2.Cu")
		(net "M_D_DQS_DP<0>")
	)
	(segment
		(start 231.0638 -87.63)
		(end 230.996998 -87.563198)
		(width 0.0889)
		(layer "In2.Cu")
		(net "M_D_DQS_DP<0>")
	)
	(segment
		(start 200.8632 -132.6642)
		(end 201.03592 -132.83692)
		(width 0.14224)
		(layer "In2.Cu")
		(net "M_D_DQS_DP<0>")
	)
	(segment
		(start 201.841608 -123.558808)
		(end 201.62012 -123.780296)
		(width 0.14224)
		(layer "In2.Cu")
		(net "M_D_DQS_DP<0>")
	)
	(segment
		(start 201.67092 -121.92508)
		(end 201.892408 -122.146568)
		(width 0.14224)
		(layer "In2.Cu")
		(net "M_D_DQS_DP<0>")
	)
	(segment
		(start 200.663302 -132.549392)
		(end 200.77811 -132.6642)
		(width 0.14224)
		(layer "In2.Cu")
		(net "M_D_DQS_DP<0>")
	)
	(segment
		(start 202.55992 -127.810768)
		(end 201.82332 -128.547368)
		(width 0.14224)
		(layer "In2.Cu")
		(net "M_D_DQS_DP<0>")
	)
	(segment
		(start 233.329734 -87.615776)
		(end 233.3498 -87.540846)
		(width 0.0889)
		(layer "In2.Cu")
		(net "M_D_DQS_DP<0>")
	)
	(segment
		(start 200.77811 -132.6642)
		(end 200.8632 -132.6642)
		(width 0.14224)
		(layer "In2.Cu")
		(net "M_D_DQS_DP<0>")
	)
	(segment
		(start 230.996998 -87.563198)
		(end 230.734108 -87.563198)
		(width 0.0889)
		(layer "In2.Cu")
		(net "M_D_DQS_DP<0>")
	)
	(segment
		(start 204.474064 -114.600736)
		(end 203.449936 -114.600736)
		(width 0.14224)
		(layer "In2.Cu")
		(net "M_D_DQS_DP<0>")
	)
	(segment
		(start 201.4728 -131.375404)
		(end 201.4728 -131.8006)
		(width 0.14224)
		(layer "In2.Cu")
		(net "M_D_DQS_DP<0>")
	)
	(segment
		(start 201.4728 -131.8006)
		(end 201.2188 -132.0546)
		(width 0.14224)
		(layer "In2.Cu")
		(net "M_D_DQS_DP<0>")
	)
	(segment
		(start 200.859136 -133.858)
		(end 201.2442 -133.858)
		(width 0.14224)
		(layer "In2.Cu")
		(net "M_D_DQS_DP<0>")
	)
	(segment
		(start 202.088242 -126.718568)
		(end 202.55992 -127.190246)
		(width 0.14224)
		(layer "In2.Cu")
		(net "M_D_DQS_DP<0>")
	)
	(segment
		(start 233.047794 -87.384636)
		(end 232.870248 -87.384636)
		(width 0.0889)
		(layer "In2.Cu")
		(net "M_D_DQS_DP<0>")
	)
	(segment
		(start 202.181714 -123.558808)
		(end 201.841608 -123.558808)
		(width 0.14224)
		(layer "In2.Cu")
		(net "M_D_DQS_DP<0>")
	)
	(segment
		(start 201.892408 -121.272808)
		(end 201.67092 -121.494296)
		(width 0.14224)
		(layer "In2.Cu")
		(net "M_D_DQS_DP<0>")
	)
	(segment
		(start 202.55992 -124.810774)
		(end 202.55992 -125.466602)
		(width 0.14224)
		(layer "In2.Cu")
		(net "M_D_DQS_DP<0>")
	)
	(segment
		(start 202.55992 -115.490752)
		(end 202.55992 -120.89384)
		(width 0.14224)
		(layer "In2.Cu")
		(net "M_D_DQS_DP<0>")
	)
	(segment
		(start 231.250998 -87.63)
		(end 231.0638 -87.63)
		(width 0.0889)
		(layer "In2.Cu")
		(net "M_D_DQS_DP<0>")
	)
	(segment
		(start 200.663302 -133.662166)
		(end 200.859136 -133.858)
		(width 0.14224)
		(layer "In2.Cu")
		(net "M_D_DQS_DP<0>")
	)
	(segment
		(start 202.55992 -127.190246)
		(end 202.55992 -127.810768)
		(width 0.14224)
		(layer "In2.Cu")
		(net "M_D_DQS_DP<0>")
	)
	(segment
		(start 201.03592 -132.83692)
		(end 201.03592 -133.123432)
		(width 0.14224)
		(layer "In2.Cu")
		(net "M_D_DQS_DP<0>")
	)
	(segment
		(start 201.82332 -130.23088)
		(end 201.504804 -130.549396)
		(width 0.14224)
		(layer "In2.Cu")
		(net "M_D_DQS_DP<0>")
	)
	(segment
		(start 201.4982 -134.112)
		(end 201.4982 -134.550912)
		(width 0.14224)
		(layer "In2.Cu")
		(net "M_D_DQS_DP<0>")
	)
	(segment
		(start 201.2442 -133.858)
		(end 201.4982 -134.112)
		(width 0.14224)
		(layer "In2.Cu")
		(net "M_D_DQS_DP<0>")
	)
	(segment
		(start 202.55992 -120.89384)
		(end 202.180952 -121.272808)
		(width 0.14224)
		(layer "In2.Cu")
		(net "M_D_DQS_DP<0>")
	)
	(segment
		(start 230.734108 -87.563198)
		(end 230.698548 -87.598758)
		(width 0.0889)
		(layer "In2.Cu")
		(net "M_D_DQS_DP<0>")
	)
	(segment
		(start 229.882446 -87.598758)
		(end 217.8558 -99.625404)
		(width 0.14224)
		(layer "In2.Cu")
		(net "M_D_DQS_DP<0>")
	)
	(segment
		(start 232.30459 -87.88019)
		(end 231.831896 -87.88019)
		(width 0.0889)
		(layer "In2.Cu")
		(net "M_D_DQS_DP<0>")
	)
	(segment
		(start 202.55992 -123.180602)
		(end 202.181714 -123.558808)
		(width 0.14224)
		(layer "In2.Cu")
		(net "M_D_DQS_DP<0>")
	)
	(segment
		(start 233.3498 -87.540846)
		(end 233.350816 -87.537036)
		(width 0.0889)
		(layer "In2.Cu")
		(net "M_D_DQS_DP<0>")
	)
	(segment
		(start 201.56932 -126.066296)
		(end 201.56932 -126.49708)
		(width 0.14224)
		(layer "In2.Cu")
		(net "M_D_DQS_DP<0>")
	)
	(segment
		(start 230.698548 -87.598758)
		(end 229.882446 -87.598758)
		(width 0.14224)
		(layer "In2.Cu")
		(net "M_D_DQS_DP<0>")
	)
	(segment
		(start 201.841608 -124.432568)
		(end 202.181714 -124.432568)
		(width 0.14224)
		(layer "In2.Cu")
		(net "M_D_DQS_DP<0>")
	)
	(segment
		(start 201.892408 -122.146568)
		(end 202.181714 -122.146568)
		(width 0.14224)
		(layer "In2.Cu")
		(net "M_D_DQS_DP<0>")
	)
	(segment
		(start 201.82332 -128.547368)
		(end 201.82332 -130.23088)
		(width 0.14224)
		(layer "In2.Cu")
		(net "M_D_DQS_DP<0>")
	)
	(segment
		(start 201.2188 -132.0546)
		(end 200.833736 -132.0546)
		(width 0.14224)
		(layer "In2.Cu")
		(net "M_D_DQS_DP<0>")
	)
	(segment
		(start 201.4982 -134.550912)
		(end 201.037952 -135.01116)
		(width 0.14224)
		(layer "In2.Cu")
		(net "M_D_DQS_DP<0>")
	)
	(segment
		(start 200.86066 -133.298692)
		(end 200.800462 -133.298692)
		(width 0.14224)
		(layer "In2.Cu")
		(net "M_D_DQS_DP<0>")
	)
	(segment
		(start 201.037952 -130.940556)
		(end 201.4728 -131.375404)
		(width 0.14224)
		(layer "In2.Cu")
		(net "M_D_DQS_DP<0>")
	)
	(segment
		(start 203.449936 -114.600736)
		(end 202.55992 -115.490752)
		(width 0.14224)
		(layer "In2.Cu")
		(net "M_D_DQS_DP<0>")
	)
	(segment
		(start 233.036618 -87.784686)
		(end 233.329734 -87.615776)
		(width 0.0889)
		(layer "In2.Cu")
		(net "M_D_DQS_DP<0>")
	)
	(segment
		(start 201.03592 -133.123432)
		(end 200.86066 -133.298692)
		(width 0.14224)
		(layer "In2.Cu")
		(net "M_D_DQS_DP<0>")
	)
	(segment
		(start 201.429112 -130.549396)
		(end 201.037952 -130.940556)
		(width 0.14224)
		(layer "In2.Cu")
		(net "M_D_DQS_DP<0>")
	)
	(segment
		(start 231.514904 -87.563198)
		(end 231.3178 -87.563198)
		(width 0.0889)
		(layer "In2.Cu")
		(net "M_D_DQS_DP<0>")
	)
	(segment
		(start 201.504804 -130.549396)
		(end 201.429112 -130.549396)
		(width 0.14224)
		(layer "In2.Cu")
		(net "M_D_DQS_DP<0>")
	)
	(segment
		(start 202.55992 -125.466602)
		(end 202.181714 -125.844808)
		(width 0.14224)
		(layer "In2.Cu")
		(net "M_D_DQS_DP<0>")
	)
	(segment
		(start 201.67092 -121.494296)
		(end 201.67092 -121.92508)
		(width 0.14224)
		(layer "In2.Cu")
		(net "M_D_DQS_DP<0>")
	)
	(segment
		(start 200.663302 -132.225034)
		(end 200.663302 -132.549392)
		(width 0.14224)
		(layer "In2.Cu")
		(net "M_D_DQS_DP<0>")
	)
	(segment
		(start 201.62012 -123.780296)
		(end 201.62012 -124.21108)
		(width 0.14224)
		(layer "In2.Cu")
		(net "M_D_DQS_DP<0>")
	)
	(segment
		(start 200.833736 -132.0546)
		(end 200.663302 -132.225034)
		(width 0.14224)
		(layer "In2.Cu")
		(net "M_D_DQS_DP<0>")
	)
	(segment
		(start 202.181714 -122.146568)
		(end 202.55992 -122.524774)
		(width 0.14224)
		(layer "In2.Cu")
		(net "M_D_DQS_DP<0>")
	)
	(segment
		(start 201.790808 -125.844808)
		(end 201.56932 -126.066296)
		(width 0.14224)
		(layer "In2.Cu")
		(net "M_D_DQS_DP<0>")
	)
	(segment
		(start 201.790808 -126.718568)
		(end 202.088242 -126.718568)
		(width 0.14224)
		(layer "In2.Cu")
		(net "M_D_DQS_DP<0>")
	)
	(segment
		(start 217.8558 -101.219)
		(end 204.474064 -114.600736)
		(width 0.14224)
		(layer "In2.Cu")
		(net "M_D_DQS_DP<0>")
	)
	(segment
		(start 217.8558 -99.625404)
		(end 217.8558 -101.219)
		(width 0.14224)
		(layer "In2.Cu")
		(net "M_D_DQS_DP<0>")
	)
	(segment
		(start 231.831896 -87.88019)
		(end 231.514904 -87.563198)
		(width 0.0889)
		(layer "In2.Cu")
		(net "M_D_DQS_DP<0>")
	)
	(segment
		(start 202.55992 -122.524774)
		(end 202.55992 -123.180602)
		(width 0.14224)
		(layer "In2.Cu")
		(net "M_D_DQS_DP<0>")
	)
	(arc
		(start 232.870248 -87.384636)
		(mid 232.744761 -87.464469)
		(end 232.653586 -87.581994)
		(width 0.0889)
		(layer "In2.Cu")
		(net "M_D_DQS_DP<0>")
	)
	(arc
		(start 233.225848 -87.432134)
		(mid 233.139594 -87.397981)
		(end 233.047794 -87.384636)
		(width 0.0889)
		(layer "In2.Cu")
		(net "M_D_DQS_DP<0>")
	)
	(arc
		(start 233.350816 -87.537036)
		(mid 233.293739 -87.478143)
		(end 233.225848 -87.432134)
		(width 0.0889)
		(layer "In2.Cu")
		(net "M_D_DQS_DP<0>")
	)
	(arc
		(start 232.653586 -87.581994)
		(mid 232.507486 -87.764328)
		(end 232.30459 -87.88019)
		(width 0.0889)
		(layer "In2.Cu")
		(net "M_D_DQS_DP<0>")
	)
	(segment
		(start 200.231756 -134.148068)
		(end 200.231756 -134.5692)
		(width 0.1651)
		(layer "F.Cu")
		(net "M_D_DQS_DN<9>")
	)
	(segment
		(start 200.64984 -133.729984)
		(end 200.231756 -134.148068)
		(width 0.1651)
		(layer "F.Cu")
		(net "M_D_DQS_DN<9>")
	)
	(segment
		(start 200.165716 -135.25373)
		(end 199.957436 -135.25373)
		(width 0.1651)
		(layer "F.Cu")
		(net "M_D_DQS_DN<9>")
	)
	(segment
		(start 200.417684 -135.001762)
		(end 200.165716 -135.25373)
		(width 0.1651)
		(layer "F.Cu")
		(net "M_D_DQS_DN<9>")
	)
	(segment
		(start 234.466638 -86.29904)
		(end 233.895138 -86.29904)
		(width 0.1651)
		(layer "F.Cu")
		(net "M_D_DQS_DN<9>")
	)
	(segment
		(start 200.64984 -133.076442)
		(end 200.64984 -133.729984)
		(width 0.1651)
		(layer "F.Cu")
		(net "M_D_DQS_DN<9>")
	)
	(segment
		(start 199.957436 -135.25373)
		(end 199.768206 -135.0645)
		(width 0.1651)
		(layer "F.Cu")
		(net "M_D_DQS_DN<9>")
	)
	(segment
		(start 200.417684 -134.755128)
		(end 200.417684 -135.001762)
		(width 0.1651)
		(layer "F.Cu")
		(net "M_D_DQS_DN<9>")
	)
	(segment
		(start 200.231756 -134.5692)
		(end 200.417684 -134.755128)
		(width 0.1651)
		(layer "F.Cu")
		(net "M_D_DQS_DN<9>")
	)
	(segment
		(start 200.650348 -133.0706)
		(end 200.64984 -133.076442)
		(width 0.1651)
		(layer "F.Cu")
		(net "M_D_DQS_DN<9>")
	)
	(segment
		(start 199.768206 -135.0645)
		(end 199.749156 -135.0645)
		(width 0.1651)
		(layer "F.Cu")
		(net "M_D_DQS_DN<9>")
	)
	(via
		(at 233.895138 -86.29904)
		(size 0.508)
		(drill 0.254)
		(layers "F.Cu" "B.Cu")
		(net "M_D_DQS_DN<9>")
	)
	(via
		(at 199.749156 -135.0645)
		(size 0.508)
		(drill 0.254)
		(layers "F.Cu" "B.Cu")
		(net "M_D_DQS_DN<9>")
	)
	(via
		(at 199.742552 -130.8862)
		(size 0.508)
		(drill 0.254)
		(layers "F.Cu" "B.Cu")
		(net "M_D_DQS_DN<9>")
	)
	(segment
		(start 200.384156 -130.9116)
		(end 200.164192 -130.691636)
		(width 0.1651)
		(layer "B.Cu")
		(net "M_D_DQS_DN<9>")
	)
	(segment
		(start 200.650094 -132.875528)
		(end 200.650094 -132.219192)
		(width 0.1651)
		(layer "B.Cu")
		(net "M_D_DQS_DN<9>")
	)
	(segment
		(start 199.937116 -130.691636)
		(end 199.742552 -130.8862)
		(width 0.1651)
		(layer "B.Cu")
		(net "M_D_DQS_DN<9>")
	)
	(segment
		(start 200.650348 -132.876036)
		(end 200.650094 -132.875528)
		(width 0.1651)
		(layer "B.Cu")
		(net "M_D_DQS_DN<9>")
	)
	(segment
		(start 200.384156 -131.2418)
		(end 200.384156 -130.9116)
		(width 0.1651)
		(layer "B.Cu")
		(net "M_D_DQS_DN<9>")
	)
	(segment
		(start 200.206356 -131.4196)
		(end 200.384156 -131.2418)
		(width 0.1651)
		(layer "B.Cu")
		(net "M_D_DQS_DN<9>")
	)
	(segment
		(start 200.650094 -132.219192)
		(end 200.206356 -131.775454)
		(width 0.1651)
		(layer "B.Cu")
		(net "M_D_DQS_DN<9>")
	)
	(segment
		(start 200.164192 -130.691636)
		(end 199.937116 -130.691636)
		(width 0.1651)
		(layer "B.Cu")
		(net "M_D_DQS_DN<9>")
	)
	(segment
		(start 200.206356 -131.775454)
		(end 200.206356 -131.4196)
		(width 0.1651)
		(layer "B.Cu")
		(net "M_D_DQS_DN<9>")
	)
	(segment
		(start 200.182226 -134.63143)
		(end 199.749156 -135.0645)
		(width 0.14224)
		(layer "In2.Cu")
		(net "M_D_DQS_DN<9>")
	)
	(segment
		(start 200.57872 -120.443498)
		(end 200.57872 -130.050032)
		(width 0.14224)
		(layer "In2.Cu")
		(net "M_D_DQS_DN<9>")
	)
	(segment
		(start 231.849676 -86.88959)
		(end 231.566466 -86.60638)
		(width 0.0889)
		(layer "In2.Cu")
		(net "M_D_DQS_DN<9>")
	)
	(segment
		(start 199.79386 -133.29666)
		(end 199.64654 -133.29666)
		(width 0.14224)
		(layer "In2.Cu")
		(net "M_D_DQS_DN<9>")
	)
	(segment
		(start 217.043 -100.939346)
		(end 204.139546 -113.8428)
		(width 0.14224)
		(layer "In2.Cu")
		(net "M_D_DQS_DN<9>")
	)
	(segment
		(start 217.043 -99.379786)
		(end 217.043 -100.939346)
		(width 0.14224)
		(layer "In2.Cu")
		(net "M_D_DQS_DN<9>")
	)
	(segment
		(start 233.3498 -86.355682)
		(end 233.200702 -86.371176)
		(width 0.0889)
		(layer "In2.Cu")
		(net "M_D_DQS_DN<9>")
	)
	(segment
		(start 204.139546 -113.8428)
		(end 203.148946 -113.8428)
		(width 0.14224)
		(layer "In2.Cu")
		(net "M_D_DQS_DN<9>")
	)
	(segment
		(start 230.836724 -86.60638)
		(end 230.78948 -86.653624)
		(width 0.0889)
		(layer "In2.Cu")
		(net "M_D_DQS_DN<9>")
	)
	(segment
		(start 199.50684 -133.43636)
		(end 199.50684 -133.79704)
		(width 0.14224)
		(layer "In2.Cu")
		(net "M_D_DQS_DN<9>")
	)
	(segment
		(start 200.83272 -116.378482)
		(end 200.952608 -116.49837)
		(width 0.14224)
		(layer "In2.Cu")
		(net "M_D_DQS_DN<9>")
	)
	(segment
		(start 199.50684 -133.79704)
		(end 199.6694 -133.9596)
		(width 0.14224)
		(layer "In2.Cu")
		(net "M_D_DQS_DN<9>")
	)
	(segment
		(start 200.182226 -134.147306)
		(end 200.182226 -134.63143)
		(width 0.14224)
		(layer "In2.Cu")
		(net "M_D_DQS_DN<9>")
	)
	(segment
		(start 199.50684 -132.15366)
		(end 199.50684 -132.50164)
		(width 0.14224)
		(layer "In2.Cu")
		(net "M_D_DQS_DN<9>")
	)
	(segment
		(start 232.195878 -86.88959)
		(end 231.849676 -86.88959)
		(width 0.0889)
		(layer "In2.Cu")
		(net "M_D_DQS_DN<9>")
	)
	(segment
		(start 200.1774 -131.7244)
		(end 199.898 -132.0038)
		(width 0.14224)
		(layer "In2.Cu")
		(net "M_D_DQS_DN<9>")
	)
	(segment
		(start 200.952608 -116.49837)
		(end 201.215752 -116.49837)
		(width 0.14224)
		(layer "In2.Cu")
		(net "M_D_DQS_DN<9>")
	)
	(segment
		(start 199.9488 -132.78866)
		(end 199.9488 -133.14172)
		(width 0.14224)
		(layer "In2.Cu")
		(net "M_D_DQS_DN<9>")
	)
	(segment
		(start 200.952608 -118.78437)
		(end 201.290682 -118.78437)
		(width 0.14224)
		(layer "In2.Cu")
		(net "M_D_DQS_DN<9>")
	)
	(segment
		(start 199.9488 -133.14172)
		(end 199.79386 -133.29666)
		(width 0.14224)
		(layer "In2.Cu")
		(net "M_D_DQS_DN<9>")
	)
	(segment
		(start 231.566466 -86.60638)
		(end 230.836724 -86.60638)
		(width 0.0889)
		(layer "In2.Cu")
		(net "M_D_DQS_DN<9>")
	)
	(segment
		(start 229.769162 -86.653624)
		(end 217.043 -99.379786)
		(width 0.14224)
		(layer "In2.Cu")
		(net "M_D_DQS_DN<9>")
	)
	(segment
		(start 199.63892 -132.63372)
		(end 199.79386 -132.63372)
		(width 0.14224)
		(layer "In2.Cu")
		(net "M_D_DQS_DN<9>")
	)
	(segment
		(start 200.825608 -120.19661)
		(end 200.57872 -120.443498)
		(width 0.14224)
		(layer "In2.Cu")
		(net "M_D_DQS_DN<9>")
	)
	(segment
		(start 201.215752 -116.49837)
		(end 201.22134 -116.503704)
		(width 0.14224)
		(layer "In2.Cu")
		(net "M_D_DQS_DN<9>")
	)
	(segment
		(start 200.901808 -117.91061)
		(end 200.73112 -118.081298)
		(width 0.14224)
		(layer "In2.Cu")
		(net "M_D_DQS_DN<9>")
	)
	(segment
		(start 200.1774 -131.321048)
		(end 200.1774 -131.7244)
		(width 0.14224)
		(layer "In2.Cu")
		(net "M_D_DQS_DN<9>")
	)
	(segment
		(start 199.6567 -132.0038)
		(end 199.50684 -132.15366)
		(width 0.14224)
		(layer "In2.Cu")
		(net "M_D_DQS_DN<9>")
	)
	(segment
		(start 233.895138 -86.29904)
		(end 233.5022 -86.339934)
		(width 0.0889)
		(layer "In2.Cu")
		(net "M_D_DQS_DN<9>")
	)
	(segment
		(start 201.54392 -117.557042)
		(end 201.190352 -117.91061)
		(width 0.14224)
		(layer "In2.Cu")
		(net "M_D_DQS_DN<9>")
	)
	(segment
		(start 199.898 -132.0038)
		(end 199.6567 -132.0038)
		(width 0.14224)
		(layer "In2.Cu")
		(net "M_D_DQS_DN<9>")
	)
	(segment
		(start 230.78948 -86.653624)
		(end 229.769162 -86.653624)
		(width 0.14224)
		(layer "In2.Cu")
		(net "M_D_DQS_DN<9>")
	)
	(segment
		(start 201.592688 -119.086376)
		(end 201.592688 -119.818404)
		(width 0.14224)
		(layer "In2.Cu")
		(net "M_D_DQS_DN<9>")
	)
	(segment
		(start 233.058208 -86.394036)
		(end 233.025442 -86.394036)
		(width 0.0889)
		(layer "In2.Cu")
		(net "M_D_DQS_DN<9>")
	)
	(segment
		(start 200.73112 -118.081298)
		(end 200.73112 -118.562882)
		(width 0.14224)
		(layer "In2.Cu")
		(net "M_D_DQS_DN<9>")
	)
	(segment
		(start 200.73112 -118.562882)
		(end 200.952608 -118.78437)
		(width 0.14224)
		(layer "In2.Cu")
		(net "M_D_DQS_DN<9>")
	)
	(segment
		(start 199.64654 -133.29666)
		(end 199.50684 -133.43636)
		(width 0.14224)
		(layer "In2.Cu")
		(net "M_D_DQS_DN<9>")
	)
	(segment
		(start 201.290682 -118.78437)
		(end 201.592688 -119.086376)
		(width 0.14224)
		(layer "In2.Cu")
		(net "M_D_DQS_DN<9>")
	)
	(segment
		(start 199.79386 -132.63372)
		(end 199.9488 -132.78866)
		(width 0.14224)
		(layer "In2.Cu")
		(net "M_D_DQS_DN<9>")
	)
	(segment
		(start 200.57872 -130.050032)
		(end 199.742552 -130.8862)
		(width 0.14224)
		(layer "In2.Cu")
		(net "M_D_DQS_DN<9>")
	)
	(segment
		(start 199.99452 -133.9596)
		(end 200.182226 -134.147306)
		(width 0.14224)
		(layer "In2.Cu")
		(net "M_D_DQS_DN<9>")
	)
	(segment
		(start 199.742552 -130.8862)
		(end 200.1774 -131.321048)
		(width 0.14224)
		(layer "In2.Cu")
		(net "M_D_DQS_DN<9>")
	)
	(segment
		(start 201.214482 -120.19661)
		(end 200.825608 -120.19661)
		(width 0.14224)
		(layer "In2.Cu")
		(net "M_D_DQS_DN<9>")
	)
	(segment
		(start 203.148946 -113.8428)
		(end 200.83272 -116.159026)
		(width 0.14224)
		(layer "In2.Cu")
		(net "M_D_DQS_DN<9>")
	)
	(segment
		(start 233.5022 -86.339934)
		(end 233.3498 -86.355682)
		(width 0.0889)
		(layer "In2.Cu")
		(net "M_D_DQS_DN<9>")
	)
	(segment
		(start 199.6694 -133.9596)
		(end 199.99452 -133.9596)
		(width 0.14224)
		(layer "In2.Cu")
		(net "M_D_DQS_DN<9>")
	)
	(segment
		(start 201.190352 -117.91061)
		(end 200.901808 -117.91061)
		(width 0.14224)
		(layer "In2.Cu")
		(net "M_D_DQS_DN<9>")
	)
	(segment
		(start 201.592688 -119.818404)
		(end 201.214482 -120.19661)
		(width 0.14224)
		(layer "In2.Cu")
		(net "M_D_DQS_DN<9>")
	)
	(segment
		(start 201.54392 -116.826538)
		(end 201.54392 -117.557042)
		(width 0.14224)
		(layer "In2.Cu")
		(net "M_D_DQS_DN<9>")
	)
	(segment
		(start 199.50684 -132.50164)
		(end 199.63892 -132.63372)
		(width 0.14224)
		(layer "In2.Cu")
		(net "M_D_DQS_DN<9>")
	)
	(segment
		(start 200.83272 -116.159026)
		(end 200.83272 -116.378482)
		(width 0.14224)
		(layer "In2.Cu")
		(net "M_D_DQS_DN<9>")
	)
	(segment
		(start 201.22134 -116.503704)
		(end 201.54392 -116.826538)
		(width 0.14224)
		(layer "In2.Cu")
		(net "M_D_DQS_DN<9>")
	)
	(arc
		(start 233.200702 -86.371176)
		(mid 233.130155 -86.386964)
		(end 233.058208 -86.394036)
		(width 0.0889)
		(layer "In2.Cu")
		(net "M_D_DQS_DN<9>")
	)
	(arc
		(start 233.025442 -86.394036)
		(mid 232.831592 -86.450386)
		(end 232.689908 -86.594188)
		(width 0.0889)
		(layer "In2.Cu")
		(net "M_D_DQS_DN<9>")
	)
	(arc
		(start 232.689908 -86.594188)
		(mid 232.4813 -86.80612)
		(end 232.195878 -86.88959)
		(width 0.0889)
		(layer "In2.Cu")
		(net "M_D_DQS_DN<9>")
	)
	(segment
		(start 249.061224 -91.747086)
		(end 248.489724 -91.747086)
		(width 0.1651)
		(layer "F.Cu")
		(net "M_D_DQS_DN<8>")
	)
	(segment
		(start 237.6678 -136.220454)
		(end 237.6678 -135.788654)
		(width 0.1651)
		(layer "F.Cu")
		(net "M_D_DQS_DN<8>")
	)
	(segment
		(start 238.049816 -137.67054)
		(end 238.049816 -136.60247)
		(width 0.1651)
		(layer "F.Cu")
		(net "M_D_DQS_DN<8>")
	)
	(segment
		(start 238.049816 -136.60247)
		(end 237.6678 -136.220454)
		(width 0.1651)
		(layer "F.Cu")
		(net "M_D_DQS_DN<8>")
	)
	(segment
		(start 238.222282 -135.4582)
		(end 238.437928 -135.673846)
		(width 0.1651)
		(layer "F.Cu")
		(net "M_D_DQS_DN<8>")
	)
	(segment
		(start 237.6678 -135.788654)
		(end 237.998254 -135.4582)
		(width 0.1651)
		(layer "F.Cu")
		(net "M_D_DQS_DN<8>")
	)
	(segment
		(start 238.050324 -137.67054)
		(end 238.049816 -137.67054)
		(width 0.1651)
		(layer "F.Cu")
		(net "M_D_DQS_DN<8>")
	)
	(segment
		(start 237.998254 -135.4582)
		(end 238.222282 -135.4582)
		(width 0.1651)
		(layer "F.Cu")
		(net "M_D_DQS_DN<8>")
	)
	(via
		(at 238.437928 -135.673846)
		(size 0.508)
		(drill 0.254)
		(layers "F.Cu" "B.Cu")
		(net "M_D_DQS_DN<8>")
	)
	(via
		(at 248.489724 -91.747086)
		(size 0.508)
		(drill 0.254)
		(layers "F.Cu" "B.Cu")
		(net "M_D_DQS_DN<8>")
	)
	(via
		(at 238.437928 -130.280156)
		(size 0.508)
		(drill 0.254)
		(layers "F.Cu" "B.Cu")
		(net "M_D_DQS_DN<8>")
	)
	(segment
		(start 237.9218 -129.565146)
		(end 237.6678 -129.819146)
		(width 0.1651)
		(layer "B.Cu")
		(net "M_D_DQS_DN<8>")
	)
	(segment
		(start 238.049816 -129.18313)
		(end 237.9218 -129.311146)
		(width 0.1651)
		(layer "B.Cu")
		(net "M_D_DQS_DN<8>")
	)
	(segment
		(start 238.0234 -130.5052)
		(end 238.212884 -130.5052)
		(width 0.1651)
		(layer "B.Cu")
		(net "M_D_DQS_DN<8>")
	)
	(segment
		(start 238.049816 -128.276096)
		(end 238.049816 -129.18313)
		(width 0.1651)
		(layer "B.Cu")
		(net "M_D_DQS_DN<8>")
	)
	(segment
		(start 237.6678 -129.819146)
		(end 237.6678 -130.1496)
		(width 0.1651)
		(layer "B.Cu")
		(net "M_D_DQS_DN<8>")
	)
	(segment
		(start 237.6678 -130.1496)
		(end 238.0234 -130.5052)
		(width 0.1651)
		(layer "B.Cu")
		(net "M_D_DQS_DN<8>")
	)
	(segment
		(start 238.212884 -130.5052)
		(end 238.437928 -130.280156)
		(width 0.1651)
		(layer "B.Cu")
		(net "M_D_DQS_DN<8>")
	)
	(segment
		(start 237.9218 -129.311146)
		(end 237.9218 -129.565146)
		(width 0.1651)
		(layer "B.Cu")
		(net "M_D_DQS_DN<8>")
	)
	(segment
		(start 238.050324 -128.276096)
		(end 238.049816 -128.276096)
		(width 0.1651)
		(layer "B.Cu")
		(net "M_D_DQS_DN<8>")
	)
	(segment
		(start 241.81308 -112.30991)
		(end 241.591592 -112.088422)
		(width 0.14224)
		(layer "In2.Cu")
		(net "M_D_DQS_DN<8>")
	)
	(segment
		(start 238.869728 -127.474218)
		(end 239.027208 -127.316738)
		(width 0.14224)
		(layer "In2.Cu")
		(net "M_D_DQS_DN<8>")
	)
	(segment
		(start 239.609376 -123.03379)
		(end 239.788954 -122.854212)
		(width 0.14224)
		(layer "In2.Cu")
		(net "M_D_DQS_DN<8>")
	)
	(segment
		(start 238.869728 -129.120138)
		(end 239.027208 -128.962658)
		(width 0.14224)
		(layer "In2.Cu")
		(net "M_D_DQS_DN<8>")
	)
	(segment
		(start 238.869728 -127.728218)
		(end 238.869728 -127.474218)
		(width 0.14224)
		(layer "In2.Cu")
		(net "M_D_DQS_DN<8>")
	)
	(segment
		(start 240.419128 -121.970038)
		(end 240.261648 -121.812558)
		(width 0.14224)
		(layer "In2.Cu")
		(net "M_D_DQS_DN<8>")
	)
	(segment
		(start 237.794038 -133.77418)
		(end 237.794038 -132.11302)
		(width 0.14224)
		(layer "In2.Cu")
		(net "M_D_DQS_DN<8>")
	)
	(segment
		(start 240.261648 -120.166638)
		(end 240.261648 -119.912638)
		(width 0.14224)
		(layer "In2.Cu")
		(net "M_D_DQS_DN<8>")
	)
	(segment
		(start 247.971564 -95.425006)
		(end 247.977914 -95.414338)
		(width 0.0889)
		(layer "In2.Cu")
		(net "M_D_DQS_DN<8>")
	)
	(segment
		(start 246.845836 -103.527098)
		(end 246.845836 -103.505)
		(width 0.0889)
		(layer "In2.Cu")
		(net "M_D_DQS_DN<8>")
	)
	(segment
		(start 248.0437 -96.119188)
		(end 247.97766 -96.004634)
		(width 0.0889)
		(layer "In2.Cu")
		(net "M_D_DQS_DN<8>")
	)
	(segment
		(start 238.869728 -124.436378)
		(end 238.869728 -124.182378)
		(width 0.14224)
		(layer "In2.Cu")
		(net "M_D_DQS_DN<8>")
	)
	(segment
		(start 240.419128 -120.578118)
		(end 240.419128 -120.324118)
		(width 0.14224)
		(layer "In2.Cu")
		(net "M_D_DQS_DN<8>")
	)
	(segment
		(start 246.885206 -101.983032)
		(end 246.83212 -101.891084)
		(width 0.0889)
		(layer "In2.Cu")
		(net "M_D_DQS_DN<8>")
	)
	(segment
		(start 238.869728 -128.297178)
		(end 239.027208 -128.139698)
		(width 0.14224)
		(layer "In2.Cu")
		(net "M_D_DQS_DN<8>")
	)
	(segment
		(start 238.89335 -126.651258)
		(end 239.027208 -126.5174)
		(width 0.14224)
		(layer "In2.Cu")
		(net "M_D_DQS_DN<8>")
	)
	(segment
		(start 239.206786 -123.43638)
		(end 239.206786 -123.213622)
		(width 0.14224)
		(layer "In2.Cu")
		(net "M_D_DQS_DN<8>")
	)
	(segment
		(start 246.814594 -101.338126)
		(end 246.915686 -101.13391)
		(width 0.0889)
		(layer "In2.Cu")
		(net "M_D_DQS_DN<8>")
	)
	(segment
		(start 248.491502 -91.750896)
		(end 248.489724 -91.747086)
		(width 0.0889)
		(layer "In2.Cu")
		(net "M_D_DQS_DN<8>")
	)
	(segment
		(start 238.004858 -135.240776)
		(end 238.004858 -133.985)
		(width 0.14224)
		(layer "In2.Cu")
		(net "M_D_DQS_DN<8>")
	)
	(segment
		(start 246.915686 -101.13391)
		(end 248.0437 -100.00615)
		(width 0.0889)
		(layer "In2.Cu")
		(net "M_D_DQS_DN<8>")
	)
	(segment
		(start 239.027208 -126.21641)
		(end 238.896398 -126.0856)
		(width 0.14224)
		(layer "In2.Cu")
		(net "M_D_DQS_DN<8>")
	)
	(segment
		(start 246.845836 -103.505)
		(end 246.885206 -103.46563)
		(width 0.0889)
		(layer "In2.Cu")
		(net "M_D_DQS_DN<8>")
	)
	(segment
		(start 239.027208 -129.970276)
		(end 239.027208 -129.531618)
		(width 0.14224)
		(layer "In2.Cu")
		(net "M_D_DQS_DN<8>")
	)
	(segment
		(start 239.968532 -122.451622)
		(end 240.191544 -122.451622)
		(width 0.14224)
		(layer "In2.Cu")
		(net "M_D_DQS_DN<8>")
	)
	(segment
		(start 240.191544 -122.451622)
		(end 240.419128 -122.224038)
		(width 0.14224)
		(layer "In2.Cu")
		(net "M_D_DQS_DN<8>")
	)
	(segment
		(start 248.47677 -93.137736)
		(end 248.50471 -93.137736)
		(width 0.0889)
		(layer "In2.Cu")
		(net "M_D_DQS_DN<8>")
	)
	(segment
		(start 239.027208 -124.593858)
		(end 238.869728 -124.436378)
		(width 0.14224)
		(layer "In2.Cu")
		(net "M_D_DQS_DN<8>")
	)
	(segment
		(start 246.885206 -103.46563)
		(end 246.885206 -101.983032)
		(width 0.0889)
		(layer "In2.Cu")
		(net "M_D_DQS_DN<8>")
	)
	(segment
		(start 239.386364 -123.03379)
		(end 239.609376 -123.03379)
		(width 0.14224)
		(layer "In2.Cu")
		(net "M_D_DQS_DN<8>")
	)
	(segment
		(start 239.027208 -128.708658)
		(end 238.869728 -128.551178)
		(width 0.14224)
		(layer "In2.Cu")
		(net "M_D_DQS_DN<8>")
	)
	(segment
		(start 247.977914 -95.414338)
		(end 247.98274 -95.405702)
		(width 0.0889)
		(layer "In2.Cu")
		(net "M_D_DQS_DN<8>")
	)
	(segment
		(start 240.261648 -120.735598)
		(end 240.419128 -120.578118)
		(width 0.14224)
		(layer "In2.Cu")
		(net "M_D_DQS_DN<8>")
	)
	(segment
		(start 241.138202 -112.088422)
		(end 240.759234 -111.709454)
		(width 0.14224)
		(layer "In2.Cu")
		(net "M_D_DQS_DN<8>")
	)
	(segment
		(start 238.717328 -130.280156)
		(end 239.027208 -129.970276)
		(width 0.14224)
		(layer "In2.Cu")
		(net "M_D_DQS_DN<8>")
	)
	(segment
		(start 239.027208 -127.885698)
		(end 238.869728 -127.728218)
		(width 0.14224)
		(layer "In2.Cu")
		(net "M_D_DQS_DN<8>")
	)
	(segment
		(start 239.027208 -125.40361)
		(end 238.889794 -125.266196)
		(width 0.14224)
		(layer "In2.Cu")
		(net "M_D_DQS_DN<8>")
	)
	(segment
		(start 238.869728 -129.374138)
		(end 238.869728 -129.120138)
		(width 0.14224)
		(layer "In2.Cu")
		(net "M_D_DQS_DN<8>")
	)
	(segment
		(start 238.004858 -133.985)
		(end 237.794038 -133.77418)
		(width 0.14224)
		(layer "In2.Cu")
		(net "M_D_DQS_DN<8>")
	)
	(segment
		(start 239.027208 -128.962658)
		(end 239.027208 -128.708658)
		(width 0.14224)
		(layer "In2.Cu")
		(net "M_D_DQS_DN<8>")
	)
	(segment
		(start 238.896398 -126.0856)
		(end 238.896398 -125.8316)
		(width 0.14224)
		(layer "In2.Cu")
		(net "M_D_DQS_DN<8>")
	)
	(segment
		(start 240.261648 -119.343678)
		(end 240.261648 -119.089678)
		(width 0.14224)
		(layer "In2.Cu")
		(net "M_D_DQS_DN<8>")
	)
	(segment
		(start 239.027208 -126.5174)
		(end 239.027208 -126.21641)
		(width 0.14224)
		(layer "In2.Cu")
		(net "M_D_DQS_DN<8>")
	)
	(segment
		(start 238.437928 -130.280156)
		(end 238.717328 -130.280156)
		(width 0.14224)
		(layer "In2.Cu")
		(net "M_D_DQS_DN<8>")
	)
	(segment
		(start 238.896398 -125.8316)
		(end 239.027208 -125.70079)
		(width 0.14224)
		(layer "In2.Cu")
		(net "M_D_DQS_DN<8>")
	)
	(segment
		(start 240.419128 -120.324118)
		(end 240.261648 -120.166638)
		(width 0.14224)
		(layer "In2.Cu")
		(net "M_D_DQS_DN<8>")
	)
	(segment
		(start 248.84126 -92.546424)
		(end 248.840752 -92.545408)
		(width 0.0889)
		(layer "In2.Cu")
		(net "M_D_DQS_DN<8>")
	)
	(segment
		(start 239.027208 -125.70079)
		(end 239.027208 -125.40361)
		(width 0.14224)
		(layer "In2.Cu")
		(net "M_D_DQS_DN<8>")
	)
	(segment
		(start 239.027208 -123.615958)
		(end 239.206786 -123.43638)
		(width 0.14224)
		(layer "In2.Cu")
		(net "M_D_DQS_DN<8>")
	)
	(segment
		(start 240.419128 -119.755158)
		(end 240.419128 -119.501158)
		(width 0.14224)
		(layer "In2.Cu")
		(net "M_D_DQS_DN<8>")
	)
	(segment
		(start 248.0437 -100.00615)
		(end 248.0437 -96.119188)
		(width 0.0889)
		(layer "In2.Cu")
		(net "M_D_DQS_DN<8>")
	)
	(segment
		(start 240.419128 -121.147078)
		(end 240.261648 -120.989598)
		(width 0.14224)
		(layer "In2.Cu")
		(net "M_D_DQS_DN<8>")
	)
	(segment
		(start 241.81308 -112.745012)
		(end 241.81308 -112.30991)
		(width 0.14224)
		(layer "In2.Cu")
		(net "M_D_DQS_DN<8>")
	)
	(segment
		(start 240.744248 -112.95888)
		(end 241.599212 -112.95888)
		(width 0.14224)
		(layer "In2.Cu")
		(net "M_D_DQS_DN<8>")
	)
	(segment
		(start 238.004858 -130.640074)
		(end 238.364776 -130.280156)
		(width 0.14224)
		(layer "In2.Cu")
		(net "M_D_DQS_DN<8>")
	)
	(segment
		(start 240.261648 -119.089678)
		(end 240.419128 -118.932198)
		(width 0.14224)
		(layer "In2.Cu")
		(net "M_D_DQS_DN<8>")
	)
	(segment
		(start 238.869728 -124.182378)
		(end 239.027208 -124.024898)
		(width 0.14224)
		(layer "In2.Cu")
		(net "M_D_DQS_DN<8>")
	)
	(segment
		(start 242.023392 -109.580426)
		(end 242.0239 -109.580426)
		(width 0.14224)
		(layer "In2.Cu")
		(net "M_D_DQS_DN<8>")
	)
	(segment
		(start 238.364776 -130.280156)
		(end 238.437928 -130.280156)
		(width 0.14224)
		(layer "In2.Cu")
		(net "M_D_DQS_DN<8>")
	)
	(segment
		(start 241.591592 -112.088422)
		(end 241.138202 -112.088422)
		(width 0.14224)
		(layer "In2.Cu")
		(net "M_D_DQS_DN<8>")
	)
	(segment
		(start 240.759234 -111.054388)
		(end 241.13744 -110.676182)
		(width 0.14224)
		(layer "In2.Cu")
		(net "M_D_DQS_DN<8>")
	)
	(segment
		(start 240.419128 -119.501158)
		(end 240.261648 -119.343678)
		(width 0.14224)
		(layer "In2.Cu")
		(net "M_D_DQS_DN<8>")
	)
	(segment
		(start 239.788954 -122.854212)
		(end 239.788954 -122.631454)
		(width 0.14224)
		(layer "In2.Cu")
		(net "M_D_DQS_DN<8>")
	)
	(segment
		(start 240.261648 -120.989598)
		(end 240.261648 -120.735598)
		(width 0.14224)
		(layer "In2.Cu")
		(net "M_D_DQS_DN<8>")
	)
	(segment
		(start 239.027208 -124.024898)
		(end 239.027208 -123.615958)
		(width 0.14224)
		(layer "In2.Cu")
		(net "M_D_DQS_DN<8>")
	)
	(segment
		(start 239.027208 -127.039116)
		(end 238.89335 -126.905258)
		(width 0.14224)
		(layer "In2.Cu")
		(net "M_D_DQS_DN<8>")
	)
	(segment
		(start 240.419128 -122.224038)
		(end 240.419128 -121.970038)
		(width 0.14224)
		(layer "In2.Cu")
		(net "M_D_DQS_DN<8>")
	)
	(segment
		(start 240.261648 -121.812558)
		(end 240.261648 -121.558558)
		(width 0.14224)
		(layer "In2.Cu")
		(net "M_D_DQS_DN<8>")
	)
	(segment
		(start 241.802666 -110.676182)
		(end 242.023392 -110.455456)
		(width 0.14224)
		(layer "In2.Cu")
		(net "M_D_DQS_DN<8>")
	)
	(segment
		(start 242.023392 -110.455456)
		(end 242.023392 -109.580426)
		(width 0.14224)
		(layer "In2.Cu")
		(net "M_D_DQS_DN<8>")
	)
	(segment
		(start 240.419128 -118.932198)
		(end 240.419128 -113.284)
		(width 0.14224)
		(layer "In2.Cu")
		(net "M_D_DQS_DN<8>")
	)
	(segment
		(start 242.0239 -109.580426)
		(end 246.845836 -104.75849)
		(width 0.14224)
		(layer "In2.Cu")
		(net "M_D_DQS_DN<8>")
	)
	(segment
		(start 240.419128 -121.401078)
		(end 240.419128 -121.147078)
		(width 0.14224)
		(layer "In2.Cu")
		(net "M_D_DQS_DN<8>")
	)
	(segment
		(start 238.89335 -126.905258)
		(end 238.89335 -126.651258)
		(width 0.14224)
		(layer "In2.Cu")
		(net "M_D_DQS_DN<8>")
	)
	(segment
		(start 248.840752 -92.545408)
		(end 248.836434 -92.537788)
		(width 0.0889)
		(layer "In2.Cu")
		(net "M_D_DQS_DN<8>")
	)
	(segment
		(start 239.027208 -124.874782)
		(end 239.027208 -124.593858)
		(width 0.14224)
		(layer "In2.Cu")
		(net "M_D_DQS_DN<8>")
	)
	(segment
		(start 241.599212 -112.95888)
		(end 241.81308 -112.745012)
		(width 0.14224)
		(layer "In2.Cu")
		(net "M_D_DQS_DN<8>")
	)
	(segment
		(start 239.027208 -128.139698)
		(end 239.027208 -127.885698)
		(width 0.14224)
		(layer "In2.Cu")
		(net "M_D_DQS_DN<8>")
	)
	(segment
		(start 238.004858 -131.9022)
		(end 238.004858 -130.640074)
		(width 0.14224)
		(layer "In2.Cu")
		(net "M_D_DQS_DN<8>")
	)
	(segment
		(start 239.027208 -127.316738)
		(end 239.027208 -127.039116)
		(width 0.14224)
		(layer "In2.Cu")
		(net "M_D_DQS_DN<8>")
	)
	(segment
		(start 241.13744 -110.676182)
		(end 241.802666 -110.676182)
		(width 0.14224)
		(layer "In2.Cu")
		(net "M_D_DQS_DN<8>")
	)
	(segment
		(start 238.437928 -135.673846)
		(end 238.004858 -135.240776)
		(width 0.14224)
		(layer "In2.Cu")
		(net "M_D_DQS_DN<8>")
	)
	(segment
		(start 246.845836 -104.75849)
		(end 246.845836 -103.527098)
		(width 0.14224)
		(layer "In2.Cu")
		(net "M_D_DQS_DN<8>")
	)
	(segment
		(start 237.794038 -132.11302)
		(end 238.004858 -131.9022)
		(width 0.14224)
		(layer "In2.Cu")
		(net "M_D_DQS_DN<8>")
	)
	(segment
		(start 240.261648 -121.558558)
		(end 240.419128 -121.401078)
		(width 0.14224)
		(layer "In2.Cu")
		(net "M_D_DQS_DN<8>")
	)
	(segment
		(start 238.889794 -125.266196)
		(end 238.889794 -125.012196)
		(width 0.14224)
		(layer "In2.Cu")
		(net "M_D_DQS_DN<8>")
	)
	(segment
		(start 238.889794 -125.012196)
		(end 239.027208 -124.874782)
		(width 0.14224)
		(layer "In2.Cu")
		(net "M_D_DQS_DN<8>")
	)
	(segment
		(start 240.261648 -119.912638)
		(end 240.419128 -119.755158)
		(width 0.14224)
		(layer "In2.Cu")
		(net "M_D_DQS_DN<8>")
	)
	(segment
		(start 239.027208 -129.531618)
		(end 238.869728 -129.374138)
		(width 0.14224)
		(layer "In2.Cu")
		(net "M_D_DQS_DN<8>")
	)
	(segment
		(start 240.419128 -113.284)
		(end 240.744248 -112.95888)
		(width 0.14224)
		(layer "In2.Cu")
		(net "M_D_DQS_DN<8>")
	)
	(segment
		(start 238.869728 -128.551178)
		(end 238.869728 -128.297178)
		(width 0.14224)
		(layer "In2.Cu")
		(net "M_D_DQS_DN<8>")
	)
	(segment
		(start 239.206786 -123.213622)
		(end 239.386364 -123.03379)
		(width 0.14224)
		(layer "In2.Cu")
		(net "M_D_DQS_DN<8>")
	)
	(segment
		(start 240.759234 -111.709454)
		(end 240.759234 -111.054388)
		(width 0.14224)
		(layer "In2.Cu")
		(net "M_D_DQS_DN<8>")
	)
	(segment
		(start 247.977914 -94.023688)
		(end 247.971564 -94.01302)
		(width 0.0889)
		(layer "In2.Cu")
		(net "M_D_DQS_DN<8>")
	)
	(segment
		(start 239.788954 -122.631454)
		(end 239.968532 -122.451622)
		(width 0.14224)
		(layer "In2.Cu")
		(net "M_D_DQS_DN<8>")
	)
	(arc
		(start 248.50471 -93.137736)
		(mid 248.837628 -92.935745)
		(end 248.84126 -92.546424)
		(width 0.0889)
		(layer "In2.Cu")
		(net "M_D_DQS_DN<8>")
	)
	(arc
		(start 247.98274 -95.405702)
		(mid 248.031495 -95.20935)
		(end 247.977914 -95.014288)
		(width 0.0889)
		(layer "In2.Cu")
		(net "M_D_DQS_DN<8>")
	)
	(arc
		(start 248.836434 -92.537788)
		(mid 248.642339 -92.153824)
		(end 248.491502 -91.750896)
		(width 0.0889)
		(layer "In2.Cu")
		(net "M_D_DQS_DN<8>")
	)
	(arc
		(start 246.83212 -101.891084)
		(mid 246.754076 -101.616801)
		(end 246.814594 -101.338126)
		(width 0.0889)
		(layer "In2.Cu")
		(net "M_D_DQS_DN<8>")
	)
	(arc
		(start 247.977914 -94.423484)
		(mid 248.031413 -94.223586)
		(end 247.977914 -94.023688)
		(width 0.0889)
		(layer "In2.Cu")
		(net "M_D_DQS_DN<8>")
	)
	(arc
		(start 247.971564 -94.01302)
		(mid 247.977741 -93.433088)
		(end 248.47677 -93.137736)
		(width 0.0889)
		(layer "In2.Cu")
		(net "M_D_DQS_DN<8>")
	)
	(arc
		(start 247.97766 -96.004634)
		(mid 247.898721 -95.715629)
		(end 247.971564 -95.425006)
		(width 0.0889)
		(layer "In2.Cu")
		(net "M_D_DQS_DN<8>")
	)
	(arc
		(start 247.977914 -95.014288)
		(mid 247.898783 -94.718886)
		(end 247.977914 -94.423484)
		(width 0.0889)
		(layer "In2.Cu")
		(net "M_D_DQS_DN<8>")
	)
	(segment
		(start 311.999884 -136.60247)
		(end 311.617868 -136.220454)
		(width 0.1651)
		(layer "F.Cu")
		(net "M_D_DQS_DN<7>")
	)
	(segment
		(start 312.000392 -137.67054)
		(end 311.999884 -137.67054)
		(width 0.1651)
		(layer "F.Cu")
		(net "M_D_DQS_DN<7>")
	)
	(segment
		(start 311.999884 -137.67054)
		(end 311.999884 -136.60247)
		(width 0.1651)
		(layer "F.Cu")
		(net "M_D_DQS_DN<7>")
	)
	(segment
		(start 311.617868 -135.788654)
		(end 311.948322 -135.4582)
		(width 0.1651)
		(layer "F.Cu")
		(net "M_D_DQS_DN<7>")
	)
	(segment
		(start 288.36366 -99.490784)
		(end 288.93516 -99.490784)
		(width 0.1651)
		(layer "F.Cu")
		(net "M_D_DQS_DN<7>")
	)
	(segment
		(start 311.948322 -135.4582)
		(end 312.17235 -135.4582)
		(width 0.1651)
		(layer "F.Cu")
		(net "M_D_DQS_DN<7>")
	)
	(segment
		(start 311.617868 -136.220454)
		(end 311.617868 -135.788654)
		(width 0.1651)
		(layer "F.Cu")
		(net "M_D_DQS_DN<7>")
	)
	(segment
		(start 312.17235 -135.4582)
		(end 312.387996 -135.673846)
		(width 0.1651)
		(layer "F.Cu")
		(net "M_D_DQS_DN<7>")
	)
	(via
		(at 288.93516 -99.490784)
		(size 0.508)
		(drill 0.254)
		(layers "F.Cu" "B.Cu")
		(net "M_D_DQS_DN<7>")
	)
	(via
		(at 312.387996 -130.280156)
		(size 0.508)
		(drill 0.254)
		(layers "F.Cu" "B.Cu")
		(net "M_D_DQS_DN<7>")
	)
	(via
		(at 312.387996 -135.673846)
		(size 0.508)
		(drill 0.254)
		(layers "F.Cu" "B.Cu")
		(net "M_D_DQS_DN<7>")
	)
	(segment
		(start 312.162952 -130.5052)
		(end 312.387996 -130.280156)
		(width 0.1651)
		(layer "B.Cu")
		(net "M_D_DQS_DN<7>")
	)
	(segment
		(start 311.871868 -129.565146)
		(end 311.617868 -129.819146)
		(width 0.1651)
		(layer "B.Cu")
		(net "M_D_DQS_DN<7>")
	)
	(segment
		(start 311.973468 -130.5052)
		(end 312.162952 -130.5052)
		(width 0.1651)
		(layer "B.Cu")
		(net "M_D_DQS_DN<7>")
	)
	(segment
		(start 311.999884 -128.276096)
		(end 311.999884 -129.18313)
		(width 0.1651)
		(layer "B.Cu")
		(net "M_D_DQS_DN<7>")
	)
	(segment
		(start 312.000392 -128.276096)
		(end 311.999884 -128.276096)
		(width 0.1651)
		(layer "B.Cu")
		(net "M_D_DQS_DN<7>")
	)
	(segment
		(start 311.999884 -129.18313)
		(end 311.871868 -129.311146)
		(width 0.1651)
		(layer "B.Cu")
		(net "M_D_DQS_DN<7>")
	)
	(segment
		(start 311.871868 -129.311146)
		(end 311.871868 -129.565146)
		(width 0.1651)
		(layer "B.Cu")
		(net "M_D_DQS_DN<7>")
	)
	(segment
		(start 311.617868 -129.819146)
		(end 311.617868 -130.1496)
		(width 0.1651)
		(layer "B.Cu")
		(net "M_D_DQS_DN<7>")
	)
	(segment
		(start 311.617868 -130.1496)
		(end 311.973468 -130.5052)
		(width 0.1651)
		(layer "B.Cu")
		(net "M_D_DQS_DN<7>")
	)
	(segment
		(start 313.97448 -118.280434)
		(end 313.97448 -123.121928)
		(width 0.14224)
		(layer "In2.Cu")
		(net "M_D_DQS_DN<7>")
	)
	(segment
		(start 313.817 -124.925328)
		(end 313.817 -125.179328)
		(width 0.14224)
		(layer "In2.Cu")
		(net "M_D_DQS_DN<7>")
	)
	(segment
		(start 312.997596 -129.069846)
		(end 312.997596 -129.949956)
		(width 0.14224)
		(layer "In2.Cu")
		(net "M_D_DQS_DN<7>")
	)
	(segment
		(start 290.960048 -104.413304)
		(end 292.71341 -104.413304)
		(width 0.0889)
		(layer "In2.Cu")
		(net "M_D_DQS_DN<7>")
	)
	(segment
		(start 313.294776 -128.772666)
		(end 312.997596 -129.069846)
		(width 0.14224)
		(layer "In2.Cu")
		(net "M_D_DQS_DN<7>")
	)
	(segment
		(start 311.744106 -133.77418)
		(end 311.954926 -133.985)
		(width 0.14224)
		(layer "In2.Cu")
		(net "M_D_DQS_DN<7>")
	)
	(segment
		(start 292.71341 -104.413304)
		(end 293.687754 -105.387648)
		(width 0.0889)
		(layer "In2.Cu")
		(net "M_D_DQS_DN<7>")
	)
	(segment
		(start 313.97448 -124.513848)
		(end 313.97448 -124.767848)
		(width 0.14224)
		(layer "In2.Cu")
		(net "M_D_DQS_DN<7>")
	)
	(segment
		(start 294.85082 -106.60634)
		(end 298.73194 -106.60634)
		(width 0.14224)
		(layer "In2.Cu")
		(net "M_D_DQS_DN<7>")
	)
	(segment
		(start 311.954926 -130.640074)
		(end 311.954926 -131.9022)
		(width 0.14224)
		(layer "In2.Cu")
		(net "M_D_DQS_DN<7>")
	)
	(segment
		(start 313.817 -126.002288)
		(end 313.97448 -126.159768)
		(width 0.14224)
		(layer "In2.Cu")
		(net "M_D_DQS_DN<7>")
	)
	(segment
		(start 313.817 -126.571248)
		(end 313.817 -126.825248)
		(width 0.14224)
		(layer "In2.Cu")
		(net "M_D_DQS_DN<7>")
	)
	(segment
		(start 313.97448 -128.092962)
		(end 313.605164 -128.462278)
		(width 0.14224)
		(layer "In2.Cu")
		(net "M_D_DQS_DN<7>")
	)
	(segment
		(start 311.954926 -133.985)
		(end 311.954926 -135.240776)
		(width 0.14224)
		(layer "In2.Cu")
		(net "M_D_DQS_DN<7>")
	)
	(segment
		(start 313.817 -123.279408)
		(end 313.817 -123.533408)
		(width 0.14224)
		(layer "In2.Cu")
		(net "M_D_DQS_DN<7>")
	)
	(segment
		(start 293.687754 -105.387648)
		(end 293.6875 -105.44302)
		(width 0.0889)
		(layer "In2.Cu")
		(net "M_D_DQS_DN<7>")
	)
	(segment
		(start 301.733712 -107.45724)
		(end 310.391302 -116.11483)
		(width 0.14224)
		(layer "In2.Cu")
		(net "M_D_DQS_DN<7>")
	)
	(segment
		(start 313.97448 -124.767848)
		(end 313.817 -124.925328)
		(width 0.14224)
		(layer "In2.Cu")
		(net "M_D_DQS_DN<7>")
	)
	(segment
		(start 312.314844 -130.280156)
		(end 311.954926 -130.640074)
		(width 0.14224)
		(layer "In2.Cu")
		(net "M_D_DQS_DN<7>")
	)
	(segment
		(start 312.387996 -130.280156)
		(end 312.314844 -130.280156)
		(width 0.14224)
		(layer "In2.Cu")
		(net "M_D_DQS_DN<7>")
	)
	(segment
		(start 289.391598 -102.680262)
		(end 289.391598 -102.844854)
		(width 0.0889)
		(layer "In2.Cu")
		(net "M_D_DQS_DN<7>")
	)
	(segment
		(start 313.11723 -117.735858)
		(end 313.429904 -117.735858)
		(width 0.14224)
		(layer "In2.Cu")
		(net "M_D_DQS_DN<7>")
	)
	(segment
		(start 311.71388 -117.436646)
		(end 312.297064 -118.01983)
		(width 0.14224)
		(layer "In2.Cu")
		(net "M_D_DQS_DN<7>")
	)
	(segment
		(start 299.58284 -107.45724)
		(end 301.733712 -107.45724)
		(width 0.14224)
		(layer "In2.Cu")
		(net "M_D_DQS_DN<7>")
	)
	(segment
		(start 313.817 -125.179328)
		(end 313.97448 -125.336808)
		(width 0.14224)
		(layer "In2.Cu")
		(net "M_D_DQS_DN<7>")
	)
	(segment
		(start 313.97448 -125.336808)
		(end 313.97448 -125.590808)
		(width 0.14224)
		(layer "In2.Cu")
		(net "M_D_DQS_DN<7>")
	)
	(segment
		(start 311.954926 -131.9022)
		(end 311.744106 -132.11302)
		(width 0.14224)
		(layer "In2.Cu")
		(net "M_D_DQS_DN<7>")
	)
	(segment
		(start 312.833258 -118.01983)
		(end 313.11723 -117.735858)
		(width 0.14224)
		(layer "In2.Cu")
		(net "M_D_DQS_DN<7>")
	)
	(segment
		(start 313.97448 -127.805688)
		(end 313.97448 -128.092962)
		(width 0.14224)
		(layer "In2.Cu")
		(net "M_D_DQS_DN<7>")
	)
	(segment
		(start 311.509156 -115.845336)
		(end 311.959752 -116.295932)
		(width 0.14224)
		(layer "In2.Cu")
		(net "M_D_DQS_DN<7>")
	)
	(segment
		(start 313.97448 -123.690888)
		(end 313.97448 -123.944888)
		(width 0.14224)
		(layer "In2.Cu")
		(net "M_D_DQS_DN<7>")
	)
	(segment
		(start 313.817 -123.533408)
		(end 313.97448 -123.690888)
		(width 0.14224)
		(layer "In2.Cu")
		(net "M_D_DQS_DN<7>")
	)
	(segment
		(start 313.97448 -123.944888)
		(end 313.817 -124.102368)
		(width 0.14224)
		(layer "In2.Cu")
		(net "M_D_DQS_DN<7>")
	)
	(segment
		(start 312.297064 -118.01983)
		(end 312.833258 -118.01983)
		(width 0.14224)
		(layer "In2.Cu")
		(net "M_D_DQS_DN<7>")
	)
	(segment
		(start 313.97448 -123.121928)
		(end 313.817 -123.279408)
		(width 0.14224)
		(layer "In2.Cu")
		(net "M_D_DQS_DN<7>")
	)
	(segment
		(start 288.93516 -99.15271)
		(end 288.993072 -99.094798)
		(width 0.0889)
		(layer "In2.Cu")
		(net "M_D_DQS_DN<7>")
	)
	(segment
		(start 311.959752 -116.295932)
		(end 311.959752 -116.607336)
		(width 0.14224)
		(layer "In2.Cu")
		(net "M_D_DQS_DN<7>")
	)
	(segment
		(start 313.817 -125.748288)
		(end 313.817 -126.002288)
		(width 0.14224)
		(layer "In2.Cu")
		(net "M_D_DQS_DN<7>")
	)
	(segment
		(start 289.391598 -102.844854)
		(end 290.960048 -104.413304)
		(width 0.0889)
		(layer "In2.Cu")
		(net "M_D_DQS_DN<7>")
	)
	(segment
		(start 313.97448 -125.590808)
		(end 313.817 -125.748288)
		(width 0.14224)
		(layer "In2.Cu")
		(net "M_D_DQS_DN<7>")
	)
	(segment
		(start 313.817 -127.648208)
		(end 313.97448 -127.805688)
		(width 0.14224)
		(layer "In2.Cu")
		(net "M_D_DQS_DN<7>")
	)
	(segment
		(start 313.97448 -126.982728)
		(end 313.97448 -127.236728)
		(width 0.14224)
		(layer "In2.Cu")
		(net "M_D_DQS_DN<7>")
	)
	(segment
		(start 313.817 -127.394208)
		(end 313.817 -127.648208)
		(width 0.14224)
		(layer "In2.Cu")
		(net "M_D_DQS_DN<7>")
	)
	(segment
		(start 311.744106 -132.11302)
		(end 311.744106 -133.77418)
		(width 0.14224)
		(layer "In2.Cu")
		(net "M_D_DQS_DN<7>")
	)
	(segment
		(start 311.959752 -116.607336)
		(end 311.71388 -116.853208)
		(width 0.14224)
		(layer "In2.Cu")
		(net "M_D_DQS_DN<7>")
	)
	(segment
		(start 312.997596 -129.949956)
		(end 312.667396 -130.280156)
		(width 0.14224)
		(layer "In2.Cu")
		(net "M_D_DQS_DN<7>")
	)
	(segment
		(start 313.97448 -126.413768)
		(end 313.817 -126.571248)
		(width 0.14224)
		(layer "In2.Cu")
		(net "M_D_DQS_DN<7>")
	)
	(segment
		(start 293.6875 -105.44302)
		(end 294.85082 -106.60634)
		(width 0.14224)
		(layer "In2.Cu")
		(net "M_D_DQS_DN<7>")
	)
	(segment
		(start 311.954926 -135.240776)
		(end 312.387996 -135.673846)
		(width 0.14224)
		(layer "In2.Cu")
		(net "M_D_DQS_DN<7>")
	)
	(segment
		(start 311.71388 -116.853208)
		(end 311.71388 -117.436646)
		(width 0.14224)
		(layer "In2.Cu")
		(net "M_D_DQS_DN<7>")
	)
	(segment
		(start 313.97448 -126.159768)
		(end 313.97448 -126.413768)
		(width 0.14224)
		(layer "In2.Cu")
		(net "M_D_DQS_DN<7>")
	)
	(segment
		(start 313.294776 -128.641856)
		(end 313.294776 -128.772666)
		(width 0.14224)
		(layer "In2.Cu")
		(net "M_D_DQS_DN<7>")
	)
	(segment
		(start 312.667396 -130.280156)
		(end 312.387996 -130.280156)
		(width 0.14224)
		(layer "In2.Cu")
		(net "M_D_DQS_DN<7>")
	)
	(segment
		(start 313.605164 -128.462278)
		(end 313.474354 -128.462278)
		(width 0.14224)
		(layer "In2.Cu")
		(net "M_D_DQS_DN<7>")
	)
	(segment
		(start 311.197752 -115.845336)
		(end 311.509156 -115.845336)
		(width 0.14224)
		(layer "In2.Cu")
		(net "M_D_DQS_DN<7>")
	)
	(segment
		(start 313.817 -124.356368)
		(end 313.97448 -124.513848)
		(width 0.14224)
		(layer "In2.Cu")
		(net "M_D_DQS_DN<7>")
	)
	(segment
		(start 313.97448 -127.236728)
		(end 313.817 -127.394208)
		(width 0.14224)
		(layer "In2.Cu")
		(net "M_D_DQS_DN<7>")
	)
	(segment
		(start 288.93516 -99.490784)
		(end 288.93516 -99.15271)
		(width 0.0889)
		(layer "In2.Cu")
		(net "M_D_DQS_DN<7>")
	)
	(segment
		(start 310.928258 -116.11483)
		(end 311.197752 -115.845336)
		(width 0.14224)
		(layer "In2.Cu")
		(net "M_D_DQS_DN<7>")
	)
	(segment
		(start 289.28187 -100.681536)
		(end 289.27552 -100.692204)
		(width 0.0889)
		(layer "In2.Cu")
		(net "M_D_DQS_DN<7>")
	)
	(segment
		(start 313.817 -126.825248)
		(end 313.97448 -126.982728)
		(width 0.14224)
		(layer "In2.Cu")
		(net "M_D_DQS_DN<7>")
	)
	(segment
		(start 313.817 -124.102368)
		(end 313.817 -124.356368)
		(width 0.14224)
		(layer "In2.Cu")
		(net "M_D_DQS_DN<7>")
	)
	(segment
		(start 313.429904 -117.735858)
		(end 313.97448 -118.280434)
		(width 0.14224)
		(layer "In2.Cu")
		(net "M_D_DQS_DN<7>")
	)
	(segment
		(start 310.391302 -116.11483)
		(end 310.928258 -116.11483)
		(width 0.14224)
		(layer "In2.Cu")
		(net "M_D_DQS_DN<7>")
	)
	(segment
		(start 313.474354 -128.462278)
		(end 313.294776 -128.641856)
		(width 0.14224)
		(layer "In2.Cu")
		(net "M_D_DQS_DN<7>")
	)
	(segment
		(start 298.73194 -106.60634)
		(end 299.58284 -107.45724)
		(width 0.14224)
		(layer "In2.Cu")
		(net "M_D_DQS_DN<7>")
	)
	(segment
		(start 289.27552 -102.252018)
		(end 289.28822 -102.273354)
		(width 0.0889)
		(layer "In2.Cu")
		(net "M_D_DQS_DN<7>")
	)
	(segment
		(start 289.28187 -101.272086)
		(end 289.286696 -101.280722)
		(width 0.0889)
		(layer "In2.Cu")
		(net "M_D_DQS_DN<7>")
	)
	(arc
		(start 289.27552 -100.692204)
		(mid 289.202722 -100.982967)
		(end 289.28187 -101.272086)
		(width 0.0889)
		(layer "In2.Cu")
		(net "M_D_DQS_DN<7>")
	)
	(arc
		(start 289.286696 -101.280722)
		(mid 289.335451 -101.477074)
		(end 289.28187 -101.672136)
		(width 0.0889)
		(layer "In2.Cu")
		(net "M_D_DQS_DN<7>")
	)
	(arc
		(start 289.28187 -100.28174)
		(mid 289.335369 -100.481638)
		(end 289.28187 -100.681536)
		(width 0.0889)
		(layer "In2.Cu")
		(net "M_D_DQS_DN<7>")
	)
	(arc
		(start 289.28187 -101.672136)
		(mid 289.202648 -101.961254)
		(end 289.27552 -102.252018)
		(width 0.0889)
		(layer "In2.Cu")
		(net "M_D_DQS_DN<7>")
	)
	(arc
		(start 289.28187 -99.690936)
		(mid 289.202739 -99.986338)
		(end 289.28187 -100.28174)
		(width 0.0889)
		(layer "In2.Cu")
		(net "M_D_DQS_DN<7>")
	)
	(arc
		(start 288.993072 -99.094798)
		(mid 289.148322 -99.15208)
		(end 289.267138 -99.267264)
		(width 0.0889)
		(layer "In2.Cu")
		(net "M_D_DQS_DN<7>")
	)
	(arc
		(start 289.267138 -99.267264)
		(mid 289.335135 -99.476974)
		(end 289.28187 -99.690936)
		(width 0.0889)
		(layer "In2.Cu")
		(net "M_D_DQS_DN<7>")
	)
	(arc
		(start 289.28822 -102.273354)
		(mid 289.365279 -102.470359)
		(end 289.391598 -102.680262)
		(width 0.0889)
		(layer "In2.Cu")
		(net "M_D_DQS_DN<7>")
	)
	(segment
		(start 302.650398 -137.67054)
		(end 302.64989 -137.67054)
		(width 0.1651)
		(layer "F.Cu")
		(net "M_D_DQS_DN<6>")
	)
	(segment
		(start 283.212794 -99.490784)
		(end 283.784294 -99.490784)
		(width 0.1651)
		(layer "F.Cu")
		(net "M_D_DQS_DN<6>")
	)
	(segment
		(start 302.64989 -136.60247)
		(end 302.267874 -136.220454)
		(width 0.1651)
		(layer "F.Cu")
		(net "M_D_DQS_DN<6>")
	)
	(segment
		(start 302.822356 -135.4582)
		(end 303.038002 -135.673846)
		(width 0.1651)
		(layer "F.Cu")
		(net "M_D_DQS_DN<6>")
	)
	(segment
		(start 302.598328 -135.4582)
		(end 302.822356 -135.4582)
		(width 0.1651)
		(layer "F.Cu")
		(net "M_D_DQS_DN<6>")
	)
	(segment
		(start 302.64989 -137.67054)
		(end 302.64989 -136.60247)
		(width 0.1651)
		(layer "F.Cu")
		(net "M_D_DQS_DN<6>")
	)
	(segment
		(start 302.267874 -135.788654)
		(end 302.598328 -135.4582)
		(width 0.1651)
		(layer "F.Cu")
		(net "M_D_DQS_DN<6>")
	)
	(segment
		(start 302.267874 -136.220454)
		(end 302.267874 -135.788654)
		(width 0.1651)
		(layer "F.Cu")
		(net "M_D_DQS_DN<6>")
	)
	(via
		(at 283.784294 -99.490784)
		(size 0.508)
		(drill 0.254)
		(layers "F.Cu" "B.Cu")
		(net "M_D_DQS_DN<6>")
	)
	(via
		(at 303.038002 -130.280156)
		(size 0.508)
		(drill 0.254)
		(layers "F.Cu" "B.Cu")
		(net "M_D_DQS_DN<6>")
	)
	(via
		(at 303.038002 -135.673846)
		(size 0.508)
		(drill 0.254)
		(layers "F.Cu" "B.Cu")
		(net "M_D_DQS_DN<6>")
	)
	(segment
		(start 302.64989 -129.18313)
		(end 302.521874 -129.311146)
		(width 0.1651)
		(layer "B.Cu")
		(net "M_D_DQS_DN<6>")
	)
	(segment
		(start 302.267874 -129.819146)
		(end 302.267874 -130.1496)
		(width 0.1651)
		(layer "B.Cu")
		(net "M_D_DQS_DN<6>")
	)
	(segment
		(start 302.623474 -130.5052)
		(end 302.812958 -130.5052)
		(width 0.1651)
		(layer "B.Cu")
		(net "M_D_DQS_DN<6>")
	)
	(segment
		(start 302.650398 -128.276096)
		(end 302.64989 -128.276096)
		(width 0.1651)
		(layer "B.Cu")
		(net "M_D_DQS_DN<6>")
	)
	(segment
		(start 302.521874 -129.565146)
		(end 302.267874 -129.819146)
		(width 0.1651)
		(layer "B.Cu")
		(net "M_D_DQS_DN<6>")
	)
	(segment
		(start 302.812958 -130.5052)
		(end 303.038002 -130.280156)
		(width 0.1651)
		(layer "B.Cu")
		(net "M_D_DQS_DN<6>")
	)
	(segment
		(start 302.267874 -130.1496)
		(end 302.623474 -130.5052)
		(width 0.1651)
		(layer "B.Cu")
		(net "M_D_DQS_DN<6>")
	)
	(segment
		(start 302.64989 -128.276096)
		(end 302.64989 -129.18313)
		(width 0.1651)
		(layer "B.Cu")
		(net "M_D_DQS_DN<6>")
	)
	(segment
		(start 302.521874 -129.311146)
		(end 302.521874 -129.565146)
		(width 0.1651)
		(layer "B.Cu")
		(net "M_D_DQS_DN<6>")
	)
	(segment
		(start 296.16146 -116.310156)
		(end 296.16146 -115.862608)
		(width 0.14224)
		(layer "In2.Cu")
		(net "M_D_DQS_DN<6>")
	)
	(segment
		(start 299.074332 -115.64112)
		(end 301.8028 -118.369588)
		(width 0.14224)
		(layer "In2.Cu")
		(net "M_D_DQS_DN<6>")
	)
	(segment
		(start 303.038002 -130.280156)
		(end 302.96485 -130.280156)
		(width 0.14224)
		(layer "In2.Cu")
		(net "M_D_DQS_DN<6>")
	)
	(segment
		(start 284.051756 -105.940352)
		(end 283.918914 -106.073194)
		(width 0.0889)
		(layer "In2.Cu")
		(net "M_D_DQS_DN<6>")
	)
	(segment
		(start 302.604932 -133.985)
		(end 302.604932 -135.240776)
		(width 0.14224)
		(layer "In2.Cu")
		(net "M_D_DQS_DN<6>")
	)
	(segment
		(start 303.551082 -128.756664)
		(end 303.373282 -128.934464)
		(width 0.14224)
		(layer "In2.Cu")
		(net "M_D_DQS_DN<6>")
	)
	(segment
		(start 298.668948 -115.64112)
		(end 299.074332 -115.64112)
		(width 0.14224)
		(layer "In2.Cu")
		(net "M_D_DQS_DN<6>")
	)
	(segment
		(start 303.373282 -129.17424)
		(end 303.551082 -129.35204)
		(width 0.14224)
		(layer "In2.Cu")
		(net "M_D_DQS_DN<6>")
	)
	(segment
		(start 302.9966 -119.779288)
		(end 303.156112 -119.9388)
		(width 0.14224)
		(layer "In2.Cu")
		(net "M_D_DQS_DN<6>")
	)
	(segment
		(start 302.4124 -118.979188)
		(end 302.4124 -119.195088)
		(width 0.14224)
		(layer "In2.Cu")
		(net "M_D_DQS_DN<6>")
	)
	(segment
		(start 296.16146 -115.862608)
		(end 296.382948 -115.64112)
		(width 0.14224)
		(layer "In2.Cu")
		(net "M_D_DQS_DN<6>")
	)
	(segment
		(start 284.124654 -103.242618)
		(end 284.131004 -103.253286)
		(width 0.0889)
		(layer "In2.Cu")
		(net "M_D_DQS_DN<6>")
	)
	(segment
		(start 298.09694 -116.623592)
		(end 298.44746 -116.273072)
		(width 0.14224)
		(layer "In2.Cu")
		(net "M_D_DQS_DN<6>")
	)
	(segment
		(start 303.373282 -121.0056)
		(end 303.551082 -121.1834)
		(width 0.14224)
		(layer "In2.Cu")
		(net "M_D_DQS_DN<6>")
	)
	(segment
		(start 303.267618 -130.32994)
		(end 303.087786 -130.32994)
		(width 0.14224)
		(layer "In2.Cu")
		(net "M_D_DQS_DN<6>")
	)
	(segment
		(start 303.373282 -121.82856)
		(end 303.551082 -122.00636)
		(width 0.14224)
		(layer "In2.Cu")
		(net "M_D_DQS_DN<6>")
	)
	(segment
		(start 302.203612 -118.7704)
		(end 302.4124 -118.979188)
		(width 0.14224)
		(layer "In2.Cu")
		(net "M_D_DQS_DN<6>")
	)
	(segment
		(start 303.551082 -124.47524)
		(end 303.551082 -126.953264)
		(width 0.14224)
		(layer "In2.Cu")
		(net "M_D_DQS_DN<6>")
	)
	(segment
		(start 303.551082 -128.469136)
		(end 303.551082 -128.756664)
		(width 0.14224)
		(layer "In2.Cu")
		(net "M_D_DQS_DN<6>")
	)
	(segment
		(start 303.373282 -128.934464)
		(end 303.373282 -129.17424)
		(width 0.14224)
		(layer "In2.Cu")
		(net "M_D_DQS_DN<6>")
	)
	(segment
		(start 284.124654 -102.252018)
		(end 284.131004 -102.262686)
		(width 0.0889)
		(layer "In2.Cu")
		(net "M_D_DQS_DN<6>")
	)
	(segment
		(start 303.373282 -124.29744)
		(end 303.551082 -124.47524)
		(width 0.14224)
		(layer "In2.Cu")
		(net "M_D_DQS_DN<6>")
	)
	(segment
		(start 303.373282 -127.131064)
		(end 303.373282 -127.402336)
		(width 0.14224)
		(layer "In2.Cu")
		(net "M_D_DQS_DN<6>")
	)
	(segment
		(start 301.8028 -118.585488)
		(end 301.987712 -118.7704)
		(width 0.14224)
		(layer "In2.Cu")
		(net "M_D_DQS_DN<6>")
	)
	(segment
		(start 303.156112 -119.9388)
		(end 303.372012 -119.9388)
		(width 0.14224)
		(layer "In2.Cu")
		(net "M_D_DQS_DN<6>")
	)
	(segment
		(start 303.373282 -123.47448)
		(end 303.551082 -123.65228)
		(width 0.14224)
		(layer "In2.Cu")
		(net "M_D_DQS_DN<6>")
	)
	(segment
		(start 303.373282 -121.64568)
		(end 303.373282 -121.82856)
		(width 0.14224)
		(layer "In2.Cu")
		(net "M_D_DQS_DN<6>")
	)
	(segment
		(start 303.087786 -130.32994)
		(end 303.038002 -130.280156)
		(width 0.14224)
		(layer "In2.Cu")
		(net "M_D_DQS_DN<6>")
	)
	(segment
		(start 296.813732 -115.64112)
		(end 297.03522 -115.862608)
		(width 0.14224)
		(layer "In2.Cu")
		(net "M_D_DQS_DN<6>")
	)
	(segment
		(start 303.551082 -130.046476)
		(end 303.267618 -130.32994)
		(width 0.14224)
		(layer "In2.Cu")
		(net "M_D_DQS_DN<6>")
	)
	(segment
		(start 303.551082 -127.893064)
		(end 303.373282 -128.070864)
		(width 0.14224)
		(layer "In2.Cu")
		(net "M_D_DQS_DN<6>")
	)
	(segment
		(start 284.131004 -102.262686)
		(end 284.13583 -102.271322)
		(width 0.0889)
		(layer "In2.Cu")
		(net "M_D_DQS_DN<6>")
	)
	(segment
		(start 298.44746 -116.273072)
		(end 298.44746 -115.862608)
		(width 0.14224)
		(layer "In2.Cu")
		(net "M_D_DQS_DN<6>")
	)
	(segment
		(start 297.38574 -116.623592)
		(end 298.09694 -116.623592)
		(width 0.14224)
		(layer "In2.Cu")
		(net "M_D_DQS_DN<6>")
	)
	(segment
		(start 303.373282 -122.46864)
		(end 303.373282 -122.65152)
		(width 0.14224)
		(layer "In2.Cu")
		(net "M_D_DQS_DN<6>")
	)
	(segment
		(start 303.373282 -120.82272)
		(end 303.373282 -121.0056)
		(width 0.14224)
		(layer "In2.Cu")
		(net "M_D_DQS_DN<6>")
	)
	(segment
		(start 303.373282 -128.070864)
		(end 303.373282 -128.291336)
		(width 0.14224)
		(layer "In2.Cu")
		(net "M_D_DQS_DN<6>")
	)
	(segment
		(start 303.551082 -126.953264)
		(end 303.373282 -127.131064)
		(width 0.14224)
		(layer "In2.Cu")
		(net "M_D_DQS_DN<6>")
	)
	(segment
		(start 303.373282 -123.2916)
		(end 303.373282 -123.47448)
		(width 0.14224)
		(layer "In2.Cu")
		(net "M_D_DQS_DN<6>")
	)
	(segment
		(start 285.88716 -112.920526)
		(end 289.655758 -116.689124)
		(width 0.14224)
		(layer "In2.Cu")
		(net "M_D_DQS_DN<6>")
	)
	(segment
		(start 301.8028 -118.369588)
		(end 301.8028 -118.585488)
		(width 0.14224)
		(layer "In2.Cu")
		(net "M_D_DQS_DN<6>")
	)
	(segment
		(start 283.879544 -106.6292)
		(end 283.879544 -106.651298)
		(width 0.0889)
		(layer "In2.Cu")
		(net "M_D_DQS_DN<6>")
	)
	(segment
		(start 303.551082 -127.580136)
		(end 303.551082 -127.893064)
		(width 0.14224)
		(layer "In2.Cu")
		(net "M_D_DQS_DN<6>")
	)
	(segment
		(start 284.131004 -101.272086)
		(end 284.13583 -101.280722)
		(width 0.0889)
		(layer "In2.Cu")
		(net "M_D_DQS_DN<6>")
	)
	(segment
		(start 302.813212 -119.38)
		(end 302.9966 -119.563388)
		(width 0.14224)
		(layer "In2.Cu")
		(net "M_D_DQS_DN<6>")
	)
	(segment
		(start 302.597312 -119.38)
		(end 302.813212 -119.38)
		(width 0.14224)
		(layer "In2.Cu")
		(net "M_D_DQS_DN<6>")
	)
	(segment
		(start 303.551082 -129.35204)
		(end 303.551082 -130.046476)
		(width 0.14224)
		(layer "In2.Cu")
		(net "M_D_DQS_DN<6>")
	)
	(segment
		(start 303.373282 -127.402336)
		(end 303.551082 -127.580136)
		(width 0.14224)
		(layer "In2.Cu")
		(net "M_D_DQS_DN<6>")
	)
	(segment
		(start 284.131004 -103.253286)
		(end 284.13583 -103.261922)
		(width 0.0889)
		(layer "In2.Cu")
		(net "M_D_DQS_DN<6>")
	)
	(segment
		(start 303.551082 -122.82932)
		(end 303.551082 -123.1138)
		(width 0.14224)
		(layer "In2.Cu")
		(net "M_D_DQS_DN<6>")
	)
	(segment
		(start 302.96485 -130.280156)
		(end 302.604932 -130.640074)
		(width 0.14224)
		(layer "In2.Cu")
		(net "M_D_DQS_DN<6>")
	)
	(segment
		(start 302.394112 -132.11302)
		(end 302.394112 -133.77418)
		(width 0.14224)
		(layer "In2.Cu")
		(net "M_D_DQS_DN<6>")
	)
	(segment
		(start 302.604932 -130.640074)
		(end 302.604932 -131.9022)
		(width 0.14224)
		(layer "In2.Cu")
		(net "M_D_DQS_DN<6>")
	)
	(segment
		(start 289.655758 -116.689124)
		(end 295.782492 -116.689124)
		(width 0.14224)
		(layer "In2.Cu")
		(net "M_D_DQS_DN<6>")
	)
	(segment
		(start 283.879544 -110.143544)
		(end 285.88716 -112.15116)
		(width 0.14224)
		(layer "In2.Cu")
		(net "M_D_DQS_DN<6>")
	)
	(segment
		(start 303.373282 -124.11456)
		(end 303.373282 -124.29744)
		(width 0.14224)
		(layer "In2.Cu")
		(net "M_D_DQS_DN<6>")
	)
	(segment
		(start 283.918914 -106.58983)
		(end 283.879544 -106.6292)
		(width 0.0889)
		(layer "In2.Cu")
		(net "M_D_DQS_DN<6>")
	)
	(segment
		(start 302.394112 -133.77418)
		(end 302.604932 -133.985)
		(width 0.14224)
		(layer "In2.Cu")
		(net "M_D_DQS_DN<6>")
	)
	(segment
		(start 283.918914 -106.073194)
		(end 283.918914 -106.58983)
		(width 0.0889)
		(layer "In2.Cu")
		(net "M_D_DQS_DN<6>")
	)
	(segment
		(start 303.373282 -122.65152)
		(end 303.551082 -122.82932)
		(width 0.14224)
		(layer "In2.Cu")
		(net "M_D_DQS_DN<6>")
	)
	(segment
		(start 303.551082 -121.1834)
		(end 303.551082 -121.46788)
		(width 0.14224)
		(layer "In2.Cu")
		(net "M_D_DQS_DN<6>")
	)
	(segment
		(start 283.879544 -106.651298)
		(end 283.879544 -110.143544)
		(width 0.14224)
		(layer "In2.Cu")
		(net "M_D_DQS_DN<6>")
	)
	(segment
		(start 303.551082 -121.46788)
		(end 303.373282 -121.64568)
		(width 0.14224)
		(layer "In2.Cu")
		(net "M_D_DQS_DN<6>")
	)
	(segment
		(start 303.373282 -128.291336)
		(end 303.551082 -128.469136)
		(width 0.14224)
		(layer "In2.Cu")
		(net "M_D_DQS_DN<6>")
	)
	(segment
		(start 303.372012 -119.9388)
		(end 303.551082 -120.11787)
		(width 0.14224)
		(layer "In2.Cu")
		(net "M_D_DQS_DN<6>")
	)
	(segment
		(start 303.551082 -120.64492)
		(end 303.373282 -120.82272)
		(width 0.14224)
		(layer "In2.Cu")
		(net "M_D_DQS_DN<6>")
	)
	(segment
		(start 284.051756 -103.948992)
		(end 284.051756 -105.940352)
		(width 0.0889)
		(layer "In2.Cu")
		(net "M_D_DQS_DN<6>")
	)
	(segment
		(start 303.551082 -120.11787)
		(end 303.551082 -120.64492)
		(width 0.14224)
		(layer "In2.Cu")
		(net "M_D_DQS_DN<6>")
	)
	(segment
		(start 303.551082 -122.29084)
		(end 303.373282 -122.46864)
		(width 0.14224)
		(layer "In2.Cu")
		(net "M_D_DQS_DN<6>")
	)
	(segment
		(start 296.382948 -115.64112)
		(end 296.813732 -115.64112)
		(width 0.14224)
		(layer "In2.Cu")
		(net "M_D_DQS_DN<6>")
	)
	(segment
		(start 301.987712 -118.7704)
		(end 302.203612 -118.7704)
		(width 0.14224)
		(layer "In2.Cu")
		(net "M_D_DQS_DN<6>")
	)
	(segment
		(start 302.4124 -119.195088)
		(end 302.597312 -119.38)
		(width 0.14224)
		(layer "In2.Cu")
		(net "M_D_DQS_DN<6>")
	)
	(segment
		(start 302.604932 -135.240776)
		(end 303.038002 -135.673846)
		(width 0.14224)
		(layer "In2.Cu")
		(net "M_D_DQS_DN<6>")
	)
	(segment
		(start 303.551082 -122.00636)
		(end 303.551082 -122.29084)
		(width 0.14224)
		(layer "In2.Cu")
		(net "M_D_DQS_DN<6>")
	)
	(segment
		(start 303.551082 -123.1138)
		(end 303.373282 -123.2916)
		(width 0.14224)
		(layer "In2.Cu")
		(net "M_D_DQS_DN<6>")
	)
	(segment
		(start 297.03522 -116.273072)
		(end 297.38574 -116.623592)
		(width 0.14224)
		(layer "In2.Cu")
		(net "M_D_DQS_DN<6>")
	)
	(segment
		(start 303.551082 -123.93676)
		(end 303.373282 -124.11456)
		(width 0.14224)
		(layer "In2.Cu")
		(net "M_D_DQS_DN<6>")
	)
	(segment
		(start 297.03522 -115.862608)
		(end 297.03522 -116.273072)
		(width 0.14224)
		(layer "In2.Cu")
		(net "M_D_DQS_DN<6>")
	)
	(segment
		(start 303.551082 -123.65228)
		(end 303.551082 -123.93676)
		(width 0.14224)
		(layer "In2.Cu")
		(net "M_D_DQS_DN<6>")
	)
	(segment
		(start 302.604932 -131.9022)
		(end 302.394112 -132.11302)
		(width 0.14224)
		(layer "In2.Cu")
		(net "M_D_DQS_DN<6>")
	)
	(segment
		(start 295.782492 -116.689124)
		(end 296.16146 -116.310156)
		(width 0.14224)
		(layer "In2.Cu")
		(net "M_D_DQS_DN<6>")
	)
	(segment
		(start 298.44746 -115.862608)
		(end 298.668948 -115.64112)
		(width 0.14224)
		(layer "In2.Cu")
		(net "M_D_DQS_DN<6>")
	)
	(segment
		(start 284.124654 -101.261418)
		(end 284.131004 -101.272086)
		(width 0.0889)
		(layer "In2.Cu")
		(net "M_D_DQS_DN<6>")
	)
	(segment
		(start 285.88716 -112.15116)
		(end 285.88716 -112.920526)
		(width 0.14224)
		(layer "In2.Cu")
		(net "M_D_DQS_DN<6>")
	)
	(segment
		(start 302.9966 -119.563388)
		(end 302.9966 -119.779288)
		(width 0.14224)
		(layer "In2.Cu")
		(net "M_D_DQS_DN<6>")
	)
	(arc
		(start 283.784294 -99.490784)
		(mid 283.924667 -99.870663)
		(end 284.103572 -100.233988)
		(width 0.0889)
		(layer "In2.Cu")
		(net "M_D_DQS_DN<6>")
	)
	(arc
		(start 284.13583 -101.280722)
		(mid 284.184585 -101.477074)
		(end 284.131004 -101.672136)
		(width 0.0889)
		(layer "In2.Cu")
		(net "M_D_DQS_DN<6>")
	)
	(arc
		(start 284.13583 -102.271322)
		(mid 284.184585 -102.467674)
		(end 284.131004 -102.662736)
		(width 0.0889)
		(layer "In2.Cu")
		(net "M_D_DQS_DN<6>")
	)
	(arc
		(start 284.131004 -100.681536)
		(mid 284.051782 -100.970654)
		(end 284.124654 -101.261418)
		(width 0.0889)
		(layer "In2.Cu")
		(net "M_D_DQS_DN<6>")
	)
	(arc
		(start 284.131004 -102.662736)
		(mid 284.051782 -102.951854)
		(end 284.124654 -103.242618)
		(width 0.0889)
		(layer "In2.Cu")
		(net "M_D_DQS_DN<6>")
	)
	(arc
		(start 284.103572 -100.233988)
		(mid 284.119529 -100.262154)
		(end 284.13583 -100.290122)
		(width 0.0889)
		(layer "In2.Cu")
		(net "M_D_DQS_DN<6>")
	)
	(arc
		(start 284.13583 -100.290122)
		(mid 284.184585 -100.486474)
		(end 284.131004 -100.681536)
		(width 0.0889)
		(layer "In2.Cu")
		(net "M_D_DQS_DN<6>")
	)
	(arc
		(start 284.13583 -103.261922)
		(mid 284.184585 -103.458274)
		(end 284.131004 -103.653336)
		(width 0.0889)
		(layer "In2.Cu")
		(net "M_D_DQS_DN<6>")
	)
	(arc
		(start 284.131004 -103.653336)
		(mid 284.071879 -103.79594)
		(end 284.051756 -103.948992)
		(width 0.0889)
		(layer "In2.Cu")
		(net "M_D_DQS_DN<6>")
	)
	(arc
		(start 284.131004 -101.672136)
		(mid 284.051782 -101.961254)
		(end 284.124654 -102.252018)
		(width 0.0889)
		(layer "In2.Cu")
		(net "M_D_DQS_DN<6>")
	)
	(segment
		(start 293.472362 -135.4582)
		(end 293.688008 -135.673846)
		(width 0.1651)
		(layer "F.Cu")
		(net "M_D_DQS_DN<5>")
	)
	(segment
		(start 293.299896 -136.60247)
		(end 292.91788 -136.220454)
		(width 0.1651)
		(layer "F.Cu")
		(net "M_D_DQS_DN<5>")
	)
	(segment
		(start 293.299896 -137.67054)
		(end 293.299896 -136.60247)
		(width 0.1651)
		(layer "F.Cu")
		(net "M_D_DQS_DN<5>")
	)
	(segment
		(start 293.300404 -137.67054)
		(end 293.299896 -137.67054)
		(width 0.1651)
		(layer "F.Cu")
		(net "M_D_DQS_DN<5>")
	)
	(segment
		(start 292.91788 -135.788654)
		(end 293.248334 -135.4582)
		(width 0.1651)
		(layer "F.Cu")
		(net "M_D_DQS_DN<5>")
	)
	(segment
		(start 278.061674 -99.490784)
		(end 278.633174 -99.490784)
		(width 0.1651)
		(layer "F.Cu")
		(net "M_D_DQS_DN<5>")
	)
	(segment
		(start 292.91788 -136.220454)
		(end 292.91788 -135.788654)
		(width 0.1651)
		(layer "F.Cu")
		(net "M_D_DQS_DN<5>")
	)
	(segment
		(start 293.248334 -135.4582)
		(end 293.472362 -135.4582)
		(width 0.1651)
		(layer "F.Cu")
		(net "M_D_DQS_DN<5>")
	)
	(via
		(at 278.633174 -99.490784)
		(size 0.508)
		(drill 0.254)
		(layers "F.Cu" "B.Cu")
		(net "M_D_DQS_DN<5>")
	)
	(via
		(at 293.688008 -135.673846)
		(size 0.508)
		(drill 0.254)
		(layers "F.Cu" "B.Cu")
		(net "M_D_DQS_DN<5>")
	)
	(via
		(at 293.688008 -130.280156)
		(size 0.508)
		(drill 0.254)
		(layers "F.Cu" "B.Cu")
		(net "M_D_DQS_DN<5>")
	)
	(segment
		(start 293.299896 -128.276096)
		(end 293.299896 -129.18313)
		(width 0.1651)
		(layer "B.Cu")
		(net "M_D_DQS_DN<5>")
	)
	(segment
		(start 292.91788 -130.1496)
		(end 293.27348 -130.5052)
		(width 0.1651)
		(layer "B.Cu")
		(net "M_D_DQS_DN<5>")
	)
	(segment
		(start 293.17188 -129.565146)
		(end 292.91788 -129.819146)
		(width 0.1651)
		(layer "B.Cu")
		(net "M_D_DQS_DN<5>")
	)
	(segment
		(start 293.27348 -130.5052)
		(end 293.462964 -130.5052)
		(width 0.1651)
		(layer "B.Cu")
		(net "M_D_DQS_DN<5>")
	)
	(segment
		(start 293.300404 -128.276096)
		(end 293.299896 -128.276096)
		(width 0.1651)
		(layer "B.Cu")
		(net "M_D_DQS_DN<5>")
	)
	(segment
		(start 293.299896 -129.18313)
		(end 293.17188 -129.311146)
		(width 0.1651)
		(layer "B.Cu")
		(net "M_D_DQS_DN<5>")
	)
	(segment
		(start 292.91788 -129.819146)
		(end 292.91788 -130.1496)
		(width 0.1651)
		(layer "B.Cu")
		(net "M_D_DQS_DN<5>")
	)
	(segment
		(start 293.462964 -130.5052)
		(end 293.688008 -130.280156)
		(width 0.1651)
		(layer "B.Cu")
		(net "M_D_DQS_DN<5>")
	)
	(segment
		(start 293.17188 -129.311146)
		(end 293.17188 -129.565146)
		(width 0.1651)
		(layer "B.Cu")
		(net "M_D_DQS_DN<5>")
	)
	(segment
		(start 293.69385 -124.085096)
		(end 294.013382 -124.085096)
		(width 0.14224)
		(layer "In2.Cu")
		(net "M_D_DQS_DN<5>")
	)
	(segment
		(start 289.83305 -124.085096)
		(end 289.99053 -124.242576)
		(width 0.14224)
		(layer "In2.Cu")
		(net "M_D_DQS_DN<5>")
	)
	(segment
		(start 284.6324 -124.085096)
		(end 286.54121 -124.085096)
		(width 0.14224)
		(layer "In2.Cu")
		(net "M_D_DQS_DN<5>")
	)
	(segment
		(start 294.277288 -128.758442)
		(end 294.119808 -128.915922)
		(width 0.14224)
		(layer "In2.Cu")
		(net "M_D_DQS_DN<5>")
	)
	(segment
		(start 293.254938 -131.9022)
		(end 293.044118 -132.11302)
		(width 0.14224)
		(layer "In2.Cu")
		(net "M_D_DQS_DN<5>")
	)
	(segment
		(start 277.163022 -102.73411)
		(end 277.163022 -103.963216)
		(width 0.0889)
		(layer "In2.Cu")
		(net "M_D_DQS_DN<5>")
	)
	(segment
		(start 278.499824 -101.127814)
		(end 278.499824 -101.839014)
		(width 0.0889)
		(layer "In2.Cu")
		(net "M_D_DQS_DN<5>")
	)
	(segment
		(start 289.99053 -124.242576)
		(end 290.24453 -124.242576)
		(width 0.14224)
		(layer "In2.Cu")
		(net "M_D_DQS_DN<5>")
	)
	(segment
		(start 294.119808 -127.524002)
		(end 294.277288 -127.681482)
		(width 0.14224)
		(layer "In2.Cu")
		(net "M_D_DQS_DN<5>")
	)
	(segment
		(start 277.971504 -102.367334)
		(end 277.529798 -102.367334)
		(width 0.0889)
		(layer "In2.Cu")
		(net "M_D_DQS_DN<5>")
	)
	(segment
		(start 278.499824 -101.839014)
		(end 277.971504 -102.367334)
		(width 0.0889)
		(layer "In2.Cu")
		(net "M_D_DQS_DN<5>")
	)
	(segment
		(start 289.16757 -124.242576)
		(end 289.42157 -124.242576)
		(width 0.14224)
		(layer "In2.Cu")
		(net "M_D_DQS_DN<5>")
	)
	(segment
		(start 294.161972 -126.423166)
		(end 294.277288 -126.538482)
		(width 0.14224)
		(layer "In2.Cu")
		(net "M_D_DQS_DN<5>")
	)
	(segment
		(start 288.34461 -124.242576)
		(end 288.59861 -124.242576)
		(width 0.14224)
		(layer "In2.Cu")
		(net "M_D_DQS_DN<5>")
	)
	(segment
		(start 277.529798 -102.367334)
		(end 277.163022 -102.73411)
		(width 0.0889)
		(layer "In2.Cu")
		(net "M_D_DQS_DN<5>")
	)
	(segment
		(start 287.52165 -124.242576)
		(end 287.77565 -124.242576)
		(width 0.14224)
		(layer "In2.Cu")
		(net "M_D_DQS_DN<5>")
	)
	(segment
		(start 286.95269 -124.242576)
		(end 287.11017 -124.085096)
		(width 0.14224)
		(layer "In2.Cu")
		(net "M_D_DQS_DN<5>")
	)
	(segment
		(start 276.311614 -112.969548)
		(end 276.013926 -112.969548)
		(width 0.14224)
		(layer "In2.Cu")
		(net "M_D_DQS_DN<5>")
	)
	(segment
		(start 292.04793 -124.085096)
		(end 292.30193 -124.085096)
		(width 0.14224)
		(layer "In2.Cu")
		(net "M_D_DQS_DN<5>")
	)
	(segment
		(start 276.013926 -112.969548)
		(end 275.707094 -113.27638)
		(width 0.14224)
		(layer "In2.Cu")
		(net "M_D_DQS_DN<5>")
	)
	(segment
		(start 288.18713 -124.085096)
		(end 288.34461 -124.242576)
		(width 0.14224)
		(layer "In2.Cu")
		(net "M_D_DQS_DN<5>")
	)
	(segment
		(start 287.77565 -124.242576)
		(end 287.93313 -124.085096)
		(width 0.14224)
		(layer "In2.Cu")
		(net "M_D_DQS_DN<5>")
	)
	(segment
		(start 276.505924 -104.620314)
		(end 276.505924 -106.23423)
		(width 0.0889)
		(layer "In2.Cu")
		(net "M_D_DQS_DN<5>")
	)
	(segment
		(start 276.505924 -106.23423)
		(end 276.466554 -106.2736)
		(width 0.0889)
		(layer "In2.Cu")
		(net "M_D_DQS_DN<5>")
	)
	(segment
		(start 294.119808 -128.346962)
		(end 294.277288 -128.504442)
		(width 0.14224)
		(layer "In2.Cu")
		(net "M_D_DQS_DN<5>")
	)
	(segment
		(start 294.277288 -129.327402)
		(end 294.277288 -129.970276)
		(width 0.14224)
		(layer "In2.Cu")
		(net "M_D_DQS_DN<5>")
	)
	(segment
		(start 294.277288 -125.657864)
		(end 294.277288 -126.05385)
		(width 0.14224)
		(layer "In2.Cu")
		(net "M_D_DQS_DN<5>")
	)
	(segment
		(start 289.01009 -124.085096)
		(end 289.16757 -124.242576)
		(width 0.14224)
		(layer "In2.Cu")
		(net "M_D_DQS_DN<5>")
	)
	(segment
		(start 293.688008 -130.280156)
		(end 293.614856 -130.280156)
		(width 0.14224)
		(layer "In2.Cu")
		(net "M_D_DQS_DN<5>")
	)
	(segment
		(start 294.153336 -125.533912)
		(end 294.277288 -125.657864)
		(width 0.14224)
		(layer "In2.Cu")
		(net "M_D_DQS_DN<5>")
	)
	(segment
		(start 276.466554 -115.91925)
		(end 284.6324 -124.085096)
		(width 0.14224)
		(layer "In2.Cu")
		(net "M_D_DQS_DN<5>")
	)
	(segment
		(start 294.119808 -128.092962)
		(end 294.119808 -128.346962)
		(width 0.14224)
		(layer "In2.Cu")
		(net "M_D_DQS_DN<5>")
	)
	(segment
		(start 294.013382 -124.085096)
		(end 294.277288 -124.349002)
		(width 0.14224)
		(layer "In2.Cu")
		(net "M_D_DQS_DN<5>")
	)
	(segment
		(start 294.277288 -129.970276)
		(end 293.967408 -130.280156)
		(width 0.14224)
		(layer "In2.Cu")
		(net "M_D_DQS_DN<5>")
	)
	(segment
		(start 276.025102 -114.170968)
		(end 276.311614 -114.170968)
		(width 0.14224)
		(layer "In2.Cu")
		(net "M_D_DQS_DN<5>")
	)
	(segment
		(start 294.277288 -127.935482)
		(end 294.119808 -128.092962)
		(width 0.14224)
		(layer "In2.Cu")
		(net "M_D_DQS_DN<5>")
	)
	(segment
		(start 287.11017 -124.085096)
		(end 287.36417 -124.085096)
		(width 0.14224)
		(layer "In2.Cu")
		(net "M_D_DQS_DN<5>")
	)
	(segment
		(start 291.89045 -124.242576)
		(end 292.04793 -124.085096)
		(width 0.14224)
		(layer "In2.Cu")
		(net "M_D_DQS_DN<5>")
	)
	(segment
		(start 276.466554 -106.295698)
		(end 276.466554 -112.814608)
		(width 0.14224)
		(layer "In2.Cu")
		(net "M_D_DQS_DN<5>")
	)
	(segment
		(start 277.163022 -103.963216)
		(end 276.505924 -104.620314)
		(width 0.0889)
		(layer "In2.Cu")
		(net "M_D_DQS_DN<5>")
	)
	(segment
		(start 289.57905 -124.085096)
		(end 289.83305 -124.085096)
		(width 0.14224)
		(layer "In2.Cu")
		(net "M_D_DQS_DN<5>")
	)
	(segment
		(start 286.54121 -124.085096)
		(end 286.69869 -124.242576)
		(width 0.14224)
		(layer "In2.Cu")
		(net "M_D_DQS_DN<5>")
	)
	(segment
		(start 293.53637 -124.242576)
		(end 293.69385 -124.085096)
		(width 0.14224)
		(layer "In2.Cu")
		(net "M_D_DQS_DN<5>")
	)
	(segment
		(start 292.71341 -124.242576)
		(end 292.87089 -124.085096)
		(width 0.14224)
		(layer "In2.Cu")
		(net "M_D_DQS_DN<5>")
	)
	(segment
		(start 293.254938 -135.240776)
		(end 293.688008 -135.673846)
		(width 0.14224)
		(layer "In2.Cu")
		(net "M_D_DQS_DN<5>")
	)
	(segment
		(start 292.87089 -124.085096)
		(end 293.12489 -124.085096)
		(width 0.14224)
		(layer "In2.Cu")
		(net "M_D_DQS_DN<5>")
	)
	(segment
		(start 294.119808 -127.270002)
		(end 294.119808 -127.524002)
		(width 0.14224)
		(layer "In2.Cu")
		(net "M_D_DQS_DN<5>")
	)
	(segment
		(start 293.28237 -124.242576)
		(end 293.53637 -124.242576)
		(width 0.14224)
		(layer "In2.Cu")
		(net "M_D_DQS_DN<5>")
	)
	(segment
		(start 276.466554 -106.2736)
		(end 276.466554 -106.295698)
		(width 0.0889)
		(layer "In2.Cu")
		(net "M_D_DQS_DN<5>")
	)
	(segment
		(start 292.30193 -124.085096)
		(end 292.45941 -124.242576)
		(width 0.14224)
		(layer "In2.Cu")
		(net "M_D_DQS_DN<5>")
	)
	(segment
		(start 294.119808 -129.169922)
		(end 294.277288 -129.327402)
		(width 0.14224)
		(layer "In2.Cu")
		(net "M_D_DQS_DN<5>")
	)
	(segment
		(start 279.033478 -100.59416)
		(end 278.499824 -101.127814)
		(width 0.0889)
		(layer "In2.Cu")
		(net "M_D_DQS_DN<5>")
	)
	(segment
		(start 294.277288 -127.681482)
		(end 294.277288 -127.935482)
		(width 0.14224)
		(layer "In2.Cu")
		(net "M_D_DQS_DN<5>")
	)
	(segment
		(start 289.42157 -124.242576)
		(end 289.57905 -124.085096)
		(width 0.14224)
		(layer "In2.Cu")
		(net "M_D_DQS_DN<5>")
	)
	(segment
		(start 294.277288 -125.15596)
		(end 294.153336 -125.279912)
		(width 0.14224)
		(layer "In2.Cu")
		(net "M_D_DQS_DN<5>")
	)
	(segment
		(start 291.47897 -124.085096)
		(end 291.63645 -124.242576)
		(width 0.14224)
		(layer "In2.Cu")
		(net "M_D_DQS_DN<5>")
	)
	(segment
		(start 292.45941 -124.242576)
		(end 292.71341 -124.242576)
		(width 0.14224)
		(layer "In2.Cu")
		(net "M_D_DQS_DN<5>")
	)
	(segment
		(start 288.59861 -124.242576)
		(end 288.75609 -124.085096)
		(width 0.14224)
		(layer "In2.Cu")
		(net "M_D_DQS_DN<5>")
	)
	(segment
		(start 276.466554 -112.814608)
		(end 276.311614 -112.969548)
		(width 0.14224)
		(layer "In2.Cu")
		(net "M_D_DQS_DN<5>")
	)
	(segment
		(start 293.044118 -132.11302)
		(end 293.044118 -133.77418)
		(width 0.14224)
		(layer "In2.Cu")
		(net "M_D_DQS_DN<5>")
	)
	(segment
		(start 294.119808 -128.915922)
		(end 294.119808 -129.169922)
		(width 0.14224)
		(layer "In2.Cu")
		(net "M_D_DQS_DN<5>")
	)
	(segment
		(start 275.707094 -113.85296)
		(end 276.025102 -114.170968)
		(width 0.14224)
		(layer "In2.Cu")
		(net "M_D_DQS_DN<5>")
	)
	(segment
		(start 293.614856 -130.280156)
		(end 293.254938 -130.640074)
		(width 0.14224)
		(layer "In2.Cu")
		(net "M_D_DQS_DN<5>")
	)
	(segment
		(start 293.12489 -124.085096)
		(end 293.28237 -124.242576)
		(width 0.14224)
		(layer "In2.Cu")
		(net "M_D_DQS_DN<5>")
	)
	(segment
		(start 290.24453 -124.242576)
		(end 290.40201 -124.085096)
		(width 0.14224)
		(layer "In2.Cu")
		(net "M_D_DQS_DN<5>")
	)
	(segment
		(start 286.69869 -124.242576)
		(end 286.95269 -124.242576)
		(width 0.14224)
		(layer "In2.Cu")
		(net "M_D_DQS_DN<5>")
	)
	(segment
		(start 294.161972 -126.169166)
		(end 294.161972 -126.423166)
		(width 0.14224)
		(layer "In2.Cu")
		(net "M_D_DQS_DN<5>")
	)
	(segment
		(start 294.277288 -128.504442)
		(end 294.277288 -128.758442)
		(width 0.14224)
		(layer "In2.Cu")
		(net "M_D_DQS_DN<5>")
	)
	(segment
		(start 294.277288 -126.05385)
		(end 294.161972 -126.169166)
		(width 0.14224)
		(layer "In2.Cu")
		(net "M_D_DQS_DN<5>")
	)
	(segment
		(start 287.36417 -124.085096)
		(end 287.52165 -124.242576)
		(width 0.14224)
		(layer "In2.Cu")
		(net "M_D_DQS_DN<5>")
	)
	(segment
		(start 288.75609 -124.085096)
		(end 289.01009 -124.085096)
		(width 0.14224)
		(layer "In2.Cu")
		(net "M_D_DQS_DN<5>")
	)
	(segment
		(start 275.707094 -113.27638)
		(end 275.707094 -113.85296)
		(width 0.14224)
		(layer "In2.Cu")
		(net "M_D_DQS_DN<5>")
	)
	(segment
		(start 287.93313 -124.085096)
		(end 288.18713 -124.085096)
		(width 0.14224)
		(layer "In2.Cu")
		(net "M_D_DQS_DN<5>")
	)
	(segment
		(start 293.044118 -133.77418)
		(end 293.254938 -133.985)
		(width 0.14224)
		(layer "In2.Cu")
		(net "M_D_DQS_DN<5>")
	)
	(segment
		(start 294.277288 -127.112522)
		(end 294.119808 -127.270002)
		(width 0.14224)
		(layer "In2.Cu")
		(net "M_D_DQS_DN<5>")
	)
	(segment
		(start 294.277288 -124.349002)
		(end 294.277288 -125.15596)
		(width 0.14224)
		(layer "In2.Cu")
		(net "M_D_DQS_DN<5>")
	)
	(segment
		(start 293.254938 -130.640074)
		(end 293.254938 -131.9022)
		(width 0.14224)
		(layer "In2.Cu")
		(net "M_D_DQS_DN<5>")
	)
	(segment
		(start 293.967408 -130.280156)
		(end 293.688008 -130.280156)
		(width 0.14224)
		(layer "In2.Cu")
		(net "M_D_DQS_DN<5>")
	)
	(segment
		(start 276.311614 -114.170968)
		(end 276.466554 -114.325908)
		(width 0.14224)
		(layer "In2.Cu")
		(net "M_D_DQS_DN<5>")
	)
	(segment
		(start 294.153336 -125.279912)
		(end 294.153336 -125.533912)
		(width 0.14224)
		(layer "In2.Cu")
		(net "M_D_DQS_DN<5>")
	)
	(segment
		(start 294.277288 -126.538482)
		(end 294.277288 -127.112522)
		(width 0.14224)
		(layer "In2.Cu")
		(net "M_D_DQS_DN<5>")
	)
	(segment
		(start 293.254938 -133.985)
		(end 293.254938 -135.240776)
		(width 0.14224)
		(layer "In2.Cu")
		(net "M_D_DQS_DN<5>")
	)
	(segment
		(start 279.033478 -100.481892)
		(end 279.033478 -100.59416)
		(width 0.0889)
		(layer "In2.Cu")
		(net "M_D_DQS_DN<5>")
	)
	(segment
		(start 291.63645 -124.242576)
		(end 291.89045 -124.242576)
		(width 0.14224)
		(layer "In2.Cu")
		(net "M_D_DQS_DN<5>")
	)
	(segment
		(start 276.466554 -114.325908)
		(end 276.466554 -115.91925)
		(width 0.14224)
		(layer "In2.Cu")
		(net "M_D_DQS_DN<5>")
	)
	(segment
		(start 290.40201 -124.085096)
		(end 291.47897 -124.085096)
		(width 0.14224)
		(layer "In2.Cu")
		(net "M_D_DQS_DN<5>")
	)
	(arc
		(start 278.979884 -100.281994)
		(mid 279.019838 -100.378418)
		(end 279.033478 -100.481892)
		(width 0.0889)
		(layer "In2.Cu")
		(net "M_D_DQS_DN<5>")
	)
	(arc
		(start 278.633174 -99.490784)
		(mid 278.784646 -99.895978)
		(end 278.979884 -100.281994)
		(width 0.0889)
		(layer "In2.Cu")
		(net "M_D_DQS_DN<5>")
	)
	(segment
		(start 282.496768 -124.272802)
		(end 282.496768 -124.495814)
		(width 0.1651)
		(layer "F.Cu")
		(net "M_D_DQS_DN<4>")
	)
	(segment
		(start 275.486114 -103.364538)
		(end 275.528024 -103.406448)
		(width 0.0889)
		(layer "F.Cu")
		(net "M_D_DQS_DN<4>")
	)
	(segment
		(start 284.69844 -129.305558)
		(end 284.69844 -129.559558)
		(width 0.1651)
		(layer "F.Cu")
		(net "M_D_DQS_DN<4>")
	)
	(segment
		(start 284.69844 -128.035558)
		(end 284.82544 -128.162558)
		(width 0.1651)
		(layer "F.Cu")
		(net "M_D_DQS_DN<4>")
	)
	(segment
		(start 278.786082 -119.832628)
		(end 278.59863 -120.02008)
		(width 0.1651)
		(layer "F.Cu")
		(net "M_D_DQS_DN<4>")
	)
	(segment
		(start 281.130756 -122.90679)
		(end 281.310334 -123.086368)
		(width 0.1651)
		(layer "F.Cu")
		(net "M_D_DQS_DN<4>")
	)
	(segment
		(start 284.82544 -128.416558)
		(end 284.69844 -128.543558)
		(width 0.1651)
		(layer "F.Cu")
		(net "M_D_DQS_DN<4>")
	)
	(segment
		(start 282.094432 -124.093224)
		(end 282.31719 -124.093224)
		(width 0.1651)
		(layer "F.Cu")
		(net "M_D_DQS_DN<4>")
	)
	(segment
		(start 280.17851 -121.45518)
		(end 280.17851 -121.954544)
		(width 0.1651)
		(layer "F.Cu")
		(net "M_D_DQS_DN<4>")
	)
	(segment
		(start 284.82544 -128.162558)
		(end 284.82544 -128.416558)
		(width 0.1651)
		(layer "F.Cu")
		(net "M_D_DQS_DN<4>")
	)
	(segment
		(start 275.528024 -103.406448)
		(end 275.528024 -104.786176)
		(width 0.0889)
		(layer "F.Cu")
		(net "M_D_DQS_DN<4>")
	)
	(segment
		(start 278.786082 -119.517922)
		(end 278.786082 -119.832628)
		(width 0.1651)
		(layer "F.Cu")
		(net "M_D_DQS_DN<4>")
	)
	(segment
		(start 275.1582 -113.3221)
		(end 275.209 -113.3729)
		(width 0.1016)
		(layer "F.Cu")
		(net "M_D_DQS_DN<4>")
	)
	(segment
		(start 282.899358 -124.675392)
		(end 283.078936 -124.85497)
		(width 0.1651)
		(layer "F.Cu")
		(net "M_D_DQS_DN<4>")
	)
	(segment
		(start 276.14626 -114.710464)
		(end 276.14626 -114.890042)
		(width 0.1651)
		(layer "F.Cu")
		(net "M_D_DQS_DN<4>")
	)
	(segment
		(start 283.567632 -135.788654)
		(end 283.567632 -136.220454)
		(width 0.1651)
		(layer "F.Cu")
		(net "M_D_DQS_DN<4>")
	)
	(segment
		(start 279.080468 -120.996202)
		(end 279.613106 -120.996202)
		(width 0.1651)
		(layer "F.Cu")
		(net "M_D_DQS_DN<4>")
	)
	(segment
		(start 277.970742 -119.376698)
		(end 278.171656 -119.175784)
		(width 0.1651)
		(layer "F.Cu")
		(net "M_D_DQS_DN<4>")
	)
	(segment
		(start 278.443944 -119.175784)
		(end 278.786082 -119.517922)
		(width 0.1651)
		(layer "F.Cu")
		(net "M_D_DQS_DN<4>")
	)
	(segment
		(start 275.224494 -113.388394)
		(end 275.224494 -113.788698)
		(width 0.1651)
		(layer "F.Cu")
		(net "M_D_DQS_DN<4>")
	)
	(segment
		(start 280.039572 -120.77065)
		(end 280.325322 -121.0564)
		(width 0.1651)
		(layer "F.Cu")
		(net "M_D_DQS_DN<4>")
	)
	(segment
		(start 277.106888 -118.962424)
		(end 277.521162 -119.376698)
		(width 0.1651)
		(layer "F.Cu")
		(net "M_D_DQS_DN<4>")
	)
	(segment
		(start 275.1582 -113.0808)
		(end 275.1582 -113.3221)
		(width 0.1016)
		(layer "F.Cu")
		(net "M_D_DQS_DN<4>")
	)
	(segment
		(start 284.82544 -129.178558)
		(end 284.69844 -129.305558)
		(width 0.1651)
		(layer "F.Cu")
		(net "M_D_DQS_DN<4>")
	)
	(segment
		(start 282.6766 -124.675392)
		(end 282.899358 -124.675392)
		(width 0.1651)
		(layer "F.Cu")
		(net "M_D_DQS_DN<4>")
	)
	(segment
		(start 283.661104 -125.66015)
		(end 283.840936 -125.839728)
		(width 0.1651)
		(layer "F.Cu")
		(net "M_D_DQS_DN<4>")
	)
	(segment
		(start 283.661104 -125.437138)
		(end 283.661104 -125.66015)
		(width 0.1651)
		(layer "F.Cu")
		(net "M_D_DQS_DN<4>")
	)
	(segment
		(start 274.759674 -106.570526)
		(end 274.759674 -112.682274)
		(width 0.1016)
		(layer "F.Cu")
		(net "M_D_DQS_DN<4>")
	)
	(segment
		(start 283.258768 -125.25756)
		(end 283.481526 -125.25756)
		(width 0.1651)
		(layer "F.Cu")
		(net "M_D_DQS_DN<4>")
	)
	(segment
		(start 283.949648 -136.60247)
		(end 283.949648 -137.67054)
		(width 0.1651)
		(layer "F.Cu")
		(net "M_D_DQS_DN<4>")
	)
	(segment
		(start 276.86508 -115.608862)
		(end 277.044658 -115.608862)
		(width 0.1651)
		(layer "F.Cu")
		(net "M_D_DQS_DN<4>")
	)
	(segment
		(start 284.82544 -126.892558)
		(end 284.69844 -127.019558)
		(width 0.1651)
		(layer "F.Cu")
		(net "M_D_DQS_DN<4>")
	)
	(segment
		(start 284.82544 -130.039872)
		(end 284.585156 -130.280156)
		(width 0.1651)
		(layer "F.Cu")
		(net "M_D_DQS_DN<4>")
	)
	(segment
		(start 275.787104 -114.530886)
		(end 275.966682 -114.530886)
		(width 0.1651)
		(layer "F.Cu")
		(net "M_D_DQS_DN<4>")
	)
	(segment
		(start 280.325322 -121.0564)
		(end 280.325322 -121.308368)
		(width 0.1651)
		(layer "F.Cu")
		(net "M_D_DQS_DN<4>")
	)
	(segment
		(start 281.310334 -123.086368)
		(end 281.310334 -123.309126)
		(width 0.1651)
		(layer "F.Cu")
		(net "M_D_DQS_DN<4>")
	)
	(segment
		(start 284.243272 -126.019306)
		(end 284.243272 -126.242318)
		(width 0.1651)
		(layer "F.Cu")
		(net "M_D_DQS_DN<4>")
	)
	(segment
		(start 275.224494 -113.788698)
		(end 275.607272 -114.171476)
		(width 0.1651)
		(layer "F.Cu")
		(net "M_D_DQS_DN<4>")
	)
	(segment
		(start 284.423104 -126.421896)
		(end 284.645862 -126.421896)
		(width 0.1651)
		(layer "F.Cu")
		(net "M_D_DQS_DN<4>")
	)
	(segment
		(start 283.840936 -125.839728)
		(end 284.063694 -125.839728)
		(width 0.1651)
		(layer "F.Cu")
		(net "M_D_DQS_DN<4>")
	)
	(segment
		(start 277.521162 -119.376698)
		(end 277.970742 -119.376698)
		(width 0.1651)
		(layer "F.Cu")
		(net "M_D_DQS_DN<4>")
	)
	(segment
		(start 284.82544 -128.924558)
		(end 284.82544 -129.178558)
		(width 0.1651)
		(layer "F.Cu")
		(net "M_D_DQS_DN<4>")
	)
	(segment
		(start 284.122114 -135.4582)
		(end 283.898086 -135.4582)
		(width 0.1651)
		(layer "F.Cu")
		(net "M_D_DQS_DN<4>")
	)
	(segment
		(start 284.33776 -135.673846)
		(end 284.122114 -135.4582)
		(width 0.1651)
		(layer "F.Cu")
		(net "M_D_DQS_DN<4>")
	)
	(segment
		(start 284.69844 -127.273558)
		(end 284.82544 -127.400558)
		(width 0.1651)
		(layer "F.Cu")
		(net "M_D_DQS_DN<4>")
	)
	(segment
		(start 277.193502 -117.154706)
		(end 277.193502 -117.408706)
		(width 0.1651)
		(layer "F.Cu")
		(net "M_D_DQS_DN<4>")
	)
	(segment
		(start 278.59863 -120.514364)
		(end 279.080468 -120.996202)
		(width 0.1651)
		(layer "F.Cu")
		(net "M_D_DQS_DN<4>")
	)
	(segment
		(start 284.243272 -126.242318)
		(end 284.423104 -126.421896)
		(width 0.1651)
		(layer "F.Cu")
		(net "M_D_DQS_DN<4>")
	)
	(segment
		(start 276.685248 -115.249452)
		(end 276.685248 -115.42903)
		(width 0.1651)
		(layer "F.Cu")
		(net "M_D_DQS_DN<4>")
	)
	(segment
		(start 283.078936 -125.077982)
		(end 283.258768 -125.25756)
		(width 0.1651)
		(layer "F.Cu")
		(net "M_D_DQS_DN<4>")
	)
	(segment
		(start 276.326092 -115.069874)
		(end 276.50567 -115.069874)
		(width 0.1651)
		(layer "F.Cu")
		(net "M_D_DQS_DN<4>")
	)
	(segment
		(start 280.907998 -122.90679)
		(end 281.130756 -122.90679)
		(width 0.1651)
		(layer "F.Cu")
		(net "M_D_DQS_DN<4>")
	)
	(segment
		(start 284.69844 -128.543558)
		(end 284.69844 -128.797558)
		(width 0.1651)
		(layer "F.Cu")
		(net "M_D_DQS_DN<4>")
	)
	(segment
		(start 275.486114 -102.958138)
		(end 275.486114 -103.364538)
		(width 0.0889)
		(layer "F.Cu")
		(net "M_D_DQS_DN<4>")
	)
	(segment
		(start 277.193502 -117.408706)
		(end 277.320502 -117.535706)
		(width 0.1651)
		(layer "F.Cu")
		(net "M_D_DQS_DN<4>")
	)
	(segment
		(start 280.728166 -122.727212)
		(end 280.907998 -122.90679)
		(width 0.1651)
		(layer "F.Cu")
		(net "M_D_DQS_DN<4>")
	)
	(segment
		(start 276.14626 -114.890042)
		(end 276.326092 -115.069874)
		(width 0.1651)
		(layer "F.Cu")
		(net "M_D_DQS_DN<4>")
	)
	(segment
		(start 281.489912 -123.488704)
		(end 281.71267 -123.488704)
		(width 0.1651)
		(layer "F.Cu")
		(net "M_D_DQS_DN<4>")
	)
	(segment
		(start 284.82544 -127.654558)
		(end 284.69844 -127.781558)
		(width 0.1651)
		(layer "F.Cu")
		(net "M_D_DQS_DN<4>")
	)
	(segment
		(start 280.728166 -122.5042)
		(end 280.728166 -122.727212)
		(width 0.1651)
		(layer "F.Cu")
		(net "M_D_DQS_DN<4>")
	)
	(segment
		(start 278.171656 -119.175784)
		(end 278.443944 -119.175784)
		(width 0.1651)
		(layer "F.Cu")
		(net "M_D_DQS_DN<4>")
	)
	(segment
		(start 281.9146 -123.690634)
		(end 281.9146 -123.913646)
		(width 0.1651)
		(layer "F.Cu")
		(net "M_D_DQS_DN<4>")
	)
	(segment
		(start 283.949648 -137.67054)
		(end 283.95041 -137.67054)
		(width 0.1651)
		(layer "F.Cu")
		(net "M_D_DQS_DN<4>")
	)
	(segment
		(start 282.496768 -124.495814)
		(end 282.6766 -124.675392)
		(width 0.1651)
		(layer "F.Cu")
		(net "M_D_DQS_DN<4>")
	)
	(segment
		(start 284.69844 -128.797558)
		(end 284.82544 -128.924558)
		(width 0.1651)
		(layer "F.Cu")
		(net "M_D_DQS_DN<4>")
	)
	(segment
		(start 283.567632 -136.220454)
		(end 283.949648 -136.60247)
		(width 0.1651)
		(layer "F.Cu")
		(net "M_D_DQS_DN<4>")
	)
	(segment
		(start 284.82544 -129.686558)
		(end 284.82544 -130.039872)
		(width 0.1651)
		(layer "F.Cu")
		(net "M_D_DQS_DN<4>")
	)
	(segment
		(start 277.320502 -118.247414)
		(end 277.106888 -118.461028)
		(width 0.1651)
		(layer "F.Cu")
		(net "M_D_DQS_DN<4>")
	)
	(segment
		(start 277.320502 -117.027706)
		(end 277.193502 -117.154706)
		(width 0.1651)
		(layer "F.Cu")
		(net "M_D_DQS_DN<4>")
	)
	(segment
		(start 284.69844 -127.781558)
		(end 284.69844 -128.035558)
		(width 0.1651)
		(layer "F.Cu")
		(net "M_D_DQS_DN<4>")
	)
	(segment
		(start 284.82544 -126.601474)
		(end 284.82544 -126.892558)
		(width 0.1651)
		(layer "F.Cu")
		(net "M_D_DQS_DN<4>")
	)
	(segment
		(start 277.320502 -115.884706)
		(end 277.320502 -117.027706)
		(width 0.1651)
		(layer "F.Cu")
		(net "M_D_DQS_DN<4>")
	)
	(segment
		(start 281.71267 -123.488704)
		(end 281.9146 -123.690634)
		(width 0.1651)
		(layer "F.Cu")
		(net "M_D_DQS_DN<4>")
	)
	(segment
		(start 284.585156 -130.280156)
		(end 284.33776 -130.280156)
		(width 0.1651)
		(layer "F.Cu")
		(net "M_D_DQS_DN<4>")
	)
	(segment
		(start 283.898086 -135.4582)
		(end 283.567632 -135.788654)
		(width 0.1651)
		(layer "F.Cu")
		(net "M_D_DQS_DN<4>")
	)
	(segment
		(start 277.044658 -115.608862)
		(end 277.320502 -115.884706)
		(width 0.1651)
		(layer "F.Cu")
		(net "M_D_DQS_DN<4>")
	)
	(segment
		(start 280.325322 -121.308368)
		(end 280.17851 -121.45518)
		(width 0.1651)
		(layer "F.Cu")
		(net "M_D_DQS_DN<4>")
	)
	(segment
		(start 274.759674 -112.682274)
		(end 275.1582 -113.0808)
		(width 0.1016)
		(layer "F.Cu")
		(net "M_D_DQS_DN<4>")
	)
	(segment
		(start 275.966682 -114.530886)
		(end 276.14626 -114.710464)
		(width 0.1651)
		(layer "F.Cu")
		(net "M_D_DQS_DN<4>")
	)
	(segment
		(start 275.607272 -114.171476)
		(end 275.607272 -114.351054)
		(width 0.1651)
		(layer "F.Cu")
		(net "M_D_DQS_DN<4>")
	)
	(segment
		(start 276.685248 -115.42903)
		(end 276.86508 -115.608862)
		(width 0.1651)
		(layer "F.Cu")
		(net "M_D_DQS_DN<4>")
	)
	(segment
		(start 284.69844 -129.559558)
		(end 284.82544 -129.686558)
		(width 0.1651)
		(layer "F.Cu")
		(net "M_D_DQS_DN<4>")
	)
	(segment
		(start 279.838658 -120.77065)
		(end 280.039572 -120.77065)
		(width 0.1651)
		(layer "F.Cu")
		(net "M_D_DQS_DN<4>")
	)
	(segment
		(start 276.50567 -115.069874)
		(end 276.685248 -115.249452)
		(width 0.1651)
		(layer "F.Cu")
		(net "M_D_DQS_DN<4>")
	)
	(segment
		(start 274.861274 -106.468926)
		(end 274.759674 -106.570526)
		(width 0.0889)
		(layer "F.Cu")
		(net "M_D_DQS_DN<4>")
	)
	(segment
		(start 278.59863 -120.02008)
		(end 278.59863 -120.514364)
		(width 0.1651)
		(layer "F.Cu")
		(net "M_D_DQS_DN<4>")
	)
	(segment
		(start 282.31719 -124.093224)
		(end 282.496768 -124.272802)
		(width 0.1651)
		(layer "F.Cu")
		(net "M_D_DQS_DN<4>")
	)
	(segment
		(start 280.17851 -121.954544)
		(end 280.728166 -122.5042)
		(width 0.1651)
		(layer "F.Cu")
		(net "M_D_DQS_DN<4>")
	)
	(segment
		(start 283.481526 -125.25756)
		(end 283.661104 -125.437138)
		(width 0.1651)
		(layer "F.Cu")
		(net "M_D_DQS_DN<4>")
	)
	(segment
		(start 284.82544 -127.400558)
		(end 284.82544 -127.654558)
		(width 0.1651)
		(layer "F.Cu")
		(net "M_D_DQS_DN<4>")
	)
	(segment
		(start 277.106888 -118.461028)
		(end 277.106888 -118.962424)
		(width 0.1651)
		(layer "F.Cu")
		(net "M_D_DQS_DN<4>")
	)
	(segment
		(start 275.607272 -114.351054)
		(end 275.787104 -114.530886)
		(width 0.1651)
		(layer "F.Cu")
		(net "M_D_DQS_DN<4>")
	)
	(segment
		(start 277.320502 -117.535706)
		(end 277.320502 -118.247414)
		(width 0.1651)
		(layer "F.Cu")
		(net "M_D_DQS_DN<4>")
	)
	(segment
		(start 279.613106 -120.996202)
		(end 279.838658 -120.77065)
		(width 0.1651)
		(layer "F.Cu")
		(net "M_D_DQS_DN<4>")
	)
	(segment
		(start 275.528024 -104.786176)
		(end 274.861274 -105.452926)
		(width 0.0889)
		(layer "F.Cu")
		(net "M_D_DQS_DN<4>")
	)
	(segment
		(start 284.69844 -127.019558)
		(end 284.69844 -127.273558)
		(width 0.1651)
		(layer "F.Cu")
		(net "M_D_DQS_DN<4>")
	)
	(segment
		(start 274.861274 -105.452926)
		(end 274.861274 -106.468926)
		(width 0.0889)
		(layer "F.Cu")
		(net "M_D_DQS_DN<4>")
	)
	(segment
		(start 275.209 -113.3729)
		(end 275.224494 -113.388394)
		(width 0.1651)
		(layer "F.Cu")
		(net "M_D_DQS_DN<4>")
	)
	(segment
		(start 281.9146 -123.913646)
		(end 282.094432 -124.093224)
		(width 0.1651)
		(layer "F.Cu")
		(net "M_D_DQS_DN<4>")
	)
	(segment
		(start 284.645862 -126.421896)
		(end 284.82544 -126.601474)
		(width 0.1651)
		(layer "F.Cu")
		(net "M_D_DQS_DN<4>")
	)
	(segment
		(start 281.310334 -123.309126)
		(end 281.489912 -123.488704)
		(width 0.1651)
		(layer "F.Cu")
		(net "M_D_DQS_DN<4>")
	)
	(segment
		(start 284.063694 -125.839728)
		(end 284.243272 -126.019306)
		(width 0.1651)
		(layer "F.Cu")
		(net "M_D_DQS_DN<4>")
	)
	(segment
		(start 283.078936 -124.85497)
		(end 283.078936 -125.077982)
		(width 0.1651)
		(layer "F.Cu")
		(net "M_D_DQS_DN<4>")
	)
	(via
		(at 284.33776 -130.280156)
		(size 0.508)
		(drill 0.254)
		(layers "F.Cu" "B.Cu")
		(net "M_D_DQS_DN<4>")
	)
	(via
		(at 284.33776 -135.673846)
		(size 0.508)
		(drill 0.254)
		(layers "F.Cu" "B.Cu")
		(net "M_D_DQS_DN<4>")
	)
	(segment
		(start 283.821632 -129.311146)
		(end 283.949902 -129.182876)
		(width 0.1651)
		(layer "B.Cu")
		(net "M_D_DQS_DN<4>")
	)
	(segment
		(start 283.567632 -129.819146)
		(end 283.821632 -129.565146)
		(width 0.1651)
		(layer "B.Cu")
		(net "M_D_DQS_DN<4>")
	)
	(segment
		(start 283.923232 -130.5052)
		(end 283.567632 -130.1496)
		(width 0.1651)
		(layer "B.Cu")
		(net "M_D_DQS_DN<4>")
	)
	(segment
		(start 284.112716 -130.5052)
		(end 283.923232 -130.5052)
		(width 0.1651)
		(layer "B.Cu")
		(net "M_D_DQS_DN<4>")
	)
	(segment
		(start 283.567632 -130.1496)
		(end 283.567632 -129.819146)
		(width 0.1651)
		(layer "B.Cu")
		(net "M_D_DQS_DN<4>")
	)
	(segment
		(start 283.821632 -129.565146)
		(end 283.821632 -129.311146)
		(width 0.1651)
		(layer "B.Cu")
		(net "M_D_DQS_DN<4>")
	)
	(segment
		(start 283.949902 -128.276096)
		(end 283.95041 -128.276096)
		(width 0.1651)
		(layer "B.Cu")
		(net "M_D_DQS_DN<4>")
	)
	(segment
		(start 284.33776 -130.280156)
		(end 284.112716 -130.5052)
		(width 0.1651)
		(layer "B.Cu")
		(net "M_D_DQS_DN<4>")
	)
	(segment
		(start 283.949902 -129.182876)
		(end 283.949902 -128.276096)
		(width 0.1651)
		(layer "B.Cu")
		(net "M_D_DQS_DN<4>")
	)
	(segment
		(start 283.694124 -132.11302)
		(end 283.90469 -131.902454)
		(width 0.14224)
		(layer "In2.Cu")
		(net "M_D_DQS_DN<4>")
	)
	(segment
		(start 283.90469 -133.984746)
		(end 283.694124 -133.77418)
		(width 0.14224)
		(layer "In2.Cu")
		(net "M_D_DQS_DN<4>")
	)
	(segment
		(start 283.90469 -131.902454)
		(end 283.90469 -130.62331)
		(width 0.14224)
		(layer "In2.Cu")
		(net "M_D_DQS_DN<4>")
	)
	(segment
		(start 283.90469 -130.62331)
		(end 284.247844 -130.280156)
		(width 0.14224)
		(layer "In2.Cu")
		(net "M_D_DQS_DN<4>")
	)
	(segment
		(start 284.247844 -130.280156)
		(end 284.33776 -130.280156)
		(width 0.14224)
		(layer "In2.Cu")
		(net "M_D_DQS_DN<4>")
	)
	(segment
		(start 284.33776 -135.673846)
		(end 283.90469 -135.240776)
		(width 0.14224)
		(layer "In2.Cu")
		(net "M_D_DQS_DN<4>")
	)
	(segment
		(start 283.694124 -133.77418)
		(end 283.694124 -132.11302)
		(width 0.14224)
		(layer "In2.Cu")
		(net "M_D_DQS_DN<4>")
	)
	(segment
		(start 283.90469 -135.240776)
		(end 283.90469 -133.984746)
		(width 0.14224)
		(layer "In2.Cu")
		(net "M_D_DQS_DN<4>")
	)
	(segment
		(start 228.317806 -135.788654)
		(end 228.64826 -135.4582)
		(width 0.1651)
		(layer "F.Cu")
		(net "M_D_DQS_DN<3>")
	)
	(segment
		(start 228.872288 -135.4582)
		(end 229.087934 -135.673846)
		(width 0.1651)
		(layer "F.Cu")
		(net "M_D_DQS_DN<3>")
	)
	(segment
		(start 228.64826 -135.4582)
		(end 228.872288 -135.4582)
		(width 0.1651)
		(layer "F.Cu")
		(net "M_D_DQS_DN<3>")
	)
	(segment
		(start 228.70033 -137.67054)
		(end 228.699822 -137.67054)
		(width 0.1651)
		(layer "F.Cu")
		(net "M_D_DQS_DN<3>")
	)
	(segment
		(start 228.699822 -136.60247)
		(end 228.317806 -136.220454)
		(width 0.1651)
		(layer "F.Cu")
		(net "M_D_DQS_DN<3>")
	)
	(segment
		(start 228.699822 -137.67054)
		(end 228.699822 -136.60247)
		(width 0.1651)
		(layer "F.Cu")
		(net "M_D_DQS_DN<3>")
	)
	(segment
		(start 228.317806 -136.220454)
		(end 228.317806 -135.788654)
		(width 0.1651)
		(layer "F.Cu")
		(net "M_D_DQS_DN<3>")
	)
	(segment
		(start 242.193318 -97.690686)
		(end 241.621818 -97.690686)
		(width 0.1651)
		(layer "F.Cu")
		(net "M_D_DQS_DN<3>")
	)
	(via
		(at 229.087934 -135.673846)
		(size 0.508)
		(drill 0.254)
		(layers "F.Cu" "B.Cu")
		(net "M_D_DQS_DN<3>")
	)
	(via
		(at 229.087934 -130.280156)
		(size 0.508)
		(drill 0.254)
		(layers "F.Cu" "B.Cu")
		(net "M_D_DQS_DN<3>")
	)
	(via
		(at 241.621818 -97.690686)
		(size 0.508)
		(drill 0.254)
		(layers "F.Cu" "B.Cu")
		(net "M_D_DQS_DN<3>")
	)
	(segment
		(start 228.571806 -129.565146)
		(end 228.317806 -129.819146)
		(width 0.1651)
		(layer "B.Cu")
		(net "M_D_DQS_DN<3>")
	)
	(segment
		(start 228.699822 -128.276096)
		(end 228.699822 -129.18313)
		(width 0.1651)
		(layer "B.Cu")
		(net "M_D_DQS_DN<3>")
	)
	(segment
		(start 228.571806 -129.311146)
		(end 228.571806 -129.565146)
		(width 0.1651)
		(layer "B.Cu")
		(net "M_D_DQS_DN<3>")
	)
	(segment
		(start 228.699822 -129.18313)
		(end 228.571806 -129.311146)
		(width 0.1651)
		(layer "B.Cu")
		(net "M_D_DQS_DN<3>")
	)
	(segment
		(start 228.317806 -129.819146)
		(end 228.317806 -130.1496)
		(width 0.1651)
		(layer "B.Cu")
		(net "M_D_DQS_DN<3>")
	)
	(segment
		(start 228.673406 -130.5052)
		(end 228.86289 -130.5052)
		(width 0.1651)
		(layer "B.Cu")
		(net "M_D_DQS_DN<3>")
	)
	(segment
		(start 228.317806 -130.1496)
		(end 228.673406 -130.5052)
		(width 0.1651)
		(layer "B.Cu")
		(net "M_D_DQS_DN<3>")
	)
	(segment
		(start 228.70033 -128.276096)
		(end 228.699822 -128.276096)
		(width 0.1651)
		(layer "B.Cu")
		(net "M_D_DQS_DN<3>")
	)
	(segment
		(start 228.86289 -130.5052)
		(end 229.087934 -130.280156)
		(width 0.1651)
		(layer "B.Cu")
		(net "M_D_DQS_DN<3>")
	)
	(segment
		(start 229.677214 -127.418084)
		(end 229.519734 -127.575564)
		(width 0.14224)
		(layer "In2.Cu")
		(net "M_D_DQS_DN<3>")
	)
	(segment
		(start 230.15448 -117.214396)
		(end 230.15448 -117.498622)
		(width 0.14224)
		(layer "In2.Cu")
		(net "M_D_DQS_DN<3>")
	)
	(segment
		(start 229.677214 -123.872244)
		(end 229.677214 -124.126244)
		(width 0.14224)
		(layer "In2.Cu")
		(net "M_D_DQS_DN<3>")
	)
	(segment
		(start 230.12908 -114.948462)
		(end 230.12908 -115.379246)
		(width 0.14224)
		(layer "In2.Cu")
		(net "M_D_DQS_DN<3>")
	)
	(segment
		(start 229.52329 -126.217172)
		(end 229.677214 -126.371096)
		(width 0.14224)
		(layer "In2.Cu")
		(net "M_D_DQS_DN<3>")
	)
	(segment
		(start 239.064292 -99.576636)
		(end 239.028478 -99.576636)
		(width 0.0889)
		(layer "In2.Cu")
		(net "M_D_DQS_DN<3>")
	)
	(segment
		(start 229.997 -117.656102)
		(end 229.997 -117.910102)
		(width 0.14224)
		(layer "In2.Cu")
		(net "M_D_DQS_DN<3>")
	)
	(segment
		(start 230.15448 -112.824006)
		(end 230.15448 -113.094008)
		(width 0.14224)
		(layer "In2.Cu")
		(net "M_D_DQS_DN<3>")
	)
	(segment
		(start 229.560628 -112.230154)
		(end 230.15448 -112.824006)
		(width 0.14224)
		(layer "In2.Cu")
		(net "M_D_DQS_DN<3>")
	)
	(segment
		(start 229.677214 -123.049284)
		(end 229.677214 -123.303284)
		(width 0.14224)
		(layer "In2.Cu")
		(net "M_D_DQS_DN<3>")
	)
	(segment
		(start 229.523036 -125.360684)
		(end 229.677214 -125.514862)
		(width 0.14224)
		(layer "In2.Cu")
		(net "M_D_DQS_DN<3>")
	)
	(segment
		(start 229.519734 -127.575564)
		(end 229.519734 -127.829564)
		(width 0.14224)
		(layer "In2.Cu")
		(net "M_D_DQS_DN<3>")
	)
	(segment
		(start 229.677214 -128.810004)
		(end 229.677214 -129.064004)
		(width 0.14224)
		(layer "In2.Cu")
		(net "M_D_DQS_DN<3>")
	)
	(segment
		(start 229.519734 -121.245884)
		(end 229.677214 -121.403364)
		(width 0.14224)
		(layer "In2.Cu")
		(net "M_D_DQS_DN<3>")
	)
	(segment
		(start 229.519734 -122.637804)
		(end 229.519734 -122.891804)
		(width 0.14224)
		(layer "In2.Cu")
		(net "M_D_DQS_DN<3>")
	)
	(segment
		(start 228.654864 -130.640074)
		(end 228.654864 -131.9022)
		(width 0.14224)
		(layer "In2.Cu")
		(net "M_D_DQS_DN<3>")
	)
	(segment
		(start 229.367334 -130.280156)
		(end 229.087934 -130.280156)
		(width 0.14224)
		(layer "In2.Cu")
		(net "M_D_DQS_DN<3>")
	)
	(segment
		(start 229.52329 -125.963172)
		(end 229.52329 -126.217172)
		(width 0.14224)
		(layer "In2.Cu")
		(net "M_D_DQS_DN<3>")
	)
	(segment
		(start 229.677214 -127.164084)
		(end 229.677214 -127.418084)
		(width 0.14224)
		(layer "In2.Cu")
		(net "M_D_DQS_DN<3>")
	)
	(segment
		(start 229.677214 -121.657364)
		(end 229.519734 -121.814844)
		(width 0.14224)
		(layer "In2.Cu")
		(net "M_D_DQS_DN<3>")
	)
	(segment
		(start 229.677214 -119.757444)
		(end 229.677214 -120.011444)
		(width 0.14224)
		(layer "In2.Cu")
		(net "M_D_DQS_DN<3>")
	)
	(segment
		(start 228.444044 -133.77418)
		(end 228.654864 -133.985)
		(width 0.14224)
		(layer "In2.Cu")
		(net "M_D_DQS_DN<3>")
	)
	(segment
		(start 229.677214 -125.514862)
		(end 229.677214 -125.809248)
		(width 0.14224)
		(layer "In2.Cu")
		(net "M_D_DQS_DN<3>")
	)
	(segment
		(start 229.677214 -118.827296)
		(end 229.677214 -119.188484)
		(width 0.14224)
		(layer "In2.Cu")
		(net "M_D_DQS_DN<3>")
	)
	(segment
		(start 229.44709 -115.600734)
		(end 229.116128 -115.931696)
		(width 0.14224)
		(layer "In2.Cu")
		(net "M_D_DQS_DN<3>")
	)
	(segment
		(start 232.787444 -104.737916)
		(end 232.731564 -104.737916)
		(width 0.0889)
		(layer "In2.Cu")
		(net "M_D_DQS_DN<3>")
	)
	(segment
		(start 229.116128 -116.587524)
		(end 229.541578 -117.012974)
		(width 0.14224)
		(layer "In2.Cu")
		(net "M_D_DQS_DN<3>")
	)
	(segment
		(start 229.997 -117.910102)
		(end 230.15448 -118.067582)
		(width 0.14224)
		(layer "In2.Cu")
		(net "M_D_DQS_DN<3>")
	)
	(segment
		(start 230.15448 -113.094008)
		(end 229.415848 -113.83264)
		(width 0.14224)
		(layer "In2.Cu")
		(net "M_D_DQS_DN<3>")
	)
	(segment
		(start 229.677214 -124.126244)
		(end 229.519734 -124.283724)
		(width 0.14224)
		(layer "In2.Cu")
		(net "M_D_DQS_DN<3>")
	)
	(segment
		(start 229.519734 -122.068844)
		(end 229.677214 -122.226324)
		(width 0.14224)
		(layer "In2.Cu")
		(net "M_D_DQS_DN<3>")
	)
	(segment
		(start 229.541578 -117.012974)
		(end 229.953058 -117.012974)
		(width 0.14224)
		(layer "In2.Cu")
		(net "M_D_DQS_DN<3>")
	)
	(segment
		(start 229.519734 -124.283724)
		(end 229.519734 -124.537724)
		(width 0.14224)
		(layer "In2.Cu")
		(net "M_D_DQS_DN<3>")
	)
	(segment
		(start 229.907592 -115.600734)
		(end 229.44709 -115.600734)
		(width 0.14224)
		(layer "In2.Cu")
		(net "M_D_DQS_DN<3>")
	)
	(segment
		(start 229.519734 -119.599964)
		(end 229.677214 -119.757444)
		(width 0.14224)
		(layer "In2.Cu")
		(net "M_D_DQS_DN<3>")
	)
	(segment
		(start 229.677214 -126.371096)
		(end 229.677214 -126.595124)
		(width 0.14224)
		(layer "In2.Cu")
		(net "M_D_DQS_DN<3>")
	)
	(segment
		(start 229.677214 -120.580404)
		(end 229.677214 -120.834404)
		(width 0.14224)
		(layer "In2.Cu")
		(net "M_D_DQS_DN<3>")
	)
	(segment
		(start 229.519734 -122.891804)
		(end 229.677214 -123.049284)
		(width 0.14224)
		(layer "In2.Cu")
		(net "M_D_DQS_DN<3>")
	)
	(segment
		(start 229.677214 -119.188484)
		(end 229.519734 -119.345964)
		(width 0.14224)
		(layer "In2.Cu")
		(net "M_D_DQS_DN<3>")
	)
	(segment
		(start 228.654864 -133.985)
		(end 228.654864 -135.240776)
		(width 0.14224)
		(layer "In2.Cu")
		(net "M_D_DQS_DN<3>")
	)
	(segment
		(start 229.677214 -122.480324)
		(end 229.519734 -122.637804)
		(width 0.14224)
		(layer "In2.Cu")
		(net "M_D_DQS_DN<3>")
	)
	(segment
		(start 229.677214 -129.970276)
		(end 229.367334 -130.280156)
		(width 0.14224)
		(layer "In2.Cu")
		(net "M_D_DQS_DN<3>")
	)
	(segment
		(start 235.692696 -101.819456)
		(end 234.454954 -103.062786)
		(width 0.0889)
		(layer "In2.Cu")
		(net "M_D_DQS_DN<3>")
	)
	(segment
		(start 229.677214 -121.403364)
		(end 229.677214 -121.657364)
		(width 0.14224)
		(layer "In2.Cu")
		(net "M_D_DQS_DN<3>")
	)
	(segment
		(start 230.12908 -115.379246)
		(end 229.907592 -115.600734)
		(width 0.14224)
		(layer "In2.Cu")
		(net "M_D_DQS_DN<3>")
	)
	(segment
		(start 228.654864 -135.240776)
		(end 229.087934 -135.673846)
		(width 0.14224)
		(layer "In2.Cu")
		(net "M_D_DQS_DN<3>")
	)
	(segment
		(start 237.340394 -100.567236)
		(end 237.316264 -100.567236)
		(width 0.0889)
		(layer "In2.Cu")
		(net "M_D_DQS_DN<3>")
	)
	(segment
		(start 229.560628 -111.375698)
		(end 229.560628 -112.230154)
		(width 0.14224)
		(layer "In2.Cu")
		(net "M_D_DQS_DN<3>")
	)
	(segment
		(start 229.415848 -114.23523)
		(end 230.12908 -114.948462)
		(width 0.14224)
		(layer "In2.Cu")
		(net "M_D_DQS_DN<3>")
	)
	(segment
		(start 229.953058 -117.012974)
		(end 230.15448 -117.214396)
		(width 0.14224)
		(layer "In2.Cu")
		(net "M_D_DQS_DN<3>")
	)
	(segment
		(start 229.519734 -127.829564)
		(end 229.677214 -127.987044)
		(width 0.14224)
		(layer "In2.Cu")
		(net "M_D_DQS_DN<3>")
	)
	(segment
		(start 235.958634 -101.357938)
		(end 235.692696 -101.819456)
		(width 0.0889)
		(layer "In2.Cu")
		(net "M_D_DQS_DN<3>")
	)
	(segment
		(start 229.677214 -129.064004)
		(end 229.519734 -129.221484)
		(width 0.14224)
		(layer "In2.Cu")
		(net "M_D_DQS_DN<3>")
	)
	(segment
		(start 229.519734 -121.814844)
		(end 229.519734 -122.068844)
		(width 0.14224)
		(layer "In2.Cu")
		(net "M_D_DQS_DN<3>")
	)
	(segment
		(start 229.519734 -123.460764)
		(end 229.519734 -123.714764)
		(width 0.14224)
		(layer "In2.Cu")
		(net "M_D_DQS_DN<3>")
	)
	(segment
		(start 229.677214 -126.595124)
		(end 229.519734 -126.752604)
		(width 0.14224)
		(layer "In2.Cu")
		(net "M_D_DQS_DN<3>")
	)
	(segment
		(start 229.677214 -120.011444)
		(end 229.519734 -120.168924)
		(width 0.14224)
		(layer "In2.Cu")
		(net "M_D_DQS_DN<3>")
	)
	(segment
		(start 228.654864 -131.9022)
		(end 228.444044 -132.11302)
		(width 0.14224)
		(layer "In2.Cu")
		(net "M_D_DQS_DN<3>")
	)
	(segment
		(start 229.677214 -124.695204)
		(end 229.677214 -124.952506)
		(width 0.14224)
		(layer "In2.Cu")
		(net "M_D_DQS_DN<3>")
	)
	(segment
		(start 229.677214 -124.952506)
		(end 229.523036 -125.106684)
		(width 0.14224)
		(layer "In2.Cu")
		(net "M_D_DQS_DN<3>")
	)
	(segment
		(start 229.677214 -122.226324)
		(end 229.677214 -122.480324)
		(width 0.14224)
		(layer "In2.Cu")
		(net "M_D_DQS_DN<3>")
	)
	(segment
		(start 229.677214 -125.809248)
		(end 229.52329 -125.963172)
		(width 0.14224)
		(layer "In2.Cu")
		(net "M_D_DQS_DN<3>")
	)
	(segment
		(start 239.919764 -99.081336)
		(end 239.891824 -99.081336)
		(width 0.0889)
		(layer "In2.Cu")
		(net "M_D_DQS_DN<3>")
	)
	(segment
		(start 232.731564 -104.737916)
		(end 232.715816 -104.753664)
		(width 0.0889)
		(layer "In2.Cu")
		(net "M_D_DQS_DN<3>")
	)
	(segment
		(start 229.677214 -120.834404)
		(end 229.519734 -120.991884)
		(width 0.14224)
		(layer "In2.Cu")
		(net "M_D_DQS_DN<3>")
	)
	(segment
		(start 229.087934 -130.280156)
		(end 229.014782 -130.280156)
		(width 0.14224)
		(layer "In2.Cu")
		(net "M_D_DQS_DN<3>")
	)
	(segment
		(start 229.519734 -129.475484)
		(end 229.677214 -129.632964)
		(width 0.14224)
		(layer "In2.Cu")
		(net "M_D_DQS_DN<3>")
	)
	(segment
		(start 231.7115 -109.224826)
		(end 229.560628 -111.375698)
		(width 0.14224)
		(layer "In2.Cu")
		(net "M_D_DQS_DN<3>")
	)
	(segment
		(start 229.519734 -119.345964)
		(end 229.519734 -119.599964)
		(width 0.14224)
		(layer "In2.Cu")
		(net "M_D_DQS_DN<3>")
	)
	(segment
		(start 229.519734 -120.991884)
		(end 229.519734 -121.245884)
		(width 0.14224)
		(layer "In2.Cu")
		(net "M_D_DQS_DN<3>")
	)
	(segment
		(start 229.014782 -130.280156)
		(end 228.654864 -130.640074)
		(width 0.14224)
		(layer "In2.Cu")
		(net "M_D_DQS_DN<3>")
	)
	(segment
		(start 232.715816 -104.753664)
		(end 231.7115 -105.75798)
		(width 0.14224)
		(layer "In2.Cu")
		(net "M_D_DQS_DN<3>")
	)
	(segment
		(start 229.519734 -128.652524)
		(end 229.677214 -128.810004)
		(width 0.14224)
		(layer "In2.Cu")
		(net "M_D_DQS_DN<3>")
	)
	(segment
		(start 229.519734 -129.221484)
		(end 229.519734 -129.475484)
		(width 0.14224)
		(layer "In2.Cu")
		(net "M_D_DQS_DN<3>")
	)
	(segment
		(start 229.415848 -113.83264)
		(end 229.415848 -114.23523)
		(width 0.14224)
		(layer "In2.Cu")
		(net "M_D_DQS_DN<3>")
	)
	(segment
		(start 229.519734 -123.714764)
		(end 229.677214 -123.872244)
		(width 0.14224)
		(layer "In2.Cu")
		(net "M_D_DQS_DN<3>")
	)
	(segment
		(start 229.677214 -123.303284)
		(end 229.519734 -123.460764)
		(width 0.14224)
		(layer "In2.Cu")
		(net "M_D_DQS_DN<3>")
	)
	(segment
		(start 240.774474 -98.58629)
		(end 240.741708 -98.58629)
		(width 0.0889)
		(layer "In2.Cu")
		(net "M_D_DQS_DN<3>")
	)
	(segment
		(start 229.677214 -129.632964)
		(end 229.677214 -129.970276)
		(width 0.14224)
		(layer "In2.Cu")
		(net "M_D_DQS_DN<3>")
	)
	(segment
		(start 236.485684 -101.062536)
		(end 236.452918 -101.062536)
		(width 0.0889)
		(layer "In2.Cu")
		(net "M_D_DQS_DN<3>")
	)
	(segment
		(start 229.519734 -126.752604)
		(end 229.519734 -127.006604)
		(width 0.14224)
		(layer "In2.Cu")
		(net "M_D_DQS_DN<3>")
	)
	(segment
		(start 229.677214 -127.987044)
		(end 229.677214 -128.241044)
		(width 0.14224)
		(layer "In2.Cu")
		(net "M_D_DQS_DN<3>")
	)
	(segment
		(start 229.519734 -124.537724)
		(end 229.677214 -124.695204)
		(width 0.14224)
		(layer "In2.Cu")
		(net "M_D_DQS_DN<3>")
	)
	(segment
		(start 229.523036 -125.106684)
		(end 229.523036 -125.360684)
		(width 0.14224)
		(layer "In2.Cu")
		(net "M_D_DQS_DN<3>")
	)
	(segment
		(start 234.454954 -103.062786)
		(end 232.787444 -104.737916)
		(width 0.0889)
		(layer "In2.Cu")
		(net "M_D_DQS_DN<3>")
	)
	(segment
		(start 229.116128 -115.931696)
		(end 229.116128 -116.587524)
		(width 0.14224)
		(layer "In2.Cu")
		(net "M_D_DQS_DN<3>")
	)
	(segment
		(start 230.15448 -118.067582)
		(end 230.15448 -118.35003)
		(width 0.14224)
		(layer "In2.Cu")
		(net "M_D_DQS_DN<3>")
	)
	(segment
		(start 230.15448 -117.498622)
		(end 229.997 -117.656102)
		(width 0.14224)
		(layer "In2.Cu")
		(net "M_D_DQS_DN<3>")
	)
	(segment
		(start 229.677214 -128.241044)
		(end 229.519734 -128.398524)
		(width 0.14224)
		(layer "In2.Cu")
		(net "M_D_DQS_DN<3>")
	)
	(segment
		(start 238.205772 -100.071936)
		(end 238.166148 -100.071936)
		(width 0.0889)
		(layer "In2.Cu")
		(net "M_D_DQS_DN<3>")
	)
	(segment
		(start 229.519734 -127.006604)
		(end 229.677214 -127.164084)
		(width 0.14224)
		(layer "In2.Cu")
		(net "M_D_DQS_DN<3>")
	)
	(segment
		(start 230.15448 -118.35003)
		(end 229.677214 -118.827296)
		(width 0.14224)
		(layer "In2.Cu")
		(net "M_D_DQS_DN<3>")
	)
	(segment
		(start 229.519734 -120.168924)
		(end 229.519734 -120.422924)
		(width 0.14224)
		(layer "In2.Cu")
		(net "M_D_DQS_DN<3>")
	)
	(segment
		(start 229.519734 -120.422924)
		(end 229.677214 -120.580404)
		(width 0.14224)
		(layer "In2.Cu")
		(net "M_D_DQS_DN<3>")
	)
	(segment
		(start 228.444044 -132.11302)
		(end 228.444044 -133.77418)
		(width 0.14224)
		(layer "In2.Cu")
		(net "M_D_DQS_DN<3>")
	)
	(segment
		(start 229.519734 -128.398524)
		(end 229.519734 -128.652524)
		(width 0.14224)
		(layer "In2.Cu")
		(net "M_D_DQS_DN<3>")
	)
	(segment
		(start 231.7115 -105.75798)
		(end 231.7115 -109.224826)
		(width 0.14224)
		(layer "In2.Cu")
		(net "M_D_DQS_DN<3>")
	)
	(arc
		(start 236.452918 -101.062536)
		(mid 236.167353 -101.145945)
		(end 235.958634 -101.357938)
		(width 0.0889)
		(layer "In2.Cu")
		(net "M_D_DQS_DN<3>")
	)
	(arc
		(start 241.110008 -98.386138)
		(mid 240.968325 -98.529942)
		(end 240.774474 -98.58629)
		(width 0.0889)
		(layer "In2.Cu")
		(net "M_D_DQS_DN<3>")
	)
	(arc
		(start 237.316264 -100.567236)
		(mid 237.028119 -100.649555)
		(end 236.817408 -100.862638)
		(width 0.0889)
		(layer "In2.Cu")
		(net "M_D_DQS_DN<3>")
	)
	(arc
		(start 241.2492 -98.2091)
		(mid 241.173251 -98.292625)
		(end 241.110008 -98.386138)
		(width 0.0889)
		(layer "In2.Cu")
		(net "M_D_DQS_DN<3>")
	)
	(arc
		(start 236.817408 -100.862638)
		(mid 236.677329 -101.005374)
		(end 236.485684 -101.062536)
		(width 0.0889)
		(layer "In2.Cu")
		(net "M_D_DQS_DN<3>")
	)
	(arc
		(start 240.251488 -98.881438)
		(mid 240.111409 -99.024174)
		(end 239.919764 -99.081336)
		(width 0.0889)
		(layer "In2.Cu")
		(net "M_D_DQS_DN<3>")
	)
	(arc
		(start 238.534448 -99.872038)
		(mid 238.395704 -100.014071)
		(end 238.205772 -100.071936)
		(width 0.0889)
		(layer "In2.Cu")
		(net "M_D_DQS_DN<3>")
	)
	(arc
		(start 241.621818 -97.690686)
		(mid 241.479119 -97.981233)
		(end 241.2492 -98.2091)
		(width 0.0889)
		(layer "In2.Cu")
		(net "M_D_DQS_DN<3>")
	)
	(arc
		(start 239.028478 -99.576636)
		(mid 238.743054 -99.660103)
		(end 238.534448 -99.872038)
		(width 0.0889)
		(layer "In2.Cu")
		(net "M_D_DQS_DN<3>")
	)
	(arc
		(start 240.741708 -98.58629)
		(mid 240.458491 -98.670571)
		(end 240.251488 -98.881438)
		(width 0.0889)
		(layer "In2.Cu")
		(net "M_D_DQS_DN<3>")
	)
	(arc
		(start 239.392968 -99.376738)
		(mid 239.254224 -99.518771)
		(end 239.064292 -99.576636)
		(width 0.0889)
		(layer "In2.Cu")
		(net "M_D_DQS_DN<3>")
	)
	(arc
		(start 237.675928 -100.367084)
		(mid 237.534245 -100.510888)
		(end 237.340394 -100.567236)
		(width 0.0889)
		(layer "In2.Cu")
		(net "M_D_DQS_DN<3>")
	)
	(arc
		(start 238.166148 -100.071936)
		(mid 237.882931 -100.156217)
		(end 237.675928 -100.367084)
		(width 0.0889)
		(layer "In2.Cu")
		(net "M_D_DQS_DN<3>")
	)
	(arc
		(start 239.891824 -99.081336)
		(mid 239.603679 -99.163655)
		(end 239.392968 -99.376738)
		(width 0.0889)
		(layer "In2.Cu")
		(net "M_D_DQS_DN<3>")
	)
	(segment
		(start 218.967812 -136.220454)
		(end 219.349828 -136.60247)
		(width 0.1651)
		(layer "F.Cu")
		(net "M_D_DQS_DN<2>")
	)
	(segment
		(start 219.298266 -135.4582)
		(end 218.967812 -135.788654)
		(width 0.1651)
		(layer "F.Cu")
		(net "M_D_DQS_DN<2>")
	)
	(segment
		(start 219.349828 -136.60247)
		(end 219.349828 -137.67054)
		(width 0.1651)
		(layer "F.Cu")
		(net "M_D_DQS_DN<2>")
	)
	(segment
		(start 218.967812 -135.788654)
		(end 218.967812 -136.220454)
		(width 0.1651)
		(layer "F.Cu")
		(net "M_D_DQS_DN<2>")
	)
	(segment
		(start 219.522294 -135.4582)
		(end 219.298266 -135.4582)
		(width 0.1651)
		(layer "F.Cu")
		(net "M_D_DQS_DN<2>")
	)
	(segment
		(start 219.73794 -135.673846)
		(end 219.522294 -135.4582)
		(width 0.1651)
		(layer "F.Cu")
		(net "M_D_DQS_DN<2>")
	)
	(segment
		(start 236.183678 -94.223586)
		(end 235.612178 -94.223586)
		(width 0.1651)
		(layer "F.Cu")
		(net "M_D_DQS_DN<2>")
	)
	(segment
		(start 219.349828 -137.67054)
		(end 219.350336 -137.67054)
		(width 0.1651)
		(layer "F.Cu")
		(net "M_D_DQS_DN<2>")
	)
	(via
		(at 219.73794 -130.280156)
		(size 0.508)
		(drill 0.254)
		(layers "F.Cu" "B.Cu")
		(net "M_D_DQS_DN<2>")
	)
	(via
		(at 219.73794 -135.673846)
		(size 0.508)
		(drill 0.254)
		(layers "F.Cu" "B.Cu")
		(net "M_D_DQS_DN<2>")
	)
	(via
		(at 235.612178 -94.223586)
		(size 0.508)
		(drill 0.254)
		(layers "F.Cu" "B.Cu")
		(net "M_D_DQS_DN<2>")
	)
	(segment
		(start 219.221812 -129.565146)
		(end 218.967812 -129.819146)
		(width 0.1651)
		(layer "B.Cu")
		(net "M_D_DQS_DN<2>")
	)
	(segment
		(start 219.323412 -130.5052)
		(end 219.512896 -130.5052)
		(width 0.1651)
		(layer "B.Cu")
		(net "M_D_DQS_DN<2>")
	)
	(segment
		(start 218.967812 -129.819146)
		(end 218.967812 -130.1496)
		(width 0.1651)
		(layer "B.Cu")
		(net "M_D_DQS_DN<2>")
	)
	(segment
		(start 219.512896 -130.5052)
		(end 219.73794 -130.280156)
		(width 0.1651)
		(layer "B.Cu")
		(net "M_D_DQS_DN<2>")
	)
	(segment
		(start 219.221812 -129.311146)
		(end 219.221812 -129.565146)
		(width 0.1651)
		(layer "B.Cu")
		(net "M_D_DQS_DN<2>")
	)
	(segment
		(start 219.349828 -128.276096)
		(end 219.349828 -129.18313)
		(width 0.1651)
		(layer "B.Cu")
		(net "M_D_DQS_DN<2>")
	)
	(segment
		(start 219.349828 -129.18313)
		(end 219.221812 -129.311146)
		(width 0.1651)
		(layer "B.Cu")
		(net "M_D_DQS_DN<2>")
	)
	(segment
		(start 218.967812 -130.1496)
		(end 219.323412 -130.5052)
		(width 0.1651)
		(layer "B.Cu")
		(net "M_D_DQS_DN<2>")
	)
	(segment
		(start 219.350336 -128.276096)
		(end 219.349828 -128.276096)
		(width 0.1651)
		(layer "B.Cu")
		(net "M_D_DQS_DN<2>")
	)
	(segment
		(start 218.54668 -122.227848)
		(end 218.54668 -121.933462)
		(width 0.14224)
		(layer "In2.Cu")
		(net "M_D_DQS_DN<2>")
	)
	(segment
		(start 219.30487 -135.240776)
		(end 219.30487 -133.985)
		(width 0.14224)
		(layer "In2.Cu")
		(net "M_D_DQS_DN<2>")
	)
	(segment
		(start 219.73794 -135.673846)
		(end 219.30487 -135.240776)
		(width 0.14224)
		(layer "In2.Cu")
		(net "M_D_DQS_DN<2>")
	)
	(segment
		(start 219.664788 -130.280156)
		(end 219.73794 -130.280156)
		(width 0.14224)
		(layer "In2.Cu")
		(net "M_D_DQS_DN<2>")
	)
	(segment
		(start 218.992958 -127.885698)
		(end 218.992958 -127.662686)
		(width 0.14224)
		(layer "In2.Cu")
		(net "M_D_DQS_DN<2>")
	)
	(segment
		(start 220.14688 -108.245148)
		(end 223.21012 -105.181908)
		(width 0.14224)
		(layer "In2.Cu")
		(net "M_D_DQS_DN<2>")
	)
	(segment
		(start 235.014008 -94.137734)
		(end 235.612178 -94.223586)
		(width 0.0889)
		(layer "In2.Cu")
		(net "M_D_DQS_DN<2>")
	)
	(segment
		(start 234.774994 -94.12859)
		(end 234.909868 -94.128082)
		(width 0.0889)
		(layer "In2.Cu")
		(net "M_D_DQS_DN<2>")
	)
	(segment
		(start 218.39428 -125.936248)
		(end 218.39428 -125.672088)
		(width 0.14224)
		(layer "In2.Cu")
		(net "M_D_DQS_DN<2>")
	)
	(segment
		(start 218.54668 -114.21364)
		(end 217.86088 -113.52784)
		(width 0.14224)
		(layer "In2.Cu")
		(net "M_D_DQS_DN<2>")
	)
	(segment
		(start 218.992958 -127.662686)
		(end 218.54668 -127.216408)
		(width 0.14224)
		(layer "In2.Cu")
		(net "M_D_DQS_DN<2>")
	)
	(segment
		(start 218.54668 -121.933462)
		(end 218.44 -121.826782)
		(width 0.14224)
		(layer "In2.Cu")
		(net "M_D_DQS_DN<2>")
	)
	(segment
		(start 218.39428 -124.849128)
		(end 218.54668 -124.696728)
		(width 0.14224)
		(layer "In2.Cu")
		(net "M_D_DQS_DN<2>")
	)
	(segment
		(start 219.73794 -130.280156)
		(end 220.01734 -130.280156)
		(width 0.14224)
		(layer "In2.Cu")
		(net "M_D_DQS_DN<2>")
	)
	(segment
		(start 218.39428 -125.113288)
		(end 218.39428 -124.849128)
		(width 0.14224)
		(layer "In2.Cu")
		(net "M_D_DQS_DN<2>")
	)
	(segment
		(start 218.54668 -123.619768)
		(end 218.39428 -123.467368)
		(width 0.14224)
		(layer "In2.Cu")
		(net "M_D_DQS_DN<2>")
	)
	(segment
		(start 223.21012 -102.73284)
		(end 229.466902 -96.475804)
		(width 0.14224)
		(layer "In2.Cu")
		(net "M_D_DQS_DN<2>")
	)
	(segment
		(start 218.39428 -126.759208)
		(end 218.39428 -126.495048)
		(width 0.14224)
		(layer "In2.Cu")
		(net "M_D_DQS_DN<2>")
	)
	(segment
		(start 219.30487 -130.640074)
		(end 219.664788 -130.280156)
		(width 0.14224)
		(layer "In2.Cu")
		(net "M_D_DQS_DN<2>")
	)
	(segment
		(start 218.281504 -112.29848)
		(end 219.925138 -112.29848)
		(width 0.14224)
		(layer "In2.Cu")
		(net "M_D_DQS_DN<2>")
	)
	(segment
		(start 229.808024 -96.19107)
		(end 229.808024 -96.098614)
		(width 0.0889)
		(layer "In2.Cu")
		(net "M_D_DQS_DN<2>")
	)
	(segment
		(start 218.54668 -124.696728)
		(end 218.54668 -124.442728)
		(width 0.14224)
		(layer "In2.Cu")
		(net "M_D_DQS_DN<2>")
	)
	(segment
		(start 218.54668 -126.911608)
		(end 218.39428 -126.759208)
		(width 0.14224)
		(layer "In2.Cu")
		(net "M_D_DQS_DN<2>")
	)
	(segment
		(start 218.54668 -123.050808)
		(end 218.54668 -122.796808)
		(width 0.14224)
		(layer "In2.Cu")
		(net "M_D_DQS_DN<2>")
	)
	(segment
		(start 223.21012 -105.181908)
		(end 223.21012 -102.73284)
		(width 0.14224)
		(layer "In2.Cu")
		(net "M_D_DQS_DN<2>")
	)
	(segment
		(start 218.54668 -122.796808)
		(end 218.39428 -122.644408)
		(width 0.14224)
		(layer "In2.Cu")
		(net "M_D_DQS_DN<2>")
	)
	(segment
		(start 217.908632 -111.083598)
		(end 217.908632 -110.42777)
		(width 0.14224)
		(layer "In2.Cu")
		(net "M_D_DQS_DN<2>")
	)
	(segment
		(start 231.459024 -94.447614)
		(end 233.567224 -94.447614)
		(width 0.0889)
		(layer "In2.Cu")
		(net "M_D_DQS_DN<2>")
	)
	(segment
		(start 220.14688 -112.076738)
		(end 220.14688 -111.683292)
		(width 0.14224)
		(layer "In2.Cu")
		(net "M_D_DQS_DN<2>")
	)
	(segment
		(start 219.582492 -128.475232)
		(end 219.582492 -128.25222)
		(width 0.14224)
		(layer "In2.Cu")
		(net "M_D_DQS_DN<2>")
	)
	(segment
		(start 218.39428 -124.026168)
		(end 218.54668 -123.873768)
		(width 0.14224)
		(layer "In2.Cu")
		(net "M_D_DQS_DN<2>")
	)
	(segment
		(start 233.886248 -94.12859)
		(end 234.774994 -94.12859)
		(width 0.0889)
		(layer "In2.Cu")
		(net "M_D_DQS_DN<2>")
	)
	(segment
		(start 220.25102 -128.920748)
		(end 219.985082 -128.65481)
		(width 0.14224)
		(layer "In2.Cu")
		(net "M_D_DQS_DN<2>")
	)
	(segment
		(start 219.30487 -133.985)
		(end 219.09405 -133.77418)
		(width 0.14224)
		(layer "In2.Cu")
		(net "M_D_DQS_DN<2>")
	)
	(segment
		(start 218.54668 -125.519688)
		(end 218.54668 -125.265688)
		(width 0.14224)
		(layer "In2.Cu")
		(net "M_D_DQS_DN<2>")
	)
	(segment
		(start 218.44 -121.558558)
		(end 218.54668 -121.451878)
		(width 0.14224)
		(layer "In2.Cu")
		(net "M_D_DQS_DN<2>")
	)
	(segment
		(start 219.172536 -128.065276)
		(end 218.992958 -127.885698)
		(width 0.14224)
		(layer "In2.Cu")
		(net "M_D_DQS_DN<2>")
	)
	(segment
		(start 218.286838 -110.049564)
		(end 219.925392 -110.049564)
		(width 0.14224)
		(layer "In2.Cu")
		(net "M_D_DQS_DN<2>")
	)
	(segment
		(start 220.14688 -109.828076)
		(end 220.14688 -108.245148)
		(width 0.14224)
		(layer "In2.Cu")
		(net "M_D_DQS_DN<2>")
	)
	(segment
		(start 218.39428 -125.672088)
		(end 218.54668 -125.519688)
		(width 0.14224)
		(layer "In2.Cu")
		(net "M_D_DQS_DN<2>")
	)
	(segment
		(start 218.44 -121.826782)
		(end 218.44 -121.558558)
		(width 0.14224)
		(layer "In2.Cu")
		(net "M_D_DQS_DN<2>")
	)
	(segment
		(start 220.01734 -130.280156)
		(end 220.25102 -130.046476)
		(width 0.14224)
		(layer "In2.Cu")
		(net "M_D_DQS_DN<2>")
	)
	(segment
		(start 218.54668 -125.265688)
		(end 218.39428 -125.113288)
		(width 0.14224)
		(layer "In2.Cu")
		(net "M_D_DQS_DN<2>")
	)
	(segment
		(start 218.286838 -111.461804)
		(end 217.908632 -111.083598)
		(width 0.14224)
		(layer "In2.Cu")
		(net "M_D_DQS_DN<2>")
	)
	(segment
		(start 218.39428 -126.495048)
		(end 218.54668 -126.342648)
		(width 0.14224)
		(layer "In2.Cu")
		(net "M_D_DQS_DN<2>")
	)
	(segment
		(start 219.925392 -110.049564)
		(end 220.14688 -109.828076)
		(width 0.14224)
		(layer "In2.Cu")
		(net "M_D_DQS_DN<2>")
	)
	(segment
		(start 219.925392 -111.461804)
		(end 218.286838 -111.461804)
		(width 0.14224)
		(layer "In2.Cu")
		(net "M_D_DQS_DN<2>")
	)
	(segment
		(start 220.25102 -130.046476)
		(end 220.25102 -128.920748)
		(width 0.14224)
		(layer "In2.Cu")
		(net "M_D_DQS_DN<2>")
	)
	(segment
		(start 219.582492 -128.25222)
		(end 219.395548 -128.065276)
		(width 0.14224)
		(layer "In2.Cu")
		(net "M_D_DQS_DN<2>")
	)
	(segment
		(start 219.395548 -128.065276)
		(end 219.172536 -128.065276)
		(width 0.14224)
		(layer "In2.Cu")
		(net "M_D_DQS_DN<2>")
	)
	(segment
		(start 219.925138 -112.29848)
		(end 220.14688 -112.076738)
		(width 0.14224)
		(layer "In2.Cu")
		(net "M_D_DQS_DN<2>")
	)
	(segment
		(start 218.54668 -123.873768)
		(end 218.54668 -123.619768)
		(width 0.14224)
		(layer "In2.Cu")
		(net "M_D_DQS_DN<2>")
	)
	(segment
		(start 218.39428 -122.380248)
		(end 218.54668 -122.227848)
		(width 0.14224)
		(layer "In2.Cu")
		(net "M_D_DQS_DN<2>")
	)
	(segment
		(start 217.908632 -110.42777)
		(end 218.286838 -110.049564)
		(width 0.14224)
		(layer "In2.Cu")
		(net "M_D_DQS_DN<2>")
	)
	(segment
		(start 229.808024 -96.098614)
		(end 231.459024 -94.447614)
		(width 0.0889)
		(layer "In2.Cu")
		(net "M_D_DQS_DN<2>")
	)
	(segment
		(start 218.39428 -123.467368)
		(end 218.39428 -123.203208)
		(width 0.14224)
		(layer "In2.Cu")
		(net "M_D_DQS_DN<2>")
	)
	(segment
		(start 218.54668 -121.451878)
		(end 218.54668 -114.21364)
		(width 0.14224)
		(layer "In2.Cu")
		(net "M_D_DQS_DN<2>")
	)
	(segment
		(start 219.30487 -131.9022)
		(end 219.30487 -130.640074)
		(width 0.14224)
		(layer "In2.Cu")
		(net "M_D_DQS_DN<2>")
	)
	(segment
		(start 217.86088 -113.52784)
		(end 217.86088 -112.719104)
		(width 0.14224)
		(layer "In2.Cu")
		(net "M_D_DQS_DN<2>")
	)
	(segment
		(start 234.909868 -94.128082)
		(end 235.014008 -94.137734)
		(width 0.0889)
		(layer "In2.Cu")
		(net "M_D_DQS_DN<2>")
	)
	(segment
		(start 220.14688 -111.683292)
		(end 219.925392 -111.461804)
		(width 0.14224)
		(layer "In2.Cu")
		(net "M_D_DQS_DN<2>")
	)
	(segment
		(start 218.54668 -126.342648)
		(end 218.54668 -126.088648)
		(width 0.14224)
		(layer "In2.Cu")
		(net "M_D_DQS_DN<2>")
	)
	(segment
		(start 218.54668 -124.442728)
		(end 218.39428 -124.290328)
		(width 0.14224)
		(layer "In2.Cu")
		(net "M_D_DQS_DN<2>")
	)
	(segment
		(start 219.09405 -132.11302)
		(end 219.30487 -131.9022)
		(width 0.14224)
		(layer "In2.Cu")
		(net "M_D_DQS_DN<2>")
	)
	(segment
		(start 218.39428 -124.290328)
		(end 218.39428 -124.026168)
		(width 0.14224)
		(layer "In2.Cu")
		(net "M_D_DQS_DN<2>")
	)
	(segment
		(start 218.39428 -122.644408)
		(end 218.39428 -122.380248)
		(width 0.14224)
		(layer "In2.Cu")
		(net "M_D_DQS_DN<2>")
	)
	(segment
		(start 233.567224 -94.447614)
		(end 233.886248 -94.12859)
		(width 0.0889)
		(layer "In2.Cu")
		(net "M_D_DQS_DN<2>")
	)
	(segment
		(start 219.09405 -133.77418)
		(end 219.09405 -132.11302)
		(width 0.14224)
		(layer "In2.Cu")
		(net "M_D_DQS_DN<2>")
	)
	(segment
		(start 218.39428 -123.203208)
		(end 218.54668 -123.050808)
		(width 0.14224)
		(layer "In2.Cu")
		(net "M_D_DQS_DN<2>")
	)
	(segment
		(start 219.76207 -128.65481)
		(end 219.582492 -128.475232)
		(width 0.14224)
		(layer "In2.Cu")
		(net "M_D_DQS_DN<2>")
	)
	(segment
		(start 229.48265 -96.460056)
		(end 229.539038 -96.460056)
		(width 0.0889)
		(layer "In2.Cu")
		(net "M_D_DQS_DN<2>")
	)
	(segment
		(start 217.86088 -112.719104)
		(end 218.281504 -112.29848)
		(width 0.14224)
		(layer "In2.Cu")
		(net "M_D_DQS_DN<2>")
	)
	(segment
		(start 218.54668 -127.216408)
		(end 218.54668 -126.911608)
		(width 0.14224)
		(layer "In2.Cu")
		(net "M_D_DQS_DN<2>")
	)
	(segment
		(start 219.985082 -128.65481)
		(end 219.76207 -128.65481)
		(width 0.14224)
		(layer "In2.Cu")
		(net "M_D_DQS_DN<2>")
	)
	(segment
		(start 229.466902 -96.475804)
		(end 229.48265 -96.460056)
		(width 0.0889)
		(layer "In2.Cu")
		(net "M_D_DQS_DN<2>")
	)
	(segment
		(start 218.54668 -126.088648)
		(end 218.39428 -125.936248)
		(width 0.14224)
		(layer "In2.Cu")
		(net "M_D_DQS_DN<2>")
	)
	(segment
		(start 229.539038 -96.460056)
		(end 229.808024 -96.19107)
		(width 0.0889)
		(layer "In2.Cu")
		(net "M_D_DQS_DN<2>")
	)
	(segment
		(start 210.503262 -129.480056)
		(end 210.503262 -129.734056)
		(width 0.1651)
		(layer "F.Cu")
		(net "M_D_DQS_DN<1>")
	)
	(segment
		(start 210.1723 -135.4582)
		(end 209.948272 -135.4582)
		(width 0.1651)
		(layer "F.Cu")
		(net "M_D_DQS_DN<1>")
	)
	(segment
		(start 211.48802 -124.780802)
		(end 211.309712 -124.95911)
		(width 0.1651)
		(layer "F.Cu")
		(net "M_D_DQS_DN<1>")
	)
	(segment
		(start 234.466638 -95.21444)
		(end 234.061 -95.167196)
		(width 0.0889)
		(layer "F.Cu")
		(net "M_D_DQS_DN<1>")
	)
	(segment
		(start 209.999834 -137.67054)
		(end 210.000342 -137.67054)
		(width 0.1651)
		(layer "F.Cu")
		(net "M_D_DQS_DN<1>")
	)
	(segment
		(start 210.556602 -127.893572)
		(end 210.556602 -128.263396)
		(width 0.1651)
		(layer "F.Cu")
		(net "M_D_DQS_DN<1>")
	)
	(segment
		(start 210.630262 -129.861056)
		(end 210.630262 -130.038094)
		(width 0.1651)
		(layer "F.Cu")
		(net "M_D_DQS_DN<1>")
	)
	(segment
		(start 233.625898 -95.118936)
		(end 232.47858 -95.118936)
		(width 0.0889)
		(layer "F.Cu")
		(net "M_D_DQS_DN<1>")
	)
	(segment
		(start 210.64728 -123.7234)
		(end 210.99653 -124.07265)
		(width 0.1651)
		(layer "F.Cu")
		(net "M_D_DQS_DN<1>")
	)
	(segment
		(start 211.48802 -119.634762)
		(end 210.70062 -120.422162)
		(width 0.1651)
		(layer "F.Cu")
		(net "M_D_DQS_DN<1>")
	)
	(segment
		(start 210.630262 -129.353056)
		(end 210.503262 -129.480056)
		(width 0.1651)
		(layer "F.Cu")
		(net "M_D_DQS_DN<1>")
	)
	(segment
		(start 210.99653 -124.95911)
		(end 210.64728 -125.30836)
		(width 0.1651)
		(layer "F.Cu")
		(net "M_D_DQS_DN<1>")
	)
	(segment
		(start 210.503262 -128.972056)
		(end 210.630262 -129.099056)
		(width 0.1651)
		(layer "F.Cu")
		(net "M_D_DQS_DN<1>")
	)
	(segment
		(start 211.48802 -121.893838)
		(end 211.48802 -122.423682)
		(width 0.1651)
		(layer "F.Cu")
		(net "M_D_DQS_DN<1>")
	)
	(segment
		(start 210.70062 -120.422162)
		(end 210.70062 -121.106438)
		(width 0.1651)
		(layer "F.Cu")
		(net "M_D_DQS_DN<1>")
	)
	(segment
		(start 210.64728 -125.30836)
		(end 210.64728 -126.08052)
		(width 0.1651)
		(layer "F.Cu")
		(net "M_D_DQS_DN<1>")
	)
	(segment
		(start 211.309712 -124.07265)
		(end 211.48802 -124.250958)
		(width 0.1651)
		(layer "F.Cu")
		(net "M_D_DQS_DN<1>")
	)
	(segment
		(start 209.999834 -136.60247)
		(end 209.999834 -137.67054)
		(width 0.1651)
		(layer "F.Cu")
		(net "M_D_DQS_DN<1>")
	)
	(segment
		(start 209.948272 -135.4582)
		(end 209.6008 -135.805672)
		(width 0.1651)
		(layer "F.Cu")
		(net "M_D_DQS_DN<1>")
	)
	(segment
		(start 234.061 -95.167196)
		(end 233.68 -95.123)
		(width 0.0889)
		(layer "F.Cu")
		(net "M_D_DQS_DN<1>")
	)
	(segment
		(start 210.630262 -130.038094)
		(end 210.3882 -130.280156)
		(width 0.1651)
		(layer "F.Cu")
		(net "M_D_DQS_DN<1>")
	)
	(segment
		(start 232.47858 -95.118936)
		(end 232.427018 -95.067374)
		(width 0.0889)
		(layer "F.Cu")
		(net "M_D_DQS_DN<1>")
	)
	(segment
		(start 211.48802 -126.962154)
		(end 210.556602 -127.893572)
		(width 0.1651)
		(layer "F.Cu")
		(net "M_D_DQS_DN<1>")
	)
	(segment
		(start 210.99653 -126.42977)
		(end 211.309712 -126.42977)
		(width 0.1651)
		(layer "F.Cu")
		(net "M_D_DQS_DN<1>")
	)
	(segment
		(start 209.6008 -136.203436)
		(end 209.999834 -136.60247)
		(width 0.1651)
		(layer "F.Cu")
		(net "M_D_DQS_DN<1>")
	)
	(segment
		(start 210.99653 -122.60199)
		(end 210.64728 -122.95124)
		(width 0.1651)
		(layer "F.Cu")
		(net "M_D_DQS_DN<1>")
	)
	(segment
		(start 210.630262 -129.099056)
		(end 210.630262 -129.353056)
		(width 0.1651)
		(layer "F.Cu")
		(net "M_D_DQS_DN<1>")
	)
	(segment
		(start 210.64728 -122.95124)
		(end 210.64728 -123.7234)
		(width 0.1651)
		(layer "F.Cu")
		(net "M_D_DQS_DN<1>")
	)
	(segment
		(start 210.64728 -126.08052)
		(end 210.99653 -126.42977)
		(width 0.1651)
		(layer "F.Cu")
		(net "M_D_DQS_DN<1>")
	)
	(segment
		(start 210.630262 -128.591056)
		(end 210.503262 -128.718056)
		(width 0.1651)
		(layer "F.Cu")
		(net "M_D_DQS_DN<1>")
	)
	(segment
		(start 211.48802 -126.608078)
		(end 211.48802 -126.962154)
		(width 0.1651)
		(layer "F.Cu")
		(net "M_D_DQS_DN<1>")
	)
	(segment
		(start 211.309712 -122.60199)
		(end 210.99653 -122.60199)
		(width 0.1651)
		(layer "F.Cu")
		(net "M_D_DQS_DN<1>")
	)
	(segment
		(start 210.70062 -121.106438)
		(end 211.48802 -121.893838)
		(width 0.1651)
		(layer "F.Cu")
		(net "M_D_DQS_DN<1>")
	)
	(segment
		(start 210.387946 -135.673846)
		(end 210.1723 -135.4582)
		(width 0.1651)
		(layer "F.Cu")
		(net "M_D_DQS_DN<1>")
	)
	(segment
		(start 211.48802 -124.250958)
		(end 211.48802 -124.780802)
		(width 0.1651)
		(layer "F.Cu")
		(net "M_D_DQS_DN<1>")
	)
	(segment
		(start 232.40492 -95.067374)
		(end 231.277922 -95.067374)
		(width 0.1651)
		(layer "F.Cu")
		(net "M_D_DQS_DN<1>")
	)
	(segment
		(start 231.277922 -95.067374)
		(end 211.48802 -114.857276)
		(width 0.1651)
		(layer "F.Cu")
		(net "M_D_DQS_DN<1>")
	)
	(segment
		(start 210.503262 -129.734056)
		(end 210.630262 -129.861056)
		(width 0.1651)
		(layer "F.Cu")
		(net "M_D_DQS_DN<1>")
	)
	(segment
		(start 209.6008 -135.805672)
		(end 209.6008 -136.203436)
		(width 0.1651)
		(layer "F.Cu")
		(net "M_D_DQS_DN<1>")
	)
	(segment
		(start 211.48802 -122.423682)
		(end 211.309712 -122.60199)
		(width 0.1651)
		(layer "F.Cu")
		(net "M_D_DQS_DN<1>")
	)
	(segment
		(start 210.503262 -128.718056)
		(end 210.503262 -128.972056)
		(width 0.1651)
		(layer "F.Cu")
		(net "M_D_DQS_DN<1>")
	)
	(segment
		(start 211.309712 -126.42977)
		(end 211.48802 -126.608078)
		(width 0.1651)
		(layer "F.Cu")
		(net "M_D_DQS_DN<1>")
	)
	(segment
		(start 210.3882 -130.280156)
		(end 210.387946 -130.280156)
		(width 0.1651)
		(layer "F.Cu")
		(net "M_D_DQS_DN<1>")
	)
	(segment
		(start 211.48802 -114.857276)
		(end 211.48802 -119.634762)
		(width 0.1651)
		(layer "F.Cu")
		(net "M_D_DQS_DN<1>")
	)
	(segment
		(start 232.427018 -95.067374)
		(end 232.40492 -95.067374)
		(width 0.0889)
		(layer "F.Cu")
		(net "M_D_DQS_DN<1>")
	)
	(segment
		(start 210.556602 -128.263396)
		(end 210.630262 -128.337056)
		(width 0.1651)
		(layer "F.Cu")
		(net "M_D_DQS_DN<1>")
	)
	(segment
		(start 211.309712 -124.95911)
		(end 210.99653 -124.95911)
		(width 0.1651)
		(layer "F.Cu")
		(net "M_D_DQS_DN<1>")
	)
	(segment
		(start 210.99653 -124.07265)
		(end 211.309712 -124.07265)
		(width 0.1651)
		(layer "F.Cu")
		(net "M_D_DQS_DN<1>")
	)
	(segment
		(start 210.630262 -128.337056)
		(end 210.630262 -128.591056)
		(width 0.1651)
		(layer "F.Cu")
		(net "M_D_DQS_DN<1>")
	)
	(via
		(at 210.387946 -135.673846)
		(size 0.508)
		(drill 0.254)
		(layers "F.Cu" "B.Cu")
		(net "M_D_DQS_DN<1>")
	)
	(via
		(at 210.387946 -130.280156)
		(size 0.508)
		(drill 0.254)
		(layers "F.Cu" "B.Cu")
		(net "M_D_DQS_DN<1>")
	)
	(arc
		(start 233.68 -95.123)
		(mid 233.652996 -95.120341)
		(end 233.625898 -95.118936)
		(width 0.0889)
		(layer "F.Cu")
		(net "M_D_DQS_DN<1>")
	)
	(segment
		(start 209.999834 -128.276096)
		(end 210.000342 -128.276096)
		(width 0.1651)
		(layer "B.Cu")
		(net "M_D_DQS_DN<1>")
	)
	(segment
		(start 210.162902 -130.5052)
		(end 209.973418 -130.5052)
		(width 0.1651)
		(layer "B.Cu")
		(net "M_D_DQS_DN<1>")
	)
	(segment
		(start 210.387946 -130.280156)
		(end 210.162902 -130.5052)
		(width 0.1651)
		(layer "B.Cu")
		(net "M_D_DQS_DN<1>")
	)
	(segment
		(start 209.871818 -129.565146)
		(end 209.871818 -129.311146)
		(width 0.1651)
		(layer "B.Cu")
		(net "M_D_DQS_DN<1>")
	)
	(segment
		(start 209.871818 -129.311146)
		(end 209.999834 -129.18313)
		(width 0.1651)
		(layer "B.Cu")
		(net "M_D_DQS_DN<1>")
	)
	(segment
		(start 209.617818 -129.819146)
		(end 209.871818 -129.565146)
		(width 0.1651)
		(layer "B.Cu")
		(net "M_D_DQS_DN<1>")
	)
	(segment
		(start 209.617818 -130.1496)
		(end 209.617818 -129.819146)
		(width 0.1651)
		(layer "B.Cu")
		(net "M_D_DQS_DN<1>")
	)
	(segment
		(start 209.999834 -129.18313)
		(end 209.999834 -128.276096)
		(width 0.1651)
		(layer "B.Cu")
		(net "M_D_DQS_DN<1>")
	)
	(segment
		(start 209.973418 -130.5052)
		(end 209.617818 -130.1496)
		(width 0.1651)
		(layer "B.Cu")
		(net "M_D_DQS_DN<1>")
	)
	(segment
		(start 209.744056 -132.11302)
		(end 209.954876 -131.9022)
		(width 0.14224)
		(layer "In2.Cu")
		(net "M_D_DQS_DN<1>")
	)
	(segment
		(start 209.954876 -133.985)
		(end 209.744056 -133.77418)
		(width 0.14224)
		(layer "In2.Cu")
		(net "M_D_DQS_DN<1>")
	)
	(segment
		(start 210.387946 -135.673846)
		(end 209.954876 -135.240776)
		(width 0.14224)
		(layer "In2.Cu")
		(net "M_D_DQS_DN<1>")
	)
	(segment
		(start 209.744056 -133.77418)
		(end 209.744056 -132.11302)
		(width 0.14224)
		(layer "In2.Cu")
		(net "M_D_DQS_DN<1>")
	)
	(segment
		(start 209.954876 -135.240776)
		(end 209.954876 -133.985)
		(width 0.14224)
		(layer "In2.Cu")
		(net "M_D_DQS_DN<1>")
	)
	(segment
		(start 209.954876 -130.640074)
		(end 210.314794 -130.280156)
		(width 0.14224)
		(layer "In2.Cu")
		(net "M_D_DQS_DN<1>")
	)
	(segment
		(start 210.314794 -130.280156)
		(end 210.387946 -130.280156)
		(width 0.14224)
		(layer "In2.Cu")
		(net "M_D_DQS_DN<1>")
	)
	(segment
		(start 209.954876 -131.9022)
		(end 209.954876 -130.640074)
		(width 0.14224)
		(layer "In2.Cu")
		(net "M_D_DQS_DN<1>")
	)
	(segment
		(start 237.631732 -134.148068)
		(end 237.631732 -134.5692)
		(width 0.1651)
		(layer "F.Cu")
		(net "M_D_DQS_DN<17>")
	)
	(segment
		(start 237.357412 -135.25373)
		(end 237.168182 -135.0645)
		(width 0.1651)
		(layer "F.Cu")
		(net "M_D_DQS_DN<17>")
	)
	(segment
		(start 238.049816 -133.076442)
		(end 238.049816 -133.729984)
		(width 0.1651)
		(layer "F.Cu")
		(net "M_D_DQS_DN<17>")
	)
	(segment
		(start 237.565692 -135.25373)
		(end 237.357412 -135.25373)
		(width 0.1651)
		(layer "F.Cu")
		(net "M_D_DQS_DN<17>")
	)
	(segment
		(start 237.81766 -135.001762)
		(end 237.565692 -135.25373)
		(width 0.1651)
		(layer "F.Cu")
		(net "M_D_DQS_DN<17>")
	)
	(segment
		(start 237.81766 -134.755128)
		(end 237.81766 -135.001762)
		(width 0.1651)
		(layer "F.Cu")
		(net "M_D_DQS_DN<17>")
	)
	(segment
		(start 238.049816 -133.729984)
		(end 237.631732 -134.148068)
		(width 0.1651)
		(layer "F.Cu")
		(net "M_D_DQS_DN<17>")
	)
	(segment
		(start 249.061224 -89.765886)
		(end 248.489724 -89.765886)
		(width 0.1651)
		(layer "F.Cu")
		(net "M_D_DQS_DN<17>")
	)
	(segment
		(start 237.631732 -134.5692)
		(end 237.81766 -134.755128)
		(width 0.1651)
		(layer "F.Cu")
		(net "M_D_DQS_DN<17>")
	)
	(segment
		(start 238.050324 -133.0706)
		(end 238.049816 -133.076442)
		(width 0.1651)
		(layer "F.Cu")
		(net "M_D_DQS_DN<17>")
	)
	(segment
		(start 237.168182 -135.0645)
		(end 237.149132 -135.0645)
		(width 0.1651)
		(layer "F.Cu")
		(net "M_D_DQS_DN<17>")
	)
	(via
		(at 248.489724 -89.765886)
		(size 0.508)
		(drill 0.254)
		(layers "F.Cu" "B.Cu")
		(net "M_D_DQS_DN<17>")
	)
	(via
		(at 237.149132 -135.0645)
		(size 0.508)
		(drill 0.254)
		(layers "F.Cu" "B.Cu")
		(net "M_D_DQS_DN<17>")
	)
	(via
		(at 237.142528 -130.8862)
		(size 0.508)
		(drill 0.254)
		(layers "F.Cu" "B.Cu")
		(net "M_D_DQS_DN<17>")
	)
	(segment
		(start 237.337092 -130.691636)
		(end 237.142528 -130.8862)
		(width 0.1651)
		(layer "B.Cu")
		(net "M_D_DQS_DN<17>")
	)
	(segment
		(start 238.050324 -132.876036)
		(end 238.05007 -132.875528)
		(width 0.1651)
		(layer "B.Cu")
		(net "M_D_DQS_DN<17>")
	)
	(segment
		(start 237.606332 -131.4196)
		(end 237.784132 -131.2418)
		(width 0.1651)
		(layer "B.Cu")
		(net "M_D_DQS_DN<17>")
	)
	(segment
		(start 238.05007 -132.875528)
		(end 238.05007 -132.219192)
		(width 0.1651)
		(layer "B.Cu")
		(net "M_D_DQS_DN<17>")
	)
	(segment
		(start 237.564168 -130.691636)
		(end 237.337092 -130.691636)
		(width 0.1651)
		(layer "B.Cu")
		(net "M_D_DQS_DN<17>")
	)
	(segment
		(start 237.784132 -130.9116)
		(end 237.564168 -130.691636)
		(width 0.1651)
		(layer "B.Cu")
		(net "M_D_DQS_DN<17>")
	)
	(segment
		(start 237.606332 -131.775454)
		(end 237.606332 -131.4196)
		(width 0.1651)
		(layer "B.Cu")
		(net "M_D_DQS_DN<17>")
	)
	(segment
		(start 237.784132 -131.2418)
		(end 237.784132 -130.9116)
		(width 0.1651)
		(layer "B.Cu")
		(net "M_D_DQS_DN<17>")
	)
	(segment
		(start 238.05007 -132.219192)
		(end 237.606332 -131.775454)
		(width 0.1651)
		(layer "B.Cu")
		(net "M_D_DQS_DN<17>")
	)
	(segment
		(start 237.924848 -123.55068)
		(end 237.924848 -130.111246)
		(width 0.14224)
		(layer "In2.Cu")
		(net "M_D_DQS_DN<17>")
	)
	(segment
		(start 248.143014 -90.556588)
		(end 248.138188 -90.565224)
		(width 0.0889)
		(layer "In2.Cu")
		(net "M_D_DQS_DN<17>")
	)
	(segment
		(start 237.582202 -134.63143)
		(end 237.149132 -135.0645)
		(width 0.14224)
		(layer "In2.Cu")
		(net "M_D_DQS_DN<17>")
	)
	(segment
		(start 237.142528 -130.8862)
		(end 237.577376 -131.321048)
		(width 0.14224)
		(layer "In2.Cu")
		(net "M_D_DQS_DN<17>")
	)
	(segment
		(start 246.108474 -104.505506)
		(end 239.51692 -111.09706)
		(width 0.14224)
		(layer "In2.Cu")
		(net "M_D_DQS_DN<17>")
	)
	(segment
		(start 237.297976 -132.0038)
		(end 237.056676 -132.0038)
		(width 0.14224)
		(layer "In2.Cu")
		(net "M_D_DQS_DN<17>")
	)
	(segment
		(start 247.279668 -95.405702)
		(end 247.284494 -95.414338)
		(width 0.0889)
		(layer "In2.Cu")
		(net "M_D_DQS_DN<17>")
	)
	(segment
		(start 246.069104 -102.66553)
		(end 246.108474 -102.7049)
		(width 0.0889)
		(layer "In2.Cu")
		(net "M_D_DQS_DN<17>")
	)
	(segment
		(start 237.394496 -133.9596)
		(end 237.582202 -134.147306)
		(width 0.14224)
		(layer "In2.Cu")
		(net "M_D_DQS_DN<17>")
	)
	(segment
		(start 248.149364 -91.53652)
		(end 248.143014 -91.547188)
		(width 0.0889)
		(layer "In2.Cu")
		(net "M_D_DQS_DN<17>")
	)
	(segment
		(start 247.279668 -96.396302)
		(end 247.284494 -96.404938)
		(width 0.0889)
		(layer "In2.Cu")
		(net "M_D_DQS_DN<17>")
	)
	(segment
		(start 237.348776 -132.78866)
		(end 237.348776 -133.14172)
		(width 0.14224)
		(layer "In2.Cu")
		(net "M_D_DQS_DN<17>")
	)
	(segment
		(start 247.648984 -92.83319)
		(end 247.616218 -92.83319)
		(width 0.0889)
		(layer "In2.Cu")
		(net "M_D_DQS_DN<17>")
	)
	(segment
		(start 237.149894 -130.8862)
		(end 237.142528 -130.8862)
		(width 0.14224)
		(layer "In2.Cu")
		(net "M_D_DQS_DN<17>")
	)
	(segment
		(start 237.582202 -134.147306)
		(end 237.582202 -134.63143)
		(width 0.14224)
		(layer "In2.Cu")
		(net "M_D_DQS_DN<17>")
	)
	(segment
		(start 236.906816 -132.50164)
		(end 237.038896 -132.63372)
		(width 0.14224)
		(layer "In2.Cu")
		(net "M_D_DQS_DN<17>")
	)
	(segment
		(start 247.279668 -93.424502)
		(end 247.284494 -93.433138)
		(width 0.0889)
		(layer "In2.Cu")
		(net "M_D_DQS_DN<17>")
	)
	(segment
		(start 237.193836 -133.29666)
		(end 237.046516 -133.29666)
		(width 0.14224)
		(layer "In2.Cu")
		(net "M_D_DQS_DN<17>")
	)
	(segment
		(start 237.046516 -133.29666)
		(end 236.906816 -133.43636)
		(width 0.14224)
		(layer "In2.Cu")
		(net "M_D_DQS_DN<17>")
	)
	(segment
		(start 236.906816 -133.79704)
		(end 237.069376 -133.9596)
		(width 0.14224)
		(layer "In2.Cu")
		(net "M_D_DQS_DN<17>")
	)
	(segment
		(start 236.906816 -132.15366)
		(end 236.906816 -132.50164)
		(width 0.14224)
		(layer "In2.Cu")
		(net "M_D_DQS_DN<17>")
	)
	(segment
		(start 248.489724 -89.765886)
		(end 248.489724 -89.427812)
		(width 0.0889)
		(layer "In2.Cu")
		(net "M_D_DQS_DN<17>")
	)
	(segment
		(start 246.108474 -102.7049)
		(end 246.108474 -102.726998)
		(width 0.0889)
		(layer "In2.Cu")
		(net "M_D_DQS_DN<17>")
	)
	(segment
		(start 237.038896 -132.63372)
		(end 237.193836 -132.63372)
		(width 0.14224)
		(layer "In2.Cu")
		(net "M_D_DQS_DN<17>")
	)
	(segment
		(start 247.130316 -97.211134)
		(end 247.130316 -100.015294)
		(width 0.0889)
		(layer "In2.Cu")
		(net "M_D_DQS_DN<17>")
	)
	(segment
		(start 247.245124 -97.058226)
		(end 247.130316 -97.211134)
		(width 0.0889)
		(layer "In2.Cu")
		(net "M_D_DQS_DN<17>")
	)
	(segment
		(start 248.143014 -91.547188)
		(end 248.138188 -91.555824)
		(width 0.0889)
		(layer "In2.Cu")
		(net "M_D_DQS_DN<17>")
	)
	(segment
		(start 237.577376 -131.7244)
		(end 237.297976 -132.0038)
		(width 0.14224)
		(layer "In2.Cu")
		(net "M_D_DQS_DN<17>")
	)
	(segment
		(start 246.069104 -101.076506)
		(end 246.069104 -102.66553)
		(width 0.0889)
		(layer "In2.Cu")
		(net "M_D_DQS_DN<17>")
	)
	(segment
		(start 236.906816 -133.43636)
		(end 236.906816 -133.79704)
		(width 0.14224)
		(layer "In2.Cu")
		(net "M_D_DQS_DN<17>")
	)
	(segment
		(start 237.193836 -132.63372)
		(end 237.348776 -132.78866)
		(width 0.14224)
		(layer "In2.Cu")
		(net "M_D_DQS_DN<17>")
	)
	(segment
		(start 237.577376 -131.321048)
		(end 237.577376 -131.7244)
		(width 0.14224)
		(layer "In2.Cu")
		(net "M_D_DQS_DN<17>")
	)
	(segment
		(start 237.069376 -133.9596)
		(end 237.394496 -133.9596)
		(width 0.14224)
		(layer "In2.Cu")
		(net "M_D_DQS_DN<17>")
	)
	(segment
		(start 247.130316 -100.015294)
		(end 246.069104 -101.076506)
		(width 0.0889)
		(layer "In2.Cu")
		(net "M_D_DQS_DN<17>")
	)
	(segment
		(start 237.348776 -133.14172)
		(end 237.193836 -133.29666)
		(width 0.14224)
		(layer "In2.Cu")
		(net "M_D_DQS_DN<17>")
	)
	(segment
		(start 248.489724 -89.427812)
		(end 248.431812 -89.3699)
		(width 0.0889)
		(layer "In2.Cu")
		(net "M_D_DQS_DN<17>")
	)
	(segment
		(start 248.149364 -90.54592)
		(end 248.143014 -90.556588)
		(width 0.0889)
		(layer "In2.Cu")
		(net "M_D_DQS_DN<17>")
	)
	(segment
		(start 239.51692 -121.958608)
		(end 237.924848 -123.55068)
		(width 0.14224)
		(layer "In2.Cu")
		(net "M_D_DQS_DN<17>")
	)
	(segment
		(start 237.056676 -132.0038)
		(end 236.906816 -132.15366)
		(width 0.14224)
		(layer "In2.Cu")
		(net "M_D_DQS_DN<17>")
	)
	(segment
		(start 246.108474 -102.726998)
		(end 246.108474 -104.505506)
		(width 0.14224)
		(layer "In2.Cu")
		(net "M_D_DQS_DN<17>")
	)
	(segment
		(start 247.284494 -95.414338)
		(end 247.290844 -95.425006)
		(width 0.0889)
		(layer "In2.Cu")
		(net "M_D_DQS_DN<17>")
	)
	(segment
		(start 239.51692 -111.09706)
		(end 239.51692 -121.958608)
		(width 0.14224)
		(layer "In2.Cu")
		(net "M_D_DQS_DN<17>")
	)
	(segment
		(start 237.924848 -130.111246)
		(end 237.149894 -130.8862)
		(width 0.14224)
		(layer "In2.Cu")
		(net "M_D_DQS_DN<17>")
	)
	(segment
		(start 247.290844 -94.01302)
		(end 247.284494 -94.023688)
		(width 0.0889)
		(layer "In2.Cu")
		(net "M_D_DQS_DN<17>")
	)
	(arc
		(start 248.138188 -91.555824)
		(mid 248.089433 -91.752176)
		(end 248.143014 -91.947238)
		(width 0.0889)
		(layer "In2.Cu")
		(net "M_D_DQS_DN<17>")
	)
	(arc
		(start 248.143014 -89.966038)
		(mid 248.222236 -90.255156)
		(end 248.149364 -90.54592)
		(width 0.0889)
		(layer "In2.Cu")
		(net "M_D_DQS_DN<17>")
	)
	(arc
		(start 248.143014 -90.956638)
		(mid 248.222236 -91.245756)
		(end 248.149364 -91.53652)
		(width 0.0889)
		(layer "In2.Cu")
		(net "M_D_DQS_DN<17>")
	)
	(arc
		(start 247.284494 -96.404938)
		(mid 247.305763 -96.445328)
		(end 247.323864 -96.487234)
		(width 0.0889)
		(layer "In2.Cu")
		(net "M_D_DQS_DN<17>")
	)
	(arc
		(start 247.284494 -95.014288)
		(mid 247.231024 -95.209351)
		(end 247.279668 -95.405702)
		(width 0.0889)
		(layer "In2.Cu")
		(net "M_D_DQS_DN<17>")
	)
	(arc
		(start 247.290844 -95.425006)
		(mid 247.363642 -95.715769)
		(end 247.284494 -96.004888)
		(width 0.0889)
		(layer "In2.Cu")
		(net "M_D_DQS_DN<17>")
	)
	(arc
		(start 248.138188 -90.565224)
		(mid 248.089433 -90.761576)
		(end 248.143014 -90.956638)
		(width 0.0889)
		(layer "In2.Cu")
		(net "M_D_DQS_DN<17>")
	)
	(arc
		(start 247.284494 -94.423484)
		(mid 247.363625 -94.718886)
		(end 247.284494 -95.014288)
		(width 0.0889)
		(layer "In2.Cu")
		(net "M_D_DQS_DN<17>")
	)
	(arc
		(start 247.284494 -93.433138)
		(mid 247.363716 -93.722256)
		(end 247.290844 -94.01302)
		(width 0.0889)
		(layer "In2.Cu")
		(net "M_D_DQS_DN<17>")
	)
	(arc
		(start 247.284494 -96.004888)
		(mid 247.231024 -96.199951)
		(end 247.279668 -96.396302)
		(width 0.0889)
		(layer "In2.Cu")
		(net "M_D_DQS_DN<17>")
	)
	(arc
		(start 248.143014 -91.947238)
		(mid 248.147343 -92.53041)
		(end 247.648984 -92.83319)
		(width 0.0889)
		(layer "In2.Cu")
		(net "M_D_DQS_DN<17>")
	)
	(arc
		(start 247.616218 -92.83319)
		(mid 247.2833 -93.035181)
		(end 247.279668 -93.424502)
		(width 0.0889)
		(layer "In2.Cu")
		(net "M_D_DQS_DN<17>")
	)
	(arc
		(start 247.323864 -96.487234)
		(mid 247.358249 -96.782899)
		(end 247.245124 -97.058226)
		(width 0.0889)
		(layer "In2.Cu")
		(net "M_D_DQS_DN<17>")
	)
	(arc
		(start 247.284494 -94.023688)
		(mid 247.230995 -94.223586)
		(end 247.284494 -94.423484)
		(width 0.0889)
		(layer "In2.Cu")
		(net "M_D_DQS_DN<17>")
	)
	(arc
		(start 248.431812 -89.3699)
		(mid 248.129543 -89.591449)
		(end 248.143014 -89.966038)
		(width 0.0889)
		(layer "In2.Cu")
		(net "M_D_DQS_DN<17>")
	)
	(segment
		(start 288.36366 -96.518984)
		(end 288.93516 -96.518984)
		(width 0.1651)
		(layer "F.Cu")
		(net "M_D_DQS_DN<16>")
	)
	(segment
		(start 311.51576 -135.25373)
		(end 311.30748 -135.25373)
		(width 0.1651)
		(layer "F.Cu")
		(net "M_D_DQS_DN<16>")
	)
	(segment
		(start 312.000392 -133.0706)
		(end 311.999884 -133.076442)
		(width 0.1651)
		(layer "F.Cu")
		(net "M_D_DQS_DN<16>")
	)
	(segment
		(start 311.999884 -133.729984)
		(end 311.5818 -134.148068)
		(width 0.1651)
		(layer "F.Cu")
		(net "M_D_DQS_DN<16>")
	)
	(segment
		(start 311.999884 -133.076442)
		(end 311.999884 -133.729984)
		(width 0.1651)
		(layer "F.Cu")
		(net "M_D_DQS_DN<16>")
	)
	(segment
		(start 311.767728 -135.001762)
		(end 311.51576 -135.25373)
		(width 0.1651)
		(layer "F.Cu")
		(net "M_D_DQS_DN<16>")
	)
	(segment
		(start 311.767728 -134.755128)
		(end 311.767728 -135.001762)
		(width 0.1651)
		(layer "F.Cu")
		(net "M_D_DQS_DN<16>")
	)
	(segment
		(start 311.30748 -135.25373)
		(end 311.11825 -135.0645)
		(width 0.1651)
		(layer "F.Cu")
		(net "M_D_DQS_DN<16>")
	)
	(segment
		(start 311.5818 -134.148068)
		(end 311.5818 -134.5692)
		(width 0.1651)
		(layer "F.Cu")
		(net "M_D_DQS_DN<16>")
	)
	(segment
		(start 311.5818 -134.5692)
		(end 311.767728 -134.755128)
		(width 0.1651)
		(layer "F.Cu")
		(net "M_D_DQS_DN<16>")
	)
	(segment
		(start 311.11825 -135.0645)
		(end 311.0992 -135.0645)
		(width 0.1651)
		(layer "F.Cu")
		(net "M_D_DQS_DN<16>")
	)
	(via
		(at 311.092596 -130.8862)
		(size 0.508)
		(drill 0.254)
		(layers "F.Cu" "B.Cu")
		(net "M_D_DQS_DN<16>")
	)
	(via
		(at 288.93516 -96.518984)
		(size 0.508)
		(drill 0.254)
		(layers "F.Cu" "B.Cu")
		(net "M_D_DQS_DN<16>")
	)
	(via
		(at 311.0992 -135.0645)
		(size 0.508)
		(drill 0.254)
		(layers "F.Cu" "B.Cu")
		(net "M_D_DQS_DN<16>")
	)
	(segment
		(start 311.5564 -131.4196)
		(end 311.5564 -131.775454)
		(width 0.1651)
		(layer "B.Cu")
		(net "M_D_DQS_DN<16>")
	)
	(segment
		(start 311.7342 -130.9116)
		(end 311.7342 -131.2418)
		(width 0.1651)
		(layer "B.Cu")
		(net "M_D_DQS_DN<16>")
	)
	(segment
		(start 311.514236 -130.691636)
		(end 311.7342 -130.9116)
		(width 0.1651)
		(layer "B.Cu")
		(net "M_D_DQS_DN<16>")
	)
	(segment
		(start 311.5564 -131.775454)
		(end 312.000138 -132.219192)
		(width 0.1651)
		(layer "B.Cu")
		(net "M_D_DQS_DN<16>")
	)
	(segment
		(start 312.000138 -132.219192)
		(end 312.000138 -132.875528)
		(width 0.1651)
		(layer "B.Cu")
		(net "M_D_DQS_DN<16>")
	)
	(segment
		(start 311.28716 -130.691636)
		(end 311.514236 -130.691636)
		(width 0.1651)
		(layer "B.Cu")
		(net "M_D_DQS_DN<16>")
	)
	(segment
		(start 311.092596 -130.8862)
		(end 311.28716 -130.691636)
		(width 0.1651)
		(layer "B.Cu")
		(net "M_D_DQS_DN<16>")
	)
	(segment
		(start 312.000138 -132.875528)
		(end 312.000392 -132.876036)
		(width 0.1651)
		(layer "B.Cu")
		(net "M_D_DQS_DN<16>")
	)
	(segment
		(start 311.7342 -131.2418)
		(end 311.5564 -131.4196)
		(width 0.1651)
		(layer "B.Cu")
		(net "M_D_DQS_DN<16>")
	)
	(segment
		(start 311.019444 -133.9596)
		(end 311.344564 -133.9596)
		(width 0.14224)
		(layer "In2.Cu")
		(net "M_D_DQS_DN<16>")
	)
	(segment
		(start 311.298844 -132.78866)
		(end 311.298844 -133.14172)
		(width 0.14224)
		(layer "In2.Cu")
		(net "M_D_DQS_DN<16>")
	)
	(segment
		(start 310.996584 -133.29666)
		(end 310.856884 -133.43636)
		(width 0.14224)
		(layer "In2.Cu")
		(net "M_D_DQS_DN<16>")
	)
	(segment
		(start 290.693348 -104.9655)
		(end 292.4302 -104.9655)
		(width 0.0889)
		(layer "In2.Cu")
		(net "M_D_DQS_DN<16>")
	)
	(segment
		(start 288.93516 -96.857058)
		(end 289.000438 -96.922336)
		(width 0.0889)
		(layer "In2.Cu")
		(net "M_D_DQS_DN<16>")
	)
	(segment
		(start 310.856884 -132.15366)
		(end 310.856884 -132.50164)
		(width 0.14224)
		(layer "In2.Cu")
		(net "M_D_DQS_DN<16>")
	)
	(segment
		(start 311.900316 -128.883918)
		(end 311.900316 -130.07848)
		(width 0.14224)
		(layer "In2.Cu")
		(net "M_D_DQS_DN<16>")
	)
	(segment
		(start 288.58845 -100.681536)
		(end 288.5948 -100.692204)
		(width 0.0889)
		(layer "In2.Cu")
		(net "M_D_DQS_DN<16>")
	)
	(segment
		(start 288.5948 -102.252018)
		(end 288.58845 -102.262686)
		(width 0.0889)
		(layer "In2.Cu")
		(net "M_D_DQS_DN<16>")
	)
	(segment
		(start 311.900316 -130.07848)
		(end 311.092596 -130.8862)
		(width 0.14224)
		(layer "In2.Cu")
		(net "M_D_DQS_DN<16>")
	)
	(segment
		(start 310.856884 -133.79704)
		(end 311.019444 -133.9596)
		(width 0.14224)
		(layer "In2.Cu")
		(net "M_D_DQS_DN<16>")
	)
	(segment
		(start 310.856884 -132.50164)
		(end 310.988964 -132.63372)
		(width 0.14224)
		(layer "In2.Cu")
		(net "M_D_DQS_DN<16>")
	)
	(segment
		(start 301.210472 -108.0008)
		(end 312.98388 -119.774208)
		(width 0.14224)
		(layer "In2.Cu")
		(net "M_D_DQS_DN<16>")
	)
	(segment
		(start 310.988964 -132.63372)
		(end 311.143904 -132.63372)
		(width 0.14224)
		(layer "In2.Cu")
		(net "M_D_DQS_DN<16>")
	)
	(segment
		(start 288.819336 -103.062786)
		(end 288.858198 -103.13035)
		(width 0.0889)
		(layer "In2.Cu")
		(net "M_D_DQS_DN<16>")
	)
	(segment
		(start 311.298844 -133.14172)
		(end 311.143904 -133.29666)
		(width 0.14224)
		(layer "In2.Cu")
		(net "M_D_DQS_DN<16>")
	)
	(segment
		(start 311.344564 -133.9596)
		(end 311.53227 -134.147306)
		(width 0.14224)
		(layer "In2.Cu")
		(net "M_D_DQS_DN<16>")
	)
	(segment
		(start 310.856884 -133.43636)
		(end 310.856884 -133.79704)
		(width 0.14224)
		(layer "In2.Cu")
		(net "M_D_DQS_DN<16>")
	)
	(segment
		(start 293.511986 -105.991406)
		(end 293.527734 -106.007154)
		(width 0.0889)
		(layer "In2.Cu")
		(net "M_D_DQS_DN<16>")
	)
	(segment
		(start 293.527734 -106.007154)
		(end 294.63238 -107.1118)
		(width 0.14224)
		(layer "In2.Cu")
		(net "M_D_DQS_DN<16>")
	)
	(segment
		(start 298.4881 -107.1118)
		(end 299.3771 -108.0008)
		(width 0.14224)
		(layer "In2.Cu")
		(net "M_D_DQS_DN<16>")
	)
	(segment
		(start 311.006744 -132.0038)
		(end 310.856884 -132.15366)
		(width 0.14224)
		(layer "In2.Cu")
		(net "M_D_DQS_DN<16>")
	)
	(segment
		(start 288.5948 -99.280218)
		(end 288.58845 -99.290886)
		(width 0.0889)
		(layer "In2.Cu")
		(net "M_D_DQS_DN<16>")
	)
	(segment
		(start 288.58845 -102.662736)
		(end 288.819336 -103.062786)
		(width 0.0889)
		(layer "In2.Cu")
		(net "M_D_DQS_DN<16>")
	)
	(segment
		(start 288.58845 -101.272086)
		(end 288.583624 -101.280722)
		(width 0.0889)
		(layer "In2.Cu")
		(net "M_D_DQS_DN<16>")
	)
	(segment
		(start 311.527444 -131.7244)
		(end 311.248044 -132.0038)
		(width 0.14224)
		(layer "In2.Cu")
		(net "M_D_DQS_DN<16>")
	)
	(segment
		(start 312.98388 -127.800354)
		(end 311.900316 -128.883918)
		(width 0.14224)
		(layer "In2.Cu")
		(net "M_D_DQS_DN<16>")
	)
	(segment
		(start 311.143904 -133.29666)
		(end 310.996584 -133.29666)
		(width 0.14224)
		(layer "In2.Cu")
		(net "M_D_DQS_DN<16>")
	)
	(segment
		(start 312.98388 -119.774208)
		(end 312.98388 -127.800354)
		(width 0.14224)
		(layer "In2.Cu")
		(net "M_D_DQS_DN<16>")
	)
	(segment
		(start 288.95675 -98.100134)
		(end 288.923984 -98.100134)
		(width 0.0889)
		(layer "In2.Cu")
		(net "M_D_DQS_DN<16>")
	)
	(segment
		(start 311.143904 -132.63372)
		(end 311.298844 -132.78866)
		(width 0.14224)
		(layer "In2.Cu")
		(net "M_D_DQS_DN<16>")
	)
	(segment
		(start 288.93516 -96.518984)
		(end 288.93516 -96.857058)
		(width 0.0889)
		(layer "In2.Cu")
		(net "M_D_DQS_DN<16>")
	)
	(segment
		(start 292.4302 -104.9655)
		(end 293.456106 -105.991406)
		(width 0.0889)
		(layer "In2.Cu")
		(net "M_D_DQS_DN<16>")
	)
	(segment
		(start 288.58845 -102.262686)
		(end 288.583624 -102.271322)
		(width 0.0889)
		(layer "In2.Cu")
		(net "M_D_DQS_DN<16>")
	)
	(segment
		(start 311.092596 -130.8862)
		(end 311.527444 -131.321048)
		(width 0.14224)
		(layer "In2.Cu")
		(net "M_D_DQS_DN<16>")
	)
	(segment
		(start 294.63238 -107.1118)
		(end 298.4881 -107.1118)
		(width 0.14224)
		(layer "In2.Cu")
		(net "M_D_DQS_DN<16>")
	)
	(segment
		(start 288.858198 -103.13035)
		(end 290.693348 -104.9655)
		(width 0.0889)
		(layer "In2.Cu")
		(net "M_D_DQS_DN<16>")
	)
	(segment
		(start 288.58845 -99.290886)
		(end 288.583624 -99.299522)
		(width 0.0889)
		(layer "In2.Cu")
		(net "M_D_DQS_DN<16>")
	)
	(segment
		(start 299.3771 -108.0008)
		(end 301.210472 -108.0008)
		(width 0.14224)
		(layer "In2.Cu")
		(net "M_D_DQS_DN<16>")
	)
	(segment
		(start 293.456106 -105.991406)
		(end 293.511986 -105.991406)
		(width 0.0889)
		(layer "In2.Cu")
		(net "M_D_DQS_DN<16>")
	)
	(segment
		(start 311.248044 -132.0038)
		(end 311.006744 -132.0038)
		(width 0.14224)
		(layer "In2.Cu")
		(net "M_D_DQS_DN<16>")
	)
	(segment
		(start 311.527444 -131.321048)
		(end 311.527444 -131.7244)
		(width 0.14224)
		(layer "In2.Cu")
		(net "M_D_DQS_DN<16>")
	)
	(segment
		(start 311.53227 -134.147306)
		(end 311.53227 -134.63143)
		(width 0.14224)
		(layer "In2.Cu")
		(net "M_D_DQS_DN<16>")
	)
	(segment
		(start 311.53227 -134.63143)
		(end 311.0992 -135.0645)
		(width 0.14224)
		(layer "In2.Cu")
		(net "M_D_DQS_DN<16>")
	)
	(arc
		(start 288.58845 -98.700336)
		(mid 288.667672 -98.989454)
		(end 288.5948 -99.280218)
		(width 0.0889)
		(layer "In2.Cu")
		(net "M_D_DQS_DN<16>")
	)
	(arc
		(start 288.58845 -100.28174)
		(mid 288.534951 -100.481638)
		(end 288.58845 -100.681536)
		(width 0.0889)
		(layer "In2.Cu")
		(net "M_D_DQS_DN<16>")
	)
	(arc
		(start 289.000438 -96.922336)
		(mid 289.525619 -97.531489)
		(end 288.95675 -98.100134)
		(width 0.0889)
		(layer "In2.Cu")
		(net "M_D_DQS_DN<16>")
	)
	(arc
		(start 288.923984 -98.100134)
		(mid 288.585815 -98.304932)
		(end 288.58845 -98.700336)
		(width 0.0889)
		(layer "In2.Cu")
		(net "M_D_DQS_DN<16>")
	)
	(arc
		(start 288.58845 -99.690936)
		(mid 288.667581 -99.986338)
		(end 288.58845 -100.28174)
		(width 0.0889)
		(layer "In2.Cu")
		(net "M_D_DQS_DN<16>")
	)
	(arc
		(start 288.583624 -99.299522)
		(mid 288.534869 -99.495874)
		(end 288.58845 -99.690936)
		(width 0.0889)
		(layer "In2.Cu")
		(net "M_D_DQS_DN<16>")
	)
	(arc
		(start 288.583624 -101.280722)
		(mid 288.534869 -101.477074)
		(end 288.58845 -101.672136)
		(width 0.0889)
		(layer "In2.Cu")
		(net "M_D_DQS_DN<16>")
	)
	(arc
		(start 288.583624 -102.271322)
		(mid 288.534869 -102.467674)
		(end 288.58845 -102.662736)
		(width 0.0889)
		(layer "In2.Cu")
		(net "M_D_DQS_DN<16>")
	)
	(arc
		(start 288.58845 -101.672136)
		(mid 288.667672 -101.961254)
		(end 288.5948 -102.252018)
		(width 0.0889)
		(layer "In2.Cu")
		(net "M_D_DQS_DN<16>")
	)
	(arc
		(start 288.5948 -100.692204)
		(mid 288.667598 -100.982967)
		(end 288.58845 -101.272086)
		(width 0.0889)
		(layer "In2.Cu")
		(net "M_D_DQS_DN<16>")
	)
	(segment
		(start 301.957486 -135.25373)
		(end 301.768256 -135.0645)
		(width 0.1651)
		(layer "F.Cu")
		(net "M_D_DQS_DN<15>")
	)
	(segment
		(start 302.417734 -134.755128)
		(end 302.417734 -135.001762)
		(width 0.1651)
		(layer "F.Cu")
		(net "M_D_DQS_DN<15>")
	)
	(segment
		(start 302.231806 -134.5692)
		(end 302.417734 -134.755128)
		(width 0.1651)
		(layer "F.Cu")
		(net "M_D_DQS_DN<15>")
	)
	(segment
		(start 302.650398 -133.0706)
		(end 302.64989 -133.076442)
		(width 0.1651)
		(layer "F.Cu")
		(net "M_D_DQS_DN<15>")
	)
	(segment
		(start 301.768256 -135.0645)
		(end 301.749206 -135.0645)
		(width 0.1651)
		(layer "F.Cu")
		(net "M_D_DQS_DN<15>")
	)
	(segment
		(start 302.417734 -135.001762)
		(end 302.165766 -135.25373)
		(width 0.1651)
		(layer "F.Cu")
		(net "M_D_DQS_DN<15>")
	)
	(segment
		(start 302.165766 -135.25373)
		(end 301.957486 -135.25373)
		(width 0.1651)
		(layer "F.Cu")
		(net "M_D_DQS_DN<15>")
	)
	(segment
		(start 302.64989 -133.729984)
		(end 302.231806 -134.148068)
		(width 0.1651)
		(layer "F.Cu")
		(net "M_D_DQS_DN<15>")
	)
	(segment
		(start 283.212794 -96.518984)
		(end 283.784294 -96.518984)
		(width 0.1651)
		(layer "F.Cu")
		(net "M_D_DQS_DN<15>")
	)
	(segment
		(start 302.64989 -133.076442)
		(end 302.64989 -133.729984)
		(width 0.1651)
		(layer "F.Cu")
		(net "M_D_DQS_DN<15>")
	)
	(segment
		(start 302.231806 -134.148068)
		(end 302.231806 -134.5692)
		(width 0.1651)
		(layer "F.Cu")
		(net "M_D_DQS_DN<15>")
	)
	(via
		(at 301.742602 -130.8862)
		(size 0.508)
		(drill 0.254)
		(layers "F.Cu" "B.Cu")
		(net "M_D_DQS_DN<15>")
	)
	(via
		(at 301.749206 -135.0645)
		(size 0.508)
		(drill 0.254)
		(layers "F.Cu" "B.Cu")
		(net "M_D_DQS_DN<15>")
	)
	(via
		(at 283.784294 -96.518984)
		(size 0.508)
		(drill 0.254)
		(layers "F.Cu" "B.Cu")
		(net "M_D_DQS_DN<15>")
	)
	(segment
		(start 302.650144 -132.219192)
		(end 302.650144 -132.875528)
		(width 0.1651)
		(layer "B.Cu")
		(net "M_D_DQS_DN<15>")
	)
	(segment
		(start 302.650144 -132.875528)
		(end 302.650398 -132.876036)
		(width 0.1651)
		(layer "B.Cu")
		(net "M_D_DQS_DN<15>")
	)
	(segment
		(start 302.164242 -130.691636)
		(end 302.384206 -130.9116)
		(width 0.1651)
		(layer "B.Cu")
		(net "M_D_DQS_DN<15>")
	)
	(segment
		(start 302.206406 -131.4196)
		(end 302.206406 -131.775454)
		(width 0.1651)
		(layer "B.Cu")
		(net "M_D_DQS_DN<15>")
	)
	(segment
		(start 302.206406 -131.775454)
		(end 302.650144 -132.219192)
		(width 0.1651)
		(layer "B.Cu")
		(net "M_D_DQS_DN<15>")
	)
	(segment
		(start 302.384206 -131.2418)
		(end 302.206406 -131.4196)
		(width 0.1651)
		(layer "B.Cu")
		(net "M_D_DQS_DN<15>")
	)
	(segment
		(start 302.384206 -130.9116)
		(end 302.384206 -131.2418)
		(width 0.1651)
		(layer "B.Cu")
		(net "M_D_DQS_DN<15>")
	)
	(segment
		(start 301.937166 -130.691636)
		(end 302.164242 -130.691636)
		(width 0.1651)
		(layer "B.Cu")
		(net "M_D_DQS_DN<15>")
	)
	(segment
		(start 301.742602 -130.8862)
		(end 301.937166 -130.691636)
		(width 0.1651)
		(layer "B.Cu")
		(net "M_D_DQS_DN<15>")
	)
	(segment
		(start 283.805884 -98.100134)
		(end 283.773118 -98.100134)
		(width 0.0889)
		(layer "In2.Cu")
		(net "M_D_DQS_DN<15>")
	)
	(segment
		(start 301.79391 -133.29666)
		(end 301.64659 -133.29666)
		(width 0.14224)
		(layer "In2.Cu")
		(net "M_D_DQS_DN<15>")
	)
	(segment
		(start 299.535596 -117.386862)
		(end 299.535088 -117.387116)
		(width 0.14224)
		(layer "In2.Cu")
		(net "M_D_DQS_DN<15>")
	)
	(segment
		(start 283.437584 -99.690682)
		(end 283.443934 -99.70135)
		(width 0.0889)
		(layer "In2.Cu")
		(net "M_D_DQS_DN<15>")
	)
	(segment
		(start 283.211524 -110.339124)
		(end 285.2674 -112.395)
		(width 0.14224)
		(layer "In2.Cu")
		(net "M_D_DQS_DN<15>")
	)
	(segment
		(start 301.65675 -132.0038)
		(end 301.50689 -132.15366)
		(width 0.14224)
		(layer "In2.Cu")
		(net "M_D_DQS_DN<15>")
	)
	(segment
		(start 283.312362 -104.81945)
		(end 283.172154 -104.959658)
		(width 0.0889)
		(layer "In2.Cu")
		(net "M_D_DQS_DN<15>")
	)
	(segment
		(start 301.64659 -133.29666)
		(end 301.50689 -133.43636)
		(width 0.14224)
		(layer "In2.Cu")
		(net "M_D_DQS_DN<15>")
	)
	(segment
		(start 301.79391 -132.63372)
		(end 301.94885 -132.78866)
		(width 0.14224)
		(layer "In2.Cu")
		(net "M_D_DQS_DN<15>")
	)
	(segment
		(start 283.172154 -104.959658)
		(end 283.172154 -105.70083)
		(width 0.0889)
		(layer "In2.Cu")
		(net "M_D_DQS_DN<15>")
	)
	(segment
		(start 283.444188 -103.241602)
		(end 283.312362 -103.47706)
		(width 0.0889)
		(layer "In2.Cu")
		(net "M_D_DQS_DN<15>")
	)
	(segment
		(start 301.50689 -133.79704)
		(end 301.66945 -133.9596)
		(width 0.14224)
		(layer "In2.Cu")
		(net "M_D_DQS_DN<15>")
	)
	(segment
		(start 301.94885 -132.78866)
		(end 301.94885 -133.14172)
		(width 0.14224)
		(layer "In2.Cu")
		(net "M_D_DQS_DN<15>")
	)
	(segment
		(start 283.430726 -100.668836)
		(end 283.446474 -100.696268)
		(width 0.0889)
		(layer "In2.Cu")
		(net "M_D_DQS_DN<15>")
	)
	(segment
		(start 283.437584 -101.671882)
		(end 283.443934 -101.68255)
		(width 0.0889)
		(layer "In2.Cu")
		(net "M_D_DQS_DN<15>")
	)
	(segment
		(start 299.535088 -117.387116)
		(end 302.53178 -120.383808)
		(width 0.14224)
		(layer "In2.Cu")
		(net "M_D_DQS_DN<15>")
	)
	(segment
		(start 283.211524 -105.762298)
		(end 283.211524 -110.339124)
		(width 0.14224)
		(layer "In2.Cu")
		(net "M_D_DQS_DN<15>")
	)
	(segment
		(start 285.2674 -112.395)
		(end 285.2674 -113.453672)
		(width 0.14224)
		(layer "In2.Cu")
		(net "M_D_DQS_DN<15>")
	)
	(segment
		(start 283.211524 -105.7402)
		(end 283.211524 -105.762298)
		(width 0.0889)
		(layer "In2.Cu")
		(net "M_D_DQS_DN<15>")
	)
	(segment
		(start 283.443934 -99.280218)
		(end 283.437584 -99.290886)
		(width 0.0889)
		(layer "In2.Cu")
		(net "M_D_DQS_DN<15>")
	)
	(segment
		(start 289.20059 -117.386862)
		(end 299.535596 -117.386862)
		(width 0.14224)
		(layer "In2.Cu")
		(net "M_D_DQS_DN<15>")
	)
	(segment
		(start 301.50689 -132.15366)
		(end 301.50689 -132.50164)
		(width 0.14224)
		(layer "In2.Cu")
		(net "M_D_DQS_DN<15>")
	)
	(segment
		(start 283.172154 -105.70083)
		(end 283.211524 -105.7402)
		(width 0.0889)
		(layer "In2.Cu")
		(net "M_D_DQS_DN<15>")
	)
	(segment
		(start 283.432758 -101.663246)
		(end 283.437584 -101.671882)
		(width 0.0889)
		(layer "In2.Cu")
		(net "M_D_DQS_DN<15>")
	)
	(segment
		(start 301.742602 -130.8862)
		(end 302.17745 -131.321048)
		(width 0.14224)
		(layer "In2.Cu")
		(net "M_D_DQS_DN<15>")
	)
	(segment
		(start 302.182276 -134.147306)
		(end 302.182276 -134.63143)
		(width 0.14224)
		(layer "In2.Cu")
		(net "M_D_DQS_DN<15>")
	)
	(segment
		(start 302.182276 -134.63143)
		(end 301.749206 -135.0645)
		(width 0.14224)
		(layer "In2.Cu")
		(net "M_D_DQS_DN<15>")
	)
	(segment
		(start 301.50689 -133.43636)
		(end 301.50689 -133.79704)
		(width 0.14224)
		(layer "In2.Cu")
		(net "M_D_DQS_DN<15>")
	)
	(segment
		(start 285.2674 -113.453672)
		(end 289.20059 -117.386862)
		(width 0.14224)
		(layer "In2.Cu")
		(net "M_D_DQS_DN<15>")
	)
	(segment
		(start 283.437584 -98.300286)
		(end 283.432758 -98.308922)
		(width 0.0889)
		(layer "In2.Cu")
		(net "M_D_DQS_DN<15>")
	)
	(segment
		(start 283.312362 -103.47706)
		(end 283.312362 -104.81945)
		(width 0.0889)
		(layer "In2.Cu")
		(net "M_D_DQS_DN<15>")
	)
	(segment
		(start 283.443934 -98.289618)
		(end 283.437584 -98.300286)
		(width 0.0889)
		(layer "In2.Cu")
		(net "M_D_DQS_DN<15>")
	)
	(segment
		(start 301.99457 -133.9596)
		(end 302.182276 -134.147306)
		(width 0.14224)
		(layer "In2.Cu")
		(net "M_D_DQS_DN<15>")
	)
	(segment
		(start 302.17745 -131.321048)
		(end 302.17745 -131.7244)
		(width 0.14224)
		(layer "In2.Cu")
		(net "M_D_DQS_DN<15>")
	)
	(segment
		(start 302.17745 -131.7244)
		(end 301.89805 -132.0038)
		(width 0.14224)
		(layer "In2.Cu")
		(net "M_D_DQS_DN<15>")
	)
	(segment
		(start 302.53178 -120.383808)
		(end 302.53178 -130.097022)
		(width 0.14224)
		(layer "In2.Cu")
		(net "M_D_DQS_DN<15>")
	)
	(segment
		(start 301.63897 -132.63372)
		(end 301.79391 -132.63372)
		(width 0.14224)
		(layer "In2.Cu")
		(net "M_D_DQS_DN<15>")
	)
	(segment
		(start 301.94885 -133.14172)
		(end 301.79391 -133.29666)
		(width 0.14224)
		(layer "In2.Cu")
		(net "M_D_DQS_DN<15>")
	)
	(segment
		(start 301.89805 -132.0038)
		(end 301.65675 -132.0038)
		(width 0.14224)
		(layer "In2.Cu")
		(net "M_D_DQS_DN<15>")
	)
	(segment
		(start 301.50689 -132.50164)
		(end 301.63897 -132.63372)
		(width 0.14224)
		(layer "In2.Cu")
		(net "M_D_DQS_DN<15>")
	)
	(segment
		(start 301.66945 -133.9596)
		(end 301.99457 -133.9596)
		(width 0.14224)
		(layer "In2.Cu")
		(net "M_D_DQS_DN<15>")
	)
	(segment
		(start 302.53178 -130.097022)
		(end 301.742602 -130.8862)
		(width 0.14224)
		(layer "In2.Cu")
		(net "M_D_DQS_DN<15>")
	)
	(arc
		(start 283.784294 -96.518984)
		(mid 283.983009 -96.825487)
		(end 284.216094 -97.10674)
		(width 0.0889)
		(layer "In2.Cu")
		(net "M_D_DQS_DN<15>")
	)
	(arc
		(start 283.437584 -99.290886)
		(mid 283.384085 -99.490784)
		(end 283.437584 -99.690682)
		(width 0.0889)
		(layer "In2.Cu")
		(net "M_D_DQS_DN<15>")
	)
	(arc
		(start 283.437584 -102.662736)
		(mid 283.516676 -102.951316)
		(end 283.444188 -103.241602)
		(width 0.0889)
		(layer "In2.Cu")
		(net "M_D_DQS_DN<15>")
	)
	(arc
		(start 283.773118 -98.100134)
		(mid 283.583198 -98.150883)
		(end 283.443934 -98.289618)
		(width 0.0889)
		(layer "In2.Cu")
		(net "M_D_DQS_DN<15>")
	)
	(arc
		(start 283.437584 -101.271832)
		(mid 283.384114 -101.466895)
		(end 283.432758 -101.663246)
		(width 0.0889)
		(layer "In2.Cu")
		(net "M_D_DQS_DN<15>")
	)
	(arc
		(start 283.446474 -100.696268)
		(mid 283.516871 -100.985219)
		(end 283.437584 -101.271832)
		(width 0.0889)
		(layer "In2.Cu")
		(net "M_D_DQS_DN<15>")
	)
	(arc
		(start 283.443934 -101.68255)
		(mid 283.516732 -101.973313)
		(end 283.437584 -102.262432)
		(width 0.0889)
		(layer "In2.Cu")
		(net "M_D_DQS_DN<15>")
	)
	(arc
		(start 283.443934 -99.70135)
		(mid 283.516732 -99.992113)
		(end 283.437584 -100.281232)
		(width 0.0889)
		(layer "In2.Cu")
		(net "M_D_DQS_DN<15>")
	)
	(arc
		(start 283.437584 -98.700336)
		(mid 283.516806 -98.989454)
		(end 283.443934 -99.280218)
		(width 0.0889)
		(layer "In2.Cu")
		(net "M_D_DQS_DN<15>")
	)
	(arc
		(start 284.216094 -97.10674)
		(mid 284.330023 -97.735098)
		(end 283.805884 -98.100134)
		(width 0.0889)
		(layer "In2.Cu")
		(net "M_D_DQS_DN<15>")
	)
	(arc
		(start 283.437584 -102.262432)
		(mid 283.383958 -102.462584)
		(end 283.437584 -102.662736)
		(width 0.0889)
		(layer "In2.Cu")
		(net "M_D_DQS_DN<15>")
	)
	(arc
		(start 283.432758 -98.308922)
		(mid 283.384003 -98.505274)
		(end 283.437584 -98.700336)
		(width 0.0889)
		(layer "In2.Cu")
		(net "M_D_DQS_DN<15>")
	)
	(arc
		(start 283.437584 -100.281232)
		(mid 283.384146 -100.474137)
		(end 283.430726 -100.668836)
		(width 0.0889)
		(layer "In2.Cu")
		(net "M_D_DQS_DN<15>")
	)
	(segment
		(start 292.607492 -135.25373)
		(end 292.418262 -135.0645)
		(width 0.1651)
		(layer "F.Cu")
		(net "M_D_DQS_DN<14>")
	)
	(segment
		(start 293.06774 -135.001762)
		(end 292.815772 -135.25373)
		(width 0.1651)
		(layer "F.Cu")
		(net "M_D_DQS_DN<14>")
	)
	(segment
		(start 292.881812 -134.5692)
		(end 293.06774 -134.755128)
		(width 0.1651)
		(layer "F.Cu")
		(net "M_D_DQS_DN<14>")
	)
	(segment
		(start 293.299896 -133.729984)
		(end 292.881812 -134.148068)
		(width 0.1651)
		(layer "F.Cu")
		(net "M_D_DQS_DN<14>")
	)
	(segment
		(start 292.881812 -134.148068)
		(end 292.881812 -134.5692)
		(width 0.1651)
		(layer "F.Cu")
		(net "M_D_DQS_DN<14>")
	)
	(segment
		(start 278.061674 -97.509584)
		(end 278.633174 -97.509584)
		(width 0.1651)
		(layer "F.Cu")
		(net "M_D_DQS_DN<14>")
	)
	(segment
		(start 292.418262 -135.0645)
		(end 292.399212 -135.0645)
		(width 0.1651)
		(layer "F.Cu")
		(net "M_D_DQS_DN<14>")
	)
	(segment
		(start 293.300404 -133.0706)
		(end 293.299896 -133.076442)
		(width 0.1651)
		(layer "F.Cu")
		(net "M_D_DQS_DN<14>")
	)
	(segment
		(start 293.06774 -134.755128)
		(end 293.06774 -135.001762)
		(width 0.1651)
		(layer "F.Cu")
		(net "M_D_DQS_DN<14>")
	)
	(segment
		(start 292.815772 -135.25373)
		(end 292.607492 -135.25373)
		(width 0.1651)
		(layer "F.Cu")
		(net "M_D_DQS_DN<14>")
	)
	(segment
		(start 293.299896 -133.076442)
		(end 293.299896 -133.729984)
		(width 0.1651)
		(layer "F.Cu")
		(net "M_D_DQS_DN<14>")
	)
	(via
		(at 292.392608 -130.8862)
		(size 0.508)
		(drill 0.254)
		(layers "F.Cu" "B.Cu")
		(net "M_D_DQS_DN<14>")
	)
	(via
		(at 292.399212 -135.0645)
		(size 0.508)
		(drill 0.254)
		(layers "F.Cu" "B.Cu")
		(net "M_D_DQS_DN<14>")
	)
	(via
		(at 278.633174 -97.509584)
		(size 0.508)
		(drill 0.254)
		(layers "F.Cu" "B.Cu")
		(net "M_D_DQS_DN<14>")
	)
	(segment
		(start 292.392608 -130.8862)
		(end 292.587172 -130.691636)
		(width 0.1651)
		(layer "B.Cu")
		(net "M_D_DQS_DN<14>")
	)
	(segment
		(start 292.814248 -130.691636)
		(end 293.034212 -130.9116)
		(width 0.1651)
		(layer "B.Cu")
		(net "M_D_DQS_DN<14>")
	)
	(segment
		(start 293.034212 -131.2418)
		(end 292.856412 -131.4196)
		(width 0.1651)
		(layer "B.Cu")
		(net "M_D_DQS_DN<14>")
	)
	(segment
		(start 293.30015 -132.219192)
		(end 293.30015 -132.875528)
		(width 0.1651)
		(layer "B.Cu")
		(net "M_D_DQS_DN<14>")
	)
	(segment
		(start 293.034212 -130.9116)
		(end 293.034212 -131.2418)
		(width 0.1651)
		(layer "B.Cu")
		(net "M_D_DQS_DN<14>")
	)
	(segment
		(start 292.856412 -131.775454)
		(end 293.30015 -132.219192)
		(width 0.1651)
		(layer "B.Cu")
		(net "M_D_DQS_DN<14>")
	)
	(segment
		(start 293.30015 -132.875528)
		(end 293.300404 -132.876036)
		(width 0.1651)
		(layer "B.Cu")
		(net "M_D_DQS_DN<14>")
	)
	(segment
		(start 292.856412 -131.4196)
		(end 292.856412 -131.775454)
		(width 0.1651)
		(layer "B.Cu")
		(net "M_D_DQS_DN<14>")
	)
	(segment
		(start 292.587172 -130.691636)
		(end 292.814248 -130.691636)
		(width 0.1651)
		(layer "B.Cu")
		(net "M_D_DQS_DN<14>")
	)
	(segment
		(start 274.906994 -106.219498)
		(end 274.906994 -115.437666)
		(width 0.14224)
		(layer "In2.Cu")
		(net "M_D_DQS_DN<14>")
	)
	(segment
		(start 277.148036 -101.261164)
		(end 276.51583 -102.35692)
		(width 0.0889)
		(layer "In2.Cu")
		(net "M_D_DQS_DN<14>")
	)
	(segment
		(start 292.306756 -132.0038)
		(end 292.156896 -132.15366)
		(width 0.14224)
		(layer "In2.Cu")
		(net "M_D_DQS_DN<14>")
	)
	(segment
		(start 278.292814 -98.289618)
		(end 278.286464 -98.300286)
		(width 0.0889)
		(layer "In2.Cu")
		(net "M_D_DQS_DN<14>")
	)
	(segment
		(start 292.156896 -133.79704)
		(end 292.319456 -133.9596)
		(width 0.14224)
		(layer "In2.Cu")
		(net "M_D_DQS_DN<14>")
	)
	(segment
		(start 292.443916 -133.29666)
		(end 292.296596 -133.29666)
		(width 0.14224)
		(layer "In2.Cu")
		(net "M_D_DQS_DN<14>")
	)
	(segment
		(start 277.796244 -100.57638)
		(end 277.75662 -100.57638)
		(width 0.0889)
		(layer "In2.Cu")
		(net "M_D_DQS_DN<14>")
	)
	(segment
		(start 278.286464 -98.300286)
		(end 278.281638 -98.308922)
		(width 0.0889)
		(layer "In2.Cu")
		(net "M_D_DQS_DN<14>")
	)
	(segment
		(start 292.156896 -132.15366)
		(end 292.156896 -132.50164)
		(width 0.14224)
		(layer "In2.Cu")
		(net "M_D_DQS_DN<14>")
	)
	(segment
		(start 278.724106 -97.509584)
		(end 278.898858 -97.334832)
		(width 0.0889)
		(layer "In2.Cu")
		(net "M_D_DQS_DN<14>")
	)
	(segment
		(start 278.898858 -97.334832)
		(end 278.898858 -97.209102)
		(width 0.0889)
		(layer "In2.Cu")
		(net "M_D_DQS_DN<14>")
	)
	(segment
		(start 292.598856 -133.14172)
		(end 292.443916 -133.29666)
		(width 0.14224)
		(layer "In2.Cu")
		(net "M_D_DQS_DN<14>")
	)
	(segment
		(start 276.51583 -103.431848)
		(end 274.867624 -105.080054)
		(width 0.0889)
		(layer "In2.Cu")
		(net "M_D_DQS_DN<14>")
	)
	(segment
		(start 274.867624 -105.080054)
		(end 274.867624 -106.15803)
		(width 0.0889)
		(layer "In2.Cu")
		(net "M_D_DQS_DN<14>")
	)
	(segment
		(start 278.286464 -99.290886)
		(end 278.281638 -99.299522)
		(width 0.0889)
		(layer "In2.Cu")
		(net "M_D_DQS_DN<14>")
	)
	(segment
		(start 292.598856 -132.78866)
		(end 292.598856 -133.14172)
		(width 0.14224)
		(layer "In2.Cu")
		(net "M_D_DQS_DN<14>")
	)
	(segment
		(start 292.296596 -133.29666)
		(end 292.156896 -133.43636)
		(width 0.14224)
		(layer "In2.Cu")
		(net "M_D_DQS_DN<14>")
	)
	(segment
		(start 288.13252 -126.695454)
		(end 288.586672 -127.149606)
		(width 0.14224)
		(layer "In2.Cu")
		(net "M_D_DQS_DN<14>")
	)
	(segment
		(start 276.51583 -102.35692)
		(end 276.51583 -103.431848)
		(width 0.0889)
		(layer "In2.Cu")
		(net "M_D_DQS_DN<14>")
	)
	(segment
		(start 284.343856 -124.874528)
		(end 287.046162 -124.874528)
		(width 0.14224)
		(layer "In2.Cu")
		(net "M_D_DQS_DN<14>")
	)
	(segment
		(start 292.832282 -134.147306)
		(end 292.832282 -134.63143)
		(width 0.14224)
		(layer "In2.Cu")
		(net "M_D_DQS_DN<14>")
	)
	(segment
		(start 292.548056 -132.0038)
		(end 292.306756 -132.0038)
		(width 0.14224)
		(layer "In2.Cu")
		(net "M_D_DQS_DN<14>")
	)
	(segment
		(start 274.906994 -106.1974)
		(end 274.906994 -106.219498)
		(width 0.0889)
		(layer "In2.Cu")
		(net "M_D_DQS_DN<14>")
	)
	(segment
		(start 278.898858 -97.209102)
		(end 278.79421 -97.104454)
		(width 0.0889)
		(layer "In2.Cu")
		(net "M_D_DQS_DN<14>")
	)
	(segment
		(start 292.156896 -133.43636)
		(end 292.156896 -133.79704)
		(width 0.14224)
		(layer "In2.Cu")
		(net "M_D_DQS_DN<14>")
	)
	(segment
		(start 274.867624 -106.15803)
		(end 274.906994 -106.1974)
		(width 0.0889)
		(layer "In2.Cu")
		(net "M_D_DQS_DN<14>")
	)
	(segment
		(start 292.36924 -127.149606)
		(end 293.174928 -127.955294)
		(width 0.14224)
		(layer "In2.Cu")
		(net "M_D_DQS_DN<14>")
	)
	(segment
		(start 292.392608 -130.8862)
		(end 292.827456 -131.321048)
		(width 0.14224)
		(layer "In2.Cu")
		(net "M_D_DQS_DN<14>")
	)
	(segment
		(start 278.633174 -97.509584)
		(end 278.724106 -97.509584)
		(width 0.0889)
		(layer "In2.Cu")
		(net "M_D_DQS_DN<14>")
	)
	(segment
		(start 292.443916 -132.63372)
		(end 292.598856 -132.78866)
		(width 0.14224)
		(layer "In2.Cu")
		(net "M_D_DQS_DN<14>")
	)
	(segment
		(start 288.586672 -127.149606)
		(end 292.36924 -127.149606)
		(width 0.14224)
		(layer "In2.Cu")
		(net "M_D_DQS_DN<14>")
	)
	(segment
		(start 274.906994 -115.437666)
		(end 284.343856 -124.874528)
		(width 0.14224)
		(layer "In2.Cu")
		(net "M_D_DQS_DN<14>")
	)
	(segment
		(start 292.827456 -131.321048)
		(end 292.827456 -131.7244)
		(width 0.14224)
		(layer "In2.Cu")
		(net "M_D_DQS_DN<14>")
	)
	(segment
		(start 293.174928 -130.10388)
		(end 292.392608 -130.8862)
		(width 0.14224)
		(layer "In2.Cu")
		(net "M_D_DQS_DN<14>")
	)
	(segment
		(start 278.79421 -97.104454)
		(end 278.584406 -97.104454)
		(width 0.0889)
		(layer "In2.Cu")
		(net "M_D_DQS_DN<14>")
	)
	(segment
		(start 292.319456 -133.9596)
		(end 292.644576 -133.9596)
		(width 0.14224)
		(layer "In2.Cu")
		(net "M_D_DQS_DN<14>")
	)
	(segment
		(start 292.832282 -134.63143)
		(end 292.399212 -135.0645)
		(width 0.14224)
		(layer "In2.Cu")
		(net "M_D_DQS_DN<14>")
	)
	(segment
		(start 293.174928 -127.955294)
		(end 293.174928 -130.10388)
		(width 0.14224)
		(layer "In2.Cu")
		(net "M_D_DQS_DN<14>")
	)
	(segment
		(start 292.827456 -131.7244)
		(end 292.548056 -132.0038)
		(width 0.14224)
		(layer "In2.Cu")
		(net "M_D_DQS_DN<14>")
	)
	(segment
		(start 278.292814 -99.280218)
		(end 278.286464 -99.290886)
		(width 0.0889)
		(layer "In2.Cu")
		(net "M_D_DQS_DN<14>")
	)
	(segment
		(start 278.584406 -97.104454)
		(end 278.575262 -97.113598)
		(width 0.0889)
		(layer "In2.Cu")
		(net "M_D_DQS_DN<14>")
	)
	(segment
		(start 292.288976 -132.63372)
		(end 292.443916 -132.63372)
		(width 0.14224)
		(layer "In2.Cu")
		(net "M_D_DQS_DN<14>")
	)
	(segment
		(start 277.427944 -100.776278)
		(end 277.148036 -101.261164)
		(width 0.0889)
		(layer "In2.Cu")
		(net "M_D_DQS_DN<14>")
	)
	(segment
		(start 292.156896 -132.50164)
		(end 292.288976 -132.63372)
		(width 0.14224)
		(layer "In2.Cu")
		(net "M_D_DQS_DN<14>")
	)
	(segment
		(start 287.046162 -124.874528)
		(end 288.13252 -125.960886)
		(width 0.14224)
		(layer "In2.Cu")
		(net "M_D_DQS_DN<14>")
	)
	(segment
		(start 292.644576 -133.9596)
		(end 292.832282 -134.147306)
		(width 0.14224)
		(layer "In2.Cu")
		(net "M_D_DQS_DN<14>")
	)
	(segment
		(start 288.13252 -125.960886)
		(end 288.13252 -126.695454)
		(width 0.14224)
		(layer "In2.Cu")
		(net "M_D_DQS_DN<14>")
	)
	(arc
		(start 278.286464 -99.690936)
		(mid 278.289573 -99.696183)
		(end 278.292814 -99.70135)
		(width 0.0889)
		(layer "In2.Cu")
		(net "M_D_DQS_DN<14>")
	)
	(arc
		(start 278.281638 -98.308922)
		(mid 278.232883 -98.505274)
		(end 278.286464 -98.700336)
		(width 0.0889)
		(layer "In2.Cu")
		(net "M_D_DQS_DN<14>")
	)
	(arc
		(start 278.575262 -97.113598)
		(mid 278.552138 -97.117628)
		(end 278.529288 -97.122996)
		(width 0.0889)
		(layer "In2.Cu")
		(net "M_D_DQS_DN<14>")
	)
	(arc
		(start 278.286464 -98.700336)
		(mid 278.365686 -98.989454)
		(end 278.292814 -99.280218)
		(width 0.0889)
		(layer "In2.Cu")
		(net "M_D_DQS_DN<14>")
	)
	(arc
		(start 278.529288 -97.122996)
		(mid 278.26312 -97.356491)
		(end 278.286464 -97.709736)
		(width 0.0889)
		(layer "In2.Cu")
		(net "M_D_DQS_DN<14>")
	)
	(arc
		(start 278.286464 -97.709736)
		(mid 278.365686 -97.998854)
		(end 278.292814 -98.289618)
		(width 0.0889)
		(layer "In2.Cu")
		(net "M_D_DQS_DN<14>")
	)
	(arc
		(start 278.292814 -99.70135)
		(mid 278.288783 -100.277532)
		(end 277.796244 -100.57638)
		(width 0.0889)
		(layer "In2.Cu")
		(net "M_D_DQS_DN<14>")
	)
	(arc
		(start 277.75662 -100.57638)
		(mid 277.566691 -100.63425)
		(end 277.427944 -100.776278)
		(width 0.0889)
		(layer "In2.Cu")
		(net "M_D_DQS_DN<14>")
	)
	(arc
		(start 278.281638 -99.299522)
		(mid 278.232883 -99.495874)
		(end 278.286464 -99.690936)
		(width 0.0889)
		(layer "In2.Cu")
		(net "M_D_DQS_DN<14>")
	)
	(segment
		(start 274.365974 -112.847374)
		(end 274.574 -113.0554)
		(width 0.1016)
		(layer "F.Cu")
		(net "M_D_DQS_DN<13>")
	)
	(segment
		(start 283.949902 -133.72973)
		(end 283.531564 -134.148068)
		(width 0.1651)
		(layer "F.Cu")
		(net "M_D_DQS_DN<13>")
	)
	(segment
		(start 283.068014 -135.0645)
		(end 283.048964 -135.0645)
		(width 0.1651)
		(layer "F.Cu")
		(net "M_D_DQS_DN<13>")
	)
	(segment
		(start 283.95041 -133.0706)
		(end 283.949902 -133.076442)
		(width 0.1651)
		(layer "F.Cu")
		(net "M_D_DQS_DN<13>")
	)
	(segment
		(start 276.44598 -119.358156)
		(end 284.0736 -126.985776)
		(width 0.1651)
		(layer "F.Cu")
		(net "M_D_DQS_DN<13>")
	)
	(segment
		(start 275.093684 -102.928166)
		(end 275.093684 -104.397302)
		(width 0.0889)
		(layer "F.Cu")
		(net "M_D_DQS_DN<13>")
	)
	(segment
		(start 275.486114 -100.645214)
		(end 275.422614 -100.581714)
		(width 0.0889)
		(layer "F.Cu")
		(net "M_D_DQS_DN<13>")
	)
	(segment
		(start 275.139404 -102.757986)
		(end 275.13915 -102.75824)
		(width 0.0889)
		(layer "F.Cu")
		(net "M_D_DQS_DN<13>")
	)
	(segment
		(start 284.0736 -128.4732)
		(end 284.0736 -129.877312)
		(width 0.1651)
		(layer "F.Cu")
		(net "M_D_DQS_DN<13>")
	)
	(segment
		(start 283.531564 -134.148068)
		(end 283.531564 -134.5692)
		(width 0.1651)
		(layer "F.Cu")
		(net "M_D_DQS_DN<13>")
	)
	(segment
		(start 283.717492 -135.001762)
		(end 283.465524 -135.25373)
		(width 0.1651)
		(layer "F.Cu")
		(net "M_D_DQS_DN<13>")
	)
	(segment
		(start 275.134578 -102.1588)
		(end 275.134578 -102.158038)
		(width 0.0889)
		(layer "F.Cu")
		(net "M_D_DQS_DN<13>")
	)
	(segment
		(start 274.574 -113.7666)
		(end 274.5232 -113.8174)
		(width 0.1016)
		(layer "F.Cu")
		(net "M_D_DQS_DN<13>")
	)
	(segment
		(start 284.0736 -129.877312)
		(end 283.064712 -130.8862)
		(width 0.1651)
		(layer "F.Cu")
		(net "M_D_DQS_DN<13>")
	)
	(segment
		(start 283.531564 -134.5692)
		(end 283.717492 -134.755128)
		(width 0.1651)
		(layer "F.Cu")
		(net "M_D_DQS_DN<13>")
	)
	(segment
		(start 284.0736 -127.508)
		(end 283.8831 -127.6985)
		(width 0.1651)
		(layer "F.Cu")
		(net "M_D_DQS_DN<13>")
	)
	(segment
		(start 274.5232 -113.8174)
		(end 274.5232 -114.2238)
		(width 0.1651)
		(layer "F.Cu")
		(net "M_D_DQS_DN<13>")
	)
	(segment
		(start 283.257244 -135.25373)
		(end 283.068014 -135.0645)
		(width 0.1651)
		(layer "F.Cu")
		(net "M_D_DQS_DN<13>")
	)
	(segment
		(start 274.574 -113.0554)
		(end 274.574 -113.7666)
		(width 0.1016)
		(layer "F.Cu")
		(net "M_D_DQS_DN<13>")
	)
	(segment
		(start 274.365974 -106.573574)
		(end 274.365974 -112.847374)
		(width 0.1016)
		(layer "F.Cu")
		(net "M_D_DQS_DN<13>")
	)
	(segment
		(start 283.717492 -134.755128)
		(end 283.717492 -135.001762)
		(width 0.1651)
		(layer "F.Cu")
		(net "M_D_DQS_DN<13>")
	)
	(segment
		(start 283.8831 -128.2827)
		(end 284.0736 -128.4732)
		(width 0.1651)
		(layer "F.Cu")
		(net "M_D_DQS_DN<13>")
	)
	(segment
		(start 274.264374 -105.226612)
		(end 274.264374 -106.471974)
		(width 0.0889)
		(layer "F.Cu")
		(net "M_D_DQS_DN<13>")
	)
	(segment
		(start 283.465524 -135.25373)
		(end 283.257244 -135.25373)
		(width 0.1651)
		(layer "F.Cu")
		(net "M_D_DQS_DN<13>")
	)
	(segment
		(start 274.5232 -114.2238)
		(end 276.44598 -116.14658)
		(width 0.1651)
		(layer "F.Cu")
		(net "M_D_DQS_DN<13>")
	)
	(segment
		(start 275.486114 -100.976684)
		(end 275.486114 -100.645214)
		(width 0.0889)
		(layer "F.Cu")
		(net "M_D_DQS_DN<13>")
	)
	(segment
		(start 274.264374 -106.471974)
		(end 274.365974 -106.573574)
		(width 0.0889)
		(layer "F.Cu")
		(net "M_D_DQS_DN<13>")
	)
	(segment
		(start 283.949902 -133.076442)
		(end 283.949902 -133.72973)
		(width 0.1651)
		(layer "F.Cu")
		(net "M_D_DQS_DN<13>")
	)
	(segment
		(start 275.134578 -102.158038)
		(end 275.146008 -102.17912)
		(width 0.0889)
		(layer "F.Cu")
		(net "M_D_DQS_DN<13>")
	)
	(segment
		(start 275.093684 -104.397302)
		(end 274.264374 -105.226612)
		(width 0.0889)
		(layer "F.Cu")
		(net "M_D_DQS_DN<13>")
	)
	(segment
		(start 283.064712 -130.8862)
		(end 283.04236 -130.8862)
		(width 0.1651)
		(layer "F.Cu")
		(net "M_D_DQS_DN<13>")
	)
	(segment
		(start 284.0736 -126.985776)
		(end 284.0736 -127.508)
		(width 0.1651)
		(layer "F.Cu")
		(net "M_D_DQS_DN<13>")
	)
	(segment
		(start 276.44598 -116.14658)
		(end 276.44598 -119.358156)
		(width 0.1651)
		(layer "F.Cu")
		(net "M_D_DQS_DN<13>")
	)
	(segment
		(start 283.8831 -127.6985)
		(end 283.8831 -128.2827)
		(width 0.1651)
		(layer "F.Cu")
		(net "M_D_DQS_DN<13>")
	)
	(via
		(at 283.048964 -135.0645)
		(size 0.508)
		(drill 0.254)
		(layers "F.Cu" "B.Cu")
		(net "M_D_DQS_DN<13>")
	)
	(via
		(at 283.04236 -130.8862)
		(size 0.508)
		(drill 0.254)
		(layers "F.Cu" "B.Cu")
		(net "M_D_DQS_DN<13>")
	)
	(arc
		(start 275.422614 -100.581714)
		(mid 275.124893 -100.804774)
		(end 275.139404 -101.176582)
		(width 0.0889)
		(layer "F.Cu")
		(net "M_D_DQS_DN<13>")
	)
	(arc
		(start 275.139404 -101.767386)
		(mid 275.085934 -101.962449)
		(end 275.134578 -102.1588)
		(width 0.0889)
		(layer "F.Cu")
		(net "M_D_DQS_DN<13>")
	)
	(arc
		(start 275.146008 -102.17912)
		(mid 275.218406 -102.469405)
		(end 275.139404 -102.757986)
		(width 0.0889)
		(layer "F.Cu")
		(net "M_D_DQS_DN<13>")
	)
	(arc
		(start 275.139404 -101.176582)
		(mid 275.218535 -101.471984)
		(end 275.139404 -101.767386)
		(width 0.0889)
		(layer "F.Cu")
		(net "M_D_DQS_DN<13>")
	)
	(arc
		(start 275.13915 -102.75824)
		(mid 275.105255 -102.840216)
		(end 275.093684 -102.928166)
		(width 0.0889)
		(layer "F.Cu")
		(net "M_D_DQS_DN<13>")
	)
	(segment
		(start 283.683964 -130.9116)
		(end 283.464 -130.691636)
		(width 0.1651)
		(layer "B.Cu")
		(net "M_D_DQS_DN<13>")
	)
	(segment
		(start 283.683964 -131.2418)
		(end 283.683964 -130.9116)
		(width 0.1651)
		(layer "B.Cu")
		(net "M_D_DQS_DN<13>")
	)
	(segment
		(start 283.95041 -132.876036)
		(end 283.949902 -132.875782)
		(width 0.1651)
		(layer "B.Cu")
		(net "M_D_DQS_DN<13>")
	)
	(segment
		(start 283.464 -130.691636)
		(end 283.236924 -130.691636)
		(width 0.1651)
		(layer "B.Cu")
		(net "M_D_DQS_DN<13>")
	)
	(segment
		(start 283.236924 -130.691636)
		(end 283.04236 -130.8862)
		(width 0.1651)
		(layer "B.Cu")
		(net "M_D_DQS_DN<13>")
	)
	(segment
		(start 283.506164 -131.775454)
		(end 283.506164 -131.4196)
		(width 0.1651)
		(layer "B.Cu")
		(net "M_D_DQS_DN<13>")
	)
	(segment
		(start 283.949902 -132.219192)
		(end 283.506164 -131.775454)
		(width 0.1651)
		(layer "B.Cu")
		(net "M_D_DQS_DN<13>")
	)
	(segment
		(start 283.506164 -131.4196)
		(end 283.683964 -131.2418)
		(width 0.1651)
		(layer "B.Cu")
		(net "M_D_DQS_DN<13>")
	)
	(segment
		(start 283.949902 -132.875782)
		(end 283.949902 -132.219192)
		(width 0.1651)
		(layer "B.Cu")
		(net "M_D_DQS_DN<13>")
	)
	(segment
		(start 282.806902 -132.50164)
		(end 282.806902 -132.15366)
		(width 0.14224)
		(layer "In2.Cu")
		(net "M_D_DQS_DN<13>")
	)
	(segment
		(start 282.806902 -133.43636)
		(end 282.946602 -133.29666)
		(width 0.14224)
		(layer "In2.Cu")
		(net "M_D_DQS_DN<13>")
	)
	(segment
		(start 283.198062 -132.0038)
		(end 283.477462 -131.7244)
		(width 0.14224)
		(layer "In2.Cu")
		(net "M_D_DQS_DN<13>")
	)
	(segment
		(start 283.248862 -132.78866)
		(end 283.093922 -132.63372)
		(width 0.14224)
		(layer "In2.Cu")
		(net "M_D_DQS_DN<13>")
	)
	(segment
		(start 283.248862 -133.14172)
		(end 283.248862 -132.78866)
		(width 0.14224)
		(layer "In2.Cu")
		(net "M_D_DQS_DN<13>")
	)
	(segment
		(start 282.806902 -132.15366)
		(end 282.956762 -132.0038)
		(width 0.14224)
		(layer "In2.Cu")
		(net "M_D_DQS_DN<13>")
	)
	(segment
		(start 283.093922 -132.63372)
		(end 282.938982 -132.63372)
		(width 0.14224)
		(layer "In2.Cu")
		(net "M_D_DQS_DN<13>")
	)
	(segment
		(start 282.938982 -132.63372)
		(end 282.806902 -132.50164)
		(width 0.14224)
		(layer "In2.Cu")
		(net "M_D_DQS_DN<13>")
	)
	(segment
		(start 283.294582 -133.9596)
		(end 282.969462 -133.9596)
		(width 0.14224)
		(layer "In2.Cu")
		(net "M_D_DQS_DN<13>")
	)
	(segment
		(start 282.946602 -133.29666)
		(end 283.093922 -133.29666)
		(width 0.14224)
		(layer "In2.Cu")
		(net "M_D_DQS_DN<13>")
	)
	(segment
		(start 283.048964 -135.0645)
		(end 283.049218 -135.0645)
		(width 0.14224)
		(layer "In2.Cu")
		(net "M_D_DQS_DN<13>")
	)
	(segment
		(start 282.806902 -133.79704)
		(end 282.806902 -133.43636)
		(width 0.14224)
		(layer "In2.Cu")
		(net "M_D_DQS_DN<13>")
	)
	(segment
		(start 282.969462 -133.9596)
		(end 282.806902 -133.79704)
		(width 0.14224)
		(layer "In2.Cu")
		(net "M_D_DQS_DN<13>")
	)
	(segment
		(start 283.477462 -131.321302)
		(end 283.04236 -130.8862)
		(width 0.14224)
		(layer "In2.Cu")
		(net "M_D_DQS_DN<13>")
	)
	(segment
		(start 283.477462 -131.7244)
		(end 283.477462 -131.321302)
		(width 0.14224)
		(layer "In2.Cu")
		(net "M_D_DQS_DN<13>")
	)
	(segment
		(start 283.482288 -134.63143)
		(end 283.482288 -134.147306)
		(width 0.14224)
		(layer "In2.Cu")
		(net "M_D_DQS_DN<13>")
	)
	(segment
		(start 283.482288 -134.147306)
		(end 283.294582 -133.9596)
		(width 0.14224)
		(layer "In2.Cu")
		(net "M_D_DQS_DN<13>")
	)
	(segment
		(start 283.049218 -135.0645)
		(end 283.482288 -134.63143)
		(width 0.14224)
		(layer "In2.Cu")
		(net "M_D_DQS_DN<13>")
	)
	(segment
		(start 282.956762 -132.0038)
		(end 283.198062 -132.0038)
		(width 0.14224)
		(layer "In2.Cu")
		(net "M_D_DQS_DN<13>")
	)
	(segment
		(start 283.093922 -133.29666)
		(end 283.248862 -133.14172)
		(width 0.14224)
		(layer "In2.Cu")
		(net "M_D_DQS_DN<13>")
	)
	(segment
		(start 228.215698 -135.25373)
		(end 228.007418 -135.25373)
		(width 0.1651)
		(layer "F.Cu")
		(net "M_D_DQS_DN<12>")
	)
	(segment
		(start 227.818188 -135.0645)
		(end 227.799138 -135.0645)
		(width 0.1651)
		(layer "F.Cu")
		(net "M_D_DQS_DN<12>")
	)
	(segment
		(start 228.281738 -134.5692)
		(end 228.467666 -134.755128)
		(width 0.1651)
		(layer "F.Cu")
		(net "M_D_DQS_DN<12>")
	)
	(segment
		(start 228.467666 -134.755128)
		(end 228.467666 -135.001762)
		(width 0.1651)
		(layer "F.Cu")
		(net "M_D_DQS_DN<12>")
	)
	(segment
		(start 228.281738 -134.148068)
		(end 228.281738 -134.5692)
		(width 0.1651)
		(layer "F.Cu")
		(net "M_D_DQS_DN<12>")
	)
	(segment
		(start 228.70033 -133.0706)
		(end 228.699822 -133.076442)
		(width 0.1651)
		(layer "F.Cu")
		(net "M_D_DQS_DN<12>")
	)
	(segment
		(start 228.699822 -133.076442)
		(end 228.699822 -133.729984)
		(width 0.1651)
		(layer "F.Cu")
		(net "M_D_DQS_DN<12>")
	)
	(segment
		(start 228.007418 -135.25373)
		(end 227.818188 -135.0645)
		(width 0.1651)
		(layer "F.Cu")
		(net "M_D_DQS_DN<12>")
	)
	(segment
		(start 228.467666 -135.001762)
		(end 228.215698 -135.25373)
		(width 0.1651)
		(layer "F.Cu")
		(net "M_D_DQS_DN<12>")
	)
	(segment
		(start 242.193318 -95.709486)
		(end 241.621818 -95.709486)
		(width 0.1651)
		(layer "F.Cu")
		(net "M_D_DQS_DN<12>")
	)
	(segment
		(start 228.699822 -133.729984)
		(end 228.281738 -134.148068)
		(width 0.1651)
		(layer "F.Cu")
		(net "M_D_DQS_DN<12>")
	)
	(via
		(at 241.621818 -95.709486)
		(size 0.508)
		(drill 0.254)
		(layers "F.Cu" "B.Cu")
		(net "M_D_DQS_DN<12>")
	)
	(via
		(at 227.799138 -135.0645)
		(size 0.508)
		(drill 0.254)
		(layers "F.Cu" "B.Cu")
		(net "M_D_DQS_DN<12>")
	)
	(via
		(at 227.792534 -130.8862)
		(size 0.508)
		(drill 0.254)
		(layers "F.Cu" "B.Cu")
		(net "M_D_DQS_DN<12>")
	)
	(segment
		(start 228.70033 -132.876036)
		(end 228.700076 -132.875528)
		(width 0.1651)
		(layer "B.Cu")
		(net "M_D_DQS_DN<12>")
	)
	(segment
		(start 228.434138 -131.2418)
		(end 228.434138 -130.9116)
		(width 0.1651)
		(layer "B.Cu")
		(net "M_D_DQS_DN<12>")
	)
	(segment
		(start 228.700076 -132.219192)
		(end 228.256338 -131.775454)
		(width 0.1651)
		(layer "B.Cu")
		(net "M_D_DQS_DN<12>")
	)
	(segment
		(start 228.256338 -131.4196)
		(end 228.434138 -131.2418)
		(width 0.1651)
		(layer "B.Cu")
		(net "M_D_DQS_DN<12>")
	)
	(segment
		(start 228.214174 -130.691636)
		(end 227.987098 -130.691636)
		(width 0.1651)
		(layer "B.Cu")
		(net "M_D_DQS_DN<12>")
	)
	(segment
		(start 228.700076 -132.875528)
		(end 228.700076 -132.219192)
		(width 0.1651)
		(layer "B.Cu")
		(net "M_D_DQS_DN<12>")
	)
	(segment
		(start 228.434138 -130.9116)
		(end 228.214174 -130.691636)
		(width 0.1651)
		(layer "B.Cu")
		(net "M_D_DQS_DN<12>")
	)
	(segment
		(start 228.256338 -131.775454)
		(end 228.256338 -131.4196)
		(width 0.1651)
		(layer "B.Cu")
		(net "M_D_DQS_DN<12>")
	)
	(segment
		(start 227.987098 -130.691636)
		(end 227.792534 -130.8862)
		(width 0.1651)
		(layer "B.Cu")
		(net "M_D_DQS_DN<12>")
	)
	(segment
		(start 227.947982 -132.0038)
		(end 227.706682 -132.0038)
		(width 0.14224)
		(layer "In2.Cu")
		(net "M_D_DQS_DN<12>")
	)
	(segment
		(start 237.350808 -99.76739)
		(end 237.311184 -99.76739)
		(width 0.0889)
		(layer "In2.Cu")
		(net "M_D_DQS_DN<12>")
	)
	(segment
		(start 227.792534 -130.8862)
		(end 228.227382 -131.321048)
		(width 0.14224)
		(layer "In2.Cu")
		(net "M_D_DQS_DN<12>")
	)
	(segment
		(start 227.998782 -132.78866)
		(end 227.998782 -133.14172)
		(width 0.14224)
		(layer "In2.Cu")
		(net "M_D_DQS_DN<12>")
	)
	(segment
		(start 227.688902 -132.63372)
		(end 227.843842 -132.63372)
		(width 0.14224)
		(layer "In2.Cu")
		(net "M_D_DQS_DN<12>")
	)
	(segment
		(start 230.814626 -105.701592)
		(end 230.814626 -109.1057)
		(width 0.14224)
		(layer "In2.Cu")
		(net "M_D_DQS_DN<12>")
	)
	(segment
		(start 228.553264 -111.367062)
		(end 228.553264 -130.12547)
		(width 0.14224)
		(layer "In2.Cu")
		(net "M_D_DQS_DN<12>")
	)
	(segment
		(start 233.499152 -103.01732)
		(end 233.483658 -103.032814)
		(width 0.0889)
		(layer "In2.Cu")
		(net "M_D_DQS_DN<12>")
	)
	(segment
		(start 236.488478 -100.26269)
		(end 236.452664 -100.26269)
		(width 0.0889)
		(layer "In2.Cu")
		(net "M_D_DQS_DN<12>")
	)
	(segment
		(start 227.843842 -132.63372)
		(end 227.998782 -132.78866)
		(width 0.14224)
		(layer "In2.Cu")
		(net "M_D_DQS_DN<12>")
	)
	(segment
		(start 233.499152 -102.96144)
		(end 233.499152 -103.01732)
		(width 0.0889)
		(layer "In2.Cu")
		(net "M_D_DQS_DN<12>")
	)
	(segment
		(start 241.621818 -95.709486)
		(end 241.621818 -95.371412)
		(width 0.0889)
		(layer "In2.Cu")
		(net "M_D_DQS_DN<12>")
	)
	(segment
		(start 227.696522 -133.29666)
		(end 227.556822 -133.43636)
		(width 0.14224)
		(layer "In2.Cu")
		(net "M_D_DQS_DN<12>")
	)
	(segment
		(start 233.846624 -102.063296)
		(end 233.846624 -102.613968)
		(width 0.0889)
		(layer "In2.Cu")
		(net "M_D_DQS_DN<12>")
	)
	(segment
		(start 239.926368 -98.281236)
		(end 239.893602 -98.281236)
		(width 0.0889)
		(layer "In2.Cu")
		(net "M_D_DQS_DN<12>")
	)
	(segment
		(start 241.275108 -96.500188)
		(end 241.270282 -96.508824)
		(width 0.0889)
		(layer "In2.Cu")
		(net "M_D_DQS_DN<12>")
	)
	(segment
		(start 227.556822 -133.43636)
		(end 227.556822 -133.79704)
		(width 0.14224)
		(layer "In2.Cu")
		(net "M_D_DQS_DN<12>")
	)
	(segment
		(start 233.483658 -103.032814)
		(end 231.497632 -105.018586)
		(width 0.14224)
		(layer "In2.Cu")
		(net "M_D_DQS_DN<12>")
	)
	(segment
		(start 241.621818 -95.371412)
		(end 241.563906 -95.3135)
		(width 0.0889)
		(layer "In2.Cu")
		(net "M_D_DQS_DN<12>")
	)
	(segment
		(start 228.232208 -134.147306)
		(end 228.232208 -134.63143)
		(width 0.14224)
		(layer "In2.Cu")
		(net "M_D_DQS_DN<12>")
	)
	(segment
		(start 227.556822 -132.15366)
		(end 227.556822 -132.50164)
		(width 0.14224)
		(layer "In2.Cu")
		(net "M_D_DQS_DN<12>")
	)
	(segment
		(start 228.232208 -134.63143)
		(end 227.799138 -135.0645)
		(width 0.14224)
		(layer "In2.Cu")
		(net "M_D_DQS_DN<12>")
	)
	(segment
		(start 228.227382 -131.7244)
		(end 227.947982 -132.0038)
		(width 0.14224)
		(layer "In2.Cu")
		(net "M_D_DQS_DN<12>")
	)
	(segment
		(start 227.719382 -133.9596)
		(end 228.044502 -133.9596)
		(width 0.14224)
		(layer "In2.Cu")
		(net "M_D_DQS_DN<12>")
	)
	(segment
		(start 234.406948 -101.453188)
		(end 234.338368 -101.571552)
		(width 0.0889)
		(layer "In2.Cu")
		(net "M_D_DQS_DN<12>")
	)
	(segment
		(start 234.338368 -101.571552)
		(end 233.846624 -102.063296)
		(width 0.0889)
		(layer "In2.Cu")
		(net "M_D_DQS_DN<12>")
	)
	(segment
		(start 240.781078 -97.78619)
		(end 240.748312 -97.78619)
		(width 0.0889)
		(layer "In2.Cu")
		(net "M_D_DQS_DN<12>")
	)
	(segment
		(start 230.814626 -109.1057)
		(end 228.553264 -111.367062)
		(width 0.14224)
		(layer "In2.Cu")
		(net "M_D_DQS_DN<12>")
	)
	(segment
		(start 241.281458 -96.48952)
		(end 241.275108 -96.500188)
		(width 0.0889)
		(layer "In2.Cu")
		(net "M_D_DQS_DN<12>")
	)
	(segment
		(start 233.846624 -102.613968)
		(end 233.499152 -102.96144)
		(width 0.0889)
		(layer "In2.Cu")
		(net "M_D_DQS_DN<12>")
	)
	(segment
		(start 239.064038 -98.77679)
		(end 239.031272 -98.77679)
		(width 0.0889)
		(layer "In2.Cu")
		(net "M_D_DQS_DN<12>")
	)
	(segment
		(start 228.227382 -131.321048)
		(end 228.227382 -131.7244)
		(width 0.14224)
		(layer "In2.Cu")
		(net "M_D_DQS_DN<12>")
	)
	(segment
		(start 227.556822 -133.79704)
		(end 227.719382 -133.9596)
		(width 0.14224)
		(layer "In2.Cu")
		(net "M_D_DQS_DN<12>")
	)
	(segment
		(start 238.200692 -99.27209)
		(end 238.176562 -99.27209)
		(width 0.0889)
		(layer "In2.Cu")
		(net "M_D_DQS_DN<12>")
	)
	(segment
		(start 234.775248 -101.253036)
		(end 234.73918 -101.253036)
		(width 0.0889)
		(layer "In2.Cu")
		(net "M_D_DQS_DN<12>")
	)
	(segment
		(start 228.553264 -130.12547)
		(end 227.792534 -130.8862)
		(width 0.14224)
		(layer "In2.Cu")
		(net "M_D_DQS_DN<12>")
	)
	(segment
		(start 231.497632 -105.018586)
		(end 230.814626 -105.701592)
		(width 0.14224)
		(layer "In2.Cu")
		(net "M_D_DQS_DN<12>")
	)
	(segment
		(start 227.556822 -132.50164)
		(end 227.688902 -132.63372)
		(width 0.14224)
		(layer "In2.Cu")
		(net "M_D_DQS_DN<12>")
	)
	(segment
		(start 227.706682 -132.0038)
		(end 227.556822 -132.15366)
		(width 0.14224)
		(layer "In2.Cu")
		(net "M_D_DQS_DN<12>")
	)
	(segment
		(start 228.044502 -133.9596)
		(end 228.232208 -134.147306)
		(width 0.14224)
		(layer "In2.Cu")
		(net "M_D_DQS_DN<12>")
	)
	(segment
		(start 227.843842 -133.29666)
		(end 227.696522 -133.29666)
		(width 0.14224)
		(layer "In2.Cu")
		(net "M_D_DQS_DN<12>")
	)
	(segment
		(start 235.625132 -100.75799)
		(end 235.597192 -100.75799)
		(width 0.0889)
		(layer "In2.Cu")
		(net "M_D_DQS_DN<12>")
	)
	(segment
		(start 227.998782 -133.14172)
		(end 227.843842 -133.29666)
		(width 0.14224)
		(layer "In2.Cu")
		(net "M_D_DQS_DN<12>")
	)
	(arc
		(start 239.893602 -98.281236)
		(mid 239.699752 -98.337586)
		(end 239.558068 -98.481388)
		(width 0.0889)
		(layer "In2.Cu")
		(net "M_D_DQS_DN<12>")
	)
	(arc
		(start 237.841028 -99.472242)
		(mid 237.634024 -99.683106)
		(end 237.350808 -99.76739)
		(width 0.0889)
		(layer "In2.Cu")
		(net "M_D_DQS_DN<12>")
	)
	(arc
		(start 236.452664 -100.26269)
		(mid 236.262735 -100.32056)
		(end 236.123988 -100.462588)
		(width 0.0889)
		(layer "In2.Cu")
		(net "M_D_DQS_DN<12>")
	)
	(arc
		(start 241.270282 -96.508824)
		(mid 241.221527 -96.705176)
		(end 241.275108 -96.900238)
		(width 0.0889)
		(layer "In2.Cu")
		(net "M_D_DQS_DN<12>")
	)
	(arc
		(start 240.416588 -97.986088)
		(mid 240.209584 -98.196952)
		(end 239.926368 -98.281236)
		(width 0.0889)
		(layer "In2.Cu")
		(net "M_D_DQS_DN<12>")
	)
	(arc
		(start 234.73918 -101.253036)
		(mid 234.547163 -101.310144)
		(end 234.406948 -101.453188)
		(width 0.0889)
		(layer "In2.Cu")
		(net "M_D_DQS_DN<12>")
	)
	(arc
		(start 239.558068 -98.481388)
		(mid 239.34946 -98.69332)
		(end 239.064038 -98.77679)
		(width 0.0889)
		(layer "In2.Cu")
		(net "M_D_DQS_DN<12>")
	)
	(arc
		(start 241.275108 -96.900238)
		(mid 241.279437 -97.48341)
		(end 240.781078 -97.78619)
		(width 0.0889)
		(layer "In2.Cu")
		(net "M_D_DQS_DN<12>")
	)
	(arc
		(start 238.176562 -99.27209)
		(mid 237.982712 -99.32844)
		(end 237.841028 -99.472242)
		(width 0.0889)
		(layer "In2.Cu")
		(net "M_D_DQS_DN<12>")
	)
	(arc
		(start 239.031272 -98.77679)
		(mid 238.83963 -98.833956)
		(end 238.699548 -98.976688)
		(width 0.0889)
		(layer "In2.Cu")
		(net "M_D_DQS_DN<12>")
	)
	(arc
		(start 240.748312 -97.78619)
		(mid 240.55667 -97.843356)
		(end 240.416588 -97.986088)
		(width 0.0889)
		(layer "In2.Cu")
		(net "M_D_DQS_DN<12>")
	)
	(arc
		(start 241.275108 -95.909638)
		(mid 241.35433 -96.198756)
		(end 241.281458 -96.48952)
		(width 0.0889)
		(layer "In2.Cu")
		(net "M_D_DQS_DN<12>")
	)
	(arc
		(start 235.597192 -100.75799)
		(mid 235.40555 -100.815156)
		(end 235.265468 -100.957888)
		(width 0.0889)
		(layer "In2.Cu")
		(net "M_D_DQS_DN<12>")
	)
	(arc
		(start 236.123988 -100.462588)
		(mid 235.913275 -100.675667)
		(end 235.625132 -100.75799)
		(width 0.0889)
		(layer "In2.Cu")
		(net "M_D_DQS_DN<12>")
	)
	(arc
		(start 238.699548 -98.976688)
		(mid 238.488835 -99.189767)
		(end 238.200692 -99.27209)
		(width 0.0889)
		(layer "In2.Cu")
		(net "M_D_DQS_DN<12>")
	)
	(arc
		(start 235.265468 -100.957888)
		(mid 235.058464 -101.168752)
		(end 234.775248 -101.253036)
		(width 0.0889)
		(layer "In2.Cu")
		(net "M_D_DQS_DN<12>")
	)
	(arc
		(start 236.982508 -99.967288)
		(mid 236.7739 -100.17922)
		(end 236.488478 -100.26269)
		(width 0.0889)
		(layer "In2.Cu")
		(net "M_D_DQS_DN<12>")
	)
	(arc
		(start 237.311184 -99.76739)
		(mid 237.121255 -99.82526)
		(end 236.982508 -99.967288)
		(width 0.0889)
		(layer "In2.Cu")
		(net "M_D_DQS_DN<12>")
	)
	(arc
		(start 241.563906 -95.3135)
		(mid 241.261637 -95.535049)
		(end 241.275108 -95.909638)
		(width 0.0889)
		(layer "In2.Cu")
		(net "M_D_DQS_DN<12>")
	)
	(segment
		(start 219.117672 -135.001762)
		(end 218.865704 -135.25373)
		(width 0.1651)
		(layer "F.Cu")
		(net "M_D_DQS_DN<11>")
	)
	(segment
		(start 218.468194 -135.0645)
		(end 218.449144 -135.0645)
		(width 0.1651)
		(layer "F.Cu")
		(net "M_D_DQS_DN<11>")
	)
	(segment
		(start 218.931744 -134.148068)
		(end 218.931744 -134.5692)
		(width 0.1651)
		(layer "F.Cu")
		(net "M_D_DQS_DN<11>")
	)
	(segment
		(start 218.931744 -134.5692)
		(end 219.117672 -134.755128)
		(width 0.1651)
		(layer "F.Cu")
		(net "M_D_DQS_DN<11>")
	)
	(segment
		(start 218.657424 -135.25373)
		(end 218.468194 -135.0645)
		(width 0.1651)
		(layer "F.Cu")
		(net "M_D_DQS_DN<11>")
	)
	(segment
		(start 219.349828 -133.729984)
		(end 218.931744 -134.148068)
		(width 0.1651)
		(layer "F.Cu")
		(net "M_D_DQS_DN<11>")
	)
	(segment
		(start 219.350336 -133.0706)
		(end 219.349828 -133.076442)
		(width 0.1651)
		(layer "F.Cu")
		(net "M_D_DQS_DN<11>")
	)
	(segment
		(start 218.865704 -135.25373)
		(end 218.657424 -135.25373)
		(width 0.1651)
		(layer "F.Cu")
		(net "M_D_DQS_DN<11>")
	)
	(segment
		(start 237.900718 -95.21444)
		(end 237.329218 -95.21444)
		(width 0.1651)
		(layer "F.Cu")
		(net "M_D_DQS_DN<11>")
	)
	(segment
		(start 219.117672 -134.755128)
		(end 219.117672 -135.001762)
		(width 0.1651)
		(layer "F.Cu")
		(net "M_D_DQS_DN<11>")
	)
	(segment
		(start 219.349828 -133.076442)
		(end 219.349828 -133.729984)
		(width 0.1651)
		(layer "F.Cu")
		(net "M_D_DQS_DN<11>")
	)
	(via
		(at 237.329218 -95.21444)
		(size 0.508)
		(drill 0.254)
		(layers "F.Cu" "B.Cu")
		(net "M_D_DQS_DN<11>")
	)
	(via
		(at 218.449144 -135.0645)
		(size 0.508)
		(drill 0.254)
		(layers "F.Cu" "B.Cu")
		(net "M_D_DQS_DN<11>")
	)
	(via
		(at 218.44254 -130.8862)
		(size 0.508)
		(drill 0.254)
		(layers "F.Cu" "B.Cu")
		(net "M_D_DQS_DN<11>")
	)
	(segment
		(start 218.86418 -130.691636)
		(end 218.637104 -130.691636)
		(width 0.1651)
		(layer "B.Cu")
		(net "M_D_DQS_DN<11>")
	)
	(segment
		(start 219.350082 -132.219192)
		(end 218.906344 -131.775454)
		(width 0.1651)
		(layer "B.Cu")
		(net "M_D_DQS_DN<11>")
	)
	(segment
		(start 218.906344 -131.775454)
		(end 218.906344 -131.4196)
		(width 0.1651)
		(layer "B.Cu")
		(net "M_D_DQS_DN<11>")
	)
	(segment
		(start 219.350336 -132.876036)
		(end 219.350082 -132.875528)
		(width 0.1651)
		(layer "B.Cu")
		(net "M_D_DQS_DN<11>")
	)
	(segment
		(start 218.637104 -130.691636)
		(end 218.44254 -130.8862)
		(width 0.1651)
		(layer "B.Cu")
		(net "M_D_DQS_DN<11>")
	)
	(segment
		(start 219.084144 -130.9116)
		(end 218.86418 -130.691636)
		(width 0.1651)
		(layer "B.Cu")
		(net "M_D_DQS_DN<11>")
	)
	(segment
		(start 219.084144 -131.2418)
		(end 219.084144 -130.9116)
		(width 0.1651)
		(layer "B.Cu")
		(net "M_D_DQS_DN<11>")
	)
	(segment
		(start 219.350082 -132.875528)
		(end 219.350082 -132.219192)
		(width 0.1651)
		(layer "B.Cu")
		(net "M_D_DQS_DN<11>")
	)
	(segment
		(start 218.906344 -131.4196)
		(end 219.084144 -131.2418)
		(width 0.1651)
		(layer "B.Cu")
		(net "M_D_DQS_DN<11>")
	)
	(segment
		(start 218.060524 -127.977392)
		(end 218.283536 -127.977392)
		(width 0.14224)
		(layer "In2.Cu")
		(net "M_D_DQS_DN<11>")
	)
	(segment
		(start 217.82532 -116.853462)
		(end 217.82532 -127.742188)
		(width 0.14224)
		(layer "In2.Cu")
		(net "M_D_DQS_DN<11>")
	)
	(segment
		(start 218.369388 -133.9596)
		(end 218.623388 -133.9596)
		(width 0.14224)
		(layer "In2.Cu")
		(net "M_D_DQS_DN<11>")
	)
	(segment
		(start 222.73133 -102.25913)
		(end 222.73133 -104.666542)
		(width 0.14224)
		(layer "In2.Cu")
		(net "M_D_DQS_DN<11>")
	)
	(segment
		(start 218.882214 -134.218426)
		(end 218.882214 -134.63143)
		(width 0.14224)
		(layer "In2.Cu")
		(net "M_D_DQS_DN<11>")
	)
	(segment
		(start 218.338908 -132.63372)
		(end 218.51747 -132.63372)
		(width 0.14224)
		(layer "In2.Cu")
		(net "M_D_DQS_DN<11>")
	)
	(segment
		(start 217.339672 -115.90147)
		(end 217.339672 -116.367814)
		(width 0.14224)
		(layer "In2.Cu")
		(net "M_D_DQS_DN<11>")
	)
	(segment
		(start 235.585762 -93.82379)
		(end 235.585762 -93.823536)
		(width 0.0889)
		(layer "In2.Cu")
		(net "M_D_DQS_DN<11>")
	)
	(segment
		(start 218.346528 -133.29666)
		(end 218.206828 -133.43636)
		(width 0.14224)
		(layer "In2.Cu")
		(net "M_D_DQS_DN<11>")
	)
	(segment
		(start 218.463114 -128.157224)
		(end 218.463114 -128.379982)
		(width 0.14224)
		(layer "In2.Cu")
		(net "M_D_DQS_DN<11>")
	)
	(segment
		(start 218.206828 -132.15366)
		(end 218.206828 -132.50164)
		(width 0.14224)
		(layer "In2.Cu")
		(net "M_D_DQS_DN<11>")
	)
	(segment
		(start 230.616506 -94.373954)
		(end 222.73133 -102.25913)
		(width 0.14224)
		(layer "In2.Cu")
		(net "M_D_DQS_DN<11>")
	)
	(segment
		(start 218.206828 -133.79704)
		(end 218.369388 -133.9596)
		(width 0.14224)
		(layer "In2.Cu")
		(net "M_D_DQS_DN<11>")
	)
	(segment
		(start 218.67241 -133.14172)
		(end 218.51747 -133.29666)
		(width 0.14224)
		(layer "In2.Cu")
		(net "M_D_DQS_DN<11>")
	)
	(segment
		(start 217.339672 -116.367814)
		(end 217.82532 -116.853462)
		(width 0.14224)
		(layer "In2.Cu")
		(net "M_D_DQS_DN<11>")
	)
	(segment
		(start 218.51747 -133.29666)
		(end 218.346528 -133.29666)
		(width 0.14224)
		(layer "In2.Cu")
		(net "M_D_DQS_DN<11>")
	)
	(segment
		(start 219.045282 -128.96215)
		(end 219.22486 -129.141728)
		(width 0.14224)
		(layer "In2.Cu")
		(net "M_D_DQS_DN<11>")
	)
	(segment
		(start 218.597988 -132.0038)
		(end 218.356688 -132.0038)
		(width 0.14224)
		(layer "In2.Cu")
		(net "M_D_DQS_DN<11>")
	)
	(segment
		(start 218.877388 -131.7244)
		(end 218.597988 -132.0038)
		(width 0.14224)
		(layer "In2.Cu")
		(net "M_D_DQS_DN<11>")
	)
	(segment
		(start 230.632 -94.35846)
		(end 230.616506 -94.373954)
		(width 0.0889)
		(layer "In2.Cu")
		(net "M_D_DQS_DN<11>")
	)
	(segment
		(start 218.38793 -128.08204)
		(end 218.463114 -128.157224)
		(width 0.14224)
		(layer "In2.Cu")
		(net "M_D_DQS_DN<11>")
	)
	(segment
		(start 217.773758 -115.467384)
		(end 217.339672 -115.90147)
		(width 0.14224)
		(layer "In2.Cu")
		(net "M_D_DQS_DN<11>")
	)
	(segment
		(start 218.882214 -134.63143)
		(end 218.449144 -135.0645)
		(width 0.14224)
		(layer "In2.Cu")
		(net "M_D_DQS_DN<11>")
	)
	(segment
		(start 235.630212 -93.82379)
		(end 235.590588 -93.82379)
		(width 0.0889)
		(layer "In2.Cu")
		(net "M_D_DQS_DN<11>")
	)
	(segment
		(start 218.206828 -133.43636)
		(end 218.206828 -133.79704)
		(width 0.14224)
		(layer "In2.Cu")
		(net "M_D_DQS_DN<11>")
	)
	(segment
		(start 218.877388 -131.321048)
		(end 218.877388 -131.7244)
		(width 0.14224)
		(layer "In2.Cu")
		(net "M_D_DQS_DN<11>")
	)
	(segment
		(start 237.344204 -94.81439)
		(end 237.316264 -94.81439)
		(width 0.0889)
		(layer "In2.Cu")
		(net "M_D_DQS_DN<11>")
	)
	(segment
		(start 232.199434 -93.799914)
		(end 231.13492 -93.799914)
		(width 0.0889)
		(layer "In2.Cu")
		(net "M_D_DQS_DN<11>")
	)
	(segment
		(start 218.463114 -128.379982)
		(end 218.642692 -128.55956)
		(width 0.14224)
		(layer "In2.Cu")
		(net "M_D_DQS_DN<11>")
	)
	(segment
		(start 218.642692 -128.55956)
		(end 218.865704 -128.55956)
		(width 0.14224)
		(layer "In2.Cu")
		(net "M_D_DQS_DN<11>")
	)
	(segment
		(start 218.356688 -132.0038)
		(end 218.206828 -132.15366)
		(width 0.14224)
		(layer "In2.Cu")
		(net "M_D_DQS_DN<11>")
	)
	(segment
		(start 217.773758 -114.56543)
		(end 217.773758 -115.467384)
		(width 0.14224)
		(layer "In2.Cu")
		(net "M_D_DQS_DN<11>")
	)
	(segment
		(start 219.22486 -130.10388)
		(end 218.44254 -130.8862)
		(width 0.14224)
		(layer "In2.Cu")
		(net "M_D_DQS_DN<11>")
	)
	(segment
		(start 237.329218 -95.21444)
		(end 237.622334 -95.38335)
		(width 0.0889)
		(layer "In2.Cu")
		(net "M_D_DQS_DN<11>")
	)
	(segment
		(start 218.623388 -133.9596)
		(end 218.882214 -134.218426)
		(width 0.14224)
		(layer "In2.Cu")
		(net "M_D_DQS_DN<11>")
	)
	(segment
		(start 219.045282 -128.739392)
		(end 219.045282 -128.96215)
		(width 0.14224)
		(layer "In2.Cu")
		(net "M_D_DQS_DN<11>")
	)
	(segment
		(start 230.631746 -94.303088)
		(end 230.632 -94.35846)
		(width 0.0889)
		(layer "In2.Cu")
		(net "M_D_DQS_DN<11>")
	)
	(segment
		(start 218.67241 -132.78866)
		(end 218.67241 -133.14172)
		(width 0.14224)
		(layer "In2.Cu")
		(net "M_D_DQS_DN<11>")
	)
	(segment
		(start 218.283536 -127.977392)
		(end 218.38793 -128.08204)
		(width 0.14224)
		(layer "In2.Cu")
		(net "M_D_DQS_DN<11>")
	)
	(segment
		(start 222.73133 -104.666542)
		(end 216.96172 -110.436152)
		(width 0.14224)
		(layer "In2.Cu")
		(net "M_D_DQS_DN<11>")
	)
	(segment
		(start 218.206828 -132.50164)
		(end 218.338908 -132.63372)
		(width 0.14224)
		(layer "In2.Cu")
		(net "M_D_DQS_DN<11>")
	)
	(segment
		(start 216.96172 -113.753392)
		(end 217.773758 -114.56543)
		(width 0.14224)
		(layer "In2.Cu")
		(net "M_D_DQS_DN<11>")
	)
	(segment
		(start 218.44254 -130.8862)
		(end 218.877388 -131.321048)
		(width 0.14224)
		(layer "In2.Cu")
		(net "M_D_DQS_DN<11>")
	)
	(segment
		(start 218.51747 -132.63372)
		(end 218.67241 -132.78866)
		(width 0.14224)
		(layer "In2.Cu")
		(net "M_D_DQS_DN<11>")
	)
	(segment
		(start 234.285028 -93.22435)
		(end 232.774998 -93.22435)
		(width 0.0889)
		(layer "In2.Cu")
		(net "M_D_DQS_DN<11>")
	)
	(segment
		(start 219.22486 -129.141728)
		(end 219.22486 -130.10388)
		(width 0.14224)
		(layer "In2.Cu")
		(net "M_D_DQS_DN<11>")
	)
	(segment
		(start 217.82532 -127.742188)
		(end 218.060524 -127.977392)
		(width 0.14224)
		(layer "In2.Cu")
		(net "M_D_DQS_DN<11>")
	)
	(segment
		(start 216.96172 -110.436152)
		(end 216.96172 -113.753392)
		(width 0.14224)
		(layer "In2.Cu")
		(net "M_D_DQS_DN<11>")
	)
	(segment
		(start 237.622334 -95.38335)
		(end 237.701074 -95.362014)
		(width 0.0889)
		(layer "In2.Cu")
		(net "M_D_DQS_DN<11>")
	)
	(segment
		(start 236.488732 -94.31909)
		(end 236.452918 -94.31909)
		(width 0.0889)
		(layer "In2.Cu")
		(net "M_D_DQS_DN<11>")
	)
	(segment
		(start 231.13492 -93.799914)
		(end 230.631746 -94.303088)
		(width 0.0889)
		(layer "In2.Cu")
		(net "M_D_DQS_DN<11>")
	)
	(segment
		(start 232.774998 -93.22435)
		(end 232.199434 -93.799914)
		(width 0.0889)
		(layer "In2.Cu")
		(net "M_D_DQS_DN<11>")
	)
	(segment
		(start 218.865704 -128.55956)
		(end 219.045282 -128.739392)
		(width 0.14224)
		(layer "In2.Cu")
		(net "M_D_DQS_DN<11>")
	)
	(segment
		(start 234.388914 -93.328236)
		(end 234.285028 -93.22435)
		(width 0.0889)
		(layer "In2.Cu")
		(net "M_D_DQS_DN<11>")
	)
	(segment
		(start 234.764072 -93.328236)
		(end 234.388914 -93.328236)
		(width 0.0889)
		(layer "In2.Cu")
		(net "M_D_DQS_DN<11>")
	)
	(arc
		(start 235.590588 -93.82379)
		(mid 235.588175 -93.823794)
		(end 235.585762 -93.82379)
		(width 0.0889)
		(layer "In2.Cu")
		(net "M_D_DQS_DN<11>")
	)
	(arc
		(start 235.585762 -93.823536)
		(mid 235.305239 -93.738152)
		(end 235.100368 -93.528388)
		(width 0.0889)
		(layer "In2.Cu")
		(net "M_D_DQS_DN<11>")
	)
	(arc
		(start 236.817408 -94.518988)
		(mid 236.678664 -94.376955)
		(end 236.488732 -94.31909)
		(width 0.0889)
		(layer "In2.Cu")
		(net "M_D_DQS_DN<11>")
	)
	(arc
		(start 236.452918 -94.31909)
		(mid 236.167494 -94.235623)
		(end 235.958888 -94.023688)
		(width 0.0889)
		(layer "In2.Cu")
		(net "M_D_DQS_DN<11>")
	)
	(arc
		(start 237.316264 -94.81439)
		(mid 237.028119 -94.732071)
		(end 236.817408 -94.518988)
		(width 0.0889)
		(layer "In2.Cu")
		(net "M_D_DQS_DN<11>")
	)
	(arc
		(start 235.958888 -94.023688)
		(mid 235.820144 -93.881655)
		(end 235.630212 -93.82379)
		(width 0.0889)
		(layer "In2.Cu")
		(net "M_D_DQS_DN<11>")
	)
	(arc
		(start 235.100368 -93.528388)
		(mid 234.958325 -93.384476)
		(end 234.764072 -93.328236)
		(width 0.0889)
		(layer "In2.Cu")
		(net "M_D_DQS_DN<11>")
	)
	(arc
		(start 237.701074 -95.362014)
		(mid 237.664334 -94.995875)
		(end 237.344204 -94.81439)
		(width 0.0889)
		(layer "In2.Cu")
		(net "M_D_DQS_DN<11>")
	)
	(segment
		(start 210.84032 -116.395754)
		(end 210.84032 -119.276114)
		(width 0.1651)
		(layer "F.Cu")
		(net "M_D_DQS_DN<10>")
	)
	(segment
		(start 233.895392 -94.553278)
		(end 233.918506 -94.466664)
		(width 0.0889)
		(layer "F.Cu")
		(net "M_D_DQS_DN<10>")
	)
	(segment
		(start 232.537 -94.37497)
		(end 230.977694 -94.37497)
		(width 0.1651)
		(layer "F.Cu")
		(net "M_D_DQS_DN<10>")
	)
	(segment
		(start 233.620564 -94.318836)
		(end 233.299 -94.318836)
		(width 0.0889)
		(layer "F.Cu")
		(net "M_D_DQS_DN<10>")
	)
	(segment
		(start 209.767678 -134.755128)
		(end 209.767678 -135.001762)
		(width 0.1651)
		(layer "F.Cu")
		(net "M_D_DQS_DN<10>")
	)
	(segment
		(start 209.937096 -130.04165)
		(end 209.092546 -130.8862)
		(width 0.1651)
		(layer "F.Cu")
		(net "M_D_DQS_DN<10>")
	)
	(segment
		(start 233.1974 -94.420436)
		(end 233.045 -94.420436)
		(width 0.0889)
		(layer "F.Cu")
		(net "M_D_DQS_DN<10>")
	)
	(segment
		(start 230.977694 -94.37497)
		(end 209.991198 -115.361466)
		(width 0.1651)
		(layer "F.Cu")
		(net "M_D_DQS_DN<10>")
	)
	(segment
		(start 209.51571 -135.25373)
		(end 209.30743 -135.25373)
		(width 0.1651)
		(layer "F.Cu")
		(net "M_D_DQS_DN<10>")
	)
	(segment
		(start 233.299 -94.318836)
		(end 233.1974 -94.420436)
		(width 0.0889)
		(layer "F.Cu")
		(net "M_D_DQS_DN<10>")
	)
	(segment
		(start 210.49107 -116.046504)
		(end 210.84032 -116.395754)
		(width 0.1651)
		(layer "F.Cu")
		(net "M_D_DQS_DN<10>")
	)
	(segment
		(start 209.767678 -135.001762)
		(end 209.51571 -135.25373)
		(width 0.1651)
		(layer "F.Cu")
		(net "M_D_DQS_DN<10>")
	)
	(segment
		(start 232.593134 -94.318836)
		(end 232.537 -94.37497)
		(width 0.0889)
		(layer "F.Cu")
		(net "M_D_DQS_DN<10>")
	)
	(segment
		(start 233.045 -94.420436)
		(end 232.9434 -94.318836)
		(width 0.0889)
		(layer "F.Cu")
		(net "M_D_DQS_DN<10>")
	)
	(segment
		(start 209.58175 -134.5692)
		(end 209.767678 -134.755128)
		(width 0.1651)
		(layer "F.Cu")
		(net "M_D_DQS_DN<10>")
	)
	(segment
		(start 209.999834 -133.076442)
		(end 209.999834 -133.729984)
		(width 0.1651)
		(layer "F.Cu")
		(net "M_D_DQS_DN<10>")
	)
	(segment
		(start 210.000342 -133.0706)
		(end 209.999834 -133.076442)
		(width 0.1651)
		(layer "F.Cu")
		(net "M_D_DQS_DN<10>")
	)
	(segment
		(start 209.991198 -115.361466)
		(end 209.991198 -115.871498)
		(width 0.1651)
		(layer "F.Cu")
		(net "M_D_DQS_DN<10>")
	)
	(segment
		(start 210.115404 -119.676164)
		(end 209.937096 -119.854472)
		(width 0.1651)
		(layer "F.Cu")
		(net "M_D_DQS_DN<10>")
	)
	(segment
		(start 209.999834 -133.729984)
		(end 209.58175 -134.148068)
		(width 0.1651)
		(layer "F.Cu")
		(net "M_D_DQS_DN<10>")
	)
	(segment
		(start 209.30743 -135.25373)
		(end 209.1182 -135.0645)
		(width 0.1651)
		(layer "F.Cu")
		(net "M_D_DQS_DN<10>")
	)
	(segment
		(start 232.9434 -94.318836)
		(end 232.593134 -94.318836)
		(width 0.0889)
		(layer "F.Cu")
		(net "M_D_DQS_DN<10>")
	)
	(segment
		(start 210.44027 -119.676164)
		(end 210.115404 -119.676164)
		(width 0.1651)
		(layer "F.Cu")
		(net "M_D_DQS_DN<10>")
	)
	(segment
		(start 209.1182 -135.0645)
		(end 209.09915 -135.0645)
		(width 0.1651)
		(layer "F.Cu")
		(net "M_D_DQS_DN<10>")
	)
	(segment
		(start 210.166204 -116.046504)
		(end 210.49107 -116.046504)
		(width 0.1651)
		(layer "F.Cu")
		(net "M_D_DQS_DN<10>")
	)
	(segment
		(start 209.937096 -119.854472)
		(end 209.937096 -130.04165)
		(width 0.1651)
		(layer "F.Cu")
		(net "M_D_DQS_DN<10>")
	)
	(segment
		(start 233.626152 -94.31909)
		(end 233.620564 -94.318836)
		(width 0.0889)
		(layer "F.Cu")
		(net "M_D_DQS_DN<10>")
	)
	(segment
		(start 210.84032 -119.276114)
		(end 210.44027 -119.676164)
		(width 0.1651)
		(layer "F.Cu")
		(net "M_D_DQS_DN<10>")
	)
	(segment
		(start 209.991198 -115.871498)
		(end 210.166204 -116.046504)
		(width 0.1651)
		(layer "F.Cu")
		(net "M_D_DQS_DN<10>")
	)
	(segment
		(start 233.608118 -94.718886)
		(end 233.895392 -94.553278)
		(width 0.0889)
		(layer "F.Cu")
		(net "M_D_DQS_DN<10>")
	)
	(segment
		(start 209.58175 -134.148068)
		(end 209.58175 -134.5692)
		(width 0.1651)
		(layer "F.Cu")
		(net "M_D_DQS_DN<10>")
	)
	(via
		(at 209.092546 -130.8862)
		(size 0.508)
		(drill 0.254)
		(layers "F.Cu" "B.Cu")
		(net "M_D_DQS_DN<10>")
	)
	(via
		(at 209.09915 -135.0645)
		(size 0.508)
		(drill 0.254)
		(layers "F.Cu" "B.Cu")
		(net "M_D_DQS_DN<10>")
	)
	(arc
		(start 233.67365 -94.32417)
		(mid 233.649977 -94.320917)
		(end 233.626152 -94.31909)
		(width 0.0889)
		(layer "F.Cu")
		(net "M_D_DQS_DN<10>")
	)
	(arc
		(start 233.918506 -94.466664)
		(mid 233.809107 -94.373031)
		(end 233.67365 -94.32417)
		(width 0.0889)
		(layer "F.Cu")
		(net "M_D_DQS_DN<10>")
	)
	(segment
		(start 209.55635 -131.4196)
		(end 209.73415 -131.2418)
		(width 0.1651)
		(layer "B.Cu")
		(net "M_D_DQS_DN<10>")
	)
	(segment
		(start 209.73415 -130.9116)
		(end 209.514186 -130.691636)
		(width 0.1651)
		(layer "B.Cu")
		(net "M_D_DQS_DN<10>")
	)
	(segment
		(start 210.000342 -132.876036)
		(end 210.000088 -132.875528)
		(width 0.1651)
		(layer "B.Cu")
		(net "M_D_DQS_DN<10>")
	)
	(segment
		(start 209.28711 -130.691636)
		(end 209.092546 -130.8862)
		(width 0.1651)
		(layer "B.Cu")
		(net "M_D_DQS_DN<10>")
	)
	(segment
		(start 210.000088 -132.875528)
		(end 210.000088 -132.219192)
		(width 0.1651)
		(layer "B.Cu")
		(net "M_D_DQS_DN<10>")
	)
	(segment
		(start 210.000088 -132.219192)
		(end 209.55635 -131.775454)
		(width 0.1651)
		(layer "B.Cu")
		(net "M_D_DQS_DN<10>")
	)
	(segment
		(start 209.55635 -131.775454)
		(end 209.55635 -131.4196)
		(width 0.1651)
		(layer "B.Cu")
		(net "M_D_DQS_DN<10>")
	)
	(segment
		(start 209.73415 -131.2418)
		(end 209.73415 -130.9116)
		(width 0.1651)
		(layer "B.Cu")
		(net "M_D_DQS_DN<10>")
	)
	(segment
		(start 209.514186 -130.691636)
		(end 209.28711 -130.691636)
		(width 0.1651)
		(layer "B.Cu")
		(net "M_D_DQS_DN<10>")
	)
	(segment
		(start 209.298794 -133.14172)
		(end 209.298794 -132.78866)
		(width 0.14224)
		(layer "In2.Cu")
		(net "M_D_DQS_DN<10>")
	)
	(segment
		(start 209.53222 -134.63143)
		(end 209.53222 -134.147306)
		(width 0.14224)
		(layer "In2.Cu")
		(net "M_D_DQS_DN<10>")
	)
	(segment
		(start 208.856834 -133.79704)
		(end 208.856834 -133.43636)
		(width 0.14224)
		(layer "In2.Cu")
		(net "M_D_DQS_DN<10>")
	)
	(segment
		(start 208.856834 -133.43636)
		(end 208.996534 -133.29666)
		(width 0.14224)
		(layer "In2.Cu")
		(net "M_D_DQS_DN<10>")
	)
	(segment
		(start 208.988914 -132.63372)
		(end 208.856834 -132.50164)
		(width 0.14224)
		(layer "In2.Cu")
		(net "M_D_DQS_DN<10>")
	)
	(segment
		(start 208.856834 -132.50164)
		(end 208.856834 -132.15366)
		(width 0.14224)
		(layer "In2.Cu")
		(net "M_D_DQS_DN<10>")
	)
	(segment
		(start 209.53222 -134.147306)
		(end 209.344514 -133.9596)
		(width 0.14224)
		(layer "In2.Cu")
		(net "M_D_DQS_DN<10>")
	)
	(segment
		(start 209.247994 -132.0038)
		(end 209.527394 -131.7244)
		(width 0.14224)
		(layer "In2.Cu")
		(net "M_D_DQS_DN<10>")
	)
	(segment
		(start 209.527394 -131.321048)
		(end 209.092546 -130.8862)
		(width 0.14224)
		(layer "In2.Cu")
		(net "M_D_DQS_DN<10>")
	)
	(segment
		(start 209.143854 -132.63372)
		(end 208.988914 -132.63372)
		(width 0.14224)
		(layer "In2.Cu")
		(net "M_D_DQS_DN<10>")
	)
	(segment
		(start 209.019394 -133.9596)
		(end 208.856834 -133.79704)
		(width 0.14224)
		(layer "In2.Cu")
		(net "M_D_DQS_DN<10>")
	)
	(segment
		(start 209.344514 -133.9596)
		(end 209.019394 -133.9596)
		(width 0.14224)
		(layer "In2.Cu")
		(net "M_D_DQS_DN<10>")
	)
	(segment
		(start 208.996534 -133.29666)
		(end 209.143854 -133.29666)
		(width 0.14224)
		(layer "In2.Cu")
		(net "M_D_DQS_DN<10>")
	)
	(segment
		(start 209.09915 -135.0645)
		(end 209.53222 -134.63143)
		(width 0.14224)
		(layer "In2.Cu")
		(net "M_D_DQS_DN<10>")
	)
	(segment
		(start 209.006694 -132.0038)
		(end 209.247994 -132.0038)
		(width 0.14224)
		(layer "In2.Cu")
		(net "M_D_DQS_DN<10>")
	)
	(segment
		(start 209.298794 -132.78866)
		(end 209.143854 -132.63372)
		(width 0.14224)
		(layer "In2.Cu")
		(net "M_D_DQS_DN<10>")
	)
	(segment
		(start 208.856834 -132.15366)
		(end 209.006694 -132.0038)
		(width 0.14224)
		(layer "In2.Cu")
		(net "M_D_DQS_DN<10>")
	)
	(segment
		(start 209.143854 -133.29666)
		(end 209.298794 -133.14172)
		(width 0.14224)
		(layer "In2.Cu")
		(net "M_D_DQS_DN<10>")
	)
	(segment
		(start 209.527394 -131.7244)
		(end 209.527394 -131.321048)
		(width 0.14224)
		(layer "In2.Cu")
		(net "M_D_DQS_DN<10>")
	)
	(segment
		(start 234.466638 -87.28964)
		(end 233.895138 -87.28964)
		(width 0.1651)
		(layer "F.Cu")
		(net "M_D_DQS_DN<0>")
	)
	(segment
		(start 200.64984 -136.60247)
		(end 200.267824 -136.220454)
		(width 0.1651)
		(layer "F.Cu")
		(net "M_D_DQS_DN<0>")
	)
	(segment
		(start 200.64984 -137.67054)
		(end 200.64984 -136.60247)
		(width 0.1651)
		(layer "F.Cu")
		(net "M_D_DQS_DN<0>")
	)
	(segment
		(start 200.267824 -136.220454)
		(end 200.267824 -135.788654)
		(width 0.1651)
		(layer "F.Cu")
		(net "M_D_DQS_DN<0>")
	)
	(segment
		(start 200.267824 -135.788654)
		(end 200.598278 -135.4582)
		(width 0.1651)
		(layer "F.Cu")
		(net "M_D_DQS_DN<0>")
	)
	(segment
		(start 200.650348 -137.67054)
		(end 200.64984 -137.67054)
		(width 0.1651)
		(layer "F.Cu")
		(net "M_D_DQS_DN<0>")
	)
	(segment
		(start 200.598278 -135.4582)
		(end 200.822306 -135.4582)
		(width 0.1651)
		(layer "F.Cu")
		(net "M_D_DQS_DN<0>")
	)
	(segment
		(start 200.822306 -135.4582)
		(end 201.037952 -135.673846)
		(width 0.1651)
		(layer "F.Cu")
		(net "M_D_DQS_DN<0>")
	)
	(via
		(at 233.895138 -87.28964)
		(size 0.508)
		(drill 0.254)
		(layers "F.Cu" "B.Cu")
		(net "M_D_DQS_DN<0>")
	)
	(via
		(at 201.037952 -130.280156)
		(size 0.508)
		(drill 0.254)
		(layers "F.Cu" "B.Cu")
		(net "M_D_DQS_DN<0>")
	)
	(via
		(at 201.037952 -135.673846)
		(size 0.508)
		(drill 0.254)
		(layers "F.Cu" "B.Cu")
		(net "M_D_DQS_DN<0>")
	)
	(segment
		(start 200.267824 -130.1496)
		(end 200.623424 -130.5052)
		(width 0.1651)
		(layer "B.Cu")
		(net "M_D_DQS_DN<0>")
	)
	(segment
		(start 200.267824 -129.819146)
		(end 200.267824 -130.1496)
		(width 0.1651)
		(layer "B.Cu")
		(net "M_D_DQS_DN<0>")
	)
	(segment
		(start 200.521824 -129.565146)
		(end 200.267824 -129.819146)
		(width 0.1651)
		(layer "B.Cu")
		(net "M_D_DQS_DN<0>")
	)
	(segment
		(start 200.812908 -130.5052)
		(end 201.037952 -130.280156)
		(width 0.1651)
		(layer "B.Cu")
		(net "M_D_DQS_DN<0>")
	)
	(segment
		(start 200.650348 -128.276096)
		(end 200.64984 -128.276096)
		(width 0.1651)
		(layer "B.Cu")
		(net "M_D_DQS_DN<0>")
	)
	(segment
		(start 200.623424 -130.5052)
		(end 200.812908 -130.5052)
		(width 0.1651)
		(layer "B.Cu")
		(net "M_D_DQS_DN<0>")
	)
	(segment
		(start 200.64984 -129.18313)
		(end 200.521824 -129.311146)
		(width 0.1651)
		(layer "B.Cu")
		(net "M_D_DQS_DN<0>")
	)
	(segment
		(start 200.521824 -129.311146)
		(end 200.521824 -129.565146)
		(width 0.1651)
		(layer "B.Cu")
		(net "M_D_DQS_DN<0>")
	)
	(segment
		(start 200.64984 -128.276096)
		(end 200.64984 -129.18313)
		(width 0.1651)
		(layer "B.Cu")
		(net "M_D_DQS_DN<0>")
	)
	(segment
		(start 201.55408 -129.41808)
		(end 201.422 -129.286)
		(width 0.14224)
		(layer "In2.Cu")
		(net "M_D_DQS_DN<0>")
	)
	(segment
		(start 201.678286 -125.575568)
		(end 202.069192 -125.575568)
		(width 0.14224)
		(layer "In2.Cu")
		(net "M_D_DQS_DN<0>")
	)
	(segment
		(start 202.29068 -122.637296)
		(end 202.069192 -122.415808)
		(width 0.14224)
		(layer "In2.Cu")
		(net "M_D_DQS_DN<0>")
	)
	(segment
		(start 217.58656 -99.513644)
		(end 229.770686 -87.329518)
		(width 0.14224)
		(layer "In2.Cu")
		(net "M_D_DQS_DN<0>")
	)
	(segment
		(start 230.698548 -87.329518)
		(end 230.741728 -87.372698)
		(width 0.0889)
		(layer "In2.Cu")
		(net "M_D_DQS_DN<0>")
	)
	(segment
		(start 229.770686 -87.329518)
		(end 230.698548 -87.329518)
		(width 0.14224)
		(layer "In2.Cu")
		(net "M_D_DQS_DN<0>")
	)
	(segment
		(start 201.30008 -125.953774)
		(end 201.678286 -125.575568)
		(width 0.14224)
		(layer "In2.Cu")
		(net "M_D_DQS_DN<0>")
	)
	(segment
		(start 200.604882 -135.240776)
		(end 200.604882 -133.985)
		(width 0.14224)
		(layer "In2.Cu")
		(net "M_D_DQS_DN<0>")
	)
	(segment
		(start 201.037952 -135.673846)
		(end 200.604882 -135.240776)
		(width 0.14224)
		(layer "In2.Cu")
		(net "M_D_DQS_DN<0>")
	)
	(segment
		(start 201.422 -128.9304)
		(end 201.55408 -128.79832)
		(width 0.14224)
		(layer "In2.Cu")
		(net "M_D_DQS_DN<0>")
	)
	(segment
		(start 201.55408 -128.434846)
		(end 202.29068 -127.698246)
		(width 0.14224)
		(layer "In2.Cu")
		(net "M_D_DQS_DN<0>")
	)
	(segment
		(start 200.604882 -133.985)
		(end 200.394062 -133.77418)
		(width 0.14224)
		(layer "In2.Cu")
		(net "M_D_DQS_DN<0>")
	)
	(segment
		(start 202.069192 -123.289568)
		(end 202.29068 -123.06808)
		(width 0.14224)
		(layer "In2.Cu")
		(net "M_D_DQS_DN<0>")
	)
	(segment
		(start 202.29068 -127.698246)
		(end 202.29068 -127.302768)
		(width 0.14224)
		(layer "In2.Cu")
		(net "M_D_DQS_DN<0>")
	)
	(segment
		(start 200.394062 -133.77418)
		(end 200.394062 -132.11302)
		(width 0.14224)
		(layer "In2.Cu")
		(net "M_D_DQS_DN<0>")
	)
	(segment
		(start 203.338176 -114.331496)
		(end 204.362304 -114.331496)
		(width 0.14224)
		(layer "In2.Cu")
		(net "M_D_DQS_DN<0>")
	)
	(segment
		(start 231.91089 -87.68969)
		(end 232.268268 -87.68969)
		(width 0.0889)
		(layer "In2.Cu")
		(net "M_D_DQS_DN<0>")
	)
	(segment
		(start 202.069192 -121.003568)
		(end 202.29068 -120.78208)
		(width 0.14224)
		(layer "In2.Cu")
		(net "M_D_DQS_DN<0>")
	)
	(segment
		(start 201.40168 -122.037602)
		(end 201.40168 -121.381774)
		(width 0.14224)
		(layer "In2.Cu")
		(net "M_D_DQS_DN<0>")
	)
	(segment
		(start 202.29068 -125.35408)
		(end 202.29068 -124.923296)
		(width 0.14224)
		(layer "In2.Cu")
		(net "M_D_DQS_DN<0>")
	)
	(segment
		(start 200.604882 -131.9022)
		(end 200.604882 -130.640074)
		(width 0.14224)
		(layer "In2.Cu")
		(net "M_D_DQS_DN<0>")
	)
	(segment
		(start 202.29068 -124.923296)
		(end 202.069192 -124.701808)
		(width 0.14224)
		(layer "In2.Cu")
		(net "M_D_DQS_DN<0>")
	)
	(segment
		(start 201.678286 -126.987808)
		(end 201.30008 -126.609602)
		(width 0.14224)
		(layer "In2.Cu")
		(net "M_D_DQS_DN<0>")
	)
	(segment
		(start 202.069192 -124.701808)
		(end 201.729086 -124.701808)
		(width 0.14224)
		(layer "In2.Cu")
		(net "M_D_DQS_DN<0>")
	)
	(segment
		(start 201.35088 -124.323602)
		(end 201.35088 -123.667774)
		(width 0.14224)
		(layer "In2.Cu")
		(net "M_D_DQS_DN<0>")
	)
	(segment
		(start 201.35088 -123.667774)
		(end 201.729086 -123.289568)
		(width 0.14224)
		(layer "In2.Cu")
		(net "M_D_DQS_DN<0>")
	)
	(segment
		(start 232.833926 -87.194136)
		(end 233.054398 -87.194136)
		(width 0.0889)
		(layer "In2.Cu")
		(net "M_D_DQS_DN<0>")
	)
	(segment
		(start 201.393044 -130.280156)
		(end 201.55408 -130.11912)
		(width 0.14224)
		(layer "In2.Cu")
		(net "M_D_DQS_DN<0>")
	)
	(segment
		(start 231.593898 -87.372698)
		(end 231.91089 -87.68969)
		(width 0.0889)
		(layer "In2.Cu")
		(net "M_D_DQS_DN<0>")
	)
	(segment
		(start 233.418126 -87.28964)
		(end 233.895138 -87.28964)
		(width 0.0889)
		(layer "In2.Cu")
		(net "M_D_DQS_DN<0>")
	)
	(segment
		(start 202.069192 -122.415808)
		(end 201.779886 -122.415808)
		(width 0.14224)
		(layer "In2.Cu")
		(net "M_D_DQS_DN<0>")
	)
	(segment
		(start 204.362304 -114.331496)
		(end 217.58656 -101.10724)
		(width 0.14224)
		(layer "In2.Cu")
		(net "M_D_DQS_DN<0>")
	)
	(segment
		(start 202.29068 -127.302768)
		(end 201.97572 -126.987808)
		(width 0.14224)
		(layer "In2.Cu")
		(net "M_D_DQS_DN<0>")
	)
	(segment
		(start 202.29068 -120.78208)
		(end 202.29068 -115.378992)
		(width 0.14224)
		(layer "In2.Cu")
		(net "M_D_DQS_DN<0>")
	)
	(segment
		(start 201.779886 -122.415808)
		(end 201.40168 -122.037602)
		(width 0.14224)
		(layer "In2.Cu")
		(net "M_D_DQS_DN<0>")
	)
	(segment
		(start 201.729086 -124.701808)
		(end 201.35088 -124.323602)
		(width 0.14224)
		(layer "In2.Cu")
		(net "M_D_DQS_DN<0>")
	)
	(segment
		(start 201.55408 -128.79832)
		(end 201.55408 -128.434846)
		(width 0.14224)
		(layer "In2.Cu")
		(net "M_D_DQS_DN<0>")
	)
	(segment
		(start 200.394062 -132.11302)
		(end 200.604882 -131.9022)
		(width 0.14224)
		(layer "In2.Cu")
		(net "M_D_DQS_DN<0>")
	)
	(segment
		(start 200.604882 -130.640074)
		(end 200.9648 -130.280156)
		(width 0.14224)
		(layer "In2.Cu")
		(net "M_D_DQS_DN<0>")
	)
	(segment
		(start 201.30008 -126.609602)
		(end 201.30008 -125.953774)
		(width 0.14224)
		(layer "In2.Cu")
		(net "M_D_DQS_DN<0>")
	)
	(segment
		(start 201.037952 -130.280156)
		(end 201.393044 -130.280156)
		(width 0.14224)
		(layer "In2.Cu")
		(net "M_D_DQS_DN<0>")
	)
	(segment
		(start 201.779886 -121.003568)
		(end 202.069192 -121.003568)
		(width 0.14224)
		(layer "In2.Cu")
		(net "M_D_DQS_DN<0>")
	)
	(segment
		(start 201.422 -129.286)
		(end 201.422 -128.9304)
		(width 0.14224)
		(layer "In2.Cu")
		(net "M_D_DQS_DN<0>")
	)
	(segment
		(start 202.29068 -123.06808)
		(end 202.29068 -122.637296)
		(width 0.14224)
		(layer "In2.Cu")
		(net "M_D_DQS_DN<0>")
	)
	(segment
		(start 202.29068 -115.378992)
		(end 203.338176 -114.331496)
		(width 0.14224)
		(layer "In2.Cu")
		(net "M_D_DQS_DN<0>")
	)
	(segment
		(start 201.729086 -123.289568)
		(end 202.069192 -123.289568)
		(width 0.14224)
		(layer "In2.Cu")
		(net "M_D_DQS_DN<0>")
	)
	(segment
		(start 201.40168 -121.381774)
		(end 201.779886 -121.003568)
		(width 0.14224)
		(layer "In2.Cu")
		(net "M_D_DQS_DN<0>")
	)
	(segment
		(start 230.741728 -87.372698)
		(end 231.593898 -87.372698)
		(width 0.0889)
		(layer "In2.Cu")
		(net "M_D_DQS_DN<0>")
	)
	(segment
		(start 201.97572 -126.987808)
		(end 201.678286 -126.987808)
		(width 0.14224)
		(layer "In2.Cu")
		(net "M_D_DQS_DN<0>")
	)
	(segment
		(start 202.069192 -125.575568)
		(end 202.29068 -125.35408)
		(width 0.14224)
		(layer "In2.Cu")
		(net "M_D_DQS_DN<0>")
	)
	(segment
		(start 200.9648 -130.280156)
		(end 201.037952 -130.280156)
		(width 0.14224)
		(layer "In2.Cu")
		(net "M_D_DQS_DN<0>")
	)
	(segment
		(start 217.58656 -101.10724)
		(end 217.58656 -99.513644)
		(width 0.14224)
		(layer "In2.Cu")
		(net "M_D_DQS_DN<0>")
	)
	(segment
		(start 201.55408 -130.11912)
		(end 201.55408 -129.41808)
		(width 0.14224)
		(layer "In2.Cu")
		(net "M_D_DQS_DN<0>")
	)
	(arc
		(start 233.054398 -87.194136)
		(mid 233.189265 -87.213868)
		(end 233.316018 -87.263986)
		(width 0.0889)
		(layer "In2.Cu")
		(net "M_D_DQS_DN<0>")
	)
	(arc
		(start 232.48493 -87.492332)
		(mid 232.63103 -87.309998)
		(end 232.833926 -87.194136)
		(width 0.0889)
		(layer "In2.Cu")
		(net "M_D_DQS_DN<0>")
	)
	(arc
		(start 233.316018 -87.263986)
		(mid 233.365487 -87.283118)
		(end 233.418126 -87.28964)
		(width 0.0889)
		(layer "In2.Cu")
		(net "M_D_DQS_DN<0>")
	)
	(arc
		(start 232.268268 -87.68969)
		(mid 232.393755 -87.609857)
		(end 232.48493 -87.492332)
		(width 0.0889)
		(layer "In2.Cu")
		(net "M_D_DQS_DN<0>")
	)
	(segment
		(start 230.886762 -93.091)
		(end 208.965038 -115.012724)
		(width 0.1651)
		(layer "F.Cu")
		(net "M_D_DQ<9>")
	)
	(segment
		(start 209.155538 -118.836186)
		(end 208.965038 -119.026686)
		(width 0.1651)
		(layer "F.Cu")
		(net "M_D_DQ<9>")
	)
	(segment
		(start 208.965038 -116.626386)
		(end 209.155538 -116.816886)
		(width 0.1651)
		(layer "F.Cu")
		(net "M_D_DQ<9>")
	)
	(segment
		(start 209.155538 -117.489986)
		(end 208.990438 -117.655086)
		(width 0.1651)
		(layer "F.Cu")
		(net "M_D_DQ<9>")
	)
	(segment
		(start 208.454244 -130.330956)
		(end 208.122012 -130.330956)
		(width 0.1651)
		(layer "F.Cu")
		(net "M_D_DQ<9>")
	)
	(segment
		(start 209.7278 -118.328186)
		(end 209.7278 -118.671086)
		(width 0.1651)
		(layer "F.Cu")
		(net "M_D_DQ<9>")
	)
	(segment
		(start 209.5627 -118.836186)
		(end 209.155538 -118.836186)
		(width 0.1651)
		(layer "F.Cu")
		(net "M_D_DQ<9>")
	)
	(segment
		(start 233.254804 -93.091)
		(end 232.488232 -93.091)
		(width 0.0889)
		(layer "F.Cu")
		(net "M_D_DQ<9>")
	)
	(segment
		(start 208.2546 -128.270254)
		(end 208.2546 -128.5494)
		(width 0.1651)
		(layer "F.Cu")
		(net "M_D_DQ<9>")
	)
	(segment
		(start 208.628996 -130.156204)
		(end 208.454244 -130.330956)
		(width 0.1651)
		(layer "F.Cu")
		(net "M_D_DQ<9>")
	)
	(segment
		(start 208.965038 -119.026686)
		(end 208.965038 -127.559816)
		(width 0.1651)
		(layer "F.Cu")
		(net "M_D_DQ<9>")
	)
	(segment
		(start 208.990438 -117.997986)
		(end 209.155538 -118.163086)
		(width 0.1651)
		(layer "F.Cu")
		(net "M_D_DQ<9>")
	)
	(segment
		(start 209.7278 -118.671086)
		(end 209.5627 -118.836186)
		(width 0.1651)
		(layer "F.Cu")
		(net "M_D_DQ<9>")
	)
	(segment
		(start 207.450436 -133.0706)
		(end 207.449928 -133.076442)
		(width 0.1651)
		(layer "F.Cu")
		(net "M_D_DQ<9>")
	)
	(segment
		(start 209.5627 -117.489986)
		(end 209.155538 -117.489986)
		(width 0.1651)
		(layer "F.Cu")
		(net "M_D_DQ<9>")
	)
	(segment
		(start 232.488232 -93.091)
		(end 230.886762 -93.091)
		(width 0.1651)
		(layer "F.Cu")
		(net "M_D_DQ<9>")
	)
	(segment
		(start 208.965038 -115.012724)
		(end 208.965038 -116.626386)
		(width 0.1651)
		(layer "F.Cu")
		(net "M_D_DQ<9>")
	)
	(segment
		(start 209.7278 -117.324886)
		(end 209.5627 -117.489986)
		(width 0.1651)
		(layer "F.Cu")
		(net "M_D_DQ<9>")
	)
	(segment
		(start 209.5627 -116.816886)
		(end 209.7278 -116.981986)
		(width 0.1651)
		(layer "F.Cu")
		(net "M_D_DQ<9>")
	)
	(segment
		(start 209.155538 -116.816886)
		(end 209.5627 -116.816886)
		(width 0.1651)
		(layer "F.Cu")
		(net "M_D_DQ<9>")
	)
	(segment
		(start 209.155538 -118.163086)
		(end 209.5627 -118.163086)
		(width 0.1651)
		(layer "F.Cu")
		(net "M_D_DQ<9>")
	)
	(segment
		(start 208.2546 -128.5494)
		(end 208.628996 -128.923796)
		(width 0.1651)
		(layer "F.Cu")
		(net "M_D_DQ<9>")
	)
	(segment
		(start 209.5627 -118.163086)
		(end 209.7278 -118.328186)
		(width 0.1651)
		(layer "F.Cu")
		(net "M_D_DQ<9>")
	)
	(segment
		(start 208.990438 -117.655086)
		(end 208.990438 -117.997986)
		(width 0.1651)
		(layer "F.Cu")
		(net "M_D_DQ<9>")
	)
	(segment
		(start 233.608118 -92.737686)
		(end 233.254804 -93.091)
		(width 0.0889)
		(layer "F.Cu")
		(net "M_D_DQ<9>")
	)
	(segment
		(start 208.628996 -128.923796)
		(end 208.628996 -130.156204)
		(width 0.1651)
		(layer "F.Cu")
		(net "M_D_DQ<9>")
	)
	(segment
		(start 208.965038 -127.559816)
		(end 208.2546 -128.270254)
		(width 0.1651)
		(layer "F.Cu")
		(net "M_D_DQ<9>")
	)
	(segment
		(start 207.449928 -133.076442)
		(end 207.449928 -134.340346)
		(width 0.1651)
		(layer "F.Cu")
		(net "M_D_DQ<9>")
	)
	(segment
		(start 209.7278 -116.981986)
		(end 209.7278 -117.324886)
		(width 0.1651)
		(layer "F.Cu")
		(net "M_D_DQ<9>")
	)
	(via
		(at 208.122012 -130.330956)
		(size 0.508)
		(drill 0.254)
		(layers "F.Cu" "B.Cu")
		(net "M_D_DQ<9>")
	)
	(via
		(at 207.449928 -134.340346)
		(size 0.508)
		(drill 0.254)
		(layers "F.Cu" "B.Cu")
		(net "M_D_DQ<9>")
	)
	(segment
		(start 208.299812 -128.276096)
		(end 208.299812 -129.649982)
		(width 0.1651)
		(layer "B.Cu")
		(net "M_D_DQ<9>")
	)
	(segment
		(start 208.299812 -129.649982)
		(end 208.122012 -129.827782)
		(width 0.1651)
		(layer "B.Cu")
		(net "M_D_DQ<9>")
	)
	(segment
		(start 208.30032 -128.276096)
		(end 208.299812 -128.276096)
		(width 0.1651)
		(layer "B.Cu")
		(net "M_D_DQ<9>")
	)
	(segment
		(start 208.122012 -129.827782)
		(end 208.122012 -130.330956)
		(width 0.1651)
		(layer "B.Cu")
		(net "M_D_DQ<9>")
	)
	(segment
		(start 207.850994 -133.8834)
		(end 207.850994 -134.1882)
		(width 0.14224)
		(layer "In2.Cu")
		(net "M_D_DQ<9>")
	)
	(segment
		(start 207.671416 -130.504184)
		(end 207.671416 -131.188968)
		(width 0.14224)
		(layer "In2.Cu")
		(net "M_D_DQ<9>")
	)
	(segment
		(start 207.671416 -131.188968)
		(end 207.901794 -131.419346)
		(width 0.14224)
		(layer "In2.Cu")
		(net "M_D_DQ<9>")
	)
	(segment
		(start 207.901794 -131.419346)
		(end 207.901794 -131.823968)
		(width 0.14224)
		(layer "In2.Cu")
		(net "M_D_DQ<9>")
	)
	(segment
		(start 207.825594 -132.6896)
		(end 207.825594 -133.1214)
		(width 0.14224)
		(layer "In2.Cu")
		(net "M_D_DQ<9>")
	)
	(segment
		(start 207.698848 -134.340346)
		(end 207.449928 -134.340346)
		(width 0.14224)
		(layer "In2.Cu")
		(net "M_D_DQ<9>")
	)
	(segment
		(start 207.611218 -133.335776)
		(end 207.611218 -133.643624)
		(width 0.14224)
		(layer "In2.Cu")
		(net "M_D_DQ<9>")
	)
	(segment
		(start 207.901794 -131.823968)
		(end 207.611218 -132.114544)
		(width 0.14224)
		(layer "In2.Cu")
		(net "M_D_DQ<9>")
	)
	(segment
		(start 207.844644 -130.330956)
		(end 207.671416 -130.504184)
		(width 0.14224)
		(layer "In2.Cu")
		(net "M_D_DQ<9>")
	)
	(segment
		(start 208.122012 -130.330956)
		(end 207.844644 -130.330956)
		(width 0.14224)
		(layer "In2.Cu")
		(net "M_D_DQ<9>")
	)
	(segment
		(start 207.611218 -132.114544)
		(end 207.611218 -132.475224)
		(width 0.14224)
		(layer "In2.Cu")
		(net "M_D_DQ<9>")
	)
	(segment
		(start 207.611218 -132.475224)
		(end 207.825594 -132.6896)
		(width 0.14224)
		(layer "In2.Cu")
		(net "M_D_DQ<9>")
	)
	(segment
		(start 207.825594 -133.1214)
		(end 207.611218 -133.335776)
		(width 0.14224)
		(layer "In2.Cu")
		(net "M_D_DQ<9>")
	)
	(segment
		(start 207.611218 -133.643624)
		(end 207.850994 -133.8834)
		(width 0.14224)
		(layer "In2.Cu")
		(net "M_D_DQ<9>")
	)
	(segment
		(start 207.850994 -134.1882)
		(end 207.698848 -134.340346)
		(width 0.14224)
		(layer "In2.Cu")
		(net "M_D_DQ<9>")
	)
	(segment
		(start 207.5434 -128.8542)
		(end 207.938116 -129.248916)
		(width 0.1651)
		(layer "F.Cu")
		(net "M_D_DQ<8>")
	)
	(segment
		(start 230.78059 -92.24264)
		(end 208.28 -114.74323)
		(width 0.1651)
		(layer "F.Cu")
		(net "M_D_DQ<8>")
	)
	(segment
		(start 208.30032 -137.67054)
		(end 208.299812 -137.676382)
		(width 0.1651)
		(layer "F.Cu")
		(net "M_D_DQ<8>")
	)
	(segment
		(start 208.28 -127.1524)
		(end 207.5434 -127.889)
		(width 0.1651)
		(layer "F.Cu")
		(net "M_D_DQ<8>")
	)
	(segment
		(start 232.464102 -92.24264)
		(end 230.78059 -92.24264)
		(width 0.1651)
		(layer "F.Cu")
		(net "M_D_DQ<8>")
	)
	(segment
		(start 207.938116 -129.248916)
		(end 207.938116 -129.710688)
		(width 0.1651)
		(layer "F.Cu")
		(net "M_D_DQ<8>")
	)
	(segment
		(start 207.449928 -130.198876)
		(end 207.449928 -131.611878)
		(width 0.1651)
		(layer "F.Cu")
		(net "M_D_DQ<8>")
	)
	(segment
		(start 208.299812 -137.676382)
		(end 208.122012 -135.8138)
		(width 0.1651)
		(layer "F.Cu")
		(net "M_D_DQ<8>")
	)
	(segment
		(start 208.28 -114.74323)
		(end 208.28 -127.1524)
		(width 0.1651)
		(layer "F.Cu")
		(net "M_D_DQ<8>")
	)
	(segment
		(start 207.5434 -127.889)
		(end 207.5434 -128.8542)
		(width 0.1651)
		(layer "F.Cu")
		(net "M_D_DQ<8>")
	)
	(segment
		(start 207.938116 -129.710688)
		(end 207.449928 -130.198876)
		(width 0.1651)
		(layer "F.Cu")
		(net "M_D_DQ<8>")
	)
	(segment
		(start 234.466638 -92.24264)
		(end 232.464102 -92.24264)
		(width 0.0889)
		(layer "F.Cu")
		(net "M_D_DQ<8>")
	)
	(via
		(at 207.449928 -131.611878)
		(size 0.508)
		(drill 0.254)
		(layers "F.Cu" "B.Cu")
		(net "M_D_DQ<8>")
	)
	(via
		(at 208.122012 -135.8138)
		(size 0.508)
		(drill 0.254)
		(layers "F.Cu" "B.Cu")
		(net "M_D_DQ<8>")
	)
	(segment
		(start 207.450436 -132.876036)
		(end 207.449928 -132.875782)
		(width 0.1651)
		(layer "B.Cu")
		(net "M_D_DQ<8>")
	)
	(segment
		(start 207.449928 -132.875782)
		(end 207.449928 -131.611878)
		(width 0.1651)
		(layer "B.Cu")
		(net "M_D_DQ<8>")
	)
	(segment
		(start 207.016858 -132.044948)
		(end 207.449928 -131.611878)
		(width 0.14224)
		(layer "In2.Cu")
		(net "M_D_DQ<8>")
	)
	(segment
		(start 208.122012 -135.8138)
		(end 207.825848 -135.8138)
		(width 0.14224)
		(layer "In2.Cu")
		(net "M_D_DQ<8>")
	)
	(segment
		(start 207.016858 -135.00481)
		(end 207.016858 -132.044948)
		(width 0.14224)
		(layer "In2.Cu")
		(net "M_D_DQ<8>")
	)
	(segment
		(start 207.825848 -135.8138)
		(end 207.016858 -135.00481)
		(width 0.14224)
		(layer "In2.Cu")
		(net "M_D_DQ<8>")
	)
	(segment
		(start 234.466638 -88.28024)
		(end 233.895138 -88.28024)
		(width 0.1651)
		(layer "F.Cu")
		(net "M_D_DQ<7>")
	)
	(segment
		(start 202.349862 -133.076442)
		(end 202.349862 -134.340346)
		(width 0.1651)
		(layer "F.Cu")
		(net "M_D_DQ<7>")
	)
	(segment
		(start 202.35037 -133.0706)
		(end 202.349862 -133.076442)
		(width 0.1651)
		(layer "F.Cu")
		(net "M_D_DQ<7>")
	)
	(via
		(at 202.349862 -134.340346)
		(size 0.508)
		(drill 0.254)
		(layers "F.Cu" "B.Cu")
		(net "M_D_DQ<7>")
	)
	(via
		(at 203.199746 -130.330956)
		(size 0.508)
		(drill 0.254)
		(layers "F.Cu" "B.Cu")
		(net "M_D_DQ<7>")
	)
	(via
		(at 233.895138 -88.28024)
		(size 0.508)
		(drill 0.254)
		(layers "F.Cu" "B.Cu")
		(net "M_D_DQ<7>")
	)
	(segment
		(start 203.199746 -128.276096)
		(end 203.199746 -130.330956)
		(width 0.1651)
		(layer "B.Cu")
		(net "M_D_DQ<7>")
	)
	(segment
		(start 203.200508 -128.276096)
		(end 203.199746 -128.276096)
		(width 0.1651)
		(layer "B.Cu")
		(net "M_D_DQ<7>")
	)
	(segment
		(start 205.3336 -123.7234)
		(end 204.9272 -123.7234)
		(width 0.14224)
		(layer "In2.Cu")
		(net "M_D_DQ<7>")
	)
	(segment
		(start 232.313734 -88.802464)
		(end 230.871268 -88.802464)
		(width 0.0889)
		(layer "In2.Cu")
		(net "M_D_DQ<7>")
	)
	(segment
		(start 203.54163 -129.989072)
		(end 203.199746 -130.330956)
		(width 0.14224)
		(layer "In2.Cu")
		(net "M_D_DQ<7>")
	)
	(segment
		(start 202.62215 -134.340346)
		(end 202.349862 -134.340346)
		(width 0.14224)
		(layer "In2.Cu")
		(net "M_D_DQ<7>")
	)
	(segment
		(start 203.9366 -128.8796)
		(end 203.552552 -129.263648)
		(width 0.14224)
		(layer "In2.Cu")
		(net "M_D_DQ<7>")
	)
	(segment
		(start 202.7936 -131.233418)
		(end 202.7936 -131.9022)
		(width 0.14224)
		(layer "In2.Cu")
		(net "M_D_DQ<7>")
	)
	(segment
		(start 202.511152 -133.550152)
		(end 202.79995 -133.83895)
		(width 0.14224)
		(layer "In2.Cu")
		(net "M_D_DQ<7>")
	)
	(segment
		(start 205.5622 -114.8842)
		(end 205.5622 -123.4948)
		(width 0.14224)
		(layer "In2.Cu")
		(net "M_D_DQ<7>")
	)
	(segment
		(start 202.74915 -131.188968)
		(end 202.7936 -131.233418)
		(width 0.14224)
		(layer "In2.Cu")
		(net "M_D_DQ<7>")
	)
	(segment
		(start 218.821 -101.6254)
		(end 205.5622 -114.8842)
		(width 0.14224)
		(layer "In2.Cu")
		(net "M_D_DQ<7>")
	)
	(segment
		(start 204.9272 -123.7234)
		(end 204.7494 -123.5456)
		(width 0.14224)
		(layer "In2.Cu")
		(net "M_D_DQ<7>")
	)
	(segment
		(start 204.7494 -119.853202)
		(end 204.5462 -119.650002)
		(width 0.14224)
		(layer "In2.Cu")
		(net "M_D_DQ<7>")
	)
	(segment
		(start 202.511152 -133.276848)
		(end 202.511152 -133.550152)
		(width 0.14224)
		(layer "In2.Cu")
		(net "M_D_DQ<7>")
	)
	(segment
		(start 203.199746 -130.330956)
		(end 203.177394 -130.330956)
		(width 0.14224)
		(layer "In2.Cu")
		(net "M_D_DQ<7>")
	)
	(segment
		(start 202.7682 -132.715)
		(end 202.7682 -133.0198)
		(width 0.14224)
		(layer "In2.Cu")
		(net "M_D_DQ<7>")
	)
	(segment
		(start 204.1398 -119.650002)
		(end 203.9366 -119.853202)
		(width 0.14224)
		(layer "In2.Cu")
		(net "M_D_DQ<7>")
	)
	(segment
		(start 230.871268 -88.802464)
		(end 230.033068 -88.802464)
		(width 0.14224)
		(layer "In2.Cu")
		(net "M_D_DQ<7>")
	)
	(segment
		(start 202.7682 -133.0198)
		(end 202.511152 -133.276848)
		(width 0.14224)
		(layer "In2.Cu")
		(net "M_D_DQ<7>")
	)
	(segment
		(start 205.5622 -123.4948)
		(end 205.3336 -123.7234)
		(width 0.14224)
		(layer "In2.Cu")
		(net "M_D_DQ<7>")
	)
	(segment
		(start 233.895138 -88.28024)
		(end 232.835958 -88.28024)
		(width 0.0889)
		(layer "In2.Cu")
		(net "M_D_DQ<7>")
	)
	(segment
		(start 230.033068 -88.802464)
		(end 218.821 -100.014532)
		(width 0.14224)
		(layer "In2.Cu")
		(net "M_D_DQ<7>")
	)
	(segment
		(start 202.7936 -131.9022)
		(end 202.511152 -132.184648)
		(width 0.14224)
		(layer "In2.Cu")
		(net "M_D_DQ<7>")
	)
	(segment
		(start 203.9366 -119.853202)
		(end 203.9366 -128.8796)
		(width 0.14224)
		(layer "In2.Cu")
		(net "M_D_DQ<7>")
	)
	(segment
		(start 202.79995 -133.83895)
		(end 202.79995 -134.162546)
		(width 0.14224)
		(layer "In2.Cu")
		(net "M_D_DQ<7>")
	)
	(segment
		(start 204.7494 -123.5456)
		(end 204.7494 -119.853202)
		(width 0.14224)
		(layer "In2.Cu")
		(net "M_D_DQ<7>")
	)
	(segment
		(start 202.79995 -134.162546)
		(end 202.62215 -134.340346)
		(width 0.14224)
		(layer "In2.Cu")
		(net "M_D_DQ<7>")
	)
	(segment
		(start 202.74915 -130.7592)
		(end 202.74915 -131.188968)
		(width 0.14224)
		(layer "In2.Cu")
		(net "M_D_DQ<7>")
	)
	(segment
		(start 203.177394 -130.330956)
		(end 202.74915 -130.7592)
		(width 0.14224)
		(layer "In2.Cu")
		(net "M_D_DQ<7>")
	)
	(segment
		(start 202.511152 -132.184648)
		(end 202.511152 -132.457952)
		(width 0.14224)
		(layer "In2.Cu")
		(net "M_D_DQ<7>")
	)
	(segment
		(start 218.821 -100.014532)
		(end 218.821 -101.6254)
		(width 0.14224)
		(layer "In2.Cu")
		(net "M_D_DQ<7>")
	)
	(segment
		(start 202.511152 -132.457952)
		(end 202.7682 -132.715)
		(width 0.14224)
		(layer "In2.Cu")
		(net "M_D_DQ<7>")
	)
	(segment
		(start 204.5462 -119.650002)
		(end 204.1398 -119.650002)
		(width 0.14224)
		(layer "In2.Cu")
		(net "M_D_DQ<7>")
	)
	(segment
		(start 203.552552 -129.989072)
		(end 203.54163 -129.989072)
		(width 0.14224)
		(layer "In2.Cu")
		(net "M_D_DQ<7>")
	)
	(segment
		(start 232.835958 -88.28024)
		(end 232.313734 -88.802464)
		(width 0.0889)
		(layer "In2.Cu")
		(net "M_D_DQ<7>")
	)
	(segment
		(start 203.552552 -129.263648)
		(end 203.552552 -129.989072)
		(width 0.14224)
		(layer "In2.Cu")
		(net "M_D_DQ<7>")
	)
	(segment
		(start 232.749598 -88.28024)
		(end 232.101898 -88.28024)
		(width 0.1651)
		(layer "F.Cu")
		(net "M_D_DQ<6>")
	)
	(segment
		(start 203.2 -136.2202)
		(end 203.2 -135.915654)
		(width 0.1651)
		(layer "F.Cu")
		(net "M_D_DQ<6>")
	)
	(segment
		(start 203.33208 -136.57072)
		(end 203.33208 -136.35228)
		(width 0.1651)
		(layer "F.Cu")
		(net "M_D_DQ<6>")
	)
	(segment
		(start 203.2 -136.7028)
		(end 203.33208 -136.57072)
		(width 0.1651)
		(layer "F.Cu")
		(net "M_D_DQ<6>")
	)
	(segment
		(start 203.2 -137.67054)
		(end 203.2 -136.7028)
		(width 0.1651)
		(layer "F.Cu")
		(net "M_D_DQ<6>")
	)
	(segment
		(start 203.2 -135.915654)
		(end 203.199746 -135.9154)
		(width 0.1651)
		(layer "F.Cu")
		(net "M_D_DQ<6>")
	)
	(segment
		(start 203.33208 -136.35228)
		(end 203.2 -136.2202)
		(width 0.1651)
		(layer "F.Cu")
		(net "M_D_DQ<6>")
	)
	(segment
		(start 203.200508 -137.67054)
		(end 203.2 -137.67054)
		(width 0.1651)
		(layer "F.Cu")
		(net "M_D_DQ<6>")
	)
	(via
		(at 232.101898 -88.28024)
		(size 0.508)
		(drill 0.254)
		(layers "F.Cu" "B.Cu")
		(net "M_D_DQ<6>")
	)
	(via
		(at 202.349862 -131.611878)
		(size 0.508)
		(drill 0.254)
		(layers "F.Cu" "B.Cu")
		(net "M_D_DQ<6>")
	)
	(via
		(at 203.199746 -135.9154)
		(size 0.508)
		(drill 0.254)
		(layers "F.Cu" "B.Cu")
		(net "M_D_DQ<6>")
	)
	(segment
		(start 202.349862 -132.875782)
		(end 202.349862 -131.611878)
		(width 0.1651)
		(layer "B.Cu")
		(net "M_D_DQ<6>")
	)
	(segment
		(start 202.35037 -132.876036)
		(end 202.349862 -132.875782)
		(width 0.1651)
		(layer "B.Cu")
		(net "M_D_DQ<6>")
	)
	(segment
		(start 201.916792 -132.044948)
		(end 201.916792 -134.632446)
		(width 0.14224)
		(layer "In2.Cu")
		(net "M_D_DQ<6>")
	)
	(segment
		(start 203.3016 -128.6002)
		(end 202.917552 -128.984248)
		(width 0.14224)
		(layer "In2.Cu")
		(net "M_D_DQ<6>")
	)
	(segment
		(start 229.878128 -88.28024)
		(end 218.3384 -99.819968)
		(width 0.14224)
		(layer "In2.Cu")
		(net "M_D_DQ<6>")
	)
	(segment
		(start 202.917552 -129.732278)
		(end 202.180952 -130.468878)
		(width 0.14224)
		(layer "In2.Cu")
		(net "M_D_DQ<6>")
	)
	(segment
		(start 204.724 -119.09298)
		(end 204.3176 -119.09298)
		(width 0.14224)
		(layer "In2.Cu")
		(net "M_D_DQ<6>")
	)
	(segment
		(start 218.3384 -101.4222)
		(end 204.9272 -114.8334)
		(width 0.14224)
		(layer "In2.Cu")
		(net "M_D_DQ<6>")
	)
	(segment
		(start 201.916792 -134.632446)
		(end 203.199746 -135.9154)
		(width 0.14224)
		(layer "In2.Cu")
		(net "M_D_DQ<6>")
	)
	(segment
		(start 204.9272 -114.8334)
		(end 204.9272 -118.88978)
		(width 0.14224)
		(layer "In2.Cu")
		(net "M_D_DQ<6>")
	)
	(segment
		(start 203.3016 -115.75542)
		(end 203.3016 -128.6002)
		(width 0.14224)
		(layer "In2.Cu")
		(net "M_D_DQ<6>")
	)
	(segment
		(start 218.3384 -99.819968)
		(end 218.3384 -101.4222)
		(width 0.14224)
		(layer "In2.Cu")
		(net "M_D_DQ<6>")
	)
	(segment
		(start 204.9272 -118.88978)
		(end 204.724 -119.09298)
		(width 0.14224)
		(layer "In2.Cu")
		(net "M_D_DQ<6>")
	)
	(segment
		(start 204.1144 -115.742212)
		(end 203.917804 -115.545616)
		(width 0.14224)
		(layer "In2.Cu")
		(net "M_D_DQ<6>")
	)
	(segment
		(start 204.3176 -119.09298)
		(end 204.1144 -118.88978)
		(width 0.14224)
		(layer "In2.Cu")
		(net "M_D_DQ<6>")
	)
	(segment
		(start 230.871268 -88.28024)
		(end 229.878128 -88.28024)
		(width 0.14224)
		(layer "In2.Cu")
		(net "M_D_DQ<6>")
	)
	(segment
		(start 203.511404 -115.545616)
		(end 203.3016 -115.75542)
		(width 0.14224)
		(layer "In2.Cu")
		(net "M_D_DQ<6>")
	)
	(segment
		(start 202.180952 -131.442968)
		(end 202.349862 -131.611878)
		(width 0.14224)
		(layer "In2.Cu")
		(net "M_D_DQ<6>")
	)
	(segment
		(start 232.101898 -88.28024)
		(end 230.871268 -88.28024)
		(width 0.0889)
		(layer "In2.Cu")
		(net "M_D_DQ<6>")
	)
	(segment
		(start 202.180952 -130.468878)
		(end 202.180952 -131.442968)
		(width 0.14224)
		(layer "In2.Cu")
		(net "M_D_DQ<6>")
	)
	(segment
		(start 202.917552 -128.984248)
		(end 202.917552 -129.732278)
		(width 0.14224)
		(layer "In2.Cu")
		(net "M_D_DQ<6>")
	)
	(segment
		(start 203.917804 -115.545616)
		(end 203.511404 -115.545616)
		(width 0.14224)
		(layer "In2.Cu")
		(net "M_D_DQ<6>")
	)
	(segment
		(start 202.349862 -131.611878)
		(end 201.916792 -132.044948)
		(width 0.14224)
		(layer "In2.Cu")
		(net "M_D_DQ<6>")
	)
	(segment
		(start 204.1144 -118.88978)
		(end 204.1144 -115.742212)
		(width 0.14224)
		(layer "In2.Cu")
		(net "M_D_DQ<6>")
	)
	(segment
		(start 313.699906 -133.076442)
		(end 313.699906 -134.340346)
		(width 0.1651)
		(layer "F.Cu")
		(net "M_D_DQ<63>")
	)
	(segment
		(start 313.700414 -133.0706)
		(end 313.699906 -133.076442)
		(width 0.1651)
		(layer "F.Cu")
		(net "M_D_DQ<63>")
	)
	(segment
		(start 289.22218 -99.986338)
		(end 289.79368 -99.986338)
		(width 0.1651)
		(layer "F.Cu")
		(net "M_D_DQ<63>")
	)
	(via
		(at 314.54979 -130.330956)
		(size 0.508)
		(drill 0.254)
		(layers "F.Cu" "B.Cu")
		(net "M_D_DQ<63>")
	)
	(via
		(at 313.699906 -134.340346)
		(size 0.508)
		(drill 0.254)
		(layers "F.Cu" "B.Cu")
		(net "M_D_DQ<63>")
	)
	(via
		(at 289.79368 -99.986338)
		(size 0.508)
		(drill 0.254)
		(layers "F.Cu" "B.Cu")
		(net "M_D_DQ<63>")
	)
	(segment
		(start 314.550298 -128.276096)
		(end 314.54979 -128.276096)
		(width 0.1651)
		(layer "B.Cu")
		(net "M_D_DQ<63>")
	)
	(segment
		(start 314.54979 -128.276096)
		(end 314.54979 -130.330956)
		(width 0.1651)
		(layer "B.Cu")
		(net "M_D_DQ<63>")
	)
	(segment
		(start 315.702442 -122.43689)
		(end 315.499242 -122.64009)
		(width 0.14224)
		(layer "In2.Cu")
		(net "M_D_DQ<63>")
	)
	(segment
		(start 310.046878 -113.330736)
		(end 310.309006 -113.068862)
		(width 0.14224)
		(layer "In2.Cu")
		(net "M_D_DQ<63>")
	)
	(segment
		(start 290.305998 -102.054152)
		(end 290.305998 -102.448106)
		(width 0.0889)
		(layer "In2.Cu")
		(net "M_D_DQ<63>")
	)
	(segment
		(start 313.861196 -132.457952)
		(end 314.118244 -132.715)
		(width 0.14224)
		(layer "In2.Cu")
		(net "M_D_DQ<63>")
	)
	(segment
		(start 300.219872 -106.2228)
		(end 302.719994 -106.2228)
		(width 0.14224)
		(layer "In2.Cu")
		(net "M_D_DQ<63>")
	)
	(segment
		(start 314.118244 -132.715)
		(end 314.118244 -133.0198)
		(width 0.14224)
		(layer "In2.Cu")
		(net "M_D_DQ<63>")
	)
	(segment
		(start 290.305998 -102.448106)
		(end 291.350192 -103.4923)
		(width 0.0889)
		(layer "In2.Cu")
		(net "M_D_DQ<63>")
	)
	(segment
		(start 314.891674 -129.989072)
		(end 314.54979 -130.330956)
		(width 0.14224)
		(layer "In2.Cu")
		(net "M_D_DQ<63>")
	)
	(segment
		(start 294.5384 -103.4923)
		(end 296.3672 -105.3211)
		(width 0.0889)
		(layer "In2.Cu")
		(net "M_D_DQ<63>")
	)
	(segment
		(start 297.6372 -105.3211)
		(end 297.7769 -105.1814)
		(width 0.0889)
		(layer "In2.Cu")
		(net "M_D_DQ<63>")
	)
	(segment
		(start 313.861196 -132.184648)
		(end 313.861196 -132.457952)
		(width 0.14224)
		(layer "In2.Cu")
		(net "M_D_DQ<63>")
	)
	(segment
		(start 310.309006 -113.068862)
		(end 310.527954 -113.068862)
		(width 0.14224)
		(layer "In2.Cu")
		(net "M_D_DQ<63>")
	)
	(segment
		(start 313.861196 -133.550152)
		(end 314.149994 -133.83895)
		(width 0.14224)
		(layer "In2.Cu")
		(net "M_D_DQ<63>")
	)
	(segment
		(start 314.149994 -134.162546)
		(end 313.972194 -134.340346)
		(width 0.14224)
		(layer "In2.Cu")
		(net "M_D_DQ<63>")
	)
	(segment
		(start 310.62168 -113.905538)
		(end 310.62168 -114.124486)
		(width 0.14224)
		(layer "In2.Cu")
		(net "M_D_DQ<63>")
	)
	(segment
		(start 291.350192 -103.4923)
		(end 294.5384 -103.4923)
		(width 0.0889)
		(layer "In2.Cu")
		(net "M_D_DQ<63>")
	)
	(segment
		(start 289.79368 -99.986338)
		(end 290.011104 -100.533454)
		(width 0.0889)
		(layer "In2.Cu")
		(net "M_D_DQ<63>")
	)
	(segment
		(start 314.902596 -129.368804)
		(end 314.902596 -129.989072)
		(width 0.14224)
		(layer "In2.Cu")
		(net "M_D_DQ<63>")
	)
	(segment
		(start 290.14039 -101.767386)
		(end 290.305998 -102.054152)
		(width 0.0889)
		(layer "In2.Cu")
		(net "M_D_DQ<63>")
	)
	(segment
		(start 315.5442 -124.353574)
		(end 315.5442 -128.7272)
		(width 0.14224)
		(layer "In2.Cu")
		(net "M_D_DQ<63>")
	)
	(segment
		(start 314.118244 -133.0198)
		(end 313.861196 -133.276848)
		(width 0.14224)
		(layer "In2.Cu")
		(net "M_D_DQ<63>")
	)
	(segment
		(start 316.72911 -123.540774)
		(end 316.72911 -123.947174)
		(width 0.14224)
		(layer "In2.Cu")
		(net "M_D_DQ<63>")
	)
	(segment
		(start 310.527954 -113.068862)
		(end 310.883808 -113.424716)
		(width 0.14224)
		(layer "In2.Cu")
		(net "M_D_DQ<63>")
	)
	(segment
		(start 297.7769 -105.1814)
		(end 299.178472 -105.1814)
		(width 0.14224)
		(layer "In2.Cu")
		(net "M_D_DQ<63>")
	)
	(segment
		(start 315.702442 -123.337574)
		(end 316.52591 -123.337574)
		(width 0.14224)
		(layer "In2.Cu")
		(net "M_D_DQ<63>")
	)
	(segment
		(start 317.1698 -119.285258)
		(end 317.1698 -122.194066)
		(width 0.14224)
		(layer "In2.Cu")
		(net "M_D_DQ<63>")
	)
	(segment
		(start 315.499242 -123.134374)
		(end 315.702442 -123.337574)
		(width 0.14224)
		(layer "In2.Cu")
		(net "M_D_DQ<63>")
	)
	(segment
		(start 314.527438 -130.330956)
		(end 314.099194 -130.7592)
		(width 0.14224)
		(layer "In2.Cu")
		(net "M_D_DQ<63>")
	)
	(segment
		(start 315.7474 -124.150374)
		(end 315.5442 -124.353574)
		(width 0.14224)
		(layer "In2.Cu")
		(net "M_D_DQ<63>")
	)
	(segment
		(start 310.883808 -113.424716)
		(end 310.883808 -113.643664)
		(width 0.14224)
		(layer "In2.Cu")
		(net "M_D_DQ<63>")
	)
	(segment
		(start 309.82793 -113.330736)
		(end 310.046878 -113.330736)
		(width 0.14224)
		(layer "In2.Cu")
		(net "M_D_DQ<63>")
	)
	(segment
		(start 314.149994 -133.83895)
		(end 314.149994 -134.162546)
		(width 0.14224)
		(layer "In2.Cu")
		(net "M_D_DQ<63>")
	)
	(segment
		(start 316.926976 -122.43689)
		(end 315.702442 -122.43689)
		(width 0.14224)
		(layer "In2.Cu")
		(net "M_D_DQ<63>")
	)
	(segment
		(start 316.72911 -123.947174)
		(end 316.52591 -124.150374)
		(width 0.14224)
		(layer "In2.Cu")
		(net "M_D_DQ<63>")
	)
	(segment
		(start 310.62168 -114.124486)
		(end 310.77281 -114.275616)
		(width 0.14224)
		(layer "In2.Cu")
		(net "M_D_DQ<63>")
	)
	(segment
		(start 296.3672 -105.3211)
		(end 297.6372 -105.3211)
		(width 0.0889)
		(layer "In2.Cu")
		(net "M_D_DQ<63>")
	)
	(segment
		(start 312.160158 -114.275616)
		(end 317.1698 -119.285258)
		(width 0.14224)
		(layer "In2.Cu")
		(net "M_D_DQ<63>")
	)
	(segment
		(start 316.52591 -123.337574)
		(end 316.72911 -123.540774)
		(width 0.14224)
		(layer "In2.Cu")
		(net "M_D_DQ<63>")
	)
	(segment
		(start 310.883808 -113.643664)
		(end 310.62168 -113.905538)
		(width 0.14224)
		(layer "In2.Cu")
		(net "M_D_DQ<63>")
	)
	(segment
		(start 310.77281 -114.275616)
		(end 312.160158 -114.275616)
		(width 0.14224)
		(layer "In2.Cu")
		(net "M_D_DQ<63>")
	)
	(segment
		(start 290.011104 -100.533454)
		(end 290.14039 -100.776786)
		(width 0.0889)
		(layer "In2.Cu")
		(net "M_D_DQ<63>")
	)
	(segment
		(start 314.54979 -130.330956)
		(end 314.527438 -130.330956)
		(width 0.14224)
		(layer "In2.Cu")
		(net "M_D_DQ<63>")
	)
	(segment
		(start 315.5442 -128.7272)
		(end 314.902596 -129.368804)
		(width 0.14224)
		(layer "In2.Cu")
		(net "M_D_DQ<63>")
	)
	(segment
		(start 313.861196 -133.276848)
		(end 313.861196 -133.550152)
		(width 0.14224)
		(layer "In2.Cu")
		(net "M_D_DQ<63>")
	)
	(segment
		(start 316.52591 -124.150374)
		(end 315.7474 -124.150374)
		(width 0.14224)
		(layer "In2.Cu")
		(net "M_D_DQ<63>")
	)
	(segment
		(start 314.099194 -130.7592)
		(end 314.099194 -131.188968)
		(width 0.14224)
		(layer "In2.Cu")
		(net "M_D_DQ<63>")
	)
	(segment
		(start 313.972194 -134.340346)
		(end 313.699906 -134.340346)
		(width 0.14224)
		(layer "In2.Cu")
		(net "M_D_DQ<63>")
	)
	(segment
		(start 314.143644 -131.233418)
		(end 314.143644 -131.9022)
		(width 0.14224)
		(layer "In2.Cu")
		(net "M_D_DQ<63>")
	)
	(segment
		(start 315.499242 -122.64009)
		(end 315.499242 -123.134374)
		(width 0.14224)
		(layer "In2.Cu")
		(net "M_D_DQ<63>")
	)
	(segment
		(start 299.178472 -105.1814)
		(end 300.219872 -106.2228)
		(width 0.14224)
		(layer "In2.Cu")
		(net "M_D_DQ<63>")
	)
	(segment
		(start 317.1698 -122.194066)
		(end 316.926976 -122.43689)
		(width 0.14224)
		(layer "In2.Cu")
		(net "M_D_DQ<63>")
	)
	(segment
		(start 314.902596 -129.989072)
		(end 314.891674 -129.989072)
		(width 0.14224)
		(layer "In2.Cu")
		(net "M_D_DQ<63>")
	)
	(segment
		(start 314.099194 -131.188968)
		(end 314.143644 -131.233418)
		(width 0.14224)
		(layer "In2.Cu")
		(net "M_D_DQ<63>")
	)
	(segment
		(start 314.143644 -131.9022)
		(end 313.861196 -132.184648)
		(width 0.14224)
		(layer "In2.Cu")
		(net "M_D_DQ<63>")
	)
	(segment
		(start 302.719994 -106.2228)
		(end 309.82793 -113.330736)
		(width 0.14224)
		(layer "In2.Cu")
		(net "M_D_DQ<63>")
	)
	(arc
		(start 290.14039 -101.176582)
		(mid 290.061259 -101.471984)
		(end 290.14039 -101.767386)
		(width 0.0889)
		(layer "In2.Cu")
		(net "M_D_DQ<63>")
	)
	(arc
		(start 290.14039 -100.776786)
		(mid 290.193889 -100.976684)
		(end 290.14039 -101.176582)
		(width 0.0889)
		(layer "In2.Cu")
		(net "M_D_DQ<63>")
	)
	(segment
		(start 314.550044 -136.2202)
		(end 314.550044 -135.915654)
		(width 0.1651)
		(layer "F.Cu")
		(net "M_D_DQ<62>")
	)
	(segment
		(start 314.550298 -137.67054)
		(end 314.550044 -137.67054)
		(width 0.1651)
		(layer "F.Cu")
		(net "M_D_DQ<62>")
	)
	(segment
		(start 314.682124 -136.35228)
		(end 314.550044 -136.2202)
		(width 0.1651)
		(layer "F.Cu")
		(net "M_D_DQ<62>")
	)
	(segment
		(start 289.22218 -101.967538)
		(end 289.79368 -101.967538)
		(width 0.1651)
		(layer "F.Cu")
		(net "M_D_DQ<62>")
	)
	(segment
		(start 314.550044 -135.915654)
		(end 314.54979 -135.9154)
		(width 0.1651)
		(layer "F.Cu")
		(net "M_D_DQ<62>")
	)
	(segment
		(start 314.682124 -136.57072)
		(end 314.682124 -136.35228)
		(width 0.1651)
		(layer "F.Cu")
		(net "M_D_DQ<62>")
	)
	(segment
		(start 314.550044 -137.67054)
		(end 314.550044 -136.7028)
		(width 0.1651)
		(layer "F.Cu")
		(net "M_D_DQ<62>")
	)
	(segment
		(start 314.550044 -136.7028)
		(end 314.682124 -136.57072)
		(width 0.1651)
		(layer "F.Cu")
		(net "M_D_DQ<62>")
	)
	(via
		(at 314.54979 -135.9154)
		(size 0.508)
		(drill 0.254)
		(layers "F.Cu" "B.Cu")
		(net "M_D_DQ<62>")
	)
	(via
		(at 313.699906 -131.611878)
		(size 0.508)
		(drill 0.254)
		(layers "F.Cu" "B.Cu")
		(net "M_D_DQ<62>")
	)
	(via
		(at 289.79368 -101.967538)
		(size 0.508)
		(drill 0.254)
		(layers "F.Cu" "B.Cu")
		(net "M_D_DQ<62>")
	)
	(segment
		(start 313.700414 -132.876036)
		(end 313.699906 -132.875782)
		(width 0.1651)
		(layer "B.Cu")
		(net "M_D_DQ<62>")
	)
	(segment
		(start 313.699906 -132.875782)
		(end 313.699906 -131.611878)
		(width 0.1651)
		(layer "B.Cu")
		(net "M_D_DQ<62>")
	)
	(segment
		(start 311.897014 -114.910616)
		(end 316.5348 -119.548402)
		(width 0.14224)
		(layer "In2.Cu")
		(net "M_D_DQ<62>")
	)
	(segment
		(start 314.9092 -128.507744)
		(end 314.267596 -129.149348)
		(width 0.14224)
		(layer "In2.Cu")
		(net "M_D_DQ<62>")
	)
	(segment
		(start 314.9092 -120.156478)
		(end 314.9092 -128.507744)
		(width 0.14224)
		(layer "In2.Cu")
		(net "M_D_DQ<62>")
	)
	(segment
		(start 297.6372 -105.5116)
		(end 297.7896 -105.664)
		(width 0.0889)
		(layer "In2.Cu")
		(net "M_D_DQ<62>")
	)
	(segment
		(start 315.529976 -119.942102)
		(end 315.123576 -119.942102)
		(width 0.14224)
		(layer "In2.Cu")
		(net "M_D_DQ<62>")
	)
	(segment
		(start 290.115498 -102.527354)
		(end 291.270944 -103.6828)
		(width 0.0889)
		(layer "In2.Cu")
		(net "M_D_DQ<62>")
	)
	(segment
		(start 315.123576 -119.942102)
		(end 314.9092 -120.156478)
		(width 0.14224)
		(layer "In2.Cu")
		(net "M_D_DQ<62>")
	)
	(segment
		(start 315.936376 -121.80951)
		(end 315.722 -121.595134)
		(width 0.14224)
		(layer "In2.Cu")
		(net "M_D_DQ<62>")
	)
	(segment
		(start 316.5348 -121.617486)
		(end 316.342776 -121.80951)
		(width 0.14224)
		(layer "In2.Cu")
		(net "M_D_DQ<62>")
	)
	(segment
		(start 313.530996 -131.442968)
		(end 313.699906 -131.611878)
		(width 0.14224)
		(layer "In2.Cu")
		(net "M_D_DQ<62>")
	)
	(segment
		(start 313.699906 -131.611878)
		(end 313.266836 -132.044948)
		(width 0.14224)
		(layer "In2.Cu")
		(net "M_D_DQ<62>")
	)
	(segment
		(start 313.266836 -134.632446)
		(end 314.54979 -135.9154)
		(width 0.14224)
		(layer "In2.Cu")
		(net "M_D_DQ<62>")
	)
	(segment
		(start 296.287952 -105.5116)
		(end 297.6372 -105.5116)
		(width 0.0889)
		(layer "In2.Cu")
		(net "M_D_DQ<62>")
	)
	(segment
		(start 302.285146 -106.7054)
		(end 310.490362 -114.910616)
		(width 0.14224)
		(layer "In2.Cu")
		(net "M_D_DQ<62>")
	)
	(segment
		(start 313.530996 -130.468878)
		(end 313.530996 -131.442968)
		(width 0.14224)
		(layer "In2.Cu")
		(net "M_D_DQ<62>")
	)
	(segment
		(start 298.983908 -105.664)
		(end 300.025308 -106.7054)
		(width 0.14224)
		(layer "In2.Cu")
		(net "M_D_DQ<62>")
	)
	(segment
		(start 316.342776 -121.80951)
		(end 315.936376 -121.80951)
		(width 0.14224)
		(layer "In2.Cu")
		(net "M_D_DQ<62>")
	)
	(segment
		(start 291.270944 -103.6828)
		(end 294.459152 -103.6828)
		(width 0.0889)
		(layer "In2.Cu")
		(net "M_D_DQ<62>")
	)
	(segment
		(start 289.79368 -101.967538)
		(end 290.115498 -102.289356)
		(width 0.0889)
		(layer "In2.Cu")
		(net "M_D_DQ<62>")
	)
	(segment
		(start 310.490362 -114.910616)
		(end 311.897014 -114.910616)
		(width 0.14224)
		(layer "In2.Cu")
		(net "M_D_DQ<62>")
	)
	(segment
		(start 290.115498 -102.289356)
		(end 290.115498 -102.527354)
		(width 0.0889)
		(layer "In2.Cu")
		(net "M_D_DQ<62>")
	)
	(segment
		(start 300.025308 -106.7054)
		(end 302.285146 -106.7054)
		(width 0.14224)
		(layer "In2.Cu")
		(net "M_D_DQ<62>")
	)
	(segment
		(start 314.267596 -129.732278)
		(end 313.530996 -130.468878)
		(width 0.14224)
		(layer "In2.Cu")
		(net "M_D_DQ<62>")
	)
	(segment
		(start 314.267596 -129.149348)
		(end 314.267596 -129.732278)
		(width 0.14224)
		(layer "In2.Cu")
		(net "M_D_DQ<62>")
	)
	(segment
		(start 315.722 -120.134126)
		(end 315.529976 -119.942102)
		(width 0.14224)
		(layer "In2.Cu")
		(net "M_D_DQ<62>")
	)
	(segment
		(start 316.5348 -119.548402)
		(end 316.5348 -121.617486)
		(width 0.14224)
		(layer "In2.Cu")
		(net "M_D_DQ<62>")
	)
	(segment
		(start 315.722 -121.595134)
		(end 315.722 -120.134126)
		(width 0.14224)
		(layer "In2.Cu")
		(net "M_D_DQ<62>")
	)
	(segment
		(start 297.7896 -105.664)
		(end 298.983908 -105.664)
		(width 0.14224)
		(layer "In2.Cu")
		(net "M_D_DQ<62>")
	)
	(segment
		(start 294.459152 -103.6828)
		(end 296.287952 -105.5116)
		(width 0.0889)
		(layer "In2.Cu")
		(net "M_D_DQ<62>")
	)
	(segment
		(start 313.266836 -132.044948)
		(end 313.266836 -134.632446)
		(width 0.14224)
		(layer "In2.Cu")
		(net "M_D_DQ<62>")
	)
	(segment
		(start 307.750464 -133.0706)
		(end 307.749956 -133.076442)
		(width 0.1651)
		(layer "F.Cu")
		(net "M_D_DQ<61>")
	)
	(segment
		(start 307.749956 -133.076442)
		(end 307.749956 -134.340346)
		(width 0.1651)
		(layer "F.Cu")
		(net "M_D_DQ<61>")
	)
	(segment
		(start 287.21812 -98.500184)
		(end 286.64662 -98.500184)
		(width 0.1651)
		(layer "F.Cu")
		(net "M_D_DQ<61>")
	)
	(via
		(at 287.21812 -98.500184)
		(size 0.508)
		(drill 0.254)
		(layers "F.Cu" "B.Cu")
		(net "M_D_DQ<61>")
	)
	(via
		(at 308.577996 -130.244596)
		(size 0.508)
		(drill 0.254)
		(layers "F.Cu" "B.Cu")
		(net "M_D_DQ<61>")
	)
	(via
		(at 307.749956 -134.340346)
		(size 0.508)
		(drill 0.254)
		(layers "F.Cu" "B.Cu")
		(net "M_D_DQ<61>")
	)
	(segment
		(start 308.600348 -128.276096)
		(end 308.59984 -128.276096)
		(width 0.1651)
		(layer "B.Cu")
		(net "M_D_DQ<61>")
	)
	(segment
		(start 308.59984 -130.222752)
		(end 308.577996 -130.244596)
		(width 0.1651)
		(layer "B.Cu")
		(net "M_D_DQ<61>")
	)
	(segment
		(start 308.59984 -128.276096)
		(end 308.59984 -130.222752)
		(width 0.1651)
		(layer "B.Cu")
		(net "M_D_DQ<61>")
	)
	(segment
		(start 307.911246 -132.216144)
		(end 307.911246 -132.553456)
		(width 0.14224)
		(layer "In2.Cu")
		(net "M_D_DQ<61>")
	)
	(segment
		(start 307.911246 -132.553456)
		(end 308.1274 -132.76961)
		(width 0.14224)
		(layer "In2.Cu")
		(net "M_D_DQ<61>")
	)
	(segment
		(start 310.635396 -120.583706)
		(end 310.635396 -122.936)
		(width 0.14224)
		(layer "In2.Cu")
		(net "M_D_DQ<61>")
	)
	(segment
		(start 301.582836 -111.531146)
		(end 301.582836 -111.945928)
		(width 0.14224)
		(layer "In2.Cu")
		(net "M_D_DQ<61>")
	)
	(segment
		(start 300.433232 -110.796324)
		(end 300.80077 -111.163862)
		(width 0.14224)
		(layer "In2.Cu")
		(net "M_D_DQ<61>")
	)
	(segment
		(start 287.08477 -102.385876)
		(end 286.953198 -102.517448)
		(width 0.0889)
		(layer "In2.Cu")
		(net "M_D_DQ<61>")
	)
	(segment
		(start 302.73244 -112.68075)
		(end 302.73244 -113.095532)
		(width 0.14224)
		(layer "In2.Cu")
		(net "M_D_DQ<61>")
	)
	(segment
		(start 286.87776 -100.270818)
		(end 286.87141 -100.281486)
		(width 0.0889)
		(layer "In2.Cu")
		(net "M_D_DQ<61>")
	)
	(segment
		(start 307.911246 -133.384544)
		(end 307.911246 -133.696456)
		(width 0.14224)
		(layer "In2.Cu")
		(net "M_D_DQ<61>")
	)
	(segment
		(start 306.963572 -116.911882)
		(end 307.330856 -117.279166)
		(width 0.14224)
		(layer "In2.Cu")
		(net "M_D_DQ<61>")
	)
	(segment
		(start 286.87776 -99.280218)
		(end 286.87141 -99.290886)
		(width 0.0889)
		(layer "In2.Cu")
		(net "M_D_DQ<61>")
	)
	(segment
		(start 294.682418 -109.7788)
		(end 299.83049 -109.7788)
		(width 0.14224)
		(layer "In2.Cu")
		(net "M_D_DQ<61>")
	)
	(segment
		(start 290.3982 -107.1753)
		(end 291.73551 -108.51261)
		(width 0.14224)
		(layer "In2.Cu")
		(net "M_D_DQ<61>")
	)
	(segment
		(start 290.068 -107.1753)
		(end 290.3982 -107.1753)
		(width 0.0889)
		(layer "In2.Cu")
		(net "M_D_DQ<61>")
	)
	(segment
		(start 302.365156 -112.313466)
		(end 302.73244 -112.68075)
		(width 0.14224)
		(layer "In2.Cu")
		(net "M_D_DQ<61>")
	)
	(segment
		(start 310.635396 -122.936)
		(end 310.432196 -123.1392)
		(width 0.14224)
		(layer "In2.Cu")
		(net "M_D_DQ<61>")
	)
	(segment
		(start 310.432196 -123.1392)
		(end 310.025796 -123.1392)
		(width 0.14224)
		(layer "In2.Cu")
		(net "M_D_DQ<61>")
	)
	(segment
		(start 308.200044 -131.927346)
		(end 307.911246 -132.216144)
		(width 0.14224)
		(layer "In2.Cu")
		(net "M_D_DQ<61>")
	)
	(segment
		(start 300.433232 -110.381542)
		(end 300.433232 -110.796324)
		(width 0.14224)
		(layer "In2.Cu")
		(net "M_D_DQ<61>")
	)
	(segment
		(start 308.123844 -134.16661)
		(end 307.950108 -134.340346)
		(width 0.14224)
		(layer "In2.Cu")
		(net "M_D_DQ<61>")
	)
	(segment
		(start 287.21812 -98.500184)
		(end 287.21812 -98.16211)
		(width 0.0889)
		(layer "In2.Cu")
		(net "M_D_DQ<61>")
	)
	(segment
		(start 286.953198 -102.517448)
		(end 286.953198 -104.060498)
		(width 0.0889)
		(layer "In2.Cu")
		(net "M_D_DQ<61>")
	)
	(segment
		(start 305.399186 -115.762278)
		(end 305.813968 -115.762278)
		(width 0.14224)
		(layer "In2.Cu")
		(net "M_D_DQ<61>")
	)
	(segment
		(start 307.330856 -117.279166)
		(end 307.330856 -117.693948)
		(width 0.14224)
		(layer "In2.Cu")
		(net "M_D_DQ<61>")
	)
	(segment
		(start 287.08477 -101.05136)
		(end 287.08477 -102.385876)
		(width 0.0889)
		(layer "In2.Cu")
		(net "M_D_DQ<61>")
	)
	(segment
		(start 308.577996 -130.244596)
		(end 308.073044 -130.749548)
		(width 0.14224)
		(layer "In2.Cu")
		(net "M_D_DQ<61>")
	)
	(segment
		(start 309.009796 -122.174)
		(end 309.009796 -129.216658)
		(width 0.14224)
		(layer "In2.Cu")
		(net "M_D_DQ<61>")
	)
	(segment
		(start 308.6608 -130.161792)
		(end 308.577996 -130.244596)
		(width 0.14224)
		(layer "In2.Cu")
		(net "M_D_DQ<61>")
	)
	(segment
		(start 308.6608 -129.565654)
		(end 308.6608 -130.161792)
		(width 0.14224)
		(layer "In2.Cu")
		(net "M_D_DQ<61>")
	)
	(segment
		(start 308.113176 -118.061486)
		(end 310.635396 -120.583706)
		(width 0.14224)
		(layer "In2.Cu")
		(net "M_D_DQ<61>")
	)
	(segment
		(start 301.215552 -111.163862)
		(end 301.582836 -111.531146)
		(width 0.14224)
		(layer "In2.Cu")
		(net "M_D_DQ<61>")
	)
	(segment
		(start 302.73244 -113.095532)
		(end 303.099978 -113.46307)
		(width 0.14224)
		(layer "In2.Cu")
		(net "M_D_DQ<61>")
	)
	(segment
		(start 308.123844 -133.909054)
		(end 308.123844 -134.16661)
		(width 0.14224)
		(layer "In2.Cu")
		(net "M_D_DQ<61>")
	)
	(segment
		(start 304.664364 -114.612674)
		(end 305.031648 -114.979958)
		(width 0.14224)
		(layer "In2.Cu")
		(net "M_D_DQ<61>")
	)
	(segment
		(start 301.582836 -111.945928)
		(end 301.950374 -112.313466)
		(width 0.14224)
		(layer "In2.Cu")
		(net "M_D_DQ<61>")
	)
	(segment
		(start 304.249582 -114.612674)
		(end 304.664364 -114.612674)
		(width 0.14224)
		(layer "In2.Cu")
		(net "M_D_DQ<61>")
	)
	(segment
		(start 303.099978 -113.46307)
		(end 303.51476 -113.46307)
		(width 0.14224)
		(layer "In2.Cu")
		(net "M_D_DQ<61>")
	)
	(segment
		(start 293.416228 -108.51261)
		(end 294.682418 -109.7788)
		(width 0.14224)
		(layer "In2.Cu")
		(net "M_D_DQ<61>")
	)
	(segment
		(start 286.87141 -99.290886)
		(end 286.866584 -99.299522)
		(width 0.0889)
		(layer "In2.Cu")
		(net "M_D_DQ<61>")
	)
	(segment
		(start 308.1274 -133.16839)
		(end 307.911246 -133.384544)
		(width 0.14224)
		(layer "In2.Cu")
		(net "M_D_DQ<61>")
	)
	(segment
		(start 303.882044 -114.245136)
		(end 304.249582 -114.612674)
		(width 0.14224)
		(layer "In2.Cu")
		(net "M_D_DQ<61>")
	)
	(segment
		(start 308.073044 -130.749548)
		(end 308.073044 -131.318)
		(width 0.14224)
		(layer "In2.Cu")
		(net "M_D_DQ<61>")
	)
	(segment
		(start 301.950374 -112.313466)
		(end 302.365156 -112.313466)
		(width 0.14224)
		(layer "In2.Cu")
		(net "M_D_DQ<61>")
	)
	(segment
		(start 307.330856 -117.693948)
		(end 307.698394 -118.061486)
		(width 0.14224)
		(layer "In2.Cu")
		(net "M_D_DQ<61>")
	)
	(segment
		(start 305.813968 -115.762278)
		(end 306.181252 -116.129562)
		(width 0.14224)
		(layer "In2.Cu")
		(net "M_D_DQ<61>")
	)
	(segment
		(start 306.181252 -116.129562)
		(end 306.181252 -116.544344)
		(width 0.14224)
		(layer "In2.Cu")
		(net "M_D_DQ<61>")
	)
	(segment
		(start 309.212996 -121.9708)
		(end 309.009796 -122.174)
		(width 0.14224)
		(layer "In2.Cu")
		(net "M_D_DQ<61>")
	)
	(segment
		(start 307.911246 -133.696456)
		(end 308.123844 -133.909054)
		(width 0.14224)
		(layer "In2.Cu")
		(net "M_D_DQ<61>")
	)
	(segment
		(start 300.80077 -111.163862)
		(end 301.215552 -111.163862)
		(width 0.14224)
		(layer "In2.Cu")
		(net "M_D_DQ<61>")
	)
	(segment
		(start 310.025796 -123.1392)
		(end 309.822596 -122.936)
		(width 0.14224)
		(layer "In2.Cu")
		(net "M_D_DQ<61>")
	)
	(segment
		(start 303.882044 -113.830354)
		(end 303.882044 -114.245136)
		(width 0.14224)
		(layer "In2.Cu")
		(net "M_D_DQ<61>")
	)
	(segment
		(start 309.822596 -122.936)
		(end 309.822596 -122.174)
		(width 0.14224)
		(layer "In2.Cu")
		(net "M_D_DQ<61>")
	)
	(segment
		(start 305.031648 -115.39474)
		(end 305.399186 -115.762278)
		(width 0.14224)
		(layer "In2.Cu")
		(net "M_D_DQ<61>")
	)
	(segment
		(start 306.54879 -116.911882)
		(end 306.963572 -116.911882)
		(width 0.14224)
		(layer "In2.Cu")
		(net "M_D_DQ<61>")
	)
	(segment
		(start 307.698394 -118.061486)
		(end 308.113176 -118.061486)
		(width 0.14224)
		(layer "In2.Cu")
		(net "M_D_DQ<61>")
	)
	(segment
		(start 309.009796 -129.216658)
		(end 308.6608 -129.565654)
		(width 0.14224)
		(layer "In2.Cu")
		(net "M_D_DQ<61>")
	)
	(segment
		(start 303.51476 -113.46307)
		(end 303.882044 -113.830354)
		(width 0.14224)
		(layer "In2.Cu")
		(net "M_D_DQ<61>")
	)
	(segment
		(start 309.822596 -122.174)
		(end 309.619396 -121.9708)
		(width 0.14224)
		(layer "In2.Cu")
		(net "M_D_DQ<61>")
	)
	(segment
		(start 299.83049 -109.7788)
		(end 300.433232 -110.381542)
		(width 0.14224)
		(layer "In2.Cu")
		(net "M_D_DQ<61>")
	)
	(segment
		(start 286.953198 -104.060498)
		(end 290.068 -107.1753)
		(width 0.0889)
		(layer "In2.Cu")
		(net "M_D_DQ<61>")
	)
	(segment
		(start 291.73551 -108.51261)
		(end 293.416228 -108.51261)
		(width 0.14224)
		(layer "In2.Cu")
		(net "M_D_DQ<61>")
	)
	(segment
		(start 308.200044 -131.445)
		(end 308.200044 -131.927346)
		(width 0.14224)
		(layer "In2.Cu")
		(net "M_D_DQ<61>")
	)
	(segment
		(start 305.031648 -114.979958)
		(end 305.031648 -115.39474)
		(width 0.14224)
		(layer "In2.Cu")
		(net "M_D_DQ<61>")
	)
	(segment
		(start 307.950108 -134.340346)
		(end 307.749956 -134.340346)
		(width 0.14224)
		(layer "In2.Cu")
		(net "M_D_DQ<61>")
	)
	(segment
		(start 308.1274 -132.76961)
		(end 308.1274 -133.16839)
		(width 0.14224)
		(layer "In2.Cu")
		(net "M_D_DQ<61>")
	)
	(segment
		(start 286.87141 -100.681536)
		(end 287.08477 -101.05136)
		(width 0.0889)
		(layer "In2.Cu")
		(net "M_D_DQ<61>")
	)
	(segment
		(start 308.073044 -131.318)
		(end 308.200044 -131.445)
		(width 0.14224)
		(layer "In2.Cu")
		(net "M_D_DQ<61>")
	)
	(segment
		(start 306.181252 -116.544344)
		(end 306.54879 -116.911882)
		(width 0.14224)
		(layer "In2.Cu")
		(net "M_D_DQ<61>")
	)
	(segment
		(start 287.21812 -98.16211)
		(end 287.160208 -98.104198)
		(width 0.0889)
		(layer "In2.Cu")
		(net "M_D_DQ<61>")
	)
	(segment
		(start 309.619396 -121.9708)
		(end 309.212996 -121.9708)
		(width 0.14224)
		(layer "In2.Cu")
		(net "M_D_DQ<61>")
	)
	(segment
		(start 286.87141 -100.281486)
		(end 286.866584 -100.290122)
		(width 0.0889)
		(layer "In2.Cu")
		(net "M_D_DQ<61>")
	)
	(arc
		(start 287.160208 -98.104198)
		(mid 286.857939 -98.325747)
		(end 286.87141 -98.700336)
		(width 0.0889)
		(layer "In2.Cu")
		(net "M_D_DQ<61>")
	)
	(arc
		(start 286.866584 -100.290122)
		(mid 286.817829 -100.486474)
		(end 286.87141 -100.681536)
		(width 0.0889)
		(layer "In2.Cu")
		(net "M_D_DQ<61>")
	)
	(arc
		(start 286.87141 -99.690936)
		(mid 286.950632 -99.980054)
		(end 286.87776 -100.270818)
		(width 0.0889)
		(layer "In2.Cu")
		(net "M_D_DQ<61>")
	)
	(arc
		(start 286.87141 -98.700336)
		(mid 286.950632 -98.989454)
		(end 286.87776 -99.280218)
		(width 0.0889)
		(layer "In2.Cu")
		(net "M_D_DQ<61>")
	)
	(arc
		(start 286.866584 -99.299522)
		(mid 286.817829 -99.495874)
		(end 286.87141 -99.690936)
		(width 0.0889)
		(layer "In2.Cu")
		(net "M_D_DQ<61>")
	)
	(segment
		(start 308.59984 -136.345168)
		(end 308.501796 -135.8138)
		(width 0.1651)
		(layer "F.Cu")
		(net "M_D_DQ<60>")
	)
	(segment
		(start 308.59984 -137.67054)
		(end 308.59984 -136.345168)
		(width 0.1651)
		(layer "F.Cu")
		(net "M_D_DQ<60>")
	)
	(segment
		(start 287.21812 -97.509584)
		(end 286.64662 -97.509584)
		(width 0.1651)
		(layer "F.Cu")
		(net "M_D_DQ<60>")
	)
	(segment
		(start 308.600348 -137.67054)
		(end 308.59984 -137.67054)
		(width 0.1651)
		(layer "F.Cu")
		(net "M_D_DQ<60>")
	)
	(via
		(at 308.501796 -135.8138)
		(size 0.508)
		(drill 0.254)
		(layers "F.Cu" "B.Cu")
		(net "M_D_DQ<60>")
	)
	(via
		(at 307.749956 -131.611878)
		(size 0.508)
		(drill 0.254)
		(layers "F.Cu" "B.Cu")
		(net "M_D_DQ<60>")
	)
	(via
		(at 287.21812 -97.509584)
		(size 0.508)
		(drill 0.254)
		(layers "F.Cu" "B.Cu")
		(net "M_D_DQ<60>")
	)
	(segment
		(start 307.749956 -132.875782)
		(end 307.749956 -131.611878)
		(width 0.1651)
		(layer "B.Cu")
		(net "M_D_DQ<60>")
	)
	(segment
		(start 307.750464 -132.876036)
		(end 307.749956 -132.875782)
		(width 0.1651)
		(layer "B.Cu")
		(net "M_D_DQ<60>")
	)
	(segment
		(start 307.474874 -135.03783)
		(end 308.250844 -135.8138)
		(width 0.14224)
		(layer "In2.Cu")
		(net "M_D_DQ<60>")
	)
	(segment
		(start 289.9664 -107.569)
		(end 291.3888 -108.9914)
		(width 0.14224)
		(layer "In2.Cu")
		(net "M_D_DQ<60>")
	)
	(segment
		(start 308.374796 -126.684278)
		(end 308.207156 -126.851918)
		(width 0.14224)
		(layer "In2.Cu")
		(net "M_D_DQ<60>")
	)
	(segment
		(start 294.64 -110.4138)
		(end 299.186346 -110.4138)
		(width 0.14224)
		(layer "In2.Cu")
		(net "M_D_DQ<60>")
	)
	(segment
		(start 307.4416 -121.520966)
		(end 307.4416 -121.927366)
		(width 0.14224)
		(layer "In2.Cu")
		(net "M_D_DQ<60>")
	)
	(segment
		(start 307.316886 -132.044948)
		(end 307.316886 -134.57809)
		(width 0.14224)
		(layer "In2.Cu")
		(net "M_D_DQ<60>")
	)
	(segment
		(start 307.474874 -134.736078)
		(end 307.474874 -135.03783)
		(width 0.14224)
		(layer "In2.Cu")
		(net "M_D_DQ<60>")
	)
	(segment
		(start 307.749956 -131.611878)
		(end 307.316886 -132.044948)
		(width 0.14224)
		(layer "In2.Cu")
		(net "M_D_DQ<60>")
	)
	(segment
		(start 286.70631 -99.195636)
		(end 286.69996 -99.206304)
		(width 0.0889)
		(layer "In2.Cu")
		(net "M_D_DQ<60>")
	)
	(segment
		(start 291.3888 -108.9914)
		(end 293.2176 -108.9914)
		(width 0.14224)
		(layer "In2.Cu")
		(net "M_D_DQ<60>")
	)
	(segment
		(start 286.89427 -101.102668)
		(end 286.89427 -102.306882)
		(width 0.0889)
		(layer "In2.Cu")
		(net "M_D_DQ<60>")
	)
	(segment
		(start 307.434996 -130.63601)
		(end 307.434996 -131.296918)
		(width 0.14224)
		(layer "In2.Cu")
		(net "M_D_DQ<60>")
	)
	(segment
		(start 308.250844 -135.8138)
		(end 308.501796 -135.8138)
		(width 0.14224)
		(layer "In2.Cu")
		(net "M_D_DQ<60>")
	)
	(segment
		(start 286.70631 -100.776786)
		(end 286.89427 -101.102668)
		(width 0.0889)
		(layer "In2.Cu")
		(net "M_D_DQ<60>")
	)
	(segment
		(start 307.6448 -121.317766)
		(end 307.4416 -121.520966)
		(width 0.14224)
		(layer "In2.Cu")
		(net "M_D_DQ<60>")
	)
	(segment
		(start 286.89427 -102.306882)
		(end 286.762698 -102.438454)
		(width 0.0889)
		(layer "In2.Cu")
		(net "M_D_DQ<60>")
	)
	(segment
		(start 286.762698 -104.139492)
		(end 288.244026 -105.62082)
		(width 0.0889)
		(layer "In2.Cu")
		(net "M_D_DQ<60>")
	)
	(segment
		(start 309.433976 -121.112026)
		(end 309.228236 -121.317766)
		(width 0.14224)
		(layer "In2.Cu")
		(net "M_D_DQ<60>")
	)
	(segment
		(start 309.233316 -120.504966)
		(end 309.433976 -120.705626)
		(width 0.14224)
		(layer "In2.Cu")
		(net "M_D_DQ<60>")
	)
	(segment
		(start 308.207156 -126.851918)
		(end 308.207156 -129.86385)
		(width 0.14224)
		(layer "In2.Cu")
		(net "M_D_DQ<60>")
	)
	(segment
		(start 288.244026 -105.62082)
		(end 289.9664 -107.343194)
		(width 0.0889)
		(layer "In2.Cu")
		(net "M_D_DQ<60>")
	)
	(segment
		(start 307.6448 -122.130566)
		(end 308.171596 -122.130566)
		(width 0.14224)
		(layer "In2.Cu")
		(net "M_D_DQ<60>")
	)
	(segment
		(start 307.434996 -131.296918)
		(end 307.749956 -131.611878)
		(width 0.14224)
		(layer "In2.Cu")
		(net "M_D_DQ<60>")
	)
	(segment
		(start 289.9664 -107.343194)
		(end 289.9664 -107.569)
		(width 0.0889)
		(layer "In2.Cu")
		(net "M_D_DQ<60>")
	)
	(segment
		(start 307.4416 -118.669054)
		(end 307.4416 -120.290082)
		(width 0.14224)
		(layer "In2.Cu")
		(net "M_D_DQ<60>")
	)
	(segment
		(start 307.4416 -120.290082)
		(end 307.656484 -120.504966)
		(width 0.14224)
		(layer "In2.Cu")
		(net "M_D_DQ<60>")
	)
	(segment
		(start 299.186346 -110.4138)
		(end 307.4416 -118.669054)
		(width 0.14224)
		(layer "In2.Cu")
		(net "M_D_DQ<60>")
	)
	(segment
		(start 307.316886 -134.57809)
		(end 307.474874 -134.736078)
		(width 0.14224)
		(layer "In2.Cu")
		(net "M_D_DQ<60>")
	)
	(segment
		(start 286.711136 -99.187)
		(end 286.70631 -99.195636)
		(width 0.0889)
		(layer "In2.Cu")
		(net "M_D_DQ<60>")
	)
	(segment
		(start 307.4416 -121.927366)
		(end 307.6448 -122.130566)
		(width 0.14224)
		(layer "In2.Cu")
		(net "M_D_DQ<60>")
	)
	(segment
		(start 309.433976 -120.705626)
		(end 309.433976 -121.112026)
		(width 0.14224)
		(layer "In2.Cu")
		(net "M_D_DQ<60>")
	)
	(segment
		(start 293.2176 -108.9914)
		(end 294.64 -110.4138)
		(width 0.14224)
		(layer "In2.Cu")
		(net "M_D_DQ<60>")
	)
	(segment
		(start 308.374796 -122.333766)
		(end 308.374796 -126.684278)
		(width 0.14224)
		(layer "In2.Cu")
		(net "M_D_DQ<60>")
	)
	(segment
		(start 308.171596 -122.130566)
		(end 308.374796 -122.333766)
		(width 0.14224)
		(layer "In2.Cu")
		(net "M_D_DQ<60>")
	)
	(segment
		(start 309.228236 -121.317766)
		(end 307.6448 -121.317766)
		(width 0.14224)
		(layer "In2.Cu")
		(net "M_D_DQ<60>")
	)
	(segment
		(start 286.70631 -100.186236)
		(end 286.69996 -100.196904)
		(width 0.0889)
		(layer "In2.Cu")
		(net "M_D_DQ<60>")
	)
	(segment
		(start 307.656484 -120.504966)
		(end 309.233316 -120.504966)
		(width 0.14224)
		(layer "In2.Cu")
		(net "M_D_DQ<60>")
	)
	(segment
		(start 287.21812 -97.847658)
		(end 287.152842 -97.912936)
		(width 0.0889)
		(layer "In2.Cu")
		(net "M_D_DQ<60>")
	)
	(segment
		(start 286.711136 -100.1776)
		(end 286.70631 -100.186236)
		(width 0.0889)
		(layer "In2.Cu")
		(net "M_D_DQ<60>")
	)
	(segment
		(start 308.207156 -129.86385)
		(end 307.434996 -130.63601)
		(width 0.14224)
		(layer "In2.Cu")
		(net "M_D_DQ<60>")
	)
	(segment
		(start 287.21812 -97.509584)
		(end 287.21812 -97.847658)
		(width 0.0889)
		(layer "In2.Cu")
		(net "M_D_DQ<60>")
	)
	(segment
		(start 286.762698 -102.438454)
		(end 286.762698 -104.139492)
		(width 0.0889)
		(layer "In2.Cu")
		(net "M_D_DQ<60>")
	)
	(arc
		(start 286.70631 -99.786186)
		(mid 286.75978 -99.981249)
		(end 286.711136 -100.1776)
		(width 0.0889)
		(layer "In2.Cu")
		(net "M_D_DQ<60>")
	)
	(arc
		(start 286.70631 -98.795586)
		(mid 286.75978 -98.990649)
		(end 286.711136 -99.187)
		(width 0.0889)
		(layer "In2.Cu")
		(net "M_D_DQ<60>")
	)
	(arc
		(start 287.152842 -97.912936)
		(mid 286.690873 -98.233478)
		(end 286.70631 -98.795586)
		(width 0.0889)
		(layer "In2.Cu")
		(net "M_D_DQ<60>")
	)
	(arc
		(start 286.69996 -99.206304)
		(mid 286.627162 -99.497067)
		(end 286.70631 -99.786186)
		(width 0.0889)
		(layer "In2.Cu")
		(net "M_D_DQ<60>")
	)
	(arc
		(start 286.69996 -100.196904)
		(mid 286.627162 -100.487667)
		(end 286.70631 -100.776786)
		(width 0.0889)
		(layer "In2.Cu")
		(net "M_D_DQ<60>")
	)
	(segment
		(start 232.749598 -84.31784)
		(end 232.101898 -84.31784)
		(width 0.1651)
		(layer "F.Cu")
		(net "M_D_DQ<5>")
	)
	(segment
		(start 196.40042 -133.0706)
		(end 196.399912 -133.076442)
		(width 0.1651)
		(layer "F.Cu")
		(net "M_D_DQ<5>")
	)
	(segment
		(start 196.399912 -133.076442)
		(end 196.399912 -134.340346)
		(width 0.1651)
		(layer "F.Cu")
		(net "M_D_DQ<5>")
	)
	(via
		(at 232.101898 -84.31784)
		(size 0.508)
		(drill 0.254)
		(layers "F.Cu" "B.Cu")
		(net "M_D_DQ<5>")
	)
	(via
		(at 196.399912 -134.340346)
		(size 0.508)
		(drill 0.254)
		(layers "F.Cu" "B.Cu")
		(net "M_D_DQ<5>")
	)
	(via
		(at 197.173596 -130.330956)
		(size 0.508)
		(drill 0.254)
		(layers "F.Cu" "B.Cu")
		(net "M_D_DQ<5>")
	)
	(segment
		(start 197.249796 -130.254756)
		(end 197.173596 -130.330956)
		(width 0.1651)
		(layer "B.Cu")
		(net "M_D_DQ<5>")
	)
	(segment
		(start 197.250304 -128.276096)
		(end 197.249796 -128.276096)
		(width 0.1651)
		(layer "B.Cu")
		(net "M_D_DQ<5>")
	)
	(segment
		(start 197.249796 -128.276096)
		(end 197.249796 -130.254756)
		(width 0.1651)
		(layer "B.Cu")
		(net "M_D_DQ<5>")
	)
	(segment
		(start 198.588376 -119.17045)
		(end 198.433436 -119.32539)
		(width 0.14224)
		(layer "In2.Cu")
		(net "M_D_DQ<5>")
	)
	(segment
		(start 203.4032 -112.0902)
		(end 202.375008 -112.0902)
		(width 0.14224)
		(layer "In2.Cu")
		(net "M_D_DQ<5>")
	)
	(segment
		(start 196.85 -131.445)
		(end 196.85 -132.020056)
		(width 0.14224)
		(layer "In2.Cu")
		(net "M_D_DQ<5>")
	)
	(segment
		(start 198.433436 -119.32539)
		(end 198.116952 -119.32539)
		(width 0.14224)
		(layer "In2.Cu")
		(net "M_D_DQ<5>")
	)
	(segment
		(start 215.2904 -100.203)
		(end 203.4032 -112.0902)
		(width 0.14224)
		(layer "In2.Cu")
		(net "M_D_DQ<5>")
	)
	(segment
		(start 197.151244 -130.330956)
		(end 196.723 -130.7592)
		(width 0.14224)
		(layer "In2.Cu")
		(net "M_D_DQ<5>")
	)
	(segment
		(start 230.845614 -84.413344)
		(end 229.596696 -84.413344)
		(width 0.14224)
		(layer "In2.Cu")
		(net "M_D_DQ<5>")
	)
	(segment
		(start 198.541894 -117.33657)
		(end 198.706994 -117.50167)
		(width 0.14224)
		(layer "In2.Cu")
		(net "M_D_DQ<5>")
	)
	(segment
		(start 197.9676 -119.474742)
		(end 197.9676 -120.029986)
		(width 0.14224)
		(layer "In2.Cu")
		(net "M_D_DQ<5>")
	)
	(segment
		(start 229.596696 -84.413344)
		(end 215.2904 -98.71964)
		(width 0.14224)
		(layer "In2.Cu")
		(net "M_D_DQ<5>")
	)
	(segment
		(start 196.7992 -132.884164)
		(end 196.7992 -133.146546)
		(width 0.14224)
		(layer "In2.Cu")
		(net "M_D_DQ<5>")
	)
	(segment
		(start 198.054976 -118.15445)
		(end 198.054976 -118.50751)
		(width 0.14224)
		(layer "In2.Cu")
		(net "M_D_DQ<5>")
	)
	(segment
		(start 197.9676 -120.029986)
		(end 198.12254 -120.184926)
		(width 0.14224)
		(layer "In2.Cu")
		(net "M_D_DQ<5>")
	)
	(segment
		(start 198.12254 -120.184926)
		(end 198.54926 -120.184926)
		(width 0.14224)
		(layer "In2.Cu")
		(net "M_D_DQ<5>")
	)
	(segment
		(start 196.723 -131.318)
		(end 196.85 -131.445)
		(width 0.14224)
		(layer "In2.Cu")
		(net "M_D_DQ<5>")
	)
	(segment
		(start 202.375008 -112.0902)
		(end 198.363332 -116.101876)
		(width 0.14224)
		(layer "In2.Cu")
		(net "M_D_DQ<5>")
	)
	(segment
		(start 198.12254 -120.847866)
		(end 197.9676 -121.002806)
		(width 0.14224)
		(layer "In2.Cu")
		(net "M_D_DQ<5>")
	)
	(segment
		(start 197.9676 -128.7526)
		(end 197.558152 -129.162048)
		(width 0.14224)
		(layer "In2.Cu")
		(net "M_D_DQ<5>")
	)
	(segment
		(start 198.116952 -119.32539)
		(end 197.9676 -119.474742)
		(width 0.14224)
		(layer "In2.Cu")
		(net "M_D_DQ<5>")
	)
	(segment
		(start 196.723 -130.7592)
		(end 196.723 -131.318)
		(width 0.14224)
		(layer "In2.Cu")
		(net "M_D_DQ<5>")
	)
	(segment
		(start 198.209916 -117.99951)
		(end 198.054976 -118.15445)
		(width 0.14224)
		(layer "In2.Cu")
		(net "M_D_DQ<5>")
	)
	(segment
		(start 198.054976 -118.50751)
		(end 198.209916 -118.66245)
		(width 0.14224)
		(layer "In2.Cu")
		(net "M_D_DQ<5>")
	)
	(segment
		(start 215.2904 -98.71964)
		(end 215.2904 -100.203)
		(width 0.14224)
		(layer "In2.Cu")
		(net "M_D_DQ<5>")
	)
	(segment
		(start 198.54926 -120.184926)
		(end 198.69912 -120.334786)
		(width 0.14224)
		(layer "In2.Cu")
		(net "M_D_DQ<5>")
	)
	(segment
		(start 198.363332 -116.101876)
		(end 198.054976 -116.846604)
		(width 0.14224)
		(layer "In2.Cu")
		(net "M_D_DQ<5>")
	)
	(segment
		(start 198.706994 -117.85473)
		(end 198.562214 -117.99951)
		(width 0.14224)
		(layer "In2.Cu")
		(net "M_D_DQ<5>")
	)
	(segment
		(start 196.561202 -133.696456)
		(end 196.8246 -133.959854)
		(width 0.14224)
		(layer "In2.Cu")
		(net "M_D_DQ<5>")
	)
	(segment
		(start 198.433436 -118.66245)
		(end 198.588376 -118.81739)
		(width 0.14224)
		(layer "In2.Cu")
		(net "M_D_DQ<5>")
	)
	(segment
		(start 232.101898 -84.31784)
		(end 231.554274 -84.31784)
		(width 0.0889)
		(layer "In2.Cu")
		(net "M_D_DQ<5>")
	)
	(segment
		(start 196.561202 -133.384544)
		(end 196.561202 -133.696456)
		(width 0.14224)
		(layer "In2.Cu")
		(net "M_D_DQ<5>")
	)
	(segment
		(start 198.588376 -118.81739)
		(end 198.588376 -119.17045)
		(width 0.14224)
		(layer "In2.Cu")
		(net "M_D_DQ<5>")
	)
	(segment
		(start 198.054976 -116.846604)
		(end 198.054976 -117.18163)
		(width 0.14224)
		(layer "In2.Cu")
		(net "M_D_DQ<5>")
	)
	(segment
		(start 196.7992 -133.146546)
		(end 196.561202 -133.384544)
		(width 0.14224)
		(layer "In2.Cu")
		(net "M_D_DQ<5>")
	)
	(segment
		(start 197.558152 -129.162048)
		(end 197.558152 -129.9464)
		(width 0.14224)
		(layer "In2.Cu")
		(net "M_D_DQ<5>")
	)
	(segment
		(start 196.6722 -134.340346)
		(end 196.399912 -134.340346)
		(width 0.14224)
		(layer "In2.Cu")
		(net "M_D_DQ<5>")
	)
	(segment
		(start 198.209916 -118.66245)
		(end 198.433436 -118.66245)
		(width 0.14224)
		(layer "In2.Cu")
		(net "M_D_DQ<5>")
	)
	(segment
		(start 198.562214 -117.99951)
		(end 198.209916 -117.99951)
		(width 0.14224)
		(layer "In2.Cu")
		(net "M_D_DQ<5>")
	)
	(segment
		(start 198.209916 -117.33657)
		(end 198.541894 -117.33657)
		(width 0.14224)
		(layer "In2.Cu")
		(net "M_D_DQ<5>")
	)
	(segment
		(start 198.69912 -120.687846)
		(end 198.5391 -120.847866)
		(width 0.14224)
		(layer "In2.Cu")
		(net "M_D_DQ<5>")
	)
	(segment
		(start 197.9676 -121.002806)
		(end 197.9676 -128.7526)
		(width 0.14224)
		(layer "In2.Cu")
		(net "M_D_DQ<5>")
	)
	(segment
		(start 196.561202 -132.646166)
		(end 196.7992 -132.884164)
		(width 0.14224)
		(layer "In2.Cu")
		(net "M_D_DQ<5>")
	)
	(segment
		(start 197.173596 -130.330956)
		(end 197.151244 -130.330956)
		(width 0.14224)
		(layer "In2.Cu")
		(net "M_D_DQ<5>")
	)
	(segment
		(start 196.8246 -134.187946)
		(end 196.6722 -134.340346)
		(width 0.14224)
		(layer "In2.Cu")
		(net "M_D_DQ<5>")
	)
	(segment
		(start 197.558152 -129.9464)
		(end 197.173596 -130.330956)
		(width 0.14224)
		(layer "In2.Cu")
		(net "M_D_DQ<5>")
	)
	(segment
		(start 198.054976 -117.18163)
		(end 198.209916 -117.33657)
		(width 0.14224)
		(layer "In2.Cu")
		(net "M_D_DQ<5>")
	)
	(segment
		(start 198.706994 -117.50167)
		(end 198.706994 -117.85473)
		(width 0.14224)
		(layer "In2.Cu")
		(net "M_D_DQ<5>")
	)
	(segment
		(start 198.5391 -120.847866)
		(end 198.12254 -120.847866)
		(width 0.14224)
		(layer "In2.Cu")
		(net "M_D_DQ<5>")
	)
	(segment
		(start 196.85 -132.020056)
		(end 196.561202 -132.308854)
		(width 0.14224)
		(layer "In2.Cu")
		(net "M_D_DQ<5>")
	)
	(segment
		(start 196.8246 -133.959854)
		(end 196.8246 -134.187946)
		(width 0.14224)
		(layer "In2.Cu")
		(net "M_D_DQ<5>")
	)
	(segment
		(start 231.45877 -84.413344)
		(end 230.845614 -84.413344)
		(width 0.0889)
		(layer "In2.Cu")
		(net "M_D_DQ<5>")
	)
	(segment
		(start 196.561202 -132.308854)
		(end 196.561202 -132.646166)
		(width 0.14224)
		(layer "In2.Cu")
		(net "M_D_DQ<5>")
	)
	(segment
		(start 231.554274 -84.31784)
		(end 231.45877 -84.413344)
		(width 0.0889)
		(layer "In2.Cu")
		(net "M_D_DQ<5>")
	)
	(segment
		(start 198.69912 -120.334786)
		(end 198.69912 -120.687846)
		(width 0.14224)
		(layer "In2.Cu")
		(net "M_D_DQ<5>")
	)
	(segment
		(start 315.400436 -134.339838)
		(end 315.399928 -134.340346)
		(width 0.1651)
		(layer "F.Cu")
		(net "M_D_DQ<59>")
	)
	(segment
		(start 315.400436 -133.0706)
		(end 315.400436 -134.339838)
		(width 0.1651)
		(layer "F.Cu")
		(net "M_D_DQ<59>")
	)
	(segment
		(start 290.0807 -101.471984)
		(end 290.6522 -101.471984)
		(width 0.1651)
		(layer "F.Cu")
		(net "M_D_DQ<59>")
	)
	(via
		(at 315.399928 -134.340346)
		(size 0.508)
		(drill 0.254)
		(layers "F.Cu" "B.Cu")
		(net "M_D_DQ<59>")
	)
	(via
		(at 290.6522 -101.471984)
		(size 0.508)
		(drill 0.254)
		(layers "F.Cu" "B.Cu")
		(net "M_D_DQ<59>")
	)
	(via
		(at 316.249812 -130.330956)
		(size 0.508)
		(drill 0.254)
		(layers "F.Cu" "B.Cu")
		(net "M_D_DQ<59>")
	)
	(segment
		(start 316.25032 -128.276096)
		(end 316.25032 -130.330448)
		(width 0.1651)
		(layer "B.Cu")
		(net "M_D_DQ<59>")
	)
	(segment
		(start 316.25032 -130.330448)
		(end 316.249812 -130.330956)
		(width 0.1651)
		(layer "B.Cu")
		(net "M_D_DQ<59>")
	)
	(segment
		(start 294.881808 -102.767892)
		(end 296.342816 -104.2289)
		(width 0.0889)
		(layer "In2.Cu")
		(net "M_D_DQ<59>")
	)
	(segment
		(start 291.029898 -101.849682)
		(end 291.029898 -102.145846)
		(width 0.0889)
		(layer "In2.Cu")
		(net "M_D_DQ<59>")
	)
	(segment
		(start 315.850016 -133.83895)
		(end 315.850016 -134.162546)
		(width 0.14224)
		(layer "In2.Cu")
		(net "M_D_DQ<59>")
	)
	(segment
		(start 315.561218 -132.184648)
		(end 315.561218 -132.457952)
		(width 0.14224)
		(layer "In2.Cu")
		(net "M_D_DQ<59>")
	)
	(segment
		(start 310.231282 -111.9378)
		(end 311.618376 -111.9378)
		(width 0.14224)
		(layer "In2.Cu")
		(net "M_D_DQ<59>")
	)
	(segment
		(start 317.77686 -126.79807)
		(end 317.62192 -126.64313)
		(width 0.14224)
		(layer "In2.Cu")
		(net "M_D_DQ<59>")
	)
	(segment
		(start 315.843666 -131.233418)
		(end 315.843666 -131.9022)
		(width 0.14224)
		(layer "In2.Cu")
		(net "M_D_DQ<59>")
	)
	(segment
		(start 317.77686 -128.567688)
		(end 317.77686 -126.79807)
		(width 0.14224)
		(layer "In2.Cu")
		(net "M_D_DQ<59>")
	)
	(segment
		(start 291.651944 -102.767892)
		(end 294.881808 -102.767892)
		(width 0.0889)
		(layer "In2.Cu")
		(net "M_D_DQ<59>")
	)
	(segment
		(start 297.7134 -104.013)
		(end 299.3644 -104.013)
		(width 0.14224)
		(layer "In2.Cu")
		(net "M_D_DQ<59>")
	)
	(segment
		(start 316.578996 -129.394204)
		(end 316.578996 -130.01498)
		(width 0.14224)
		(layer "In2.Cu")
		(net "M_D_DQ<59>")
	)
	(segment
		(start 299.3644 -104.013)
		(end 300.5074 -105.156)
		(width 0.14224)
		(layer "In2.Cu")
		(net "M_D_DQ<59>")
	)
	(segment
		(start 315.561218 -132.457952)
		(end 315.818266 -132.715)
		(width 0.14224)
		(layer "In2.Cu")
		(net "M_D_DQ<59>")
	)
	(segment
		(start 317.26886 -126.64313)
		(end 317.11392 -126.79807)
		(width 0.14224)
		(layer "In2.Cu")
		(net "M_D_DQ<59>")
	)
	(segment
		(start 291.029898 -102.145846)
		(end 291.651944 -102.767892)
		(width 0.0889)
		(layer "In2.Cu")
		(net "M_D_DQ<59>")
	)
	(segment
		(start 318.28486 -128.722628)
		(end 317.9318 -128.722628)
		(width 0.14224)
		(layer "In2.Cu")
		(net "M_D_DQ<59>")
	)
	(segment
		(start 315.799216 -131.188968)
		(end 315.843666 -131.233418)
		(width 0.14224)
		(layer "In2.Cu")
		(net "M_D_DQ<59>")
	)
	(segment
		(start 315.818266 -133.0198)
		(end 315.561218 -133.276848)
		(width 0.14224)
		(layer "In2.Cu")
		(net "M_D_DQ<59>")
	)
	(segment
		(start 315.561218 -133.276848)
		(end 315.561218 -133.550152)
		(width 0.14224)
		(layer "In2.Cu")
		(net "M_D_DQ<59>")
	)
	(segment
		(start 318.4398 -118.759224)
		(end 318.4398 -128.567688)
		(width 0.14224)
		(layer "In2.Cu")
		(net "M_D_DQ<59>")
	)
	(segment
		(start 316.578996 -130.01498)
		(end 316.249812 -130.344164)
		(width 0.14224)
		(layer "In2.Cu")
		(net "M_D_DQ<59>")
	)
	(segment
		(start 315.799216 -130.7592)
		(end 315.799216 -131.188968)
		(width 0.14224)
		(layer "In2.Cu")
		(net "M_D_DQ<59>")
	)
	(segment
		(start 315.561218 -133.550152)
		(end 315.850016 -133.83895)
		(width 0.14224)
		(layer "In2.Cu")
		(net "M_D_DQ<59>")
	)
	(segment
		(start 315.672216 -134.340346)
		(end 315.399928 -134.340346)
		(width 0.14224)
		(layer "In2.Cu")
		(net "M_D_DQ<59>")
	)
	(segment
		(start 297.4975 -104.2289)
		(end 297.7134 -104.013)
		(width 0.0889)
		(layer "In2.Cu")
		(net "M_D_DQ<59>")
	)
	(segment
		(start 317.62192 -126.64313)
		(end 317.26886 -126.64313)
		(width 0.14224)
		(layer "In2.Cu")
		(net "M_D_DQ<59>")
	)
	(segment
		(start 316.249812 -130.330956)
		(end 316.22746 -130.330956)
		(width 0.14224)
		(layer "In2.Cu")
		(net "M_D_DQ<59>")
	)
	(segment
		(start 315.843666 -131.9022)
		(end 315.561218 -132.184648)
		(width 0.14224)
		(layer "In2.Cu")
		(net "M_D_DQ<59>")
	)
	(segment
		(start 290.6522 -101.471984)
		(end 291.029898 -101.849682)
		(width 0.0889)
		(layer "In2.Cu")
		(net "M_D_DQ<59>")
	)
	(segment
		(start 317.11392 -126.79807)
		(end 317.11392 -128.85928)
		(width 0.14224)
		(layer "In2.Cu")
		(net "M_D_DQ<59>")
	)
	(segment
		(start 315.818266 -132.715)
		(end 315.818266 -133.0198)
		(width 0.14224)
		(layer "In2.Cu")
		(net "M_D_DQ<59>")
	)
	(segment
		(start 316.22746 -130.330956)
		(end 315.799216 -130.7592)
		(width 0.14224)
		(layer "In2.Cu")
		(net "M_D_DQ<59>")
	)
	(segment
		(start 317.11392 -128.85928)
		(end 316.578996 -129.394204)
		(width 0.14224)
		(layer "In2.Cu")
		(net "M_D_DQ<59>")
	)
	(segment
		(start 317.9318 -128.722628)
		(end 317.77686 -128.567688)
		(width 0.14224)
		(layer "In2.Cu")
		(net "M_D_DQ<59>")
	)
	(segment
		(start 300.5074 -105.156)
		(end 303.449482 -105.156)
		(width 0.14224)
		(layer "In2.Cu")
		(net "M_D_DQ<59>")
	)
	(segment
		(start 303.449482 -105.156)
		(end 310.231282 -111.9378)
		(width 0.14224)
		(layer "In2.Cu")
		(net "M_D_DQ<59>")
	)
	(segment
		(start 318.4398 -128.567688)
		(end 318.28486 -128.722628)
		(width 0.14224)
		(layer "In2.Cu")
		(net "M_D_DQ<59>")
	)
	(segment
		(start 316.249812 -130.344164)
		(end 316.249812 -130.330956)
		(width 0.14224)
		(layer "In2.Cu")
		(net "M_D_DQ<59>")
	)
	(segment
		(start 315.850016 -134.162546)
		(end 315.672216 -134.340346)
		(width 0.14224)
		(layer "In2.Cu")
		(net "M_D_DQ<59>")
	)
	(segment
		(start 296.342816 -104.2289)
		(end 297.4975 -104.2289)
		(width 0.0889)
		(layer "In2.Cu")
		(net "M_D_DQ<59>")
	)
	(segment
		(start 311.618376 -111.9378)
		(end 318.4398 -118.759224)
		(width 0.14224)
		(layer "In2.Cu")
		(net "M_D_DQ<59>")
	)
	(segment
		(start 316.381384 -136.32434)
		(end 316.249812 -136.192768)
		(width 0.1651)
		(layer "F.Cu")
		(net "M_D_DQ<58>")
	)
	(segment
		(start 316.249812 -136.192768)
		(end 316.249812 -135.9154)
		(width 0.1651)
		(layer "F.Cu")
		(net "M_D_DQ<58>")
	)
	(segment
		(start 316.249812 -136.679432)
		(end 316.381384 -136.54786)
		(width 0.1651)
		(layer "F.Cu")
		(net "M_D_DQ<58>")
	)
	(segment
		(start 290.0807 -100.481638)
		(end 290.6522 -100.481638)
		(width 0.1651)
		(layer "F.Cu")
		(net "M_D_DQ<58>")
	)
	(segment
		(start 316.25032 -137.67054)
		(end 316.25032 -136.67994)
		(width 0.1651)
		(layer "F.Cu")
		(net "M_D_DQ<58>")
	)
	(segment
		(start 316.25032 -136.67994)
		(end 316.249812 -136.679432)
		(width 0.1651)
		(layer "F.Cu")
		(net "M_D_DQ<58>")
	)
	(segment
		(start 316.381384 -136.54786)
		(end 316.381384 -136.32434)
		(width 0.1651)
		(layer "F.Cu")
		(net "M_D_DQ<58>")
	)
	(via
		(at 316.249812 -135.9154)
		(size 0.508)
		(drill 0.254)
		(layers "F.Cu" "B.Cu")
		(net "M_D_DQ<58>")
	)
	(via
		(at 290.6522 -100.481638)
		(size 0.508)
		(drill 0.254)
		(layers "F.Cu" "B.Cu")
		(net "M_D_DQ<58>")
	)
	(via
		(at 315.399928 -131.611878)
		(size 0.508)
		(drill 0.254)
		(layers "F.Cu" "B.Cu")
		(net "M_D_DQ<58>")
	)
	(segment
		(start 315.400436 -132.876036)
		(end 315.400436 -131.612386)
		(width 0.1651)
		(layer "B.Cu")
		(net "M_D_DQ<58>")
	)
	(segment
		(start 315.400436 -131.612386)
		(end 315.399928 -131.611878)
		(width 0.1651)
		(layer "B.Cu")
		(net "M_D_DQ<58>")
	)
	(segment
		(start 315.2902 -130.398774)
		(end 315.2902 -131.50215)
		(width 0.14224)
		(layer "In2.Cu")
		(net "M_D_DQ<58>")
	)
	(segment
		(start 317.598044 -125.99416)
		(end 317.200788 -125.99416)
		(width 0.14224)
		(layer "In2.Cu")
		(net "M_D_DQ<58>")
	)
	(segment
		(start 303.084738 -105.6894)
		(end 309.841138 -112.4458)
		(width 0.14224)
		(layer "In2.Cu")
		(net "M_D_DQ<58>")
	)
	(segment
		(start 290.30549 -101.672136)
		(end 290.341558 -101.728016)
		(width 0.0889)
		(layer "In2.Cu")
		(net "M_D_DQ<58>")
	)
	(segment
		(start 299.322236 -104.648)
		(end 300.363636 -105.6894)
		(width 0.14224)
		(layer "In2.Cu")
		(net "M_D_DQ<58>")
	)
	(segment
		(start 315.2902 -131.50215)
		(end 315.399928 -131.611878)
		(width 0.14224)
		(layer "In2.Cu")
		(net "M_D_DQ<58>")
	)
	(segment
		(start 300.363636 -105.6894)
		(end 303.084738 -105.6894)
		(width 0.14224)
		(layer "In2.Cu")
		(net "M_D_DQ<58>")
	)
	(segment
		(start 297.484546 -104.4194)
		(end 297.713146 -104.648)
		(width 0.0889)
		(layer "In2.Cu")
		(net "M_D_DQ<58>")
	)
	(segment
		(start 315.918596 -129.216404)
		(end 315.918596 -129.770378)
		(width 0.14224)
		(layer "In2.Cu")
		(net "M_D_DQ<58>")
	)
	(segment
		(start 290.447984 -101.01707)
		(end 290.300664 -101.280722)
		(width 0.0889)
		(layer "In2.Cu")
		(net "M_D_DQ<58>")
	)
	(segment
		(start 316.1792 -125.109732)
		(end 316.1792 -128.9558)
		(width 0.14224)
		(layer "In2.Cu")
		(net "M_D_DQ<58>")
	)
	(segment
		(start 316.992 -125.092968)
		(end 316.797182 -124.89815)
		(width 0.14224)
		(layer "In2.Cu")
		(net "M_D_DQ<58>")
	)
	(segment
		(start 290.89604 -102.281736)
		(end 291.572696 -102.958392)
		(width 0.0889)
		(layer "In2.Cu")
		(net "M_D_DQ<58>")
	)
	(segment
		(start 317.8048 -119.022368)
		(end 317.8048 -125.787404)
		(width 0.14224)
		(layer "In2.Cu")
		(net "M_D_DQ<58>")
	)
	(segment
		(start 296.263568 -104.4194)
		(end 297.484546 -104.4194)
		(width 0.0889)
		(layer "In2.Cu")
		(net "M_D_DQ<58>")
	)
	(segment
		(start 315.399928 -131.611878)
		(end 314.966858 -132.044948)
		(width 0.14224)
		(layer "In2.Cu")
		(net "M_D_DQ<58>")
	)
	(segment
		(start 291.572696 -102.958392)
		(end 294.80256 -102.958392)
		(width 0.0889)
		(layer "In2.Cu")
		(net "M_D_DQ<58>")
	)
	(segment
		(start 316.390782 -124.89815)
		(end 316.1792 -125.109732)
		(width 0.14224)
		(layer "In2.Cu")
		(net "M_D_DQ<58>")
	)
	(segment
		(start 309.841138 -112.4458)
		(end 311.228232 -112.4458)
		(width 0.14224)
		(layer "In2.Cu")
		(net "M_D_DQ<58>")
	)
	(segment
		(start 290.6522 -100.481638)
		(end 290.6522 -100.812854)
		(width 0.0889)
		(layer "In2.Cu")
		(net "M_D_DQ<58>")
	)
	(segment
		(start 290.341558 -101.728016)
		(end 290.895024 -102.281482)
		(width 0.0889)
		(layer "In2.Cu")
		(net "M_D_DQ<58>")
	)
	(segment
		(start 316.992 -125.785372)
		(end 316.992 -125.092968)
		(width 0.14224)
		(layer "In2.Cu")
		(net "M_D_DQ<58>")
	)
	(segment
		(start 311.228232 -112.4458)
		(end 317.8048 -119.022368)
		(width 0.14224)
		(layer "In2.Cu")
		(net "M_D_DQ<58>")
	)
	(segment
		(start 314.966858 -134.632446)
		(end 316.249812 -135.9154)
		(width 0.14224)
		(layer "In2.Cu")
		(net "M_D_DQ<58>")
	)
	(segment
		(start 290.895024 -102.281736)
		(end 290.89604 -102.281736)
		(width 0.0889)
		(layer "In2.Cu")
		(net "M_D_DQ<58>")
	)
	(segment
		(start 317.8048 -125.787404)
		(end 317.598044 -125.99416)
		(width 0.14224)
		(layer "In2.Cu")
		(net "M_D_DQ<58>")
	)
	(segment
		(start 315.918596 -129.770378)
		(end 315.2902 -130.398774)
		(width 0.14224)
		(layer "In2.Cu")
		(net "M_D_DQ<58>")
	)
	(segment
		(start 316.1792 -128.9558)
		(end 315.918596 -129.216404)
		(width 0.14224)
		(layer "In2.Cu")
		(net "M_D_DQ<58>")
	)
	(segment
		(start 297.713146 -104.648)
		(end 299.322236 -104.648)
		(width 0.14224)
		(layer "In2.Cu")
		(net "M_D_DQ<58>")
	)
	(segment
		(start 314.966858 -132.044948)
		(end 314.966858 -134.632446)
		(width 0.14224)
		(layer "In2.Cu")
		(net "M_D_DQ<58>")
	)
	(segment
		(start 316.797182 -124.89815)
		(end 316.390782 -124.89815)
		(width 0.14224)
		(layer "In2.Cu")
		(net "M_D_DQ<58>")
	)
	(segment
		(start 290.6522 -100.812854)
		(end 290.447984 -101.01707)
		(width 0.0889)
		(layer "In2.Cu")
		(net "M_D_DQ<58>")
	)
	(segment
		(start 290.895024 -102.281482)
		(end 290.895024 -102.281736)
		(width 0.0889)
		(layer "In2.Cu")
		(net "M_D_DQ<58>")
	)
	(segment
		(start 317.200788 -125.99416)
		(end 316.992 -125.785372)
		(width 0.14224)
		(layer "In2.Cu")
		(net "M_D_DQ<58>")
	)
	(segment
		(start 294.80256 -102.958392)
		(end 296.263568 -104.4194)
		(width 0.0889)
		(layer "In2.Cu")
		(net "M_D_DQ<58>")
	)
	(arc
		(start 290.300664 -101.280722)
		(mid 290.251909 -101.477074)
		(end 290.30549 -101.672136)
		(width 0.0889)
		(layer "In2.Cu")
		(net "M_D_DQ<58>")
	)
	(segment
		(start 309.450486 -133.0706)
		(end 309.449978 -133.076442)
		(width 0.1651)
		(layer "F.Cu")
		(net "M_D_DQ<57>")
	)
	(segment
		(start 287.50514 -98.995738)
		(end 288.07664 -98.995738)
		(width 0.1651)
		(layer "F.Cu")
		(net "M_D_DQ<57>")
	)
	(segment
		(start 309.449978 -133.076442)
		(end 309.449978 -134.340346)
		(width 0.1651)
		(layer "F.Cu")
		(net "M_D_DQ<57>")
	)
	(via
		(at 288.07664 -98.995738)
		(size 0.508)
		(drill 0.254)
		(layers "F.Cu" "B.Cu")
		(net "M_D_DQ<57>")
	)
	(via
		(at 309.449978 -134.340346)
		(size 0.508)
		(drill 0.254)
		(layers "F.Cu" "B.Cu")
		(net "M_D_DQ<57>")
	)
	(via
		(at 310.122062 -130.330956)
		(size 0.508)
		(drill 0.254)
		(layers "F.Cu" "B.Cu")
		(net "M_D_DQ<57>")
	)
	(segment
		(start 310.122062 -130.330956)
		(end 310.122062 -129.827782)
		(width 0.1651)
		(layer "B.Cu")
		(net "M_D_DQ<57>")
	)
	(segment
		(start 310.299862 -128.276096)
		(end 310.30037 -128.276096)
		(width 0.1651)
		(layer "B.Cu")
		(net "M_D_DQ<57>")
	)
	(segment
		(start 310.122062 -129.827782)
		(end 310.299862 -129.649982)
		(width 0.1651)
		(layer "B.Cu")
		(net "M_D_DQ<57>")
	)
	(segment
		(start 310.299862 -129.649982)
		(end 310.299862 -128.276096)
		(width 0.1651)
		(layer "B.Cu")
		(net "M_D_DQ<57>")
	)
	(segment
		(start 310.257444 -125.75159)
		(end 310.480456 -125.974602)
		(width 0.14224)
		(layer "In2.Cu")
		(net "M_D_DQ<57>")
	)
	(segment
		(start 287.725104 -100.1776)
		(end 287.80867 -100.322888)
		(width 0.0889)
		(layer "In2.Cu")
		(net "M_D_DQ<57>")
	)
	(segment
		(start 310.09971 -130.330956)
		(end 309.671466 -130.7592)
		(width 0.14224)
		(layer "In2.Cu")
		(net "M_D_DQ<57>")
	)
	(segment
		(start 309.851044 -133.8834)
		(end 309.851044 -134.1882)
		(width 0.14224)
		(layer "In2.Cu")
		(net "M_D_DQ<57>")
	)
	(segment
		(start 291.353748 -106.5657)
		(end 292.343078 -107.55503)
		(width 0.14224)
		(layer "In2.Cu")
		(net "M_D_DQ<57>")
	)
	(segment
		(start 309.671466 -130.7592)
		(end 309.671466 -131.188968)
		(width 0.14224)
		(layer "In2.Cu")
		(net "M_D_DQ<57>")
	)
	(segment
		(start 311.351422 -128.2446)
		(end 310.598566 -128.2446)
		(width 0.14224)
		(layer "In2.Cu")
		(net "M_D_DQ<57>")
	)
	(segment
		(start 295.0464 -108.7882)
		(end 300.676056 -108.7882)
		(width 0.14224)
		(layer "In2.Cu")
		(net "M_D_DQ<57>")
	)
	(segment
		(start 309.901844 -131.823968)
		(end 309.611268 -132.114544)
		(width 0.14224)
		(layer "In2.Cu")
		(net "M_D_DQ<57>")
	)
	(segment
		(start 311.351422 -127.58166)
		(end 311.506362 -127.7366)
		(width 0.14224)
		(layer "In2.Cu")
		(net "M_D_DQ<57>")
	)
	(segment
		(start 300.676056 -108.7882)
		(end 310.56453 -118.676674)
		(width 0.14224)
		(layer "In2.Cu")
		(net "M_D_DQ<57>")
	)
	(segment
		(start 311.920382 -126.628652)
		(end 311.761632 -126.787402)
		(width 0.14224)
		(layer "In2.Cu")
		(net "M_D_DQ<57>")
	)
	(segment
		(start 310.598566 -128.2446)
		(end 310.40451 -128.438656)
		(width 0.14224)
		(layer "In2.Cu")
		(net "M_D_DQ<57>")
	)
	(segment
		(start 310.480456 -125.974602)
		(end 311.772808 -125.974602)
		(width 0.14224)
		(layer "In2.Cu")
		(net "M_D_DQ<57>")
	)
	(segment
		(start 292.343078 -107.55503)
		(end 293.81323 -107.55503)
		(width 0.14224)
		(layer "In2.Cu")
		(net "M_D_DQ<57>")
	)
	(segment
		(start 309.698898 -134.340346)
		(end 309.449978 -134.340346)
		(width 0.14224)
		(layer "In2.Cu")
		(net "M_D_DQ<57>")
	)
	(segment
		(start 287.746694 -99.757484)
		(end 287.72993 -99.786186)
		(width 0.0889)
		(layer "In2.Cu")
		(net "M_D_DQ<57>")
	)
	(segment
		(start 310.40451 -129.959608)
		(end 310.122062 -130.242056)
		(width 0.14224)
		(layer "In2.Cu")
		(net "M_D_DQ<57>")
	)
	(segment
		(start 311.905396 -124.829316)
		(end 311.583832 -125.15088)
		(width 0.14224)
		(layer "In2.Cu")
		(net "M_D_DQ<57>")
	)
	(segment
		(start 311.506362 -127.7366)
		(end 311.506362 -128.08966)
		(width 0.14224)
		(layer "In2.Cu")
		(net "M_D_DQ<57>")
	)
	(segment
		(start 310.56453 -118.676674)
		(end 310.827674 -118.676674)
		(width 0.14224)
		(layer "In2.Cu")
		(net "M_D_DQ<57>")
	)
	(segment
		(start 309.671466 -131.188968)
		(end 309.901844 -131.419346)
		(width 0.14224)
		(layer "In2.Cu")
		(net "M_D_DQ<57>")
	)
	(segment
		(start 310.35244 -127.42672)
		(end 310.50738 -127.58166)
		(width 0.14224)
		(layer "In2.Cu")
		(net "M_D_DQ<57>")
	)
	(segment
		(start 309.901844 -131.419346)
		(end 309.901844 -131.823968)
		(width 0.14224)
		(layer "In2.Cu")
		(net "M_D_DQ<57>")
	)
	(segment
		(start 311.905396 -120.31345)
		(end 312.1914 -120.599454)
		(width 0.14224)
		(layer "In2.Cu")
		(net "M_D_DQ<57>")
	)
	(segment
		(start 312.1914 -120.599454)
		(end 312.1914 -121.12625)
		(width 0.14224)
		(layer "In2.Cu")
		(net "M_D_DQ<57>")
	)
	(segment
		(start 311.905396 -120.01754)
		(end 311.905396 -120.31345)
		(width 0.14224)
		(layer "In2.Cu")
		(net "M_D_DQ<57>")
	)
	(segment
		(start 311.920382 -126.122176)
		(end 311.920382 -126.628652)
		(width 0.14224)
		(layer "In2.Cu")
		(net "M_D_DQ<57>")
	)
	(segment
		(start 310.122062 -130.242056)
		(end 310.122062 -130.330956)
		(width 0.14224)
		(layer "In2.Cu")
		(net "M_D_DQ<57>")
	)
	(segment
		(start 310.544464 -126.787402)
		(end 310.35244 -126.979426)
		(width 0.14224)
		(layer "In2.Cu")
		(net "M_D_DQ<57>")
	)
	(segment
		(start 310.40451 -128.438656)
		(end 310.40451 -129.959608)
		(width 0.14224)
		(layer "In2.Cu")
		(net "M_D_DQ<57>")
	)
	(segment
		(start 310.257444 -125.349)
		(end 310.257444 -125.75159)
		(width 0.14224)
		(layer "In2.Cu")
		(net "M_D_DQ<57>")
	)
	(segment
		(start 310.455564 -125.15088)
		(end 310.257444 -125.349)
		(width 0.14224)
		(layer "In2.Cu")
		(net "M_D_DQ<57>")
	)
	(segment
		(start 312.1914 -121.12625)
		(end 311.905396 -121.412254)
		(width 0.14224)
		(layer "In2.Cu")
		(net "M_D_DQ<57>")
	)
	(segment
		(start 287.67659 -103.193342)
		(end 291.048948 -106.5657)
		(width 0.0889)
		(layer "In2.Cu")
		(net "M_D_DQ<57>")
	)
	(segment
		(start 309.825644 -132.6896)
		(end 309.825644 -133.1214)
		(width 0.14224)
		(layer "In2.Cu")
		(net "M_D_DQ<57>")
	)
	(segment
		(start 311.761632 -126.787402)
		(end 310.544464 -126.787402)
		(width 0.14224)
		(layer "In2.Cu")
		(net "M_D_DQ<57>")
	)
	(segment
		(start 309.825644 -133.1214)
		(end 309.611268 -133.335776)
		(width 0.14224)
		(layer "In2.Cu")
		(net "M_D_DQ<57>")
	)
	(segment
		(start 287.80867 -102.66045)
		(end 287.67659 -102.79253)
		(width 0.0889)
		(layer "In2.Cu")
		(net "M_D_DQ<57>")
	)
	(segment
		(start 310.827674 -118.676674)
		(end 311.270904 -119.119904)
		(width 0.14224)
		(layer "In2.Cu")
		(net "M_D_DQ<57>")
	)
	(segment
		(start 288.07664 -98.995738)
		(end 287.746694 -99.757484)
		(width 0.0889)
		(layer "In2.Cu")
		(net "M_D_DQ<57>")
	)
	(segment
		(start 291.048948 -106.5657)
		(end 291.353748 -106.5657)
		(width 0.0889)
		(layer "In2.Cu")
		(net "M_D_DQ<57>")
	)
	(segment
		(start 311.905396 -121.412254)
		(end 311.905396 -124.829316)
		(width 0.14224)
		(layer "In2.Cu")
		(net "M_D_DQ<57>")
	)
	(segment
		(start 309.611268 -132.114544)
		(end 309.611268 -132.475224)
		(width 0.14224)
		(layer "In2.Cu")
		(net "M_D_DQ<57>")
	)
	(segment
		(start 311.772808 -125.974602)
		(end 311.920382 -126.122176)
		(width 0.14224)
		(layer "In2.Cu")
		(net "M_D_DQ<57>")
	)
	(segment
		(start 311.583832 -125.15088)
		(end 310.455564 -125.15088)
		(width 0.14224)
		(layer "In2.Cu")
		(net "M_D_DQ<57>")
	)
	(segment
		(start 309.611268 -133.643624)
		(end 309.851044 -133.8834)
		(width 0.14224)
		(layer "In2.Cu")
		(net "M_D_DQ<57>")
	)
	(segment
		(start 309.611268 -133.335776)
		(end 309.611268 -133.643624)
		(width 0.14224)
		(layer "In2.Cu")
		(net "M_D_DQ<57>")
	)
	(segment
		(start 309.851044 -134.1882)
		(end 309.698898 -134.340346)
		(width 0.14224)
		(layer "In2.Cu")
		(net "M_D_DQ<57>")
	)
	(segment
		(start 311.270904 -119.383048)
		(end 311.905396 -120.01754)
		(width 0.14224)
		(layer "In2.Cu")
		(net "M_D_DQ<57>")
	)
	(segment
		(start 309.611268 -132.475224)
		(end 309.825644 -132.6896)
		(width 0.14224)
		(layer "In2.Cu")
		(net "M_D_DQ<57>")
	)
	(segment
		(start 310.50738 -127.58166)
		(end 311.351422 -127.58166)
		(width 0.14224)
		(layer "In2.Cu")
		(net "M_D_DQ<57>")
	)
	(segment
		(start 287.80867 -100.322888)
		(end 287.80867 -102.66045)
		(width 0.0889)
		(layer "In2.Cu")
		(net "M_D_DQ<57>")
	)
	(segment
		(start 311.270904 -119.119904)
		(end 311.270904 -119.383048)
		(width 0.14224)
		(layer "In2.Cu")
		(net "M_D_DQ<57>")
	)
	(segment
		(start 311.506362 -128.08966)
		(end 311.351422 -128.2446)
		(width 0.14224)
		(layer "In2.Cu")
		(net "M_D_DQ<57>")
	)
	(segment
		(start 310.35244 -126.979426)
		(end 310.35244 -127.42672)
		(width 0.14224)
		(layer "In2.Cu")
		(net "M_D_DQ<57>")
	)
	(segment
		(start 293.81323 -107.55503)
		(end 295.0464 -108.7882)
		(width 0.14224)
		(layer "In2.Cu")
		(net "M_D_DQ<57>")
	)
	(segment
		(start 287.67659 -102.79253)
		(end 287.67659 -103.193342)
		(width 0.0889)
		(layer "In2.Cu")
		(net "M_D_DQ<57>")
	)
	(segment
		(start 310.122062 -130.330956)
		(end 310.09971 -130.330956)
		(width 0.14224)
		(layer "In2.Cu")
		(net "M_D_DQ<57>")
	)
	(arc
		(start 287.72993 -99.786186)
		(mid 287.67646 -99.981249)
		(end 287.725104 -100.1776)
		(width 0.0889)
		(layer "In2.Cu")
		(net "M_D_DQ<57>")
	)
	(segment
		(start 287.50514 -97.014538)
		(end 288.07664 -97.014538)
		(width 0.1651)
		(layer "F.Cu")
		(net "M_D_DQ<56>")
	)
	(segment
		(start 310.30037 -137.67054)
		(end 310.299862 -137.676382)
		(width 0.1651)
		(layer "F.Cu")
		(net "M_D_DQ<56>")
	)
	(segment
		(start 310.299862 -137.676382)
		(end 310.122062 -135.8138)
		(width 0.1651)
		(layer "F.Cu")
		(net "M_D_DQ<56>")
	)
	(via
		(at 309.449978 -131.611878)
		(size 0.508)
		(drill 0.254)
		(layers "F.Cu" "B.Cu")
		(net "M_D_DQ<56>")
	)
	(via
		(at 288.07664 -97.014538)
		(size 0.508)
		(drill 0.254)
		(layers "F.Cu" "B.Cu")
		(net "M_D_DQ<56>")
	)
	(via
		(at 310.122062 -135.8138)
		(size 0.508)
		(drill 0.254)
		(layers "F.Cu" "B.Cu")
		(net "M_D_DQ<56>")
	)
	(segment
		(start 309.449978 -132.875782)
		(end 309.449978 -131.611878)
		(width 0.1651)
		(layer "B.Cu")
		(net "M_D_DQ<56>")
	)
	(segment
		(start 309.450486 -132.876036)
		(end 309.449978 -132.875782)
		(width 0.1651)
		(layer "B.Cu")
		(net "M_D_DQ<56>")
	)
	(segment
		(start 309.644796 -129.076196)
		(end 309.88 -129.3114)
		(width 0.14224)
		(layer "In2.Cu")
		(net "M_D_DQ<56>")
	)
	(segment
		(start 310.457596 -124.0028)
		(end 310.254396 -123.7996)
		(width 0.14224)
		(layer "In2.Cu")
		(net "M_D_DQ<56>")
	)
	(segment
		(start 287.581594 -97.680272)
		(end 287.56483 -97.709736)
		(width 0.0889)
		(layer "In2.Cu")
		(net "M_D_DQ<56>")
	)
	(segment
		(start 311.270396 -120.280684)
		(end 311.270396 -124.409962)
		(width 0.14224)
		(layer "In2.Cu")
		(net "M_D_DQ<56>")
	)
	(segment
		(start 291.99332 -108.03382)
		(end 293.614856 -108.03382)
		(width 0.14224)
		(layer "In2.Cu")
		(net "M_D_DQ<56>")
	)
	(segment
		(start 287.55848 -100.270818)
		(end 287.61817 -100.373942)
		(width 0.0889)
		(layer "In2.Cu")
		(net "M_D_DQ<56>")
	)
	(segment
		(start 287.56483 -98.300286)
		(end 287.569656 -98.308922)
		(width 0.0889)
		(layer "In2.Cu")
		(net "M_D_DQ<56>")
	)
	(segment
		(start 288.07664 -97.014538)
		(end 287.581594 -97.680272)
		(width 0.0889)
		(layer "In2.Cu")
		(net "M_D_DQ<56>")
	)
	(segment
		(start 294.851836 -109.2708)
		(end 300.260512 -109.2708)
		(width 0.14224)
		(layer "In2.Cu")
		(net "M_D_DQ<56>")
	)
	(segment
		(start 309.88 -129.3114)
		(end 309.88 -129.814574)
		(width 0.14224)
		(layer "In2.Cu")
		(net "M_D_DQ<56>")
	)
	(segment
		(start 309.449978 -131.611878)
		(end 309.016908 -132.044948)
		(width 0.14224)
		(layer "In2.Cu")
		(net "M_D_DQ<56>")
	)
	(segment
		(start 287.486598 -103.272844)
		(end 290.9316 -106.717846)
		(width 0.0889)
		(layer "In2.Cu")
		(net "M_D_DQ<56>")
	)
	(segment
		(start 287.55848 -99.280218)
		(end 287.56483 -99.290886)
		(width 0.0889)
		(layer "In2.Cu")
		(net "M_D_DQ<56>")
	)
	(segment
		(start 300.260512 -109.2708)
		(end 311.270396 -120.280684)
		(width 0.14224)
		(layer "In2.Cu")
		(net "M_D_DQ<56>")
	)
	(segment
		(start 309.016908 -135.00481)
		(end 309.825898 -135.8138)
		(width 0.14224)
		(layer "In2.Cu")
		(net "M_D_DQ<56>")
	)
	(segment
		(start 309.644796 -124.0028)
		(end 309.644796 -129.076196)
		(width 0.14224)
		(layer "In2.Cu")
		(net "M_D_DQ<56>")
	)
	(segment
		(start 311.270396 -124.409962)
		(end 311.067196 -124.613162)
		(width 0.14224)
		(layer "In2.Cu")
		(net "M_D_DQ<56>")
	)
	(segment
		(start 310.457596 -124.409962)
		(end 310.457596 -124.0028)
		(width 0.14224)
		(layer "In2.Cu")
		(net "M_D_DQ<56>")
	)
	(segment
		(start 287.486598 -102.713028)
		(end 287.486598 -103.272844)
		(width 0.0889)
		(layer "In2.Cu")
		(net "M_D_DQ<56>")
	)
	(segment
		(start 309.0926 -131.2545)
		(end 309.449978 -131.611878)
		(width 0.14224)
		(layer "In2.Cu")
		(net "M_D_DQ<56>")
	)
	(segment
		(start 309.88 -129.814574)
		(end 309.0926 -130.601974)
		(width 0.14224)
		(layer "In2.Cu")
		(net "M_D_DQ<56>")
	)
	(segment
		(start 290.9316 -106.9721)
		(end 291.99332 -108.03382)
		(width 0.14224)
		(layer "In2.Cu")
		(net "M_D_DQ<56>")
	)
	(segment
		(start 287.56483 -99.290886)
		(end 287.569656 -99.299522)
		(width 0.0889)
		(layer "In2.Cu")
		(net "M_D_DQ<56>")
	)
	(segment
		(start 310.254396 -123.7996)
		(end 309.847996 -123.7996)
		(width 0.14224)
		(layer "In2.Cu")
		(net "M_D_DQ<56>")
	)
	(segment
		(start 309.016908 -132.044948)
		(end 309.016908 -135.00481)
		(width 0.14224)
		(layer "In2.Cu")
		(net "M_D_DQ<56>")
	)
	(segment
		(start 311.067196 -124.613162)
		(end 310.660796 -124.613162)
		(width 0.14224)
		(layer "In2.Cu")
		(net "M_D_DQ<56>")
	)
	(segment
		(start 290.9316 -106.717846)
		(end 290.9316 -106.9721)
		(width 0.0889)
		(layer "In2.Cu")
		(net "M_D_DQ<56>")
	)
	(segment
		(start 287.55848 -98.289618)
		(end 287.56483 -98.300286)
		(width 0.0889)
		(layer "In2.Cu")
		(net "M_D_DQ<56>")
	)
	(segment
		(start 293.614856 -108.03382)
		(end 294.851836 -109.2708)
		(width 0.14224)
		(layer "In2.Cu")
		(net "M_D_DQ<56>")
	)
	(segment
		(start 309.0926 -130.601974)
		(end 309.0926 -131.2545)
		(width 0.14224)
		(layer "In2.Cu")
		(net "M_D_DQ<56>")
	)
	(segment
		(start 287.61817 -102.581456)
		(end 287.486598 -102.713028)
		(width 0.0889)
		(layer "In2.Cu")
		(net "M_D_DQ<56>")
	)
	(segment
		(start 287.61817 -100.373942)
		(end 287.61817 -102.581456)
		(width 0.0889)
		(layer "In2.Cu")
		(net "M_D_DQ<56>")
	)
	(segment
		(start 309.825898 -135.8138)
		(end 310.122062 -135.8138)
		(width 0.14224)
		(layer "In2.Cu")
		(net "M_D_DQ<56>")
	)
	(segment
		(start 310.660796 -124.613162)
		(end 310.457596 -124.409962)
		(width 0.14224)
		(layer "In2.Cu")
		(net "M_D_DQ<56>")
	)
	(segment
		(start 309.847996 -123.7996)
		(end 309.644796 -124.0028)
		(width 0.14224)
		(layer "In2.Cu")
		(net "M_D_DQ<56>")
	)
	(arc
		(start 287.569656 -98.308922)
		(mid 287.618411 -98.505274)
		(end 287.56483 -98.700336)
		(width 0.0889)
		(layer "In2.Cu")
		(net "M_D_DQ<56>")
	)
	(arc
		(start 287.56483 -98.700336)
		(mid 287.485608 -98.989454)
		(end 287.55848 -99.280218)
		(width 0.0889)
		(layer "In2.Cu")
		(net "M_D_DQ<56>")
	)
	(arc
		(start 287.56483 -97.709736)
		(mid 287.485608 -97.998854)
		(end 287.55848 -98.289618)
		(width 0.0889)
		(layer "In2.Cu")
		(net "M_D_DQ<56>")
	)
	(arc
		(start 287.569656 -99.299522)
		(mid 287.618411 -99.495874)
		(end 287.56483 -99.690936)
		(width 0.0889)
		(layer "In2.Cu")
		(net "M_D_DQ<56>")
	)
	(arc
		(start 287.56483 -99.690936)
		(mid 287.485608 -99.980054)
		(end 287.55848 -100.270818)
		(width 0.0889)
		(layer "In2.Cu")
		(net "M_D_DQ<56>")
	)
	(segment
		(start 304.349912 -133.076442)
		(end 304.349912 -134.340346)
		(width 0.1651)
		(layer "F.Cu")
		(net "M_D_DQ<55>")
	)
	(segment
		(start 304.35042 -133.0706)
		(end 304.349912 -133.076442)
		(width 0.1651)
		(layer "F.Cu")
		(net "M_D_DQ<55>")
	)
	(segment
		(start 284.071314 -98.995738)
		(end 284.642814 -98.995738)
		(width 0.1651)
		(layer "F.Cu")
		(net "M_D_DQ<55>")
	)
	(via
		(at 305.199796 -130.330956)
		(size 0.508)
		(drill 0.254)
		(layers "F.Cu" "B.Cu")
		(net "M_D_DQ<55>")
	)
	(via
		(at 284.642814 -98.995738)
		(size 0.508)
		(drill 0.254)
		(layers "F.Cu" "B.Cu")
		(net "M_D_DQ<55>")
	)
	(via
		(at 304.349912 -134.340346)
		(size 0.508)
		(drill 0.254)
		(layers "F.Cu" "B.Cu")
		(net "M_D_DQ<55>")
	)
	(segment
		(start 305.199796 -128.276096)
		(end 305.199796 -130.330956)
		(width 0.1651)
		(layer "B.Cu")
		(net "M_D_DQ<55>")
	)
	(segment
		(start 305.200304 -128.276096)
		(end 305.199796 -128.276096)
		(width 0.1651)
		(layer "B.Cu")
		(net "M_D_DQ<55>")
	)
	(segment
		(start 298.219876 -113.80978)
		(end 298.219876 -114.182144)
		(width 0.14224)
		(layer "In2.Cu")
		(net "M_D_DQ<55>")
	)
	(segment
		(start 285.160974 -102.252018)
		(end 285.154624 -102.262686)
		(width 0.0889)
		(layer "In2.Cu")
		(net "M_D_DQ<55>")
	)
	(segment
		(start 296.893996 -113.80978)
		(end 296.893996 -114.182144)
		(width 0.14224)
		(layer "In2.Cu")
		(net "M_D_DQ<55>")
	)
	(segment
		(start 304.79365 -131.233418)
		(end 304.79365 -131.9022)
		(width 0.14224)
		(layer "In2.Cu")
		(net "M_D_DQ<55>")
	)
	(segment
		(start 296.893996 -114.182144)
		(end 297.048936 -114.337084)
		(width 0.14224)
		(layer "In2.Cu")
		(net "M_D_DQ<55>")
	)
	(segment
		(start 305.56962 -128.401318)
		(end 305.414934 -128.556004)
		(width 0.14224)
		(layer "In2.Cu")
		(net "M_D_DQ<55>")
	)
	(segment
		(start 285.154624 -100.281486)
		(end 285.149798 -100.290122)
		(width 0.0889)
		(layer "In2.Cu")
		(net "M_D_DQ<55>")
	)
	(segment
		(start 297.048936 -114.337084)
		(end 297.401996 -114.337084)
		(width 0.14224)
		(layer "In2.Cu")
		(net "M_D_DQ<55>")
	)
	(segment
		(start 305.1302 -119.329454)
		(end 305.1302 -123.695968)
		(width 0.14224)
		(layer "In2.Cu")
		(net "M_D_DQ<55>")
	)
	(segment
		(start 285.160974 -104.233218)
		(end 285.160974 -106.192066)
		(width 0.0889)
		(layer "In2.Cu")
		(net "M_D_DQ<55>")
	)
	(segment
		(start 287.274 -111.1504)
		(end 287.274 -112.572038)
		(width 0.14224)
		(layer "In2.Cu")
		(net "M_D_DQ<55>")
	)
	(segment
		(start 285.160974 -101.261418)
		(end 285.154624 -101.272086)
		(width 0.0889)
		(layer "In2.Cu")
		(net "M_D_DQ<55>")
	)
	(segment
		(start 304.76825 -133.0198)
		(end 304.511202 -133.276848)
		(width 0.14224)
		(layer "In2.Cu")
		(net "M_D_DQ<55>")
	)
	(segment
		(start 304.511202 -133.276848)
		(end 304.511202 -133.550152)
		(width 0.14224)
		(layer "In2.Cu")
		(net "M_D_DQ<55>")
	)
	(segment
		(start 305.39817 -127.546608)
		(end 305.58994 -127.738378)
		(width 0.14224)
		(layer "In2.Cu")
		(net "M_D_DQ<55>")
	)
	(segment
		(start 297.711876 -113.65484)
		(end 298.064936 -113.65484)
		(width 0.14224)
		(layer "In2.Cu")
		(net "M_D_DQ<55>")
	)
	(segment
		(start 285.160974 -103.242618)
		(end 285.154624 -103.253286)
		(width 0.0889)
		(layer "In2.Cu")
		(net "M_D_DQ<55>")
	)
	(segment
		(start 305.88077 -128.401318)
		(end 305.56962 -128.401318)
		(width 0.14224)
		(layer "In2.Cu")
		(net "M_D_DQ<55>")
	)
	(segment
		(start 304.76825 -132.715)
		(end 304.76825 -133.0198)
		(width 0.14224)
		(layer "In2.Cu")
		(net "M_D_DQ<55>")
	)
	(segment
		(start 305.88077 -127.738378)
		(end 306.03571 -127.893318)
		(width 0.14224)
		(layer "In2.Cu")
		(net "M_D_DQ<55>")
	)
	(segment
		(start 285.160974 -106.192066)
		(end 285.451804 -106.482896)
		(width 0.0889)
		(layer "In2.Cu")
		(net "M_D_DQ<55>")
	)
	(segment
		(start 305.1302 -123.695968)
		(end 305.81219 -124.377958)
		(width 0.14224)
		(layer "In2.Cu")
		(net "M_D_DQ<55>")
	)
	(segment
		(start 298.064936 -113.65484)
		(end 298.219876 -113.80978)
		(width 0.14224)
		(layer "In2.Cu")
		(net "M_D_DQ<55>")
	)
	(segment
		(start 305.199796 -130.330956)
		(end 305.177444 -130.330956)
		(width 0.14224)
		(layer "In2.Cu")
		(net "M_D_DQ<55>")
	)
	(segment
		(start 304.7492 -130.7592)
		(end 304.7492 -131.188968)
		(width 0.14224)
		(layer "In2.Cu")
		(net "M_D_DQ<55>")
	)
	(segment
		(start 297.556936 -113.80978)
		(end 297.711876 -113.65484)
		(width 0.14224)
		(layer "In2.Cu")
		(net "M_D_DQ<55>")
	)
	(segment
		(start 305.39817 -125.69063)
		(end 305.39817 -127.546608)
		(width 0.14224)
		(layer "In2.Cu")
		(net "M_D_DQ<55>")
	)
	(segment
		(start 298.882816 -113.80978)
		(end 299.037756 -113.65484)
		(width 0.14224)
		(layer "In2.Cu")
		(net "M_D_DQ<55>")
	)
	(segment
		(start 305.81219 -125.27661)
		(end 305.39817 -125.69063)
		(width 0.14224)
		(layer "In2.Cu")
		(net "M_D_DQ<55>")
	)
	(segment
		(start 285.13786 -99.661472)
		(end 285.154624 -99.690936)
		(width 0.0889)
		(layer "In2.Cu")
		(net "M_D_DQ<55>")
	)
	(segment
		(start 297.401996 -114.337084)
		(end 297.556936 -114.182144)
		(width 0.14224)
		(layer "In2.Cu")
		(net "M_D_DQ<55>")
	)
	(segment
		(start 298.727876 -114.337084)
		(end 298.882816 -114.182144)
		(width 0.14224)
		(layer "In2.Cu")
		(net "M_D_DQ<55>")
	)
	(segment
		(start 296.16908 -113.65484)
		(end 296.739056 -113.65484)
		(width 0.14224)
		(layer "In2.Cu")
		(net "M_D_DQ<55>")
	)
	(segment
		(start 305.58994 -127.738378)
		(end 305.88077 -127.738378)
		(width 0.14224)
		(layer "In2.Cu")
		(net "M_D_DQ<55>")
	)
	(segment
		(start 298.219876 -114.182144)
		(end 298.374816 -114.337084)
		(width 0.14224)
		(layer "In2.Cu")
		(net "M_D_DQ<55>")
	)
	(segment
		(start 304.6222 -134.340346)
		(end 304.349912 -134.340346)
		(width 0.14224)
		(layer "In2.Cu")
		(net "M_D_DQ<55>")
	)
	(segment
		(start 305.177444 -130.330956)
		(end 304.7492 -130.7592)
		(width 0.14224)
		(layer "In2.Cu")
		(net "M_D_DQ<55>")
	)
	(segment
		(start 305.414934 -130.115818)
		(end 305.199796 -130.330956)
		(width 0.14224)
		(layer "In2.Cu")
		(net "M_D_DQ<55>")
	)
	(segment
		(start 299.037756 -113.65484)
		(end 299.455586 -113.65484)
		(width 0.14224)
		(layer "In2.Cu")
		(net "M_D_DQ<55>")
	)
	(segment
		(start 298.882816 -114.182144)
		(end 298.882816 -113.80978)
		(width 0.14224)
		(layer "In2.Cu")
		(net "M_D_DQ<55>")
	)
	(segment
		(start 296.739056 -113.65484)
		(end 296.893996 -113.80978)
		(width 0.14224)
		(layer "In2.Cu")
		(net "M_D_DQ<55>")
	)
	(segment
		(start 285.160974 -100.270818)
		(end 285.154624 -100.281486)
		(width 0.0889)
		(layer "In2.Cu")
		(net "M_D_DQ<55>")
	)
	(segment
		(start 285.154624 -102.262686)
		(end 285.149798 -102.271322)
		(width 0.0889)
		(layer "In2.Cu")
		(net "M_D_DQ<55>")
	)
	(segment
		(start 304.79365 -131.9022)
		(end 304.511202 -132.184648)
		(width 0.14224)
		(layer "In2.Cu")
		(net "M_D_DQ<55>")
	)
	(segment
		(start 285.451804 -106.482896)
		(end 285.451804 -109.328204)
		(width 0.14224)
		(layer "In2.Cu")
		(net "M_D_DQ<55>")
	)
	(segment
		(start 305.81219 -124.377958)
		(end 305.81219 -125.27661)
		(width 0.14224)
		(layer "In2.Cu")
		(net "M_D_DQ<55>")
	)
	(segment
		(start 306.03571 -128.246378)
		(end 305.88077 -128.401318)
		(width 0.14224)
		(layer "In2.Cu")
		(net "M_D_DQ<55>")
	)
	(segment
		(start 285.451804 -109.328204)
		(end 287.274 -111.1504)
		(width 0.14224)
		(layer "In2.Cu")
		(net "M_D_DQ<55>")
	)
	(segment
		(start 287.274 -112.572038)
		(end 290.164266 -115.462304)
		(width 0.14224)
		(layer "In2.Cu")
		(net "M_D_DQ<55>")
	)
	(segment
		(start 284.642814 -98.995738)
		(end 285.13786 -99.661472)
		(width 0.0889)
		(layer "In2.Cu")
		(net "M_D_DQ<55>")
	)
	(segment
		(start 297.556936 -114.182144)
		(end 297.556936 -113.80978)
		(width 0.14224)
		(layer "In2.Cu")
		(net "M_D_DQ<55>")
	)
	(segment
		(start 306.03571 -127.893318)
		(end 306.03571 -128.246378)
		(width 0.14224)
		(layer "In2.Cu")
		(net "M_D_DQ<55>")
	)
	(segment
		(start 304.511202 -133.550152)
		(end 304.8 -133.83895)
		(width 0.14224)
		(layer "In2.Cu")
		(net "M_D_DQ<55>")
	)
	(segment
		(start 304.7492 -131.188968)
		(end 304.79365 -131.233418)
		(width 0.14224)
		(layer "In2.Cu")
		(net "M_D_DQ<55>")
	)
	(segment
		(start 299.455586 -113.65484)
		(end 305.1302 -119.329454)
		(width 0.14224)
		(layer "In2.Cu")
		(net "M_D_DQ<55>")
	)
	(segment
		(start 298.374816 -114.337084)
		(end 298.727876 -114.337084)
		(width 0.14224)
		(layer "In2.Cu")
		(net "M_D_DQ<55>")
	)
	(segment
		(start 285.154624 -101.272086)
		(end 285.149798 -101.280722)
		(width 0.0889)
		(layer "In2.Cu")
		(net "M_D_DQ<55>")
	)
	(segment
		(start 304.8 -134.162546)
		(end 304.6222 -134.340346)
		(width 0.14224)
		(layer "In2.Cu")
		(net "M_D_DQ<55>")
	)
	(segment
		(start 285.154624 -103.253286)
		(end 285.149798 -103.261922)
		(width 0.0889)
		(layer "In2.Cu")
		(net "M_D_DQ<55>")
	)
	(segment
		(start 304.8 -133.83895)
		(end 304.8 -134.162546)
		(width 0.14224)
		(layer "In2.Cu")
		(net "M_D_DQ<55>")
	)
	(segment
		(start 290.164266 -115.462304)
		(end 294.361616 -115.462304)
		(width 0.14224)
		(layer "In2.Cu")
		(net "M_D_DQ<55>")
	)
	(segment
		(start 305.414934 -128.556004)
		(end 305.414934 -130.115818)
		(width 0.14224)
		(layer "In2.Cu")
		(net "M_D_DQ<55>")
	)
	(segment
		(start 294.361616 -115.462304)
		(end 296.16908 -113.65484)
		(width 0.14224)
		(layer "In2.Cu")
		(net "M_D_DQ<55>")
	)
	(segment
		(start 304.511202 -132.184648)
		(end 304.511202 -132.457952)
		(width 0.14224)
		(layer "In2.Cu")
		(net "M_D_DQ<55>")
	)
	(segment
		(start 304.511202 -132.457952)
		(end 304.76825 -132.715)
		(width 0.14224)
		(layer "In2.Cu")
		(net "M_D_DQ<55>")
	)
	(arc
		(start 285.149798 -100.290122)
		(mid 285.101043 -100.486474)
		(end 285.154624 -100.681536)
		(width 0.0889)
		(layer "In2.Cu")
		(net "M_D_DQ<55>")
	)
	(arc
		(start 285.154624 -102.662736)
		(mid 285.233846 -102.951854)
		(end 285.160974 -103.242618)
		(width 0.0889)
		(layer "In2.Cu")
		(net "M_D_DQ<55>")
	)
	(arc
		(start 285.149798 -103.261922)
		(mid 285.101043 -103.458274)
		(end 285.154624 -103.653336)
		(width 0.0889)
		(layer "In2.Cu")
		(net "M_D_DQ<55>")
	)
	(arc
		(start 285.149798 -101.280722)
		(mid 285.101043 -101.477074)
		(end 285.154624 -101.672136)
		(width 0.0889)
		(layer "In2.Cu")
		(net "M_D_DQ<55>")
	)
	(arc
		(start 285.154624 -101.672136)
		(mid 285.233846 -101.961254)
		(end 285.160974 -102.252018)
		(width 0.0889)
		(layer "In2.Cu")
		(net "M_D_DQ<55>")
	)
	(arc
		(start 285.149798 -102.271322)
		(mid 285.101043 -102.467674)
		(end 285.154624 -102.662736)
		(width 0.0889)
		(layer "In2.Cu")
		(net "M_D_DQ<55>")
	)
	(arc
		(start 285.154624 -103.653336)
		(mid 285.233846 -103.942454)
		(end 285.160974 -104.233218)
		(width 0.0889)
		(layer "In2.Cu")
		(net "M_D_DQ<55>")
	)
	(arc
		(start 285.154624 -100.681536)
		(mid 285.233846 -100.970654)
		(end 285.160974 -101.261418)
		(width 0.0889)
		(layer "In2.Cu")
		(net "M_D_DQ<55>")
	)
	(arc
		(start 285.154624 -99.690936)
		(mid 285.233846 -99.980054)
		(end 285.160974 -100.270818)
		(width 0.0889)
		(layer "In2.Cu")
		(net "M_D_DQ<55>")
	)
	(segment
		(start 305.20005 -136.2202)
		(end 305.20005 -135.915654)
		(width 0.1651)
		(layer "F.Cu")
		(net "M_D_DQ<54>")
	)
	(segment
		(start 305.20005 -135.915654)
		(end 305.199796 -135.9154)
		(width 0.1651)
		(layer "F.Cu")
		(net "M_D_DQ<54>")
	)
	(segment
		(start 305.33213 -136.57072)
		(end 305.33213 -136.35228)
		(width 0.1651)
		(layer "F.Cu")
		(net "M_D_DQ<54>")
	)
	(segment
		(start 305.20005 -137.67054)
		(end 305.20005 -136.7028)
		(width 0.1651)
		(layer "F.Cu")
		(net "M_D_DQ<54>")
	)
	(segment
		(start 305.33213 -136.35228)
		(end 305.20005 -136.2202)
		(width 0.1651)
		(layer "F.Cu")
		(net "M_D_DQ<54>")
	)
	(segment
		(start 305.20005 -136.7028)
		(end 305.33213 -136.57072)
		(width 0.1651)
		(layer "F.Cu")
		(net "M_D_DQ<54>")
	)
	(segment
		(start 284.071314 -97.014538)
		(end 284.642814 -97.014538)
		(width 0.1651)
		(layer "F.Cu")
		(net "M_D_DQ<54>")
	)
	(segment
		(start 305.200304 -137.67054)
		(end 305.20005 -137.67054)
		(width 0.1651)
		(layer "F.Cu")
		(net "M_D_DQ<54>")
	)
	(via
		(at 305.199796 -135.9154)
		(size 0.508)
		(drill 0.254)
		(layers "F.Cu" "B.Cu")
		(net "M_D_DQ<54>")
	)
	(via
		(at 284.642814 -97.014538)
		(size 0.508)
		(drill 0.254)
		(layers "F.Cu" "B.Cu")
		(net "M_D_DQ<54>")
	)
	(via
		(at 304.349912 -131.611878)
		(size 0.508)
		(drill 0.254)
		(layers "F.Cu" "B.Cu")
		(net "M_D_DQ<54>")
	)
	(segment
		(start 304.35042 -132.876036)
		(end 304.349912 -132.875782)
		(width 0.1651)
		(layer "B.Cu")
		(net "M_D_DQ<54>")
	)
	(segment
		(start 304.349912 -132.875782)
		(end 304.349912 -131.611878)
		(width 0.1651)
		(layer "B.Cu")
		(net "M_D_DQ<54>")
	)
	(segment
		(start 284.97276 -97.776284)
		(end 284.989524 -97.804986)
		(width 0.0889)
		(layer "In2.Cu")
		(net "M_D_DQ<54>")
	)
	(segment
		(start 304.349912 -131.611878)
		(end 303.916842 -132.044948)
		(width 0.14224)
		(layer "In2.Cu")
		(net "M_D_DQ<54>")
	)
	(segment
		(start 295.810432 -114.862864)
		(end 299.69841 -114.862864)
		(width 0.14224)
		(layer "In2.Cu")
		(net "M_D_DQ<54>")
	)
	(segment
		(start 286.7406 -112.715802)
		(end 289.965892 -115.941094)
		(width 0.14224)
		(layer "In2.Cu")
		(net "M_D_DQ<54>")
	)
	(segment
		(start 304.8762 -129.77368)
		(end 304.181002 -130.468878)
		(width 0.14224)
		(layer "In2.Cu")
		(net "M_D_DQ<54>")
	)
	(segment
		(start 286.7406 -111.7854)
		(end 286.7406 -112.715802)
		(width 0.14224)
		(layer "In2.Cu")
		(net "M_D_DQ<54>")
	)
	(segment
		(start 303.916842 -134.632446)
		(end 305.199796 -135.9154)
		(width 0.14224)
		(layer "In2.Cu")
		(net "M_D_DQ<54>")
	)
	(segment
		(start 289.965892 -115.941094)
		(end 294.732202 -115.941094)
		(width 0.14224)
		(layer "In2.Cu")
		(net "M_D_DQ<54>")
	)
	(segment
		(start 304.4952 -119.659654)
		(end 304.4952 -125.5014)
		(width 0.14224)
		(layer "In2.Cu")
		(net "M_D_DQ<54>")
	)
	(segment
		(start 284.804104 -106.271314)
		(end 284.804104 -109.848904)
		(width 0.14224)
		(layer "In2.Cu")
		(net "M_D_DQ<54>")
	)
	(segment
		(start 294.732202 -115.941094)
		(end 295.810432 -114.862864)
		(width 0.14224)
		(layer "In2.Cu")
		(net "M_D_DQ<54>")
	)
	(segment
		(start 304.181002 -131.442968)
		(end 304.349912 -131.611878)
		(width 0.14224)
		(layer "In2.Cu")
		(net "M_D_DQ<54>")
	)
	(segment
		(start 284.970474 -104.182926)
		(end 284.970474 -106.104944)
		(width 0.0889)
		(layer "In2.Cu")
		(net "M_D_DQ<54>")
	)
	(segment
		(start 299.69841 -114.862864)
		(end 304.4952 -119.659654)
		(width 0.14224)
		(layer "In2.Cu")
		(net "M_D_DQ<54>")
	)
	(segment
		(start 304.7492 -125.7554)
		(end 304.7492 -126.336806)
		(width 0.14224)
		(layer "In2.Cu")
		(net "M_D_DQ<54>")
	)
	(segment
		(start 284.989524 -102.167436)
		(end 284.983174 -102.178104)
		(width 0.0889)
		(layer "In2.Cu")
		(net "M_D_DQ<54>")
	)
	(segment
		(start 304.181002 -130.468878)
		(end 304.181002 -131.442968)
		(width 0.14224)
		(layer "In2.Cu")
		(net "M_D_DQ<54>")
	)
	(segment
		(start 284.359604 -99.278694)
		(end 284.368748 -99.287584)
		(width 0.0889)
		(layer "In2.Cu")
		(net "M_D_DQ<54>")
	)
	(segment
		(start 284.804104 -109.848904)
		(end 286.7406 -111.7854)
		(width 0.14224)
		(layer "In2.Cu")
		(net "M_D_DQ<54>")
	)
	(segment
		(start 284.642814 -97.014538)
		(end 284.97276 -97.776284)
		(width 0.0889)
		(layer "In2.Cu")
		(net "M_D_DQ<54>")
	)
	(segment
		(start 284.99435 -100.1776)
		(end 284.989524 -100.186236)
		(width 0.0889)
		(layer "In2.Cu")
		(net "M_D_DQ<54>")
	)
	(segment
		(start 284.989524 -101.176836)
		(end 284.983174 -101.187504)
		(width 0.0889)
		(layer "In2.Cu")
		(net "M_D_DQ<54>")
	)
	(segment
		(start 304.4952 -125.5014)
		(end 304.7492 -125.7554)
		(width 0.14224)
		(layer "In2.Cu")
		(net "M_D_DQ<54>")
	)
	(segment
		(start 284.970474 -106.104944)
		(end 284.804104 -106.271314)
		(width 0.0889)
		(layer "In2.Cu")
		(net "M_D_DQ<54>")
	)
	(segment
		(start 284.989524 -103.158036)
		(end 284.983174 -103.168704)
		(width 0.0889)
		(layer "In2.Cu")
		(net "M_D_DQ<54>")
	)
	(segment
		(start 304.7492 -126.336806)
		(end 304.8762 -126.463806)
		(width 0.14224)
		(layer "In2.Cu")
		(net "M_D_DQ<54>")
	)
	(segment
		(start 284.989524 -100.186236)
		(end 284.983174 -100.196904)
		(width 0.0889)
		(layer "In2.Cu")
		(net "M_D_DQ<54>")
	)
	(segment
		(start 304.8762 -126.463806)
		(end 304.8762 -129.77368)
		(width 0.14224)
		(layer "In2.Cu")
		(net "M_D_DQ<54>")
	)
	(segment
		(start 284.99435 -103.1494)
		(end 284.989524 -103.158036)
		(width 0.0889)
		(layer "In2.Cu")
		(net "M_D_DQ<54>")
	)
	(segment
		(start 284.99435 -102.1588)
		(end 284.989524 -102.167436)
		(width 0.0889)
		(layer "In2.Cu")
		(net "M_D_DQ<54>")
	)
	(segment
		(start 284.99435 -104.14)
		(end 284.970474 -104.182926)
		(width 0.0889)
		(layer "In2.Cu")
		(net "M_D_DQ<54>")
	)
	(segment
		(start 303.916842 -132.044948)
		(end 303.916842 -134.632446)
		(width 0.14224)
		(layer "In2.Cu")
		(net "M_D_DQ<54>")
	)
	(segment
		(start 284.99435 -101.1682)
		(end 284.989524 -101.176836)
		(width 0.0889)
		(layer "In2.Cu")
		(net "M_D_DQ<54>")
	)
	(arc
		(start 284.983174 -100.196904)
		(mid 284.910376 -100.487667)
		(end 284.989524 -100.776786)
		(width 0.0889)
		(layer "In2.Cu")
		(net "M_D_DQ<54>")
	)
	(arc
		(start 284.773116 -98.383598)
		(mid 284.499835 -98.549325)
		(end 284.296104 -98.795586)
		(width 0.0889)
		(layer "In2.Cu")
		(net "M_D_DQ<54>")
	)
	(arc
		(start 284.989524 -103.748586)
		(mid 285.042994 -103.943649)
		(end 284.99435 -104.14)
		(width 0.0889)
		(layer "In2.Cu")
		(net "M_D_DQ<54>")
	)
	(arc
		(start 284.989524 -99.786186)
		(mid 285.042994 -99.981249)
		(end 284.99435 -100.1776)
		(width 0.0889)
		(layer "In2.Cu")
		(net "M_D_DQ<54>")
	)
	(arc
		(start 284.989524 -102.757986)
		(mid 285.042994 -102.953049)
		(end 284.99435 -103.1494)
		(width 0.0889)
		(layer "In2.Cu")
		(net "M_D_DQ<54>")
	)
	(arc
		(start 284.296104 -98.795586)
		(mid 284.24586 -99.04791)
		(end 284.359604 -99.278694)
		(width 0.0889)
		(layer "In2.Cu")
		(net "M_D_DQ<54>")
	)
	(arc
		(start 284.983174 -101.187504)
		(mid 284.910376 -101.478267)
		(end 284.989524 -101.767386)
		(width 0.0889)
		(layer "In2.Cu")
		(net "M_D_DQ<54>")
	)
	(arc
		(start 284.989524 -97.804986)
		(mid 285.017792 -98.145352)
		(end 284.773116 -98.383598)
		(width 0.0889)
		(layer "In2.Cu")
		(net "M_D_DQ<54>")
	)
	(arc
		(start 284.829504 -99.63277)
		(mid 284.860208 -99.650746)
		(end 284.889194 -99.671378)
		(width 0.0889)
		(layer "In2.Cu")
		(net "M_D_DQ<54>")
	)
	(arc
		(start 284.989524 -101.767386)
		(mid 285.042994 -101.962449)
		(end 284.99435 -102.1588)
		(width 0.0889)
		(layer "In2.Cu")
		(net "M_D_DQ<54>")
	)
	(arc
		(start 284.989524 -100.776786)
		(mid 285.042994 -100.971849)
		(end 284.99435 -101.1682)
		(width 0.0889)
		(layer "In2.Cu")
		(net "M_D_DQ<54>")
	)
	(arc
		(start 284.368748 -99.287584)
		(mid 284.585351 -99.478566)
		(end 284.829504 -99.63277)
		(width 0.0889)
		(layer "In2.Cu")
		(net "M_D_DQ<54>")
	)
	(arc
		(start 284.889194 -99.671378)
		(mid 284.944789 -99.724032)
		(end 284.989524 -99.786186)
		(width 0.0889)
		(layer "In2.Cu")
		(net "M_D_DQ<54>")
	)
	(arc
		(start 284.983174 -102.178104)
		(mid 284.910376 -102.468867)
		(end 284.989524 -102.757986)
		(width 0.0889)
		(layer "In2.Cu")
		(net "M_D_DQ<54>")
	)
	(arc
		(start 284.983174 -103.168704)
		(mid 284.910376 -103.459467)
		(end 284.989524 -103.748586)
		(width 0.0889)
		(layer "In2.Cu")
		(net "M_D_DQ<54>")
	)
	(segment
		(start 281.495754 -98.500184)
		(end 282.067254 -98.500184)
		(width 0.1651)
		(layer "F.Cu")
		(net "M_D_DQ<53>")
	)
	(segment
		(start 298.399962 -133.076442)
		(end 298.399962 -134.340346)
		(width 0.1651)
		(layer "F.Cu")
		(net "M_D_DQ<53>")
	)
	(segment
		(start 298.40047 -133.0706)
		(end 298.399962 -133.076442)
		(width 0.1651)
		(layer "F.Cu")
		(net "M_D_DQ<53>")
	)
	(via
		(at 282.067254 -98.500184)
		(size 0.508)
		(drill 0.254)
		(layers "F.Cu" "B.Cu")
		(net "M_D_DQ<53>")
	)
	(via
		(at 298.399962 -134.340346)
		(size 0.508)
		(drill 0.254)
		(layers "F.Cu" "B.Cu")
		(net "M_D_DQ<53>")
	)
	(via
		(at 299.173646 -130.330956)
		(size 0.508)
		(drill 0.254)
		(layers "F.Cu" "B.Cu")
		(net "M_D_DQ<53>")
	)
	(segment
		(start 299.249846 -128.276096)
		(end 299.249846 -130.254756)
		(width 0.1651)
		(layer "B.Cu")
		(net "M_D_DQ<53>")
	)
	(segment
		(start 299.249846 -130.254756)
		(end 299.173646 -130.330956)
		(width 0.1651)
		(layer "B.Cu")
		(net "M_D_DQ<53>")
	)
	(segment
		(start 299.250354 -128.276096)
		(end 299.249846 -128.276096)
		(width 0.1651)
		(layer "B.Cu")
		(net "M_D_DQ<53>")
	)
	(segment
		(start 299.230034 -128.161034)
		(end 300.0248 -128.161034)
		(width 0.14224)
		(layer "In2.Cu")
		(net "M_D_DQ<53>")
	)
	(segment
		(start 297.360086 -120.956578)
		(end 299.63745 -123.233942)
		(width 0.14224)
		(layer "In2.Cu")
		(net "M_D_DQ<53>")
	)
	(segment
		(start 298.79925 -132.791454)
		(end 298.79925 -133.146546)
		(width 0.14224)
		(layer "In2.Cu")
		(net "M_D_DQ<53>")
	)
	(segment
		(start 281.666696 -102.462584)
		(end 281.666696 -103.459026)
		(width 0.0889)
		(layer "In2.Cu")
		(net "M_D_DQ<53>")
	)
	(segment
		(start 281.726894 -100.270818)
		(end 281.720544 -100.281486)
		(width 0.0889)
		(layer "In2.Cu")
		(net "M_D_DQ<53>")
	)
	(segment
		(start 299.2882 -127.3556)
		(end 299.085 -127.5588)
		(width 0.14224)
		(layer "In2.Cu")
		(net "M_D_DQ<53>")
	)
	(segment
		(start 299.3644 -129.177034)
		(end 299.3644 -130.140202)
		(width 0.14224)
		(layer "In2.Cu")
		(net "M_D_DQ<53>")
	)
	(segment
		(start 281.666696 -103.459026)
		(end 280.752296 -104.373426)
		(width 0.0889)
		(layer "In2.Cu")
		(net "M_D_DQ<53>")
	)
	(segment
		(start 282.2321 -113.778792)
		(end 282.825444 -113.185448)
		(width 0.14224)
		(layer "In2.Cu")
		(net "M_D_DQ<53>")
	)
	(segment
		(start 300.0248 -128.973834)
		(end 299.5676 -128.973834)
		(width 0.14224)
		(layer "In2.Cu")
		(net "M_D_DQ<53>")
	)
	(segment
		(start 282.067 -112.635538)
		(end 281.561032 -113.141506)
		(width 0.14224)
		(layer "In2.Cu")
		(net "M_D_DQ<53>")
	)
	(segment
		(start 283.400246 -113.76025)
		(end 282.939998 -114.220498)
		(width 0.14224)
		(layer "In2.Cu")
		(net "M_D_DQ<53>")
	)
	(segment
		(start 299.2882 -125.857)
		(end 299.2882 -127.3556)
		(width 0.14224)
		(layer "In2.Cu")
		(net "M_D_DQ<53>")
	)
	(segment
		(start 282.067 -112.317276)
		(end 282.067 -112.635538)
		(width 0.14224)
		(layer "In2.Cu")
		(net "M_D_DQ<53>")
	)
	(segment
		(start 282.939998 -114.220498)
		(end 282.939998 -114.537998)
		(width 0.14224)
		(layer "In2.Cu")
		(net "M_D_DQ<53>")
	)
	(segment
		(start 280.752296 -105.106216)
		(end 280.981404 -105.335324)
		(width 0.0889)
		(layer "In2.Cu")
		(net "M_D_DQ<53>")
	)
	(segment
		(start 297.984672 -120.04548)
		(end 297.360086 -120.670066)
		(width 0.14224)
		(layer "In2.Cu")
		(net "M_D_DQ<53>")
	)
	(segment
		(start 283.044392 -113.185448)
		(end 283.400246 -113.541302)
		(width 0.14224)
		(layer "In2.Cu")
		(net "M_D_DQ<53>")
	)
	(segment
		(start 298.72305 -130.7592)
		(end 298.72305 -131.318)
		(width 0.14224)
		(layer "In2.Cu")
		(net "M_D_DQ<53>")
	)
	(segment
		(start 281.729434 -102.247446)
		(end 281.713686 -102.274878)
		(width 0.0889)
		(layer "In2.Cu")
		(net "M_D_DQ<53>")
	)
	(segment
		(start 282.825444 -113.185448)
		(end 283.044392 -113.185448)
		(width 0.14224)
		(layer "In2.Cu")
		(net "M_D_DQ<53>")
	)
	(segment
		(start 299.5676 -128.973834)
		(end 299.3644 -129.177034)
		(width 0.14224)
		(layer "In2.Cu")
		(net "M_D_DQ<53>")
	)
	(segment
		(start 298.85005 -131.927346)
		(end 298.561252 -132.216144)
		(width 0.14224)
		(layer "In2.Cu")
		(net "M_D_DQ<53>")
	)
	(segment
		(start 295.99763 -119.594376)
		(end 296.498264 -120.09501)
		(width 0.14224)
		(layer "In2.Cu")
		(net "M_D_DQ<53>")
	)
	(segment
		(start 297.38066 -119.499888)
		(end 297.681396 -119.499888)
		(width 0.14224)
		(layer "In2.Cu")
		(net "M_D_DQ<53>")
	)
	(segment
		(start 300.0248 -128.161034)
		(end 300.228 -128.364234)
		(width 0.14224)
		(layer "In2.Cu")
		(net "M_D_DQ<53>")
	)
	(segment
		(start 298.82465 -133.959854)
		(end 298.82465 -134.187946)
		(width 0.14224)
		(layer "In2.Cu")
		(net "M_D_DQ<53>")
	)
	(segment
		(start 300.228 -128.364234)
		(end 300.228 -128.770634)
		(width 0.14224)
		(layer "In2.Cu")
		(net "M_D_DQ<53>")
	)
	(segment
		(start 282.001976 -113.778792)
		(end 282.2321 -113.778792)
		(width 0.14224)
		(layer "In2.Cu")
		(net "M_D_DQ<53>")
	)
	(segment
		(start 298.561252 -132.553456)
		(end 298.79925 -132.791454)
		(width 0.14224)
		(layer "In2.Cu")
		(net "M_D_DQ<53>")
	)
	(segment
		(start 298.561252 -133.696456)
		(end 298.82465 -133.959854)
		(width 0.14224)
		(layer "In2.Cu")
		(net "M_D_DQ<53>")
	)
	(segment
		(start 298.561252 -133.384544)
		(end 298.561252 -133.696456)
		(width 0.14224)
		(layer "In2.Cu")
		(net "M_D_DQ<53>")
	)
	(segment
		(start 299.63745 -123.233942)
		(end 299.63745 -125.50775)
		(width 0.14224)
		(layer "In2.Cu")
		(net "M_D_DQ<53>")
	)
	(segment
		(start 297.360086 -120.670066)
		(end 297.360086 -120.956578)
		(width 0.14224)
		(layer "In2.Cu")
		(net "M_D_DQ<53>")
	)
	(segment
		(start 297.681396 -119.499888)
		(end 297.984672 -119.803164)
		(width 0.14224)
		(layer "In2.Cu")
		(net "M_D_DQ<53>")
	)
	(segment
		(start 300.228 -128.770634)
		(end 300.0248 -128.973834)
		(width 0.14224)
		(layer "In2.Cu")
		(net "M_D_DQ<53>")
	)
	(segment
		(start 298.85005 -131.445)
		(end 298.85005 -131.927346)
		(width 0.14224)
		(layer "In2.Cu")
		(net "M_D_DQ<53>")
	)
	(segment
		(start 280.981404 -105.335324)
		(end 280.981404 -111.23168)
		(width 0.14224)
		(layer "In2.Cu")
		(net "M_D_DQ<53>")
	)
	(segment
		(start 281.729434 -101.256846)
		(end 281.726894 -101.261164)
		(width 0.0889)
		(layer "In2.Cu")
		(net "M_D_DQ<53>")
	)
	(segment
		(start 298.82465 -134.187946)
		(end 298.67225 -134.340346)
		(width 0.14224)
		(layer "In2.Cu")
		(net "M_D_DQ<53>")
	)
	(segment
		(start 299.63745 -125.50775)
		(end 299.2882 -125.857)
		(width 0.14224)
		(layer "In2.Cu")
		(net "M_D_DQ<53>")
	)
	(segment
		(start 299.085 -128.016)
		(end 299.230034 -128.161034)
		(width 0.14224)
		(layer "In2.Cu")
		(net "M_D_DQ<53>")
	)
	(segment
		(start 297.984672 -119.803164)
		(end 297.984672 -120.04548)
		(width 0.14224)
		(layer "In2.Cu")
		(net "M_D_DQ<53>")
	)
	(segment
		(start 298.72305 -131.318)
		(end 298.85005 -131.445)
		(width 0.14224)
		(layer "In2.Cu")
		(net "M_D_DQ<53>")
	)
	(segment
		(start 298.79925 -133.146546)
		(end 298.561252 -133.384544)
		(width 0.14224)
		(layer "In2.Cu")
		(net "M_D_DQ<53>")
	)
	(segment
		(start 280.981404 -111.23168)
		(end 282.067 -112.317276)
		(width 0.14224)
		(layer "In2.Cu")
		(net "M_D_DQ<53>")
	)
	(segment
		(start 281.561032 -113.337848)
		(end 282.001976 -113.778792)
		(width 0.14224)
		(layer "In2.Cu")
		(net "M_D_DQ<53>")
	)
	(segment
		(start 280.752296 -104.373426)
		(end 280.752296 -105.106216)
		(width 0.0889)
		(layer "In2.Cu")
		(net "M_D_DQ<53>")
	)
	(segment
		(start 299.173646 -130.330956)
		(end 299.151294 -130.330956)
		(width 0.14224)
		(layer "In2.Cu")
		(net "M_D_DQ<53>")
	)
	(segment
		(start 296.785538 -120.09501)
		(end 297.38066 -119.499888)
		(width 0.14224)
		(layer "In2.Cu")
		(net "M_D_DQ<53>")
	)
	(segment
		(start 299.3644 -130.140202)
		(end 299.173646 -130.330956)
		(width 0.14224)
		(layer "In2.Cu")
		(net "M_D_DQ<53>")
	)
	(segment
		(start 287.996376 -119.594376)
		(end 295.99763 -119.594376)
		(width 0.14224)
		(layer "In2.Cu")
		(net "M_D_DQ<53>")
	)
	(segment
		(start 283.400246 -113.541302)
		(end 283.400246 -113.76025)
		(width 0.14224)
		(layer "In2.Cu")
		(net "M_D_DQ<53>")
	)
	(segment
		(start 299.151294 -130.330956)
		(end 298.72305 -130.7592)
		(width 0.14224)
		(layer "In2.Cu")
		(net "M_D_DQ<53>")
	)
	(segment
		(start 299.085 -127.5588)
		(end 299.085 -128.016)
		(width 0.14224)
		(layer "In2.Cu")
		(net "M_D_DQ<53>")
	)
	(segment
		(start 281.720544 -100.281486)
		(end 281.713686 -100.293678)
		(width 0.0889)
		(layer "In2.Cu")
		(net "M_D_DQ<53>")
	)
	(segment
		(start 281.561032 -113.141506)
		(end 281.561032 -113.337848)
		(width 0.14224)
		(layer "In2.Cu")
		(net "M_D_DQ<53>")
	)
	(segment
		(start 296.498264 -120.09501)
		(end 296.785538 -120.09501)
		(width 0.14224)
		(layer "In2.Cu")
		(net "M_D_DQ<53>")
	)
	(segment
		(start 281.726894 -101.261164)
		(end 281.713686 -101.284278)
		(width 0.0889)
		(layer "In2.Cu")
		(net "M_D_DQ<53>")
	)
	(segment
		(start 298.67225 -134.340346)
		(end 298.399962 -134.340346)
		(width 0.14224)
		(layer "In2.Cu")
		(net "M_D_DQ<53>")
	)
	(segment
		(start 298.561252 -132.216144)
		(end 298.561252 -132.553456)
		(width 0.14224)
		(layer "In2.Cu")
		(net "M_D_DQ<53>")
	)
	(segment
		(start 282.939998 -114.537998)
		(end 287.996376 -119.594376)
		(width 0.14224)
		(layer "In2.Cu")
		(net "M_D_DQ<53>")
	)
	(segment
		(start 281.713686 -102.274878)
		(end 281.713432 -102.274878)
		(width 0.0889)
		(layer "In2.Cu")
		(net "M_D_DQ<53>")
	)
	(arc
		(start 281.720544 -100.681282)
		(mid 281.799733 -100.967897)
		(end 281.729434 -101.256846)
		(width 0.0889)
		(layer "In2.Cu")
		(net "M_D_DQ<53>")
	)
	(arc
		(start 281.720544 -99.690936)
		(mid 281.799766 -99.980054)
		(end 281.726894 -100.270818)
		(width 0.0889)
		(layer "In2.Cu")
		(net "M_D_DQ<53>")
	)
	(arc
		(start 281.720544 -101.671882)
		(mid 281.799733 -101.958497)
		(end 281.729434 -102.247446)
		(width 0.0889)
		(layer "In2.Cu")
		(net "M_D_DQ<53>")
	)
	(arc
		(start 281.713686 -101.284278)
		(mid 281.66701 -101.478979)
		(end 281.720544 -101.671882)
		(width 0.0889)
		(layer "In2.Cu")
		(net "M_D_DQ<53>")
	)
	(arc
		(start 281.686 -99.613212)
		(mid 281.701156 -99.653014)
		(end 281.720544 -99.690936)
		(width 0.0889)
		(layer "In2.Cu")
		(net "M_D_DQ<53>")
	)
	(arc
		(start 281.720544 -99.291648)
		(mid 281.669336 -99.448786)
		(end 281.686 -99.613212)
		(width 0.0889)
		(layer "In2.Cu")
		(net "M_D_DQ<53>")
	)
	(arc
		(start 282.067254 -98.500184)
		(mid 281.915699 -98.905465)
		(end 281.720544 -99.291648)
		(width 0.0889)
		(layer "In2.Cu")
		(net "M_D_DQ<53>")
	)
	(arc
		(start 281.713686 -100.293678)
		(mid 281.66701 -100.488379)
		(end 281.720544 -100.681282)
		(width 0.0889)
		(layer "In2.Cu")
		(net "M_D_DQ<53>")
	)
	(arc
		(start 281.713432 -102.274878)
		(mid 281.678555 -102.365866)
		(end 281.666696 -102.462584)
		(width 0.0889)
		(layer "In2.Cu")
		(net "M_D_DQ<53>")
	)
	(segment
		(start 299.250354 -137.67054)
		(end 299.249846 -137.67054)
		(width 0.1651)
		(layer "F.Cu")
		(net "M_D_DQ<52>")
	)
	(segment
		(start 299.249846 -137.67054)
		(end 299.249846 -136.345168)
		(width 0.1651)
		(layer "F.Cu")
		(net "M_D_DQ<52>")
	)
	(segment
		(start 299.249846 -136.345168)
		(end 299.151802 -135.8138)
		(width 0.1651)
		(layer "F.Cu")
		(net "M_D_DQ<52>")
	)
	(segment
		(start 281.495754 -97.509584)
		(end 282.067254 -97.509584)
		(width 0.1651)
		(layer "F.Cu")
		(net "M_D_DQ<52>")
	)
	(via
		(at 282.067254 -97.509584)
		(size 0.508)
		(drill 0.254)
		(layers "F.Cu" "B.Cu")
		(net "M_D_DQ<52>")
	)
	(via
		(at 298.399962 -131.611878)
		(size 0.508)
		(drill 0.254)
		(layers "F.Cu" "B.Cu")
		(net "M_D_DQ<52>")
	)
	(via
		(at 299.151802 -135.8138)
		(size 0.508)
		(drill 0.254)
		(layers "F.Cu" "B.Cu")
		(net "M_D_DQ<52>")
	)
	(segment
		(start 298.40047 -132.876036)
		(end 298.399962 -132.875782)
		(width 0.1651)
		(layer "B.Cu")
		(net "M_D_DQ<52>")
	)
	(segment
		(start 298.399962 -132.875782)
		(end 298.399962 -131.611878)
		(width 0.1651)
		(layer "B.Cu")
		(net "M_D_DQ<52>")
	)
	(segment
		(start 285.213552 -117.726206)
		(end 285.213552 -118.013226)
		(width 0.14224)
		(layer "In2.Cu")
		(net "M_D_DQ<52>")
	)
	(segment
		(start 295.717976 -120.229376)
		(end 298.6024 -123.1138)
		(width 0.14224)
		(layer "In2.Cu")
		(net "M_D_DQ<52>")
	)
	(segment
		(start 298.6024 -124.923804)
		(end 298.6786 -125.000004)
		(width 0.14224)
		(layer "In2.Cu")
		(net "M_D_DQ<52>")
	)
	(segment
		(start 287.224978 -119.737632)
		(end 287.716722 -120.229376)
		(width 0.14224)
		(layer "In2.Cu")
		(net "M_D_DQ<52>")
	)
	(segment
		(start 298.283122 -131.495038)
		(end 298.399962 -131.611878)
		(width 0.14224)
		(layer "In2.Cu")
		(net "M_D_DQ<52>")
	)
	(segment
		(start 284.063948 -116.576602)
		(end 284.063948 -116.863622)
		(width 0.14224)
		(layer "In2.Cu")
		(net "M_D_DQ<52>")
	)
	(segment
		(start 281.475942 -102.46233)
		(end 281.475942 -103.381048)
		(width 0.0889)
		(layer "In2.Cu")
		(net "M_D_DQ<52>")
	)
	(segment
		(start 284.418024 -117.658896)
		(end 284.63875 -117.438424)
		(width 0.14224)
		(layer "In2.Cu")
		(net "M_D_DQ<52>")
	)
	(segment
		(start 283.843222 -117.084094)
		(end 283.843222 -117.371114)
		(width 0.14224)
		(layer "In2.Cu")
		(net "M_D_DQ<52>")
	)
	(segment
		(start 284.063948 -116.863622)
		(end 283.843222 -117.084094)
		(width 0.14224)
		(layer "In2.Cu")
		(net "M_D_DQ<52>")
	)
	(segment
		(start 298.7294 -126.283466)
		(end 298.7294 -127)
		(width 0.14224)
		(layer "In2.Cu")
		(net "M_D_DQ<52>")
	)
	(segment
		(start 297.966892 -132.044948)
		(end 297.966892 -134.57809)
		(width 0.14224)
		(layer "In2.Cu")
		(net "M_D_DQ<52>")
	)
	(segment
		(start 284.992826 -118.233698)
		(end 284.992826 -118.520718)
		(width 0.14224)
		(layer "In2.Cu")
		(net "M_D_DQ<52>")
	)
	(segment
		(start 298.90085 -135.8138)
		(end 299.151802 -135.8138)
		(width 0.14224)
		(layer "In2.Cu")
		(net "M_D_DQ<52>")
	)
	(segment
		(start 280.561796 -105.114852)
		(end 280.333704 -105.342944)
		(width 0.0889)
		(layer "In2.Cu")
		(net "M_D_DQ<52>")
	)
	(segment
		(start 284.92577 -117.438424)
		(end 285.213552 -117.726206)
		(width 0.14224)
		(layer "In2.Cu")
		(net "M_D_DQ<52>")
	)
	(segment
		(start 287.716722 -120.229376)
		(end 295.717976 -120.229376)
		(width 0.14224)
		(layer "In2.Cu")
		(net "M_D_DQ<52>")
	)
	(segment
		(start 286.363156 -119.16283)
		(end 286.14243 -119.383302)
		(width 0.14224)
		(layer "In2.Cu")
		(net "M_D_DQ<52>")
	)
	(segment
		(start 298.859194 -129.31394)
		(end 298.859194 -129.846578)
		(width 0.14224)
		(layer "In2.Cu")
		(net "M_D_DQ<52>")
	)
	(segment
		(start 298.859194 -129.846578)
		(end 298.283122 -130.42265)
		(width 0.14224)
		(layer "In2.Cu")
		(net "M_D_DQ<52>")
	)
	(segment
		(start 286.717232 -119.958104)
		(end 286.937958 -119.737632)
		(width 0.14224)
		(layer "In2.Cu")
		(net "M_D_DQ<52>")
	)
	(segment
		(start 280.333704 -105.342944)
		(end 280.333704 -112.846358)
		(width 0.14224)
		(layer "In2.Cu")
		(net "M_D_DQ<52>")
	)
	(segment
		(start 284.992826 -118.520718)
		(end 285.280608 -118.8085)
		(width 0.14224)
		(layer "In2.Cu")
		(net "M_D_DQ<52>")
	)
	(segment
		(start 282.067254 -97.509584)
		(end 281.697684 -97.509584)
		(width 0.0889)
		(layer "In2.Cu")
		(net "M_D_DQ<52>")
	)
	(segment
		(start 283.843222 -117.371114)
		(end 284.131004 -117.658896)
		(width 0.14224)
		(layer "In2.Cu")
		(net "M_D_DQ<52>")
	)
	(segment
		(start 298.6024 -127.127)
		(end 298.6024 -129.057146)
		(width 0.14224)
		(layer "In2.Cu")
		(net "M_D_DQ<52>")
	)
	(segment
		(start 286.14243 -119.670322)
		(end 286.430212 -119.958104)
		(width 0.14224)
		(layer "In2.Cu")
		(net "M_D_DQ<52>")
	)
	(segment
		(start 286.075374 -118.588028)
		(end 286.363156 -118.87581)
		(width 0.14224)
		(layer "In2.Cu")
		(net "M_D_DQ<52>")
	)
	(segment
		(start 285.280608 -118.8085)
		(end 285.567628 -118.8085)
		(width 0.14224)
		(layer "In2.Cu")
		(net "M_D_DQ<52>")
	)
	(segment
		(start 281.697684 -97.509584)
		(end 281.608784 -97.598484)
		(width 0.0889)
		(layer "In2.Cu")
		(net "M_D_DQ<52>")
	)
	(segment
		(start 281.475942 -103.381048)
		(end 280.561796 -104.295194)
		(width 0.0889)
		(layer "In2.Cu")
		(net "M_D_DQ<52>")
	)
	(segment
		(start 284.63875 -117.438424)
		(end 284.92577 -117.438424)
		(width 0.14224)
		(layer "In2.Cu")
		(net "M_D_DQ<52>")
	)
	(segment
		(start 285.567628 -118.8085)
		(end 285.788354 -118.588028)
		(width 0.14224)
		(layer "In2.Cu")
		(net "M_D_DQ<52>")
	)
	(segment
		(start 286.363156 -118.87581)
		(end 286.363156 -119.16283)
		(width 0.14224)
		(layer "In2.Cu")
		(net "M_D_DQ<52>")
	)
	(segment
		(start 298.399962 -131.611878)
		(end 297.966892 -132.044948)
		(width 0.14224)
		(layer "In2.Cu")
		(net "M_D_DQ<52>")
	)
	(segment
		(start 281.608784 -98.152204)
		(end 281.555444 -98.205544)
		(width 0.0889)
		(layer "In2.Cu")
		(net "M_D_DQ<52>")
	)
	(segment
		(start 285.213552 -118.013226)
		(end 284.992826 -118.233698)
		(width 0.14224)
		(layer "In2.Cu")
		(net "M_D_DQ<52>")
	)
	(segment
		(start 298.6786 -125.000004)
		(end 298.6786 -126.232666)
		(width 0.14224)
		(layer "In2.Cu")
		(net "M_D_DQ<52>")
	)
	(segment
		(start 298.283122 -130.42265)
		(end 298.283122 -131.495038)
		(width 0.14224)
		(layer "In2.Cu")
		(net "M_D_DQ<52>")
	)
	(segment
		(start 286.430212 -119.958104)
		(end 286.717232 -119.958104)
		(width 0.14224)
		(layer "In2.Cu")
		(net "M_D_DQ<52>")
	)
	(segment
		(start 298.6024 -123.1138)
		(end 298.6024 -124.923804)
		(width 0.14224)
		(layer "In2.Cu")
		(net "M_D_DQ<52>")
	)
	(segment
		(start 297.966892 -134.57809)
		(end 298.12488 -134.736078)
		(width 0.14224)
		(layer "In2.Cu")
		(net "M_D_DQ<52>")
	)
	(segment
		(start 285.788354 -118.588028)
		(end 286.075374 -118.588028)
		(width 0.14224)
		(layer "In2.Cu")
		(net "M_D_DQ<52>")
	)
	(segment
		(start 281.562302 -101.16439)
		(end 281.546554 -101.191822)
		(width 0.0889)
		(layer "In2.Cu")
		(net "M_D_DQ<52>")
	)
	(segment
		(start 286.14243 -119.383302)
		(end 286.14243 -119.670322)
		(width 0.14224)
		(layer "In2.Cu")
		(net "M_D_DQ<52>")
	)
	(segment
		(start 298.12488 -134.736078)
		(end 298.12488 -135.03783)
		(width 0.14224)
		(layer "In2.Cu")
		(net "M_D_DQ<52>")
	)
	(segment
		(start 280.561796 -104.295194)
		(end 280.561796 -105.114852)
		(width 0.0889)
		(layer "In2.Cu")
		(net "M_D_DQ<52>")
	)
	(segment
		(start 286.937958 -119.737632)
		(end 287.224978 -119.737632)
		(width 0.14224)
		(layer "In2.Cu")
		(net "M_D_DQ<52>")
	)
	(segment
		(start 281.562302 -102.15499)
		(end 281.546554 -102.182422)
		(width 0.0889)
		(layer "In2.Cu")
		(net "M_D_DQ<52>")
	)
	(segment
		(start 284.131004 -117.658896)
		(end 284.418024 -117.658896)
		(width 0.14224)
		(layer "In2.Cu")
		(net "M_D_DQ<52>")
	)
	(segment
		(start 281.562302 -100.17379)
		(end 281.546554 -100.201222)
		(width 0.0889)
		(layer "In2.Cu")
		(net "M_D_DQ<52>")
	)
	(segment
		(start 281.608784 -97.598484)
		(end 281.608784 -98.152204)
		(width 0.0889)
		(layer "In2.Cu")
		(net "M_D_DQ<52>")
	)
	(segment
		(start 280.333704 -112.846358)
		(end 284.063948 -116.576602)
		(width 0.14224)
		(layer "In2.Cu")
		(net "M_D_DQ<52>")
	)
	(segment
		(start 298.12488 -135.03783)
		(end 298.90085 -135.8138)
		(width 0.14224)
		(layer "In2.Cu")
		(net "M_D_DQ<52>")
	)
	(segment
		(start 298.7294 -127)
		(end 298.6024 -127.127)
		(width 0.14224)
		(layer "In2.Cu")
		(net "M_D_DQ<52>")
	)
	(segment
		(start 298.6024 -129.057146)
		(end 298.859194 -129.31394)
		(width 0.14224)
		(layer "In2.Cu")
		(net "M_D_DQ<52>")
	)
	(segment
		(start 298.6786 -126.232666)
		(end 298.7294 -126.283466)
		(width 0.14224)
		(layer "In2.Cu")
		(net "M_D_DQ<52>")
	)
	(arc
		(start 281.525726 -98.263964)
		(mid 281.477166 -98.533689)
		(end 281.555444 -98.796348)
		(width 0.0889)
		(layer "In2.Cu")
		(net "M_D_DQ<52>")
	)
	(arc
		(start 281.546554 -100.201222)
		(mid 281.476157 -100.490173)
		(end 281.555444 -100.776786)
		(width 0.0889)
		(layer "In2.Cu")
		(net "M_D_DQ<52>")
	)
	(arc
		(start 281.50439 -99.671632)
		(mid 281.526951 -99.73023)
		(end 281.555444 -99.786186)
		(width 0.0889)
		(layer "In2.Cu")
		(net "M_D_DQ<52>")
	)
	(arc
		(start 281.555444 -98.205544)
		(mid 281.539735 -98.234321)
		(end 281.525726 -98.263964)
		(width 0.0889)
		(layer "In2.Cu")
		(net "M_D_DQ<52>")
	)
	(arc
		(start 281.555444 -100.776786)
		(mid 281.608882 -100.969691)
		(end 281.562302 -101.16439)
		(width 0.0889)
		(layer "In2.Cu")
		(net "M_D_DQ<52>")
	)
	(arc
		(start 281.555444 -99.196144)
		(mid 281.479686 -99.428491)
		(end 281.50439 -99.671632)
		(width 0.0889)
		(layer "In2.Cu")
		(net "M_D_DQ<52>")
	)
	(arc
		(start 281.546554 -101.191822)
		(mid 281.476157 -101.480773)
		(end 281.555444 -101.767386)
		(width 0.0889)
		(layer "In2.Cu")
		(net "M_D_DQ<52>")
	)
	(arc
		(start 281.555444 -98.796348)
		(mid 281.608943 -98.996246)
		(end 281.555444 -99.196144)
		(width 0.0889)
		(layer "In2.Cu")
		(net "M_D_DQ<52>")
	)
	(arc
		(start 281.555444 -99.786186)
		(mid 281.608882 -99.979091)
		(end 281.562302 -100.17379)
		(width 0.0889)
		(layer "In2.Cu")
		(net "M_D_DQ<52>")
	)
	(arc
		(start 281.546554 -102.182422)
		(mid 281.493895 -102.317999)
		(end 281.475942 -102.46233)
		(width 0.0889)
		(layer "In2.Cu")
		(net "M_D_DQ<52>")
	)
	(arc
		(start 281.555444 -101.767386)
		(mid 281.608882 -101.960291)
		(end 281.562302 -102.15499)
		(width 0.0889)
		(layer "In2.Cu")
		(net "M_D_DQ<52>")
	)
	(segment
		(start 284.929834 -98.500184)
		(end 285.501334 -98.500184)
		(width 0.1651)
		(layer "F.Cu")
		(net "M_D_DQ<51>")
	)
	(segment
		(start 306.049934 -133.076442)
		(end 306.049934 -134.340346)
		(width 0.1651)
		(layer "F.Cu")
		(net "M_D_DQ<51>")
	)
	(segment
		(start 306.050442 -133.0706)
		(end 306.049934 -133.076442)
		(width 0.1651)
		(layer "F.Cu")
		(net "M_D_DQ<51>")
	)
	(via
		(at 306.049934 -134.340346)
		(size 0.508)
		(drill 0.254)
		(layers "F.Cu" "B.Cu")
		(net "M_D_DQ<51>")
	)
	(via
		(at 285.501334 -98.500184)
		(size 0.508)
		(drill 0.254)
		(layers "F.Cu" "B.Cu")
		(net "M_D_DQ<51>")
	)
	(via
		(at 306.899818 -130.330956)
		(size 0.508)
		(drill 0.254)
		(layers "F.Cu" "B.Cu")
		(net "M_D_DQ<51>")
	)
	(segment
		(start 306.900326 -128.276096)
		(end 306.899818 -128.276096)
		(width 0.1651)
		(layer "B.Cu")
		(net "M_D_DQ<51>")
	)
	(segment
		(start 306.899818 -128.276096)
		(end 306.899818 -130.330956)
		(width 0.1651)
		(layer "B.Cu")
		(net "M_D_DQ<51>")
	)
	(segment
		(start 296.967148 -112.50676)
		(end 296.967148 -112.1537)
		(width 0.14224)
		(layer "In2.Cu")
		(net "M_D_DQ<51>")
	)
	(segment
		(start 306.449222 -130.7592)
		(end 306.449222 -131.188968)
		(width 0.14224)
		(layer "In2.Cu")
		(net "M_D_DQ<51>")
	)
	(segment
		(start 298.801028 -111.99876)
		(end 298.955968 -112.1537)
		(width 0.14224)
		(layer "In2.Cu")
		(net "M_D_DQ<51>")
	)
	(segment
		(start 286.6898 -106.242358)
		(end 286.8168 -106.369358)
		(width 0.14224)
		(layer "In2.Cu")
		(net "M_D_DQ<51>")
	)
	(segment
		(start 290.597336 -114.493548)
		(end 293.830248 -114.493548)
		(width 0.14224)
		(layer "In2.Cu")
		(net "M_D_DQ<51>")
	)
	(segment
		(start 306.4002 -123.16968)
		(end 307.358796 -124.128276)
		(width 0.14224)
		(layer "In2.Cu")
		(net "M_D_DQ<51>")
	)
	(segment
		(start 307.142134 -126.480062)
		(end 307.142134 -130.101848)
		(width 0.14224)
		(layer "In2.Cu")
		(net "M_D_DQ<51>")
	)
	(segment
		(start 296.967148 -112.1537)
		(end 297.122088 -111.99876)
		(width 0.14224)
		(layer "In2.Cu")
		(net "M_D_DQ<51>")
	)
	(segment
		(start 299.110908 -112.6617)
		(end 300.316646 -112.6617)
		(width 0.14224)
		(layer "In2.Cu")
		(net "M_D_DQ<51>")
	)
	(segment
		(start 295.662096 -112.6617)
		(end 296.812208 -112.6617)
		(width 0.14224)
		(layer "In2.Cu")
		(net "M_D_DQ<51>")
	)
	(segment
		(start 307.142134 -130.101848)
		(end 306.899818 -130.344164)
		(width 0.14224)
		(layer "In2.Cu")
		(net "M_D_DQ<51>")
	)
	(segment
		(start 306.899818 -130.330956)
		(end 306.877466 -130.330956)
		(width 0.14224)
		(layer "In2.Cu")
		(net "M_D_DQ<51>")
	)
	(segment
		(start 297.475148 -111.99876)
		(end 297.630088 -112.1537)
		(width 0.14224)
		(layer "In2.Cu")
		(net "M_D_DQ<51>")
	)
	(segment
		(start 306.493672 -131.233418)
		(end 306.493672 -131.9022)
		(width 0.14224)
		(layer "In2.Cu")
		(net "M_D_DQ<51>")
	)
	(segment
		(start 298.293028 -112.1537)
		(end 298.447968 -111.99876)
		(width 0.14224)
		(layer "In2.Cu")
		(net "M_D_DQ<51>")
	)
	(segment
		(start 298.138088 -112.6617)
		(end 298.293028 -112.50676)
		(width 0.14224)
		(layer "In2.Cu")
		(net "M_D_DQ<51>")
	)
	(segment
		(start 306.211224 -133.550152)
		(end 306.500022 -133.83895)
		(width 0.14224)
		(layer "In2.Cu")
		(net "M_D_DQ<51>")
	)
	(segment
		(start 306.899818 -130.344164)
		(end 306.899818 -130.330956)
		(width 0.14224)
		(layer "In2.Cu")
		(net "M_D_DQ<51>")
	)
	(segment
		(start 286.130746 -105.934256)
		(end 286.438848 -106.242358)
		(width 0.0889)
		(layer "In2.Cu")
		(net "M_D_DQ<51>")
	)
	(segment
		(start 300.316646 -112.6617)
		(end 306.4002 -118.745254)
		(width 0.14224)
		(layer "In2.Cu")
		(net "M_D_DQ<51>")
	)
	(segment
		(start 298.293028 -112.50676)
		(end 298.293028 -112.1537)
		(width 0.14224)
		(layer "In2.Cu")
		(net "M_D_DQ<51>")
	)
	(segment
		(start 297.630088 -112.50676)
		(end 297.785028 -112.6617)
		(width 0.14224)
		(layer "In2.Cu")
		(net "M_D_DQ<51>")
	)
	(segment
		(start 306.500022 -134.162546)
		(end 306.322222 -134.340346)
		(width 0.14224)
		(layer "In2.Cu")
		(net "M_D_DQ<51>")
	)
	(segment
		(start 297.785028 -112.6617)
		(end 298.138088 -112.6617)
		(width 0.14224)
		(layer "In2.Cu")
		(net "M_D_DQ<51>")
	)
	(segment
		(start 286.130746 -104.405938)
		(end 286.130746 -105.934256)
		(width 0.0889)
		(layer "In2.Cu")
		(net "M_D_DQ<51>")
	)
	(segment
		(start 286.8168 -106.369358)
		(end 286.8168 -108.5088)
		(width 0.14224)
		(layer "In2.Cu")
		(net "M_D_DQ<51>")
	)
	(segment
		(start 293.830248 -114.493548)
		(end 295.662096 -112.6617)
		(width 0.14224)
		(layer "In2.Cu")
		(net "M_D_DQ<51>")
	)
	(segment
		(start 306.211224 -133.276848)
		(end 306.211224 -133.550152)
		(width 0.14224)
		(layer "In2.Cu")
		(net "M_D_DQ<51>")
	)
	(segment
		(start 297.122088 -111.99876)
		(end 297.475148 -111.99876)
		(width 0.14224)
		(layer "In2.Cu")
		(net "M_D_DQ<51>")
	)
	(segment
		(start 298.447968 -111.99876)
		(end 298.801028 -111.99876)
		(width 0.14224)
		(layer "In2.Cu")
		(net "M_D_DQ<51>")
	)
	(segment
		(start 285.979362 -99.138486)
		(end 285.980124 -99.139756)
		(width 0.0889)
		(layer "In2.Cu")
		(net "M_D_DQ<51>")
	)
	(segment
		(start 286.013144 -103.158036)
		(end 286.022034 -103.173276)
		(width 0.0889)
		(layer "In2.Cu")
		(net "M_D_DQ<51>")
	)
	(segment
		(start 286.438848 -106.242358)
		(end 286.6898 -106.242358)
		(width 0.0889)
		(layer "In2.Cu")
		(net "M_D_DQ<51>")
	)
	(segment
		(start 306.211224 -132.184648)
		(end 306.211224 -132.457952)
		(width 0.14224)
		(layer "In2.Cu")
		(net "M_D_DQ<51>")
	)
	(segment
		(start 298.955968 -112.50676)
		(end 299.110908 -112.6617)
		(width 0.14224)
		(layer "In2.Cu")
		(net "M_D_DQ<51>")
	)
	(segment
		(start 286.013144 -104.148636)
		(end 286.130746 -104.405938)
		(width 0.0889)
		(layer "In2.Cu")
		(net "M_D_DQ<51>")
	)
	(segment
		(start 306.449222 -131.188968)
		(end 306.493672 -131.233418)
		(width 0.14224)
		(layer "In2.Cu")
		(net "M_D_DQ<51>")
	)
	(segment
		(start 306.500022 -133.83895)
		(end 306.500022 -134.162546)
		(width 0.14224)
		(layer "In2.Cu")
		(net "M_D_DQ<51>")
	)
	(segment
		(start 306.468272 -133.0198)
		(end 306.211224 -133.276848)
		(width 0.14224)
		(layer "In2.Cu")
		(net "M_D_DQ<51>")
	)
	(segment
		(start 288.72815 -110.42015)
		(end 288.72815 -112.624362)
		(width 0.14224)
		(layer "In2.Cu")
		(net "M_D_DQ<51>")
	)
	(segment
		(start 306.877466 -130.330956)
		(end 306.449222 -130.7592)
		(width 0.14224)
		(layer "In2.Cu")
		(net "M_D_DQ<51>")
	)
	(segment
		(start 306.493672 -131.9022)
		(end 306.211224 -132.184648)
		(width 0.14224)
		(layer "In2.Cu")
		(net "M_D_DQ<51>")
	)
	(segment
		(start 286.013144 -102.167436)
		(end 286.022034 -102.182676)
		(width 0.0889)
		(layer "In2.Cu")
		(net "M_D_DQ<51>")
	)
	(segment
		(start 306.4002 -118.745254)
		(end 306.4002 -123.16968)
		(width 0.14224)
		(layer "In2.Cu")
		(net "M_D_DQ<51>")
	)
	(segment
		(start 288.72815 -112.624362)
		(end 290.597336 -114.493548)
		(width 0.14224)
		(layer "In2.Cu")
		(net "M_D_DQ<51>")
	)
	(segment
		(start 286.013144 -100.186236)
		(end 286.022034 -100.201476)
		(width 0.0889)
		(layer "In2.Cu")
		(net "M_D_DQ<51>")
	)
	(segment
		(start 286.8168 -108.5088)
		(end 288.72815 -110.42015)
		(width 0.14224)
		(layer "In2.Cu")
		(net "M_D_DQ<51>")
	)
	(segment
		(start 306.322222 -134.340346)
		(end 306.049934 -134.340346)
		(width 0.14224)
		(layer "In2.Cu")
		(net "M_D_DQ<51>")
	)
	(segment
		(start 306.211224 -132.457952)
		(end 306.468272 -132.715)
		(width 0.14224)
		(layer "In2.Cu")
		(net "M_D_DQ<51>")
	)
	(segment
		(start 296.812208 -112.6617)
		(end 296.967148 -112.50676)
		(width 0.14224)
		(layer "In2.Cu")
		(net "M_D_DQ<51>")
	)
	(segment
		(start 286.013144 -101.176836)
		(end 286.022034 -101.192076)
		(width 0.0889)
		(layer "In2.Cu")
		(net "M_D_DQ<51>")
	)
	(segment
		(start 297.630088 -112.1537)
		(end 297.630088 -112.50676)
		(width 0.14224)
		(layer "In2.Cu")
		(net "M_D_DQ<51>")
	)
	(segment
		(start 306.468272 -132.715)
		(end 306.468272 -133.0198)
		(width 0.14224)
		(layer "In2.Cu")
		(net "M_D_DQ<51>")
	)
	(segment
		(start 307.358796 -126.2634)
		(end 307.142134 -126.480062)
		(width 0.14224)
		(layer "In2.Cu")
		(net "M_D_DQ<51>")
	)
	(segment
		(start 298.955968 -112.1537)
		(end 298.955968 -112.50676)
		(width 0.14224)
		(layer "In2.Cu")
		(net "M_D_DQ<51>")
	)
	(segment
		(start 307.358796 -124.128276)
		(end 307.358796 -126.2634)
		(width 0.14224)
		(layer "In2.Cu")
		(net "M_D_DQ<51>")
	)
	(arc
		(start 286.022034 -99.21113)
		(mid 286.092339 -99.499937)
		(end 286.013144 -99.78644)
		(width 0.0889)
		(layer "In2.Cu")
		(net "M_D_DQ<51>")
	)
	(arc
		(start 286.013144 -102.75824)
		(mid 285.959611 -102.958138)
		(end 286.013144 -103.158036)
		(width 0.0889)
		(layer "In2.Cu")
		(net "M_D_DQ<51>")
	)
	(arc
		(start 286.013144 -99.78644)
		(mid 285.959611 -99.986338)
		(end 286.013144 -100.186236)
		(width 0.0889)
		(layer "In2.Cu")
		(net "M_D_DQ<51>")
	)
	(arc
		(start 286.013144 -101.76764)
		(mid 285.959611 -101.967538)
		(end 286.013144 -102.167436)
		(width 0.0889)
		(layer "In2.Cu")
		(net "M_D_DQ<51>")
	)
	(arc
		(start 285.980124 -99.139756)
		(mid 286.001756 -99.175046)
		(end 286.022034 -99.21113)
		(width 0.0889)
		(layer "In2.Cu")
		(net "M_D_DQ<51>")
	)
	(arc
		(start 286.013144 -100.77704)
		(mid 285.959611 -100.976938)
		(end 286.013144 -101.176836)
		(width 0.0889)
		(layer "In2.Cu")
		(net "M_D_DQ<51>")
	)
	(arc
		(start 285.501334 -98.500184)
		(mid 285.756648 -98.807127)
		(end 285.979362 -99.138486)
		(width 0.0889)
		(layer "In2.Cu")
		(net "M_D_DQ<51>")
	)
	(arc
		(start 286.022034 -103.173276)
		(mid 286.092431 -103.462227)
		(end 286.013144 -103.74884)
		(width 0.0889)
		(layer "In2.Cu")
		(net "M_D_DQ<51>")
	)
	(arc
		(start 286.013144 -103.74884)
		(mid 285.959611 -103.948738)
		(end 286.013144 -104.148636)
		(width 0.0889)
		(layer "In2.Cu")
		(net "M_D_DQ<51>")
	)
	(arc
		(start 286.022034 -102.182676)
		(mid 286.092431 -102.471627)
		(end 286.013144 -102.75824)
		(width 0.0889)
		(layer "In2.Cu")
		(net "M_D_DQ<51>")
	)
	(arc
		(start 286.022034 -101.192076)
		(mid 286.092431 -101.481027)
		(end 286.013144 -101.76764)
		(width 0.0889)
		(layer "In2.Cu")
		(net "M_D_DQ<51>")
	)
	(arc
		(start 286.022034 -100.201476)
		(mid 286.092431 -100.490427)
		(end 286.013144 -100.77704)
		(width 0.0889)
		(layer "In2.Cu")
		(net "M_D_DQ<51>")
	)
	(segment
		(start 307.03139 -136.54786)
		(end 307.03139 -136.32434)
		(width 0.1651)
		(layer "F.Cu")
		(net "M_D_DQ<50>")
	)
	(segment
		(start 306.900326 -137.67054)
		(end 306.899818 -137.67054)
		(width 0.1651)
		(layer "F.Cu")
		(net "M_D_DQ<50>")
	)
	(segment
		(start 306.899818 -136.679432)
		(end 307.03139 -136.54786)
		(width 0.1651)
		(layer "F.Cu")
		(net "M_D_DQ<50>")
	)
	(segment
		(start 284.929834 -97.509584)
		(end 285.501334 -97.509584)
		(width 0.1651)
		(layer "F.Cu")
		(net "M_D_DQ<50>")
	)
	(segment
		(start 306.899818 -136.192768)
		(end 306.899818 -135.9154)
		(width 0.1651)
		(layer "F.Cu")
		(net "M_D_DQ<50>")
	)
	(segment
		(start 306.899818 -137.67054)
		(end 306.899818 -136.679432)
		(width 0.1651)
		(layer "F.Cu")
		(net "M_D_DQ<50>")
	)
	(segment
		(start 307.03139 -136.32434)
		(end 306.899818 -136.192768)
		(width 0.1651)
		(layer "F.Cu")
		(net "M_D_DQ<50>")
	)
	(via
		(at 285.501334 -97.509584)
		(size 0.508)
		(drill 0.254)
		(layers "F.Cu" "B.Cu")
		(net "M_D_DQ<50>")
	)
	(via
		(at 306.049934 -131.611878)
		(size 0.508)
		(drill 0.254)
		(layers "F.Cu" "B.Cu")
		(net "M_D_DQ<50>")
	)
	(via
		(at 306.899818 -135.9154)
		(size 0.508)
		(drill 0.254)
		(layers "F.Cu" "B.Cu")
		(net "M_D_DQ<50>")
	)
	(segment
		(start 306.050442 -132.876036)
		(end 306.049934 -132.875782)
		(width 0.1651)
		(layer "B.Cu")
		(net "M_D_DQ<50>")
	)
	(segment
		(start 306.049934 -132.875782)
		(end 306.049934 -131.611878)
		(width 0.1651)
		(layer "B.Cu")
		(net "M_D_DQ<50>")
	)
	(segment
		(start 294.07993 -114.983514)
		(end 295.91762 -113.145824)
		(width 0.14224)
		(layer "In2.Cu")
		(net "M_D_DQ<50>")
	)
	(segment
		(start 295.91762 -113.145824)
		(end 299.86097 -113.145824)
		(width 0.14224)
		(layer "In2.Cu")
		(net "M_D_DQ<50>")
	)
	(segment
		(start 285.501334 -97.509584)
		(end 285.171896 -98.270568)
		(width 0.0889)
		(layer "In2.Cu")
		(net "M_D_DQ<50>")
	)
	(segment
		(start 285.171896 -98.270568)
		(end 285.149798 -98.308922)
		(width 0.0889)
		(layer "In2.Cu")
		(net "M_D_DQ<50>")
	)
	(segment
		(start 290.36264 -114.983514)
		(end 294.07993 -114.983514)
		(width 0.14224)
		(layer "In2.Cu")
		(net "M_D_DQ<50>")
	)
	(segment
		(start 285.8389 -101.256846)
		(end 285.84144 -101.261164)
		(width 0.0889)
		(layer "In2.Cu")
		(net "M_D_DQ<50>")
	)
	(segment
		(start 286.288988 -106.714544)
		(end 286.288988 -109.073188)
		(width 0.14224)
		(layer "In2.Cu")
		(net "M_D_DQ<50>")
	)
	(segment
		(start 286.288988 -106.361738)
		(end 286.288988 -106.714544)
		(width 0.0889)
		(layer "In2.Cu")
		(net "M_D_DQ<50>")
	)
	(segment
		(start 285.8389 -102.247446)
		(end 285.84779 -102.262686)
		(width 0.0889)
		(layer "In2.Cu")
		(net "M_D_DQ<50>")
	)
	(segment
		(start 285.8389 -100.266246)
		(end 285.84779 -100.281486)
		(width 0.0889)
		(layer "In2.Cu")
		(net "M_D_DQ<50>")
	)
	(segment
		(start 305.7652 -119.050054)
		(end 305.7652 -123.432824)
		(width 0.14224)
		(layer "In2.Cu")
		(net "M_D_DQ<50>")
	)
	(segment
		(start 305.616864 -132.044948)
		(end 305.616864 -134.632446)
		(width 0.14224)
		(layer "In2.Cu")
		(net "M_D_DQ<50>")
	)
	(segment
		(start 287.8836 -112.504474)
		(end 290.36264 -114.983514)
		(width 0.14224)
		(layer "In2.Cu")
		(net "M_D_DQ<50>")
	)
	(segment
		(start 285.84144 -101.261164)
		(end 285.84779 -101.272086)
		(width 0.0889)
		(layer "In2.Cu")
		(net "M_D_DQ<50>")
	)
	(segment
		(start 287.8836 -110.6678)
		(end 287.8836 -112.504474)
		(width 0.14224)
		(layer "In2.Cu")
		(net "M_D_DQ<50>")
	)
	(segment
		(start 306.507134 -129.890266)
		(end 305.705002 -130.692398)
		(width 0.14224)
		(layer "In2.Cu")
		(net "M_D_DQ<50>")
	)
	(segment
		(start 306.507134 -126.364746)
		(end 306.507134 -129.890266)
		(width 0.14224)
		(layer "In2.Cu")
		(net "M_D_DQ<50>")
	)
	(segment
		(start 305.705002 -130.692398)
		(end 305.705002 -131.266946)
		(width 0.14224)
		(layer "In2.Cu")
		(net "M_D_DQ<50>")
	)
	(segment
		(start 305.705002 -131.266946)
		(end 306.049934 -131.611878)
		(width 0.14224)
		(layer "In2.Cu")
		(net "M_D_DQ<50>")
	)
	(segment
		(start 285.940246 -104.449372)
		(end 285.940246 -106.012996)
		(width 0.0889)
		(layer "In2.Cu")
		(net "M_D_DQ<50>")
	)
	(segment
		(start 285.8389 -103.238046)
		(end 285.84779 -103.253286)
		(width 0.0889)
		(layer "In2.Cu")
		(net "M_D_DQ<50>")
	)
	(segment
		(start 285.8389 -104.228646)
		(end 285.940246 -104.449372)
		(width 0.0889)
		(layer "In2.Cu")
		(net "M_D_DQ<50>")
	)
	(segment
		(start 285.940246 -106.012996)
		(end 286.288988 -106.361738)
		(width 0.0889)
		(layer "In2.Cu")
		(net "M_D_DQ<50>")
	)
	(segment
		(start 305.7652 -123.432824)
		(end 306.568602 -124.236226)
		(width 0.14224)
		(layer "In2.Cu")
		(net "M_D_DQ<50>")
	)
	(segment
		(start 285.378652 -98.881184)
		(end 285.403798 -98.89236)
		(width 0.0889)
		(layer "In2.Cu")
		(net "M_D_DQ<50>")
	)
	(segment
		(start 286.288988 -109.073188)
		(end 287.8836 -110.6678)
		(width 0.14224)
		(layer "In2.Cu")
		(net "M_D_DQ<50>")
	)
	(segment
		(start 306.568602 -124.236226)
		(end 306.568602 -124.803408)
		(width 0.14224)
		(layer "In2.Cu")
		(net "M_D_DQ<50>")
	)
	(segment
		(start 306.451 -124.92101)
		(end 306.451 -126.308612)
		(width 0.14224)
		(layer "In2.Cu")
		(net "M_D_DQ<50>")
	)
	(segment
		(start 305.616864 -134.632446)
		(end 306.899818 -135.9154)
		(width 0.14224)
		(layer "In2.Cu")
		(net "M_D_DQ<50>")
	)
	(segment
		(start 306.451 -126.308612)
		(end 306.507134 -126.364746)
		(width 0.14224)
		(layer "In2.Cu")
		(net "M_D_DQ<50>")
	)
	(segment
		(start 299.86097 -113.145824)
		(end 305.7652 -119.050054)
		(width 0.14224)
		(layer "In2.Cu")
		(net "M_D_DQ<50>")
	)
	(segment
		(start 306.568602 -124.803408)
		(end 306.451 -124.92101)
		(width 0.14224)
		(layer "In2.Cu")
		(net "M_D_DQ<50>")
	)
	(segment
		(start 306.049934 -131.611878)
		(end 305.616864 -132.044948)
		(width 0.14224)
		(layer "In2.Cu")
		(net "M_D_DQ<50>")
	)
	(arc
		(start 285.84779 -100.281486)
		(mid 285.901323 -100.481384)
		(end 285.84779 -100.681282)
		(width 0.0889)
		(layer "In2.Cu")
		(net "M_D_DQ<50>")
	)
	(arc
		(start 285.805372 -99.224592)
		(mid 285.827234 -99.25745)
		(end 285.84779 -99.29114)
		(width 0.0889)
		(layer "In2.Cu")
		(net "M_D_DQ<50>")
	)
	(arc
		(start 285.84779 -103.653082)
		(mid 285.768601 -103.939697)
		(end 285.8389 -104.228646)
		(width 0.0889)
		(layer "In2.Cu")
		(net "M_D_DQ<50>")
	)
	(arc
		(start 285.84779 -102.662482)
		(mid 285.768601 -102.949097)
		(end 285.8389 -103.238046)
		(width 0.0889)
		(layer "In2.Cu")
		(net "M_D_DQ<50>")
	)
	(arc
		(start 285.403798 -98.89236)
		(mid 285.627391 -99.030909)
		(end 285.805372 -99.224592)
		(width 0.0889)
		(layer "In2.Cu")
		(net "M_D_DQ<50>")
	)
	(arc
		(start 285.84779 -101.272086)
		(mid 285.901323 -101.471984)
		(end 285.84779 -101.671882)
		(width 0.0889)
		(layer "In2.Cu")
		(net "M_D_DQ<50>")
	)
	(arc
		(start 285.84779 -103.253286)
		(mid 285.901323 -103.453184)
		(end 285.84779 -103.653082)
		(width 0.0889)
		(layer "In2.Cu")
		(net "M_D_DQ<50>")
	)
	(arc
		(start 285.84779 -102.262686)
		(mid 285.901323 -102.462584)
		(end 285.84779 -102.662482)
		(width 0.0889)
		(layer "In2.Cu")
		(net "M_D_DQ<50>")
	)
	(arc
		(start 285.84779 -100.681282)
		(mid 285.768601 -100.967897)
		(end 285.8389 -101.256846)
		(width 0.0889)
		(layer "In2.Cu")
		(net "M_D_DQ<50>")
	)
	(arc
		(start 285.84779 -99.690682)
		(mid 285.768601 -99.977297)
		(end 285.8389 -100.266246)
		(width 0.0889)
		(layer "In2.Cu")
		(net "M_D_DQ<50>")
	)
	(arc
		(start 285.84779 -101.671882)
		(mid 285.768601 -101.958497)
		(end 285.8389 -102.247446)
		(width 0.0889)
		(layer "In2.Cu")
		(net "M_D_DQ<50>")
	)
	(arc
		(start 285.84779 -99.29114)
		(mid 285.901357 -99.490928)
		(end 285.84779 -99.690682)
		(width 0.0889)
		(layer "In2.Cu")
		(net "M_D_DQ<50>")
	)
	(arc
		(start 285.149798 -98.308922)
		(mid 285.129758 -98.648811)
		(end 285.378652 -98.881184)
		(width 0.0889)
		(layer "In2.Cu")
		(net "M_D_DQ<50>")
	)
	(segment
		(start 197.249796 -136.345168)
		(end 197.151752 -135.8138)
		(width 0.1651)
		(layer "F.Cu")
		(net "M_D_DQ<4>")
	)
	(segment
		(start 234.466638 -84.31784)
		(end 233.895138 -84.31784)
		(width 0.1651)
		(layer "F.Cu")
		(net "M_D_DQ<4>")
	)
	(segment
		(start 197.250304 -137.67054)
		(end 197.249796 -137.67054)
		(width 0.1651)
		(layer "F.Cu")
		(net "M_D_DQ<4>")
	)
	(segment
		(start 197.249796 -137.67054)
		(end 197.249796 -136.345168)
		(width 0.1651)
		(layer "F.Cu")
		(net "M_D_DQ<4>")
	)
	(via
		(at 197.151752 -135.8138)
		(size 0.508)
		(drill 0.254)
		(layers "F.Cu" "B.Cu")
		(net "M_D_DQ<4>")
	)
	(via
		(at 196.399912 -131.611878)
		(size 0.508)
		(drill 0.254)
		(layers "F.Cu" "B.Cu")
		(net "M_D_DQ<4>")
	)
	(via
		(at 233.895138 -84.31784)
		(size 0.508)
		(drill 0.254)
		(layers "F.Cu" "B.Cu")
		(net "M_D_DQ<4>")
	)
	(segment
		(start 196.40042 -132.876036)
		(end 196.399912 -132.875782)
		(width 0.1651)
		(layer "B.Cu")
		(net "M_D_DQ<4>")
	)
	(segment
		(start 196.399912 -132.875782)
		(end 196.399912 -131.611878)
		(width 0.1651)
		(layer "B.Cu")
		(net "M_D_DQ<4>")
	)
	(segment
		(start 196.784468 -129.877058)
		(end 196.24294 -130.418586)
		(width 0.14224)
		(layer "In2.Cu")
		(net "M_D_DQ<4>")
	)
	(segment
		(start 196.24294 -131.454906)
		(end 196.399912 -131.611878)
		(width 0.14224)
		(layer "In2.Cu")
		(net "M_D_DQ<4>")
	)
	(segment
		(start 197.476618 -116.9543)
		(end 197.476618 -128.205738)
		(width 0.14224)
		(layer "In2.Cu")
		(net "M_D_DQ<4>")
	)
	(segment
		(start 196.102986 -134.765034)
		(end 197.151752 -135.8138)
		(width 0.14224)
		(layer "In2.Cu")
		(net "M_D_DQ<4>")
	)
	(segment
		(start 230.817928 -83.882738)
		(end 229.450138 -83.882738)
		(width 0.14224)
		(layer "In2.Cu")
		(net "M_D_DQ<4>")
	)
	(segment
		(start 203.1746 -111.6076)
		(end 202.156568 -111.6076)
		(width 0.14224)
		(layer "In2.Cu")
		(net "M_D_DQ<4>")
	)
	(segment
		(start 195.966842 -132.657596)
		(end 195.966842 -134.436358)
		(width 0.14224)
		(layer "In2.Cu")
		(net "M_D_DQ<4>")
	)
	(segment
		(start 233.083354 -84.31784)
		(end 232.484422 -84.069682)
		(width 0.0889)
		(layer "In2.Cu")
		(net "M_D_DQ<4>")
	)
	(segment
		(start 214.8078 -98.525076)
		(end 214.8078 -99.9744)
		(width 0.14224)
		(layer "In2.Cu")
		(net "M_D_DQ<4>")
	)
	(segment
		(start 233.895138 -84.31784)
		(end 233.083354 -84.31784)
		(width 0.0889)
		(layer "In2.Cu")
		(net "M_D_DQ<4>")
	)
	(segment
		(start 197.476618 -128.205738)
		(end 196.784468 -129.877058)
		(width 0.14224)
		(layer "In2.Cu")
		(net "M_D_DQ<4>")
	)
	(segment
		(start 197.948296 -115.815872)
		(end 197.476618 -116.9543)
		(width 0.14224)
		(layer "In2.Cu")
		(net "M_D_DQ<4>")
	)
	(segment
		(start 214.8078 -99.9744)
		(end 203.1746 -111.6076)
		(width 0.14224)
		(layer "In2.Cu")
		(net "M_D_DQ<4>")
	)
	(segment
		(start 232.484422 -84.069682)
		(end 232.297478 -83.882738)
		(width 0.0889)
		(layer "In2.Cu")
		(net "M_D_DQ<4>")
	)
	(segment
		(start 195.966842 -134.436358)
		(end 196.102986 -134.765034)
		(width 0.14224)
		(layer "In2.Cu")
		(net "M_D_DQ<4>")
	)
	(segment
		(start 196.24294 -130.418586)
		(end 196.24294 -131.454906)
		(width 0.14224)
		(layer "In2.Cu")
		(net "M_D_DQ<4>")
	)
	(segment
		(start 202.156568 -111.6076)
		(end 197.948296 -115.815872)
		(width 0.14224)
		(layer "In2.Cu")
		(net "M_D_DQ<4>")
	)
	(segment
		(start 232.297478 -83.882738)
		(end 230.817928 -83.882738)
		(width 0.0889)
		(layer "In2.Cu")
		(net "M_D_DQ<4>")
	)
	(segment
		(start 229.450138 -83.882738)
		(end 214.8078 -98.525076)
		(width 0.14224)
		(layer "In2.Cu")
		(net "M_D_DQ<4>")
	)
	(segment
		(start 196.399912 -131.611878)
		(end 195.966842 -132.657596)
		(width 0.14224)
		(layer "In2.Cu")
		(net "M_D_DQ<4>")
	)
	(segment
		(start 300.099984 -133.076442)
		(end 300.099984 -134.340346)
		(width 0.1651)
		(layer "F.Cu")
		(net "M_D_DQ<49>")
	)
	(segment
		(start 282.354274 -98.995738)
		(end 282.925774 -98.995738)
		(width 0.1651)
		(layer "F.Cu")
		(net "M_D_DQ<49>")
	)
	(segment
		(start 300.100492 -133.0706)
		(end 300.099984 -133.076442)
		(width 0.1651)
		(layer "F.Cu")
		(net "M_D_DQ<49>")
	)
	(via
		(at 282.925774 -98.995738)
		(size 0.508)
		(drill 0.254)
		(layers "F.Cu" "B.Cu")
		(net "M_D_DQ<49>")
	)
	(via
		(at 300.772068 -130.330956)
		(size 0.508)
		(drill 0.254)
		(layers "F.Cu" "B.Cu")
		(net "M_D_DQ<49>")
	)
	(via
		(at 300.099984 -134.340346)
		(size 0.508)
		(drill 0.254)
		(layers "F.Cu" "B.Cu")
		(net "M_D_DQ<49>")
	)
	(segment
		(start 300.772068 -130.330956)
		(end 300.772068 -129.827782)
		(width 0.1651)
		(layer "B.Cu")
		(net "M_D_DQ<49>")
	)
	(segment
		(start 300.949868 -129.649982)
		(end 300.949868 -128.276096)
		(width 0.1651)
		(layer "B.Cu")
		(net "M_D_DQ<49>")
	)
	(segment
		(start 300.949868 -128.276096)
		(end 300.950376 -128.276096)
		(width 0.1651)
		(layer "B.Cu")
		(net "M_D_DQ<49>")
	)
	(segment
		(start 300.772068 -129.827782)
		(end 300.949868 -129.649982)
		(width 0.1651)
		(layer "B.Cu")
		(net "M_D_DQ<49>")
	)
	(segment
		(start 300.50105 -133.8834)
		(end 300.50105 -134.1882)
		(width 0.14224)
		(layer "In2.Cu")
		(net "M_D_DQ<49>")
	)
	(segment
		(start 300.772068 -130.330956)
		(end 300.749716 -130.330956)
		(width 0.14224)
		(layer "In2.Cu")
		(net "M_D_DQ<49>")
	)
	(segment
		(start 301.22622 -121.756424)
		(end 299.796708 -120.326912)
		(width 0.14224)
		(layer "In2.Cu")
		(net "M_D_DQ<49>")
	)
	(segment
		(start 300.55185 -131.823968)
		(end 300.261274 -132.114544)
		(width 0.14224)
		(layer "In2.Cu")
		(net "M_D_DQ<49>")
	)
	(segment
		(start 300.321472 -130.7592)
		(end 300.321472 -131.188968)
		(width 0.14224)
		(layer "In2.Cu")
		(net "M_D_DQ<49>")
	)
	(segment
		(start 301.5234 -127.762254)
		(end 301.5234 -129.1082)
		(width 0.14224)
		(layer "In2.Cu")
		(net "M_D_DQ<49>")
	)
	(segment
		(start 284.48 -112.9792)
		(end 284.48 -114.0714)
		(width 0.14224)
		(layer "In2.Cu")
		(net "M_D_DQ<49>")
	)
	(segment
		(start 282.585414 -100.76561)
		(end 282.579064 -100.776278)
		(width 0.0889)
		(layer "In2.Cu")
		(net "M_D_DQ<49>")
	)
	(segment
		(start 299.221906 -120.901714)
		(end 301.260002 -122.93981)
		(width 0.14224)
		(layer "In2.Cu")
		(net "M_D_DQ<49>")
	)
	(segment
		(start 300.50105 -134.1882)
		(end 300.348904 -134.340346)
		(width 0.14224)
		(layer "In2.Cu")
		(net "M_D_DQ<49>")
	)
	(segment
		(start 300.749716 -130.330956)
		(end 300.321472 -130.7592)
		(width 0.14224)
		(layer "In2.Cu")
		(net "M_D_DQ<49>")
	)
	(segment
		(start 282.01493 -105.1306)
		(end 282.01493 -105.271316)
		(width 0.0889)
		(layer "In2.Cu")
		(net "M_D_DQ<49>")
	)
	(segment
		(start 282.52547 -102.957884)
		(end 282.52547 -104.62006)
		(width 0.0889)
		(layer "In2.Cu")
		(net "M_D_DQ<49>")
	)
	(segment
		(start 301.77867 -121.15927)
		(end 301.77867 -121.46915)
		(width 0.14224)
		(layer "In2.Cu")
		(net "M_D_DQ<49>")
	)
	(segment
		(start 300.261274 -133.643624)
		(end 300.50105 -133.8834)
		(width 0.14224)
		(layer "In2.Cu")
		(net "M_D_DQ<49>")
	)
	(segment
		(start 301.5234 -129.1082)
		(end 301.260002 -129.371598)
		(width 0.14224)
		(layer "In2.Cu")
		(net "M_D_DQ<49>")
	)
	(segment
		(start 299.221906 -120.614186)
		(end 299.221906 -120.901714)
		(width 0.14224)
		(layer "In2.Cu")
		(net "M_D_DQ<49>")
	)
	(segment
		(start 300.348904 -134.340346)
		(end 300.099984 -134.340346)
		(width 0.14224)
		(layer "In2.Cu")
		(net "M_D_DQ<49>")
	)
	(segment
		(start 284.48 -114.0714)
		(end 288.732976 -118.324376)
		(width 0.14224)
		(layer "In2.Cu")
		(net "M_D_DQ<49>")
	)
	(segment
		(start 301.260002 -127.498856)
		(end 301.5234 -127.762254)
		(width 0.14224)
		(layer "In2.Cu")
		(net "M_D_DQ<49>")
	)
	(segment
		(start 299.796708 -120.326912)
		(end 299.50918 -120.326912)
		(width 0.14224)
		(layer "In2.Cu")
		(net "M_D_DQ<49>")
	)
	(segment
		(start 300.47565 -133.1214)
		(end 300.261274 -133.335776)
		(width 0.14224)
		(layer "In2.Cu")
		(net "M_D_DQ<49>")
	)
	(segment
		(start 300.47565 -132.6896)
		(end 300.47565 -133.1214)
		(width 0.14224)
		(layer "In2.Cu")
		(net "M_D_DQ<49>")
	)
	(segment
		(start 301.260002 -129.754122)
		(end 300.772068 -130.242056)
		(width 0.14224)
		(layer "In2.Cu")
		(net "M_D_DQ<49>")
	)
	(segment
		(start 300.261274 -132.114544)
		(end 300.261274 -132.475224)
		(width 0.14224)
		(layer "In2.Cu")
		(net "M_D_DQ<49>")
	)
	(segment
		(start 300.772068 -130.242056)
		(end 300.772068 -130.330956)
		(width 0.14224)
		(layer "In2.Cu")
		(net "M_D_DQ<49>")
	)
	(segment
		(start 300.55185 -131.419346)
		(end 300.55185 -131.823968)
		(width 0.14224)
		(layer "In2.Cu")
		(net "M_D_DQ<49>")
	)
	(segment
		(start 288.732976 -118.324376)
		(end 298.943776 -118.324376)
		(width 0.14224)
		(layer "In2.Cu")
		(net "M_D_DQ<49>")
	)
	(segment
		(start 282.579064 -102.166928)
		(end 282.585414 -102.177596)
		(width 0.0889)
		(layer "In2.Cu")
		(net "M_D_DQ<49>")
	)
	(segment
		(start 298.943776 -118.324376)
		(end 301.77867 -121.15927)
		(width 0.14224)
		(layer "In2.Cu")
		(net "M_D_DQ<49>")
	)
	(segment
		(start 300.261274 -132.475224)
		(end 300.47565 -132.6896)
		(width 0.14224)
		(layer "In2.Cu")
		(net "M_D_DQ<49>")
	)
	(segment
		(start 301.491396 -121.756424)
		(end 301.22622 -121.756424)
		(width 0.14224)
		(layer "In2.Cu")
		(net "M_D_DQ<49>")
	)
	(segment
		(start 282.52547 -104.62006)
		(end 282.01493 -105.1306)
		(width 0.0889)
		(layer "In2.Cu")
		(net "M_D_DQ<49>")
	)
	(segment
		(start 282.276804 -110.776004)
		(end 284.48 -112.9792)
		(width 0.14224)
		(layer "In2.Cu")
		(net "M_D_DQ<49>")
	)
	(segment
		(start 301.260002 -122.93981)
		(end 301.260002 -127.498856)
		(width 0.14224)
		(layer "In2.Cu")
		(net "M_D_DQ<49>")
	)
	(segment
		(start 282.01493 -105.271316)
		(end 282.276804 -105.53319)
		(width 0.0889)
		(layer "In2.Cu")
		(net "M_D_DQ<49>")
	)
	(segment
		(start 299.50918 -120.326912)
		(end 299.221906 -120.614186)
		(width 0.14224)
		(layer "In2.Cu")
		(net "M_D_DQ<49>")
	)
	(segment
		(start 301.260002 -129.371598)
		(end 301.260002 -129.754122)
		(width 0.14224)
		(layer "In2.Cu")
		(net "M_D_DQ<49>")
	)
	(segment
		(start 282.925774 -98.995738)
		(end 282.632912 -99.661472)
		(width 0.0889)
		(layer "In2.Cu")
		(net "M_D_DQ<49>")
	)
	(segment
		(start 300.261274 -133.335776)
		(end 300.261274 -133.643624)
		(width 0.14224)
		(layer "In2.Cu")
		(net "M_D_DQ<49>")
	)
	(segment
		(start 282.579064 -100.776278)
		(end 282.574238 -100.784914)
		(width 0.0889)
		(layer "In2.Cu")
		(net "M_D_DQ<49>")
	)
	(segment
		(start 282.276804 -105.53319)
		(end 282.276804 -110.776004)
		(width 0.14224)
		(layer "In2.Cu")
		(net "M_D_DQ<49>")
	)
	(segment
		(start 300.321472 -131.188968)
		(end 300.55185 -131.419346)
		(width 0.14224)
		(layer "In2.Cu")
		(net "M_D_DQ<49>")
	)
	(segment
		(start 301.77867 -121.46915)
		(end 301.491396 -121.756424)
		(width 0.14224)
		(layer "In2.Cu")
		(net "M_D_DQ<49>")
	)
	(arc
		(start 282.574238 -100.784914)
		(mid 282.525483 -100.981266)
		(end 282.579064 -101.176328)
		(width 0.0889)
		(layer "In2.Cu")
		(net "M_D_DQ<49>")
	)
	(arc
		(start 282.579064 -99.786186)
		(mid 282.526564 -99.962255)
		(end 282.557728 -100.14331)
		(width 0.0889)
		(layer "In2.Cu")
		(net "M_D_DQ<49>")
	)
	(arc
		(start 282.579064 -102.757986)
		(mid 282.53911 -102.85441)
		(end 282.52547 -102.957884)
		(width 0.0889)
		(layer "In2.Cu")
		(net "M_D_DQ<49>")
	)
	(arc
		(start 282.579064 -100.185728)
		(mid 282.658286 -100.474846)
		(end 282.585414 -100.76561)
		(width 0.0889)
		(layer "In2.Cu")
		(net "M_D_DQ<49>")
	)
	(arc
		(start 282.632912 -99.661472)
		(mid 282.609592 -99.725386)
		(end 282.579064 -99.786186)
		(width 0.0889)
		(layer "In2.Cu")
		(net "M_D_DQ<49>")
	)
	(arc
		(start 282.585414 -102.177596)
		(mid 282.658334 -102.468613)
		(end 282.579064 -102.757986)
		(width 0.0889)
		(layer "In2.Cu")
		(net "M_D_DQ<49>")
	)
	(arc
		(start 282.557728 -100.14331)
		(mid 282.567693 -100.164873)
		(end 282.579064 -100.185728)
		(width 0.0889)
		(layer "In2.Cu")
		(net "M_D_DQ<49>")
	)
	(arc
		(start 282.579064 -101.767132)
		(mid 282.525565 -101.96703)
		(end 282.579064 -102.166928)
		(width 0.0889)
		(layer "In2.Cu")
		(net "M_D_DQ<49>")
	)
	(arc
		(start 282.579064 -101.176328)
		(mid 282.658195 -101.47173)
		(end 282.579064 -101.767132)
		(width 0.0889)
		(layer "In2.Cu")
		(net "M_D_DQ<49>")
	)
	(segment
		(start 282.354274 -97.014538)
		(end 282.925774 -97.014538)
		(width 0.1651)
		(layer "F.Cu")
		(net "M_D_DQ<48>")
	)
	(segment
		(start 300.949868 -137.676382)
		(end 300.772068 -135.8138)
		(width 0.1651)
		(layer "F.Cu")
		(net "M_D_DQ<48>")
	)
	(segment
		(start 300.950376 -137.67054)
		(end 300.949868 -137.676382)
		(width 0.1651)
		(layer "F.Cu")
		(net "M_D_DQ<48>")
	)
	(via
		(at 300.099984 -131.611878)
		(size 0.508)
		(drill 0.254)
		(layers "F.Cu" "B.Cu")
		(net "M_D_DQ<48>")
	)
	(via
		(at 282.925774 -97.014538)
		(size 0.508)
		(drill 0.254)
		(layers "F.Cu" "B.Cu")
		(net "M_D_DQ<48>")
	)
	(via
		(at 300.772068 -135.8138)
		(size 0.508)
		(drill 0.254)
		(layers "F.Cu" "B.Cu")
		(net "M_D_DQ<48>")
	)
	(segment
		(start 300.099984 -132.875782)
		(end 300.099984 -131.611878)
		(width 0.1651)
		(layer "B.Cu")
		(net "M_D_DQ<48>")
	)
	(segment
		(start 300.100492 -132.876036)
		(end 300.099984 -132.875782)
		(width 0.1651)
		(layer "B.Cu")
		(net "M_D_DQ<48>")
	)
	(segment
		(start 282.413964 -102.262432)
		(end 282.41879 -102.271068)
		(width 0.0889)
		(layer "In2.Cu")
		(net "M_D_DQ<48>")
	)
	(segment
		(start 299.138848 -119.736362)
		(end 298.260008 -120.615202)
		(width 0.14224)
		(layer "In2.Cu")
		(net "M_D_DQ<48>")
	)
	(segment
		(start 300.5836 -127.696976)
		(end 300.794928 -127.908304)
		(width 0.14224)
		(layer "In2.Cu")
		(net "M_D_DQ<48>")
	)
	(segment
		(start 300.5836 -126.384812)
		(end 300.5836 -127.696976)
		(width 0.14224)
		(layer "In2.Cu")
		(net "M_D_DQ<48>")
	)
	(segment
		(start 282.474924 -97.482914)
		(end 282.474924 -97.104454)
		(width 0.0889)
		(layer "In2.Cu")
		(net "M_D_DQ<48>")
	)
	(segment
		(start 298.260008 -120.891808)
		(end 300.297596 -122.929396)
		(width 0.14224)
		(layer "In2.Cu")
		(net "M_D_DQ<48>")
	)
	(segment
		(start 282.547314 -97.875852)
		(end 282.547314 -97.555304)
		(width 0.0889)
		(layer "In2.Cu")
		(net "M_D_DQ<48>")
	)
	(segment
		(start 300.099984 -131.611878)
		(end 299.666914 -132.044948)
		(width 0.14224)
		(layer "In2.Cu")
		(net "M_D_DQ<48>")
	)
	(segment
		(start 282.56484 -97.014538)
		(end 282.925774 -97.014538)
		(width 0.0889)
		(layer "In2.Cu")
		(net "M_D_DQ<48>")
	)
	(segment
		(start 282.547314 -97.555304)
		(end 282.474924 -97.482914)
		(width 0.0889)
		(layer "In2.Cu")
		(net "M_D_DQ<48>")
	)
	(segment
		(start 282.41879 -101.662992)
		(end 282.413964 -101.671628)
		(width 0.0889)
		(layer "In2.Cu")
		(net "M_D_DQ<48>")
	)
	(segment
		(start 298.69384 -118.959376)
		(end 299.138848 -119.404384)
		(width 0.14224)
		(layer "In2.Cu")
		(net "M_D_DQ<48>")
	)
	(segment
		(start 281.824176 -105.329228)
		(end 281.629104 -105.5243)
		(width 0.0889)
		(layer "In2.Cu")
		(net "M_D_DQ<48>")
	)
	(segment
		(start 281.629104 -110.941358)
		(end 283.9339 -113.246154)
		(width 0.14224)
		(layer "In2.Cu")
		(net "M_D_DQ<48>")
	)
	(segment
		(start 282.474924 -97.104454)
		(end 282.56484 -97.014538)
		(width 0.0889)
		(layer "In2.Cu")
		(net "M_D_DQ<48>")
	)
	(segment
		(start 300.794928 -129.074672)
		(end 300.5582 -129.3114)
		(width 0.14224)
		(layer "In2.Cu")
		(net "M_D_DQ<48>")
	)
	(segment
		(start 282.334716 -102.958138)
		(end 282.334716 -104.540812)
		(width 0.0889)
		(layer "In2.Cu")
		(net "M_D_DQ<48>")
	)
	(segment
		(start 299.882814 -130.44551)
		(end 299.882814 -131.394708)
		(width 0.14224)
		(layer "In2.Cu")
		(net "M_D_DQ<48>")
	)
	(segment
		(start 283.9339 -113.246154)
		(end 283.9339 -114.464846)
		(width 0.14224)
		(layer "In2.Cu")
		(net "M_D_DQ<48>")
	)
	(segment
		(start 288.42843 -118.959376)
		(end 298.69384 -118.959376)
		(width 0.14224)
		(layer "In2.Cu")
		(net "M_D_DQ<48>")
	)
	(segment
		(start 299.882814 -131.394708)
		(end 300.099984 -131.611878)
		(width 0.14224)
		(layer "In2.Cu")
		(net "M_D_DQ<48>")
	)
	(segment
		(start 282.413964 -100.681028)
		(end 282.407614 -100.691696)
		(width 0.0889)
		(layer "In2.Cu")
		(net "M_D_DQ<48>")
	)
	(segment
		(start 281.824176 -105.051352)
		(end 281.824176 -105.329228)
		(width 0.0889)
		(layer "In2.Cu")
		(net "M_D_DQ<48>")
	)
	(segment
		(start 300.297596 -126.098808)
		(end 300.5836 -126.384812)
		(width 0.14224)
		(layer "In2.Cu")
		(net "M_D_DQ<48>")
	)
	(segment
		(start 300.5582 -129.3114)
		(end 300.5582 -129.770124)
		(width 0.14224)
		(layer "In2.Cu")
		(net "M_D_DQ<48>")
	)
	(segment
		(start 299.666914 -132.044948)
		(end 299.666914 -135.00481)
		(width 0.14224)
		(layer "In2.Cu")
		(net "M_D_DQ<48>")
	)
	(segment
		(start 298.260008 -120.615202)
		(end 298.260008 -120.891808)
		(width 0.14224)
		(layer "In2.Cu")
		(net "M_D_DQ<48>")
	)
	(segment
		(start 299.138848 -119.404384)
		(end 299.138848 -119.736362)
		(width 0.14224)
		(layer "In2.Cu")
		(net "M_D_DQ<48>")
	)
	(segment
		(start 300.794928 -127.908304)
		(end 300.794928 -129.074672)
		(width 0.14224)
		(layer "In2.Cu")
		(net "M_D_DQ<48>")
	)
	(segment
		(start 300.475904 -135.8138)
		(end 300.772068 -135.8138)
		(width 0.14224)
		(layer "In2.Cu")
		(net "M_D_DQ<48>")
	)
	(segment
		(start 300.297596 -122.929396)
		(end 300.297596 -126.098808)
		(width 0.14224)
		(layer "In2.Cu")
		(net "M_D_DQ<48>")
	)
	(segment
		(start 282.334716 -104.540812)
		(end 281.824176 -105.051352)
		(width 0.0889)
		(layer "In2.Cu")
		(net "M_D_DQ<48>")
	)
	(segment
		(start 299.666914 -135.00481)
		(end 300.475904 -135.8138)
		(width 0.14224)
		(layer "In2.Cu")
		(net "M_D_DQ<48>")
	)
	(segment
		(start 281.629104 -105.5243)
		(end 281.629104 -110.941358)
		(width 0.14224)
		(layer "In2.Cu")
		(net "M_D_DQ<48>")
	)
	(segment
		(start 300.5582 -129.770124)
		(end 299.882814 -130.44551)
		(width 0.14224)
		(layer "In2.Cu")
		(net "M_D_DQ<48>")
	)
	(segment
		(start 283.9339 -114.464846)
		(end 288.42843 -118.959376)
		(width 0.14224)
		(layer "In2.Cu")
		(net "M_D_DQ<48>")
	)
	(arc
		(start 282.407614 -100.691696)
		(mid 282.334816 -100.982459)
		(end 282.413964 -101.271578)
		(width 0.0889)
		(layer "In2.Cu")
		(net "M_D_DQ<48>")
	)
	(arc
		(start 282.413964 -101.271578)
		(mid 282.467434 -101.466641)
		(end 282.41879 -101.662992)
		(width 0.0889)
		(layer "In2.Cu")
		(net "M_D_DQ<48>")
	)
	(arc
		(start 282.413964 -99.291648)
		(mid 282.467438 -99.491292)
		(end 282.413964 -99.690936)
		(width 0.0889)
		(layer "In2.Cu")
		(net "M_D_DQ<48>")
	)
	(arc
		(start 282.53055 -98.068638)
		(mid 282.526621 -98.394773)
		(end 282.413964 -98.700844)
		(width 0.0889)
		(layer "In2.Cu")
		(net "M_D_DQ<48>")
	)
	(arc
		(start 282.38831 -100.231956)
		(mid 282.400508 -100.256921)
		(end 282.413964 -100.281232)
		(width 0.0889)
		(layer "In2.Cu")
		(net "M_D_DQ<48>")
	)
	(arc
		(start 282.413964 -99.690936)
		(mid 282.335496 -99.958335)
		(end 282.38831 -100.231956)
		(width 0.0889)
		(layer "In2.Cu")
		(net "M_D_DQ<48>")
	)
	(arc
		(start 282.413964 -101.671628)
		(mid 282.334833 -101.96703)
		(end 282.413964 -102.262432)
		(width 0.0889)
		(layer "In2.Cu")
		(net "M_D_DQ<48>")
	)
	(arc
		(start 282.413964 -100.281232)
		(mid 282.467463 -100.48113)
		(end 282.413964 -100.681028)
		(width 0.0889)
		(layer "In2.Cu")
		(net "M_D_DQ<48>")
	)
	(arc
		(start 282.41879 -102.271068)
		(mid 282.467545 -102.46742)
		(end 282.413964 -102.662482)
		(width 0.0889)
		(layer "In2.Cu")
		(net "M_D_DQ<48>")
	)
	(arc
		(start 282.413964 -98.700844)
		(mid 282.334833 -98.996246)
		(end 282.413964 -99.291648)
		(width 0.0889)
		(layer "In2.Cu")
		(net "M_D_DQ<48>")
	)
	(arc
		(start 282.53055 -98.068638)
		(mid 282.527107 -97.971217)
		(end 282.547314 -97.875852)
		(width 0.0889)
		(layer "In2.Cu")
		(net "M_D_DQ<48>")
	)
	(arc
		(start 282.413964 -102.662482)
		(mid 282.354864 -102.80509)
		(end 282.334716 -102.958138)
		(width 0.0889)
		(layer "In2.Cu")
		(net "M_D_DQ<48>")
	)
	(segment
		(start 294.999918 -133.076442)
		(end 294.999918 -134.340346)
		(width 0.1651)
		(layer "F.Cu")
		(net "M_D_DQ<47>")
	)
	(segment
		(start 278.920194 -98.995738)
		(end 279.491694 -98.995738)
		(width 0.1651)
		(layer "F.Cu")
		(net "M_D_DQ<47>")
	)
	(segment
		(start 295.000426 -133.0706)
		(end 294.999918 -133.076442)
		(width 0.1651)
		(layer "F.Cu")
		(net "M_D_DQ<47>")
	)
	(via
		(at 279.491694 -98.995738)
		(size 0.508)
		(drill 0.254)
		(layers "F.Cu" "B.Cu")
		(net "M_D_DQ<47>")
	)
	(via
		(at 294.999918 -134.340346)
		(size 0.508)
		(drill 0.254)
		(layers "F.Cu" "B.Cu")
		(net "M_D_DQ<47>")
	)
	(via
		(at 295.849802 -130.330956)
		(size 0.508)
		(drill 0.254)
		(layers "F.Cu" "B.Cu")
		(net "M_D_DQ<47>")
	)
	(segment
		(start 295.849802 -128.276096)
		(end 295.849802 -130.330956)
		(width 0.1651)
		(layer "B.Cu")
		(net "M_D_DQ<47>")
	)
	(segment
		(start 295.85031 -128.276096)
		(end 295.849802 -128.276096)
		(width 0.1651)
		(layer "B.Cu")
		(net "M_D_DQ<47>")
	)
	(segment
		(start 296.1894 -124.003054)
		(end 296.1894 -125.5776)
		(width 0.14224)
		(layer "In2.Cu")
		(net "M_D_DQ<47>")
	)
	(segment
		(start 295.418256 -133.0198)
		(end 295.161208 -133.276848)
		(width 0.14224)
		(layer "In2.Cu")
		(net "M_D_DQ<47>")
	)
	(segment
		(start 284.327092 -121.198386)
		(end 284.54604 -121.198386)
		(width 0.14224)
		(layer "In2.Cu")
		(net "M_D_DQ<47>")
	)
	(segment
		(start 281.453082 -118.324376)
		(end 281.30373 -118.473728)
		(width 0.14224)
		(layer "In2.Cu")
		(net "M_D_DQ<47>")
	)
	(segment
		(start 284.901894 -121.55424)
		(end 284.901894 -121.773188)
		(width 0.14224)
		(layer "In2.Cu")
		(net "M_D_DQ<47>")
	)
	(segment
		(start 278.139144 -106.021378)
		(end 278.139144 -114.78895)
		(width 0.14224)
		(layer "In2.Cu")
		(net "M_D_DQ<47>")
	)
	(segment
		(start 277.889208 -105.771442)
		(end 278.139144 -106.021378)
		(width 0.0889)
		(layer "In2.Cu")
		(net "M_D_DQ<47>")
	)
	(segment
		(start 295.443656 -131.233418)
		(end 295.443656 -131.9022)
		(width 0.14224)
		(layer "In2.Cu")
		(net "M_D_DQ<47>")
	)
	(segment
		(start 295.161208 -132.457952)
		(end 295.418256 -132.715)
		(width 0.14224)
		(layer "In2.Cu")
		(net "M_D_DQ<47>")
	)
	(segment
		(start 280.303478 -117.174772)
		(end 280.154126 -117.324124)
		(width 0.14224)
		(layer "In2.Cu")
		(net "M_D_DQ<47>")
	)
	(segment
		(start 284.54604 -121.198386)
		(end 284.901894 -121.55424)
		(width 0.14224)
		(layer "In2.Cu")
		(net "M_D_DQ<47>")
	)
	(segment
		(start 281.30373 -118.473728)
		(end 281.30373 -118.692676)
		(width 0.14224)
		(layer "In2.Cu")
		(net "M_D_DQ<47>")
	)
	(segment
		(start 282.027884 -118.899178)
		(end 282.246832 -118.899178)
		(width 0.14224)
		(layer "In2.Cu")
		(net "M_D_DQ<47>")
	)
	(segment
		(start 282.809188 -120.198134)
		(end 283.028136 -120.198134)
		(width 0.14224)
		(layer "In2.Cu")
		(net "M_D_DQ<47>")
	)
	(segment
		(start 284.17774 -121.347738)
		(end 284.327092 -121.198386)
		(width 0.14224)
		(layer "In2.Cu")
		(net "M_D_DQ<47>")
	)
	(segment
		(start 281.30373 -118.692676)
		(end 281.659584 -119.04853)
		(width 0.14224)
		(layer "In2.Cu")
		(net "M_D_DQ<47>")
	)
	(segment
		(start 296.5196 -128.204468)
		(end 296.7228 -128.407668)
		(width 0.14224)
		(layer "In2.Cu")
		(net "M_D_DQ<47>")
	)
	(segment
		(start 277.889208 -105.104946)
		(end 277.889208 -105.771442)
		(width 0.0889)
		(layer "In2.Cu")
		(net "M_D_DQ<47>")
	)
	(segment
		(start 295.418256 -132.715)
		(end 295.418256 -133.0198)
		(width 0.14224)
		(layer "In2.Cu")
		(net "M_D_DQ<47>")
	)
	(segment
		(start 280.081736 -101.591618)
		(end 279.236424 -102.43693)
		(width 0.0889)
		(layer "In2.Cu")
		(net "M_D_DQ<47>")
	)
	(segment
		(start 295.399206 -131.188968)
		(end 295.443656 -131.233418)
		(width 0.14224)
		(layer "In2.Cu")
		(net "M_D_DQ<47>")
	)
	(segment
		(start 283.177488 -120.048782)
		(end 283.396436 -120.048782)
		(width 0.14224)
		(layer "In2.Cu")
		(net "M_D_DQ<47>")
	)
	(segment
		(start 278.139144 -114.78895)
		(end 280.303478 -116.953284)
		(width 0.14224)
		(layer "In2.Cu")
		(net "M_D_DQ<47>")
	)
	(segment
		(start 295.399206 -130.7592)
		(end 295.399206 -131.188968)
		(width 0.14224)
		(layer "In2.Cu")
		(net "M_D_DQ<47>")
	)
	(segment
		(start 295.161208 -133.276848)
		(end 295.161208 -133.550152)
		(width 0.14224)
		(layer "In2.Cu")
		(net "M_D_DQ<47>")
	)
	(segment
		(start 295.9608 -127.848868)
		(end 296.3164 -128.204468)
		(width 0.14224)
		(layer "In2.Cu")
		(net "M_D_DQ<47>")
	)
	(segment
		(start 282.602686 -119.47398)
		(end 282.453334 -119.623332)
		(width 0.14224)
		(layer "In2.Cu")
		(net "M_D_DQ<47>")
	)
	(segment
		(start 296.0624 -129.220468)
		(end 296.0624 -130.127756)
		(width 0.14224)
		(layer "In2.Cu")
		(net "M_D_DQ<47>")
	)
	(segment
		(start 285.12643 -122.515376)
		(end 294.701722 -122.515376)
		(width 0.14224)
		(layer "In2.Cu")
		(net "M_D_DQ<47>")
	)
	(segment
		(start 283.396436 -120.048782)
		(end 283.75229 -120.404636)
		(width 0.14224)
		(layer "In2.Cu")
		(net "M_D_DQ<47>")
	)
	(segment
		(start 279.236424 -103.75773)
		(end 277.889208 -105.104946)
		(width 0.0889)
		(layer "In2.Cu")
		(net "M_D_DQ<47>")
	)
	(segment
		(start 282.246832 -118.899178)
		(end 282.602686 -119.255032)
		(width 0.14224)
		(layer "In2.Cu")
		(net "M_D_DQ<47>")
	)
	(segment
		(start 283.75229 -120.623584)
		(end 283.602938 -120.772936)
		(width 0.14224)
		(layer "In2.Cu")
		(net "M_D_DQ<47>")
	)
	(segment
		(start 296.1894 -125.5776)
		(end 295.9608 -125.8062)
		(width 0.14224)
		(layer "In2.Cu")
		(net "M_D_DQ<47>")
	)
	(segment
		(start 296.5196 -129.017268)
		(end 296.2656 -129.017268)
		(width 0.14224)
		(layer "In2.Cu")
		(net "M_D_DQ<47>")
	)
	(segment
		(start 281.097228 -117.749574)
		(end 281.453082 -118.105428)
		(width 0.14224)
		(layer "In2.Cu")
		(net "M_D_DQ<47>")
	)
	(segment
		(start 296.7228 -128.407668)
		(end 296.7228 -128.814068)
		(width 0.14224)
		(layer "In2.Cu")
		(net "M_D_DQ<47>")
	)
	(segment
		(start 279.98674 -99.661472)
		(end 280.081736 -99.82708)
		(width 0.0889)
		(layer "In2.Cu")
		(net "M_D_DQ<47>")
	)
	(segment
		(start 296.7228 -128.814068)
		(end 296.5196 -129.017268)
		(width 0.14224)
		(layer "In2.Cu")
		(net "M_D_DQ<47>")
	)
	(segment
		(start 295.443656 -131.9022)
		(end 295.161208 -132.184648)
		(width 0.14224)
		(layer "In2.Cu")
		(net "M_D_DQ<47>")
	)
	(segment
		(start 295.82745 -130.330956)
		(end 295.399206 -130.7592)
		(width 0.14224)
		(layer "In2.Cu")
		(net "M_D_DQ<47>")
	)
	(segment
		(start 283.602938 -120.991884)
		(end 283.958792 -121.347738)
		(width 0.14224)
		(layer "In2.Cu")
		(net "M_D_DQ<47>")
	)
	(segment
		(start 295.161208 -132.184648)
		(end 295.161208 -132.457952)
		(width 0.14224)
		(layer "In2.Cu")
		(net "M_D_DQ<47>")
	)
	(segment
		(start 279.236424 -102.43693)
		(end 279.236424 -103.75773)
		(width 0.0889)
		(layer "In2.Cu")
		(net "M_D_DQ<47>")
	)
	(segment
		(start 283.75229 -120.404636)
		(end 283.75229 -120.623584)
		(width 0.14224)
		(layer "In2.Cu")
		(net "M_D_DQ<47>")
	)
	(segment
		(start 280.081736 -99.82708)
		(end 280.081736 -101.591618)
		(width 0.0889)
		(layer "In2.Cu")
		(net "M_D_DQ<47>")
	)
	(segment
		(start 295.849802 -130.330956)
		(end 295.82745 -130.330956)
		(width 0.14224)
		(layer "In2.Cu")
		(net "M_D_DQ<47>")
	)
	(segment
		(start 281.453082 -118.105428)
		(end 281.453082 -118.324376)
		(width 0.14224)
		(layer "In2.Cu")
		(net "M_D_DQ<47>")
	)
	(segment
		(start 281.878532 -119.04853)
		(end 282.027884 -118.899178)
		(width 0.14224)
		(layer "In2.Cu")
		(net "M_D_DQ<47>")
	)
	(segment
		(start 282.453334 -119.623332)
		(end 282.453334 -119.84228)
		(width 0.14224)
		(layer "In2.Cu")
		(net "M_D_DQ<47>")
	)
	(segment
		(start 283.028136 -120.198134)
		(end 283.177488 -120.048782)
		(width 0.14224)
		(layer "In2.Cu")
		(net "M_D_DQ<47>")
	)
	(segment
		(start 279.491694 -98.995738)
		(end 279.98674 -99.661472)
		(width 0.0889)
		(layer "In2.Cu")
		(net "M_D_DQ<47>")
	)
	(segment
		(start 282.602686 -119.255032)
		(end 282.602686 -119.47398)
		(width 0.14224)
		(layer "In2.Cu")
		(net "M_D_DQ<47>")
	)
	(segment
		(start 280.154126 -117.324124)
		(end 280.154126 -117.543072)
		(width 0.14224)
		(layer "In2.Cu")
		(net "M_D_DQ<47>")
	)
	(segment
		(start 296.0624 -130.127756)
		(end 295.8592 -130.330956)
		(width 0.14224)
		(layer "In2.Cu")
		(net "M_D_DQ<47>")
	)
	(segment
		(start 295.9608 -125.8062)
		(end 295.9608 -127.848868)
		(width 0.14224)
		(layer "In2.Cu")
		(net "M_D_DQ<47>")
	)
	(segment
		(start 284.752542 -122.141488)
		(end 285.12643 -122.515376)
		(width 0.14224)
		(layer "In2.Cu")
		(net "M_D_DQ<47>")
	)
	(segment
		(start 282.453334 -119.84228)
		(end 282.809188 -120.198134)
		(width 0.14224)
		(layer "In2.Cu")
		(net "M_D_DQ<47>")
	)
	(segment
		(start 284.752542 -121.92254)
		(end 284.752542 -122.141488)
		(width 0.14224)
		(layer "In2.Cu")
		(net "M_D_DQ<47>")
	)
	(segment
		(start 284.901894 -121.773188)
		(end 284.752542 -121.92254)
		(width 0.14224)
		(layer "In2.Cu")
		(net "M_D_DQ<47>")
	)
	(segment
		(start 280.50998 -117.898926)
		(end 280.728928 -117.898926)
		(width 0.14224)
		(layer "In2.Cu")
		(net "M_D_DQ<47>")
	)
	(segment
		(start 283.958792 -121.347738)
		(end 284.17774 -121.347738)
		(width 0.14224)
		(layer "In2.Cu")
		(net "M_D_DQ<47>")
	)
	(segment
		(start 295.272206 -134.340346)
		(end 294.999918 -134.340346)
		(width 0.14224)
		(layer "In2.Cu")
		(net "M_D_DQ<47>")
	)
	(segment
		(start 296.3164 -128.204468)
		(end 296.5196 -128.204468)
		(width 0.14224)
		(layer "In2.Cu")
		(net "M_D_DQ<47>")
	)
	(segment
		(start 280.154126 -117.543072)
		(end 280.50998 -117.898926)
		(width 0.14224)
		(layer "In2.Cu")
		(net "M_D_DQ<47>")
	)
	(segment
		(start 295.450006 -134.162546)
		(end 295.272206 -134.340346)
		(width 0.14224)
		(layer "In2.Cu")
		(net "M_D_DQ<47>")
	)
	(segment
		(start 283.602938 -120.772936)
		(end 283.602938 -120.991884)
		(width 0.14224)
		(layer "In2.Cu")
		(net "M_D_DQ<47>")
	)
	(segment
		(start 280.728928 -117.898926)
		(end 280.87828 -117.749574)
		(width 0.14224)
		(layer "In2.Cu")
		(net "M_D_DQ<47>")
	)
	(segment
		(start 281.659584 -119.04853)
		(end 281.878532 -119.04853)
		(width 0.14224)
		(layer "In2.Cu")
		(net "M_D_DQ<47>")
	)
	(segment
		(start 280.87828 -117.749574)
		(end 281.097228 -117.749574)
		(width 0.14224)
		(layer "In2.Cu")
		(net "M_D_DQ<47>")
	)
	(segment
		(start 295.161208 -133.550152)
		(end 295.450006 -133.83895)
		(width 0.14224)
		(layer "In2.Cu")
		(net "M_D_DQ<47>")
	)
	(segment
		(start 295.450006 -133.83895)
		(end 295.450006 -134.162546)
		(width 0.14224)
		(layer "In2.Cu")
		(net "M_D_DQ<47>")
	)
	(segment
		(start 295.8592 -130.330956)
		(end 295.849802 -130.330956)
		(width 0.14224)
		(layer "In2.Cu")
		(net "M_D_DQ<47>")
	)
	(segment
		(start 296.2656 -129.017268)
		(end 296.0624 -129.220468)
		(width 0.14224)
		(layer "In2.Cu")
		(net "M_D_DQ<47>")
	)
	(segment
		(start 280.303478 -116.953284)
		(end 280.303478 -117.174772)
		(width 0.14224)
		(layer "In2.Cu")
		(net "M_D_DQ<47>")
	)
	(segment
		(start 294.701722 -122.515376)
		(end 296.1894 -124.003054)
		(width 0.14224)
		(layer "In2.Cu")
		(net "M_D_DQ<47>")
	)
	(segment
		(start 295.85031 -137.67054)
		(end 295.850056 -137.67054)
		(width 0.1651)
		(layer "F.Cu")
		(net "M_D_DQ<46>")
	)
	(segment
		(start 295.850056 -135.915654)
		(end 295.849802 -135.9154)
		(width 0.1651)
		(layer "F.Cu")
		(net "M_D_DQ<46>")
	)
	(segment
		(start 295.850056 -136.7028)
		(end 295.982136 -136.57072)
		(width 0.1651)
		(layer "F.Cu")
		(net "M_D_DQ<46>")
	)
	(segment
		(start 295.850056 -136.2202)
		(end 295.850056 -135.915654)
		(width 0.1651)
		(layer "F.Cu")
		(net "M_D_DQ<46>")
	)
	(segment
		(start 295.982136 -136.57072)
		(end 295.982136 -136.35228)
		(width 0.1651)
		(layer "F.Cu")
		(net "M_D_DQ<46>")
	)
	(segment
		(start 295.850056 -137.67054)
		(end 295.850056 -136.7028)
		(width 0.1651)
		(layer "F.Cu")
		(net "M_D_DQ<46>")
	)
	(segment
		(start 278.920194 -97.014538)
		(end 279.491694 -97.014538)
		(width 0.1651)
		(layer "F.Cu")
		(net "M_D_DQ<46>")
	)
	(segment
		(start 295.982136 -136.35228)
		(end 295.850056 -136.2202)
		(width 0.1651)
		(layer "F.Cu")
		(net "M_D_DQ<46>")
	)
	(via
		(at 279.491694 -97.014538)
		(size 0.508)
		(drill 0.254)
		(layers "F.Cu" "B.Cu")
		(net "M_D_DQ<46>")
	)
	(via
		(at 295.849802 -135.9154)
		(size 0.508)
		(drill 0.254)
		(layers "F.Cu" "B.Cu")
		(net "M_D_DQ<46>")
	)
	(via
		(at 294.999918 -131.611878)
		(size 0.508)
		(drill 0.254)
		(layers "F.Cu" "B.Cu")
		(net "M_D_DQ<46>")
	)
	(segment
		(start 294.999918 -132.875782)
		(end 294.999918 -131.611878)
		(width 0.1651)
		(layer "B.Cu")
		(net "M_D_DQ<46>")
	)
	(segment
		(start 295.000426 -132.876036)
		(end 294.999918 -132.875782)
		(width 0.1651)
		(layer "B.Cu")
		(net "M_D_DQ<46>")
	)
	(segment
		(start 294.999918 -131.611878)
		(end 294.566848 -132.044948)
		(width 0.14224)
		(layer "In2.Cu")
		(net "M_D_DQ<46>")
	)
	(segment
		(start 295.4782 -129.821686)
		(end 294.831008 -130.468878)
		(width 0.14224)
		(layer "In2.Cu")
		(net "M_D_DQ<46>")
	)
	(segment
		(start 279.491694 -99.586288)
		(end 279.50668 -99.586288)
		(width 0.0889)
		(layer "In2.Cu")
		(net "M_D_DQ<46>")
	)
	(segment
		(start 294.566848 -134.632446)
		(end 295.849802 -135.9154)
		(width 0.14224)
		(layer "In2.Cu")
		(net "M_D_DQ<46>")
	)
	(segment
		(start 294.422576 -123.150376)
		(end 295.0464 -123.7742)
		(width 0.14224)
		(layer "In2.Cu")
		(net "M_D_DQ<46>")
	)
	(segment
		(start 279.161748 -97.776284)
		(end 279.144984 -97.804986)
		(width 0.0889)
		(layer "In2.Cu")
		(net "M_D_DQ<46>")
	)
	(segment
		(start 279.144984 -98.205036)
		(end 279.151334 -98.215704)
		(width 0.0889)
		(layer "In2.Cu")
		(net "M_D_DQ<46>")
	)
	(segment
		(start 294.831008 -130.468878)
		(end 294.831008 -131.442968)
		(width 0.14224)
		(layer "In2.Cu")
		(net "M_D_DQ<46>")
	)
	(segment
		(start 277.394924 -106.036618)
		(end 277.394924 -115.571524)
		(width 0.14224)
		(layer "In2.Cu")
		(net "M_D_DQ<46>")
	)
	(segment
		(start 295.4782 -128.1938)
		(end 295.4782 -129.821686)
		(width 0.14224)
		(layer "In2.Cu")
		(net "M_D_DQ<46>")
	)
	(segment
		(start 279.891744 -101.512878)
		(end 279.046432 -102.35819)
		(width 0.0889)
		(layer "In2.Cu")
		(net "M_D_DQ<46>")
	)
	(segment
		(start 279.140158 -99.187)
		(end 279.309576 -99.481132)
		(width 0.0889)
		(layer "In2.Cu")
		(net "M_D_DQ<46>")
	)
	(segment
		(start 295.0464 -125.3744)
		(end 295.4274 -125.7554)
		(width 0.14224)
		(layer "In2.Cu")
		(net "M_D_DQ<46>")
	)
	(segment
		(start 277.699216 -105.732326)
		(end 277.394924 -106.036618)
		(width 0.0889)
		(layer "In2.Cu")
		(net "M_D_DQ<46>")
	)
	(segment
		(start 279.891744 -99.878388)
		(end 279.891744 -101.512878)
		(width 0.0889)
		(layer "In2.Cu")
		(net "M_D_DQ<46>")
	)
	(segment
		(start 279.140158 -98.1964)
		(end 279.144984 -98.205036)
		(width 0.0889)
		(layer "In2.Cu")
		(net "M_D_DQ<46>")
	)
	(segment
		(start 279.046432 -102.35819)
		(end 279.046432 -103.67899)
		(width 0.0889)
		(layer "In2.Cu")
		(net "M_D_DQ<46>")
	)
	(segment
		(start 277.699216 -105.026206)
		(end 277.699216 -105.732326)
		(width 0.0889)
		(layer "In2.Cu")
		(net "M_D_DQ<46>")
	)
	(segment
		(start 279.838404 -99.786186)
		(end 279.891744 -99.878388)
		(width 0.0889)
		(layer "In2.Cu")
		(net "M_D_DQ<46>")
	)
	(segment
		(start 294.566848 -132.044948)
		(end 294.566848 -134.632446)
		(width 0.14224)
		(layer "In2.Cu")
		(net "M_D_DQ<46>")
	)
	(segment
		(start 279.046432 -103.67899)
		(end 277.699216 -105.026206)
		(width 0.0889)
		(layer "In2.Cu")
		(net "M_D_DQ<46>")
	)
	(segment
		(start 294.831008 -131.442968)
		(end 294.999918 -131.611878)
		(width 0.14224)
		(layer "In2.Cu")
		(net "M_D_DQ<46>")
	)
	(segment
		(start 295.4274 -125.7554)
		(end 295.4274 -128.143)
		(width 0.14224)
		(layer "In2.Cu")
		(net "M_D_DQ<46>")
	)
	(segment
		(start 295.0464 -123.7742)
		(end 295.0464 -125.3744)
		(width 0.14224)
		(layer "In2.Cu")
		(net "M_D_DQ<46>")
	)
	(segment
		(start 295.4274 -128.143)
		(end 295.4782 -128.1938)
		(width 0.14224)
		(layer "In2.Cu")
		(net "M_D_DQ<46>")
	)
	(segment
		(start 279.491694 -97.014538)
		(end 279.161748 -97.776284)
		(width 0.0889)
		(layer "In2.Cu")
		(net "M_D_DQ<46>")
	)
	(segment
		(start 284.973776 -123.150376)
		(end 294.422576 -123.150376)
		(width 0.14224)
		(layer "In2.Cu")
		(net "M_D_DQ<46>")
	)
	(segment
		(start 277.394924 -115.571524)
		(end 284.973776 -123.150376)
		(width 0.14224)
		(layer "In2.Cu")
		(net "M_D_DQ<46>")
	)
	(arc
		(start 279.144984 -97.804986)
		(mid 279.091514 -98.000049)
		(end 279.140158 -98.1964)
		(width 0.0889)
		(layer "In2.Cu")
		(net "M_D_DQ<46>")
	)
	(arc
		(start 279.309576 -99.481132)
		(mid 279.386549 -99.558101)
		(end 279.491694 -99.586288)
		(width 0.0889)
		(layer "In2.Cu")
		(net "M_D_DQ<46>")
	)
	(arc
		(start 279.144984 -98.795586)
		(mid 279.091514 -98.990649)
		(end 279.140158 -99.187)
		(width 0.0889)
		(layer "In2.Cu")
		(net "M_D_DQ<46>")
	)
	(arc
		(start 279.151334 -98.215704)
		(mid 279.224132 -98.506467)
		(end 279.144984 -98.795586)
		(width 0.0889)
		(layer "In2.Cu")
		(net "M_D_DQ<46>")
	)
	(arc
		(start 279.50668 -99.586288)
		(mid 279.698322 -99.643454)
		(end 279.838404 -99.786186)
		(width 0.0889)
		(layer "In2.Cu")
		(net "M_D_DQ<46>")
	)
	(segment
		(start 289.050476 -133.0706)
		(end 289.049968 -133.076442)
		(width 0.1651)
		(layer "F.Cu")
		(net "M_D_DQ<45>")
	)
	(segment
		(start 276.344634 -98.500184)
		(end 276.916134 -98.500184)
		(width 0.1651)
		(layer "F.Cu")
		(net "M_D_DQ<45>")
	)
	(segment
		(start 289.049968 -133.076442)
		(end 289.049968 -134.340346)
		(width 0.1651)
		(layer "F.Cu")
		(net "M_D_DQ<45>")
	)
	(via
		(at 289.049968 -134.340346)
		(size 0.508)
		(drill 0.254)
		(layers "F.Cu" "B.Cu")
		(net "M_D_DQ<45>")
	)
	(via
		(at 289.823652 -130.330956)
		(size 0.508)
		(drill 0.254)
		(layers "F.Cu" "B.Cu")
		(net "M_D_DQ<45>")
	)
	(via
		(at 276.916134 -98.500184)
		(size 0.508)
		(drill 0.254)
		(layers "F.Cu" "B.Cu")
		(net "M_D_DQ<45>")
	)
	(segment
		(start 289.899852 -128.276096)
		(end 289.899852 -130.254756)
		(width 0.1651)
		(layer "B.Cu")
		(net "M_D_DQ<45>")
	)
	(segment
		(start 289.899852 -130.254756)
		(end 289.823652 -130.330956)
		(width 0.1651)
		(layer "B.Cu")
		(net "M_D_DQ<45>")
	)
	(segment
		(start 289.90036 -128.276096)
		(end 289.899852 -128.276096)
		(width 0.1651)
		(layer "B.Cu")
		(net "M_D_DQ<45>")
	)
	(segment
		(start 276.916134 -98.16211)
		(end 276.858222 -98.104198)
		(width 0.0889)
		(layer "In2.Cu")
		(net "M_D_DQ<45>")
	)
	(segment
		(start 274.2184 -119.297196)
		(end 274.505674 -119.58447)
		(width 0.14224)
		(layer "In2.Cu")
		(net "M_D_DQ<45>")
	)
	(segment
		(start 289.6616 -130.168904)
		(end 289.823652 -130.330956)
		(width 0.14224)
		(layer "In2.Cu")
		(net "M_D_DQ<45>")
	)
	(segment
		(start 289.449256 -133.146546)
		(end 289.211258 -133.384544)
		(width 0.14224)
		(layer "In2.Cu")
		(net "M_D_DQ<45>")
	)
	(segment
		(start 274.79879 -119.58447)
		(end 275.203666 -119.179594)
		(width 0.14224)
		(layer "In2.Cu")
		(net "M_D_DQ<45>")
	)
	(segment
		(start 280.953718 -126.098046)
		(end 281.241246 -126.098046)
		(width 0.14224)
		(layer "In2.Cu")
		(net "M_D_DQ<45>")
	)
	(segment
		(start 282.103322 -127.24765)
		(end 282.39085 -127.24765)
		(width 0.14224)
		(layer "In2.Cu")
		(net "M_D_DQ<45>")
	)
	(segment
		(start 289.500056 -131.445)
		(end 289.500056 -131.927346)
		(width 0.14224)
		(layer "In2.Cu")
		(net "M_D_DQ<45>")
	)
	(segment
		(start 272.683224 -105.965498)
		(end 272.683224 -116.371624)
		(width 0.14224)
		(layer "In2.Cu")
		(net "M_D_DQ<45>")
	)
	(segment
		(start 281.717496 -127.633476)
		(end 282.103322 -127.24765)
		(width 0.14224)
		(layer "In2.Cu")
		(net "M_D_DQ<45>")
	)
	(segment
		(start 289.823652 -130.330956)
		(end 289.8013 -130.330956)
		(width 0.14224)
		(layer "In2.Cu")
		(net "M_D_DQ<45>")
	)
	(segment
		(start 289.211258 -133.696456)
		(end 289.474656 -133.959854)
		(width 0.14224)
		(layer "In2.Cu")
		(net "M_D_DQ<45>")
	)
	(segment
		(start 274.2184 -119.015256)
		(end 274.2184 -119.297196)
		(width 0.14224)
		(layer "In2.Cu")
		(net "M_D_DQ<45>")
	)
	(segment
		(start 279.931622 -125.970538)
		(end 279.931622 -126.258066)
		(width 0.14224)
		(layer "In2.Cu")
		(net "M_D_DQ<45>")
	)
	(segment
		(start 280.378916 -125.523244)
		(end 279.931622 -125.970538)
		(width 0.14224)
		(layer "In2.Cu")
		(net "M_D_DQ<45>")
	)
	(segment
		(start 289.449256 -132.791454)
		(end 289.449256 -133.146546)
		(width 0.14224)
		(layer "In2.Cu")
		(net "M_D_DQ<45>")
	)
	(segment
		(start 275.203666 -119.179594)
		(end 275.491194 -119.179594)
		(width 0.14224)
		(layer "In2.Cu")
		(net "M_D_DQ<45>")
	)
	(segment
		(start 275.71446 -99.780598)
		(end 274.858734 -101.261164)
		(width 0.0889)
		(layer "In2.Cu")
		(net "M_D_DQ<45>")
	)
	(segment
		(start 289.211258 -133.384544)
		(end 289.211258 -133.696456)
		(width 0.14224)
		(layer "In2.Cu")
		(net "M_D_DQ<45>")
	)
	(segment
		(start 289.8013 -130.330956)
		(end 289.373056 -130.7592)
		(width 0.14224)
		(layer "In2.Cu")
		(net "M_D_DQ<45>")
	)
	(segment
		(start 289.322256 -134.340346)
		(end 289.049968 -134.340346)
		(width 0.14224)
		(layer "In2.Cu")
		(net "M_D_DQ<45>")
	)
	(segment
		(start 289.474656 -134.187946)
		(end 289.322256 -134.340346)
		(width 0.14224)
		(layer "In2.Cu")
		(net "M_D_DQ<45>")
	)
	(segment
		(start 281.142694 -127.346202)
		(end 281.429968 -127.633476)
		(width 0.14224)
		(layer "In2.Cu")
		(net "M_D_DQ<45>")
	)
	(segment
		(start 281.52852 -126.672848)
		(end 281.142694 -127.058674)
		(width 0.14224)
		(layer "In2.Cu")
		(net "M_D_DQ<45>")
	)
	(segment
		(start 274.505674 -119.58447)
		(end 274.79879 -119.58447)
		(width 0.14224)
		(layer "In2.Cu")
		(net "M_D_DQ<45>")
	)
	(segment
		(start 275.461476 -120.074944)
		(end 275.461476 -120.318276)
		(width 0.14224)
		(layer "In2.Cu")
		(net "M_D_DQ<45>")
	)
	(segment
		(start 275.491194 -119.179594)
		(end 275.780246 -119.468646)
		(width 0.14224)
		(layer "In2.Cu")
		(net "M_D_DQ<45>")
	)
	(segment
		(start 281.142694 -127.058674)
		(end 281.142694 -127.346202)
		(width 0.14224)
		(layer "In2.Cu")
		(net "M_D_DQ<45>")
	)
	(segment
		(start 279.931622 -126.258066)
		(end 280.218896 -126.54534)
		(width 0.14224)
		(layer "In2.Cu")
		(net "M_D_DQ<45>")
	)
	(segment
		(start 276.075394 -99.586288)
		(end 276.057614 -99.586288)
		(width 0.0889)
		(layer "In2.Cu")
		(net "M_D_DQ<45>")
	)
	(segment
		(start 282.39085 -127.24765)
		(end 282.956 -127.8128)
		(width 0.14224)
		(layer "In2.Cu")
		(net "M_D_DQ<45>")
	)
	(segment
		(start 287.074356 -129.111756)
		(end 289.4584 -129.111756)
		(width 0.14224)
		(layer "In2.Cu")
		(net "M_D_DQ<45>")
	)
	(segment
		(start 272.446496 -105.72877)
		(end 272.683224 -105.965498)
		(width 0.0889)
		(layer "In2.Cu")
		(net "M_D_DQ<45>")
	)
	(segment
		(start 281.241246 -126.098046)
		(end 281.52852 -126.38532)
		(width 0.14224)
		(layer "In2.Cu")
		(net "M_D_DQ<45>")
	)
	(segment
		(start 274.85467 -101.762052)
		(end 272.446496 -104.170226)
		(width 0.0889)
		(layer "In2.Cu")
		(net "M_D_DQ<45>")
	)
	(segment
		(start 275.780246 -119.468646)
		(end 275.780246 -119.756174)
		(width 0.14224)
		(layer "In2.Cu")
		(net "M_D_DQ<45>")
	)
	(segment
		(start 289.4584 -129.111756)
		(end 289.6616 -129.314956)
		(width 0.14224)
		(layer "In2.Cu")
		(net "M_D_DQ<45>")
	)
	(segment
		(start 280.506424 -126.54534)
		(end 280.953718 -126.098046)
		(width 0.14224)
		(layer "In2.Cu")
		(net "M_D_DQ<45>")
	)
	(segment
		(start 280.218896 -126.54534)
		(end 280.506424 -126.54534)
		(width 0.14224)
		(layer "In2.Cu")
		(net "M_D_DQ<45>")
	)
	(segment
		(start 289.211258 -132.553456)
		(end 289.449256 -132.791454)
		(width 0.14224)
		(layer "In2.Cu")
		(net "M_D_DQ<45>")
	)
	(segment
		(start 280.378916 -125.235716)
		(end 280.378916 -125.523244)
		(width 0.14224)
		(layer "In2.Cu")
		(net "M_D_DQ<45>")
	)
	(segment
		(start 272.446496 -104.170226)
		(end 272.446496 -105.72877)
		(width 0.0889)
		(layer "In2.Cu")
		(net "M_D_DQ<45>")
	)
	(segment
		(start 274.85467 -101.268022)
		(end 274.85467 -101.762052)
		(width 0.0889)
		(layer "In2.Cu")
		(net "M_D_DQ<45>")
	)
	(segment
		(start 289.373056 -130.7592)
		(end 289.373056 -131.318)
		(width 0.14224)
		(layer "In2.Cu")
		(net "M_D_DQ<45>")
	)
	(segment
		(start 276.916134 -98.500184)
		(end 276.916134 -98.16211)
		(width 0.0889)
		(layer "In2.Cu")
		(net "M_D_DQ<45>")
	)
	(segment
		(start 274.628864 -118.317264)
		(end 274.628864 -118.604792)
		(width 0.14224)
		(layer "In2.Cu")
		(net "M_D_DQ<45>")
	)
	(segment
		(start 272.683224 -116.371624)
		(end 274.628864 -118.317264)
		(width 0.14224)
		(layer "In2.Cu")
		(net "M_D_DQ<45>")
	)
	(segment
		(start 275.461476 -120.318276)
		(end 280.378916 -125.235716)
		(width 0.14224)
		(layer "In2.Cu")
		(net "M_D_DQ<45>")
	)
	(segment
		(start 285.7754 -127.8128)
		(end 287.074356 -129.111756)
		(width 0.14224)
		(layer "In2.Cu")
		(net "M_D_DQ<45>")
	)
	(segment
		(start 274.858734 -101.261164)
		(end 274.85467 -101.268022)
		(width 0.0889)
		(layer "In2.Cu")
		(net "M_D_DQ<45>")
	)
	(segment
		(start 289.500056 -131.927346)
		(end 289.211258 -132.216144)
		(width 0.14224)
		(layer "In2.Cu")
		(net "M_D_DQ<45>")
	)
	(segment
		(start 289.6616 -129.314956)
		(end 289.6616 -130.168904)
		(width 0.14224)
		(layer "In2.Cu")
		(net "M_D_DQ<45>")
	)
	(segment
		(start 289.474656 -133.959854)
		(end 289.474656 -134.187946)
		(width 0.14224)
		(layer "In2.Cu")
		(net "M_D_DQ<45>")
	)
	(segment
		(start 289.373056 -131.318)
		(end 289.500056 -131.445)
		(width 0.14224)
		(layer "In2.Cu")
		(net "M_D_DQ<45>")
	)
	(segment
		(start 289.211258 -132.216144)
		(end 289.211258 -132.553456)
		(width 0.14224)
		(layer "In2.Cu")
		(net "M_D_DQ<45>")
	)
	(segment
		(start 282.956 -127.8128)
		(end 285.7754 -127.8128)
		(width 0.14224)
		(layer "In2.Cu")
		(net "M_D_DQ<45>")
	)
	(segment
		(start 281.429968 -127.633476)
		(end 281.717496 -127.633476)
		(width 0.14224)
		(layer "In2.Cu")
		(net "M_D_DQ<45>")
	)
	(segment
		(start 281.52852 -126.38532)
		(end 281.52852 -126.672848)
		(width 0.14224)
		(layer "In2.Cu")
		(net "M_D_DQ<45>")
	)
	(segment
		(start 274.628864 -118.604792)
		(end 274.2184 -119.015256)
		(width 0.14224)
		(layer "In2.Cu")
		(net "M_D_DQ<45>")
	)
	(segment
		(start 275.780246 -119.756174)
		(end 275.461476 -120.074944)
		(width 0.14224)
		(layer "In2.Cu")
		(net "M_D_DQ<45>")
	)
	(arc
		(start 276.858222 -98.104198)
		(mid 276.555953 -98.325747)
		(end 276.569424 -98.700336)
		(width 0.0889)
		(layer "In2.Cu")
		(net "M_D_DQ<45>")
	)
	(arc
		(start 276.057614 -99.586288)
		(mid 275.860453 -99.638247)
		(end 275.71446 -99.780598)
		(width 0.0889)
		(layer "In2.Cu")
		(net "M_D_DQ<45>")
	)
	(arc
		(start 276.569424 -98.700336)
		(mid 276.573753 -99.283508)
		(end 276.075394 -99.586288)
		(width 0.0889)
		(layer "In2.Cu")
		(net "M_D_DQ<45>")
	)
	(segment
		(start 289.899852 -136.345168)
		(end 289.801808 -135.8138)
		(width 0.1651)
		(layer "F.Cu")
		(net "M_D_DQ<44>")
	)
	(segment
		(start 289.899852 -137.67054)
		(end 289.899852 -136.345168)
		(width 0.1651)
		(layer "F.Cu")
		(net "M_D_DQ<44>")
	)
	(segment
		(start 276.344634 -97.509584)
		(end 276.916134 -97.509584)
		(width 0.1651)
		(layer "F.Cu")
		(net "M_D_DQ<44>")
	)
	(segment
		(start 289.90036 -137.67054)
		(end 289.899852 -137.67054)
		(width 0.1651)
		(layer "F.Cu")
		(net "M_D_DQ<44>")
	)
	(via
		(at 276.916134 -97.509584)
		(size 0.508)
		(drill 0.254)
		(layers "F.Cu" "B.Cu")
		(net "M_D_DQ<44>")
	)
	(via
		(at 289.801808 -135.8138)
		(size 0.508)
		(drill 0.254)
		(layers "F.Cu" "B.Cu")
		(net "M_D_DQ<44>")
	)
	(via
		(at 289.049968 -131.611878)
		(size 0.508)
		(drill 0.254)
		(layers "F.Cu" "B.Cu")
		(net "M_D_DQ<44>")
	)
	(segment
		(start 289.049968 -132.875782)
		(end 289.049968 -131.611878)
		(width 0.1651)
		(layer "B.Cu")
		(net "M_D_DQ<44>")
	)
	(segment
		(start 289.050476 -132.876036)
		(end 289.049968 -132.875782)
		(width 0.1651)
		(layer "B.Cu")
		(net "M_D_DQ<44>")
	)
	(segment
		(start 288.8488 -130.2512)
		(end 288.8488 -131.41071)
		(width 0.14224)
		(layer "In2.Cu")
		(net "M_D_DQ<44>")
	)
	(segment
		(start 284.757876 -128.2954)
		(end 285.374588 -128.2954)
		(width 0.14224)
		(layer "In2.Cu")
		(net "M_D_DQ<44>")
	)
	(segment
		(start 271.946878 -105.965498)
		(end 271.946878 -117.718078)
		(width 0.14224)
		(layer "In2.Cu")
		(net "M_D_DQ<44>")
	)
	(segment
		(start 288.616898 -132.044948)
		(end 288.616898 -134.57809)
		(width 0.14224)
		(layer "In2.Cu")
		(net "M_D_DQ<44>")
	)
	(segment
		(start 288.774886 -134.736078)
		(end 288.774886 -135.03783)
		(width 0.14224)
		(layer "In2.Cu")
		(net "M_D_DQ<44>")
	)
	(segment
		(start 283.431996 -128.2954)
		(end 283.785056 -128.2954)
		(width 0.14224)
		(layer "In2.Cu")
		(net "M_D_DQ<44>")
	)
	(segment
		(start 276.916134 -97.847658)
		(end 276.850856 -97.912936)
		(width 0.0889)
		(layer "In2.Cu")
		(net "M_D_DQ<44>")
	)
	(segment
		(start 284.602936 -128.982978)
		(end 284.602936 -128.45034)
		(width 0.14224)
		(layer "In2.Cu")
		(net "M_D_DQ<44>")
	)
	(segment
		(start 279.278588 -125.049788)
		(end 279.278588 -126.321312)
		(width 0.14224)
		(layer "In2.Cu")
		(net "M_D_DQ<44>")
	)
	(segment
		(start 285.374588 -128.2954)
		(end 287.114996 -130.035808)
		(width 0.14224)
		(layer "In2.Cu")
		(net "M_D_DQ<44>")
	)
	(segment
		(start 284.602936 -128.45034)
		(end 284.757876 -128.2954)
		(width 0.14224)
		(layer "In2.Cu")
		(net "M_D_DQ<44>")
	)
	(segment
		(start 279.278588 -126.321312)
		(end 281.252676 -128.2954)
		(width 0.14224)
		(layer "In2.Cu")
		(net "M_D_DQ<44>")
	)
	(segment
		(start 283.785056 -128.2954)
		(end 283.939996 -128.45034)
		(width 0.14224)
		(layer "In2.Cu")
		(net "M_D_DQ<44>")
	)
	(segment
		(start 272.256504 -104.091486)
		(end 272.256504 -105.655872)
		(width 0.0889)
		(layer "In2.Cu")
		(net "M_D_DQ<44>")
	)
	(segment
		(start 274.66417 -101.68382)
		(end 272.256504 -104.091486)
		(width 0.0889)
		(layer "In2.Cu")
		(net "M_D_DQ<44>")
	)
	(segment
		(start 283.122116 -128.92532)
		(end 283.277056 -128.77038)
		(width 0.14224)
		(layer "In2.Cu")
		(net "M_D_DQ<44>")
	)
	(segment
		(start 287.597596 -130.035808)
		(end 287.826196 -129.807208)
		(width 0.14224)
		(layer "In2.Cu")
		(net "M_D_DQ<44>")
	)
	(segment
		(start 288.8488 -131.41071)
		(end 289.049968 -131.611878)
		(width 0.14224)
		(layer "In2.Cu")
		(net "M_D_DQ<44>")
	)
	(segment
		(start 288.616898 -134.57809)
		(end 288.774886 -134.736078)
		(width 0.14224)
		(layer "In2.Cu")
		(net "M_D_DQ<44>")
	)
	(segment
		(start 288.404808 -129.807208)
		(end 288.8488 -130.2512)
		(width 0.14224)
		(layer "In2.Cu")
		(net "M_D_DQ<44>")
	)
	(segment
		(start 287.826196 -129.807208)
		(end 288.404808 -129.807208)
		(width 0.14224)
		(layer "In2.Cu")
		(net "M_D_DQ<44>")
	)
	(segment
		(start 275.545296 -99.69119)
		(end 274.66417 -101.215444)
		(width 0.0889)
		(layer "In2.Cu")
		(net "M_D_DQ<44>")
	)
	(segment
		(start 289.550856 -135.8138)
		(end 289.801808 -135.8138)
		(width 0.14224)
		(layer "In2.Cu")
		(net "M_D_DQ<44>")
	)
	(segment
		(start 282.459176 -128.2954)
		(end 282.614116 -128.45034)
		(width 0.14224)
		(layer "In2.Cu")
		(net "M_D_DQ<44>")
	)
	(segment
		(start 282.769056 -128.92532)
		(end 283.122116 -128.92532)
		(width 0.14224)
		(layer "In2.Cu")
		(net "M_D_DQ<44>")
	)
	(segment
		(start 289.049968 -131.611878)
		(end 288.616898 -132.044948)
		(width 0.14224)
		(layer "In2.Cu")
		(net "M_D_DQ<44>")
	)
	(segment
		(start 281.252676 -128.2954)
		(end 282.459176 -128.2954)
		(width 0.14224)
		(layer "In2.Cu")
		(net "M_D_DQ<44>")
	)
	(segment
		(start 283.277056 -128.77038)
		(end 283.277056 -128.45034)
		(width 0.14224)
		(layer "In2.Cu")
		(net "M_D_DQ<44>")
	)
	(segment
		(start 283.939996 -128.45034)
		(end 283.939996 -128.971802)
		(width 0.14224)
		(layer "In2.Cu")
		(net "M_D_DQ<44>")
	)
	(segment
		(start 284.100524 -129.13233)
		(end 284.453584 -129.13233)
		(width 0.14224)
		(layer "In2.Cu")
		(net "M_D_DQ<44>")
	)
	(segment
		(start 274.66417 -101.215444)
		(end 274.66417 -101.68382)
		(width 0.0889)
		(layer "In2.Cu")
		(net "M_D_DQ<44>")
	)
	(segment
		(start 272.256504 -105.655872)
		(end 271.946878 -105.965498)
		(width 0.0889)
		(layer "In2.Cu")
		(net "M_D_DQ<44>")
	)
	(segment
		(start 282.614116 -128.45034)
		(end 282.614116 -128.77038)
		(width 0.14224)
		(layer "In2.Cu")
		(net "M_D_DQ<44>")
	)
	(segment
		(start 288.774886 -135.03783)
		(end 289.550856 -135.8138)
		(width 0.14224)
		(layer "In2.Cu")
		(net "M_D_DQ<44>")
	)
	(segment
		(start 284.453584 -129.13233)
		(end 284.602936 -128.982978)
		(width 0.14224)
		(layer "In2.Cu")
		(net "M_D_DQ<44>")
	)
	(segment
		(start 271.946878 -117.718078)
		(end 279.278588 -125.049788)
		(width 0.14224)
		(layer "In2.Cu")
		(net "M_D_DQ<44>")
	)
	(segment
		(start 287.114996 -130.035808)
		(end 287.597596 -130.035808)
		(width 0.14224)
		(layer "In2.Cu")
		(net "M_D_DQ<44>")
	)
	(segment
		(start 276.06879 -99.395788)
		(end 276.032722 -99.395788)
		(width 0.0889)
		(layer "In2.Cu")
		(net "M_D_DQ<44>")
	)
	(segment
		(start 283.939996 -128.971802)
		(end 284.100524 -129.13233)
		(width 0.14224)
		(layer "In2.Cu")
		(net "M_D_DQ<44>")
	)
	(segment
		(start 282.614116 -128.77038)
		(end 282.769056 -128.92532)
		(width 0.14224)
		(layer "In2.Cu")
		(net "M_D_DQ<44>")
	)
	(segment
		(start 283.277056 -128.45034)
		(end 283.431996 -128.2954)
		(width 0.14224)
		(layer "In2.Cu")
		(net "M_D_DQ<44>")
	)
	(segment
		(start 275.545804 -99.690682)
		(end 275.545296 -99.69119)
		(width 0.0889)
		(layer "In2.Cu")
		(net "M_D_DQ<44>")
	)
	(segment
		(start 276.916134 -97.509584)
		(end 276.916134 -97.847658)
		(width 0.0889)
		(layer "In2.Cu")
		(net "M_D_DQ<44>")
	)
	(arc
		(start 276.850856 -97.912936)
		(mid 276.388887 -98.233478)
		(end 276.404324 -98.795586)
		(width 0.0889)
		(layer "In2.Cu")
		(net "M_D_DQ<44>")
	)
	(arc
		(start 276.032722 -99.395788)
		(mid 275.751422 -99.480754)
		(end 275.545804 -99.690682)
		(width 0.0889)
		(layer "In2.Cu")
		(net "M_D_DQ<44>")
	)
	(arc
		(start 276.404324 -98.795586)
		(mid 276.407072 -99.191053)
		(end 276.06879 -99.395788)
		(width 0.0889)
		(layer "In2.Cu")
		(net "M_D_DQ<44>")
	)
	(segment
		(start 296.69994 -133.076442)
		(end 296.69994 -134.340346)
		(width 0.1651)
		(layer "F.Cu")
		(net "M_D_DQ<43>")
	)
	(segment
		(start 296.700448 -133.0706)
		(end 296.69994 -133.076442)
		(width 0.1651)
		(layer "F.Cu")
		(net "M_D_DQ<43>")
	)
	(segment
		(start 279.778714 -98.500184)
		(end 280.350214 -98.500184)
		(width 0.1651)
		(layer "F.Cu")
		(net "M_D_DQ<43>")
	)
	(via
		(at 297.549824 -130.330956)
		(size 0.508)
		(drill 0.254)
		(layers "F.Cu" "B.Cu")
		(net "M_D_DQ<43>")
	)
	(via
		(at 296.69994 -134.340346)
		(size 0.508)
		(drill 0.254)
		(layers "F.Cu" "B.Cu")
		(net "M_D_DQ<43>")
	)
	(via
		(at 280.350214 -98.500184)
		(size 0.508)
		(drill 0.254)
		(layers "F.Cu" "B.Cu")
		(net "M_D_DQ<43>")
	)
	(segment
		(start 297.549824 -128.276096)
		(end 297.549824 -130.330956)
		(width 0.1651)
		(layer "B.Cu")
		(net "M_D_DQ<43>")
	)
	(segment
		(start 297.550332 -128.276096)
		(end 297.549824 -128.276096)
		(width 0.1651)
		(layer "B.Cu")
		(net "M_D_DQ<43>")
	)
	(segment
		(start 281.777186 -116.422932)
		(end 281.777186 -116.64188)
		(width 0.14224)
		(layer "In2.Cu")
		(net "M_D_DQ<43>")
	)
	(segment
		(start 283.978096 -119.03964)
		(end 283.978096 -119.258588)
		(width 0.14224)
		(layer "In2.Cu")
		(net "M_D_DQ<43>")
	)
	(segment
		(start 280.350214 -98.500184)
		(end 280.84526 -99.166172)
		(width 0.0889)
		(layer "In2.Cu")
		(net "M_D_DQ<43>")
	)
	(segment
		(start 280.19883 -114.60099)
		(end 280.417778 -114.60099)
		(width 0.14224)
		(layer "In2.Cu")
		(net "M_D_DQ<43>")
	)
	(segment
		(start 283.501846 -118.366286)
		(end 283.72054 -118.366286)
		(width 0.14224)
		(layer "In2.Cu")
		(net "M_D_DQ<43>")
	)
	(segment
		(start 284.552898 -119.614442)
		(end 284.65145 -119.51589)
		(width 0.14224)
		(layer "In2.Cu")
		(net "M_D_DQ<43>")
	)
	(segment
		(start 282.570936 -117.216682)
		(end 282.92679 -117.572536)
		(width 0.14224)
		(layer "In2.Cu")
		(net "M_D_DQ<43>")
	)
	(segment
		(start 283.72054 -118.366286)
		(end 284.076394 -118.72214)
		(width 0.14224)
		(layer "In2.Cu")
		(net "M_D_DQ<43>")
	)
	(segment
		(start 280.417778 -114.60099)
		(end 280.667714 -114.850926)
		(width 0.14224)
		(layer "In2.Cu")
		(net "M_D_DQ<43>")
	)
	(segment
		(start 297.7896 -124.886212)
		(end 297.7896 -127.508)
		(width 0.14224)
		(layer "In2.Cu")
		(net "M_D_DQ<43>")
	)
	(segment
		(start 297.143678 -131.233418)
		(end 297.143678 -131.9022)
		(width 0.14224)
		(layer "In2.Cu")
		(net "M_D_DQ<43>")
	)
	(segment
		(start 280.338022 -115.618514)
		(end 280.885138 -116.16563)
		(width 0.14224)
		(layer "In2.Cu")
		(net "M_D_DQ<43>")
	)
	(segment
		(start 282.92679 -117.791484)
		(end 282.828492 -117.890036)
		(width 0.14224)
		(layer "In2.Cu")
		(net "M_D_DQ<43>")
	)
	(segment
		(start 295.285922 -121.245376)
		(end 297.8404 -123.799854)
		(width 0.14224)
		(layer "In2.Cu")
		(net "M_D_DQ<43>")
	)
	(segment
		(start 282.828492 -118.108984)
		(end 283.184346 -118.464838)
		(width 0.14224)
		(layer "In2.Cu")
		(net "M_D_DQ<43>")
	)
	(segment
		(start 282.034742 -117.315234)
		(end 282.25369 -117.315234)
		(width 0.14224)
		(layer "In2.Cu")
		(net "M_D_DQ<43>")
	)
	(segment
		(start 285.225998 -120.090692)
		(end 285.1277 -120.189244)
		(width 0.14224)
		(layer "In2.Cu")
		(net "M_D_DQ<43>")
	)
	(segment
		(start 297.9166 -129.96418)
		(end 297.549824 -130.330956)
		(width 0.14224)
		(layer "In2.Cu")
		(net "M_D_DQ<43>")
	)
	(segment
		(start 281.421332 -116.067078)
		(end 281.777186 -116.422932)
		(width 0.14224)
		(layer "In2.Cu")
		(net "M_D_DQ<43>")
	)
	(segment
		(start 297.549824 -130.330956)
		(end 297.527472 -130.330956)
		(width 0.14224)
		(layer "In2.Cu")
		(net "M_D_DQ<43>")
	)
	(segment
		(start 296.86123 -132.457952)
		(end 297.118278 -132.715)
		(width 0.14224)
		(layer "In2.Cu")
		(net "M_D_DQ<43>")
	)
	(segment
		(start 284.870144 -119.51589)
		(end 285.225998 -119.871744)
		(width 0.14224)
		(layer "In2.Cu")
		(net "M_D_DQ<43>")
	)
	(segment
		(start 283.184346 -118.464838)
		(end 283.403294 -118.464838)
		(width 0.14224)
		(layer "In2.Cu")
		(net "M_D_DQ<43>")
	)
	(segment
		(start 297.8404 -124.835412)
		(end 297.7896 -124.886212)
		(width 0.14224)
		(layer "In2.Cu")
		(net "M_D_DQ<43>")
	)
	(segment
		(start 284.076394 -118.72214)
		(end 284.076394 -118.941088)
		(width 0.14224)
		(layer "In2.Cu")
		(net "M_D_DQ<43>")
	)
	(segment
		(start 297.150028 -133.83895)
		(end 297.150028 -134.162546)
		(width 0.14224)
		(layer "In2.Cu")
		(net "M_D_DQ<43>")
	)
	(segment
		(start 285.225998 -119.871744)
		(end 285.225998 -120.090692)
		(width 0.14224)
		(layer "In2.Cu")
		(net "M_D_DQ<43>")
	)
	(segment
		(start 297.143678 -131.9022)
		(end 296.86123 -132.184648)
		(width 0.14224)
		(layer "In2.Cu")
		(net "M_D_DQ<43>")
	)
	(segment
		(start 281.678888 -116.95938)
		(end 282.034742 -117.315234)
		(width 0.14224)
		(layer "In2.Cu")
		(net "M_D_DQ<43>")
	)
	(segment
		(start 279.65019 -114.930682)
		(end 279.869138 -114.930682)
		(width 0.14224)
		(layer "In2.Cu")
		(net "M_D_DQ<43>")
	)
	(segment
		(start 296.86123 -132.184648)
		(end 296.86123 -132.457952)
		(width 0.14224)
		(layer "In2.Cu")
		(net "M_D_DQ<43>")
	)
	(segment
		(start 284.076394 -118.941088)
		(end 283.978096 -119.03964)
		(width 0.14224)
		(layer "In2.Cu")
		(net "M_D_DQ<43>")
	)
	(segment
		(start 285.1277 -120.189244)
		(end 285.1277 -120.408192)
		(width 0.14224)
		(layer "In2.Cu")
		(net "M_D_DQ<43>")
	)
	(segment
		(start 297.118278 -133.0198)
		(end 296.86123 -133.276848)
		(width 0.14224)
		(layer "In2.Cu")
		(net "M_D_DQ<43>")
	)
	(segment
		(start 280.667714 -115.069874)
		(end 280.338022 -115.399566)
		(width 0.14224)
		(layer "In2.Cu")
		(net "M_D_DQ<43>")
	)
	(segment
		(start 280.84526 -99.166172)
		(end 280.86177 -99.195382)
		(width 0.0889)
		(layer "In2.Cu")
		(net "M_D_DQ<43>")
	)
	(segment
		(start 282.25369 -117.315234)
		(end 282.352242 -117.216682)
		(width 0.14224)
		(layer "In2.Cu")
		(net "M_D_DQ<43>")
	)
	(segment
		(start 279.223216 -104.817926)
		(end 279.223216 -105.707434)
		(width 0.0889)
		(layer "In2.Cu")
		(net "M_D_DQ<43>")
	)
	(segment
		(start 281.104086 -116.16563)
		(end 281.202638 -116.067078)
		(width 0.14224)
		(layer "In2.Cu")
		(net "M_D_DQ<43>")
	)
	(segment
		(start 280.002996 -102.907084)
		(end 280.002996 -104.038146)
		(width 0.0889)
		(layer "In2.Cu")
		(net "M_D_DQ<43>")
	)
	(segment
		(start 280.862532 -99.195382)
		(end 280.869644 -99.208336)
		(width 0.0889)
		(layer "In2.Cu")
		(net "M_D_DQ<43>")
	)
	(segment
		(start 284.33395 -119.614442)
		(end 284.552898 -119.614442)
		(width 0.14224)
		(layer "In2.Cu")
		(net "M_D_DQ<43>")
	)
	(segment
		(start 281.777186 -116.64188)
		(end 281.678888 -116.740432)
		(width 0.14224)
		(layer "In2.Cu")
		(net "M_D_DQ<43>")
	)
	(segment
		(start 280.857198 -100.16617)
		(end 280.857198 -102.052882)
		(width 0.0889)
		(layer "In2.Cu")
		(net "M_D_DQ<43>")
	)
	(segment
		(start 281.678888 -116.740432)
		(end 281.678888 -116.95938)
		(width 0.14224)
		(layer "In2.Cu")
		(net "M_D_DQ<43>")
	)
	(segment
		(start 282.828492 -117.890036)
		(end 282.828492 -118.108984)
		(width 0.14224)
		(layer "In2.Cu")
		(net "M_D_DQ<43>")
	)
	(segment
		(start 280.338022 -115.399566)
		(end 280.338022 -115.618514)
		(width 0.14224)
		(layer "In2.Cu")
		(net "M_D_DQ<43>")
	)
	(segment
		(start 282.352242 -117.216682)
		(end 282.570936 -117.216682)
		(width 0.14224)
		(layer "In2.Cu")
		(net "M_D_DQ<43>")
	)
	(segment
		(start 297.7896 -127.508)
		(end 297.9166 -127.635)
		(width 0.14224)
		(layer "In2.Cu")
		(net "M_D_DQ<43>")
	)
	(segment
		(start 280.940256 -99.505516)
		(end 280.940256 -100.083112)
		(width 0.0889)
		(layer "In2.Cu")
		(net "M_D_DQ<43>")
	)
	(segment
		(start 279.869138 -114.930682)
		(end 280.19883 -114.60099)
		(width 0.14224)
		(layer "In2.Cu")
		(net "M_D_DQ<43>")
	)
	(segment
		(start 280.667714 -114.850926)
		(end 280.667714 -115.069874)
		(width 0.14224)
		(layer "In2.Cu")
		(net "M_D_DQ<43>")
	)
	(segment
		(start 297.527472 -130.330956)
		(end 297.099228 -130.7592)
		(width 0.14224)
		(layer "In2.Cu")
		(net "M_D_DQ<43>")
	)
	(segment
		(start 283.978096 -119.258588)
		(end 284.33395 -119.614442)
		(width 0.14224)
		(layer "In2.Cu")
		(net "M_D_DQ<43>")
	)
	(segment
		(start 280.857198 -102.052882)
		(end 280.002996 -102.907084)
		(width 0.0889)
		(layer "In2.Cu")
		(net "M_D_DQ<43>")
	)
	(segment
		(start 297.150028 -134.162546)
		(end 296.972228 -134.340346)
		(width 0.14224)
		(layer "In2.Cu")
		(net "M_D_DQ<43>")
	)
	(segment
		(start 282.92679 -117.572536)
		(end 282.92679 -117.791484)
		(width 0.14224)
		(layer "In2.Cu")
		(net "M_D_DQ<43>")
	)
	(segment
		(start 297.118278 -132.715)
		(end 297.118278 -133.0198)
		(width 0.14224)
		(layer "In2.Cu")
		(net "M_D_DQ<43>")
	)
	(segment
		(start 279.469596 -114.750088)
		(end 279.65019 -114.930682)
		(width 0.14224)
		(layer "In2.Cu")
		(net "M_D_DQ<43>")
	)
	(segment
		(start 281.202638 -116.067078)
		(end 281.421332 -116.067078)
		(width 0.14224)
		(layer "In2.Cu")
		(net "M_D_DQ<43>")
	)
	(segment
		(start 297.9166 -127.635)
		(end 297.9166 -129.96418)
		(width 0.14224)
		(layer "In2.Cu")
		(net "M_D_DQ<43>")
	)
	(segment
		(start 296.972228 -134.340346)
		(end 296.69994 -134.340346)
		(width 0.14224)
		(layer "In2.Cu")
		(net "M_D_DQ<43>")
	)
	(segment
		(start 279.469596 -105.953814)
		(end 279.469596 -114.750088)
		(width 0.14224)
		(layer "In2.Cu")
		(net "M_D_DQ<43>")
	)
	(segment
		(start 285.964884 -121.245376)
		(end 295.285922 -121.245376)
		(width 0.14224)
		(layer "In2.Cu")
		(net "M_D_DQ<43>")
	)
	(segment
		(start 280.86177 -99.195382)
		(end 280.862532 -99.195382)
		(width 0.0889)
		(layer "In2.Cu")
		(net "M_D_DQ<43>")
	)
	(segment
		(start 297.8404 -123.799854)
		(end 297.8404 -124.835412)
		(width 0.14224)
		(layer "In2.Cu")
		(net "M_D_DQ<43>")
	)
	(segment
		(start 284.65145 -119.51589)
		(end 284.870144 -119.51589)
		(width 0.14224)
		(layer "In2.Cu")
		(net "M_D_DQ<43>")
	)
	(segment
		(start 280.885138 -116.16563)
		(end 281.104086 -116.16563)
		(width 0.14224)
		(layer "In2.Cu")
		(net "M_D_DQ<43>")
	)
	(segment
		(start 280.941272 -99.5045)
		(end 280.940256 -99.505516)
		(width 0.0889)
		(layer "In2.Cu")
		(net "M_D_DQ<43>")
	)
	(segment
		(start 297.099228 -130.7592)
		(end 297.099228 -131.188968)
		(width 0.14224)
		(layer "In2.Cu")
		(net "M_D_DQ<43>")
	)
	(segment
		(start 280.940256 -100.083112)
		(end 280.857198 -100.16617)
		(width 0.0889)
		(layer "In2.Cu")
		(net "M_D_DQ<43>")
	)
	(segment
		(start 297.099228 -131.188968)
		(end 297.143678 -131.233418)
		(width 0.14224)
		(layer "In2.Cu")
		(net "M_D_DQ<43>")
	)
	(segment
		(start 280.002996 -104.038146)
		(end 279.223216 -104.817926)
		(width 0.0889)
		(layer "In2.Cu")
		(net "M_D_DQ<43>")
	)
	(segment
		(start 279.223216 -105.707434)
		(end 279.469596 -105.953814)
		(width 0.0889)
		(layer "In2.Cu")
		(net "M_D_DQ<43>")
	)
	(segment
		(start 296.86123 -133.276848)
		(end 296.86123 -133.550152)
		(width 0.14224)
		(layer "In2.Cu")
		(net "M_D_DQ<43>")
	)
	(segment
		(start 283.403294 -118.464838)
		(end 283.501846 -118.366286)
		(width 0.14224)
		(layer "In2.Cu")
		(net "M_D_DQ<43>")
	)
	(segment
		(start 296.86123 -133.550152)
		(end 297.150028 -133.83895)
		(width 0.14224)
		(layer "In2.Cu")
		(net "M_D_DQ<43>")
	)
	(segment
		(start 285.1277 -120.408192)
		(end 285.964884 -121.245376)
		(width 0.14224)
		(layer "In2.Cu")
		(net "M_D_DQ<43>")
	)
	(arc
		(start 280.869644 -99.208336)
		(mid 280.924885 -99.351722)
		(end 280.941272 -99.5045)
		(width 0.0889)
		(layer "In2.Cu")
		(net "M_D_DQ<43>")
	)
	(segment
		(start 297.549824 -136.192768)
		(end 297.549824 -135.9154)
		(width 0.1651)
		(layer "F.Cu")
		(net "M_D_DQ<42>")
	)
	(segment
		(start 297.681396 -136.32434)
		(end 297.549824 -136.192768)
		(width 0.1651)
		(layer "F.Cu")
		(net "M_D_DQ<42>")
	)
	(segment
		(start 297.550332 -137.67054)
		(end 297.549824 -137.67054)
		(width 0.1651)
		(layer "F.Cu")
		(net "M_D_DQ<42>")
	)
	(segment
		(start 297.549824 -136.679432)
		(end 297.681396 -136.54786)
		(width 0.1651)
		(layer "F.Cu")
		(net "M_D_DQ<42>")
	)
	(segment
		(start 297.549824 -137.67054)
		(end 297.549824 -136.679432)
		(width 0.1651)
		(layer "F.Cu")
		(net "M_D_DQ<42>")
	)
	(segment
		(start 297.681396 -136.54786)
		(end 297.681396 -136.32434)
		(width 0.1651)
		(layer "F.Cu")
		(net "M_D_DQ<42>")
	)
	(segment
		(start 279.778714 -97.509584)
		(end 280.350214 -97.509584)
		(width 0.1651)
		(layer "F.Cu")
		(net "M_D_DQ<42>")
	)
	(via
		(at 297.549824 -135.9154)
		(size 0.508)
		(drill 0.254)
		(layers "F.Cu" "B.Cu")
		(net "M_D_DQ<42>")
	)
	(via
		(at 280.350214 -97.509584)
		(size 0.508)
		(drill 0.254)
		(layers "F.Cu" "B.Cu")
		(net "M_D_DQ<42>")
	)
	(via
		(at 296.69994 -131.611878)
		(size 0.508)
		(drill 0.254)
		(layers "F.Cu" "B.Cu")
		(net "M_D_DQ<42>")
	)
	(segment
		(start 296.700448 -132.876036)
		(end 296.69994 -132.875782)
		(width 0.1651)
		(layer "B.Cu")
		(net "M_D_DQ<42>")
	)
	(segment
		(start 296.69994 -132.875782)
		(end 296.69994 -131.611878)
		(width 0.1651)
		(layer "B.Cu")
		(net "M_D_DQ<42>")
	)
	(segment
		(start 297.218608 -126.87681)
		(end 297.015408 -127.08001)
		(width 0.14224)
		(layer "In2.Cu")
		(net "M_D_DQ<42>")
	)
	(segment
		(start 280.667206 -101.974142)
		(end 279.813004 -102.828344)
		(width 0.0889)
		(layer "In2.Cu")
		(net "M_D_DQ<42>")
	)
	(segment
		(start 279.033224 -105.73639)
		(end 278.8158 -105.953814)
		(width 0.0889)
		(layer "In2.Cu")
		(net "M_D_DQ<42>")
	)
	(segment
		(start 297.015408 -127.89281)
		(end 297.218608 -128.09601)
		(width 0.14224)
		(layer "In2.Cu")
		(net "M_D_DQ<42>")
	)
	(segment
		(start 297.218608 -129.805938)
		(end 296.545 -130.479546)
		(width 0.14224)
		(layer "In2.Cu")
		(net "M_D_DQ<42>")
	)
	(segment
		(start 296.9768 -125.7554)
		(end 296.9768 -126.1618)
		(width 0.14224)
		(layer "In2.Cu")
		(net "M_D_DQ<42>")
	)
	(segment
		(start 280.750264 -100.004372)
		(end 280.667206 -100.08743)
		(width 0.0889)
		(layer "In2.Cu")
		(net "M_D_DQ<42>")
	)
	(segment
		(start 279.813004 -103.959406)
		(end 279.033224 -104.739186)
		(width 0.0889)
		(layer "In2.Cu")
		(net "M_D_DQ<42>")
	)
	(segment
		(start 296.7482 -127.68961)
		(end 296.9514 -127.89281)
		(width 0.14224)
		(layer "In2.Cu")
		(net "M_D_DQ<42>")
	)
	(segment
		(start 279.813004 -102.828344)
		(end 279.813004 -103.959406)
		(width 0.0889)
		(layer "In2.Cu")
		(net "M_D_DQ<42>")
	)
	(segment
		(start 296.545 -130.479546)
		(end 296.545 -131.456938)
		(width 0.14224)
		(layer "In2.Cu")
		(net "M_D_DQ<42>")
	)
	(segment
		(start 296.9514 -127.89281)
		(end 297.015408 -127.89281)
		(width 0.14224)
		(layer "In2.Cu")
		(net "M_D_DQ<42>")
	)
	(segment
		(start 280.350214 -99.090734)
		(end 280.36139 -99.090734)
		(width 0.0889)
		(layer "In2.Cu")
		(net "M_D_DQ<42>")
	)
	(segment
		(start 296.26687 -134.632446)
		(end 297.549824 -135.9154)
		(width 0.14224)
		(layer "In2.Cu")
		(net "M_D_DQ<42>")
	)
	(segment
		(start 294.981122 -121.880376)
		(end 296.8498 -123.749054)
		(width 0.14224)
		(layer "In2.Cu")
		(net "M_D_DQ<42>")
	)
	(segment
		(start 296.8498 -123.749054)
		(end 296.8498 -125.6284)
		(width 0.14224)
		(layer "In2.Cu")
		(net "M_D_DQ<42>")
	)
	(segment
		(start 280.003504 -98.700336)
		(end 280.168096 -98.985578)
		(width 0.0889)
		(layer "In2.Cu")
		(net "M_D_DQ<42>")
	)
	(segment
		(start 296.9768 -126.1618)
		(end 297.218608 -126.403608)
		(width 0.14224)
		(layer "In2.Cu")
		(net "M_D_DQ<42>")
	)
	(segment
		(start 296.545 -131.456938)
		(end 296.69994 -131.611878)
		(width 0.14224)
		(layer "In2.Cu")
		(net "M_D_DQ<42>")
	)
	(segment
		(start 297.218608 -128.09601)
		(end 297.218608 -129.805938)
		(width 0.14224)
		(layer "In2.Cu")
		(net "M_D_DQ<42>")
	)
	(segment
		(start 296.7482 -127.28321)
		(end 296.7482 -127.68961)
		(width 0.14224)
		(layer "In2.Cu")
		(net "M_D_DQ<42>")
	)
	(segment
		(start 278.8158 -105.953814)
		(end 278.8158 -114.782346)
		(width 0.14224)
		(layer "In2.Cu")
		(net "M_D_DQ<42>")
	)
	(segment
		(start 279.033224 -104.739186)
		(end 279.033224 -105.73639)
		(width 0.0889)
		(layer "In2.Cu")
		(net "M_D_DQ<42>")
	)
	(segment
		(start 296.69994 -131.611878)
		(end 296.26687 -132.044948)
		(width 0.14224)
		(layer "In2.Cu")
		(net "M_D_DQ<42>")
	)
	(segment
		(start 296.9514 -127.08001)
		(end 296.7482 -127.28321)
		(width 0.14224)
		(layer "In2.Cu")
		(net "M_D_DQ<42>")
	)
	(segment
		(start 297.218608 -126.403608)
		(end 297.218608 -126.87681)
		(width 0.14224)
		(layer "In2.Cu")
		(net "M_D_DQ<42>")
	)
	(segment
		(start 280.350214 -97.509584)
		(end 280.020776 -98.270568)
		(width 0.0889)
		(layer "In2.Cu")
		(net "M_D_DQ<42>")
	)
	(segment
		(start 280.667206 -100.08743)
		(end 280.667206 -101.974142)
		(width 0.0889)
		(layer "In2.Cu")
		(net "M_D_DQ<42>")
	)
	(segment
		(start 296.8498 -125.6284)
		(end 296.9768 -125.7554)
		(width 0.14224)
		(layer "In2.Cu")
		(net "M_D_DQ<42>")
	)
	(segment
		(start 297.015408 -127.08001)
		(end 296.9514 -127.08001)
		(width 0.14224)
		(layer "In2.Cu")
		(net "M_D_DQ<42>")
	)
	(segment
		(start 296.26687 -132.044948)
		(end 296.26687 -134.632446)
		(width 0.14224)
		(layer "In2.Cu")
		(net "M_D_DQ<42>")
	)
	(segment
		(start 280.020776 -98.270568)
		(end 279.998678 -98.308922)
		(width 0.0889)
		(layer "In2.Cu")
		(net "M_D_DQ<42>")
	)
	(segment
		(start 278.8158 -114.782346)
		(end 285.91383 -121.880376)
		(width 0.14224)
		(layer "In2.Cu")
		(net "M_D_DQ<42>")
	)
	(segment
		(start 280.750264 -99.50196)
		(end 280.750264 -100.004372)
		(width 0.0889)
		(layer "In2.Cu")
		(net "M_D_DQ<42>")
	)
	(segment
		(start 285.91383 -121.880376)
		(end 294.981122 -121.880376)
		(width 0.14224)
		(layer "In2.Cu")
		(net "M_D_DQ<42>")
	)
	(arc
		(start 279.998678 -98.308922)
		(mid 279.949923 -98.505274)
		(end 280.003504 -98.700336)
		(width 0.0889)
		(layer "In2.Cu")
		(net "M_D_DQ<42>")
	)
	(arc
		(start 280.36139 -99.090734)
		(mid 280.640995 -99.215809)
		(end 280.750264 -99.50196)
		(width 0.0889)
		(layer "In2.Cu")
		(net "M_D_DQ<42>")
	)
	(arc
		(start 280.168096 -98.985578)
		(mid 280.245069 -99.062547)
		(end 280.350214 -99.090734)
		(width 0.0889)
		(layer "In2.Cu")
		(net "M_D_DQ<42>")
	)
	(segment
		(start 277.203154 -98.995738)
		(end 277.774654 -98.995738)
		(width 0.1651)
		(layer "F.Cu")
		(net "M_D_DQ<41>")
	)
	(segment
		(start 290.750498 -133.0706)
		(end 290.74999 -133.076442)
		(width 0.1651)
		(layer "F.Cu")
		(net "M_D_DQ<41>")
	)
	(segment
		(start 290.74999 -133.076442)
		(end 290.74999 -134.340346)
		(width 0.1651)
		(layer "F.Cu")
		(net "M_D_DQ<41>")
	)
	(via
		(at 290.74999 -134.340346)
		(size 0.508)
		(drill 0.254)
		(layers "F.Cu" "B.Cu")
		(net "M_D_DQ<41>")
	)
	(via
		(at 277.774654 -98.995738)
		(size 0.508)
		(drill 0.254)
		(layers "F.Cu" "B.Cu")
		(net "M_D_DQ<41>")
	)
	(via
		(at 291.422074 -130.330956)
		(size 0.508)
		(drill 0.254)
		(layers "F.Cu" "B.Cu")
		(net "M_D_DQ<41>")
	)
	(segment
		(start 291.422074 -129.827782)
		(end 291.599874 -129.649982)
		(width 0.1651)
		(layer "B.Cu")
		(net "M_D_DQ<41>")
	)
	(segment
		(start 291.599874 -128.276096)
		(end 291.600382 -128.276096)
		(width 0.1651)
		(layer "B.Cu")
		(net "M_D_DQ<41>")
	)
	(segment
		(start 291.422074 -130.330956)
		(end 291.422074 -129.827782)
		(width 0.1651)
		(layer "B.Cu")
		(net "M_D_DQ<41>")
	)
	(segment
		(start 291.599874 -129.649982)
		(end 291.599874 -128.276096)
		(width 0.1651)
		(layer "B.Cu")
		(net "M_D_DQ<41>")
	)
	(segment
		(start 275.722842 -103.071168)
		(end 273.745452 -105.048558)
		(width 0.0889)
		(layer "In2.Cu")
		(net "M_D_DQ<41>")
	)
	(segment
		(start 290.971478 -130.7592)
		(end 290.971478 -131.188968)
		(width 0.14224)
		(layer "In2.Cu")
		(net "M_D_DQ<41>")
	)
	(segment
		(start 290.971478 -131.188968)
		(end 291.201856 -131.419346)
		(width 0.14224)
		(layer "In2.Cu")
		(net "M_D_DQ<41>")
	)
	(segment
		(start 283.60497 -125.239018)
		(end 283.60497 -125.526546)
		(width 0.14224)
		(layer "In2.Cu")
		(net "M_D_DQ<41>")
	)
	(segment
		(start 288.064702 -128.197356)
		(end 292.128956 -128.197356)
		(width 0.14224)
		(layer "In2.Cu")
		(net "M_D_DQ<41>")
	)
	(segment
		(start 292.128956 -128.197356)
		(end 292.27272 -128.34112)
		(width 0.14224)
		(layer "In2.Cu")
		(net "M_D_DQ<41>")
	)
	(segment
		(start 283.030168 -124.951744)
		(end 283.317696 -124.951744)
		(width 0.14224)
		(layer "In2.Cu")
		(net "M_D_DQ<41>")
	)
	(segment
		(start 282.601924 -125.379988)
		(end 283.030168 -124.951744)
		(width 0.14224)
		(layer "In2.Cu")
		(net "M_D_DQ<41>")
	)
	(segment
		(start 292.27272 -128.34112)
		(end 292.27272 -128.73228)
		(width 0.14224)
		(layer "In2.Cu")
		(net "M_D_DQ<41>")
	)
	(segment
		(start 282.027122 -125.092714)
		(end 282.314396 -125.379988)
		(width 0.14224)
		(layer "In2.Cu")
		(net "M_D_DQ<41>")
	)
	(segment
		(start 290.91128 -132.114544)
		(end 290.91128 -132.475224)
		(width 0.14224)
		(layer "In2.Cu")
		(net "M_D_DQ<41>")
	)
	(segment
		(start 280.860754 -123.959874)
		(end 281.148028 -124.247148)
		(width 0.14224)
		(layer "In2.Cu")
		(net "M_D_DQ<41>")
	)
	(segment
		(start 290.99891 -134.340346)
		(end 290.74999 -134.340346)
		(width 0.14224)
		(layer "In2.Cu")
		(net "M_D_DQ<41>")
	)
	(segment
		(start 281.192986 -123.340114)
		(end 280.860754 -123.672346)
		(width 0.14224)
		(layer "In2.Cu")
		(net "M_D_DQ<41>")
	)
	(segment
		(start 273.978624 -115.838224)
		(end 281.192986 -123.052586)
		(width 0.14224)
		(layer "In2.Cu")
		(net "M_D_DQ<41>")
	)
	(segment
		(start 292.27272 -128.73228)
		(end 292.1254 -128.8796)
		(width 0.14224)
		(layer "In2.Cu")
		(net "M_D_DQ<41>")
	)
	(segment
		(start 281.847036 -123.835668)
		(end 282.134564 -123.835668)
		(width 0.14224)
		(layer "In2.Cu")
		(net "M_D_DQ<41>")
	)
	(segment
		(start 275.952204 -101.261164)
		(end 275.722842 -101.658166)
		(width 0.0889)
		(layer "In2.Cu")
		(net "M_D_DQ<41>")
	)
	(segment
		(start 291.201856 -131.419346)
		(end 291.201856 -131.823968)
		(width 0.14224)
		(layer "In2.Cu")
		(net "M_D_DQ<41>")
	)
	(segment
		(start 283.60497 -125.526546)
		(end 283.182314 -125.949202)
		(width 0.14224)
		(layer "In2.Cu")
		(net "M_D_DQ<41>")
	)
	(segment
		(start 281.148028 -124.247148)
		(end 281.435556 -124.247148)
		(width 0.14224)
		(layer "In2.Cu")
		(net "M_D_DQ<41>")
	)
	(segment
		(start 280.860754 -123.672346)
		(end 280.860754 -123.959874)
		(width 0.14224)
		(layer "In2.Cu")
		(net "M_D_DQ<41>")
	)
	(segment
		(start 273.745452 -105.048558)
		(end 273.745452 -105.757726)
		(width 0.0889)
		(layer "In2.Cu")
		(net "M_D_DQ<41>")
	)
	(segment
		(start 277.444708 -99.75723)
		(end 277.427944 -99.785932)
		(width 0.0889)
		(layer "In2.Cu")
		(net "M_D_DQ<41>")
	)
	(segment
		(start 290.91128 -132.475224)
		(end 291.125656 -132.6896)
		(width 0.14224)
		(layer "In2.Cu")
		(net "M_D_DQ<41>")
	)
	(segment
		(start 282.027122 -124.805186)
		(end 282.027122 -125.092714)
		(width 0.14224)
		(layer "In2.Cu")
		(net "M_D_DQ<41>")
	)
	(segment
		(start 291.2872 -129.548128)
		(end 291.592 -129.548128)
		(width 0.14224)
		(layer "In2.Cu")
		(net "M_D_DQ<41>")
	)
	(segment
		(start 273.745452 -105.757726)
		(end 273.978624 -105.990898)
		(width 0.0889)
		(layer "In2.Cu")
		(net "M_D_DQ<41>")
	)
	(segment
		(start 283.182314 -126.242318)
		(end 283.457396 -126.5174)
		(width 0.14224)
		(layer "In2.Cu")
		(net "M_D_DQ<41>")
	)
	(segment
		(start 282.421838 -124.41047)
		(end 282.027122 -124.805186)
		(width 0.14224)
		(layer "In2.Cu")
		(net "M_D_DQ<41>")
	)
	(segment
		(start 291.1094 -129.0828)
		(end 291.1094 -129.370328)
		(width 0.14224)
		(layer "In2.Cu")
		(net "M_D_DQ<41>")
	)
	(segment
		(start 283.317696 -124.951744)
		(end 283.60497 -125.239018)
		(width 0.14224)
		(layer "In2.Cu")
		(net "M_D_DQ<41>")
	)
	(segment
		(start 282.314396 -125.379988)
		(end 282.601924 -125.379988)
		(width 0.14224)
		(layer "In2.Cu")
		(net "M_D_DQ<41>")
	)
	(segment
		(start 275.722842 -101.658166)
		(end 275.722842 -103.071168)
		(width 0.0889)
		(layer "In2.Cu")
		(net "M_D_DQ<41>")
	)
	(segment
		(start 276.32025 -100.62464)
		(end 275.952204 -101.261164)
		(width 0.0889)
		(layer "In2.Cu")
		(net "M_D_DQ<41>")
	)
	(segment
		(start 276.933914 -100.081334)
		(end 276.901148 -100.081334)
		(width 0.0889)
		(layer "In2.Cu")
		(net "M_D_DQ<41>")
	)
	(segment
		(start 292.1254 -128.8796)
		(end 291.3126 -128.8796)
		(width 0.14224)
		(layer "In2.Cu")
		(net "M_D_DQ<41>")
	)
	(segment
		(start 291.125656 -133.1214)
		(end 290.91128 -133.335776)
		(width 0.14224)
		(layer "In2.Cu")
		(net "M_D_DQ<41>")
	)
	(segment
		(start 291.422074 -130.330956)
		(end 291.399722 -130.330956)
		(width 0.14224)
		(layer "In2.Cu")
		(net "M_D_DQ<41>")
	)
	(segment
		(start 273.978624 -105.990898)
		(end 273.978624 -115.838224)
		(width 0.14224)
		(layer "In2.Cu")
		(net "M_D_DQ<41>")
	)
	(segment
		(start 291.201856 -131.823968)
		(end 290.91128 -132.114544)
		(width 0.14224)
		(layer "In2.Cu")
		(net "M_D_DQ<41>")
	)
	(segment
		(start 283.457396 -126.5174)
		(end 286.384746 -126.5174)
		(width 0.14224)
		(layer "In2.Cu")
		(net "M_D_DQ<41>")
	)
	(segment
		(start 282.134564 -123.835668)
		(end 282.421838 -124.122942)
		(width 0.14224)
		(layer "In2.Cu")
		(net "M_D_DQ<41>")
	)
	(segment
		(start 283.182314 -125.949202)
		(end 283.182314 -126.242318)
		(width 0.14224)
		(layer "In2.Cu")
		(net "M_D_DQ<41>")
	)
	(segment
		(start 281.435556 -124.247148)
		(end 281.847036 -123.835668)
		(width 0.14224)
		(layer "In2.Cu")
		(net "M_D_DQ<41>")
	)
	(segment
		(start 290.91128 -133.643624)
		(end 291.151056 -133.8834)
		(width 0.14224)
		(layer "In2.Cu")
		(net "M_D_DQ<41>")
	)
	(segment
		(start 291.3126 -128.8796)
		(end 291.1094 -129.0828)
		(width 0.14224)
		(layer "In2.Cu")
		(net "M_D_DQ<41>")
	)
	(segment
		(start 290.91128 -133.335776)
		(end 290.91128 -133.643624)
		(width 0.14224)
		(layer "In2.Cu")
		(net "M_D_DQ<41>")
	)
	(segment
		(start 282.421838 -124.122942)
		(end 282.421838 -124.41047)
		(width 0.14224)
		(layer "In2.Cu")
		(net "M_D_DQ<41>")
	)
	(segment
		(start 291.592 -129.548128)
		(end 291.7952 -129.751328)
		(width 0.14224)
		(layer "In2.Cu")
		(net "M_D_DQ<41>")
	)
	(segment
		(start 281.192986 -123.052586)
		(end 281.192986 -123.340114)
		(width 0.14224)
		(layer "In2.Cu")
		(net "M_D_DQ<41>")
	)
	(segment
		(start 291.1094 -129.370328)
		(end 291.2872 -129.548128)
		(width 0.14224)
		(layer "In2.Cu")
		(net "M_D_DQ<41>")
	)
	(segment
		(start 277.774654 -98.995738)
		(end 277.444708 -99.75723)
		(width 0.0889)
		(layer "In2.Cu")
		(net "M_D_DQ<41>")
	)
	(segment
		(start 291.399722 -130.330956)
		(end 290.971478 -130.7592)
		(width 0.14224)
		(layer "In2.Cu")
		(net "M_D_DQ<41>")
	)
	(segment
		(start 291.7952 -129.751328)
		(end 291.7952 -130.038856)
		(width 0.14224)
		(layer "In2.Cu")
		(net "M_D_DQ<41>")
	)
	(segment
		(start 291.151056 -134.1882)
		(end 290.99891 -134.340346)
		(width 0.14224)
		(layer "In2.Cu")
		(net "M_D_DQ<41>")
	)
	(segment
		(start 286.384746 -126.5174)
		(end 288.064702 -128.197356)
		(width 0.14224)
		(layer "In2.Cu")
		(net "M_D_DQ<41>")
	)
	(segment
		(start 291.7952 -130.038856)
		(end 291.5031 -130.330956)
		(width 0.14224)
		(layer "In2.Cu")
		(net "M_D_DQ<41>")
	)
	(segment
		(start 291.151056 -133.8834)
		(end 291.151056 -134.1882)
		(width 0.14224)
		(layer "In2.Cu")
		(net "M_D_DQ<41>")
	)
	(segment
		(start 291.125656 -132.6896)
		(end 291.125656 -133.1214)
		(width 0.14224)
		(layer "In2.Cu")
		(net "M_D_DQ<41>")
	)
	(segment
		(start 291.5031 -130.330956)
		(end 291.422074 -130.330956)
		(width 0.14224)
		(layer "In2.Cu")
		(net "M_D_DQ<41>")
	)
	(arc
		(start 276.901148 -100.081334)
		(mid 276.750554 -100.116926)
		(end 276.624796 -100.207064)
		(width 0.0889)
		(layer "In2.Cu")
		(net "M_D_DQ<41>")
	)
	(arc
		(start 277.427944 -99.785932)
		(mid 277.219336 -99.997864)
		(end 276.933914 -100.081334)
		(width 0.0889)
		(layer "In2.Cu")
		(net "M_D_DQ<41>")
	)
	(arc
		(start 276.624796 -100.207064)
		(mid 276.459481 -100.406341)
		(end 276.32025 -100.62464)
		(width 0.0889)
		(layer "In2.Cu")
		(net "M_D_DQ<41>")
	)
	(segment
		(start 291.599874 -137.676382)
		(end 291.422074 -135.8138)
		(width 0.1651)
		(layer "F.Cu")
		(net "M_D_DQ<40>")
	)
	(segment
		(start 277.203154 -97.014538)
		(end 277.774654 -97.014538)
		(width 0.1651)
		(layer "F.Cu")
		(net "M_D_DQ<40>")
	)
	(segment
		(start 291.600382 -137.67054)
		(end 291.599874 -137.676382)
		(width 0.1651)
		(layer "F.Cu")
		(net "M_D_DQ<40>")
	)
	(via
		(at 291.422074 -135.8138)
		(size 0.508)
		(drill 0.254)
		(layers "F.Cu" "B.Cu")
		(net "M_D_DQ<40>")
	)
	(via
		(at 290.74999 -131.611878)
		(size 0.508)
		(drill 0.254)
		(layers "F.Cu" "B.Cu")
		(net "M_D_DQ<40>")
	)
	(via
		(at 277.774654 -97.014538)
		(size 0.508)
		(drill 0.254)
		(layers "F.Cu" "B.Cu")
		(net "M_D_DQ<40>")
	)
	(segment
		(start 290.750498 -132.876036)
		(end 290.74999 -132.875782)
		(width 0.1651)
		(layer "B.Cu")
		(net "M_D_DQ<40>")
	)
	(segment
		(start 290.74999 -132.875782)
		(end 290.74999 -131.611878)
		(width 0.1651)
		(layer "B.Cu")
		(net "M_D_DQ<40>")
	)
	(segment
		(start 277.57755 -121.232422)
		(end 277.57755 -121.51995)
		(width 0.14224)
		(layer "In2.Cu")
		(net "M_D_DQ<40>")
	)
	(segment
		(start 291.12591 -135.8138)
		(end 291.422074 -135.8138)
		(width 0.14224)
		(layer "In2.Cu")
		(net "M_D_DQ<40>")
	)
	(segment
		(start 275.53285 -102.992428)
		(end 273.55546 -104.969818)
		(width 0.0889)
		(layer "In2.Cu")
		(net "M_D_DQ<40>")
	)
	(segment
		(start 273.330924 -105.990898)
		(end 273.330924 -116.104924)
		(width 0.14224)
		(layer "In2.Cu")
		(net "M_D_DQ<40>")
	)
	(segment
		(start 273.55546 -105.766362)
		(end 273.330924 -105.990898)
		(width 0.0889)
		(layer "In2.Cu")
		(net "M_D_DQ<40>")
	)
	(segment
		(start 273.330924 -116.104924)
		(end 277.874222 -120.648222)
		(width 0.14224)
		(layer "In2.Cu")
		(net "M_D_DQ<40>")
	)
	(segment
		(start 278.736552 -121.510552)
		(end 279.023826 -121.797826)
		(width 0.14224)
		(layer "In2.Cu")
		(net "M_D_DQ<40>")
	)
	(segment
		(start 279.585928 -122.672856)
		(end 279.873456 -122.672856)
		(width 0.14224)
		(layer "In2.Cu")
		(net "M_D_DQ<40>")
	)
	(segment
		(start 279.023826 -121.797826)
		(end 279.023826 -122.085354)
		(width 0.14224)
		(layer "In2.Cu")
		(net "M_D_DQ<40>")
	)
	(segment
		(start 280.16073 -122.96013)
		(end 280.16073 -123.247658)
		(width 0.14224)
		(layer "In2.Cu")
		(net "M_D_DQ<40>")
	)
	(segment
		(start 276.285198 -100.303584)
		(end 276.281896 -100.308664)
		(width 0.0889)
		(layer "In2.Cu")
		(net "M_D_DQ<40>")
	)
	(segment
		(start 278.752554 -122.644154)
		(end 279.039828 -122.931428)
		(width 0.14224)
		(layer "In2.Cu")
		(net "M_D_DQ<40>")
	)
	(segment
		(start 277.279608 -97.680272)
		(end 277.262844 -97.709736)
		(width 0.0889)
		(layer "In2.Cu")
		(net "M_D_DQ<40>")
	)
	(segment
		(start 277.256494 -98.289618)
		(end 277.262844 -98.300286)
		(width 0.0889)
		(layer "In2.Cu")
		(net "M_D_DQ<40>")
	)
	(segment
		(start 283.2862 -127.1524)
		(end 286.054546 -127.1524)
		(width 0.14224)
		(layer "In2.Cu")
		(net "M_D_DQ<40>")
	)
	(segment
		(start 280.16073 -123.247658)
		(end 279.914858 -123.49353)
		(width 0.14224)
		(layer "In2.Cu")
		(net "M_D_DQ<40>")
	)
	(segment
		(start 290.576254 -131.611878)
		(end 290.74999 -131.611878)
		(width 0.14224)
		(layer "In2.Cu")
		(net "M_D_DQ<40>")
	)
	(segment
		(start 277.57755 -121.51995)
		(end 277.864824 -121.807224)
		(width 0.14224)
		(layer "In2.Cu")
		(net "M_D_DQ<40>")
	)
	(segment
		(start 287.556702 -128.654556)
		(end 289.842956 -128.654556)
		(width 0.14224)
		(layer "In2.Cu")
		(net "M_D_DQ<40>")
	)
	(segment
		(start 278.152352 -121.807224)
		(end 278.449024 -121.510552)
		(width 0.14224)
		(layer "In2.Cu")
		(net "M_D_DQ<40>")
	)
	(segment
		(start 275.53285 -101.604826)
		(end 275.53285 -102.992428)
		(width 0.0889)
		(layer "In2.Cu")
		(net "M_D_DQ<40>")
	)
	(segment
		(start 279.039828 -122.931428)
		(end 279.327356 -122.931428)
		(width 0.14224)
		(layer "In2.Cu")
		(net "M_D_DQ<40>")
	)
	(segment
		(start 290.31692 -132.044948)
		(end 290.31692 -135.00481)
		(width 0.14224)
		(layer "In2.Cu")
		(net "M_D_DQ<40>")
	)
	(segment
		(start 290.31692 -135.00481)
		(end 291.12591 -135.8138)
		(width 0.14224)
		(layer "In2.Cu")
		(net "M_D_DQ<40>")
	)
	(segment
		(start 290.1696 -129.83845)
		(end 290.3728 -130.04165)
		(width 0.14224)
		(layer "In2.Cu")
		(net "M_D_DQ<40>")
	)
	(segment
		(start 278.449024 -121.510552)
		(end 278.736552 -121.510552)
		(width 0.14224)
		(layer "In2.Cu")
		(net "M_D_DQ<40>")
	)
	(segment
		(start 279.914858 -123.781058)
		(end 283.2862 -127.1524)
		(width 0.14224)
		(layer "In2.Cu")
		(net "M_D_DQ<40>")
	)
	(segment
		(start 278.752554 -122.356626)
		(end 278.752554 -122.644154)
		(width 0.14224)
		(layer "In2.Cu")
		(net "M_D_DQ<40>")
	)
	(segment
		(start 277.874222 -120.93575)
		(end 277.57755 -121.232422)
		(width 0.14224)
		(layer "In2.Cu")
		(net "M_D_DQ<40>")
	)
	(segment
		(start 290.1696 -128.9812)
		(end 290.1696 -129.83845)
		(width 0.14224)
		(layer "In2.Cu")
		(net "M_D_DQ<40>")
	)
	(segment
		(start 277.262844 -98.300286)
		(end 277.26767 -98.308922)
		(width 0.0889)
		(layer "In2.Cu")
		(net "M_D_DQ<40>")
	)
	(segment
		(start 289.842956 -128.654556)
		(end 290.1696 -128.9812)
		(width 0.14224)
		(layer "In2.Cu")
		(net "M_D_DQ<40>")
	)
	(segment
		(start 277.256494 -99.280218)
		(end 277.262844 -99.290886)
		(width 0.0889)
		(layer "In2.Cu")
		(net "M_D_DQ<40>")
	)
	(segment
		(start 273.55546 -104.969818)
		(end 273.55546 -105.766362)
		(width 0.0889)
		(layer "In2.Cu")
		(net "M_D_DQ<40>")
	)
	(segment
		(start 290.3728 -130.04165)
		(end 290.3728 -131.408424)
		(width 0.14224)
		(layer "In2.Cu")
		(net "M_D_DQ<40>")
	)
	(segment
		(start 277.874222 -120.648222)
		(end 277.874222 -120.93575)
		(width 0.14224)
		(layer "In2.Cu")
		(net "M_D_DQ<40>")
	)
	(segment
		(start 279.327356 -122.931428)
		(end 279.585928 -122.672856)
		(width 0.14224)
		(layer "In2.Cu")
		(net "M_D_DQ<40>")
	)
	(segment
		(start 286.054546 -127.1524)
		(end 287.556702 -128.654556)
		(width 0.14224)
		(layer "In2.Cu")
		(net "M_D_DQ<40>")
	)
	(segment
		(start 279.023826 -122.085354)
		(end 278.752554 -122.356626)
		(width 0.14224)
		(layer "In2.Cu")
		(net "M_D_DQ<40>")
	)
	(segment
		(start 290.3728 -131.408424)
		(end 290.576254 -131.611878)
		(width 0.14224)
		(layer "In2.Cu")
		(net "M_D_DQ<40>")
	)
	(segment
		(start 277.774654 -97.014538)
		(end 277.279608 -97.680272)
		(width 0.0889)
		(layer "In2.Cu")
		(net "M_D_DQ<40>")
	)
	(segment
		(start 276.281896 -100.308664)
		(end 275.53285 -101.604826)
		(width 0.0889)
		(layer "In2.Cu")
		(net "M_D_DQ<40>")
	)
	(segment
		(start 279.873456 -122.672856)
		(end 280.16073 -122.96013)
		(width 0.14224)
		(layer "In2.Cu")
		(net "M_D_DQ<40>")
	)
	(segment
		(start 276.934168 -99.89058)
		(end 276.898354 -99.89058)
		(width 0.0889)
		(layer "In2.Cu")
		(net "M_D_DQ<40>")
	)
	(segment
		(start 279.914858 -123.49353)
		(end 279.914858 -123.781058)
		(width 0.14224)
		(layer "In2.Cu")
		(net "M_D_DQ<40>")
	)
	(segment
		(start 277.864824 -121.807224)
		(end 278.152352 -121.807224)
		(width 0.14224)
		(layer "In2.Cu")
		(net "M_D_DQ<40>")
	)
	(segment
		(start 290.74999 -131.611878)
		(end 290.31692 -132.044948)
		(width 0.14224)
		(layer "In2.Cu")
		(net "M_D_DQ<40>")
	)
	(arc
		(start 277.262844 -99.290886)
		(mid 277.267089 -99.683131)
		(end 276.934168 -99.89058)
		(width 0.0889)
		(layer "In2.Cu")
		(net "M_D_DQ<40>")
	)
	(arc
		(start 276.573234 -100.000054)
		(mid 276.414579 -100.13793)
		(end 276.285198 -100.303584)
		(width 0.0889)
		(layer "In2.Cu")
		(net "M_D_DQ<40>")
	)
	(arc
		(start 276.898354 -99.89058)
		(mid 276.727663 -99.92118)
		(end 276.573234 -100.000054)
		(width 0.0889)
		(layer "In2.Cu")
		(net "M_D_DQ<40>")
	)
	(arc
		(start 277.262844 -98.700336)
		(mid 277.183622 -98.989454)
		(end 277.256494 -99.280218)
		(width 0.0889)
		(layer "In2.Cu")
		(net "M_D_DQ<40>")
	)
	(arc
		(start 277.26767 -98.308922)
		(mid 277.316425 -98.505274)
		(end 277.262844 -98.700336)
		(width 0.0889)
		(layer "In2.Cu")
		(net "M_D_DQ<40>")
	)
	(arc
		(start 277.262844 -97.709736)
		(mid 277.183622 -97.998854)
		(end 277.256494 -98.289618)
		(width 0.0889)
		(layer "In2.Cu")
		(net "M_D_DQ<40>")
	)
	(segment
		(start 234.466638 -89.27084)
		(end 233.895138 -89.27084)
		(width 0.1651)
		(layer "F.Cu")
		(net "M_D_DQ<3>")
	)
	(segment
		(start 204.050392 -133.0706)
		(end 204.049884 -133.076442)
		(width 0.1651)
		(layer "F.Cu")
		(net "M_D_DQ<3>")
	)
	(segment
		(start 204.049884 -133.076442)
		(end 204.049884 -134.340346)
		(width 0.1651)
		(layer "F.Cu")
		(net "M_D_DQ<3>")
	)
	(via
		(at 204.049884 -134.340346)
		(size 0.508)
		(drill 0.254)
		(layers "F.Cu" "B.Cu")
		(net "M_D_DQ<3>")
	)
	(via
		(at 233.895138 -89.27084)
		(size 0.508)
		(drill 0.254)
		(layers "F.Cu" "B.Cu")
		(net "M_D_DQ<3>")
	)
	(via
		(at 204.899768 -130.330956)
		(size 0.508)
		(drill 0.254)
		(layers "F.Cu" "B.Cu")
		(net "M_D_DQ<3>")
	)
	(segment
		(start 204.900276 -128.276096)
		(end 204.899768 -128.276096)
		(width 0.1651)
		(layer "B.Cu")
		(net "M_D_DQ<3>")
	)
	(segment
		(start 204.899768 -128.276096)
		(end 204.899768 -130.330956)
		(width 0.1651)
		(layer "B.Cu")
		(net "M_D_DQ<3>")
	)
	(segment
		(start 230.274114 -89.916)
		(end 219.78239 -100.407724)
		(width 0.14224)
		(layer "In2.Cu")
		(net "M_D_DQ<3>")
	)
	(segment
		(start 204.493622 -131.9022)
		(end 204.211174 -132.184648)
		(width 0.14224)
		(layer "In2.Cu")
		(net "M_D_DQ<3>")
	)
	(segment
		(start 219.78239 -102.027228)
		(end 208.480152 -113.329466)
		(width 0.14224)
		(layer "In2.Cu")
		(net "M_D_DQ<3>")
	)
	(segment
		(start 230.908352 -89.916)
		(end 230.274114 -89.916)
		(width 0.14224)
		(layer "In2.Cu")
		(net "M_D_DQ<3>")
	)
	(segment
		(start 207.667352 -115.1636)
		(end 207.464152 -114.9604)
		(width 0.14224)
		(layer "In2.Cu")
		(net "M_D_DQ<3>")
	)
	(segment
		(start 219.78239 -100.407724)
		(end 219.78239 -102.027228)
		(width 0.14224)
		(layer "In2.Cu")
		(net "M_D_DQ<3>")
	)
	(segment
		(start 232.82529 -89.27084)
		(end 232.295446 -89.800684)
		(width 0.0889)
		(layer "In2.Cu")
		(net "M_D_DQ<3>")
	)
	(segment
		(start 207.464152 -114.9604)
		(end 207.057752 -114.9604)
		(width 0.14224)
		(layer "In2.Cu")
		(net "M_D_DQ<3>")
	)
	(segment
		(start 204.493622 -131.233418)
		(end 204.493622 -131.9022)
		(width 0.14224)
		(layer "In2.Cu")
		(net "M_D_DQ<3>")
	)
	(segment
		(start 204.899768 -130.344164)
		(end 204.899768 -130.330956)
		(width 0.14224)
		(layer "In2.Cu")
		(net "M_D_DQ<3>")
	)
	(segment
		(start 204.877416 -130.330956)
		(end 204.449172 -130.7592)
		(width 0.14224)
		(layer "In2.Cu")
		(net "M_D_DQ<3>")
	)
	(segment
		(start 204.211174 -133.276848)
		(end 204.211174 -133.550152)
		(width 0.14224)
		(layer "In2.Cu")
		(net "M_D_DQ<3>")
	)
	(segment
		(start 204.899768 -130.330956)
		(end 204.877416 -130.330956)
		(width 0.14224)
		(layer "In2.Cu")
		(net "M_D_DQ<3>")
	)
	(segment
		(start 232.295446 -89.800684)
		(end 231.892602 -89.800684)
		(width 0.0889)
		(layer "In2.Cu")
		(net "M_D_DQ<3>")
	)
	(segment
		(start 207.057752 -114.9604)
		(end 206.854552 -115.1636)
		(width 0.14224)
		(layer "In2.Cu")
		(net "M_D_DQ<3>")
	)
	(segment
		(start 207.870552 -119.7356)
		(end 207.667352 -119.5324)
		(width 0.14224)
		(layer "In2.Cu")
		(net "M_D_DQ<3>")
	)
	(segment
		(start 206.575152 -129.0574)
		(end 205.355952 -129.0574)
		(width 0.14224)
		(layer "In2.Cu")
		(net "M_D_DQ<3>")
	)
	(segment
		(start 204.211174 -132.457952)
		(end 204.468222 -132.715)
		(width 0.14224)
		(layer "In2.Cu")
		(net "M_D_DQ<3>")
	)
	(segment
		(start 205.228952 -129.1844)
		(end 205.228952 -130.01498)
		(width 0.14224)
		(layer "In2.Cu")
		(net "M_D_DQ<3>")
	)
	(segment
		(start 233.895138 -89.27084)
		(end 232.82529 -89.27084)
		(width 0.0889)
		(layer "In2.Cu")
		(net "M_D_DQ<3>")
	)
	(segment
		(start 208.480152 -119.5324)
		(end 208.276952 -119.7356)
		(width 0.14224)
		(layer "In2.Cu")
		(net "M_D_DQ<3>")
	)
	(segment
		(start 204.449172 -130.7592)
		(end 204.449172 -131.188968)
		(width 0.14224)
		(layer "In2.Cu")
		(net "M_D_DQ<3>")
	)
	(segment
		(start 206.854552 -128.778)
		(end 206.575152 -129.0574)
		(width 0.14224)
		(layer "In2.Cu")
		(net "M_D_DQ<3>")
	)
	(segment
		(start 204.211174 -133.550152)
		(end 204.499972 -133.83895)
		(width 0.14224)
		(layer "In2.Cu")
		(net "M_D_DQ<3>")
	)
	(segment
		(start 204.468222 -133.0198)
		(end 204.211174 -133.276848)
		(width 0.14224)
		(layer "In2.Cu")
		(net "M_D_DQ<3>")
	)
	(segment
		(start 204.499972 -133.83895)
		(end 204.499972 -134.162546)
		(width 0.14224)
		(layer "In2.Cu")
		(net "M_D_DQ<3>")
	)
	(segment
		(start 206.854552 -115.1636)
		(end 206.854552 -128.778)
		(width 0.14224)
		(layer "In2.Cu")
		(net "M_D_DQ<3>")
	)
	(segment
		(start 231.892602 -89.800684)
		(end 231.777286 -89.916)
		(width 0.0889)
		(layer "In2.Cu")
		(net "M_D_DQ<3>")
	)
	(segment
		(start 207.667352 -119.5324)
		(end 207.667352 -115.1636)
		(width 0.14224)
		(layer "In2.Cu")
		(net "M_D_DQ<3>")
	)
	(segment
		(start 208.276952 -119.7356)
		(end 207.870552 -119.7356)
		(width 0.14224)
		(layer "In2.Cu")
		(net "M_D_DQ<3>")
	)
	(segment
		(start 204.211174 -132.184648)
		(end 204.211174 -132.457952)
		(width 0.14224)
		(layer "In2.Cu")
		(net "M_D_DQ<3>")
	)
	(segment
		(start 204.322172 -134.340346)
		(end 204.049884 -134.340346)
		(width 0.14224)
		(layer "In2.Cu")
		(net "M_D_DQ<3>")
	)
	(segment
		(start 208.480152 -113.329466)
		(end 208.480152 -119.5324)
		(width 0.14224)
		(layer "In2.Cu")
		(net "M_D_DQ<3>")
	)
	(segment
		(start 231.777286 -89.916)
		(end 230.908352 -89.916)
		(width 0.0889)
		(layer "In2.Cu")
		(net "M_D_DQ<3>")
	)
	(segment
		(start 205.228952 -130.01498)
		(end 204.899768 -130.344164)
		(width 0.14224)
		(layer "In2.Cu")
		(net "M_D_DQ<3>")
	)
	(segment
		(start 204.499972 -134.162546)
		(end 204.322172 -134.340346)
		(width 0.14224)
		(layer "In2.Cu")
		(net "M_D_DQ<3>")
	)
	(segment
		(start 205.355952 -129.0574)
		(end 205.228952 -129.1844)
		(width 0.14224)
		(layer "In2.Cu")
		(net "M_D_DQ<3>")
	)
	(segment
		(start 204.449172 -131.188968)
		(end 204.493622 -131.233418)
		(width 0.14224)
		(layer "In2.Cu")
		(net "M_D_DQ<3>")
	)
	(segment
		(start 204.468222 -132.715)
		(end 204.468222 -133.0198)
		(width 0.14224)
		(layer "In2.Cu")
		(net "M_D_DQ<3>")
	)
	(segment
		(start 282.21178 -120.701054)
		(end 281.917648 -120.995186)
		(width 0.1651)
		(layer "F.Cu")
		(net "M_D_DQ<39>")
	)
	(segment
		(start 286.8168 -125.86716)
		(end 286.6517 -126.03226)
		(width 0.1651)
		(layer "F.Cu")
		(net "M_D_DQ<39>")
	)
	(segment
		(start 278.9936 -117.242336)
		(end 282.21178 -120.460516)
		(width 0.1651)
		(layer "F.Cu")
		(net "M_D_DQ<39>")
	)
	(segment
		(start 286.780224 -127.93218)
		(end 286.430212 -127.93218)
		(width 0.1651)
		(layer "F.Cu")
		(net "M_D_DQ<39>")
	)
	(segment
		(start 284.69844 -124.14504)
		(end 285.7627 -125.2093)
		(width 0.1651)
		(layer "F.Cu")
		(net "M_D_DQ<39>")
	)
	(segment
		(start 286.303212 -128.75768)
		(end 286.8676 -129.322068)
		(width 0.1651)
		(layer "F.Cu")
		(net "M_D_DQ<39>")
	)
	(segment
		(start 286.938974 -127.77343)
		(end 286.780224 -127.93218)
		(width 0.1651)
		(layer "F.Cu")
		(net "M_D_DQ<39>")
	)
	(segment
		(start 286.6009 -127.10922)
		(end 286.767524 -127.10922)
		(width 0.1651)
		(layer "F.Cu")
		(net "M_D_DQ<39>")
	)
	(segment
		(start 282.686506 -121.17832)
		(end 282.929584 -121.17832)
		(width 0.1651)
		(layer "F.Cu")
		(net "M_D_DQ<39>")
	)
	(segment
		(start 277.0378 -113.284)
		(end 277.4696 -113.284)
		(width 0.1016)
		(layer "F.Cu")
		(net "M_D_DQ<39>")
	)
	(segment
		(start 284.831028 -123.045728)
		(end 285.066486 -123.281186)
		(width 0.1651)
		(layer "F.Cu")
		(net "M_D_DQ<39>")
	)
	(segment
		(start 286.938974 -127.28067)
		(end 286.938974 -127.77343)
		(width 0.1651)
		(layer "F.Cu")
		(net "M_D_DQ<39>")
	)
	(segment
		(start 276.344634 -102.462584)
		(end 276.344634 -103.768144)
		(width 0.0889)
		(layer "F.Cu")
		(net "M_D_DQ<39>")
	)
	(segment
		(start 286.430212 -127.93218)
		(end 286.303212 -128.05918)
		(width 0.1651)
		(layer "F.Cu")
		(net "M_D_DQ<39>")
	)
	(segment
		(start 286.8676 -129.322068)
		(end 286.8676 -129.963164)
		(width 0.1651)
		(layer "F.Cu")
		(net "M_D_DQ<39>")
	)
	(segment
		(start 283.9974 -122.246136)
		(end 283.9974 -122.563128)
		(width 0.1651)
		(layer "F.Cu")
		(net "M_D_DQ<39>")
	)
	(segment
		(start 284.583124 -123.045728)
		(end 284.831028 -123.045728)
		(width 0.1651)
		(layer "F.Cu")
		(net "M_D_DQ<39>")
	)
	(segment
		(start 276.344634 -103.768144)
		(end 276.494494 -103.918004)
		(width 0.0889)
		(layer "F.Cu")
		(net "M_D_DQ<39>")
	)
	(segment
		(start 286.6517 -125.2093)
		(end 286.8168 -125.3744)
		(width 0.1651)
		(layer "F.Cu")
		(net "M_D_DQ<39>")
	)
	(segment
		(start 285.650432 -133.0706)
		(end 285.649924 -133.076442)
		(width 0.1651)
		(layer "F.Cu")
		(net "M_D_DQ<39>")
	)
	(segment
		(start 286.4612 -126.96952)
		(end 286.6009 -127.10922)
		(width 0.1651)
		(layer "F.Cu")
		(net "M_D_DQ<39>")
	)
	(segment
		(start 285.066486 -123.281186)
		(end 285.066486 -123.52909)
		(width 0.1651)
		(layer "F.Cu")
		(net "M_D_DQ<39>")
	)
	(segment
		(start 286.6517 -126.03226)
		(end 286.6263 -126.03226)
		(width 0.1651)
		(layer "F.Cu")
		(net "M_D_DQ<39>")
	)
	(segment
		(start 282.194762 -121.452386)
		(end 282.41244 -121.452386)
		(width 0.1651)
		(layer "F.Cu")
		(net "M_D_DQ<39>")
	)
	(segment
		(start 285.649924 -133.076442)
		(end 285.649924 -134.340346)
		(width 0.1651)
		(layer "F.Cu")
		(net "M_D_DQ<39>")
	)
	(segment
		(start 286.8168 -125.3744)
		(end 286.8168 -125.86716)
		(width 0.1651)
		(layer "F.Cu")
		(net "M_D_DQ<39>")
	)
	(segment
		(start 275.839174 -105.973626)
		(end 275.839174 -106.4514)
		(width 0.0889)
		(layer "F.Cu")
		(net "M_D_DQ<39>")
	)
	(segment
		(start 285.7627 -125.2093)
		(end 286.6517 -125.2093)
		(width 0.1651)
		(layer "F.Cu")
		(net "M_D_DQ<39>")
	)
	(segment
		(start 283.951172 -123.445778)
		(end 284.183074 -123.445778)
		(width 0.1651)
		(layer "F.Cu")
		(net "M_D_DQ<39>")
	)
	(segment
		(start 276.494494 -103.918004)
		(end 276.494494 -105.318306)
		(width 0.0889)
		(layer "F.Cu")
		(net "M_D_DQ<39>")
	)
	(segment
		(start 277.4696 -113.284)
		(end 278.9936 -114.808)
		(width 0.1651)
		(layer "F.Cu")
		(net "M_D_DQ<39>")
	)
	(segment
		(start 276.494494 -105.318306)
		(end 275.839174 -105.973626)
		(width 0.0889)
		(layer "F.Cu")
		(net "M_D_DQ<39>")
	)
	(segment
		(start 275.940774 -112.186974)
		(end 277.0378 -113.284)
		(width 0.1016)
		(layer "F.Cu")
		(net "M_D_DQ<39>")
	)
	(segment
		(start 286.8676 -129.963164)
		(end 286.499808 -130.330956)
		(width 0.1651)
		(layer "F.Cu")
		(net "M_D_DQ<39>")
	)
	(segment
		(start 275.940774 -106.553)
		(end 275.940774 -112.186974)
		(width 0.1016)
		(layer "F.Cu")
		(net "M_D_DQ<39>")
	)
	(segment
		(start 281.917648 -120.995186)
		(end 281.917648 -121.175272)
		(width 0.1651)
		(layer "F.Cu")
		(net "M_D_DQ<39>")
	)
	(segment
		(start 278.9936 -114.808)
		(end 278.9936 -117.242336)
		(width 0.1651)
		(layer "F.Cu")
		(net "M_D_DQ<39>")
	)
	(segment
		(start 283.664914 -123.15952)
		(end 283.951172 -123.445778)
		(width 0.1651)
		(layer "F.Cu")
		(net "M_D_DQ<39>")
	)
	(segment
		(start 283.9974 -122.563128)
		(end 283.664914 -122.895614)
		(width 0.1651)
		(layer "F.Cu")
		(net "M_D_DQ<39>")
	)
	(segment
		(start 286.6263 -126.03226)
		(end 286.4612 -126.19736)
		(width 0.1651)
		(layer "F.Cu")
		(net "M_D_DQ<39>")
	)
	(segment
		(start 275.839174 -106.4514)
		(end 275.940774 -106.553)
		(width 0.0889)
		(layer "F.Cu")
		(net "M_D_DQ<39>")
	)
	(segment
		(start 281.917648 -121.175272)
		(end 282.194762 -121.452386)
		(width 0.1651)
		(layer "F.Cu")
		(net "M_D_DQ<39>")
	)
	(segment
		(start 282.41244 -121.452386)
		(end 282.686506 -121.17832)
		(width 0.1651)
		(layer "F.Cu")
		(net "M_D_DQ<39>")
	)
	(segment
		(start 286.4612 -126.19736)
		(end 286.4612 -126.96952)
		(width 0.1651)
		(layer "F.Cu")
		(net "M_D_DQ<39>")
	)
	(segment
		(start 282.21178 -120.460516)
		(end 282.21178 -120.701054)
		(width 0.1651)
		(layer "F.Cu")
		(net "M_D_DQ<39>")
	)
	(segment
		(start 284.69844 -123.897136)
		(end 284.69844 -124.14504)
		(width 0.1651)
		(layer "F.Cu")
		(net "M_D_DQ<39>")
	)
	(segment
		(start 286.767524 -127.10922)
		(end 286.938974 -127.28067)
		(width 0.1651)
		(layer "F.Cu")
		(net "M_D_DQ<39>")
	)
	(segment
		(start 282.929584 -121.17832)
		(end 283.9974 -122.246136)
		(width 0.1651)
		(layer "F.Cu")
		(net "M_D_DQ<39>")
	)
	(segment
		(start 285.066486 -123.52909)
		(end 284.69844 -123.897136)
		(width 0.1651)
		(layer "F.Cu")
		(net "M_D_DQ<39>")
	)
	(segment
		(start 283.664914 -122.895614)
		(end 283.664914 -123.15952)
		(width 0.1651)
		(layer "F.Cu")
		(net "M_D_DQ<39>")
	)
	(segment
		(start 286.303212 -128.05918)
		(end 286.303212 -128.75768)
		(width 0.1651)
		(layer "F.Cu")
		(net "M_D_DQ<39>")
	)
	(segment
		(start 284.183074 -123.445778)
		(end 284.583124 -123.045728)
		(width 0.1651)
		(layer "F.Cu")
		(net "M_D_DQ<39>")
	)
	(via
		(at 285.649924 -134.340346)
		(size 0.508)
		(drill 0.254)
		(layers "F.Cu" "B.Cu")
		(net "M_D_DQ<39>")
	)
	(via
		(at 286.499808 -130.330956)
		(size 0.508)
		(drill 0.254)
		(layers "F.Cu" "B.Cu")
		(net "M_D_DQ<39>")
	)
	(segment
		(start 286.500316 -128.276096)
		(end 286.499808 -128.276096)
		(width 0.1651)
		(layer "B.Cu")
		(net "M_D_DQ<39>")
	)
	(segment
		(start 286.499808 -128.276096)
		(end 286.499808 -130.330956)
		(width 0.1651)
		(layer "B.Cu")
		(net "M_D_DQ<39>")
	)
	(segment
		(start 286.068262 -133.0198)
		(end 286.068262 -132.715)
		(width 0.14224)
		(layer "In2.Cu")
		(net "M_D_DQ<39>")
	)
	(segment
		(start 285.922212 -134.340346)
		(end 286.100012 -134.162546)
		(width 0.14224)
		(layer "In2.Cu")
		(net "M_D_DQ<39>")
	)
	(segment
		(start 286.068262 -132.715)
		(end 285.811214 -132.457952)
		(width 0.14224)
		(layer "In2.Cu")
		(net "M_D_DQ<39>")
	)
	(segment
		(start 286.100012 -133.83895)
		(end 285.811214 -133.550152)
		(width 0.14224)
		(layer "In2.Cu")
		(net "M_D_DQ<39>")
	)
	(segment
		(start 286.049212 -131.188968)
		(end 286.049212 -130.7592)
		(width 0.14224)
		(layer "In2.Cu")
		(net "M_D_DQ<39>")
	)
	(segment
		(start 286.093662 -131.9022)
		(end 286.093662 -131.233418)
		(width 0.14224)
		(layer "In2.Cu")
		(net "M_D_DQ<39>")
	)
	(segment
		(start 286.093662 -131.233418)
		(end 286.049212 -131.188968)
		(width 0.14224)
		(layer "In2.Cu")
		(net "M_D_DQ<39>")
	)
	(segment
		(start 285.811214 -133.276848)
		(end 286.068262 -133.0198)
		(width 0.14224)
		(layer "In2.Cu")
		(net "M_D_DQ<39>")
	)
	(segment
		(start 285.811214 -133.550152)
		(end 285.811214 -133.276848)
		(width 0.14224)
		(layer "In2.Cu")
		(net "M_D_DQ<39>")
	)
	(segment
		(start 286.100012 -134.162546)
		(end 286.100012 -133.83895)
		(width 0.14224)
		(layer "In2.Cu")
		(net "M_D_DQ<39>")
	)
	(segment
		(start 285.649924 -134.340346)
		(end 285.922212 -134.340346)
		(width 0.14224)
		(layer "In2.Cu")
		(net "M_D_DQ<39>")
	)
	(segment
		(start 286.049212 -130.7592)
		(end 286.477456 -130.330956)
		(width 0.14224)
		(layer "In2.Cu")
		(net "M_D_DQ<39>")
	)
	(segment
		(start 285.811214 -132.457952)
		(end 285.811214 -132.184648)
		(width 0.14224)
		(layer "In2.Cu")
		(net "M_D_DQ<39>")
	)
	(segment
		(start 285.811214 -132.184648)
		(end 286.093662 -131.9022)
		(width 0.14224)
		(layer "In2.Cu")
		(net "M_D_DQ<39>")
	)
	(segment
		(start 286.477456 -130.330956)
		(end 286.499808 -130.330956)
		(width 0.14224)
		(layer "In2.Cu")
		(net "M_D_DQ<39>")
	)
	(segment
		(start 276.344634 -100.481638)
		(end 276.041612 -100.78466)
		(width 0.0889)
		(layer "F.Cu")
		(net "M_D_DQ<38>")
	)
	(segment
		(start 282.726384 -123.127516)
		(end 285.8008 -126.201932)
		(width 0.1651)
		(layer "F.Cu")
		(net "M_D_DQ<38>")
	)
	(segment
		(start 275.648674 -106.4514)
		(end 275.547074 -106.553)
		(width 0.0889)
		(layer "F.Cu")
		(net "M_D_DQ<38>")
	)
	(segment
		(start 282.230068 -122.39625)
		(end 282.535376 -122.090942)
		(width 0.1651)
		(layer "F.Cu")
		(net "M_D_DQ<38>")
	)
	(segment
		(start 276.041612 -100.78466)
		(end 276.041612 -101.181662)
		(width 0.0889)
		(layer "F.Cu")
		(net "M_D_DQ<38>")
	)
	(segment
		(start 286.632142 -136.57072)
		(end 286.632142 -136.35228)
		(width 0.1651)
		(layer "F.Cu")
		(net "M_D_DQ<38>")
	)
	(segment
		(start 286.500062 -135.915654)
		(end 286.499808 -135.9154)
		(width 0.1651)
		(layer "F.Cu")
		(net "M_D_DQ<38>")
	)
	(segment
		(start 286.500062 -137.67054)
		(end 286.500062 -136.7028)
		(width 0.1651)
		(layer "F.Cu")
		(net "M_D_DQ<38>")
	)
	(segment
		(start 283.018738 -122.3264)
		(end 283.018738 -122.587258)
		(width 0.1651)
		(layer "F.Cu")
		(net "M_D_DQ<38>")
	)
	(segment
		(start 276.303994 -104.011984)
		(end 276.303994 -105.239312)
		(width 0.0889)
		(layer "F.Cu")
		(net "M_D_DQ<38>")
	)
	(segment
		(start 275.547074 -112.352074)
		(end 277.0251 -113.8301)
		(width 0.1016)
		(layer "F.Cu")
		(net "M_D_DQ<38>")
	)
	(segment
		(start 282.78328 -122.090942)
		(end 283.018738 -122.3264)
		(width 0.1651)
		(layer "F.Cu")
		(net "M_D_DQ<38>")
	)
	(segment
		(start 281.276552 -120.47982)
		(end 281.276552 -121.677684)
		(width 0.1651)
		(layer "F.Cu")
		(net "M_D_DQ<38>")
	)
	(segment
		(start 276.014688 -101.243638)
		(end 275.997924 -101.272594)
		(width 0.0889)
		(layer "F.Cu")
		(net "M_D_DQ<38>")
	)
	(segment
		(start 282.535376 -122.090942)
		(end 282.78328 -122.090942)
		(width 0.1651)
		(layer "F.Cu")
		(net "M_D_DQ<38>")
	)
	(segment
		(start 286.1818 -129.826004)
		(end 285.115 -130.892804)
		(width 0.1651)
		(layer "F.Cu")
		(net "M_D_DQ<38>")
	)
	(segment
		(start 285.8008 -126.201932)
		(end 285.8008 -129.0574)
		(width 0.1651)
		(layer "F.Cu")
		(net "M_D_DQ<38>")
	)
	(segment
		(start 276.041612 -101.181662)
		(end 276.014688 -101.243638)
		(width 0.0889)
		(layer "F.Cu")
		(net "M_D_DQ<38>")
	)
	(segment
		(start 285.115 -130.892804)
		(end 285.115 -131.076954)
		(width 0.1651)
		(layer "F.Cu")
		(net "M_D_DQ<38>")
	)
	(segment
		(start 275.547074 -106.553)
		(end 275.547074 -112.352074)
		(width 0.1016)
		(layer "F.Cu")
		(net "M_D_DQ<38>")
	)
	(segment
		(start 282.726384 -122.879612)
		(end 282.726384 -123.127516)
		(width 0.1651)
		(layer "F.Cu")
		(net "M_D_DQ<38>")
	)
	(segment
		(start 281.276552 -121.677684)
		(end 281.995118 -122.39625)
		(width 0.1651)
		(layer "F.Cu")
		(net "M_D_DQ<38>")
	)
	(segment
		(start 286.1818 -129.4384)
		(end 286.1818 -129.826004)
		(width 0.1651)
		(layer "F.Cu")
		(net "M_D_DQ<38>")
	)
	(segment
		(start 285.8008 -129.0574)
		(end 286.1818 -129.4384)
		(width 0.1651)
		(layer "F.Cu")
		(net "M_D_DQ<38>")
	)
	(segment
		(start 286.632142 -136.35228)
		(end 286.500062 -136.2202)
		(width 0.1651)
		(layer "F.Cu")
		(net "M_D_DQ<38>")
	)
	(segment
		(start 283.018738 -122.587258)
		(end 282.726384 -122.879612)
		(width 0.1651)
		(layer "F.Cu")
		(net "M_D_DQ<38>")
	)
	(segment
		(start 278.3332 -115.1382)
		(end 278.3332 -117.536468)
		(width 0.1651)
		(layer "F.Cu")
		(net "M_D_DQ<38>")
	)
	(segment
		(start 275.997924 -101.67239)
		(end 276.004274 -101.683058)
		(width 0.0889)
		(layer "F.Cu")
		(net "M_D_DQ<38>")
	)
	(segment
		(start 277.0251 -113.8301)
		(end 278.3332 -115.1382)
		(width 0.1651)
		(layer "F.Cu")
		(net "M_D_DQ<38>")
	)
	(segment
		(start 281.995118 -122.39625)
		(end 282.230068 -122.39625)
		(width 0.1651)
		(layer "F.Cu")
		(net "M_D_DQ<38>")
	)
	(segment
		(start 276.153372 -103.861362)
		(end 276.303994 -104.011984)
		(width 0.0889)
		(layer "F.Cu")
		(net "M_D_DQ<38>")
	)
	(segment
		(start 276.303994 -105.239312)
		(end 275.648674 -105.894632)
		(width 0.0889)
		(layer "F.Cu")
		(net "M_D_DQ<38>")
	)
	(segment
		(start 275.997924 -102.26294)
		(end 275.993098 -102.271576)
		(width 0.0889)
		(layer "F.Cu")
		(net "M_D_DQ<38>")
	)
	(segment
		(start 275.648674 -105.894632)
		(end 275.648674 -106.4514)
		(width 0.0889)
		(layer "F.Cu")
		(net "M_D_DQ<38>")
	)
	(segment
		(start 286.500062 -136.7028)
		(end 286.632142 -136.57072)
		(width 0.1651)
		(layer "F.Cu")
		(net "M_D_DQ<38>")
	)
	(segment
		(start 286.500062 -136.2202)
		(end 286.500062 -135.915654)
		(width 0.1651)
		(layer "F.Cu")
		(net "M_D_DQ<38>")
	)
	(segment
		(start 285.115 -131.076954)
		(end 285.649924 -131.611878)
		(width 0.1651)
		(layer "F.Cu")
		(net "M_D_DQ<38>")
	)
	(segment
		(start 278.3332 -117.536468)
		(end 281.276552 -120.47982)
		(width 0.1651)
		(layer "F.Cu")
		(net "M_D_DQ<38>")
	)
	(segment
		(start 286.500316 -137.67054)
		(end 286.500062 -137.67054)
		(width 0.1651)
		(layer "F.Cu")
		(net "M_D_DQ<38>")
	)
	(segment
		(start 276.153372 -103.242872)
		(end 276.153372 -103.861362)
		(width 0.0889)
		(layer "F.Cu")
		(net "M_D_DQ<38>")
	)
	(via
		(at 285.649924 -131.611878)
		(size 0.508)
		(drill 0.254)
		(layers "F.Cu" "B.Cu")
		(net "M_D_DQ<38>")
	)
	(via
		(at 286.499808 -135.9154)
		(size 0.508)
		(drill 0.254)
		(layers "F.Cu" "B.Cu")
		(net "M_D_DQ<38>")
	)
	(arc
		(start 275.997924 -101.272594)
		(mid 275.944425 -101.472492)
		(end 275.997924 -101.67239)
		(width 0.0889)
		(layer "F.Cu")
		(net "M_D_DQ<38>")
	)
	(arc
		(start 275.993098 -102.271576)
		(mid 275.944343 -102.467928)
		(end 275.997924 -102.66299)
		(width 0.0889)
		(layer "F.Cu")
		(net "M_D_DQ<38>")
	)
	(arc
		(start 276.004274 -101.683058)
		(mid 276.077072 -101.973821)
		(end 275.997924 -102.26294)
		(width 0.0889)
		(layer "F.Cu")
		(net "M_D_DQ<38>")
	)
	(arc
		(start 275.997924 -102.66299)
		(mid 276.113867 -102.942689)
		(end 276.153372 -103.242872)
		(width 0.0889)
		(layer "F.Cu")
		(net "M_D_DQ<38>")
	)
	(segment
		(start 285.649924 -132.875782)
		(end 285.649924 -131.611878)
		(width 0.1651)
		(layer "B.Cu")
		(net "M_D_DQ<38>")
	)
	(segment
		(start 285.650432 -132.876036)
		(end 285.649924 -132.875782)
		(width 0.1651)
		(layer "B.Cu")
		(net "M_D_DQ<38>")
	)
	(segment
		(start 285.216854 -132.044948)
		(end 285.649924 -131.611878)
		(width 0.14224)
		(layer "In2.Cu")
		(net "M_D_DQ<38>")
	)
	(segment
		(start 286.499808 -135.9154)
		(end 285.216854 -134.632446)
		(width 0.14224)
		(layer "In2.Cu")
		(net "M_D_DQ<38>")
	)
	(segment
		(start 285.216854 -134.632446)
		(end 285.216854 -132.044948)
		(width 0.14224)
		(layer "In2.Cu")
		(net "M_D_DQ<38>")
	)
	(segment
		(start 279.556718 -126.044198)
		(end 279.790398 -126.044198)
		(width 0.1651)
		(layer "F.Cu")
		(net "M_D_DQ<37>")
	)
	(segment
		(start 280.802334 -128.107948)
		(end 280.450036 -128.460246)
		(width 0.1651)
		(layer "F.Cu")
		(net "M_D_DQ<37>")
	)
	(segment
		(start 279.486614 -127.081026)
		(end 279.486614 -127.378206)
		(width 0.1651)
		(layer "F.Cu")
		(net "M_D_DQ<37>")
	)
	(segment
		(start 278.764492 -125.849126)
		(end 278.53513 -126.078488)
		(width 0.1651)
		(layer "F.Cu")
		(net "M_D_DQ<37>")
	)
	(segment
		(start 278.813514 -126.56566)
		(end 279.035256 -126.56566)
		(width 0.1651)
		(layer "F.Cu")
		(net "M_D_DQ<37>")
	)
	(segment
		(start 272.298922 -115.453922)
		(end 273.1262 -116.2812)
		(width 0.1651)
		(layer "F.Cu")
		(net "M_D_DQ<37>")
	)
	(segment
		(start 272.791174 -112.145826)
		(end 272.298922 -112.638078)
		(width 0.1016)
		(layer "F.Cu")
		(net "M_D_DQ<37>")
	)
	(segment
		(start 279.82291 -127.714502)
		(end 280.017728 -127.714502)
		(width 0.1651)
		(layer "F.Cu")
		(net "M_D_DQ<37>")
	)
	(segment
		(start 279.035256 -126.56566)
		(end 279.556718 -126.044198)
		(width 0.1651)
		(layer "F.Cu")
		(net "M_D_DQ<37>")
	)
	(segment
		(start 273.422364 -101.76764)
		(end 273.417538 -101.776276)
		(width 0.0889)
		(layer "F.Cu")
		(net "M_D_DQ<37>")
	)
	(segment
		(start 272.689574 -106.426)
		(end 272.791174 -106.5276)
		(width 0.0889)
		(layer "F.Cu")
		(net "M_D_DQ<37>")
	)
	(segment
		(start 279.486614 -127.378206)
		(end 279.82291 -127.714502)
		(width 0.1651)
		(layer "F.Cu")
		(net "M_D_DQ<37>")
	)
	(segment
		(start 278.764492 -125.508004)
		(end 278.764492 -125.849126)
		(width 0.1651)
		(layer "F.Cu")
		(net "M_D_DQ<37>")
	)
	(segment
		(start 273.1262 -116.2812)
		(end 273.1262 -119.869712)
		(width 0.1651)
		(layer "F.Cu")
		(net "M_D_DQ<37>")
	)
	(segment
		(start 280.04008 -126.29388)
		(end 280.04008 -126.52756)
		(width 0.1651)
		(layer "F.Cu")
		(net "M_D_DQ<37>")
	)
	(segment
		(start 279.700482 -133.0706)
		(end 279.699974 -133.076442)
		(width 0.1651)
		(layer "F.Cu")
		(net "M_D_DQ<37>")
	)
	(segment
		(start 272.298922 -112.638078)
		(end 272.298922 -115.453922)
		(width 0.1651)
		(layer "F.Cu")
		(net "M_D_DQ<37>")
	)
	(segment
		(start 280.04008 -126.52756)
		(end 279.486614 -127.081026)
		(width 0.1651)
		(layer "F.Cu")
		(net "M_D_DQ<37>")
	)
	(segment
		(start 273.769328 -100.976684)
		(end 273.645376 -101.261164)
		(width 0.0889)
		(layer "F.Cu")
		(net "M_D_DQ<37>")
	)
	(segment
		(start 279.699974 -133.076442)
		(end 279.699974 -134.340346)
		(width 0.1651)
		(layer "F.Cu")
		(net "M_D_DQ<37>")
	)
	(segment
		(start 273.1262 -119.869712)
		(end 278.764492 -125.508004)
		(width 0.1651)
		(layer "F.Cu")
		(net "M_D_DQ<37>")
	)
	(segment
		(start 273.414744 -102.77094)
		(end 273.376644 -102.824788)
		(width 0.0889)
		(layer "F.Cu")
		(net "M_D_DQ<37>")
	)
	(segment
		(start 279.790398 -126.044198)
		(end 280.04008 -126.29388)
		(width 0.1651)
		(layer "F.Cu")
		(net "M_D_DQ<37>")
	)
	(segment
		(start 280.898346 -129.906268)
		(end 280.473658 -130.330956)
		(width 0.1651)
		(layer "F.Cu")
		(net "M_D_DQ<37>")
	)
	(segment
		(start 272.689574 -103.511858)
		(end 272.689574 -106.426)
		(width 0.0889)
		(layer "F.Cu")
		(net "M_D_DQ<37>")
	)
	(segment
		(start 280.450036 -128.460246)
		(end 280.450036 -128.710182)
		(width 0.1651)
		(layer "F.Cu")
		(net "M_D_DQ<37>")
	)
	(segment
		(start 280.49474 -127.49022)
		(end 280.802334 -127.797814)
		(width 0.1651)
		(layer "F.Cu")
		(net "M_D_DQ<37>")
	)
	(segment
		(start 278.53513 -126.287276)
		(end 278.813514 -126.56566)
		(width 0.1651)
		(layer "F.Cu")
		(net "M_D_DQ<37>")
	)
	(segment
		(start 278.53513 -126.078488)
		(end 278.53513 -126.287276)
		(width 0.1651)
		(layer "F.Cu")
		(net "M_D_DQ<37>")
	)
	(segment
		(start 272.791174 -106.5276)
		(end 272.791174 -112.145826)
		(width 0.1016)
		(layer "F.Cu")
		(net "M_D_DQ<37>")
	)
	(segment
		(start 280.24201 -127.49022)
		(end 280.49474 -127.49022)
		(width 0.1651)
		(layer "F.Cu")
		(net "M_D_DQ<37>")
	)
	(segment
		(start 273.645376 -101.261164)
		(end 273.469862 -101.6635)
		(width 0.0889)
		(layer "F.Cu")
		(net "M_D_DQ<37>")
	)
	(segment
		(start 273.428714 -102.747572)
		(end 273.414744 -102.77094)
		(width 0.0889)
		(layer "F.Cu")
		(net "M_D_DQ<37>")
	)
	(segment
		(start 280.802334 -127.797814)
		(end 280.802334 -128.107948)
		(width 0.1651)
		(layer "F.Cu")
		(net "M_D_DQ<37>")
	)
	(segment
		(start 273.376644 -102.824788)
		(end 272.689574 -103.511858)
		(width 0.0889)
		(layer "F.Cu")
		(net "M_D_DQ<37>")
	)
	(segment
		(start 280.898346 -129.158492)
		(end 280.898346 -129.906268)
		(width 0.1651)
		(layer "F.Cu")
		(net "M_D_DQ<37>")
	)
	(segment
		(start 280.450036 -128.710182)
		(end 280.898346 -129.158492)
		(width 0.1651)
		(layer "F.Cu")
		(net "M_D_DQ<37>")
	)
	(segment
		(start 280.017728 -127.714502)
		(end 280.24201 -127.49022)
		(width 0.1651)
		(layer "F.Cu")
		(net "M_D_DQ<37>")
	)
	(via
		(at 280.473658 -130.330956)
		(size 0.508)
		(drill 0.254)
		(layers "F.Cu" "B.Cu")
		(net "M_D_DQ<37>")
	)
	(via
		(at 279.699974 -134.340346)
		(size 0.508)
		(drill 0.254)
		(layers "F.Cu" "B.Cu")
		(net "M_D_DQ<37>")
	)
	(arc
		(start 273.469862 -101.6635)
		(mid 273.448644 -101.716725)
		(end 273.422364 -101.76764)
		(width 0.0889)
		(layer "F.Cu")
		(net "M_D_DQ<37>")
	)
	(arc
		(start 273.417538 -101.776276)
		(mid 273.368783 -101.972628)
		(end 273.422364 -102.16769)
		(width 0.0889)
		(layer "F.Cu")
		(net "M_D_DQ<37>")
	)
	(arc
		(start 273.422364 -102.16769)
		(mid 273.501586 -102.456808)
		(end 273.428714 -102.747572)
		(width 0.0889)
		(layer "F.Cu")
		(net "M_D_DQ<37>")
	)
	(segment
		(start 280.549858 -128.276096)
		(end 280.549858 -130.254756)
		(width 0.1651)
		(layer "B.Cu")
		(net "M_D_DQ<37>")
	)
	(segment
		(start 280.550366 -128.276096)
		(end 280.549858 -128.276096)
		(width 0.1651)
		(layer "B.Cu")
		(net "M_D_DQ<37>")
	)
	(segment
		(start 280.549858 -130.254756)
		(end 280.473658 -130.330956)
		(width 0.1651)
		(layer "B.Cu")
		(net "M_D_DQ<37>")
	)
	(segment
		(start 280.150062 -131.445)
		(end 280.023062 -131.318)
		(width 0.14224)
		(layer "In2.Cu")
		(net "M_D_DQ<37>")
	)
	(segment
		(start 280.124662 -134.187946)
		(end 280.124662 -133.959854)
		(width 0.14224)
		(layer "In2.Cu")
		(net "M_D_DQ<37>")
	)
	(segment
		(start 280.023062 -130.7592)
		(end 280.451306 -130.330956)
		(width 0.14224)
		(layer "In2.Cu")
		(net "M_D_DQ<37>")
	)
	(segment
		(start 280.099262 -133.146546)
		(end 280.099262 -132.791454)
		(width 0.14224)
		(layer "In2.Cu")
		(net "M_D_DQ<37>")
	)
	(segment
		(start 279.861264 -132.553456)
		(end 279.861264 -132.216144)
		(width 0.14224)
		(layer "In2.Cu")
		(net "M_D_DQ<37>")
	)
	(segment
		(start 279.972262 -134.340346)
		(end 280.124662 -134.187946)
		(width 0.14224)
		(layer "In2.Cu")
		(net "M_D_DQ<37>")
	)
	(segment
		(start 279.699974 -134.340346)
		(end 279.972262 -134.340346)
		(width 0.14224)
		(layer "In2.Cu")
		(net "M_D_DQ<37>")
	)
	(segment
		(start 280.023062 -131.318)
		(end 280.023062 -130.7592)
		(width 0.14224)
		(layer "In2.Cu")
		(net "M_D_DQ<37>")
	)
	(segment
		(start 280.451306 -130.330956)
		(end 280.473658 -130.330956)
		(width 0.14224)
		(layer "In2.Cu")
		(net "M_D_DQ<37>")
	)
	(segment
		(start 280.099262 -132.791454)
		(end 279.861264 -132.553456)
		(width 0.14224)
		(layer "In2.Cu")
		(net "M_D_DQ<37>")
	)
	(segment
		(start 279.861264 -133.696456)
		(end 279.861264 -133.384544)
		(width 0.14224)
		(layer "In2.Cu")
		(net "M_D_DQ<37>")
	)
	(segment
		(start 280.150062 -131.927346)
		(end 280.150062 -131.445)
		(width 0.14224)
		(layer "In2.Cu")
		(net "M_D_DQ<37>")
	)
	(segment
		(start 279.861264 -132.216144)
		(end 280.150062 -131.927346)
		(width 0.14224)
		(layer "In2.Cu")
		(net "M_D_DQ<37>")
	)
	(segment
		(start 280.124662 -133.959854)
		(end 279.861264 -133.696456)
		(width 0.14224)
		(layer "In2.Cu")
		(net "M_D_DQ<37>")
	)
	(segment
		(start 279.861264 -133.384544)
		(end 280.099262 -133.146546)
		(width 0.14224)
		(layer "In2.Cu")
		(net "M_D_DQ<37>")
	)
	(segment
		(start 273.238976 -102.68712)
		(end 272.499074 -103.427022)
		(width 0.0889)
		(layer "F.Cu")
		(net "M_D_DQ<36>")
	)
	(segment
		(start 272.397474 -111.904526)
		(end 271.653 -112.649)
		(width 0.1016)
		(layer "F.Cu")
		(net "M_D_DQ<36>")
	)
	(segment
		(start 273.805396 -100.386134)
		(end 273.751548 -100.386134)
		(width 0.0889)
		(layer "F.Cu")
		(net "M_D_DQ<36>")
	)
	(segment
		(start 280.549858 -137.67054)
		(end 280.549858 -136.345168)
		(width 0.1651)
		(layer "F.Cu")
		(net "M_D_DQ<36>")
	)
	(segment
		(start 274.627848 -100.481638)
		(end 273.805396 -100.386134)
		(width 0.0889)
		(layer "F.Cu")
		(net "M_D_DQ<36>")
	)
	(segment
		(start 277.7998 -126.5936)
		(end 279.5524 -128.3462)
		(width 0.1651)
		(layer "F.Cu")
		(net "M_D_DQ<36>")
	)
	(segment
		(start 272.499074 -106.426)
		(end 272.397474 -106.5276)
		(width 0.0889)
		(layer "F.Cu")
		(net "M_D_DQ<36>")
	)
	(segment
		(start 272.397474 -106.5276)
		(end 272.397474 -111.904526)
		(width 0.1016)
		(layer "F.Cu")
		(net "M_D_DQ<36>")
	)
	(segment
		(start 280.200862 -129.401062)
		(end 280.200862 -129.780538)
		(width 0.1651)
		(layer "F.Cu")
		(net "M_D_DQ<36>")
	)
	(segment
		(start 273.26209 -102.654354)
		(end 273.254978 -102.667054)
		(width 0.0889)
		(layer "F.Cu")
		(net "M_D_DQ<36>")
	)
	(segment
		(start 280.550366 -137.67054)
		(end 280.549858 -137.67054)
		(width 0.1651)
		(layer "F.Cu")
		(net "M_D_DQ<36>")
	)
	(segment
		(start 271.653 -112.649)
		(end 271.653 -115.7478)
		(width 0.1651)
		(layer "F.Cu")
		(net "M_D_DQ<36>")
	)
	(segment
		(start 279.9334 -130.048)
		(end 279.9334 -131.378452)
		(width 0.1651)
		(layer "F.Cu")
		(net "M_D_DQ<36>")
	)
	(segment
		(start 272.499074 -103.427022)
		(end 272.499074 -106.426)
		(width 0.0889)
		(layer "F.Cu")
		(net "M_D_DQ<36>")
	)
	(segment
		(start 279.9334 -131.378452)
		(end 279.699974 -131.611878)
		(width 0.1651)
		(layer "F.Cu")
		(net "M_D_DQ<36>")
	)
	(segment
		(start 271.653 -115.7478)
		(end 272.4658 -116.5606)
		(width 0.1651)
		(layer "F.Cu")
		(net "M_D_DQ<36>")
	)
	(segment
		(start 280.200862 -129.780538)
		(end 279.9334 -130.048)
		(width 0.1651)
		(layer "F.Cu")
		(net "M_D_DQ<36>")
	)
	(segment
		(start 277.7998 -125.448568)
		(end 277.7998 -126.5936)
		(width 0.1651)
		(layer "F.Cu")
		(net "M_D_DQ<36>")
	)
	(segment
		(start 273.257518 -101.272086)
		(end 273.262344 -101.280722)
		(width 0.0889)
		(layer "F.Cu")
		(net "M_D_DQ<36>")
	)
	(segment
		(start 279.5524 -128.3462)
		(end 279.5524 -128.7526)
		(width 0.1651)
		(layer "F.Cu")
		(net "M_D_DQ<36>")
	)
	(segment
		(start 272.4658 -120.114568)
		(end 277.7998 -125.448568)
		(width 0.1651)
		(layer "F.Cu")
		(net "M_D_DQ<36>")
	)
	(segment
		(start 279.5524 -128.7526)
		(end 280.200862 -129.401062)
		(width 0.1651)
		(layer "F.Cu")
		(net "M_D_DQ<36>")
	)
	(segment
		(start 272.4658 -116.5606)
		(end 272.4658 -120.114568)
		(width 0.1651)
		(layer "F.Cu")
		(net "M_D_DQ<36>")
	)
	(segment
		(start 280.549858 -136.345168)
		(end 280.451814 -135.8138)
		(width 0.1651)
		(layer "F.Cu")
		(net "M_D_DQ<36>")
	)
	(via
		(at 279.699974 -131.611878)
		(size 0.508)
		(drill 0.254)
		(layers "F.Cu" "B.Cu")
		(net "M_D_DQ<36>")
	)
	(via
		(at 280.451814 -135.8138)
		(size 0.508)
		(drill 0.254)
		(layers "F.Cu" "B.Cu")
		(net "M_D_DQ<36>")
	)
	(arc
		(start 273.751548 -100.386134)
		(mid 273.253297 -100.688974)
		(end 273.257518 -101.272086)
		(width 0.0889)
		(layer "F.Cu")
		(net "M_D_DQ<36>")
	)
	(arc
		(start 273.254978 -102.667054)
		(mid 273.247718 -102.677679)
		(end 273.238976 -102.68712)
		(width 0.0889)
		(layer "F.Cu")
		(net "M_D_DQ<36>")
	)
	(arc
		(start 273.257264 -102.26294)
		(mid 273.310734 -102.458003)
		(end 273.26209 -102.654354)
		(width 0.0889)
		(layer "F.Cu")
		(net "M_D_DQ<36>")
	)
	(arc
		(start 273.287236 -101.608382)
		(mid 273.273725 -101.640952)
		(end 273.257264 -101.672136)
		(width 0.0889)
		(layer "F.Cu")
		(net "M_D_DQ<36>")
	)
	(arc
		(start 273.257264 -101.672136)
		(mid 273.178133 -101.967538)
		(end 273.257264 -102.26294)
		(width 0.0889)
		(layer "F.Cu")
		(net "M_D_DQ<36>")
	)
	(arc
		(start 273.262344 -101.280722)
		(mid 273.309975 -101.441882)
		(end 273.287236 -101.608382)
		(width 0.0889)
		(layer "F.Cu")
		(net "M_D_DQ<36>")
	)
	(segment
		(start 279.699974 -132.875782)
		(end 279.699974 -131.611878)
		(width 0.1651)
		(layer "B.Cu")
		(net "M_D_DQ<36>")
	)
	(segment
		(start 279.700482 -132.876036)
		(end 279.699974 -132.875782)
		(width 0.1651)
		(layer "B.Cu")
		(net "M_D_DQ<36>")
	)
	(segment
		(start 279.424892 -134.736078)
		(end 279.266904 -134.57809)
		(width 0.14224)
		(layer "In2.Cu")
		(net "M_D_DQ<36>")
	)
	(segment
		(start 280.200862 -135.8138)
		(end 279.424892 -135.03783)
		(width 0.14224)
		(layer "In2.Cu")
		(net "M_D_DQ<36>")
	)
	(segment
		(start 279.266904 -132.044948)
		(end 279.699974 -131.611878)
		(width 0.14224)
		(layer "In2.Cu")
		(net "M_D_DQ<36>")
	)
	(segment
		(start 279.424892 -135.03783)
		(end 279.424892 -134.736078)
		(width 0.14224)
		(layer "In2.Cu")
		(net "M_D_DQ<36>")
	)
	(segment
		(start 279.266904 -134.57809)
		(end 279.266904 -132.044948)
		(width 0.14224)
		(layer "In2.Cu")
		(net "M_D_DQ<36>")
	)
	(segment
		(start 280.451814 -135.8138)
		(end 280.200862 -135.8138)
		(width 0.14224)
		(layer "In2.Cu")
		(net "M_D_DQ<36>")
	)
	(segment
		(start 277.203154 -101.635814)
		(end 277.139654 -101.572314)
		(width 0.0889)
		(layer "F.Cu")
		(net "M_D_DQ<35>")
	)
	(segment
		(start 289.013646 -128.439926)
		(end 289.247326 -128.439926)
		(width 0.1651)
		(layer "F.Cu")
		(net "M_D_DQ<35>")
	)
	(segment
		(start 276.856444 -102.167436)
		(end 276.862794 -102.178104)
		(width 0.0889)
		(layer "F.Cu")
		(net "M_D_DQ<35>")
	)
	(segment
		(start 288.379916 -128.871726)
		(end 288.581846 -128.871726)
		(width 0.1651)
		(layer "F.Cu")
		(net "M_D_DQ<35>")
	)
	(segment
		(start 289.247326 -128.439926)
		(end 289.5854 -128.778)
		(width 0.1651)
		(layer "F.Cu")
		(net "M_D_DQ<35>")
	)
	(segment
		(start 276.851618 -102.1588)
		(end 276.856444 -102.167436)
		(width 0.0889)
		(layer "F.Cu")
		(net "M_D_DQ<35>")
	)
	(segment
		(start 276.626574 -106.54792)
		(end 276.728174 -106.64952)
		(width 0.0889)
		(layer "F.Cu")
		(net "M_D_DQ<35>")
	)
	(segment
		(start 287.350454 -133.0706)
		(end 287.349946 -133.076442)
		(width 0.1651)
		(layer "F.Cu")
		(net "M_D_DQ<35>")
	)
	(segment
		(start 289.5854 -129.7686)
		(end 289.023044 -130.330956)
		(width 0.1651)
		(layer "F.Cu")
		(net "M_D_DQ<35>")
	)
	(segment
		(start 280.3906 -116.730272)
		(end 288.163 -124.502672)
		(width 0.1651)
		(layer "F.Cu")
		(net "M_D_DQ<35>")
	)
	(segment
		(start 277.0378 -111.9886)
		(end 278.2824 -111.9886)
		(width 0.1651)
		(layer "F.Cu")
		(net "M_D_DQ<35>")
	)
	(segment
		(start 276.728174 -106.64952)
		(end 276.728174 -111.678974)
		(width 0.1016)
		(layer "F.Cu")
		(net "M_D_DQ<35>")
	)
	(segment
		(start 277.287228 -105.617772)
		(end 276.626574 -106.278426)
		(width 0.0889)
		(layer "F.Cu")
		(net "M_D_DQ<35>")
	)
	(segment
		(start 276.856444 -103.18369)
		(end 277.287228 -103.92918)
		(width 0.0889)
		(layer "F.Cu")
		(net "M_D_DQ<35>")
	)
	(segment
		(start 289.023044 -130.330956)
		(end 288.19983 -130.330956)
		(width 0.1651)
		(layer "F.Cu")
		(net "M_D_DQ<35>")
	)
	(segment
		(start 288.581846 -128.871726)
		(end 289.013646 -128.439926)
		(width 0.1651)
		(layer "F.Cu")
		(net "M_D_DQ<35>")
	)
	(segment
		(start 277.287228 -103.92918)
		(end 277.287228 -105.617772)
		(width 0.0889)
		(layer "F.Cu")
		(net "M_D_DQ<35>")
	)
	(segment
		(start 289.5854 -128.778)
		(end 289.5854 -129.7686)
		(width 0.1651)
		(layer "F.Cu")
		(net "M_D_DQ<35>")
	)
	(segment
		(start 288.163 -124.502672)
		(end 288.163 -127.3556)
		(width 0.1651)
		(layer "F.Cu")
		(net "M_D_DQ<35>")
	)
	(segment
		(start 288.431478 -127.624078)
		(end 288.431478 -127.857758)
		(width 0.1651)
		(layer "F.Cu")
		(net "M_D_DQ<35>")
	)
	(segment
		(start 277.203154 -101.967538)
		(end 277.203154 -101.635814)
		(width 0.0889)
		(layer "F.Cu")
		(net "M_D_DQ<35>")
	)
	(segment
		(start 288.031428 -128.257808)
		(end 288.031428 -128.523238)
		(width 0.1651)
		(layer "F.Cu")
		(net "M_D_DQ<35>")
	)
	(segment
		(start 278.2824 -111.9886)
		(end 280.3906 -114.0968)
		(width 0.1651)
		(layer "F.Cu")
		(net "M_D_DQ<35>")
	)
	(segment
		(start 287.349946 -133.076442)
		(end 287.349946 -134.340346)
		(width 0.1651)
		(layer "F.Cu")
		(net "M_D_DQ<35>")
	)
	(segment
		(start 288.031428 -128.523238)
		(end 288.379916 -128.871726)
		(width 0.1651)
		(layer "F.Cu")
		(net "M_D_DQ<35>")
	)
	(segment
		(start 276.626574 -106.278426)
		(end 276.626574 -106.54792)
		(width 0.0889)
		(layer "F.Cu")
		(net "M_D_DQ<35>")
	)
	(segment
		(start 280.3906 -114.0968)
		(end 280.3906 -116.730272)
		(width 0.1651)
		(layer "F.Cu")
		(net "M_D_DQ<35>")
	)
	(segment
		(start 288.431478 -127.857758)
		(end 288.031428 -128.257808)
		(width 0.1651)
		(layer "F.Cu")
		(net "M_D_DQ<35>")
	)
	(segment
		(start 276.728174 -111.678974)
		(end 277.0378 -111.9886)
		(width 0.1016)
		(layer "F.Cu")
		(net "M_D_DQ<35>")
	)
	(segment
		(start 288.163 -127.3556)
		(end 288.431478 -127.624078)
		(width 0.1651)
		(layer "F.Cu")
		(net "M_D_DQ<35>")
	)
	(via
		(at 287.349946 -134.340346)
		(size 0.508)
		(drill 0.254)
		(layers "F.Cu" "B.Cu")
		(net "M_D_DQ<35>")
	)
	(via
		(at 288.19983 -130.330956)
		(size 0.508)
		(drill 0.254)
		(layers "F.Cu" "B.Cu")
		(net "M_D_DQ<35>")
	)
	(arc
		(start 276.856444 -102.757986)
		(mid 276.799429 -102.970838)
		(end 276.856444 -103.18369)
		(width 0.0889)
		(layer "F.Cu")
		(net "M_D_DQ<35>")
	)
	(arc
		(start 277.139654 -101.572314)
		(mid 276.843869 -101.791048)
		(end 276.851618 -102.1588)
		(width 0.0889)
		(layer "F.Cu")
		(net "M_D_DQ<35>")
	)
	(arc
		(start 276.862794 -102.178104)
		(mid 276.935592 -102.468867)
		(end 276.856444 -102.757986)
		(width 0.0889)
		(layer "F.Cu")
		(net "M_D_DQ<35>")
	)
	(segment
		(start 288.19983 -130.330956)
		(end 288.19983 -128.276096)
		(width 0.1651)
		(layer "B.Cu")
		(net "M_D_DQ<35>")
	)
	(segment
		(start 288.19983 -128.276096)
		(end 288.200338 -128.276096)
		(width 0.1651)
		(layer "B.Cu")
		(net "M_D_DQ<35>")
	)
	(segment
		(start 287.768284 -132.715)
		(end 287.511236 -132.457952)
		(width 0.14224)
		(layer "In2.Cu")
		(net "M_D_DQ<35>")
	)
	(segment
		(start 287.511236 -132.457952)
		(end 287.511236 -132.184648)
		(width 0.14224)
		(layer "In2.Cu")
		(net "M_D_DQ<35>")
	)
	(segment
		(start 287.511236 -133.276848)
		(end 287.768284 -133.0198)
		(width 0.14224)
		(layer "In2.Cu")
		(net "M_D_DQ<35>")
	)
	(segment
		(start 287.800034 -133.83895)
		(end 287.511236 -133.550152)
		(width 0.14224)
		(layer "In2.Cu")
		(net "M_D_DQ<35>")
	)
	(segment
		(start 287.349946 -134.340346)
		(end 287.622234 -134.340346)
		(width 0.14224)
		(layer "In2.Cu")
		(net "M_D_DQ<35>")
	)
	(segment
		(start 287.793684 -131.233418)
		(end 287.749234 -131.188968)
		(width 0.14224)
		(layer "In2.Cu")
		(net "M_D_DQ<35>")
	)
	(segment
		(start 287.793684 -131.9022)
		(end 287.793684 -131.233418)
		(width 0.14224)
		(layer "In2.Cu")
		(net "M_D_DQ<35>")
	)
	(segment
		(start 287.768284 -133.0198)
		(end 287.768284 -132.715)
		(width 0.14224)
		(layer "In2.Cu")
		(net "M_D_DQ<35>")
	)
	(segment
		(start 287.749234 -130.7592)
		(end 288.177478 -130.330956)
		(width 0.14224)
		(layer "In2.Cu")
		(net "M_D_DQ<35>")
	)
	(segment
		(start 287.622234 -134.340346)
		(end 287.800034 -134.162546)
		(width 0.14224)
		(layer "In2.Cu")
		(net "M_D_DQ<35>")
	)
	(segment
		(start 288.177478 -130.330956)
		(end 288.19983 -130.330956)
		(width 0.14224)
		(layer "In2.Cu")
		(net "M_D_DQ<35>")
	)
	(segment
		(start 287.749234 -131.188968)
		(end 287.749234 -130.7592)
		(width 0.14224)
		(layer "In2.Cu")
		(net "M_D_DQ<35>")
	)
	(segment
		(start 287.511236 -132.184648)
		(end 287.793684 -131.9022)
		(width 0.14224)
		(layer "In2.Cu")
		(net "M_D_DQ<35>")
	)
	(segment
		(start 287.511236 -133.550152)
		(end 287.511236 -133.276848)
		(width 0.14224)
		(layer "In2.Cu")
		(net "M_D_DQ<35>")
	)
	(segment
		(start 287.800034 -134.162546)
		(end 287.800034 -133.83895)
		(width 0.14224)
		(layer "In2.Cu")
		(net "M_D_DQ<35>")
	)
	(segment
		(start 286.742632 -124.036836)
		(end 286.494728 -124.036836)
		(width 0.1651)
		(layer "F.Cu")
		(net "M_D_DQ<34>")
	)
	(segment
		(start 288.331402 -136.54786)
		(end 288.19983 -136.679432)
		(width 0.1651)
		(layer "F.Cu")
		(net "M_D_DQ<34>")
	)
	(segment
		(start 277.088854 -112.649)
		(end 276.334474 -111.89462)
		(width 0.1016)
		(layer "F.Cu")
		(net "M_D_DQ<34>")
	)
	(segment
		(start 276.436074 -106.544872)
		(end 276.436074 -106.172254)
		(width 0.0889)
		(layer "F.Cu")
		(net "M_D_DQ<34>")
	)
	(segment
		(start 287.02 -131.281932)
		(end 287.02 -130.8354)
		(width 0.1651)
		(layer "F.Cu")
		(net "M_D_DQ<34>")
	)
	(segment
		(start 288.0233 -129.8321)
		(end 288.0233 -129.488184)
		(width 0.1651)
		(layer "F.Cu")
		(net "M_D_DQ<34>")
	)
	(segment
		(start 287.02 -130.8354)
		(end 288.0233 -129.8321)
		(width 0.1651)
		(layer "F.Cu")
		(net "M_D_DQ<34>")
	)
	(segment
		(start 288.19983 -135.9154)
		(end 288.19983 -136.192768)
		(width 0.1651)
		(layer "F.Cu")
		(net "M_D_DQ<34>")
	)
	(segment
		(start 286.494728 -124.036836)
		(end 286.136842 -124.394722)
		(width 0.1651)
		(layer "F.Cu")
		(net "M_D_DQ<34>")
	)
	(segment
		(start 285.901384 -124.394722)
		(end 285.665926 -124.159264)
		(width 0.1651)
		(layer "F.Cu")
		(net "M_D_DQ<34>")
	)
	(segment
		(start 285.665926 -123.898914)
		(end 286.011366 -123.553474)
		(width 0.1651)
		(layer "F.Cu")
		(net "M_D_DQ<34>")
	)
	(segment
		(start 276.436074 -106.172254)
		(end 277.096728 -105.5116)
		(width 0.0889)
		(layer "F.Cu")
		(net "M_D_DQ<34>")
	)
	(segment
		(start 276.69617 -102.271322)
		(end 276.691344 -102.262686)
		(width 0.0889)
		(layer "F.Cu")
		(net "M_D_DQ<34>")
	)
	(segment
		(start 285.665926 -124.159264)
		(end 285.665926 -123.898914)
		(width 0.1651)
		(layer "F.Cu")
		(net "M_D_DQ<34>")
	)
	(segment
		(start 288.19983 -137.67054)
		(end 288.200338 -137.67054)
		(width 0.1651)
		(layer "F.Cu")
		(net "M_D_DQ<34>")
	)
	(segment
		(start 276.334474 -106.646472)
		(end 276.436074 -106.544872)
		(width 0.0889)
		(layer "F.Cu")
		(net "M_D_DQ<34>")
	)
	(segment
		(start 286.011366 -123.30557)
		(end 279.654 -116.948204)
		(width 0.1651)
		(layer "F.Cu")
		(net "M_D_DQ<34>")
	)
	(segment
		(start 276.691344 -102.262686)
		(end 276.684994 -102.252018)
		(width 0.0889)
		(layer "F.Cu")
		(net "M_D_DQ<34>")
	)
	(segment
		(start 277.13051 -101.381052)
		(end 277.203154 -101.308408)
		(width 0.0889)
		(layer "F.Cu")
		(net "M_D_DQ<34>")
	)
	(segment
		(start 287.4772 -124.771404)
		(end 286.742632 -124.036836)
		(width 0.1651)
		(layer "F.Cu")
		(net "M_D_DQ<34>")
	)
	(segment
		(start 288.19983 -136.192768)
		(end 288.331402 -136.32434)
		(width 0.1651)
		(layer "F.Cu")
		(net "M_D_DQ<34>")
	)
	(segment
		(start 277.203154 -101.308408)
		(end 277.203154 -100.976684)
		(width 0.0889)
		(layer "F.Cu")
		(net "M_D_DQ<34>")
	)
	(segment
		(start 279.654 -116.948204)
		(end 279.654 -114.4016)
		(width 0.1651)
		(layer "F.Cu")
		(net "M_D_DQ<34>")
	)
	(segment
		(start 277.096728 -105.5116)
		(end 277.096728 -103.979726)
		(width 0.0889)
		(layer "F.Cu")
		(net "M_D_DQ<34>")
	)
	(segment
		(start 286.136842 -124.394722)
		(end 285.901384 -124.394722)
		(width 0.1651)
		(layer "F.Cu")
		(net "M_D_DQ<34>")
	)
	(segment
		(start 287.4772 -128.942084)
		(end 287.4772 -124.771404)
		(width 0.1651)
		(layer "F.Cu")
		(net "M_D_DQ<34>")
	)
	(segment
		(start 277.096474 -103.978964)
		(end 276.691344 -103.278178)
		(width 0.0889)
		(layer "F.Cu")
		(net "M_D_DQ<34>")
	)
	(segment
		(start 277.096728 -103.979726)
		(end 277.096474 -103.979218)
		(width 0.0889)
		(layer "F.Cu")
		(net "M_D_DQ<34>")
	)
	(segment
		(start 288.0233 -129.488184)
		(end 287.4772 -128.942084)
		(width 0.1651)
		(layer "F.Cu")
		(net "M_D_DQ<34>")
	)
	(segment
		(start 288.331402 -136.32434)
		(end 288.331402 -136.54786)
		(width 0.1651)
		(layer "F.Cu")
		(net "M_D_DQ<34>")
	)
	(segment
		(start 277.9014 -112.649)
		(end 277.088854 -112.649)
		(width 0.1651)
		(layer "F.Cu")
		(net "M_D_DQ<34>")
	)
	(segment
		(start 286.011366 -123.553474)
		(end 286.011366 -123.30557)
		(width 0.1651)
		(layer "F.Cu")
		(net "M_D_DQ<34>")
	)
	(segment
		(start 277.096474 -103.979218)
		(end 277.096474 -103.978964)
		(width 0.0889)
		(layer "F.Cu")
		(net "M_D_DQ<34>")
	)
	(segment
		(start 279.654 -114.4016)
		(end 277.9014 -112.649)
		(width 0.1651)
		(layer "F.Cu")
		(net "M_D_DQ<34>")
	)
	(segment
		(start 287.349946 -131.611878)
		(end 287.02 -131.281932)
		(width 0.1651)
		(layer "F.Cu")
		(net "M_D_DQ<34>")
	)
	(segment
		(start 276.334474 -111.89462)
		(end 276.334474 -106.646472)
		(width 0.1016)
		(layer "F.Cu")
		(net "M_D_DQ<34>")
	)
	(segment
		(start 288.19983 -136.679432)
		(end 288.19983 -137.67054)
		(width 0.1651)
		(layer "F.Cu")
		(net "M_D_DQ<34>")
	)
	(via
		(at 287.349946 -131.611878)
		(size 0.508)
		(drill 0.254)
		(layers "F.Cu" "B.Cu")
		(net "M_D_DQ<34>")
	)
	(via
		(at 288.19983 -135.9154)
		(size 0.508)
		(drill 0.254)
		(layers "F.Cu" "B.Cu")
		(net "M_D_DQ<34>")
	)
	(arc
		(start 276.691344 -102.662736)
		(mid 276.744814 -102.467673)
		(end 276.69617 -102.271322)
		(width 0.0889)
		(layer "F.Cu")
		(net "M_D_DQ<34>")
	)
	(arc
		(start 276.691344 -103.278178)
		(mid 276.608941 -102.970474)
		(end 276.691344 -102.662736)
		(width 0.0889)
		(layer "F.Cu")
		(net "M_D_DQ<34>")
	)
	(arc
		(start 276.684994 -102.252018)
		(mid 276.676868 -101.698389)
		(end 277.13051 -101.381052)
		(width 0.0889)
		(layer "F.Cu")
		(net "M_D_DQ<34>")
	)
	(segment
		(start 287.350454 -132.876036)
		(end 287.349946 -132.875782)
		(width 0.1651)
		(layer "B.Cu")
		(net "M_D_DQ<34>")
	)
	(segment
		(start 287.349946 -132.875782)
		(end 287.349946 -131.611878)
		(width 0.1651)
		(layer "B.Cu")
		(net "M_D_DQ<34>")
	)
	(segment
		(start 286.916876 -132.044948)
		(end 287.349946 -131.611878)
		(width 0.14224)
		(layer "In2.Cu")
		(net "M_D_DQ<34>")
	)
	(segment
		(start 286.916876 -134.632446)
		(end 286.916876 -132.044948)
		(width 0.14224)
		(layer "In2.Cu")
		(net "M_D_DQ<34>")
	)
	(segment
		(start 288.19983 -135.9154)
		(end 286.916876 -134.632446)
		(width 0.14224)
		(layer "In2.Cu")
		(net "M_D_DQ<34>")
	)
	(segment
		(start 275.099272 -119.101108)
		(end 275.296376 -119.298212)
		(width 0.1651)
		(layer "F.Cu")
		(net "M_D_DQ<33>")
	)
	(segment
		(start 277.00859 -121.274332)
		(end 277.357078 -121.62282)
		(width 0.1651)
		(layer "F.Cu")
		(net "M_D_DQ<33>")
	)
	(segment
		(start 278.52116 -123.046744)
		(end 278.434292 -123.133612)
		(width 0.1651)
		(layer "F.Cu")
		(net "M_D_DQ<33>")
	)
	(segment
		(start 275.099272 -117.754908)
		(end 275.296376 -117.952012)
		(width 0.1651)
		(layer "F.Cu")
		(net "M_D_DQ<33>")
	)
	(segment
		(start 273.476974 -106.4514)
		(end 273.578574 -106.553)
		(width 0.0889)
		(layer "F.Cu")
		(net "M_D_DQ<33>")
	)
	(segment
		(start 275.099272 -118.428008)
		(end 274.644104 -118.428008)
		(width 0.1651)
		(layer "F.Cu")
		(net "M_D_DQ<33>")
	)
	(segment
		(start 275.296376 -116.527834)
		(end 275.296376 -116.884704)
		(width 0.1651)
		(layer "F.Cu")
		(net "M_D_DQ<33>")
	)
	(segment
		(start 275.296376 -116.884704)
		(end 275.099272 -117.081808)
		(width 0.1651)
		(layer "F.Cu")
		(net "M_D_DQ<33>")
	)
	(segment
		(start 277.269956 -121.969276)
		(end 277.269956 -122.202956)
		(width 0.1651)
		(layer "F.Cu")
		(net "M_D_DQ<33>")
	)
	(segment
		(start 276.211792 -120.698768)
		(end 276.10562 -120.80494)
		(width 0.1651)
		(layer "F.Cu")
		(net "M_D_DQ<33>")
	)
	(segment
		(start 275.296376 -117.952012)
		(end 275.296376 -118.230904)
		(width 0.1651)
		(layer "F.Cu")
		(net "M_D_DQ<33>")
	)
	(segment
		(start 276.10562 -120.80494)
		(end 276.10562 -121.03862)
		(width 0.1651)
		(layer "F.Cu")
		(net "M_D_DQ<33>")
	)
	(segment
		(start 275.461476 -120.12295)
		(end 275.863304 -120.12295)
		(width 0.1651)
		(layer "F.Cu")
		(net "M_D_DQ<33>")
	)
	(segment
		(start 279.01646 -123.71578)
		(end 279.084278 -123.647962)
		(width 0.1651)
		(layer "F.Cu")
		(net "M_D_DQ<33>")
	)
	(segment
		(start 277.357078 -121.62282)
		(end 277.357078 -121.882154)
		(width 0.1651)
		(layer "F.Cu")
		(net "M_D_DQ<33>")
	)
	(segment
		(start 274.644104 -118.428008)
		(end 274.447 -118.625112)
		(width 0.1651)
		(layer "F.Cu")
		(net "M_D_DQ<33>")
	)
	(segment
		(start 275.863304 -120.12295)
		(end 276.211792 -120.471438)
		(width 0.1651)
		(layer "F.Cu")
		(net "M_D_DQ<33>")
	)
	(segment
		(start 279.317958 -123.647962)
		(end 282.4734 -126.803404)
		(width 0.1651)
		(layer "F.Cu")
		(net "M_D_DQ<33>")
	)
	(segment
		(start 275.296376 -119.95785)
		(end 275.461476 -120.12295)
		(width 0.1651)
		(layer "F.Cu")
		(net "M_D_DQ<33>")
	)
	(segment
		(start 282.579064 -129.332736)
		(end 282.579064 -130.094736)
		(width 0.1651)
		(layer "F.Cu")
		(net "M_D_DQ<33>")
	)
	(segment
		(start 282.4734 -126.803404)
		(end 282.4734 -127.616458)
		(width 0.1651)
		(layer "F.Cu")
		(net "M_D_DQ<33>")
	)
	(segment
		(start 274.627848 -102.462584)
		(end 274.372578 -102.717854)
		(width 0.0889)
		(layer "F.Cu")
		(net "M_D_DQ<33>")
	)
	(segment
		(start 282.436062 -129.189734)
		(end 282.579064 -129.332736)
		(width 0.1651)
		(layer "F.Cu")
		(net "M_D_DQ<33>")
	)
	(segment
		(start 282.342844 -130.330956)
		(end 282.07208 -130.330956)
		(width 0.1651)
		(layer "F.Cu")
		(net "M_D_DQ<33>")
	)
	(segment
		(start 282.8417 -128.604518)
		(end 282.6385 -128.604518)
		(width 0.1651)
		(layer "F.Cu")
		(net "M_D_DQ<33>")
	)
	(segment
		(start 273.578574 -114.810032)
		(end 275.296376 -116.527834)
		(width 0.1651)
		(layer "F.Cu")
		(net "M_D_DQ<33>")
	)
	(segment
		(start 278.434292 -123.367292)
		(end 278.78278 -123.71578)
		(width 0.1651)
		(layer "F.Cu")
		(net "M_D_DQ<33>")
	)
	(segment
		(start 281.399996 -133.076442)
		(end 281.399996 -134.340346)
		(width 0.1651)
		(layer "F.Cu")
		(net "M_D_DQ<33>")
	)
	(segment
		(start 274.447 -118.904004)
		(end 274.644104 -119.101108)
		(width 0.1651)
		(layer "F.Cu")
		(net "M_D_DQ<33>")
	)
	(segment
		(start 276.10562 -121.03862)
		(end 276.454108 -121.387108)
		(width 0.1651)
		(layer "F.Cu")
		(net "M_D_DQ<33>")
	)
	(segment
		(start 273.578574 -113.533174)
		(end 273.578574 -114.810032)
		(width 0.1651)
		(layer "F.Cu")
		(net "M_D_DQ<33>")
	)
	(segment
		(start 281.400504 -133.0706)
		(end 281.399996 -133.076442)
		(width 0.1651)
		(layer "F.Cu")
		(net "M_D_DQ<33>")
	)
	(segment
		(start 282.8417 -127.781558)
		(end 283.0068 -127.946658)
		(width 0.1651)
		(layer "F.Cu")
		(net "M_D_DQ<33>")
	)
	(segment
		(start 274.447 -117.557804)
		(end 274.644104 -117.754908)
		(width 0.1651)
		(layer "F.Cu")
		(net "M_D_DQ<33>")
	)
	(segment
		(start 278.78278 -123.71578)
		(end 279.01646 -123.71578)
		(width 0.1651)
		(layer "F.Cu")
		(net "M_D_DQ<33>")
	)
	(segment
		(start 276.454108 -121.387108)
		(end 276.687788 -121.387108)
		(width 0.1651)
		(layer "F.Cu")
		(net "M_D_DQ<33>")
	)
	(segment
		(start 283.0068 -127.946658)
		(end 283.0068 -128.439418)
		(width 0.1651)
		(layer "F.Cu")
		(net "M_D_DQ<33>")
	)
	(segment
		(start 282.4734 -127.616458)
		(end 282.6385 -127.781558)
		(width 0.1651)
		(layer "F.Cu")
		(net "M_D_DQ<33>")
	)
	(segment
		(start 274.447 -117.278912)
		(end 274.447 -117.557804)
		(width 0.1651)
		(layer "F.Cu")
		(net "M_D_DQ<33>")
	)
	(segment
		(start 274.644104 -117.081808)
		(end 274.447 -117.278912)
		(width 0.1651)
		(layer "F.Cu")
		(net "M_D_DQ<33>")
	)
	(segment
		(start 274.447 -118.625112)
		(end 274.447 -118.904004)
		(width 0.1651)
		(layer "F.Cu")
		(net "M_D_DQ<33>")
	)
	(segment
		(start 283.0068 -128.439418)
		(end 282.8417 -128.604518)
		(width 0.1651)
		(layer "F.Cu")
		(net "M_D_DQ<33>")
	)
	(segment
		(start 273.578574 -106.553)
		(end 273.578574 -113.533174)
		(width 0.1016)
		(layer "F.Cu")
		(net "M_D_DQ<33>")
	)
	(segment
		(start 278.172672 -122.438922)
		(end 278.52116 -122.78741)
		(width 0.1651)
		(layer "F.Cu")
		(net "M_D_DQ<33>")
	)
	(segment
		(start 276.211792 -120.471438)
		(end 276.211792 -120.698768)
		(width 0.1651)
		(layer "F.Cu")
		(net "M_D_DQ<33>")
	)
	(segment
		(start 277.852124 -122.551444)
		(end 277.964646 -122.438922)
		(width 0.1651)
		(layer "F.Cu")
		(net "M_D_DQ<33>")
	)
	(segment
		(start 275.296376 -118.230904)
		(end 275.099272 -118.428008)
		(width 0.1651)
		(layer "F.Cu")
		(net "M_D_DQ<33>")
	)
	(segment
		(start 275.296376 -119.298212)
		(end 275.296376 -119.95785)
		(width 0.1651)
		(layer "F.Cu")
		(net "M_D_DQ<33>")
	)
	(segment
		(start 282.579064 -130.094736)
		(end 282.342844 -130.330956)
		(width 0.1651)
		(layer "F.Cu")
		(net "M_D_DQ<33>")
	)
	(segment
		(start 274.644104 -119.101108)
		(end 275.099272 -119.101108)
		(width 0.1651)
		(layer "F.Cu")
		(net "M_D_DQ<33>")
	)
	(segment
		(start 277.269956 -122.202956)
		(end 277.618444 -122.551444)
		(width 0.1651)
		(layer "F.Cu")
		(net "M_D_DQ<33>")
	)
	(segment
		(start 274.644104 -117.754908)
		(end 275.099272 -117.754908)
		(width 0.1651)
		(layer "F.Cu")
		(net "M_D_DQ<33>")
	)
	(segment
		(start 274.372578 -102.717854)
		(end 274.372578 -103.99268)
		(width 0.0889)
		(layer "F.Cu")
		(net "M_D_DQ<33>")
	)
	(segment
		(start 277.357078 -121.882154)
		(end 277.269956 -121.969276)
		(width 0.1651)
		(layer "F.Cu")
		(net "M_D_DQ<33>")
	)
	(segment
		(start 277.618444 -122.551444)
		(end 277.852124 -122.551444)
		(width 0.1651)
		(layer "F.Cu")
		(net "M_D_DQ<33>")
	)
	(segment
		(start 278.434292 -123.133612)
		(end 278.434292 -123.367292)
		(width 0.1651)
		(layer "F.Cu")
		(net "M_D_DQ<33>")
	)
	(segment
		(start 276.687788 -121.387108)
		(end 276.800564 -121.274332)
		(width 0.1651)
		(layer "F.Cu")
		(net "M_D_DQ<33>")
	)
	(segment
		(start 277.964646 -122.438922)
		(end 278.172672 -122.438922)
		(width 0.1651)
		(layer "F.Cu")
		(net "M_D_DQ<33>")
	)
	(segment
		(start 282.6385 -127.781558)
		(end 282.8417 -127.781558)
		(width 0.1651)
		(layer "F.Cu")
		(net "M_D_DQ<33>")
	)
	(segment
		(start 282.436062 -128.806956)
		(end 282.436062 -129.189734)
		(width 0.1651)
		(layer "F.Cu")
		(net "M_D_DQ<33>")
	)
	(segment
		(start 279.084278 -123.647962)
		(end 279.317958 -123.647962)
		(width 0.1651)
		(layer "F.Cu")
		(net "M_D_DQ<33>")
	)
	(segment
		(start 276.800564 -121.274332)
		(end 277.00859 -121.274332)
		(width 0.1651)
		(layer "F.Cu")
		(net "M_D_DQ<33>")
	)
	(segment
		(start 273.476974 -104.888284)
		(end 273.476974 -106.4514)
		(width 0.0889)
		(layer "F.Cu")
		(net "M_D_DQ<33>")
	)
	(segment
		(start 278.52116 -122.78741)
		(end 278.52116 -123.046744)
		(width 0.1651)
		(layer "F.Cu")
		(net "M_D_DQ<33>")
	)
	(segment
		(start 274.372578 -103.99268)
		(end 273.476974 -104.888284)
		(width 0.0889)
		(layer "F.Cu")
		(net "M_D_DQ<33>")
	)
	(segment
		(start 282.6385 -128.604518)
		(end 282.436062 -128.806956)
		(width 0.1651)
		(layer "F.Cu")
		(net "M_D_DQ<33>")
	)
	(segment
		(start 275.099272 -117.081808)
		(end 274.644104 -117.081808)
		(width 0.1651)
		(layer "F.Cu")
		(net "M_D_DQ<33>")
	)
	(via
		(at 281.399996 -134.340346)
		(size 0.508)
		(drill 0.254)
		(layers "F.Cu" "B.Cu")
		(net "M_D_DQ<33>")
	)
	(via
		(at 282.07208 -130.330956)
		(size 0.508)
		(drill 0.254)
		(layers "F.Cu" "B.Cu")
		(net "M_D_DQ<33>")
	)
	(segment
		(start 282.24988 -128.276096)
		(end 282.24988 -129.649982)
		(width 0.1651)
		(layer "B.Cu")
		(net "M_D_DQ<33>")
	)
	(segment
		(start 282.24988 -129.649982)
		(end 282.07208 -129.827782)
		(width 0.1651)
		(layer "B.Cu")
		(net "M_D_DQ<33>")
	)
	(segment
		(start 282.250388 -128.276096)
		(end 282.24988 -128.276096)
		(width 0.1651)
		(layer "B.Cu")
		(net "M_D_DQ<33>")
	)
	(segment
		(start 282.07208 -129.827782)
		(end 282.07208 -130.330956)
		(width 0.1651)
		(layer "B.Cu")
		(net "M_D_DQ<33>")
	)
	(segment
		(start 281.621484 -131.188968)
		(end 281.621484 -130.7592)
		(width 0.14224)
		(layer "In2.Cu")
		(net "M_D_DQ<33>")
	)
	(segment
		(start 281.399996 -134.340346)
		(end 281.648916 -134.340346)
		(width 0.14224)
		(layer "In2.Cu")
		(net "M_D_DQ<33>")
	)
	(segment
		(start 281.648916 -134.340346)
		(end 281.801062 -134.1882)
		(width 0.14224)
		(layer "In2.Cu")
		(net "M_D_DQ<33>")
	)
	(segment
		(start 281.801062 -134.1882)
		(end 281.801062 -133.8834)
		(width 0.14224)
		(layer "In2.Cu")
		(net "M_D_DQ<33>")
	)
	(segment
		(start 282.049728 -130.330956)
		(end 282.07208 -130.330956)
		(width 0.14224)
		(layer "In2.Cu")
		(net "M_D_DQ<33>")
	)
	(segment
		(start 281.561286 -133.643624)
		(end 281.561286 -133.335776)
		(width 0.14224)
		(layer "In2.Cu")
		(net "M_D_DQ<33>")
	)
	(segment
		(start 281.621484 -130.7592)
		(end 282.049728 -130.330956)
		(width 0.14224)
		(layer "In2.Cu")
		(net "M_D_DQ<33>")
	)
	(segment
		(start 281.851862 -131.419346)
		(end 281.621484 -131.188968)
		(width 0.14224)
		(layer "In2.Cu")
		(net "M_D_DQ<33>")
	)
	(segment
		(start 281.561286 -132.475224)
		(end 281.561286 -132.114544)
		(width 0.14224)
		(layer "In2.Cu")
		(net "M_D_DQ<33>")
	)
	(segment
		(start 281.851862 -131.823968)
		(end 281.851862 -131.419346)
		(width 0.14224)
		(layer "In2.Cu")
		(net "M_D_DQ<33>")
	)
	(segment
		(start 281.561286 -132.114544)
		(end 281.851862 -131.823968)
		(width 0.14224)
		(layer "In2.Cu")
		(net "M_D_DQ<33>")
	)
	(segment
		(start 281.775662 -132.6896)
		(end 281.561286 -132.475224)
		(width 0.14224)
		(layer "In2.Cu")
		(net "M_D_DQ<33>")
	)
	(segment
		(start 281.801062 -133.8834)
		(end 281.561286 -133.643624)
		(width 0.14224)
		(layer "In2.Cu")
		(net "M_D_DQ<33>")
	)
	(segment
		(start 281.775662 -133.1214)
		(end 281.775662 -132.6896)
		(width 0.14224)
		(layer "In2.Cu")
		(net "M_D_DQ<33>")
	)
	(segment
		(start 281.561286 -133.335776)
		(end 281.775662 -133.1214)
		(width 0.14224)
		(layer "In2.Cu")
		(net "M_D_DQ<33>")
	)
	(segment
		(start 274.182078 -103.913432)
		(end 273.286474 -104.809036)
		(width 0.0889)
		(layer "F.Cu")
		(net "M_D_DQ<32>")
	)
	(segment
		(start 274.01393 -101.889814)
		(end 274.330922 -101.890068)
		(width 0.0889)
		(layer "F.Cu")
		(net "M_D_DQ<32>")
	)
	(segment
		(start 273.184874 -112.513872)
		(end 272.938748 -112.759998)
		(width 0.1016)
		(layer "F.Cu")
		(net "M_D_DQ<32>")
	)
	(segment
		(start 273.286474 -104.809036)
		(end 273.286474 -106.4514)
		(width 0.0889)
		(layer "F.Cu")
		(net "M_D_DQ<32>")
	)
	(segment
		(start 280.776934 -127.064262)
		(end 281.012392 -127.29972)
		(width 0.1651)
		(layer "F.Cu")
		(net "M_D_DQ<32>")
	)
	(segment
		(start 281.8638 -129.0574)
		(end 281.8638 -129.7686)
		(width 0.1651)
		(layer "F.Cu")
		(net "M_D_DQ<32>")
	)
	(segment
		(start 273.184874 -106.553)
		(end 273.184874 -112.513872)
		(width 0.1016)
		(layer "F.Cu")
		(net "M_D_DQ<32>")
	)
	(segment
		(start 274.182078 -102.359206)
		(end 274.182078 -103.913432)
		(width 0.0889)
		(layer "F.Cu")
		(net "M_D_DQ<32>")
	)
	(segment
		(start 272.938748 -112.759998)
		(end 272.938748 -115.128802)
		(width 0.1651)
		(layer "F.Cu")
		(net "M_D_DQ<32>")
	)
	(segment
		(start 281.9908 -127.275336)
		(end 281.9908 -127.635)
		(width 0.1651)
		(layer "F.Cu")
		(net "M_D_DQ<32>")
	)
	(segment
		(start 281.8638 -129.7686)
		(end 280.9494 -130.683)
		(width 0.1651)
		(layer "F.Cu")
		(net "M_D_DQ<32>")
	)
	(segment
		(start 281.507438 -127.039878)
		(end 281.755342 -127.039878)
		(width 0.1651)
		(layer "F.Cu")
		(net "M_D_DQ<32>")
	)
	(segment
		(start 272.938748 -115.128802)
		(end 273.7866 -115.976654)
		(width 0.1651)
		(layer "F.Cu")
		(net "M_D_DQ<32>")
	)
	(segment
		(start 281.024076 -126.308612)
		(end 281.024076 -126.556516)
		(width 0.1651)
		(layer "F.Cu")
		(net "M_D_DQ<32>")
	)
	(segment
		(start 281.024076 -126.556516)
		(end 280.776934 -126.803658)
		(width 0.1651)
		(layer "F.Cu")
		(net "M_D_DQ<32>")
	)
	(segment
		(start 280.776934 -126.803658)
		(end 280.776934 -127.064262)
		(width 0.1651)
		(layer "F.Cu")
		(net "M_D_DQ<32>")
	)
	(segment
		(start 280.9494 -130.683)
		(end 280.9494 -131.161282)
		(width 0.1651)
		(layer "F.Cu")
		(net "M_D_DQ<32>")
	)
	(segment
		(start 279.632664 -124.9172)
		(end 281.024076 -126.308612)
		(width 0.1651)
		(layer "F.Cu")
		(net "M_D_DQ<32>")
	)
	(segment
		(start 282.250388 -137.67054)
		(end 282.24988 -137.676382)
		(width 0.1651)
		(layer "F.Cu")
		(net "M_D_DQ<32>")
	)
	(segment
		(start 279.078944 -124.9172)
		(end 279.632664 -124.9172)
		(width 0.1651)
		(layer "F.Cu")
		(net "M_D_DQ<32>")
	)
	(segment
		(start 274.330922 -101.890068)
		(end 274.402804 -101.96195)
		(width 0.0889)
		(layer "F.Cu")
		(net "M_D_DQ<32>")
	)
	(segment
		(start 281.3558 -128.27)
		(end 281.3558 -128.5494)
		(width 0.1651)
		(layer "F.Cu")
		(net "M_D_DQ<32>")
	)
	(segment
		(start 281.3558 -128.5494)
		(end 281.8638 -129.0574)
		(width 0.1651)
		(layer "F.Cu")
		(net "M_D_DQ<32>")
	)
	(segment
		(start 281.755342 -127.039878)
		(end 281.9908 -127.275336)
		(width 0.1651)
		(layer "F.Cu")
		(net "M_D_DQ<32>")
	)
	(segment
		(start 273.769328 -101.967538)
		(end 274.01393 -101.889814)
		(width 0.0889)
		(layer "F.Cu")
		(net "M_D_DQ<32>")
	)
	(segment
		(start 280.9494 -131.161282)
		(end 281.399996 -131.611878)
		(width 0.1651)
		(layer "F.Cu")
		(net "M_D_DQ<32>")
	)
	(segment
		(start 281.247596 -127.29972)
		(end 281.507438 -127.039878)
		(width 0.1651)
		(layer "F.Cu")
		(net "M_D_DQ<32>")
	)
	(segment
		(start 273.7866 -115.976654)
		(end 273.7866 -119.624856)
		(width 0.1651)
		(layer "F.Cu")
		(net "M_D_DQ<32>")
	)
	(segment
		(start 282.24988 -137.676382)
		(end 282.07208 -135.8138)
		(width 0.1651)
		(layer "F.Cu")
		(net "M_D_DQ<32>")
	)
	(segment
		(start 281.9908 -127.635)
		(end 281.3558 -128.27)
		(width 0.1651)
		(layer "F.Cu")
		(net "M_D_DQ<32>")
	)
	(segment
		(start 281.012392 -127.29972)
		(end 281.247596 -127.29972)
		(width 0.1651)
		(layer "F.Cu")
		(net "M_D_DQ<32>")
	)
	(segment
		(start 273.7866 -119.624856)
		(end 279.078944 -124.9172)
		(width 0.1651)
		(layer "F.Cu")
		(net "M_D_DQ<32>")
	)
	(segment
		(start 273.286474 -106.4514)
		(end 273.184874 -106.553)
		(width 0.0889)
		(layer "F.Cu")
		(net "M_D_DQ<32>")
	)
	(segment
		(start 274.402804 -101.96195)
		(end 274.402804 -102.13848)
		(width 0.0889)
		(layer "F.Cu")
		(net "M_D_DQ<32>")
	)
	(segment
		(start 274.402804 -102.13848)
		(end 274.182078 -102.359206)
		(width 0.0889)
		(layer "F.Cu")
		(net "M_D_DQ<32>")
	)
	(via
		(at 282.07208 -135.8138)
		(size 0.508)
		(drill 0.254)
		(layers "F.Cu" "B.Cu")
		(net "M_D_DQ<32>")
	)
	(via
		(at 281.399996 -131.611878)
		(size 0.508)
		(drill 0.254)
		(layers "F.Cu" "B.Cu")
		(net "M_D_DQ<32>")
	)
	(segment
		(start 281.400504 -132.876036)
		(end 281.399996 -132.875782)
		(width 0.1651)
		(layer "B.Cu")
		(net "M_D_DQ<32>")
	)
	(segment
		(start 281.399996 -132.875782)
		(end 281.399996 -131.611878)
		(width 0.1651)
		(layer "B.Cu")
		(net "M_D_DQ<32>")
	)
	(segment
		(start 282.07208 -135.8138)
		(end 281.775916 -135.8138)
		(width 0.14224)
		(layer "In2.Cu")
		(net "M_D_DQ<32>")
	)
	(segment
		(start 280.966926 -135.00481)
		(end 280.966926 -132.044948)
		(width 0.14224)
		(layer "In2.Cu")
		(net "M_D_DQ<32>")
	)
	(segment
		(start 280.966926 -132.044948)
		(end 281.399996 -131.611878)
		(width 0.14224)
		(layer "In2.Cu")
		(net "M_D_DQ<32>")
	)
	(segment
		(start 281.775916 -135.8138)
		(end 280.966926 -135.00481)
		(width 0.14224)
		(layer "In2.Cu")
		(net "M_D_DQ<32>")
	)
	(segment
		(start 230.399844 -133.076442)
		(end 230.399844 -134.340346)
		(width 0.1651)
		(layer "F.Cu")
		(net "M_D_DQ<31>")
	)
	(segment
		(start 243.051838 -97.19564)
		(end 242.480338 -97.19564)
		(width 0.1651)
		(layer "F.Cu")
		(net "M_D_DQ<31>")
	)
	(segment
		(start 230.400352 -133.0706)
		(end 230.399844 -133.076442)
		(width 0.1651)
		(layer "F.Cu")
		(net "M_D_DQ<31>")
	)
	(via
		(at 242.480338 -97.19564)
		(size 0.508)
		(drill 0.254)
		(layers "F.Cu" "B.Cu")
		(net "M_D_DQ<31>")
	)
	(via
		(at 230.399844 -134.340346)
		(size 0.508)
		(drill 0.254)
		(layers "F.Cu" "B.Cu")
		(net "M_D_DQ<31>")
	)
	(via
		(at 231.249728 -130.330956)
		(size 0.508)
		(drill 0.254)
		(layers "F.Cu" "B.Cu")
		(net "M_D_DQ<31>")
	)
	(segment
		(start 231.25049 -128.276096)
		(end 231.25049 -130.330194)
		(width 0.1651)
		(layer "B.Cu")
		(net "M_D_DQ<31>")
	)
	(segment
		(start 231.25049 -130.330194)
		(end 231.249728 -130.330956)
		(width 0.1651)
		(layer "B.Cu")
		(net "M_D_DQ<31>")
	)
	(segment
		(start 230.799132 -131.188968)
		(end 230.843582 -131.233418)
		(width 0.14224)
		(layer "In2.Cu")
		(net "M_D_DQ<31>")
	)
	(segment
		(start 231.602534 -129.989072)
		(end 231.591612 -129.989072)
		(width 0.14224)
		(layer "In2.Cu")
		(net "M_D_DQ<31>")
	)
	(segment
		(start 230.799132 -130.7592)
		(end 230.799132 -131.188968)
		(width 0.14224)
		(layer "In2.Cu")
		(net "M_D_DQ<31>")
	)
	(segment
		(start 231.7242 -114.132614)
		(end 231.7242 -125.552454)
		(width 0.14224)
		(layer "In2.Cu")
		(net "M_D_DQ<31>")
	)
	(segment
		(start 231.8766 -128.724152)
		(end 231.805734 -128.724152)
		(width 0.14224)
		(layer "In2.Cu")
		(net "M_D_DQ<31>")
	)
	(segment
		(start 230.849932 -133.83895)
		(end 230.849932 -134.162546)
		(width 0.14224)
		(layer "In2.Cu")
		(net "M_D_DQ<31>")
	)
	(segment
		(start 233.25836 -113.340134)
		(end 233.4006 -113.482374)
		(width 0.14224)
		(layer "In2.Cu")
		(net "M_D_DQ<31>")
	)
	(segment
		(start 231.7242 -111.3028)
		(end 231.7242 -111.897414)
		(width 0.14224)
		(layer "In2.Cu")
		(net "M_D_DQ<31>")
	)
	(segment
		(start 231.602534 -128.927352)
		(end 231.602534 -129.989072)
		(width 0.14224)
		(layer "In2.Cu")
		(net "M_D_DQ<31>")
	)
	(segment
		(start 232.85196 -112.039654)
		(end 232.9942 -112.181894)
		(width 0.14224)
		(layer "In2.Cu")
		(net "M_D_DQ<31>")
	)
	(segment
		(start 231.7242 -111.897414)
		(end 231.86644 -112.039654)
		(width 0.14224)
		(layer "In2.Cu")
		(net "M_D_DQ<31>")
	)
	(segment
		(start 239.059212 -100.75799)
		(end 239.031272 -100.75799)
		(width 0.0889)
		(layer "In2.Cu")
		(net "M_D_DQ<31>")
	)
	(segment
		(start 232.0798 -128.520952)
		(end 231.8766 -128.724152)
		(width 0.14224)
		(layer "In2.Cu")
		(net "M_D_DQ<31>")
	)
	(segment
		(start 230.672132 -134.340346)
		(end 230.399844 -134.340346)
		(width 0.14224)
		(layer "In2.Cu")
		(net "M_D_DQ<31>")
	)
	(segment
		(start 233.4006 -113.482374)
		(end 233.4006 -113.848134)
		(width 0.14224)
		(layer "In2.Cu")
		(net "M_D_DQ<31>")
	)
	(segment
		(start 240.781078 -99.76739)
		(end 240.745264 -99.76739)
		(width 0.0889)
		(layer "In2.Cu")
		(net "M_D_DQ<31>")
	)
	(segment
		(start 242.212876 -98.585274)
		(end 242.212876 -98.681286)
		(width 0.0889)
		(layer "In2.Cu")
		(net "M_D_DQ<31>")
	)
	(segment
		(start 230.849932 -134.162546)
		(end 230.672132 -134.340346)
		(width 0.14224)
		(layer "In2.Cu")
		(net "M_D_DQ<31>")
	)
	(segment
		(start 232.9942 -112.547654)
		(end 232.85196 -112.689894)
		(width 0.14224)
		(layer "In2.Cu")
		(net "M_D_DQ<31>")
	)
	(segment
		(start 231.602534 -127.708152)
		(end 231.805734 -127.911352)
		(width 0.14224)
		(layer "In2.Cu")
		(net "M_D_DQ<31>")
	)
	(segment
		(start 232.9942 -112.181894)
		(end 232.9942 -112.547654)
		(width 0.14224)
		(layer "In2.Cu")
		(net "M_D_DQ<31>")
	)
	(segment
		(start 230.843582 -131.9022)
		(end 230.561134 -132.184648)
		(width 0.14224)
		(layer "In2.Cu")
		(net "M_D_DQ<31>")
	)
	(segment
		(start 232.0798 -128.114552)
		(end 232.0798 -128.520952)
		(width 0.14224)
		(layer "In2.Cu")
		(net "M_D_DQ<31>")
	)
	(segment
		(start 231.227376 -130.330956)
		(end 230.799132 -130.7592)
		(width 0.14224)
		(layer "In2.Cu")
		(net "M_D_DQ<31>")
	)
	(segment
		(start 231.86644 -113.990374)
		(end 231.7242 -114.132614)
		(width 0.14224)
		(layer "In2.Cu")
		(net "M_D_DQ<31>")
	)
	(segment
		(start 233.4006 -113.848134)
		(end 233.25836 -113.990374)
		(width 0.14224)
		(layer "In2.Cu")
		(net "M_D_DQ<31>")
	)
	(segment
		(start 237.841028 -101.452934)
		(end 237.748318 -101.613462)
		(width 0.0889)
		(layer "In2.Cu")
		(net "M_D_DQ<31>")
	)
	(segment
		(start 230.818182 -132.715)
		(end 230.818182 -133.0198)
		(width 0.14224)
		(layer "In2.Cu")
		(net "M_D_DQ<31>")
	)
	(segment
		(start 231.86644 -113.340134)
		(end 233.25836 -113.340134)
		(width 0.14224)
		(layer "In2.Cu")
		(net "M_D_DQ<31>")
	)
	(segment
		(start 231.7242 -112.832134)
		(end 231.7242 -113.197894)
		(width 0.14224)
		(layer "In2.Cu")
		(net "M_D_DQ<31>")
	)
	(segment
		(start 233.25836 -113.990374)
		(end 231.86644 -113.990374)
		(width 0.14224)
		(layer "In2.Cu")
		(net "M_D_DQ<31>")
	)
	(segment
		(start 238.209328 -101.253036)
		(end 238.176562 -101.253036)
		(width 0.0889)
		(layer "In2.Cu")
		(net "M_D_DQ<31>")
	)
	(segment
		(start 242.480338 -97.19564)
		(end 242.480338 -97.672144)
		(width 0.0889)
		(layer "In2.Cu")
		(net "M_D_DQ<31>")
	)
	(segment
		(start 230.561134 -133.550152)
		(end 230.849932 -133.83895)
		(width 0.14224)
		(layer "In2.Cu")
		(net "M_D_DQ<31>")
	)
	(segment
		(start 230.561134 -132.457952)
		(end 230.818182 -132.715)
		(width 0.14224)
		(layer "In2.Cu")
		(net "M_D_DQ<31>")
	)
	(segment
		(start 241.615722 -99.272344)
		(end 241.610642 -99.272344)
		(width 0.0889)
		(layer "In2.Cu")
		(net "M_D_DQ<31>")
	)
	(segment
		(start 233.1974 -106.50728)
		(end 233.1974 -109.8296)
		(width 0.14224)
		(layer "In2.Cu")
		(net "M_D_DQ<31>")
	)
	(segment
		(start 235.03382 -104.67086)
		(end 233.1974 -106.50728)
		(width 0.14224)
		(layer "In2.Cu")
		(net "M_D_DQ<31>")
	)
	(segment
		(start 233.1974 -109.8296)
		(end 231.7242 -111.3028)
		(width 0.14224)
		(layer "In2.Cu")
		(net "M_D_DQ<31>")
	)
	(segment
		(start 235.090716 -104.271064)
		(end 235.090716 -104.613964)
		(width 0.0889)
		(layer "In2.Cu")
		(net "M_D_DQ<31>")
	)
	(segment
		(start 230.561134 -133.276848)
		(end 230.561134 -133.550152)
		(width 0.14224)
		(layer "In2.Cu")
		(net "M_D_DQ<31>")
	)
	(segment
		(start 231.7242 -113.197894)
		(end 231.86644 -113.340134)
		(width 0.14224)
		(layer "In2.Cu")
		(net "M_D_DQ<31>")
	)
	(segment
		(start 231.249728 -130.330956)
		(end 231.227376 -130.330956)
		(width 0.14224)
		(layer "In2.Cu")
		(net "M_D_DQ<31>")
	)
	(segment
		(start 230.843582 -131.233418)
		(end 230.843582 -131.9022)
		(width 0.14224)
		(layer "In2.Cu")
		(net "M_D_DQ<31>")
	)
	(segment
		(start 235.090716 -104.613964)
		(end 235.03382 -104.67086)
		(width 0.0889)
		(layer "In2.Cu")
		(net "M_D_DQ<31>")
	)
	(segment
		(start 239.922558 -100.26269)
		(end 239.886744 -100.26269)
		(width 0.0889)
		(layer "In2.Cu")
		(net "M_D_DQ<31>")
	)
	(segment
		(start 230.561134 -132.184648)
		(end 230.561134 -132.457952)
		(width 0.14224)
		(layer "In2.Cu")
		(net "M_D_DQ<31>")
	)
	(segment
		(start 232.85196 -112.689894)
		(end 231.86644 -112.689894)
		(width 0.14224)
		(layer "In2.Cu")
		(net "M_D_DQ<31>")
	)
	(segment
		(start 231.8766 -127.911352)
		(end 232.0798 -128.114552)
		(width 0.14224)
		(layer "In2.Cu")
		(net "M_D_DQ<31>")
	)
	(segment
		(start 237.748318 -101.613462)
		(end 235.090716 -104.271064)
		(width 0.0889)
		(layer "In2.Cu")
		(net "M_D_DQ<31>")
	)
	(segment
		(start 231.602534 -125.67412)
		(end 231.602534 -127.708152)
		(width 0.14224)
		(layer "In2.Cu")
		(net "M_D_DQ<31>")
	)
	(segment
		(start 231.86644 -112.039654)
		(end 232.85196 -112.039654)
		(width 0.14224)
		(layer "In2.Cu")
		(net "M_D_DQ<31>")
	)
	(segment
		(start 231.591612 -129.989072)
		(end 231.249728 -130.330956)
		(width 0.14224)
		(layer "In2.Cu")
		(net "M_D_DQ<31>")
	)
	(segment
		(start 231.805734 -128.724152)
		(end 231.602534 -128.927352)
		(width 0.14224)
		(layer "In2.Cu")
		(net "M_D_DQ<31>")
	)
	(segment
		(start 230.818182 -133.0198)
		(end 230.561134 -133.276848)
		(width 0.14224)
		(layer "In2.Cu")
		(net "M_D_DQ<31>")
	)
	(segment
		(start 231.7242 -125.552454)
		(end 231.602534 -125.67412)
		(width 0.14224)
		(layer "In2.Cu")
		(net "M_D_DQ<31>")
	)
	(segment
		(start 231.805734 -127.911352)
		(end 231.8766 -127.911352)
		(width 0.14224)
		(layer "In2.Cu")
		(net "M_D_DQ<31>")
	)
	(segment
		(start 231.86644 -112.689894)
		(end 231.7242 -112.832134)
		(width 0.14224)
		(layer "In2.Cu")
		(net "M_D_DQ<31>")
	)
	(arc
		(start 239.031272 -100.75799)
		(mid 238.83963 -100.815156)
		(end 238.699548 -100.957888)
		(width 0.0889)
		(layer "In2.Cu")
		(net "M_D_DQ<31>")
	)
	(arc
		(start 241.643408 -99.271836)
		(mid 241.629567 -99.272214)
		(end 241.615722 -99.272344)
		(width 0.0889)
		(layer "In2.Cu")
		(net "M_D_DQ<31>")
	)
	(arc
		(start 242.212876 -98.681286)
		(mid 242.047325 -99.091521)
		(end 241.643408 -99.271836)
		(width 0.0889)
		(layer "In2.Cu")
		(net "M_D_DQ<31>")
	)
	(arc
		(start 240.745264 -99.76739)
		(mid 240.555335 -99.82526)
		(end 240.416588 -99.967288)
		(width 0.0889)
		(layer "In2.Cu")
		(net "M_D_DQ<31>")
	)
	(arc
		(start 238.699548 -100.957888)
		(mid 238.492544 -101.168752)
		(end 238.209328 -101.253036)
		(width 0.0889)
		(layer "In2.Cu")
		(net "M_D_DQ<31>")
	)
	(arc
		(start 239.558068 -100.462588)
		(mid 239.347355 -100.675667)
		(end 239.059212 -100.75799)
		(width 0.0889)
		(layer "In2.Cu")
		(net "M_D_DQ<31>")
	)
	(arc
		(start 242.480338 -97.672144)
		(mid 242.464229 -97.86582)
		(end 242.384326 -98.042984)
		(width 0.0889)
		(layer "In2.Cu")
		(net "M_D_DQ<31>")
	)
	(arc
		(start 240.416588 -99.967288)
		(mid 240.20798 -100.17922)
		(end 239.922558 -100.26269)
		(width 0.0889)
		(layer "In2.Cu")
		(net "M_D_DQ<31>")
	)
	(arc
		(start 242.384326 -98.042984)
		(mid 242.341306 -98.112089)
		(end 242.303554 -98.184208)
		(width 0.0889)
		(layer "In2.Cu")
		(net "M_D_DQ<31>")
	)
	(arc
		(start 241.275108 -99.471988)
		(mid 241.0665 -99.68392)
		(end 240.781078 -99.76739)
		(width 0.0889)
		(layer "In2.Cu")
		(net "M_D_DQ<31>")
	)
	(arc
		(start 241.610642 -99.272344)
		(mid 241.415426 -99.326031)
		(end 241.275108 -99.471988)
		(width 0.0889)
		(layer "In2.Cu")
		(net "M_D_DQ<31>")
	)
	(arc
		(start 239.886744 -100.26269)
		(mid 239.696815 -100.32056)
		(end 239.558068 -100.462588)
		(width 0.0889)
		(layer "In2.Cu")
		(net "M_D_DQ<31>")
	)
	(arc
		(start 242.303554 -98.184208)
		(mid 242.23582 -98.379678)
		(end 242.212876 -98.585274)
		(width 0.0889)
		(layer "In2.Cu")
		(net "M_D_DQ<31>")
	)
	(arc
		(start 238.176562 -101.253036)
		(mid 237.982774 -101.309308)
		(end 237.841028 -101.452934)
		(width 0.0889)
		(layer "In2.Cu")
		(net "M_D_DQ<31>")
	)
	(segment
		(start 231.382062 -136.57072)
		(end 231.382062 -136.35228)
		(width 0.1651)
		(layer "F.Cu")
		(net "M_D_DQ<30>")
	)
	(segment
		(start 243.051838 -95.21444)
		(end 242.480338 -95.21444)
		(width 0.1651)
		(layer "F.Cu")
		(net "M_D_DQ<30>")
	)
	(segment
		(start 231.249982 -137.67054)
		(end 231.249982 -136.7028)
		(width 0.1651)
		(layer "F.Cu")
		(net "M_D_DQ<30>")
	)
	(segment
		(start 231.249982 -135.915654)
		(end 231.249728 -135.9154)
		(width 0.1651)
		(layer "F.Cu")
		(net "M_D_DQ<30>")
	)
	(segment
		(start 231.249982 -136.2202)
		(end 231.249982 -135.915654)
		(width 0.1651)
		(layer "F.Cu")
		(net "M_D_DQ<30>")
	)
	(segment
		(start 231.249982 -136.7028)
		(end 231.382062 -136.57072)
		(width 0.1651)
		(layer "F.Cu")
		(net "M_D_DQ<30>")
	)
	(segment
		(start 231.25049 -137.67054)
		(end 231.249982 -137.67054)
		(width 0.1651)
		(layer "F.Cu")
		(net "M_D_DQ<30>")
	)
	(segment
		(start 231.382062 -136.35228)
		(end 231.249982 -136.2202)
		(width 0.1651)
		(layer "F.Cu")
		(net "M_D_DQ<30>")
	)
	(via
		(at 230.399844 -131.611878)
		(size 0.508)
		(drill 0.254)
		(layers "F.Cu" "B.Cu")
		(net "M_D_DQ<30>")
	)
	(via
		(at 242.480338 -95.21444)
		(size 0.508)
		(drill 0.254)
		(layers "F.Cu" "B.Cu")
		(net "M_D_DQ<30>")
	)
	(via
		(at 231.249728 -135.9154)
		(size 0.508)
		(drill 0.254)
		(layers "F.Cu" "B.Cu")
		(net "M_D_DQ<30>")
	)
	(segment
		(start 230.400352 -132.876036)
		(end 230.399844 -132.875782)
		(width 0.1651)
		(layer "B.Cu")
		(net "M_D_DQ<30>")
	)
	(segment
		(start 230.399844 -132.875782)
		(end 230.399844 -131.611878)
		(width 0.1651)
		(layer "B.Cu")
		(net "M_D_DQ<30>")
	)
	(segment
		(start 242.480338 -95.21444)
		(end 242.150392 -95.976186)
		(width 0.0889)
		(layer "In2.Cu")
		(net "M_D_DQ<30>")
	)
	(segment
		(start 230.967534 -129.732278)
		(end 230.230934 -130.468878)
		(width 0.14224)
		(layer "In2.Cu")
		(net "M_D_DQ<30>")
	)
	(segment
		(start 231.0892 -118.5418)
		(end 230.4288 -119.2022)
		(width 0.14224)
		(layer "In2.Cu")
		(net "M_D_DQ<30>")
	)
	(segment
		(start 230.4288 -123.002294)
		(end 230.57104 -123.144534)
		(width 0.14224)
		(layer "In2.Cu")
		(net "M_D_DQ<30>")
	)
	(segment
		(start 230.230934 -130.468878)
		(end 230.230934 -131.442968)
		(width 0.14224)
		(layer "In2.Cu")
		(net "M_D_DQ<30>")
	)
	(segment
		(start 230.967534 -125.76048)
		(end 230.967534 -129.732278)
		(width 0.14224)
		(layer "In2.Cu")
		(net "M_D_DQ<30>")
	)
	(segment
		(start 242.128802 -96.396302)
		(end 242.133628 -96.404938)
		(width 0.0889)
		(layer "In2.Cu")
		(net "M_D_DQ<30>")
	)
	(segment
		(start 230.9622 -122.494294)
		(end 230.57104 -122.494294)
		(width 0.14224)
		(layer "In2.Cu")
		(net "M_D_DQ<30>")
	)
	(segment
		(start 231.0892 -122.367294)
		(end 230.9622 -122.494294)
		(width 0.14224)
		(layer "In2.Cu")
		(net "M_D_DQ<30>")
	)
	(segment
		(start 230.4288 -121.640854)
		(end 230.632 -121.844054)
		(width 0.14224)
		(layer "In2.Cu")
		(net "M_D_DQ<30>")
	)
	(segment
		(start 231.0892 -122.011694)
		(end 231.0892 -122.367294)
		(width 0.14224)
		(layer "In2.Cu")
		(net "M_D_DQ<30>")
	)
	(segment
		(start 240.781332 -99.576636)
		(end 240.745518 -99.576636)
		(width 0.0889)
		(layer "In2.Cu")
		(net "M_D_DQ<30>")
	)
	(segment
		(start 242.13058 -97.390458)
		(end 242.139978 -97.406206)
		(width 0.0889)
		(layer "In2.Cu")
		(net "M_D_DQ<30>")
	)
	(segment
		(start 231.0892 -111.18723)
		(end 231.0892 -118.5418)
		(width 0.14224)
		(layer "In2.Cu")
		(net "M_D_DQ<30>")
	)
	(segment
		(start 239.922812 -100.071936)
		(end 239.883188 -100.071936)
		(width 0.0889)
		(layer "In2.Cu")
		(net "M_D_DQ<30>")
	)
	(segment
		(start 230.4288 -119.2022)
		(end 230.4288 -121.640854)
		(width 0.14224)
		(layer "In2.Cu")
		(net "M_D_DQ<30>")
	)
	(segment
		(start 232.664 -109.61243)
		(end 231.0892 -111.18723)
		(width 0.14224)
		(layer "In2.Cu")
		(net "M_D_DQ<30>")
	)
	(segment
		(start 229.966774 -132.044948)
		(end 229.966774 -134.632446)
		(width 0.14224)
		(layer "In2.Cu")
		(net "M_D_DQ<30>")
	)
	(segment
		(start 237.675674 -101.357938)
		(end 237.594648 -101.4984)
		(width 0.0889)
		(layer "In2.Cu")
		(net "M_D_DQ<30>")
	)
	(segment
		(start 230.57104 -123.144534)
		(end 230.92156 -123.144534)
		(width 0.14224)
		(layer "In2.Cu")
		(net "M_D_DQ<30>")
	)
	(segment
		(start 230.57104 -123.794774)
		(end 230.4288 -123.937014)
		(width 0.14224)
		(layer "In2.Cu")
		(net "M_D_DQ<30>")
	)
	(segment
		(start 230.9622 -123.794774)
		(end 230.57104 -123.794774)
		(width 0.14224)
		(layer "In2.Cu")
		(net "M_D_DQ<30>")
	)
	(segment
		(start 242.150392 -95.976186)
		(end 242.133628 -96.004888)
		(width 0.0889)
		(layer "In2.Cu")
		(net "M_D_DQ<30>")
	)
	(segment
		(start 242.133628 -96.404938)
		(end 242.139978 -96.415606)
		(width 0.0889)
		(layer "In2.Cu")
		(net "M_D_DQ<30>")
	)
	(segment
		(start 238.202724 -101.062536)
		(end 238.174022 -101.062536)
		(width 0.0889)
		(layer "In2.Cu")
		(net "M_D_DQ<30>")
	)
	(segment
		(start 230.92156 -123.144534)
		(end 231.0892 -123.312174)
		(width 0.14224)
		(layer "In2.Cu")
		(net "M_D_DQ<30>")
	)
	(segment
		(start 232.664 -106.124502)
		(end 232.664 -109.61243)
		(width 0.14224)
		(layer "In2.Cu")
		(net "M_D_DQ<30>")
	)
	(segment
		(start 230.57104 -122.494294)
		(end 230.4288 -122.636534)
		(width 0.14224)
		(layer "In2.Cu")
		(net "M_D_DQ<30>")
	)
	(segment
		(start 231.0892 -123.667774)
		(end 230.9622 -123.794774)
		(width 0.14224)
		(layer "In2.Cu")
		(net "M_D_DQ<30>")
	)
	(segment
		(start 242.212876 -97.691194)
		(end 242.212876 -97.793302)
		(width 0.0889)
		(layer "In2.Cu")
		(net "M_D_DQ<30>")
	)
	(segment
		(start 234.912154 -104.180894)
		(end 234.607608 -104.180894)
		(width 0.0889)
		(layer "In2.Cu")
		(net "M_D_DQ<30>")
	)
	(segment
		(start 229.966774 -134.632446)
		(end 231.249728 -135.9154)
		(width 0.14224)
		(layer "In2.Cu")
		(net "M_D_DQ<30>")
	)
	(segment
		(start 237.594648 -101.4984)
		(end 234.912154 -104.180894)
		(width 0.0889)
		(layer "In2.Cu")
		(net "M_D_DQ<30>")
	)
	(segment
		(start 241.609626 -99.081844)
		(end 241.600228 -99.081844)
		(width 0.0889)
		(layer "In2.Cu")
		(net "M_D_DQ<30>")
	)
	(segment
		(start 230.399844 -131.611878)
		(end 229.966774 -132.044948)
		(width 0.14224)
		(layer "In2.Cu")
		(net "M_D_DQ<30>")
	)
	(segment
		(start 230.230934 -131.442968)
		(end 230.399844 -131.611878)
		(width 0.14224)
		(layer "In2.Cu")
		(net "M_D_DQ<30>")
	)
	(segment
		(start 242.022122 -98.429318)
		(end 242.022122 -98.681286)
		(width 0.0889)
		(layer "In2.Cu")
		(net "M_D_DQ<30>")
	)
	(segment
		(start 230.4288 -122.636534)
		(end 230.4288 -123.002294)
		(width 0.14224)
		(layer "In2.Cu")
		(net "M_D_DQ<30>")
	)
	(segment
		(start 239.057434 -100.567236)
		(end 239.033304 -100.567236)
		(width 0.0889)
		(layer "In2.Cu")
		(net "M_D_DQ<30>")
	)
	(segment
		(start 230.4288 -123.937014)
		(end 230.4288 -125.221746)
		(width 0.14224)
		(layer "In2.Cu")
		(net "M_D_DQ<30>")
	)
	(segment
		(start 230.632 -121.844054)
		(end 230.92156 -121.844054)
		(width 0.14224)
		(layer "In2.Cu")
		(net "M_D_DQ<30>")
	)
	(segment
		(start 230.92156 -121.844054)
		(end 231.0892 -122.011694)
		(width 0.14224)
		(layer "In2.Cu")
		(net "M_D_DQ<30>")
	)
	(segment
		(start 231.0892 -123.312174)
		(end 231.0892 -123.667774)
		(width 0.14224)
		(layer "In2.Cu")
		(net "M_D_DQ<30>")
	)
	(segment
		(start 230.4288 -125.221746)
		(end 230.967534 -125.76048)
		(width 0.14224)
		(layer "In2.Cu")
		(net "M_D_DQ<30>")
	)
	(segment
		(start 234.607608 -104.180894)
		(end 232.664 -106.124502)
		(width 0.14224)
		(layer "In2.Cu")
		(net "M_D_DQ<30>")
	)
	(arc
		(start 242.212876 -97.793302)
		(mid 242.194427 -97.925604)
		(end 242.140486 -98.04781)
		(width 0.0889)
		(layer "In2.Cu")
		(net "M_D_DQ<30>")
	)
	(arc
		(start 240.745518 -99.576636)
		(mid 240.460094 -99.660103)
		(end 240.251488 -99.872038)
		(width 0.0889)
		(layer "In2.Cu")
		(net "M_D_DQ<30>")
	)
	(arc
		(start 241.600228 -99.081844)
		(mid 241.314176 -99.161242)
		(end 241.110008 -99.376738)
		(width 0.0889)
		(layer "In2.Cu")
		(net "M_D_DQ<30>")
	)
	(arc
		(start 242.022122 -98.681286)
		(mid 241.910125 -98.958995)
		(end 241.636804 -99.081336)
		(width 0.0889)
		(layer "In2.Cu")
		(net "M_D_DQ<30>")
	)
	(arc
		(start 242.139978 -97.406206)
		(mid 242.194409 -97.544096)
		(end 242.212876 -97.691194)
		(width 0.0889)
		(layer "In2.Cu")
		(net "M_D_DQ<30>")
	)
	(arc
		(start 242.140486 -98.04781)
		(mid 242.05699 -98.231023)
		(end 242.022122 -98.429318)
		(width 0.0889)
		(layer "In2.Cu")
		(net "M_D_DQ<30>")
	)
	(arc
		(start 242.133628 -96.004888)
		(mid 242.080158 -96.199951)
		(end 242.128802 -96.396302)
		(width 0.0889)
		(layer "In2.Cu")
		(net "M_D_DQ<30>")
	)
	(arc
		(start 240.251488 -99.872038)
		(mid 240.112744 -100.014071)
		(end 239.922812 -100.071936)
		(width 0.0889)
		(layer "In2.Cu")
		(net "M_D_DQ<30>")
	)
	(arc
		(start 238.171482 -101.062536)
		(mid 237.885069 -101.145591)
		(end 237.675674 -101.357938)
		(width 0.0889)
		(layer "In2.Cu")
		(net "M_D_DQ<30>")
	)
	(arc
		(start 242.139978 -96.415606)
		(mid 242.212776 -96.706369)
		(end 242.133628 -96.995488)
		(width 0.0889)
		(layer "In2.Cu")
		(net "M_D_DQ<30>")
	)
	(arc
		(start 238.534448 -100.862638)
		(mid 238.394369 -101.005374)
		(end 238.202724 -101.062536)
		(width 0.0889)
		(layer "In2.Cu")
		(net "M_D_DQ<30>")
	)
	(arc
		(start 239.883188 -100.071936)
		(mid 239.599971 -100.156217)
		(end 239.392968 -100.367084)
		(width 0.0889)
		(layer "In2.Cu")
		(net "M_D_DQ<30>")
	)
	(arc
		(start 241.636804 -99.081336)
		(mid 241.623217 -99.081718)
		(end 241.609626 -99.081844)
		(width 0.0889)
		(layer "In2.Cu")
		(net "M_D_DQ<30>")
	)
	(arc
		(start 242.133628 -96.995488)
		(mid 242.077438 -97.192533)
		(end 242.13058 -97.390458)
		(width 0.0889)
		(layer "In2.Cu")
		(net "M_D_DQ<30>")
	)
	(arc
		(start 239.033304 -100.567236)
		(mid 238.745159 -100.649555)
		(end 238.534448 -100.862638)
		(width 0.0889)
		(layer "In2.Cu")
		(net "M_D_DQ<30>")
	)
	(arc
		(start 241.110008 -99.376738)
		(mid 240.971264 -99.518771)
		(end 240.781332 -99.576636)
		(width 0.0889)
		(layer "In2.Cu")
		(net "M_D_DQ<30>")
	)
	(arc
		(start 239.392968 -100.367084)
		(mid 239.251285 -100.510888)
		(end 239.057434 -100.567236)
		(width 0.0889)
		(layer "In2.Cu")
		(net "M_D_DQ<30>")
	)
	(arc
		(start 238.174022 -101.062536)
		(mid 238.172752 -101.062535)
		(end 238.171482 -101.062536)
		(width 0.0889)
		(layer "In2.Cu")
		(net "M_D_DQ<30>")
	)
	(segment
		(start 232.749598 -89.27084)
		(end 232.101898 -89.27084)
		(width 0.1651)
		(layer "F.Cu")
		(net "M_D_DQ<2>")
	)
	(segment
		(start 204.899768 -137.67054)
		(end 204.899768 -136.679432)
		(width 0.1651)
		(layer "F.Cu")
		(net "M_D_DQ<2>")
	)
	(segment
		(start 205.03134 -136.54786)
		(end 205.03134 -136.32434)
		(width 0.1651)
		(layer "F.Cu")
		(net "M_D_DQ<2>")
	)
	(segment
		(start 204.900276 -137.67054)
		(end 204.899768 -137.67054)
		(width 0.1651)
		(layer "F.Cu")
		(net "M_D_DQ<2>")
	)
	(segment
		(start 204.899768 -136.679432)
		(end 205.03134 -136.54786)
		(width 0.1651)
		(layer "F.Cu")
		(net "M_D_DQ<2>")
	)
	(segment
		(start 204.899768 -136.192768)
		(end 204.899768 -135.9154)
		(width 0.1651)
		(layer "F.Cu")
		(net "M_D_DQ<2>")
	)
	(segment
		(start 205.03134 -136.32434)
		(end 204.899768 -136.192768)
		(width 0.1651)
		(layer "F.Cu")
		(net "M_D_DQ<2>")
	)
	(via
		(at 232.101898 -89.27084)
		(size 0.508)
		(drill 0.254)
		(layers "F.Cu" "B.Cu")
		(net "M_D_DQ<2>")
	)
	(via
		(at 204.899768 -135.9154)
		(size 0.508)
		(drill 0.254)
		(layers "F.Cu" "B.Cu")
		(net "M_D_DQ<2>")
	)
	(via
		(at 204.049884 -131.611878)
		(size 0.508)
		(drill 0.254)
		(layers "F.Cu" "B.Cu")
		(net "M_D_DQ<2>")
	)
	(segment
		(start 204.050392 -132.876036)
		(end 204.049884 -132.875782)
		(width 0.1651)
		(layer "B.Cu")
		(net "M_D_DQ<2>")
	)
	(segment
		(start 204.049884 -132.875782)
		(end 204.049884 -131.611878)
		(width 0.1651)
		(layer "B.Cu")
		(net "M_D_DQ<2>")
	)
	(segment
		(start 205.174596 -124.223272)
		(end 204.768196 -124.223272)
		(width 0.14224)
		(layer "In2.Cu")
		(net "M_D_DQ<2>")
	)
	(segment
		(start 230.241856 -89.27084)
		(end 219.3036 -100.209096)
		(width 0.14224)
		(layer "In2.Cu")
		(net "M_D_DQ<2>")
	)
	(segment
		(start 203.616814 -134.632446)
		(end 204.899768 -135.9154)
		(width 0.14224)
		(layer "In2.Cu")
		(net "M_D_DQ<2>")
	)
	(segment
		(start 205.3844 -128.2954)
		(end 205.3844 -124.433076)
		(width 0.14224)
		(layer "In2.Cu")
		(net "M_D_DQ<2>")
	)
	(segment
		(start 203.616814 -132.044948)
		(end 203.616814 -134.632446)
		(width 0.14224)
		(layer "In2.Cu")
		(net "M_D_DQ<2>")
	)
	(segment
		(start 203.704952 -130.633978)
		(end 203.704952 -131.266946)
		(width 0.14224)
		(layer "In2.Cu")
		(net "M_D_DQ<2>")
	)
	(segment
		(start 219.3036 -101.8286)
		(end 206.1972 -114.935)
		(width 0.14224)
		(layer "In2.Cu")
		(net "M_D_DQ<2>")
	)
	(segment
		(start 205.994 -128.4986)
		(end 205.5876 -128.4986)
		(width 0.14224)
		(layer "In2.Cu")
		(net "M_D_DQ<2>")
	)
	(segment
		(start 204.049884 -131.611878)
		(end 203.616814 -132.044948)
		(width 0.14224)
		(layer "In2.Cu")
		(net "M_D_DQ<2>")
	)
	(segment
		(start 204.768196 -124.223272)
		(end 204.5716 -124.419868)
		(width 0.14224)
		(layer "In2.Cu")
		(net "M_D_DQ<2>")
	)
	(segment
		(start 203.704952 -131.266946)
		(end 204.049884 -131.611878)
		(width 0.14224)
		(layer "In2.Cu")
		(net "M_D_DQ<2>")
	)
	(segment
		(start 204.5716 -129.76733)
		(end 203.704952 -130.633978)
		(width 0.14224)
		(layer "In2.Cu")
		(net "M_D_DQ<2>")
	)
	(segment
		(start 205.3844 -124.433076)
		(end 205.174596 -124.223272)
		(width 0.14224)
		(layer "In2.Cu")
		(net "M_D_DQ<2>")
	)
	(segment
		(start 206.1972 -128.2954)
		(end 205.994 -128.4986)
		(width 0.14224)
		(layer "In2.Cu")
		(net "M_D_DQ<2>")
	)
	(segment
		(start 205.5876 -128.4986)
		(end 205.3844 -128.2954)
		(width 0.14224)
		(layer "In2.Cu")
		(net "M_D_DQ<2>")
	)
	(segment
		(start 204.5716 -124.419868)
		(end 204.5716 -129.76733)
		(width 0.14224)
		(layer "In2.Cu")
		(net "M_D_DQ<2>")
	)
	(segment
		(start 206.1972 -114.935)
		(end 206.1972 -128.2954)
		(width 0.14224)
		(layer "In2.Cu")
		(net "M_D_DQ<2>")
	)
	(segment
		(start 230.89362 -89.27084)
		(end 230.241856 -89.27084)
		(width 0.14224)
		(layer "In2.Cu")
		(net "M_D_DQ<2>")
	)
	(segment
		(start 219.3036 -100.209096)
		(end 219.3036 -101.8286)
		(width 0.14224)
		(layer "In2.Cu")
		(net "M_D_DQ<2>")
	)
	(segment
		(start 232.101898 -89.27084)
		(end 230.89362 -89.27084)
		(width 0.0889)
		(layer "In2.Cu")
		(net "M_D_DQ<2>")
	)
	(segment
		(start 240.476278 -96.700086)
		(end 239.904778 -96.700086)
		(width 0.1651)
		(layer "F.Cu")
		(net "M_D_DQ<29>")
	)
	(segment
		(start 224.449894 -133.076442)
		(end 224.449894 -134.340346)
		(width 0.1651)
		(layer "F.Cu")
		(net "M_D_DQ<29>")
	)
	(segment
		(start 224.450402 -133.0706)
		(end 224.449894 -133.076442)
		(width 0.1651)
		(layer "F.Cu")
		(net "M_D_DQ<29>")
	)
	(via
		(at 224.449894 -134.340346)
		(size 0.508)
		(drill 0.254)
		(layers "F.Cu" "B.Cu")
		(net "M_D_DQ<29>")
	)
	(via
		(at 225.223578 -130.330956)
		(size 0.508)
		(drill 0.254)
		(layers "F.Cu" "B.Cu")
		(net "M_D_DQ<29>")
	)
	(via
		(at 239.904778 -96.700086)
		(size 0.508)
		(drill 0.254)
		(layers "F.Cu" "B.Cu")
		(net "M_D_DQ<29>")
	)
	(segment
		(start 225.299778 -128.276096)
		(end 225.299778 -130.254756)
		(width 0.1651)
		(layer "B.Cu")
		(net "M_D_DQ<29>")
	)
	(segment
		(start 225.300286 -128.276096)
		(end 225.299778 -128.276096)
		(width 0.1651)
		(layer "B.Cu")
		(net "M_D_DQ<29>")
	)
	(segment
		(start 225.299778 -130.254756)
		(end 225.223578 -130.330956)
		(width 0.1651)
		(layer "B.Cu")
		(net "M_D_DQ<29>")
	)
	(segment
		(start 224.899982 -131.927346)
		(end 224.899982 -131.445)
		(width 0.14224)
		(layer "In2.Cu")
		(net "M_D_DQ<29>")
	)
	(segment
		(start 235.601002 -98.77679)
		(end 235.629958 -98.77679)
		(width 0.0889)
		(layer "In2.Cu")
		(net "M_D_DQ<29>")
	)
	(segment
		(start 224.899982 -131.445)
		(end 224.772982 -131.318)
		(width 0.14224)
		(layer "In2.Cu")
		(net "M_D_DQ<29>")
	)
	(segment
		(start 239.904778 -96.362012)
		(end 239.904778 -96.700086)
		(width 0.0889)
		(layer "In2.Cu")
		(net "M_D_DQ<29>")
	)
	(segment
		(start 226.20986 -122.262646)
		(end 226.3648 -122.107706)
		(width 0.14224)
		(layer "In2.Cu")
		(net "M_D_DQ<29>")
	)
	(segment
		(start 225.6282 -125.5014)
		(end 225.6282 -124.2314)
		(width 0.14224)
		(layer "In2.Cu")
		(net "M_D_DQ<29>")
	)
	(segment
		(start 224.611184 -132.216144)
		(end 224.899982 -131.927346)
		(width 0.14224)
		(layer "In2.Cu")
		(net "M_D_DQ<29>")
	)
	(segment
		(start 225.68154 -123.075446)
		(end 225.5266 -122.920506)
		(width 0.14224)
		(layer "In2.Cu")
		(net "M_D_DQ<29>")
	)
	(segment
		(start 225.3488 -125.7808)
		(end 225.6282 -125.5014)
		(width 0.14224)
		(layer "In2.Cu")
		(net "M_D_DQ<29>")
	)
	(segment
		(start 225.201226 -130.330956)
		(end 225.223578 -130.330956)
		(width 0.14224)
		(layer "In2.Cu")
		(net "M_D_DQ<29>")
	)
	(segment
		(start 231.400604 -101.683566)
		(end 231.700324 -101.683566)
		(width 0.0889)
		(layer "In2.Cu")
		(net "M_D_DQ<29>")
	)
	(segment
		(start 225.5266 -122.920506)
		(end 225.5266 -122.417586)
		(width 0.14224)
		(layer "In2.Cu")
		(net "M_D_DQ<29>")
	)
	(segment
		(start 224.874582 -133.959854)
		(end 224.611184 -133.696456)
		(width 0.14224)
		(layer "In2.Cu")
		(net "M_D_DQ<29>")
	)
	(segment
		(start 225.6536 -129.335784)
		(end 225.3488 -129.030984)
		(width 0.14224)
		(layer "In2.Cu")
		(net "M_D_DQ<29>")
	)
	(segment
		(start 239.846866 -96.3041)
		(end 239.904778 -96.362012)
		(width 0.0889)
		(layer "In2.Cu")
		(net "M_D_DQ<29>")
	)
	(segment
		(start 238.176562 -97.290636)
		(end 238.209328 -97.290636)
		(width 0.0889)
		(layer "In2.Cu")
		(net "M_D_DQ<29>")
	)
	(segment
		(start 239.031272 -96.79559)
		(end 239.064038 -96.79559)
		(width 0.0889)
		(layer "In2.Cu")
		(net "M_D_DQ<29>")
	)
	(segment
		(start 225.666046 -116.7257)
		(end 225.666046 -111.080296)
		(width 0.14224)
		(layer "In2.Cu")
		(net "M_D_DQ<29>")
	)
	(segment
		(start 230.418894 -102.949502)
		(end 230.418894 -102.665276)
		(width 0.0889)
		(layer "In2.Cu")
		(net "M_D_DQ<29>")
	)
	(segment
		(start 224.611184 -133.696456)
		(end 224.611184 -133.384544)
		(width 0.14224)
		(layer "In2.Cu")
		(net "M_D_DQ<29>")
	)
	(segment
		(start 225.3488 -128.522984)
		(end 225.6536 -128.218184)
		(width 0.14224)
		(layer "In2.Cu")
		(net "M_D_DQ<29>")
	)
	(segment
		(start 224.772982 -131.318)
		(end 224.772982 -130.7592)
		(width 0.14224)
		(layer "In2.Cu")
		(net "M_D_DQ<29>")
	)
	(segment
		(start 224.849182 -132.791454)
		(end 224.611184 -132.553456)
		(width 0.14224)
		(layer "In2.Cu")
		(net "M_D_DQ<29>")
	)
	(segment
		(start 233.06151 -100.322126)
		(end 233.280458 -100.322126)
		(width 0.0889)
		(layer "In2.Cu")
		(net "M_D_DQ<29>")
	)
	(segment
		(start 230.418894 -102.665276)
		(end 231.400604 -101.683566)
		(width 0.0889)
		(layer "In2.Cu")
		(net "M_D_DQ<29>")
	)
	(segment
		(start 224.874582 -134.187946)
		(end 224.874582 -133.959854)
		(width 0.14224)
		(layer "In2.Cu")
		(net "M_D_DQ<29>")
	)
	(segment
		(start 224.849182 -133.146546)
		(end 224.849182 -132.791454)
		(width 0.14224)
		(layer "In2.Cu")
		(net "M_D_DQ<29>")
	)
	(segment
		(start 226.3648 -123.4948)
		(end 226.3648 -123.230386)
		(width 0.14224)
		(layer "In2.Cu")
		(net "M_D_DQ<29>")
	)
	(segment
		(start 225.6536 -128.218184)
		(end 225.6536 -127.710184)
		(width 0.14224)
		(layer "In2.Cu")
		(net "M_D_DQ<29>")
	)
	(segment
		(start 236.459522 -98.281236)
		(end 236.492288 -98.281236)
		(width 0.0889)
		(layer "In2.Cu")
		(net "M_D_DQ<29>")
	)
	(segment
		(start 224.722182 -134.340346)
		(end 224.874582 -134.187946)
		(width 0.14224)
		(layer "In2.Cu")
		(net "M_D_DQ<29>")
	)
	(segment
		(start 233.54792 -99.967034)
		(end 233.548428 -99.967288)
		(width 0.0889)
		(layer "In2.Cu")
		(net "M_D_DQ<29>")
	)
	(segment
		(start 225.5266 -122.417586)
		(end 225.68154 -122.262646)
		(width 0.14224)
		(layer "In2.Cu")
		(net "M_D_DQ<29>")
	)
	(segment
		(start 233.280458 -100.322126)
		(end 233.42854 -100.174044)
		(width 0.0889)
		(layer "In2.Cu")
		(net "M_D_DQ<29>")
	)
	(segment
		(start 225.6536 -127.710184)
		(end 225.3488 -127.405384)
		(width 0.14224)
		(layer "In2.Cu")
		(net "M_D_DQ<29>")
	)
	(segment
		(start 228.6127 -108.133642)
		(end 228.6127 -104.755696)
		(width 0.14224)
		(layer "In2.Cu")
		(net "M_D_DQ<29>")
	)
	(segment
		(start 225.6536 -130.124454)
		(end 225.6536 -129.335784)
		(width 0.14224)
		(layer "In2.Cu")
		(net "M_D_DQ<29>")
	)
	(segment
		(start 224.611184 -132.553456)
		(end 224.611184 -132.216144)
		(width 0.14224)
		(layer "In2.Cu")
		(net "M_D_DQ<29>")
	)
	(segment
		(start 224.772982 -130.7592)
		(end 225.201226 -130.330956)
		(width 0.14224)
		(layer "In2.Cu")
		(net "M_D_DQ<29>")
	)
	(segment
		(start 225.6282 -124.2314)
		(end 226.3648 -123.4948)
		(width 0.14224)
		(layer "In2.Cu")
		(net "M_D_DQ<29>")
	)
	(segment
		(start 224.611184 -133.384544)
		(end 224.849182 -133.146546)
		(width 0.14224)
		(layer "In2.Cu")
		(net "M_D_DQ<29>")
	)
	(segment
		(start 226.3648 -117.424454)
		(end 225.666046 -116.7257)
		(width 0.14224)
		(layer "In2.Cu")
		(net "M_D_DQ<29>")
	)
	(segment
		(start 224.449894 -134.340346)
		(end 224.722182 -134.340346)
		(width 0.14224)
		(layer "In2.Cu")
		(net "M_D_DQ<29>")
	)
	(segment
		(start 233.877104 -99.76739)
		(end 233.916728 -99.76739)
		(width 0.0889)
		(layer "In2.Cu")
		(net "M_D_DQ<29>")
	)
	(segment
		(start 237.314232 -97.78619)
		(end 237.346998 -97.78619)
		(width 0.0889)
		(layer "In2.Cu")
		(net "M_D_DQ<29>")
	)
	(segment
		(start 226.20986 -123.075446)
		(end 225.68154 -123.075446)
		(width 0.14224)
		(layer "In2.Cu")
		(net "M_D_DQ<29>")
	)
	(segment
		(start 225.447098 -130.330956)
		(end 225.6536 -130.124454)
		(width 0.14224)
		(layer "In2.Cu")
		(net "M_D_DQ<29>")
	)
	(segment
		(start 234.742482 -99.27209)
		(end 234.775248 -99.27209)
		(width 0.0889)
		(layer "In2.Cu")
		(net "M_D_DQ<29>")
	)
	(segment
		(start 225.3488 -127.405384)
		(end 225.3488 -125.7808)
		(width 0.14224)
		(layer "In2.Cu")
		(net "M_D_DQ<29>")
	)
	(segment
		(start 231.700324 -101.683566)
		(end 233.06151 -100.322126)
		(width 0.0889)
		(layer "In2.Cu")
		(net "M_D_DQ<29>")
	)
	(segment
		(start 226.3648 -122.107706)
		(end 226.3648 -117.424454)
		(width 0.14224)
		(layer "In2.Cu")
		(net "M_D_DQ<29>")
	)
	(segment
		(start 226.3648 -123.230386)
		(end 226.20986 -123.075446)
		(width 0.14224)
		(layer "In2.Cu")
		(net "M_D_DQ<29>")
	)
	(segment
		(start 228.6127 -104.755696)
		(end 230.418894 -102.949502)
		(width 0.14224)
		(layer "In2.Cu")
		(net "M_D_DQ<29>")
	)
	(segment
		(start 225.68154 -122.262646)
		(end 226.20986 -122.262646)
		(width 0.14224)
		(layer "In2.Cu")
		(net "M_D_DQ<29>")
	)
	(segment
		(start 225.3488 -129.030984)
		(end 225.3488 -128.522984)
		(width 0.14224)
		(layer "In2.Cu")
		(net "M_D_DQ<29>")
	)
	(segment
		(start 233.42854 -100.174044)
		(end 233.54792 -99.967034)
		(width 0.0889)
		(layer "In2.Cu")
		(net "M_D_DQ<29>")
	)
	(segment
		(start 225.666046 -111.080296)
		(end 228.6127 -108.133642)
		(width 0.14224)
		(layer "In2.Cu")
		(net "M_D_DQ<29>")
	)
	(segment
		(start 225.223578 -130.330956)
		(end 225.447098 -130.330956)
		(width 0.14224)
		(layer "In2.Cu")
		(net "M_D_DQ<29>")
	)
	(arc
		(start 233.548428 -99.967288)
		(mid 233.687172 -99.825255)
		(end 233.877104 -99.76739)
		(width 0.0889)
		(layer "In2.Cu")
		(net "M_D_DQ<29>")
	)
	(arc
		(start 238.209328 -97.290636)
		(mid 238.492545 -97.206355)
		(end 238.699548 -96.995488)
		(width 0.0889)
		(layer "In2.Cu")
		(net "M_D_DQ<29>")
	)
	(arc
		(start 239.558068 -96.500188)
		(mid 239.679959 -96.368992)
		(end 239.846866 -96.3041)
		(width 0.0889)
		(layer "In2.Cu")
		(net "M_D_DQ<29>")
	)
	(arc
		(start 234.775248 -99.27209)
		(mid 235.058465 -99.187809)
		(end 235.265468 -98.976942)
		(width 0.0889)
		(layer "In2.Cu")
		(net "M_D_DQ<29>")
	)
	(arc
		(start 239.064038 -96.79559)
		(mid 239.349462 -96.712123)
		(end 239.558068 -96.500188)
		(width 0.0889)
		(layer "In2.Cu")
		(net "M_D_DQ<29>")
	)
	(arc
		(start 234.406948 -99.472242)
		(mid 234.548631 -99.328438)
		(end 234.742482 -99.27209)
		(width 0.0889)
		(layer "In2.Cu")
		(net "M_D_DQ<29>")
	)
	(arc
		(start 237.346998 -97.78619)
		(mid 237.632422 -97.702723)
		(end 237.841028 -97.490788)
		(width 0.0889)
		(layer "In2.Cu")
		(net "M_D_DQ<29>")
	)
	(arc
		(start 236.982508 -97.986088)
		(mid 237.122587 -97.843352)
		(end 237.314232 -97.78619)
		(width 0.0889)
		(layer "In2.Cu")
		(net "M_D_DQ<29>")
	)
	(arc
		(start 235.629958 -98.77679)
		(mid 235.915382 -98.693323)
		(end 236.123988 -98.481388)
		(width 0.0889)
		(layer "In2.Cu")
		(net "M_D_DQ<29>")
	)
	(arc
		(start 238.699548 -96.995488)
		(mid 238.839627 -96.852752)
		(end 239.031272 -96.79559)
		(width 0.0889)
		(layer "In2.Cu")
		(net "M_D_DQ<29>")
	)
	(arc
		(start 233.916728 -99.76739)
		(mid 234.199945 -99.683109)
		(end 234.406948 -99.472242)
		(width 0.0889)
		(layer "In2.Cu")
		(net "M_D_DQ<29>")
	)
	(arc
		(start 235.265468 -98.976942)
		(mid 235.407151 -98.833138)
		(end 235.601002 -98.77679)
		(width 0.0889)
		(layer "In2.Cu")
		(net "M_D_DQ<29>")
	)
	(arc
		(start 237.841028 -97.490788)
		(mid 237.982711 -97.346984)
		(end 238.176562 -97.290636)
		(width 0.0889)
		(layer "In2.Cu")
		(net "M_D_DQ<29>")
	)
	(arc
		(start 236.123988 -98.481388)
		(mid 236.265671 -98.337584)
		(end 236.459522 -98.281236)
		(width 0.0889)
		(layer "In2.Cu")
		(net "M_D_DQ<29>")
	)
	(arc
		(start 236.492288 -98.281236)
		(mid 236.775505 -98.196955)
		(end 236.982508 -97.986088)
		(width 0.0889)
		(layer "In2.Cu")
		(net "M_D_DQ<29>")
	)
	(segment
		(start 240.476278 -95.709486)
		(end 239.904778 -95.709486)
		(width 0.1651)
		(layer "F.Cu")
		(net "M_D_DQ<28>")
	)
	(segment
		(start 225.300286 -137.67054)
		(end 225.299778 -137.67054)
		(width 0.1651)
		(layer "F.Cu")
		(net "M_D_DQ<28>")
	)
	(segment
		(start 225.299778 -137.67054)
		(end 225.299778 -136.345168)
		(width 0.1651)
		(layer "F.Cu")
		(net "M_D_DQ<28>")
	)
	(segment
		(start 225.299778 -136.345168)
		(end 225.201734 -135.8138)
		(width 0.1651)
		(layer "F.Cu")
		(net "M_D_DQ<28>")
	)
	(via
		(at 239.904778 -95.709486)
		(size 0.508)
		(drill 0.254)
		(layers "F.Cu" "B.Cu")
		(net "M_D_DQ<28>")
	)
	(via
		(at 225.201734 -135.8138)
		(size 0.508)
		(drill 0.254)
		(layers "F.Cu" "B.Cu")
		(net "M_D_DQ<28>")
	)
	(via
		(at 224.449894 -131.611878)
		(size 0.508)
		(drill 0.254)
		(layers "F.Cu" "B.Cu")
		(net "M_D_DQ<28>")
	)
	(segment
		(start 224.450402 -132.876036)
		(end 224.449894 -132.875782)
		(width 0.1651)
		(layer "B.Cu")
		(net "M_D_DQ<28>")
	)
	(segment
		(start 224.449894 -132.875782)
		(end 224.449894 -131.611878)
		(width 0.1651)
		(layer "B.Cu")
		(net "M_D_DQ<28>")
	)
	(segment
		(start 227.9777 -104.474518)
		(end 227.9777 -107.870498)
		(width 0.14224)
		(layer "In2.Cu")
		(net "M_D_DQ<28>")
	)
	(segment
		(start 239.904778 -96.04756)
		(end 239.8395 -96.112838)
		(width 0.0889)
		(layer "In2.Cu")
		(net "M_D_DQ<28>")
	)
	(segment
		(start 232.98277 -100.132134)
		(end 231.621584 -101.493574)
		(width 0.0889)
		(layer "In2.Cu")
		(net "M_D_DQ<28>")
	)
	(segment
		(start 231.321864 -101.493574)
		(end 230.324152 -102.491286)
		(width 0.0889)
		(layer "In2.Cu")
		(net "M_D_DQ<28>")
	)
	(segment
		(start 224.0788 -131.408424)
		(end 224.282254 -131.611878)
		(width 0.14224)
		(layer "In2.Cu")
		(net "M_D_DQ<28>")
	)
	(segment
		(start 231.621584 -101.493574)
		(end 231.321864 -101.493574)
		(width 0.0889)
		(layer "In2.Cu")
		(net "M_D_DQ<28>")
	)
	(segment
		(start 237.340394 -97.59569)
		(end 237.307628 -97.59569)
		(width 0.0889)
		(layer "In2.Cu")
		(net "M_D_DQ<28>")
	)
	(segment
		(start 224.9424 -122.0216)
		(end 224.9424 -124.1552)
		(width 0.14224)
		(layer "In2.Cu")
		(net "M_D_DQ<28>")
	)
	(segment
		(start 224.016824 -132.044948)
		(end 224.016824 -134.57809)
		(width 0.14224)
		(layer "In2.Cu")
		(net "M_D_DQ<28>")
	)
	(segment
		(start 224.174812 -134.736078)
		(end 224.174812 -135.03783)
		(width 0.14224)
		(layer "In2.Cu")
		(net "M_D_DQ<28>")
	)
	(segment
		(start 233.201718 -100.132134)
		(end 232.98277 -100.132134)
		(width 0.0889)
		(layer "In2.Cu")
		(net "M_D_DQ<28>")
	)
	(segment
		(start 224.9424 -124.1552)
		(end 224.732596 -124.365004)
		(width 0.14224)
		(layer "In2.Cu")
		(net "M_D_DQ<28>")
	)
	(segment
		(start 229.960932 -102.491286)
		(end 227.9777 -104.474518)
		(width 0.14224)
		(layer "In2.Cu")
		(net "M_D_DQ<28>")
	)
	(segment
		(start 236.485684 -98.090736)
		(end 236.452918 -98.090736)
		(width 0.0889)
		(layer "In2.Cu")
		(net "M_D_DQ<28>")
	)
	(segment
		(start 224.174812 -135.03783)
		(end 224.950782 -135.8138)
		(width 0.14224)
		(layer "In2.Cu")
		(net "M_D_DQ<28>")
	)
	(segment
		(start 239.904778 -95.709486)
		(end 239.904778 -96.04756)
		(width 0.0889)
		(layer "In2.Cu")
		(net "M_D_DQ<28>")
	)
	(segment
		(start 224.950782 -135.8138)
		(end 225.201734 -135.8138)
		(width 0.14224)
		(layer "In2.Cu")
		(net "M_D_DQ<28>")
	)
	(segment
		(start 224.0788 -130.613912)
		(end 224.0788 -131.408424)
		(width 0.14224)
		(layer "In2.Cu")
		(net "M_D_DQ<28>")
	)
	(segment
		(start 224.732596 -127.52705)
		(end 224.917 -127.711454)
		(width 0.14224)
		(layer "In2.Cu")
		(net "M_D_DQ<28>")
	)
	(segment
		(start 225.158046 -110.690152)
		(end 225.158046 -117.030246)
		(width 0.14224)
		(layer "In2.Cu")
		(net "M_D_DQ<28>")
	)
	(segment
		(start 225.6028 -117.475)
		(end 225.6028 -121.3612)
		(width 0.14224)
		(layer "In2.Cu")
		(net "M_D_DQ<28>")
	)
	(segment
		(start 225.158046 -117.030246)
		(end 225.6028 -117.475)
		(width 0.14224)
		(layer "In2.Cu")
		(net "M_D_DQ<28>")
	)
	(segment
		(start 233.383328 -99.872038)
		(end 233.276394 -100.057458)
		(width 0.0889)
		(layer "In2.Cu")
		(net "M_D_DQ<28>")
	)
	(segment
		(start 233.276394 -100.057458)
		(end 233.201718 -100.132134)
		(width 0.0889)
		(layer "In2.Cu")
		(net "M_D_DQ<28>")
	)
	(segment
		(start 235.623354 -98.58629)
		(end 235.590588 -98.58629)
		(width 0.0889)
		(layer "In2.Cu")
		(net "M_D_DQ<28>")
	)
	(segment
		(start 224.449894 -131.611878)
		(end 224.016824 -132.044948)
		(width 0.14224)
		(layer "In2.Cu")
		(net "M_D_DQ<28>")
	)
	(segment
		(start 224.917 -129.775712)
		(end 224.0788 -130.613912)
		(width 0.14224)
		(layer "In2.Cu")
		(net "M_D_DQ<28>")
	)
	(segment
		(start 233.913172 -99.576636)
		(end 233.877358 -99.576636)
		(width 0.0889)
		(layer "In2.Cu")
		(net "M_D_DQ<28>")
	)
	(segment
		(start 224.016824 -134.57809)
		(end 224.174812 -134.736078)
		(width 0.14224)
		(layer "In2.Cu")
		(net "M_D_DQ<28>")
	)
	(segment
		(start 234.764834 -99.08159)
		(end 234.732068 -99.08159)
		(width 0.0889)
		(layer "In2.Cu")
		(net "M_D_DQ<28>")
	)
	(segment
		(start 227.9777 -107.870498)
		(end 225.158046 -110.690152)
		(width 0.14224)
		(layer "In2.Cu")
		(net "M_D_DQ<28>")
	)
	(segment
		(start 239.057434 -96.60509)
		(end 239.024668 -96.60509)
		(width 0.0889)
		(layer "In2.Cu")
		(net "M_D_DQ<28>")
	)
	(segment
		(start 224.917 -127.711454)
		(end 224.917 -129.775712)
		(width 0.14224)
		(layer "In2.Cu")
		(net "M_D_DQ<28>")
	)
	(segment
		(start 224.732596 -124.365004)
		(end 224.732596 -127.52705)
		(width 0.14224)
		(layer "In2.Cu")
		(net "M_D_DQ<28>")
	)
	(segment
		(start 225.6028 -121.3612)
		(end 224.9424 -122.0216)
		(width 0.14224)
		(layer "In2.Cu")
		(net "M_D_DQ<28>")
	)
	(segment
		(start 230.324152 -102.491286)
		(end 229.960932 -102.491286)
		(width 0.0889)
		(layer "In2.Cu")
		(net "M_D_DQ<28>")
	)
	(segment
		(start 224.282254 -131.611878)
		(end 224.449894 -131.611878)
		(width 0.14224)
		(layer "In2.Cu")
		(net "M_D_DQ<28>")
	)
	(segment
		(start 238.202724 -97.100136)
		(end 238.169958 -97.100136)
		(width 0.0889)
		(layer "In2.Cu")
		(net "M_D_DQ<28>")
	)
	(arc
		(start 236.452918 -98.090736)
		(mid 236.167494 -98.174203)
		(end 235.958888 -98.386138)
		(width 0.0889)
		(layer "In2.Cu")
		(net "M_D_DQ<28>")
	)
	(arc
		(start 235.958888 -98.386138)
		(mid 235.817205 -98.529942)
		(end 235.623354 -98.58629)
		(width 0.0889)
		(layer "In2.Cu")
		(net "M_D_DQ<28>")
	)
	(arc
		(start 234.732068 -99.08159)
		(mid 234.448851 -99.165871)
		(end 234.241848 -99.376738)
		(width 0.0889)
		(layer "In2.Cu")
		(net "M_D_DQ<28>")
	)
	(arc
		(start 239.392968 -96.404938)
		(mid 239.251285 -96.548742)
		(end 239.057434 -96.60509)
		(width 0.0889)
		(layer "In2.Cu")
		(net "M_D_DQ<28>")
	)
	(arc
		(start 239.024668 -96.60509)
		(mid 238.741451 -96.689371)
		(end 238.534448 -96.900238)
		(width 0.0889)
		(layer "In2.Cu")
		(net "M_D_DQ<28>")
	)
	(arc
		(start 235.590588 -98.58629)
		(mid 235.307371 -98.670571)
		(end 235.100368 -98.881438)
		(width 0.0889)
		(layer "In2.Cu")
		(net "M_D_DQ<28>")
	)
	(arc
		(start 237.307628 -97.59569)
		(mid 237.024411 -97.679971)
		(end 236.817408 -97.890838)
		(width 0.0889)
		(layer "In2.Cu")
		(net "M_D_DQ<28>")
	)
	(arc
		(start 233.877358 -99.576636)
		(mid 233.591934 -99.660103)
		(end 233.383328 -99.872038)
		(width 0.0889)
		(layer "In2.Cu")
		(net "M_D_DQ<28>")
	)
	(arc
		(start 239.8395 -96.112838)
		(mid 239.581363 -96.205592)
		(end 239.392968 -96.404938)
		(width 0.0889)
		(layer "In2.Cu")
		(net "M_D_DQ<28>")
	)
	(arc
		(start 238.169958 -97.100136)
		(mid 237.884534 -97.183603)
		(end 237.675928 -97.395538)
		(width 0.0889)
		(layer "In2.Cu")
		(net "M_D_DQ<28>")
	)
	(arc
		(start 234.241848 -99.376738)
		(mid 234.103104 -99.518771)
		(end 233.913172 -99.576636)
		(width 0.0889)
		(layer "In2.Cu")
		(net "M_D_DQ<28>")
	)
	(arc
		(start 238.534448 -96.900238)
		(mid 238.394369 -97.042974)
		(end 238.202724 -97.100136)
		(width 0.0889)
		(layer "In2.Cu")
		(net "M_D_DQ<28>")
	)
	(arc
		(start 237.675928 -97.395538)
		(mid 237.534245 -97.539342)
		(end 237.340394 -97.59569)
		(width 0.0889)
		(layer "In2.Cu")
		(net "M_D_DQ<28>")
	)
	(arc
		(start 235.100368 -98.881438)
		(mid 234.958685 -99.025242)
		(end 234.764834 -99.08159)
		(width 0.0889)
		(layer "In2.Cu")
		(net "M_D_DQ<28>")
	)
	(arc
		(start 236.817408 -97.890838)
		(mid 236.677329 -98.033574)
		(end 236.485684 -98.090736)
		(width 0.0889)
		(layer "In2.Cu")
		(net "M_D_DQ<28>")
	)
	(segment
		(start 243.910104 -96.700086)
		(end 243.338604 -96.700086)
		(width 0.1651)
		(layer "F.Cu")
		(net "M_D_DQ<27>")
	)
	(segment
		(start 232.099866 -133.076442)
		(end 232.099866 -134.340346)
		(width 0.1651)
		(layer "F.Cu")
		(net "M_D_DQ<27>")
	)
	(segment
		(start 232.100374 -133.0706)
		(end 232.099866 -133.076442)
		(width 0.1651)
		(layer "F.Cu")
		(net "M_D_DQ<27>")
	)
	(via
		(at 232.94975 -130.330956)
		(size 0.508)
		(drill 0.254)
		(layers "F.Cu" "B.Cu")
		(net "M_D_DQ<27>")
	)
	(via
		(at 243.338604 -96.700086)
		(size 0.508)
		(drill 0.254)
		(layers "F.Cu" "B.Cu")
		(net "M_D_DQ<27>")
	)
	(via
		(at 232.099866 -134.340346)
		(size 0.508)
		(drill 0.254)
		(layers "F.Cu" "B.Cu")
		(net "M_D_DQ<27>")
	)
	(segment
		(start 232.950512 -128.276096)
		(end 232.94975 -128.276096)
		(width 0.1651)
		(layer "B.Cu")
		(net "M_D_DQ<27>")
	)
	(segment
		(start 232.94975 -128.276096)
		(end 232.94975 -130.330956)
		(width 0.1651)
		(layer "B.Cu")
		(net "M_D_DQ<27>")
	)
	(segment
		(start 232.927398 -130.330956)
		(end 232.499154 -130.7592)
		(width 0.14224)
		(layer "In2.Cu")
		(net "M_D_DQ<27>")
	)
	(segment
		(start 234.78744 -112.73028)
		(end 234.6452 -112.87252)
		(width 0.14224)
		(layer "In2.Cu")
		(net "M_D_DQ<27>")
	)
	(segment
		(start 232.372154 -134.340346)
		(end 232.099866 -134.340346)
		(width 0.14224)
		(layer "In2.Cu")
		(net "M_D_DQ<27>")
	)
	(segment
		(start 235.13796 -114.03076)
		(end 234.78744 -114.03076)
		(width 0.14224)
		(layer "In2.Cu")
		(net "M_D_DQ<27>")
	)
	(segment
		(start 236.334046 -105.19029)
		(end 234.6452 -106.879136)
		(width 0.14224)
		(layer "In2.Cu")
		(net "M_D_DQ<27>")
	)
	(segment
		(start 239.558068 -101.452934)
		(end 239.466628 -101.611176)
		(width 0.0889)
		(layer "In2.Cu")
		(net "M_D_DQ<27>")
	)
	(segment
		(start 235.13796 -110.77956)
		(end 235.2802 -110.9218)
		(width 0.14224)
		(layer "In2.Cu")
		(net "M_D_DQ<27>")
	)
	(segment
		(start 234.6452 -111.9378)
		(end 234.78744 -112.08004)
		(width 0.14224)
		(layer "In2.Cu")
		(net "M_D_DQ<27>")
	)
	(segment
		(start 234.78744 -114.03076)
		(end 234.6452 -114.173)
		(width 0.14224)
		(layer "In2.Cu")
		(net "M_D_DQ<27>")
	)
	(segment
		(start 233.8324 -116.1542)
		(end 233.405934 -116.1542)
		(width 0.14224)
		(layer "In2.Cu")
		(net "M_D_DQ<27>")
	)
	(segment
		(start 239.922558 -101.253036)
		(end 239.886744 -101.253036)
		(width 0.0889)
		(layer "In2.Cu")
		(net "M_D_DQ<27>")
	)
	(segment
		(start 234.78744 -112.08004)
		(end 235.13796 -112.08004)
		(width 0.14224)
		(layer "In2.Cu")
		(net "M_D_DQ<27>")
	)
	(segment
		(start 232.94975 -130.330956)
		(end 232.927398 -130.330956)
		(width 0.14224)
		(layer "In2.Cu")
		(net "M_D_DQ<27>")
	)
	(segment
		(start 232.261156 -133.550152)
		(end 232.549954 -133.83895)
		(width 0.14224)
		(layer "In2.Cu")
		(net "M_D_DQ<27>")
	)
	(segment
		(start 234.6452 -106.879136)
		(end 234.6452 -110.63732)
		(width 0.14224)
		(layer "In2.Cu")
		(net "M_D_DQ<27>")
	)
	(segment
		(start 233.426 -122.7328)
		(end 233.426 -126.281942)
		(width 0.14224)
		(layer "In2.Cu")
		(net "M_D_DQ<27>")
	)
	(segment
		(start 236.334046 -104.865424)
		(end 236.334046 -105.19029)
		(width 0.0889)
		(layer "In2.Cu")
		(net "M_D_DQ<27>")
	)
	(segment
		(start 237.640876 -103.558594)
		(end 236.334046 -104.865424)
		(width 0.0889)
		(layer "In2.Cu")
		(net "M_D_DQ<27>")
	)
	(segment
		(start 234.6452 -112.87252)
		(end 234.6452 -113.23828)
		(width 0.14224)
		(layer "In2.Cu")
		(net "M_D_DQ<27>")
	)
	(segment
		(start 232.543604 -131.233418)
		(end 232.543604 -131.9022)
		(width 0.14224)
		(layer "In2.Cu")
		(net "M_D_DQ<27>")
	)
	(segment
		(start 241.634772 -100.262436)
		(end 241.610642 -100.262436)
		(width 0.0889)
		(layer "In2.Cu")
		(net "M_D_DQ<27>")
	)
	(segment
		(start 232.261156 -133.276848)
		(end 232.261156 -133.550152)
		(width 0.14224)
		(layer "In2.Cu")
		(net "M_D_DQ<27>")
	)
	(segment
		(start 232.549954 -134.162546)
		(end 232.372154 -134.340346)
		(width 0.14224)
		(layer "In2.Cu")
		(net "M_D_DQ<27>")
	)
	(segment
		(start 234.4674 -116.84)
		(end 234.1118 -116.84)
		(width 0.14224)
		(layer "In2.Cu")
		(net "M_D_DQ<27>")
	)
	(segment
		(start 238.644938 -102.432866)
		(end 238.085884 -102.432866)
		(width 0.0889)
		(layer "In2.Cu")
		(net "M_D_DQ<27>")
	)
	(segment
		(start 239.466628 -101.611176)
		(end 238.644938 -102.432866)
		(width 0.0889)
		(layer "In2.Cu")
		(net "M_D_DQ<27>")
	)
	(segment
		(start 243.338604 -96.700086)
		(end 243.338604 -96.362012)
		(width 0.0889)
		(layer "In2.Cu")
		(net "M_D_DQ<27>")
	)
	(segment
		(start 235.2802 -113.52276)
		(end 235.2802 -113.88852)
		(width 0.14224)
		(layer "In2.Cu")
		(net "M_D_DQ<27>")
	)
	(segment
		(start 233.278934 -130.01498)
		(end 232.94975 -130.344164)
		(width 0.14224)
		(layer "In2.Cu")
		(net "M_D_DQ<27>")
	)
	(segment
		(start 235.2802 -113.88852)
		(end 235.13796 -114.03076)
		(width 0.14224)
		(layer "In2.Cu")
		(net "M_D_DQ<27>")
	)
	(segment
		(start 235.13796 -112.73028)
		(end 234.78744 -112.73028)
		(width 0.14224)
		(layer "In2.Cu")
		(net "M_D_DQ<27>")
	)
	(segment
		(start 233.426 -126.281942)
		(end 233.278934 -126.429008)
		(width 0.14224)
		(layer "In2.Cu")
		(net "M_D_DQ<27>")
	)
	(segment
		(start 232.94975 -130.344164)
		(end 232.94975 -130.330956)
		(width 0.14224)
		(layer "In2.Cu")
		(net "M_D_DQ<27>")
	)
	(segment
		(start 243.338604 -96.362012)
		(end 243.280946 -96.304354)
		(width 0.0889)
		(layer "In2.Cu")
		(net "M_D_DQ<27>")
	)
	(segment
		(start 232.518204 -133.0198)
		(end 232.261156 -133.276848)
		(width 0.14224)
		(layer "In2.Cu")
		(net "M_D_DQ<27>")
	)
	(segment
		(start 234.6452 -113.23828)
		(end 234.78744 -113.38052)
		(width 0.14224)
		(layer "In2.Cu")
		(net "M_D_DQ<27>")
	)
	(segment
		(start 234.78744 -110.77956)
		(end 235.13796 -110.77956)
		(width 0.14224)
		(layer "In2.Cu")
		(net "M_D_DQ<27>")
	)
	(segment
		(start 240.784888 -100.757736)
		(end 240.745264 -100.757736)
		(width 0.0889)
		(layer "In2.Cu")
		(net "M_D_DQ<27>")
	)
	(segment
		(start 235.13796 -113.38052)
		(end 235.2802 -113.52276)
		(width 0.14224)
		(layer "In2.Cu")
		(net "M_D_DQ<27>")
	)
	(segment
		(start 242.498118 -99.76739)
		(end 242.480338 -99.76739)
		(width 0.0889)
		(layer "In2.Cu")
		(net "M_D_DQ<27>")
	)
	(segment
		(start 233.278934 -126.429008)
		(end 233.278934 -130.01498)
		(width 0.14224)
		(layer "In2.Cu")
		(net "M_D_DQ<27>")
	)
	(segment
		(start 233.278934 -116.2812)
		(end 233.278934 -122.585734)
		(width 0.14224)
		(layer "In2.Cu")
		(net "M_D_DQ<27>")
	)
	(segment
		(start 235.13796 -112.08004)
		(end 235.2802 -112.22228)
		(width 0.14224)
		(layer "In2.Cu")
		(net "M_D_DQ<27>")
	)
	(segment
		(start 233.278934 -122.585734)
		(end 233.426 -122.7328)
		(width 0.14224)
		(layer "In2.Cu")
		(net "M_D_DQ<27>")
	)
	(segment
		(start 234.6452 -110.63732)
		(end 234.78744 -110.77956)
		(width 0.14224)
		(layer "In2.Cu")
		(net "M_D_DQ<27>")
	)
	(segment
		(start 234.78744 -113.38052)
		(end 235.13796 -113.38052)
		(width 0.14224)
		(layer "In2.Cu")
		(net "M_D_DQ<27>")
	)
	(segment
		(start 243.001038 -97.475548)
		(end 242.992148 -97.490788)
		(width 0.0889)
		(layer "In2.Cu")
		(net "M_D_DQ<27>")
	)
	(segment
		(start 232.499154 -130.7592)
		(end 232.499154 -131.188968)
		(width 0.14224)
		(layer "In2.Cu")
		(net "M_D_DQ<27>")
	)
	(segment
		(start 232.261156 -132.184648)
		(end 232.261156 -132.457952)
		(width 0.14224)
		(layer "In2.Cu")
		(net "M_D_DQ<27>")
	)
	(segment
		(start 234.78744 -111.4298)
		(end 234.6452 -111.57204)
		(width 0.14224)
		(layer "In2.Cu")
		(net "M_D_DQ<27>")
	)
	(segment
		(start 232.261156 -132.457952)
		(end 232.518204 -132.715)
		(width 0.14224)
		(layer "In2.Cu")
		(net "M_D_DQ<27>")
	)
	(segment
		(start 235.13796 -111.4298)
		(end 234.78744 -111.4298)
		(width 0.14224)
		(layer "In2.Cu")
		(net "M_D_DQ<27>")
	)
	(segment
		(start 233.405934 -116.1542)
		(end 233.278934 -116.2812)
		(width 0.14224)
		(layer "In2.Cu")
		(net "M_D_DQ<27>")
	)
	(segment
		(start 235.2802 -112.58804)
		(end 235.13796 -112.73028)
		(width 0.14224)
		(layer "In2.Cu")
		(net "M_D_DQ<27>")
	)
	(segment
		(start 243.001038 -98.466148)
		(end 242.992148 -98.481388)
		(width 0.0889)
		(layer "In2.Cu")
		(net "M_D_DQ<27>")
	)
	(segment
		(start 234.6452 -116.6622)
		(end 234.4674 -116.84)
		(width 0.14224)
		(layer "In2.Cu")
		(net "M_D_DQ<27>")
	)
	(segment
		(start 237.640876 -102.877874)
		(end 237.640876 -103.558594)
		(width 0.0889)
		(layer "In2.Cu")
		(net "M_D_DQ<27>")
	)
	(segment
		(start 233.9594 -116.2812)
		(end 233.8324 -116.1542)
		(width 0.14224)
		(layer "In2.Cu")
		(net "M_D_DQ<27>")
	)
	(segment
		(start 234.6452 -111.57204)
		(end 234.6452 -111.9378)
		(width 0.14224)
		(layer "In2.Cu")
		(net "M_D_DQ<27>")
	)
	(segment
		(start 234.6452 -114.173)
		(end 234.6452 -116.6622)
		(width 0.14224)
		(layer "In2.Cu")
		(net "M_D_DQ<27>")
	)
	(segment
		(start 232.543604 -131.9022)
		(end 232.261156 -132.184648)
		(width 0.14224)
		(layer "In2.Cu")
		(net "M_D_DQ<27>")
	)
	(segment
		(start 235.2802 -112.22228)
		(end 235.2802 -112.58804)
		(width 0.14224)
		(layer "In2.Cu")
		(net "M_D_DQ<27>")
	)
	(segment
		(start 238.085884 -102.432866)
		(end 237.640876 -102.877874)
		(width 0.0889)
		(layer "In2.Cu")
		(net "M_D_DQ<27>")
	)
	(segment
		(start 232.499154 -131.188968)
		(end 232.543604 -131.233418)
		(width 0.14224)
		(layer "In2.Cu")
		(net "M_D_DQ<27>")
	)
	(segment
		(start 233.9594 -116.6876)
		(end 233.9594 -116.2812)
		(width 0.14224)
		(layer "In2.Cu")
		(net "M_D_DQ<27>")
	)
	(segment
		(start 235.2802 -111.28756)
		(end 235.13796 -111.4298)
		(width 0.14224)
		(layer "In2.Cu")
		(net "M_D_DQ<27>")
	)
	(segment
		(start 232.549954 -133.83895)
		(end 232.549954 -134.162546)
		(width 0.14224)
		(layer "In2.Cu")
		(net "M_D_DQ<27>")
	)
	(segment
		(start 232.518204 -132.715)
		(end 232.518204 -133.0198)
		(width 0.14224)
		(layer "In2.Cu")
		(net "M_D_DQ<27>")
	)
	(segment
		(start 235.2802 -110.9218)
		(end 235.2802 -111.28756)
		(width 0.14224)
		(layer "In2.Cu")
		(net "M_D_DQ<27>")
	)
	(segment
		(start 234.1118 -116.84)
		(end 233.9594 -116.6876)
		(width 0.14224)
		(layer "In2.Cu")
		(net "M_D_DQ<27>")
	)
	(arc
		(start 240.745264 -100.757736)
		(mid 240.555335 -100.815606)
		(end 240.416588 -100.957634)
		(width 0.0889)
		(layer "In2.Cu")
		(net "M_D_DQ<27>")
	)
	(arc
		(start 242.992148 -97.890584)
		(mid 243.071337 -98.177199)
		(end 243.001038 -98.466148)
		(width 0.0889)
		(layer "In2.Cu")
		(net "M_D_DQ<27>")
	)
	(arc
		(start 240.416588 -100.957634)
		(mid 240.20798 -101.169566)
		(end 239.922558 -101.253036)
		(width 0.0889)
		(layer "In2.Cu")
		(net "M_D_DQ<27>")
	)
	(arc
		(start 242.992148 -98.481388)
		(mid 242.938615 -98.681286)
		(end 242.992148 -98.881184)
		(width 0.0889)
		(layer "In2.Cu")
		(net "M_D_DQ<27>")
	)
	(arc
		(start 242.992148 -97.490788)
		(mid 242.938615 -97.690686)
		(end 242.992148 -97.890584)
		(width 0.0889)
		(layer "In2.Cu")
		(net "M_D_DQ<27>")
	)
	(arc
		(start 242.480338 -99.76739)
		(mid 242.472844 -99.767326)
		(end 242.465352 -99.767136)
		(width 0.0889)
		(layer "In2.Cu")
		(net "M_D_DQ<27>")
	)
	(arc
		(start 242.992148 -98.881184)
		(mid 242.996476 -99.46436)
		(end 242.498118 -99.76739)
		(width 0.0889)
		(layer "In2.Cu")
		(net "M_D_DQ<27>")
	)
	(arc
		(start 241.610642 -100.262436)
		(mid 241.416792 -100.318786)
		(end 241.275108 -100.462588)
		(width 0.0889)
		(layer "In2.Cu")
		(net "M_D_DQ<27>")
	)
	(arc
		(start 241.275108 -100.462588)
		(mid 241.068104 -100.673452)
		(end 240.784888 -100.757736)
		(width 0.0889)
		(layer "In2.Cu")
		(net "M_D_DQ<27>")
	)
	(arc
		(start 239.886744 -101.253036)
		(mid 239.696815 -101.310906)
		(end 239.558068 -101.452934)
		(width 0.0889)
		(layer "In2.Cu")
		(net "M_D_DQ<27>")
	)
	(arc
		(start 242.133628 -99.967034)
		(mid 241.922915 -100.180113)
		(end 241.634772 -100.262436)
		(width 0.0889)
		(layer "In2.Cu")
		(net "M_D_DQ<27>")
	)
	(arc
		(start 242.992148 -96.899984)
		(mid 243.071337 -97.186599)
		(end 243.001038 -97.475548)
		(width 0.0889)
		(layer "In2.Cu")
		(net "M_D_DQ<27>")
	)
	(arc
		(start 243.280946 -96.304354)
		(mid 242.978749 -96.525636)
		(end 242.992148 -96.899984)
		(width 0.0889)
		(layer "In2.Cu")
		(net "M_D_DQ<27>")
	)
	(arc
		(start 242.465352 -99.767136)
		(mid 242.27371 -99.824302)
		(end 242.133628 -99.967034)
		(width 0.0889)
		(layer "In2.Cu")
		(net "M_D_DQ<27>")
	)
	(segment
		(start 233.081322 -136.54786)
		(end 233.081322 -136.32434)
		(width 0.1651)
		(layer "F.Cu")
		(net "M_D_DQ<26>")
	)
	(segment
		(start 232.94975 -137.67054)
		(end 232.94975 -136.679432)
		(width 0.1651)
		(layer "F.Cu")
		(net "M_D_DQ<26>")
	)
	(segment
		(start 232.94975 -136.679432)
		(end 233.081322 -136.54786)
		(width 0.1651)
		(layer "F.Cu")
		(net "M_D_DQ<26>")
	)
	(segment
		(start 232.94975 -136.192768)
		(end 232.94975 -135.9154)
		(width 0.1651)
		(layer "F.Cu")
		(net "M_D_DQ<26>")
	)
	(segment
		(start 232.950512 -137.67054)
		(end 232.94975 -137.67054)
		(width 0.1651)
		(layer "F.Cu")
		(net "M_D_DQ<26>")
	)
	(segment
		(start 233.081322 -136.32434)
		(end 232.94975 -136.192768)
		(width 0.1651)
		(layer "F.Cu")
		(net "M_D_DQ<26>")
	)
	(segment
		(start 243.910104 -95.709486)
		(end 243.338604 -95.709486)
		(width 0.1651)
		(layer "F.Cu")
		(net "M_D_DQ<26>")
	)
	(via
		(at 232.94975 -135.9154)
		(size 0.508)
		(drill 0.254)
		(layers "F.Cu" "B.Cu")
		(net "M_D_DQ<26>")
	)
	(via
		(at 243.338604 -95.709486)
		(size 0.508)
		(drill 0.254)
		(layers "F.Cu" "B.Cu")
		(net "M_D_DQ<26>")
	)
	(via
		(at 232.099866 -131.611878)
		(size 0.508)
		(drill 0.254)
		(layers "F.Cu" "B.Cu")
		(net "M_D_DQ<26>")
	)
	(segment
		(start 232.100374 -132.876036)
		(end 232.099866 -132.875782)
		(width 0.1651)
		(layer "B.Cu")
		(net "M_D_DQ<26>")
	)
	(segment
		(start 232.099866 -132.875782)
		(end 232.099866 -131.611878)
		(width 0.1651)
		(layer "B.Cu")
		(net "M_D_DQ<26>")
	)
	(segment
		(start 242.49253 -99.576636)
		(end 242.458748 -99.576636)
		(width 0.0889)
		(layer "In2.Cu")
		(net "M_D_DQ<26>")
	)
	(segment
		(start 241.636804 -100.071682)
		(end 241.608864 -100.071682)
		(width 0.0889)
		(layer "In2.Cu")
		(net "M_D_DQ<26>")
	)
	(segment
		(start 231.666796 -132.044948)
		(end 231.666796 -134.632446)
		(width 0.14224)
		(layer "In2.Cu")
		(net "M_D_DQ<26>")
	)
	(segment
		(start 231.666796 -134.632446)
		(end 232.94975 -135.9154)
		(width 0.14224)
		(layer "In2.Cu")
		(net "M_D_DQ<26>")
	)
	(segment
		(start 232.537 -125.729746)
		(end 232.618534 -125.81128)
		(width 0.14224)
		(layer "In2.Cu")
		(net "M_D_DQ<26>")
	)
	(segment
		(start 237.450884 -102.799134)
		(end 237.450884 -103.479854)
		(width 0.0889)
		(layer "In2.Cu")
		(net "M_D_DQ<26>")
	)
	(segment
		(start 232.6386 -123.952)
		(end 232.537 -124.0536)
		(width 0.14224)
		(layer "In2.Cu")
		(net "M_D_DQ<26>")
	)
	(segment
		(start 236.198664 -104.732074)
		(end 235.888784 -104.732074)
		(width 0.0889)
		(layer "In2.Cu")
		(net "M_D_DQ<26>")
	)
	(segment
		(start 232.618534 -129.770378)
		(end 231.754934 -130.633978)
		(width 0.14224)
		(layer "In2.Cu")
		(net "M_D_DQ<26>")
	)
	(segment
		(start 232.6386 -114.681)
		(end 232.6386 -123.952)
		(width 0.14224)
		(layer "In2.Cu")
		(net "M_D_DQ<26>")
	)
	(segment
		(start 242.826794 -97.395538)
		(end 242.817904 -97.410778)
		(width 0.0889)
		(layer "In2.Cu")
		(net "M_D_DQ<26>")
	)
	(segment
		(start 243.338604 -96.04756)
		(end 243.273326 -96.112838)
		(width 0.0889)
		(layer "In2.Cu")
		(net "M_D_DQ<26>")
	)
	(segment
		(start 232.537 -124.0536)
		(end 232.537 -125.729746)
		(width 0.14224)
		(layer "In2.Cu")
		(net "M_D_DQ<26>")
	)
	(segment
		(start 238.56569 -102.242366)
		(end 238.007652 -102.242366)
		(width 0.0889)
		(layer "In2.Cu")
		(net "M_D_DQ<26>")
	)
	(segment
		(start 237.450884 -103.479854)
		(end 236.198664 -104.732074)
		(width 0.0889)
		(layer "In2.Cu")
		(net "M_D_DQ<26>")
	)
	(segment
		(start 235.882434 -104.738424)
		(end 233.9848 -106.636058)
		(width 0.14224)
		(layer "In2.Cu")
		(net "M_D_DQ<26>")
	)
	(segment
		(start 239.313974 -101.494082)
		(end 238.56569 -102.242366)
		(width 0.0889)
		(layer "In2.Cu")
		(net "M_D_DQ<26>")
	)
	(segment
		(start 239.922812 -101.062282)
		(end 239.883188 -101.062282)
		(width 0.0889)
		(layer "In2.Cu")
		(net "M_D_DQ<26>")
	)
	(segment
		(start 238.007652 -102.242366)
		(end 237.450884 -102.799134)
		(width 0.0889)
		(layer "In2.Cu")
		(net "M_D_DQ<26>")
	)
	(segment
		(start 233.3752 -115.4938)
		(end 233.3752 -114.7064)
		(width 0.14224)
		(layer "In2.Cu")
		(net "M_D_DQ<26>")
	)
	(segment
		(start 232.791 -114.5286)
		(end 232.6386 -114.681)
		(width 0.14224)
		(layer "In2.Cu")
		(net "M_D_DQ<26>")
	)
	(segment
		(start 233.1974 -114.5286)
		(end 232.791 -114.5286)
		(width 0.14224)
		(layer "In2.Cu")
		(net "M_D_DQ<26>")
	)
	(segment
		(start 233.9848 -106.636058)
		(end 233.9848 -115.4938)
		(width 0.14224)
		(layer "In2.Cu")
		(net "M_D_DQ<26>")
	)
	(segment
		(start 239.392968 -101.35743)
		(end 239.313974 -101.494082)
		(width 0.0889)
		(layer "In2.Cu")
		(net "M_D_DQ<26>")
	)
	(segment
		(start 232.099866 -131.611878)
		(end 231.666796 -132.044948)
		(width 0.14224)
		(layer "In2.Cu")
		(net "M_D_DQ<26>")
	)
	(segment
		(start 232.618534 -125.81128)
		(end 232.618534 -129.770378)
		(width 0.14224)
		(layer "In2.Cu")
		(net "M_D_DQ<26>")
	)
	(segment
		(start 243.338604 -95.709486)
		(end 243.338604 -96.04756)
		(width 0.0889)
		(layer "In2.Cu")
		(net "M_D_DQ<26>")
	)
	(segment
		(start 233.8324 -115.6462)
		(end 233.5276 -115.6462)
		(width 0.14224)
		(layer "In2.Cu")
		(net "M_D_DQ<26>")
	)
	(segment
		(start 240.781332 -100.566982)
		(end 240.745518 -100.566982)
		(width 0.0889)
		(layer "In2.Cu")
		(net "M_D_DQ<26>")
	)
	(segment
		(start 235.888784 -104.732074)
		(end 235.882434 -104.738424)
		(width 0.0889)
		(layer "In2.Cu")
		(net "M_D_DQ<26>")
	)
	(segment
		(start 233.5276 -115.6462)
		(end 233.3752 -115.4938)
		(width 0.14224)
		(layer "In2.Cu")
		(net "M_D_DQ<26>")
	)
	(segment
		(start 233.3752 -114.7064)
		(end 233.1974 -114.5286)
		(width 0.14224)
		(layer "In2.Cu")
		(net "M_D_DQ<26>")
	)
	(segment
		(start 231.754934 -130.633978)
		(end 231.754934 -131.266946)
		(width 0.14224)
		(layer "In2.Cu")
		(net "M_D_DQ<26>")
	)
	(segment
		(start 231.754934 -131.266946)
		(end 232.099866 -131.611878)
		(width 0.14224)
		(layer "In2.Cu")
		(net "M_D_DQ<26>")
	)
	(segment
		(start 233.9848 -115.4938)
		(end 233.8324 -115.6462)
		(width 0.14224)
		(layer "In2.Cu")
		(net "M_D_DQ<26>")
	)
	(arc
		(start 242.817904 -97.410778)
		(mid 242.747507 -97.699729)
		(end 242.826794 -97.986342)
		(width 0.0889)
		(layer "In2.Cu")
		(net "M_D_DQ<26>")
	)
	(arc
		(start 242.826794 -97.986342)
		(mid 242.880327 -98.18624)
		(end 242.826794 -98.386138)
		(width 0.0889)
		(layer "In2.Cu")
		(net "M_D_DQ<26>")
	)
	(arc
		(start 241.968528 -99.871784)
		(mid 241.828449 -100.01452)
		(end 241.636804 -100.071682)
		(width 0.0889)
		(layer "In2.Cu")
		(net "M_D_DQ<26>")
	)
	(arc
		(start 241.608864 -100.071682)
		(mid 241.320719 -100.154001)
		(end 241.110008 -100.367084)
		(width 0.0889)
		(layer "In2.Cu")
		(net "M_D_DQ<26>")
	)
	(arc
		(start 240.251488 -100.862384)
		(mid 240.112744 -101.004417)
		(end 239.922812 -101.062282)
		(width 0.0889)
		(layer "In2.Cu")
		(net "M_D_DQ<26>")
	)
	(arc
		(start 242.458748 -99.576636)
		(mid 242.175531 -99.660917)
		(end 241.968528 -99.871784)
		(width 0.0889)
		(layer "In2.Cu")
		(net "M_D_DQ<26>")
	)
	(arc
		(start 241.110008 -100.367084)
		(mid 240.971264 -100.509117)
		(end 240.781332 -100.566982)
		(width 0.0889)
		(layer "In2.Cu")
		(net "M_D_DQ<26>")
	)
	(arc
		(start 239.883188 -101.062282)
		(mid 239.599971 -101.146563)
		(end 239.392968 -101.35743)
		(width 0.0889)
		(layer "In2.Cu")
		(net "M_D_DQ<26>")
	)
	(arc
		(start 242.826794 -98.976942)
		(mid 242.829719 -99.37158)
		(end 242.49253 -99.576636)
		(width 0.0889)
		(layer "In2.Cu")
		(net "M_D_DQ<26>")
	)
	(arc
		(start 242.817904 -98.401378)
		(mid 242.747507 -98.690329)
		(end 242.826794 -98.976942)
		(width 0.0889)
		(layer "In2.Cu")
		(net "M_D_DQ<26>")
	)
	(arc
		(start 243.273326 -96.112838)
		(mid 242.811107 -96.433435)
		(end 242.826794 -96.995742)
		(width 0.0889)
		(layer "In2.Cu")
		(net "M_D_DQ<26>")
	)
	(arc
		(start 240.745518 -100.566982)
		(mid 240.460094 -100.650449)
		(end 240.251488 -100.862384)
		(width 0.0889)
		(layer "In2.Cu")
		(net "M_D_DQ<26>")
	)
	(arc
		(start 242.826794 -96.995742)
		(mid 242.880327 -97.19564)
		(end 242.826794 -97.395538)
		(width 0.0889)
		(layer "In2.Cu")
		(net "M_D_DQ<26>")
	)
	(arc
		(start 242.826794 -98.386138)
		(mid 242.822216 -98.39368)
		(end 242.817904 -98.401378)
		(width 0.0889)
		(layer "In2.Cu")
		(net "M_D_DQ<26>")
	)
	(segment
		(start 226.150424 -133.0706)
		(end 226.149916 -133.076442)
		(width 0.1651)
		(layer "F.Cu")
		(net "M_D_DQ<25>")
	)
	(segment
		(start 241.334798 -97.19564)
		(end 240.763298 -97.19564)
		(width 0.1651)
		(layer "F.Cu")
		(net "M_D_DQ<25>")
	)
	(segment
		(start 226.149916 -133.076442)
		(end 226.149916 -134.340346)
		(width 0.1651)
		(layer "F.Cu")
		(net "M_D_DQ<25>")
	)
	(via
		(at 226.822 -130.330956)
		(size 0.508)
		(drill 0.254)
		(layers "F.Cu" "B.Cu")
		(net "M_D_DQ<25>")
	)
	(via
		(at 240.763298 -97.19564)
		(size 0.508)
		(drill 0.254)
		(layers "F.Cu" "B.Cu")
		(net "M_D_DQ<25>")
	)
	(via
		(at 226.149916 -134.340346)
		(size 0.508)
		(drill 0.254)
		(layers "F.Cu" "B.Cu")
		(net "M_D_DQ<25>")
	)
	(segment
		(start 226.9998 -129.649982)
		(end 226.822 -129.827782)
		(width 0.1651)
		(layer "B.Cu")
		(net "M_D_DQ<25>")
	)
	(segment
		(start 227.000308 -128.276096)
		(end 226.9998 -128.276096)
		(width 0.1651)
		(layer "B.Cu")
		(net "M_D_DQ<25>")
	)
	(segment
		(start 226.822 -129.827782)
		(end 226.822 -130.330956)
		(width 0.1651)
		(layer "B.Cu")
		(net "M_D_DQ<25>")
	)
	(segment
		(start 226.9998 -128.276096)
		(end 226.9998 -129.649982)
		(width 0.1651)
		(layer "B.Cu")
		(net "M_D_DQ<25>")
	)
	(segment
		(start 233.709464 -100.75799)
		(end 233.460036 -101.007418)
		(width 0.0889)
		(layer "In2.Cu")
		(net "M_D_DQ<25>")
	)
	(segment
		(start 226.550982 -133.8834)
		(end 226.550982 -134.1882)
		(width 0.14224)
		(layer "In2.Cu")
		(net "M_D_DQ<25>")
	)
	(segment
		(start 227.584 -114.50447)
		(end 227.584 -115.00739)
		(width 0.14224)
		(layer "In2.Cu")
		(net "M_D_DQ<25>")
	)
	(segment
		(start 234.771438 -100.26269)
		(end 234.735624 -100.26269)
		(width 0.0889)
		(layer "In2.Cu")
		(net "M_D_DQ<25>")
	)
	(segment
		(start 227.42906 -112.72393)
		(end 227.584 -112.87887)
		(width 0.14224)
		(layer "In2.Cu")
		(net "M_D_DQ<25>")
	)
	(segment
		(start 226.601782 -131.419346)
		(end 226.601782 -131.823968)
		(width 0.14224)
		(layer "In2.Cu")
		(net "M_D_DQ<25>")
	)
	(segment
		(start 226.398836 -134.340346)
		(end 226.149916 -134.340346)
		(width 0.14224)
		(layer "In2.Cu")
		(net "M_D_DQ<25>")
	)
	(segment
		(start 238.209328 -98.281236)
		(end 238.176562 -98.281236)
		(width 0.0889)
		(layer "In2.Cu")
		(net "M_D_DQ<25>")
	)
	(segment
		(start 227.584 -123.9266)
		(end 227.323396 -124.187204)
		(width 0.14224)
		(layer "In2.Cu")
		(net "M_D_DQ<25>")
	)
	(segment
		(start 226.371404 -131.188968)
		(end 226.601782 -131.419346)
		(width 0.14224)
		(layer "In2.Cu")
		(net "M_D_DQ<25>")
	)
	(segment
		(start 231.462072 -103.420418)
		(end 231.462072 -103.739188)
		(width 0.0889)
		(layer "In2.Cu")
		(net "M_D_DQ<25>")
	)
	(segment
		(start 233.460036 -101.007418)
		(end 233.460036 -101.422454)
		(width 0.0889)
		(layer "In2.Cu")
		(net "M_D_DQ<25>")
	)
	(segment
		(start 226.601782 -131.823968)
		(end 226.311206 -132.114544)
		(width 0.14224)
		(layer "In2.Cu")
		(net "M_D_DQ<25>")
	)
	(segment
		(start 233.460036 -101.422454)
		(end 231.462072 -103.420418)
		(width 0.0889)
		(layer "In2.Cu")
		(net "M_D_DQ<25>")
	)
	(segment
		(start 227.42906 -113.53673)
		(end 226.87534 -113.53673)
		(width 0.14224)
		(layer "In2.Cu")
		(net "M_D_DQ<25>")
	)
	(segment
		(start 226.87534 -114.34953)
		(end 227.42906 -114.34953)
		(width 0.14224)
		(layer "In2.Cu")
		(net "M_D_DQ<25>")
	)
	(segment
		(start 226.822 -130.330956)
		(end 226.799648 -130.330956)
		(width 0.14224)
		(layer "In2.Cu")
		(net "M_D_DQ<25>")
	)
	(segment
		(start 227.584 -110.978696)
		(end 227.584 -111.75619)
		(width 0.14224)
		(layer "In2.Cu")
		(net "M_D_DQ<25>")
	)
	(segment
		(start 227.584 -111.75619)
		(end 227.42906 -111.91113)
		(width 0.14224)
		(layer "In2.Cu")
		(net "M_D_DQ<25>")
	)
	(segment
		(start 226.371404 -130.7592)
		(end 226.371404 -131.188968)
		(width 0.14224)
		(layer "In2.Cu")
		(net "M_D_DQ<25>")
	)
	(segment
		(start 226.7204 -115.82019)
		(end 226.87534 -115.97513)
		(width 0.14224)
		(layer "In2.Cu")
		(net "M_D_DQ<25>")
	)
	(segment
		(start 227.584 -113.38179)
		(end 227.42906 -113.53673)
		(width 0.14224)
		(layer "In2.Cu")
		(net "M_D_DQ<25>")
	)
	(segment
		(start 226.8982 -112.06607)
		(end 226.8982 -112.56899)
		(width 0.14224)
		(layer "In2.Cu")
		(net "M_D_DQ<25>")
	)
	(segment
		(start 233.908092 -100.75799)
		(end 233.709464 -100.75799)
		(width 0.0889)
		(layer "In2.Cu")
		(net "M_D_DQ<25>")
	)
	(segment
		(start 226.525582 -133.1214)
		(end 226.311206 -133.335776)
		(width 0.14224)
		(layer "In2.Cu")
		(net "M_D_DQ<25>")
	)
	(segment
		(start 231.462072 -103.739188)
		(end 229.896924 -105.304336)
		(width 0.14224)
		(layer "In2.Cu")
		(net "M_D_DQ<25>")
	)
	(segment
		(start 227.323396 -129.82956)
		(end 226.822 -130.330956)
		(width 0.14224)
		(layer "In2.Cu")
		(net "M_D_DQ<25>")
	)
	(segment
		(start 226.311206 -132.114544)
		(end 226.311206 -132.475224)
		(width 0.14224)
		(layer "In2.Cu")
		(net "M_D_DQ<25>")
	)
	(segment
		(start 226.525582 -132.6896)
		(end 226.525582 -133.1214)
		(width 0.14224)
		(layer "In2.Cu")
		(net "M_D_DQ<25>")
	)
	(segment
		(start 227.05314 -111.91113)
		(end 226.8982 -112.06607)
		(width 0.14224)
		(layer "In2.Cu")
		(net "M_D_DQ<25>")
	)
	(segment
		(start 240.763298 -97.19564)
		(end 239.941862 -97.290636)
		(width 0.0889)
		(layer "In2.Cu")
		(net "M_D_DQ<25>")
	)
	(segment
		(start 226.7204 -114.19459)
		(end 226.87534 -114.34953)
		(width 0.14224)
		(layer "In2.Cu")
		(net "M_D_DQ<25>")
	)
	(segment
		(start 227.584 -115.00739)
		(end 227.42906 -115.16233)
		(width 0.14224)
		(layer "In2.Cu")
		(net "M_D_DQ<25>")
	)
	(segment
		(start 226.87534 -113.53673)
		(end 226.7204 -113.69167)
		(width 0.14224)
		(layer "In2.Cu")
		(net "M_D_DQ<25>")
	)
	(segment
		(start 229.896924 -108.665772)
		(end 227.584 -110.978696)
		(width 0.14224)
		(layer "In2.Cu")
		(net "M_D_DQ<25>")
	)
	(segment
		(start 226.87534 -115.97513)
		(end 227.42906 -115.97513)
		(width 0.14224)
		(layer "In2.Cu")
		(net "M_D_DQ<25>")
	)
	(segment
		(start 227.584 -116.13007)
		(end 227.584 -123.9266)
		(width 0.14224)
		(layer "In2.Cu")
		(net "M_D_DQ<25>")
	)
	(segment
		(start 226.311206 -132.475224)
		(end 226.525582 -132.6896)
		(width 0.14224)
		(layer "In2.Cu")
		(net "M_D_DQ<25>")
	)
	(segment
		(start 239.064038 -97.78619)
		(end 239.031272 -97.78619)
		(width 0.0889)
		(layer "In2.Cu")
		(net "M_D_DQ<25>")
	)
	(segment
		(start 226.87534 -115.16233)
		(end 226.7204 -115.31727)
		(width 0.14224)
		(layer "In2.Cu")
		(net "M_D_DQ<25>")
	)
	(segment
		(start 226.7204 -113.69167)
		(end 226.7204 -114.19459)
		(width 0.14224)
		(layer "In2.Cu")
		(net "M_D_DQ<25>")
	)
	(segment
		(start 226.7204 -115.31727)
		(end 226.7204 -115.82019)
		(width 0.14224)
		(layer "In2.Cu")
		(net "M_D_DQ<25>")
	)
	(segment
		(start 226.311206 -133.643624)
		(end 226.550982 -133.8834)
		(width 0.14224)
		(layer "In2.Cu")
		(net "M_D_DQ<25>")
	)
	(segment
		(start 227.42906 -115.97513)
		(end 227.584 -116.13007)
		(width 0.14224)
		(layer "In2.Cu")
		(net "M_D_DQ<25>")
	)
	(segment
		(start 236.483652 -99.27209)
		(end 236.459522 -99.27209)
		(width 0.0889)
		(layer "In2.Cu")
		(net "M_D_DQ<25>")
	)
	(segment
		(start 229.896924 -105.304336)
		(end 229.896924 -108.665772)
		(width 0.14224)
		(layer "In2.Cu")
		(net "M_D_DQ<25>")
	)
	(segment
		(start 227.323396 -124.187204)
		(end 227.323396 -129.82956)
		(width 0.14224)
		(layer "In2.Cu")
		(net "M_D_DQ<25>")
	)
	(segment
		(start 226.799648 -130.330956)
		(end 226.371404 -130.7592)
		(width 0.14224)
		(layer "In2.Cu")
		(net "M_D_DQ<25>")
	)
	(segment
		(start 226.311206 -133.335776)
		(end 226.311206 -133.643624)
		(width 0.14224)
		(layer "In2.Cu")
		(net "M_D_DQ<25>")
	)
	(segment
		(start 227.42906 -115.16233)
		(end 226.87534 -115.16233)
		(width 0.14224)
		(layer "In2.Cu")
		(net "M_D_DQ<25>")
	)
	(segment
		(start 226.550982 -134.1882)
		(end 226.398836 -134.340346)
		(width 0.14224)
		(layer "In2.Cu")
		(net "M_D_DQ<25>")
	)
	(segment
		(start 237.346998 -98.77679)
		(end 237.314232 -98.77679)
		(width 0.0889)
		(layer "In2.Cu")
		(net "M_D_DQ<25>")
	)
	(segment
		(start 226.8982 -112.56899)
		(end 227.05314 -112.72393)
		(width 0.14224)
		(layer "In2.Cu")
		(net "M_D_DQ<25>")
	)
	(segment
		(start 227.584 -112.87887)
		(end 227.584 -113.38179)
		(width 0.14224)
		(layer "In2.Cu")
		(net "M_D_DQ<25>")
	)
	(segment
		(start 227.42906 -114.34953)
		(end 227.584 -114.50447)
		(width 0.14224)
		(layer "In2.Cu")
		(net "M_D_DQ<25>")
	)
	(segment
		(start 239.941862 -97.290636)
		(end 239.893602 -97.290636)
		(width 0.0889)
		(layer "In2.Cu")
		(net "M_D_DQ<25>")
	)
	(segment
		(start 235.633768 -99.76739)
		(end 235.594144 -99.76739)
		(width 0.0889)
		(layer "In2.Cu")
		(net "M_D_DQ<25>")
	)
	(segment
		(start 227.42906 -111.91113)
		(end 227.05314 -111.91113)
		(width 0.14224)
		(layer "In2.Cu")
		(net "M_D_DQ<25>")
	)
	(segment
		(start 227.05314 -112.72393)
		(end 227.42906 -112.72393)
		(width 0.14224)
		(layer "In2.Cu")
		(net "M_D_DQ<25>")
	)
	(arc
		(start 236.123988 -99.472242)
		(mid 235.916984 -99.683106)
		(end 235.633768 -99.76739)
		(width 0.0889)
		(layer "In2.Cu")
		(net "M_D_DQ<25>")
	)
	(arc
		(start 237.841028 -98.481388)
		(mid 237.63242 -98.69332)
		(end 237.346998 -98.77679)
		(width 0.0889)
		(layer "In2.Cu")
		(net "M_D_DQ<25>")
	)
	(arc
		(start 238.699548 -97.986088)
		(mid 238.492544 -98.196952)
		(end 238.209328 -98.281236)
		(width 0.0889)
		(layer "In2.Cu")
		(net "M_D_DQ<25>")
	)
	(arc
		(start 234.735624 -100.26269)
		(mid 234.545695 -100.32056)
		(end 234.406948 -100.462588)
		(width 0.0889)
		(layer "In2.Cu")
		(net "M_D_DQ<25>")
	)
	(arc
		(start 236.459522 -99.27209)
		(mid 236.265672 -99.32844)
		(end 236.123988 -99.472242)
		(width 0.0889)
		(layer "In2.Cu")
		(net "M_D_DQ<25>")
	)
	(arc
		(start 236.982508 -98.976688)
		(mid 236.771795 -99.189767)
		(end 236.483652 -99.27209)
		(width 0.0889)
		(layer "In2.Cu")
		(net "M_D_DQ<25>")
	)
	(arc
		(start 239.031272 -97.78619)
		(mid 238.83963 -97.843356)
		(end 238.699548 -97.986088)
		(width 0.0889)
		(layer "In2.Cu")
		(net "M_D_DQ<25>")
	)
	(arc
		(start 235.265468 -99.967288)
		(mid 235.05686 -100.17922)
		(end 234.771438 -100.26269)
		(width 0.0889)
		(layer "In2.Cu")
		(net "M_D_DQ<25>")
	)
	(arc
		(start 239.893602 -97.290636)
		(mid 239.699752 -97.346986)
		(end 239.558068 -97.490788)
		(width 0.0889)
		(layer "In2.Cu")
		(net "M_D_DQ<25>")
	)
	(arc
		(start 237.314232 -98.77679)
		(mid 237.12259 -98.833956)
		(end 236.982508 -98.976688)
		(width 0.0889)
		(layer "In2.Cu")
		(net "M_D_DQ<25>")
	)
	(arc
		(start 238.176562 -98.281236)
		(mid 237.982712 -98.337586)
		(end 237.841028 -98.481388)
		(width 0.0889)
		(layer "In2.Cu")
		(net "M_D_DQ<25>")
	)
	(arc
		(start 235.594144 -99.76739)
		(mid 235.404215 -99.82526)
		(end 235.265468 -99.967288)
		(width 0.0889)
		(layer "In2.Cu")
		(net "M_D_DQ<25>")
	)
	(arc
		(start 239.558068 -97.490788)
		(mid 239.34946 -97.70272)
		(end 239.064038 -97.78619)
		(width 0.0889)
		(layer "In2.Cu")
		(net "M_D_DQ<25>")
	)
	(arc
		(start 234.406948 -100.462588)
		(mid 234.196235 -100.675667)
		(end 233.908092 -100.75799)
		(width 0.0889)
		(layer "In2.Cu")
		(net "M_D_DQ<25>")
	)
	(segment
		(start 227.000308 -137.67054)
		(end 226.9998 -137.676382)
		(width 0.1651)
		(layer "F.Cu")
		(net "M_D_DQ<24>")
	)
	(segment
		(start 241.334798 -95.21444)
		(end 240.763298 -95.21444)
		(width 0.1651)
		(layer "F.Cu")
		(net "M_D_DQ<24>")
	)
	(segment
		(start 226.9998 -137.676382)
		(end 226.822 -135.8138)
		(width 0.1651)
		(layer "F.Cu")
		(net "M_D_DQ<24>")
	)
	(via
		(at 226.822 -135.8138)
		(size 0.508)
		(drill 0.254)
		(layers "F.Cu" "B.Cu")
		(net "M_D_DQ<24>")
	)
	(via
		(at 240.763298 -95.21444)
		(size 0.508)
		(drill 0.254)
		(layers "F.Cu" "B.Cu")
		(net "M_D_DQ<24>")
	)
	(via
		(at 226.149916 -131.611878)
		(size 0.508)
		(drill 0.254)
		(layers "F.Cu" "B.Cu")
		(net "M_D_DQ<24>")
	)
	(segment
		(start 226.150424 -132.876036)
		(end 226.149916 -132.875782)
		(width 0.1651)
		(layer "B.Cu")
		(net "M_D_DQ<24>")
	)
	(segment
		(start 226.149916 -132.875782)
		(end 226.149916 -131.611878)
		(width 0.1651)
		(layer "B.Cu")
		(net "M_D_DQ<24>")
	)
	(segment
		(start 225.716846 -135.00481)
		(end 226.525836 -135.8138)
		(width 0.14224)
		(layer "In2.Cu")
		(net "M_D_DQ<24>")
	)
	(segment
		(start 225.95459 -131.416552)
		(end 226.149916 -131.611878)
		(width 0.14224)
		(layer "In2.Cu")
		(net "M_D_DQ<24>")
	)
	(segment
		(start 231.307894 -103.305864)
		(end 231.00411 -103.305864)
		(width 0.0889)
		(layer "In2.Cu")
		(net "M_D_DQ<24>")
	)
	(segment
		(start 240.763298 -95.21444)
		(end 240.268252 -95.880174)
		(width 0.0889)
		(layer "In2.Cu")
		(net "M_D_DQ<24>")
	)
	(segment
		(start 240.251488 -96.500188)
		(end 240.256314 -96.508824)
		(width 0.0889)
		(layer "In2.Cu")
		(net "M_D_DQ<24>")
	)
	(segment
		(start 226.2886 -128.4224)
		(end 226.5426 -128.6764)
		(width 0.14224)
		(layer "In2.Cu")
		(net "M_D_DQ<24>")
	)
	(segment
		(start 229.2477 -105.037382)
		(end 229.2477 -108.396786)
		(width 0.14224)
		(layer "In2.Cu")
		(net "M_D_DQ<24>")
	)
	(segment
		(start 238.202724 -98.090736)
		(end 238.169958 -98.090736)
		(width 0.0889)
		(layer "In2.Cu")
		(net "M_D_DQ<24>")
	)
	(segment
		(start 240.268252 -95.880174)
		(end 240.251488 -95.909638)
		(width 0.0889)
		(layer "In2.Cu")
		(net "M_D_DQ<24>")
	)
	(segment
		(start 236.485684 -99.081336)
		(end 236.457744 -99.081336)
		(width 0.0889)
		(layer "In2.Cu")
		(net "M_D_DQ<24>")
	)
	(segment
		(start 226.196906 -116.392706)
		(end 226.8982 -117.094)
		(width 0.14224)
		(layer "In2.Cu")
		(net "M_D_DQ<24>")
	)
	(segment
		(start 233.270044 -100.928678)
		(end 233.270044 -101.343714)
		(width 0.0889)
		(layer "In2.Cu")
		(net "M_D_DQ<24>")
	)
	(segment
		(start 226.8982 -117.094)
		(end 226.8982 -123.962668)
		(width 0.14224)
		(layer "In2.Cu")
		(net "M_D_DQ<24>")
	)
	(segment
		(start 226.2886 -124.572268)
		(end 226.2886 -128.4224)
		(width 0.14224)
		(layer "In2.Cu")
		(net "M_D_DQ<24>")
	)
	(segment
		(start 233.631994 -100.566728)
		(end 233.270044 -100.928678)
		(width 0.0889)
		(layer "In2.Cu")
		(net "M_D_DQ<24>")
	)
	(segment
		(start 226.525836 -135.8138)
		(end 226.822 -135.8138)
		(width 0.14224)
		(layer "In2.Cu")
		(net "M_D_DQ<24>")
	)
	(segment
		(start 233.896408 -100.566728)
		(end 233.631994 -100.566728)
		(width 0.0889)
		(layer "In2.Cu")
		(net "M_D_DQ<24>")
	)
	(segment
		(start 226.196906 -111.44758)
		(end 226.196906 -116.392706)
		(width 0.14224)
		(layer "In2.Cu")
		(net "M_D_DQ<24>")
	)
	(segment
		(start 239.919764 -97.100136)
		(end 239.886998 -97.100136)
		(width 0.0889)
		(layer "In2.Cu")
		(net "M_D_DQ<24>")
	)
	(segment
		(start 225.95459 -130.439922)
		(end 225.95459 -131.416552)
		(width 0.14224)
		(layer "In2.Cu")
		(net "M_D_DQ<24>")
	)
	(segment
		(start 237.340394 -98.58629)
		(end 237.307628 -98.58629)
		(width 0.0889)
		(layer "In2.Cu")
		(net "M_D_DQ<24>")
	)
	(segment
		(start 226.5426 -128.6764)
		(end 226.5426 -129.851912)
		(width 0.14224)
		(layer "In2.Cu")
		(net "M_D_DQ<24>")
	)
	(segment
		(start 230.991664 -103.293418)
		(end 229.2477 -105.037382)
		(width 0.14224)
		(layer "In2.Cu")
		(net "M_D_DQ<24>")
	)
	(segment
		(start 240.245138 -96.48952)
		(end 240.251488 -96.500188)
		(width 0.0889)
		(layer "In2.Cu")
		(net "M_D_DQ<24>")
	)
	(segment
		(start 234.771692 -100.071936)
		(end 234.732068 -100.071936)
		(width 0.0889)
		(layer "In2.Cu")
		(net "M_D_DQ<24>")
	)
	(segment
		(start 233.270044 -101.343714)
		(end 231.307894 -103.305864)
		(width 0.0889)
		(layer "In2.Cu")
		(net "M_D_DQ<24>")
	)
	(segment
		(start 229.2477 -108.396786)
		(end 226.196906 -111.44758)
		(width 0.14224)
		(layer "In2.Cu")
		(net "M_D_DQ<24>")
	)
	(segment
		(start 226.8982 -123.962668)
		(end 226.2886 -124.572268)
		(width 0.14224)
		(layer "In2.Cu")
		(net "M_D_DQ<24>")
	)
	(segment
		(start 231.00411 -103.305864)
		(end 230.991664 -103.293418)
		(width 0.0889)
		(layer "In2.Cu")
		(net "M_D_DQ<24>")
	)
	(segment
		(start 226.5426 -129.851912)
		(end 225.95459 -130.439922)
		(width 0.14224)
		(layer "In2.Cu")
		(net "M_D_DQ<24>")
	)
	(segment
		(start 239.057434 -97.59569)
		(end 239.024668 -97.59569)
		(width 0.0889)
		(layer "In2.Cu")
		(net "M_D_DQ<24>")
	)
	(segment
		(start 225.716846 -132.044948)
		(end 225.716846 -135.00481)
		(width 0.14224)
		(layer "In2.Cu")
		(net "M_D_DQ<24>")
	)
	(segment
		(start 235.630212 -99.576636)
		(end 235.594398 -99.576636)
		(width 0.0889)
		(layer "In2.Cu")
		(net "M_D_DQ<24>")
	)
	(segment
		(start 226.149916 -131.611878)
		(end 225.716846 -132.044948)
		(width 0.14224)
		(layer "In2.Cu")
		(net "M_D_DQ<24>")
	)
	(arc
		(start 239.024668 -97.59569)
		(mid 238.741451 -97.679971)
		(end 238.534448 -97.890838)
		(width 0.0889)
		(layer "In2.Cu")
		(net "M_D_DQ<24>")
	)
	(arc
		(start 235.594398 -99.576636)
		(mid 235.308974 -99.660103)
		(end 235.100368 -99.872038)
		(width 0.0889)
		(layer "In2.Cu")
		(net "M_D_DQ<24>")
	)
	(arc
		(start 240.251488 -95.909638)
		(mid 240.172266 -96.198756)
		(end 240.245138 -96.48952)
		(width 0.0889)
		(layer "In2.Cu")
		(net "M_D_DQ<24>")
	)
	(arc
		(start 234.241848 -100.367084)
		(mid 234.095886 -100.513191)
		(end 233.896408 -100.566728)
		(width 0.0889)
		(layer "In2.Cu")
		(net "M_D_DQ<24>")
	)
	(arc
		(start 235.100368 -99.872038)
		(mid 234.961624 -100.014071)
		(end 234.771692 -100.071936)
		(width 0.0889)
		(layer "In2.Cu")
		(net "M_D_DQ<24>")
	)
	(arc
		(start 239.392968 -97.395538)
		(mid 239.251285 -97.539342)
		(end 239.057434 -97.59569)
		(width 0.0889)
		(layer "In2.Cu")
		(net "M_D_DQ<24>")
	)
	(arc
		(start 238.169958 -98.090736)
		(mid 237.884534 -98.174203)
		(end 237.675928 -98.386138)
		(width 0.0889)
		(layer "In2.Cu")
		(net "M_D_DQ<24>")
	)
	(arc
		(start 235.958888 -99.376738)
		(mid 235.820144 -99.518771)
		(end 235.630212 -99.576636)
		(width 0.0889)
		(layer "In2.Cu")
		(net "M_D_DQ<24>")
	)
	(arc
		(start 236.457744 -99.081336)
		(mid 236.169599 -99.163655)
		(end 235.958888 -99.376738)
		(width 0.0889)
		(layer "In2.Cu")
		(net "M_D_DQ<24>")
	)
	(arc
		(start 240.256314 -96.508824)
		(mid 240.252567 -96.89808)
		(end 239.919764 -97.100136)
		(width 0.0889)
		(layer "In2.Cu")
		(net "M_D_DQ<24>")
	)
	(arc
		(start 237.675928 -98.386138)
		(mid 237.534245 -98.529942)
		(end 237.340394 -98.58629)
		(width 0.0889)
		(layer "In2.Cu")
		(net "M_D_DQ<24>")
	)
	(arc
		(start 239.886998 -97.100136)
		(mid 239.601574 -97.183603)
		(end 239.392968 -97.395538)
		(width 0.0889)
		(layer "In2.Cu")
		(net "M_D_DQ<24>")
	)
	(arc
		(start 238.534448 -97.890838)
		(mid 238.394369 -98.033574)
		(end 238.202724 -98.090736)
		(width 0.0889)
		(layer "In2.Cu")
		(net "M_D_DQ<24>")
	)
	(arc
		(start 237.307628 -98.58629)
		(mid 237.024411 -98.670571)
		(end 236.817408 -98.881438)
		(width 0.0889)
		(layer "In2.Cu")
		(net "M_D_DQ<24>")
	)
	(arc
		(start 234.732068 -100.071936)
		(mid 234.448851 -100.156217)
		(end 234.241848 -100.367084)
		(width 0.0889)
		(layer "In2.Cu")
		(net "M_D_DQ<24>")
	)
	(arc
		(start 236.817408 -98.881438)
		(mid 236.677329 -99.024174)
		(end 236.485684 -99.081336)
		(width 0.0889)
		(layer "In2.Cu")
		(net "M_D_DQ<24>")
	)
	(segment
		(start 221.050358 -133.0706)
		(end 221.04985 -133.076442)
		(width 0.1651)
		(layer "F.Cu")
		(net "M_D_DQ<23>")
	)
	(segment
		(start 221.04985 -133.076442)
		(end 221.04985 -134.340346)
		(width 0.1651)
		(layer "F.Cu")
		(net "M_D_DQ<23>")
	)
	(segment
		(start 236.183678 -95.21444)
		(end 235.612178 -95.21444)
		(width 0.1651)
		(layer "F.Cu")
		(net "M_D_DQ<23>")
	)
	(via
		(at 221.899734 -130.330956)
		(size 0.508)
		(drill 0.254)
		(layers "F.Cu" "B.Cu")
		(net "M_D_DQ<23>")
	)
	(via
		(at 221.04985 -134.340346)
		(size 0.508)
		(drill 0.254)
		(layers "F.Cu" "B.Cu")
		(net "M_D_DQ<23>")
	)
	(via
		(at 235.612178 -95.21444)
		(size 0.508)
		(drill 0.254)
		(layers "F.Cu" "B.Cu")
		(net "M_D_DQ<23>")
	)
	(segment
		(start 221.899734 -128.276096)
		(end 221.899734 -130.330956)
		(width 0.1651)
		(layer "B.Cu")
		(net "M_D_DQ<23>")
	)
	(segment
		(start 221.900496 -128.276096)
		(end 221.899734 -128.276096)
		(width 0.1651)
		(layer "B.Cu")
		(net "M_D_DQ<23>")
	)
	(segment
		(start 234.524296 -95.309436)
		(end 234.408726 -95.425006)
		(width 0.0889)
		(layer "In2.Cu")
		(net "M_D_DQ<23>")
	)
	(segment
		(start 224.877884 -103.26497)
		(end 224.877884 -106.118914)
		(width 0.14224)
		(layer "In2.Cu")
		(net "M_D_DQ<23>")
	)
	(segment
		(start 221.449138 -130.7592)
		(end 221.449138 -131.188968)
		(width 0.14224)
		(layer "In2.Cu")
		(net "M_D_DQ<23>")
	)
	(segment
		(start 221.615 -116.488718)
		(end 221.75724 -116.630958)
		(width 0.14224)
		(layer "In2.Cu")
		(net "M_D_DQ<23>")
	)
	(segment
		(start 221.75724 -112.729518)
		(end 222.53956 -112.729518)
		(width 0.14224)
		(layer "In2.Cu")
		(net "M_D_DQ<23>")
	)
	(segment
		(start 221.615 -111.286798)
		(end 221.75724 -111.429038)
		(width 0.14224)
		(layer "In2.Cu")
		(net "M_D_DQ<23>")
	)
	(segment
		(start 235.276898 -95.21444)
		(end 235.181902 -95.309436)
		(width 0.0889)
		(layer "In2.Cu")
		(net "M_D_DQ<23>")
	)
	(segment
		(start 221.75724 -115.980718)
		(end 221.615 -116.122958)
		(width 0.14224)
		(layer "In2.Cu")
		(net "M_D_DQ<23>")
	)
	(segment
		(start 221.615 -113.887758)
		(end 221.75724 -114.029998)
		(width 0.14224)
		(layer "In2.Cu")
		(net "M_D_DQ<23>")
	)
	(segment
		(start 221.499938 -134.162546)
		(end 221.322138 -134.340346)
		(width 0.14224)
		(layer "In2.Cu")
		(net "M_D_DQ<23>")
	)
	(segment
		(start 221.21114 -132.457952)
		(end 221.468188 -132.715)
		(width 0.14224)
		(layer "In2.Cu")
		(net "M_D_DQ<23>")
	)
	(segment
		(start 221.5642 -118.7704)
		(end 221.5642 -120.015)
		(width 0.14224)
		(layer "In2.Cu")
		(net "M_D_DQ<23>")
	)
	(segment
		(start 234.408726 -95.425006)
		(end 231.867964 -95.425006)
		(width 0.0889)
		(layer "In2.Cu")
		(net "M_D_DQ<23>")
	)
	(segment
		(start 222.53956 -112.729518)
		(end 222.6818 -112.871758)
		(width 0.14224)
		(layer "In2.Cu")
		(net "M_D_DQ<23>")
	)
	(segment
		(start 222.6818 -115.838478)
		(end 222.53956 -115.980718)
		(width 0.14224)
		(layer "In2.Cu")
		(net "M_D_DQ<23>")
	)
	(segment
		(start 221.877382 -130.330956)
		(end 221.449138 -130.7592)
		(width 0.14224)
		(layer "In2.Cu")
		(net "M_D_DQ<23>")
	)
	(segment
		(start 221.21114 -133.276848)
		(end 221.21114 -133.550152)
		(width 0.14224)
		(layer "In2.Cu")
		(net "M_D_DQ<23>")
	)
	(segment
		(start 221.75724 -116.630958)
		(end 222.53956 -116.630958)
		(width 0.14224)
		(layer "In2.Cu")
		(net "M_D_DQ<23>")
	)
	(segment
		(start 221.493588 -131.233418)
		(end 221.493588 -131.9022)
		(width 0.14224)
		(layer "In2.Cu")
		(net "M_D_DQ<23>")
	)
	(segment
		(start 230.558848 -97.292922)
		(end 230.558848 -97.614232)
		(width 0.0889)
		(layer "In2.Cu")
		(net "M_D_DQ<23>")
	)
	(segment
		(start 222.6818 -116.773198)
		(end 222.6818 -117.6528)
		(width 0.14224)
		(layer "In2.Cu")
		(net "M_D_DQ<23>")
	)
	(segment
		(start 221.499938 -133.83895)
		(end 221.499938 -134.162546)
		(width 0.14224)
		(layer "In2.Cu")
		(net "M_D_DQ<23>")
	)
	(segment
		(start 222.6818 -111.571278)
		(end 222.6818 -111.937038)
		(width 0.14224)
		(layer "In2.Cu")
		(net "M_D_DQ<23>")
	)
	(segment
		(start 221.615 -113.521998)
		(end 221.615 -113.887758)
		(width 0.14224)
		(layer "In2.Cu")
		(net "M_D_DQ<23>")
	)
	(segment
		(start 235.181902 -95.309436)
		(end 234.524296 -95.309436)
		(width 0.0889)
		(layer "In2.Cu")
		(net "M_D_DQ<23>")
	)
	(segment
		(start 220.2434 -120.142)
		(end 220.1164 -120.269)
		(width 0.14224)
		(layer "In2.Cu")
		(net "M_D_DQ<23>")
	)
	(segment
		(start 221.75724 -111.429038)
		(end 222.53956 -111.429038)
		(width 0.14224)
		(layer "In2.Cu")
		(net "M_D_DQ<23>")
	)
	(segment
		(start 221.869 -127.4826)
		(end 222.0849 -127.6985)
		(width 0.14224)
		(layer "In2.Cu")
		(net "M_D_DQ<23>")
	)
	(segment
		(start 220.1164 -120.269)
		(end 220.1164 -126.5428)
		(width 0.14224)
		(layer "In2.Cu")
		(net "M_D_DQ<23>")
	)
	(segment
		(start 230.528622 -97.614232)
		(end 224.877884 -103.26497)
		(width 0.14224)
		(layer "In2.Cu")
		(net "M_D_DQ<23>")
	)
	(segment
		(start 221.899734 -130.330956)
		(end 221.877382 -130.330956)
		(width 0.14224)
		(layer "In2.Cu")
		(net "M_D_DQ<23>")
	)
	(segment
		(start 222.53956 -116.630958)
		(end 222.6818 -116.773198)
		(width 0.14224)
		(layer "In2.Cu")
		(net "M_D_DQ<23>")
	)
	(segment
		(start 221.75724 -114.029998)
		(end 222.53956 -114.029998)
		(width 0.14224)
		(layer "In2.Cu")
		(net "M_D_DQ<23>")
	)
	(segment
		(start 222.0849 -128.1811)
		(end 222.5548 -128.651)
		(width 0.14224)
		(layer "In2.Cu")
		(net "M_D_DQ<23>")
	)
	(segment
		(start 222.53956 -115.980718)
		(end 221.75724 -115.980718)
		(width 0.14224)
		(layer "In2.Cu")
		(net "M_D_DQ<23>")
	)
	(segment
		(start 221.4372 -120.142)
		(end 220.2434 -120.142)
		(width 0.14224)
		(layer "In2.Cu")
		(net "M_D_DQ<23>")
	)
	(segment
		(start 221.615 -112.221518)
		(end 221.615 -112.587278)
		(width 0.14224)
		(layer "In2.Cu")
		(net "M_D_DQ<23>")
	)
	(segment
		(start 221.5642 -120.015)
		(end 221.4372 -120.142)
		(width 0.14224)
		(layer "In2.Cu")
		(net "M_D_DQ<23>")
	)
	(segment
		(start 224.877884 -106.118914)
		(end 222.6818 -108.314998)
		(width 0.14224)
		(layer "In2.Cu")
		(net "M_D_DQ<23>")
	)
	(segment
		(start 222.53956 -110.778798)
		(end 221.75724 -110.778798)
		(width 0.14224)
		(layer "In2.Cu")
		(net "M_D_DQ<23>")
	)
	(segment
		(start 222.241618 -129.989072)
		(end 221.899734 -130.330956)
		(width 0.14224)
		(layer "In2.Cu")
		(net "M_D_DQ<23>")
	)
	(segment
		(start 235.612178 -95.21444)
		(end 235.276898 -95.21444)
		(width 0.0889)
		(layer "In2.Cu")
		(net "M_D_DQ<23>")
	)
	(segment
		(start 230.558848 -97.614232)
		(end 230.528622 -97.614232)
		(width 0.14224)
		(layer "In2.Cu")
		(net "M_D_DQ<23>")
	)
	(segment
		(start 222.53956 -115.330478)
		(end 222.6818 -115.472718)
		(width 0.14224)
		(layer "In2.Cu")
		(net "M_D_DQ<23>")
	)
	(segment
		(start 221.615 -115.188238)
		(end 221.75724 -115.330478)
		(width 0.14224)
		(layer "In2.Cu")
		(net "M_D_DQ<23>")
	)
	(segment
		(start 222.53956 -112.079278)
		(end 221.75724 -112.079278)
		(width 0.14224)
		(layer "In2.Cu")
		(net "M_D_DQ<23>")
	)
	(segment
		(start 230.783638 -97.068132)
		(end 230.558848 -97.292922)
		(width 0.0889)
		(layer "In2.Cu")
		(net "M_D_DQ<23>")
	)
	(segment
		(start 221.322138 -134.340346)
		(end 221.04985 -134.340346)
		(width 0.14224)
		(layer "In2.Cu")
		(net "M_D_DQ<23>")
	)
	(segment
		(start 221.615 -114.822478)
		(end 221.615 -115.188238)
		(width 0.14224)
		(layer "In2.Cu")
		(net "M_D_DQ<23>")
	)
	(segment
		(start 221.449138 -131.188968)
		(end 221.493588 -131.233418)
		(width 0.14224)
		(layer "In2.Cu")
		(net "M_D_DQ<23>")
	)
	(segment
		(start 222.53956 -114.029998)
		(end 222.6818 -114.172238)
		(width 0.14224)
		(layer "In2.Cu")
		(net "M_D_DQ<23>")
	)
	(segment
		(start 221.468188 -132.715)
		(end 221.468188 -133.0198)
		(width 0.14224)
		(layer "In2.Cu")
		(net "M_D_DQ<23>")
	)
	(segment
		(start 221.493588 -131.9022)
		(end 221.21114 -132.184648)
		(width 0.14224)
		(layer "In2.Cu")
		(net "M_D_DQ<23>")
	)
	(segment
		(start 221.75724 -114.680238)
		(end 221.615 -114.822478)
		(width 0.14224)
		(layer "In2.Cu")
		(net "M_D_DQ<23>")
	)
	(segment
		(start 222.0849 -127.6985)
		(end 222.0849 -128.1811)
		(width 0.14224)
		(layer "In2.Cu")
		(net "M_D_DQ<23>")
	)
	(segment
		(start 221.468188 -133.0198)
		(end 221.21114 -133.276848)
		(width 0.14224)
		(layer "In2.Cu")
		(net "M_D_DQ<23>")
	)
	(segment
		(start 222.6818 -112.871758)
		(end 222.6818 -113.237518)
		(width 0.14224)
		(layer "In2.Cu")
		(net "M_D_DQ<23>")
	)
	(segment
		(start 221.21114 -132.184648)
		(end 221.21114 -132.457952)
		(width 0.14224)
		(layer "In2.Cu")
		(net "M_D_DQ<23>")
	)
	(segment
		(start 231.867964 -95.425006)
		(end 230.783638 -96.509332)
		(width 0.0889)
		(layer "In2.Cu")
		(net "M_D_DQ<23>")
	)
	(segment
		(start 222.53956 -111.429038)
		(end 222.6818 -111.571278)
		(width 0.14224)
		(layer "In2.Cu")
		(net "M_D_DQ<23>")
	)
	(segment
		(start 220.1164 -126.5428)
		(end 221.0562 -127.4826)
		(width 0.14224)
		(layer "In2.Cu")
		(net "M_D_DQ<23>")
	)
	(segment
		(start 221.75724 -112.079278)
		(end 221.615 -112.221518)
		(width 0.14224)
		(layer "In2.Cu")
		(net "M_D_DQ<23>")
	)
	(segment
		(start 222.6818 -111.937038)
		(end 222.53956 -112.079278)
		(width 0.14224)
		(layer "In2.Cu")
		(net "M_D_DQ<23>")
	)
	(segment
		(start 221.75724 -115.330478)
		(end 222.53956 -115.330478)
		(width 0.14224)
		(layer "In2.Cu")
		(net "M_D_DQ<23>")
	)
	(segment
		(start 222.5548 -128.651)
		(end 222.5548 -129.0828)
		(width 0.14224)
		(layer "In2.Cu")
		(net "M_D_DQ<23>")
	)
	(segment
		(start 221.615 -110.921038)
		(end 221.615 -111.286798)
		(width 0.14224)
		(layer "In2.Cu")
		(net "M_D_DQ<23>")
	)
	(segment
		(start 222.25254 -129.38506)
		(end 222.25254 -129.989072)
		(width 0.14224)
		(layer "In2.Cu")
		(net "M_D_DQ<23>")
	)
	(segment
		(start 221.0562 -127.4826)
		(end 221.869 -127.4826)
		(width 0.14224)
		(layer "In2.Cu")
		(net "M_D_DQ<23>")
	)
	(segment
		(start 222.53956 -113.379758)
		(end 221.75724 -113.379758)
		(width 0.14224)
		(layer "In2.Cu")
		(net "M_D_DQ<23>")
	)
	(segment
		(start 222.25254 -129.989072)
		(end 222.241618 -129.989072)
		(width 0.14224)
		(layer "In2.Cu")
		(net "M_D_DQ<23>")
	)
	(segment
		(start 222.6818 -117.6528)
		(end 221.5642 -118.7704)
		(width 0.14224)
		(layer "In2.Cu")
		(net "M_D_DQ<23>")
	)
	(segment
		(start 222.53956 -114.680238)
		(end 221.75724 -114.680238)
		(width 0.14224)
		(layer "In2.Cu")
		(net "M_D_DQ<23>")
	)
	(segment
		(start 222.6818 -115.472718)
		(end 222.6818 -115.838478)
		(width 0.14224)
		(layer "In2.Cu")
		(net "M_D_DQ<23>")
	)
	(segment
		(start 221.75724 -110.778798)
		(end 221.615 -110.921038)
		(width 0.14224)
		(layer "In2.Cu")
		(net "M_D_DQ<23>")
	)
	(segment
		(start 230.783638 -96.509332)
		(end 230.783638 -97.068132)
		(width 0.0889)
		(layer "In2.Cu")
		(net "M_D_DQ<23>")
	)
	(segment
		(start 221.21114 -133.550152)
		(end 221.499938 -133.83895)
		(width 0.14224)
		(layer "In2.Cu")
		(net "M_D_DQ<23>")
	)
	(segment
		(start 222.5548 -129.0828)
		(end 222.25254 -129.38506)
		(width 0.14224)
		(layer "In2.Cu")
		(net "M_D_DQ<23>")
	)
	(segment
		(start 222.6818 -114.172238)
		(end 222.6818 -114.537998)
		(width 0.14224)
		(layer "In2.Cu")
		(net "M_D_DQ<23>")
	)
	(segment
		(start 222.6818 -114.537998)
		(end 222.53956 -114.680238)
		(width 0.14224)
		(layer "In2.Cu")
		(net "M_D_DQ<23>")
	)
	(segment
		(start 221.615 -116.122958)
		(end 221.615 -116.488718)
		(width 0.14224)
		(layer "In2.Cu")
		(net "M_D_DQ<23>")
	)
	(segment
		(start 222.6818 -110.636558)
		(end 222.53956 -110.778798)
		(width 0.14224)
		(layer "In2.Cu")
		(net "M_D_DQ<23>")
	)
	(segment
		(start 221.615 -112.587278)
		(end 221.75724 -112.729518)
		(width 0.14224)
		(layer "In2.Cu")
		(net "M_D_DQ<23>")
	)
	(segment
		(start 222.6818 -113.237518)
		(end 222.53956 -113.379758)
		(width 0.14224)
		(layer "In2.Cu")
		(net "M_D_DQ<23>")
	)
	(segment
		(start 222.6818 -108.314998)
		(end 222.6818 -110.636558)
		(width 0.14224)
		(layer "In2.Cu")
		(net "M_D_DQ<23>")
	)
	(segment
		(start 221.75724 -113.379758)
		(end 221.615 -113.521998)
		(width 0.14224)
		(layer "In2.Cu")
		(net "M_D_DQ<23>")
	)
	(segment
		(start 221.899988 -136.7028)
		(end 222.032068 -136.57072)
		(width 0.1651)
		(layer "F.Cu")
		(net "M_D_DQ<22>")
	)
	(segment
		(start 221.900496 -137.67054)
		(end 221.899988 -137.67054)
		(width 0.1651)
		(layer "F.Cu")
		(net "M_D_DQ<22>")
	)
	(segment
		(start 221.899988 -136.2202)
		(end 221.899988 -135.915654)
		(width 0.1651)
		(layer "F.Cu")
		(net "M_D_DQ<22>")
	)
	(segment
		(start 237.900718 -96.20504)
		(end 237.329218 -96.20504)
		(width 0.1651)
		(layer "F.Cu")
		(net "M_D_DQ<22>")
	)
	(segment
		(start 221.899988 -137.67054)
		(end 221.899988 -136.7028)
		(width 0.1651)
		(layer "F.Cu")
		(net "M_D_DQ<22>")
	)
	(segment
		(start 222.032068 -136.35228)
		(end 221.899988 -136.2202)
		(width 0.1651)
		(layer "F.Cu")
		(net "M_D_DQ<22>")
	)
	(segment
		(start 221.899988 -135.915654)
		(end 221.899734 -135.9154)
		(width 0.1651)
		(layer "F.Cu")
		(net "M_D_DQ<22>")
	)
	(segment
		(start 222.032068 -136.57072)
		(end 222.032068 -136.35228)
		(width 0.1651)
		(layer "F.Cu")
		(net "M_D_DQ<22>")
	)
	(via
		(at 221.04985 -131.612894)
		(size 0.508)
		(drill 0.254)
		(layers "F.Cu" "B.Cu")
		(net "M_D_DQ<22>")
	)
	(via
		(at 221.899734 -135.9154)
		(size 0.508)
		(drill 0.254)
		(layers "F.Cu" "B.Cu")
		(net "M_D_DQ<22>")
	)
	(via
		(at 237.329218 -96.20504)
		(size 0.508)
		(drill 0.254)
		(layers "F.Cu" "B.Cu")
		(net "M_D_DQ<22>")
	)
	(segment
		(start 221.050358 -132.876036)
		(end 221.04985 -132.875782)
		(width 0.1651)
		(layer "B.Cu")
		(net "M_D_DQ<22>")
	)
	(segment
		(start 221.04985 -132.875782)
		(end 221.04985 -131.612894)
		(width 0.1651)
		(layer "B.Cu")
		(net "M_D_DQ<22>")
	)
	(segment
		(start 234.329224 -95.235014)
		(end 231.789224 -95.235014)
		(width 0.0889)
		(layer "In2.Cu")
		(net "M_D_DQ<22>")
	)
	(segment
		(start 237.329218 -96.20504)
		(end 236.834172 -95.539052)
		(width 0.0889)
		(layer "In2.Cu")
		(net "M_D_DQ<22>")
	)
	(segment
		(start 234.445302 -95.118936)
		(end 234.329224 -95.235014)
		(width 0.0889)
		(layer "In2.Cu")
		(net "M_D_DQ<22>")
	)
	(segment
		(start 220.61678 -134.632446)
		(end 221.899734 -135.9154)
		(width 0.14224)
		(layer "In2.Cu")
		(net "M_D_DQ<22>")
	)
	(segment
		(start 221.5388 -129.3368)
		(end 221.5388 -129.811018)
		(width 0.14224)
		(layer "In2.Cu")
		(net "M_D_DQ<22>")
	)
	(segment
		(start 221.0816 -110.2614)
		(end 220.7768 -110.5662)
		(width 0.14224)
		(layer "In2.Cu")
		(net "M_D_DQ<22>")
	)
	(segment
		(start 230.593646 -96.430592)
		(end 230.593646 -96.989392)
		(width 0.0889)
		(layer "In2.Cu")
		(net "M_D_DQ<22>")
	)
	(segment
		(start 221.04985 -131.612894)
		(end 220.61678 -132.045964)
		(width 0.14224)
		(layer "In2.Cu")
		(net "M_D_DQ<22>")
	)
	(segment
		(start 220.2688 -115.6462)
		(end 220.2688 -113.4618)
		(width 0.14224)
		(layer "In2.Cu")
		(net "M_D_DQ<22>")
	)
	(segment
		(start 224.2312 -105.850944)
		(end 221.0816 -109.000544)
		(width 0.14224)
		(layer "In2.Cu")
		(net "M_D_DQ<22>")
	)
	(segment
		(start 220.472 -115.8494)
		(end 220.2688 -115.6462)
		(width 0.14224)
		(layer "In2.Cu")
		(net "M_D_DQ<22>")
	)
	(segment
		(start 219.4814 -126.821946)
		(end 221.081854 -128.4224)
		(width 0.14224)
		(layer "In2.Cu")
		(net "M_D_DQ<22>")
	)
	(segment
		(start 220.61678 -132.045964)
		(end 220.61678 -134.632446)
		(width 0.14224)
		(layer "In2.Cu")
		(net "M_D_DQ<22>")
	)
	(segment
		(start 230.126032 -97.13087)
		(end 224.2312 -103.025702)
		(width 0.14224)
		(layer "In2.Cu")
		(net "M_D_DQ<22>")
	)
	(segment
		(start 221.8182 -129.0574)
		(end 221.5388 -129.3368)
		(width 0.14224)
		(layer "In2.Cu")
		(net "M_D_DQ<22>")
	)
	(segment
		(start 219.6846 -113.2586)
		(end 219.4814 -113.4618)
		(width 0.14224)
		(layer "In2.Cu")
		(net "M_D_DQ<22>")
	)
	(segment
		(start 220.7768 -110.8964)
		(end 221.0816 -111.2012)
		(width 0.14224)
		(layer "In2.Cu")
		(net "M_D_DQ<22>")
	)
	(segment
		(start 221.0816 -109.000544)
		(end 221.0816 -110.2614)
		(width 0.14224)
		(layer "In2.Cu")
		(net "M_D_DQ<22>")
	)
	(segment
		(start 220.8784 -115.8494)
		(end 220.472 -115.8494)
		(width 0.14224)
		(layer "In2.Cu")
		(net "M_D_DQ<22>")
	)
	(segment
		(start 235.627164 -94.81439)
		(end 235.597192 -94.81439)
		(width 0.0889)
		(layer "In2.Cu")
		(net "M_D_DQ<22>")
	)
	(segment
		(start 221.6404 -128.4224)
		(end 221.8182 -128.6002)
		(width 0.14224)
		(layer "In2.Cu")
		(net "M_D_DQ<22>")
	)
	(segment
		(start 235.265468 -95.014288)
		(end 234.927648 -95.118936)
		(width 0.0889)
		(layer "In2.Cu")
		(net "M_D_DQ<22>")
	)
	(segment
		(start 221.081854 -128.4224)
		(end 221.6404 -128.4224)
		(width 0.14224)
		(layer "In2.Cu")
		(net "M_D_DQ<22>")
	)
	(segment
		(start 230.452168 -97.13087)
		(end 230.126032 -97.13087)
		(width 0.0889)
		(layer "In2.Cu")
		(net "M_D_DQ<22>")
	)
	(segment
		(start 230.593646 -96.989392)
		(end 230.452168 -97.13087)
		(width 0.0889)
		(layer "In2.Cu")
		(net "M_D_DQ<22>")
	)
	(segment
		(start 224.2312 -103.025702)
		(end 224.2312 -105.850944)
		(width 0.14224)
		(layer "In2.Cu")
		(net "M_D_DQ<22>")
	)
	(segment
		(start 234.927648 -95.118936)
		(end 234.445302 -95.118936)
		(width 0.0889)
		(layer "In2.Cu")
		(net "M_D_DQ<22>")
	)
	(segment
		(start 220.2688 -113.4618)
		(end 220.0656 -113.2586)
		(width 0.14224)
		(layer "In2.Cu")
		(net "M_D_DQ<22>")
	)
	(segment
		(start 236.481874 -95.309436)
		(end 236.449108 -95.309436)
		(width 0.0889)
		(layer "In2.Cu")
		(net "M_D_DQ<22>")
	)
	(segment
		(start 221.5388 -129.811018)
		(end 220.6752 -130.674618)
		(width 0.14224)
		(layer "In2.Cu")
		(net "M_D_DQ<22>")
	)
	(segment
		(start 236.834172 -95.539052)
		(end 236.817408 -95.509588)
		(width 0.0889)
		(layer "In2.Cu")
		(net "M_D_DQ<22>")
	)
	(segment
		(start 220.6752 -130.674618)
		(end 220.6752 -131.238244)
		(width 0.14224)
		(layer "In2.Cu")
		(net "M_D_DQ<22>")
	)
	(segment
		(start 221.0816 -111.2012)
		(end 221.0816 -115.6462)
		(width 0.14224)
		(layer "In2.Cu")
		(net "M_D_DQ<22>")
	)
	(segment
		(start 220.7768 -110.5662)
		(end 220.7768 -110.8964)
		(width 0.14224)
		(layer "In2.Cu")
		(net "M_D_DQ<22>")
	)
	(segment
		(start 231.789224 -95.235014)
		(end 230.593646 -96.430592)
		(width 0.0889)
		(layer "In2.Cu")
		(net "M_D_DQ<22>")
	)
	(segment
		(start 221.8182 -128.6002)
		(end 221.8182 -129.0574)
		(width 0.14224)
		(layer "In2.Cu")
		(net "M_D_DQ<22>")
	)
	(segment
		(start 220.6752 -131.238244)
		(end 221.04985 -131.612894)
		(width 0.14224)
		(layer "In2.Cu")
		(net "M_D_DQ<22>")
	)
	(segment
		(start 220.0656 -113.2586)
		(end 219.6846 -113.2586)
		(width 0.14224)
		(layer "In2.Cu")
		(net "M_D_DQ<22>")
	)
	(segment
		(start 219.4814 -113.4618)
		(end 219.4814 -126.821946)
		(width 0.14224)
		(layer "In2.Cu")
		(net "M_D_DQ<22>")
	)
	(segment
		(start 221.0816 -115.6462)
		(end 220.8784 -115.8494)
		(width 0.14224)
		(layer "In2.Cu")
		(net "M_D_DQ<22>")
	)
	(arc
		(start 235.597192 -94.81439)
		(mid 235.40555 -94.871556)
		(end 235.265468 -95.014288)
		(width 0.0889)
		(layer "In2.Cu")
		(net "M_D_DQ<22>")
	)
	(arc
		(start 236.449108 -95.309436)
		(mid 236.165891 -95.225155)
		(end 235.958888 -95.014288)
		(width 0.0889)
		(layer "In2.Cu")
		(net "M_D_DQ<22>")
	)
	(arc
		(start 235.958888 -95.014288)
		(mid 235.818809 -94.871552)
		(end 235.627164 -94.81439)
		(width 0.0889)
		(layer "In2.Cu")
		(net "M_D_DQ<22>")
	)
	(arc
		(start 236.817408 -95.509588)
		(mid 236.675725 -95.365784)
		(end 236.481874 -95.309436)
		(width 0.0889)
		(layer "In2.Cu")
		(net "M_D_DQ<22>")
	)
	(segment
		(start 215.100408 -133.0706)
		(end 215.0999 -133.076442)
		(width 0.1651)
		(layer "F.Cu")
		(net "M_D_DQ<21>")
	)
	(segment
		(start 215.0999 -133.076442)
		(end 215.0999 -134.340346)
		(width 0.1651)
		(layer "F.Cu")
		(net "M_D_DQ<21>")
	)
	(segment
		(start 237.900718 -93.23324)
		(end 237.329218 -93.23324)
		(width 0.1651)
		(layer "F.Cu")
		(net "M_D_DQ<21>")
	)
	(via
		(at 237.329218 -93.23324)
		(size 0.508)
		(drill 0.254)
		(layers "F.Cu" "B.Cu")
		(net "M_D_DQ<21>")
	)
	(via
		(at 215.873584 -130.330956)
		(size 0.508)
		(drill 0.254)
		(layers "F.Cu" "B.Cu")
		(net "M_D_DQ<21>")
	)
	(via
		(at 215.0999 -134.340346)
		(size 0.508)
		(drill 0.254)
		(layers "F.Cu" "B.Cu")
		(net "M_D_DQ<21>")
	)
	(segment
		(start 215.950292 -128.276096)
		(end 215.949784 -128.276096)
		(width 0.1651)
		(layer "B.Cu")
		(net "M_D_DQ<21>")
	)
	(segment
		(start 215.949784 -130.254756)
		(end 215.873584 -130.330956)
		(width 0.1651)
		(layer "B.Cu")
		(net "M_D_DQ<21>")
	)
	(segment
		(start 215.949784 -128.276096)
		(end 215.949784 -130.254756)
		(width 0.1651)
		(layer "B.Cu")
		(net "M_D_DQ<21>")
	)
	(segment
		(start 214.6554 -128.481328)
		(end 214.79764 -128.623568)
		(width 0.14224)
		(layer "In2.Cu")
		(net "M_D_DQ<21>")
	)
	(segment
		(start 214.6046 -127.180848)
		(end 214.74684 -127.323088)
		(width 0.14224)
		(layer "In2.Cu")
		(net "M_D_DQ<21>")
	)
	(segment
		(start 215.26119 -132.553456)
		(end 215.499188 -132.791454)
		(width 0.14224)
		(layer "In2.Cu")
		(net "M_D_DQ<21>")
	)
	(segment
		(start 215.5952 -127.465328)
		(end 215.5952 -127.831088)
		(width 0.14224)
		(layer "In2.Cu")
		(net "M_D_DQ<21>")
	)
	(segment
		(start 215.499188 -133.146546)
		(end 215.26119 -133.384544)
		(width 0.14224)
		(layer "In2.Cu")
		(net "M_D_DQ<21>")
	)
	(segment
		(start 234.764834 -91.347036)
		(end 234.528614 -91.347036)
		(width 0.0889)
		(layer "In2.Cu")
		(net "M_D_DQ<21>")
	)
	(segment
		(start 215.26119 -133.696456)
		(end 215.524588 -133.959854)
		(width 0.14224)
		(layer "In2.Cu")
		(net "M_D_DQ<21>")
	)
	(segment
		(start 215.549988 -131.927346)
		(end 215.26119 -132.216144)
		(width 0.14224)
		(layer "In2.Cu")
		(net "M_D_DQ<21>")
	)
	(segment
		(start 215.26119 -132.216144)
		(end 215.26119 -132.553456)
		(width 0.14224)
		(layer "In2.Cu")
		(net "M_D_DQ<21>")
	)
	(segment
		(start 214.79764 -127.973328)
		(end 214.6554 -128.115568)
		(width 0.14224)
		(layer "In2.Cu")
		(net "M_D_DQ<21>")
	)
	(segment
		(start 214.6046 -109.595412)
		(end 214.6046 -127.180848)
		(width 0.14224)
		(layer "In2.Cu")
		(net "M_D_DQ<21>")
	)
	(segment
		(start 234.479084 -91.297506)
		(end 232.108756 -91.297506)
		(width 0.0889)
		(layer "In2.Cu")
		(net "M_D_DQ<21>")
	)
	(segment
		(start 235.627164 -91.84259)
		(end 235.594398 -91.84259)
		(width 0.0889)
		(layer "In2.Cu")
		(net "M_D_DQ<21>")
	)
	(segment
		(start 215.873584 -129.030984)
		(end 215.873584 -130.330956)
		(width 0.14224)
		(layer "In2.Cu")
		(net "M_D_DQ<21>")
	)
	(segment
		(start 215.45296 -127.323088)
		(end 215.5952 -127.465328)
		(width 0.14224)
		(layer "In2.Cu")
		(net "M_D_DQ<21>")
	)
	(segment
		(start 215.851232 -130.330956)
		(end 215.422988 -130.7592)
		(width 0.14224)
		(layer "In2.Cu")
		(net "M_D_DQ<21>")
	)
	(segment
		(start 230.80091 -91.536774)
		(end 221.02572 -101.311964)
		(width 0.14224)
		(layer "In2.Cu")
		(net "M_D_DQ<21>")
	)
	(segment
		(start 234.528614 -91.347036)
		(end 234.479084 -91.297506)
		(width 0.0889)
		(layer "In2.Cu")
		(net "M_D_DQ<21>")
	)
	(segment
		(start 214.74684 -127.323088)
		(end 215.45296 -127.323088)
		(width 0.14224)
		(layer "In2.Cu")
		(net "M_D_DQ<21>")
	)
	(segment
		(start 215.873584 -130.330956)
		(end 215.851232 -130.330956)
		(width 0.14224)
		(layer "In2.Cu")
		(net "M_D_DQ<21>")
	)
	(segment
		(start 215.422988 -131.318)
		(end 215.549988 -131.445)
		(width 0.14224)
		(layer "In2.Cu")
		(net "M_D_DQ<21>")
	)
	(segment
		(start 215.5952 -127.831088)
		(end 215.45296 -127.973328)
		(width 0.14224)
		(layer "In2.Cu")
		(net "M_D_DQ<21>")
	)
	(segment
		(start 236.481874 -92.337636)
		(end 236.449108 -92.337636)
		(width 0.0889)
		(layer "In2.Cu")
		(net "M_D_DQ<21>")
	)
	(segment
		(start 237.329218 -93.23324)
		(end 236.834172 -92.566998)
		(width 0.0889)
		(layer "In2.Cu")
		(net "M_D_DQ<21>")
	)
	(segment
		(start 231.869488 -91.536774)
		(end 230.80091 -91.536774)
		(width 0.14224)
		(layer "In2.Cu")
		(net "M_D_DQ<21>")
	)
	(segment
		(start 215.26119 -133.384544)
		(end 215.26119 -133.696456)
		(width 0.14224)
		(layer "In2.Cu")
		(net "M_D_DQ<21>")
	)
	(segment
		(start 215.466168 -128.623568)
		(end 215.873584 -129.030984)
		(width 0.14224)
		(layer "In2.Cu")
		(net "M_D_DQ<21>")
	)
	(segment
		(start 236.834172 -92.566998)
		(end 236.817408 -92.537788)
		(width 0.0889)
		(layer "In2.Cu")
		(net "M_D_DQ<21>")
	)
	(segment
		(start 221.02572 -101.311964)
		(end 221.02572 -103.174292)
		(width 0.14224)
		(layer "In2.Cu")
		(net "M_D_DQ<21>")
	)
	(segment
		(start 214.6554 -128.115568)
		(end 214.6554 -128.481328)
		(width 0.14224)
		(layer "In2.Cu")
		(net "M_D_DQ<21>")
	)
	(segment
		(start 215.524588 -134.187946)
		(end 215.372188 -134.340346)
		(width 0.14224)
		(layer "In2.Cu")
		(net "M_D_DQ<21>")
	)
	(segment
		(start 215.422988 -130.7592)
		(end 215.422988 -131.318)
		(width 0.14224)
		(layer "In2.Cu")
		(net "M_D_DQ<21>")
	)
	(segment
		(start 215.549988 -131.445)
		(end 215.549988 -131.927346)
		(width 0.14224)
		(layer "In2.Cu")
		(net "M_D_DQ<21>")
	)
	(segment
		(start 214.79764 -128.623568)
		(end 215.466168 -128.623568)
		(width 0.14224)
		(layer "In2.Cu")
		(net "M_D_DQ<21>")
	)
	(segment
		(start 215.45296 -127.973328)
		(end 214.79764 -127.973328)
		(width 0.14224)
		(layer "In2.Cu")
		(net "M_D_DQ<21>")
	)
	(segment
		(start 232.108756 -91.297506)
		(end 231.869488 -91.536774)
		(width 0.0889)
		(layer "In2.Cu")
		(net "M_D_DQ<21>")
	)
	(segment
		(start 215.524588 -133.959854)
		(end 215.524588 -134.187946)
		(width 0.14224)
		(layer "In2.Cu")
		(net "M_D_DQ<21>")
	)
	(segment
		(start 221.02572 -103.174292)
		(end 214.6046 -109.595412)
		(width 0.14224)
		(layer "In2.Cu")
		(net "M_D_DQ<21>")
	)
	(segment
		(start 215.372188 -134.340346)
		(end 215.0999 -134.340346)
		(width 0.14224)
		(layer "In2.Cu")
		(net "M_D_DQ<21>")
	)
	(segment
		(start 215.499188 -132.791454)
		(end 215.499188 -133.146546)
		(width 0.14224)
		(layer "In2.Cu")
		(net "M_D_DQ<21>")
	)
	(arc
		(start 236.449108 -92.337636)
		(mid 236.165891 -92.253355)
		(end 235.958888 -92.042488)
		(width 0.0889)
		(layer "In2.Cu")
		(net "M_D_DQ<21>")
	)
	(arc
		(start 235.594398 -91.84259)
		(mid 235.308974 -91.759123)
		(end 235.100368 -91.547188)
		(width 0.0889)
		(layer "In2.Cu")
		(net "M_D_DQ<21>")
	)
	(arc
		(start 236.817408 -92.537788)
		(mid 236.675725 -92.393984)
		(end 236.481874 -92.337636)
		(width 0.0889)
		(layer "In2.Cu")
		(net "M_D_DQ<21>")
	)
	(arc
		(start 235.100368 -91.547188)
		(mid 234.958685 -91.403384)
		(end 234.764834 -91.347036)
		(width 0.0889)
		(layer "In2.Cu")
		(net "M_D_DQ<21>")
	)
	(arc
		(start 235.958888 -92.042488)
		(mid 235.818809 -91.899752)
		(end 235.627164 -91.84259)
		(width 0.0889)
		(layer "In2.Cu")
		(net "M_D_DQ<21>")
	)
	(segment
		(start 215.949784 -136.345168)
		(end 215.85174 -135.8138)
		(width 0.1651)
		(layer "F.Cu")
		(net "M_D_DQ<20>")
	)
	(segment
		(start 215.950292 -137.67054)
		(end 215.949784 -137.67054)
		(width 0.1651)
		(layer "F.Cu")
		(net "M_D_DQ<20>")
	)
	(segment
		(start 215.949784 -137.67054)
		(end 215.949784 -136.345168)
		(width 0.1651)
		(layer "F.Cu")
		(net "M_D_DQ<20>")
	)
	(segment
		(start 238.759238 -93.72854)
		(end 238.187738 -93.72854)
		(width 0.1651)
		(layer "F.Cu")
		(net "M_D_DQ<20>")
	)
	(via
		(at 215.0999 -131.611878)
		(size 0.508)
		(drill 0.254)
		(layers "F.Cu" "B.Cu")
		(net "M_D_DQ<20>")
	)
	(via
		(at 238.187738 -93.72854)
		(size 0.508)
		(drill 0.254)
		(layers "F.Cu" "B.Cu")
		(net "M_D_DQ<20>")
	)
	(via
		(at 215.85174 -135.8138)
		(size 0.508)
		(drill 0.254)
		(layers "F.Cu" "B.Cu")
		(net "M_D_DQ<20>")
	)
	(segment
		(start 215.0999 -132.875782)
		(end 215.0999 -131.611878)
		(width 0.1651)
		(layer "B.Cu")
		(net "M_D_DQ<20>")
	)
	(segment
		(start 215.100408 -132.876036)
		(end 215.0999 -132.875782)
		(width 0.1651)
		(layer "B.Cu")
		(net "M_D_DQ<20>")
	)
	(segment
		(start 214.66683 -132.220716)
		(end 214.66683 -134.57809)
		(width 0.14224)
		(layer "In2.Cu")
		(net "M_D_DQ<20>")
	)
	(segment
		(start 236.488478 -92.147136)
		(end 236.455712 -92.147136)
		(width 0.0889)
		(layer "In2.Cu")
		(net "M_D_DQ<20>")
	)
	(segment
		(start 232.080816 -91.107514)
		(end 231.862376 -90.889074)
		(width 0.0889)
		(layer "In2.Cu")
		(net "M_D_DQ<20>")
	)
	(segment
		(start 214.66683 -134.57809)
		(end 214.824818 -134.736078)
		(width 0.14224)
		(layer "In2.Cu")
		(net "M_D_DQ<20>")
	)
	(segment
		(start 215.0999 -131.611878)
		(end 215.0999 -131.787646)
		(width 0.14224)
		(layer "In2.Cu")
		(net "M_D_DQ<20>")
	)
	(segment
		(start 220.54693 -102.74427)
		(end 213.9696 -109.3216)
		(width 0.14224)
		(layer "In2.Cu")
		(net "M_D_DQ<20>")
	)
	(segment
		(start 235.633768 -91.65209)
		(end 235.601002 -91.65209)
		(width 0.0889)
		(layer "In2.Cu")
		(net "M_D_DQ<20>")
	)
	(segment
		(start 213.9696 -109.3216)
		(end 213.9696 -128.275842)
		(width 0.14224)
		(layer "In2.Cu")
		(net "M_D_DQ<20>")
	)
	(segment
		(start 231.862376 -90.889074)
		(end 230.771446 -90.889074)
		(width 0.14224)
		(layer "In2.Cu")
		(net "M_D_DQ<20>")
	)
	(segment
		(start 215.0999 -131.787646)
		(end 214.66683 -132.220716)
		(width 0.14224)
		(layer "In2.Cu")
		(net "M_D_DQ<20>")
	)
	(segment
		(start 238.187738 -93.72854)
		(end 237.841028 -92.937838)
		(width 0.0889)
		(layer "In2.Cu")
		(net "M_D_DQ<20>")
	)
	(segment
		(start 234.557824 -91.107514)
		(end 232.080816 -91.107514)
		(width 0.0889)
		(layer "In2.Cu")
		(net "M_D_DQ<20>")
	)
	(segment
		(start 234.606846 -91.156536)
		(end 234.557824 -91.107514)
		(width 0.0889)
		(layer "In2.Cu")
		(net "M_D_DQ<20>")
	)
	(segment
		(start 214.824818 -134.736078)
		(end 214.824818 -135.03783)
		(width 0.14224)
		(layer "In2.Cu")
		(net "M_D_DQ<20>")
	)
	(segment
		(start 220.54693 -101.11359)
		(end 220.54693 -102.74427)
		(width 0.14224)
		(layer "In2.Cu")
		(net "M_D_DQ<20>")
	)
	(segment
		(start 214.975694 -131.311904)
		(end 215.0999 -131.611878)
		(width 0.14224)
		(layer "In2.Cu")
		(net "M_D_DQ<20>")
	)
	(segment
		(start 230.771446 -90.889074)
		(end 220.54693 -101.11359)
		(width 0.14224)
		(layer "In2.Cu")
		(net "M_D_DQ<20>")
	)
	(segment
		(start 213.9696 -128.275842)
		(end 214.975694 -130.705098)
		(width 0.14224)
		(layer "In2.Cu")
		(net "M_D_DQ<20>")
	)
	(segment
		(start 214.975694 -130.705098)
		(end 214.975694 -131.311904)
		(width 0.14224)
		(layer "In2.Cu")
		(net "M_D_DQ<20>")
	)
	(segment
		(start 214.824818 -135.03783)
		(end 215.600788 -135.8138)
		(width 0.14224)
		(layer "In2.Cu")
		(net "M_D_DQ<20>")
	)
	(segment
		(start 215.600788 -135.8138)
		(end 215.85174 -135.8138)
		(width 0.14224)
		(layer "In2.Cu")
		(net "M_D_DQ<20>")
	)
	(segment
		(start 237.350808 -92.64269)
		(end 237.318042 -92.64269)
		(width 0.0889)
		(layer "In2.Cu")
		(net "M_D_DQ<20>")
	)
	(segment
		(start 234.771438 -91.156536)
		(end 234.606846 -91.156536)
		(width 0.0889)
		(layer "In2.Cu")
		(net "M_D_DQ<20>")
	)
	(arc
		(start 237.318042 -92.64269)
		(mid 237.124192 -92.58634)
		(end 236.982508 -92.442538)
		(width 0.0889)
		(layer "In2.Cu")
		(net "M_D_DQ<20>")
	)
	(arc
		(start 235.601002 -91.65209)
		(mid 235.407152 -91.59574)
		(end 235.265468 -91.451938)
		(width 0.0889)
		(layer "In2.Cu")
		(net "M_D_DQ<20>")
	)
	(arc
		(start 236.982508 -92.442538)
		(mid 236.7739 -92.230606)
		(end 236.488478 -92.147136)
		(width 0.0889)
		(layer "In2.Cu")
		(net "M_D_DQ<20>")
	)
	(arc
		(start 237.841028 -92.937838)
		(mid 237.634024 -92.726974)
		(end 237.350808 -92.64269)
		(width 0.0889)
		(layer "In2.Cu")
		(net "M_D_DQ<20>")
	)
	(arc
		(start 236.123988 -91.947238)
		(mid 235.916984 -91.736374)
		(end 235.633768 -91.65209)
		(width 0.0889)
		(layer "In2.Cu")
		(net "M_D_DQ<20>")
	)
	(arc
		(start 236.455712 -92.147136)
		(mid 236.26407 -92.08997)
		(end 236.123988 -91.947238)
		(width 0.0889)
		(layer "In2.Cu")
		(net "M_D_DQ<20>")
	)
	(arc
		(start 235.265468 -91.451938)
		(mid 235.05686 -91.240006)
		(end 234.771438 -91.156536)
		(width 0.0889)
		(layer "In2.Cu")
		(net "M_D_DQ<20>")
	)
	(segment
		(start 198.100442 -133.0706)
		(end 198.099934 -133.076442)
		(width 0.1651)
		(layer "F.Cu")
		(net "M_D_DQ<1>")
	)
	(segment
		(start 232.749598 -85.30844)
		(end 232.101898 -85.30844)
		(width 0.1651)
		(layer "F.Cu")
		(net "M_D_DQ<1>")
	)
	(segment
		(start 198.099934 -133.076442)
		(end 198.099934 -134.340346)
		(width 0.1651)
		(layer "F.Cu")
		(net "M_D_DQ<1>")
	)
	(via
		(at 198.772018 -130.330956)
		(size 0.508)
		(drill 0.254)
		(layers "F.Cu" "B.Cu")
		(net "M_D_DQ<1>")
	)
	(via
		(at 198.099934 -134.340346)
		(size 0.508)
		(drill 0.254)
		(layers "F.Cu" "B.Cu")
		(net "M_D_DQ<1>")
	)
	(via
		(at 232.101898 -85.30844)
		(size 0.508)
		(drill 0.254)
		(layers "F.Cu" "B.Cu")
		(net "M_D_DQ<1>")
	)
	(segment
		(start 198.949818 -128.276096)
		(end 198.949818 -129.649982)
		(width 0.1651)
		(layer "B.Cu")
		(net "M_D_DQ<1>")
	)
	(segment
		(start 198.950326 -128.276096)
		(end 198.949818 -128.276096)
		(width 0.1651)
		(layer "B.Cu")
		(net "M_D_DQ<1>")
	)
	(segment
		(start 198.772018 -129.827782)
		(end 198.772018 -130.330956)
		(width 0.1651)
		(layer "B.Cu")
		(net "M_D_DQ<1>")
	)
	(segment
		(start 198.949818 -129.649982)
		(end 198.772018 -129.827782)
		(width 0.1651)
		(layer "B.Cu")
		(net "M_D_DQ<1>")
	)
	(segment
		(start 199.723248 -125.438154)
		(end 199.878188 -125.593094)
		(width 0.14224)
		(layer "In2.Cu")
		(net "M_D_DQ<1>")
	)
	(segment
		(start 198.261224 -133.335776)
		(end 198.261224 -133.643624)
		(width 0.14224)
		(layer "In2.Cu")
		(net "M_D_DQ<1>")
	)
	(segment
		(start 199.259952 -128.12776)
		(end 199.259952 -129.843022)
		(width 0.14224)
		(layer "In2.Cu")
		(net "M_D_DQ<1>")
	)
	(segment
		(start 199.878188 -125.946154)
		(end 199.723248 -126.101094)
		(width 0.14224)
		(layer "In2.Cu")
		(net "M_D_DQ<1>")
	)
	(segment
		(start 199.817482 -124.267214)
		(end 199.817482 -124.620274)
		(width 0.14224)
		(layer "In2.Cu")
		(net "M_D_DQ<1>")
	)
	(segment
		(start 202.869546 -113.0554)
		(end 199.699118 -116.225828)
		(width 0.14224)
		(layer "In2.Cu")
		(net "M_D_DQ<1>")
	)
	(segment
		(start 198.321422 -131.188968)
		(end 198.5518 -131.419346)
		(width 0.14224)
		(layer "In2.Cu")
		(net "M_D_DQ<1>")
	)
	(segment
		(start 198.321422 -130.7592)
		(end 198.321422 -131.188968)
		(width 0.14224)
		(layer "In2.Cu")
		(net "M_D_DQ<1>")
	)
	(segment
		(start 199.662542 -124.112274)
		(end 199.817482 -124.267214)
		(width 0.14224)
		(layer "In2.Cu")
		(net "M_D_DQ<1>")
	)
	(segment
		(start 199.07377 -125.283214)
		(end 199.22871 -125.438154)
		(width 0.14224)
		(layer "In2.Cu")
		(net "M_D_DQ<1>")
	)
	(segment
		(start 199.282558 -124.112274)
		(end 199.662542 -124.112274)
		(width 0.14224)
		(layer "In2.Cu")
		(net "M_D_DQ<1>")
	)
	(segment
		(start 199.107298 -122.278394)
		(end 199.107298 -122.631454)
		(width 0.14224)
		(layer "In2.Cu")
		(net "M_D_DQ<1>")
	)
	(segment
		(start 216.281 -100.583746)
		(end 203.809346 -113.0554)
		(width 0.14224)
		(layer "In2.Cu")
		(net "M_D_DQ<1>")
	)
	(segment
		(start 199.114156 -123.943872)
		(end 199.282558 -124.112274)
		(width 0.14224)
		(layer "In2.Cu")
		(net "M_D_DQ<1>")
	)
	(segment
		(start 231.726994 -85.683344)
		(end 230.864156 -85.683344)
		(width 0.0889)
		(layer "In2.Cu")
		(net "M_D_DQ<1>")
	)
	(segment
		(start 199.259952 -129.843022)
		(end 198.772018 -130.330956)
		(width 0.14224)
		(layer "In2.Cu")
		(net "M_D_DQ<1>")
	)
	(segment
		(start 198.772018 -130.330956)
		(end 198.749666 -130.330956)
		(width 0.14224)
		(layer "In2.Cu")
		(net "M_D_DQ<1>")
	)
	(segment
		(start 199.810878 -122.961654)
		(end 199.810878 -123.314714)
		(width 0.14224)
		(layer "In2.Cu")
		(net "M_D_DQ<1>")
	)
	(segment
		(start 199.699118 -116.225828)
		(end 199.699118 -121.938796)
		(width 0.14224)
		(layer "In2.Cu")
		(net "M_D_DQ<1>")
	)
	(segment
		(start 199.114156 -123.590812)
		(end 199.114156 -123.943872)
		(width 0.14224)
		(layer "In2.Cu")
		(net "M_D_DQ<1>")
	)
	(segment
		(start 198.261224 -132.114544)
		(end 198.261224 -132.475224)
		(width 0.14224)
		(layer "In2.Cu")
		(net "M_D_DQ<1>")
	)
	(segment
		(start 198.5518 -131.419346)
		(end 198.5518 -131.823968)
		(width 0.14224)
		(layer "In2.Cu")
		(net "M_D_DQ<1>")
	)
	(segment
		(start 199.07377 -124.930154)
		(end 199.07377 -125.283214)
		(width 0.14224)
		(layer "In2.Cu")
		(net "M_D_DQ<1>")
	)
	(segment
		(start 199.51446 -122.123454)
		(end 199.262238 -122.123454)
		(width 0.14224)
		(layer "In2.Cu")
		(net "M_D_DQ<1>")
	)
	(segment
		(start 198.4756 -132.6896)
		(end 198.4756 -133.1214)
		(width 0.14224)
		(layer "In2.Cu")
		(net "M_D_DQ<1>")
	)
	(segment
		(start 199.662542 -124.775214)
		(end 199.22871 -124.775214)
		(width 0.14224)
		(layer "In2.Cu")
		(net "M_D_DQ<1>")
	)
	(segment
		(start 199.066912 -126.256034)
		(end 199.066912 -126.609094)
		(width 0.14224)
		(layer "In2.Cu")
		(net "M_D_DQ<1>")
	)
	(segment
		(start 199.655938 -126.764034)
		(end 199.810878 -126.918974)
		(width 0.14224)
		(layer "In2.Cu")
		(net "M_D_DQ<1>")
	)
	(segment
		(start 203.809346 -113.0554)
		(end 202.869546 -113.0554)
		(width 0.14224)
		(layer "In2.Cu")
		(net "M_D_DQ<1>")
	)
	(segment
		(start 198.4756 -133.1214)
		(end 198.261224 -133.335776)
		(width 0.14224)
		(layer "In2.Cu")
		(net "M_D_DQ<1>")
	)
	(segment
		(start 199.810878 -123.314714)
		(end 199.676258 -123.449334)
		(width 0.14224)
		(layer "In2.Cu")
		(net "M_D_DQ<1>")
	)
	(segment
		(start 232.101898 -85.30844)
		(end 231.726994 -85.683344)
		(width 0.0889)
		(layer "In2.Cu")
		(net "M_D_DQ<1>")
	)
	(segment
		(start 199.066912 -126.609094)
		(end 199.221852 -126.764034)
		(width 0.14224)
		(layer "In2.Cu")
		(net "M_D_DQ<1>")
	)
	(segment
		(start 229.681278 -85.683344)
		(end 216.281 -99.083622)
		(width 0.14224)
		(layer "In2.Cu")
		(net "M_D_DQ<1>")
	)
	(segment
		(start 198.501 -134.1882)
		(end 198.348854 -134.340346)
		(width 0.14224)
		(layer "In2.Cu")
		(net "M_D_DQ<1>")
	)
	(segment
		(start 199.107298 -122.631454)
		(end 199.262238 -122.786394)
		(width 0.14224)
		(layer "In2.Cu")
		(net "M_D_DQ<1>")
	)
	(segment
		(start 199.810878 -127.272034)
		(end 199.655938 -127.426974)
		(width 0.14224)
		(layer "In2.Cu")
		(net "M_D_DQ<1>")
	)
	(segment
		(start 198.261224 -132.475224)
		(end 198.4756 -132.6896)
		(width 0.14224)
		(layer "In2.Cu")
		(net "M_D_DQ<1>")
	)
	(segment
		(start 199.817482 -124.620274)
		(end 199.662542 -124.775214)
		(width 0.14224)
		(layer "In2.Cu")
		(net "M_D_DQ<1>")
	)
	(segment
		(start 216.281 -99.083622)
		(end 216.281 -100.583746)
		(width 0.14224)
		(layer "In2.Cu")
		(net "M_D_DQ<1>")
	)
	(segment
		(start 230.864156 -85.683344)
		(end 229.681278 -85.683344)
		(width 0.14224)
		(layer "In2.Cu")
		(net "M_D_DQ<1>")
	)
	(segment
		(start 198.5518 -131.823968)
		(end 198.261224 -132.114544)
		(width 0.14224)
		(layer "In2.Cu")
		(net "M_D_DQ<1>")
	)
	(segment
		(start 199.255634 -123.449334)
		(end 199.114156 -123.590812)
		(width 0.14224)
		(layer "In2.Cu")
		(net "M_D_DQ<1>")
	)
	(segment
		(start 199.222106 -127.426974)
		(end 199.067166 -127.581914)
		(width 0.14224)
		(layer "In2.Cu")
		(net "M_D_DQ<1>")
	)
	(segment
		(start 199.221852 -126.764034)
		(end 199.655938 -126.764034)
		(width 0.14224)
		(layer "In2.Cu")
		(net "M_D_DQ<1>")
	)
	(segment
		(start 199.221852 -126.101094)
		(end 199.066912 -126.256034)
		(width 0.14224)
		(layer "In2.Cu")
		(net "M_D_DQ<1>")
	)
	(segment
		(start 199.22871 -124.775214)
		(end 199.07377 -124.930154)
		(width 0.14224)
		(layer "In2.Cu")
		(net "M_D_DQ<1>")
	)
	(segment
		(start 199.878188 -125.593094)
		(end 199.878188 -125.946154)
		(width 0.14224)
		(layer "In2.Cu")
		(net "M_D_DQ<1>")
	)
	(segment
		(start 198.501 -133.8834)
		(end 198.501 -134.1882)
		(width 0.14224)
		(layer "In2.Cu")
		(net "M_D_DQ<1>")
	)
	(segment
		(start 199.262238 -122.786394)
		(end 199.635618 -122.786394)
		(width 0.14224)
		(layer "In2.Cu")
		(net "M_D_DQ<1>")
	)
	(segment
		(start 199.810878 -126.918974)
		(end 199.810878 -127.272034)
		(width 0.14224)
		(layer "In2.Cu")
		(net "M_D_DQ<1>")
	)
	(segment
		(start 199.262238 -122.123454)
		(end 199.107298 -122.278394)
		(width 0.14224)
		(layer "In2.Cu")
		(net "M_D_DQ<1>")
	)
	(segment
		(start 199.067166 -127.934974)
		(end 199.259952 -128.12776)
		(width 0.14224)
		(layer "In2.Cu")
		(net "M_D_DQ<1>")
	)
	(segment
		(start 199.067166 -127.581914)
		(end 199.067166 -127.934974)
		(width 0.14224)
		(layer "In2.Cu")
		(net "M_D_DQ<1>")
	)
	(segment
		(start 199.655938 -127.426974)
		(end 199.222106 -127.426974)
		(width 0.14224)
		(layer "In2.Cu")
		(net "M_D_DQ<1>")
	)
	(segment
		(start 198.261224 -133.643624)
		(end 198.501 -133.8834)
		(width 0.14224)
		(layer "In2.Cu")
		(net "M_D_DQ<1>")
	)
	(segment
		(start 198.749666 -130.330956)
		(end 198.321422 -130.7592)
		(width 0.14224)
		(layer "In2.Cu")
		(net "M_D_DQ<1>")
	)
	(segment
		(start 199.635618 -122.786394)
		(end 199.810878 -122.961654)
		(width 0.14224)
		(layer "In2.Cu")
		(net "M_D_DQ<1>")
	)
	(segment
		(start 199.723248 -126.101094)
		(end 199.221852 -126.101094)
		(width 0.14224)
		(layer "In2.Cu")
		(net "M_D_DQ<1>")
	)
	(segment
		(start 199.699118 -121.938796)
		(end 199.51446 -122.123454)
		(width 0.14224)
		(layer "In2.Cu")
		(net "M_D_DQ<1>")
	)
	(segment
		(start 198.348854 -134.340346)
		(end 198.099934 -134.340346)
		(width 0.14224)
		(layer "In2.Cu")
		(net "M_D_DQ<1>")
	)
	(segment
		(start 199.22871 -125.438154)
		(end 199.723248 -125.438154)
		(width 0.14224)
		(layer "In2.Cu")
		(net "M_D_DQ<1>")
	)
	(segment
		(start 199.676258 -123.449334)
		(end 199.255634 -123.449334)
		(width 0.14224)
		(layer "In2.Cu")
		(net "M_D_DQ<1>")
	)
	(segment
		(start 236.183678 -96.20504)
		(end 235.612178 -96.20504)
		(width 0.1651)
		(layer "F.Cu")
		(net "M_D_DQ<19>")
	)
	(segment
		(start 222.75038 -133.0706)
		(end 222.749872 -133.076442)
		(width 0.1651)
		(layer "F.Cu")
		(net "M_D_DQ<19>")
	)
	(segment
		(start 222.749872 -133.076442)
		(end 222.749872 -134.340346)
		(width 0.1651)
		(layer "F.Cu")
		(net "M_D_DQ<19>")
	)
	(via
		(at 223.599756 -130.330956)
		(size 0.508)
		(drill 0.254)
		(layers "F.Cu" "B.Cu")
		(net "M_D_DQ<19>")
	)
	(via
		(at 222.749872 -134.340346)
		(size 0.508)
		(drill 0.254)
		(layers "F.Cu" "B.Cu")
		(net "M_D_DQ<19>")
	)
	(via
		(at 235.612178 -96.20504)
		(size 0.508)
		(drill 0.254)
		(layers "F.Cu" "B.Cu")
		(net "M_D_DQ<19>")
	)
	(segment
		(start 223.600518 -130.330194)
		(end 223.599756 -130.330956)
		(width 0.1651)
		(layer "B.Cu")
		(net "M_D_DQ<19>")
	)
	(segment
		(start 223.600518 -128.276096)
		(end 223.600518 -130.330194)
		(width 0.1651)
		(layer "B.Cu")
		(net "M_D_DQ<19>")
	)
	(segment
		(start 222.911162 -132.457952)
		(end 223.16821 -132.715)
		(width 0.14224)
		(layer "In2.Cu")
		(net "M_D_DQ<19>")
	)
	(segment
		(start 223.16821 -133.0198)
		(end 222.911162 -133.276848)
		(width 0.14224)
		(layer "In2.Cu")
		(net "M_D_DQ<19>")
	)
	(segment
		(start 223.599756 -130.344164)
		(end 223.599756 -130.330956)
		(width 0.14224)
		(layer "In2.Cu")
		(net "M_D_DQ<19>")
	)
	(segment
		(start 223.647 -126.313438)
		(end 223.647 -128.0414)
		(width 0.14224)
		(layer "In2.Cu")
		(net "M_D_DQ<19>")
	)
	(segment
		(start 223.647 -125.378718)
		(end 223.50476 -125.520958)
		(width 0.14224)
		(layer "In2.Cu")
		(net "M_D_DQ<19>")
	)
	(segment
		(start 223.647 -121.111518)
		(end 223.647 -121.477278)
		(width 0.14224)
		(layer "In2.Cu")
		(net "M_D_DQ<19>")
	)
	(segment
		(start 222.5294 -121.761758)
		(end 222.5294 -122.127518)
		(width 0.14224)
		(layer "In2.Cu")
		(net "M_D_DQ<19>")
	)
	(segment
		(start 226.286314 -107.545378)
		(end 225.93046 -107.901232)
		(width 0.14224)
		(layer "In2.Cu")
		(net "M_D_DQ<19>")
	)
	(segment
		(start 223.50476 -120.319038)
		(end 222.67164 -120.319038)
		(width 0.14224)
		(layer "In2.Cu")
		(net "M_D_DQ<19>")
	)
	(segment
		(start 224.286064 -108.774738)
		(end 224.067116 -108.774738)
		(width 0.14224)
		(layer "In2.Cu")
		(net "M_D_DQ<19>")
	)
	(segment
		(start 224.860866 -107.980988)
		(end 224.860866 -108.199936)
		(width 0.14224)
		(layer "In2.Cu")
		(net "M_D_DQ<19>")
	)
	(segment
		(start 223.647 -128.0414)
		(end 223.92894 -128.32334)
		(width 0.14224)
		(layer "In2.Cu")
		(net "M_D_DQ<19>")
	)
	(segment
		(start 223.02216 -134.340346)
		(end 222.749872 -134.340346)
		(width 0.14224)
		(layer "In2.Cu")
		(net "M_D_DQ<19>")
	)
	(segment
		(start 222.5294 -120.827038)
		(end 222.67164 -120.969278)
		(width 0.14224)
		(layer "In2.Cu")
		(net "M_D_DQ<19>")
	)
	(segment
		(start 232.31856 -96.187006)
		(end 231.750616 -96.75495)
		(width 0.0889)
		(layer "In2.Cu")
		(net "M_D_DQ<19>")
	)
	(segment
		(start 222.911162 -133.276848)
		(end 222.911162 -133.550152)
		(width 0.14224)
		(layer "In2.Cu")
		(net "M_D_DQ<19>")
	)
	(segment
		(start 223.50476 -122.269758)
		(end 223.647 -122.411998)
		(width 0.14224)
		(layer "In2.Cu")
		(net "M_D_DQ<19>")
	)
	(segment
		(start 223.647 -121.477278)
		(end 223.50476 -121.619518)
		(width 0.14224)
		(layer "In2.Cu")
		(net "M_D_DQ<19>")
	)
	(segment
		(start 223.19996 -134.162546)
		(end 223.02216 -134.340346)
		(width 0.14224)
		(layer "In2.Cu")
		(net "M_D_DQ<19>")
	)
	(segment
		(start 223.16821 -132.715)
		(end 223.16821 -133.0198)
		(width 0.14224)
		(layer "In2.Cu")
		(net "M_D_DQ<19>")
	)
	(segment
		(start 222.5294 -125.663198)
		(end 222.5294 -126.028958)
		(width 0.14224)
		(layer "In2.Cu")
		(net "M_D_DQ<19>")
	)
	(segment
		(start 231.750616 -97.929954)
		(end 230.214424 -99.466146)
		(width 0.0889)
		(layer "In2.Cu")
		(net "M_D_DQ<19>")
	)
	(segment
		(start 223.14916 -131.188968)
		(end 223.19361 -131.233418)
		(width 0.14224)
		(layer "In2.Cu")
		(net "M_D_DQ<19>")
	)
	(segment
		(start 223.647 -122.411998)
		(end 223.647 -122.777758)
		(width 0.14224)
		(layer "In2.Cu")
		(net "M_D_DQ<19>")
	)
	(segment
		(start 223.50476 -123.570238)
		(end 223.647 -123.712478)
		(width 0.14224)
		(layer "In2.Cu")
		(net "M_D_DQ<19>")
	)
	(segment
		(start 225.711512 -107.901232)
		(end 225.435668 -107.625134)
		(width 0.14224)
		(layer "In2.Cu")
		(net "M_D_DQ<19>")
	)
	(segment
		(start 223.50476 -126.171198)
		(end 223.647 -126.313438)
		(width 0.14224)
		(layer "In2.Cu")
		(net "M_D_DQ<19>")
	)
	(segment
		(start 223.50476 -120.969278)
		(end 223.647 -121.111518)
		(width 0.14224)
		(layer "In2.Cu")
		(net "M_D_DQ<19>")
	)
	(segment
		(start 223.647 -118.876318)
		(end 223.50476 -119.018558)
		(width 0.14224)
		(layer "In2.Cu")
		(net "M_D_DQ<19>")
	)
	(segment
		(start 223.647 -125.012958)
		(end 223.647 -125.378718)
		(width 0.14224)
		(layer "In2.Cu")
		(net "M_D_DQ<19>")
	)
	(segment
		(start 225.93046 -107.901232)
		(end 225.711512 -107.901232)
		(width 0.14224)
		(layer "In2.Cu")
		(net "M_D_DQ<19>")
	)
	(segment
		(start 223.19996 -133.83895)
		(end 223.19996 -134.162546)
		(width 0.14224)
		(layer "In2.Cu")
		(net "M_D_DQ<19>")
	)
	(segment
		(start 222.5294 -122.127518)
		(end 222.67164 -122.269758)
		(width 0.14224)
		(layer "In2.Cu")
		(net "M_D_DQ<19>")
	)
	(segment
		(start 222.5294 -123.062238)
		(end 222.5294 -123.427998)
		(width 0.14224)
		(layer "In2.Cu")
		(net "M_D_DQ<19>")
	)
	(segment
		(start 223.50476 -125.520958)
		(end 222.67164 -125.520958)
		(width 0.14224)
		(layer "In2.Cu")
		(net "M_D_DQ<19>")
	)
	(segment
		(start 223.50476 -124.870718)
		(end 223.647 -125.012958)
		(width 0.14224)
		(layer "In2.Cu")
		(net "M_D_DQ<19>")
	)
	(segment
		(start 223.19361 -131.9022)
		(end 222.911162 -132.184648)
		(width 0.14224)
		(layer "In2.Cu")
		(net "M_D_DQ<19>")
	)
	(segment
		(start 225.21672 -107.625134)
		(end 224.860866 -107.980988)
		(width 0.14224)
		(layer "In2.Cu")
		(net "M_D_DQ<19>")
	)
	(segment
		(start 222.67164 -120.319038)
		(end 222.5294 -120.461278)
		(width 0.14224)
		(layer "In2.Cu")
		(net "M_D_DQ<19>")
	)
	(segment
		(start 225.13671 -108.694982)
		(end 224.780856 -109.050836)
		(width 0.14224)
		(layer "In2.Cu")
		(net "M_D_DQ<19>")
	)
	(segment
		(start 222.5294 -123.427998)
		(end 222.67164 -123.570238)
		(width 0.14224)
		(layer "In2.Cu")
		(net "M_D_DQ<19>")
	)
	(segment
		(start 222.67164 -121.619518)
		(end 222.5294 -121.761758)
		(width 0.14224)
		(layer "In2.Cu")
		(net "M_D_DQ<19>")
	)
	(segment
		(start 222.911162 -132.184648)
		(end 222.911162 -132.457952)
		(width 0.14224)
		(layer "In2.Cu")
		(net "M_D_DQ<19>")
	)
	(segment
		(start 223.92894 -128.32334)
		(end 223.92894 -130.01498)
		(width 0.14224)
		(layer "In2.Cu")
		(net "M_D_DQ<19>")
	)
	(segment
		(start 223.50476 -121.619518)
		(end 222.67164 -121.619518)
		(width 0.14224)
		(layer "In2.Cu")
		(net "M_D_DQ<19>")
	)
	(segment
		(start 225.13671 -108.476034)
		(end 225.13671 -108.694982)
		(width 0.14224)
		(layer "In2.Cu")
		(net "M_D_DQ<19>")
	)
	(segment
		(start 223.647 -124.078238)
		(end 223.50476 -124.220478)
		(width 0.14224)
		(layer "In2.Cu")
		(net "M_D_DQ<19>")
	)
	(segment
		(start 235.612178 -96.20504)
		(end 235.236004 -96.20504)
		(width 0.0889)
		(layer "In2.Cu")
		(net "M_D_DQ<19>")
	)
	(segment
		(start 222.67164 -125.520958)
		(end 222.5294 -125.663198)
		(width 0.14224)
		(layer "In2.Cu")
		(net "M_D_DQ<19>")
	)
	(segment
		(start 222.67164 -120.969278)
		(end 223.50476 -120.969278)
		(width 0.14224)
		(layer "In2.Cu")
		(net "M_D_DQ<19>")
	)
	(segment
		(start 234.134152 -96.300036)
		(end 234.021122 -96.187006)
		(width 0.0889)
		(layer "In2.Cu")
		(net "M_D_DQ<19>")
	)
	(segment
		(start 223.50476 -119.018558)
		(end 222.67164 -119.018558)
		(width 0.14224)
		(layer "In2.Cu")
		(net "M_D_DQ<19>")
	)
	(segment
		(start 223.647 -109.194854)
		(end 223.647 -118.876318)
		(width 0.14224)
		(layer "In2.Cu")
		(net "M_D_DQ<19>")
	)
	(segment
		(start 223.50476 -119.668798)
		(end 223.647 -119.811038)
		(width 0.14224)
		(layer "In2.Cu")
		(net "M_D_DQ<19>")
	)
	(segment
		(start 226.286314 -107.32643)
		(end 226.286314 -107.545378)
		(width 0.14224)
		(layer "In2.Cu")
		(net "M_D_DQ<19>")
	)
	(segment
		(start 222.67164 -122.269758)
		(end 223.50476 -122.269758)
		(width 0.14224)
		(layer "In2.Cu")
		(net "M_D_DQ<19>")
	)
	(segment
		(start 222.67164 -119.668798)
		(end 223.50476 -119.668798)
		(width 0.14224)
		(layer "In2.Cu")
		(net "M_D_DQ<19>")
	)
	(segment
		(start 223.92894 -130.01498)
		(end 223.599756 -130.344164)
		(width 0.14224)
		(layer "In2.Cu")
		(net "M_D_DQ<19>")
	)
	(segment
		(start 226.01047 -107.050332)
		(end 226.286314 -107.32643)
		(width 0.14224)
		(layer "In2.Cu")
		(net "M_D_DQ<19>")
	)
	(segment
		(start 223.647 -122.777758)
		(end 223.50476 -122.919998)
		(width 0.14224)
		(layer "In2.Cu")
		(net "M_D_DQ<19>")
	)
	(segment
		(start 223.50476 -124.220478)
		(end 222.67164 -124.220478)
		(width 0.14224)
		(layer "In2.Cu")
		(net "M_D_DQ<19>")
	)
	(segment
		(start 223.19361 -131.233418)
		(end 223.19361 -131.9022)
		(width 0.14224)
		(layer "In2.Cu")
		(net "M_D_DQ<19>")
	)
	(segment
		(start 223.647 -120.176798)
		(end 223.50476 -120.319038)
		(width 0.14224)
		(layer "In2.Cu")
		(net "M_D_DQ<19>")
	)
	(segment
		(start 222.67164 -126.171198)
		(end 223.50476 -126.171198)
		(width 0.14224)
		(layer "In2.Cu")
		(net "M_D_DQ<19>")
	)
	(segment
		(start 222.67164 -123.570238)
		(end 223.50476 -123.570238)
		(width 0.14224)
		(layer "In2.Cu")
		(net "M_D_DQ<19>")
	)
	(segment
		(start 224.860866 -108.199936)
		(end 225.13671 -108.476034)
		(width 0.14224)
		(layer "In2.Cu")
		(net "M_D_DQ<19>")
	)
	(segment
		(start 225.435668 -107.625134)
		(end 225.21672 -107.625134)
		(width 0.14224)
		(layer "In2.Cu")
		(net "M_D_DQ<19>")
	)
	(segment
		(start 224.561908 -109.050836)
		(end 224.286064 -108.774738)
		(width 0.14224)
		(layer "In2.Cu")
		(net "M_D_DQ<19>")
	)
	(segment
		(start 222.5294 -124.362718)
		(end 222.5294 -124.728478)
		(width 0.14224)
		(layer "In2.Cu")
		(net "M_D_DQ<19>")
	)
	(segment
		(start 224.780856 -109.050836)
		(end 224.561908 -109.050836)
		(width 0.14224)
		(layer "In2.Cu")
		(net "M_D_DQ<19>")
	)
	(segment
		(start 226.182428 -103.823008)
		(end 226.182428 -106.659426)
		(width 0.14224)
		(layer "In2.Cu")
		(net "M_D_DQ<19>")
	)
	(segment
		(start 223.14916 -130.7592)
		(end 223.14916 -131.188968)
		(width 0.14224)
		(layer "In2.Cu")
		(net "M_D_DQ<19>")
	)
	(segment
		(start 234.021122 -96.187006)
		(end 232.31856 -96.187006)
		(width 0.0889)
		(layer "In2.Cu")
		(net "M_D_DQ<19>")
	)
	(segment
		(start 235.236004 -96.20504)
		(end 235.141008 -96.300036)
		(width 0.0889)
		(layer "In2.Cu")
		(net "M_D_DQ<19>")
	)
	(segment
		(start 222.67164 -124.220478)
		(end 222.5294 -124.362718)
		(width 0.14224)
		(layer "In2.Cu")
		(net "M_D_DQ<19>")
	)
	(segment
		(start 223.647 -119.811038)
		(end 223.647 -120.176798)
		(width 0.14224)
		(layer "In2.Cu")
		(net "M_D_DQ<19>")
	)
	(segment
		(start 223.647 -123.712478)
		(end 223.647 -124.078238)
		(width 0.14224)
		(layer "In2.Cu")
		(net "M_D_DQ<19>")
	)
	(segment
		(start 224.067116 -108.774738)
		(end 223.647 -109.194854)
		(width 0.14224)
		(layer "In2.Cu")
		(net "M_D_DQ<19>")
	)
	(segment
		(start 226.182428 -106.659426)
		(end 226.01047 -106.831384)
		(width 0.14224)
		(layer "In2.Cu")
		(net "M_D_DQ<19>")
	)
	(segment
		(start 223.50476 -122.919998)
		(end 222.67164 -122.919998)
		(width 0.14224)
		(layer "In2.Cu")
		(net "M_D_DQ<19>")
	)
	(segment
		(start 222.67164 -119.018558)
		(end 222.5294 -119.160798)
		(width 0.14224)
		(layer "In2.Cu")
		(net "M_D_DQ<19>")
	)
	(segment
		(start 230.214424 -99.791012)
		(end 226.182428 -103.823008)
		(width 0.14224)
		(layer "In2.Cu")
		(net "M_D_DQ<19>")
	)
	(segment
		(start 222.5294 -119.160798)
		(end 222.5294 -119.526558)
		(width 0.14224)
		(layer "In2.Cu")
		(net "M_D_DQ<19>")
	)
	(segment
		(start 222.5294 -120.461278)
		(end 222.5294 -120.827038)
		(width 0.14224)
		(layer "In2.Cu")
		(net "M_D_DQ<19>")
	)
	(segment
		(start 222.67164 -124.870718)
		(end 223.50476 -124.870718)
		(width 0.14224)
		(layer "In2.Cu")
		(net "M_D_DQ<19>")
	)
	(segment
		(start 226.01047 -106.831384)
		(end 226.01047 -107.050332)
		(width 0.14224)
		(layer "In2.Cu")
		(net "M_D_DQ<19>")
	)
	(segment
		(start 231.750616 -96.75495)
		(end 231.750616 -97.929954)
		(width 0.0889)
		(layer "In2.Cu")
		(net "M_D_DQ<19>")
	)
	(segment
		(start 223.577404 -130.330956)
		(end 223.14916 -130.7592)
		(width 0.14224)
		(layer "In2.Cu")
		(net "M_D_DQ<19>")
	)
	(segment
		(start 222.5294 -119.526558)
		(end 222.67164 -119.668798)
		(width 0.14224)
		(layer "In2.Cu")
		(net "M_D_DQ<19>")
	)
	(segment
		(start 222.5294 -126.028958)
		(end 222.67164 -126.171198)
		(width 0.14224)
		(layer "In2.Cu")
		(net "M_D_DQ<19>")
	)
	(segment
		(start 222.911162 -133.550152)
		(end 223.19996 -133.83895)
		(width 0.14224)
		(layer "In2.Cu")
		(net "M_D_DQ<19>")
	)
	(segment
		(start 222.5294 -124.728478)
		(end 222.67164 -124.870718)
		(width 0.14224)
		(layer "In2.Cu")
		(net "M_D_DQ<19>")
	)
	(segment
		(start 222.67164 -122.919998)
		(end 222.5294 -123.062238)
		(width 0.14224)
		(layer "In2.Cu")
		(net "M_D_DQ<19>")
	)
	(segment
		(start 235.141008 -96.300036)
		(end 234.134152 -96.300036)
		(width 0.0889)
		(layer "In2.Cu")
		(net "M_D_DQ<19>")
	)
	(segment
		(start 230.214424 -99.466146)
		(end 230.214424 -99.791012)
		(width 0.0889)
		(layer "In2.Cu")
		(net "M_D_DQ<19>")
	)
	(segment
		(start 223.599756 -130.330956)
		(end 223.577404 -130.330956)
		(width 0.14224)
		(layer "In2.Cu")
		(net "M_D_DQ<19>")
	)
	(segment
		(start 223.731328 -136.54786)
		(end 223.731328 -136.32434)
		(width 0.1651)
		(layer "F.Cu")
		(net "M_D_DQ<18>")
	)
	(segment
		(start 223.731328 -136.32434)
		(end 223.599756 -136.192768)
		(width 0.1651)
		(layer "F.Cu")
		(net "M_D_DQ<18>")
	)
	(segment
		(start 223.599756 -136.679432)
		(end 223.731328 -136.54786)
		(width 0.1651)
		(layer "F.Cu")
		(net "M_D_DQ<18>")
	)
	(segment
		(start 223.600518 -137.67054)
		(end 223.599756 -137.67054)
		(width 0.1651)
		(layer "F.Cu")
		(net "M_D_DQ<18>")
	)
	(segment
		(start 237.042198 -96.700086)
		(end 236.470698 -96.700086)
		(width 0.1651)
		(layer "F.Cu")
		(net "M_D_DQ<18>")
	)
	(segment
		(start 223.599756 -137.67054)
		(end 223.599756 -136.679432)
		(width 0.1651)
		(layer "F.Cu")
		(net "M_D_DQ<18>")
	)
	(segment
		(start 223.599756 -136.192768)
		(end 223.599756 -135.9154)
		(width 0.1651)
		(layer "F.Cu")
		(net "M_D_DQ<18>")
	)
	(via
		(at 236.470698 -96.700086)
		(size 0.508)
		(drill 0.254)
		(layers "F.Cu" "B.Cu")
		(net "M_D_DQ<18>")
	)
	(via
		(at 222.749872 -131.611878)
		(size 0.508)
		(drill 0.254)
		(layers "F.Cu" "B.Cu")
		(net "M_D_DQ<18>")
	)
	(via
		(at 223.599756 -135.9154)
		(size 0.508)
		(drill 0.254)
		(layers "F.Cu" "B.Cu")
		(net "M_D_DQ<18>")
	)
	(segment
		(start 222.749872 -132.875782)
		(end 222.749872 -131.611878)
		(width 0.1651)
		(layer "B.Cu")
		(net "M_D_DQ<18>")
	)
	(segment
		(start 222.75038 -132.876036)
		(end 222.749872 -132.875782)
		(width 0.1651)
		(layer "B.Cu")
		(net "M_D_DQ<18>")
	)
	(segment
		(start 236.470698 -96.700086)
		(end 236.470698 -96.309688)
		(width 0.0889)
		(layer "In2.Cu")
		(net "M_D_DQ<18>")
	)
	(segment
		(start 221.72676 -123.943364)
		(end 221.869 -124.085604)
		(width 0.14224)
		(layer "In2.Cu")
		(net "M_D_DQ<18>")
	)
	(segment
		(start 220.7768 -124.735844)
		(end 220.7768 -125.101604)
		(width 0.14224)
		(layer "In2.Cu")
		(net "M_D_DQ<18>")
	)
	(segment
		(start 222.316802 -134.632446)
		(end 223.599756 -135.9154)
		(width 0.14224)
		(layer "In2.Cu")
		(net "M_D_DQ<18>")
	)
	(segment
		(start 221.869 -124.085604)
		(end 221.869 -124.451364)
		(width 0.14224)
		(layer "In2.Cu")
		(net "M_D_DQ<18>")
	)
	(segment
		(start 222.0468 -120.4976)
		(end 221.9198 -120.6246)
		(width 0.14224)
		(layer "In2.Cu")
		(net "M_D_DQ<18>")
	)
	(segment
		(start 221.72676 -123.293124)
		(end 220.91904 -123.293124)
		(width 0.14224)
		(layer "In2.Cu")
		(net "M_D_DQ<18>")
	)
	(segment
		(start 231.560624 -96.67621)
		(end 231.560624 -97.851214)
		(width 0.0889)
		(layer "In2.Cu")
		(net "M_D_DQ<18>")
	)
	(segment
		(start 220.7768 -120.8278)
		(end 220.7768 -121.200164)
		(width 0.14224)
		(layer "In2.Cu")
		(net "M_D_DQ<18>")
	)
	(segment
		(start 221.72676 -121.992644)
		(end 220.91904 -121.992644)
		(width 0.14224)
		(layer "In2.Cu")
		(net "M_D_DQ<18>")
	)
	(segment
		(start 235.916724 -95.755714)
		(end 235.38307 -95.755714)
		(width 0.0889)
		(layer "In2.Cu")
		(net "M_D_DQ<18>")
	)
	(segment
		(start 220.7768 -126.365)
		(end 221.3356 -126.9238)
		(width 0.14224)
		(layer "In2.Cu")
		(net "M_D_DQ<18>")
	)
	(segment
		(start 220.7768 -126.036324)
		(end 220.7768 -126.365)
		(width 0.14224)
		(layer "In2.Cu")
		(net "M_D_DQ<18>")
	)
	(segment
		(start 220.7768 -122.500644)
		(end 220.91904 -122.642884)
		(width 0.14224)
		(layer "In2.Cu")
		(net "M_D_DQ<18>")
	)
	(segment
		(start 225.542348 -106.39425)
		(end 223.1644 -108.772198)
		(width 0.14224)
		(layer "In2.Cu")
		(net "M_D_DQ<18>")
	)
	(segment
		(start 220.91904 -121.992644)
		(end 220.7768 -122.134884)
		(width 0.14224)
		(layer "In2.Cu")
		(net "M_D_DQ<18>")
	)
	(segment
		(start 220.91904 -121.342404)
		(end 221.72676 -121.342404)
		(width 0.14224)
		(layer "In2.Cu")
		(net "M_D_DQ<18>")
	)
	(segment
		(start 230.087424 -99.324414)
		(end 229.764844 -99.324414)
		(width 0.0889)
		(layer "In2.Cu")
		(net "M_D_DQ<18>")
	)
	(segment
		(start 221.3356 -126.9238)
		(end 222.8342 -126.9238)
		(width 0.14224)
		(layer "In2.Cu")
		(net "M_D_DQ<18>")
	)
	(segment
		(start 223.012 -128.4224)
		(end 223.26854 -128.67894)
		(width 0.14224)
		(layer "In2.Cu")
		(net "M_D_DQ<18>")
	)
	(segment
		(start 225.542348 -103.54691)
		(end 225.542348 -106.39425)
		(width 0.14224)
		(layer "In2.Cu")
		(net "M_D_DQ<18>")
	)
	(segment
		(start 223.26854 -128.67894)
		(end 223.26854 -129.770378)
		(width 0.14224)
		(layer "In2.Cu")
		(net "M_D_DQ<18>")
	)
	(segment
		(start 221.72676 -124.593604)
		(end 220.91904 -124.593604)
		(width 0.14224)
		(layer "In2.Cu")
		(net "M_D_DQ<18>")
	)
	(segment
		(start 220.7768 -121.200164)
		(end 220.91904 -121.342404)
		(width 0.14224)
		(layer "In2.Cu")
		(net "M_D_DQ<18>")
	)
	(segment
		(start 221.9198 -120.6246)
		(end 220.98 -120.6246)
		(width 0.14224)
		(layer "In2.Cu")
		(net "M_D_DQ<18>")
	)
	(segment
		(start 223.1644 -108.772198)
		(end 223.1644 -117.856)
		(width 0.14224)
		(layer "In2.Cu")
		(net "M_D_DQ<18>")
	)
	(segment
		(start 232.23982 -95.997014)
		(end 231.560624 -96.67621)
		(width 0.0889)
		(layer "In2.Cu")
		(net "M_D_DQ<18>")
	)
	(segment
		(start 236.470698 -96.309688)
		(end 235.916724 -95.755714)
		(width 0.0889)
		(layer "In2.Cu")
		(net "M_D_DQ<18>")
	)
	(segment
		(start 229.764844 -99.324414)
		(end 225.542348 -103.54691)
		(width 0.14224)
		(layer "In2.Cu")
		(net "M_D_DQ<18>")
	)
	(segment
		(start 220.91904 -123.943364)
		(end 221.72676 -123.943364)
		(width 0.14224)
		(layer "In2.Cu")
		(net "M_D_DQ<18>")
	)
	(segment
		(start 221.869 -125.386084)
		(end 221.869 -125.751844)
		(width 0.14224)
		(layer "In2.Cu")
		(net "M_D_DQ<18>")
	)
	(segment
		(start 220.91904 -125.894084)
		(end 220.7768 -126.036324)
		(width 0.14224)
		(layer "In2.Cu")
		(net "M_D_DQ<18>")
	)
	(segment
		(start 220.7768 -122.134884)
		(end 220.7768 -122.500644)
		(width 0.14224)
		(layer "In2.Cu")
		(net "M_D_DQ<18>")
	)
	(segment
		(start 220.91904 -122.642884)
		(end 221.72676 -122.642884)
		(width 0.14224)
		(layer "In2.Cu")
		(net "M_D_DQ<18>")
	)
	(segment
		(start 221.72676 -125.894084)
		(end 220.91904 -125.894084)
		(width 0.14224)
		(layer "In2.Cu")
		(net "M_D_DQ<18>")
	)
	(segment
		(start 234.100624 -95.997014)
		(end 232.23982 -95.997014)
		(width 0.0889)
		(layer "In2.Cu")
		(net "M_D_DQ<18>")
	)
	(segment
		(start 221.869 -123.150884)
		(end 221.72676 -123.293124)
		(width 0.14224)
		(layer "In2.Cu")
		(net "M_D_DQ<18>")
	)
	(segment
		(start 220.91904 -125.243844)
		(end 221.72676 -125.243844)
		(width 0.14224)
		(layer "In2.Cu")
		(net "M_D_DQ<18>")
	)
	(segment
		(start 221.869 -124.451364)
		(end 221.72676 -124.593604)
		(width 0.14224)
		(layer "In2.Cu")
		(net "M_D_DQ<18>")
	)
	(segment
		(start 231.560624 -97.851214)
		(end 230.087424 -99.324414)
		(width 0.0889)
		(layer "In2.Cu")
		(net "M_D_DQ<18>")
	)
	(segment
		(start 223.012 -127.1016)
		(end 223.012 -128.4224)
		(width 0.14224)
		(layer "In2.Cu")
		(net "M_D_DQ<18>")
	)
	(segment
		(start 222.0468 -118.9736)
		(end 222.0468 -120.4976)
		(width 0.14224)
		(layer "In2.Cu")
		(net "M_D_DQ<18>")
	)
	(segment
		(start 222.749872 -131.611878)
		(end 222.316802 -132.044948)
		(width 0.14224)
		(layer "In2.Cu")
		(net "M_D_DQ<18>")
	)
	(segment
		(start 222.40494 -130.633978)
		(end 222.40494 -131.266946)
		(width 0.14224)
		(layer "In2.Cu")
		(net "M_D_DQ<18>")
	)
	(segment
		(start 221.72676 -122.642884)
		(end 221.869 -122.785124)
		(width 0.14224)
		(layer "In2.Cu")
		(net "M_D_DQ<18>")
	)
	(segment
		(start 222.8342 -126.9238)
		(end 223.012 -127.1016)
		(width 0.14224)
		(layer "In2.Cu")
		(net "M_D_DQ<18>")
	)
	(segment
		(start 221.72676 -121.342404)
		(end 221.869 -121.484644)
		(width 0.14224)
		(layer "In2.Cu")
		(net "M_D_DQ<18>")
	)
	(segment
		(start 220.91904 -123.293124)
		(end 220.7768 -123.435364)
		(width 0.14224)
		(layer "In2.Cu")
		(net "M_D_DQ<18>")
	)
	(segment
		(start 221.869 -125.751844)
		(end 221.72676 -125.894084)
		(width 0.14224)
		(layer "In2.Cu")
		(net "M_D_DQ<18>")
	)
	(segment
		(start 220.7768 -125.101604)
		(end 220.91904 -125.243844)
		(width 0.14224)
		(layer "In2.Cu")
		(net "M_D_DQ<18>")
	)
	(segment
		(start 235.38307 -95.755714)
		(end 235.029248 -96.109536)
		(width 0.0889)
		(layer "In2.Cu")
		(net "M_D_DQ<18>")
	)
	(segment
		(start 223.1644 -117.856)
		(end 222.0468 -118.9736)
		(width 0.14224)
		(layer "In2.Cu")
		(net "M_D_DQ<18>")
	)
	(segment
		(start 220.91904 -124.593604)
		(end 220.7768 -124.735844)
		(width 0.14224)
		(layer "In2.Cu")
		(net "M_D_DQ<18>")
	)
	(segment
		(start 221.869 -121.484644)
		(end 221.869 -121.850404)
		(width 0.14224)
		(layer "In2.Cu")
		(net "M_D_DQ<18>")
	)
	(segment
		(start 234.213146 -96.109536)
		(end 234.100624 -95.997014)
		(width 0.0889)
		(layer "In2.Cu")
		(net "M_D_DQ<18>")
	)
	(segment
		(start 221.72676 -125.243844)
		(end 221.869 -125.386084)
		(width 0.14224)
		(layer "In2.Cu")
		(net "M_D_DQ<18>")
	)
	(segment
		(start 220.98 -120.6246)
		(end 220.7768 -120.8278)
		(width 0.14224)
		(layer "In2.Cu")
		(net "M_D_DQ<18>")
	)
	(segment
		(start 235.029248 -96.109536)
		(end 234.213146 -96.109536)
		(width 0.0889)
		(layer "In2.Cu")
		(net "M_D_DQ<18>")
	)
	(segment
		(start 221.869 -121.850404)
		(end 221.72676 -121.992644)
		(width 0.14224)
		(layer "In2.Cu")
		(net "M_D_DQ<18>")
	)
	(segment
		(start 220.7768 -123.801124)
		(end 220.91904 -123.943364)
		(width 0.14224)
		(layer "In2.Cu")
		(net "M_D_DQ<18>")
	)
	(segment
		(start 223.26854 -129.770378)
		(end 222.40494 -130.633978)
		(width 0.14224)
		(layer "In2.Cu")
		(net "M_D_DQ<18>")
	)
	(segment
		(start 222.316802 -132.044948)
		(end 222.316802 -134.632446)
		(width 0.14224)
		(layer "In2.Cu")
		(net "M_D_DQ<18>")
	)
	(segment
		(start 221.869 -122.785124)
		(end 221.869 -123.150884)
		(width 0.14224)
		(layer "In2.Cu")
		(net "M_D_DQ<18>")
	)
	(segment
		(start 220.7768 -123.435364)
		(end 220.7768 -123.801124)
		(width 0.14224)
		(layer "In2.Cu")
		(net "M_D_DQ<18>")
	)
	(segment
		(start 222.40494 -131.266946)
		(end 222.749872 -131.611878)
		(width 0.14224)
		(layer "In2.Cu")
		(net "M_D_DQ<18>")
	)
	(segment
		(start 216.80043 -133.0706)
		(end 216.799922 -133.076442)
		(width 0.1651)
		(layer "F.Cu")
		(net "M_D_DQ<17>")
	)
	(segment
		(start 237.042198 -93.72854)
		(end 236.470698 -93.72854)
		(width 0.1651)
		(layer "F.Cu")
		(net "M_D_DQ<17>")
	)
	(segment
		(start 216.799922 -133.076442)
		(end 216.799922 -134.340346)
		(width 0.1651)
		(layer "F.Cu")
		(net "M_D_DQ<17>")
	)
	(via
		(at 236.470698 -93.72854)
		(size 0.508)
		(drill 0.254)
		(layers "F.Cu" "B.Cu")
		(net "M_D_DQ<17>")
	)
	(via
		(at 217.472006 -130.330956)
		(size 0.508)
		(drill 0.254)
		(layers "F.Cu" "B.Cu")
		(net "M_D_DQ<17>")
	)
	(via
		(at 216.799922 -134.340346)
		(size 0.508)
		(drill 0.254)
		(layers "F.Cu" "B.Cu")
		(net "M_D_DQ<17>")
	)
	(segment
		(start 217.472006 -129.827782)
		(end 217.472006 -130.330956)
		(width 0.1651)
		(layer "B.Cu")
		(net "M_D_DQ<17>")
	)
	(segment
		(start 217.649806 -129.649982)
		(end 217.472006 -129.827782)
		(width 0.1651)
		(layer "B.Cu")
		(net "M_D_DQ<17>")
	)
	(segment
		(start 217.649806 -128.276096)
		(end 217.649806 -129.649982)
		(width 0.1651)
		(layer "B.Cu")
		(net "M_D_DQ<17>")
	)
	(segment
		(start 217.650314 -128.276096)
		(end 217.649806 -128.276096)
		(width 0.1651)
		(layer "B.Cu")
		(net "M_D_DQ<17>")
	)
	(segment
		(start 235.627164 -92.83319)
		(end 235.594398 -92.83319)
		(width 0.0889)
		(layer "In2.Cu")
		(net "M_D_DQ<17>")
	)
	(segment
		(start 216.06764 -124.796804)
		(end 216.92616 -124.796804)
		(width 0.14224)
		(layer "In2.Cu")
		(net "M_D_DQ<17>")
	)
	(segment
		(start 216.92616 -124.796804)
		(end 217.0684 -124.939044)
		(width 0.14224)
		(layer "In2.Cu")
		(net "M_D_DQ<17>")
	)
	(segment
		(start 217.472006 -130.330956)
		(end 217.449654 -130.330956)
		(width 0.14224)
		(layer "In2.Cu")
		(net "M_D_DQ<17>")
	)
	(segment
		(start 215.9254 -124.288804)
		(end 215.9254 -124.654564)
		(width 0.14224)
		(layer "In2.Cu")
		(net "M_D_DQ<17>")
	)
	(segment
		(start 217.251788 -131.419346)
		(end 217.251788 -131.823968)
		(width 0.14224)
		(layer "In2.Cu")
		(net "M_D_DQ<17>")
	)
	(segment
		(start 217.200988 -133.8834)
		(end 217.200988 -134.1882)
		(width 0.14224)
		(layer "In2.Cu")
		(net "M_D_DQ<17>")
	)
	(segment
		(start 217.251788 -131.823968)
		(end 216.961212 -132.114544)
		(width 0.14224)
		(layer "In2.Cu")
		(net "M_D_DQ<17>")
	)
	(segment
		(start 215.9254 -124.654564)
		(end 216.06764 -124.796804)
		(width 0.14224)
		(layer "In2.Cu")
		(net "M_D_DQ<17>")
	)
	(segment
		(start 217.0684 -124.939044)
		(end 217.0684 -125.304804)
		(width 0.14224)
		(layer "In2.Cu")
		(net "M_D_DQ<17>")
	)
	(segment
		(start 216.92616 -124.146564)
		(end 216.06764 -124.146564)
		(width 0.14224)
		(layer "In2.Cu")
		(net "M_D_DQ<17>")
	)
	(segment
		(start 217.02141 -130.7592)
		(end 217.02141 -131.188968)
		(width 0.14224)
		(layer "In2.Cu")
		(net "M_D_DQ<17>")
	)
	(segment
		(start 235.975652 -93.062298)
		(end 235.958888 -93.033088)
		(width 0.0889)
		(layer "In2.Cu")
		(net "M_D_DQ<17>")
	)
	(segment
		(start 216.06764 -123.496324)
		(end 216.92616 -123.496324)
		(width 0.14224)
		(layer "In2.Cu")
		(net "M_D_DQ<17>")
	)
	(segment
		(start 217.048842 -134.340346)
		(end 216.799922 -134.340346)
		(width 0.14224)
		(layer "In2.Cu")
		(net "M_D_DQ<17>")
	)
	(segment
		(start 216.92616 -125.447044)
		(end 216.06764 -125.447044)
		(width 0.14224)
		(layer "In2.Cu")
		(net "M_D_DQ<17>")
	)
	(segment
		(start 217.200988 -134.1882)
		(end 217.048842 -134.340346)
		(width 0.14224)
		(layer "In2.Cu")
		(net "M_D_DQ<17>")
	)
	(segment
		(start 215.9254 -126.0602)
		(end 216.1286 -126.2634)
		(width 0.14224)
		(layer "In2.Cu")
		(net "M_D_DQ<17>")
	)
	(segment
		(start 215.9254 -125.589284)
		(end 215.9254 -126.0602)
		(width 0.14224)
		(layer "In2.Cu")
		(net "M_D_DQ<17>")
	)
	(segment
		(start 232.299002 -92.337636)
		(end 232.050336 -92.586302)
		(width 0.0889)
		(layer "In2.Cu")
		(net "M_D_DQ<17>")
	)
	(segment
		(start 215.9254 -123.354084)
		(end 216.06764 -123.496324)
		(width 0.14224)
		(layer "In2.Cu")
		(net "M_D_DQ<17>")
	)
	(segment
		(start 217.449654 -130.330956)
		(end 217.02141 -130.7592)
		(width 0.14224)
		(layer "In2.Cu")
		(net "M_D_DQ<17>")
	)
	(segment
		(start 217.175588 -133.1214)
		(end 216.961212 -133.335776)
		(width 0.14224)
		(layer "In2.Cu")
		(net "M_D_DQ<17>")
	)
	(segment
		(start 216.961212 -133.643624)
		(end 217.200988 -133.8834)
		(width 0.14224)
		(layer "In2.Cu")
		(net "M_D_DQ<17>")
	)
	(segment
		(start 217.0684 -125.304804)
		(end 216.92616 -125.447044)
		(width 0.14224)
		(layer "In2.Cu")
		(net "M_D_DQ<17>")
	)
	(segment
		(start 216.961212 -132.114544)
		(end 216.961212 -132.475224)
		(width 0.14224)
		(layer "In2.Cu")
		(net "M_D_DQ<17>")
	)
	(segment
		(start 217.0684 -123.638564)
		(end 217.0684 -124.004324)
		(width 0.14224)
		(layer "In2.Cu")
		(net "M_D_DQ<17>")
	)
	(segment
		(start 231.958134 -92.586302)
		(end 231.675178 -92.869258)
		(width 0.0889)
		(layer "In2.Cu")
		(net "M_D_DQ<17>")
	)
	(segment
		(start 236.470698 -93.72854)
		(end 235.975652 -93.062298)
		(width 0.0889)
		(layer "In2.Cu")
		(net "M_D_DQ<17>")
	)
	(segment
		(start 216.06764 -125.447044)
		(end 215.9254 -125.589284)
		(width 0.14224)
		(layer "In2.Cu")
		(net "M_D_DQ<17>")
	)
	(segment
		(start 217.175588 -132.6896)
		(end 217.175588 -133.1214)
		(width 0.14224)
		(layer "In2.Cu")
		(net "M_D_DQ<17>")
	)
	(segment
		(start 221.9833 -101.708712)
		(end 221.9833 -104.019096)
		(width 0.14224)
		(layer "In2.Cu")
		(net "M_D_DQ<17>")
	)
	(segment
		(start 231.675178 -92.869258)
		(end 230.822754 -92.869258)
		(width 0.14224)
		(layer "In2.Cu")
		(net "M_D_DQ<17>")
	)
	(segment
		(start 216.92616 -123.496324)
		(end 217.0684 -123.638564)
		(width 0.14224)
		(layer "In2.Cu")
		(net "M_D_DQ<17>")
	)
	(segment
		(start 216.961212 -133.335776)
		(end 216.961212 -133.643624)
		(width 0.14224)
		(layer "In2.Cu")
		(net "M_D_DQ<17>")
	)
	(segment
		(start 216.06764 -124.146564)
		(end 215.9254 -124.288804)
		(width 0.14224)
		(layer "In2.Cu")
		(net "M_D_DQ<17>")
	)
	(segment
		(start 216.961212 -132.475224)
		(end 217.175588 -132.6896)
		(width 0.14224)
		(layer "In2.Cu")
		(net "M_D_DQ<17>")
	)
	(segment
		(start 217.02141 -131.188968)
		(end 217.251788 -131.419346)
		(width 0.14224)
		(layer "In2.Cu")
		(net "M_D_DQ<17>")
	)
	(segment
		(start 217.8558 -129.947162)
		(end 217.472006 -130.330956)
		(width 0.14224)
		(layer "In2.Cu")
		(net "M_D_DQ<17>")
	)
	(segment
		(start 217.8558 -129.032)
		(end 217.8558 -129.947162)
		(width 0.14224)
		(layer "In2.Cu")
		(net "M_D_DQ<17>")
	)
	(segment
		(start 216.1286 -126.2634)
		(end 216.535 -126.2634)
		(width 0.14224)
		(layer "In2.Cu")
		(net "M_D_DQ<17>")
	)
	(segment
		(start 216.7382 -127.9144)
		(end 217.8558 -129.032)
		(width 0.14224)
		(layer "In2.Cu")
		(net "M_D_DQ<17>")
	)
	(segment
		(start 230.822754 -92.869258)
		(end 221.9833 -101.708712)
		(width 0.14224)
		(layer "In2.Cu")
		(net "M_D_DQ<17>")
	)
	(segment
		(start 216.7382 -126.4666)
		(end 216.7382 -127.9144)
		(width 0.14224)
		(layer "In2.Cu")
		(net "M_D_DQ<17>")
	)
	(segment
		(start 234.764834 -92.337636)
		(end 232.299002 -92.337636)
		(width 0.0889)
		(layer "In2.Cu")
		(net "M_D_DQ<17>")
	)
	(segment
		(start 221.9833 -104.019096)
		(end 215.9254 -110.076996)
		(width 0.14224)
		(layer "In2.Cu")
		(net "M_D_DQ<17>")
	)
	(segment
		(start 215.9254 -110.076996)
		(end 215.9254 -123.354084)
		(width 0.14224)
		(layer "In2.Cu")
		(net "M_D_DQ<17>")
	)
	(segment
		(start 216.535 -126.2634)
		(end 216.7382 -126.4666)
		(width 0.14224)
		(layer "In2.Cu")
		(net "M_D_DQ<17>")
	)
	(segment
		(start 217.0684 -124.004324)
		(end 216.92616 -124.146564)
		(width 0.14224)
		(layer "In2.Cu")
		(net "M_D_DQ<17>")
	)
	(segment
		(start 232.050336 -92.586302)
		(end 231.958134 -92.586302)
		(width 0.0889)
		(layer "In2.Cu")
		(net "M_D_DQ<17>")
	)
	(arc
		(start 235.594398 -92.83319)
		(mid 235.308974 -92.749723)
		(end 235.100368 -92.537788)
		(width 0.0889)
		(layer "In2.Cu")
		(net "M_D_DQ<17>")
	)
	(arc
		(start 235.958888 -93.033088)
		(mid 235.818809 -92.890352)
		(end 235.627164 -92.83319)
		(width 0.0889)
		(layer "In2.Cu")
		(net "M_D_DQ<17>")
	)
	(arc
		(start 235.100368 -92.537788)
		(mid 234.958685 -92.393984)
		(end 234.764834 -92.337636)
		(width 0.0889)
		(layer "In2.Cu")
		(net "M_D_DQ<17>")
	)
	(segment
		(start 238.759238 -94.718886)
		(end 238.187738 -94.718886)
		(width 0.1651)
		(layer "F.Cu")
		(net "M_D_DQ<16>")
	)
	(segment
		(start 217.650314 -137.67054)
		(end 217.649806 -137.676382)
		(width 0.1651)
		(layer "F.Cu")
		(net "M_D_DQ<16>")
	)
	(segment
		(start 217.649806 -137.676382)
		(end 217.472006 -135.8138)
		(width 0.1651)
		(layer "F.Cu")
		(net "M_D_DQ<16>")
	)
	(via
		(at 217.472006 -135.8138)
		(size 0.508)
		(drill 0.254)
		(layers "F.Cu" "B.Cu")
		(net "M_D_DQ<16>")
	)
	(via
		(at 238.187738 -94.718886)
		(size 0.508)
		(drill 0.254)
		(layers "F.Cu" "B.Cu")
		(net "M_D_DQ<16>")
	)
	(via
		(at 216.799922 -131.611878)
		(size 0.508)
		(drill 0.254)
		(layers "F.Cu" "B.Cu")
		(net "M_D_DQ<16>")
	)
	(segment
		(start 216.80043 -132.876036)
		(end 216.799922 -132.875782)
		(width 0.1651)
		(layer "B.Cu")
		(net "M_D_DQ<16>")
	)
	(segment
		(start 216.799922 -132.875782)
		(end 216.799922 -131.611878)
		(width 0.1651)
		(layer "B.Cu")
		(net "M_D_DQ<16>")
	)
	(segment
		(start 216.366852 -132.044948)
		(end 216.366852 -135.00481)
		(width 0.14224)
		(layer "In2.Cu")
		(net "M_D_DQ<16>")
	)
	(segment
		(start 216.366852 -135.00481)
		(end 217.175842 -135.8138)
		(width 0.14224)
		(layer "In2.Cu")
		(net "M_D_DQ<16>")
	)
	(segment
		(start 236.483652 -93.137736)
		(end 236.455712 -93.137736)
		(width 0.0889)
		(layer "In2.Cu")
		(net "M_D_DQ<16>")
	)
	(segment
		(start 232.22077 -92.147136)
		(end 231.971596 -92.39631)
		(width 0.0889)
		(layer "In2.Cu")
		(net "M_D_DQ<16>")
	)
	(segment
		(start 217.175842 -135.8138)
		(end 217.472006 -135.8138)
		(width 0.14224)
		(layer "In2.Cu")
		(net "M_D_DQ<16>")
	)
	(segment
		(start 216.0778 -128.0668)
		(end 217.2208 -129.2098)
		(width 0.14224)
		(layer "In2.Cu")
		(net "M_D_DQ<16>")
	)
	(segment
		(start 231.675178 -92.221304)
		(end 230.793544 -92.221304)
		(width 0.14224)
		(layer "In2.Cu")
		(net "M_D_DQ<16>")
	)
	(segment
		(start 230.793544 -92.221304)
		(end 221.50451 -101.510338)
		(width 0.14224)
		(layer "In2.Cu")
		(net "M_D_DQ<16>")
	)
	(segment
		(start 217.2208 -129.7686)
		(end 216.43594 -130.55346)
		(width 0.14224)
		(layer "In2.Cu")
		(net "M_D_DQ<16>")
	)
	(segment
		(start 215.265 -109.839252)
		(end 215.265 -126.3142)
		(width 0.14224)
		(layer "In2.Cu")
		(net "M_D_DQ<16>")
	)
	(segment
		(start 231.971596 -92.39631)
		(end 231.850184 -92.39631)
		(width 0.0889)
		(layer "In2.Cu")
		(net "M_D_DQ<16>")
	)
	(segment
		(start 238.187738 -94.718886)
		(end 237.858046 -93.957648)
		(width 0.0889)
		(layer "In2.Cu")
		(net "M_D_DQ<16>")
	)
	(segment
		(start 216.0778 -127.127)
		(end 216.0778 -128.0668)
		(width 0.14224)
		(layer "In2.Cu")
		(net "M_D_DQ<16>")
	)
	(segment
		(start 231.850184 -92.39631)
		(end 231.675178 -92.221304)
		(width 0.0889)
		(layer "In2.Cu")
		(net "M_D_DQ<16>")
	)
	(segment
		(start 237.346998 -93.633036)
		(end 237.311184 -93.633036)
		(width 0.0889)
		(layer "In2.Cu")
		(net "M_D_DQ<16>")
	)
	(segment
		(start 235.633768 -92.64269)
		(end 235.601002 -92.64269)
		(width 0.0889)
		(layer "In2.Cu")
		(net "M_D_DQ<16>")
	)
	(segment
		(start 216.43594 -130.55346)
		(end 216.43594 -131.299204)
		(width 0.14224)
		(layer "In2.Cu")
		(net "M_D_DQ<16>")
	)
	(segment
		(start 234.771438 -92.147136)
		(end 232.22077 -92.147136)
		(width 0.0889)
		(layer "In2.Cu")
		(net "M_D_DQ<16>")
	)
	(segment
		(start 221.50451 -101.510338)
		(end 221.50451 -103.599742)
		(width 0.14224)
		(layer "In2.Cu")
		(net "M_D_DQ<16>")
	)
	(segment
		(start 216.43594 -131.299204)
		(end 216.748614 -131.611878)
		(width 0.14224)
		(layer "In2.Cu")
		(net "M_D_DQ<16>")
	)
	(segment
		(start 216.799922 -131.611878)
		(end 216.366852 -132.044948)
		(width 0.14224)
		(layer "In2.Cu")
		(net "M_D_DQ<16>")
	)
	(segment
		(start 221.50451 -103.599742)
		(end 215.265 -109.839252)
		(width 0.14224)
		(layer "In2.Cu")
		(net "M_D_DQ<16>")
	)
	(segment
		(start 216.748614 -131.611878)
		(end 216.799922 -131.611878)
		(width 0.14224)
		(layer "In2.Cu")
		(net "M_D_DQ<16>")
	)
	(segment
		(start 215.265 -126.3142)
		(end 216.0778 -127.127)
		(width 0.14224)
		(layer "In2.Cu")
		(net "M_D_DQ<16>")
	)
	(segment
		(start 217.2208 -129.2098)
		(end 217.2208 -129.7686)
		(width 0.14224)
		(layer "In2.Cu")
		(net "M_D_DQ<16>")
	)
	(segment
		(start 237.858046 -93.957648)
		(end 237.841028 -93.928438)
		(width 0.0889)
		(layer "In2.Cu")
		(net "M_D_DQ<16>")
	)
	(arc
		(start 237.311184 -93.633036)
		(mid 237.121255 -93.575166)
		(end 236.982508 -93.433138)
		(width 0.0889)
		(layer "In2.Cu")
		(net "M_D_DQ<16>")
	)
	(arc
		(start 235.601002 -92.64269)
		(mid 235.407152 -92.58634)
		(end 235.265468 -92.442538)
		(width 0.0889)
		(layer "In2.Cu")
		(net "M_D_DQ<16>")
	)
	(arc
		(start 237.841028 -93.928438)
		(mid 237.63242 -93.716506)
		(end 237.346998 -93.633036)
		(width 0.0889)
		(layer "In2.Cu")
		(net "M_D_DQ<16>")
	)
	(arc
		(start 236.982508 -93.433138)
		(mid 236.771795 -93.220059)
		(end 236.483652 -93.137736)
		(width 0.0889)
		(layer "In2.Cu")
		(net "M_D_DQ<16>")
	)
	(arc
		(start 236.455712 -93.137736)
		(mid 236.26407 -93.08057)
		(end 236.123988 -92.937838)
		(width 0.0889)
		(layer "In2.Cu")
		(net "M_D_DQ<16>")
	)
	(arc
		(start 236.123988 -92.937838)
		(mid 235.916984 -92.726974)
		(end 235.633768 -92.64269)
		(width 0.0889)
		(layer "In2.Cu")
		(net "M_D_DQ<16>")
	)
	(arc
		(start 235.265468 -92.442538)
		(mid 235.05686 -92.230606)
		(end 234.771438 -92.147136)
		(width 0.0889)
		(layer "In2.Cu")
		(net "M_D_DQ<16>")
	)
	(segment
		(start 213.854538 -122.83694)
		(end 213.854538 -118.782338)
		(width 0.1651)
		(layer "F.Cu")
		(net "M_D_DQ<15>")
	)
	(segment
		(start 232.697782 -97.242122)
		(end 231.450388 -97.242122)
		(width 0.1651)
		(layer "F.Cu")
		(net "M_D_DQ<15>")
	)
	(segment
		(start 213.346538 -118.607078)
		(end 213.171278 -118.782338)
		(width 0.1651)
		(layer "F.Cu")
		(net "M_D_DQ<15>")
	)
	(segment
		(start 213.854538 -118.782338)
		(end 213.679278 -118.607078)
		(width 0.1651)
		(layer "F.Cu")
		(net "M_D_DQ<15>")
	)
	(segment
		(start 213.171278 -118.782338)
		(end 213.171278 -128.788922)
		(width 0.1651)
		(layer "F.Cu")
		(net "M_D_DQ<15>")
	)
	(segment
		(start 231.450388 -97.242122)
		(end 214.537798 -114.154712)
		(width 0.1651)
		(layer "F.Cu")
		(net "M_D_DQ<15>")
	)
	(segment
		(start 212.9282 -129.952496)
		(end 212.54974 -130.330956)
		(width 0.1651)
		(layer "F.Cu")
		(net "M_D_DQ<15>")
	)
	(segment
		(start 213.171278 -128.788922)
		(end 212.9282 -129.032)
		(width 0.1651)
		(layer "F.Cu")
		(net "M_D_DQ<15>")
	)
	(segment
		(start 212.9282 -129.032)
		(end 212.9282 -129.952496)
		(width 0.1651)
		(layer "F.Cu")
		(net "M_D_DQ<15>")
	)
	(segment
		(start 213.679278 -118.607078)
		(end 213.346538 -118.607078)
		(width 0.1651)
		(layer "F.Cu")
		(net "M_D_DQ<15>")
	)
	(segment
		(start 214.537798 -114.154712)
		(end 214.537798 -122.88774)
		(width 0.1651)
		(layer "F.Cu")
		(net "M_D_DQ<15>")
	)
	(segment
		(start 233.159554 -97.242122)
		(end 232.697782 -97.242122)
		(width 0.0889)
		(layer "F.Cu")
		(net "M_D_DQ<15>")
	)
	(segment
		(start 211.700364 -133.0706)
		(end 211.699856 -133.076442)
		(width 0.1651)
		(layer "F.Cu")
		(net "M_D_DQ<15>")
	)
	(segment
		(start 211.699856 -133.076442)
		(end 211.699856 -134.340346)
		(width 0.1651)
		(layer "F.Cu")
		(net "M_D_DQ<15>")
	)
	(segment
		(start 214.055198 -123.0376)
		(end 213.854538 -122.83694)
		(width 0.1651)
		(layer "F.Cu")
		(net "M_D_DQ<15>")
	)
	(segment
		(start 214.537798 -122.88774)
		(end 214.387938 -123.0376)
		(width 0.1651)
		(layer "F.Cu")
		(net "M_D_DQ<15>")
	)
	(segment
		(start 214.387938 -123.0376)
		(end 214.055198 -123.0376)
		(width 0.1651)
		(layer "F.Cu")
		(net "M_D_DQ<15>")
	)
	(segment
		(start 233.608118 -97.690686)
		(end 233.159554 -97.242122)
		(width 0.0889)
		(layer "F.Cu")
		(net "M_D_DQ<15>")
	)
	(via
		(at 212.54974 -130.330956)
		(size 0.508)
		(drill 0.254)
		(layers "F.Cu" "B.Cu")
		(net "M_D_DQ<15>")
	)
	(via
		(at 211.699856 -134.340346)
		(size 0.508)
		(drill 0.254)
		(layers "F.Cu" "B.Cu")
		(net "M_D_DQ<15>")
	)
	(segment
		(start 212.550502 -130.330194)
		(end 212.54974 -130.330956)
		(width 0.1651)
		(layer "B.Cu")
		(net "M_D_DQ<15>")
	)
	(segment
		(start 212.550502 -128.276096)
		(end 212.550502 -130.330194)
		(width 0.1651)
		(layer "B.Cu")
		(net "M_D_DQ<15>")
	)
	(segment
		(start 212.099144 -131.188968)
		(end 212.099144 -130.7592)
		(width 0.14224)
		(layer "In2.Cu")
		(net "M_D_DQ<15>")
	)
	(segment
		(start 212.118194 -132.715)
		(end 211.861146 -132.457952)
		(width 0.14224)
		(layer "In2.Cu")
		(net "M_D_DQ<15>")
	)
	(segment
		(start 211.861146 -133.550152)
		(end 211.861146 -133.276848)
		(width 0.14224)
		(layer "In2.Cu")
		(net "M_D_DQ<15>")
	)
	(segment
		(start 212.143594 -131.233418)
		(end 212.099144 -131.188968)
		(width 0.14224)
		(layer "In2.Cu")
		(net "M_D_DQ<15>")
	)
	(segment
		(start 211.699856 -134.340346)
		(end 211.972144 -134.340346)
		(width 0.14224)
		(layer "In2.Cu")
		(net "M_D_DQ<15>")
	)
	(segment
		(start 212.149944 -133.83895)
		(end 211.861146 -133.550152)
		(width 0.14224)
		(layer "In2.Cu")
		(net "M_D_DQ<15>")
	)
	(segment
		(start 211.861146 -132.184648)
		(end 212.143594 -131.9022)
		(width 0.14224)
		(layer "In2.Cu")
		(net "M_D_DQ<15>")
	)
	(segment
		(start 212.527388 -130.330956)
		(end 212.54974 -130.330956)
		(width 0.14224)
		(layer "In2.Cu")
		(net "M_D_DQ<15>")
	)
	(segment
		(start 211.861146 -133.276848)
		(end 212.118194 -133.0198)
		(width 0.14224)
		(layer "In2.Cu")
		(net "M_D_DQ<15>")
	)
	(segment
		(start 211.861146 -132.457952)
		(end 211.861146 -132.184648)
		(width 0.14224)
		(layer "In2.Cu")
		(net "M_D_DQ<15>")
	)
	(segment
		(start 212.143594 -131.9022)
		(end 212.143594 -131.233418)
		(width 0.14224)
		(layer "In2.Cu")
		(net "M_D_DQ<15>")
	)
	(segment
		(start 212.099144 -130.7592)
		(end 212.527388 -130.330956)
		(width 0.14224)
		(layer "In2.Cu")
		(net "M_D_DQ<15>")
	)
	(segment
		(start 211.972144 -134.340346)
		(end 212.149944 -134.162546)
		(width 0.14224)
		(layer "In2.Cu")
		(net "M_D_DQ<15>")
	)
	(segment
		(start 212.118194 -133.0198)
		(end 212.118194 -132.715)
		(width 0.14224)
		(layer "In2.Cu")
		(net "M_D_DQ<15>")
	)
	(segment
		(start 212.149944 -134.162546)
		(end 212.149944 -133.83895)
		(width 0.14224)
		(layer "In2.Cu")
		(net "M_D_DQ<15>")
	)
	(segment
		(start 212.4964 -128.524)
		(end 212.2424 -128.778)
		(width 0.1651)
		(layer "F.Cu")
		(net "M_D_DQ<14>")
	)
	(segment
		(start 212.682074 -136.57072)
		(end 212.549994 -136.7028)
		(width 0.1651)
		(layer "F.Cu")
		(net "M_D_DQ<14>")
	)
	(segment
		(start 213.86292 -113.862612)
		(end 213.86292 -117.75694)
		(width 0.1651)
		(layer "F.Cu")
		(net "M_D_DQ<14>")
	)
	(segment
		(start 213.86292 -117.75694)
		(end 213.68766 -117.9322)
		(width 0.1651)
		(layer "F.Cu")
		(net "M_D_DQ<14>")
	)
	(segment
		(start 234.466638 -96.20504)
		(end 232.733342 -96.20504)
		(width 0.0889)
		(layer "F.Cu")
		(net "M_D_DQ<14>")
	)
	(segment
		(start 231.520492 -96.20504)
		(end 213.86292 -113.862612)
		(width 0.1651)
		(layer "F.Cu")
		(net "M_D_DQ<14>")
	)
	(segment
		(start 213.17966 -115.31346)
		(end 213.0044 -115.1382)
		(width 0.1651)
		(layer "F.Cu")
		(net "M_D_DQ<14>")
	)
	(segment
		(start 211.699856 -130.285744)
		(end 211.699856 -131.611878)
		(width 0.1651)
		(layer "F.Cu")
		(net "M_D_DQ<14>")
	)
	(segment
		(start 212.2424 -128.778)
		(end 212.2424 -129.7432)
		(width 0.1651)
		(layer "F.Cu")
		(net "M_D_DQ<14>")
	)
	(segment
		(start 212.54974 -135.9154)
		(end 212.549994 -135.915654)
		(width 0.1651)
		(layer "F.Cu")
		(net "M_D_DQ<14>")
	)
	(segment
		(start 213.0044 -115.1382)
		(end 212.67166 -115.1382)
		(width 0.1651)
		(layer "F.Cu")
		(net "M_D_DQ<14>")
	)
	(segment
		(start 212.4964 -115.31346)
		(end 212.4964 -128.524)
		(width 0.1651)
		(layer "F.Cu")
		(net "M_D_DQ<14>")
	)
	(segment
		(start 213.17966 -117.75694)
		(end 213.17966 -115.31346)
		(width 0.1651)
		(layer "F.Cu")
		(net "M_D_DQ<14>")
	)
	(segment
		(start 212.549994 -136.2202)
		(end 212.682074 -136.35228)
		(width 0.1651)
		(layer "F.Cu")
		(net "M_D_DQ<14>")
	)
	(segment
		(start 212.549994 -136.7028)
		(end 212.549994 -137.67054)
		(width 0.1651)
		(layer "F.Cu")
		(net "M_D_DQ<14>")
	)
	(segment
		(start 232.733342 -96.20504)
		(end 231.520492 -96.20504)
		(width 0.1651)
		(layer "F.Cu")
		(net "M_D_DQ<14>")
	)
	(segment
		(start 212.549994 -137.67054)
		(end 212.550502 -137.67054)
		(width 0.1651)
		(layer "F.Cu")
		(net "M_D_DQ<14>")
	)
	(segment
		(start 213.35492 -117.9322)
		(end 213.17966 -117.75694)
		(width 0.1651)
		(layer "F.Cu")
		(net "M_D_DQ<14>")
	)
	(segment
		(start 212.67166 -115.1382)
		(end 212.4964 -115.31346)
		(width 0.1651)
		(layer "F.Cu")
		(net "M_D_DQ<14>")
	)
	(segment
		(start 212.549994 -135.915654)
		(end 212.549994 -136.2202)
		(width 0.1651)
		(layer "F.Cu")
		(net "M_D_DQ<14>")
	)
	(segment
		(start 212.682074 -136.35228)
		(end 212.682074 -136.57072)
		(width 0.1651)
		(layer "F.Cu")
		(net "M_D_DQ<14>")
	)
	(segment
		(start 212.2424 -129.7432)
		(end 211.699856 -130.285744)
		(width 0.1651)
		(layer "F.Cu")
		(net "M_D_DQ<14>")
	)
	(segment
		(start 213.68766 -117.9322)
		(end 213.35492 -117.9322)
		(width 0.1651)
		(layer "F.Cu")
		(net "M_D_DQ<14>")
	)
	(via
		(at 212.54974 -135.9154)
		(size 0.508)
		(drill 0.254)
		(layers "F.Cu" "B.Cu")
		(net "M_D_DQ<14>")
	)
	(via
		(at 211.699856 -131.611878)
		(size 0.508)
		(drill 0.254)
		(layers "F.Cu" "B.Cu")
		(net "M_D_DQ<14>")
	)
	(segment
		(start 211.699856 -132.875782)
		(end 211.699856 -131.611878)
		(width 0.1651)
		(layer "B.Cu")
		(net "M_D_DQ<14>")
	)
	(segment
		(start 211.700364 -132.876036)
		(end 211.699856 -132.875782)
		(width 0.1651)
		(layer "B.Cu")
		(net "M_D_DQ<14>")
	)
	(segment
		(start 211.266786 -132.044948)
		(end 211.699856 -131.611878)
		(width 0.14224)
		(layer "In2.Cu")
		(net "M_D_DQ<14>")
	)
	(segment
		(start 211.266786 -134.632446)
		(end 211.266786 -132.044948)
		(width 0.14224)
		(layer "In2.Cu")
		(net "M_D_DQ<14>")
	)
	(segment
		(start 212.54974 -135.9154)
		(end 211.266786 -134.632446)
		(width 0.14224)
		(layer "In2.Cu")
		(net "M_D_DQ<14>")
	)
	(segment
		(start 206.888842 -127.451104)
		(end 206.888842 -129.965704)
		(width 0.1651)
		(layer "F.Cu")
		(net "M_D_DQ<13>")
	)
	(segment
		(start 207.5942 -126.745746)
		(end 206.888842 -127.451104)
		(width 0.1651)
		(layer "F.Cu")
		(net "M_D_DQ<13>")
	)
	(segment
		(start 206.888842 -129.965704)
		(end 206.52359 -130.330956)
		(width 0.1651)
		(layer "F.Cu")
		(net "M_D_DQ<13>")
	)
	(segment
		(start 205.750414 -133.0706)
		(end 205.749906 -133.076442)
		(width 0.1651)
		(layer "F.Cu")
		(net "M_D_DQ<13>")
	)
	(segment
		(start 232.442512 -91.567)
		(end 230.501698 -91.567)
		(width 0.1651)
		(layer "F.Cu")
		(net "M_D_DQ<13>")
	)
	(segment
		(start 230.501698 -91.567)
		(end 207.5942 -114.474498)
		(width 0.1651)
		(layer "F.Cu")
		(net "M_D_DQ<13>")
	)
	(segment
		(start 207.5942 -114.474498)
		(end 207.5942 -126.745746)
		(width 0.1651)
		(layer "F.Cu")
		(net "M_D_DQ<13>")
	)
	(segment
		(start 232.69067 -91.318842)
		(end 232.442512 -91.567)
		(width 0.0889)
		(layer "F.Cu")
		(net "M_D_DQ<13>")
	)
	(segment
		(start 234.399836 -91.318842)
		(end 232.69067 -91.318842)
		(width 0.0889)
		(layer "F.Cu")
		(net "M_D_DQ<13>")
	)
	(segment
		(start 205.749906 -133.076442)
		(end 205.749906 -134.340346)
		(width 0.1651)
		(layer "F.Cu")
		(net "M_D_DQ<13>")
	)
	(segment
		(start 234.466638 -91.25204)
		(end 234.399836 -91.318842)
		(width 0.0889)
		(layer "F.Cu")
		(net "M_D_DQ<13>")
	)
	(via
		(at 205.749906 -134.340346)
		(size 0.508)
		(drill 0.254)
		(layers "F.Cu" "B.Cu")
		(net "M_D_DQ<13>")
	)
	(via
		(at 206.52359 -130.330956)
		(size 0.508)
		(drill 0.254)
		(layers "F.Cu" "B.Cu")
		(net "M_D_DQ<13>")
	)
	(segment
		(start 206.52359 -130.330956)
		(end 206.59979 -130.254756)
		(width 0.1651)
		(layer "B.Cu")
		(net "M_D_DQ<13>")
	)
	(segment
		(start 206.59979 -128.276096)
		(end 206.600298 -128.276096)
		(width 0.1651)
		(layer "B.Cu")
		(net "M_D_DQ<13>")
	)
	(segment
		(start 206.59979 -130.254756)
		(end 206.59979 -128.276096)
		(width 0.1651)
		(layer "B.Cu")
		(net "M_D_DQ<13>")
	)
	(segment
		(start 205.749906 -134.340346)
		(end 206.022194 -134.340346)
		(width 0.14224)
		(layer "In2.Cu")
		(net "M_D_DQ<13>")
	)
	(segment
		(start 206.174594 -134.187946)
		(end 206.174594 -133.959854)
		(width 0.14224)
		(layer "In2.Cu")
		(net "M_D_DQ<13>")
	)
	(segment
		(start 206.174594 -133.959854)
		(end 205.911196 -133.696456)
		(width 0.14224)
		(layer "In2.Cu")
		(net "M_D_DQ<13>")
	)
	(segment
		(start 205.911196 -132.553456)
		(end 205.911196 -132.216144)
		(width 0.14224)
		(layer "In2.Cu")
		(net "M_D_DQ<13>")
	)
	(segment
		(start 206.501238 -130.330956)
		(end 206.52359 -130.330956)
		(width 0.14224)
		(layer "In2.Cu")
		(net "M_D_DQ<13>")
	)
	(segment
		(start 206.199994 -131.445)
		(end 206.072994 -131.318)
		(width 0.14224)
		(layer "In2.Cu")
		(net "M_D_DQ<13>")
	)
	(segment
		(start 206.149194 -132.791454)
		(end 205.911196 -132.553456)
		(width 0.14224)
		(layer "In2.Cu")
		(net "M_D_DQ<13>")
	)
	(segment
		(start 206.022194 -134.340346)
		(end 206.174594 -134.187946)
		(width 0.14224)
		(layer "In2.Cu")
		(net "M_D_DQ<13>")
	)
	(segment
		(start 206.072994 -131.318)
		(end 206.072994 -130.7592)
		(width 0.14224)
		(layer "In2.Cu")
		(net "M_D_DQ<13>")
	)
	(segment
		(start 206.149194 -133.146546)
		(end 206.149194 -132.791454)
		(width 0.14224)
		(layer "In2.Cu")
		(net "M_D_DQ<13>")
	)
	(segment
		(start 205.911196 -133.696456)
		(end 205.911196 -133.384544)
		(width 0.14224)
		(layer "In2.Cu")
		(net "M_D_DQ<13>")
	)
	(segment
		(start 205.911196 -132.216144)
		(end 206.199994 -131.927346)
		(width 0.14224)
		(layer "In2.Cu")
		(net "M_D_DQ<13>")
	)
	(segment
		(start 206.072994 -130.7592)
		(end 206.501238 -130.330956)
		(width 0.14224)
		(layer "In2.Cu")
		(net "M_D_DQ<13>")
	)
	(segment
		(start 205.911196 -133.384544)
		(end 206.149194 -133.146546)
		(width 0.14224)
		(layer "In2.Cu")
		(net "M_D_DQ<13>")
	)
	(segment
		(start 206.199994 -131.927346)
		(end 206.199994 -131.445)
		(width 0.14224)
		(layer "In2.Cu")
		(net "M_D_DQ<13>")
	)
	(segment
		(start 206.9084 -126.4412)
		(end 206.215996 -127.133604)
		(width 0.1651)
		(layer "F.Cu")
		(net "M_D_DQ<12>")
	)
	(segment
		(start 233.608118 -90.756486)
		(end 232.436162 -90.756486)
		(width 0.0889)
		(layer "F.Cu")
		(net "M_D_DQ<12>")
	)
	(segment
		(start 206.215996 -127.133604)
		(end 206.215996 -129.908808)
		(width 0.1651)
		(layer "F.Cu")
		(net "M_D_DQ<12>")
	)
	(segment
		(start 206.215996 -129.908808)
		(end 205.749906 -130.374898)
		(width 0.1651)
		(layer "F.Cu")
		(net "M_D_DQ<12>")
	)
	(segment
		(start 205.749906 -130.374898)
		(end 205.749906 -131.611878)
		(width 0.1651)
		(layer "F.Cu")
		(net "M_D_DQ<12>")
	)
	(segment
		(start 206.59979 -136.345168)
		(end 206.59979 -137.67054)
		(width 0.1651)
		(layer "F.Cu")
		(net "M_D_DQ<12>")
	)
	(segment
		(start 206.501746 -135.8138)
		(end 206.59979 -136.345168)
		(width 0.1651)
		(layer "F.Cu")
		(net "M_D_DQ<12>")
	)
	(segment
		(start 206.59979 -137.67054)
		(end 206.600298 -137.67054)
		(width 0.1651)
		(layer "F.Cu")
		(net "M_D_DQ<12>")
	)
	(segment
		(start 230.35768 -90.756486)
		(end 206.9084 -114.205766)
		(width 0.1651)
		(layer "F.Cu")
		(net "M_D_DQ<12>")
	)
	(segment
		(start 206.9084 -114.205766)
		(end 206.9084 -126.4412)
		(width 0.1651)
		(layer "F.Cu")
		(net "M_D_DQ<12>")
	)
	(segment
		(start 232.436162 -90.756486)
		(end 230.35768 -90.756486)
		(width 0.1651)
		(layer "F.Cu")
		(net "M_D_DQ<12>")
	)
	(via
		(at 206.501746 -135.8138)
		(size 0.508)
		(drill 0.254)
		(layers "F.Cu" "B.Cu")
		(net "M_D_DQ<12>")
	)
	(via
		(at 205.749906 -131.611878)
		(size 0.508)
		(drill 0.254)
		(layers "F.Cu" "B.Cu")
		(net "M_D_DQ<12>")
	)
	(segment
		(start 205.750414 -132.876036)
		(end 205.749906 -132.875782)
		(width 0.1651)
		(layer "B.Cu")
		(net "M_D_DQ<12>")
	)
	(segment
		(start 205.749906 -132.875782)
		(end 205.749906 -131.611878)
		(width 0.1651)
		(layer "B.Cu")
		(net "M_D_DQ<12>")
	)
	(segment
		(start 205.474824 -134.736078)
		(end 205.316836 -134.57809)
		(width 0.14224)
		(layer "In2.Cu")
		(net "M_D_DQ<12>")
	)
	(segment
		(start 205.474824 -135.03783)
		(end 205.474824 -134.736078)
		(width 0.14224)
		(layer "In2.Cu")
		(net "M_D_DQ<12>")
	)
	(segment
		(start 206.501746 -135.8138)
		(end 206.250794 -135.8138)
		(width 0.14224)
		(layer "In2.Cu")
		(net "M_D_DQ<12>")
	)
	(segment
		(start 206.250794 -135.8138)
		(end 205.474824 -135.03783)
		(width 0.14224)
		(layer "In2.Cu")
		(net "M_D_DQ<12>")
	)
	(segment
		(start 205.316836 -132.044948)
		(end 205.749906 -131.611878)
		(width 0.14224)
		(layer "In2.Cu")
		(net "M_D_DQ<12>")
	)
	(segment
		(start 205.316836 -134.57809)
		(end 205.316836 -132.044948)
		(width 0.14224)
		(layer "In2.Cu")
		(net "M_D_DQ<12>")
	)
	(segment
		(start 214.53348 -128.08712)
		(end 214.53348 -130.047238)
		(width 0.1651)
		(layer "F.Cu")
		(net "M_D_DQ<11>")
	)
	(segment
		(start 232.8291 -98.28149)
		(end 232.573068 -98.537522)
		(width 0.0889)
		(layer "F.Cu")
		(net "M_D_DQ<11>")
	)
	(segment
		(start 217.2462 -127.362712)
		(end 217.0049 -127.604012)
		(width 0.1651)
		(layer "F.Cu")
		(net "M_D_DQ<11>")
	)
	(segment
		(start 213.399878 -133.076442)
		(end 213.399878 -134.340346)
		(width 0.1651)
		(layer "F.Cu")
		(net "M_D_DQ<11>")
	)
	(segment
		(start 213.400386 -133.0706)
		(end 213.399878 -133.076442)
		(width 0.1651)
		(layer "F.Cu")
		(net "M_D_DQ<11>")
	)
	(segment
		(start 215.9 -123.921012)
		(end 216.0651 -124.086112)
		(width 0.1651)
		(layer "F.Cu")
		(net "M_D_DQ<11>")
	)
	(segment
		(start 217.0811 -120.5484)
		(end 217.2462 -120.7135)
		(width 0.1651)
		(layer "F.Cu")
		(net "M_D_DQ<11>")
	)
	(segment
		(start 215.9 -114.7318)
		(end 215.9 -123.921012)
		(width 0.1651)
		(layer "F.Cu")
		(net "M_D_DQ<11>")
	)
	(segment
		(start 233.82478 -98.28149)
		(end 232.8291 -98.28149)
		(width 0.0889)
		(layer "F.Cu")
		(net "M_D_DQ<11>")
	)
	(segment
		(start 216.408 -124.086112)
		(end 216.5731 -123.921012)
		(width 0.1651)
		(layer "F.Cu")
		(net "M_D_DQ<11>")
	)
	(segment
		(start 216.5731 -120.7135)
		(end 216.7382 -120.5484)
		(width 0.1651)
		(layer "F.Cu")
		(net "M_D_DQ<11>")
	)
	(segment
		(start 216.5731 -123.921012)
		(end 216.5731 -120.7135)
		(width 0.1651)
		(layer "F.Cu")
		(net "M_D_DQ<11>")
	)
	(segment
		(start 216.7382 -120.5484)
		(end 217.0811 -120.5484)
		(width 0.1651)
		(layer "F.Cu")
		(net "M_D_DQ<11>")
	)
	(segment
		(start 235.325158 -98.681286)
		(end 234.224576 -98.681286)
		(width 0.0889)
		(layer "F.Cu")
		(net "M_D_DQ<11>")
	)
	(segment
		(start 216.0651 -124.086112)
		(end 216.408 -124.086112)
		(width 0.1651)
		(layer "F.Cu")
		(net "M_D_DQ<11>")
	)
	(segment
		(start 217.0049 -127.604012)
		(end 215.016588 -127.604012)
		(width 0.1651)
		(layer "F.Cu")
		(net "M_D_DQ<11>")
	)
	(segment
		(start 234.224576 -98.681286)
		(end 233.82478 -98.28149)
		(width 0.0889)
		(layer "F.Cu")
		(net "M_D_DQ<11>")
	)
	(segment
		(start 215.016588 -127.604012)
		(end 214.53348 -128.08712)
		(width 0.1651)
		(layer "F.Cu")
		(net "M_D_DQ<11>")
	)
	(segment
		(start 217.2462 -120.7135)
		(end 217.2462 -127.362712)
		(width 0.1651)
		(layer "F.Cu")
		(net "M_D_DQ<11>")
	)
	(segment
		(start 232.094278 -98.537522)
		(end 215.9 -114.7318)
		(width 0.1651)
		(layer "F.Cu")
		(net "M_D_DQ<11>")
	)
	(segment
		(start 214.53348 -130.047238)
		(end 214.249762 -130.330956)
		(width 0.1651)
		(layer "F.Cu")
		(net "M_D_DQ<11>")
	)
	(segment
		(start 232.573068 -98.537522)
		(end 232.094278 -98.537522)
		(width 0.1651)
		(layer "F.Cu")
		(net "M_D_DQ<11>")
	)
	(via
		(at 213.399878 -134.340346)
		(size 0.508)
		(drill 0.254)
		(layers "F.Cu" "B.Cu")
		(net "M_D_DQ<11>")
	)
	(via
		(at 214.249762 -130.330956)
		(size 0.508)
		(drill 0.254)
		(layers "F.Cu" "B.Cu")
		(net "M_D_DQ<11>")
	)
	(segment
		(start 214.249762 -130.330956)
		(end 214.249762 -128.276096)
		(width 0.1651)
		(layer "B.Cu")
		(net "M_D_DQ<11>")
	)
	(segment
		(start 214.249762 -128.276096)
		(end 214.250524 -128.276096)
		(width 0.1651)
		(layer "B.Cu")
		(net "M_D_DQ<11>")
	)
	(segment
		(start 214.249762 -130.330956)
		(end 214.22741 -130.330956)
		(width 0.14224)
		(layer "In2.Cu")
		(net "M_D_DQ<11>")
	)
	(segment
		(start 213.561168 -133.550152)
		(end 213.849966 -133.83895)
		(width 0.14224)
		(layer "In2.Cu")
		(net "M_D_DQ<11>")
	)
	(segment
		(start 213.849966 -134.162546)
		(end 213.672166 -134.340346)
		(width 0.14224)
		(layer "In2.Cu")
		(net "M_D_DQ<11>")
	)
	(segment
		(start 213.672166 -134.340346)
		(end 213.399878 -134.340346)
		(width 0.14224)
		(layer "In2.Cu")
		(net "M_D_DQ<11>")
	)
	(segment
		(start 213.561168 -132.457952)
		(end 213.818216 -132.715)
		(width 0.14224)
		(layer "In2.Cu")
		(net "M_D_DQ<11>")
	)
	(segment
		(start 214.22741 -130.330956)
		(end 213.799166 -130.7592)
		(width 0.14224)
		(layer "In2.Cu")
		(net "M_D_DQ<11>")
	)
	(segment
		(start 213.561168 -133.276848)
		(end 213.561168 -133.550152)
		(width 0.14224)
		(layer "In2.Cu")
		(net "M_D_DQ<11>")
	)
	(segment
		(start 213.818216 -132.715)
		(end 213.818216 -133.0198)
		(width 0.14224)
		(layer "In2.Cu")
		(net "M_D_DQ<11>")
	)
	(segment
		(start 213.849966 -133.83895)
		(end 213.849966 -134.162546)
		(width 0.14224)
		(layer "In2.Cu")
		(net "M_D_DQ<11>")
	)
	(segment
		(start 213.561168 -132.184648)
		(end 213.561168 -132.457952)
		(width 0.14224)
		(layer "In2.Cu")
		(net "M_D_DQ<11>")
	)
	(segment
		(start 213.843616 -131.9022)
		(end 213.561168 -132.184648)
		(width 0.14224)
		(layer "In2.Cu")
		(net "M_D_DQ<11>")
	)
	(segment
		(start 213.799166 -131.188968)
		(end 213.843616 -131.233418)
		(width 0.14224)
		(layer "In2.Cu")
		(net "M_D_DQ<11>")
	)
	(segment
		(start 213.799166 -130.7592)
		(end 213.799166 -131.188968)
		(width 0.14224)
		(layer "In2.Cu")
		(net "M_D_DQ<11>")
	)
	(segment
		(start 213.818216 -133.0198)
		(end 213.561168 -133.276848)
		(width 0.14224)
		(layer "In2.Cu")
		(net "M_D_DQ<11>")
	)
	(segment
		(start 213.843616 -131.233418)
		(end 213.843616 -131.9022)
		(width 0.14224)
		(layer "In2.Cu")
		(net "M_D_DQ<11>")
	)
	(segment
		(start 214.250524 -137.67054)
		(end 214.249762 -137.67054)
		(width 0.1651)
		(layer "F.Cu")
		(net "M_D_DQ<10>")
	)
	(segment
		(start 213.855808 -129.888996)
		(end 213.399878 -130.344926)
		(width 0.1651)
		(layer "F.Cu")
		(net "M_D_DQ<10>")
	)
	(segment
		(start 214.249762 -137.67054)
		(end 214.249762 -136.679432)
		(width 0.1651)
		(layer "F.Cu")
		(net "M_D_DQ<10>")
	)
	(segment
		(start 214.539068 -126.67234)
		(end 214.539068 -123.87326)
		(width 0.1651)
		(layer "F.Cu")
		(net "M_D_DQ<10>")
	)
	(segment
		(start 214.381334 -136.32434)
		(end 214.249762 -136.192768)
		(width 0.1651)
		(layer "F.Cu")
		(net "M_D_DQ<10>")
	)
	(segment
		(start 213.855808 -123.87326)
		(end 213.855808 -129.888996)
		(width 0.1651)
		(layer "F.Cu")
		(net "M_D_DQ<10>")
	)
	(segment
		(start 214.539068 -123.87326)
		(end 214.363808 -123.698)
		(width 0.1651)
		(layer "F.Cu")
		(net "M_D_DQ<10>")
	)
	(segment
		(start 214.031068 -123.698)
		(end 213.855808 -123.87326)
		(width 0.1651)
		(layer "F.Cu")
		(net "M_D_DQ<10>")
	)
	(segment
		(start 233.850688 -98.065336)
		(end 232.862882 -98.065336)
		(width 0.0889)
		(layer "F.Cu")
		(net "M_D_DQ<10>")
	)
	(segment
		(start 215.222328 -114.43716)
		(end 215.222328 -126.67234)
		(width 0.1651)
		(layer "F.Cu")
		(net "M_D_DQ<10>")
	)
	(segment
		(start 215.222328 -126.67234)
		(end 215.047068 -126.8476)
		(width 0.1651)
		(layer "F.Cu")
		(net "M_D_DQ<10>")
	)
	(segment
		(start 232.687368 -97.889822)
		(end 231.769666 -97.889822)
		(width 0.1651)
		(layer "F.Cu")
		(net "M_D_DQ<10>")
	)
	(segment
		(start 214.714328 -126.8476)
		(end 214.539068 -126.67234)
		(width 0.1651)
		(layer "F.Cu")
		(net "M_D_DQ<10>")
	)
	(segment
		(start 215.047068 -126.8476)
		(end 214.714328 -126.8476)
		(width 0.1651)
		(layer "F.Cu")
		(net "M_D_DQ<10>")
	)
	(segment
		(start 214.249762 -136.679432)
		(end 214.381334 -136.54786)
		(width 0.1651)
		(layer "F.Cu")
		(net "M_D_DQ<10>")
	)
	(segment
		(start 213.399878 -130.344926)
		(end 213.399878 -131.611878)
		(width 0.1651)
		(layer "F.Cu")
		(net "M_D_DQ<10>")
	)
	(segment
		(start 214.249762 -136.192768)
		(end 214.249762 -135.9154)
		(width 0.1651)
		(layer "F.Cu")
		(net "M_D_DQ<10>")
	)
	(segment
		(start 214.381334 -136.54786)
		(end 214.381334 -136.32434)
		(width 0.1651)
		(layer "F.Cu")
		(net "M_D_DQ<10>")
	)
	(segment
		(start 235.325158 -97.690686)
		(end 234.225338 -97.690686)
		(width 0.0889)
		(layer "F.Cu")
		(net "M_D_DQ<10>")
	)
	(segment
		(start 234.225338 -97.690686)
		(end 233.850688 -98.065336)
		(width 0.0889)
		(layer "F.Cu")
		(net "M_D_DQ<10>")
	)
	(segment
		(start 232.862882 -98.065336)
		(end 232.687368 -97.889822)
		(width 0.0889)
		(layer "F.Cu")
		(net "M_D_DQ<10>")
	)
	(segment
		(start 231.769666 -97.889822)
		(end 215.222328 -114.43716)
		(width 0.1651)
		(layer "F.Cu")
		(net "M_D_DQ<10>")
	)
	(segment
		(start 214.363808 -123.698)
		(end 214.031068 -123.698)
		(width 0.1651)
		(layer "F.Cu")
		(net "M_D_DQ<10>")
	)
	(via
		(at 214.249762 -135.9154)
		(size 0.508)
		(drill 0.254)
		(layers "F.Cu" "B.Cu")
		(net "M_D_DQ<10>")
	)
	(via
		(at 213.399878 -131.611878)
		(size 0.508)
		(drill 0.254)
		(layers "F.Cu" "B.Cu")
		(net "M_D_DQ<10>")
	)
	(segment
		(start 213.400386 -132.876036)
		(end 213.399878 -132.875782)
		(width 0.1651)
		(layer "B.Cu")
		(net "M_D_DQ<10>")
	)
	(segment
		(start 213.399878 -132.875782)
		(end 213.399878 -131.611878)
		(width 0.1651)
		(layer "B.Cu")
		(net "M_D_DQ<10>")
	)
	(segment
		(start 212.966808 -132.044948)
		(end 213.399878 -131.611878)
		(width 0.14224)
		(layer "In2.Cu")
		(net "M_D_DQ<10>")
	)
	(segment
		(start 212.966808 -134.632446)
		(end 212.966808 -132.044948)
		(width 0.14224)
		(layer "In2.Cu")
		(net "M_D_DQ<10>")
	)
	(segment
		(start 214.249762 -135.9154)
		(end 212.966808 -134.632446)
		(width 0.14224)
		(layer "In2.Cu")
		(net "M_D_DQ<10>")
	)
	(segment
		(start 234.466638 -85.30844)
		(end 233.895138 -85.30844)
		(width 0.1651)
		(layer "F.Cu")
		(net "M_D_DQ<0>")
	)
	(segment
		(start 198.949818 -137.676382)
		(end 198.772018 -135.8138)
		(width 0.1651)
		(layer "F.Cu")
		(net "M_D_DQ<0>")
	)
	(segment
		(start 198.950326 -137.67054)
		(end 198.949818 -137.676382)
		(width 0.1651)
		(layer "F.Cu")
		(net "M_D_DQ<0>")
	)
	(via
		(at 233.895138 -85.30844)
		(size 0.508)
		(drill 0.254)
		(layers "F.Cu" "B.Cu")
		(net "M_D_DQ<0>")
	)
	(via
		(at 198.099934 -131.611878)
		(size 0.508)
		(drill 0.254)
		(layers "F.Cu" "B.Cu")
		(net "M_D_DQ<0>")
	)
	(via
		(at 198.772018 -135.8138)
		(size 0.508)
		(drill 0.254)
		(layers "F.Cu" "B.Cu")
		(net "M_D_DQ<0>")
	)
	(segment
		(start 198.100442 -132.876036)
		(end 198.099934 -132.875782)
		(width 0.1651)
		(layer "B.Cu")
		(net "M_D_DQ<0>")
	)
	(segment
		(start 198.099934 -132.875782)
		(end 198.099934 -131.611878)
		(width 0.1651)
		(layer "B.Cu")
		(net "M_D_DQ<0>")
	)
	(segment
		(start 199.173846 -116.065554)
		(end 199.173846 -121.348754)
		(width 0.14224)
		(layer "In2.Cu")
		(net "M_D_DQ<0>")
	)
	(segment
		(start 232.868724 -85.30844)
		(end 232.374186 -84.813902)
		(width 0.0889)
		(layer "In2.Cu")
		(net "M_D_DQ<0>")
	)
	(segment
		(start 203.6064 -112.5728)
		(end 202.6666 -112.5728)
		(width 0.14224)
		(layer "In2.Cu")
		(net "M_D_DQ<0>")
	)
	(segment
		(start 198.6026 -121.92)
		(end 198.6026 -129.722118)
		(width 0.14224)
		(layer "In2.Cu")
		(net "M_D_DQ<0>")
	)
	(segment
		(start 197.8152 -130.509518)
		(end 197.8152 -131.327144)
		(width 0.14224)
		(layer "In2.Cu")
		(net "M_D_DQ<0>")
	)
	(segment
		(start 229.63886 -85.048344)
		(end 215.773 -98.914204)
		(width 0.14224)
		(layer "In2.Cu")
		(net "M_D_DQ<0>")
	)
	(segment
		(start 232.210102 -84.813902)
		(end 231.79659 -84.81441)
		(width 0.0889)
		(layer "In2.Cu")
		(net "M_D_DQ<0>")
	)
	(segment
		(start 199.173846 -121.348754)
		(end 198.6026 -121.92)
		(width 0.14224)
		(layer "In2.Cu")
		(net "M_D_DQ<0>")
	)
	(segment
		(start 197.8152 -131.327144)
		(end 198.099934 -131.611878)
		(width 0.14224)
		(layer "In2.Cu")
		(net "M_D_DQ<0>")
	)
	(segment
		(start 198.6026 -129.722118)
		(end 197.8152 -130.509518)
		(width 0.14224)
		(layer "In2.Cu")
		(net "M_D_DQ<0>")
	)
	(segment
		(start 197.666864 -132.044948)
		(end 197.666864 -134.708646)
		(width 0.14224)
		(layer "In2.Cu")
		(net "M_D_DQ<0>")
	)
	(segment
		(start 233.895138 -85.30844)
		(end 232.868724 -85.30844)
		(width 0.0889)
		(layer "In2.Cu")
		(net "M_D_DQ<0>")
	)
	(segment
		(start 231.79659 -84.81441)
		(end 231.562656 -85.048344)
		(width 0.0889)
		(layer "In2.Cu")
		(net "M_D_DQ<0>")
	)
	(segment
		(start 232.374186 -84.813902)
		(end 232.210102 -84.813902)
		(width 0.0889)
		(layer "In2.Cu")
		(net "M_D_DQ<0>")
	)
	(segment
		(start 215.773 -100.4062)
		(end 203.6064 -112.5728)
		(width 0.14224)
		(layer "In2.Cu")
		(net "M_D_DQ<0>")
	)
	(segment
		(start 231.562656 -85.048344)
		(end 230.860346 -85.048344)
		(width 0.0889)
		(layer "In2.Cu")
		(net "M_D_DQ<0>")
	)
	(segment
		(start 198.099934 -131.611878)
		(end 197.666864 -132.044948)
		(width 0.14224)
		(layer "In2.Cu")
		(net "M_D_DQ<0>")
	)
	(segment
		(start 202.6666 -112.5728)
		(end 199.173846 -116.065554)
		(width 0.14224)
		(layer "In2.Cu")
		(net "M_D_DQ<0>")
	)
	(segment
		(start 230.860346 -85.048344)
		(end 229.63886 -85.048344)
		(width 0.14224)
		(layer "In2.Cu")
		(net "M_D_DQ<0>")
	)
	(segment
		(start 215.773 -98.914204)
		(end 215.773 -100.4062)
		(width 0.14224)
		(layer "In2.Cu")
		(net "M_D_DQ<0>")
	)
	(segment
		(start 197.666864 -134.708646)
		(end 198.772018 -135.8138)
		(width 0.14224)
		(layer "In2.Cu")
		(net "M_D_DQ<0>")
	)
	(segment
		(start 271.213072 -120.997472)
		(end 271.213072 -121.231152)
		(width 0.1651)
		(layer "F.Cu")
		(net "M_D_CS_N<7>")
	)
	(segment
		(start 269.4559 -103.7209)
		(end 270.15694 -104.42194)
		(width 0.1651)
		(layer "F.Cu")
		(net "M_D_CS_N<7>")
	)
	(segment
		(start 271.922748 -121.707148)
		(end 272.277332 -122.061732)
		(width 0.1651)
		(layer "F.Cu")
		(net "M_D_CS_N<7>")
	)
	(segment
		(start 268.769592 -102.446836)
		(end 268.620494 -102.595934)
		(width 0.1651)
		(layer "F.Cu")
		(net "M_D_CS_N<7>")
	)
	(segment
		(start 273.304508 -123.886722)
		(end 273.541998 -123.886722)
		(width 0.1651)
		(layer "F.Cu")
		(net "M_D_CS_N<7>")
	)
	(segment
		(start 267.948156 -99.67214)
		(end 267.948156 -100.071428)
		(width 0.1651)
		(layer "F.Cu")
		(net "M_D_CS_N<7>")
	)
	(segment
		(start 272.590006 -122.93473)
		(end 272.753328 -122.771408)
		(width 0.1651)
		(layer "F.Cu")
		(net "M_D_CS_N<7>")
	)
	(segment
		(start 268.620494 -102.938834)
		(end 268.801596 -103.119936)
		(width 0.1651)
		(layer "F.Cu")
		(net "M_D_CS_N<7>")
	)
	(segment
		(start 270.15694 -120.155716)
		(end 270.422116 -120.420892)
		(width 0.1651)
		(layer "F.Cu")
		(net "M_D_CS_N<7>")
	)
	(segment
		(start 273.229324 -123.247404)
		(end 273.062192 -123.414536)
		(width 0.1651)
		(layer "F.Cu")
		(net "M_D_CS_N<7>")
	)
	(segment
		(start 271.529048 -121.867168)
		(end 271.689068 -121.707148)
		(width 0.1651)
		(layer "F.Cu")
		(net "M_D_CS_N<7>")
	)
	(segment
		(start 272.277332 -122.295412)
		(end 272.1102 -122.462544)
		(width 0.1651)
		(layer "F.Cu")
		(net "M_D_CS_N<7>")
	)
	(segment
		(start 270.636492 -120.420892)
		(end 271.213072 -120.997472)
		(width 0.1651)
		(layer "F.Cu")
		(net "M_D_CS_N<7>")
	)
	(segment
		(start 268.620494 -102.595934)
		(end 268.620494 -102.938834)
		(width 0.1651)
		(layer "F.Cu")
		(net "M_D_CS_N<7>")
	)
	(segment
		(start 274.514564 -124.81814)
		(end 274.657312 -124.675392)
		(width 0.1651)
		(layer "F.Cu")
		(net "M_D_CS_N<7>")
	)
	(segment
		(start 272.352516 -122.93473)
		(end 272.590006 -122.93473)
		(width 0.1651)
		(layer "F.Cu")
		(net "M_D_CS_N<7>")
	)
	(segment
		(start 270.15694 -104.42194)
		(end 270.15694 -120.155716)
		(width 0.1651)
		(layer "F.Cu")
		(net "M_D_CS_N<7>")
	)
	(segment
		(start 274.010374 -124.370338)
		(end 274.010374 -124.586238)
		(width 0.1651)
		(layer "F.Cu")
		(net "M_D_CS_N<7>")
	)
	(segment
		(start 272.1102 -122.692414)
		(end 272.352516 -122.93473)
		(width 0.1651)
		(layer "F.Cu")
		(net "M_D_CS_N<7>")
	)
	(segment
		(start 274.242276 -124.81814)
		(end 274.514564 -124.81814)
		(width 0.1651)
		(layer "F.Cu")
		(net "M_D_CS_N<7>")
	)
	(segment
		(start 276.237446 -126.021846)
		(end 276.237446 -127.3429)
		(width 0.1651)
		(layer "F.Cu")
		(net "M_D_CS_N<7>")
	)
	(segment
		(start 268.587728 -100.711)
		(end 269.24 -100.711)
		(width 0.1651)
		(layer "F.Cu")
		(net "M_D_CS_N<7>")
	)
	(segment
		(start 274.181316 -124.199396)
		(end 274.010374 -124.370338)
		(width 0.1651)
		(layer "F.Cu")
		(net "M_D_CS_N<7>")
	)
	(segment
		(start 272.753328 -122.771408)
		(end 272.987008 -122.771408)
		(width 0.1651)
		(layer "F.Cu")
		(net "M_D_CS_N<7>")
	)
	(segment
		(start 272.1102 -122.462544)
		(end 272.1102 -122.692414)
		(width 0.1651)
		(layer "F.Cu")
		(net "M_D_CS_N<7>")
	)
	(segment
		(start 274.890992 -124.675392)
		(end 276.237446 -126.021846)
		(width 0.1651)
		(layer "F.Cu")
		(net "M_D_CS_N<7>")
	)
	(segment
		(start 272.277332 -122.061732)
		(end 272.277332 -122.295412)
		(width 0.1651)
		(layer "F.Cu")
		(net "M_D_CS_N<7>")
	)
	(segment
		(start 269.24 -100.711)
		(end 269.4559 -100.9269)
		(width 0.1651)
		(layer "F.Cu")
		(net "M_D_CS_N<7>")
	)
	(segment
		(start 269.2908 -103.119936)
		(end 269.4559 -103.285036)
		(width 0.1651)
		(layer "F.Cu")
		(net "M_D_CS_N<7>")
	)
	(segment
		(start 270.422116 -120.420892)
		(end 270.636492 -120.420892)
		(width 0.1651)
		(layer "F.Cu")
		(net "M_D_CS_N<7>")
	)
	(segment
		(start 271.689068 -121.707148)
		(end 271.922748 -121.707148)
		(width 0.1651)
		(layer "F.Cu")
		(net "M_D_CS_N<7>")
	)
	(segment
		(start 271.213072 -121.231152)
		(end 271.053052 -121.391172)
		(width 0.1651)
		(layer "F.Cu")
		(net "M_D_CS_N<7>")
	)
	(segment
		(start 273.70532 -123.7234)
		(end 273.939 -123.7234)
		(width 0.1651)
		(layer "F.Cu")
		(net "M_D_CS_N<7>")
	)
	(segment
		(start 269.4559 -103.285036)
		(end 269.4559 -103.7209)
		(width 0.1651)
		(layer "F.Cu")
		(net "M_D_CS_N<7>")
	)
	(segment
		(start 267.948156 -100.071428)
		(end 268.587728 -100.711)
		(width 0.1651)
		(layer "F.Cu")
		(net "M_D_CS_N<7>")
	)
	(segment
		(start 273.541998 -123.886722)
		(end 273.70532 -123.7234)
		(width 0.1651)
		(layer "F.Cu")
		(net "M_D_CS_N<7>")
	)
	(segment
		(start 271.053052 -121.624852)
		(end 271.295368 -121.867168)
		(width 0.1651)
		(layer "F.Cu")
		(net "M_D_CS_N<7>")
	)
	(segment
		(start 272.987008 -122.771408)
		(end 273.229324 -123.013724)
		(width 0.1651)
		(layer "F.Cu")
		(net "M_D_CS_N<7>")
	)
	(segment
		(start 273.062192 -123.414536)
		(end 273.062192 -123.644406)
		(width 0.1651)
		(layer "F.Cu")
		(net "M_D_CS_N<7>")
	)
	(segment
		(start 269.2908 -102.446836)
		(end 268.769592 -102.446836)
		(width 0.1651)
		(layer "F.Cu")
		(net "M_D_CS_N<7>")
	)
	(segment
		(start 273.062192 -123.644406)
		(end 273.304508 -123.886722)
		(width 0.1651)
		(layer "F.Cu")
		(net "M_D_CS_N<7>")
	)
	(segment
		(start 273.939 -123.7234)
		(end 274.181316 -123.965716)
		(width 0.1651)
		(layer "F.Cu")
		(net "M_D_CS_N<7>")
	)
	(segment
		(start 274.657312 -124.675392)
		(end 274.890992 -124.675392)
		(width 0.1651)
		(layer "F.Cu")
		(net "M_D_CS_N<7>")
	)
	(segment
		(start 274.010374 -124.586238)
		(end 274.242276 -124.81814)
		(width 0.1651)
		(layer "F.Cu")
		(net "M_D_CS_N<7>")
	)
	(segment
		(start 271.053052 -121.391172)
		(end 271.053052 -121.624852)
		(width 0.1651)
		(layer "F.Cu")
		(net "M_D_CS_N<7>")
	)
	(segment
		(start 276.237446 -127.3429)
		(end 277.999952 -129.105406)
		(width 0.1651)
		(layer "F.Cu")
		(net "M_D_CS_N<7>")
	)
	(segment
		(start 271.295368 -121.867168)
		(end 271.529048 -121.867168)
		(width 0.1651)
		(layer "F.Cu")
		(net "M_D_CS_N<7>")
	)
	(segment
		(start 269.4559 -102.281736)
		(end 269.2908 -102.446836)
		(width 0.1651)
		(layer "F.Cu")
		(net "M_D_CS_N<7>")
	)
	(segment
		(start 274.181316 -123.965716)
		(end 274.181316 -124.199396)
		(width 0.1651)
		(layer "F.Cu")
		(net "M_D_CS_N<7>")
	)
	(segment
		(start 277.999952 -129.105406)
		(end 277.999952 -129.568956)
		(width 0.1651)
		(layer "F.Cu")
		(net "M_D_CS_N<7>")
	)
	(segment
		(start 269.4559 -100.9269)
		(end 269.4559 -102.281736)
		(width 0.1651)
		(layer "F.Cu")
		(net "M_D_CS_N<7>")
	)
	(segment
		(start 268.801596 -103.119936)
		(end 269.2908 -103.119936)
		(width 0.1651)
		(layer "F.Cu")
		(net "M_D_CS_N<7>")
	)
	(segment
		(start 273.229324 -123.013724)
		(end 273.229324 -123.247404)
		(width 0.1651)
		(layer "F.Cu")
		(net "M_D_CS_N<7>")
	)
	(via
		(at 277.999952 -129.568956)
		(size 0.508)
		(drill 0.254)
		(layers "F.Cu" "B.Cu")
		(net "M_D_CS_N<7>")
	)
	(segment
		(start 278.00046 -128.276096)
		(end 277.999952 -128.276096)
		(width 0.1651)
		(layer "B.Cu")
		(net "M_D_CS_N<7>")
	)
	(segment
		(start 277.999952 -128.276096)
		(end 277.999952 -129.568956)
		(width 0.1651)
		(layer "B.Cu")
		(net "M_D_CS_N<7>")
	)
	(segment
		(start 278.257 -130.28168)
		(end 277.999952 -130.902456)
		(width 0.1651)
		(layer "F.Cu")
		(net "M_D_CS_N<6>")
	)
	(segment
		(start 270.0655 -100.615242)
		(end 270.0655 -103.517446)
		(width 0.1651)
		(layer "F.Cu")
		(net "M_D_CS_N<6>")
	)
	(segment
		(start 270.0655 -100.250752)
		(end 270.0655 -100.615242)
		(width 0.0889)
		(layer "F.Cu")
		(net "M_D_CS_N<6>")
	)
	(segment
		(start 270.0655 -103.517446)
		(end 270.66113 -104.113076)
		(width 0.1651)
		(layer "F.Cu")
		(net "M_D_CS_N<6>")
	)
	(segment
		(start 276.749256 -127.256032)
		(end 278.4856 -128.992376)
		(width 0.1651)
		(layer "F.Cu")
		(net "M_D_CS_N<6>")
	)
	(segment
		(start 278.257 -129.9718)
		(end 278.257 -130.28168)
		(width 0.1651)
		(layer "F.Cu")
		(net "M_D_CS_N<6>")
	)
	(segment
		(start 267.948156 -97.690686)
		(end 268.322806 -98.554032)
		(width 0.0889)
		(layer "F.Cu")
		(net "M_D_CS_N<6>")
	)
	(segment
		(start 268.322806 -98.554032)
		(end 268.322806 -99.27717)
		(width 0.0889)
		(layer "F.Cu")
		(net "M_D_CS_N<6>")
	)
	(segment
		(start 268.322806 -99.27717)
		(end 268.715236 -99.6696)
		(width 0.0889)
		(layer "F.Cu")
		(net "M_D_CS_N<6>")
	)
	(segment
		(start 276.749256 -125.810264)
		(end 276.749256 -127.256032)
		(width 0.1651)
		(layer "F.Cu")
		(net "M_D_CS_N<6>")
	)
	(segment
		(start 278.4856 -129.7432)
		(end 278.257 -129.9718)
		(width 0.1651)
		(layer "F.Cu")
		(net "M_D_CS_N<6>")
	)
	(segment
		(start 268.715236 -99.6696)
		(end 269.484348 -99.6696)
		(width 0.0889)
		(layer "F.Cu")
		(net "M_D_CS_N<6>")
	)
	(segment
		(start 270.66113 -104.113076)
		(end 270.66113 -119.722138)
		(width 0.1651)
		(layer "F.Cu")
		(net "M_D_CS_N<6>")
	)
	(segment
		(start 269.484348 -99.6696)
		(end 270.0655 -100.250752)
		(width 0.0889)
		(layer "F.Cu")
		(net "M_D_CS_N<6>")
	)
	(segment
		(start 278.4856 -128.992376)
		(end 278.4856 -129.7432)
		(width 0.1651)
		(layer "F.Cu")
		(net "M_D_CS_N<6>")
	)
	(segment
		(start 270.66113 -119.722138)
		(end 276.749256 -125.810264)
		(width 0.1651)
		(layer "F.Cu")
		(net "M_D_CS_N<6>")
	)
	(via
		(at 277.999952 -130.902456)
		(size 0.508)
		(drill 0.254)
		(layers "F.Cu" "B.Cu")
		(net "M_D_CS_N<6>")
	)
	(segment
		(start 278.00046 -132.876036)
		(end 277.999952 -132.875782)
		(width 0.1651)
		(layer "B.Cu")
		(net "M_D_CS_N<6>")
	)
	(segment
		(start 277.999952 -132.875782)
		(end 277.999952 -130.902456)
		(width 0.1651)
		(layer "B.Cu")
		(net "M_D_CS_N<6>")
	)
	(segment
		(start 274.840446 -130.661918)
		(end 274.840446 -130.137154)
		(width 0.1651)
		(layer "F.Cu")
		(net "M_D_CS_N<5>")
	)
	(segment
		(start 275.248116 -129.389378)
		(end 274.865338 -129.0066)
		(width 0.1651)
		(layer "F.Cu")
		(net "M_D_CS_N<5>")
	)
	(segment
		(start 265.216894 -102.529894)
		(end 265.216894 -101.555042)
		(width 0.0889)
		(layer "F.Cu")
		(net "M_D_CS_N<5>")
	)
	(segment
		(start 274.840446 -130.137154)
		(end 275.248116 -129.729484)
		(width 0.1651)
		(layer "F.Cu")
		(net "M_D_CS_N<5>")
	)
	(segment
		(start 265.03503 -101.373178)
		(end 265.02614 -101.357938)
		(width 0.0889)
		(layer "F.Cu")
		(net "M_D_CS_N<5>")
	)
	(segment
		(start 267.63599 -104.94899)
		(end 265.216894 -102.529894)
		(width 0.0889)
		(layer "F.Cu")
		(net "M_D_CS_N<5>")
	)
	(segment
		(start 273.175984 -127.83566)
		(end 272.664936 -127.324612)
		(width 0.1651)
		(layer "F.Cu")
		(net "M_D_CS_N<5>")
	)
	(segment
		(start 265.02614 -100.367084)
		(end 264.51433 -99.67214)
		(width 0.0889)
		(layer "F.Cu")
		(net "M_D_CS_N<5>")
	)
	(segment
		(start 265.216894 -101.555042)
		(end 265.03503 -101.373178)
		(width 0.0889)
		(layer "F.Cu")
		(net "M_D_CS_N<5>")
	)
	(segment
		(start 272.664936 -127.324612)
		(end 272.664936 -127.02159)
		(width 0.1651)
		(layer "F.Cu")
		(net "M_D_CS_N<5>")
	)
	(segment
		(start 267.63599 -106.030522)
		(end 267.63599 -104.94899)
		(width 0.0889)
		(layer "F.Cu")
		(net "M_D_CS_N<5>")
	)
	(segment
		(start 275.248116 -129.729484)
		(end 275.248116 -129.389378)
		(width 0.1651)
		(layer "F.Cu")
		(net "M_D_CS_N<5>")
	)
	(segment
		(start 272.664936 -127.02159)
		(end 267.63599 -121.992644)
		(width 0.1651)
		(layer "F.Cu")
		(net "M_D_CS_N<5>")
	)
	(segment
		(start 267.63599 -121.992644)
		(end 267.63599 -106.030522)
		(width 0.1651)
		(layer "F.Cu")
		(net "M_D_CS_N<5>")
	)
	(segment
		(start 273.924522 -128.131824)
		(end 273.628358 -127.83566)
		(width 0.1651)
		(layer "F.Cu")
		(net "M_D_CS_N<5>")
	)
	(segment
		(start 265.03249 -100.377752)
		(end 265.02614 -100.367084)
		(width 0.0889)
		(layer "F.Cu")
		(net "M_D_CS_N<5>")
	)
	(segment
		(start 274.381976 -129.0066)
		(end 273.924522 -128.549146)
		(width 0.1651)
		(layer "F.Cu")
		(net "M_D_CS_N<5>")
	)
	(segment
		(start 273.628358 -127.83566)
		(end 273.175984 -127.83566)
		(width 0.1651)
		(layer "F.Cu")
		(net "M_D_CS_N<5>")
	)
	(segment
		(start 274.599908 -130.902456)
		(end 274.840446 -130.661918)
		(width 0.1651)
		(layer "F.Cu")
		(net "M_D_CS_N<5>")
	)
	(segment
		(start 273.924522 -128.549146)
		(end 273.924522 -128.131824)
		(width 0.1651)
		(layer "F.Cu")
		(net "M_D_CS_N<5>")
	)
	(segment
		(start 274.865338 -129.0066)
		(end 274.381976 -129.0066)
		(width 0.1651)
		(layer "F.Cu")
		(net "M_D_CS_N<5>")
	)
	(via
		(at 274.599908 -130.902456)
		(size 0.508)
		(drill 0.254)
		(layers "F.Cu" "B.Cu")
		(net "M_D_CS_N<5>")
	)
	(arc
		(start 265.02614 -101.357938)
		(mid 264.972607 -101.15804)
		(end 265.02614 -100.958142)
		(width 0.0889)
		(layer "F.Cu")
		(net "M_D_CS_N<5>")
	)
	(arc
		(start 265.02614 -100.958142)
		(mid 265.105489 -100.66877)
		(end 265.03249 -100.377752)
		(width 0.0889)
		(layer "F.Cu")
		(net "M_D_CS_N<5>")
	)
	(segment
		(start 274.599908 -132.875782)
		(end 274.599908 -130.902456)
		(width 0.1651)
		(layer "B.Cu")
		(net "M_D_CS_N<5>")
	)
	(segment
		(start 274.600416 -132.876036)
		(end 274.599908 -132.875782)
		(width 0.1651)
		(layer "B.Cu")
		(net "M_D_CS_N<5>")
	)
	(segment
		(start 265.61923 -105.151682)
		(end 265.67765 -105.093262)
		(width 0.1651)
		(layer "F.Cu")
		(net "M_D_CS_N<4>")
	)
	(segment
		(start 271.660112 -129.812288)
		(end 271.660112 -129.343912)
		(width 0.1651)
		(layer "F.Cu")
		(net "M_D_CS_N<4>")
	)
	(segment
		(start 268.390624 -127.428244)
		(end 268.390624 -125.936248)
		(width 0.1651)
		(layer "F.Cu")
		(net "M_D_CS_N<4>")
	)
	(segment
		(start 269.51178 -128.5494)
		(end 268.390624 -127.428244)
		(width 0.1651)
		(layer "F.Cu")
		(net "M_D_CS_N<4>")
	)
	(segment
		(start 271.6784 -130.6322)
		(end 271.5514 -130.5052)
		(width 0.1651)
		(layer "F.Cu")
		(net "M_D_CS_N<4>")
	)
	(segment
		(start 271.6784 -131.1148)
		(end 271.6784 -130.6322)
		(width 0.1651)
		(layer "F.Cu")
		(net "M_D_CS_N<4>")
	)
	(segment
		(start 270.349726 -131.611878)
		(end 271.181322 -131.611878)
		(width 0.1651)
		(layer "F.Cu")
		(net "M_D_CS_N<4>")
	)
	(segment
		(start 263.197594 -100.510594)
		(end 263.017 -100.33)
		(width 0.0889)
		(layer "F.Cu")
		(net "M_D_CS_N<4>")
	)
	(segment
		(start 263.4742 -101.571806)
		(end 263.197594 -101.2952)
		(width 0.0889)
		(layer "F.Cu")
		(net "M_D_CS_N<4>")
	)
	(segment
		(start 265.61923 -123.164854)
		(end 265.61923 -105.151682)
		(width 0.1651)
		(layer "F.Cu")
		(net "M_D_CS_N<4>")
	)
	(segment
		(start 271.181322 -131.611878)
		(end 271.6784 -131.1148)
		(width 0.1651)
		(layer "F.Cu")
		(net "M_D_CS_N<4>")
	)
	(segment
		(start 265.67765 -104.641904)
		(end 263.4742 -102.438454)
		(width 0.0889)
		(layer "F.Cu")
		(net "M_D_CS_N<4>")
	)
	(segment
		(start 270.8656 -128.5494)
		(end 269.51178 -128.5494)
		(width 0.1651)
		(layer "F.Cu")
		(net "M_D_CS_N<4>")
	)
	(segment
		(start 271.5514 -130.5052)
		(end 271.5514 -129.921)
		(width 0.1651)
		(layer "F.Cu")
		(net "M_D_CS_N<4>")
	)
	(segment
		(start 265.67765 -105.093262)
		(end 265.67765 -104.641904)
		(width 0.0889)
		(layer "F.Cu")
		(net "M_D_CS_N<4>")
	)
	(segment
		(start 271.660112 -129.343912)
		(end 270.8656 -128.5494)
		(width 0.1651)
		(layer "F.Cu")
		(net "M_D_CS_N<4>")
	)
	(segment
		(start 271.5514 -129.921)
		(end 271.660112 -129.812288)
		(width 0.1651)
		(layer "F.Cu")
		(net "M_D_CS_N<4>")
	)
	(segment
		(start 268.390624 -125.936248)
		(end 265.61923 -123.164854)
		(width 0.1651)
		(layer "F.Cu")
		(net "M_D_CS_N<4>")
	)
	(segment
		(start 263.4742 -102.438454)
		(end 263.4742 -101.571806)
		(width 0.0889)
		(layer "F.Cu")
		(net "M_D_CS_N<4>")
	)
	(segment
		(start 263.017 -100.33)
		(end 263.017 -99.89185)
		(width 0.0889)
		(layer "F.Cu")
		(net "M_D_CS_N<4>")
	)
	(segment
		(start 263.197594 -101.2952)
		(end 263.197594 -100.510594)
		(width 0.0889)
		(layer "F.Cu")
		(net "M_D_CS_N<4>")
	)
	(segment
		(start 263.017 -99.89185)
		(end 262.79729 -99.67214)
		(width 0.0889)
		(layer "F.Cu")
		(net "M_D_CS_N<4>")
	)
	(via
		(at 270.349726 -131.611878)
		(size 0.508)
		(drill 0.254)
		(layers "F.Cu" "B.Cu")
		(net "M_D_CS_N<4>")
	)
	(segment
		(start 270.350488 -132.876036)
		(end 270.34998 -132.875782)
		(width 0.1651)
		(layer "B.Cu")
		(net "M_D_CS_N<4>")
	)
	(segment
		(start 270.34998 -132.875782)
		(end 270.34998 -131.612132)
		(width 0.1651)
		(layer "B.Cu")
		(net "M_D_CS_N<4>")
	)
	(segment
		(start 270.34998 -131.612132)
		(end 270.349726 -131.611878)
		(width 0.1651)
		(layer "B.Cu")
		(net "M_D_CS_N<4>")
	)
	(segment
		(start 266.742926 -100.367084)
		(end 266.726416 -100.338128)
		(width 0.0889)
		(layer "F.Cu")
		(net "M_D_CS_N<3>")
	)
	(segment
		(start 275.5392 -126.2634)
		(end 275.123402 -125.847602)
		(width 0.1651)
		(layer "F.Cu")
		(net "M_D_CS_N<3>")
	)
	(segment
		(start 269.65275 -104.65435)
		(end 267.1572 -102.1588)
		(width 0.1651)
		(layer "F.Cu")
		(net "M_D_CS_N<3>")
	)
	(segment
		(start 266.2682 -99.721924)
		(end 266.231116 -99.67214)
		(width 0.0889)
		(layer "F.Cu")
		(net "M_D_CS_N<3>")
	)
	(segment
		(start 266.8778 -101.530912)
		(end 266.848844 -101.501956)
		(width 0.0889)
		(layer "F.Cu")
		(net "M_D_CS_N<3>")
	)
	(segment
		(start 275.123402 -125.847602)
		(end 274.549108 -125.847602)
		(width 0.1651)
		(layer "F.Cu")
		(net "M_D_CS_N<3>")
	)
	(segment
		(start 267.0556 -102.1588)
		(end 266.8778 -101.981)
		(width 0.0889)
		(layer "F.Cu")
		(net "M_D_CS_N<3>")
	)
	(segment
		(start 266.8778 -101.981)
		(end 266.8778 -101.530912)
		(width 0.0889)
		(layer "F.Cu")
		(net "M_D_CS_N<3>")
	)
	(segment
		(start 267.1572 -102.1588)
		(end 267.0556 -102.1588)
		(width 0.0889)
		(layer "F.Cu")
		(net "M_D_CS_N<3>")
	)
	(segment
		(start 277.999952 -136.387586)
		(end 278.00046 -136.387078)
		(width 0.1651)
		(layer "F.Cu")
		(net "M_D_CS_N<3>")
	)
	(segment
		(start 278.00046 -137.67054)
		(end 277.999952 -137.67054)
		(width 0.1651)
		(layer "F.Cu")
		(net "M_D_CS_N<3>")
	)
	(segment
		(start 270.049244 -121.347738)
		(end 270.049244 -121.347484)
		(width 0.1651)
		(layer "F.Cu")
		(net "M_D_CS_N<3>")
	)
	(segment
		(start 270.049244 -121.347484)
		(end 269.65275 -120.95099)
		(width 0.1651)
		(layer "F.Cu")
		(net "M_D_CS_N<3>")
	)
	(segment
		(start 277.999952 -137.67054)
		(end 277.999952 -136.387586)
		(width 0.1651)
		(layer "F.Cu")
		(net "M_D_CS_N<3>")
	)
	(segment
		(start 266.742926 -101.357938)
		(end 266.7381 -101.349302)
		(width 0.0889)
		(layer "F.Cu")
		(net "M_D_CS_N<3>")
	)
	(segment
		(start 275.5392 -126.8476)
		(end 275.5392 -126.2634)
		(width 0.1651)
		(layer "F.Cu")
		(net "M_D_CS_N<3>")
	)
	(segment
		(start 266.726416 -100.338128)
		(end 266.2682 -99.721924)
		(width 0.0889)
		(layer "F.Cu")
		(net "M_D_CS_N<3>")
	)
	(segment
		(start 274.549108 -125.847602)
		(end 270.049244 -121.347738)
		(width 0.1651)
		(layer "F.Cu")
		(net "M_D_CS_N<3>")
	)
	(segment
		(start 269.65275 -120.95099)
		(end 269.65275 -104.65435)
		(width 0.1651)
		(layer "F.Cu")
		(net "M_D_CS_N<3>")
	)
	(via
		(at 278.00046 -136.387078)
		(size 0.4572)
		(drill 0.2032)
		(layers "F.Cu" "B.Cu")
		(net "M_D_CS_N<3>")
	)
	(via
		(at 275.5392 -126.8476)
		(size 0.508)
		(drill 0.254)
		(layers "F.Cu" "B.Cu")
		(net "M_D_CS_N<3>")
	)
	(arc
		(start 266.7381 -101.349302)
		(mid 266.689345 -101.15295)
		(end 266.742926 -100.957888)
		(width 0.0889)
		(layer "F.Cu")
		(net "M_D_CS_N<3>")
	)
	(arc
		(start 266.742926 -100.957888)
		(mid 266.822057 -100.662486)
		(end 266.742926 -100.367084)
		(width 0.0889)
		(layer "F.Cu")
		(net "M_D_CS_N<3>")
	)
	(arc
		(start 266.848844 -101.501956)
		(mid 266.79141 -101.433238)
		(end 266.742926 -101.357938)
		(width 0.0889)
		(layer "F.Cu")
		(net "M_D_CS_N<3>")
	)
	(segment
		(start 277.7744 -131.4196)
		(end 277.7744 -133.8326)
		(width 0.14224)
		(layer "In9.Cu")
		(net "M_D_CS_N<3>")
	)
	(segment
		(start 275.5392 -127.9144)
		(end 277.6474 -130.0226)
		(width 0.14224)
		(layer "In9.Cu")
		(net "M_D_CS_N<3>")
	)
	(segment
		(start 277.589742 -134.017258)
		(end 277.589742 -134.663942)
		(width 0.14224)
		(layer "In9.Cu")
		(net "M_D_CS_N<3>")
	)
	(segment
		(start 277.5458 -130.556)
		(end 277.5458 -131.191)
		(width 0.14224)
		(layer "In9.Cu")
		(net "M_D_CS_N<3>")
	)
	(segment
		(start 277.589742 -134.663942)
		(end 277.999952 -135.074152)
		(width 0.14224)
		(layer "In9.Cu")
		(net "M_D_CS_N<3>")
	)
	(segment
		(start 277.6474 -130.4544)
		(end 277.5458 -130.556)
		(width 0.14224)
		(layer "In9.Cu")
		(net "M_D_CS_N<3>")
	)
	(segment
		(start 277.999952 -136.38657)
		(end 278.00046 -136.387078)
		(width 0.14224)
		(layer "In9.Cu")
		(net "M_D_CS_N<3>")
	)
	(segment
		(start 277.5458 -131.191)
		(end 277.7744 -131.4196)
		(width 0.14224)
		(layer "In9.Cu")
		(net "M_D_CS_N<3>")
	)
	(segment
		(start 277.6474 -130.0226)
		(end 277.6474 -130.4544)
		(width 0.14224)
		(layer "In9.Cu")
		(net "M_D_CS_N<3>")
	)
	(segment
		(start 277.999952 -135.074152)
		(end 277.999952 -136.38657)
		(width 0.14224)
		(layer "In9.Cu")
		(net "M_D_CS_N<3>")
	)
	(segment
		(start 277.7744 -133.8326)
		(end 277.589742 -134.017258)
		(width 0.14224)
		(layer "In9.Cu")
		(net "M_D_CS_N<3>")
	)
	(segment
		(start 275.5392 -126.8476)
		(end 275.5392 -127.9144)
		(width 0.14224)
		(layer "In9.Cu")
		(net "M_D_CS_N<3>")
	)
	(segment
		(start 277.5458 -131.2164)
		(end 277.5458 -130.6322)
		(width 0.1651)
		(layer "F.Cu")
		(net "M_D_CS_N<2>")
	)
	(segment
		(start 267.073634 -102.862888)
		(end 266.6492 -102.438454)
		(width 0.0889)
		(layer "F.Cu")
		(net "M_D_CS_N<2>")
	)
	(segment
		(start 277.4061 -129.2225)
		(end 277.066502 -128.882902)
		(width 0.1651)
		(layer "F.Cu")
		(net "M_D_CS_N<2>")
	)
	(segment
		(start 266.560554 -101.42347)
		(end 266.2682 -100.748084)
		(width 0.0889)
		(layer "F.Cu")
		(net "M_D_CS_N<2>")
	)
	(segment
		(start 269.14856 -104.937814)
		(end 267.073634 -102.862888)
		(width 0.1651)
		(layer "F.Cu")
		(net "M_D_CS_N<2>")
	)
	(segment
		(start 277.5458 -130.6322)
		(end 277.7236 -130.4544)
		(width 0.1651)
		(layer "F.Cu")
		(net "M_D_CS_N<2>")
	)
	(segment
		(start 277.999952 -133.0706)
		(end 277.999952 -131.670552)
		(width 0.1651)
		(layer "F.Cu")
		(net "M_D_CS_N<2>")
	)
	(segment
		(start 276.676104 -128.721104)
		(end 269.14856 -121.19356)
		(width 0.1651)
		(layer "F.Cu")
		(net "M_D_CS_N<2>")
	)
	(segment
		(start 277.999952 -131.670552)
		(end 277.5458 -131.2164)
		(width 0.1651)
		(layer "F.Cu")
		(net "M_D_CS_N<2>")
	)
	(segment
		(start 277.7236 -129.9718)
		(end 277.4061 -129.6543)
		(width 0.1651)
		(layer "F.Cu")
		(net "M_D_CS_N<2>")
	)
	(segment
		(start 278.00046 -133.0706)
		(end 277.999952 -133.0706)
		(width 0.1651)
		(layer "F.Cu")
		(net "M_D_CS_N<2>")
	)
	(segment
		(start 269.14856 -121.19356)
		(end 269.14856 -120.541288)
		(width 0.1651)
		(layer "F.Cu")
		(net "M_D_CS_N<2>")
	)
	(segment
		(start 266.2682 -100.748084)
		(end 266.231116 -100.662486)
		(width 0.0889)
		(layer "F.Cu")
		(net "M_D_CS_N<2>")
	)
	(segment
		(start 266.577826 -101.453188)
		(end 266.560554 -101.42347)
		(width 0.0889)
		(layer "F.Cu")
		(net "M_D_CS_N<2>")
	)
	(segment
		(start 266.6492 -102.438454)
		(end 266.6492 -101.717602)
		(width 0.0889)
		(layer "F.Cu")
		(net "M_D_CS_N<2>")
	)
	(segment
		(start 277.7236 -130.4544)
		(end 277.7236 -129.9718)
		(width 0.1651)
		(layer "F.Cu")
		(net "M_D_CS_N<2>")
	)
	(segment
		(start 277.066502 -128.882902)
		(end 276.676104 -128.721104)
		(width 0.1651)
		(layer "F.Cu")
		(net "M_D_CS_N<2>")
	)
	(segment
		(start 269.14856 -120.541288)
		(end 269.14856 -104.937814)
		(width 0.1651)
		(layer "F.Cu")
		(net "M_D_CS_N<2>")
	)
	(segment
		(start 277.4061 -129.6543)
		(end 277.4061 -129.2225)
		(width 0.1651)
		(layer "F.Cu")
		(net "M_D_CS_N<2>")
	)
	(via
		(at 269.14856 -120.541288)
		(size 0.508)
		(drill 0.254)
		(layers "F.Cu" "B.Cu")
		(net "M_D_CS_N<2>")
	)
	(arc
		(start 266.6492 -101.717602)
		(mid 266.631029 -101.580671)
		(end 266.577826 -101.453188)
		(width 0.0889)
		(layer "F.Cu")
		(net "M_D_CS_N<2>")
	)
	(segment
		(start 264.865612 -101.461824)
		(end 264.860786 -101.453188)
		(width 0.0889)
		(layer "F.Cu")
		(net "M_D_CS_N<1>")
	)
	(segment
		(start 267.1318 -120.936004)
		(end 267.1318 -105.671112)
		(width 0.1651)
		(layer "F.Cu")
		(net "M_D_CS_N<1>")
	)
	(segment
		(start 264.920476 -102.56393)
		(end 264.920476 -101.677216)
		(width 0.0889)
		(layer "F.Cu")
		(net "M_D_CS_N<1>")
	)
	(segment
		(start 273.8374 -129.1082)
		(end 273.8374 -129.6162)
		(width 0.1651)
		(layer "F.Cu")
		(net "M_D_CS_N<1>")
	)
	(segment
		(start 274.1168 -131.1148)
		(end 274.5486 -131.5466)
		(width 0.1651)
		(layer "F.Cu")
		(net "M_D_CS_N<1>")
	)
	(segment
		(start 274.206716 -129.985516)
		(end 274.206716 -130.593084)
		(width 0.1651)
		(layer "F.Cu")
		(net "M_D_CS_N<1>")
	)
	(segment
		(start 274.5486 -133.025134)
		(end 274.597114 -133.073648)
		(width 0.1651)
		(layer "F.Cu")
		(net "M_D_CS_N<1>")
	)
	(segment
		(start 267.1318 -105.671112)
		(end 267.1318 -104.775254)
		(width 0.0889)
		(layer "F.Cu")
		(net "M_D_CS_N<1>")
	)
	(segment
		(start 274.1168 -130.683)
		(end 274.1168 -131.1148)
		(width 0.1651)
		(layer "F.Cu")
		(net "M_D_CS_N<1>")
	)
	(segment
		(start 274.206716 -130.593084)
		(end 274.1168 -130.683)
		(width 0.1651)
		(layer "F.Cu")
		(net "M_D_CS_N<1>")
	)
	(segment
		(start 274.597114 -133.073648)
		(end 274.600416 -133.0706)
		(width 0.1651)
		(layer "F.Cu")
		(net "M_D_CS_N<1>")
	)
	(segment
		(start 267.1318 -122.4026)
		(end 273.8374 -129.1082)
		(width 0.1651)
		(layer "F.Cu")
		(net "M_D_CS_N<1>")
	)
	(segment
		(start 274.5486 -131.5466)
		(end 274.5486 -133.025134)
		(width 0.1651)
		(layer "F.Cu")
		(net "M_D_CS_N<1>")
	)
	(segment
		(start 273.8374 -129.6162)
		(end 274.206716 -129.985516)
		(width 0.1651)
		(layer "F.Cu")
		(net "M_D_CS_N<1>")
	)
	(segment
		(start 267.1318 -104.775254)
		(end 264.920476 -102.56393)
		(width 0.0889)
		(layer "F.Cu")
		(net "M_D_CS_N<1>")
	)
	(segment
		(start 267.1318 -120.936004)
		(end 267.1318 -122.4026)
		(width 0.1651)
		(layer "F.Cu")
		(net "M_D_CS_N<1>")
	)
	(segment
		(start 264.820908 -101.370384)
		(end 264.51433 -100.662486)
		(width 0.0889)
		(layer "F.Cu")
		(net "M_D_CS_N<1>")
	)
	(segment
		(start 264.860786 -101.453188)
		(end 264.851896 -101.437948)
		(width 0.0889)
		(layer "F.Cu")
		(net "M_D_CS_N<1>")
	)
	(via
		(at 267.1318 -120.936004)
		(size 0.508)
		(drill 0.254)
		(layers "F.Cu" "B.Cu")
		(net "M_D_CS_N<1>")
	)
	(arc
		(start 264.920476 -101.677216)
		(mid 264.90654 -101.566083)
		(end 264.865612 -101.461824)
		(width 0.0889)
		(layer "F.Cu")
		(net "M_D_CS_N<1>")
	)
	(arc
		(start 264.851896 -101.437948)
		(mid 264.835342 -101.404652)
		(end 264.820908 -101.370384)
		(width 0.0889)
		(layer "F.Cu")
		(net "M_D_CS_N<1>")
	)
	(segment
		(start 269.8496 -129.0828)
		(end 270.8148 -130.048)
		(width 0.1651)
		(layer "F.Cu")
		(net "M_D_CS_N<0>")
	)
	(segment
		(start 266.48664 -125.683264)
		(end 266.72032 -125.683264)
		(width 0.1651)
		(layer "F.Cu")
		(net "M_D_CS_N<0>")
	)
	(segment
		(start 267.4112 -125.74651)
		(end 267.4112 -126.604522)
		(width 0.1651)
		(layer "F.Cu")
		(net "M_D_CS_N<0>")
	)
	(segment
		(start 269.875 -131.4196)
		(end 269.875 -131.851654)
		(width 0.1651)
		(layer "F.Cu")
		(net "M_D_CS_N<0>")
	)
	(segment
		(start 270.8148 -130.048)
		(end 270.8148 -130.4798)
		(width 0.1651)
		(layer "F.Cu")
		(net "M_D_CS_N<0>")
	)
	(segment
		(start 262.79729 -101.653086)
		(end 263.1948 -102.050596)
		(width 0.0889)
		(layer "F.Cu")
		(net "M_D_CS_N<0>")
	)
	(segment
		(start 265.14425 -104.38765)
		(end 265.14425 -104.915462)
		(width 0.0889)
		(layer "F.Cu")
		(net "M_D_CS_N<0>")
	)
	(segment
		(start 266.90701 -125.496574)
		(end 267.161264 -125.496574)
		(width 0.1651)
		(layer "F.Cu")
		(net "M_D_CS_N<0>")
	)
	(segment
		(start 266.338812 -124.937012)
		(end 266.16914 -125.106684)
		(width 0.1651)
		(layer "F.Cu")
		(net "M_D_CS_N<0>")
	)
	(segment
		(start 267.4112 -127.4572)
		(end 269.0368 -129.0828)
		(width 0.1651)
		(layer "F.Cu")
		(net "M_D_CS_N<0>")
	)
	(segment
		(start 263.1948 -102.050596)
		(end 263.1948 -102.4382)
		(width 0.0889)
		(layer "F.Cu")
		(net "M_D_CS_N<0>")
	)
	(segment
		(start 266.16914 -125.365764)
		(end 266.48664 -125.683264)
		(width 0.1651)
		(layer "F.Cu")
		(net "M_D_CS_N<0>")
	)
	(segment
		(start 270.34998 -133.0706)
		(end 270.350488 -133.0706)
		(width 0.1651)
		(layer "F.Cu")
		(net "M_D_CS_N<0>")
	)
	(segment
		(start 266.72032 -125.683264)
		(end 266.90701 -125.496574)
		(width 0.1651)
		(layer "F.Cu")
		(net "M_D_CS_N<0>")
	)
	(segment
		(start 265.11504 -123.399042)
		(end 266.338812 -124.622814)
		(width 0.1651)
		(layer "F.Cu")
		(net "M_D_CS_N<0>")
	)
	(segment
		(start 270.8148 -130.4798)
		(end 269.875 -131.4196)
		(width 0.1651)
		(layer "F.Cu")
		(net "M_D_CS_N<0>")
	)
	(segment
		(start 269.0368 -129.0828)
		(end 269.8496 -129.0828)
		(width 0.1651)
		(layer "F.Cu")
		(net "M_D_CS_N<0>")
	)
	(segment
		(start 266.16914 -125.106684)
		(end 266.16914 -125.365764)
		(width 0.1651)
		(layer "F.Cu")
		(net "M_D_CS_N<0>")
	)
	(segment
		(start 267.4112 -126.604522)
		(end 267.4112 -127.4572)
		(width 0.1651)
		(layer "F.Cu")
		(net "M_D_CS_N<0>")
	)
	(segment
		(start 270.34998 -132.326634)
		(end 270.34998 -133.0706)
		(width 0.1651)
		(layer "F.Cu")
		(net "M_D_CS_N<0>")
	)
	(segment
		(start 269.875 -131.851654)
		(end 270.34998 -132.326634)
		(width 0.1651)
		(layer "F.Cu")
		(net "M_D_CS_N<0>")
	)
	(segment
		(start 266.338812 -124.622814)
		(end 266.338812 -124.937012)
		(width 0.1651)
		(layer "F.Cu")
		(net "M_D_CS_N<0>")
	)
	(segment
		(start 265.14425 -104.915462)
		(end 265.11504 -104.944672)
		(width 0.1651)
		(layer "F.Cu")
		(net "M_D_CS_N<0>")
	)
	(segment
		(start 263.1948 -102.4382)
		(end 265.14425 -104.38765)
		(width 0.0889)
		(layer "F.Cu")
		(net "M_D_CS_N<0>")
	)
	(segment
		(start 267.161264 -125.496574)
		(end 267.4112 -125.74651)
		(width 0.1651)
		(layer "F.Cu")
		(net "M_D_CS_N<0>")
	)
	(segment
		(start 265.11504 -104.944672)
		(end 265.11504 -123.399042)
		(width 0.1651)
		(layer "F.Cu")
		(net "M_D_CS_N<0>")
	)
	(via
		(at 267.4112 -126.604522)
		(size 0.508)
		(drill 0.254)
		(layers "F.Cu" "B.Cu")
		(net "M_D_CS_N<0>")
	)
	(segment
		(start 258.494784 -127.113538)
		(end 258.158742 -127.44958)
		(width 0.1651)
		(layer "F.Cu")
		(net "M_D_CLK_DP<3>")
	)
	(segment
		(start 258.494784 -124.597922)
		(end 258.494784 -125.183138)
		(width 0.1651)
		(layer "F.Cu")
		(net "M_D_CLK_DP<3>")
	)
	(segment
		(start 257.337814 -130.3782)
		(end 257.03403 -130.074416)
		(width 0.1651)
		(layer "F.Cu")
		(net "M_D_CLK_DP<3>")
	)
	(segment
		(start 257.19405 -125.68428)
		(end 257.19405 -126.02718)
		(width 0.1651)
		(layer "F.Cu")
		(net "M_D_CLK_DP<3>")
	)
	(segment
		(start 257.19405 -126.02718)
		(end 257.35915 -126.19228)
		(width 0.1651)
		(layer "F.Cu")
		(net "M_D_CLK_DP<3>")
	)
	(segment
		(start 260.2357 -103.907082)
		(end 260.2357 -104.12349)
		(width 0.0889)
		(layer "F.Cu")
		(net "M_D_CLK_DP<3>")
	)
	(segment
		(start 257.19405 -127.61468)
		(end 257.19405 -128.211326)
		(width 0.1651)
		(layer "F.Cu")
		(net "M_D_CLK_DP<3>")
	)
	(segment
		(start 258.158742 -127.44958)
		(end 257.35915 -127.44958)
		(width 0.1651)
		(layer "F.Cu")
		(net "M_D_CLK_DP<3>")
	)
	(segment
		(start 257.35915 -125.51918)
		(end 257.19405 -125.68428)
		(width 0.1651)
		(layer "F.Cu")
		(net "M_D_CLK_DP<3>")
	)
	(segment
		(start 258.494784 -125.183138)
		(end 258.158742 -125.51918)
		(width 0.1651)
		(layer "F.Cu")
		(net "M_D_CLK_DP<3>")
	)
	(segment
		(start 258.267454 -101.938836)
		(end 260.2357 -103.907082)
		(width 0.0889)
		(layer "F.Cu")
		(net "M_D_CLK_DP<3>")
	)
	(segment
		(start 260.291072 -117.797834)
		(end 257.19405 -120.894856)
		(width 0.1651)
		(layer "F.Cu")
		(net "M_D_CLK_DP<3>")
	)
	(segment
		(start 258.158742 -126.19228)
		(end 258.494784 -126.528322)
		(width 0.1651)
		(layer "F.Cu")
		(net "M_D_CLK_DP<3>")
	)
	(segment
		(start 258.267454 -101.395276)
		(end 258.267454 -101.938836)
		(width 0.0889)
		(layer "F.Cu")
		(net "M_D_CLK_DP<3>")
	)
	(segment
		(start 258.494784 -126.528322)
		(end 258.494784 -127.113538)
		(width 0.1651)
		(layer "F.Cu")
		(net "M_D_CLK_DP<3>")
	)
	(segment
		(start 258.949952 -129.061464)
		(end 258.949952 -129.870962)
		(width 0.1651)
		(layer "F.Cu")
		(net "M_D_CLK_DP<3>")
	)
	(segment
		(start 258.50469 -101.15804)
		(end 258.267454 -101.395276)
		(width 0.0889)
		(layer "F.Cu")
		(net "M_D_CLK_DP<3>")
	)
	(segment
		(start 260.291072 -104.180894)
		(end 260.291072 -117.797834)
		(width 0.1651)
		(layer "F.Cu")
		(net "M_D_CLK_DP<3>")
	)
	(segment
		(start 257.35915 -126.19228)
		(end 258.158742 -126.19228)
		(width 0.1651)
		(layer "F.Cu")
		(net "M_D_CLK_DP<3>")
	)
	(segment
		(start 258.442714 -130.3782)
		(end 257.337814 -130.3782)
		(width 0.1651)
		(layer "F.Cu")
		(net "M_D_CLK_DP<3>")
	)
	(segment
		(start 257.469894 -128.48717)
		(end 258.375658 -128.48717)
		(width 0.1651)
		(layer "F.Cu")
		(net "M_D_CLK_DP<3>")
	)
	(segment
		(start 257.03403 -130.074416)
		(end 257.03403 -129.776982)
		(width 0.1651)
		(layer "F.Cu")
		(net "M_D_CLK_DP<3>")
	)
	(segment
		(start 258.158742 -125.51918)
		(end 257.35915 -125.51918)
		(width 0.1651)
		(layer "F.Cu")
		(net "M_D_CLK_DP<3>")
	)
	(segment
		(start 258.375658 -128.48717)
		(end 258.949952 -129.061464)
		(width 0.1651)
		(layer "F.Cu")
		(net "M_D_CLK_DP<3>")
	)
	(segment
		(start 257.19405 -120.894856)
		(end 257.19405 -124.09678)
		(width 0.1651)
		(layer "F.Cu")
		(net "M_D_CLK_DP<3>")
	)
	(segment
		(start 257.35915 -124.26188)
		(end 258.158742 -124.26188)
		(width 0.1651)
		(layer "F.Cu")
		(net "M_D_CLK_DP<3>")
	)
	(segment
		(start 260.291072 -104.178862)
		(end 260.291072 -104.180894)
		(width 0.0889)
		(layer "F.Cu")
		(net "M_D_CLK_DP<3>")
	)
	(segment
		(start 257.35915 -127.44958)
		(end 257.19405 -127.61468)
		(width 0.1651)
		(layer "F.Cu")
		(net "M_D_CLK_DP<3>")
	)
	(segment
		(start 258.949952 -129.870962)
		(end 258.442714 -130.3782)
		(width 0.1651)
		(layer "F.Cu")
		(net "M_D_CLK_DP<3>")
	)
	(segment
		(start 257.03403 -129.776982)
		(end 256.826004 -129.568956)
		(width 0.1651)
		(layer "F.Cu")
		(net "M_D_CLK_DP<3>")
	)
	(segment
		(start 257.19405 -128.211326)
		(end 257.469894 -128.48717)
		(width 0.1651)
		(layer "F.Cu")
		(net "M_D_CLK_DP<3>")
	)
	(segment
		(start 258.158742 -124.26188)
		(end 258.494784 -124.597922)
		(width 0.1651)
		(layer "F.Cu")
		(net "M_D_CLK_DP<3>")
	)
	(segment
		(start 257.19405 -124.09678)
		(end 257.35915 -124.26188)
		(width 0.1651)
		(layer "F.Cu")
		(net "M_D_CLK_DP<3>")
	)
	(segment
		(start 260.2357 -104.12349)
		(end 260.291072 -104.178862)
		(width 0.0889)
		(layer "F.Cu")
		(net "M_D_CLK_DP<3>")
	)
	(via
		(at 256.826004 -129.568956)
		(size 0.508)
		(drill 0.254)
		(layers "F.Cu" "B.Cu")
		(net "M_D_CLK_DP<3>")
	)
	(segment
		(start 256.750312 -128.276096)
		(end 256.749804 -128.276096)
		(width 0.1651)
		(layer "B.Cu")
		(net "M_D_CLK_DP<3>")
	)
	(segment
		(start 256.749804 -129.492756)
		(end 256.826004 -129.568956)
		(width 0.1651)
		(layer "B.Cu")
		(net "M_D_CLK_DP<3>")
	)
	(segment
		(start 256.749804 -128.276096)
		(end 256.749804 -129.492756)
		(width 0.1651)
		(layer "B.Cu")
		(net "M_D_CLK_DP<3>")
	)
	(segment
		(start 260.4008 -129.7559)
		(end 260.4008 -129.2606)
		(width 0.1651)
		(layer "F.Cu")
		(net "M_D_CLK_DP<1>")
	)
	(segment
		(start 261.0104 -132.987288)
		(end 261.0104 -130.8608)
		(width 0.1651)
		(layer "F.Cu")
		(net "M_D_CLK_DP<1>")
	)
	(segment
		(start 261.658354 -104.11968)
		(end 261.658354 -103.734362)
		(width 0.0889)
		(layer "F.Cu")
		(net "M_D_CLK_DP<1>")
	)
	(segment
		(start 261.015226 -120.153176)
		(end 261.015226 -119.26824)
		(width 0.1651)
		(layer "F.Cu")
		(net "M_D_CLK_DP<1>")
	)
	(segment
		(start 260.632956 -133.364732)
		(end 261.0104 -132.987288)
		(width 0.1651)
		(layer "F.Cu")
		(net "M_D_CLK_DP<1>")
	)
	(segment
		(start 260.572504 -101.350572)
		(end 260.574282 -101.348032)
		(width 0.0889)
		(layer "F.Cu")
		(net "M_D_CLK_DP<1>")
	)
	(segment
		(start 261.609332 -104.173782)
		(end 261.609332 -104.168702)
		(width 0.0889)
		(layer "F.Cu")
		(net "M_D_CLK_DP<1>")
	)
	(segment
		(start 260.4008 -127.3175)
		(end 260.4008 -126.8222)
		(width 0.1651)
		(layer "F.Cu")
		(net "M_D_CLK_DP<1>")
	)
	(segment
		(start 256.749804 -136.532366)
		(end 257.028696 -136.253474)
		(width 0.1651)
		(layer "F.Cu")
		(net "M_D_CLK_DP<1>")
	)
	(segment
		(start 257.511804 -135.256016)
		(end 258.741672 -135.256016)
		(width 0.1651)
		(layer "F.Cu")
		(net "M_D_CLK_DP<1>")
	)
	(segment
		(start 260.5151 -129.1463)
		(end 260.5151 -128.651)
		(width 0.1651)
		(layer "F.Cu")
		(net "M_D_CLK_DP<1>")
	)
	(segment
		(start 261.015226 -119.26824)
		(end 261.609332 -118.674134)
		(width 0.1651)
		(layer "F.Cu")
		(net "M_D_CLK_DP<1>")
	)
	(segment
		(start 256.749804 -137.67054)
		(end 256.749804 -136.532366)
		(width 0.1651)
		(layer "F.Cu")
		(net "M_D_CLK_DP<1>")
	)
	(segment
		(start 260.5151 -129.8702)
		(end 260.4008 -129.7559)
		(width 0.1651)
		(layer "F.Cu")
		(net "M_D_CLK_DP<1>")
	)
	(segment
		(start 260.512306 -133.364732)
		(end 260.632956 -133.364732)
		(width 0.1651)
		(layer "F.Cu")
		(net "M_D_CLK_DP<1>")
	)
	(segment
		(start 260.477 -102.553008)
		(end 260.477 -101.54158)
		(width 0.0889)
		(layer "F.Cu")
		(net "M_D_CLK_DP<1>")
	)
	(segment
		(start 260.5151 -127.4318)
		(end 260.4008 -127.3175)
		(width 0.1651)
		(layer "F.Cu")
		(net "M_D_CLK_DP<1>")
	)
	(segment
		(start 259.118862 -134.761224)
		(end 259.469382 -134.410704)
		(width 0.1651)
		(layer "F.Cu")
		(net "M_D_CLK_DP<1>")
	)
	(segment
		(start 259.118862 -134.878826)
		(end 259.118862 -134.761224)
		(width 0.1651)
		(layer "F.Cu")
		(net "M_D_CLK_DP<1>")
	)
	(segment
		(start 261.015226 -122.961654)
		(end 261.015226 -120.90146)
		(width 0.1651)
		(layer "F.Cu")
		(net "M_D_CLK_DP<1>")
	)
	(segment
		(start 260.5151 -127.9271)
		(end 260.5151 -127.4318)
		(width 0.1651)
		(layer "F.Cu")
		(net "M_D_CLK_DP<1>")
	)
	(segment
		(start 259.586984 -134.410704)
		(end 260.161786 -133.835902)
		(width 0.1651)
		(layer "F.Cu")
		(net "M_D_CLK_DP<1>")
	)
	(segment
		(start 260.5151 -126.7079)
		(end 260.5151 -123.46178)
		(width 0.1651)
		(layer "F.Cu")
		(net "M_D_CLK_DP<1>")
	)
	(segment
		(start 259.469382 -134.410704)
		(end 259.586984 -134.410704)
		(width 0.1651)
		(layer "F.Cu")
		(net "M_D_CLK_DP<1>")
	)
	(segment
		(start 260.4008 -128.5367)
		(end 260.4008 -128.0414)
		(width 0.1651)
		(layer "F.Cu")
		(net "M_D_CLK_DP<1>")
	)
	(segment
		(start 260.4008 -126.8222)
		(end 260.5151 -126.7079)
		(width 0.1651)
		(layer "F.Cu")
		(net "M_D_CLK_DP<1>")
	)
	(segment
		(start 261.609332 -118.674134)
		(end 261.609332 -114.776504)
		(width 0.1651)
		(layer "F.Cu")
		(net "M_D_CLK_DP<1>")
	)
	(segment
		(start 261.658354 -103.734362)
		(end 260.477 -102.553008)
		(width 0.0889)
		(layer "F.Cu")
		(net "M_D_CLK_DP<1>")
	)
	(segment
		(start 259.82168 -101.168708)
		(end 259.823966 -101.257608)
		(width 0.0889)
		(layer "F.Cu")
		(net "M_D_CLK_DP<1>")
	)
	(segment
		(start 260.477 -101.54158)
		(end 260.57098 -101.353874)
		(width 0.0889)
		(layer "F.Cu")
		(net "M_D_CLK_DP<1>")
	)
	(segment
		(start 260.888734 -120.774968)
		(end 260.888734 -120.279668)
		(width 0.1651)
		(layer "F.Cu")
		(net "M_D_CLK_DP<1>")
	)
	(segment
		(start 260.5151 -128.651)
		(end 260.4008 -128.5367)
		(width 0.1651)
		(layer "F.Cu")
		(net "M_D_CLK_DP<1>")
	)
	(segment
		(start 261.609332 -104.168702)
		(end 261.658354 -104.11968)
		(width 0.0889)
		(layer "F.Cu")
		(net "M_D_CLK_DP<1>")
	)
	(segment
		(start 260.079744 -100.783898)
		(end 260.07949 -100.784152)
		(width 0.0889)
		(layer "F.Cu")
		(net "M_D_CLK_DP<1>")
	)
	(segment
		(start 260.4008 -128.0414)
		(end 260.5151 -127.9271)
		(width 0.1651)
		(layer "F.Cu")
		(net "M_D_CLK_DP<1>")
	)
	(segment
		(start 260.57098 -101.353874)
		(end 260.572504 -101.350572)
		(width 0.0889)
		(layer "F.Cu")
		(net "M_D_CLK_DP<1>")
	)
	(segment
		(start 260.4008 -129.2606)
		(end 260.5151 -129.1463)
		(width 0.1651)
		(layer "F.Cu")
		(net "M_D_CLK_DP<1>")
	)
	(segment
		(start 258.741672 -135.256016)
		(end 259.118862 -134.878826)
		(width 0.1651)
		(layer "F.Cu")
		(net "M_D_CLK_DP<1>")
	)
	(segment
		(start 261.0104 -130.8608)
		(end 260.5151 -130.3655)
		(width 0.1651)
		(layer "F.Cu")
		(net "M_D_CLK_DP<1>")
	)
	(segment
		(start 260.888734 -120.279668)
		(end 261.015226 -120.153176)
		(width 0.1651)
		(layer "F.Cu")
		(net "M_D_CLK_DP<1>")
	)
	(segment
		(start 260.5151 -123.46178)
		(end 261.015226 -122.961654)
		(width 0.1651)
		(layer "F.Cu")
		(net "M_D_CLK_DP<1>")
	)
	(segment
		(start 256.750312 -137.67054)
		(end 256.749804 -137.67054)
		(width 0.1651)
		(layer "F.Cu")
		(net "M_D_CLK_DP<1>")
	)
	(segment
		(start 261.609332 -114.776504)
		(end 261.609332 -104.173782)
		(width 0.1651)
		(layer "F.Cu")
		(net "M_D_CLK_DP<1>")
	)
	(segment
		(start 260.5151 -130.3655)
		(end 260.5151 -129.8702)
		(width 0.1651)
		(layer "F.Cu")
		(net "M_D_CLK_DP<1>")
	)
	(segment
		(start 261.015226 -120.90146)
		(end 260.888734 -120.774968)
		(width 0.1651)
		(layer "F.Cu")
		(net "M_D_CLK_DP<1>")
	)
	(segment
		(start 260.161786 -133.715252)
		(end 260.512306 -133.364732)
		(width 0.1651)
		(layer "F.Cu")
		(net "M_D_CLK_DP<1>")
	)
	(segment
		(start 260.037326 -101.342698)
		(end 260.22173 -101.15804)
		(width 0.0889)
		(layer "F.Cu")
		(net "M_D_CLK_DP<1>")
	)
	(segment
		(start 260.07949 -100.784152)
		(end 260.078982 -100.784152)
		(width 0.0889)
		(layer "F.Cu")
		(net "M_D_CLK_DP<1>")
	)
	(segment
		(start 257.028696 -136.253474)
		(end 257.028696 -135.739124)
		(width 0.1651)
		(layer "F.Cu")
		(net "M_D_CLK_DP<1>")
	)
	(segment
		(start 257.028696 -135.739124)
		(end 257.511804 -135.256016)
		(width 0.1651)
		(layer "F.Cu")
		(net "M_D_CLK_DP<1>")
	)
	(segment
		(start 260.161786 -133.835902)
		(end 260.161786 -133.715252)
		(width 0.1651)
		(layer "F.Cu")
		(net "M_D_CLK_DP<1>")
	)
	(via
		(at 261.609332 -114.776504)
		(size 0.508)
		(drill 0.254)
		(layers "F.Cu" "B.Cu")
		(net "M_D_CLK_DP<1>")
	)
	(arc
		(start 260.574282 -101.348032)
		(mid 260.522969 -100.894186)
		(end 260.079744 -100.783898)
		(width 0.0889)
		(layer "F.Cu")
		(net "M_D_CLK_DP<1>")
	)
	(arc
		(start 259.823966 -101.257608)
		(mid 259.902624 -101.370423)
		(end 260.037326 -101.342698)
		(width 0.0889)
		(layer "F.Cu")
		(net "M_D_CLK_DP<1>")
	)
	(arc
		(start 259.82168 -101.16566)
		(mid 259.821682 -101.167184)
		(end 259.82168 -101.168708)
		(width 0.0889)
		(layer "F.Cu")
		(net "M_D_CLK_DP<1>")
	)
	(arc
		(start 260.078982 -100.784152)
		(mid 259.890077 -100.934255)
		(end 259.82168 -101.16566)
		(width 0.0889)
		(layer "F.Cu")
		(net "M_D_CLK_DP<1>")
	)
	(segment
		(start 256.0828 -122.869452)
		(end 256.209292 -122.995944)
		(width 0.1651)
		(layer "F.Cu")
		(net "M_D_CLK_DP<2>")
	)
	(segment
		(start 259.494274 -107.272582)
		(end 259.494274 -107.767882)
		(width 0.1651)
		(layer "F.Cu")
		(net "M_D_CLK_DP<2>")
	)
	(segment
		(start 256.209292 -127.221996)
		(end 256.0828 -127.348488)
		(width 0.1651)
		(layer "F.Cu")
		(net "M_D_CLK_DP<2>")
	)
	(segment
		(start 258.697984 -117.996716)
		(end 258.347464 -118.347236)
		(width 0.1651)
		(layer "F.Cu")
		(net "M_D_CLK_DP<2>")
	)
	(segment
		(start 255.70815 -129.810256)
		(end 255.805686 -129.907792)
		(width 0.1651)
		(layer "F.Cu")
		(net "M_D_CLK_DP<2>")
	)
	(segment
		(start 259.329174 -104.155748)
		(end 259.379974 -104.206548)
		(width 0.0889)
		(layer "F.Cu")
		(net "M_D_CLK_DP<2>")
	)
	(segment
		(start 257.66776 -101.253036)
		(end 257.634994 -101.253036)
		(width 0.0889)
		(layer "F.Cu")
		(net "M_D_CLK_DP<2>")
	)
	(segment
		(start 257.323336 -119.233442)
		(end 256.962148 -119.59463)
		(width 0.1651)
		(layer "F.Cu")
		(net "M_D_CLK_DP<2>")
	)
	(segment
		(start 256.209292 -122.24766)
		(end 256.0828 -122.374152)
		(width 0.1651)
		(layer "F.Cu")
		(net "M_D_CLK_DP<2>")
	)
	(segment
		(start 258.50469 -99.17684)
		(end 258.50469 -99.077018)
		(width 0.0889)
		(layer "F.Cu")
		(net "M_D_CLK_DP<2>")
	)
	(segment
		(start 255.805686 -130.609848)
		(end 255.73482 -130.680714)
		(width 0.1651)
		(layer "F.Cu")
		(net "M_D_CLK_DP<2>")
	)
	(segment
		(start 256.0828 -127.348488)
		(end 256.0828 -127.749554)
		(width 0.1651)
		(layer "F.Cu")
		(net "M_D_CLK_DP<2>")
	)
	(segment
		(start 256.209292 -124.734828)
		(end 256.0828 -124.86132)
		(width 0.1651)
		(layer "F.Cu")
		(net "M_D_CLK_DP<2>")
	)
	(segment
		(start 255.805686 -129.907792)
		(end 255.805686 -130.609848)
		(width 0.1651)
		(layer "F.Cu")
		(net "M_D_CLK_DP<2>")
	)
	(segment
		(start 259.379974 -117.176804)
		(end 258.697984 -117.858794)
		(width 0.1651)
		(layer "F.Cu")
		(net "M_D_CLK_DP<2>")
	)
	(segment
		(start 259.379974 -104.206548)
		(end 259.379974 -105.939082)
		(width 0.1651)
		(layer "F.Cu")
		(net "M_D_CLK_DP<2>")
	)
	(segment
		(start 258.209542 -118.347236)
		(end 257.823462 -118.733316)
		(width 0.1651)
		(layer "F.Cu")
		(net "M_D_CLK_DP<2>")
	)
	(segment
		(start 257.257804 -101.962204)
		(end 259.329174 -104.033574)
		(width 0.0889)
		(layer "F.Cu")
		(net "M_D_CLK_DP<2>")
	)
	(segment
		(start 257.29946 -101.453188)
		(end 257.257804 -101.525324)
		(width 0.0889)
		(layer "F.Cu")
		(net "M_D_CLK_DP<2>")
	)
	(segment
		(start 259.494274 -109.710982)
		(end 259.494274 -110.206282)
		(width 0.1651)
		(layer "F.Cu")
		(net "M_D_CLK_DP<2>")
	)
	(segment
		(start 256.432812 -120.123966)
		(end 256.0828 -120.473978)
		(width 0.1651)
		(layer "F.Cu")
		(net "M_D_CLK_DP<2>")
	)
	(segment
		(start 257.257804 -101.525324)
		(end 257.257804 -101.962204)
		(width 0.0889)
		(layer "F.Cu")
		(net "M_D_CLK_DP<2>")
	)
	(segment
		(start 256.209292 -126.726696)
		(end 256.209292 -127.221996)
		(width 0.1651)
		(layer "F.Cu")
		(net "M_D_CLK_DP<2>")
	)
	(segment
		(start 255.73482 -130.680714)
		(end 255.73482 -131.153916)
		(width 0.1651)
		(layer "F.Cu")
		(net "M_D_CLK_DP<2>")
	)
	(segment
		(start 259.379974 -110.320582)
		(end 259.379974 -117.176804)
		(width 0.1651)
		(layer "F.Cu")
		(net "M_D_CLK_DP<2>")
	)
	(segment
		(start 259.494274 -110.206282)
		(end 259.379974 -110.320582)
		(width 0.1651)
		(layer "F.Cu")
		(net "M_D_CLK_DP<2>")
	)
	(segment
		(start 256.0828 -125.35662)
		(end 256.209292 -125.483112)
		(width 0.1651)
		(layer "F.Cu")
		(net "M_D_CLK_DP<2>")
	)
	(segment
		(start 256.209292 -123.491244)
		(end 256.0828 -123.617736)
		(width 0.1651)
		(layer "F.Cu")
		(net "M_D_CLK_DP<2>")
	)
	(segment
		(start 256.0828 -128.70053)
		(end 255.70815 -129.07518)
		(width 0.1651)
		(layer "F.Cu")
		(net "M_D_CLK_DP<2>")
	)
	(segment
		(start 259.379974 -105.939082)
		(end 259.494274 -106.053382)
		(width 0.1651)
		(layer "F.Cu")
		(net "M_D_CLK_DP<2>")
	)
	(segment
		(start 256.161032 -120.850914)
		(end 256.161032 -121.181114)
		(width 0.1651)
		(layer "F.Cu")
		(net "M_D_CLK_DP<2>")
	)
	(segment
		(start 256.0828 -123.617736)
		(end 256.0828 -124.113036)
		(width 0.1651)
		(layer "F.Cu")
		(net "M_D_CLK_DP<2>")
	)
	(segment
		(start 256.998978 -131.14401)
		(end 256.998978 -131.002278)
		(width 0.1651)
		(layer "F.Cu")
		(net "M_D_CLK_DP<2>")
	)
	(segment
		(start 255.73482 -131.153916)
		(end 255.921256 -131.340352)
		(width 0.1651)
		(layer "F.Cu")
		(net "M_D_CLK_DP<2>")
	)
	(segment
		(start 257.472942 -119.233442)
		(end 257.323336 -119.233442)
		(width 0.1651)
		(layer "F.Cu")
		(net "M_D_CLK_DP<2>")
	)
	(segment
		(start 256.209292 -125.483112)
		(end 256.209292 -125.978412)
		(width 0.1651)
		(layer "F.Cu")
		(net "M_D_CLK_DP<2>")
	)
	(segment
		(start 256.226056 -128.376934)
		(end 256.0828 -128.52019)
		(width 0.1651)
		(layer "F.Cu")
		(net "M_D_CLK_DP<2>")
	)
	(segment
		(start 259.494274 -108.491782)
		(end 259.494274 -108.987082)
		(width 0.1651)
		(layer "F.Cu")
		(net "M_D_CLK_DP<2>")
	)
	(segment
		(start 256.0828 -122.374152)
		(end 256.0828 -122.869452)
		(width 0.1651)
		(layer "F.Cu")
		(net "M_D_CLK_DP<2>")
	)
	(segment
		(start 259.379974 -106.662982)
		(end 259.379974 -107.158282)
		(width 0.1651)
		(layer "F.Cu")
		(net "M_D_CLK_DP<2>")
	)
	(segment
		(start 258.194048 -98.933)
		(end 258.16941 -98.957638)
		(width 0.0889)
		(layer "F.Cu")
		(net "M_D_CLK_DP<2>")
	)
	(segment
		(start 256.0828 -124.86132)
		(end 256.0828 -125.35662)
		(width 0.1651)
		(layer "F.Cu")
		(net "M_D_CLK_DP<2>")
	)
	(segment
		(start 259.494274 -107.767882)
		(end 259.379974 -107.882182)
		(width 0.1651)
		(layer "F.Cu")
		(net "M_D_CLK_DP<2>")
	)
	(segment
		(start 257.823462 -118.733316)
		(end 257.823462 -118.882922)
		(width 0.1651)
		(layer "F.Cu")
		(net "M_D_CLK_DP<2>")
	)
	(segment
		(start 258.697984 -117.858794)
		(end 258.697984 -117.996716)
		(width 0.1651)
		(layer "F.Cu")
		(net "M_D_CLK_DP<2>")
	)
	(segment
		(start 256.611882 -120.123966)
		(end 256.432812 -120.123966)
		(width 0.1651)
		(layer "F.Cu")
		(net "M_D_CLK_DP<2>")
	)
	(segment
		(start 256.962148 -119.59463)
		(end 256.962148 -119.773446)
		(width 0.1651)
		(layer "F.Cu")
		(net "M_D_CLK_DP<2>")
	)
	(segment
		(start 256.802636 -131.340352)
		(end 256.998978 -131.14401)
		(width 0.1651)
		(layer "F.Cu")
		(net "M_D_CLK_DP<2>")
	)
	(segment
		(start 256.0828 -126.600204)
		(end 256.209292 -126.726696)
		(width 0.1651)
		(layer "F.Cu")
		(net "M_D_CLK_DP<2>")
	)
	(segment
		(start 259.494274 -106.548682)
		(end 259.379974 -106.662982)
		(width 0.1651)
		(layer "F.Cu")
		(net "M_D_CLK_DP<2>")
	)
	(segment
		(start 256.209292 -125.978412)
		(end 256.0828 -126.104904)
		(width 0.1651)
		(layer "F.Cu")
		(net "M_D_CLK_DP<2>")
	)
	(segment
		(start 256.209292 -122.995944)
		(end 256.209292 -123.491244)
		(width 0.1651)
		(layer "F.Cu")
		(net "M_D_CLK_DP<2>")
	)
	(segment
		(start 256.0828 -120.473978)
		(end 256.0828 -120.772682)
		(width 0.1651)
		(layer "F.Cu")
		(net "M_D_CLK_DP<2>")
	)
	(segment
		(start 259.494274 -108.987082)
		(end 259.379974 -109.101382)
		(width 0.1651)
		(layer "F.Cu")
		(net "M_D_CLK_DP<2>")
	)
	(segment
		(start 259.379974 -109.596682)
		(end 259.494274 -109.710982)
		(width 0.1651)
		(layer "F.Cu")
		(net "M_D_CLK_DP<2>")
	)
	(segment
		(start 259.379974 -107.158282)
		(end 259.494274 -107.272582)
		(width 0.1651)
		(layer "F.Cu")
		(net "M_D_CLK_DP<2>")
	)
	(segment
		(start 255.921256 -131.340352)
		(end 256.802636 -131.340352)
		(width 0.1651)
		(layer "F.Cu")
		(net "M_D_CLK_DP<2>")
	)
	(segment
		(start 256.0828 -121.259346)
		(end 256.0828 -121.625868)
		(width 0.1651)
		(layer "F.Cu")
		(net "M_D_CLK_DP<2>")
	)
	(segment
		(start 258.165092 -99.97059)
		(end 258.147312 -100.00615)
		(width 0.0889)
		(layer "F.Cu")
		(net "M_D_CLK_DP<2>")
	)
	(segment
		(start 259.494274 -106.053382)
		(end 259.494274 -106.548682)
		(width 0.1651)
		(layer "F.Cu")
		(net "M_D_CLK_DP<2>")
	)
	(segment
		(start 256.998978 -131.002278)
		(end 256.8575 -130.8608)
		(width 0.1651)
		(layer "F.Cu")
		(net "M_D_CLK_DP<2>")
	)
	(segment
		(start 259.379974 -109.101382)
		(end 259.379974 -109.596682)
		(width 0.1651)
		(layer "F.Cu")
		(net "M_D_CLK_DP<2>")
	)
	(segment
		(start 256.0828 -120.772682)
		(end 256.161032 -120.850914)
		(width 0.1651)
		(layer "F.Cu")
		(net "M_D_CLK_DP<2>")
	)
	(segment
		(start 256.962148 -119.773446)
		(end 256.611882 -120.123966)
		(width 0.1651)
		(layer "F.Cu")
		(net "M_D_CLK_DP<2>")
	)
	(segment
		(start 256.226056 -127.89281)
		(end 256.226056 -128.376934)
		(width 0.1651)
		(layer "F.Cu")
		(net "M_D_CLK_DP<2>")
	)
	(segment
		(start 257.823462 -118.882922)
		(end 257.472942 -119.233442)
		(width 0.1651)
		(layer "F.Cu")
		(net "M_D_CLK_DP<2>")
	)
	(segment
		(start 256.209292 -121.75236)
		(end 256.209292 -122.24766)
		(width 0.1651)
		(layer "F.Cu")
		(net "M_D_CLK_DP<2>")
	)
	(segment
		(start 259.329174 -104.033574)
		(end 259.329174 -104.155748)
		(width 0.0889)
		(layer "F.Cu")
		(net "M_D_CLK_DP<2>")
	)
	(segment
		(start 255.70815 -129.07518)
		(end 255.70815 -129.810256)
		(width 0.1651)
		(layer "F.Cu")
		(net "M_D_CLK_DP<2>")
	)
	(segment
		(start 256.161032 -121.181114)
		(end 256.0828 -121.259346)
		(width 0.1651)
		(layer "F.Cu")
		(net "M_D_CLK_DP<2>")
	)
	(segment
		(start 256.209292 -124.239528)
		(end 256.209292 -124.734828)
		(width 0.1651)
		(layer "F.Cu")
		(net "M_D_CLK_DP<2>")
	)
	(segment
		(start 256.0828 -124.113036)
		(end 256.209292 -124.239528)
		(width 0.1651)
		(layer "F.Cu")
		(net "M_D_CLK_DP<2>")
	)
	(segment
		(start 259.379974 -107.882182)
		(end 259.379974 -108.377482)
		(width 0.1651)
		(layer "F.Cu")
		(net "M_D_CLK_DP<2>")
	)
	(segment
		(start 256.0828 -121.625868)
		(end 256.209292 -121.75236)
		(width 0.1651)
		(layer "F.Cu")
		(net "M_D_CLK_DP<2>")
	)
	(segment
		(start 258.347464 -118.347236)
		(end 258.209542 -118.347236)
		(width 0.1651)
		(layer "F.Cu")
		(net "M_D_CLK_DP<2>")
	)
	(segment
		(start 256.0828 -126.104904)
		(end 256.0828 -126.600204)
		(width 0.1651)
		(layer "F.Cu")
		(net "M_D_CLK_DP<2>")
	)
	(segment
		(start 259.379974 -108.377482)
		(end 259.494274 -108.491782)
		(width 0.1651)
		(layer "F.Cu")
		(net "M_D_CLK_DP<2>")
	)
	(segment
		(start 256.0828 -128.52019)
		(end 256.0828 -128.70053)
		(width 0.1651)
		(layer "F.Cu")
		(net "M_D_CLK_DP<2>")
	)
	(segment
		(start 256.0828 -127.749554)
		(end 256.226056 -127.89281)
		(width 0.1651)
		(layer "F.Cu")
		(net "M_D_CLK_DP<2>")
	)
	(via
		(at 256.8575 -130.8608)
		(size 0.508)
		(drill 0.254)
		(layers "F.Cu" "B.Cu")
		(net "M_D_CLK_DP<2>")
	)
	(arc
		(start 258.15798 -100.367084)
		(mid 258.163234 -100.948592)
		(end 257.66776 -101.253036)
		(width 0.0889)
		(layer "F.Cu")
		(net "M_D_CLK_DP<2>")
	)
	(arc
		(start 258.50469 -99.077018)
		(mid 258.489184 -98.999062)
		(end 258.445 -98.933)
		(width 0.0889)
		(layer "F.Cu")
		(net "M_D_CLK_DP<2>")
	)
	(arc
		(start 258.15798 -99.376992)
		(mid 258.239212 -99.672847)
		(end 258.165092 -99.97059)
		(width 0.0889)
		(layer "F.Cu")
		(net "M_D_CLK_DP<2>")
	)
	(arc
		(start 257.634994 -101.253036)
		(mid 257.441144 -101.309386)
		(end 257.29946 -101.453188)
		(width 0.0889)
		(layer "F.Cu")
		(net "M_D_CLK_DP<2>")
	)
	(arc
		(start 258.16941 -98.957638)
		(mid 258.104358 -99.165695)
		(end 258.15798 -99.376992)
		(width 0.0889)
		(layer "F.Cu")
		(net "M_D_CLK_DP<2>")
	)
	(arc
		(start 258.147312 -100.00615)
		(mid 258.107247 -100.187945)
		(end 258.15798 -100.367084)
		(width 0.0889)
		(layer "F.Cu")
		(net "M_D_CLK_DP<2>")
	)
	(arc
		(start 258.445 -98.933)
		(mid 258.319524 -98.881026)
		(end 258.194048 -98.933)
		(width 0.0889)
		(layer "F.Cu")
		(net "M_D_CLK_DP<2>")
	)
	(segment
		(start 256.749804 -130.968496)
		(end 256.8575 -130.8608)
		(width 0.1651)
		(layer "B.Cu")
		(net "M_D_CLK_DP<2>")
	)
	(segment
		(start 256.749804 -132.875782)
		(end 256.749804 -130.968496)
		(width 0.1651)
		(layer "B.Cu")
		(net "M_D_CLK_DP<2>")
	)
	(segment
		(start 256.750312 -132.876036)
		(end 256.749804 -132.875782)
		(width 0.1651)
		(layer "B.Cu")
		(net "M_D_CLK_DP<2>")
	)
	(segment
		(start 259.394706 -124.042424)
		(end 259.394706 -130.298698)
		(width 0.1651)
		(layer "F.Cu")
		(net "M_D_CLK_DP<0>")
	)
	(segment
		(start 260.796278 -117.120924)
		(end 260.796278 -118.080282)
		(width 0.1651)
		(layer "F.Cu")
		(net "M_D_CLK_DP<0>")
	)
	(segment
		(start 260.796278 -118.080282)
		(end 259.4991 -119.37746)
		(width 0.1651)
		(layer "F.Cu")
		(net "M_D_CLK_DP<0>")
	)
	(segment
		(start 256.749804 -133.0706)
		(end 256.750312 -133.0706)
		(width 0.1651)
		(layer "F.Cu")
		(net "M_D_CLK_DP<0>")
	)
	(segment
		(start 260.796278 -117.120924)
		(end 260.796278 -104.158542)
		(width 0.1651)
		(layer "F.Cu")
		(net "M_D_CLK_DP<0>")
	)
	(segment
		(start 257.958336 -122.852688)
		(end 257.958336 -123.437904)
		(width 0.1651)
		(layer "F.Cu")
		(net "M_D_CLK_DP<0>")
	)
	(segment
		(start 260.796278 -104.136444)
		(end 260.847078 -104.085644)
		(width 0.0889)
		(layer "F.Cu")
		(net "M_D_CLK_DP<0>")
	)
	(segment
		(start 258.781804 -101.952044)
		(end 258.781804 -101.497892)
		(width 0.0889)
		(layer "F.Cu")
		(net "M_D_CLK_DP<0>")
	)
	(segment
		(start 258.781804 -101.497892)
		(end 258.846828 -101.365304)
		(width 0.0889)
		(layer "F.Cu")
		(net "M_D_CLK_DP<0>")
	)
	(segment
		(start 260.007354 -121.843546)
		(end 260.172454 -122.008646)
		(width 0.1651)
		(layer "F.Cu")
		(net "M_D_CLK_DP<0>")
	)
	(segment
		(start 258.847336 -101.364542)
		(end 258.8514 -101.357938)
		(width 0.0889)
		(layer "F.Cu")
		(net "M_D_CLK_DP<0>")
	)
	(segment
		(start 260.796278 -104.158542)
		(end 260.796278 -104.136444)
		(width 0.0889)
		(layer "F.Cu")
		(net "M_D_CLK_DP<0>")
	)
	(segment
		(start 258.294378 -123.773946)
		(end 259.126228 -123.773946)
		(width 0.1651)
		(layer "F.Cu")
		(net "M_D_CLK_DP<0>")
	)
	(segment
		(start 256.749804 -132.404104)
		(end 256.749804 -133.0706)
		(width 0.1651)
		(layer "F.Cu")
		(net "M_D_CLK_DP<0>")
	)
	(segment
		(start 259.334 -120.586246)
		(end 258.294378 -120.586246)
		(width 0.1651)
		(layer "F.Cu")
		(net "M_D_CLK_DP<0>")
	)
	(segment
		(start 258.846828 -101.365304)
		(end 258.847082 -101.364542)
		(width 0.0889)
		(layer "F.Cu")
		(net "M_D_CLK_DP<0>")
	)
	(segment
		(start 258.294378 -121.843546)
		(end 260.007354 -121.843546)
		(width 0.1651)
		(layer "F.Cu")
		(net "M_D_CLK_DP<0>")
	)
	(segment
		(start 258.294378 -122.516646)
		(end 257.958336 -122.852688)
		(width 0.1651)
		(layer "F.Cu")
		(net "M_D_CLK_DP<0>")
	)
	(segment
		(start 257.958336 -121.507504)
		(end 258.294378 -121.843546)
		(width 0.1651)
		(layer "F.Cu")
		(net "M_D_CLK_DP<0>")
	)
	(segment
		(start 257.958336 -123.437904)
		(end 258.294378 -123.773946)
		(width 0.1651)
		(layer "F.Cu")
		(net "M_D_CLK_DP<0>")
	)
	(segment
		(start 257.225038 -131.92887)
		(end 256.749804 -132.404104)
		(width 0.1651)
		(layer "F.Cu")
		(net "M_D_CLK_DP<0>")
	)
	(segment
		(start 258.05003 -131.643374)
		(end 257.593338 -131.643374)
		(width 0.1651)
		(layer "F.Cu")
		(net "M_D_CLK_DP<0>")
	)
	(segment
		(start 260.847078 -104.085644)
		(end 260.847078 -104.017318)
		(width 0.0889)
		(layer "F.Cu")
		(net "M_D_CLK_DP<0>")
	)
	(segment
		(start 259.394706 -130.298698)
		(end 258.05003 -131.643374)
		(width 0.1651)
		(layer "F.Cu")
		(net "M_D_CLK_DP<0>")
	)
	(segment
		(start 258.98348 -100.209096)
		(end 259.19557 -100.031296)
		(width 0.0889)
		(layer "F.Cu")
		(net "M_D_CLK_DP<0>")
	)
	(segment
		(start 260.172454 -122.008646)
		(end 260.172454 -122.351546)
		(width 0.1651)
		(layer "F.Cu")
		(net "M_D_CLK_DP<0>")
	)
	(segment
		(start 258.8514 -101.357938)
		(end 258.856226 -101.349302)
		(width 0.0889)
		(layer "F.Cu")
		(net "M_D_CLK_DP<0>")
	)
	(segment
		(start 257.958336 -120.922288)
		(end 257.958336 -121.507504)
		(width 0.1651)
		(layer "F.Cu")
		(net "M_D_CLK_DP<0>")
	)
	(segment
		(start 257.307842 -131.92887)
		(end 257.225038 -131.92887)
		(width 0.1651)
		(layer "F.Cu")
		(net "M_D_CLK_DP<0>")
	)
	(segment
		(start 259.4991 -120.421146)
		(end 259.334 -120.586246)
		(width 0.1651)
		(layer "F.Cu")
		(net "M_D_CLK_DP<0>")
	)
	(segment
		(start 259.4991 -119.37746)
		(end 259.4991 -120.421146)
		(width 0.1651)
		(layer "F.Cu")
		(net "M_D_CLK_DP<0>")
	)
	(segment
		(start 257.593338 -131.643374)
		(end 257.307842 -131.92887)
		(width 0.1651)
		(layer "F.Cu")
		(net "M_D_CLK_DP<0>")
	)
	(segment
		(start 260.847078 -104.017318)
		(end 258.781804 -101.952044)
		(width 0.0889)
		(layer "F.Cu")
		(net "M_D_CLK_DP<0>")
	)
	(segment
		(start 258.294378 -120.586246)
		(end 257.958336 -120.922288)
		(width 0.1651)
		(layer "F.Cu")
		(net "M_D_CLK_DP<0>")
	)
	(segment
		(start 260.007354 -122.516646)
		(end 258.294378 -122.516646)
		(width 0.1651)
		(layer "F.Cu")
		(net "M_D_CLK_DP<0>")
	)
	(segment
		(start 258.847082 -101.364542)
		(end 258.847336 -101.364542)
		(width 0.0889)
		(layer "F.Cu")
		(net "M_D_CLK_DP<0>")
	)
	(segment
		(start 260.172454 -122.351546)
		(end 260.007354 -122.516646)
		(width 0.1651)
		(layer "F.Cu")
		(net "M_D_CLK_DP<0>")
	)
	(segment
		(start 259.126228 -123.773946)
		(end 259.394706 -124.042424)
		(width 0.1651)
		(layer "F.Cu")
		(net "M_D_CLK_DP<0>")
	)
	(via
		(at 260.796278 -117.120924)
		(size 0.508)
		(drill 0.254)
		(layers "F.Cu" "B.Cu")
		(net "M_D_CLK_DP<0>")
	)
	(arc
		(start 258.856226 -101.349302)
		(mid 258.904981 -101.15295)
		(end 258.8514 -100.957888)
		(width 0.0889)
		(layer "F.Cu")
		(net "M_D_CLK_DP<0>")
	)
	(arc
		(start 258.8514 -100.957888)
		(mid 258.780952 -100.559394)
		(end 258.98348 -100.209096)
		(width 0.0889)
		(layer "F.Cu")
		(net "M_D_CLK_DP<0>")
	)
	(arc
		(start 259.19557 -100.031296)
		(mid 259.319217 -99.870311)
		(end 259.36321 -99.67214)
		(width 0.0889)
		(layer "F.Cu")
		(net "M_D_CLK_DP<0>")
	)
	(segment
		(start 259.897372 -114.692176)
		(end 259.998972 -114.793776)
		(width 0.1651)
		(layer "F.Cu")
		(net "M_D_CLK_DN<3>")
	)
	(segment
		(start 259.897372 -114.196876)
		(end 259.897372 -114.692176)
		(width 0.1651)
		(layer "F.Cu")
		(net "M_D_CLK_DN<3>")
	)
	(segment
		(start 257.64617 -101.653086)
		(end 257.800856 -101.4984)
		(width 0.0889)
		(layer "F.Cu")
		(net "M_D_CLK_DN<3>")
	)
	(segment
		(start 257.609086 -119.896636)
		(end 257.25882 -120.246902)
		(width 0.1651)
		(layer "F.Cu")
		(net "M_D_CLK_DN<3>")
	)
	(segment
		(start 257.25882 -120.246902)
		(end 257.25882 -120.416828)
		(width 0.1651)
		(layer "F.Cu")
		(net "M_D_CLK_DN<3>")
	)
	(segment
		(start 258.202684 -125.06198)
		(end 258.037584 -125.22708)
		(width 0.1651)
		(layer "F.Cu")
		(net "M_D_CLK_DN<3>")
	)
	(segment
		(start 259.998972 -115.289076)
		(end 259.897372 -115.390676)
		(width 0.1651)
		(layer "F.Cu")
		(net "M_D_CLK_DN<3>")
	)
	(segment
		(start 256.90195 -121.73077)
		(end 256.775458 -121.857262)
		(width 0.1651)
		(layer "F.Cu")
		(net "M_D_CLK_DN<3>")
	)
	(segment
		(start 259.897372 -111.809276)
		(end 259.897372 -112.304576)
		(width 0.1651)
		(layer "F.Cu")
		(net "M_D_CLK_DN<3>")
	)
	(segment
		(start 256.90195 -125.563122)
		(end 256.90195 -126.148338)
		(width 0.1651)
		(layer "F.Cu")
		(net "M_D_CLK_DN<3>")
	)
	(segment
		(start 259.897372 -115.390676)
		(end 259.897372 -115.885976)
		(width 0.1651)
		(layer "F.Cu")
		(net "M_D_CLK_DN<3>")
	)
	(segment
		(start 259.998972 -104.180132)
		(end 259.998972 -110.513876)
		(width 0.1651)
		(layer "F.Cu")
		(net "M_D_CLK_DN<3>")
	)
	(segment
		(start 259.998972 -114.793776)
		(end 259.998972 -115.289076)
		(width 0.1651)
		(layer "F.Cu")
		(net "M_D_CLK_DN<3>")
	)
	(segment
		(start 256.90195 -122.479054)
		(end 256.90195 -122.974354)
		(width 0.1651)
		(layer "F.Cu")
		(net "M_D_CLK_DN<3>")
	)
	(segment
		(start 259.897372 -110.615476)
		(end 259.897372 -111.110776)
		(width 0.1651)
		(layer "F.Cu")
		(net "M_D_CLK_DN<3>")
	)
	(segment
		(start 259.897372 -113.003076)
		(end 259.897372 -113.498376)
		(width 0.1651)
		(layer "F.Cu")
		(net "M_D_CLK_DN<3>")
	)
	(segment
		(start 258.076954 -102.01783)
		(end 260.0452 -103.986076)
		(width 0.0889)
		(layer "F.Cu")
		(net "M_D_CLK_DN<3>")
	)
	(segment
		(start 258.037584 -125.22708)
		(end 257.237992 -125.22708)
		(width 0.1651)
		(layer "F.Cu")
		(net "M_D_CLK_DN<3>")
	)
	(segment
		(start 256.775458 -122.352562)
		(end 256.90195 -122.479054)
		(width 0.1651)
		(layer "F.Cu")
		(net "M_D_CLK_DN<3>")
	)
	(segment
		(start 256.775458 -123.596146)
		(end 256.90195 -123.722638)
		(width 0.1651)
		(layer "F.Cu")
		(net "M_D_CLK_DN<3>")
	)
	(segment
		(start 258.97459 -118.701058)
		(end 258.651502 -119.024146)
		(width 0.1651)
		(layer "F.Cu")
		(net "M_D_CLK_DN<3>")
	)
	(segment
		(start 259.998972 -110.513876)
		(end 259.897372 -110.615476)
		(width 0.1651)
		(layer "F.Cu")
		(net "M_D_CLK_DN<3>")
	)
	(segment
		(start 258.149598 -119.52605)
		(end 257.779012 -119.896636)
		(width 0.1651)
		(layer "F.Cu")
		(net "M_D_CLK_DN<3>")
	)
	(segment
		(start 256.90195 -124.217938)
		(end 257.237992 -124.55398)
		(width 0.1651)
		(layer "F.Cu")
		(net "M_D_CLK_DN<3>")
	)
	(segment
		(start 256.90195 -122.974354)
		(end 256.775458 -123.100846)
		(width 0.1651)
		(layer "F.Cu")
		(net "M_D_CLK_DN<3>")
	)
	(segment
		(start 259.998972 -117.676676)
		(end 259.439664 -118.235984)
		(width 0.1651)
		(layer "F.Cu")
		(net "M_D_CLK_DN<3>")
	)
	(segment
		(start 256.90195 -123.722638)
		(end 256.90195 -124.217938)
		(width 0.1651)
		(layer "F.Cu")
		(net "M_D_CLK_DN<3>")
	)
	(segment
		(start 256.90195 -120.773698)
		(end 256.90195 -121.73077)
		(width 0.1651)
		(layer "F.Cu")
		(net "M_D_CLK_DN<3>")
	)
	(segment
		(start 259.998972 -112.406176)
		(end 259.998972 -112.901476)
		(width 0.1651)
		(layer "F.Cu")
		(net "M_D_CLK_DN<3>")
	)
	(segment
		(start 259.439664 -118.235984)
		(end 259.32511 -118.235984)
		(width 0.1651)
		(layer "F.Cu")
		(net "M_D_CLK_DN<3>")
	)
	(segment
		(start 256.775458 -121.857262)
		(end 256.775458 -122.352562)
		(width 0.1651)
		(layer "F.Cu")
		(net "M_D_CLK_DN<3>")
	)
	(segment
		(start 259.998972 -115.987576)
		(end 259.998972 -116.482876)
		(width 0.1651)
		(layer "F.Cu")
		(net "M_D_CLK_DN<3>")
	)
	(segment
		(start 257.458972 -130.0861)
		(end 257.32613 -129.953258)
		(width 0.1651)
		(layer "F.Cu")
		(net "M_D_CLK_DN<3>")
	)
	(segment
		(start 257.32613 -129.953258)
		(end 257.32613 -129.766568)
		(width 0.1651)
		(layer "F.Cu")
		(net "M_D_CLK_DN<3>")
	)
	(segment
		(start 259.998972 -111.707676)
		(end 259.897372 -111.809276)
		(width 0.1651)
		(layer "F.Cu")
		(net "M_D_CLK_DN<3>")
	)
	(segment
		(start 258.076954 -101.590094)
		(end 258.076954 -102.01783)
		(width 0.0889)
		(layer "F.Cu")
		(net "M_D_CLK_DN<3>")
	)
	(segment
		(start 258.321556 -130.0861)
		(end 257.458972 -130.0861)
		(width 0.1651)
		(layer "F.Cu")
		(net "M_D_CLK_DN<3>")
	)
	(segment
		(start 259.897372 -117.079776)
		(end 259.998972 -117.181376)
		(width 0.1651)
		(layer "F.Cu")
		(net "M_D_CLK_DN<3>")
	)
	(segment
		(start 257.237992 -124.55398)
		(end 258.037584 -124.55398)
		(width 0.1651)
		(layer "F.Cu")
		(net "M_D_CLK_DN<3>")
	)
	(segment
		(start 260.0452 -104.115616)
		(end 259.998972 -104.161844)
		(width 0.0889)
		(layer "F.Cu")
		(net "M_D_CLK_DN<3>")
	)
	(segment
		(start 259.998972 -114.095276)
		(end 259.897372 -114.196876)
		(width 0.1651)
		(layer "F.Cu")
		(net "M_D_CLK_DN<3>")
	)
	(segment
		(start 258.149598 -119.374412)
		(end 258.149598 -119.52605)
		(width 0.1651)
		(layer "F.Cu")
		(net "M_D_CLK_DN<3>")
	)
	(segment
		(start 258.499864 -119.024146)
		(end 258.149598 -119.374412)
		(width 0.1651)
		(layer "F.Cu")
		(net "M_D_CLK_DN<3>")
	)
	(segment
		(start 258.037584 -124.55398)
		(end 258.202684 -124.71908)
		(width 0.1651)
		(layer "F.Cu")
		(net "M_D_CLK_DN<3>")
	)
	(segment
		(start 257.779012 -119.896636)
		(end 257.609086 -119.896636)
		(width 0.1651)
		(layer "F.Cu")
		(net "M_D_CLK_DN<3>")
	)
	(segment
		(start 258.657852 -129.749804)
		(end 258.321556 -130.0861)
		(width 0.1651)
		(layer "F.Cu")
		(net "M_D_CLK_DN<3>")
	)
	(segment
		(start 259.897372 -115.885976)
		(end 259.998972 -115.987576)
		(width 0.1651)
		(layer "F.Cu")
		(net "M_D_CLK_DN<3>")
	)
	(segment
		(start 258.657852 -129.182622)
		(end 258.657852 -129.749804)
		(width 0.1651)
		(layer "F.Cu")
		(net "M_D_CLK_DN<3>")
	)
	(segment
		(start 259.897372 -116.584476)
		(end 259.897372 -117.079776)
		(width 0.1651)
		(layer "F.Cu")
		(net "M_D_CLK_DN<3>")
	)
	(segment
		(start 257.25882 -120.416828)
		(end 256.90195 -120.773698)
		(width 0.1651)
		(layer "F.Cu")
		(net "M_D_CLK_DN<3>")
	)
	(segment
		(start 258.97459 -118.586504)
		(end 258.97459 -118.701058)
		(width 0.1651)
		(layer "F.Cu")
		(net "M_D_CLK_DN<3>")
	)
	(segment
		(start 258.202684 -124.71908)
		(end 258.202684 -125.06198)
		(width 0.1651)
		(layer "F.Cu")
		(net "M_D_CLK_DN<3>")
	)
	(segment
		(start 258.2545 -128.77927)
		(end 258.657852 -129.182622)
		(width 0.1651)
		(layer "F.Cu")
		(net "M_D_CLK_DN<3>")
	)
	(segment
		(start 256.775458 -123.100846)
		(end 256.775458 -123.596146)
		(width 0.1651)
		(layer "F.Cu")
		(net "M_D_CLK_DN<3>")
	)
	(segment
		(start 259.998972 -112.901476)
		(end 259.897372 -113.003076)
		(width 0.1651)
		(layer "F.Cu")
		(net "M_D_CLK_DN<3>")
	)
	(segment
		(start 257.348736 -128.77927)
		(end 258.2545 -128.77927)
		(width 0.1651)
		(layer "F.Cu")
		(net "M_D_CLK_DN<3>")
	)
	(segment
		(start 257.32613 -129.766568)
		(end 257.523742 -129.568956)
		(width 0.1651)
		(layer "F.Cu")
		(net "M_D_CLK_DN<3>")
	)
	(segment
		(start 259.998972 -104.161844)
		(end 259.998972 -104.180132)
		(width 0.0889)
		(layer "F.Cu")
		(net "M_D_CLK_DN<3>")
	)
	(segment
		(start 257.98526 -101.4984)
		(end 258.076954 -101.590094)
		(width 0.0889)
		(layer "F.Cu")
		(net "M_D_CLK_DN<3>")
	)
	(segment
		(start 257.237992 -127.15748)
		(end 256.90195 -127.493522)
		(width 0.1651)
		(layer "F.Cu")
		(net "M_D_CLK_DN<3>")
	)
	(segment
		(start 259.897372 -113.498376)
		(end 259.998972 -113.599976)
		(width 0.1651)
		(layer "F.Cu")
		(net "M_D_CLK_DN<3>")
	)
	(segment
		(start 257.237992 -125.22708)
		(end 256.90195 -125.563122)
		(width 0.1651)
		(layer "F.Cu")
		(net "M_D_CLK_DN<3>")
	)
	(segment
		(start 259.998972 -113.599976)
		(end 259.998972 -114.095276)
		(width 0.1651)
		(layer "F.Cu")
		(net "M_D_CLK_DN<3>")
	)
	(segment
		(start 259.32511 -118.235984)
		(end 258.97459 -118.586504)
		(width 0.1651)
		(layer "F.Cu")
		(net "M_D_CLK_DN<3>")
	)
	(segment
		(start 258.202684 -126.64948)
		(end 258.202684 -126.99238)
		(width 0.1651)
		(layer "F.Cu")
		(net "M_D_CLK_DN<3>")
	)
	(segment
		(start 257.800856 -101.4984)
		(end 257.98526 -101.4984)
		(width 0.0889)
		(layer "F.Cu")
		(net "M_D_CLK_DN<3>")
	)
	(segment
		(start 259.998972 -111.212376)
		(end 259.998972 -111.707676)
		(width 0.1651)
		(layer "F.Cu")
		(net "M_D_CLK_DN<3>")
	)
	(segment
		(start 257.237992 -126.48438)
		(end 258.037584 -126.48438)
		(width 0.1651)
		(layer "F.Cu")
		(net "M_D_CLK_DN<3>")
	)
	(segment
		(start 256.90195 -128.332484)
		(end 257.348736 -128.77927)
		(width 0.1651)
		(layer "F.Cu")
		(net "M_D_CLK_DN<3>")
	)
	(segment
		(start 260.0452 -103.986076)
		(end 260.0452 -104.115616)
		(width 0.0889)
		(layer "F.Cu")
		(net "M_D_CLK_DN<3>")
	)
	(segment
		(start 259.897372 -111.110776)
		(end 259.998972 -111.212376)
		(width 0.1651)
		(layer "F.Cu")
		(net "M_D_CLK_DN<3>")
	)
	(segment
		(start 259.897372 -112.304576)
		(end 259.998972 -112.406176)
		(width 0.1651)
		(layer "F.Cu")
		(net "M_D_CLK_DN<3>")
	)
	(segment
		(start 258.037584 -127.15748)
		(end 257.237992 -127.15748)
		(width 0.1651)
		(layer "F.Cu")
		(net "M_D_CLK_DN<3>")
	)
	(segment
		(start 258.202684 -126.99238)
		(end 258.037584 -127.15748)
		(width 0.1651)
		(layer "F.Cu")
		(net "M_D_CLK_DN<3>")
	)
	(segment
		(start 259.998972 -116.482876)
		(end 259.897372 -116.584476)
		(width 0.1651)
		(layer "F.Cu")
		(net "M_D_CLK_DN<3>")
	)
	(segment
		(start 258.037584 -126.48438)
		(end 258.202684 -126.64948)
		(width 0.1651)
		(layer "F.Cu")
		(net "M_D_CLK_DN<3>")
	)
	(segment
		(start 256.90195 -127.493522)
		(end 256.90195 -128.332484)
		(width 0.1651)
		(layer "F.Cu")
		(net "M_D_CLK_DN<3>")
	)
	(segment
		(start 259.998972 -117.181376)
		(end 259.998972 -117.676676)
		(width 0.1651)
		(layer "F.Cu")
		(net "M_D_CLK_DN<3>")
	)
	(segment
		(start 256.90195 -126.148338)
		(end 257.237992 -126.48438)
		(width 0.1651)
		(layer "F.Cu")
		(net "M_D_CLK_DN<3>")
	)
	(segment
		(start 258.651502 -119.024146)
		(end 258.499864 -119.024146)
		(width 0.1651)
		(layer "F.Cu")
		(net "M_D_CLK_DN<3>")
	)
	(via
		(at 257.523742 -129.568956)
		(size 0.508)
		(drill 0.254)
		(layers "F.Cu" "B.Cu")
		(net "M_D_CLK_DN<3>")
	)
	(segment
		(start 257.60045 -128.276096)
		(end 257.599942 -128.276096)
		(width 0.1651)
		(layer "B.Cu")
		(net "M_D_CLK_DN<3>")
	)
	(segment
		(start 257.599942 -128.276096)
		(end 257.599942 -129.492756)
		(width 0.1651)
		(layer "B.Cu")
		(net "M_D_CLK_DN<3>")
	)
	(segment
		(start 257.599942 -129.492756)
		(end 257.523742 -129.568956)
		(width 0.1651)
		(layer "B.Cu")
		(net "M_D_CLK_DN<3>")
	)
	(segment
		(start 260.8072 -130.244342)
		(end 261.3025 -130.739642)
		(width 0.1651)
		(layer "F.Cu")
		(net "M_D_CLK_DN<1>")
	)
	(segment
		(start 261.848854 -103.655368)
		(end 261.848854 -104.099106)
		(width 0.0889)
		(layer "F.Cu")
		(net "M_D_CLK_DN<1>")
	)
	(segment
		(start 259.36321 -101.653086)
		(end 259.476748 -101.539294)
		(width 0.0889)
		(layer "F.Cu")
		(net "M_D_CLK_DN<1>")
	)
	(segment
		(start 261.3025 -130.739642)
		(end 261.3025 -133.108446)
		(width 0.1651)
		(layer "F.Cu")
		(net "M_D_CLK_DN<1>")
	)
	(segment
		(start 257.632962 -135.548116)
		(end 257.320796 -135.860282)
		(width 0.1651)
		(layer "F.Cu")
		(net "M_D_CLK_DN<1>")
	)
	(segment
		(start 260.8072 -123.582938)
		(end 260.8072 -126.447296)
		(width 0.1651)
		(layer "F.Cu")
		(net "M_D_CLK_DN<1>")
	)
	(segment
		(start 261.3025 -133.108446)
		(end 258.86283 -135.548116)
		(width 0.1651)
		(layer "F.Cu")
		(net "M_D_CLK_DN<1>")
	)
	(segment
		(start 257.599942 -137.67054)
		(end 257.60045 -137.67054)
		(width 0.1651)
		(layer "F.Cu")
		(net "M_D_CLK_DN<1>")
	)
	(segment
		(start 258.86283 -135.548116)
		(end 257.632962 -135.548116)
		(width 0.1651)
		(layer "F.Cu")
		(net "M_D_CLK_DN<1>")
	)
	(segment
		(start 261.307326 -119.389398)
		(end 261.307326 -123.082812)
		(width 0.1651)
		(layer "F.Cu")
		(net "M_D_CLK_DN<1>")
	)
	(segment
		(start 260.667754 -101.586538)
		(end 260.667754 -102.474268)
		(width 0.0889)
		(layer "F.Cu")
		(net "M_D_CLK_DN<1>")
	)
	(segment
		(start 261.901432 -104.173782)
		(end 261.901432 -118.795292)
		(width 0.1651)
		(layer "F.Cu")
		(net "M_D_CLK_DN<1>")
	)
	(segment
		(start 260.667754 -102.474268)
		(end 261.848854 -103.655368)
		(width 0.0889)
		(layer "F.Cu")
		(net "M_D_CLK_DN<1>")
	)
	(segment
		(start 257.320796 -135.860282)
		(end 257.320796 -136.27862)
		(width 0.1651)
		(layer "F.Cu")
		(net "M_D_CLK_DN<1>")
	)
	(segment
		(start 261.901432 -118.795292)
		(end 261.307326 -119.389398)
		(width 0.1651)
		(layer "F.Cu")
		(net "M_D_CLK_DN<1>")
	)
	(segment
		(start 260.73989 -101.44252)
		(end 260.739128 -101.44379)
		(width 0.0889)
		(layer "F.Cu")
		(net "M_D_CLK_DN<1>")
	)
	(segment
		(start 261.901432 -104.151684)
		(end 261.901432 -104.173782)
		(width 0.0889)
		(layer "F.Cu")
		(net "M_D_CLK_DN<1>")
	)
	(segment
		(start 261.848854 -104.099106)
		(end 261.901432 -104.151684)
		(width 0.0889)
		(layer "F.Cu")
		(net "M_D_CLK_DN<1>")
	)
	(segment
		(start 257.599942 -136.557766)
		(end 257.599942 -137.67054)
		(width 0.1651)
		(layer "F.Cu")
		(net "M_D_CLK_DN<1>")
	)
	(segment
		(start 260.739128 -101.44379)
		(end 260.667754 -101.586538)
		(width 0.0889)
		(layer "F.Cu")
		(net "M_D_CLK_DN<1>")
	)
	(segment
		(start 260.8072 -126.447296)
		(end 260.8072 -130.244342)
		(width 0.1651)
		(layer "F.Cu")
		(net "M_D_CLK_DN<1>")
	)
	(segment
		(start 257.320796 -136.27862)
		(end 257.599942 -136.557766)
		(width 0.1651)
		(layer "F.Cu")
		(net "M_D_CLK_DN<1>")
	)
	(segment
		(start 261.307326 -123.082812)
		(end 260.8072 -123.582938)
		(width 0.1651)
		(layer "F.Cu")
		(net "M_D_CLK_DN<1>")
	)
	(via
		(at 260.8072 -126.447296)
		(size 0.508)
		(drill 0.254)
		(layers "F.Cu" "B.Cu")
		(net "M_D_CLK_DN<1>")
	)
	(arc
		(start 259.476748 -101.539294)
		(mid 259.590828 -101.3687)
		(end 259.630926 -101.167438)
		(width 0.0889)
		(layer "F.Cu")
		(net "M_D_CLK_DN<1>")
	)
	(arc
		(start 259.630926 -101.167438)
		(mid 259.7324 -100.82684)
		(end 260.01091 -100.606098)
		(width 0.0889)
		(layer "F.Cu")
		(net "M_D_CLK_DN<1>")
	)
	(arc
		(start 260.01091 -100.606098)
		(mid 260.667174 -100.769884)
		(end 260.73989 -101.44252)
		(width 0.0889)
		(layer "F.Cu")
		(net "M_D_CLK_DN<1>")
	)
	(segment
		(start 257.523742 -130.848608)
		(end 257.291078 -131.081272)
		(width 0.1651)
		(layer "F.Cu")
		(net "M_D_CLK_DN<2>")
	)
	(segment
		(start 255.800098 -131.632452)
		(end 255.44272 -131.275074)
		(width 0.1651)
		(layer "F.Cu")
		(net "M_D_CLK_DN<2>")
	)
	(segment
		(start 257.067304 -101.47427)
		(end 257.13436 -101.357938)
		(width 0.0889)
		(layer "F.Cu")
		(net "M_D_CLK_DN<2>")
	)
	(segment
		(start 255.7907 -120.35282)
		(end 259.087874 -117.055646)
		(width 0.1651)
		(layer "F.Cu")
		(net "M_D_CLK_DN<2>")
	)
	(segment
		(start 259.138674 -104.112568)
		(end 257.067304 -102.041198)
		(width 0.0889)
		(layer "F.Cu")
		(net "M_D_CLK_DN<2>")
	)
	(segment
		(start 255.513586 -130.48869)
		(end 255.513586 -130.02895)
		(width 0.1651)
		(layer "F.Cu")
		(net "M_D_CLK_DN<2>")
	)
	(segment
		(start 255.513586 -130.02895)
		(end 255.41605 -129.931414)
		(width 0.1651)
		(layer "F.Cu")
		(net "M_D_CLK_DN<2>")
	)
	(segment
		(start 255.44272 -130.559556)
		(end 255.513586 -130.48869)
		(width 0.1651)
		(layer "F.Cu")
		(net "M_D_CLK_DN<2>")
	)
	(segment
		(start 258.009644 -98.853498)
		(end 258.201414 -98.55962)
		(width 0.0889)
		(layer "F.Cu")
		(net "M_D_CLK_DN<2>")
	)
	(segment
		(start 255.41605 -129.931414)
		(end 255.41605 -128.954022)
		(width 0.1651)
		(layer "F.Cu")
		(net "M_D_CLK_DN<2>")
	)
	(segment
		(start 255.44272 -131.275074)
		(end 255.44272 -130.559556)
		(width 0.1651)
		(layer "F.Cu")
		(net "M_D_CLK_DN<2>")
	)
	(segment
		(start 257.067304 -102.041198)
		(end 257.067304 -101.47427)
		(width 0.0889)
		(layer "F.Cu")
		(net "M_D_CLK_DN<2>")
	)
	(segment
		(start 256.923794 -131.632452)
		(end 255.800098 -131.632452)
		(width 0.1651)
		(layer "F.Cu")
		(net "M_D_CLK_DN<2>")
	)
	(segment
		(start 257.997706 -100.471224)
		(end 257.99288 -100.462588)
		(width 0.0889)
		(layer "F.Cu")
		(net "M_D_CLK_DN<2>")
	)
	(segment
		(start 257.291078 -131.081272)
		(end 257.291078 -131.265168)
		(width 0.1651)
		(layer "F.Cu")
		(net "M_D_CLK_DN<2>")
	)
	(segment
		(start 259.087874 -117.055646)
		(end 259.087874 -104.26446)
		(width 0.1651)
		(layer "F.Cu")
		(net "M_D_CLK_DN<2>")
	)
	(segment
		(start 257.291078 -131.265168)
		(end 256.923794 -131.632452)
		(width 0.1651)
		(layer "F.Cu")
		(net "M_D_CLK_DN<2>")
	)
	(segment
		(start 257.632454 -101.062536)
		(end 257.661156 -101.062536)
		(width 0.0889)
		(layer "F.Cu")
		(net "M_D_CLK_DN<2>")
	)
	(segment
		(start 259.138674 -104.21366)
		(end 259.138674 -104.112568)
		(width 0.0889)
		(layer "F.Cu")
		(net "M_D_CLK_DN<2>")
	)
	(segment
		(start 259.087874 -104.26446)
		(end 259.138674 -104.21366)
		(width 0.0889)
		(layer "F.Cu")
		(net "M_D_CLK_DN<2>")
	)
	(segment
		(start 255.7907 -128.579372)
		(end 255.7907 -120.35282)
		(width 0.1651)
		(layer "F.Cu")
		(net "M_D_CLK_DN<2>")
	)
	(segment
		(start 257.98653 -99.882706)
		(end 257.99288 -99.872038)
		(width 0.0889)
		(layer "F.Cu")
		(net "M_D_CLK_DN<2>")
	)
	(segment
		(start 255.41605 -128.954022)
		(end 255.7907 -128.579372)
		(width 0.1651)
		(layer "F.Cu")
		(net "M_D_CLK_DN<2>")
	)
	(via
		(at 257.523742 -130.848608)
		(size 0.508)
		(drill 0.254)
		(layers "F.Cu" "B.Cu")
		(net "M_D_CLK_DN<2>")
	)
	(arc
		(start 257.661156 -101.062536)
		(mid 257.994074 -100.860545)
		(end 257.997706 -100.471224)
		(width 0.0889)
		(layer "F.Cu")
		(net "M_D_CLK_DN<2>")
	)
	(arc
		(start 257.13436 -101.357938)
		(mid 257.344713 -101.144966)
		(end 257.632454 -101.062536)
		(width 0.0889)
		(layer "F.Cu")
		(net "M_D_CLK_DN<2>")
	)
	(arc
		(start 257.99288 -99.472242)
		(mid 257.913806 -99.160513)
		(end 258.009644 -98.853498)
		(width 0.0889)
		(layer "F.Cu")
		(net "M_D_CLK_DN<2>")
	)
	(arc
		(start 258.201414 -98.55962)
		(mid 258.343388 -98.365081)
		(end 258.50469 -98.18624)
		(width 0.0889)
		(layer "F.Cu")
		(net "M_D_CLK_DN<2>")
	)
	(arc
		(start 257.99288 -99.872038)
		(mid 258.046379 -99.67214)
		(end 257.99288 -99.472242)
		(width 0.0889)
		(layer "F.Cu")
		(net "M_D_CLK_DN<2>")
	)
	(arc
		(start 257.99288 -100.462588)
		(mid 257.913658 -100.17347)
		(end 257.98653 -99.882706)
		(width 0.0889)
		(layer "F.Cu")
		(net "M_D_CLK_DN<2>")
	)
	(segment
		(start 257.599942 -130.924808)
		(end 257.523742 -130.848608)
		(width 0.1651)
		(layer "B.Cu")
		(net "M_D_CLK_DN<2>")
	)
	(segment
		(start 257.60045 -132.876036)
		(end 257.599942 -132.875782)
		(width 0.1651)
		(layer "B.Cu")
		(net "M_D_CLK_DN<2>")
	)
	(segment
		(start 257.599942 -132.875782)
		(end 257.599942 -130.924808)
		(width 0.1651)
		(layer "B.Cu")
		(net "M_D_CLK_DN<2>")
	)
	(segment
		(start 257.60045 -133.0706)
		(end 257.599942 -133.0706)
		(width 0.1651)
		(layer "F.Cu")
		(net "M_D_CLK_DN<0>")
	)
	(segment
		(start 259.774182 -125.609604)
		(end 259.686806 -125.522228)
		(width 0.1651)
		(layer "F.Cu")
		(net "M_D_CLK_DN<0>")
	)
	(segment
		(start 259.783072 -128.490472)
		(end 259.783072 -127.995172)
		(width 0.1651)
		(layer "F.Cu")
		(net "M_D_CLK_DN<0>")
	)
	(segment
		(start 258.250436 -122.973846)
		(end 258.415536 -122.808746)
		(width 0.1651)
		(layer "F.Cu")
		(net "M_D_CLK_DN<0>")
	)
	(segment
		(start 260.464554 -122.472704)
		(end 260.464554 -121.887488)
		(width 0.1651)
		(layer "F.Cu")
		(net "M_D_CLK_DN<0>")
	)
	(segment
		(start 260.621272 -118.668546)
		(end 261.088378 -118.20144)
		(width 0.1651)
		(layer "F.Cu")
		(net "M_D_CLK_DN<0>")
	)
	(segment
		(start 261.037578 -103.938324)
		(end 258.972304 -101.87305)
		(width 0.0889)
		(layer "F.Cu")
		(net "M_D_CLK_DN<0>")
	)
	(segment
		(start 258.250436 -121.386346)
		(end 258.250436 -121.043446)
		(width 0.1651)
		(layer "F.Cu")
		(net "M_D_CLK_DN<0>")
	)
	(segment
		(start 260.128512 -122.808746)
		(end 260.464554 -122.472704)
		(width 0.1651)
		(layer "F.Cu")
		(net "M_D_CLK_DN<0>")
	)
	(segment
		(start 259.7912 -119.498618)
		(end 260.154928 -119.13489)
		(width 0.1651)
		(layer "F.Cu")
		(net "M_D_CLK_DN<0>")
	)
	(segment
		(start 259.455158 -120.878346)
		(end 259.7912 -120.542304)
		(width 0.1651)
		(layer "F.Cu")
		(net "M_D_CLK_DN<0>")
	)
	(segment
		(start 260.154928 -119.13489)
		(end 260.270752 -119.13489)
		(width 0.1651)
		(layer "F.Cu")
		(net "M_D_CLK_DN<0>")
	)
	(segment
		(start 258.972304 -101.542342)
		(end 259.014722 -101.456236)
		(width 0.0889)
		(layer "F.Cu")
		(net "M_D_CLK_DN<0>")
	)
	(segment
		(start 259.774182 -126.104904)
		(end 259.774182 -125.609604)
		(width 0.1651)
		(layer "F.Cu")
		(net "M_D_CLK_DN<0>")
	)
	(segment
		(start 257.599942 -133.0706)
		(end 257.599942 -132.050028)
		(width 0.1651)
		(layer "F.Cu")
		(net "M_D_CLK_DN<0>")
	)
	(segment
		(start 261.088378 -104.153462)
		(end 261.037578 -104.102662)
		(width 0.0889)
		(layer "F.Cu")
		(net "M_D_CLK_DN<0>")
	)
	(segment
		(start 259.014722 -101.456236)
		(end 259.02285 -101.44252)
		(width 0.0889)
		(layer "F.Cu")
		(net "M_D_CLK_DN<0>")
	)
	(segment
		(start 259.686806 -126.19228)
		(end 259.774182 -126.104904)
		(width 0.1651)
		(layer "F.Cu")
		(net "M_D_CLK_DN<0>")
	)
	(segment
		(start 259.686806 -124.4981)
		(end 259.686806 -123.921266)
		(width 0.1651)
		(layer "F.Cu")
		(net "M_D_CLK_DN<0>")
	)
	(segment
		(start 259.247386 -123.481846)
		(end 258.415536 -123.481846)
		(width 0.1651)
		(layer "F.Cu")
		(net "M_D_CLK_DN<0>")
	)
	(segment
		(start 259.686806 -127.385064)
		(end 259.774182 -127.297688)
		(width 0.1651)
		(layer "F.Cu")
		(net "M_D_CLK_DN<0>")
	)
	(segment
		(start 260.621272 -118.78437)
		(end 260.621272 -118.668546)
		(width 0.1651)
		(layer "F.Cu")
		(net "M_D_CLK_DN<0>")
	)
	(segment
		(start 257.714496 -131.935474)
		(end 258.171188 -131.935474)
		(width 0.1651)
		(layer "F.Cu")
		(net "M_D_CLK_DN<0>")
	)
	(segment
		(start 258.250436 -123.316746)
		(end 258.250436 -122.973846)
		(width 0.1651)
		(layer "F.Cu")
		(net "M_D_CLK_DN<0>")
	)
	(segment
		(start 260.128512 -121.551446)
		(end 258.415536 -121.551446)
		(width 0.1651)
		(layer "F.Cu")
		(net "M_D_CLK_DN<0>")
	)
	(segment
		(start 261.088378 -118.20144)
		(end 261.088378 -104.153462)
		(width 0.1651)
		(layer "F.Cu")
		(net "M_D_CLK_DN<0>")
	)
	(segment
		(start 259.7912 -120.542304)
		(end 259.7912 -119.498618)
		(width 0.1651)
		(layer "F.Cu")
		(net "M_D_CLK_DN<0>")
	)
	(segment
		(start 259.686806 -126.715012)
		(end 259.686806 -126.19228)
		(width 0.1651)
		(layer "F.Cu")
		(net "M_D_CLK_DN<0>")
	)
	(segment
		(start 258.415536 -122.808746)
		(end 260.128512 -122.808746)
		(width 0.1651)
		(layer "F.Cu")
		(net "M_D_CLK_DN<0>")
	)
	(segment
		(start 260.464554 -121.887488)
		(end 260.128512 -121.551446)
		(width 0.1651)
		(layer "F.Cu")
		(net "M_D_CLK_DN<0>")
	)
	(segment
		(start 258.171188 -131.935474)
		(end 259.686806 -130.419856)
		(width 0.1651)
		(layer "F.Cu")
		(net "M_D_CLK_DN<0>")
	)
	(segment
		(start 257.599942 -132.050028)
		(end 257.714496 -131.935474)
		(width 0.1651)
		(layer "F.Cu")
		(net "M_D_CLK_DN<0>")
	)
	(segment
		(start 259.774182 -127.297688)
		(end 259.774182 -126.802388)
		(width 0.1651)
		(layer "F.Cu")
		(net "M_D_CLK_DN<0>")
	)
	(segment
		(start 259.774182 -126.802388)
		(end 259.686806 -126.715012)
		(width 0.1651)
		(layer "F.Cu")
		(net "M_D_CLK_DN<0>")
	)
	(segment
		(start 260.270752 -119.13489)
		(end 260.621272 -118.78437)
		(width 0.1651)
		(layer "F.Cu")
		(net "M_D_CLK_DN<0>")
	)
	(segment
		(start 259.29971 -100.267516)
		(end 259.351526 -100.259134)
		(width 0.0889)
		(layer "F.Cu")
		(net "M_D_CLK_DN<0>")
	)
	(segment
		(start 258.415536 -123.481846)
		(end 258.250436 -123.316746)
		(width 0.1651)
		(layer "F.Cu")
		(net "M_D_CLK_DN<0>")
	)
	(segment
		(start 259.491988 -100.533708)
		(end 259.36321 -100.662486)
		(width 0.0889)
		(layer "F.Cu")
		(net "M_D_CLK_DN<0>")
	)
	(segment
		(start 259.686806 -130.419856)
		(end 259.686806 -128.586738)
		(width 0.1651)
		(layer "F.Cu")
		(net "M_D_CLK_DN<0>")
	)
	(segment
		(start 259.686806 -127.898906)
		(end 259.686806 -127.385064)
		(width 0.1651)
		(layer "F.Cu")
		(net "M_D_CLK_DN<0>")
	)
	(segment
		(start 259.783072 -127.995172)
		(end 259.686806 -127.898906)
		(width 0.1651)
		(layer "F.Cu")
		(net "M_D_CLK_DN<0>")
	)
	(segment
		(start 258.415536 -120.878346)
		(end 259.455158 -120.878346)
		(width 0.1651)
		(layer "F.Cu")
		(net "M_D_CLK_DN<0>")
	)
	(segment
		(start 261.037578 -104.102662)
		(end 261.037578 -103.938324)
		(width 0.0889)
		(layer "F.Cu")
		(net "M_D_CLK_DN<0>")
	)
	(segment
		(start 259.686806 -125.522228)
		(end 259.686806 -124.4981)
		(width 0.1651)
		(layer "F.Cu")
		(net "M_D_CLK_DN<0>")
	)
	(segment
		(start 259.686806 -128.586738)
		(end 259.783072 -128.490472)
		(width 0.1651)
		(layer "F.Cu")
		(net "M_D_CLK_DN<0>")
	)
	(segment
		(start 258.250436 -121.043446)
		(end 258.415536 -120.878346)
		(width 0.1651)
		(layer "F.Cu")
		(net "M_D_CLK_DN<0>")
	)
	(segment
		(start 258.415536 -121.551446)
		(end 258.250436 -121.386346)
		(width 0.1651)
		(layer "F.Cu")
		(net "M_D_CLK_DN<0>")
	)
	(segment
		(start 259.686806 -123.921266)
		(end 259.247386 -123.481846)
		(width 0.1651)
		(layer "F.Cu")
		(net "M_D_CLK_DN<0>")
	)
	(segment
		(start 258.972304 -101.87305)
		(end 258.972304 -101.542342)
		(width 0.0889)
		(layer "F.Cu")
		(net "M_D_CLK_DN<0>")
	)
	(via
		(at 259.686806 -124.4981)
		(size 0.508)
		(drill 0.254)
		(layers "F.Cu" "B.Cu")
		(net "M_D_CLK_DN<0>")
	)
	(arc
		(start 259.02285 -101.44252)
		(mid 259.095648 -101.151757)
		(end 259.0165 -100.862638)
		(width 0.0889)
		(layer "F.Cu")
		(net "M_D_CLK_DN<0>")
	)
	(arc
		(start 259.0165 -100.862638)
		(mid 259.001847 -100.490741)
		(end 259.29971 -100.267516)
		(width 0.0889)
		(layer "F.Cu")
		(net "M_D_CLK_DN<0>")
	)
	(arc
		(start 259.351526 -100.259134)
		(mid 259.521743 -100.345313)
		(end 259.491988 -100.533708)
		(width 0.0889)
		(layer "F.Cu")
		(net "M_D_CLK_DN<0>")
	)
	(segment
		(start 246.962676 -118.308882)
		(end 246.962676 -125.462792)
		(width 0.1651)
		(layer "F.Cu")
		(net "M_D_CKE<3>")
	)
	(segment
		(start 251.493274 -100.412296)
		(end 251.4092 -100.589334)
		(width 0.0889)
		(layer "F.Cu")
		(net "M_D_CKE<3>")
	)
	(segment
		(start 251.613416 -101.88194)
		(end 251.613416 -102.332028)
		(width 0.0889)
		(layer "F.Cu")
		(net "M_D_CKE<3>")
	)
	(segment
		(start 251.4092 -101.677724)
		(end 251.613416 -101.88194)
		(width 0.0889)
		(layer "F.Cu")
		(net "M_D_CKE<3>")
	)
	(segment
		(start 246.962676 -125.462792)
		(end 243.999766 -128.425702)
		(width 0.1651)
		(layer "F.Cu")
		(net "M_D_CKE<3>")
	)
	(segment
		(start 251.717556 -100.257102)
		(end 251.493274 -100.412296)
		(width 0.0889)
		(layer "F.Cu")
		(net "M_D_CKE<3>")
	)
	(segment
		(start 243.999766 -128.425702)
		(end 243.999766 -129.568956)
		(width 0.1651)
		(layer "F.Cu")
		(net "M_D_CKE<3>")
	)
	(segment
		(start 251.4092 -100.589334)
		(end 251.4092 -101.677724)
		(width 0.0889)
		(layer "F.Cu")
		(net "M_D_CKE<3>")
	)
	(segment
		(start 251.613416 -102.332028)
		(end 251.613416 -113.658142)
		(width 0.1651)
		(layer "F.Cu")
		(net "M_D_CKE<3>")
	)
	(segment
		(start 251.613416 -113.658142)
		(end 246.962676 -118.308882)
		(width 0.1651)
		(layer "F.Cu")
		(net "M_D_CKE<3>")
	)
	(segment
		(start 252.495304 -99.67214)
		(end 251.910342 -100.257102)
		(width 0.0889)
		(layer "F.Cu")
		(net "M_D_CKE<3>")
	)
	(segment
		(start 251.910342 -100.257102)
		(end 251.717556 -100.257102)
		(width 0.0889)
		(layer "F.Cu")
		(net "M_D_CKE<3>")
	)
	(via
		(at 243.999766 -129.568956)
		(size 0.508)
		(drill 0.254)
		(layers "F.Cu" "B.Cu")
		(net "M_D_CKE<3>")
	)
	(segment
		(start 243.999766 -128.276096)
		(end 243.999766 -129.568956)
		(width 0.1651)
		(layer "B.Cu")
		(net "M_D_CKE<3>")
	)
	(segment
		(start 244.000274 -128.276096)
		(end 243.999766 -128.276096)
		(width 0.1651)
		(layer "B.Cu")
		(net "M_D_CKE<3>")
	)
	(segment
		(start 252.145546 -114.058446)
		(end 247.495568 -118.708424)
		(width 0.1651)
		(layer "F.Cu")
		(net "M_D_CKE<2>")
	)
	(segment
		(start 252.073918 -101.976174)
		(end 252.145546 -102.047802)
		(width 0.0889)
		(layer "F.Cu")
		(net "M_D_CKE<2>")
	)
	(segment
		(start 252.895354 -99.781614)
		(end 252.895354 -100.871274)
		(width 0.0889)
		(layer "F.Cu")
		(net "M_D_CKE<2>")
	)
	(segment
		(start 252.073918 -101.50729)
		(end 252.073918 -101.976174)
		(width 0.0889)
		(layer "F.Cu")
		(net "M_D_CKE<2>")
	)
	(segment
		(start 252.439424 -101.141784)
		(end 252.073918 -101.50729)
		(width 0.0889)
		(layer "F.Cu")
		(net "M_D_CKE<2>")
	)
	(segment
		(start 244.5512 -130.6322)
		(end 244.5512 -131.287774)
		(width 0.1651)
		(layer "F.Cu")
		(net "M_D_CKE<2>")
	)
	(segment
		(start 252.624844 -101.141784)
		(end 252.439424 -101.141784)
		(width 0.0889)
		(layer "F.Cu")
		(net "M_D_CKE<2>")
	)
	(segment
		(start 244.5512 -131.287774)
		(end 244.849904 -131.586478)
		(width 0.1651)
		(layer "F.Cu")
		(net "M_D_CKE<2>")
	)
	(segment
		(start 252.145546 -102.047802)
		(end 252.145546 -102.338886)
		(width 0.0889)
		(layer "F.Cu")
		(net "M_D_CKE<2>")
	)
	(segment
		(start 252.145546 -102.338886)
		(end 252.145546 -114.058446)
		(width 0.1651)
		(layer "F.Cu")
		(net "M_D_CKE<2>")
	)
	(segment
		(start 253.353824 -99.17684)
		(end 252.895354 -99.781614)
		(width 0.0889)
		(layer "F.Cu")
		(net "M_D_CKE<2>")
	)
	(segment
		(start 252.895354 -100.871274)
		(end 252.624844 -101.141784)
		(width 0.0889)
		(layer "F.Cu")
		(net "M_D_CKE<2>")
	)
	(segment
		(start 244.2718 -130.3528)
		(end 244.5512 -130.6322)
		(width 0.1651)
		(layer "F.Cu")
		(net "M_D_CKE<2>")
	)
	(segment
		(start 244.5004 -129.7686)
		(end 244.2718 -129.9972)
		(width 0.1651)
		(layer "F.Cu")
		(net "M_D_CKE<2>")
	)
	(segment
		(start 244.2718 -129.9972)
		(end 244.2718 -130.3528)
		(width 0.1651)
		(layer "F.Cu")
		(net "M_D_CKE<2>")
	)
	(segment
		(start 247.495568 -125.70206)
		(end 244.5004 -128.697228)
		(width 0.1651)
		(layer "F.Cu")
		(net "M_D_CKE<2>")
	)
	(segment
		(start 244.5004 -128.697228)
		(end 244.5004 -129.7686)
		(width 0.1651)
		(layer "F.Cu")
		(net "M_D_CKE<2>")
	)
	(segment
		(start 247.495568 -118.708424)
		(end 247.495568 -125.70206)
		(width 0.1651)
		(layer "F.Cu")
		(net "M_D_CKE<2>")
	)
	(via
		(at 244.849904 -131.586478)
		(size 0.508)
		(drill 0.254)
		(layers "F.Cu" "B.Cu")
		(net "M_D_CKE<2>")
	)
	(segment
		(start 244.849904 -132.875782)
		(end 244.849904 -131.586478)
		(width 0.1651)
		(layer "B.Cu")
		(net "M_D_CKE<2>")
	)
	(segment
		(start 244.850412 -132.876036)
		(end 244.849904 -132.875782)
		(width 0.1651)
		(layer "B.Cu")
		(net "M_D_CKE<2>")
	)
	(segment
		(start 252.727968 -102.543356)
		(end 252.727968 -114.353594)
		(width 0.1651)
		(layer "F.Cu")
		(net "M_D_CKE<1>")
	)
	(segment
		(start 252.495304 -101.653086)
		(end 252.727968 -101.88575)
		(width 0.0889)
		(layer "F.Cu")
		(net "M_D_CKE<1>")
	)
	(segment
		(start 243.999766 -137.67054)
		(end 243.999766 -136.387078)
		(width 0.1651)
		(layer "F.Cu")
		(net "M_D_CKE<1>")
	)
	(segment
		(start 248.03862 -119.042942)
		(end 248.03862 -126.28118)
		(width 0.1651)
		(layer "F.Cu")
		(net "M_D_CKE<1>")
	)
	(segment
		(start 252.727968 -101.88575)
		(end 252.727968 -102.543356)
		(width 0.0889)
		(layer "F.Cu")
		(net "M_D_CKE<1>")
	)
	(segment
		(start 252.727968 -114.353594)
		(end 248.03862 -119.042942)
		(width 0.1651)
		(layer "F.Cu")
		(net "M_D_CKE<1>")
	)
	(segment
		(start 244.000274 -137.67054)
		(end 243.999766 -137.67054)
		(width 0.1651)
		(layer "F.Cu")
		(net "M_D_CKE<1>")
	)
	(via
		(at 248.03862 -126.28118)
		(size 0.508)
		(drill 0.254)
		(layers "F.Cu" "B.Cu")
		(net "M_D_CKE<1>")
	)
	(via
		(at 243.999766 -136.387078)
		(size 0.4572)
		(drill 0.2032)
		(layers "F.Cu" "B.Cu")
		(net "M_D_CKE<1>")
	)
	(segment
		(start 247.25122 -126.28118)
		(end 248.03862 -126.28118)
		(width 0.14224)
		(layer "In11.Cu")
		(net "M_D_CKE<1>")
	)
	(segment
		(start 245.3386 -132.115052)
		(end 246.163592 -131.29006)
		(width 0.14224)
		(layer "In11.Cu")
		(net "M_D_CKE<1>")
	)
	(segment
		(start 246.163592 -131.29006)
		(end 246.163592 -130.536442)
		(width 0.14224)
		(layer "In11.Cu")
		(net "M_D_CKE<1>")
	)
	(segment
		(start 246.163592 -130.536442)
		(end 246.081296 -130.454146)
		(width 0.14224)
		(layer "In11.Cu")
		(net "M_D_CKE<1>")
	)
	(segment
		(start 244.43944 -135.947404)
		(end 244.43944 -134.07136)
		(width 0.14224)
		(layer "In11.Cu")
		(net "M_D_CKE<1>")
	)
	(segment
		(start 246.081296 -129.856992)
		(end 246.432324 -129.505964)
		(width 0.14224)
		(layer "In11.Cu")
		(net "M_D_CKE<1>")
	)
	(segment
		(start 243.999766 -136.387078)
		(end 244.43944 -135.947404)
		(width 0.14224)
		(layer "In11.Cu")
		(net "M_D_CKE<1>")
	)
	(segment
		(start 246.081296 -130.454146)
		(end 246.081296 -129.856992)
		(width 0.14224)
		(layer "In11.Cu")
		(net "M_D_CKE<1>")
	)
	(segment
		(start 246.432324 -127.100076)
		(end 247.25122 -126.28118)
		(width 0.14224)
		(layer "In11.Cu")
		(net "M_D_CKE<1>")
	)
	(segment
		(start 245.3386 -133.1722)
		(end 245.3386 -132.115052)
		(width 0.14224)
		(layer "In11.Cu")
		(net "M_D_CKE<1>")
	)
	(segment
		(start 246.432324 -129.505964)
		(end 246.432324 -127.100076)
		(width 0.14224)
		(layer "In11.Cu")
		(net "M_D_CKE<1>")
	)
	(segment
		(start 244.43944 -134.07136)
		(end 245.3386 -133.1722)
		(width 0.14224)
		(layer "In11.Cu")
		(net "M_D_CKE<1>")
	)
	(segment
		(start 248.751852 -124.674122)
		(end 248.751852 -127.523748)
		(width 0.1651)
		(layer "F.Cu")
		(net "M_D_CKE<0>")
	)
	(segment
		(start 245.9101 -130.0607)
		(end 245.8085 -130.0607)
		(width 0.1651)
		(layer "F.Cu")
		(net "M_D_CKE<0>")
	)
	(segment
		(start 246.3546 -129.6162)
		(end 245.9101 -130.0607)
		(width 0.1651)
		(layer "F.Cu")
		(net "M_D_CKE<0>")
	)
	(segment
		(start 246.3546 -129.4892)
		(end 246.3546 -129.6162)
		(width 0.1651)
		(layer "F.Cu")
		(net "M_D_CKE<0>")
	)
	(segment
		(start 245.3386 -131.749546)
		(end 244.849904 -132.238242)
		(width 0.1651)
		(layer "F.Cu")
		(net "M_D_CKE<0>")
	)
	(segment
		(start 248.751852 -127.523748)
		(end 248.031 -128.2446)
		(width 0.1651)
		(layer "F.Cu")
		(net "M_D_CKE<0>")
	)
	(segment
		(start 253.260098 -101.577648)
		(end 253.260098 -102.979728)
		(width 0.0889)
		(layer "F.Cu")
		(net "M_D_CKE<0>")
	)
	(segment
		(start 244.849904 -132.238242)
		(end 244.849904 -133.0706)
		(width 0.1651)
		(layer "F.Cu")
		(net "M_D_CKE<0>")
	)
	(segment
		(start 245.8085 -130.0607)
		(end 245.1608 -130.7084)
		(width 0.1651)
		(layer "F.Cu")
		(net "M_D_CKE<0>")
	)
	(segment
		(start 245.1608 -131.201668)
		(end 245.3386 -131.379468)
		(width 0.1651)
		(layer "F.Cu")
		(net "M_D_CKE<0>")
	)
	(segment
		(start 244.849904 -133.0706)
		(end 244.850412 -133.0706)
		(width 0.1651)
		(layer "F.Cu")
		(net "M_D_CKE<0>")
	)
	(segment
		(start 248.751852 -119.06631)
		(end 248.751852 -124.674122)
		(width 0.1651)
		(layer "F.Cu")
		(net "M_D_CKE<0>")
	)
	(segment
		(start 253.260098 -102.979728)
		(end 253.260098 -114.558064)
		(width 0.1651)
		(layer "F.Cu")
		(net "M_D_CKE<0>")
	)
	(segment
		(start 248.031 -128.2446)
		(end 247.5992 -128.2446)
		(width 0.1651)
		(layer "F.Cu")
		(net "M_D_CKE<0>")
	)
	(segment
		(start 253.260098 -114.558064)
		(end 248.751852 -119.06631)
		(width 0.1651)
		(layer "F.Cu")
		(net "M_D_CKE<0>")
	)
	(segment
		(start 245.1608 -130.7084)
		(end 245.1608 -131.201668)
		(width 0.1651)
		(layer "F.Cu")
		(net "M_D_CKE<0>")
	)
	(segment
		(start 253.353824 -101.15804)
		(end 253.353824 -101.483922)
		(width 0.0889)
		(layer "F.Cu")
		(net "M_D_CKE<0>")
	)
	(segment
		(start 253.353824 -101.483922)
		(end 253.260098 -101.577648)
		(width 0.0889)
		(layer "F.Cu")
		(net "M_D_CKE<0>")
	)
	(segment
		(start 245.3386 -131.379468)
		(end 245.3386 -131.749546)
		(width 0.1651)
		(layer "F.Cu")
		(net "M_D_CKE<0>")
	)
	(segment
		(start 247.5992 -128.2446)
		(end 246.3546 -129.4892)
		(width 0.1651)
		(layer "F.Cu")
		(net "M_D_CKE<0>")
	)
	(via
		(at 248.751852 -124.674122)
		(size 0.508)
		(drill 0.254)
		(layers "F.Cu" "B.Cu")
		(net "M_D_CKE<0>")
	)
	(segment
		(start 276.300438 -137.67054)
		(end 276.29993 -137.67054)
		(width 0.10795)
		(layer "F.Cu")
		(net "M_D_C<2>")
	)
	(segment
		(start 266.231116 -97.690686)
		(end 265.659616 -97.690686)
		(width 0.1651)
		(layer "F.Cu")
		(net "M_D_C<2>")
	)
	(segment
		(start 276.29993 -137.67054)
		(end 276.29993 -136.387586)
		(width 0.10795)
		(layer "F.Cu")
		(net "M_D_C<2>")
	)
	(segment
		(start 276.29993 -136.387586)
		(end 276.300438 -136.387078)
		(width 0.10795)
		(layer "F.Cu")
		(net "M_D_C<2>")
	)
	(via
		(at 276.300438 -136.387078)
		(size 0.4572)
		(drill 0.2032)
		(layers "F.Cu" "B.Cu")
		(net "M_D_C<2>")
	)
	(via
		(at 276.29993 -129.568956)
		(size 0.508)
		(drill 0.254)
		(layers "F.Cu" "B.Cu")
		(net "M_D_C<2>")
	)
	(via
		(at 265.659616 -97.690686)
		(size 0.508)
		(drill 0.254)
		(layers "F.Cu" "B.Cu")
		(net "M_D_C<2>")
	)
	(segment
		(start 276.29993 -128.276096)
		(end 276.29993 -129.568956)
		(width 0.1651)
		(layer "B.Cu")
		(net "M_D_C<2>")
	)
	(segment
		(start 276.300438 -128.276096)
		(end 276.29993 -128.276096)
		(width 0.1651)
		(layer "B.Cu")
		(net "M_D_C<2>")
	)
	(segment
		(start 267.8684 -100.050854)
		(end 269.494 -101.676454)
		(width 0.0889)
		(layer "In11.Cu")
		(net "M_D_C<2>")
	)
	(segment
		(start 276.715982 -131.885182)
		(end 276.715982 -134.637018)
		(width 0.14224)
		(layer "In11.Cu")
		(net "M_D_C<2>")
	)
	(segment
		(start 269.494 -102.014782)
		(end 269.494 -119.361712)
		(width 0.14224)
		(layer "In11.Cu")
		(net "M_D_C<2>")
	)
	(segment
		(start 276.7584 -131.1656)
		(end 276.6822 -131.2418)
		(width 0.14224)
		(layer "In11.Cu")
		(net "M_D_C<2>")
	)
	(segment
		(start 267.184886 -97.690686)
		(end 267.8684 -98.3742)
		(width 0.0889)
		(layer "In11.Cu")
		(net "M_D_C<2>")
	)
	(segment
		(start 276.6568 -136.030716)
		(end 276.300438 -136.387078)
		(width 0.14224)
		(layer "In11.Cu")
		(net "M_D_C<2>")
	)
	(segment
		(start 276.7584 -129.110486)
		(end 276.29993 -129.568956)
		(width 0.14224)
		(layer "In11.Cu")
		(net "M_D_C<2>")
	)
	(segment
		(start 265.659616 -97.690686)
		(end 267.184886 -97.690686)
		(width 0.0889)
		(layer "In11.Cu")
		(net "M_D_C<2>")
	)
	(segment
		(start 276.29993 -129.568956)
		(end 276.29993 -130.17373)
		(width 0.14224)
		(layer "In11.Cu")
		(net "M_D_C<2>")
	)
	(segment
		(start 276.6822 -131.2418)
		(end 276.6822 -131.8514)
		(width 0.14224)
		(layer "In11.Cu")
		(net "M_D_C<2>")
	)
	(segment
		(start 276.6568 -134.6962)
		(end 276.6568 -136.030716)
		(width 0.14224)
		(layer "In11.Cu")
		(net "M_D_C<2>")
	)
	(segment
		(start 267.8684 -98.3742)
		(end 267.8684 -100.050854)
		(width 0.0889)
		(layer "In11.Cu")
		(net "M_D_C<2>")
	)
	(segment
		(start 276.6822 -131.8514)
		(end 276.715982 -131.885182)
		(width 0.14224)
		(layer "In11.Cu")
		(net "M_D_C<2>")
	)
	(segment
		(start 276.715982 -134.637018)
		(end 276.6568 -134.6962)
		(width 0.14224)
		(layer "In11.Cu")
		(net "M_D_C<2>")
	)
	(segment
		(start 269.494 -101.676454)
		(end 269.494 -102.014782)
		(width 0.0889)
		(layer "In11.Cu")
		(net "M_D_C<2>")
	)
	(segment
		(start 269.494 -119.361712)
		(end 276.7584 -126.626112)
		(width 0.14224)
		(layer "In11.Cu")
		(net "M_D_C<2>")
	)
	(segment
		(start 276.29993 -130.17373)
		(end 276.7584 -130.6322)
		(width 0.14224)
		(layer "In11.Cu")
		(net "M_D_C<2>")
	)
	(segment
		(start 276.7584 -130.6322)
		(end 276.7584 -131.1656)
		(width 0.14224)
		(layer "In11.Cu")
		(net "M_D_C<2>")
	)
	(segment
		(start 276.7584 -126.626112)
		(end 276.7584 -129.110486)
		(width 0.14224)
		(layer "In11.Cu")
		(net "M_D_C<2>")
	)
	(segment
		(start 247.39981 -137.67054)
		(end 247.39981 -136.387078)
		(width 0.1651)
		(layer "F.Cu")
		(net "M_D_BG<1>")
	)
	(segment
		(start 253.353824 -98.18624)
		(end 252.782324 -98.18624)
		(width 0.1651)
		(layer "F.Cu")
		(net "M_D_BG<1>")
	)
	(segment
		(start 247.400318 -137.67054)
		(end 247.39981 -137.67054)
		(width 0.1651)
		(layer "F.Cu")
		(net "M_D_BG<1>")
	)
	(via
		(at 247.39981 -129.539746)
		(size 0.508)
		(drill 0.254)
		(layers "F.Cu" "B.Cu")
		(net "M_D_BG<1>")
	)
	(via
		(at 252.782324 -98.18624)
		(size 0.508)
		(drill 0.254)
		(layers "F.Cu" "B.Cu")
		(net "M_D_BG<1>")
	)
	(via
		(at 247.39981 -136.387078)
		(size 0.4572)
		(drill 0.2032)
		(layers "F.Cu" "B.Cu")
		(net "M_D_BG<1>")
	)
	(segment
		(start 247.400318 -128.276096)
		(end 247.39981 -128.276096)
		(width 0.1651)
		(layer "B.Cu")
		(net "M_D_BG<1>")
	)
	(segment
		(start 247.39981 -128.276096)
		(end 247.39981 -129.539746)
		(width 0.1651)
		(layer "B.Cu")
		(net "M_D_BG<1>")
	)
	(segment
		(start 248.539 -127.859282)
		(end 248.25833 -128.139952)
		(width 0.14224)
		(layer "In11.Cu")
		(net "M_D_BG<1>")
	)
	(segment
		(start 247.142 -135.445246)
		(end 247.39981 -135.703056)
		(width 0.14224)
		(layer "In11.Cu")
		(net "M_D_BG<1>")
	)
	(segment
		(start 247.794018 -127.90805)
		(end 247.579388 -127.90805)
		(width 0.14224)
		(layer "In11.Cu")
		(net "M_D_BG<1>")
	)
	(segment
		(start 251.958094 -102.155244)
		(end 251.958348 -102.155498)
		(width 0.14224)
		(layer "In11.Cu")
		(net "M_D_BG<1>")
	)
	(segment
		(start 252.391926 -99.779074)
		(end 251.968 -100.203)
		(width 0.0889)
		(layer "In11.Cu")
		(net "M_D_BG<1>")
	)
	(segment
		(start 251.4346 -100.4316)
		(end 251.4346 -100.9396)
		(width 0.0889)
		(layer "In11.Cu")
		(net "M_D_BG<1>")
	)
	(segment
		(start 247.015 -131.2926)
		(end 247.015 -131.9022)
		(width 0.14224)
		(layer "In11.Cu")
		(net "M_D_BG<1>")
	)
	(segment
		(start 251.958094 -101.463094)
		(end 251.958094 -101.894894)
		(width 0.0889)
		(layer "In11.Cu")
		(net "M_D_BG<1>")
	)
	(segment
		(start 248.25833 -128.139952)
		(end 248.02592 -128.139952)
		(width 0.14224)
		(layer "In11.Cu")
		(net "M_D_BG<1>")
	)
	(segment
		(start 252.452378 -98.947986)
		(end 252.435614 -98.976688)
		(width 0.0889)
		(layer "In11.Cu")
		(net "M_D_BG<1>")
	)
	(segment
		(start 251.6632 -100.203)
		(end 251.4346 -100.4316)
		(width 0.0889)
		(layer "In11.Cu")
		(net "M_D_BG<1>")
	)
	(segment
		(start 247.015 -131.9022)
		(end 246.9642 -131.953)
		(width 0.14224)
		(layer "In11.Cu")
		(net "M_D_BG<1>")
	)
	(segment
		(start 246.9642 -131.953)
		(end 246.9642 -134.6962)
		(width 0.14224)
		(layer "In11.Cu")
		(net "M_D_BG<1>")
	)
	(segment
		(start 247.39981 -135.703056)
		(end 247.39981 -136.387078)
		(width 0.14224)
		(layer "In11.Cu")
		(net "M_D_BG<1>")
	)
	(segment
		(start 247.39981 -130.17119)
		(end 246.9388 -130.6322)
		(width 0.14224)
		(layer "In11.Cu")
		(net "M_D_BG<1>")
	)
	(segment
		(start 251.4346 -100.9396)
		(end 251.958094 -101.463094)
		(width 0.0889)
		(layer "In11.Cu")
		(net "M_D_BG<1>")
	)
	(segment
		(start 247.401334 -128.30937)
		(end 247.64238 -128.550416)
		(width 0.14224)
		(layer "In11.Cu")
		(net "M_D_BG<1>")
	)
	(segment
		(start 246.9388 -130.6322)
		(end 246.9388 -131.2164)
		(width 0.14224)
		(layer "In11.Cu")
		(net "M_D_BG<1>")
	)
	(segment
		(start 252.782324 -98.18624)
		(end 252.452378 -98.947986)
		(width 0.0889)
		(layer "In11.Cu")
		(net "M_D_BG<1>")
	)
	(segment
		(start 247.39981 -129.539746)
		(end 247.39981 -130.17119)
		(width 0.14224)
		(layer "In11.Cu")
		(net "M_D_BG<1>")
	)
	(segment
		(start 247.401334 -128.086104)
		(end 247.401334 -128.30937)
		(width 0.14224)
		(layer "In11.Cu")
		(net "M_D_BG<1>")
	)
	(segment
		(start 247.579388 -127.90805)
		(end 247.401334 -128.086104)
		(width 0.14224)
		(layer "In11.Cu")
		(net "M_D_BG<1>")
	)
	(segment
		(start 251.958348 -120.727216)
		(end 248.539 -124.146564)
		(width 0.14224)
		(layer "In11.Cu")
		(net "M_D_BG<1>")
	)
	(segment
		(start 247.39981 -129.011934)
		(end 247.39981 -129.539746)
		(width 0.14224)
		(layer "In11.Cu")
		(net "M_D_BG<1>")
	)
	(segment
		(start 252.391926 -99.264978)
		(end 252.391926 -99.779074)
		(width 0.0889)
		(layer "In11.Cu")
		(net "M_D_BG<1>")
	)
	(segment
		(start 246.9642 -134.6962)
		(end 247.142 -134.874)
		(width 0.14224)
		(layer "In11.Cu")
		(net "M_D_BG<1>")
	)
	(segment
		(start 247.142 -134.874)
		(end 247.142 -135.445246)
		(width 0.14224)
		(layer "In11.Cu")
		(net "M_D_BG<1>")
	)
	(segment
		(start 251.958094 -101.894894)
		(end 251.958094 -102.155244)
		(width 0.14224)
		(layer "In11.Cu")
		(net "M_D_BG<1>")
	)
	(segment
		(start 251.958348 -102.155498)
		(end 251.958348 -120.727216)
		(width 0.14224)
		(layer "In11.Cu")
		(net "M_D_BG<1>")
	)
	(segment
		(start 247.64238 -128.769364)
		(end 247.39981 -129.011934)
		(width 0.14224)
		(layer "In11.Cu")
		(net "M_D_BG<1>")
	)
	(segment
		(start 248.539 -124.146564)
		(end 248.539 -127.859282)
		(width 0.14224)
		(layer "In11.Cu")
		(net "M_D_BG<1>")
	)
	(segment
		(start 251.968 -100.203)
		(end 251.6632 -100.203)
		(width 0.0889)
		(layer "In11.Cu")
		(net "M_D_BG<1>")
	)
	(segment
		(start 247.64238 -128.550416)
		(end 247.64238 -128.769364)
		(width 0.14224)
		(layer "In11.Cu")
		(net "M_D_BG<1>")
	)
	(segment
		(start 246.9388 -131.2164)
		(end 247.015 -131.2926)
		(width 0.14224)
		(layer "In11.Cu")
		(net "M_D_BG<1>")
	)
	(segment
		(start 248.02592 -128.139952)
		(end 247.794018 -127.90805)
		(width 0.14224)
		(layer "In11.Cu")
		(net "M_D_BG<1>")
	)
	(arc
		(start 252.435614 -98.976688)
		(mid 252.386619 -99.116712)
		(end 252.391926 -99.264978)
		(width 0.0889)
		(layer "In11.Cu")
		(net "M_D_BG<1>")
	)
	(segment
		(start 249.983752 -120.092978)
		(end 250.237244 -120.092978)
		(width 0.1651)
		(layer "F.Cu")
		(net "M_D_BG<0>")
	)
	(segment
		(start 248.24944 -130.902456)
		(end 247.39981 -130.902456)
		(width 0.1651)
		(layer "F.Cu")
		(net "M_D_BG<0>")
	)
	(segment
		(start 249.818652 -119.927878)
		(end 249.983752 -120.092978)
		(width 0.1651)
		(layer "F.Cu")
		(net "M_D_BG<0>")
	)
	(segment
		(start 248.730516 -129.960116)
		(end 248.730516 -130.42138)
		(width 0.1651)
		(layer "F.Cu")
		(net "M_D_BG<0>")
	)
	(segment
		(start 253.7714 -102.006654)
		(end 253.7714 -102.4636)
		(width 0.0889)
		(layer "F.Cu")
		(net "M_D_BG<0>")
	)
	(segment
		(start 250.229116 -120.766078)
		(end 249.983752 -120.766078)
		(width 0.1651)
		(layer "F.Cu")
		(net "M_D_BG<0>")
	)
	(segment
		(start 249.983752 -124.80417)
		(end 250.28017 -124.80417)
		(width 0.1651)
		(layer "F.Cu")
		(net "M_D_BG<0>")
	)
	(segment
		(start 254.324358 -114.992658)
		(end 249.818652 -119.498364)
		(width 0.1651)
		(layer "F.Cu")
		(net "M_D_BG<0>")
	)
	(segment
		(start 253.814326 -101.650038)
		(end 253.81204 -101.966014)
		(width 0.0889)
		(layer "F.Cu")
		(net "M_D_BG<0>")
	)
	(segment
		(start 250.049538 -128.179322)
		(end 250.049538 -128.730756)
		(width 0.1651)
		(layer "F.Cu")
		(net "M_D_BG<0>")
	)
	(segment
		(start 250.288298 -125.47727)
		(end 249.983752 -125.47727)
		(width 0.1651)
		(layer "F.Cu")
		(net "M_D_BG<0>")
	)
	(segment
		(start 247.39981 -133.076442)
		(end 247.39981 -134.369556)
		(width 0.1651)
		(layer "F.Cu")
		(net "M_D_BG<0>")
	)
	(segment
		(start 249.818652 -124.63907)
		(end 249.983752 -124.80417)
		(width 0.1651)
		(layer "F.Cu")
		(net "M_D_BG<0>")
	)
	(segment
		(start 247.400318 -133.0706)
		(end 247.39981 -133.076442)
		(width 0.1651)
		(layer "F.Cu")
		(net "M_D_BG<0>")
	)
	(segment
		(start 254.212344 -100.662486)
		(end 253.882906 -101.42347)
		(width 0.0889)
		(layer "F.Cu")
		(net "M_D_BG<0>")
	)
	(segment
		(start 250.39828 -120.596914)
		(end 250.229116 -120.766078)
		(width 0.1651)
		(layer "F.Cu")
		(net "M_D_BG<0>")
	)
	(segment
		(start 250.449334 -125.316234)
		(end 250.288298 -125.47727)
		(width 0.1651)
		(layer "F.Cu")
		(net "M_D_BG<0>")
	)
	(segment
		(start 250.28017 -124.80417)
		(end 250.449334 -124.973334)
		(width 0.1651)
		(layer "F.Cu")
		(net "M_D_BG<0>")
	)
	(segment
		(start 248.730516 -130.42138)
		(end 248.24944 -130.902456)
		(width 0.1651)
		(layer "F.Cu")
		(net "M_D_BG<0>")
	)
	(segment
		(start 254.324358 -103.016558)
		(end 254.324358 -103.473758)
		(width 0.0889)
		(layer "F.Cu")
		(net "M_D_BG<0>")
	)
	(segment
		(start 249.818652 -127.948436)
		(end 250.049538 -128.179322)
		(width 0.1651)
		(layer "F.Cu")
		(net "M_D_BG<0>")
	)
	(segment
		(start 248.878852 -129.098548)
		(end 248.5898 -129.3876)
		(width 0.1651)
		(layer "F.Cu")
		(net "M_D_BG<0>")
	)
	(segment
		(start 253.81204 -101.966014)
		(end 253.7714 -102.006654)
		(width 0.0889)
		(layer "F.Cu")
		(net "M_D_BG<0>")
	)
	(segment
		(start 250.449334 -124.973334)
		(end 250.449334 -125.316234)
		(width 0.1651)
		(layer "F.Cu")
		(net "M_D_BG<0>")
	)
	(segment
		(start 250.237244 -120.092978)
		(end 250.39828 -120.254014)
		(width 0.1651)
		(layer "F.Cu")
		(net "M_D_BG<0>")
	)
	(segment
		(start 253.7714 -102.4636)
		(end 254.324358 -103.016558)
		(width 0.0889)
		(layer "F.Cu")
		(net "M_D_BG<0>")
	)
	(segment
		(start 249.818652 -119.498364)
		(end 249.818652 -119.927878)
		(width 0.1651)
		(layer "F.Cu")
		(net "M_D_BG<0>")
	)
	(segment
		(start 249.681746 -129.098548)
		(end 248.878852 -129.098548)
		(width 0.1651)
		(layer "F.Cu")
		(net "M_D_BG<0>")
	)
	(segment
		(start 248.5898 -129.8194)
		(end 248.730516 -129.960116)
		(width 0.1651)
		(layer "F.Cu")
		(net "M_D_BG<0>")
	)
	(segment
		(start 249.818652 -125.64237)
		(end 249.818652 -127.948436)
		(width 0.1651)
		(layer "F.Cu")
		(net "M_D_BG<0>")
	)
	(segment
		(start 249.983752 -125.47727)
		(end 249.818652 -125.64237)
		(width 0.1651)
		(layer "F.Cu")
		(net "M_D_BG<0>")
	)
	(segment
		(start 254.324358 -103.473758)
		(end 254.324358 -114.992658)
		(width 0.1651)
		(layer "F.Cu")
		(net "M_D_BG<0>")
	)
	(segment
		(start 250.049538 -128.730756)
		(end 249.681746 -129.098548)
		(width 0.1651)
		(layer "F.Cu")
		(net "M_D_BG<0>")
	)
	(segment
		(start 249.818652 -120.931178)
		(end 249.818652 -124.63907)
		(width 0.1651)
		(layer "F.Cu")
		(net "M_D_BG<0>")
	)
	(segment
		(start 250.39828 -120.254014)
		(end 250.39828 -120.596914)
		(width 0.1651)
		(layer "F.Cu")
		(net "M_D_BG<0>")
	)
	(segment
		(start 249.983752 -120.766078)
		(end 249.818652 -120.931178)
		(width 0.1651)
		(layer "F.Cu")
		(net "M_D_BG<0>")
	)
	(segment
		(start 253.882906 -101.42347)
		(end 253.865634 -101.453188)
		(width 0.0889)
		(layer "F.Cu")
		(net "M_D_BG<0>")
	)
	(segment
		(start 248.5898 -129.3876)
		(end 248.5898 -129.8194)
		(width 0.1651)
		(layer "F.Cu")
		(net "M_D_BG<0>")
	)
	(via
		(at 247.39981 -130.902456)
		(size 0.508)
		(drill 0.254)
		(layers "F.Cu" "B.Cu")
		(net "M_D_BG<0>")
	)
	(via
		(at 247.39981 -134.369556)
		(size 0.4572)
		(drill 0.2032)
		(layers "F.Cu" "B.Cu")
		(net "M_D_BG<0>")
	)
	(arc
		(start 253.81458 -101.64699)
		(mid 253.81445 -101.648514)
		(end 253.814326 -101.650038)
		(width 0.0889)
		(layer "F.Cu")
		(net "M_D_BG<0>")
	)
	(arc
		(start 253.84633 -101.49713)
		(mid 253.823184 -101.570518)
		(end 253.81458 -101.64699)
		(width 0.0889)
		(layer "F.Cu")
		(net "M_D_BG<0>")
	)
	(arc
		(start 253.865634 -101.453188)
		(mid 253.855383 -101.474896)
		(end 253.84633 -101.49713)
		(width 0.0889)
		(layer "F.Cu")
		(net "M_D_BG<0>")
	)
	(segment
		(start 247.39981 -132.875782)
		(end 247.39981 -130.902456)
		(width 0.1651)
		(layer "B.Cu")
		(net "M_D_BG<0>")
	)
	(segment
		(start 247.400318 -132.876036)
		(end 247.39981 -132.875782)
		(width 0.1651)
		(layer "B.Cu")
		(net "M_D_BG<0>")
	)
	(segment
		(start 247.39981 -130.902456)
		(end 247.39981 -134.369556)
		(width 0.14224)
		(layer "In9.Cu")
		(net "M_D_BG<0>")
	)
	(segment
		(start 266.949936 -137.67054)
		(end 266.949936 -136.387332)
		(width 0.1651)
		(layer "F.Cu")
		(net "M_D_BA<1>")
	)
	(segment
		(start 259.65023 -99.17684)
		(end 260.22173 -99.17684)
		(width 0.1651)
		(layer "F.Cu")
		(net "M_D_BA<1>")
	)
	(segment
		(start 266.949936 -136.387332)
		(end 266.95019 -136.387078)
		(width 0.1651)
		(layer "F.Cu")
		(net "M_D_BA<1>")
	)
	(segment
		(start 266.950444 -137.67054)
		(end 266.949936 -137.67054)
		(width 0.1651)
		(layer "F.Cu")
		(net "M_D_BA<1>")
	)
	(via
		(at 266.949682 -130.249168)
		(size 0.508)
		(drill 0.254)
		(layers "F.Cu" "B.Cu")
		(net "M_D_BA<1>")
	)
	(via
		(at 259.65023 -99.17684)
		(size 0.508)
		(drill 0.254)
		(layers "F.Cu" "B.Cu")
		(net "M_D_BA<1>")
	)
	(via
		(at 266.95019 -136.387078)
		(size 0.4572)
		(drill 0.2032)
		(layers "F.Cu" "B.Cu")
		(net "M_D_BA<1>")
	)
	(segment
		(start 266.950444 -128.276096)
		(end 266.949936 -128.276096)
		(width 0.1651)
		(layer "B.Cu")
		(net "M_D_BA<1>")
	)
	(segment
		(start 266.949936 -128.276096)
		(end 266.949936 -130.248914)
		(width 0.1651)
		(layer "B.Cu")
		(net "M_D_BA<1>")
	)
	(segment
		(start 266.949936 -130.248914)
		(end 266.949682 -130.249168)
		(width 0.1651)
		(layer "B.Cu")
		(net "M_D_BA<1>")
	)
	(segment
		(start 259.848604 -99.879404)
		(end 261.9248 -101.9556)
		(width 0.0889)
		(layer "In11.Cu")
		(net "M_D_BA<1>")
	)
	(segment
		(start 266.539218 -134.729982)
		(end 266.4714 -134.7978)
		(width 0.14224)
		(layer "In11.Cu")
		(net "M_D_BA<1>")
	)
	(segment
		(start 262.321548 -104.184704)
		(end 262.321548 -104.445816)
		(width 0.0889)
		(layer "In11.Cu")
		(net "M_D_BA<1>")
	)
	(segment
		(start 259.848604 -99.375214)
		(end 259.848604 -99.879404)
		(width 0.0889)
		(layer "In11.Cu")
		(net "M_D_BA<1>")
	)
	(segment
		(start 266.4714 -134.7978)
		(end 266.4714 -135.3058)
		(width 0.14224)
		(layer "In11.Cu")
		(net "M_D_BA<1>")
	)
	(segment
		(start 266.949682 -130.249168)
		(end 266.949682 -130.763518)
		(width 0.14224)
		(layer "In11.Cu")
		(net "M_D_BA<1>")
	)
	(segment
		(start 266.25677 -133.83387)
		(end 266.539218 -134.116318)
		(width 0.14224)
		(layer "In11.Cu")
		(net "M_D_BA<1>")
	)
	(segment
		(start 262.321548 -104.445816)
		(end 262.321548 -122.908314)
		(width 0.14224)
		(layer "In11.Cu")
		(net "M_D_BA<1>")
	)
	(segment
		(start 266.139168 -132.483606)
		(end 266.29487 -132.639308)
		(width 0.14224)
		(layer "In11.Cu")
		(net "M_D_BA<1>")
	)
	(segment
		(start 266.949682 -130.763518)
		(end 266.139168 -131.574032)
		(width 0.14224)
		(layer "In11.Cu")
		(net "M_D_BA<1>")
	)
	(segment
		(start 266.749784 -133.200648)
		(end 266.41171 -133.200648)
		(width 0.14224)
		(layer "In11.Cu")
		(net "M_D_BA<1>")
	)
	(segment
		(start 266.949936 -136.386824)
		(end 266.95019 -136.387078)
		(width 0.14224)
		(layer "In11.Cu")
		(net "M_D_BA<1>")
	)
	(segment
		(start 261.9248 -103.787956)
		(end 262.321548 -104.184704)
		(width 0.0889)
		(layer "In11.Cu")
		(net "M_D_BA<1>")
	)
	(segment
		(start 261.9248 -101.9556)
		(end 261.9248 -103.787956)
		(width 0.0889)
		(layer "In11.Cu")
		(net "M_D_BA<1>")
	)
	(segment
		(start 266.756896 -132.639308)
		(end 266.90828 -132.790692)
		(width 0.14224)
		(layer "In11.Cu")
		(net "M_D_BA<1>")
	)
	(segment
		(start 266.539218 -134.116318)
		(end 266.539218 -134.729982)
		(width 0.14224)
		(layer "In11.Cu")
		(net "M_D_BA<1>")
	)
	(segment
		(start 266.4714 -135.3058)
		(end 266.949936 -135.784336)
		(width 0.14224)
		(layer "In11.Cu")
		(net "M_D_BA<1>")
	)
	(segment
		(start 266.29487 -132.639308)
		(end 266.756896 -132.639308)
		(width 0.14224)
		(layer "In11.Cu")
		(net "M_D_BA<1>")
	)
	(segment
		(start 266.949682 -127.536448)
		(end 266.949682 -130.249168)
		(width 0.14224)
		(layer "In11.Cu")
		(net "M_D_BA<1>")
	)
	(segment
		(start 266.90828 -132.790692)
		(end 266.90828 -133.042152)
		(width 0.14224)
		(layer "In11.Cu")
		(net "M_D_BA<1>")
	)
	(segment
		(start 266.25677 -133.355588)
		(end 266.25677 -133.83387)
		(width 0.14224)
		(layer "In11.Cu")
		(net "M_D_BA<1>")
	)
	(segment
		(start 266.949936 -135.784336)
		(end 266.949936 -136.386824)
		(width 0.14224)
		(layer "In11.Cu")
		(net "M_D_BA<1>")
	)
	(segment
		(start 259.65023 -99.17684)
		(end 259.848604 -99.375214)
		(width 0.0889)
		(layer "In11.Cu")
		(net "M_D_BA<1>")
	)
	(segment
		(start 266.41171 -133.200648)
		(end 266.25677 -133.355588)
		(width 0.14224)
		(layer "In11.Cu")
		(net "M_D_BA<1>")
	)
	(segment
		(start 266.90828 -133.042152)
		(end 266.749784 -133.200648)
		(width 0.14224)
		(layer "In11.Cu")
		(net "M_D_BA<1>")
	)
	(segment
		(start 266.139168 -131.574032)
		(end 266.139168 -132.483606)
		(width 0.14224)
		(layer "In11.Cu")
		(net "M_D_BA<1>")
	)
	(segment
		(start 262.321548 -122.908314)
		(end 266.949682 -127.536448)
		(width 0.14224)
		(layer "In11.Cu")
		(net "M_D_BA<1>")
	)
	(segment
		(start 263.54405 -103.95585)
		(end 261.93877 -102.35057)
		(width 0.0889)
		(layer "F.Cu")
		(net "M_D_BA<0>")
	)
	(segment
		(start 263.54405 -125.949202)
		(end 263.54405 -104.408224)
		(width 0.1651)
		(layer "F.Cu")
		(net "M_D_BA<0>")
	)
	(segment
		(start 264.860532 -128.31826)
		(end 264.860532 -127.265684)
		(width 0.1651)
		(layer "F.Cu")
		(net "M_D_BA<0>")
	)
	(segment
		(start 266.247372 -128.999996)
		(end 265.542268 -128.999996)
		(width 0.1651)
		(layer "F.Cu")
		(net "M_D_BA<0>")
	)
	(segment
		(start 263.54405 -104.408224)
		(end 263.54405 -103.95585)
		(width 0.0889)
		(layer "F.Cu")
		(net "M_D_BA<0>")
	)
	(segment
		(start 261.93877 -102.35057)
		(end 261.93877 -101.15804)
		(width 0.0889)
		(layer "F.Cu")
		(net "M_D_BA<0>")
	)
	(segment
		(start 266.5984 -129.351024)
		(end 266.247372 -128.999996)
		(width 0.1651)
		(layer "F.Cu")
		(net "M_D_BA<0>")
	)
	(segment
		(start 266.789916 -130.902456)
		(end 266.4714 -130.58394)
		(width 0.1651)
		(layer "F.Cu")
		(net "M_D_BA<0>")
	)
	(segment
		(start 266.5984 -129.921)
		(end 266.5984 -129.351024)
		(width 0.1651)
		(layer "F.Cu")
		(net "M_D_BA<0>")
	)
	(segment
		(start 267.79982 -134.371334)
		(end 267.800074 -134.371588)
		(width 0.1651)
		(layer "F.Cu")
		(net "M_D_BA<0>")
	)
	(segment
		(start 264.860532 -127.265684)
		(end 263.54405 -125.949202)
		(width 0.1651)
		(layer "F.Cu")
		(net "M_D_BA<0>")
	)
	(segment
		(start 267.79982 -130.902456)
		(end 266.789916 -130.902456)
		(width 0.1651)
		(layer "F.Cu")
		(net "M_D_BA<0>")
	)
	(segment
		(start 267.79982 -133.076442)
		(end 267.79982 -134.371334)
		(width 0.1651)
		(layer "F.Cu")
		(net "M_D_BA<0>")
	)
	(segment
		(start 266.4714 -130.048)
		(end 266.5984 -129.921)
		(width 0.1651)
		(layer "F.Cu")
		(net "M_D_BA<0>")
	)
	(segment
		(start 265.542268 -128.999996)
		(end 264.860532 -128.31826)
		(width 0.1651)
		(layer "F.Cu")
		(net "M_D_BA<0>")
	)
	(segment
		(start 266.4714 -130.58394)
		(end 266.4714 -130.048)
		(width 0.1651)
		(layer "F.Cu")
		(net "M_D_BA<0>")
	)
	(segment
		(start 267.800328 -133.0706)
		(end 267.79982 -133.076442)
		(width 0.1651)
		(layer "F.Cu")
		(net "M_D_BA<0>")
	)
	(via
		(at 267.79982 -130.902456)
		(size 0.508)
		(drill 0.254)
		(layers "F.Cu" "B.Cu")
		(net "M_D_BA<0>")
	)
	(via
		(at 267.800074 -134.371588)
		(size 0.4572)
		(drill 0.2032)
		(layers "F.Cu" "B.Cu")
		(net "M_D_BA<0>")
	)
	(segment
		(start 267.79982 -132.875782)
		(end 267.79982 -130.902456)
		(width 0.1651)
		(layer "B.Cu")
		(net "M_D_BA<0>")
	)
	(segment
		(start 267.800328 -132.876036)
		(end 267.79982 -132.875782)
		(width 0.1651)
		(layer "B.Cu")
		(net "M_D_BA<0>")
	)
	(segment
		(start 267.79982 -130.902456)
		(end 267.79982 -134.371334)
		(width 0.14224)
		(layer "In9.Cu")
		(net "M_D_BA<0>")
	)
	(segment
		(start 267.79982 -134.371334)
		(end 267.800074 -134.371588)
		(width 0.14224)
		(layer "In9.Cu")
		(net "M_D_BA<0>")
	)
	(segment
		(start 251.843032 -100.662486)
		(end 251.841 -100.660454)
		(width 0.1651)
		(layer "F.Cu")
		(net "M_D_ALERT_N")
	)
	(segment
		(start 252.495304 -100.662486)
		(end 251.843032 -100.662486)
		(width 0.1651)
		(layer "F.Cu")
		(net "M_D_ALERT_N")
	)
	(segment
		(start 248.250456 -137.67054)
		(end 248.249948 -137.67054)
		(width 0.1651)
		(layer "F.Cu")
		(net "M_D_ALERT_N")
	)
	(segment
		(start 248.249948 -137.67054)
		(end 248.249948 -136.387078)
		(width 0.1651)
		(layer "F.Cu")
		(net "M_D_ALERT_N")
	)
	(via
		(at 251.841 -100.660454)
		(size 0.508)
		(drill 0.254)
		(layers "F.Cu" "B.Cu")
		(net "M_D_ALERT_N")
	)
	(via
		(at 248.249948 -136.387078)
		(size 0.4572)
		(drill 0.2032)
		(layers "F.Cu" "B.Cu")
		(net "M_D_ALERT_N")
	)
	(via
		(at 248.249948 -130.249168)
		(size 0.508)
		(drill 0.254)
		(layers "F.Cu" "B.Cu")
		(net "M_D_ALERT_N")
	)
	(segment
		(start 248.250456 -128.276096)
		(end 248.249948 -128.276096)
		(width 0.1651)
		(layer "B.Cu")
		(net "M_D_ALERT_N")
	)
	(segment
		(start 248.249948 -128.276096)
		(end 248.249948 -130.249168)
		(width 0.1651)
		(layer "B.Cu")
		(net "M_D_ALERT_N")
	)
	(segment
		(start 249.047 -124.22124)
		(end 249.047 -127.9652)
		(width 0.14224)
		(layer "In11.Cu")
		(net "M_D_ALERT_N")
	)
	(segment
		(start 252.466348 -120.801892)
		(end 249.047 -124.22124)
		(width 0.14224)
		(layer "In11.Cu")
		(net "M_D_ALERT_N")
	)
	(segment
		(start 247.816624 -131.941824)
		(end 247.816624 -135.300212)
		(width 0.14224)
		(layer "In11.Cu")
		(net "M_D_ALERT_N")
	)
	(segment
		(start 247.816624 -135.300212)
		(end 248.249948 -135.733536)
		(width 0.14224)
		(layer "In11.Cu")
		(net "M_D_ALERT_N")
	)
	(segment
		(start 248.249948 -130.249168)
		(end 248.249948 -130.819652)
		(width 0.14224)
		(layer "In11.Cu")
		(net "M_D_ALERT_N")
	)
	(segment
		(start 248.249948 -130.819652)
		(end 247.7262 -131.3434)
		(width 0.14224)
		(layer "In11.Cu")
		(net "M_D_ALERT_N")
	)
	(segment
		(start 249.047 -127.9652)
		(end 248.08053 -128.93167)
		(width 0.14224)
		(layer "In11.Cu")
		(net "M_D_ALERT_N")
	)
	(segment
		(start 248.08053 -128.93167)
		(end 248.0818 -128.934718)
		(width 0.14224)
		(layer "In11.Cu")
		(net "M_D_ALERT_N")
	)
	(segment
		(start 252.466348 -101.285802)
		(end 252.466348 -120.801892)
		(width 0.14224)
		(layer "In11.Cu")
		(net "M_D_ALERT_N")
	)
	(segment
		(start 248.0818 -130.08102)
		(end 248.249948 -130.249168)
		(width 0.14224)
		(layer "In11.Cu")
		(net "M_D_ALERT_N")
	)
	(segment
		(start 247.7262 -131.8514)
		(end 247.816624 -131.941824)
		(width 0.14224)
		(layer "In11.Cu")
		(net "M_D_ALERT_N")
	)
	(segment
		(start 247.7262 -131.3434)
		(end 247.7262 -131.8514)
		(width 0.14224)
		(layer "In11.Cu")
		(net "M_D_ALERT_N")
	)
	(segment
		(start 248.249948 -135.733536)
		(end 248.249948 -136.387078)
		(width 0.14224)
		(layer "In11.Cu")
		(net "M_D_ALERT_N")
	)
	(segment
		(start 251.841 -100.660454)
		(end 252.466348 -101.285802)
		(width 0.14224)
		(layer "In11.Cu")
		(net "M_D_ALERT_N")
	)
	(segment
		(start 248.0818 -128.934718)
		(end 248.0818 -130.08102)
		(width 0.14224)
		(layer "In11.Cu")
		(net "M_D_ALERT_N")
	)
	(segment
		(start 253.792228 -114.788188)
		(end 249.285252 -119.295164)
		(width 0.1651)
		(layer "F.Cu")
		(net "M_D_ACT_N")
	)
	(segment
		(start 246.550434 -133.0706)
		(end 246.549926 -133.076442)
		(width 0.1651)
		(layer "F.Cu")
		(net "M_D_ACT_N")
	)
	(segment
		(start 249.285252 -127.803148)
		(end 247.9929 -129.0955)
		(width 0.1651)
		(layer "F.Cu")
		(net "M_D_ACT_N")
	)
	(segment
		(start 253.792228 -103.15702)
		(end 253.792228 -114.788188)
		(width 0.1651)
		(layer "F.Cu")
		(net "M_D_ACT_N")
	)
	(segment
		(start 253.792228 -102.789228)
		(end 253.792228 -103.15702)
		(width 0.0889)
		(layer "F.Cu")
		(net "M_D_ACT_N")
	)
	(segment
		(start 247.9929 -129.627376)
		(end 246.549926 -131.07035)
		(width 0.1651)
		(layer "F.Cu")
		(net "M_D_ACT_N")
	)
	(segment
		(start 246.549926 -133.076442)
		(end 246.549926 -134.369556)
		(width 0.1651)
		(layer "F.Cu")
		(net "M_D_ACT_N")
	)
	(segment
		(start 247.9929 -129.0955)
		(end 247.9929 -129.627376)
		(width 0.1651)
		(layer "F.Cu")
		(net "M_D_ACT_N")
	)
	(segment
		(start 249.285252 -119.295164)
		(end 249.285252 -127.803148)
		(width 0.1651)
		(layer "F.Cu")
		(net "M_D_ACT_N")
	)
	(segment
		(start 253.5428 -101.944932)
		(end 253.5428 -102.5398)
		(width 0.0889)
		(layer "F.Cu")
		(net "M_D_ACT_N")
	)
	(segment
		(start 246.549926 -131.07035)
		(end 246.549926 -131.611878)
		(width 0.1651)
		(layer "F.Cu")
		(net "M_D_ACT_N")
	)
	(segment
		(start 253.5428 -102.5398)
		(end 253.792228 -102.789228)
		(width 0.0889)
		(layer "F.Cu")
		(net "M_D_ACT_N")
	)
	(via
		(at 246.549926 -131.611878)
		(size 0.508)
		(drill 0.254)
		(layers "F.Cu" "B.Cu")
		(net "M_D_ACT_N")
	)
	(via
		(at 246.549926 -134.369556)
		(size 0.4572)
		(drill 0.2032)
		(layers "F.Cu" "B.Cu")
		(net "M_D_ACT_N")
	)
	(arc
		(start 254.60833 -99.616006)
		(mid 254.604997 -99.748164)
		(end 254.5588 -99.872038)
		(width 0.0889)
		(layer "F.Cu")
		(net "M_D_ACT_N")
	)
	(arc
		(start 253.747016 -101.082856)
		(mid 253.749277 -101.219684)
		(end 253.70536 -101.349302)
		(width 0.0889)
		(layer "F.Cu")
		(net "M_D_ACT_N")
	)
	(arc
		(start 255.07061 -98.18624)
		(mid 254.674553 -98.847791)
		(end 254.60833 -99.616006)
		(width 0.0889)
		(layer "F.Cu")
		(net "M_D_ACT_N")
	)
	(arc
		(start 253.70028 -101.35743)
		(mid 253.582815 -101.640804)
		(end 253.5428 -101.944932)
		(width 0.0889)
		(layer "F.Cu")
		(net "M_D_ACT_N")
	)
	(arc
		(start 254.5588 -99.872038)
		(mid 254.346895 -100.111237)
		(end 254.058166 -100.248212)
		(width 0.0889)
		(layer "F.Cu")
		(net "M_D_ACT_N")
	)
	(arc
		(start 253.70536 -101.349302)
		(mid 253.702746 -101.35332)
		(end 253.70028 -101.35743)
		(width 0.0889)
		(layer "F.Cu")
		(net "M_D_ACT_N")
	)
	(arc
		(start 254.058166 -100.248212)
		(mid 253.785957 -100.62205)
		(end 253.747016 -101.082856)
		(width 0.0889)
		(layer "F.Cu")
		(net "M_D_ACT_N")
	)
	(segment
		(start 246.550434 -132.876036)
		(end 246.549926 -132.875782)
		(width 0.1651)
		(layer "B.Cu")
		(net "M_D_ACT_N")
	)
	(segment
		(start 246.549926 -132.875782)
		(end 246.549926 -131.611878)
		(width 0.1651)
		(layer "B.Cu")
		(net "M_D_ACT_N")
	)
	(segment
		(start 246.549926 -131.611878)
		(end 246.549926 -134.369556)
		(width 0.14224)
		(layer "In9.Cu")
		(net "M_D_ACT_N")
	)
	(segment
		(start 243.149882 -152.278842)
		(end 243.149882 -154.111452)
		(width 0.10795)
		(layer "F.Cu")
		(net "M_DEF_RST_N")
	)
	(segment
		(start 243.15039 -152.273)
		(end 243.149882 -152.278842)
		(width 0.10795)
		(layer "F.Cu")
		(net "M_DEF_RST_N")
	)
	(segment
		(start 243.15039 -133.0706)
		(end 243.149882 -133.076442)
		(width 0.10795)
		(layer "F.Cu")
		(net "M_DEF_RST_N")
	)
	(segment
		(start 243.149882 -154.111452)
		(end 243.27231 -154.23388)
		(width 0.10795)
		(layer "F.Cu")
		(net "M_DEF_RST_N")
	)
	(segment
		(start 243.15039 -142.6718)
		(end 243.149882 -142.677642)
		(width 0.10795)
		(layer "F.Cu")
		(net "M_DEF_RST_N")
	)
	(segment
		(start 243.149882 -133.076442)
		(end 243.149882 -134.19836)
		(width 0.10795)
		(layer "F.Cu")
		(net "M_DEF_RST_N")
	)
	(segment
		(start 243.149882 -143.874236)
		(end 243.228368 -143.952722)
		(width 0.10795)
		(layer "F.Cu")
		(net "M_DEF_RST_N")
	)
	(segment
		(start 243.149882 -142.677642)
		(end 243.149882 -143.874236)
		(width 0.10795)
		(layer "F.Cu")
		(net "M_DEF_RST_N")
	)
	(segment
		(start 252.495304 -97.690686)
		(end 251.923804 -97.690686)
		(width 0.1016)
		(layer "F.Cu")
		(net "M_DEF_RST_N")
	)
	(segment
		(start 243.149882 -134.19836)
		(end 243.282724 -134.331202)
		(width 0.10795)
		(layer "F.Cu")
		(net "M_DEF_RST_N")
	)
	(via
		(at 243.228368 -143.952722)
		(size 0.4572)
		(drill 0.2032)
		(layers "F.Cu" "B.Cu")
		(net "M_DEF_RST_N")
	)
	(via
		(at 243.149882 -150.788878)
		(size 0.4572)
		(drill 0.2032)
		(layers "F.Cu" "B.Cu")
		(net "M_DEF_RST_N")
	)
	(via
		(at 243.282724 -134.331202)
		(size 0.4572)
		(drill 0.2032)
		(layers "F.Cu" "B.Cu")
		(net "M_DEF_RST_N")
	)
	(via
		(at 243.27231 -154.23388)
		(size 0.508)
		(drill 0.254)
		(layers "F.Cu" "B.Cu")
		(net "M_DEF_RST_N")
	)
	(via
		(at 251.923804 -97.690686)
		(size 0.508)
		(drill 0.254)
		(layers "F.Cu" "B.Cu")
		(net "M_DEF_RST_N")
	)
	(via
		(at 243.149882 -131.586478)
		(size 0.508)
		(drill 0.254)
		(layers "F.Cu" "B.Cu")
		(net "M_DEF_RST_N")
	)
	(via
		(at 243.149882 -141.187678)
		(size 0.4572)
		(drill 0.2032)
		(layers "F.Cu" "B.Cu")
		(net "M_DEF_RST_N")
	)
	(segment
		(start 243.15039 -142.477236)
		(end 243.149882 -142.476982)
		(width 0.10795)
		(layer "B.Cu")
		(net "M_DEF_RST_N")
	)
	(segment
		(start 243.149882 -132.875782)
		(end 243.149882 -131.586478)
		(width 0.10795)
		(layer "B.Cu")
		(net "M_DEF_RST_N")
	)
	(segment
		(start 243.15039 -132.876036)
		(end 243.149882 -132.875782)
		(width 0.10795)
		(layer "B.Cu")
		(net "M_DEF_RST_N")
	)
	(segment
		(start 243.15039 -152.078436)
		(end 243.149882 -152.078182)
		(width 0.10795)
		(layer "B.Cu")
		(net "M_DEF_RST_N")
	)
	(segment
		(start 243.149882 -152.078182)
		(end 243.149882 -150.788878)
		(width 0.10795)
		(layer "B.Cu")
		(net "M_DEF_RST_N")
	)
	(segment
		(start 243.149882 -142.476982)
		(end 243.149882 -141.187678)
		(width 0.10795)
		(layer "B.Cu")
		(net "M_DEF_RST_N")
	)
	(segment
		(start 251.1298 -120.381776)
		(end 244.602 -126.909576)
		(width 0.089408)
		(layer "In11.Cu")
		(net "M_DEF_RST_N")
	)
	(segment
		(start 244.602 -129.6162)
		(end 244.0178 -130.2004)
		(width 0.089408)
		(layer "In11.Cu")
		(net "M_DEF_RST_N")
	)
	(segment
		(start 243.586 -132.022596)
		(end 243.586 -134.027926)
		(width 0.089408)
		(layer "In11.Cu")
		(net "M_DEF_RST_N")
	)
	(segment
		(start 244.602 -126.909576)
		(end 244.602 -129.6162)
		(width 0.089408)
		(layer "In11.Cu")
		(net "M_DEF_RST_N")
	)
	(segment
		(start 243.586 -151.224996)
		(end 243.586 -153.92019)
		(width 0.089408)
		(layer "In11.Cu")
		(net "M_DEF_RST_N")
	)
	(segment
		(start 251.831094 -99.08159)
		(end 251.159518 -99.753166)
		(width 0.0889)
		(layer "In11.Cu")
		(net "M_DEF_RST_N")
	)
	(segment
		(start 243.282724 -134.331202)
		(end 243.633244 -134.681722)
		(width 0.089408)
		(layer "In11.Cu")
		(net "M_DEF_RST_N")
	)
	(segment
		(start 251.2314 -101.290374)
		(end 251.2314 -106.400854)
		(width 0.089408)
		(layer "In11.Cu")
		(net "M_DEF_RST_N")
	)
	(segment
		(start 243.586 -143.59509)
		(end 243.228368 -143.952722)
		(width 0.089408)
		(layer "In11.Cu")
		(net "M_DEF_RST_N")
	)
	(segment
		(start 251.923804 -97.690686)
		(end 252.253242 -98.45167)
		(width 0.0889)
		(layer "In11.Cu")
		(net "M_DEF_RST_N")
	)
	(segment
		(start 244.0178 -130.2004)
		(end 244.0178 -130.2258)
		(width 0.089408)
		(layer "In11.Cu")
		(net "M_DEF_RST_N")
	)
	(segment
		(start 251.92863 -99.08159)
		(end 251.831094 -99.08159)
		(width 0.0889)
		(layer "In11.Cu")
		(net "M_DEF_RST_N")
	)
	(segment
		(start 243.586 -141.623796)
		(end 243.586 -143.59509)
		(width 0.089408)
		(layer "In11.Cu")
		(net "M_DEF_RST_N")
	)
	(segment
		(start 243.670836 -139.657836)
		(end 243.670836 -140.666724)
		(width 0.089408)
		(layer "In11.Cu")
		(net "M_DEF_RST_N")
	)
	(segment
		(start 243.5606 -139.5476)
		(end 243.670836 -139.657836)
		(width 0.089408)
		(layer "In11.Cu")
		(net "M_DEF_RST_N")
	)
	(segment
		(start 243.633244 -135.955024)
		(end 243.5606 -136.027668)
		(width 0.089408)
		(layer "In11.Cu")
		(net "M_DEF_RST_N")
	)
	(segment
		(start 252.253242 -98.45167)
		(end 252.27534 -98.490024)
		(width 0.0889)
		(layer "In11.Cu")
		(net "M_DEF_RST_N")
	)
	(segment
		(start 243.586 -149.0726)
		(end 243.65585 -149.14245)
		(width 0.089408)
		(layer "In11.Cu")
		(net "M_DEF_RST_N")
	)
	(segment
		(start 243.66347 -145.743676)
		(end 243.586 -145.821146)
		(width 0.089408)
		(layer "In11.Cu")
		(net "M_DEF_RST_N")
	)
	(segment
		(start 243.459 -130.7846)
		(end 243.459 -131.27736)
		(width 0.089408)
		(layer "In11.Cu")
		(net "M_DEF_RST_N")
	)
	(segment
		(start 243.633244 -134.681722)
		(end 243.633244 -135.955024)
		(width 0.089408)
		(layer "In11.Cu")
		(net "M_DEF_RST_N")
	)
	(segment
		(start 251.2314 -106.400854)
		(end 251.1298 -106.502454)
		(width 0.089408)
		(layer "In11.Cu")
		(net "M_DEF_RST_N")
	)
	(segment
		(start 243.65585 -149.14245)
		(end 243.65585 -150.28291)
		(width 0.089408)
		(layer "In11.Cu")
		(net "M_DEF_RST_N")
	)
	(segment
		(start 243.65585 -150.28291)
		(end 243.149882 -150.788878)
		(width 0.089408)
		(layer "In11.Cu")
		(net "M_DEF_RST_N")
	)
	(segment
		(start 243.149882 -131.586478)
		(end 243.586 -132.022596)
		(width 0.089408)
		(layer "In11.Cu")
		(net "M_DEF_RST_N")
	)
	(segment
		(start 251.159518 -101.218492)
		(end 251.2314 -101.290374)
		(width 0.089408)
		(layer "In11.Cu")
		(net "M_DEF_RST_N")
	)
	(segment
		(start 244.0178 -130.2258)
		(end 243.459 -130.7846)
		(width 0.089408)
		(layer "In11.Cu")
		(net "M_DEF_RST_N")
	)
	(segment
		(start 243.5606 -136.027668)
		(end 243.5606 -139.5476)
		(width 0.089408)
		(layer "In11.Cu")
		(net "M_DEF_RST_N")
	)
	(segment
		(start 243.586 -145.821146)
		(end 243.586 -149.0726)
		(width 0.089408)
		(layer "In11.Cu")
		(net "M_DEF_RST_N")
	)
	(segment
		(start 243.149882 -141.187678)
		(end 243.586 -141.623796)
		(width 0.089408)
		(layer "In11.Cu")
		(net "M_DEF_RST_N")
	)
	(segment
		(start 243.149882 -150.788878)
		(end 243.586 -151.224996)
		(width 0.089408)
		(layer "In11.Cu")
		(net "M_DEF_RST_N")
	)
	(segment
		(start 251.1298 -106.502454)
		(end 251.1298 -120.381776)
		(width 0.089408)
		(layer "In11.Cu")
		(net "M_DEF_RST_N")
	)
	(segment
		(start 243.586 -134.027926)
		(end 243.282724 -134.331202)
		(width 0.089408)
		(layer "In11.Cu")
		(net "M_DEF_RST_N")
	)
	(segment
		(start 243.670836 -140.666724)
		(end 243.149882 -141.187678)
		(width 0.089408)
		(layer "In11.Cu")
		(net "M_DEF_RST_N")
	)
	(segment
		(start 243.228368 -143.952722)
		(end 243.66347 -144.387824)
		(width 0.089408)
		(layer "In11.Cu")
		(net "M_DEF_RST_N")
	)
	(segment
		(start 243.459 -131.27736)
		(end 243.149882 -131.586478)
		(width 0.089408)
		(layer "In11.Cu")
		(net "M_DEF_RST_N")
	)
	(segment
		(start 243.66347 -144.387824)
		(end 243.66347 -145.743676)
		(width 0.089408)
		(layer "In11.Cu")
		(net "M_DEF_RST_N")
	)
	(segment
		(start 251.159518 -99.753166)
		(end 251.159518 -101.218492)
		(width 0.089408)
		(layer "In11.Cu")
		(net "M_DEF_RST_N")
	)
	(segment
		(start 243.586 -153.92019)
		(end 243.27231 -154.23388)
		(width 0.089408)
		(layer "In11.Cu")
		(net "M_DEF_RST_N")
	)
	(arc
		(start 252.27534 -98.490024)
		(mid 252.269052 -98.883679)
		(end 251.92863 -99.08159)
		(width 0.0889)
		(layer "In11.Cu")
		(net "M_DEF_RST_N")
	)
	(segment
		(start 254.212344 -85.803486)
		(end 253.640844 -85.803486)
		(width 0.1016)
		(layer "F.Cu")
		(net "M_D_CPU_VREF")
	)
	(via
		(at 192.024 -133.5913)
		(size 0.508)
		(drill 0.254)
		(layers "F.Cu" "B.Cu")
		(net "M_D_CPU_VREF")
	)
	(via
		(at 209.296 -102.327202)
		(size 0.508)
		(drill 0.254)
		(layers "F.Cu" "B.Cu")
		(net "M_D_CPU_VREF")
	)
	(via
		(at 253.640844 -85.803486)
		(size 0.508)
		(drill 0.254)
		(layers "F.Cu" "B.Cu")
		(net "M_D_CPU_VREF")
	)
	(segment
		(start 192.024 -133.5913)
		(end 192.024 -134.874)
		(width 0.254)
		(layer "B.Cu")
		(net "M_D_CPU_VREF")
	)
	(segment
		(start 192.024 -134.874)
		(end 192.913 -134.874)
		(width 0.254)
		(layer "B.Cu")
		(net "M_D_CPU_VREF")
	)
	(segment
		(start 199.8218 -109.934756)
		(end 199.8218 -109.934502)
		(width 0.254)
		(layer "In2.Cu")
		(net "M_D_CPU_VREF")
	)
	(segment
		(start 201.345546 -109.0422)
		(end 202.1713 -109.0422)
		(width 0.254)
		(layer "In2.Cu")
		(net "M_D_CPU_VREF")
	)
	(segment
		(start 202.1713 -109.0422)
		(end 208.886298 -102.327202)
		(width 0.254)
		(layer "In2.Cu")
		(net "M_D_CPU_VREF")
	)
	(segment
		(start 194.7418 -123.459494)
		(end 194.7418 -115.014756)
		(width 0.254)
		(layer "In2.Cu")
		(net "M_D_CPU_VREF")
	)
	(segment
		(start 200.714356 -109.041946)
		(end 201.345292 -109.041946)
		(width 0.254)
		(layer "In2.Cu")
		(net "M_D_CPU_VREF")
	)
	(segment
		(start 201.345292 -109.041946)
		(end 201.345546 -109.0422)
		(width 0.254)
		(layer "In2.Cu")
		(net "M_D_CPU_VREF")
	)
	(segment
		(start 191.7192 -126.482094)
		(end 194.7418 -123.459494)
		(width 0.254)
		(layer "In2.Cu")
		(net "M_D_CPU_VREF")
	)
	(segment
		(start 194.7418 -115.014756)
		(end 199.8218 -109.934756)
		(width 0.254)
		(layer "In2.Cu")
		(net "M_D_CPU_VREF")
	)
	(segment
		(start 208.886298 -102.327202)
		(end 209.296 -102.327202)
		(width 0.254)
		(layer "In2.Cu")
		(net "M_D_CPU_VREF")
	)
	(segment
		(start 192.024 -133.5913)
		(end 191.7192 -133.2865)
		(width 0.254)
		(layer "In2.Cu")
		(net "M_D_CPU_VREF")
	)
	(segment
		(start 191.7192 -133.2865)
		(end 191.7192 -126.482094)
		(width 0.254)
		(layer "In2.Cu")
		(net "M_D_CPU_VREF")
	)
	(segment
		(start 199.8218 -109.934502)
		(end 200.714356 -109.041946)
		(width 0.254)
		(layer "In2.Cu")
		(net "M_D_CPU_VREF")
	)
	(segment
		(start 252.92558 -86.819994)
		(end 252.58776 -86.819994)
		(width 0.2286)
		(layer "In9.Cu")
		(net "M_D_CPU_VREF")
	)
	(segment
		(start 241.842036 -93.207332)
		(end 241.4016 -93.207332)
		(width 0.2286)
		(layer "In9.Cu")
		(net "M_D_CPU_VREF")
	)
	(segment
		(start 241.4016 -93.207332)
		(end 240.957862 -92.763594)
		(width 0.2286)
		(layer "In9.Cu")
		(net "M_D_CPU_VREF")
	)
	(segment
		(start 248.658634 -89.29624)
		(end 248.29516 -89.29624)
		(width 0.2286)
		(layer "In9.Cu")
		(net "M_D_CPU_VREF")
	)
	(segment
		(start 246.303038 -91.552522)
		(end 246.303038 -91.96705)
		(width 0.2286)
		(layer "In9.Cu")
		(net "M_D_CPU_VREF")
	)
	(segment
		(start 210.38439 -100.79101)
		(end 209.296 -101.8794)
		(width 0.3048)
		(layer "In9.Cu")
		(net "M_D_CPU_VREF")
	)
	(segment
		(start 236.690916 -93.207332)
		(end 236.25048 -93.207332)
		(width 0.2286)
		(layer "In9.Cu")
		(net "M_D_CPU_VREF")
	)
	(segment
		(start 236.25048 -93.207332)
		(end 235.806742 -92.763594)
		(width 0.2286)
		(layer "In9.Cu")
		(net "M_D_CPU_VREF")
	)
	(segment
		(start 250.426982 -88.254332)
		(end 250.038362 -88.254332)
		(width 0.2286)
		(layer "In9.Cu")
		(net "M_D_CPU_VREF")
	)
	(segment
		(start 246.108728 -92.712286)
		(end 245.745254 -92.712286)
		(width 0.2286)
		(layer "In9.Cu")
		(net "M_D_CPU_VREF")
	)
	(segment
		(start 244.835426 -93.207332)
		(end 244.391688 -92.763594)
		(width 0.2286)
		(layer "In9.Cu")
		(net "M_D_CPU_VREF")
	)
	(segment
		(start 209.296 -101.8794)
		(end 209.296 -102.327202)
		(width 0.3048)
		(layer "In9.Cu")
		(net "M_D_CPU_VREF")
	)
	(segment
		(start 245.745254 -92.712286)
		(end 245.250208 -93.207332)
		(width 0.2286)
		(layer "In9.Cu")
		(net "M_D_CPU_VREF")
	)
	(segment
		(start 253.25197 -86.493604)
		(end 252.92558 -86.819994)
		(width 0.2286)
		(layer "In9.Cu")
		(net "M_D_CPU_VREF")
	)
	(segment
		(start 243.558822 -93.207332)
		(end 243.11864 -93.207332)
		(width 0.2286)
		(layer "In9.Cu")
		(net "M_D_CPU_VREF")
	)
	(segment
		(start 248.10085 -90.456004)
		(end 247.825768 -90.731086)
		(width 0.2286)
		(layer "In9.Cu")
		(net "M_D_CPU_VREF")
	)
	(segment
		(start 251.719334 -87.2998)
		(end 251.20854 -87.810594)
		(width 0.2286)
		(layer "In9.Cu")
		(net "M_D_CPU_VREF")
	)
	(segment
		(start 246.38381 -92.048076)
		(end 246.38381 -92.437204)
		(width 0.2286)
		(layer "In9.Cu")
		(net "M_D_CPU_VREF")
	)
	(segment
		(start 247.462294 -90.731086)
		(end 246.91594 -91.27744)
		(width 0.2286)
		(layer "In9.Cu")
		(net "M_D_CPU_VREF")
	)
	(segment
		(start 246.303038 -91.96705)
		(end 246.38381 -92.048076)
		(width 0.2286)
		(layer "In9.Cu")
		(net "M_D_CPU_VREF")
	)
	(segment
		(start 242.674902 -92.763594)
		(end 242.285774 -92.763594)
		(width 0.2286)
		(layer "In9.Cu")
		(net "M_D_CPU_VREF")
	)
	(segment
		(start 234.973876 -93.207332)
		(end 232.094532 -93.207332)
		(width 0.2286)
		(layer "In9.Cu")
		(net "M_D_CPU_VREF")
	)
	(segment
		(start 240.568734 -92.763594)
		(end 240.124996 -93.207332)
		(width 0.2286)
		(layer "In9.Cu")
		(net "M_D_CPU_VREF")
	)
	(segment
		(start 244.00256 -92.763594)
		(end 243.558822 -93.207332)
		(width 0.2286)
		(layer "In9.Cu")
		(net "M_D_CPU_VREF")
	)
	(segment
		(start 235.806742 -92.763594)
		(end 235.417614 -92.763594)
		(width 0.2286)
		(layer "In9.Cu")
		(net "M_D_CPU_VREF")
	)
	(segment
		(start 248.10085 -90.041222)
		(end 248.10085 -90.456004)
		(width 0.2286)
		(layer "In9.Cu")
		(net "M_D_CPU_VREF")
	)
	(segment
		(start 222.375984 -93.207332)
		(end 214.792306 -100.79101)
		(width 0.3048)
		(layer "In9.Cu")
		(net "M_D_CPU_VREF")
	)
	(segment
		(start 252.107954 -87.2998)
		(end 251.719334 -87.2998)
		(width 0.2286)
		(layer "In9.Cu")
		(net "M_D_CPU_VREF")
	)
	(segment
		(start 250.038362 -88.254332)
		(end 249.4915 -88.801194)
		(width 0.2286)
		(layer "In9.Cu")
		(net "M_D_CPU_VREF")
	)
	(segment
		(start 240.957862 -92.763594)
		(end 240.568734 -92.763594)
		(width 0.2286)
		(layer "In9.Cu")
		(net "M_D_CPU_VREF")
	)
	(segment
		(start 243.11864 -93.207332)
		(end 242.674902 -92.763594)
		(width 0.2286)
		(layer "In9.Cu")
		(net "M_D_CPU_VREF")
	)
	(segment
		(start 250.87072 -87.810594)
		(end 250.426982 -88.254332)
		(width 0.2286)
		(layer "In9.Cu")
		(net "M_D_CPU_VREF")
	)
	(segment
		(start 239.240822 -92.763594)
		(end 238.851694 -92.763594)
		(width 0.2286)
		(layer "In9.Cu")
		(net "M_D_CPU_VREF")
	)
	(segment
		(start 242.285774 -92.763594)
		(end 241.842036 -93.207332)
		(width 0.2286)
		(layer "In9.Cu")
		(net "M_D_CPU_VREF")
	)
	(segment
		(start 237.96752 -93.207332)
		(end 237.523782 -92.763594)
		(width 0.2286)
		(layer "In9.Cu")
		(net "M_D_CPU_VREF")
	)
	(segment
		(start 251.20854 -87.810594)
		(end 250.87072 -87.810594)
		(width 0.2286)
		(layer "In9.Cu")
		(net "M_D_CPU_VREF")
	)
	(segment
		(start 246.57812 -91.27744)
		(end 246.303038 -91.552522)
		(width 0.2286)
		(layer "In9.Cu")
		(net "M_D_CPU_VREF")
	)
	(segment
		(start 237.134654 -92.763594)
		(end 236.690916 -93.207332)
		(width 0.2286)
		(layer "In9.Cu")
		(net "M_D_CPU_VREF")
	)
	(segment
		(start 246.38381 -92.437204)
		(end 246.108728 -92.712286)
		(width 0.2286)
		(layer "In9.Cu")
		(net "M_D_CPU_VREF")
	)
	(segment
		(start 240.124996 -93.207332)
		(end 239.68456 -93.207332)
		(width 0.2286)
		(layer "In9.Cu")
		(net "M_D_CPU_VREF")
	)
	(segment
		(start 239.68456 -93.207332)
		(end 239.240822 -92.763594)
		(width 0.2286)
		(layer "In9.Cu")
		(net "M_D_CPU_VREF")
	)
	(segment
		(start 252.58776 -86.819994)
		(end 252.107954 -87.2998)
		(width 0.2286)
		(layer "In9.Cu")
		(net "M_D_CPU_VREF")
	)
	(segment
		(start 248.020078 -89.96045)
		(end 248.10085 -90.041222)
		(width 0.2286)
		(layer "In9.Cu")
		(net "M_D_CPU_VREF")
	)
	(segment
		(start 237.523782 -92.763594)
		(end 237.134654 -92.763594)
		(width 0.2286)
		(layer "In9.Cu")
		(net "M_D_CPU_VREF")
	)
	(segment
		(start 245.250208 -93.207332)
		(end 244.835426 -93.207332)
		(width 0.2286)
		(layer "In9.Cu")
		(net "M_D_CPU_VREF")
	)
	(segment
		(start 246.91594 -91.27744)
		(end 246.57812 -91.27744)
		(width 0.2286)
		(layer "In9.Cu")
		(net "M_D_CPU_VREF")
	)
	(segment
		(start 235.417614 -92.763594)
		(end 234.973876 -93.207332)
		(width 0.2286)
		(layer "In9.Cu")
		(net "M_D_CPU_VREF")
	)
	(segment
		(start 238.851694 -92.763594)
		(end 238.407956 -93.207332)
		(width 0.2286)
		(layer "In9.Cu")
		(net "M_D_CPU_VREF")
	)
	(segment
		(start 248.020078 -89.571322)
		(end 248.020078 -89.96045)
		(width 0.2286)
		(layer "In9.Cu")
		(net "M_D_CPU_VREF")
	)
	(segment
		(start 247.825768 -90.731086)
		(end 247.462294 -90.731086)
		(width 0.2286)
		(layer "In9.Cu")
		(net "M_D_CPU_VREF")
	)
	(segment
		(start 249.4915 -88.801194)
		(end 249.15368 -88.801194)
		(width 0.2286)
		(layer "In9.Cu")
		(net "M_D_CPU_VREF")
	)
	(segment
		(start 244.391688 -92.763594)
		(end 244.00256 -92.763594)
		(width 0.2286)
		(layer "In9.Cu")
		(net "M_D_CPU_VREF")
	)
	(segment
		(start 249.15368 -88.801194)
		(end 248.658634 -89.29624)
		(width 0.2286)
		(layer "In9.Cu")
		(net "M_D_CPU_VREF")
	)
	(segment
		(start 232.094532 -93.207332)
		(end 222.375984 -93.207332)
		(width 0.3048)
		(layer "In9.Cu")
		(net "M_D_CPU_VREF")
	)
	(segment
		(start 253.640844 -85.803486)
		(end 253.25197 -86.19236)
		(width 0.2286)
		(layer "In9.Cu")
		(net "M_D_CPU_VREF")
	)
	(segment
		(start 253.25197 -86.19236)
		(end 253.25197 -86.493604)
		(width 0.2286)
		(layer "In9.Cu")
		(net "M_D_CPU_VREF")
	)
	(segment
		(start 214.792306 -100.79101)
		(end 210.38439 -100.79101)
		(width 0.3048)
		(layer "In9.Cu")
		(net "M_D_CPU_VREF")
	)
	(segment
		(start 238.407956 -93.207332)
		(end 237.96752 -93.207332)
		(width 0.2286)
		(layer "In9.Cu")
		(net "M_D_CPU_VREF")
	)
	(segment
		(start 248.29516 -89.29624)
		(end 248.020078 -89.571322)
		(width 0.2286)
		(layer "In9.Cu")
		(net "M_D_CPU_VREF")
	)
	(segment
		(start 265.249914 -0.821182)
		(end 265.249914 0.5588)
		(width 0.1651)
		(layer "F.Cu")
		(net "M_C_PAR")
	)
	(segment
		(start 265.250422 -0.821182)
		(end 265.249914 -0.821182)
		(width 0.1651)
		(layer "F.Cu")
		(net "M_C_PAR")
	)
	(segment
		(start 261.08025 -58.06694)
		(end 260.50875 -58.06694)
		(width 0.1651)
		(layer "F.Cu")
		(net "M_C_PAR")
	)
	(via
		(at 260.50875 -58.06694)
		(size 0.508)
		(drill 0.254)
		(layers "F.Cu" "B.Cu")
		(net "M_C_PAR")
	)
	(via
		(at 265.24966 -2.995168)
		(size 0.508)
		(drill 0.254)
		(layers "F.Cu" "B.Cu")
		(net "M_C_PAR")
	)
	(via
		(at 265.249914 0.5588)
		(size 0.508)
		(drill 0.254)
		(layers "F.Cu" "B.Cu")
		(net "M_C_PAR")
	)
	(segment
		(start 265.250422 -2.994406)
		(end 265.24966 -2.995168)
		(width 0.1651)
		(layer "B.Cu")
		(net "M_C_PAR")
	)
	(segment
		(start 265.250422 -1.021842)
		(end 265.250422 -2.994406)
		(width 0.1651)
		(layer "B.Cu")
		(net "M_C_PAR")
	)
	(segment
		(start 264.3124 -25.306528)
		(end 264.7442 -24.874728)
		(width 0.14224)
		(layer "In2.Cu")
		(net "M_C_PAR")
	)
	(segment
		(start 260.860286 -52.922424)
		(end 260.85546 -52.913788)
		(width 0.0889)
		(layer "In2.Cu")
		(net "M_C_PAR")
	)
	(segment
		(start 261.68096 -48.328834)
		(end 261.68096 -29.17698)
		(width 0.14224)
		(layer "In2.Cu")
		(net "M_C_PAR")
	)
	(segment
		(start 264.7442 -24.874728)
		(end 264.7442 -3.9116)
		(width 0.14224)
		(layer "In2.Cu")
		(net "M_C_PAR")
	)
	(segment
		(start 265.249914 0.289814)
		(end 265.249914 0.5588)
		(width 0.14224)
		(layer "In2.Cu")
		(net "M_C_PAR")
	)
	(segment
		(start 261.68096 -29.17698)
		(end 264.3124 -26.54554)
		(width 0.14224)
		(layer "In2.Cu")
		(net "M_C_PAR")
	)
	(segment
		(start 260.50875 -58.06694)
		(end 260.838696 -57.305194)
		(width 0.0889)
		(layer "In2.Cu")
		(net "M_C_PAR")
	)
	(segment
		(start 260.860286 -53.913024)
		(end 260.85546 -53.904388)
		(width 0.0889)
		(layer "In2.Cu")
		(net "M_C_PAR")
	)
	(segment
		(start 260.84911 -52.333906)
		(end 260.85546 -52.323238)
		(width 0.0889)
		(layer "In2.Cu")
		(net "M_C_PAR")
	)
	(segment
		(start 260.85546 -55.885588)
		(end 260.84911 -55.87492)
		(width 0.0889)
		(layer "In2.Cu")
		(net "M_C_PAR")
	)
	(segment
		(start 265.24966 -2.995168)
		(end 265.24966 0.28956)
		(width 0.14224)
		(layer "In2.Cu")
		(net "M_C_PAR")
	)
	(segment
		(start 260.860286 -54.903624)
		(end 260.85546 -54.894988)
		(width 0.0889)
		(layer "In2.Cu")
		(net "M_C_PAR")
	)
	(segment
		(start 260.85546 -54.894988)
		(end 260.84911 -54.88432)
		(width 0.0889)
		(layer "In2.Cu")
		(net "M_C_PAR")
	)
	(segment
		(start 264.7442 -3.9116)
		(end 265.24966 -3.40614)
		(width 0.14224)
		(layer "In2.Cu")
		(net "M_C_PAR")
	)
	(segment
		(start 260.838696 -57.305194)
		(end 260.85546 -57.276238)
		(width 0.0889)
		(layer "In2.Cu")
		(net "M_C_PAR")
	)
	(segment
		(start 264.3124 -26.54554)
		(end 264.3124 -25.306528)
		(width 0.14224)
		(layer "In2.Cu")
		(net "M_C_PAR")
	)
	(segment
		(start 261.136892 -50.647346)
		(end 261.680452 -50.103786)
		(width 0.0889)
		(layer "In2.Cu")
		(net "M_C_PAR")
	)
	(segment
		(start 260.965188 -52.075588)
		(end 261.136892 -51.904138)
		(width 0.0889)
		(layer "In2.Cu")
		(net "M_C_PAR")
	)
	(segment
		(start 260.85546 -56.876188)
		(end 260.84911 -56.86552)
		(width 0.0889)
		(layer "In2.Cu")
		(net "M_C_PAR")
	)
	(segment
		(start 260.85546 -53.904388)
		(end 260.84911 -53.89372)
		(width 0.0889)
		(layer "In2.Cu")
		(net "M_C_PAR")
	)
	(segment
		(start 260.860286 -56.884824)
		(end 260.85546 -56.876188)
		(width 0.0889)
		(layer "In2.Cu")
		(net "M_C_PAR")
	)
	(segment
		(start 261.680452 -48.329342)
		(end 261.68096 -48.328834)
		(width 0.14224)
		(layer "In2.Cu")
		(net "M_C_PAR")
	)
	(segment
		(start 260.860286 -55.894224)
		(end 260.85546 -55.885588)
		(width 0.0889)
		(layer "In2.Cu")
		(net "M_C_PAR")
	)
	(segment
		(start 261.680452 -50.103786)
		(end 261.680452 -48.329342)
		(width 0.0889)
		(layer "In2.Cu")
		(net "M_C_PAR")
	)
	(segment
		(start 265.24966 0.28956)
		(end 265.249914 0.289814)
		(width 0.14224)
		(layer "In2.Cu")
		(net "M_C_PAR")
	)
	(segment
		(start 265.24966 -3.40614)
		(end 265.24966 -2.995168)
		(width 0.14224)
		(layer "In2.Cu")
		(net "M_C_PAR")
	)
	(segment
		(start 261.136892 -51.904138)
		(end 261.136892 -50.647346)
		(width 0.0889)
		(layer "In2.Cu")
		(net "M_C_PAR")
	)
	(segment
		(start 260.943598 -52.097432)
		(end 260.965188 -52.075588)
		(width 0.0889)
		(layer "In2.Cu")
		(net "M_C_PAR")
	)
	(arc
		(start 260.84911 -53.89372)
		(mid 260.776312 -53.602957)
		(end 260.85546 -53.313838)
		(width 0.0889)
		(layer "In2.Cu")
		(net "M_C_PAR")
	)
	(arc
		(start 260.85546 -56.285638)
		(mid 260.90893 -56.090575)
		(end 260.860286 -55.894224)
		(width 0.0889)
		(layer "In2.Cu")
		(net "M_C_PAR")
	)
	(arc
		(start 260.85546 -53.313838)
		(mid 260.90893 -53.118775)
		(end 260.860286 -52.922424)
		(width 0.0889)
		(layer "In2.Cu")
		(net "M_C_PAR")
	)
	(arc
		(start 260.85546 -54.304438)
		(mid 260.90893 -54.109375)
		(end 260.860286 -53.913024)
		(width 0.0889)
		(layer "In2.Cu")
		(net "M_C_PAR")
	)
	(arc
		(start 260.85546 -52.913788)
		(mid 260.776238 -52.62467)
		(end 260.84911 -52.333906)
		(width 0.0889)
		(layer "In2.Cu")
		(net "M_C_PAR")
	)
	(arc
		(start 260.85546 -57.276238)
		(mid 260.90893 -57.081175)
		(end 260.860286 -56.884824)
		(width 0.0889)
		(layer "In2.Cu")
		(net "M_C_PAR")
	)
	(arc
		(start 260.85546 -52.323238)
		(mid 260.908851 -52.213972)
		(end 260.943598 -52.097432)
		(width 0.0889)
		(layer "In2.Cu")
		(net "M_C_PAR")
	)
	(arc
		(start 260.85546 -55.295038)
		(mid 260.90893 -55.099975)
		(end 260.860286 -54.903624)
		(width 0.0889)
		(layer "In2.Cu")
		(net "M_C_PAR")
	)
	(arc
		(start 260.84911 -55.87492)
		(mid 260.776312 -55.584157)
		(end 260.85546 -55.295038)
		(width 0.0889)
		(layer "In2.Cu")
		(net "M_C_PAR")
	)
	(arc
		(start 260.84911 -56.86552)
		(mid 260.776312 -56.574757)
		(end 260.85546 -56.285638)
		(width 0.0889)
		(layer "In2.Cu")
		(net "M_C_PAR")
	)
	(arc
		(start 260.84911 -54.88432)
		(mid 260.776312 -54.593557)
		(end 260.85546 -54.304438)
		(width 0.0889)
		(layer "In2.Cu")
		(net "M_C_PAR")
	)
	(segment
		(start 266.231116 -60.047886)
		(end 265.659616 -60.047886)
		(width 0.1016)
		(layer "F.Cu")
		(net "M_C_ODT<3>")
	)
	(via
		(at 265.659616 -60.047886)
		(size 0.508)
		(drill 0.254)
		(layers "F.Cu" "B.Cu")
		(net "M_C_ODT<3>")
	)
	(via
		(at 276.29993 -4.332986)
		(size 0.4572)
		(drill 0.2032)
		(layers "F.Cu" "B.Cu")
		(net "M_C_ODT<3>")
	)
	(segment
		(start 276.300438 -5.621782)
		(end 276.29993 -5.621782)
		(width 0.1651)
		(layer "B.Cu")
		(net "M_C_ODT<3>")
	)
	(segment
		(start 276.29993 -5.621782)
		(end 276.29993 -4.332986)
		(width 0.1651)
		(layer "B.Cu")
		(net "M_C_ODT<3>")
	)
	(segment
		(start 275.096478 -22.662896)
		(end 274.842478 -22.408896)
		(width 0.14224)
		(layer "In2.Cu")
		(net "M_C_ODT<3>")
	)
	(segment
		(start 274.664424 -12.54125)
		(end 275.040344 -12.16533)
		(width 0.14224)
		(layer "In2.Cu")
		(net "M_C_ODT<3>")
	)
	(segment
		(start 274.658074 -18.03019)
		(end 274.658074 -17.34439)
		(width 0.14224)
		(layer "In2.Cu")
		(net "M_C_ODT<3>")
	)
	(segment
		(start 266.7 -50.2412)
		(end 266.7 -49.71796)
		(width 0.0889)
		(layer "In2.Cu")
		(net "M_C_ODT<3>")
	)
	(segment
		(start 275.008594 -13.67028)
		(end 274.664424 -13.32611)
		(width 0.14224)
		(layer "In2.Cu")
		(net "M_C_ODT<3>")
	)
	(segment
		(start 273.1008 -27.348434)
		(end 273.1008 -26.034746)
		(width 0.14224)
		(layer "In2.Cu")
		(net "M_C_ODT<3>")
	)
	(segment
		(start 275.035772 -21.771102)
		(end 275.035772 -18.407888)
		(width 0.14224)
		(layer "In2.Cu")
		(net "M_C_ODT<3>")
	)
	(segment
		(start 274.842478 -21.964396)
		(end 275.035772 -21.771102)
		(width 0.14224)
		(layer "In2.Cu")
		(net "M_C_ODT<3>")
	)
	(segment
		(start 274.842478 -22.408896)
		(end 274.842478 -21.964396)
		(width 0.14224)
		(layer "In2.Cu")
		(net "M_C_ODT<3>")
	)
	(segment
		(start 275.040344 -12.16533)
		(end 275.040344 -8.83412)
		(width 0.14224)
		(layer "In2.Cu")
		(net "M_C_ODT<3>")
	)
	(segment
		(start 267.77696 -32.672274)
		(end 273.1008 -27.348434)
		(width 0.14224)
		(layer "In2.Cu")
		(net "M_C_ODT<3>")
	)
	(segment
		(start 266.079224 -59.624214)
		(end 266.079224 -50.861976)
		(width 0.0889)
		(layer "In2.Cu")
		(net "M_C_ODT<3>")
	)
	(segment
		(start 275.03882 -16.963644)
		(end 275.03882 -14.6939)
		(width 0.14224)
		(layer "In2.Cu")
		(net "M_C_ODT<3>")
	)
	(segment
		(start 274.670774 -8.46455)
		(end 274.670774 -7.73049)
		(width 0.14224)
		(layer "In2.Cu")
		(net "M_C_ODT<3>")
	)
	(segment
		(start 274.670774 -7.73049)
		(end 275.042122 -7.359142)
		(width 0.14224)
		(layer "In2.Cu")
		(net "M_C_ODT<3>")
	)
	(segment
		(start 265.659616 -60.043822)
		(end 266.079224 -59.624214)
		(width 0.0889)
		(layer "In2.Cu")
		(net "M_C_ODT<3>")
	)
	(segment
		(start 267.77696 -48.641)
		(end 267.77696 -48.330358)
		(width 0.0889)
		(layer "In2.Cu")
		(net "M_C_ODT<3>")
	)
	(segment
		(start 275.042122 -7.359142)
		(end 275.042122 -5.590794)
		(width 0.14224)
		(layer "In2.Cu")
		(net "M_C_ODT<3>")
	)
	(segment
		(start 274.664424 -13.32611)
		(end 274.664424 -12.54125)
		(width 0.14224)
		(layer "In2.Cu")
		(net "M_C_ODT<3>")
	)
	(segment
		(start 275.096478 -23.183596)
		(end 275.096478 -22.662896)
		(width 0.14224)
		(layer "In2.Cu")
		(net "M_C_ODT<3>")
	)
	(segment
		(start 274.658074 -17.34439)
		(end 275.03882 -16.963644)
		(width 0.14224)
		(layer "In2.Cu")
		(net "M_C_ODT<3>")
	)
	(segment
		(start 266.079224 -50.861976)
		(end 266.7 -50.2412)
		(width 0.0889)
		(layer "In2.Cu")
		(net "M_C_ODT<3>")
	)
	(segment
		(start 275.035772 -18.407888)
		(end 274.658074 -18.03019)
		(width 0.14224)
		(layer "In2.Cu")
		(net "M_C_ODT<3>")
	)
	(segment
		(start 265.659616 -60.047886)
		(end 265.659616 -60.043822)
		(width 0.0889)
		(layer "In2.Cu")
		(net "M_C_ODT<3>")
	)
	(segment
		(start 275.03882 -14.6939)
		(end 275.008594 -14.663674)
		(width 0.14224)
		(layer "In2.Cu")
		(net "M_C_ODT<3>")
	)
	(segment
		(start 274.8534 -23.426674)
		(end 275.096478 -23.183596)
		(width 0.14224)
		(layer "In2.Cu")
		(net "M_C_ODT<3>")
	)
	(segment
		(start 267.77696 -48.330358)
		(end 267.77696 -32.672274)
		(width 0.14224)
		(layer "In2.Cu")
		(net "M_C_ODT<3>")
	)
	(segment
		(start 273.1008 -26.034746)
		(end 274.8534 -24.282146)
		(width 0.14224)
		(layer "In2.Cu")
		(net "M_C_ODT<3>")
	)
	(segment
		(start 275.040344 -8.83412)
		(end 274.670774 -8.46455)
		(width 0.14224)
		(layer "In2.Cu")
		(net "M_C_ODT<3>")
	)
	(segment
		(start 275.008594 -14.663674)
		(end 275.008594 -13.67028)
		(width 0.14224)
		(layer "In2.Cu")
		(net "M_C_ODT<3>")
	)
	(segment
		(start 274.8534 -24.282146)
		(end 274.8534 -23.426674)
		(width 0.14224)
		(layer "In2.Cu")
		(net "M_C_ODT<3>")
	)
	(segment
		(start 275.042122 -5.590794)
		(end 276.29993 -4.332986)
		(width 0.14224)
		(layer "In2.Cu")
		(net "M_C_ODT<3>")
	)
	(segment
		(start 266.7 -49.71796)
		(end 267.77696 -48.641)
		(width 0.0889)
		(layer "In2.Cu")
		(net "M_C_ODT<3>")
	)
	(segment
		(start 264.51433 -58.06694)
		(end 263.94283 -58.06694)
		(width 0.1016)
		(layer "F.Cu")
		(net "M_C_ODT<2>")
	)
	(via
		(at 272.899886 -4.328668)
		(size 0.4572)
		(drill 0.2032)
		(layers "F.Cu" "B.Cu")
		(net "M_C_ODT<2>")
	)
	(via
		(at 263.94283 -58.06694)
		(size 0.508)
		(drill 0.254)
		(layers "F.Cu" "B.Cu")
		(net "M_C_ODT<2>")
	)
	(segment
		(start 272.899886 -5.621782)
		(end 272.899886 -4.328668)
		(width 0.1651)
		(layer "B.Cu")
		(net "M_C_ODT<2>")
	)
	(segment
		(start 272.900394 -5.621782)
		(end 272.899886 -5.621782)
		(width 0.1651)
		(layer "B.Cu")
		(net "M_C_ODT<2>")
	)
	(segment
		(start 271.37614 -12.42949)
		(end 271.639284 -12.166346)
		(width 0.14224)
		(layer "In2.Cu")
		(net "M_C_ODT<2>")
	)
	(segment
		(start 271.639284 -12.166346)
		(end 271.639284 -11.406124)
		(width 0.14224)
		(layer "In2.Cu")
		(net "M_C_ODT<2>")
	)
	(segment
		(start 269.907258 -25.621742)
		(end 271.442434 -24.086566)
		(width 0.14224)
		(layer "In2.Cu")
		(net "M_C_ODT<2>")
	)
	(segment
		(start 271.426432 -20.247102)
		(end 271.745456 -20.247102)
		(width 0.14224)
		(layer "In2.Cu")
		(net "M_C_ODT<2>")
	)
	(segment
		(start 264.7442 -50.171096)
		(end 265.74496 -49.170336)
		(width 0.0889)
		(layer "In2.Cu")
		(net "M_C_ODT<2>")
	)
	(segment
		(start 271.745456 -20.247102)
		(end 271.900396 -20.092162)
		(width 0.14224)
		(layer "In2.Cu")
		(net "M_C_ODT<2>")
	)
	(segment
		(start 271.633696 -5.864098)
		(end 272.701512 -4.796282)
		(width 0.14224)
		(layer "In2.Cu")
		(net "M_C_ODT<2>")
	)
	(segment
		(start 264.289286 -55.885588)
		(end 264.280396 -55.870348)
		(width 0.0889)
		(layer "In2.Cu")
		(net "M_C_ODT<2>")
	)
	(segment
		(start 271.639284 -11.406124)
		(end 271.425416 -11.192256)
		(width 0.14224)
		(layer "In2.Cu")
		(net "M_C_ODT<2>")
	)
	(segment
		(start 271.442434 -21.964396)
		(end 271.900396 -21.506434)
		(width 0.14224)
		(layer "In2.Cu")
		(net "M_C_ODT<2>")
	)
	(segment
		(start 271.426432 -20.910042)
		(end 271.271492 -20.755102)
		(width 0.14224)
		(layer "In2.Cu")
		(net "M_C_ODT<2>")
	)
	(segment
		(start 271.637506 -19.209258)
		(end 271.637506 -18.218658)
		(width 0.14224)
		(layer "In2.Cu")
		(net "M_C_ODT<2>")
	)
	(segment
		(start 271.634966 -15.1257)
		(end 271.84477 -14.915896)
		(width 0.14224)
		(layer "In2.Cu")
		(net "M_C_ODT<2>")
	)
	(segment
		(start 272.701512 -4.796282)
		(end 272.701512 -4.527042)
		(width 0.14224)
		(layer "In2.Cu")
		(net "M_C_ODT<2>")
	)
	(segment
		(start 271.696434 -23.183596)
		(end 271.696434 -22.662896)
		(width 0.14224)
		(layer "In2.Cu")
		(net "M_C_ODT<2>")
	)
	(segment
		(start 271.745456 -20.910042)
		(end 271.426432 -20.910042)
		(width 0.14224)
		(layer "In2.Cu")
		(net "M_C_ODT<2>")
	)
	(segment
		(start 271.84477 -14.915896)
		(end 271.84477 -14.519402)
		(width 0.14224)
		(layer "In2.Cu")
		(net "M_C_ODT<2>")
	)
	(segment
		(start 271.639284 -10.529316)
		(end 271.639284 -8.789416)
		(width 0.14224)
		(layer "In2.Cu")
		(net "M_C_ODT<2>")
	)
	(segment
		(start 271.633696 -7.367524)
		(end 271.633696 -5.864098)
		(width 0.14224)
		(layer "In2.Cu")
		(net "M_C_ODT<2>")
	)
	(segment
		(start 264.289286 -53.904388)
		(end 264.280396 -53.889148)
		(width 0.0889)
		(layer "In2.Cu")
		(net "M_C_ODT<2>")
	)
	(segment
		(start 271.271492 -20.402042)
		(end 271.426432 -20.247102)
		(width 0.14224)
		(layer "In2.Cu")
		(net "M_C_ODT<2>")
	)
	(segment
		(start 271.425416 -10.743184)
		(end 271.639284 -10.529316)
		(width 0.14224)
		(layer "In2.Cu")
		(net "M_C_ODT<2>")
	)
	(segment
		(start 271.776698 -16.300196)
		(end 271.776698 -15.720568)
		(width 0.14224)
		(layer "In2.Cu")
		(net "M_C_ODT<2>")
	)
	(segment
		(start 264.289286 -56.876188)
		(end 264.280396 -56.860948)
		(width 0.0889)
		(layer "In2.Cu")
		(net "M_C_ODT<2>")
	)
	(segment
		(start 271.363948 -7.637272)
		(end 271.633696 -7.367524)
		(width 0.14224)
		(layer "In2.Cu")
		(net "M_C_ODT<2>")
	)
	(segment
		(start 271.442434 -23.437596)
		(end 271.696434 -23.183596)
		(width 0.14224)
		(layer "In2.Cu")
		(net "M_C_ODT<2>")
	)
	(segment
		(start 271.900396 -19.472148)
		(end 271.637506 -19.209258)
		(width 0.14224)
		(layer "In2.Cu")
		(net "M_C_ODT<2>")
	)
	(segment
		(start 271.271492 -20.755102)
		(end 271.271492 -20.402042)
		(width 0.14224)
		(layer "In2.Cu")
		(net "M_C_ODT<2>")
	)
	(segment
		(start 271.442434 -17.159986)
		(end 271.634712 -16.967708)
		(width 0.14224)
		(layer "In2.Cu")
		(net "M_C_ODT<2>")
	)
	(segment
		(start 271.442434 -22.408896)
		(end 271.442434 -21.964396)
		(width 0.14224)
		(layer "In2.Cu")
		(net "M_C_ODT<2>")
	)
	(segment
		(start 271.442434 -24.086566)
		(end 271.442434 -23.437596)
		(width 0.14224)
		(layer "In2.Cu")
		(net "M_C_ODT<2>")
	)
	(segment
		(start 271.634712 -16.442182)
		(end 271.776698 -16.300196)
		(width 0.14224)
		(layer "In2.Cu")
		(net "M_C_ODT<2>")
	)
	(segment
		(start 263.94283 -58.06694)
		(end 264.273284 -57.303162)
		(width 0.0889)
		(layer "In2.Cu")
		(net "M_C_ODT<2>")
	)
	(segment
		(start 271.37614 -13.385546)
		(end 271.37614 -12.42949)
		(width 0.14224)
		(layer "In2.Cu")
		(net "M_C_ODT<2>")
	)
	(segment
		(start 265.74496 -31.828994)
		(end 269.907258 -27.666696)
		(width 0.14224)
		(layer "In2.Cu")
		(net "M_C_ODT<2>")
	)
	(segment
		(start 271.442434 -18.023586)
		(end 271.442434 -17.159986)
		(width 0.14224)
		(layer "In2.Cu")
		(net "M_C_ODT<2>")
	)
	(segment
		(start 271.900396 -20.092162)
		(end 271.900396 -19.472148)
		(width 0.14224)
		(layer "In2.Cu")
		(net "M_C_ODT<2>")
	)
	(segment
		(start 271.900396 -21.064982)
		(end 271.745456 -20.910042)
		(width 0.14224)
		(layer "In2.Cu")
		(net "M_C_ODT<2>")
	)
	(segment
		(start 265.74496 -48.66259)
		(end 265.74496 -31.828994)
		(width 0.14224)
		(layer "In2.Cu")
		(net "M_C_ODT<2>")
	)
	(segment
		(start 271.696434 -22.662896)
		(end 271.442434 -22.408896)
		(width 0.14224)
		(layer "In2.Cu")
		(net "M_C_ODT<2>")
	)
	(segment
		(start 271.900396 -21.506434)
		(end 271.900396 -21.064982)
		(width 0.14224)
		(layer "In2.Cu")
		(net "M_C_ODT<2>")
	)
	(segment
		(start 264.7442 -51.104546)
		(end 264.7442 -50.171096)
		(width 0.0889)
		(layer "In2.Cu")
		(net "M_C_ODT<2>")
	)
	(segment
		(start 271.634712 -16.967708)
		(end 271.634712 -16.442182)
		(width 0.14224)
		(layer "In2.Cu")
		(net "M_C_ODT<2>")
	)
	(segment
		(start 271.84477 -14.519402)
		(end 271.634712 -14.309344)
		(width 0.14224)
		(layer "In2.Cu")
		(net "M_C_ODT<2>")
	)
	(segment
		(start 264.390124 -53.139086)
		(end 264.390124 -51.458622)
		(width 0.0889)
		(layer "In2.Cu")
		(net "M_C_ODT<2>")
	)
	(segment
		(start 264.289286 -54.894988)
		(end 264.280396 -54.879748)
		(width 0.0889)
		(layer "In2.Cu")
		(net "M_C_ODT<2>")
	)
	(segment
		(start 271.363948 -8.51408)
		(end 271.363948 -7.637272)
		(width 0.14224)
		(layer "In2.Cu")
		(net "M_C_ODT<2>")
	)
	(segment
		(start 272.701512 -4.527042)
		(end 272.899886 -4.328668)
		(width 0.14224)
		(layer "In2.Cu")
		(net "M_C_ODT<2>")
	)
	(segment
		(start 264.390124 -51.458622)
		(end 264.7442 -51.104546)
		(width 0.0889)
		(layer "In2.Cu")
		(net "M_C_ODT<2>")
	)
	(segment
		(start 264.289286 -53.313584)
		(end 264.390124 -53.139086)
		(width 0.0889)
		(layer "In2.Cu")
		(net "M_C_ODT<2>")
	)
	(segment
		(start 271.634712 -13.644118)
		(end 271.37614 -13.385546)
		(width 0.14224)
		(layer "In2.Cu")
		(net "M_C_ODT<2>")
	)
	(segment
		(start 265.74496 -49.170336)
		(end 265.74496 -48.66259)
		(width 0.0889)
		(layer "In2.Cu")
		(net "M_C_ODT<2>")
	)
	(segment
		(start 264.273284 -57.303162)
		(end 264.289286 -57.275984)
		(width 0.0889)
		(layer "In2.Cu")
		(net "M_C_ODT<2>")
	)
	(segment
		(start 271.776698 -15.720568)
		(end 271.634966 -15.578836)
		(width 0.14224)
		(layer "In2.Cu")
		(net "M_C_ODT<2>")
	)
	(segment
		(start 269.907258 -27.666696)
		(end 269.907258 -25.621742)
		(width 0.14224)
		(layer "In2.Cu")
		(net "M_C_ODT<2>")
	)
	(segment
		(start 271.634712 -14.309344)
		(end 271.634712 -13.644118)
		(width 0.14224)
		(layer "In2.Cu")
		(net "M_C_ODT<2>")
	)
	(segment
		(start 271.639284 -8.789416)
		(end 271.363948 -8.51408)
		(width 0.14224)
		(layer "In2.Cu")
		(net "M_C_ODT<2>")
	)
	(segment
		(start 271.634966 -15.578836)
		(end 271.634966 -15.1257)
		(width 0.14224)
		(layer "In2.Cu")
		(net "M_C_ODT<2>")
	)
	(segment
		(start 271.425416 -11.192256)
		(end 271.425416 -10.743184)
		(width 0.14224)
		(layer "In2.Cu")
		(net "M_C_ODT<2>")
	)
	(segment
		(start 271.637506 -18.218658)
		(end 271.442434 -18.023586)
		(width 0.14224)
		(layer "In2.Cu")
		(net "M_C_ODT<2>")
	)
	(arc
		(start 264.280396 -54.879748)
		(mid 264.209999 -54.590797)
		(end 264.289286 -54.304184)
		(width 0.0889)
		(layer "In2.Cu")
		(net "M_C_ODT<2>")
	)
	(arc
		(start 264.289286 -56.285384)
		(mid 264.342819 -56.085486)
		(end 264.289286 -55.885588)
		(width 0.0889)
		(layer "In2.Cu")
		(net "M_C_ODT<2>")
	)
	(arc
		(start 264.280396 -56.860948)
		(mid 264.209999 -56.571997)
		(end 264.289286 -56.285384)
		(width 0.0889)
		(layer "In2.Cu")
		(net "M_C_ODT<2>")
	)
	(arc
		(start 264.289286 -57.275984)
		(mid 264.342819 -57.076086)
		(end 264.289286 -56.876188)
		(width 0.0889)
		(layer "In2.Cu")
		(net "M_C_ODT<2>")
	)
	(arc
		(start 264.289286 -54.304184)
		(mid 264.342819 -54.104286)
		(end 264.289286 -53.904388)
		(width 0.0889)
		(layer "In2.Cu")
		(net "M_C_ODT<2>")
	)
	(arc
		(start 264.289286 -55.294784)
		(mid 264.342819 -55.094886)
		(end 264.289286 -54.894988)
		(width 0.0889)
		(layer "In2.Cu")
		(net "M_C_ODT<2>")
	)
	(arc
		(start 264.280396 -55.870348)
		(mid 264.209999 -55.581397)
		(end 264.289286 -55.294784)
		(width 0.0889)
		(layer "In2.Cu")
		(net "M_C_ODT<2>")
	)
	(arc
		(start 264.280396 -53.889148)
		(mid 264.209999 -53.600197)
		(end 264.289286 -53.313584)
		(width 0.0889)
		(layer "In2.Cu")
		(net "M_C_ODT<2>")
	)
	(segment
		(start 276.29993 3.778758)
		(end 276.29993 2.485644)
		(width 0.1651)
		(layer "F.Cu")
		(net "M_C_ODT<1>")
	)
	(segment
		(start 276.300438 3.778758)
		(end 276.29993 3.778758)
		(width 0.1651)
		(layer "F.Cu")
		(net "M_C_ODT<1>")
	)
	(segment
		(start 265.372596 -59.55284)
		(end 264.801096 -59.55284)
		(width 0.1016)
		(layer "F.Cu")
		(net "M_C_ODT<1>")
	)
	(via
		(at 276.29993 2.485644)
		(size 0.508)
		(drill 0.254)
		(layers "F.Cu" "B.Cu")
		(net "M_C_ODT<1>")
	)
	(via
		(at 264.801096 -59.55284)
		(size 0.508)
		(drill 0.254)
		(layers "F.Cu" "B.Cu")
		(net "M_C_ODT<1>")
	)
	(segment
		(start 274.160488 -5.493512)
		(end 275.00961 -4.64439)
		(width 0.14224)
		(layer "In2.Cu")
		(net "M_C_ODT<1>")
	)
	(segment
		(start 274.105878 -18.404586)
		(end 274.105878 -17.769586)
		(width 0.14224)
		(layer "In2.Cu")
		(net "M_C_ODT<1>")
	)
	(segment
		(start 275.041614 -2.553208)
		(end 275.041614 -0.137414)
		(width 0.14224)
		(layer "In2.Cu")
		(net "M_C_ODT<1>")
	)
	(segment
		(start 274.635214 -2.959608)
		(end 275.041614 -2.553208)
		(width 0.14224)
		(layer "In2.Cu")
		(net "M_C_ODT<1>")
	)
	(segment
		(start 274.160488 -21.266658)
		(end 274.160488 -18.459196)
		(width 0.14224)
		(layer "In2.Cu")
		(net "M_C_ODT<1>")
	)
	(segment
		(start 266.3698 -50.292)
		(end 266.3698 -49.6062)
		(width 0.0889)
		(layer "In2.Cu")
		(net "M_C_ODT<1>")
	)
	(segment
		(start 274.984464 0.639064)
		(end 276.29993 1.95453)
		(width 0.14224)
		(layer "In2.Cu")
		(net "M_C_ODT<1>")
	)
	(segment
		(start 274.984464 -0.080264)
		(end 274.984464 0.639064)
		(width 0.14224)
		(layer "In2.Cu")
		(net "M_C_ODT<1>")
	)
	(segment
		(start 274.240752 -23.31847)
		(end 274.055078 -23.132796)
		(width 0.14224)
		(layer "In2.Cu")
		(net "M_C_ODT<1>")
	)
	(segment
		(start 274.190206 -13.666724)
		(end 274.160488 -13.637006)
		(width 0.14224)
		(layer "In2.Cu")
		(net "M_C_ODT<1>")
	)
	(segment
		(start 267.26896 -48.39208)
		(end 267.26896 -32.461454)
		(width 0.14224)
		(layer "In2.Cu")
		(net "M_C_ODT<1>")
	)
	(segment
		(start 274.160488 -13.637006)
		(end 274.160488 -5.493512)
		(width 0.14224)
		(layer "In2.Cu")
		(net "M_C_ODT<1>")
	)
	(segment
		(start 274.160488 -18.459196)
		(end 274.105878 -18.404586)
		(width 0.14224)
		(layer "In2.Cu")
		(net "M_C_ODT<1>")
	)
	(segment
		(start 274.055078 -23.132796)
		(end 274.055078 -22.599396)
		(width 0.14224)
		(layer "In2.Cu")
		(net "M_C_ODT<1>")
	)
	(segment
		(start 265.35253 -52.845462)
		(end 265.736324 -52.461668)
		(width 0.0889)
		(layer "In2.Cu")
		(net "M_C_ODT<1>")
	)
	(segment
		(start 275.00961 -4.13639)
		(end 274.635214 -3.761994)
		(width 0.14224)
		(layer "In2.Cu")
		(net "M_C_ODT<1>")
	)
	(segment
		(start 265.736324 -50.925476)
		(end 266.3698 -50.292)
		(width 0.0889)
		(layer "In2.Cu")
		(net "M_C_ODT<1>")
	)
	(segment
		(start 274.232878 -21.938996)
		(end 274.105878 -21.811996)
		(width 0.14224)
		(layer "In2.Cu")
		(net "M_C_ODT<1>")
	)
	(segment
		(start 276.29993 1.95453)
		(end 276.29993 2.485644)
		(width 0.14224)
		(layer "In2.Cu")
		(net "M_C_ODT<1>")
	)
	(segment
		(start 267.26896 -48.70704)
		(end 267.26896 -48.39208)
		(width 0.0889)
		(layer "In2.Cu")
		(net "M_C_ODT<1>")
	)
	(segment
		(start 274.055078 -22.599396)
		(end 274.232878 -22.421596)
		(width 0.14224)
		(layer "In2.Cu")
		(net "M_C_ODT<1>")
	)
	(segment
		(start 266.3698 -49.6062)
		(end 267.26896 -48.70704)
		(width 0.0889)
		(layer "In2.Cu")
		(net "M_C_ODT<1>")
	)
	(segment
		(start 274.232878 -22.421596)
		(end 274.232878 -21.938996)
		(width 0.14224)
		(layer "In2.Cu")
		(net "M_C_ODT<1>")
	)
	(segment
		(start 274.163536 -14.574774)
		(end 274.190206 -14.548104)
		(width 0.14224)
		(layer "In2.Cu")
		(net "M_C_ODT<1>")
	)
	(segment
		(start 274.105878 -17.769586)
		(end 274.163536 -17.711928)
		(width 0.14224)
		(layer "In2.Cu")
		(net "M_C_ODT<1>")
	)
	(segment
		(start 267.26896 -32.461454)
		(end 272.5674 -27.163014)
		(width 0.14224)
		(layer "In2.Cu")
		(net "M_C_ODT<1>")
	)
	(segment
		(start 274.105878 -21.321268)
		(end 274.160488 -21.266658)
		(width 0.14224)
		(layer "In2.Cu")
		(net "M_C_ODT<1>")
	)
	(segment
		(start 274.163536 -17.711928)
		(end 274.163536 -14.574774)
		(width 0.14224)
		(layer "In2.Cu")
		(net "M_C_ODT<1>")
	)
	(segment
		(start 265.736324 -52.461668)
		(end 265.736324 -50.925476)
		(width 0.0889)
		(layer "In2.Cu")
		(net "M_C_ODT<1>")
	)
	(segment
		(start 275.041614 -0.137414)
		(end 274.984464 -0.080264)
		(width 0.14224)
		(layer "In2.Cu")
		(net "M_C_ODT<1>")
	)
	(segment
		(start 274.635214 -3.761994)
		(end 274.635214 -2.959608)
		(width 0.14224)
		(layer "In2.Cu")
		(net "M_C_ODT<1>")
	)
	(segment
		(start 275.00961 -4.64439)
		(end 275.00961 -4.13639)
		(width 0.14224)
		(layer "In2.Cu")
		(net "M_C_ODT<1>")
	)
	(segment
		(start 274.240752 -24.133048)
		(end 274.240752 -23.31847)
		(width 0.14224)
		(layer "In2.Cu")
		(net "M_C_ODT<1>")
	)
	(segment
		(start 274.190206 -14.548104)
		(end 274.190206 -13.666724)
		(width 0.14224)
		(layer "In2.Cu")
		(net "M_C_ODT<1>")
	)
	(segment
		(start 272.5674 -27.163014)
		(end 272.5674 -25.8064)
		(width 0.14224)
		(layer "In2.Cu")
		(net "M_C_ODT<1>")
	)
	(segment
		(start 264.801096 -59.55284)
		(end 265.237722 -58.960766)
		(width 0.0889)
		(layer "In2.Cu")
		(net "M_C_ODT<1>")
	)
	(segment
		(start 274.105878 -21.811996)
		(end 274.105878 -21.321268)
		(width 0.14224)
		(layer "In2.Cu")
		(net "M_C_ODT<1>")
	)
	(segment
		(start 265.312906 -52.914296)
		(end 265.35253 -52.845462)
		(width 0.0889)
		(layer "In2.Cu")
		(net "M_C_ODT<1>")
	)
	(segment
		(start 272.5674 -25.8064)
		(end 274.240752 -24.133048)
		(width 0.14224)
		(layer "In2.Cu")
		(net "M_C_ODT<1>")
	)
	(arc
		(start 265.312906 -55.886096)
		(mid 265.392037 -55.590694)
		(end 265.312906 -55.295292)
		(width 0.0889)
		(layer "In2.Cu")
		(net "M_C_ODT<1>")
	)
	(arc
		(start 265.312906 -56.285892)
		(mid 265.259407 -56.085994)
		(end 265.312906 -55.886096)
		(width 0.0889)
		(layer "In2.Cu")
		(net "M_C_ODT<1>")
	)
	(arc
		(start 265.312906 -56.876696)
		(mid 265.392037 -56.581294)
		(end 265.312906 -56.285892)
		(width 0.0889)
		(layer "In2.Cu")
		(net "M_C_ODT<1>")
	)
	(arc
		(start 265.312906 -57.276492)
		(mid 265.259407 -57.076594)
		(end 265.312906 -56.876696)
		(width 0.0889)
		(layer "In2.Cu")
		(net "M_C_ODT<1>")
	)
	(arc
		(start 265.312906 -54.304692)
		(mid 265.259373 -54.104794)
		(end 265.312906 -53.904896)
		(width 0.0889)
		(layer "In2.Cu")
		(net "M_C_ODT<1>")
	)
	(arc
		(start 265.312906 -53.314092)
		(mid 265.259407 -53.114194)
		(end 265.312906 -52.914296)
		(width 0.0889)
		(layer "In2.Cu")
		(net "M_C_ODT<1>")
	)
	(arc
		(start 265.312906 -58.267092)
		(mid 265.259407 -58.067194)
		(end 265.312906 -57.867296)
		(width 0.0889)
		(layer "In2.Cu")
		(net "M_C_ODT<1>")
	)
	(arc
		(start 265.312906 -55.295292)
		(mid 265.259407 -55.095394)
		(end 265.312906 -54.895496)
		(width 0.0889)
		(layer "In2.Cu")
		(net "M_C_ODT<1>")
	)
	(arc
		(start 265.237722 -58.960766)
		(mid 265.388636 -58.626204)
		(end 265.312906 -58.267092)
		(width 0.0889)
		(layer "In2.Cu")
		(net "M_C_ODT<1>")
	)
	(arc
		(start 265.312906 -57.867296)
		(mid 265.392037 -57.571894)
		(end 265.312906 -57.276492)
		(width 0.0889)
		(layer "In2.Cu")
		(net "M_C_ODT<1>")
	)
	(arc
		(start 265.312906 -54.895496)
		(mid 265.392037 -54.600094)
		(end 265.312906 -54.304692)
		(width 0.0889)
		(layer "In2.Cu")
		(net "M_C_ODT<1>")
	)
	(arc
		(start 265.312906 -53.904896)
		(mid 265.392037 -53.609494)
		(end 265.312906 -53.314092)
		(width 0.0889)
		(layer "In2.Cu")
		(net "M_C_ODT<1>")
	)
	(segment
		(start 272.900394 3.778758)
		(end 272.899886 3.778758)
		(width 0.1651)
		(layer "F.Cu")
		(net "M_C_ODT<0>")
	)
	(segment
		(start 263.65581 -59.55284)
		(end 263.08431 -59.55284)
		(width 0.1016)
		(layer "F.Cu")
		(net "M_C_ODT<0>")
	)
	(segment
		(start 272.899886 3.778758)
		(end 272.899886 2.485644)
		(width 0.1651)
		(layer "F.Cu")
		(net "M_C_ODT<0>")
	)
	(via
		(at 272.899886 2.485644)
		(size 0.508)
		(drill 0.254)
		(layers "F.Cu" "B.Cu")
		(net "M_C_ODT<0>")
	)
	(via
		(at 263.08431 -59.55284)
		(size 0.508)
		(drill 0.254)
		(layers "F.Cu" "B.Cu")
		(net "M_C_ODT<0>")
	)
	(segment
		(start 270.726662 -22.527768)
		(end 270.832834 -22.421596)
		(width 0.14224)
		(layer "In2.Cu")
		(net "M_C_ODT<0>")
	)
	(segment
		(start 263.983724 -51.382422)
		(end 264.3886 -50.977546)
		(width 0.0889)
		(layer "In2.Cu")
		(net "M_C_ODT<0>")
	)
	(segment
		(start 272.461228 -0.434594)
		(end 272.567146 -0.328676)
		(width 0.14224)
		(layer "In2.Cu")
		(net "M_C_ODT<0>")
	)
	(segment
		(start 265.23696 -48.52035)
		(end 265.23696 -48.327564)
		(width 0.0889)
		(layer "In2.Cu")
		(net "M_C_ODT<0>")
	)
	(segment
		(start 272.567146 -0.328676)
		(end 272.567146 0.741934)
		(width 0.14224)
		(layer "In2.Cu")
		(net "M_C_ODT<0>")
	)
	(segment
		(start 263.08431 -59.55284)
		(end 263.57961 -58.88609)
		(width 0.0889)
		(layer "In2.Cu")
		(net "M_C_ODT<0>")
	)
	(segment
		(start 271.888712 -2.7813)
		(end 272.1991 -2.7813)
		(width 0.14224)
		(layer "In2.Cu")
		(net "M_C_ODT<0>")
	)
	(segment
		(start 270.761206 -8.113014)
		(end 270.758412 -8.11022)
		(width 0.14224)
		(layer "In2.Cu")
		(net "M_C_ODT<0>")
	)
	(segment
		(start 263.57961 -58.88609)
		(end 263.59612 -58.857388)
		(width 0.0889)
		(layer "In2.Cu")
		(net "M_C_ODT<0>")
	)
	(segment
		(start 263.59612 -55.885588)
		(end 263.60247 -55.87492)
		(width 0.0889)
		(layer "In2.Cu")
		(net "M_C_ODT<0>")
	)
	(segment
		(start 269.399258 -27.455876)
		(end 269.399258 -25.393396)
		(width 0.14224)
		(layer "In2.Cu")
		(net "M_C_ODT<0>")
	)
	(segment
		(start 271.50314 -3.166872)
		(end 271.888712 -2.7813)
		(width 0.14224)
		(layer "In2.Cu")
		(net "M_C_ODT<0>")
	)
	(segment
		(start 271.633442 -3.795776)
		(end 271.50314 -3.665474)
		(width 0.14224)
		(layer "In2.Cu")
		(net "M_C_ODT<0>")
	)
	(segment
		(start 272.461228 -2.519172)
		(end 272.461228 -0.434594)
		(width 0.14224)
		(layer "In2.Cu")
		(net "M_C_ODT<0>")
	)
	(segment
		(start 263.591294 -54.903624)
		(end 263.59612 -54.894988)
		(width 0.0889)
		(layer "In2.Cu")
		(net "M_C_ODT<0>")
	)
	(segment
		(start 263.591294 -52.922424)
		(end 263.983724 -52.241958)
		(width 0.0889)
		(layer "In2.Cu")
		(net "M_C_ODT<0>")
	)
	(segment
		(start 265.23696 -48.327564)
		(end 265.23696 -31.618174)
		(width 0.14224)
		(layer "In2.Cu")
		(net "M_C_ODT<0>")
	)
	(segment
		(start 270.705834 -19.285966)
		(end 270.761206 -19.230594)
		(width 0.14224)
		(layer "In2.Cu")
		(net "M_C_ODT<0>")
	)
	(segment
		(start 263.591294 -55.894224)
		(end 263.59612 -55.885588)
		(width 0.0889)
		(layer "In2.Cu")
		(net "M_C_ODT<0>")
	)
	(segment
		(start 271.633442 -5.145786)
		(end 271.633442 -3.795776)
		(width 0.14224)
		(layer "In2.Cu")
		(net "M_C_ODT<0>")
	)
	(segment
		(start 270.758412 -8.11022)
		(end 270.758412 -6.020816)
		(width 0.14224)
		(layer "In2.Cu")
		(net "M_C_ODT<0>")
	)
	(segment
		(start 263.591294 -53.913024)
		(end 263.59612 -53.904388)
		(width 0.0889)
		(layer "In2.Cu")
		(net "M_C_ODT<0>")
	)
	(segment
		(start 272.461228 0.847852)
		(end 272.461228 1.519936)
		(width 0.14224)
		(layer "In2.Cu")
		(net "M_C_ODT<0>")
	)
	(segment
		(start 271.50314 -3.665474)
		(end 271.50314 -3.166872)
		(width 0.14224)
		(layer "In2.Cu")
		(net "M_C_ODT<0>")
	)
	(segment
		(start 270.705834 -21.811996)
		(end 270.705834 -19.285966)
		(width 0.14224)
		(layer "In2.Cu")
		(net "M_C_ODT<0>")
	)
	(segment
		(start 270.726662 -23.204424)
		(end 270.726662 -22.527768)
		(width 0.14224)
		(layer "In2.Cu")
		(net "M_C_ODT<0>")
	)
	(segment
		(start 263.60247 -58.277506)
		(end 263.59612 -58.266838)
		(width 0.0889)
		(layer "In2.Cu")
		(net "M_C_ODT<0>")
	)
	(segment
		(start 270.840708 -23.951946)
		(end 270.840708 -23.31847)
		(width 0.14224)
		(layer "In2.Cu")
		(net "M_C_ODT<0>")
	)
	(segment
		(start 263.59612 -56.876188)
		(end 263.60247 -56.86552)
		(width 0.0889)
		(layer "In2.Cu")
		(net "M_C_ODT<0>")
	)
	(segment
		(start 272.461228 1.519936)
		(end 272.899886 1.958594)
		(width 0.14224)
		(layer "In2.Cu")
		(net "M_C_ODT<0>")
	)
	(segment
		(start 264.3886 -49.36871)
		(end 265.23696 -48.52035)
		(width 0.0889)
		(layer "In2.Cu")
		(net "M_C_ODT<0>")
	)
	(segment
		(start 270.758412 -6.020816)
		(end 271.633442 -5.145786)
		(width 0.14224)
		(layer "In2.Cu")
		(net "M_C_ODT<0>")
	)
	(segment
		(start 263.983724 -52.241958)
		(end 263.983724 -51.382422)
		(width 0.0889)
		(layer "In2.Cu")
		(net "M_C_ODT<0>")
	)
	(segment
		(start 263.59612 -53.904388)
		(end 263.60247 -53.89372)
		(width 0.0889)
		(layer "In2.Cu")
		(net "M_C_ODT<0>")
	)
	(segment
		(start 272.567146 0.741934)
		(end 272.461228 0.847852)
		(width 0.14224)
		(layer "In2.Cu")
		(net "M_C_ODT<0>")
	)
	(segment
		(start 270.832834 -21.938996)
		(end 270.705834 -21.811996)
		(width 0.14224)
		(layer "In2.Cu")
		(net "M_C_ODT<0>")
	)
	(segment
		(start 263.59612 -54.894988)
		(end 263.60247 -54.88432)
		(width 0.0889)
		(layer "In2.Cu")
		(net "M_C_ODT<0>")
	)
	(segment
		(start 269.399258 -25.393396)
		(end 270.840708 -23.951946)
		(width 0.14224)
		(layer "In2.Cu")
		(net "M_C_ODT<0>")
	)
	(segment
		(start 270.832834 -22.421596)
		(end 270.832834 -21.938996)
		(width 0.14224)
		(layer "In2.Cu")
		(net "M_C_ODT<0>")
	)
	(segment
		(start 272.1991 -2.7813)
		(end 272.461228 -2.519172)
		(width 0.14224)
		(layer "In2.Cu")
		(net "M_C_ODT<0>")
	)
	(segment
		(start 265.52144 -31.33344)
		(end 269.399258 -27.455876)
		(width 0.14224)
		(layer "In2.Cu")
		(net "M_C_ODT<0>")
	)
	(segment
		(start 272.899886 1.958594)
		(end 272.899886 2.485644)
		(width 0.14224)
		(layer "In2.Cu")
		(net "M_C_ODT<0>")
	)
	(segment
		(start 263.591294 -56.884824)
		(end 263.59612 -56.876188)
		(width 0.0889)
		(layer "In2.Cu")
		(net "M_C_ODT<0>")
	)
	(segment
		(start 270.840708 -23.31847)
		(end 270.726662 -23.204424)
		(width 0.14224)
		(layer "In2.Cu")
		(net "M_C_ODT<0>")
	)
	(segment
		(start 265.23696 -31.618174)
		(end 265.52144 -31.33344)
		(width 0.14224)
		(layer "In2.Cu")
		(net "M_C_ODT<0>")
	)
	(segment
		(start 264.3886 -50.977546)
		(end 264.3886 -49.36871)
		(width 0.0889)
		(layer "In2.Cu")
		(net "M_C_ODT<0>")
	)
	(segment
		(start 270.761206 -19.230594)
		(end 270.761206 -8.113014)
		(width 0.14224)
		(layer "In2.Cu")
		(net "M_C_ODT<0>")
	)
	(arc
		(start 263.59612 -53.313838)
		(mid 263.54265 -53.118775)
		(end 263.591294 -52.922424)
		(width 0.0889)
		(layer "In2.Cu")
		(net "M_C_ODT<0>")
	)
	(arc
		(start 263.60247 -53.89372)
		(mid 263.675268 -53.602957)
		(end 263.59612 -53.313838)
		(width 0.0889)
		(layer "In2.Cu")
		(net "M_C_ODT<0>")
	)
	(arc
		(start 263.59612 -57.867042)
		(mid 263.675251 -57.57164)
		(end 263.59612 -57.276238)
		(width 0.0889)
		(layer "In2.Cu")
		(net "M_C_ODT<0>")
	)
	(arc
		(start 263.60247 -54.88432)
		(mid 263.675268 -54.593557)
		(end 263.59612 -54.304438)
		(width 0.0889)
		(layer "In2.Cu")
		(net "M_C_ODT<0>")
	)
	(arc
		(start 263.59612 -57.276238)
		(mid 263.54265 -57.081175)
		(end 263.591294 -56.884824)
		(width 0.0889)
		(layer "In2.Cu")
		(net "M_C_ODT<0>")
	)
	(arc
		(start 263.59612 -54.304438)
		(mid 263.54265 -54.109375)
		(end 263.591294 -53.913024)
		(width 0.0889)
		(layer "In2.Cu")
		(net "M_C_ODT<0>")
	)
	(arc
		(start 263.60247 -56.86552)
		(mid 263.675268 -56.574757)
		(end 263.59612 -56.285638)
		(width 0.0889)
		(layer "In2.Cu")
		(net "M_C_ODT<0>")
	)
	(arc
		(start 263.59612 -58.266838)
		(mid 263.542621 -58.06694)
		(end 263.59612 -57.867042)
		(width 0.0889)
		(layer "In2.Cu")
		(net "M_C_ODT<0>")
	)
	(arc
		(start 263.59612 -55.295038)
		(mid 263.54265 -55.099975)
		(end 263.591294 -54.903624)
		(width 0.0889)
		(layer "In2.Cu")
		(net "M_C_ODT<0>")
	)
	(arc
		(start 263.60247 -55.87492)
		(mid 263.675268 -55.584157)
		(end 263.59612 -55.295038)
		(width 0.0889)
		(layer "In2.Cu")
		(net "M_C_ODT<0>")
	)
	(arc
		(start 263.59612 -58.857388)
		(mid 263.675342 -58.56827)
		(end 263.60247 -58.277506)
		(width 0.0889)
		(layer "In2.Cu")
		(net "M_C_ODT<0>")
	)
	(arc
		(start 263.59612 -56.285638)
		(mid 263.54265 -56.090575)
		(end 263.591294 -55.894224)
		(width 0.0889)
		(layer "In2.Cu")
		(net "M_C_ODT<0>")
	)
	(segment
		(start 249.94997 3.778758)
		(end 249.94997 1.805432)
		(width 0.1651)
		(layer "F.Cu")
		(net "M_C_MA<9>")
	)
	(segment
		(start 256.78765 -62.52464)
		(end 256.21615 -62.52464)
		(width 0.0889)
		(layer "F.Cu")
		(net "M_C_MA<9>")
	)
	(segment
		(start 249.950478 3.778758)
		(end 249.94997 3.778758)
		(width 0.1651)
		(layer "F.Cu")
		(net "M_C_MA<9>")
	)
	(via
		(at 249.94997 -4.332478)
		(size 0.4572)
		(drill 0.2032)
		(layers "F.Cu" "B.Cu")
		(net "M_C_MA<9>")
	)
	(via
		(at 249.94997 1.805432)
		(size 0.508)
		(drill 0.254)
		(layers "F.Cu" "B.Cu")
		(net "M_C_MA<9>")
	)
	(via
		(at 256.21615 -62.52464)
		(size 0.508)
		(drill 0.254)
		(layers "F.Cu" "B.Cu")
		(net "M_C_MA<9>")
	)
	(segment
		(start 249.94997 -5.621782)
		(end 249.94997 -4.332478)
		(width 0.1651)
		(layer "B.Cu")
		(net "M_C_MA<9>")
	)
	(segment
		(start 249.950478 -5.621782)
		(end 249.94997 -5.621782)
		(width 0.1651)
		(layer "B.Cu")
		(net "M_C_MA<9>")
	)
	(segment
		(start 257.085338 -60.447936)
		(end 257.085846 -60.448444)
		(width 0.0889)
		(layer "In11.Cu")
		(net "M_C_MA<9>")
	)
	(segment
		(start 253.79045 -7.94385)
		(end 253.79045 -6.8707)
		(width 0.14224)
		(layer "In11.Cu")
		(net "M_C_MA<9>")
	)
	(segment
		(start 250.566174 -4.948682)
		(end 249.94997 -4.332478)
		(width 0.14224)
		(layer "In11.Cu")
		(net "M_C_MA<9>")
	)
	(segment
		(start 258.9276 -22.591014)
		(end 258.9276 -20.738592)
		(width 0.14224)
		(layer "In11.Cu")
		(net "M_C_MA<9>")
	)
	(segment
		(start 257.671824 -13.4874)
		(end 256.3368 -12.152376)
		(width 0.14224)
		(layer "In11.Cu")
		(net "M_C_MA<9>")
	)
	(segment
		(start 257.05689 -60.447936)
		(end 257.085338 -60.447936)
		(width 0.0889)
		(layer "In11.Cu")
		(net "M_C_MA<9>")
	)
	(segment
		(start 249.534426 -2.866898)
		(end 249.534426 -2.036826)
		(width 0.14224)
		(layer "In11.Cu")
		(net "M_C_MA<9>")
	)
	(segment
		(start 249.534426 -2.036826)
		(end 249.4788 -1.9812)
		(width 0.14224)
		(layer "In11.Cu")
		(net "M_C_MA<9>")
	)
	(segment
		(start 257.474974 -52.016152)
		(end 257.3274 -51.76139)
		(width 0.0889)
		(layer "In11.Cu")
		(net "M_C_MA<9>")
	)
	(segment
		(start 257.3274 -51.1048)
		(end 257.422904 -51.009296)
		(width 0.0889)
		(layer "In11.Cu")
		(net "M_C_MA<9>")
	)
	(segment
		(start 258.647184 -13.4874)
		(end 257.671824 -13.4874)
		(width 0.14224)
		(layer "In11.Cu")
		(net "M_C_MA<9>")
	)
	(segment
		(start 253.79045 -6.8707)
		(end 251.868432 -4.948682)
		(width 0.14224)
		(layer "In11.Cu")
		(net "M_C_MA<9>")
	)
	(segment
		(start 257.474974 -54.10073)
		(end 257.474974 -52.016152)
		(width 0.0889)
		(layer "In11.Cu")
		(net "M_C_MA<9>")
	)
	(segment
		(start 256.545588 -61.763656)
		(end 256.567686 -61.725302)
		(width 0.0889)
		(layer "In11.Cu")
		(net "M_C_MA<9>")
	)
	(segment
		(start 257.422904 -51.009296)
		(end 257.422904 -50.457354)
		(width 0.0889)
		(layer "In11.Cu")
		(net "M_C_MA<9>")
	)
	(segment
		(start 258.699 -19.088354)
		(end 258.9276 -18.859754)
		(width 0.14224)
		(layer "In11.Cu")
		(net "M_C_MA<9>")
	)
	(segment
		(start 249.4788 -1.9812)
		(end 249.4788 0.889)
		(width 0.14224)
		(layer "In11.Cu")
		(net "M_C_MA<9>")
	)
	(segment
		(start 259.12445 -23.669244)
		(end 259.12445 -22.787864)
		(width 0.14224)
		(layer "In11.Cu")
		(net "M_C_MA<9>")
	)
	(segment
		(start 256.21615 -62.52464)
		(end 256.545588 -61.763656)
		(width 0.0889)
		(layer "In11.Cu")
		(net "M_C_MA<9>")
	)
	(segment
		(start 249.94997 1.36017)
		(end 249.94997 1.805432)
		(width 0.14224)
		(layer "In11.Cu")
		(net "M_C_MA<9>")
	)
	(segment
		(start 258.9276 -18.859754)
		(end 258.9276 -13.767816)
		(width 0.14224)
		(layer "In11.Cu")
		(net "M_C_MA<9>")
	)
	(segment
		(start 257.3274 -51.76139)
		(end 257.3274 -51.1048)
		(width 0.0889)
		(layer "In11.Cu")
		(net "M_C_MA<9>")
	)
	(segment
		(start 249.4788 0.889)
		(end 249.94997 1.36017)
		(width 0.14224)
		(layer "In11.Cu")
		(net "M_C_MA<9>")
	)
	(segment
		(start 259.12445 -22.787864)
		(end 258.9276 -22.591014)
		(width 0.14224)
		(layer "In11.Cu")
		(net "M_C_MA<9>")
	)
	(segment
		(start 258.9276 -13.767816)
		(end 258.647184 -13.4874)
		(width 0.14224)
		(layer "In11.Cu")
		(net "M_C_MA<9>")
	)
	(segment
		(start 257.422904 -25.372822)
		(end 259.12445 -23.669244)
		(width 0.14224)
		(layer "In11.Cu")
		(net "M_C_MA<9>")
	)
	(segment
		(start 249.94997 -4.332478)
		(end 249.94997 -4.004818)
		(width 0.14224)
		(layer "In11.Cu")
		(net "M_C_MA<9>")
	)
	(segment
		(start 249.412252 -2.989072)
		(end 249.534426 -2.866898)
		(width 0.14224)
		(layer "In11.Cu")
		(net "M_C_MA<9>")
	)
	(segment
		(start 249.412252 -3.4671)
		(end 249.412252 -2.989072)
		(width 0.14224)
		(layer "In11.Cu")
		(net "M_C_MA<9>")
	)
	(segment
		(start 256.3368 -11.32586)
		(end 254.635 -9.62406)
		(width 0.14224)
		(layer "In11.Cu")
		(net "M_C_MA<9>")
	)
	(segment
		(start 257.422904 -50.457354)
		(end 257.422904 -25.372822)
		(width 0.14224)
		(layer "In11.Cu")
		(net "M_C_MA<9>")
	)
	(segment
		(start 251.868432 -4.948682)
		(end 250.566174 -4.948682)
		(width 0.14224)
		(layer "In11.Cu")
		(net "M_C_MA<9>")
	)
	(segment
		(start 256.3368 -12.152376)
		(end 256.3368 -11.32586)
		(width 0.14224)
		(layer "In11.Cu")
		(net "M_C_MA<9>")
	)
	(segment
		(start 249.94997 -4.004818)
		(end 249.412252 -3.4671)
		(width 0.14224)
		(layer "In11.Cu")
		(net "M_C_MA<9>")
	)
	(segment
		(start 254.635 -9.62406)
		(end 254.635 -8.7884)
		(width 0.14224)
		(layer "In11.Cu")
		(net "M_C_MA<9>")
	)
	(segment
		(start 258.699 -20.509992)
		(end 258.699 -19.088354)
		(width 0.14224)
		(layer "In11.Cu")
		(net "M_C_MA<9>")
	)
	(segment
		(start 254.635 -8.7884)
		(end 253.79045 -7.94385)
		(width 0.14224)
		(layer "In11.Cu")
		(net "M_C_MA<9>")
	)
	(segment
		(start 258.9276 -20.738592)
		(end 258.699 -20.509992)
		(width 0.14224)
		(layer "In11.Cu")
		(net "M_C_MA<9>")
	)
	(arc
		(start 257.42138 -54.895496)
		(mid 257.342249 -54.600094)
		(end 257.42138 -54.304692)
		(width 0.0889)
		(layer "In11.Cu")
		(net "M_C_MA<9>")
	)
	(arc
		(start 257.42138 -59.848496)
		(mid 257.342249 -59.553094)
		(end 257.42138 -59.257692)
		(width 0.0889)
		(layer "In11.Cu")
		(net "M_C_MA<9>")
	)
	(arc
		(start 257.42138 -56.285892)
		(mid 257.474879 -56.085994)
		(end 257.42138 -55.886096)
		(width 0.0889)
		(layer "In11.Cu")
		(net "M_C_MA<9>")
	)
	(arc
		(start 256.567686 -61.725302)
		(mid 256.616441 -61.52895)
		(end 256.56286 -61.333888)
		(width 0.0889)
		(layer "In11.Cu")
		(net "M_C_MA<9>")
	)
	(arc
		(start 257.42138 -59.257692)
		(mid 257.474879 -59.057794)
		(end 257.42138 -58.857896)
		(width 0.0889)
		(layer "In11.Cu")
		(net "M_C_MA<9>")
	)
	(arc
		(start 257.42138 -56.876696)
		(mid 257.342249 -56.581294)
		(end 257.42138 -56.285892)
		(width 0.0889)
		(layer "In11.Cu")
		(net "M_C_MA<9>")
	)
	(arc
		(start 256.56286 -61.333888)
		(mid 256.558531 -60.750716)
		(end 257.05689 -60.447936)
		(width 0.0889)
		(layer "In11.Cu")
		(net "M_C_MA<9>")
	)
	(arc
		(start 257.42138 -58.857896)
		(mid 257.342249 -58.562494)
		(end 257.42138 -58.267092)
		(width 0.0889)
		(layer "In11.Cu")
		(net "M_C_MA<9>")
	)
	(arc
		(start 257.42138 -54.304692)
		(mid 257.461856 -54.206304)
		(end 257.474974 -54.10073)
		(width 0.0889)
		(layer "In11.Cu")
		(net "M_C_MA<9>")
	)
	(arc
		(start 257.42138 -57.276492)
		(mid 257.474879 -57.076594)
		(end 257.42138 -56.876696)
		(width 0.0889)
		(layer "In11.Cu")
		(net "M_C_MA<9>")
	)
	(arc
		(start 257.42138 -58.267092)
		(mid 257.474879 -58.067194)
		(end 257.42138 -57.867296)
		(width 0.0889)
		(layer "In11.Cu")
		(net "M_C_MA<9>")
	)
	(arc
		(start 257.42138 -55.886096)
		(mid 257.342249 -55.590694)
		(end 257.42138 -55.295292)
		(width 0.0889)
		(layer "In11.Cu")
		(net "M_C_MA<9>")
	)
	(arc
		(start 257.085846 -60.448444)
		(mid 257.423961 -60.243742)
		(end 257.42138 -59.848496)
		(width 0.0889)
		(layer "In11.Cu")
		(net "M_C_MA<9>")
	)
	(arc
		(start 257.42138 -57.867296)
		(mid 257.342249 -57.571894)
		(end 257.42138 -57.276492)
		(width 0.0889)
		(layer "In11.Cu")
		(net "M_C_MA<9>")
	)
	(arc
		(start 257.42138 -55.295292)
		(mid 257.474879 -55.095394)
		(end 257.42138 -54.895496)
		(width 0.0889)
		(layer "In11.Cu")
		(net "M_C_MA<9>")
	)
	(segment
		(start 255.92913 -61.038486)
		(end 255.35763 -61.038486)
		(width 0.1016)
		(layer "F.Cu")
		(net "M_C_MA<8>")
	)
	(segment
		(start 251.6505 3.778758)
		(end 251.649992 3.778758)
		(width 0.1651)
		(layer "F.Cu")
		(net "M_C_MA<8>")
	)
	(segment
		(start 251.649992 3.778758)
		(end 251.649992 1.805432)
		(width 0.1651)
		(layer "F.Cu")
		(net "M_C_MA<8>")
	)
	(via
		(at 251.649992 1.805432)
		(size 0.508)
		(drill 0.254)
		(layers "F.Cu" "B.Cu")
		(net "M_C_MA<8>")
	)
	(via
		(at 251.649992 -4.332478)
		(size 0.4572)
		(drill 0.2032)
		(layers "F.Cu" "B.Cu")
		(net "M_C_MA<8>")
	)
	(via
		(at 255.35763 -61.038486)
		(size 0.508)
		(drill 0.254)
		(layers "F.Cu" "B.Cu")
		(net "M_C_MA<8>")
	)
	(segment
		(start 251.6505 -5.621782)
		(end 251.649992 -5.621782)
		(width 0.1651)
		(layer "B.Cu")
		(net "M_C_MA<8>")
	)
	(segment
		(start 251.649992 -5.621782)
		(end 251.649992 -4.332478)
		(width 0.1651)
		(layer "B.Cu")
		(net "M_C_MA<8>")
	)
	(segment
		(start 254.724408 -58.228992)
		(end 254.288544 -57.92089)
		(width 0.0889)
		(layer "In2.Cu")
		(net "M_C_MA<8>")
	)
	(segment
		(start 250.303284 -23.183596)
		(end 250.303284 -22.671024)
		(width 0.14224)
		(layer "In2.Cu")
		(net "M_C_MA<8>")
	)
	(segment
		(start 254.95885 -59.091322)
		(end 254.910082 -58.542936)
		(width 0.0889)
		(layer "In2.Cu")
		(net "M_C_MA<8>")
	)
	(segment
		(start 254.152654 -54.400196)
		(end 254.160274 -54.386988)
		(width 0.0889)
		(layer "In2.Cu")
		(net "M_C_MA<8>")
	)
	(segment
		(start 254.738124 -50.925222)
		(end 254.738124 -30.496002)
		(width 0.14224)
		(layer "In2.Cu")
		(net "M_C_MA<8>")
	)
	(segment
		(start 251.333 -1.5494)
		(end 251.333 0.1016)
		(width 0.14224)
		(layer "In2.Cu")
		(net "M_C_MA<8>")
	)
	(segment
		(start 250.3678 -8.18007)
		(end 250.557284 -7.990586)
		(width 0.14224)
		(layer "In2.Cu")
		(net "M_C_MA<8>")
	)
	(segment
		(start 251.3457 1.50114)
		(end 251.649992 1.805432)
		(width 0.14224)
		(layer "In2.Cu")
		(net "M_C_MA<8>")
	)
	(segment
		(start 254.738124 -51.433476)
		(end 254.738124 -50.925222)
		(width 0.0889)
		(layer "In2.Cu")
		(net "M_C_MA<8>")
	)
	(segment
		(start 252.78334 -27.470862)
		(end 252.356874 -27.897328)
		(width 0.14224)
		(layer "In2.Cu")
		(net "M_C_MA<8>")
	)
	(segment
		(start 252.356874 -27.897328)
		(end 252.057662 -27.897328)
		(width 0.14224)
		(layer "In2.Cu")
		(net "M_C_MA<8>")
	)
	(segment
		(start 254.152146 -53.409088)
		(end 254.2159 -53.298598)
		(width 0.0889)
		(layer "In2.Cu")
		(net "M_C_MA<8>")
	)
	(segment
		(start 252.057662 -27.897328)
		(end 251.758958 -27.598624)
		(width 0.14224)
		(layer "In2.Cu")
		(net "M_C_MA<8>")
	)
	(segment
		(start 254.910082 -58.542936)
		(end 254.880364 -58.422032)
		(width 0.0889)
		(layer "In2.Cu")
		(net "M_C_MA<8>")
	)
	(segment
		(start 251.333 0.1016)
		(end 251.192792 0.241808)
		(width 0.14224)
		(layer "In2.Cu")
		(net "M_C_MA<8>")
	)
	(segment
		(start 250.487434 -22.486874)
		(end 250.487434 -21.813774)
		(width 0.14224)
		(layer "In2.Cu")
		(net "M_C_MA<8>")
	)
	(segment
		(start 252.201426 -26.902918)
		(end 252.201426 -26.60904)
		(width 0.14224)
		(layer "In2.Cu")
		(net "M_C_MA<8>")
	)
	(segment
		(start 250.437396 -24.84501)
		(end 250.437396 -23.317708)
		(width 0.14224)
		(layer "In2.Cu")
		(net "M_C_MA<8>")
	)
	(segment
		(start 252.201426 -26.60904)
		(end 251.913644 -26.321258)
		(width 0.14224)
		(layer "In2.Cu")
		(net "M_C_MA<8>")
	)
	(segment
		(start 251.192792 0.241808)
		(end 251.192792 0.799592)
		(width 0.14224)
		(layer "In2.Cu")
		(net "M_C_MA<8>")
	)
	(segment
		(start 250.377452 -19.194018)
		(end 250.377452 -16.980154)
		(width 0.14224)
		(layer "In2.Cu")
		(net "M_C_MA<8>")
	)
	(segment
		(start 250.3678 -12.2428)
		(end 250.3678 -8.18007)
		(width 0.14224)
		(layer "In2.Cu")
		(net "M_C_MA<8>")
	)
	(segment
		(start 254.160274 -54.386988)
		(end 254.160528 -54.385718)
		(width 0.0889)
		(layer "In2.Cu")
		(net "M_C_MA<8>")
	)
	(segment
		(start 251.004578 -26.613612)
		(end 250.742704 -26.351738)
		(width 0.14224)
		(layer "In2.Cu")
		(net "M_C_MA<8>")
	)
	(segment
		(start 250.487434 -21.813774)
		(end 250.303284 -21.629624)
		(width 0.14224)
		(layer "In2.Cu")
		(net "M_C_MA<8>")
	)
	(segment
		(start 250.303284 -19.268186)
		(end 250.377452 -19.194018)
		(width 0.14224)
		(layer "In2.Cu")
		(net "M_C_MA<8>")
	)
	(segment
		(start 254.880364 -58.422032)
		(end 254.84582 -58.362088)
		(width 0.0889)
		(layer "In2.Cu")
		(net "M_C_MA<8>")
	)
	(segment
		(start 250.303284 -22.671024)
		(end 250.487434 -22.486874)
		(width 0.14224)
		(layer "In2.Cu")
		(net "M_C_MA<8>")
	)
	(segment
		(start 251.758958 -27.598624)
		(end 251.758958 -27.345386)
		(width 0.14224)
		(layer "In2.Cu")
		(net "M_C_MA<8>")
	)
	(segment
		(start 250.36272 -16.965422)
		(end 250.36272 -12.24788)
		(width 0.14224)
		(layer "In2.Cu")
		(net "M_C_MA<8>")
	)
	(segment
		(start 250.377452 -16.980154)
		(end 250.36272 -16.965422)
		(width 0.14224)
		(layer "In2.Cu")
		(net "M_C_MA<8>")
	)
	(segment
		(start 251.626878 -26.321258)
		(end 251.334524 -26.613612)
		(width 0.14224)
		(layer "In2.Cu")
		(net "M_C_MA<8>")
	)
	(segment
		(start 250.36272 -12.24788)
		(end 250.3678 -12.2428)
		(width 0.14224)
		(layer "In2.Cu")
		(net "M_C_MA<8>")
	)
	(segment
		(start 251.334524 -26.613612)
		(end 251.004578 -26.613612)
		(width 0.14224)
		(layer "In2.Cu")
		(net "M_C_MA<8>")
	)
	(segment
		(start 250.366784 -7.368286)
		(end 250.366784 -6.40207)
		(width 0.14224)
		(layer "In2.Cu")
		(net "M_C_MA<8>")
	)
	(segment
		(start 251.216922 -3.899408)
		(end 251.216922 -1.665478)
		(width 0.14224)
		(layer "In2.Cu")
		(net "M_C_MA<8>")
	)
	(segment
		(start 251.216922 -1.665478)
		(end 251.333 -1.5494)
		(width 0.14224)
		(layer "In2.Cu")
		(net "M_C_MA<8>")
	)
	(segment
		(start 251.649992 -5.118862)
		(end 251.649992 -4.332478)
		(width 0.14224)
		(layer "In2.Cu")
		(net "M_C_MA<8>")
	)
	(segment
		(start 254.4572 -52.396136)
		(end 254.4572 -51.7144)
		(width 0.0889)
		(layer "In2.Cu")
		(net "M_C_MA<8>")
	)
	(segment
		(start 250.557284 -7.558786)
		(end 250.366784 -7.368286)
		(width 0.14224)
		(layer "In2.Cu")
		(net "M_C_MA<8>")
	)
	(segment
		(start 250.366784 -6.40207)
		(end 251.649992 -5.118862)
		(width 0.14224)
		(layer "In2.Cu")
		(net "M_C_MA<8>")
	)
	(segment
		(start 251.913644 -26.321258)
		(end 251.626878 -26.321258)
		(width 0.14224)
		(layer "In2.Cu")
		(net "M_C_MA<8>")
	)
	(segment
		(start 255.027684 -60.27674)
		(end 255.01092 -60.248038)
		(width 0.0889)
		(layer "In2.Cu")
		(net "M_C_MA<8>")
	)
	(segment
		(start 255.35763 -61.038486)
		(end 255.027684 -60.27674)
		(width 0.0889)
		(layer "In2.Cu")
		(net "M_C_MA<8>")
	)
	(segment
		(start 254.152654 -53.809138)
		(end 254.1524 -53.809138)
		(width 0.0889)
		(layer "In2.Cu")
		(net "M_C_MA<8>")
	)
	(segment
		(start 251.758958 -27.345386)
		(end 252.201426 -26.902918)
		(width 0.14224)
		(layer "In2.Cu")
		(net "M_C_MA<8>")
	)
	(segment
		(start 251.051822 -25.746456)
		(end 251.051822 -25.459436)
		(width 0.14224)
		(layer "In2.Cu")
		(net "M_C_MA<8>")
	)
	(segment
		(start 250.303284 -21.629624)
		(end 250.303284 -19.268186)
		(width 0.14224)
		(layer "In2.Cu")
		(net "M_C_MA<8>")
	)
	(segment
		(start 253.31801 -29.075888)
		(end 253.31801 -27.725624)
		(width 0.14224)
		(layer "In2.Cu")
		(net "M_C_MA<8>")
	)
	(segment
		(start 250.557284 -7.990586)
		(end 250.557284 -7.558786)
		(width 0.14224)
		(layer "In2.Cu")
		(net "M_C_MA<8>")
	)
	(segment
		(start 251.051822 -25.459436)
		(end 250.437396 -24.84501)
		(width 0.14224)
		(layer "In2.Cu")
		(net "M_C_MA<8>")
	)
	(segment
		(start 254.738124 -30.496002)
		(end 253.31801 -29.075888)
		(width 0.14224)
		(layer "In2.Cu")
		(net "M_C_MA<8>")
	)
	(segment
		(start 251.192792 0.799592)
		(end 251.3457 0.9525)
		(width 0.14224)
		(layer "In2.Cu")
		(net "M_C_MA<8>")
	)
	(segment
		(start 250.742704 -26.055574)
		(end 251.051822 -25.746456)
		(width 0.14224)
		(layer "In2.Cu")
		(net "M_C_MA<8>")
	)
	(segment
		(start 255.006094 -59.856624)
		(end 255.01092 -59.847988)
		(width 0.0889)
		(layer "In2.Cu")
		(net "M_C_MA<8>")
	)
	(segment
		(start 254.4572 -51.7144)
		(end 254.738124 -51.433476)
		(width 0.0889)
		(layer "In2.Cu")
		(net "M_C_MA<8>")
	)
	(segment
		(start 251.649992 -4.332478)
		(end 251.216922 -3.899408)
		(width 0.14224)
		(layer "In2.Cu")
		(net "M_C_MA<8>")
	)
	(segment
		(start 251.3457 0.9525)
		(end 251.3457 1.50114)
		(width 0.14224)
		(layer "In2.Cu")
		(net "M_C_MA<8>")
	)
	(segment
		(start 250.437396 -23.317708)
		(end 250.303284 -23.183596)
		(width 0.14224)
		(layer "In2.Cu")
		(net "M_C_MA<8>")
	)
	(segment
		(start 255.01092 -59.847988)
		(end 255.01727 -59.83732)
		(width 0.0889)
		(layer "In2.Cu")
		(net "M_C_MA<8>")
	)
	(segment
		(start 253.31801 -27.725624)
		(end 253.063248 -27.470862)
		(width 0.14224)
		(layer "In2.Cu")
		(net "M_C_MA<8>")
	)
	(segment
		(start 253.063248 -27.470862)
		(end 252.78334 -27.470862)
		(width 0.14224)
		(layer "In2.Cu")
		(net "M_C_MA<8>")
	)
	(segment
		(start 254.161544 -53.824378)
		(end 254.152654 -53.809138)
		(width 0.0889)
		(layer "In2.Cu")
		(net "M_C_MA<8>")
	)
	(segment
		(start 250.742704 -26.351738)
		(end 250.742704 -26.055574)
		(width 0.14224)
		(layer "In2.Cu")
		(net "M_C_MA<8>")
	)
	(arc
		(start 254.152654 -55.790592)
		(mid 254.099121 -55.590694)
		(end 254.152654 -55.390796)
		(width 0.0889)
		(layer "In2.Cu")
		(net "M_C_MA<8>")
	)
	(arc
		(start 254.1524 -53.809138)
		(mid 254.148759 -53.802637)
		(end 254.145034 -53.796184)
		(width 0.0889)
		(layer "In2.Cu")
		(net "M_C_MA<8>")
	)
	(arc
		(start 254.152654 -54.799992)
		(mid 254.099121 -54.600094)
		(end 254.152654 -54.400196)
		(width 0.0889)
		(layer "In2.Cu")
		(net "M_C_MA<8>")
	)
	(arc
		(start 254.2159 -53.298598)
		(mid 254.395861 -52.863223)
		(end 254.4572 -52.396136)
		(width 0.0889)
		(layer "In2.Cu")
		(net "M_C_MA<8>")
	)
	(arc
		(start 254.145034 -53.796184)
		(mid 254.09866 -53.601707)
		(end 254.152146 -53.409088)
		(width 0.0889)
		(layer "In2.Cu")
		(net "M_C_MA<8>")
	)
	(arc
		(start 254.160528 -54.385718)
		(mid 254.231959 -54.105167)
		(end 254.161544 -53.824378)
		(width 0.0889)
		(layer "In2.Cu")
		(net "M_C_MA<8>")
	)
	(arc
		(start 255.01092 -60.248038)
		(mid 254.95745 -60.052975)
		(end 255.006094 -59.856624)
		(width 0.0889)
		(layer "In2.Cu")
		(net "M_C_MA<8>")
	)
	(arc
		(start 254.152654 -56.781192)
		(mid 254.099121 -56.581294)
		(end 254.152654 -56.381396)
		(width 0.0889)
		(layer "In2.Cu")
		(net "M_C_MA<8>")
	)
	(arc
		(start 255.01092 -59.257438)
		(mid 254.975743 -59.177246)
		(end 254.95885 -59.091322)
		(width 0.0889)
		(layer "In2.Cu")
		(net "M_C_MA<8>")
	)
	(arc
		(start 254.288544 -57.92089)
		(mid 254.212498 -57.853722)
		(end 254.152654 -57.771792)
		(width 0.0889)
		(layer "In2.Cu")
		(net "M_C_MA<8>")
	)
	(arc
		(start 255.01727 -59.83732)
		(mid 255.090068 -59.546557)
		(end 255.01092 -59.257438)
		(width 0.0889)
		(layer "In2.Cu")
		(net "M_C_MA<8>")
	)
	(arc
		(start 254.152654 -57.771792)
		(mid 254.099121 -57.571894)
		(end 254.152654 -57.371996)
		(width 0.0889)
		(layer "In2.Cu")
		(net "M_C_MA<8>")
	)
	(arc
		(start 254.152654 -55.390796)
		(mid 254.231785 -55.095394)
		(end 254.152654 -54.799992)
		(width 0.0889)
		(layer "In2.Cu")
		(net "M_C_MA<8>")
	)
	(arc
		(start 254.152654 -57.371996)
		(mid 254.231785 -57.076594)
		(end 254.152654 -56.781192)
		(width 0.0889)
		(layer "In2.Cu")
		(net "M_C_MA<8>")
	)
	(arc
		(start 254.152654 -56.381396)
		(mid 254.231785 -56.085994)
		(end 254.152654 -55.790592)
		(width 0.0889)
		(layer "In2.Cu")
		(net "M_C_MA<8>")
	)
	(arc
		(start 254.84582 -58.362088)
		(mid 254.792331 -58.28896)
		(end 254.724408 -58.228992)
		(width 0.0889)
		(layer "In2.Cu")
		(net "M_C_MA<8>")
	)
	(segment
		(start 255.07061 -61.53404)
		(end 254.49911 -61.53404)
		(width 0.1016)
		(layer "F.Cu")
		(net "M_C_MA<7>")
	)
	(segment
		(start 250.799854 -0.821182)
		(end 250.799854 1.152144)
		(width 0.1651)
		(layer "F.Cu")
		(net "M_C_MA<7>")
	)
	(segment
		(start 250.800362 -0.821182)
		(end 250.799854 -0.821182)
		(width 0.1651)
		(layer "F.Cu")
		(net "M_C_MA<7>")
	)
	(via
		(at 250.799854 -2.314956)
		(size 0.4572)
		(drill 0.2032)
		(layers "F.Cu" "B.Cu")
		(net "M_C_MA<7>")
	)
	(via
		(at 254.49911 -61.53404)
		(size 0.508)
		(drill 0.254)
		(layers "F.Cu" "B.Cu")
		(net "M_C_MA<7>")
	)
	(via
		(at 250.799854 1.152144)
		(size 0.508)
		(drill 0.254)
		(layers "F.Cu" "B.Cu")
		(net "M_C_MA<7>")
	)
	(segment
		(start 250.800362 -1.021842)
		(end 250.799854 -1.021842)
		(width 0.1651)
		(layer "B.Cu")
		(net "M_C_MA<7>")
	)
	(segment
		(start 250.799854 -1.021842)
		(end 250.799854 -2.314956)
		(width 0.1651)
		(layer "B.Cu")
		(net "M_C_MA<7>")
	)
	(segment
		(start 249.59564 -21.278596)
		(end 249.59564 -21.735796)
		(width 0.14224)
		(layer "In2.Cu")
		(net "M_C_MA<7>")
	)
	(segment
		(start 254.850646 -60.734702)
		(end 254.828548 -60.773056)
		(width 0.0889)
		(layer "In2.Cu")
		(net "M_C_MA<7>")
	)
	(segment
		(start 250.2154 0.823976)
		(end 250.6218 0.417576)
		(width 0.14224)
		(layer "In2.Cu")
		(net "M_C_MA<7>")
	)
	(segment
		(start 253.97841 -53.889148)
		(end 253.9873 -53.904388)
		(width 0.0889)
		(layer "In2.Cu")
		(net "M_C_MA<7>")
	)
	(segment
		(start 250.799854 -0.080264)
		(end 250.799854 -0.639572)
		(width 0.14224)
		(layer "In2.Cu")
		(net "M_C_MA<7>")
	)
	(segment
		(start 249.533156 -18.39087)
		(end 249.533156 -21.216112)
		(width 0.14224)
		(layer "In2.Cu")
		(net "M_C_MA<7>")
	)
	(segment
		(start 250.2916 -26.768044)
		(end 254.230124 -30.706568)
		(width 0.14224)
		(layer "In2.Cu")
		(net "M_C_MA<7>")
	)
	(segment
		(start 250.799854 -0.639572)
		(end 250.644914 -0.794512)
		(width 0.14224)
		(layer "In2.Cu")
		(net "M_C_MA<7>")
	)
	(segment
		(start 249.407172 -12.598908)
		(end 249.407172 -13.283692)
		(width 0.14224)
		(layer "In2.Cu")
		(net "M_C_MA<7>")
	)
	(segment
		(start 250.2916 -25.603454)
		(end 250.2916 -26.768044)
		(width 0.14224)
		(layer "In2.Cu")
		(net "M_C_MA<7>")
	)
	(segment
		(start 249.53468 -12.4714)
		(end 249.407172 -12.598908)
		(width 0.14224)
		(layer "In2.Cu")
		(net "M_C_MA<7>")
	)
	(segment
		(start 250.644914 -0.794512)
		(end 249.712226 -0.794512)
		(width 0.14224)
		(layer "In2.Cu")
		(net "M_C_MA<7>")
	)
	(segment
		(start 254.828548 -60.773056)
		(end 254.49911 -61.53404)
		(width 0.0889)
		(layer "In2.Cu")
		(net "M_C_MA<7>")
	)
	(segment
		(start 249.44324 -11.524996)
		(end 249.53468 -11.616436)
		(width 0.14224)
		(layer "In2.Cu")
		(net "M_C_MA<7>")
	)
	(segment
		(start 249.59564 -21.735796)
		(end 249.44324 -21.888196)
		(width 0.14224)
		(layer "In2.Cu")
		(net "M_C_MA<7>")
	)
	(segment
		(start 249.59564 -23.107396)
		(end 249.44324 -23.259796)
		(width 0.14224)
		(layer "In2.Cu")
		(net "M_C_MA<7>")
	)
	(segment
		(start 253.97841 -56.860948)
		(end 253.9873 -56.876188)
		(width 0.0889)
		(layer "In2.Cu")
		(net "M_C_MA<7>")
	)
	(segment
		(start 254.016002 -57.928002)
		(end 254.043688 -58.004456)
		(width 0.0889)
		(layer "In2.Cu")
		(net "M_C_MA<7>")
	)
	(segment
		(start 249.712226 -0.794512)
		(end 249.557286 -0.949452)
		(width 0.14224)
		(layer "In2.Cu")
		(net "M_C_MA<7>")
	)
	(segment
		(start 249.44324 -22.446996)
		(end 249.59564 -22.599396)
		(width 0.14224)
		(layer "In2.Cu")
		(net "M_C_MA<7>")
	)
	(segment
		(start 249.441716 -7.56031)
		(end 249.441716 -8.499094)
		(width 0.14224)
		(layer "In2.Cu")
		(net "M_C_MA<7>")
	)
	(segment
		(start 254.800354 -59.273948)
		(end 254.84582 -59.352688)
		(width 0.0889)
		(layer "In2.Cu")
		(net "M_C_MA<7>")
	)
	(segment
		(start 249.59564 -22.599396)
		(end 249.59564 -23.107396)
		(width 0.14224)
		(layer "In2.Cu")
		(net "M_C_MA<7>")
	)
	(segment
		(start 249.53468 -13.4112)
		(end 249.53468 -17.068546)
		(width 0.14224)
		(layer "In2.Cu")
		(net "M_C_MA<7>")
	)
	(segment
		(start 250.35764 -4.73456)
		(end 249.5296 -5.5626)
		(width 0.14224)
		(layer "In2.Cu")
		(net "M_C_MA<7>")
	)
	(segment
		(start 249.5296 -7.472426)
		(end 249.441716 -7.56031)
		(width 0.14224)
		(layer "In2.Cu")
		(net "M_C_MA<7>")
	)
	(segment
		(start 249.533156 -21.216112)
		(end 249.59564 -21.278596)
		(width 0.14224)
		(layer "In2.Cu")
		(net "M_C_MA<7>")
	)
	(segment
		(start 249.557286 -1.432052)
		(end 249.712226 -1.586992)
		(width 0.14224)
		(layer "In2.Cu")
		(net "M_C_MA<7>")
	)
	(segment
		(start 250.2154 1.1938)
		(end 250.2154 0.823976)
		(width 0.14224)
		(layer "In2.Cu")
		(net "M_C_MA<7>")
	)
	(segment
		(start 249.5423 -8.599678)
		(end 249.5423 -9.639046)
		(width 0.14224)
		(layer "In2.Cu")
		(net "M_C_MA<7>")
	)
	(segment
		(start 249.441716 -8.499094)
		(end 249.5423 -8.599678)
		(width 0.14224)
		(layer "In2.Cu")
		(net "M_C_MA<7>")
	)
	(segment
		(start 250.799854 1.152144)
		(end 250.605798 1.3462)
		(width 0.14224)
		(layer "In2.Cu")
		(net "M_C_MA<7>")
	)
	(segment
		(start 254.850646 -59.744102)
		(end 254.84582 -59.752738)
		(width 0.0889)
		(layer "In2.Cu")
		(net "M_C_MA<7>")
	)
	(segment
		(start 249.5423 -9.639046)
		(end 249.44324 -9.738106)
		(width 0.14224)
		(layer "In2.Cu")
		(net "M_C_MA<7>")
	)
	(segment
		(start 249.53468 -17.068546)
		(end 249.451622 -17.151604)
		(width 0.14224)
		(layer "In2.Cu")
		(net "M_C_MA<7>")
	)
	(segment
		(start 250.605798 1.3462)
		(end 250.3678 1.3462)
		(width 0.14224)
		(layer "In2.Cu")
		(net "M_C_MA<7>")
	)
	(segment
		(start 254.352806 -58.93435)
		(end 254.800354 -59.273948)
		(width 0.0889)
		(layer "In2.Cu")
		(net "M_C_MA<7>")
	)
	(segment
		(start 249.44324 -9.738106)
		(end 249.44324 -11.524996)
		(width 0.14224)
		(layer "In2.Cu")
		(net "M_C_MA<7>")
	)
	(segment
		(start 249.557286 -0.949452)
		(end 249.557286 -1.432052)
		(width 0.14224)
		(layer "In2.Cu")
		(net "M_C_MA<7>")
	)
	(segment
		(start 249.53468 -11.616436)
		(end 249.53468 -12.4714)
		(width 0.14224)
		(layer "In2.Cu")
		(net "M_C_MA<7>")
	)
	(segment
		(start 254.230124 -51.148996)
		(end 254.1778 -51.20132)
		(width 0.0889)
		(layer "In2.Cu")
		(net "M_C_MA<7>")
	)
	(segment
		(start 254.1778 -51.20132)
		(end 254.1778 -52.603146)
		(width 0.0889)
		(layer "In2.Cu")
		(net "M_C_MA<7>")
	)
	(segment
		(start 249.44324 -23.259796)
		(end 249.44324 -24.755094)
		(width 0.14224)
		(layer "In2.Cu")
		(net "M_C_MA<7>")
	)
	(segment
		(start 254.84582 -59.752738)
		(end 254.83947 -59.763406)
		(width 0.0889)
		(layer "In2.Cu")
		(net "M_C_MA<7>")
	)
	(segment
		(start 254.230124 -50.843942)
		(end 254.230124 -51.148996)
		(width 0.0889)
		(layer "In2.Cu")
		(net "M_C_MA<7>")
	)
	(segment
		(start 249.712226 -1.586992)
		(end 250.644914 -1.586992)
		(width 0.14224)
		(layer "In2.Cu")
		(net "M_C_MA<7>")
	)
	(segment
		(start 254.230124 -30.706568)
		(end 254.230124 -50.843942)
		(width 0.14224)
		(layer "In2.Cu")
		(net "M_C_MA<7>")
	)
	(segment
		(start 249.451622 -18.309336)
		(end 249.533156 -18.39087)
		(width 0.14224)
		(layer "In2.Cu")
		(net "M_C_MA<7>")
	)
	(segment
		(start 249.44324 -21.888196)
		(end 249.44324 -22.446996)
		(width 0.14224)
		(layer "In2.Cu")
		(net "M_C_MA<7>")
	)
	(segment
		(start 249.451622 -17.151604)
		(end 249.451622 -18.309336)
		(width 0.14224)
		(layer "In2.Cu")
		(net "M_C_MA<7>")
	)
	(segment
		(start 250.35764 -2.75717)
		(end 250.35764 -4.73456)
		(width 0.14224)
		(layer "In2.Cu")
		(net "M_C_MA<7>")
	)
	(segment
		(start 250.6218 0.09779)
		(end 250.799854 -0.080264)
		(width 0.14224)
		(layer "In2.Cu")
		(net "M_C_MA<7>")
	)
	(segment
		(start 253.97841 -54.879748)
		(end 253.9873 -54.894988)
		(width 0.0889)
		(layer "In2.Cu")
		(net "M_C_MA<7>")
	)
	(segment
		(start 254.043688 -58.004456)
		(end 254.09906 -58.563764)
		(width 0.0889)
		(layer "In2.Cu")
		(net "M_C_MA<7>")
	)
	(segment
		(start 250.644914 -1.586992)
		(end 250.799854 -1.741932)
		(width 0.14224)
		(layer "In2.Cu")
		(net "M_C_MA<7>")
	)
	(segment
		(start 249.5296 -5.5626)
		(end 249.5296 -7.472426)
		(width 0.14224)
		(layer "In2.Cu")
		(net "M_C_MA<7>")
	)
	(segment
		(start 250.3678 1.3462)
		(end 250.2154 1.1938)
		(width 0.14224)
		(layer "In2.Cu")
		(net "M_C_MA<7>")
	)
	(segment
		(start 249.407172 -13.283692)
		(end 249.53468 -13.4112)
		(width 0.14224)
		(layer "In2.Cu")
		(net "M_C_MA<7>")
	)
	(segment
		(start 253.97841 -55.870348)
		(end 253.9873 -55.885588)
		(width 0.0889)
		(layer "In2.Cu")
		(net "M_C_MA<7>")
	)
	(segment
		(start 253.98095 -57.856374)
		(end 253.9873 -57.867042)
		(width 0.0889)
		(layer "In2.Cu")
		(net "M_C_MA<7>")
	)
	(segment
		(start 249.44324 -24.755094)
		(end 250.2916 -25.603454)
		(width 0.14224)
		(layer "In2.Cu")
		(net "M_C_MA<7>")
	)
	(segment
		(start 250.799854 -2.314956)
		(end 250.35764 -2.75717)
		(width 0.14224)
		(layer "In2.Cu")
		(net "M_C_MA<7>")
	)
	(segment
		(start 250.6218 0.417576)
		(end 250.6218 0.09779)
		(width 0.14224)
		(layer "In2.Cu")
		(net "M_C_MA<7>")
	)
	(segment
		(start 250.799854 -1.741932)
		(end 250.799854 -2.314956)
		(width 0.14224)
		(layer "In2.Cu")
		(net "M_C_MA<7>")
	)
	(arc
		(start 253.9873 -55.885588)
		(mid 254.040833 -56.085486)
		(end 253.9873 -56.285384)
		(width 0.0889)
		(layer "In2.Cu")
		(net "M_C_MA<7>")
	)
	(arc
		(start 253.9873 -53.904388)
		(mid 254.040833 -54.104286)
		(end 253.9873 -54.304184)
		(width 0.0889)
		(layer "In2.Cu")
		(net "M_C_MA<7>")
	)
	(arc
		(start 253.9873 -56.876188)
		(mid 254.040833 -57.076086)
		(end 253.9873 -57.275984)
		(width 0.0889)
		(layer "In2.Cu")
		(net "M_C_MA<7>")
	)
	(arc
		(start 253.9873 -54.894988)
		(mid 254.040833 -55.094886)
		(end 253.9873 -55.294784)
		(width 0.0889)
		(layer "In2.Cu")
		(net "M_C_MA<7>")
	)
	(arc
		(start 253.9873 -55.294784)
		(mid 253.908111 -55.581399)
		(end 253.97841 -55.870348)
		(width 0.0889)
		(layer "In2.Cu")
		(net "M_C_MA<7>")
	)
	(arc
		(start 253.9873 -56.285384)
		(mid 253.908111 -56.571999)
		(end 253.97841 -56.860948)
		(width 0.0889)
		(layer "In2.Cu")
		(net "M_C_MA<7>")
	)
	(arc
		(start 254.84582 -59.352688)
		(mid 254.89929 -59.547751)
		(end 254.850646 -59.744102)
		(width 0.0889)
		(layer "In2.Cu")
		(net "M_C_MA<7>")
	)
	(arc
		(start 253.9873 -57.867042)
		(mid 254.002931 -57.896919)
		(end 254.016002 -57.928002)
		(width 0.0889)
		(layer "In2.Cu")
		(net "M_C_MA<7>")
	)
	(arc
		(start 254.84582 -60.343288)
		(mid 254.89929 -60.538351)
		(end 254.850646 -60.734702)
		(width 0.0889)
		(layer "In2.Cu")
		(net "M_C_MA<7>")
	)
	(arc
		(start 253.9873 -57.275984)
		(mid 253.907951 -57.565356)
		(end 253.98095 -57.856374)
		(width 0.0889)
		(layer "In2.Cu")
		(net "M_C_MA<7>")
	)
	(arc
		(start 253.9873 -53.313584)
		(mid 253.908111 -53.600199)
		(end 253.97841 -53.889148)
		(width 0.0889)
		(layer "In2.Cu")
		(net "M_C_MA<7>")
	)
	(arc
		(start 254.09906 -58.563764)
		(mid 254.169029 -58.788016)
		(end 254.352806 -58.93435)
		(width 0.0889)
		(layer "In2.Cu")
		(net "M_C_MA<7>")
	)
	(arc
		(start 253.9873 -54.304184)
		(mid 253.908111 -54.590799)
		(end 253.97841 -54.879748)
		(width 0.0889)
		(layer "In2.Cu")
		(net "M_C_MA<7>")
	)
	(arc
		(start 254.83947 -59.763406)
		(mid 254.766672 -60.054169)
		(end 254.84582 -60.343288)
		(width 0.0889)
		(layer "In2.Cu")
		(net "M_C_MA<7>")
	)
	(arc
		(start 254.1778 -52.603146)
		(mid 254.12936 -52.97092)
		(end 253.9873 -53.313584)
		(width 0.0889)
		(layer "In2.Cu")
		(net "M_C_MA<7>")
	)
	(segment
		(start 252.499876 3.778758)
		(end 252.499876 2.485644)
		(width 0.1651)
		(layer "F.Cu")
		(net "M_C_MA<6>")
	)
	(segment
		(start 252.500384 3.778758)
		(end 252.499876 3.778758)
		(width 0.1651)
		(layer "F.Cu")
		(net "M_C_MA<6>")
	)
	(segment
		(start 255.92913 -60.047886)
		(end 255.35763 -60.047886)
		(width 0.1016)
		(layer "F.Cu")
		(net "M_C_MA<6>")
	)
	(via
		(at 255.35763 -60.047886)
		(size 0.508)
		(drill 0.254)
		(layers "F.Cu" "B.Cu")
		(net "M_C_MA<6>")
	)
	(via
		(at 252.499876 -4.332478)
		(size 0.4572)
		(drill 0.2032)
		(layers "F.Cu" "B.Cu")
		(net "M_C_MA<6>")
	)
	(via
		(at 252.499876 2.485644)
		(size 0.508)
		(drill 0.254)
		(layers "F.Cu" "B.Cu")
		(net "M_C_MA<6>")
	)
	(segment
		(start 252.500384 -5.621782)
		(end 252.499876 -5.621782)
		(width 0.1651)
		(layer "B.Cu")
		(net "M_C_MA<6>")
	)
	(segment
		(start 252.499876 -5.621782)
		(end 252.499876 -4.332478)
		(width 0.1651)
		(layer "B.Cu")
		(net "M_C_MA<6>")
	)
	(segment
		(start 255.35763 -60.047886)
		(end 255.687576 -59.28614)
		(width 0.0889)
		(layer "In2.Cu")
		(net "M_C_MA<6>")
	)
	(segment
		(start 251.293884 -20.73402)
		(end 251.209302 -20.649438)
		(width 0.14224)
		(layer "In2.Cu")
		(net "M_C_MA<6>")
	)
	(segment
		(start 253.82601 -27.515058)
		(end 251.15901 -24.848058)
		(width 0.14224)
		(layer "In2.Cu")
		(net "M_C_MA<6>")
	)
	(segment
		(start 255.550162 -58.706512)
		(end 255.223772 -58.494422)
		(width 0.0889)
		(layer "In2.Cu")
		(net "M_C_MA<6>")
	)
	(segment
		(start 254.84582 -56.780938)
		(end 254.850646 -56.772302)
		(width 0.0889)
		(layer "In2.Cu")
		(net "M_C_MA<6>")
	)
	(segment
		(start 251.23648 -12.889992)
		(end 251.20854 -12.862052)
		(width 0.14224)
		(layer "In2.Cu")
		(net "M_C_MA<6>")
	)
	(segment
		(start 253.82601 -28.865322)
		(end 253.82601 -27.515058)
		(width 0.14224)
		(layer "In2.Cu")
		(net "M_C_MA<6>")
	)
	(segment
		(start 251.20854 -12.862052)
		(end 251.20854 -11.062462)
		(width 0.14224)
		(layer "In2.Cu")
		(net "M_C_MA<6>")
	)
	(segment
		(start 251.242322 -8.047228)
		(end 251.242322 -6.288278)
		(width 0.14224)
		(layer "In2.Cu")
		(net "M_C_MA<6>")
	)
	(segment
		(start 251.899674 -1.902714)
		(end 251.899674 0.053594)
		(width 0.14224)
		(layer "In2.Cu")
		(net "M_C_MA<6>")
	)
	(segment
		(start 254.95758 -58.076592)
		(end 254.94234 -57.923938)
		(width 0.0889)
		(layer "In2.Cu")
		(net "M_C_MA<6>")
	)
	(segment
		(start 251.166884 -22.421596)
		(end 251.166884 -21.938996)
		(width 0.14224)
		(layer "In2.Cu")
		(net "M_C_MA<6>")
	)
	(segment
		(start 255.052068 -58.338212)
		(end 255.01092 -58.266838)
		(width 0.0889)
		(layer "In2.Cu")
		(net "M_C_MA<6>")
	)
	(segment
		(start 251.15901 -23.31847)
		(end 251.344684 -23.132796)
		(width 0.14224)
		(layer "In2.Cu")
		(net "M_C_MA<6>")
	)
	(segment
		(start 255.223772 -58.494422)
		(end 255.052068 -58.338212)
		(width 0.0889)
		(layer "In2.Cu")
		(net "M_C_MA<6>")
	)
	(segment
		(start 252.087634 -3.337052)
		(end 252.087634 -2.090674)
		(width 0.14224)
		(layer "In2.Cu")
		(net "M_C_MA<6>")
	)
	(segment
		(start 254.94234 -57.923938)
		(end 254.89916 -57.580784)
		(width 0.0889)
		(layer "In2.Cu")
		(net "M_C_MA<6>")
	)
	(segment
		(start 251.207524 -8.082026)
		(end 251.242322 -8.047228)
		(width 0.14224)
		(layer "In2.Cu")
		(net "M_C_MA<6>")
	)
	(segment
		(start 252.499876 -5.030724)
		(end 252.499876 -4.332478)
		(width 0.14224)
		(layer "In2.Cu")
		(net "M_C_MA<6>")
	)
	(segment
		(start 254.83947 -56.791606)
		(end 254.84582 -56.780938)
		(width 0.0889)
		(layer "In2.Cu")
		(net "M_C_MA<6>")
	)
	(segment
		(start 252.1204 0.27432)
		(end 252.1204 0.7874)
		(width 0.14224)
		(layer "In2.Cu")
		(net "M_C_MA<6>")
	)
	(segment
		(start 252.499876 -4.332478)
		(end 252.087634 -3.337052)
		(width 0.14224)
		(layer "In2.Cu")
		(net "M_C_MA<6>")
	)
	(segment
		(start 254.84582 -54.799738)
		(end 254.850646 -54.791102)
		(width 0.0889)
		(layer "In2.Cu")
		(net "M_C_MA<6>")
	)
	(segment
		(start 254.84582 -53.809138)
		(end 254.850646 -53.800502)
		(width 0.0889)
		(layer "In2.Cu")
		(net "M_C_MA<6>")
	)
	(segment
		(start 252.037596 0.870204)
		(end 252.037596 1.369568)
		(width 0.14224)
		(layer "In2.Cu")
		(net "M_C_MA<6>")
	)
	(segment
		(start 251.242322 -6.288278)
		(end 252.499876 -5.030724)
		(width 0.14224)
		(layer "In2.Cu")
		(net "M_C_MA<6>")
	)
	(segment
		(start 251.166884 -21.938996)
		(end 251.293884 -21.811996)
		(width 0.14224)
		(layer "In2.Cu")
		(net "M_C_MA<6>")
	)
	(segment
		(start 254.83947 -53.819806)
		(end 254.84582 -53.809138)
		(width 0.0889)
		(layer "In2.Cu")
		(net "M_C_MA<6>")
	)
	(segment
		(start 255.246124 -51.281076)
		(end 255.246124 -48.44415)
		(width 0.0889)
		(layer "In2.Cu")
		(net "M_C_MA<6>")
	)
	(segment
		(start 251.344684 -23.132796)
		(end 251.344684 -22.599396)
		(width 0.14224)
		(layer "In2.Cu")
		(net "M_C_MA<6>")
	)
	(segment
		(start 255.687576 -59.28614)
		(end 255.70434 -59.257438)
		(width 0.0889)
		(layer "In2.Cu")
		(net "M_C_MA<6>")
	)
	(segment
		(start 255.246124 -30.285436)
		(end 253.82601 -28.865322)
		(width 0.14224)
		(layer "In2.Cu")
		(net "M_C_MA<6>")
	)
	(segment
		(start 251.293884 -21.811996)
		(end 251.293884 -20.73402)
		(width 0.14224)
		(layer "In2.Cu")
		(net "M_C_MA<6>")
	)
	(segment
		(start 251.209302 -20.649438)
		(end 251.209302 -17.769586)
		(width 0.14224)
		(layer "In2.Cu")
		(net "M_C_MA<6>")
	)
	(segment
		(start 254.83947 -54.810406)
		(end 254.84582 -54.799738)
		(width 0.0889)
		(layer "In2.Cu")
		(net "M_C_MA<6>")
	)
	(segment
		(start 251.20854 -11.062462)
		(end 251.207524 -11.061446)
		(width 0.14224)
		(layer "In2.Cu")
		(net "M_C_MA<6>")
	)
	(segment
		(start 251.209302 -17.769586)
		(end 251.23648 -17.742408)
		(width 0.14224)
		(layer "In2.Cu")
		(net "M_C_MA<6>")
	)
	(segment
		(start 252.087634 -2.090674)
		(end 251.899674 -1.902714)
		(width 0.14224)
		(layer "In2.Cu")
		(net "M_C_MA<6>")
	)
	(segment
		(start 251.344684 -22.599396)
		(end 251.166884 -22.421596)
		(width 0.14224)
		(layer "In2.Cu")
		(net "M_C_MA<6>")
	)
	(segment
		(start 251.23648 -17.742408)
		(end 251.23648 -12.889992)
		(width 0.14224)
		(layer "In2.Cu")
		(net "M_C_MA<6>")
	)
	(segment
		(start 251.899674 0.053594)
		(end 252.1204 0.27432)
		(width 0.14224)
		(layer "In2.Cu")
		(net "M_C_MA<6>")
	)
	(segment
		(start 254.84582 -53.409342)
		(end 254.736092 -53.21935)
		(width 0.0889)
		(layer "In2.Cu")
		(net "M_C_MA<6>")
	)
	(segment
		(start 251.15901 -24.848058)
		(end 251.15901 -23.31847)
		(width 0.14224)
		(layer "In2.Cu")
		(net "M_C_MA<6>")
	)
	(segment
		(start 255.246124 -48.44415)
		(end 255.246124 -30.285436)
		(width 0.14224)
		(layer "In2.Cu")
		(net "M_C_MA<6>")
	)
	(segment
		(start 252.037596 1.369568)
		(end 252.499876 2.485644)
		(width 0.14224)
		(layer "In2.Cu")
		(net "M_C_MA<6>")
	)
	(segment
		(start 254.736092 -51.791108)
		(end 255.246124 -51.281076)
		(width 0.0889)
		(layer "In2.Cu")
		(net "M_C_MA<6>")
	)
	(segment
		(start 251.207524 -11.061446)
		(end 251.207524 -8.082026)
		(width 0.14224)
		(layer "In2.Cu")
		(net "M_C_MA<6>")
	)
	(segment
		(start 252.1204 0.7874)
		(end 252.037596 0.870204)
		(width 0.14224)
		(layer "In2.Cu")
		(net "M_C_MA<6>")
	)
	(segment
		(start 254.736092 -53.21935)
		(end 254.736092 -51.791108)
		(width 0.0889)
		(layer "In2.Cu")
		(net "M_C_MA<6>")
	)
	(segment
		(start 254.84582 -55.790338)
		(end 254.850646 -55.781702)
		(width 0.0889)
		(layer "In2.Cu")
		(net "M_C_MA<6>")
	)
	(segment
		(start 254.83947 -55.801006)
		(end 254.84582 -55.790338)
		(width 0.0889)
		(layer "In2.Cu")
		(net "M_C_MA<6>")
	)
	(arc
		(start 254.84582 -54.399688)
		(mid 254.766598 -54.11057)
		(end 254.83947 -53.819806)
		(width 0.0889)
		(layer "In2.Cu")
		(net "M_C_MA<6>")
	)
	(arc
		(start 254.850646 -54.791102)
		(mid 254.899401 -54.59475)
		(end 254.84582 -54.399688)
		(width 0.0889)
		(layer "In2.Cu")
		(net "M_C_MA<6>")
	)
	(arc
		(start 254.89916 -57.580784)
		(mid 254.886854 -57.472479)
		(end 254.84582 -57.371488)
		(width 0.0889)
		(layer "In2.Cu")
		(net "M_C_MA<6>")
	)
	(arc
		(start 255.01092 -58.266838)
		(mid 254.972303 -58.175062)
		(end 254.95758 -58.076592)
		(width 0.0889)
		(layer "In2.Cu")
		(net "M_C_MA<6>")
	)
	(arc
		(start 255.70434 -59.257438)
		(mid 255.743011 -58.949613)
		(end 255.550162 -58.706512)
		(width 0.0889)
		(layer "In2.Cu")
		(net "M_C_MA<6>")
	)
	(arc
		(start 254.84582 -57.371488)
		(mid 254.766598 -57.08237)
		(end 254.83947 -56.791606)
		(width 0.0889)
		(layer "In2.Cu")
		(net "M_C_MA<6>")
	)
	(arc
		(start 254.84582 -56.380888)
		(mid 254.766598 -56.09177)
		(end 254.83947 -55.801006)
		(width 0.0889)
		(layer "In2.Cu")
		(net "M_C_MA<6>")
	)
	(arc
		(start 254.850646 -55.781702)
		(mid 254.899401 -55.58535)
		(end 254.84582 -55.390288)
		(width 0.0889)
		(layer "In2.Cu")
		(net "M_C_MA<6>")
	)
	(arc
		(start 254.84582 -55.390288)
		(mid 254.766598 -55.10117)
		(end 254.83947 -54.810406)
		(width 0.0889)
		(layer "In2.Cu")
		(net "M_C_MA<6>")
	)
	(arc
		(start 254.850646 -53.800502)
		(mid 254.899278 -53.604294)
		(end 254.84582 -53.409342)
		(width 0.0889)
		(layer "In2.Cu")
		(net "M_C_MA<6>")
	)
	(arc
		(start 254.850646 -56.772302)
		(mid 254.899401 -56.57595)
		(end 254.84582 -56.380888)
		(width 0.0889)
		(layer "In2.Cu")
		(net "M_C_MA<6>")
	)
	(segment
		(start 255.92913 -58.06694)
		(end 255.35763 -58.06694)
		(width 0.1016)
		(layer "F.Cu")
		(net "M_C_MA<5>")
	)
	(segment
		(start 252.499876 -0.821182)
		(end 252.499876 1.152144)
		(width 0.1651)
		(layer "F.Cu")
		(net "M_C_MA<5>")
	)
	(segment
		(start 252.500384 -0.821182)
		(end 252.499876 -0.821182)
		(width 0.1651)
		(layer "F.Cu")
		(net "M_C_MA<5>")
	)
	(via
		(at 252.499876 -2.316988)
		(size 0.4572)
		(drill 0.2032)
		(layers "F.Cu" "B.Cu")
		(net "M_C_MA<5>")
	)
	(via
		(at 255.35763 -58.06694)
		(size 0.508)
		(drill 0.254)
		(layers "F.Cu" "B.Cu")
		(net "M_C_MA<5>")
	)
	(via
		(at 252.499876 1.152144)
		(size 0.508)
		(drill 0.254)
		(layers "F.Cu" "B.Cu")
		(net "M_C_MA<5>")
	)
	(segment
		(start 252.499876 -1.021842)
		(end 252.499876 -2.316988)
		(width 0.1651)
		(layer "B.Cu")
		(net "M_C_MA<5>")
	)
	(segment
		(start 252.500384 -1.021842)
		(end 252.499876 -1.021842)
		(width 0.1651)
		(layer "B.Cu")
		(net "M_C_MA<5>")
	)
	(segment
		(start 252.687074 -1.706626)
		(end 252.475238 -1.706626)
		(width 0.14224)
		(layer "In2.Cu")
		(net "M_C_MA<5>")
	)
	(segment
		(start 254.9398 -51.9176)
		(end 255.525524 -51.331876)
		(width 0.0889)
		(layer "In2.Cu")
		(net "M_C_MA<5>")
	)
	(segment
		(start 252.157484 -22.396196)
		(end 252.157484 -21.913596)
		(width 0.14224)
		(layer "In2.Cu")
		(net "M_C_MA<5>")
	)
	(segment
		(start 255.35763 -58.06694)
		(end 255.154684 -57.52465)
		(width 0.0889)
		(layer "In2.Cu")
		(net "M_C_MA<5>")
	)
	(segment
		(start 252.902212 -0.990346)
		(end 252.902212 -0.738886)
		(width 0.14224)
		(layer "In2.Cu")
		(net "M_C_MA<5>")
	)
	(segment
		(start 255.01092 -55.885588)
		(end 255.01727 -55.87492)
		(width 0.0889)
		(layer "In2.Cu")
		(net "M_C_MA<5>")
	)
	(segment
		(start 255.525524 -51.331876)
		(end 255.525524 -48.943514)
		(width 0.0889)
		(layer "In2.Cu")
		(net "M_C_MA<5>")
	)
	(segment
		(start 252.092206 -12.860274)
		(end 252.092206 -6.200394)
		(width 0.14224)
		(layer "In2.Cu")
		(net "M_C_MA<5>")
	)
	(segment
		(start 254.9398 -53.190648)
		(end 254.9398 -51.9176)
		(width 0.0889)
		(layer "In2.Cu")
		(net "M_C_MA<5>")
	)
	(segment
		(start 254.479044 -28.477718)
		(end 254.479044 -27.449526)
		(width 0.14224)
		(layer "In2.Cu")
		(net "M_C_MA<5>")
	)
	(segment
		(start 255.754124 -29.00553)
		(end 255.461008 -28.712414)
		(width 0.14224)
		(layer "In2.Cu")
		(net "M_C_MA<5>")
	)
	(segment
		(start 252.005084 -19.141186)
		(end 252.08738 -19.05889)
		(width 0.14224)
		(layer "In2.Cu")
		(net "M_C_MA<5>")
	)
	(segment
		(start 255.006094 -53.913024)
		(end 255.01092 -53.904388)
		(width 0.0889)
		(layer "In2.Cu")
		(net "M_C_MA<5>")
	)
	(segment
		(start 251.979684 -22.573996)
		(end 252.157484 -22.396196)
		(width 0.14224)
		(layer "In2.Cu")
		(net "M_C_MA<5>")
	)
	(segment
		(start 252.07722 -18.451322)
		(end 252.07722 -12.87526)
		(width 0.14224)
		(layer "In2.Cu")
		(net "M_C_MA<5>")
	)
	(segment
		(start 252.911864 0.681228)
		(end 253.201678 0.971042)
		(width 0.14224)
		(layer "In2.Cu")
		(net "M_C_MA<5>")
	)
	(segment
		(start 252.842014 -2.189734)
		(end 252.842014 -1.861566)
		(width 0.14224)
		(layer "In2.Cu")
		(net "M_C_MA<5>")
	)
	(segment
		(start 253.201678 0.971042)
		(end 253.201678 1.223772)
		(width 0.14224)
		(layer "In2.Cu")
		(net "M_C_MA<5>")
	)
	(segment
		(start 252.71476 -2.316988)
		(end 252.842014 -2.189734)
		(width 0.14224)
		(layer "In2.Cu")
		(net "M_C_MA<5>")
	)
	(segment
		(start 252.31344 -1.544828)
		(end 252.31344 -1.293368)
		(width 0.14224)
		(layer "In2.Cu")
		(net "M_C_MA<5>")
	)
	(segment
		(start 252.747272 -0.583946)
		(end 252.45822 -0.583946)
		(width 0.14224)
		(layer "In2.Cu")
		(net "M_C_MA<5>")
	)
	(segment
		(start 255.754124 -48.55845)
		(end 255.754124 -29.00553)
		(width 0.14224)
		(layer "In2.Cu")
		(net "M_C_MA<5>")
	)
	(segment
		(start 252.313186 -0.438912)
		(end 252.313186 -0.187452)
		(width 0.14224)
		(layer "In2.Cu")
		(net "M_C_MA<5>")
	)
	(segment
		(start 252.461522 -1.145286)
		(end 252.747272 -1.145286)
		(width 0.14224)
		(layer "In2.Cu")
		(net "M_C_MA<5>")
	)
	(segment
		(start 255.01092 -54.894988)
		(end 255.01727 -54.88432)
		(width 0.0889)
		(layer "In2.Cu")
		(net "M_C_MA<5>")
	)
	(segment
		(start 254.71374 -28.712414)
		(end 254.479044 -28.477718)
		(width 0.14224)
		(layer "In2.Cu")
		(net "M_C_MA<5>")
	)
	(segment
		(start 252.992382 1.433068)
		(end 252.7808 1.433068)
		(width 0.14224)
		(layer "In2.Cu")
		(net "M_C_MA<5>")
	)
	(segment
		(start 255.01092 -53.904388)
		(end 255.01727 -53.89372)
		(width 0.0889)
		(layer "In2.Cu")
		(net "M_C_MA<5>")
	)
	(segment
		(start 252.499876 -3.043428)
		(end 252.499876 -2.316988)
		(width 0.14224)
		(layer "In2.Cu")
		(net "M_C_MA<5>")
	)
	(segment
		(start 252.7808 1.433068)
		(end 252.499876 1.152144)
		(width 0.14224)
		(layer "In2.Cu")
		(net "M_C_MA<5>")
	)
	(segment
		(start 255.461008 -28.712414)
		(end 254.71374 -28.712414)
		(width 0.14224)
		(layer "In2.Cu")
		(net "M_C_MA<5>")
	)
	(segment
		(start 255.006094 -56.884824)
		(end 255.01092 -56.876188)
		(width 0.0889)
		(layer "In2.Cu")
		(net "M_C_MA<5>")
	)
	(segment
		(start 255.154684 -57.52465)
		(end 255.01092 -57.276238)
		(width 0.0889)
		(layer "In2.Cu")
		(net "M_C_MA<5>")
	)
	(segment
		(start 254.479044 -27.449526)
		(end 252.157484 -25.127966)
		(width 0.14224)
		(layer "In2.Cu")
		(net "M_C_MA<5>")
	)
	(segment
		(start 252.45822 -0.583946)
		(end 252.313186 -0.438912)
		(width 0.14224)
		(layer "In2.Cu")
		(net "M_C_MA<5>")
	)
	(segment
		(start 252.902212 -0.738886)
		(end 252.747272 -0.583946)
		(width 0.14224)
		(layer "In2.Cu")
		(net "M_C_MA<5>")
	)
	(segment
		(start 252.911864 0.160528)
		(end 252.911864 0.681228)
		(width 0.14224)
		(layer "In2.Cu")
		(net "M_C_MA<5>")
	)
	(segment
		(start 252.475238 -1.706626)
		(end 252.31344 -1.544828)
		(width 0.14224)
		(layer "In2.Cu")
		(net "M_C_MA<5>")
	)
	(segment
		(start 253.201678 1.223772)
		(end 252.992382 1.433068)
		(width 0.14224)
		(layer "In2.Cu")
		(net "M_C_MA<5>")
	)
	(segment
		(start 252.313186 -0.187452)
		(end 252.478032 -0.022606)
		(width 0.14224)
		(layer "In2.Cu")
		(net "M_C_MA<5>")
	)
	(segment
		(start 252.747272 -1.145286)
		(end 252.902212 -0.990346)
		(width 0.14224)
		(layer "In2.Cu")
		(net "M_C_MA<5>")
	)
	(segment
		(start 251.979684 -23.107396)
		(end 251.979684 -22.573996)
		(width 0.14224)
		(layer "In2.Cu")
		(net "M_C_MA<5>")
	)
	(segment
		(start 252.915166 -3.458718)
		(end 252.499876 -3.043428)
		(width 0.14224)
		(layer "In2.Cu")
		(net "M_C_MA<5>")
	)
	(segment
		(start 255.01092 -56.876188)
		(end 255.01727 -56.86552)
		(width 0.0889)
		(layer "In2.Cu")
		(net "M_C_MA<5>")
	)
	(segment
		(start 252.915166 -5.377434)
		(end 252.915166 -3.458718)
		(width 0.14224)
		(layer "In2.Cu")
		(net "M_C_MA<5>")
	)
	(segment
		(start 255.006094 -54.903624)
		(end 255.01092 -54.894988)
		(width 0.0889)
		(layer "In2.Cu")
		(net "M_C_MA<5>")
	)
	(segment
		(start 252.478032 -0.022606)
		(end 252.72873 -0.022606)
		(width 0.14224)
		(layer "In2.Cu")
		(net "M_C_MA<5>")
	)
	(segment
		(start 255.525524 -48.943514)
		(end 255.754124 -48.714914)
		(width 0.0889)
		(layer "In2.Cu")
		(net "M_C_MA<5>")
	)
	(segment
		(start 255.006094 -55.894224)
		(end 255.01092 -55.885588)
		(width 0.0889)
		(layer "In2.Cu")
		(net "M_C_MA<5>")
	)
	(segment
		(start 252.092206 -6.200394)
		(end 252.915166 -5.377434)
		(width 0.14224)
		(layer "In2.Cu")
		(net "M_C_MA<5>")
	)
	(segment
		(start 252.31344 -1.293368)
		(end 252.461522 -1.145286)
		(width 0.14224)
		(layer "In2.Cu")
		(net "M_C_MA<5>")
	)
	(segment
		(start 252.08738 -19.05889)
		(end 252.08738 -18.461482)
		(width 0.14224)
		(layer "In2.Cu")
		(net "M_C_MA<5>")
	)
	(segment
		(start 252.005084 -21.761196)
		(end 252.005084 -19.141186)
		(width 0.14224)
		(layer "In2.Cu")
		(net "M_C_MA<5>")
	)
	(segment
		(start 252.72873 -0.022606)
		(end 252.911864 0.160528)
		(width 0.14224)
		(layer "In2.Cu")
		(net "M_C_MA<5>")
	)
	(segment
		(start 252.157484 -25.127966)
		(end 252.157484 -23.285196)
		(width 0.14224)
		(layer "In2.Cu")
		(net "M_C_MA<5>")
	)
	(segment
		(start 252.08738 -18.461482)
		(end 252.07722 -18.451322)
		(width 0.14224)
		(layer "In2.Cu")
		(net "M_C_MA<5>")
	)
	(segment
		(start 252.842014 -1.861566)
		(end 252.687074 -1.706626)
		(width 0.14224)
		(layer "In2.Cu")
		(net "M_C_MA<5>")
	)
	(segment
		(start 252.499876 -2.316988)
		(end 252.71476 -2.316988)
		(width 0.14224)
		(layer "In2.Cu")
		(net "M_C_MA<5>")
	)
	(segment
		(start 252.157484 -23.285196)
		(end 251.979684 -23.107396)
		(width 0.14224)
		(layer "In2.Cu")
		(net "M_C_MA<5>")
	)
	(segment
		(start 255.754124 -48.714914)
		(end 255.754124 -48.55845)
		(width 0.0889)
		(layer "In2.Cu")
		(net "M_C_MA<5>")
	)
	(segment
		(start 255.01092 -53.313838)
		(end 254.9398 -53.190648)
		(width 0.0889)
		(layer "In2.Cu")
		(net "M_C_MA<5>")
	)
	(segment
		(start 252.157484 -21.913596)
		(end 252.005084 -21.761196)
		(width 0.14224)
		(layer "In2.Cu")
		(net "M_C_MA<5>")
	)
	(segment
		(start 252.07722 -12.87526)
		(end 252.092206 -12.860274)
		(width 0.14224)
		(layer "In2.Cu")
		(net "M_C_MA<5>")
	)
	(arc
		(start 255.01092 -56.285638)
		(mid 254.95745 -56.090575)
		(end 255.006094 -55.894224)
		(width 0.0889)
		(layer "In2.Cu")
		(net "M_C_MA<5>")
	)
	(arc
		(start 255.01727 -54.88432)
		(mid 255.090068 -54.593557)
		(end 255.01092 -54.304438)
		(width 0.0889)
		(layer "In2.Cu")
		(net "M_C_MA<5>")
	)
	(arc
		(start 255.01092 -57.276238)
		(mid 254.95745 -57.081175)
		(end 255.006094 -56.884824)
		(width 0.0889)
		(layer "In2.Cu")
		(net "M_C_MA<5>")
	)
	(arc
		(start 255.01092 -54.304438)
		(mid 254.95745 -54.109375)
		(end 255.006094 -53.913024)
		(width 0.0889)
		(layer "In2.Cu")
		(net "M_C_MA<5>")
	)
	(arc
		(start 255.01727 -53.89372)
		(mid 255.090068 -53.602957)
		(end 255.01092 -53.313838)
		(width 0.0889)
		(layer "In2.Cu")
		(net "M_C_MA<5>")
	)
	(arc
		(start 255.01727 -56.86552)
		(mid 255.090068 -56.574757)
		(end 255.01092 -56.285638)
		(width 0.0889)
		(layer "In2.Cu")
		(net "M_C_MA<5>")
	)
	(arc
		(start 255.01727 -55.87492)
		(mid 255.090068 -55.584157)
		(end 255.01092 -55.295038)
		(width 0.0889)
		(layer "In2.Cu")
		(net "M_C_MA<5>")
	)
	(arc
		(start 255.01092 -55.295038)
		(mid 254.95745 -55.099975)
		(end 255.006094 -54.903624)
		(width 0.0889)
		(layer "In2.Cu")
		(net "M_C_MA<5>")
	)
	(segment
		(start 253.350014 -0.821182)
		(end 253.350014 0.442722)
		(width 0.1651)
		(layer "F.Cu")
		(net "M_C_MA<4>")
	)
	(segment
		(start 253.350522 -0.821182)
		(end 253.350014 -0.821182)
		(width 0.1651)
		(layer "F.Cu")
		(net "M_C_MA<4>")
	)
	(segment
		(start 256.78765 -59.55284)
		(end 256.21615 -59.55284)
		(width 0.1016)
		(layer "F.Cu")
		(net "M_C_MA<4>")
	)
	(via
		(at 256.21615 -59.55284)
		(size 0.508)
		(drill 0.254)
		(layers "F.Cu" "B.Cu")
		(net "M_C_MA<4>")
	)
	(via
		(at 253.350014 0.442722)
		(size 0.508)
		(drill 0.254)
		(layers "F.Cu" "B.Cu")
		(net "M_C_MA<4>")
	)
	(via
		(at 253.350014 -2.316988)
		(size 0.4572)
		(drill 0.2032)
		(layers "F.Cu" "B.Cu")
		(net "M_C_MA<4>")
	)
	(segment
		(start 253.350014 -1.021842)
		(end 253.350014 -2.316988)
		(width 0.1651)
		(layer "B.Cu")
		(net "M_C_MA<4>")
	)
	(segment
		(start 253.350522 -1.021842)
		(end 253.350014 -1.021842)
		(width 0.1651)
		(layer "B.Cu")
		(net "M_C_MA<4>")
	)
	(segment
		(start 255.770634 -50.705004)
		(end 256.338324 -50.137314)
		(width 0.0889)
		(layer "In2.Cu")
		(net "M_C_MA<4>")
	)
	(segment
		(start 255.949704 -58.897774)
		(end 255.86944 -58.762392)
		(width 0.0889)
		(layer "In2.Cu")
		(net "M_C_MA<4>")
	)
	(segment
		(start 255.330452 -27.582368)
		(end 253.428754 -25.68067)
		(width 0.14224)
		(layer "In2.Cu")
		(net "M_C_MA<4>")
	)
	(segment
		(start 252.843284 -22.446996)
		(end 252.843284 -21.888196)
		(width 0.14224)
		(layer "In2.Cu")
		(net "M_C_MA<4>")
	)
	(segment
		(start 253.783084 -5.322316)
		(end 253.783084 -3.43027)
		(width 0.14224)
		(layer "In2.Cu")
		(net "M_C_MA<4>")
	)
	(segment
		(start 252.995684 -18.328386)
		(end 252.995684 -17.769586)
		(width 0.14224)
		(layer "In2.Cu")
		(net "M_C_MA<4>")
	)
	(segment
		(start 253.385066 -24.562308)
		(end 252.95098 -24.562308)
		(width 0.14224)
		(layer "In2.Cu")
		(net "M_C_MA<4>")
	)
	(segment
		(start 253.428754 -25.68067)
		(end 253.428754 -25.420828)
		(width 0.14224)
		(layer "In2.Cu")
		(net "M_C_MA<4>")
	)
	(segment
		(start 252.995684 -22.599396)
		(end 252.843284 -22.446996)
		(width 0.14224)
		(layer "In2.Cu")
		(net "M_C_MA<4>")
	)
	(segment
		(start 255.828546 -27.582368)
		(end 255.330452 -27.582368)
		(width 0.14224)
		(layer "In2.Cu")
		(net "M_C_MA<4>")
	)
	(segment
		(start 253.350014 0.442722)
		(end 253.350014 -2.316988)
		(width 0.14224)
		(layer "In2.Cu")
		(net "M_C_MA<4>")
	)
	(segment
		(start 255.770634 -53.066442)
		(end 255.770634 -50.705004)
		(width 0.0889)
		(layer "In2.Cu")
		(net "M_C_MA<4>")
	)
	(segment
		(start 252.91034 -15.148052)
		(end 252.91034 -12.21994)
		(width 0.14224)
		(layer "In2.Cu")
		(net "M_C_MA<4>")
	)
	(segment
		(start 252.843284 -21.888196)
		(end 252.995684 -21.735796)
		(width 0.14224)
		(layer "In2.Cu")
		(net "M_C_MA<4>")
	)
	(segment
		(start 256.21615 -59.55284)
		(end 255.949704 -58.897774)
		(width 0.0889)
		(layer "In2.Cu")
		(net "M_C_MA<4>")
	)
	(segment
		(start 252.932692 -21.215604)
		(end 252.932692 -18.391378)
		(width 0.14224)
		(layer "In2.Cu")
		(net "M_C_MA<4>")
	)
	(segment
		(start 253.350014 -2.9972)
		(end 253.350014 -2.316988)
		(width 0.14224)
		(layer "In2.Cu")
		(net "M_C_MA<4>")
	)
	(segment
		(start 256.338324 -48.956214)
		(end 256.262124 -48.880014)
		(width 0.0889)
		(layer "In2.Cu")
		(net "M_C_MA<4>")
	)
	(segment
		(start 252.9078 -8.77443)
		(end 252.9078 -6.1976)
		(width 0.14224)
		(layer "In2.Cu")
		(net "M_C_MA<4>")
	)
	(segment
		(start 253.783084 -3.43027)
		(end 253.350014 -2.9972)
		(width 0.14224)
		(layer "In2.Cu")
		(net "M_C_MA<4>")
	)
	(segment
		(start 252.91034 -17.09293)
		(end 252.91034 -16.192246)
		(width 0.14224)
		(layer "In2.Cu")
		(net "M_C_MA<4>")
	)
	(segment
		(start 256.262124 -48.880014)
		(end 256.262124 -48.57115)
		(width 0.0889)
		(layer "In2.Cu")
		(net "M_C_MA<4>")
	)
	(segment
		(start 256.338324 -50.137314)
		(end 256.338324 -48.956214)
		(width 0.0889)
		(layer "In2.Cu")
		(net "M_C_MA<4>")
	)
	(segment
		(start 253.726696 -25.122886)
		(end 253.726696 -24.903938)
		(width 0.14224)
		(layer "In2.Cu")
		(net "M_C_MA<4>")
	)
	(segment
		(start 252.995684 -21.735796)
		(end 252.995684 -21.278596)
		(width 0.14224)
		(layer "In2.Cu")
		(net "M_C_MA<4>")
	)
	(segment
		(start 252.91034 -16.192246)
		(end 253.162054 -15.940532)
		(width 0.14224)
		(layer "In2.Cu")
		(net "M_C_MA<4>")
	)
	(segment
		(start 253.162054 -15.399766)
		(end 252.91034 -15.148052)
		(width 0.14224)
		(layer "In2.Cu")
		(net "M_C_MA<4>")
	)
	(segment
		(start 252.79604 -24.407368)
		(end 252.79604 -23.30704)
		(width 0.14224)
		(layer "In2.Cu")
		(net "M_C_MA<4>")
	)
	(segment
		(start 252.92812 -8.79475)
		(end 252.9078 -8.77443)
		(width 0.14224)
		(layer "In2.Cu")
		(net "M_C_MA<4>")
	)
	(segment
		(start 252.92812 -12.20216)
		(end 252.92812 -8.79475)
		(width 0.14224)
		(layer "In2.Cu")
		(net "M_C_MA<4>")
	)
	(segment
		(start 252.932692 -18.391378)
		(end 252.995684 -18.328386)
		(width 0.14224)
		(layer "In2.Cu")
		(net "M_C_MA<4>")
	)
	(segment
		(start 253.162054 -15.940532)
		(end 253.162054 -15.399766)
		(width 0.14224)
		(layer "In2.Cu")
		(net "M_C_MA<4>")
	)
	(segment
		(start 252.995684 -23.107396)
		(end 252.995684 -22.599396)
		(width 0.14224)
		(layer "In2.Cu")
		(net "M_C_MA<4>")
	)
	(segment
		(start 252.79604 -23.30704)
		(end 252.995684 -23.107396)
		(width 0.14224)
		(layer "In2.Cu")
		(net "M_C_MA<4>")
	)
	(segment
		(start 252.95098 -24.562308)
		(end 252.79604 -24.407368)
		(width 0.14224)
		(layer "In2.Cu")
		(net "M_C_MA<4>")
	)
	(segment
		(start 253.428754 -25.420828)
		(end 253.726696 -25.122886)
		(width 0.14224)
		(layer "In2.Cu")
		(net "M_C_MA<4>")
	)
	(segment
		(start 256.262124 -48.57115)
		(end 256.262124 -28.015946)
		(width 0.14224)
		(layer "In2.Cu")
		(net "M_C_MA<4>")
	)
	(segment
		(start 252.792484 -17.566386)
		(end 252.792484 -17.210786)
		(width 0.14224)
		(layer "In2.Cu")
		(net "M_C_MA<4>")
	)
	(segment
		(start 252.9078 -6.1976)
		(end 253.783084 -5.322316)
		(width 0.14224)
		(layer "In2.Cu")
		(net "M_C_MA<4>")
	)
	(segment
		(start 253.726696 -24.903938)
		(end 253.385066 -24.562308)
		(width 0.14224)
		(layer "In2.Cu")
		(net "M_C_MA<4>")
	)
	(segment
		(start 252.91034 -12.21994)
		(end 252.92812 -12.20216)
		(width 0.14224)
		(layer "In2.Cu")
		(net "M_C_MA<4>")
	)
	(segment
		(start 252.792484 -17.210786)
		(end 252.91034 -17.09293)
		(width 0.14224)
		(layer "In2.Cu")
		(net "M_C_MA<4>")
	)
	(segment
		(start 252.995684 -17.769586)
		(end 252.792484 -17.566386)
		(width 0.14224)
		(layer "In2.Cu")
		(net "M_C_MA<4>")
	)
	(segment
		(start 256.262124 -28.015946)
		(end 255.828546 -27.582368)
		(width 0.14224)
		(layer "In2.Cu")
		(net "M_C_MA<4>")
	)
	(segment
		(start 252.995684 -21.278596)
		(end 252.932692 -21.215604)
		(width 0.14224)
		(layer "In2.Cu")
		(net "M_C_MA<4>")
	)
	(arc
		(start 255.70434 -53.904896)
		(mid 255.625209 -53.609494)
		(end 255.70434 -53.314092)
		(width 0.0889)
		(layer "In2.Cu")
		(net "M_C_MA<4>")
	)
	(arc
		(start 255.70434 -55.886096)
		(mid 255.625209 -55.590694)
		(end 255.70434 -55.295292)
		(width 0.0889)
		(layer "In2.Cu")
		(net "M_C_MA<4>")
	)
	(arc
		(start 255.70434 -56.876696)
		(mid 255.625209 -56.581294)
		(end 255.70434 -56.285892)
		(width 0.0889)
		(layer "In2.Cu")
		(net "M_C_MA<4>")
	)
	(arc
		(start 255.70434 -54.304692)
		(mid 255.757873 -54.104794)
		(end 255.70434 -53.904896)
		(width 0.0889)
		(layer "In2.Cu")
		(net "M_C_MA<4>")
	)
	(arc
		(start 255.86944 -58.762392)
		(mid 255.824209 -58.643421)
		(end 255.81864 -58.516266)
		(width 0.0889)
		(layer "In2.Cu")
		(net "M_C_MA<4>")
	)
	(arc
		(start 255.70434 -56.285892)
		(mid 255.757839 -56.085994)
		(end 255.70434 -55.886096)
		(width 0.0889)
		(layer "In2.Cu")
		(net "M_C_MA<4>")
	)
	(arc
		(start 255.785112 -58.239406)
		(mid 255.766298 -58.145774)
		(end 255.757426 -58.050684)
		(width 0.0889)
		(layer "In2.Cu")
		(net "M_C_MA<4>")
	)
	(arc
		(start 255.70434 -53.314092)
		(mid 255.753764 -53.194625)
		(end 255.770634 -53.066442)
		(width 0.0889)
		(layer "In2.Cu")
		(net "M_C_MA<4>")
	)
	(arc
		(start 255.81864 -58.516266)
		(mid 255.818313 -58.375845)
		(end 255.785112 -58.239406)
		(width 0.0889)
		(layer "In2.Cu")
		(net "M_C_MA<4>")
	)
	(arc
		(start 255.70434 -57.867296)
		(mid 255.625209 -57.571894)
		(end 255.70434 -57.276492)
		(width 0.0889)
		(layer "In2.Cu")
		(net "M_C_MA<4>")
	)
	(arc
		(start 255.757426 -58.050684)
		(mid 255.742002 -57.955768)
		(end 255.70434 -57.867296)
		(width 0.0889)
		(layer "In2.Cu")
		(net "M_C_MA<4>")
	)
	(arc
		(start 255.70434 -57.276492)
		(mid 255.757839 -57.076594)
		(end 255.70434 -56.876696)
		(width 0.0889)
		(layer "In2.Cu")
		(net "M_C_MA<4>")
	)
	(arc
		(start 255.70434 -54.895496)
		(mid 255.625209 -54.600094)
		(end 255.70434 -54.304692)
		(width 0.0889)
		(layer "In2.Cu")
		(net "M_C_MA<4>")
	)
	(arc
		(start 255.70434 -55.295292)
		(mid 255.757839 -55.095394)
		(end 255.70434 -54.895496)
		(width 0.0889)
		(layer "In2.Cu")
		(net "M_C_MA<4>")
	)
	(segment
		(start 256.78765 -58.561986)
		(end 256.21615 -58.561986)
		(width 0.1016)
		(layer "F.Cu")
		(net "M_C_MA<3>")
	)
	(segment
		(start 254.199898 3.778758)
		(end 254.199898 2.514854)
		(width 0.1651)
		(layer "F.Cu")
		(net "M_C_MA<3>")
	)
	(segment
		(start 254.200406 3.778758)
		(end 254.199898 3.778758)
		(width 0.1651)
		(layer "F.Cu")
		(net "M_C_MA<3>")
	)
	(via
		(at 254.199898 -4.332478)
		(size 0.4572)
		(drill 0.2032)
		(layers "F.Cu" "B.Cu")
		(net "M_C_MA<3>")
	)
	(via
		(at 256.21615 -58.561986)
		(size 0.508)
		(drill 0.254)
		(layers "F.Cu" "B.Cu")
		(net "M_C_MA<3>")
	)
	(via
		(at 254.199898 2.514854)
		(size 0.508)
		(drill 0.254)
		(layers "F.Cu" "B.Cu")
		(net "M_C_MA<3>")
	)
	(segment
		(start 254.199898 -5.621782)
		(end 254.199898 -4.332478)
		(width 0.1651)
		(layer "B.Cu")
		(net "M_C_MA<3>")
	)
	(segment
		(start 254.200406 -5.621782)
		(end 254.199898 -5.621782)
		(width 0.1651)
		(layer "B.Cu")
		(net "M_C_MA<3>")
	)
	(segment
		(start 253.957328 -22.408896)
		(end 253.703328 -22.662896)
		(width 0.14224)
		(layer "In2.Cu")
		(net "M_C_MA<3>")
	)
	(segment
		(start 253.703328 -21.710396)
		(end 253.957328 -21.964396)
		(width 0.14224)
		(layer "In2.Cu")
		(net "M_C_MA<3>")
	)
	(segment
		(start 253.961646 -20.389342)
		(end 253.961646 -20.923504)
		(width 0.14224)
		(layer "In2.Cu")
		(net "M_C_MA<3>")
	)
	(segment
		(start 254.113792 -25.32761)
		(end 254.113792 -25.615138)
		(width 0.14224)
		(layer "In2.Cu")
		(net "M_C_MA<3>")
	)
	(segment
		(start 256.770124 -27.24531)
		(end 256.770124 -48.58385)
		(width 0.14224)
		(layer "In2.Cu")
		(net "M_C_MA<3>")
	)
	(segment
		(start 254.3302 -5.7912)
		(end 253.792228 -6.329172)
		(width 0.14224)
		(layer "In2.Cu")
		(net "M_C_MA<3>")
	)
	(segment
		(start 253.7841 -15.183104)
		(end 254.06477 -15.463774)
		(width 0.14224)
		(layer "In2.Cu")
		(net "M_C_MA<3>")
	)
	(segment
		(start 253.703328 -18.379186)
		(end 253.758954 -18.434812)
		(width 0.14224)
		(layer "In2.Cu")
		(net "M_C_MA<3>")
	)
	(segment
		(start 253.961646 -20.923504)
		(end 253.703328 -21.181822)
		(width 0.14224)
		(layer "In2.Cu")
		(net "M_C_MA<3>")
	)
	(segment
		(start 253.957328 -17.159986)
		(end 253.957328 -17.591786)
		(width 0.14224)
		(layer "In2.Cu")
		(net "M_C_MA<3>")
	)
	(segment
		(start 254.196088 2.51333)
		(end 254.199898 2.514854)
		(width 0.14224)
		(layer "In2.Cu")
		(net "M_C_MA<3>")
	)
	(segment
		(start 253.760986 1.462786)
		(end 254.196088 2.51333)
		(width 0.14224)
		(layer "In2.Cu")
		(net "M_C_MA<3>")
	)
	(segment
		(start 253.672086 -13.551154)
		(end 253.7841 -13.663168)
		(width 0.14224)
		(layer "In2.Cu")
		(net "M_C_MA<3>")
	)
	(segment
		(start 254.06477 -15.463774)
		(end 254.06477 -16.136112)
		(width 0.14224)
		(layer "In2.Cu")
		(net "M_C_MA<3>")
	)
	(segment
		(start 255.66497 -26.937716)
		(end 255.952498 -26.937716)
		(width 0.14224)
		(layer "In2.Cu")
		(net "M_C_MA<3>")
	)
	(segment
		(start 253.764288 -2.583942)
		(end 253.764288 -1.861312)
		(width 0.14224)
		(layer "In2.Cu")
		(net "M_C_MA<3>")
	)
	(segment
		(start 256.770124 -48.58385)
		(end 256.770124 -50.239168)
		(width 0.0889)
		(layer "In2.Cu")
		(net "M_C_MA<3>")
	)
	(segment
		(start 254 0.32512)
		(end 253.760986 0.902208)
		(width 0.14224)
		(layer "In2.Cu")
		(net "M_C_MA<3>")
	)
	(segment
		(start 253.76124 -11.598656)
		(end 253.76124 -12.167108)
		(width 0.14224)
		(layer "In2.Cu")
		(net "M_C_MA<3>")
	)
	(segment
		(start 253.7841 -13.663168)
		(end 253.7841 -15.183104)
		(width 0.14224)
		(layer "In2.Cu")
		(net "M_C_MA<3>")
	)
	(segment
		(start 255.86944 -57.771792)
		(end 255.88595 -57.80024)
		(width 0.0889)
		(layer "In2.Cu")
		(net "M_C_MA<3>")
	)
	(segment
		(start 254.339344 -24.81453)
		(end 254.339344 -25.102058)
		(width 0.14224)
		(layer "In2.Cu")
		(net "M_C_MA<3>")
	)
	(segment
		(start 253.703328 -19.268186)
		(end 253.703328 -20.131024)
		(width 0.14224)
		(layer "In2.Cu")
		(net "M_C_MA<3>")
	)
	(segment
		(start 253.957328 -17.591786)
		(end 253.703328 -17.845786)
		(width 0.14224)
		(layer "In2.Cu")
		(net "M_C_MA<3>")
	)
	(segment
		(start 253.764288 -1.861312)
		(end 254 -1.6256)
		(width 0.14224)
		(layer "In2.Cu")
		(net "M_C_MA<3>")
	)
	(segment
		(start 256.034794 -50.974498)
		(end 256.034794 -52.792376)
		(width 0.0889)
		(layer "In2.Cu")
		(net "M_C_MA<3>")
	)
	(segment
		(start 253.703328 -23.183596)
		(end 253.840996 -23.321264)
		(width 0.14224)
		(layer "In2.Cu")
		(net "M_C_MA<3>")
	)
	(segment
		(start 253.76124 -12.167108)
		(end 253.918974 -12.324842)
		(width 0.14224)
		(layer "In2.Cu")
		(net "M_C_MA<3>")
	)
	(segment
		(start 253.703328 -17.845786)
		(end 253.703328 -18.379186)
		(width 0.14224)
		(layer "In2.Cu")
		(net "M_C_MA<3>")
	)
	(segment
		(start 255.377696 -26.650442)
		(end 255.66497 -26.937716)
		(width 0.14224)
		(layer "In2.Cu")
		(net "M_C_MA<3>")
	)
	(segment
		(start 254.02667 -10.787126)
		(end 254.02667 -11.333226)
		(width 0.14224)
		(layer "In2.Cu")
		(net "M_C_MA<3>")
	)
	(segment
		(start 253.703328 -21.181822)
		(end 253.703328 -21.710396)
		(width 0.14224)
		(layer "In2.Cu")
		(net "M_C_MA<3>")
	)
	(segment
		(start 255.488948 -26.251662)
		(end 255.377696 -26.362914)
		(width 0.14224)
		(layer "In2.Cu")
		(net "M_C_MA<3>")
	)
	(segment
		(start 253.918974 -12.324842)
		(end 253.918974 -12.84605)
		(width 0.14224)
		(layer "In2.Cu")
		(net "M_C_MA<3>")
	)
	(segment
		(start 253.957328 -21.964396)
		(end 253.957328 -22.408896)
		(width 0.14224)
		(layer "In2.Cu")
		(net "M_C_MA<3>")
	)
	(segment
		(start 253.76124 -10.521696)
		(end 254.02667 -10.787126)
		(width 0.14224)
		(layer "In2.Cu")
		(net "M_C_MA<3>")
	)
	(segment
		(start 255.88595 -57.80024)
		(end 256.21615 -58.561986)
		(width 0.0889)
		(layer "In2.Cu")
		(net "M_C_MA<3>")
	)
	(segment
		(start 253.918974 -12.84605)
		(end 253.672086 -13.092938)
		(width 0.14224)
		(layer "In2.Cu")
		(net "M_C_MA<3>")
	)
	(segment
		(start 254.02667 -11.333226)
		(end 253.76124 -11.598656)
		(width 0.14224)
		(layer "In2.Cu")
		(net "M_C_MA<3>")
	)
	(segment
		(start 253.7841 -16.416782)
		(end 253.7841 -16.986758)
		(width 0.14224)
		(layer "In2.Cu")
		(net "M_C_MA<3>")
	)
	(segment
		(start 253.672086 -13.092938)
		(end 253.672086 -13.551154)
		(width 0.14224)
		(layer "In2.Cu")
		(net "M_C_MA<3>")
	)
	(segment
		(start 253.760986 0.902208)
		(end 253.760986 1.462786)
		(width 0.14224)
		(layer "In2.Cu")
		(net "M_C_MA<3>")
	)
	(segment
		(start 254 -1.6256)
		(end 254 0.32512)
		(width 0.14224)
		(layer "In2.Cu")
		(net "M_C_MA<3>")
	)
	(segment
		(start 254.3302 -4.46278)
		(end 254.3302 -5.7912)
		(width 0.14224)
		(layer "In2.Cu")
		(net "M_C_MA<3>")
	)
	(segment
		(start 254.339344 -25.102058)
		(end 254.113792 -25.32761)
		(width 0.14224)
		(layer "In2.Cu")
		(net "M_C_MA<3>")
	)
	(segment
		(start 253.97587 -8.66902)
		(end 253.76124 -8.88365)
		(width 0.14224)
		(layer "In2.Cu")
		(net "M_C_MA<3>")
	)
	(segment
		(start 255.488948 -25.964134)
		(end 255.488948 -26.251662)
		(width 0.14224)
		(layer "In2.Cu")
		(net "M_C_MA<3>")
	)
	(segment
		(start 255.377696 -26.362914)
		(end 255.377696 -26.650442)
		(width 0.14224)
		(layer "In2.Cu")
		(net "M_C_MA<3>")
	)
	(segment
		(start 254.401066 -25.902412)
		(end 254.688594 -25.902412)
		(width 0.14224)
		(layer "In2.Cu")
		(net "M_C_MA<3>")
	)
	(segment
		(start 253.758954 -18.434812)
		(end 253.758954 -19.21256)
		(width 0.14224)
		(layer "In2.Cu")
		(net "M_C_MA<3>")
	)
	(segment
		(start 253.792228 -6.329172)
		(end 253.792228 -7.637018)
		(width 0.14224)
		(layer "In2.Cu")
		(net "M_C_MA<3>")
	)
	(segment
		(start 256.06375 -26.826464)
		(end 256.351278 -26.826464)
		(width 0.14224)
		(layer "In2.Cu")
		(net "M_C_MA<3>")
	)
	(segment
		(start 254.688594 -25.902412)
		(end 254.914146 -25.67686)
		(width 0.14224)
		(layer "In2.Cu")
		(net "M_C_MA<3>")
	)
	(segment
		(start 253.792228 -7.637018)
		(end 253.97587 -7.82066)
		(width 0.14224)
		(layer "In2.Cu")
		(net "M_C_MA<3>")
	)
	(segment
		(start 253.97587 -7.82066)
		(end 253.97587 -8.66902)
		(width 0.14224)
		(layer "In2.Cu")
		(net "M_C_MA<3>")
	)
	(segment
		(start 255.952498 -26.937716)
		(end 256.06375 -26.826464)
		(width 0.14224)
		(layer "In2.Cu")
		(net "M_C_MA<3>")
	)
	(segment
		(start 254.113792 -25.615138)
		(end 254.401066 -25.902412)
		(width 0.14224)
		(layer "In2.Cu")
		(net "M_C_MA<3>")
	)
	(segment
		(start 255.201674 -25.67686)
		(end 255.488948 -25.964134)
		(width 0.14224)
		(layer "In2.Cu")
		(net "M_C_MA<3>")
	)
	(segment
		(start 254.199898 -4.332478)
		(end 254.3302 -4.46278)
		(width 0.14224)
		(layer "In2.Cu")
		(net "M_C_MA<3>")
	)
	(segment
		(start 253.703328 -22.662896)
		(end 253.703328 -23.183596)
		(width 0.14224)
		(layer "In2.Cu")
		(net "M_C_MA<3>")
	)
	(segment
		(start 253.758954 -19.21256)
		(end 253.703328 -19.268186)
		(width 0.14224)
		(layer "In2.Cu")
		(net "M_C_MA<3>")
	)
	(segment
		(start 253.840996 -23.321264)
		(end 253.840996 -24.316182)
		(width 0.14224)
		(layer "In2.Cu")
		(net "M_C_MA<3>")
	)
	(segment
		(start 254.199898 -3.019552)
		(end 253.764288 -2.583942)
		(width 0.14224)
		(layer "In2.Cu")
		(net "M_C_MA<3>")
	)
	(segment
		(start 253.76124 -8.88365)
		(end 253.76124 -10.521696)
		(width 0.14224)
		(layer "In2.Cu")
		(net "M_C_MA<3>")
	)
	(segment
		(start 253.7841 -16.986758)
		(end 253.957328 -17.159986)
		(width 0.14224)
		(layer "In2.Cu")
		(net "M_C_MA<3>")
	)
	(segment
		(start 253.840996 -24.316182)
		(end 254.339344 -24.81453)
		(width 0.14224)
		(layer "In2.Cu")
		(net "M_C_MA<3>")
	)
	(segment
		(start 253.703328 -20.131024)
		(end 253.961646 -20.389342)
		(width 0.14224)
		(layer "In2.Cu")
		(net "M_C_MA<3>")
	)
	(segment
		(start 254.914146 -25.67686)
		(end 255.201674 -25.67686)
		(width 0.14224)
		(layer "In2.Cu")
		(net "M_C_MA<3>")
	)
	(segment
		(start 254.06477 -16.136112)
		(end 253.7841 -16.416782)
		(width 0.14224)
		(layer "In2.Cu")
		(net "M_C_MA<3>")
	)
	(segment
		(start 256.770124 -50.239168)
		(end 256.034794 -50.974498)
		(width 0.0889)
		(layer "In2.Cu")
		(net "M_C_MA<3>")
	)
	(segment
		(start 254.199898 -4.332478)
		(end 254.199898 -3.019552)
		(width 0.14224)
		(layer "In2.Cu")
		(net "M_C_MA<3>")
	)
	(segment
		(start 256.351278 -26.826464)
		(end 256.770124 -27.24531)
		(width 0.14224)
		(layer "In2.Cu")
		(net "M_C_MA<3>")
	)
	(arc
		(start 255.86944 -54.400196)
		(mid 255.815941 -54.600094)
		(end 255.86944 -54.799992)
		(width 0.0889)
		(layer "In2.Cu")
		(net "M_C_MA<3>")
	)
	(arc
		(start 255.86944 -55.390796)
		(mid 255.815941 -55.590694)
		(end 255.86944 -55.790592)
		(width 0.0889)
		(layer "In2.Cu")
		(net "M_C_MA<3>")
	)
	(arc
		(start 255.86944 -56.781192)
		(mid 255.948571 -57.076594)
		(end 255.86944 -57.371996)
		(width 0.0889)
		(layer "In2.Cu")
		(net "M_C_MA<3>")
	)
	(arc
		(start 255.86944 -55.790592)
		(mid 255.948571 -56.085994)
		(end 255.86944 -56.381396)
		(width 0.0889)
		(layer "In2.Cu")
		(net "M_C_MA<3>")
	)
	(arc
		(start 255.86944 -54.799992)
		(mid 255.948571 -55.095394)
		(end 255.86944 -55.390796)
		(width 0.0889)
		(layer "In2.Cu")
		(net "M_C_MA<3>")
	)
	(arc
		(start 255.86944 -57.371996)
		(mid 255.815941 -57.571894)
		(end 255.86944 -57.771792)
		(width 0.0889)
		(layer "In2.Cu")
		(net "M_C_MA<3>")
	)
	(arc
		(start 256.034794 -52.792376)
		(mid 255.992749 -53.111874)
		(end 255.86944 -53.409596)
		(width 0.0889)
		(layer "In2.Cu")
		(net "M_C_MA<3>")
	)
	(arc
		(start 255.86944 -53.409596)
		(mid 255.815941 -53.609494)
		(end 255.86944 -53.809392)
		(width 0.0889)
		(layer "In2.Cu")
		(net "M_C_MA<3>")
	)
	(arc
		(start 255.86944 -56.381396)
		(mid 255.815941 -56.581294)
		(end 255.86944 -56.781192)
		(width 0.0889)
		(layer "In2.Cu")
		(net "M_C_MA<3>")
	)
	(arc
		(start 255.86944 -53.809392)
		(mid 255.948503 -54.104794)
		(end 255.86944 -54.400196)
		(width 0.0889)
		(layer "In2.Cu")
		(net "M_C_MA<3>")
	)
	(segment
		(start 257.64617 -61.038486)
		(end 257.07467 -61.038486)
		(width 0.1016)
		(layer "F.Cu")
		(net "M_C_MA<2>")
	)
	(segment
		(start 255.049782 -0.821182)
		(end 255.049782 0.442468)
		(width 0.1651)
		(layer "F.Cu")
		(net "M_C_MA<2>")
	)
	(segment
		(start 255.05029 -0.821182)
		(end 255.049782 -0.821182)
		(width 0.1651)
		(layer "F.Cu")
		(net "M_C_MA<2>")
	)
	(via
		(at 257.07467 -61.038486)
		(size 0.508)
		(drill 0.254)
		(layers "F.Cu" "B.Cu")
		(net "M_C_MA<2>")
	)
	(via
		(at 255.049782 0.442468)
		(size 0.508)
		(drill 0.254)
		(layers "F.Cu" "B.Cu")
		(net "M_C_MA<2>")
	)
	(via
		(at 255.049782 -2.316988)
		(size 0.4572)
		(drill 0.2032)
		(layers "F.Cu" "B.Cu")
		(net "M_C_MA<2>")
	)
	(segment
		(start 255.049782 -1.021842)
		(end 255.049782 -2.316988)
		(width 0.1651)
		(layer "B.Cu")
		(net "M_C_MA<2>")
	)
	(segment
		(start 255.05029 -1.021842)
		(end 255.049782 -1.021842)
		(width 0.1651)
		(layer "B.Cu")
		(net "M_C_MA<2>")
	)
	(segment
		(start 255.088898 0.403352)
		(end 255.049782 0.442468)
		(width 0.14224)
		(layer "In2.Cu")
		(net "M_C_MA<2>")
	)
	(segment
		(start 255.46685 -11.56335)
		(end 255.5748 -11.4554)
		(width 0.14224)
		(layer "In2.Cu")
		(net "M_C_MA<2>")
	)
	(segment
		(start 255.2446 -8.6868)
		(end 255.2446 -7.5184)
		(width 0.14224)
		(layer "In2.Cu")
		(net "M_C_MA<2>")
	)
	(segment
		(start 256.672334 -53.10632)
		(end 256.672334 -51.434746)
		(width 0.0889)
		(layer "In2.Cu")
		(net "M_C_MA<2>")
	)
	(segment
		(start 256.672334 -51.434746)
		(end 257.786124 -50.320956)
		(width 0.0889)
		(layer "In2.Cu")
		(net "M_C_MA<2>")
	)
	(segment
		(start 257.786124 -49.86655)
		(end 257.786124 -26.824178)
		(width 0.14224)
		(layer "In2.Cu")
		(net "M_C_MA<2>")
	)
	(segment
		(start 255.049782 -2.316988)
		(end 255.088898 -2.277872)
		(width 0.14224)
		(layer "In2.Cu")
		(net "M_C_MA<2>")
	)
	(segment
		(start 255.463294 -13.748766)
		(end 255.405128 -13.6906)
		(width 0.14224)
		(layer "In2.Cu")
		(net "M_C_MA<2>")
	)
	(segment
		(start 255.143 -3.784854)
		(end 255.143 -2.410206)
		(width 0.14224)
		(layer "In2.Cu")
		(net "M_C_MA<2>")
	)
	(segment
		(start 255.476756 -18.56359)
		(end 255.338072 -18.424906)
		(width 0.14224)
		(layer "In2.Cu")
		(net "M_C_MA<2>")
	)
	(segment
		(start 256.74447 -60.27674)
		(end 256.72796 -60.248292)
		(width 0.0889)
		(layer "In2.Cu")
		(net "M_C_MA<2>")
	)
	(segment
		(start 255.46685 -12.200128)
		(end 255.46685 -11.56335)
		(width 0.14224)
		(layer "In2.Cu")
		(net "M_C_MA<2>")
	)
	(segment
		(start 255.5748 -9.017)
		(end 255.2446 -8.6868)
		(width 0.14224)
		(layer "In2.Cu")
		(net "M_C_MA<2>")
	)
	(segment
		(start 255.338072 -18.424906)
		(end 255.338072 -17.049242)
		(width 0.14224)
		(layer "In2.Cu")
		(net "M_C_MA<2>")
	)
	(segment
		(start 255.405128 -21.761196)
		(end 255.405128 -19.141186)
		(width 0.14224)
		(layer "In2.Cu")
		(net "M_C_MA<2>")
	)
	(segment
		(start 255.463294 -16.92402)
		(end 255.463294 -13.748766)
		(width 0.14224)
		(layer "In2.Cu")
		(net "M_C_MA<2>")
	)
	(segment
		(start 255.458976 -4.10083)
		(end 255.143 -3.784854)
		(width 0.14224)
		(layer "In2.Cu")
		(net "M_C_MA<2>")
	)
	(segment
		(start 257.786124 -26.824178)
		(end 255.454912 -24.492966)
		(width 0.14224)
		(layer "In2.Cu")
		(net "M_C_MA<2>")
	)
	(segment
		(start 257.07467 -61.038486)
		(end 256.74447 -60.27674)
		(width 0.0889)
		(layer "In2.Cu")
		(net "M_C_MA<2>")
	)
	(segment
		(start 255.454912 -24.492966)
		(end 255.454912 -21.81098)
		(width 0.14224)
		(layer "In2.Cu")
		(net "M_C_MA<2>")
	)
	(segment
		(start 255.2446 -7.5184)
		(end 255.458976 -7.304024)
		(width 0.14224)
		(layer "In2.Cu")
		(net "M_C_MA<2>")
	)
	(segment
		(start 255.458976 -7.304024)
		(end 255.458976 -4.10083)
		(width 0.14224)
		(layer "In2.Cu")
		(net "M_C_MA<2>")
	)
	(segment
		(start 255.143 -2.410206)
		(end 255.049782 -2.316988)
		(width 0.14224)
		(layer "In2.Cu")
		(net "M_C_MA<2>")
	)
	(segment
		(start 257.786124 -50.320956)
		(end 257.786124 -49.86655)
		(width 0.0889)
		(layer "In2.Cu")
		(net "M_C_MA<2>")
	)
	(segment
		(start 255.454912 -21.81098)
		(end 255.405128 -21.761196)
		(width 0.14224)
		(layer "In2.Cu")
		(net "M_C_MA<2>")
	)
	(segment
		(start 255.338072 -17.049242)
		(end 255.463294 -16.92402)
		(width 0.14224)
		(layer "In2.Cu")
		(net "M_C_MA<2>")
	)
	(segment
		(start 255.5748 -11.4554)
		(end 255.5748 -9.017)
		(width 0.14224)
		(layer "In2.Cu")
		(net "M_C_MA<2>")
	)
	(segment
		(start 255.088898 -2.277872)
		(end 255.088898 0.403352)
		(width 0.14224)
		(layer "In2.Cu")
		(net "M_C_MA<2>")
	)
	(segment
		(start 255.405128 -12.26185)
		(end 255.46685 -12.200128)
		(width 0.14224)
		(layer "In2.Cu")
		(net "M_C_MA<2>")
	)
	(segment
		(start 255.405128 -13.6906)
		(end 255.405128 -12.26185)
		(width 0.14224)
		(layer "In2.Cu")
		(net "M_C_MA<2>")
	)
	(segment
		(start 255.476756 -19.069558)
		(end 255.476756 -18.56359)
		(width 0.14224)
		(layer "In2.Cu")
		(net "M_C_MA<2>")
	)
	(segment
		(start 255.405128 -19.141186)
		(end 255.476756 -19.069558)
		(width 0.14224)
		(layer "In2.Cu")
		(net "M_C_MA<2>")
	)
	(arc
		(start 256.72796 -57.867296)
		(mid 256.807091 -57.571894)
		(end 256.72796 -57.276492)
		(width 0.0889)
		(layer "In2.Cu")
		(net "M_C_MA<2>")
	)
	(arc
		(start 256.72796 -59.257692)
		(mid 256.674461 -59.057794)
		(end 256.72796 -58.857896)
		(width 0.0889)
		(layer "In2.Cu")
		(net "M_C_MA<2>")
	)
	(arc
		(start 256.72796 -56.285892)
		(mid 256.674461 -56.085994)
		(end 256.72796 -55.886096)
		(width 0.0889)
		(layer "In2.Cu")
		(net "M_C_MA<2>")
	)
	(arc
		(start 256.72796 -60.248292)
		(mid 256.674461 -60.048394)
		(end 256.72796 -59.848496)
		(width 0.0889)
		(layer "In2.Cu")
		(net "M_C_MA<2>")
	)
	(arc
		(start 256.72796 -54.895496)
		(mid 256.807091 -54.600094)
		(end 256.72796 -54.304692)
		(width 0.0889)
		(layer "In2.Cu")
		(net "M_C_MA<2>")
	)
	(arc
		(start 256.72796 -59.848496)
		(mid 256.807091 -59.553094)
		(end 256.72796 -59.257692)
		(width 0.0889)
		(layer "In2.Cu")
		(net "M_C_MA<2>")
	)
	(arc
		(start 256.72796 -54.304692)
		(mid 256.674461 -54.104794)
		(end 256.72796 -53.904896)
		(width 0.0889)
		(layer "In2.Cu")
		(net "M_C_MA<2>")
	)
	(arc
		(start 256.72796 -53.314092)
		(mid 256.686502 -53.213861)
		(end 256.672334 -53.10632)
		(width 0.0889)
		(layer "In2.Cu")
		(net "M_C_MA<2>")
	)
	(arc
		(start 256.72796 -57.276492)
		(mid 256.674461 -57.076594)
		(end 256.72796 -56.876696)
		(width 0.0889)
		(layer "In2.Cu")
		(net "M_C_MA<2>")
	)
	(arc
		(start 256.72796 -55.295292)
		(mid 256.674461 -55.095394)
		(end 256.72796 -54.895496)
		(width 0.0889)
		(layer "In2.Cu")
		(net "M_C_MA<2>")
	)
	(arc
		(start 256.72796 -58.267092)
		(mid 256.674461 -58.067194)
		(end 256.72796 -57.867296)
		(width 0.0889)
		(layer "In2.Cu")
		(net "M_C_MA<2>")
	)
	(arc
		(start 256.72796 -55.886096)
		(mid 256.807091 -55.590694)
		(end 256.72796 -55.295292)
		(width 0.0889)
		(layer "In2.Cu")
		(net "M_C_MA<2>")
	)
	(arc
		(start 256.72796 -58.857896)
		(mid 256.807091 -58.562494)
		(end 256.72796 -58.267092)
		(width 0.0889)
		(layer "In2.Cu")
		(net "M_C_MA<2>")
	)
	(arc
		(start 256.72796 -56.876696)
		(mid 256.807091 -56.581294)
		(end 256.72796 -56.285892)
		(width 0.0889)
		(layer "In2.Cu")
		(net "M_C_MA<2>")
	)
	(arc
		(start 256.72796 -53.904896)
		(mid 256.807091 -53.609494)
		(end 256.72796 -53.314092)
		(width 0.0889)
		(layer "In2.Cu")
		(net "M_C_MA<2>")
	)
	(segment
		(start 256.78765 -61.53404)
		(end 256.21615 -61.53404)
		(width 0.1016)
		(layer "F.Cu")
		(net "M_C_MA<1>")
	)
	(segment
		(start 255.050036 3.778504)
		(end 255.05029 3.778758)
		(width 0.1651)
		(layer "F.Cu")
		(net "M_C_MA<1>")
	)
	(segment
		(start 255.050036 1.805432)
		(end 255.050036 3.778504)
		(width 0.1651)
		(layer "F.Cu")
		(net "M_C_MA<1>")
	)
	(via
		(at 255.050036 1.805432)
		(size 0.508)
		(drill 0.254)
		(layers "F.Cu" "B.Cu")
		(net "M_C_MA<1>")
	)
	(via
		(at 255.050036 -4.332478)
		(size 0.4572)
		(drill 0.2032)
		(layers "F.Cu" "B.Cu")
		(net "M_C_MA<1>")
	)
	(via
		(at 256.21615 -61.53404)
		(size 0.508)
		(drill 0.254)
		(layers "F.Cu" "B.Cu")
		(net "M_C_MA<1>")
	)
	(segment
		(start 255.049782 -5.621782)
		(end 255.049782 -4.358132)
		(width 0.1651)
		(layer "B.Cu")
		(net "M_C_MA<1>")
	)
	(segment
		(start 255.049782 -4.358132)
		(end 255.050036 -4.357878)
		(width 0.1651)
		(layer "B.Cu")
		(net "M_C_MA<1>")
	)
	(segment
		(start 255.05029 -5.621782)
		(end 255.049782 -5.621782)
		(width 0.1651)
		(layer "B.Cu")
		(net "M_C_MA<1>")
	)
	(segment
		(start 255.050036 -4.357878)
		(end 255.050036 -4.332478)
		(width 0.1651)
		(layer "B.Cu")
		(net "M_C_MA<1>")
	)
	(segment
		(start 254.639826 -17.715484)
		(end 254.61722 -17.692878)
		(width 0.14224)
		(layer "In2.Cu")
		(net "M_C_MA<1>")
	)
	(segment
		(start 254.559054 -23.31847)
		(end 254.744728 -23.132796)
		(width 0.14224)
		(layer "In2.Cu")
		(net "M_C_MA<1>")
	)
	(segment
		(start 254.61722 -12.287504)
		(end 254.635 -12.269724)
		(width 0.14224)
		(layer "In2.Cu")
		(net "M_C_MA<1>")
	)
	(segment
		(start 254.744728 -23.132796)
		(end 254.744728 -22.599396)
		(width 0.14224)
		(layer "In2.Cu")
		(net "M_C_MA<1>")
	)
	(segment
		(start 254.744728 -22.599396)
		(end 254.566928 -22.421596)
		(width 0.14224)
		(layer "In2.Cu")
		(net "M_C_MA<1>")
	)
	(segment
		(start 255.050036 1.805432)
		(end 255.050036 1.202436)
		(width 0.14224)
		(layer "In2.Cu")
		(net "M_C_MA<1>")
	)
	(segment
		(start 255.050036 1.202436)
		(end 254.5842 0.7366)
		(width 0.14224)
		(layer "In2.Cu")
		(net "M_C_MA<1>")
	)
	(segment
		(start 257.278124 -49.87925)
		(end 257.278124 -27.034744)
		(width 0.14224)
		(layer "In2.Cu")
		(net "M_C_MA<1>")
	)
	(segment
		(start 256.21615 -61.53404)
		(end 256.54635 -60.77204)
		(width 0.0889)
		(layer "In2.Cu")
		(net "M_C_MA<1>")
	)
	(segment
		(start 254.5842 -0.8128)
		(end 254.642112 -0.870712)
		(width 0.14224)
		(layer "In2.Cu")
		(net "M_C_MA<1>")
	)
	(segment
		(start 255.050036 -6.392164)
		(end 255.050036 -4.332478)
		(width 0.14224)
		(layer "In2.Cu")
		(net "M_C_MA<1>")
	)
	(segment
		(start 254.559054 -24.315674)
		(end 254.559054 -23.31847)
		(width 0.14224)
		(layer "In2.Cu")
		(net "M_C_MA<1>")
	)
	(segment
		(start 256.394204 -51.221894)
		(end 257.278124 -50.337974)
		(width 0.0889)
		(layer "In2.Cu")
		(net "M_C_MA<1>")
	)
	(segment
		(start 254.635 -6.8072)
		(end 255.050036 -6.392164)
		(width 0.14224)
		(layer "In2.Cu")
		(net "M_C_MA<1>")
	)
	(segment
		(start 254.566928 -21.938996)
		(end 254.639826 -21.866098)
		(width 0.14224)
		(layer "In2.Cu")
		(net "M_C_MA<1>")
	)
	(segment
		(start 254.642112 -3.924554)
		(end 255.050036 -4.332478)
		(width 0.14224)
		(layer "In2.Cu")
		(net "M_C_MA<1>")
	)
	(segment
		(start 254.5842 0.7366)
		(end 254.5842 -0.8128)
		(width 0.14224)
		(layer "In2.Cu")
		(net "M_C_MA<1>")
	)
	(segment
		(start 254.61722 -17.692878)
		(end 254.61722 -12.287504)
		(width 0.14224)
		(layer "In2.Cu")
		(net "M_C_MA<1>")
	)
	(segment
		(start 256.394204 -52.77993)
		(end 256.394204 -51.221894)
		(width 0.0889)
		(layer "In2.Cu")
		(net "M_C_MA<1>")
	)
	(segment
		(start 257.278124 -27.034744)
		(end 254.559054 -24.315674)
		(width 0.14224)
		(layer "In2.Cu")
		(net "M_C_MA<1>")
	)
	(segment
		(start 256.54635 -60.77204)
		(end 256.56286 -60.743592)
		(width 0.0889)
		(layer "In2.Cu")
		(net "M_C_MA<1>")
	)
	(segment
		(start 254.635 -12.269724)
		(end 254.635 -6.8072)
		(width 0.14224)
		(layer "In2.Cu")
		(net "M_C_MA<1>")
	)
	(segment
		(start 254.566928 -22.421596)
		(end 254.566928 -21.938996)
		(width 0.14224)
		(layer "In2.Cu")
		(net "M_C_MA<1>")
	)
	(segment
		(start 257.278124 -50.337974)
		(end 257.278124 -49.87925)
		(width 0.0889)
		(layer "In2.Cu")
		(net "M_C_MA<1>")
	)
	(segment
		(start 254.642112 -0.870712)
		(end 254.642112 -3.924554)
		(width 0.14224)
		(layer "In2.Cu")
		(net "M_C_MA<1>")
	)
	(segment
		(start 254.639826 -21.866098)
		(end 254.639826 -17.715484)
		(width 0.14224)
		(layer "In2.Cu")
		(net "M_C_MA<1>")
	)
	(arc
		(start 256.56286 -56.381396)
		(mid 256.483729 -56.085994)
		(end 256.56286 -55.790592)
		(width 0.0889)
		(layer "In2.Cu")
		(net "M_C_MA<1>")
	)
	(arc
		(start 256.56286 -53.809392)
		(mid 256.616359 -53.609494)
		(end 256.56286 -53.409596)
		(width 0.0889)
		(layer "In2.Cu")
		(net "M_C_MA<1>")
	)
	(arc
		(start 256.56286 -58.362596)
		(mid 256.483729 -58.067194)
		(end 256.56286 -57.771792)
		(width 0.0889)
		(layer "In2.Cu")
		(net "M_C_MA<1>")
	)
	(arc
		(start 256.56286 -59.353196)
		(mid 256.483729 -59.057794)
		(end 256.56286 -58.762392)
		(width 0.0889)
		(layer "In2.Cu")
		(net "M_C_MA<1>")
	)
	(arc
		(start 256.56286 -57.371996)
		(mid 256.483729 -57.076594)
		(end 256.56286 -56.781192)
		(width 0.0889)
		(layer "In2.Cu")
		(net "M_C_MA<1>")
	)
	(arc
		(start 256.56286 -53.409596)
		(mid 256.437083 -53.105864)
		(end 256.394204 -52.77993)
		(width 0.0889)
		(layer "In2.Cu")
		(net "M_C_MA<1>")
	)
	(arc
		(start 256.56286 -54.400196)
		(mid 256.483729 -54.104794)
		(end 256.56286 -53.809392)
		(width 0.0889)
		(layer "In2.Cu")
		(net "M_C_MA<1>")
	)
	(arc
		(start 256.56286 -60.743592)
		(mid 256.616359 -60.543694)
		(end 256.56286 -60.343796)
		(width 0.0889)
		(layer "In2.Cu")
		(net "M_C_MA<1>")
	)
	(arc
		(start 256.56286 -59.752992)
		(mid 256.616359 -59.553094)
		(end 256.56286 -59.353196)
		(width 0.0889)
		(layer "In2.Cu")
		(net "M_C_MA<1>")
	)
	(arc
		(start 256.56286 -56.781192)
		(mid 256.616359 -56.581294)
		(end 256.56286 -56.381396)
		(width 0.0889)
		(layer "In2.Cu")
		(net "M_C_MA<1>")
	)
	(arc
		(start 256.56286 -54.799992)
		(mid 256.616359 -54.600094)
		(end 256.56286 -54.400196)
		(width 0.0889)
		(layer "In2.Cu")
		(net "M_C_MA<1>")
	)
	(arc
		(start 256.56286 -57.771792)
		(mid 256.616359 -57.571894)
		(end 256.56286 -57.371996)
		(width 0.0889)
		(layer "In2.Cu")
		(net "M_C_MA<1>")
	)
	(arc
		(start 256.56286 -60.343796)
		(mid 256.483729 -60.048394)
		(end 256.56286 -59.752992)
		(width 0.0889)
		(layer "In2.Cu")
		(net "M_C_MA<1>")
	)
	(arc
		(start 256.56286 -58.762392)
		(mid 256.616359 -58.562494)
		(end 256.56286 -58.362596)
		(width 0.0889)
		(layer "In2.Cu")
		(net "M_C_MA<1>")
	)
	(arc
		(start 256.56286 -55.390796)
		(mid 256.483729 -55.095394)
		(end 256.56286 -54.799992)
		(width 0.0889)
		(layer "In2.Cu")
		(net "M_C_MA<1>")
	)
	(arc
		(start 256.56286 -55.790592)
		(mid 256.616359 -55.590694)
		(end 256.56286 -55.390796)
		(width 0.0889)
		(layer "In2.Cu")
		(net "M_C_MA<1>")
	)
	(segment
		(start 275.449792 -0.821182)
		(end 275.449792 0.442722)
		(width 0.1651)
		(layer "F.Cu")
		(net "M_C_MA<17>")
	)
	(segment
		(start 267.089636 -60.54344)
		(end 266.518136 -60.54344)
		(width 0.1016)
		(layer "F.Cu")
		(net "M_C_MA<17>")
	)
	(segment
		(start 275.4503 -0.821182)
		(end 275.449792 -0.821182)
		(width 0.1651)
		(layer "F.Cu")
		(net "M_C_MA<17>")
	)
	(via
		(at 275.4503 -2.316988)
		(size 0.4572)
		(drill 0.2032)
		(layers "F.Cu" "B.Cu")
		(net "M_C_MA<17>")
	)
	(via
		(at 275.449792 0.442722)
		(size 0.508)
		(drill 0.254)
		(layers "F.Cu" "B.Cu")
		(net "M_C_MA<17>")
	)
	(via
		(at 266.518136 -60.54344)
		(size 0.508)
		(drill 0.254)
		(layers "F.Cu" "B.Cu")
		(net "M_C_MA<17>")
	)
	(segment
		(start 275.4503 -1.021842)
		(end 275.449792 -1.021842)
		(width 0.1651)
		(layer "B.Cu")
		(net "M_C_MA<17>")
	)
	(segment
		(start 275.449792 -1.021842)
		(end 275.449792 -2.31648)
		(width 0.1651)
		(layer "B.Cu")
		(net "M_C_MA<17>")
	)
	(segment
		(start 275.449792 -2.31648)
		(end 275.4503 -2.316988)
		(width 0.1651)
		(layer "B.Cu")
		(net "M_C_MA<17>")
	)
	(segment
		(start 277.59152 -18.95348)
		(end 277.5204 -19.0246)
		(width 0.14224)
		(layer "In11.Cu")
		(net "M_C_MA<17>")
	)
	(segment
		(start 269.497048 -35.896296)
		(end 269.497048 -49.337722)
		(width 0.14224)
		(layer "In11.Cu")
		(net "M_C_MA<17>")
	)
	(segment
		(start 277.5204 -22.606)
		(end 277.5204 -23.114)
		(width 0.14224)
		(layer "In11.Cu")
		(net "M_C_MA<17>")
	)
	(segment
		(start 277.4442 -15.533624)
		(end 277.59152 -15.680944)
		(width 0.14224)
		(layer "In11.Cu")
		(net "M_C_MA<17>")
	)
	(segment
		(start 277.4442 -14.351)
		(end 277.4442 -15.533624)
		(width 0.14224)
		(layer "In11.Cu")
		(net "M_C_MA<17>")
	)
	(segment
		(start 274.719034 -1.427226)
		(end 275.294852 -1.427226)
		(width 0.14224)
		(layer "In11.Cu")
		(net "M_C_MA<17>")
	)
	(segment
		(start 277.4188 -9.6012)
		(end 277.4188 -10.957052)
		(width 0.14224)
		(layer "In11.Cu")
		(net "M_C_MA<17>")
	)
	(segment
		(start 275.885656 -3.215132)
		(end 275.885656 -7.395464)
		(width 0.14224)
		(layer "In11.Cu")
		(net "M_C_MA<17>")
	)
	(segment
		(start 277.5204 -19.0246)
		(end 277.5204 -21.8948)
		(width 0.14224)
		(layer "In11.Cu")
		(net "M_C_MA<17>")
	)
	(segment
		(start 275.449792 -1.582166)
		(end 275.449792 -2.31648)
		(width 0.14224)
		(layer "In11.Cu")
		(net "M_C_MA<17>")
	)
	(segment
		(start 277.5204 -23.114)
		(end 277.622 -23.2156)
		(width 0.14224)
		(layer "In11.Cu")
		(net "M_C_MA<17>")
	)
	(segment
		(start 277.59152 -15.680944)
		(end 277.59152 -18.95348)
		(width 0.14224)
		(layer "In11.Cu")
		(net "M_C_MA<17>")
	)
	(segment
		(start 277.4188 -10.957052)
		(end 277.584154 -11.122406)
		(width 0.14224)
		(layer "In11.Cu")
		(net "M_C_MA<17>")
	)
	(segment
		(start 277.622 -23.2156)
		(end 277.622 -23.7236)
		(width 0.14224)
		(layer "In11.Cu")
		(net "M_C_MA<17>")
	)
	(segment
		(start 274.564094 -0.789686)
		(end 274.564094 -1.272286)
		(width 0.14224)
		(layer "In11.Cu")
		(net "M_C_MA<17>")
	)
	(segment
		(start 268.421104 -51.795934)
		(end 267.278866 -52.938172)
		(width 0.14224)
		(layer "In11.Cu")
		(net "M_C_MA<17>")
	)
	(segment
		(start 277.58644 -9.43356)
		(end 277.4188 -9.6012)
		(width 0.14224)
		(layer "In11.Cu")
		(net "M_C_MA<17>")
	)
	(segment
		(start 275.449792 -2.779268)
		(end 275.885656 -3.215132)
		(width 0.14224)
		(layer "In11.Cu")
		(net "M_C_MA<17>")
	)
	(segment
		(start 275.449792 0.442722)
		(end 275.449792 -0.479806)
		(width 0.14224)
		(layer "In11.Cu")
		(net "M_C_MA<17>")
	)
	(segment
		(start 267.278866 -52.938172)
		(end 267.278866 -59.78271)
		(width 0.14224)
		(layer "In11.Cu")
		(net "M_C_MA<17>")
	)
	(segment
		(start 274.719034 -0.634746)
		(end 274.564094 -0.789686)
		(width 0.14224)
		(layer "In11.Cu")
		(net "M_C_MA<17>")
	)
	(segment
		(start 276.652482 -7.989062)
		(end 277.58644 -8.92302)
		(width 0.14224)
		(layer "In11.Cu")
		(net "M_C_MA<17>")
	)
	(segment
		(start 277.58644 -8.92302)
		(end 277.58644 -9.43356)
		(width 0.14224)
		(layer "In11.Cu")
		(net "M_C_MA<17>")
	)
	(segment
		(start 267.278866 -59.78271)
		(end 266.518136 -60.54344)
		(width 0.14224)
		(layer "In11.Cu")
		(net "M_C_MA<17>")
	)
	(segment
		(start 275.449792 -2.317496)
		(end 275.449792 -2.779268)
		(width 0.14224)
		(layer "In11.Cu")
		(net "M_C_MA<17>")
	)
	(segment
		(start 277.622 -22.5044)
		(end 277.5204 -22.606)
		(width 0.14224)
		(layer "In11.Cu")
		(net "M_C_MA<17>")
	)
	(segment
		(start 275.294852 -0.634746)
		(end 274.719034 -0.634746)
		(width 0.14224)
		(layer "In11.Cu")
		(net "M_C_MA<17>")
	)
	(segment
		(start 274.564094 -1.272286)
		(end 274.719034 -1.427226)
		(width 0.14224)
		(layer "In11.Cu")
		(net "M_C_MA<17>")
	)
	(segment
		(start 275.294852 -1.427226)
		(end 275.449792 -1.582166)
		(width 0.14224)
		(layer "In11.Cu")
		(net "M_C_MA<17>")
	)
	(segment
		(start 277.584154 -11.122406)
		(end 277.584154 -14.211046)
		(width 0.14224)
		(layer "In11.Cu")
		(net "M_C_MA<17>")
	)
	(segment
		(start 275.4503 -2.316988)
		(end 275.449792 -2.317496)
		(width 0.14224)
		(layer "In11.Cu")
		(net "M_C_MA<17>")
	)
	(segment
		(start 275.885656 -7.395464)
		(end 276.479254 -7.989062)
		(width 0.14224)
		(layer "In11.Cu")
		(net "M_C_MA<17>")
	)
	(segment
		(start 276.479254 -7.989062)
		(end 276.652482 -7.989062)
		(width 0.14224)
		(layer "In11.Cu")
		(net "M_C_MA<17>")
	)
	(segment
		(start 277.5712 -23.7744)
		(end 277.5712 -27.822144)
		(width 0.14224)
		(layer "In11.Cu")
		(net "M_C_MA<17>")
	)
	(segment
		(start 277.584154 -14.211046)
		(end 277.4442 -14.351)
		(width 0.14224)
		(layer "In11.Cu")
		(net "M_C_MA<17>")
	)
	(segment
		(start 268.421104 -50.413666)
		(end 268.421104 -51.795934)
		(width 0.14224)
		(layer "In11.Cu")
		(net "M_C_MA<17>")
	)
	(segment
		(start 277.5712 -27.822144)
		(end 269.497048 -35.896296)
		(width 0.14224)
		(layer "In11.Cu")
		(net "M_C_MA<17>")
	)
	(segment
		(start 277.622 -21.9964)
		(end 277.622 -22.5044)
		(width 0.14224)
		(layer "In11.Cu")
		(net "M_C_MA<17>")
	)
	(segment
		(start 277.622 -23.7236)
		(end 277.5712 -23.7744)
		(width 0.14224)
		(layer "In11.Cu")
		(net "M_C_MA<17>")
	)
	(segment
		(start 275.449792 -2.31648)
		(end 275.4503 -2.316988)
		(width 0.14224)
		(layer "In11.Cu")
		(net "M_C_MA<17>")
	)
	(segment
		(start 269.497048 -49.337722)
		(end 268.421104 -50.413666)
		(width 0.14224)
		(layer "In11.Cu")
		(net "M_C_MA<17>")
	)
	(segment
		(start 277.5204 -21.8948)
		(end 277.622 -21.9964)
		(width 0.14224)
		(layer "In11.Cu")
		(net "M_C_MA<17>")
	)
	(segment
		(start 275.449792 -0.479806)
		(end 275.294852 -0.634746)
		(width 0.14224)
		(layer "In11.Cu")
		(net "M_C_MA<17>")
	)
	(segment
		(start 261.93877 -59.55284)
		(end 261.36727 -59.55284)
		(width 0.1651)
		(layer "F.Cu")
		(net "M_C_MA<16>")
	)
	(segment
		(start 268.650466 3.778758)
		(end 268.649958 3.778758)
		(width 0.1651)
		(layer "F.Cu")
		(net "M_C_MA<16>")
	)
	(segment
		(start 268.649958 1.805686)
		(end 268.649704 1.805432)
		(width 0.1651)
		(layer "F.Cu")
		(net "M_C_MA<16>")
	)
	(segment
		(start 268.649958 3.778758)
		(end 268.649958 1.805686)
		(width 0.1651)
		(layer "F.Cu")
		(net "M_C_MA<16>")
	)
	(via
		(at 268.649704 1.805432)
		(size 0.508)
		(drill 0.254)
		(layers "F.Cu" "B.Cu")
		(net "M_C_MA<16>")
	)
	(via
		(at 261.36727 -59.55284)
		(size 0.508)
		(drill 0.254)
		(layers "F.Cu" "B.Cu")
		(net "M_C_MA<16>")
	)
	(via
		(at 268.649958 -4.328668)
		(size 0.4572)
		(drill 0.2032)
		(layers "F.Cu" "B.Cu")
		(net "M_C_MA<16>")
	)
	(segment
		(start 268.649958 -5.621782)
		(end 268.649958 -4.328668)
		(width 0.1651)
		(layer "B.Cu")
		(net "M_C_MA<16>")
	)
	(segment
		(start 268.650466 -5.621782)
		(end 268.649958 -5.621782)
		(width 0.1651)
		(layer "B.Cu")
		(net "M_C_MA<16>")
	)
	(segment
		(start 268.1732 -3.85191)
		(end 268.1732 -2.5908)
		(width 0.14224)
		(layer "In2.Cu")
		(net "M_C_MA<16>")
	)
	(segment
		(start 267.178282 -8.295894)
		(end 267.45819 -8.015986)
		(width 0.14224)
		(layer "In2.Cu")
		(net "M_C_MA<16>")
	)
	(segment
		(start 267.376656 -7.426452)
		(end 267.376656 -5.60197)
		(width 0.14224)
		(layer "In2.Cu")
		(net "M_C_MA<16>")
	)
	(segment
		(start 267.390118 -13.666724)
		(end 267.196824 -13.47343)
		(width 0.14224)
		(layer "In2.Cu")
		(net "M_C_MA<16>")
	)
	(segment
		(start 267.43279 -22.421596)
		(end 267.43279 -21.938996)
		(width 0.14224)
		(layer "In2.Cu")
		(net "M_C_MA<16>")
	)
	(segment
		(start 263.20496 -30.775148)
		(end 264.76071 -29.219398)
		(width 0.14224)
		(layer "In2.Cu")
		(net "M_C_MA<16>")
	)
	(segment
		(start 267.228066 -22.62632)
		(end 267.43279 -22.421596)
		(width 0.14224)
		(layer "In2.Cu")
		(net "M_C_MA<16>")
	)
	(segment
		(start 262.0518 -52.3748)
		(end 262.0518 -52.07)
		(width 0.0889)
		(layer "In2.Cu")
		(net "M_C_MA<16>")
	)
	(segment
		(start 264.76071 -28.93187)
		(end 264.565384 -28.736544)
		(width 0.14224)
		(layer "In2.Cu")
		(net "M_C_MA<16>")
	)
	(segment
		(start 261.36727 -59.55284)
		(end 261.825486 -59.094624)
		(width 0.0889)
		(layer "In2.Cu")
		(net "M_C_MA<16>")
	)
	(segment
		(start 267.45819 -17.617186)
		(end 267.45819 -17.109186)
		(width 0.14224)
		(layer "In2.Cu")
		(net "M_C_MA<16>")
	)
	(segment
		(start 268.1732 -2.5908)
		(end 268.216634 -2.547366)
		(width 0.14224)
		(layer "In2.Cu")
		(net "M_C_MA<16>")
	)
	(segment
		(start 261.87908 -54.894988)
		(end 261.88543 -54.88432)
		(width 0.0889)
		(layer "In2.Cu")
		(net "M_C_MA<16>")
	)
	(segment
		(start 267.30579 -19.58721)
		(end 267.365988 -19.527012)
		(width 0.14224)
		(layer "In2.Cu")
		(net "M_C_MA<16>")
	)
	(segment
		(start 261.87908 -53.904388)
		(end 261.88543 -53.89372)
		(width 0.0889)
		(layer "In2.Cu")
		(net "M_C_MA<16>")
	)
	(segment
		(start 267.390118 -17.041114)
		(end 267.390118 -13.666724)
		(width 0.14224)
		(layer "In2.Cu")
		(net "M_C_MA<16>")
	)
	(segment
		(start 268.1732 0.272288)
		(end 268.1732 0.762)
		(width 0.14224)
		(layer "In2.Cu")
		(net "M_C_MA<16>")
	)
	(segment
		(start 267.233654 -18.33245)
		(end 267.233654 -17.841722)
		(width 0.14224)
		(layer "In2.Cu")
		(net "M_C_MA<16>")
	)
	(segment
		(start 267.233654 -17.841722)
		(end 267.45819 -17.617186)
		(width 0.14224)
		(layer "In2.Cu")
		(net "M_C_MA<16>")
	)
	(segment
		(start 267.196824 -13.47343)
		(end 267.196824 -13.056362)
		(width 0.14224)
		(layer "In2.Cu")
		(net "M_C_MA<16>")
	)
	(segment
		(start 261.825486 -59.094624)
		(end 261.825486 -58.064146)
		(width 0.0889)
		(layer "In2.Cu")
		(net "M_C_MA<16>")
	)
	(segment
		(start 262.726424 -50.811176)
		(end 262.9154 -50.6222)
		(width 0.0889)
		(layer "In2.Cu")
		(net "M_C_MA<16>")
	)
	(segment
		(start 267.228066 -23.105872)
		(end 267.228066 -22.62632)
		(width 0.14224)
		(layer "In2.Cu")
		(net "M_C_MA<16>")
	)
	(segment
		(start 265.8364 -25.938988)
		(end 267.440664 -24.334724)
		(width 0.14224)
		(layer "In2.Cu")
		(net "M_C_MA<16>")
	)
	(segment
		(start 267.45819 -17.109186)
		(end 267.390118 -17.041114)
		(width 0.14224)
		(layer "In2.Cu")
		(net "M_C_MA<16>")
	)
	(segment
		(start 268.3383 1.494028)
		(end 268.649704 1.805432)
		(width 0.14224)
		(layer "In2.Cu")
		(net "M_C_MA<16>")
	)
	(segment
		(start 265.62304 -28.357068)
		(end 265.8364 -28.143708)
		(width 0.14224)
		(layer "In2.Cu")
		(net "M_C_MA<16>")
	)
	(segment
		(start 261.874254 -52.922424)
		(end 261.939786 -52.80533)
		(width 0.0889)
		(layer "In2.Cu")
		(net "M_C_MA<16>")
	)
	(segment
		(start 264.852658 -28.161742)
		(end 265.140186 -28.161742)
		(width 0.14224)
		(layer "In2.Cu")
		(net "M_C_MA<16>")
	)
	(segment
		(start 267.45819 -7.507986)
		(end 267.376656 -7.426452)
		(width 0.14224)
		(layer "In2.Cu")
		(net "M_C_MA<16>")
	)
	(segment
		(start 262.0518 -52.07)
		(end 262.726424 -51.395376)
		(width 0.0889)
		(layer "In2.Cu")
		(net "M_C_MA<16>")
	)
	(segment
		(start 263.20496 -48.525684)
		(end 263.20496 -48.302672)
		(width 0.0889)
		(layer "In2.Cu")
		(net "M_C_MA<16>")
	)
	(segment
		(start 267.43279 -12.337796)
		(end 267.387324 -12.29233)
		(width 0.14224)
		(layer "In2.Cu")
		(net "M_C_MA<16>")
	)
	(segment
		(start 261.874254 -56.884824)
		(end 261.87908 -56.876188)
		(width 0.0889)
		(layer "In2.Cu")
		(net "M_C_MA<16>")
	)
	(segment
		(start 267.440664 -24.334724)
		(end 267.440664 -23.31847)
		(width 0.14224)
		(layer "In2.Cu")
		(net "M_C_MA<16>")
	)
	(segment
		(start 265.140186 -28.161742)
		(end 265.335512 -28.357068)
		(width 0.14224)
		(layer "In2.Cu")
		(net "M_C_MA<16>")
	)
	(segment
		(start 262.9154 -48.815244)
		(end 263.20496 -48.525684)
		(width 0.0889)
		(layer "In2.Cu")
		(net "M_C_MA<16>")
	)
	(segment
		(start 267.387324 -12.29233)
		(end 267.387324 -8.88492)
		(width 0.14224)
		(layer "In2.Cu")
		(net "M_C_MA<16>")
	)
	(segment
		(start 267.365988 -19.527012)
		(end 267.365988 -18.464784)
		(width 0.14224)
		(layer "In2.Cu")
		(net "M_C_MA<16>")
	)
	(segment
		(start 267.376656 -5.60197)
		(end 268.649958 -4.328668)
		(width 0.14224)
		(layer "In2.Cu")
		(net "M_C_MA<16>")
	)
	(segment
		(start 268.3383 0.9271)
		(end 268.3383 1.494028)
		(width 0.14224)
		(layer "In2.Cu")
		(net "M_C_MA<16>")
	)
	(segment
		(start 264.565384 -28.736544)
		(end 264.565384 -28.449016)
		(width 0.14224)
		(layer "In2.Cu")
		(net "M_C_MA<16>")
	)
	(segment
		(start 261.87908 -55.885588)
		(end 261.88543 -55.87492)
		(width 0.0889)
		(layer "In2.Cu")
		(net "M_C_MA<16>")
	)
	(segment
		(start 263.20496 -48.302672)
		(end 263.20496 -30.775148)
		(width 0.14224)
		(layer "In2.Cu")
		(net "M_C_MA<16>")
	)
	(segment
		(start 268.216634 0.228854)
		(end 268.1732 0.272288)
		(width 0.14224)
		(layer "In2.Cu")
		(net "M_C_MA<16>")
	)
	(segment
		(start 267.43279 -21.938996)
		(end 267.30579 -21.811996)
		(width 0.14224)
		(layer "In2.Cu")
		(net "M_C_MA<16>")
	)
	(segment
		(start 267.387324 -8.88492)
		(end 267.178282 -8.675878)
		(width 0.14224)
		(layer "In2.Cu")
		(net "M_C_MA<16>")
	)
	(segment
		(start 262.9154 -50.6222)
		(end 262.9154 -48.815244)
		(width 0.0889)
		(layer "In2.Cu")
		(net "M_C_MA<16>")
	)
	(segment
		(start 267.196824 -13.056362)
		(end 267.43279 -12.820396)
		(width 0.14224)
		(layer "In2.Cu")
		(net "M_C_MA<16>")
	)
	(segment
		(start 261.874254 -55.894224)
		(end 261.87908 -55.885588)
		(width 0.0889)
		(layer "In2.Cu")
		(net "M_C_MA<16>")
	)
	(segment
		(start 267.440664 -23.31847)
		(end 267.228066 -23.105872)
		(width 0.14224)
		(layer "In2.Cu")
		(net "M_C_MA<16>")
	)
	(segment
		(start 264.76071 -29.219398)
		(end 264.76071 -28.93187)
		(width 0.14224)
		(layer "In2.Cu")
		(net "M_C_MA<16>")
	)
	(segment
		(start 267.30579 -21.811996)
		(end 267.30579 -19.58721)
		(width 0.14224)
		(layer "In2.Cu")
		(net "M_C_MA<16>")
	)
	(segment
		(start 261.874254 -54.903624)
		(end 261.87908 -54.894988)
		(width 0.0889)
		(layer "In2.Cu")
		(net "M_C_MA<16>")
	)
	(segment
		(start 267.45819 -8.015986)
		(end 267.45819 -7.507986)
		(width 0.14224)
		(layer "In2.Cu")
		(net "M_C_MA<16>")
	)
	(segment
		(start 268.1732 0.762)
		(end 268.3383 0.9271)
		(width 0.14224)
		(layer "In2.Cu")
		(net "M_C_MA<16>")
	)
	(segment
		(start 267.43279 -12.820396)
		(end 267.43279 -12.337796)
		(width 0.14224)
		(layer "In2.Cu")
		(net "M_C_MA<16>")
	)
	(segment
		(start 261.874254 -53.913024)
		(end 261.87908 -53.904388)
		(width 0.0889)
		(layer "In2.Cu")
		(net "M_C_MA<16>")
	)
	(segment
		(start 264.565384 -28.449016)
		(end 264.852658 -28.161742)
		(width 0.14224)
		(layer "In2.Cu")
		(net "M_C_MA<16>")
	)
	(segment
		(start 265.335512 -28.357068)
		(end 265.62304 -28.357068)
		(width 0.14224)
		(layer "In2.Cu")
		(net "M_C_MA<16>")
	)
	(segment
		(start 261.87908 -56.876188)
		(end 261.88543 -56.86552)
		(width 0.0889)
		(layer "In2.Cu")
		(net "M_C_MA<16>")
	)
	(segment
		(start 268.216634 -2.547366)
		(end 268.216634 0.228854)
		(width 0.14224)
		(layer "In2.Cu")
		(net "M_C_MA<16>")
	)
	(segment
		(start 268.649958 -4.328668)
		(end 268.1732 -3.85191)
		(width 0.14224)
		(layer "In2.Cu")
		(net "M_C_MA<16>")
	)
	(segment
		(start 267.365988 -18.464784)
		(end 267.233654 -18.33245)
		(width 0.14224)
		(layer "In2.Cu")
		(net "M_C_MA<16>")
	)
	(segment
		(start 267.178282 -8.675878)
		(end 267.178282 -8.295894)
		(width 0.14224)
		(layer "In2.Cu")
		(net "M_C_MA<16>")
	)
	(segment
		(start 265.8364 -28.143708)
		(end 265.8364 -25.938988)
		(width 0.14224)
		(layer "In2.Cu")
		(net "M_C_MA<16>")
	)
	(segment
		(start 262.726424 -51.395376)
		(end 262.726424 -50.811176)
		(width 0.0889)
		(layer "In2.Cu")
		(net "M_C_MA<16>")
	)
	(arc
		(start 261.87908 -57.276238)
		(mid 261.82561 -57.081175)
		(end 261.874254 -56.884824)
		(width 0.0889)
		(layer "In2.Cu")
		(net "M_C_MA<16>")
	)
	(arc
		(start 261.87908 -54.304438)
		(mid 261.82561 -54.109375)
		(end 261.874254 -53.913024)
		(width 0.0889)
		(layer "In2.Cu")
		(net "M_C_MA<16>")
	)
	(arc
		(start 261.88543 -54.88432)
		(mid 261.958228 -54.593557)
		(end 261.87908 -54.304438)
		(width 0.0889)
		(layer "In2.Cu")
		(net "M_C_MA<16>")
	)
	(arc
		(start 261.87908 -53.313838)
		(mid 261.82561 -53.118775)
		(end 261.874254 -52.922424)
		(width 0.0889)
		(layer "In2.Cu")
		(net "M_C_MA<16>")
	)
	(arc
		(start 261.825486 -58.064146)
		(mid 261.83951 -57.962122)
		(end 261.87908 -57.867042)
		(width 0.0889)
		(layer "In2.Cu")
		(net "M_C_MA<16>")
	)
	(arc
		(start 261.88543 -56.86552)
		(mid 261.958228 -56.574757)
		(end 261.87908 -56.285638)
		(width 0.0889)
		(layer "In2.Cu")
		(net "M_C_MA<16>")
	)
	(arc
		(start 261.939786 -52.80533)
		(mid 262.023347 -52.597236)
		(end 262.0518 -52.3748)
		(width 0.0889)
		(layer "In2.Cu")
		(net "M_C_MA<16>")
	)
	(arc
		(start 261.88543 -53.89372)
		(mid 261.958228 -53.602957)
		(end 261.87908 -53.313838)
		(width 0.0889)
		(layer "In2.Cu")
		(net "M_C_MA<16>")
	)
	(arc
		(start 261.88543 -55.87492)
		(mid 261.958228 -55.584157)
		(end 261.87908 -55.295038)
		(width 0.0889)
		(layer "In2.Cu")
		(net "M_C_MA<16>")
	)
	(arc
		(start 261.87908 -56.285638)
		(mid 261.82561 -56.090575)
		(end 261.874254 -55.894224)
		(width 0.0889)
		(layer "In2.Cu")
		(net "M_C_MA<16>")
	)
	(arc
		(start 261.87908 -57.867042)
		(mid 261.958211 -57.57164)
		(end 261.87908 -57.276238)
		(width 0.0889)
		(layer "In2.Cu")
		(net "M_C_MA<16>")
	)
	(arc
		(start 261.87908 -55.295038)
		(mid 261.82561 -55.099975)
		(end 261.874254 -54.903624)
		(width 0.0889)
		(layer "In2.Cu")
		(net "M_C_MA<16>")
	)
	(segment
		(start 272.05051 1.806194)
		(end 272.049748 1.805432)
		(width 0.1651)
		(layer "F.Cu")
		(net "M_C_MA<15>")
	)
	(segment
		(start 272.05051 3.778758)
		(end 272.05051 1.806194)
		(width 0.1651)
		(layer "F.Cu")
		(net "M_C_MA<15>")
	)
	(segment
		(start 260.22173 -61.53404)
		(end 259.65023 -61.53404)
		(width 0.1016)
		(layer "F.Cu")
		(net "M_C_MA<15>")
	)
	(via
		(at 272.050256 -4.332478)
		(size 0.4572)
		(drill 0.2032)
		(layers "F.Cu" "B.Cu")
		(net "M_C_MA<15>")
	)
	(via
		(at 272.049748 1.805432)
		(size 0.508)
		(drill 0.254)
		(layers "F.Cu" "B.Cu")
		(net "M_C_MA<15>")
	)
	(via
		(at 259.65023 -61.53404)
		(size 0.508)
		(drill 0.254)
		(layers "F.Cu" "B.Cu")
		(net "M_C_MA<15>")
	)
	(segment
		(start 272.05051 -5.621782)
		(end 272.05051 -4.332732)
		(width 0.1651)
		(layer "B.Cu")
		(net "M_C_MA<15>")
	)
	(segment
		(start 272.05051 -4.332732)
		(end 272.050256 -4.332478)
		(width 0.1651)
		(layer "B.Cu")
		(net "M_C_MA<15>")
	)
	(segment
		(start 260.985 -52.298346)
		(end 260.9342 -52.349146)
		(width 0.0889)
		(layer "In11.Cu")
		(net "M_C_MA<15>")
	)
	(segment
		(start 262.668004 -49.920652)
		(end 261.765796 -50.82286)
		(width 0.0889)
		(layer "In11.Cu")
		(net "M_C_MA<15>")
	)
	(segment
		(start 269.91818 -7.522972)
		(end 269.919704 -7.524496)
		(width 0.14224)
		(layer "In11.Cu")
		(net "M_C_MA<15>")
	)
	(segment
		(start 264.800334 -30.058614)
		(end 264.54735 -29.80563)
		(width 0.14224)
		(layer "In11.Cu")
		(net "M_C_MA<15>")
	)
	(segment
		(start 269.091664 -12.540234)
		(end 269.158466 -12.607036)
		(width 0.14224)
		(layer "In11.Cu")
		(net "M_C_MA<15>")
	)
	(segment
		(start 263.986772 -30.366208)
		(end 264.239756 -30.619192)
		(width 0.14224)
		(layer "In11.Cu")
		(net "M_C_MA<15>")
	)
	(segment
		(start 267.19784 -27.880056)
		(end 265.019282 -30.058614)
		(width 0.14224)
		(layer "In11.Cu")
		(net "M_C_MA<15>")
	)
	(segment
		(start 269.061438 -14.26337)
		(end 268.213078 -15.11173)
		(width 0.14224)
		(layer "In11.Cu")
		(net "M_C_MA<15>")
	)
	(segment
		(start 263.898126 -31.17977)
		(end 263.679178 -31.17977)
		(width 0.14224)
		(layer "In11.Cu")
		(net "M_C_MA<15>")
	)
	(segment
		(start 272.050256 -4.332478)
		(end 272.050256 -4.723638)
		(width 0.14224)
		(layer "In11.Cu")
		(net "M_C_MA<15>")
	)
	(segment
		(start 268.4526 -19.2278)
		(end 268.4526 -21.6916)
		(width 0.14224)
		(layer "In11.Cu")
		(net "M_C_MA<15>")
	)
	(segment
		(start 269.91818 -6.855714)
		(end 269.91818 -7.522972)
		(width 0.14224)
		(layer "In11.Cu")
		(net "M_C_MA<15>")
	)
	(segment
		(start 268.30528 -27.880056)
		(end 267.19784 -27.880056)
		(width 0.14224)
		(layer "In11.Cu")
		(net "M_C_MA<15>")
	)
	(segment
		(start 271.5768 -1.9304)
		(end 271.638776 -1.992376)
		(width 0.14224)
		(layer "In11.Cu")
		(net "M_C_MA<15>")
	)
	(segment
		(start 262.865616 -31.268416)
		(end 262.865616 -31.487364)
		(width 0.14224)
		(layer "In11.Cu")
		(net "M_C_MA<15>")
	)
	(segment
		(start 263.679178 -31.17977)
		(end 263.426194 -30.926786)
		(width 0.14224)
		(layer "In11.Cu")
		(net "M_C_MA<15>")
	)
	(segment
		(start 264.239756 -30.619192)
		(end 264.239756 -30.83814)
		(width 0.14224)
		(layer "In11.Cu")
		(net "M_C_MA<15>")
	)
	(segment
		(start 269.919704 -7.524496)
		(end 269.919704 -7.913624)
		(width 0.14224)
		(layer "In11.Cu")
		(net "M_C_MA<15>")
	)
	(segment
		(start 261.765796 -51.51755)
		(end 261.0866 -52.197)
		(width 0.0889)
		(layer "In11.Cu")
		(net "M_C_MA<15>")
	)
	(segment
		(start 271.638776 -2.681224)
		(end 271.5768 -2.7432)
		(width 0.14224)
		(layer "In11.Cu")
		(net "M_C_MA<15>")
	)
	(segment
		(start 263.1186 -31.959296)
		(end 262.668004 -32.409892)
		(width 0.14224)
		(layer "In11.Cu")
		(net "M_C_MA<15>")
	)
	(segment
		(start 260.59384 -53.594)
		(end 260.453632 -53.594)
		(width 0.0889)
		(layer "In11.Cu")
		(net "M_C_MA<15>")
	)
	(segment
		(start 260.077204 -60.629292)
		(end 259.65023 -61.53404)
		(width 0.0889)
		(layer "In11.Cu")
		(net "M_C_MA<15>")
	)
	(segment
		(start 262.668004 -49.453038)
		(end 262.668004 -49.920652)
		(width 0.0889)
		(layer "In11.Cu")
		(net "M_C_MA<15>")
	)
	(segment
		(start 260.9342 -53.25364)
		(end 260.59384 -53.594)
		(width 0.0889)
		(layer "In11.Cu")
		(net "M_C_MA<15>")
	)
	(segment
		(start 269.158466 -13.321792)
		(end 269.061438 -13.41882)
		(width 0.14224)
		(layer "In11.Cu")
		(net "M_C_MA<15>")
	)
	(segment
		(start 260.9342 -52.349146)
		(end 260.9342 -53.25364)
		(width 0.0889)
		(layer "In11.Cu")
		(net "M_C_MA<15>")
	)
	(segment
		(start 260.077204 -53.970428)
		(end 260.077204 -60.629292)
		(width 0.0889)
		(layer "In11.Cu")
		(net "M_C_MA<15>")
	)
	(segment
		(start 262.865616 -31.487364)
		(end 263.1186 -31.740348)
		(width 0.14224)
		(layer "In11.Cu")
		(net "M_C_MA<15>")
	)
	(segment
		(start 262.668004 -32.409892)
		(end 262.668004 -49.453038)
		(width 0.14224)
		(layer "In11.Cu")
		(net "M_C_MA<15>")
	)
	(segment
		(start 269.061438 -13.41882)
		(end 269.061438 -14.26337)
		(width 0.14224)
		(layer "In11.Cu")
		(net "M_C_MA<15>")
	)
	(segment
		(start 271.5768 0.679704)
		(end 271.5768 -1.9304)
		(width 0.14224)
		(layer "In11.Cu")
		(net "M_C_MA<15>")
	)
	(segment
		(start 263.986772 -30.14726)
		(end 263.986772 -30.366208)
		(width 0.14224)
		(layer "In11.Cu")
		(net "M_C_MA<15>")
	)
	(segment
		(start 269.1892 -26.996136)
		(end 268.30528 -27.880056)
		(width 0.14224)
		(layer "In11.Cu")
		(net "M_C_MA<15>")
	)
	(segment
		(start 269.919704 -7.913624)
		(end 269.091664 -8.741664)
		(width 0.14224)
		(layer "In11.Cu")
		(net "M_C_MA<15>")
	)
	(segment
		(start 264.328402 -29.80563)
		(end 263.986772 -30.14726)
		(width 0.14224)
		(layer "In11.Cu")
		(net "M_C_MA<15>")
	)
	(segment
		(start 264.239756 -30.83814)
		(end 263.898126 -31.17977)
		(width 0.14224)
		(layer "In11.Cu")
		(net "M_C_MA<15>")
	)
	(segment
		(start 264.54735 -29.80563)
		(end 264.328402 -29.80563)
		(width 0.14224)
		(layer "In11.Cu")
		(net "M_C_MA<15>")
	)
	(segment
		(start 260.453632 -53.594)
		(end 260.077204 -53.970428)
		(width 0.0889)
		(layer "In11.Cu")
		(net "M_C_MA<15>")
	)
	(segment
		(start 268.21511 -17.72031)
		(end 268.21511 -18.99031)
		(width 0.14224)
		(layer "In11.Cu")
		(net "M_C_MA<15>")
	)
	(segment
		(start 268.213078 -15.11173)
		(end 268.213078 -17.718278)
		(width 0.14224)
		(layer "In11.Cu")
		(net "M_C_MA<15>")
	)
	(segment
		(start 269.158466 -12.607036)
		(end 269.158466 -13.321792)
		(width 0.14224)
		(layer "In11.Cu")
		(net "M_C_MA<15>")
	)
	(segment
		(start 272.049748 1.152652)
		(end 271.5768 0.679704)
		(width 0.14224)
		(layer "In11.Cu")
		(net "M_C_MA<15>")
	)
	(segment
		(start 268.1732 -21.971)
		(end 268.1732 -22.436836)
		(width 0.14224)
		(layer "In11.Cu")
		(net "M_C_MA<15>")
	)
	(segment
		(start 268.1732 -22.436836)
		(end 269.1892 -23.452836)
		(width 0.14224)
		(layer "In11.Cu")
		(net "M_C_MA<15>")
	)
	(segment
		(start 263.426194 -30.926786)
		(end 263.207246 -30.926786)
		(width 0.14224)
		(layer "In11.Cu")
		(net "M_C_MA<15>")
	)
	(segment
		(start 261.0866 -52.197)
		(end 260.985 -52.298346)
		(width 0.0889)
		(layer "In11.Cu")
		(net "M_C_MA<15>")
	)
	(segment
		(start 272.050256 -4.04495)
		(end 272.050256 -4.332478)
		(width 0.14224)
		(layer "In11.Cu")
		(net "M_C_MA<15>")
	)
	(segment
		(start 265.019282 -30.058614)
		(end 264.800334 -30.058614)
		(width 0.14224)
		(layer "In11.Cu")
		(net "M_C_MA<15>")
	)
	(segment
		(start 269.091664 -8.741664)
		(end 269.091664 -12.540234)
		(width 0.14224)
		(layer "In11.Cu")
		(net "M_C_MA<15>")
	)
	(segment
		(start 268.213078 -17.718278)
		(end 268.21511 -17.72031)
		(width 0.14224)
		(layer "In11.Cu")
		(net "M_C_MA<15>")
	)
	(segment
		(start 261.765796 -50.82286)
		(end 261.765796 -51.51755)
		(width 0.0889)
		(layer "In11.Cu")
		(net "M_C_MA<15>")
	)
	(segment
		(start 268.4526 -21.6916)
		(end 268.1732 -21.971)
		(width 0.14224)
		(layer "In11.Cu")
		(net "M_C_MA<15>")
	)
	(segment
		(start 268.21511 -18.99031)
		(end 268.4526 -19.2278)
		(width 0.14224)
		(layer "In11.Cu")
		(net "M_C_MA<15>")
	)
	(segment
		(start 263.1186 -31.740348)
		(end 263.1186 -31.959296)
		(width 0.14224)
		(layer "In11.Cu")
		(net "M_C_MA<15>")
	)
	(segment
		(start 271.5768 -2.7432)
		(end 271.5768 -3.571494)
		(width 0.14224)
		(layer "In11.Cu")
		(net "M_C_MA<15>")
	)
	(segment
		(start 263.207246 -30.926786)
		(end 262.865616 -31.268416)
		(width 0.14224)
		(layer "In11.Cu")
		(net "M_C_MA<15>")
	)
	(segment
		(start 269.1892 -23.452836)
		(end 269.1892 -26.996136)
		(width 0.14224)
		(layer "In11.Cu")
		(net "M_C_MA<15>")
	)
	(segment
		(start 272.050256 -4.723638)
		(end 269.91818 -6.855714)
		(width 0.14224)
		(layer "In11.Cu")
		(net "M_C_MA<15>")
	)
	(segment
		(start 271.638776 -1.992376)
		(end 271.638776 -2.681224)
		(width 0.14224)
		(layer "In11.Cu")
		(net "M_C_MA<15>")
	)
	(segment
		(start 271.5768 -3.571494)
		(end 272.050256 -4.04495)
		(width 0.14224)
		(layer "In11.Cu")
		(net "M_C_MA<15>")
	)
	(segment
		(start 272.049748 1.805432)
		(end 272.049748 1.152652)
		(width 0.14224)
		(layer "In11.Cu")
		(net "M_C_MA<15>")
	)
	(segment
		(start 270.34998 0.442468)
		(end 270.349726 0.442722)
		(width 0.1651)
		(layer "F.Cu")
		(net "M_C_MA<14>")
	)
	(segment
		(start 270.34998 -0.821182)
		(end 270.34998 0.442468)
		(width 0.1651)
		(layer "F.Cu")
		(net "M_C_MA<14>")
	)
	(segment
		(start 270.350488 -0.821182)
		(end 270.34998 -0.821182)
		(width 0.1651)
		(layer "F.Cu")
		(net "M_C_MA<14>")
	)
	(segment
		(start 263.65581 -58.561986)
		(end 263.08431 -58.561986)
		(width 0.1016)
		(layer "F.Cu")
		(net "M_C_MA<14>")
	)
	(via
		(at 263.08431 -58.561986)
		(size 0.508)
		(drill 0.254)
		(layers "F.Cu" "B.Cu")
		(net "M_C_MA<14>")
	)
	(via
		(at 270.350234 -2.316988)
		(size 0.4572)
		(drill 0.2032)
		(layers "F.Cu" "B.Cu")
		(net "M_C_MA<14>")
	)
	(via
		(at 270.349726 0.442722)
		(size 0.508)
		(drill 0.254)
		(layers "F.Cu" "B.Cu")
		(net "M_C_MA<14>")
	)
	(segment
		(start 270.34998 -1.021842)
		(end 270.34998 -2.316734)
		(width 0.1651)
		(layer "B.Cu")
		(net "M_C_MA<14>")
	)
	(segment
		(start 270.34998 -2.316734)
		(end 270.350234 -2.316988)
		(width 0.1651)
		(layer "B.Cu")
		(net "M_C_MA<14>")
	)
	(segment
		(start 270.350488 -1.021842)
		(end 270.34998 -1.021842)
		(width 0.1651)
		(layer "B.Cu")
		(net "M_C_MA<14>")
	)
	(segment
		(start 263.43102 -52.818284)
		(end 263.512046 -52.67325)
		(width 0.0889)
		(layer "In2.Cu")
		(net "M_C_MA<14>")
	)
	(segment
		(start 264.72896 -31.407608)
		(end 268.1986 -27.937968)
		(width 0.14224)
		(layer "In2.Cu")
		(net "M_C_MA<14>")
	)
	(segment
		(start 263.43102 -55.790338)
		(end 263.435846 -55.781702)
		(width 0.0889)
		(layer "In2.Cu")
		(net "M_C_MA<14>")
	)
	(segment
		(start 264.72896 -48.52924)
		(end 264.72896 -48.315372)
		(width 0.0889)
		(layer "In2.Cu")
		(net "M_C_MA<14>")
	)
	(segment
		(start 270.762476 -4.011676)
		(end 270.349726 -3.598926)
		(width 0.14224)
		(layer "In2.Cu")
		(net "M_C_MA<14>")
	)
	(segment
		(start 270.349726 0.442722)
		(end 270.349726 -1.079246)
		(width 0.14224)
		(layer "In2.Cu")
		(net "M_C_MA<14>")
	)
	(segment
		(start 269.842234 -21.913596)
		(end 269.994634 -21.761196)
		(width 0.14224)
		(layer "In2.Cu")
		(net "M_C_MA<14>")
	)
	(segment
		(start 270.020034 -23.107396)
		(end 270.020034 -22.573996)
		(width 0.14224)
		(layer "In2.Cu")
		(net "M_C_MA<14>")
	)
	(segment
		(start 263.640824 -51.26863)
		(end 264.072624 -50.83683)
		(width 0.0889)
		(layer "In2.Cu")
		(net "M_C_MA<14>")
	)
	(segment
		(start 263.42467 -54.810406)
		(end 263.43102 -54.799738)
		(width 0.0889)
		(layer "In2.Cu")
		(net "M_C_MA<14>")
	)
	(segment
		(start 269.93342 -17.0434)
		(end 269.93342 -13.59281)
		(width 0.14224)
		(layer "In2.Cu")
		(net "M_C_MA<14>")
	)
	(segment
		(start 271.058894 0.132842)
		(end 271.310354 0.132842)
		(width 0.14224)
		(layer "In2.Cu")
		(net "M_C_MA<14>")
	)
	(segment
		(start 269.715996 -23.411434)
		(end 270.020034 -23.107396)
		(width 0.14224)
		(layer "In2.Cu")
		(net "M_C_MA<14>")
	)
	(segment
		(start 270.911066 -1.079246)
		(end 270.911066 -0.014986)
		(width 0.14224)
		(layer "In2.Cu")
		(net "M_C_MA<14>")
	)
	(segment
		(start 269.842234 -8.041386)
		(end 269.842234 -7.533386)
		(width 0.14224)
		(layer "In2.Cu")
		(net "M_C_MA<14>")
	)
	(segment
		(start 270.911066 -0.014986)
		(end 271.058894 0.132842)
		(width 0.14224)
		(layer "In2.Cu")
		(net "M_C_MA<14>")
	)
	(segment
		(start 269.937484 -6.122924)
		(end 270.762476 -5.297932)
		(width 0.14224)
		(layer "In2.Cu")
		(net "M_C_MA<14>")
	)
	(segment
		(start 269.93342 -13.59281)
		(end 270.020034 -13.506196)
		(width 0.14224)
		(layer "In2.Cu")
		(net "M_C_MA<14>")
	)
	(segment
		(start 269.842234 -7.533386)
		(end 269.937484 -7.438136)
		(width 0.14224)
		(layer "In2.Cu")
		(net "M_C_MA<14>")
	)
	(segment
		(start 269.92453 -18.44929)
		(end 269.994634 -18.379186)
		(width 0.14224)
		(layer "In2.Cu")
		(net "M_C_MA<14>")
	)
	(segment
		(start 270.504666 -1.234186)
		(end 270.756126 -1.234186)
		(width 0.14224)
		(layer "In2.Cu")
		(net "M_C_MA<14>")
	)
	(segment
		(start 263.42467 -56.791606)
		(end 263.43102 -56.780938)
		(width 0.0889)
		(layer "In2.Cu")
		(net "M_C_MA<14>")
	)
	(segment
		(start 270.504666 -1.826006)
		(end 270.349726 -1.980946)
		(width 0.14224)
		(layer "In2.Cu")
		(net "M_C_MA<14>")
	)
	(segment
		(start 263.640824 -52.245514)
		(end 263.640824 -51.26863)
		(width 0.0889)
		(layer "In2.Cu")
		(net "M_C_MA<14>")
	)
	(segment
		(start 269.842234 -12.794996)
		(end 269.842234 -12.312396)
		(width 0.14224)
		(layer "In2.Cu")
		(net "M_C_MA<14>")
	)
	(segment
		(start 269.942564 -8.830056)
		(end 269.994634 -8.777986)
		(width 0.14224)
		(layer "In2.Cu")
		(net "M_C_MA<14>")
	)
	(segment
		(start 269.994634 -8.777986)
		(end 269.994634 -8.193786)
		(width 0.14224)
		(layer "In2.Cu")
		(net "M_C_MA<14>")
	)
	(segment
		(start 269.937484 -7.438136)
		(end 269.937484 -6.122924)
		(width 0.14224)
		(layer "In2.Cu")
		(net "M_C_MA<14>")
	)
	(segment
		(start 263.512046 -52.67325)
		(end 263.640824 -52.245514)
		(width 0.0889)
		(layer "In2.Cu")
		(net "M_C_MA<14>")
	)
	(segment
		(start 269.942564 -12.212066)
		(end 269.942564 -8.830056)
		(width 0.14224)
		(layer "In2.Cu")
		(net "M_C_MA<14>")
	)
	(segment
		(start 268.1986 -27.937968)
		(end 268.1986 -25.875488)
		(width 0.14224)
		(layer "In2.Cu")
		(net "M_C_MA<14>")
	)
	(segment
		(start 269.994634 -19.141186)
		(end 269.92453 -19.071082)
		(width 0.14224)
		(layer "In2.Cu")
		(net "M_C_MA<14>")
	)
	(segment
		(start 263.42467 -55.801006)
		(end 263.43102 -55.790338)
		(width 0.0889)
		(layer "In2.Cu")
		(net "M_C_MA<14>")
	)
	(segment
		(start 263.41451 -57.799986)
		(end 263.435846 -57.762902)
		(width 0.0889)
		(layer "In2.Cu")
		(net "M_C_MA<14>")
	)
	(segment
		(start 270.020034 -12.972796)
		(end 269.842234 -12.794996)
		(width 0.14224)
		(layer "In2.Cu")
		(net "M_C_MA<14>")
	)
	(segment
		(start 263.43102 -54.799738)
		(end 263.435846 -54.791102)
		(width 0.0889)
		(layer "In2.Cu")
		(net "M_C_MA<14>")
	)
	(segment
		(start 269.994634 -21.761196)
		(end 269.994634 -19.141186)
		(width 0.14224)
		(layer "In2.Cu")
		(net "M_C_MA<14>")
	)
	(segment
		(start 270.762476 -5.297932)
		(end 270.762476 -4.011676)
		(width 0.14224)
		(layer "In2.Cu")
		(net "M_C_MA<14>")
	)
	(segment
		(start 263.43102 -56.780938)
		(end 263.435846 -56.772302)
		(width 0.0889)
		(layer "In2.Cu")
		(net "M_C_MA<14>")
	)
	(segment
		(start 269.994634 -8.193786)
		(end 269.842234 -8.041386)
		(width 0.14224)
		(layer "In2.Cu")
		(net "M_C_MA<14>")
	)
	(segment
		(start 271.472406 -1.671066)
		(end 271.317466 -1.826006)
		(width 0.14224)
		(layer "In2.Cu")
		(net "M_C_MA<14>")
	)
	(segment
		(start 271.317466 -1.826006)
		(end 270.504666 -1.826006)
		(width 0.14224)
		(layer "In2.Cu")
		(net "M_C_MA<14>")
	)
	(segment
		(start 270.349726 -1.980946)
		(end 270.349726 -2.31648)
		(width 0.14224)
		(layer "In2.Cu")
		(net "M_C_MA<14>")
	)
	(segment
		(start 270.349726 -3.598926)
		(end 270.349726 -2.317496)
		(width 0.14224)
		(layer "In2.Cu")
		(net "M_C_MA<14>")
	)
	(segment
		(start 264.72896 -48.315372)
		(end 264.72896 -31.407608)
		(width 0.14224)
		(layer "In2.Cu")
		(net "M_C_MA<14>")
	)
	(segment
		(start 263.43102 -53.809138)
		(end 263.435846 -53.800502)
		(width 0.0889)
		(layer "In2.Cu")
		(net "M_C_MA<14>")
	)
	(segment
		(start 270.020034 -22.573996)
		(end 269.842234 -22.396196)
		(width 0.14224)
		(layer "In2.Cu")
		(net "M_C_MA<14>")
	)
	(segment
		(start 269.842234 -22.396196)
		(end 269.842234 -21.913596)
		(width 0.14224)
		(layer "In2.Cu")
		(net "M_C_MA<14>")
	)
	(segment
		(start 270.020034 -13.506196)
		(end 270.020034 -12.972796)
		(width 0.14224)
		(layer "In2.Cu")
		(net "M_C_MA<14>")
	)
	(segment
		(start 269.92453 -19.071082)
		(end 269.92453 -18.44929)
		(width 0.14224)
		(layer "In2.Cu")
		(net "M_C_MA<14>")
	)
	(segment
		(start 270.349726 -2.31648)
		(end 270.350234 -2.316988)
		(width 0.14224)
		(layer "In2.Cu")
		(net "M_C_MA<14>")
	)
	(segment
		(start 269.994634 -18.379186)
		(end 269.994634 -17.104614)
		(width 0.14224)
		(layer "In2.Cu")
		(net "M_C_MA<14>")
	)
	(segment
		(start 269.994634 -17.104614)
		(end 269.93342 -17.0434)
		(width 0.14224)
		(layer "In2.Cu")
		(net "M_C_MA<14>")
	)
	(segment
		(start 263.08431 -58.561986)
		(end 263.41451 -57.799986)
		(width 0.0889)
		(layer "In2.Cu")
		(net "M_C_MA<14>")
	)
	(segment
		(start 263.42467 -53.819806)
		(end 263.43102 -53.809138)
		(width 0.0889)
		(layer "In2.Cu")
		(net "M_C_MA<14>")
	)
	(segment
		(start 264.072624 -50.83683)
		(end 264.072624 -49.185576)
		(width 0.0889)
		(layer "In2.Cu")
		(net "M_C_MA<14>")
	)
	(segment
		(start 270.349726 -1.079246)
		(end 270.504666 -1.234186)
		(width 0.14224)
		(layer "In2.Cu")
		(net "M_C_MA<14>")
	)
	(segment
		(start 270.756126 -1.234186)
		(end 270.911066 -1.079246)
		(width 0.14224)
		(layer "In2.Cu")
		(net "M_C_MA<14>")
	)
	(segment
		(start 264.072624 -49.185576)
		(end 264.72896 -48.52924)
		(width 0.0889)
		(layer "In2.Cu")
		(net "M_C_MA<14>")
	)
	(segment
		(start 271.472406 -0.02921)
		(end 271.472406 -1.671066)
		(width 0.14224)
		(layer "In2.Cu")
		(net "M_C_MA<14>")
	)
	(segment
		(start 271.310354 0.132842)
		(end 271.472406 -0.02921)
		(width 0.14224)
		(layer "In2.Cu")
		(net "M_C_MA<14>")
	)
	(segment
		(start 268.1986 -25.875488)
		(end 269.715996 -24.358092)
		(width 0.14224)
		(layer "In2.Cu")
		(net "M_C_MA<14>")
	)
	(segment
		(start 269.842234 -12.312396)
		(end 269.942564 -12.212066)
		(width 0.14224)
		(layer "In2.Cu")
		(net "M_C_MA<14>")
	)
	(segment
		(start 270.349726 -2.317496)
		(end 270.350234 -2.316988)
		(width 0.14224)
		(layer "In2.Cu")
		(net "M_C_MA<14>")
	)
	(segment
		(start 269.715996 -24.358092)
		(end 269.715996 -23.411434)
		(width 0.14224)
		(layer "In2.Cu")
		(net "M_C_MA<14>")
	)
	(arc
		(start 263.435846 -53.800502)
		(mid 263.484601 -53.60415)
		(end 263.43102 -53.409088)
		(width 0.0889)
		(layer "In2.Cu")
		(net "M_C_MA<14>")
	)
	(arc
		(start 263.43102 -53.409088)
		(mid 263.351889 -53.113686)
		(end 263.43102 -52.818284)
		(width 0.0889)
		(layer "In2.Cu")
		(net "M_C_MA<14>")
	)
	(arc
		(start 263.43102 -55.390288)
		(mid 263.351798 -55.10117)
		(end 263.42467 -54.810406)
		(width 0.0889)
		(layer "In2.Cu")
		(net "M_C_MA<14>")
	)
	(arc
		(start 263.43102 -54.399688)
		(mid 263.351798 -54.11057)
		(end 263.42467 -53.819806)
		(width 0.0889)
		(layer "In2.Cu")
		(net "M_C_MA<14>")
	)
	(arc
		(start 263.435846 -56.772302)
		(mid 263.484601 -56.57595)
		(end 263.43102 -56.380888)
		(width 0.0889)
		(layer "In2.Cu")
		(net "M_C_MA<14>")
	)
	(arc
		(start 263.43102 -56.380888)
		(mid 263.351798 -56.09177)
		(end 263.42467 -55.801006)
		(width 0.0889)
		(layer "In2.Cu")
		(net "M_C_MA<14>")
	)
	(arc
		(start 263.435846 -54.791102)
		(mid 263.484601 -54.59475)
		(end 263.43102 -54.399688)
		(width 0.0889)
		(layer "In2.Cu")
		(net "M_C_MA<14>")
	)
	(arc
		(start 263.435846 -57.762902)
		(mid 263.484601 -57.56655)
		(end 263.43102 -57.371488)
		(width 0.0889)
		(layer "In2.Cu")
		(net "M_C_MA<14>")
	)
	(arc
		(start 263.435846 -55.781702)
		(mid 263.484601 -55.58535)
		(end 263.43102 -55.390288)
		(width 0.0889)
		(layer "In2.Cu")
		(net "M_C_MA<14>")
	)
	(arc
		(start 263.43102 -57.371488)
		(mid 263.351798 -57.08237)
		(end 263.42467 -56.791606)
		(width 0.0889)
		(layer "In2.Cu")
		(net "M_C_MA<14>")
	)
	(segment
		(start 273.74977 -0.821182)
		(end 273.74977 0.442722)
		(width 0.1651)
		(layer "F.Cu")
		(net "M_C_MA<13>")
	)
	(segment
		(start 261.08025 -61.038486)
		(end 260.50875 -61.038486)
		(width 0.1016)
		(layer "F.Cu")
		(net "M_C_MA<13>")
	)
	(segment
		(start 273.750278 -0.821182)
		(end 273.74977 -0.821182)
		(width 0.1651)
		(layer "F.Cu")
		(net "M_C_MA<13>")
	)
	(via
		(at 273.74977 0.442722)
		(size 0.508)
		(drill 0.254)
		(layers "F.Cu" "B.Cu")
		(net "M_C_MA<13>")
	)
	(via
		(at 273.750278 -2.316988)
		(size 0.4572)
		(drill 0.2032)
		(layers "F.Cu" "B.Cu")
		(net "M_C_MA<13>")
	)
	(via
		(at 260.50875 -61.038486)
		(size 0.508)
		(drill 0.254)
		(layers "F.Cu" "B.Cu")
		(net "M_C_MA<13>")
	)
	(segment
		(start 273.750278 -1.021842)
		(end 273.74977 -1.021842)
		(width 0.1651)
		(layer "B.Cu")
		(net "M_C_MA<13>")
	)
	(segment
		(start 273.74977 -2.31648)
		(end 273.750278 -2.316988)
		(width 0.1651)
		(layer "B.Cu")
		(net "M_C_MA<13>")
	)
	(segment
		(start 273.74977 -1.021842)
		(end 273.74977 -2.31648)
		(width 0.1651)
		(layer "B.Cu")
		(net "M_C_MA<13>")
	)
	(segment
		(start 269.943834 -15.526766)
		(end 269.943834 -14.345412)
		(width 0.14224)
		(layer "In11.Cu")
		(net "M_C_MA<13>")
	)
	(segment
		(start 273.033998 -1.776476)
		(end 272.782538 -1.776476)
		(width 0.14224)
		(layer "In11.Cu")
		(net "M_C_MA<13>")
	)
	(segment
		(start 273.750278 -0.493522)
		(end 273.605498 -0.348742)
		(width 0.14224)
		(layer "In11.Cu")
		(net "M_C_MA<13>")
	)
	(segment
		(start 269.9766 -22.6314)
		(end 269.2908 -21.9456)
		(width 0.14224)
		(layer "In11.Cu")
		(net "M_C_MA<13>")
	)
	(segment
		(start 269.6972 -23.4442)
		(end 269.9766 -23.1648)
		(width 0.14224)
		(layer "In11.Cu")
		(net "M_C_MA<13>")
	)
	(segment
		(start 272.627598 -1.621536)
		(end 272.627598 0.144526)
		(width 0.14224)
		(layer "In11.Cu")
		(net "M_C_MA<13>")
	)
	(segment
		(start 269.7734 -11.5316)
		(end 269.7734 -9.758172)
		(width 0.14224)
		(layer "In11.Cu")
		(net "M_C_MA<13>")
	)
	(segment
		(start 273.605498 -0.348742)
		(end 273.354038 -0.348742)
		(width 0.14224)
		(layer "In11.Cu")
		(net "M_C_MA<13>")
	)
	(segment
		(start 267.236702 -28.388056)
		(end 268.515846 -28.388056)
		(width 0.14224)
		(layer "In11.Cu")
		(net "M_C_MA<13>")
	)
	(segment
		(start 270.764 -7.9756)
		(end 270.764 -6.872732)
		(width 0.14224)
		(layer "In11.Cu")
		(net "M_C_MA<13>")
	)
	(segment
		(start 262.6868 -50.47488)
		(end 263.176004 -49.985676)
		(width 0.0889)
		(layer "In11.Cu")
		(net "M_C_MA<13>")
	)
	(segment
		(start 269.9766 -23.1648)
		(end 269.9766 -22.6314)
		(width 0.14224)
		(layer "In11.Cu")
		(net "M_C_MA<13>")
	)
	(segment
		(start 273.749262 0.442214)
		(end 273.74977 0.442722)
		(width 0.14224)
		(layer "In11.Cu")
		(net "M_C_MA<13>")
	)
	(segment
		(start 260.9342 -53.9496)
		(end 261.767066 -53.116734)
		(width 0.0889)
		(layer "In11.Cu")
		(net "M_C_MA<13>")
	)
	(segment
		(start 269.934182 -14.33576)
		(end 269.934182 -11.692382)
		(width 0.14224)
		(layer "In11.Cu")
		(net "M_C_MA<13>")
	)
	(segment
		(start 269.934182 -11.692382)
		(end 269.7734 -11.5316)
		(width 0.14224)
		(layer "In11.Cu")
		(net "M_C_MA<13>")
	)
	(segment
		(start 269.090902 -16.379698)
		(end 269.943834 -15.526766)
		(width 0.14224)
		(layer "In11.Cu")
		(net "M_C_MA<13>")
	)
	(segment
		(start 273.188938 -0.513842)
		(end 273.188938 -1.621536)
		(width 0.14224)
		(layer "In11.Cu")
		(net "M_C_MA<13>")
	)
	(segment
		(start 269.93977 -9.591802)
		(end 269.93977 -8.79983)
		(width 0.14224)
		(layer "In11.Cu")
		(net "M_C_MA<13>")
	)
	(segment
		(start 261.767066 -52.402486)
		(end 262.6868 -51.482752)
		(width 0.0889)
		(layer "In11.Cu")
		(net "M_C_MA<13>")
	)
	(segment
		(start 273.188938 -1.621536)
		(end 273.033998 -1.776476)
		(width 0.14224)
		(layer "In11.Cu")
		(net "M_C_MA<13>")
	)
	(segment
		(start 269.93977 -8.79983)
		(end 270.764 -7.9756)
		(width 0.14224)
		(layer "In11.Cu")
		(net "M_C_MA<13>")
	)
	(segment
		(start 269.204186 -18.08861)
		(end 269.204186 -17.300702)
		(width 0.14224)
		(layer "In11.Cu")
		(net "M_C_MA<13>")
	)
	(segment
		(start 269.943834 -14.345412)
		(end 269.934182 -14.33576)
		(width 0.14224)
		(layer "In11.Cu")
		(net "M_C_MA<13>")
	)
	(segment
		(start 263.176004 -49.539398)
		(end 263.176004 -32.448754)
		(width 0.14224)
		(layer "In11.Cu")
		(net "M_C_MA<13>")
	)
	(segment
		(start 273.750278 -2.316988)
		(end 273.750278 -0.493522)
		(width 0.14224)
		(layer "In11.Cu")
		(net "M_C_MA<13>")
	)
	(segment
		(start 269.0114 -21.675852)
		(end 269.0114 -19.1262)
		(width 0.14224)
		(layer "In11.Cu")
		(net "M_C_MA<13>")
	)
	(segment
		(start 272.925286 0.442214)
		(end 273.749262 0.442214)
		(width 0.14224)
		(layer "In11.Cu")
		(net "M_C_MA<13>")
	)
	(segment
		(start 269.2908 -21.9456)
		(end 269.281148 -21.9456)
		(width 0.14224)
		(layer "In11.Cu")
		(net "M_C_MA<13>")
	)
	(segment
		(start 269.0114 -19.1262)
		(end 269.08506 -19.05254)
		(width 0.14224)
		(layer "In11.Cu")
		(net "M_C_MA<13>")
	)
	(segment
		(start 269.7734 -9.758172)
		(end 269.93977 -9.591802)
		(width 0.14224)
		(layer "In11.Cu")
		(net "M_C_MA<13>")
	)
	(segment
		(start 272.627598 0.144526)
		(end 272.925286 0.442214)
		(width 0.14224)
		(layer "In11.Cu")
		(net "M_C_MA<13>")
	)
	(segment
		(start 273.74977 -2.317496)
		(end 273.750278 -2.316988)
		(width 0.14224)
		(layer "In11.Cu")
		(net "M_C_MA<13>")
	)
	(segment
		(start 269.08506 -18.207736)
		(end 269.204186 -18.08861)
		(width 0.14224)
		(layer "In11.Cu")
		(net "M_C_MA<13>")
	)
	(segment
		(start 273.74977 -2.662682)
		(end 273.74977 -2.317496)
		(width 0.14224)
		(layer "In11.Cu")
		(net "M_C_MA<13>")
	)
	(segment
		(start 263.176004 -32.448754)
		(end 267.236702 -28.388056)
		(width 0.14224)
		(layer "In11.Cu")
		(net "M_C_MA<13>")
	)
	(segment
		(start 272.782538 -1.776476)
		(end 272.627598 -1.621536)
		(width 0.14224)
		(layer "In11.Cu")
		(net "M_C_MA<13>")
	)
	(segment
		(start 269.090902 -17.187418)
		(end 269.090902 -16.379698)
		(width 0.14224)
		(layer "In11.Cu")
		(net "M_C_MA<13>")
	)
	(segment
		(start 270.764 -6.872732)
		(end 272.474944 -5.161788)
		(width 0.14224)
		(layer "In11.Cu")
		(net "M_C_MA<13>")
	)
	(segment
		(start 261.767066 -53.116734)
		(end 261.767066 -52.402486)
		(width 0.0889)
		(layer "In11.Cu")
		(net "M_C_MA<13>")
	)
	(segment
		(start 260.9342 -60.613036)
		(end 260.9342 -53.9496)
		(width 0.0889)
		(layer "In11.Cu")
		(net "M_C_MA<13>")
	)
	(segment
		(start 268.515846 -28.388056)
		(end 269.6972 -27.206702)
		(width 0.14224)
		(layer "In11.Cu")
		(net "M_C_MA<13>")
	)
	(segment
		(start 262.6868 -51.482752)
		(end 262.6868 -50.47488)
		(width 0.0889)
		(layer "In11.Cu")
		(net "M_C_MA<13>")
	)
	(segment
		(start 269.204186 -17.300702)
		(end 269.090902 -17.187418)
		(width 0.14224)
		(layer "In11.Cu")
		(net "M_C_MA<13>")
	)
	(segment
		(start 263.176004 -49.985676)
		(end 263.176004 -49.539398)
		(width 0.0889)
		(layer "In11.Cu")
		(net "M_C_MA<13>")
	)
	(segment
		(start 260.50875 -61.038486)
		(end 260.9342 -60.613036)
		(width 0.0889)
		(layer "In11.Cu")
		(net "M_C_MA<13>")
	)
	(segment
		(start 272.474944 -5.161788)
		(end 272.474944 -3.937508)
		(width 0.14224)
		(layer "In11.Cu")
		(net "M_C_MA<13>")
	)
	(segment
		(start 269.08506 -19.05254)
		(end 269.08506 -18.207736)
		(width 0.14224)
		(layer "In11.Cu")
		(net "M_C_MA<13>")
	)
	(segment
		(start 269.281148 -21.9456)
		(end 269.0114 -21.675852)
		(width 0.14224)
		(layer "In11.Cu")
		(net "M_C_MA<13>")
	)
	(segment
		(start 272.474944 -3.937508)
		(end 273.74977 -2.662682)
		(width 0.14224)
		(layer "In11.Cu")
		(net "M_C_MA<13>")
	)
	(segment
		(start 269.6972 -27.206702)
		(end 269.6972 -23.4442)
		(width 0.14224)
		(layer "In11.Cu")
		(net "M_C_MA<13>")
	)
	(segment
		(start 273.354038 -0.348742)
		(end 273.188938 -0.513842)
		(width 0.14224)
		(layer "In11.Cu")
		(net "M_C_MA<13>")
	)
	(segment
		(start 249.099832 3.778758)
		(end 249.099832 2.485644)
		(width 0.1651)
		(layer "F.Cu")
		(net "M_C_MA<12>")
	)
	(segment
		(start 253.353824 -62.52464)
		(end 252.782324 -62.52464)
		(width 0.0889)
		(layer "F.Cu")
		(net "M_C_MA<12>")
	)
	(segment
		(start 249.10034 3.778758)
		(end 249.099832 3.778758)
		(width 0.1651)
		(layer "F.Cu")
		(net "M_C_MA<12>")
	)
	(via
		(at 249.099832 -4.332478)
		(size 0.4572)
		(drill 0.2032)
		(layers "F.Cu" "B.Cu")
		(net "M_C_MA<12>")
	)
	(via
		(at 249.099832 2.485644)
		(size 0.508)
		(drill 0.254)
		(layers "F.Cu" "B.Cu")
		(net "M_C_MA<12>")
	)
	(via
		(at 252.782324 -62.52464)
		(size 0.508)
		(drill 0.254)
		(layers "F.Cu" "B.Cu")
		(net "M_C_MA<12>")
	)
	(segment
		(start 249.099832 -5.621782)
		(end 249.099832 -4.332478)
		(width 0.1651)
		(layer "B.Cu")
		(net "M_C_MA<12>")
	)
	(segment
		(start 249.10034 -5.621782)
		(end 249.099832 -5.621782)
		(width 0.1651)
		(layer "B.Cu")
		(net "M_C_MA<12>")
	)
	(segment
		(start 255.50876 -15.63116)
		(end 255.50876 -13.80236)
		(width 0.14224)
		(layer "In11.Cu")
		(net "M_C_MA<12>")
	)
	(segment
		(start 248.8184 -2.7686)
		(end 248.8184 -4.051046)
		(width 0.14224)
		(layer "In11.Cu")
		(net "M_C_MA<12>")
	)
	(segment
		(start 256.912364 -17.034764)
		(end 255.50876 -15.63116)
		(width 0.14224)
		(layer "In11.Cu")
		(net "M_C_MA<12>")
	)
	(segment
		(start 249.099832 1.889506)
		(end 248.629932 1.419606)
		(width 0.14224)
		(layer "In11.Cu")
		(net "M_C_MA<12>")
	)
	(segment
		(start 248.629932 1.419606)
		(end 248.629932 0.747268)
		(width 0.14224)
		(layer "In11.Cu")
		(net "M_C_MA<12>")
	)
	(segment
		(start 256.193036 -19.30908)
		(end 256.912364 -18.589752)
		(width 0.14224)
		(layer "In11.Cu")
		(net "M_C_MA<12>")
	)
	(segment
		(start 252.0696 -6.275832)
		(end 251.367798 -5.57403)
		(width 0.14224)
		(layer "In11.Cu")
		(net "M_C_MA<12>")
	)
	(segment
		(start 253.438152 -61.6839)
		(end 256.06883 -60.160154)
		(width 0.0889)
		(layer "In11.Cu")
		(net "M_C_MA<12>")
	)
	(segment
		(start 252.0696 -7.39648)
		(end 252.0696 -6.275832)
		(width 0.14224)
		(layer "In11.Cu")
		(net "M_C_MA<12>")
	)
	(segment
		(start 256.65049 -52.02682)
		(end 256.902204 -50.808382)
		(width 0.0889)
		(layer "In11.Cu")
		(net "M_C_MA<12>")
	)
	(segment
		(start 256.193036 -21.090636)
		(end 256.193036 -19.30908)
		(width 0.14224)
		(layer "In11.Cu")
		(net "M_C_MA<12>")
	)
	(segment
		(start 256.419604 -21.317204)
		(end 256.193036 -21.090636)
		(width 0.14224)
		(layer "In11.Cu")
		(net "M_C_MA<12>")
	)
	(segment
		(start 256.06883 -60.160154)
		(end 256.272284 -60.050426)
		(width 0.0889)
		(layer "In11.Cu")
		(net "M_C_MA<12>")
	)
	(segment
		(start 248.659396 -2.064004)
		(end 248.659396 -2.609596)
		(width 0.14224)
		(layer "In11.Cu")
		(net "M_C_MA<12>")
	)
	(segment
		(start 253.76124 -8.85444)
		(end 253.2634 -8.3566)
		(width 0.14224)
		(layer "In11.Cu")
		(net "M_C_MA<12>")
	)
	(segment
		(start 253.02972 -8.3566)
		(end 252.0696 -7.39648)
		(width 0.14224)
		(layer "In11.Cu")
		(net "M_C_MA<12>")
	)
	(segment
		(start 253.27737 -61.858652)
		(end 253.294134 -61.829188)
		(width 0.0889)
		(layer "In11.Cu")
		(net "M_C_MA<12>")
	)
	(segment
		(start 256.912364 -18.589752)
		(end 256.912364 -17.034764)
		(width 0.14224)
		(layer "In11.Cu")
		(net "M_C_MA<12>")
	)
	(segment
		(start 248.793 -1.9304)
		(end 248.659396 -2.064004)
		(width 0.14224)
		(layer "In11.Cu")
		(net "M_C_MA<12>")
	)
	(segment
		(start 256.419604 -24.532844)
		(end 256.419604 -21.317204)
		(width 0.14224)
		(layer "In11.Cu")
		(net "M_C_MA<12>")
	)
	(segment
		(start 254.0762 -12.6238)
		(end 253.76124 -12.30884)
		(width 0.14224)
		(layer "In11.Cu")
		(net "M_C_MA<12>")
	)
	(segment
		(start 256.65049 -59.55792)
		(end 256.65049 -52.02682)
		(width 0.0889)
		(layer "In11.Cu")
		(net "M_C_MA<12>")
	)
	(segment
		(start 256.902204 -25.015444)
		(end 256.419604 -24.532844)
		(width 0.14224)
		(layer "In11.Cu")
		(net "M_C_MA<12>")
	)
	(segment
		(start 256.272284 -60.050426)
		(end 256.55143 -59.81319)
		(width 0.0889)
		(layer "In11.Cu")
		(net "M_C_MA<12>")
	)
	(segment
		(start 255.50876 -13.80236)
		(end 254.3302 -12.6238)
		(width 0.14224)
		(layer "In11.Cu")
		(net "M_C_MA<12>")
	)
	(segment
		(start 248.793 0.5842)
		(end 248.793 -1.9304)
		(width 0.14224)
		(layer "In11.Cu")
		(net "M_C_MA<12>")
	)
	(segment
		(start 256.902204 -50.451258)
		(end 256.902204 -25.015444)
		(width 0.14224)
		(layer "In11.Cu")
		(net "M_C_MA<12>")
	)
	(segment
		(start 253.76124 -12.30884)
		(end 253.76124 -8.85444)
		(width 0.14224)
		(layer "In11.Cu")
		(net "M_C_MA<12>")
	)
	(segment
		(start 249.099832 2.485644)
		(end 249.099832 1.889506)
		(width 0.14224)
		(layer "In11.Cu")
		(net "M_C_MA<12>")
	)
	(segment
		(start 250.341384 -5.57403)
		(end 249.099832 -4.332478)
		(width 0.14224)
		(layer "In11.Cu")
		(net "M_C_MA<12>")
	)
	(segment
		(start 248.659396 -2.609596)
		(end 248.8184 -2.7686)
		(width 0.14224)
		(layer "In11.Cu")
		(net "M_C_MA<12>")
	)
	(segment
		(start 256.902204 -50.808382)
		(end 256.902204 -50.451258)
		(width 0.0889)
		(layer "In11.Cu")
		(net "M_C_MA<12>")
	)
	(segment
		(start 253.2634 -8.3566)
		(end 253.02972 -8.3566)
		(width 0.14224)
		(layer "In11.Cu")
		(net "M_C_MA<12>")
	)
	(segment
		(start 254.3302 -12.6238)
		(end 254.0762 -12.6238)
		(width 0.14224)
		(layer "In11.Cu")
		(net "M_C_MA<12>")
	)
	(segment
		(start 256.55143 -59.81319)
		(end 256.65049 -59.55792)
		(width 0.0889)
		(layer "In11.Cu")
		(net "M_C_MA<12>")
	)
	(segment
		(start 252.782324 -62.52464)
		(end 253.27737 -61.858652)
		(width 0.0889)
		(layer "In11.Cu")
		(net "M_C_MA<12>")
	)
	(segment
		(start 248.629932 0.747268)
		(end 248.793 0.5842)
		(width 0.14224)
		(layer "In11.Cu")
		(net "M_C_MA<12>")
	)
	(segment
		(start 251.367798 -5.57403)
		(end 250.341384 -5.57403)
		(width 0.14224)
		(layer "In11.Cu")
		(net "M_C_MA<12>")
	)
	(segment
		(start 248.8184 -4.051046)
		(end 249.099832 -4.332478)
		(width 0.14224)
		(layer "In11.Cu")
		(net "M_C_MA<12>")
	)
	(arc
		(start 253.294134 -61.829188)
		(mid 253.356699 -61.747182)
		(end 253.438152 -61.6839)
		(width 0.0889)
		(layer "In11.Cu")
		(net "M_C_MA<12>")
	)
	(segment
		(start 249.94997 -0.821182)
		(end 249.94997 0.442722)
		(width 0.1651)
		(layer "F.Cu")
		(net "M_C_MA<11>")
	)
	(segment
		(start 255.07061 -62.52464)
		(end 254.49911 -62.52464)
		(width 0.0889)
		(layer "F.Cu")
		(net "M_C_MA<11>")
	)
	(segment
		(start 249.950478 -0.821182)
		(end 249.94997 -0.821182)
		(width 0.1651)
		(layer "F.Cu")
		(net "M_C_MA<11>")
	)
	(via
		(at 254.49911 -62.52464)
		(size 0.508)
		(drill 0.254)
		(layers "F.Cu" "B.Cu")
		(net "M_C_MA<11>")
	)
	(via
		(at 249.94997 0.442722)
		(size 0.508)
		(drill 0.254)
		(layers "F.Cu" "B.Cu")
		(net "M_C_MA<11>")
	)
	(via
		(at 249.949716 -2.314956)
		(size 0.4572)
		(drill 0.2032)
		(layers "F.Cu" "B.Cu")
		(net "M_C_MA<11>")
	)
	(segment
		(start 249.950478 -1.021842)
		(end 249.94997 -1.021842)
		(width 0.1651)
		(layer "B.Cu")
		(net "M_C_MA<11>")
	)
	(segment
		(start 249.94997 -1.021842)
		(end 249.94997 -2.314702)
		(width 0.1651)
		(layer "B.Cu")
		(net "M_C_MA<11>")
	)
	(segment
		(start 249.94997 -2.314702)
		(end 249.949716 -2.314956)
		(width 0.1651)
		(layer "B.Cu")
		(net "M_C_MA<11>")
	)
	(segment
		(start 250.672092 -1.418336)
		(end 250.827032 -1.263396)
		(width 0.14224)
		(layer "In11.Cu")
		(net "M_C_MA<11>")
	)
	(segment
		(start 257.683 -51.994562)
		(end 257.5306 -51.731672)
		(width 0.0889)
		(layer "In11.Cu")
		(net "M_C_MA<11>")
	)
	(segment
		(start 259.595874 -22.639274)
		(end 259.4356 -22.479)
		(width 0.14224)
		(layer "In11.Cu")
		(net "M_C_MA<11>")
	)
	(segment
		(start 249.949716 -0.470916)
		(end 249.949716 0.442468)
		(width 0.14224)
		(layer "In11.Cu")
		(net "M_C_MA<11>")
	)
	(segment
		(start 257.152394 -61.629036)
		(end 257.53314 -61.24829)
		(width 0.0889)
		(layer "In11.Cu")
		(net "M_C_MA<11>")
	)
	(segment
		(start 249.949716 -2.314956)
		(end 249.949716 -1.573276)
		(width 0.14224)
		(layer "In11.Cu")
		(net "M_C_MA<11>")
	)
	(segment
		(start 257.58648 -54.400196)
		(end 257.683 -54.242716)
		(width 0.0889)
		(layer "In11.Cu")
		(net "M_C_MA<11>")
	)
	(segment
		(start 253.115826 -3.459226)
		(end 252.8316 -3.175)
		(width 0.14224)
		(layer "In11.Cu")
		(net "M_C_MA<11>")
	)
	(segment
		(start 255.586484 -9.241282)
		(end 255.586484 -8.546084)
		(width 0.14224)
		(layer "In11.Cu")
		(net "M_C_MA<11>")
	)
	(segment
		(start 255.51384 -62.52464)
		(end 255.9304 -62.9412)
		(width 0.0889)
		(layer "In11.Cu")
		(net "M_C_MA<11>")
	)
	(segment
		(start 254.635 -4.055872)
		(end 254.038354 -3.459226)
		(width 0.14224)
		(layer "In11.Cu")
		(net "M_C_MA<11>")
	)
	(segment
		(start 259.4356 -19.074384)
		(end 259.4356 -13.3096)
		(width 0.14224)
		(layer "In11.Cu")
		(net "M_C_MA<11>")
	)
	(segment
		(start 250.104656 -1.418336)
		(end 250.672092 -1.418336)
		(width 0.14224)
		(layer "In11.Cu")
		(net "M_C_MA<11>")
	)
	(segment
		(start 259.4356 -13.3096)
		(end 259.8928 -12.8524)
		(width 0.14224)
		(layer "In11.Cu")
		(net "M_C_MA<11>")
	)
	(segment
		(start 257.5306 -51.3588)
		(end 257.984498 -50.904902)
		(width 0.0889)
		(layer "In11.Cu")
		(net "M_C_MA<11>")
	)
	(segment
		(start 257.683 -54.242716)
		(end 257.683 -51.994562)
		(width 0.0889)
		(layer "In11.Cu")
		(net "M_C_MA<11>")
	)
	(segment
		(start 257.5306 -51.731672)
		(end 257.5306 -51.3588)
		(width 0.0889)
		(layer "In11.Cu")
		(net "M_C_MA<11>")
	)
	(segment
		(start 259.4356 -22.479)
		(end 259.4356 -20.33905)
		(width 0.14224)
		(layer "In11.Cu")
		(net "M_C_MA<11>")
	)
	(segment
		(start 252.8316 -3.175)
		(end 250.80976 -3.175)
		(width 0.14224)
		(layer "In11.Cu")
		(net "M_C_MA<11>")
	)
	(segment
		(start 250.827032 -1.263396)
		(end 250.827032 -0.780796)
		(width 0.14224)
		(layer "In11.Cu")
		(net "M_C_MA<11>")
	)
	(segment
		(start 259.119624 -11.1252)
		(end 257.470402 -11.1252)
		(width 0.14224)
		(layer "In11.Cu")
		(net "M_C_MA<11>")
	)
	(segment
		(start 259.8928 -11.898376)
		(end 259.119624 -11.1252)
		(width 0.14224)
		(layer "In11.Cu")
		(net "M_C_MA<11>")
	)
	(segment
		(start 257.470402 -11.1252)
		(end 255.586484 -9.241282)
		(width 0.14224)
		(layer "In11.Cu")
		(net "M_C_MA<11>")
	)
	(segment
		(start 257.984498 -50.432716)
		(end 257.984498 -26.001726)
		(width 0.14224)
		(layer "In11.Cu")
		(net "M_C_MA<11>")
	)
	(segment
		(start 259.4356 -20.33905)
		(end 259.207 -20.11045)
		(width 0.14224)
		(layer "In11.Cu")
		(net "M_C_MA<11>")
	)
	(segment
		(start 249.949716 -1.573276)
		(end 250.104656 -1.418336)
		(width 0.14224)
		(layer "In11.Cu")
		(net "M_C_MA<11>")
	)
	(segment
		(start 257.063494 -61.629036)
		(end 257.152394 -61.629036)
		(width 0.0889)
		(layer "In11.Cu")
		(net "M_C_MA<11>")
	)
	(segment
		(start 254.038354 -3.459226)
		(end 253.115826 -3.459226)
		(width 0.14224)
		(layer "In11.Cu")
		(net "M_C_MA<11>")
	)
	(segment
		(start 259.207 -19.302984)
		(end 259.4356 -19.074384)
		(width 0.14224)
		(layer "In11.Cu")
		(net "M_C_MA<11>")
	)
	(segment
		(start 255.9304 -62.9412)
		(end 256.3876 -62.9412)
		(width 0.0889)
		(layer "In11.Cu")
		(net "M_C_MA<11>")
	)
	(segment
		(start 259.8928 -12.8524)
		(end 259.8928 -11.898376)
		(width 0.14224)
		(layer "In11.Cu")
		(net "M_C_MA<11>")
	)
	(segment
		(start 256.3876 -62.9412)
		(end 256.674366 -62.654434)
		(width 0.0889)
		(layer "In11.Cu")
		(net "M_C_MA<11>")
	)
	(segment
		(start 257.984498 -50.904902)
		(end 257.984498 -50.432716)
		(width 0.0889)
		(layer "In11.Cu")
		(net "M_C_MA<11>")
	)
	(segment
		(start 250.80976 -3.175)
		(end 249.949716 -2.314956)
		(width 0.14224)
		(layer "In11.Cu")
		(net "M_C_MA<11>")
	)
	(segment
		(start 255.586484 -8.546084)
		(end 254.635 -7.5946)
		(width 0.14224)
		(layer "In11.Cu")
		(net "M_C_MA<11>")
	)
	(segment
		(start 259.207 -20.11045)
		(end 259.207 -19.302984)
		(width 0.14224)
		(layer "In11.Cu")
		(net "M_C_MA<11>")
	)
	(segment
		(start 250.104656 -0.625856)
		(end 249.949716 -0.470916)
		(width 0.14224)
		(layer "In11.Cu")
		(net "M_C_MA<11>")
	)
	(segment
		(start 250.672092 -0.625856)
		(end 250.104656 -0.625856)
		(width 0.14224)
		(layer "In11.Cu")
		(net "M_C_MA<11>")
	)
	(segment
		(start 254.635 -7.5946)
		(end 254.635 -4.055872)
		(width 0.14224)
		(layer "In11.Cu")
		(net "M_C_MA<11>")
	)
	(segment
		(start 259.595874 -24.39035)
		(end 259.595874 -22.639274)
		(width 0.14224)
		(layer "In11.Cu")
		(net "M_C_MA<11>")
	)
	(segment
		(start 254.49911 -62.52464)
		(end 255.51384 -62.52464)
		(width 0.0889)
		(layer "In11.Cu")
		(net "M_C_MA<11>")
	)
	(segment
		(start 257.984498 -26.001726)
		(end 259.595874 -24.39035)
		(width 0.14224)
		(layer "In11.Cu")
		(net "M_C_MA<11>")
	)
	(segment
		(start 249.949716 0.442468)
		(end 249.94997 0.442722)
		(width 0.14224)
		(layer "In11.Cu")
		(net "M_C_MA<11>")
	)
	(segment
		(start 257.53314 -61.24829)
		(end 257.53314 -60.55487)
		(width 0.0889)
		(layer "In11.Cu")
		(net "M_C_MA<11>")
	)
	(segment
		(start 250.827032 -0.780796)
		(end 250.672092 -0.625856)
		(width 0.14224)
		(layer "In11.Cu")
		(net "M_C_MA<11>")
	)
	(segment
		(start 256.674366 -62.654434)
		(end 256.674366 -62.0268)
		(width 0.0889)
		(layer "In11.Cu")
		(net "M_C_MA<11>")
	)
	(arc
		(start 257.58648 -55.790592)
		(mid 257.532981 -55.590694)
		(end 257.58648 -55.390796)
		(width 0.0889)
		(layer "In11.Cu")
		(net "M_C_MA<11>")
	)
	(arc
		(start 257.58648 -59.752992)
		(mid 257.532981 -59.553094)
		(end 257.58648 -59.353196)
		(width 0.0889)
		(layer "In11.Cu")
		(net "M_C_MA<11>")
	)
	(arc
		(start 257.58648 -60.343796)
		(mid 257.665611 -60.048394)
		(end 257.58648 -59.752992)
		(width 0.0889)
		(layer "In11.Cu")
		(net "M_C_MA<11>")
	)
	(arc
		(start 257.58648 -58.362596)
		(mid 257.665611 -58.067194)
		(end 257.58648 -57.771792)
		(width 0.0889)
		(layer "In11.Cu")
		(net "M_C_MA<11>")
	)
	(arc
		(start 257.58648 -58.762392)
		(mid 257.532981 -58.562494)
		(end 257.58648 -58.362596)
		(width 0.0889)
		(layer "In11.Cu")
		(net "M_C_MA<11>")
	)
	(arc
		(start 257.58648 -56.381396)
		(mid 257.665611 -56.085994)
		(end 257.58648 -55.790592)
		(width 0.0889)
		(layer "In11.Cu")
		(net "M_C_MA<11>")
	)
	(arc
		(start 257.53314 -60.55487)
		(mid 257.545183 -60.445637)
		(end 257.58648 -60.343796)
		(width 0.0889)
		(layer "In11.Cu")
		(net "M_C_MA<11>")
	)
	(arc
		(start 257.58648 -54.799992)
		(mid 257.532981 -54.600094)
		(end 257.58648 -54.400196)
		(width 0.0889)
		(layer "In11.Cu")
		(net "M_C_MA<11>")
	)
	(arc
		(start 257.58648 -57.371996)
		(mid 257.665611 -57.076594)
		(end 257.58648 -56.781192)
		(width 0.0889)
		(layer "In11.Cu")
		(net "M_C_MA<11>")
	)
	(arc
		(start 257.58648 -56.781192)
		(mid 257.532981 -56.581294)
		(end 257.58648 -56.381396)
		(width 0.0889)
		(layer "In11.Cu")
		(net "M_C_MA<11>")
	)
	(arc
		(start 257.58648 -57.771792)
		(mid 257.532981 -57.571894)
		(end 257.58648 -57.371996)
		(width 0.0889)
		(layer "In11.Cu")
		(net "M_C_MA<11>")
	)
	(arc
		(start 257.58648 -55.390796)
		(mid 257.665611 -55.095394)
		(end 257.58648 -54.799992)
		(width 0.0889)
		(layer "In11.Cu")
		(net "M_C_MA<11>")
	)
	(arc
		(start 256.674366 -62.0268)
		(mid 256.788481 -61.749186)
		(end 257.063494 -61.629036)
		(width 0.0889)
		(layer "In11.Cu")
		(net "M_C_MA<11>")
	)
	(arc
		(start 257.58648 -59.353196)
		(mid 257.665611 -59.057794)
		(end 257.58648 -58.762392)
		(width 0.0889)
		(layer "In11.Cu")
		(net "M_C_MA<11>")
	)
	(segment
		(start 259.36321 -61.038486)
		(end 258.79171 -61.038486)
		(width 0.1016)
		(layer "F.Cu")
		(net "M_C_MA<10>")
	)
	(segment
		(start 267.79982 -0.821182)
		(end 267.79982 1.152144)
		(width 0.1651)
		(layer "F.Cu")
		(net "M_C_MA<10>")
	)
	(segment
		(start 267.800328 -0.821182)
		(end 267.79982 -0.821182)
		(width 0.1651)
		(layer "F.Cu")
		(net "M_C_MA<10>")
	)
	(via
		(at 267.79982 1.152144)
		(size 0.508)
		(drill 0.254)
		(layers "F.Cu" "B.Cu")
		(net "M_C_MA<10>")
	)
	(via
		(at 258.79171 -61.038486)
		(size 0.508)
		(drill 0.254)
		(layers "F.Cu" "B.Cu")
		(net "M_C_MA<10>")
	)
	(via
		(at 267.800074 -2.316988)
		(size 0.4572)
		(drill 0.2032)
		(layers "F.Cu" "B.Cu")
		(net "M_C_MA<10>")
	)
	(segment
		(start 267.79982 -2.316734)
		(end 267.800074 -2.316988)
		(width 0.1651)
		(layer "B.Cu")
		(net "M_C_MA<10>")
	)
	(segment
		(start 267.800328 -1.021842)
		(end 267.79982 -1.021842)
		(width 0.1651)
		(layer "B.Cu")
		(net "M_C_MA<10>")
	)
	(segment
		(start 267.79982 -1.021842)
		(end 267.79982 -2.316734)
		(width 0.1651)
		(layer "B.Cu")
		(net "M_C_MA<10>")
	)
	(segment
		(start 258.39166 -53.901594)
		(end 258.572 -53.721254)
		(width 0.0889)
		(layer "In11.Cu")
		(net "M_C_MA<10>")
	)
	(segment
		(start 264.285984 -9.922764)
		(end 264.285984 -9.703816)
		(width 0.14224)
		(layer "In11.Cu")
		(net "M_C_MA<10>")
	)
	(segment
		(start 263.506458 -10.483342)
		(end 263.725406 -10.483342)
		(width 0.14224)
		(layer "In11.Cu")
		(net "M_C_MA<10>")
	)
	(segment
		(start 267.800074 1.15189)
		(end 267.79982 1.152144)
		(width 0.14224)
		(layer "In11.Cu")
		(net "M_C_MA<10>")
	)
	(segment
		(start 259.010404 -50.432716)
		(end 259.010404 -26.746708)
		(width 0.14224)
		(layer "In11.Cu")
		(net "M_C_MA<10>")
	)
	(segment
		(start 264.760456 -10.397236)
		(end 264.285984 -9.922764)
		(width 0.14224)
		(layer "In11.Cu")
		(net "M_C_MA<10>")
	)
	(segment
		(start 258.46151 -60.27674)
		(end 258.445 -60.248292)
		(width 0.0889)
		(layer "In11.Cu")
		(net "M_C_MA<10>")
	)
	(segment
		(start 263.725406 -10.483342)
		(end 264.19302 -10.950956)
		(width 0.14224)
		(layer "In11.Cu")
		(net "M_C_MA<10>")
	)
	(segment
		(start 264.19302 -10.950956)
		(end 264.386568 -10.950956)
		(width 0.14224)
		(layer "In11.Cu")
		(net "M_C_MA<10>")
	)
	(segment
		(start 264.7061 -9.2837)
		(end 264.7061 -7.654036)
		(width 0.14224)
		(layer "In11.Cu")
		(net "M_C_MA<10>")
	)
	(segment
		(start 267.384784 -4.975352)
		(end 267.384784 -4.062984)
		(width 0.14224)
		(layer "In11.Cu")
		(net "M_C_MA<10>")
	)
	(segment
		(start 260.858 -24.899112)
		(end 260.858 -21.6408)
		(width 0.14224)
		(layer "In11.Cu")
		(net "M_C_MA<10>")
	)
	(segment
		(start 261.239 -13.9827)
		(end 262.4582 -12.7635)
		(width 0.14224)
		(layer "In11.Cu")
		(net "M_C_MA<10>")
	)
	(segment
		(start 261.0358 -18.4658)
		(end 261.239 -18.2626)
		(width 0.14224)
		(layer "In11.Cu")
		(net "M_C_MA<10>")
	)
	(segment
		(start 259.010404 -50.793396)
		(end 259.010404 -50.432716)
		(width 0.0889)
		(layer "In11.Cu")
		(net "M_C_MA<10>")
	)
	(segment
		(start 267.800074 -2.887726)
		(end 267.800074 -2.316988)
		(width 0.14224)
		(layer "In11.Cu")
		(net "M_C_MA<10>")
	)
	(segment
		(start 261.239 -18.2626)
		(end 261.239 -13.9827)
		(width 0.14224)
		(layer "In11.Cu")
		(net "M_C_MA<10>")
	)
	(segment
		(start 258.572 -51.2318)
		(end 259.010404 -50.793396)
		(width 0.0889)
		(layer "In11.Cu")
		(net "M_C_MA<10>")
	)
	(segment
		(start 258.79171 -61.038486)
		(end 258.46151 -60.27674)
		(width 0.0889)
		(layer "In11.Cu")
		(net "M_C_MA<10>")
	)
	(segment
		(start 264.760456 -10.577068)
		(end 264.760456 -10.397236)
		(width 0.14224)
		(layer "In11.Cu")
		(net "M_C_MA<10>")
	)
	(segment
		(start 264.386568 -10.950956)
		(end 264.760456 -10.577068)
		(width 0.14224)
		(layer "In11.Cu")
		(net "M_C_MA<10>")
	)
	(segment
		(start 264.285984 -9.703816)
		(end 264.7061 -9.2837)
		(width 0.14224)
		(layer "In11.Cu")
		(net "M_C_MA<10>")
	)
	(segment
		(start 258.572 -53.721254)
		(end 258.572 -51.2318)
		(width 0.0889)
		(layer "In11.Cu")
		(net "M_C_MA<10>")
	)
	(segment
		(start 258.39166 -54.095396)
		(end 258.39166 -53.901594)
		(width 0.0889)
		(layer "In11.Cu")
		(net "M_C_MA<10>")
	)
	(segment
		(start 262.4582 -12.7635)
		(end 262.4582 -11.5316)
		(width 0.14224)
		(layer "In11.Cu")
		(net "M_C_MA<10>")
	)
	(segment
		(start 267.2842 -3.4036)
		(end 267.800074 -2.887726)
		(width 0.14224)
		(layer "In11.Cu")
		(net "M_C_MA<10>")
	)
	(segment
		(start 267.384784 -4.062984)
		(end 267.2842 -3.9624)
		(width 0.14224)
		(layer "In11.Cu")
		(net "M_C_MA<10>")
	)
	(segment
		(start 267.800074 -2.316988)
		(end 267.800074 1.15189)
		(width 0.14224)
		(layer "In11.Cu")
		(net "M_C_MA<10>")
	)
	(segment
		(start 267.2842 -3.9624)
		(end 267.2842 -3.4036)
		(width 0.14224)
		(layer "In11.Cu")
		(net "M_C_MA<10>")
	)
	(segment
		(start 264.7061 -7.654036)
		(end 267.384784 -4.975352)
		(width 0.14224)
		(layer "In11.Cu")
		(net "M_C_MA<10>")
	)
	(segment
		(start 260.858 -21.6408)
		(end 261.0358 -21.463)
		(width 0.14224)
		(layer "In11.Cu")
		(net "M_C_MA<10>")
	)
	(segment
		(start 261.0358 -21.463)
		(end 261.0358 -18.4658)
		(width 0.14224)
		(layer "In11.Cu")
		(net "M_C_MA<10>")
	)
	(segment
		(start 259.010404 -26.746708)
		(end 260.858 -24.899112)
		(width 0.14224)
		(layer "In11.Cu")
		(net "M_C_MA<10>")
	)
	(segment
		(start 262.4582 -11.5316)
		(end 263.506458 -10.483342)
		(width 0.14224)
		(layer "In11.Cu")
		(net "M_C_MA<10>")
	)
	(arc
		(start 258.445 -57.276492)
		(mid 258.391501 -57.076594)
		(end 258.445 -56.876696)
		(width 0.0889)
		(layer "In11.Cu")
		(net "M_C_MA<10>")
	)
	(arc
		(start 258.445 -59.848496)
		(mid 258.524131 -59.553094)
		(end 258.445 -59.257692)
		(width 0.0889)
		(layer "In11.Cu")
		(net "M_C_MA<10>")
	)
	(arc
		(start 258.445 -55.886096)
		(mid 258.524131 -55.590694)
		(end 258.445 -55.295292)
		(width 0.0889)
		(layer "In11.Cu")
		(net "M_C_MA<10>")
	)
	(arc
		(start 258.445 -56.285892)
		(mid 258.391501 -56.085994)
		(end 258.445 -55.886096)
		(width 0.0889)
		(layer "In11.Cu")
		(net "M_C_MA<10>")
	)
	(arc
		(start 258.445 -55.295292)
		(mid 258.391501 -55.095394)
		(end 258.445 -54.895496)
		(width 0.0889)
		(layer "In11.Cu")
		(net "M_C_MA<10>")
	)
	(arc
		(start 258.445 -56.876696)
		(mid 258.524131 -56.581294)
		(end 258.445 -56.285892)
		(width 0.0889)
		(layer "In11.Cu")
		(net "M_C_MA<10>")
	)
	(arc
		(start 258.445 -60.248292)
		(mid 258.391501 -60.048394)
		(end 258.445 -59.848496)
		(width 0.0889)
		(layer "In11.Cu")
		(net "M_C_MA<10>")
	)
	(arc
		(start 258.445 -58.267092)
		(mid 258.391501 -58.067194)
		(end 258.445 -57.867296)
		(width 0.0889)
		(layer "In11.Cu")
		(net "M_C_MA<10>")
	)
	(arc
		(start 258.445 -58.857896)
		(mid 258.524131 -58.562494)
		(end 258.445 -58.267092)
		(width 0.0889)
		(layer "In11.Cu")
		(net "M_C_MA<10>")
	)
	(arc
		(start 258.445 -54.895496)
		(mid 258.524131 -54.600094)
		(end 258.445 -54.304692)
		(width 0.0889)
		(layer "In11.Cu")
		(net "M_C_MA<10>")
	)
	(arc
		(start 258.445 -57.867296)
		(mid 258.524131 -57.571894)
		(end 258.445 -57.276492)
		(width 0.0889)
		(layer "In11.Cu")
		(net "M_C_MA<10>")
	)
	(arc
		(start 258.445 -59.257692)
		(mid 258.391501 -59.057794)
		(end 258.445 -58.857896)
		(width 0.0889)
		(layer "In11.Cu")
		(net "M_C_MA<10>")
	)
	(arc
		(start 258.445 -54.304692)
		(mid 258.403919 -54.203713)
		(end 258.39166 -54.095396)
		(width 0.0889)
		(layer "In11.Cu")
		(net "M_C_MA<10>")
	)
	(segment
		(start 266.100306 3.778758)
		(end 266.099798 3.778758)
		(width 0.1651)
		(layer "F.Cu")
		(net "M_C_MA<0>")
	)
	(segment
		(start 261.08025 -60.047886)
		(end 260.50875 -60.047886)
		(width 0.1016)
		(layer "F.Cu")
		(net "M_C_MA<0>")
	)
	(segment
		(start 266.099798 3.778758)
		(end 266.099798 2.514854)
		(width 0.1651)
		(layer "F.Cu")
		(net "M_C_MA<0>")
	)
	(via
		(at 266.099798 -4.328668)
		(size 0.4572)
		(drill 0.2032)
		(layers "F.Cu" "B.Cu")
		(net "M_C_MA<0>")
	)
	(via
		(at 260.50875 -60.047886)
		(size 0.508)
		(drill 0.254)
		(layers "F.Cu" "B.Cu")
		(net "M_C_MA<0>")
	)
	(via
		(at 266.099798 2.514854)
		(size 0.508)
		(drill 0.254)
		(layers "F.Cu" "B.Cu")
		(net "M_C_MA<0>")
	)
	(segment
		(start 266.099798 -5.621782)
		(end 266.099798 -4.328668)
		(width 0.1651)
		(layer "B.Cu")
		(net "M_C_MA<0>")
	)
	(segment
		(start 266.100306 -5.621782)
		(end 266.099798 -5.621782)
		(width 0.1651)
		(layer "B.Cu")
		(net "M_C_MA<0>")
	)
	(segment
		(start 266.454382 0.694182)
		(end 266.61491 0.85471)
		(width 0.14224)
		(layer "In2.Cu")
		(net "M_C_MA<0>")
	)
	(segment
		(start 265.749532 -9.690354)
		(end 265.661394 -9.602216)
		(width 0.14224)
		(layer "In2.Cu")
		(net "M_C_MA<0>")
	)
	(segment
		(start 261.02056 -58.362088)
		(end 261.02691 -58.35142)
		(width 0.0889)
		(layer "In2.Cu")
		(net "M_C_MA<0>")
	)
	(segment
		(start 260.50875 -60.047886)
		(end 260.96722 -59.589416)
		(width 0.0889)
		(layer "In2.Cu")
		(net "M_C_MA<0>")
	)
	(segment
		(start 265.605768 -16.105632)
		(end 265.646662 -16.064738)
		(width 0.14224)
		(layer "In2.Cu")
		(net "M_C_MA<0>")
	)
	(segment
		(start 266.099798 -2.987802)
		(end 266.534646 -2.552954)
		(width 0.14224)
		(layer "In2.Cu")
		(net "M_C_MA<0>")
	)
	(segment
		(start 265.605768 -21.811996)
		(end 265.605768 -17.769078)
		(width 0.14224)
		(layer "In2.Cu")
		(net "M_C_MA<0>")
	)
	(segment
		(start 265.938 -6.5786)
		(end 265.938 -4.490466)
		(width 0.14224)
		(layer "In2.Cu")
		(net "M_C_MA<0>")
	)
	(segment
		(start 261.02056 -57.771538)
		(end 261.015734 -57.762902)
		(width 0.0889)
		(layer "In2.Cu")
		(net "M_C_MA<0>")
	)
	(segment
		(start 261.02691 -53.819806)
		(end 261.02056 -53.809138)
		(width 0.0889)
		(layer "In2.Cu")
		(net "M_C_MA<0>")
	)
	(segment
		(start 261.02056 -56.780938)
		(end 261.015734 -56.772302)
		(width 0.0889)
		(layer "In2.Cu")
		(net "M_C_MA<0>")
	)
	(segment
		(start 265.605768 -7.355586)
		(end 265.605768 -6.910832)
		(width 0.14224)
		(layer "In2.Cu")
		(net "M_C_MA<0>")
	)
	(segment
		(start 261.02691 -56.791606)
		(end 261.02056 -56.780938)
		(width 0.0889)
		(layer "In2.Cu")
		(net "M_C_MA<0>")
	)
	(segment
		(start 265.758168 -17.109186)
		(end 265.605768 -16.956786)
		(width 0.14224)
		(layer "In2.Cu")
		(net "M_C_MA<0>")
	)
	(segment
		(start 262.18896 -50.104294)
		(end 262.18896 -48.35525)
		(width 0.0889)
		(layer "In2.Cu")
		(net "M_C_MA<0>")
	)
	(segment
		(start 265.732768 -22.421596)
		(end 265.732768 -21.938996)
		(width 0.14224)
		(layer "In2.Cu")
		(net "M_C_MA<0>")
	)
	(segment
		(start 261.4422 -51.922172)
		(end 261.4422 -50.851054)
		(width 0.0889)
		(layer "In2.Cu")
		(net "M_C_MA<0>")
	)
	(segment
		(start 265.749532 -11.004042)
		(end 265.749532 -9.690354)
		(width 0.14224)
		(layer "In2.Cu")
		(net "M_C_MA<0>")
	)
	(segment
		(start 261.089902 -52.27447)
		(end 261.4422 -51.922172)
		(width 0.0889)
		(layer "In2.Cu")
		(net "M_C_MA<0>")
	)
	(segment
		(start 261.02056 -53.809138)
		(end 261.015734 -53.800502)
		(width 0.0889)
		(layer "In2.Cu")
		(net "M_C_MA<0>")
	)
	(segment
		(start 265.554968 -22.599396)
		(end 265.732768 -22.421596)
		(width 0.14224)
		(layer "In2.Cu")
		(net "M_C_MA<0>")
	)
	(segment
		(start 261.015734 -52.427378)
		(end 261.02056 -52.418742)
		(width 0.0889)
		(layer "In2.Cu")
		(net "M_C_MA<0>")
	)
	(segment
		(start 266.454382 -0.084582)
		(end 266.454382 0.694182)
		(width 0.14224)
		(layer "In2.Cu")
		(net "M_C_MA<0>")
	)
	(segment
		(start 260.96722 -59.589416)
		(end 260.96722 -58.572146)
		(width 0.0889)
		(layer "In2.Cu")
		(net "M_C_MA<0>")
	)
	(segment
		(start 262.18896 -29.3878)
		(end 264.8204 -26.75636)
		(width 0.14224)
		(layer "In2.Cu")
		(net "M_C_MA<0>")
	)
	(segment
		(start 265.605768 -16.956786)
		(end 265.605768 -16.105632)
		(width 0.14224)
		(layer "In2.Cu")
		(net "M_C_MA<0>")
	)
	(segment
		(start 266.534646 -2.552954)
		(end 266.534646 -0.164846)
		(width 0.14224)
		(layer "In2.Cu")
		(net "M_C_MA<0>")
	)
	(segment
		(start 265.938 -4.490466)
		(end 266.099798 -4.328668)
		(width 0.14224)
		(layer "In2.Cu")
		(net "M_C_MA<0>")
	)
	(segment
		(start 265.605768 -17.769078)
		(end 265.758168 -17.616678)
		(width 0.14224)
		(layer "In2.Cu")
		(net "M_C_MA<0>")
	)
	(segment
		(start 265.646662 -16.064738)
		(end 265.646662 -12.906502)
		(width 0.14224)
		(layer "In2.Cu")
		(net "M_C_MA<0>")
	)
	(segment
		(start 266.534646 -0.164846)
		(end 266.454382 -0.084582)
		(width 0.14224)
		(layer "In2.Cu")
		(net "M_C_MA<0>")
	)
	(segment
		(start 265.661394 -9.602216)
		(end 265.661394 -7.411212)
		(width 0.14224)
		(layer "In2.Cu")
		(net "M_C_MA<0>")
	)
	(segment
		(start 265.740642 -24.597106)
		(end 265.740642 -23.31847)
		(width 0.14224)
		(layer "In2.Cu")
		(net "M_C_MA<0>")
	)
	(segment
		(start 266.099798 -4.328668)
		(end 266.099798 -2.987802)
		(width 0.14224)
		(layer "In2.Cu")
		(net "M_C_MA<0>")
	)
	(segment
		(start 265.605768 -12.210796)
		(end 265.605768 -11.147806)
		(width 0.14224)
		(layer "In2.Cu")
		(net "M_C_MA<0>")
	)
	(segment
		(start 264.8204 -25.517348)
		(end 265.740642 -24.597106)
		(width 0.14224)
		(layer "In2.Cu")
		(net "M_C_MA<0>")
	)
	(segment
		(start 265.758168 -17.616678)
		(end 265.758168 -17.109186)
		(width 0.14224)
		(layer "In2.Cu")
		(net "M_C_MA<0>")
	)
	(segment
		(start 266.099798 1.926082)
		(end 266.099798 2.514854)
		(width 0.14224)
		(layer "In2.Cu")
		(net "M_C_MA<0>")
	)
	(segment
		(start 264.8204 -26.75636)
		(end 264.8204 -25.517348)
		(width 0.14224)
		(layer "In2.Cu")
		(net "M_C_MA<0>")
	)
	(segment
		(start 262.18896 -48.35525)
		(end 262.18896 -29.3878)
		(width 0.14224)
		(layer "In2.Cu")
		(net "M_C_MA<0>")
	)
	(segment
		(start 265.732768 -12.337796)
		(end 265.605768 -12.210796)
		(width 0.14224)
		(layer "In2.Cu")
		(net "M_C_MA<0>")
	)
	(segment
		(start 261.02691 -55.801006)
		(end 261.02056 -55.790338)
		(width 0.0889)
		(layer "In2.Cu")
		(net "M_C_MA<0>")
	)
	(segment
		(start 265.740642 -23.31847)
		(end 265.554968 -23.132796)
		(width 0.14224)
		(layer "In2.Cu")
		(net "M_C_MA<0>")
	)
	(segment
		(start 265.554968 -23.132796)
		(end 265.554968 -22.599396)
		(width 0.14224)
		(layer "In2.Cu")
		(net "M_C_MA<0>")
	)
	(segment
		(start 265.661394 -7.411212)
		(end 265.605768 -7.355586)
		(width 0.14224)
		(layer "In2.Cu")
		(net "M_C_MA<0>")
	)
	(segment
		(start 265.605768 -11.147806)
		(end 265.749532 -11.004042)
		(width 0.14224)
		(layer "In2.Cu")
		(net "M_C_MA<0>")
	)
	(segment
		(start 265.646662 -12.906502)
		(end 265.732768 -12.820396)
		(width 0.14224)
		(layer "In2.Cu")
		(net "M_C_MA<0>")
	)
	(segment
		(start 265.732768 -12.820396)
		(end 265.732768 -12.337796)
		(width 0.14224)
		(layer "In2.Cu")
		(net "M_C_MA<0>")
	)
	(segment
		(start 266.61491 1.41097)
		(end 266.099798 1.926082)
		(width 0.14224)
		(layer "In2.Cu")
		(net "M_C_MA<0>")
	)
	(segment
		(start 261.02056 -54.799738)
		(end 261.015734 -54.791102)
		(width 0.0889)
		(layer "In2.Cu")
		(net "M_C_MA<0>")
	)
	(segment
		(start 265.732768 -21.938996)
		(end 265.605768 -21.811996)
		(width 0.14224)
		(layer "In2.Cu")
		(net "M_C_MA<0>")
	)
	(segment
		(start 266.61491 0.85471)
		(end 266.61491 1.41097)
		(width 0.14224)
		(layer "In2.Cu")
		(net "M_C_MA<0>")
	)
	(segment
		(start 265.605768 -6.910832)
		(end 265.938 -6.5786)
		(width 0.14224)
		(layer "In2.Cu")
		(net "M_C_MA<0>")
	)
	(segment
		(start 261.4422 -50.851054)
		(end 262.18896 -50.104294)
		(width 0.0889)
		(layer "In2.Cu")
		(net "M_C_MA<0>")
	)
	(segment
		(start 261.02056 -55.790338)
		(end 261.015734 -55.781702)
		(width 0.0889)
		(layer "In2.Cu")
		(net "M_C_MA<0>")
	)
	(segment
		(start 261.02691 -54.810406)
		(end 261.02056 -54.799738)
		(width 0.0889)
		(layer "In2.Cu")
		(net "M_C_MA<0>")
	)
	(arc
		(start 261.02056 -52.818284)
		(mid 260.967217 -52.623475)
		(end 261.015734 -52.427378)
		(width 0.0889)
		(layer "In2.Cu")
		(net "M_C_MA<0>")
	)
	(arc
		(start 261.02056 -53.409088)
		(mid 261.099691 -53.113686)
		(end 261.02056 -52.818284)
		(width 0.0889)
		(layer "In2.Cu")
		(net "M_C_MA<0>")
	)
	(arc
		(start 261.015734 -55.781702)
		(mid 260.966979 -55.58535)
		(end 261.02056 -55.390288)
		(width 0.0889)
		(layer "In2.Cu")
		(net "M_C_MA<0>")
	)
	(arc
		(start 261.02056 -52.418742)
		(mid 261.058329 -52.348095)
		(end 261.089902 -52.27447)
		(width 0.0889)
		(layer "In2.Cu")
		(net "M_C_MA<0>")
	)
	(arc
		(start 260.96722 -58.572146)
		(mid 260.979414 -58.463443)
		(end 261.02056 -58.362088)
		(width 0.0889)
		(layer "In2.Cu")
		(net "M_C_MA<0>")
	)
	(arc
		(start 261.02691 -58.35142)
		(mid 261.099708 -58.060657)
		(end 261.02056 -57.771538)
		(width 0.0889)
		(layer "In2.Cu")
		(net "M_C_MA<0>")
	)
	(arc
		(start 261.02056 -54.399688)
		(mid 261.099782 -54.11057)
		(end 261.02691 -53.819806)
		(width 0.0889)
		(layer "In2.Cu")
		(net "M_C_MA<0>")
	)
	(arc
		(start 261.02056 -57.371488)
		(mid 261.099782 -57.08237)
		(end 261.02691 -56.791606)
		(width 0.0889)
		(layer "In2.Cu")
		(net "M_C_MA<0>")
	)
	(arc
		(start 261.015734 -57.762902)
		(mid 260.966979 -57.56655)
		(end 261.02056 -57.371488)
		(width 0.0889)
		(layer "In2.Cu")
		(net "M_C_MA<0>")
	)
	(arc
		(start 261.015734 -54.791102)
		(mid 260.966979 -54.59475)
		(end 261.02056 -54.399688)
		(width 0.0889)
		(layer "In2.Cu")
		(net "M_C_MA<0>")
	)
	(arc
		(start 261.015734 -56.772302)
		(mid 260.966979 -56.57595)
		(end 261.02056 -56.380888)
		(width 0.0889)
		(layer "In2.Cu")
		(net "M_C_MA<0>")
	)
	(arc
		(start 261.02056 -56.380888)
		(mid 261.099782 -56.09177)
		(end 261.02691 -55.801006)
		(width 0.0889)
		(layer "In2.Cu")
		(net "M_C_MA<0>")
	)
	(arc
		(start 261.015734 -53.800502)
		(mid 260.966979 -53.60415)
		(end 261.02056 -53.409088)
		(width 0.0889)
		(layer "In2.Cu")
		(net "M_C_MA<0>")
	)
	(arc
		(start 261.02056 -55.390288)
		(mid 261.099782 -55.10117)
		(end 261.02691 -54.810406)
		(width 0.0889)
		(layer "In2.Cu")
		(net "M_C_MA<0>")
	)
	(segment
		(start 239.749838 3.778758)
		(end 239.749838 2.514854)
		(width 0.1651)
		(layer "F.Cu")
		(net "M_C_ECC<7>")
	)
	(segment
		(start 246.485664 -69.45884)
		(end 245.914164 -69.45884)
		(width 0.1016)
		(layer "F.Cu")
		(net "M_C_ECC<7>")
	)
	(segment
		(start 239.750346 3.778758)
		(end 239.749838 3.778758)
		(width 0.1651)
		(layer "F.Cu")
		(net "M_C_ECC<7>")
	)
	(via
		(at 240.599722 -3.076956)
		(size 0.508)
		(drill 0.254)
		(layers "F.Cu" "B.Cu")
		(net "M_C_ECC<7>")
	)
	(via
		(at 245.914164 -69.45884)
		(size 0.508)
		(drill 0.254)
		(layers "F.Cu" "B.Cu")
		(net "M_C_ECC<7>")
	)
	(via
		(at 239.749838 2.514854)
		(size 0.508)
		(drill 0.254)
		(layers "F.Cu" "B.Cu")
		(net "M_C_ECC<7>")
	)
	(segment
		(start 240.600484 -3.076194)
		(end 240.599722 -3.076956)
		(width 0.1651)
		(layer "B.Cu")
		(net "M_C_ECC<7>")
	)
	(segment
		(start 240.600484 -1.021842)
		(end 240.600484 -3.076194)
		(width 0.1651)
		(layer "B.Cu")
		(net "M_C_ECC<7>")
	)
	(segment
		(start 246.21363 -68.771516)
		(end 245.914164 -69.45884)
		(width 0.0889)
		(layer "In4.Cu")
		(net "M_C_ECC<7>")
	)
	(segment
		(start 246.425974 -64.800988)
		(end 246.421148 -64.809624)
		(width 0.0889)
		(layer "In4.Cu")
		(net "M_C_ECC<7>")
	)
	(segment
		(start 246.432324 -65.78092)
		(end 246.425974 -65.791588)
		(width 0.0889)
		(layer "In4.Cu")
		(net "M_C_ECC<7>")
	)
	(segment
		(start 246.431816 -45.568616)
		(end 247.77065 -46.90745)
		(width 0.14224)
		(layer "In4.Cu")
		(net "M_C_ECC<7>")
	)
	(segment
		(start 240.599722 -3.076956)
		(end 240.114328 -3.56235)
		(width 0.14224)
		(layer "In4.Cu")
		(net "M_C_ECC<7>")
	)
	(segment
		(start 241.166396 -26.561796)
		(end 241.166396 -27.438604)
		(width 0.14224)
		(layer "In4.Cu")
		(net "M_C_ECC<7>")
	)
	(segment
		(start 247.070118 -52.523136)
		(end 246.445024 -53.14823)
		(width 0.0889)
		(layer "In4.Cu")
		(net "M_C_ECC<7>")
	)
	(segment
		(start 246.425974 -59.847988)
		(end 246.421148 -59.856624)
		(width 0.0889)
		(layer "In4.Cu")
		(net "M_C_ECC<7>")
	)
	(segment
		(start 240.977928 -16.890746)
		(end 241.181128 -17.093946)
		(width 0.14224)
		(layer "In4.Cu")
		(net "M_C_ECC<7>")
	)
	(segment
		(start 243.8527 -34.5313)
		(end 243.8527 -43.363642)
		(width 0.14224)
		(layer "In4.Cu")
		(net "M_C_ECC<7>")
	)
	(segment
		(start 246.504714 -55.201058)
		(end 246.504714 -55.59298)
		(width 0.0889)
		(layer "In4.Cu")
		(net "M_C_ECC<7>")
	)
	(segment
		(start 241.181128 -18.355818)
		(end 240.952528 -18.584418)
		(width 0.14224)
		(layer "In4.Cu")
		(net "M_C_ECC<7>")
	)
	(segment
		(start 240.114328 -3.56235)
		(end 240.114328 -3.980688)
		(width 0.14224)
		(layer "In4.Cu")
		(net "M_C_ECC<7>")
	)
	(segment
		(start 246.425974 -60.838588)
		(end 246.421148 -60.847224)
		(width 0.0889)
		(layer "In4.Cu")
		(net "M_C_ECC<7>")
	)
	(segment
		(start 243.1542 -33.8328)
		(end 243.8527 -34.5313)
		(width 0.14224)
		(layer "In4.Cu")
		(net "M_C_ECC<7>")
	)
	(segment
		(start 241.181128 -8.729218)
		(end 240.952528 -8.957818)
		(width 0.14224)
		(layer "In4.Cu")
		(net "M_C_ECC<7>")
	)
	(segment
		(start 240.952528 -12.170156)
		(end 241.155728 -12.373356)
		(width 0.14224)
		(layer "In4.Cu")
		(net "M_C_ECC<7>")
	)
	(segment
		(start 246.425974 -58.857388)
		(end 246.421148 -58.866024)
		(width 0.0889)
		(layer "In4.Cu")
		(net "M_C_ECC<7>")
	)
	(segment
		(start 247.77065 -46.90745)
		(end 247.77065 -49.893728)
		(width 0.14224)
		(layer "In4.Cu")
		(net "M_C_ECC<7>")
	)
	(segment
		(start 246.432324 -60.82792)
		(end 246.425974 -60.838588)
		(width 0.0889)
		(layer "In4.Cu")
		(net "M_C_ECC<7>")
	)
	(segment
		(start 241.155728 -21.974556)
		(end 241.155728 -23.117556)
		(width 0.14224)
		(layer "In4.Cu")
		(net "M_C_ECC<7>")
	)
	(segment
		(start 246.42572 -56.285892)
		(end 246.425974 -56.285638)
		(width 0.0889)
		(layer "In4.Cu")
		(net "M_C_ECC<7>")
	)
	(segment
		(start 241.166396 -27.438604)
		(end 240.977928 -27.627072)
		(width 0.14224)
		(layer "In4.Cu")
		(net "M_C_ECC<7>")
	)
	(segment
		(start 243.1542 -31.75)
		(end 243.1542 -33.8328)
		(width 0.14224)
		(layer "In4.Cu")
		(net "M_C_ECC<7>")
	)
	(segment
		(start 243.8527 -43.363642)
		(end 246.057674 -45.568616)
		(width 0.14224)
		(layer "In4.Cu")
		(net "M_C_ECC<7>")
	)
	(segment
		(start 246.432324 -64.79032)
		(end 246.425974 -64.800988)
		(width 0.0889)
		(layer "In4.Cu")
		(net "M_C_ECC<7>")
	)
	(segment
		(start 240.977928 -29.573728)
		(end 243.1542 -31.75)
		(width 0.14224)
		(layer "In4.Cu")
		(net "M_C_ECC<7>")
	)
	(segment
		(start 246.425974 -63.810388)
		(end 246.421148 -63.819024)
		(width 0.0889)
		(layer "In4.Cu")
		(net "M_C_ECC<7>")
	)
	(segment
		(start 247.463564 -50.413666)
		(end 246.937276 -50.939954)
		(width 0.0889)
		(layer "In4.Cu")
		(net "M_C_ECC<7>")
	)
	(segment
		(start 240.963196 -26.358596)
		(end 241.166396 -26.561796)
		(width 0.14224)
		(layer "In4.Cu")
		(net "M_C_ECC<7>")
	)
	(segment
		(start 246.425974 -58.266838)
		(end 246.432324 -58.277506)
		(width 0.0889)
		(layer "In4.Cu")
		(net "M_C_ECC<7>")
	)
	(segment
		(start 240.114328 -3.980688)
		(end 240.977928 -4.844288)
		(width 0.14224)
		(layer "In4.Cu")
		(net "M_C_ECC<7>")
	)
	(segment
		(start 246.425974 -62.819788)
		(end 246.421148 -62.828424)
		(width 0.0889)
		(layer "In4.Cu")
		(net "M_C_ECC<7>")
	)
	(segment
		(start 240.952528 -21.771356)
		(end 241.155728 -21.974556)
		(width 0.14224)
		(layer "In4.Cu")
		(net "M_C_ECC<7>")
	)
	(segment
		(start 241.181128 -7.492746)
		(end 241.181128 -8.729218)
		(width 0.14224)
		(layer "In4.Cu")
		(net "M_C_ECC<7>")
	)
	(segment
		(start 246.425974 -61.829188)
		(end 246.421148 -61.837824)
		(width 0.0889)
		(layer "In4.Cu")
		(net "M_C_ECC<7>")
	)
	(segment
		(start 246.432324 -62.80912)
		(end 246.425974 -62.819788)
		(width 0.0889)
		(layer "In4.Cu")
		(net "M_C_ECC<7>")
	)
	(segment
		(start 247.463564 -50.200814)
		(end 247.463564 -50.413666)
		(width 0.0889)
		(layer "In4.Cu")
		(net "M_C_ECC<7>")
	)
	(segment
		(start 240.952528 -18.584418)
		(end 240.952528 -21.771356)
		(width 0.14224)
		(layer "In4.Cu")
		(net "M_C_ECC<7>")
	)
	(segment
		(start 246.057674 -45.568616)
		(end 246.431816 -45.568616)
		(width 0.14224)
		(layer "In4.Cu")
		(net "M_C_ECC<7>")
	)
	(segment
		(start 246.432324 -63.79972)
		(end 246.425974 -63.810388)
		(width 0.0889)
		(layer "In4.Cu")
		(net "M_C_ECC<7>")
	)
	(segment
		(start 246.937276 -50.939954)
		(end 246.937276 -51.220624)
		(width 0.0889)
		(layer "In4.Cu")
		(net "M_C_ECC<7>")
	)
	(segment
		(start 241.155728 -13.516356)
		(end 240.977928 -13.694156)
		(width 0.14224)
		(layer "In4.Cu")
		(net "M_C_ECC<7>")
	)
	(segment
		(start 246.445024 -55.141368)
		(end 246.504714 -55.201058)
		(width 0.0889)
		(layer "In4.Cu")
		(net "M_C_ECC<7>")
	)
	(segment
		(start 246.425974 -65.791588)
		(end 246.421148 -65.800224)
		(width 0.0889)
		(layer "In4.Cu")
		(net "M_C_ECC<7>")
	)
	(segment
		(start 241.155728 -12.373356)
		(end 241.155728 -13.516356)
		(width 0.14224)
		(layer "In4.Cu")
		(net "M_C_ECC<7>")
	)
	(segment
		(start 246.432324 -59.83732)
		(end 246.425974 -59.847988)
		(width 0.0889)
		(layer "In4.Cu")
		(net "M_C_ECC<7>")
	)
	(segment
		(start 240.952528 -8.957818)
		(end 240.952528 -12.170156)
		(width 0.14224)
		(layer "In4.Cu")
		(net "M_C_ECC<7>")
	)
	(segment
		(start 246.445024 -53.14823)
		(end 246.445024 -55.141368)
		(width 0.0889)
		(layer "In4.Cu")
		(net "M_C_ECC<7>")
	)
	(segment
		(start 241.181128 -17.093946)
		(end 241.181128 -18.355818)
		(width 0.14224)
		(layer "In4.Cu")
		(net "M_C_ECC<7>")
	)
	(segment
		(start 247.070118 -51.452526)
		(end 247.070118 -52.523136)
		(width 0.0889)
		(layer "In4.Cu")
		(net "M_C_ECC<7>")
	)
	(segment
		(start 247.77065 -49.893728)
		(end 247.715024 -49.949354)
		(width 0.14224)
		(layer "In4.Cu")
		(net "M_C_ECC<7>")
	)
	(segment
		(start 240.963196 -23.310088)
		(end 240.963196 -26.358596)
		(width 0.14224)
		(layer "In4.Cu")
		(net "M_C_ECC<7>")
	)
	(segment
		(start 246.937276 -51.220624)
		(end 247.070118 -51.452526)
		(width 0.0889)
		(layer "In4.Cu")
		(net "M_C_ECC<7>")
	)
	(segment
		(start 246.432324 -61.81852)
		(end 246.425974 -61.829188)
		(width 0.0889)
		(layer "In4.Cu")
		(net "M_C_ECC<7>")
	)
	(segment
		(start 246.425974 -56.876188)
		(end 246.421148 -56.884824)
		(width 0.0889)
		(layer "In4.Cu")
		(net "M_C_ECC<7>")
	)
	(segment
		(start 240.901728 -7.213346)
		(end 241.181128 -7.492746)
		(width 0.14224)
		(layer "In4.Cu")
		(net "M_C_ECC<7>")
	)
	(segment
		(start 240.977928 -6.375146)
		(end 240.901728 -6.451346)
		(width 0.14224)
		(layer "In4.Cu")
		(net "M_C_ECC<7>")
	)
	(segment
		(start 240.977928 -13.694156)
		(end 240.977928 -16.890746)
		(width 0.14224)
		(layer "In4.Cu")
		(net "M_C_ECC<7>")
	)
	(segment
		(start 240.901728 -6.451346)
		(end 240.901728 -7.213346)
		(width 0.14224)
		(layer "In4.Cu")
		(net "M_C_ECC<7>")
	)
	(segment
		(start 241.155728 -23.117556)
		(end 240.963196 -23.310088)
		(width 0.14224)
		(layer "In4.Cu")
		(net "M_C_ECC<7>")
	)
	(segment
		(start 247.715024 -49.949354)
		(end 247.463564 -50.200814)
		(width 0.0889)
		(layer "In4.Cu")
		(net "M_C_ECC<7>")
	)
	(segment
		(start 240.977928 -4.844288)
		(end 240.977928 -6.375146)
		(width 0.14224)
		(layer "In4.Cu")
		(net "M_C_ECC<7>")
	)
	(segment
		(start 240.977928 -27.627072)
		(end 240.977928 -29.573728)
		(width 0.14224)
		(layer "In4.Cu")
		(net "M_C_ECC<7>")
	)
	(segment
		(start 246.432324 -56.86552)
		(end 246.425974 -56.876188)
		(width 0.0889)
		(layer "In4.Cu")
		(net "M_C_ECC<7>")
	)
	(arc
		(start 246.425974 -60.248038)
		(mid 246.505196 -60.537156)
		(end 246.432324 -60.82792)
		(width 0.0889)
		(layer "In4.Cu")
		(net "M_C_ECC<7>")
	)
	(arc
		(start 246.425974 -56.285638)
		(mid 246.505196 -56.574756)
		(end 246.432324 -56.86552)
		(width 0.0889)
		(layer "In4.Cu")
		(net "M_C_ECC<7>")
	)
	(arc
		(start 246.469408 -55.793132)
		(mid 246.447775 -55.844374)
		(end 246.421148 -55.893208)
		(width 0.0889)
		(layer "In4.Cu")
		(net "M_C_ECC<7>")
	)
	(arc
		(start 246.421148 -60.847224)
		(mid 246.372393 -61.043576)
		(end 246.425974 -61.238638)
		(width 0.0889)
		(layer "In4.Cu")
		(net "M_C_ECC<7>")
	)
	(arc
		(start 246.421148 -56.884824)
		(mid 246.372393 -57.081176)
		(end 246.425974 -57.276238)
		(width 0.0889)
		(layer "In4.Cu")
		(net "M_C_ECC<7>")
	)
	(arc
		(start 246.425974 -59.257438)
		(mid 246.505196 -59.546556)
		(end 246.432324 -59.83732)
		(width 0.0889)
		(layer "In4.Cu")
		(net "M_C_ECC<7>")
	)
	(arc
		(start 246.425974 -64.210438)
		(mid 246.505196 -64.499556)
		(end 246.432324 -64.79032)
		(width 0.0889)
		(layer "In4.Cu")
		(net "M_C_ECC<7>")
	)
	(arc
		(start 246.425974 -66.191384)
		(mid 246.505105 -66.486786)
		(end 246.425974 -66.782188)
		(width 0.0889)
		(layer "In4.Cu")
		(net "M_C_ECC<7>")
	)
	(arc
		(start 246.504714 -55.59298)
		(mid 246.495812 -55.694598)
		(end 246.469408 -55.793132)
		(width 0.0889)
		(layer "In4.Cu")
		(net "M_C_ECC<7>")
	)
	(arc
		(start 246.421148 -64.809624)
		(mid 246.372393 -65.005976)
		(end 246.425974 -65.201038)
		(width 0.0889)
		(layer "In4.Cu")
		(net "M_C_ECC<7>")
	)
	(arc
		(start 246.425974 -57.867042)
		(mid 246.372475 -58.06694)
		(end 246.425974 -58.266838)
		(width 0.0889)
		(layer "In4.Cu")
		(net "M_C_ECC<7>")
	)
	(arc
		(start 246.425974 -62.229238)
		(mid 246.505196 -62.518356)
		(end 246.432324 -62.80912)
		(width 0.0889)
		(layer "In4.Cu")
		(net "M_C_ECC<7>")
	)
	(arc
		(start 246.421148 -61.837824)
		(mid 246.372393 -62.034176)
		(end 246.425974 -62.229238)
		(width 0.0889)
		(layer "In4.Cu")
		(net "M_C_ECC<7>")
	)
	(arc
		(start 246.308372 -68.399406)
		(mid 246.308155 -68.537801)
		(end 246.260874 -68.667884)
		(width 0.0889)
		(layer "In4.Cu")
		(net "M_C_ECC<7>")
	)
	(arc
		(start 246.421148 -58.866024)
		(mid 246.372393 -59.062376)
		(end 246.425974 -59.257438)
		(width 0.0889)
		(layer "In4.Cu")
		(net "M_C_ECC<7>")
	)
	(arc
		(start 246.425974 -61.238638)
		(mid 246.505196 -61.527756)
		(end 246.432324 -61.81852)
		(width 0.0889)
		(layer "In4.Cu")
		(net "M_C_ECC<7>")
	)
	(arc
		(start 246.432324 -58.277506)
		(mid 246.505122 -58.568269)
		(end 246.425974 -58.857388)
		(width 0.0889)
		(layer "In4.Cu")
		(net "M_C_ECC<7>")
	)
	(arc
		(start 246.425974 -57.276238)
		(mid 246.505105 -57.57164)
		(end 246.425974 -57.867042)
		(width 0.0889)
		(layer "In4.Cu")
		(net "M_C_ECC<7>")
	)
	(arc
		(start 246.425974 -66.782188)
		(mid 246.372475 -66.982086)
		(end 246.425974 -67.181984)
		(width 0.0889)
		(layer "In4.Cu")
		(net "M_C_ECC<7>")
	)
	(arc
		(start 246.421148 -55.893208)
		(mid 246.372026 -56.090149)
		(end 246.42572 -56.285892)
		(width 0.0889)
		(layer "In4.Cu")
		(net "M_C_ECC<7>")
	)
	(arc
		(start 246.421148 -63.819024)
		(mid 246.372393 -64.015376)
		(end 246.425974 -64.210438)
		(width 0.0889)
		(layer "In4.Cu")
		(net "M_C_ECC<7>")
	)
	(arc
		(start 246.421148 -62.828424)
		(mid 246.372393 -63.024776)
		(end 246.425974 -63.219838)
		(width 0.0889)
		(layer "In4.Cu")
		(net "M_C_ECC<7>")
	)
	(arc
		(start 246.425974 -67.181984)
		(mid 246.505105 -67.477386)
		(end 246.425974 -67.772788)
		(width 0.0889)
		(layer "In4.Cu")
		(net "M_C_ECC<7>")
	)
	(arc
		(start 246.425974 -63.219838)
		(mid 246.505196 -63.508956)
		(end 246.432324 -63.79972)
		(width 0.0889)
		(layer "In4.Cu")
		(net "M_C_ECC<7>")
	)
	(arc
		(start 246.421148 -65.800224)
		(mid 246.372454 -65.996432)
		(end 246.425974 -66.191384)
		(width 0.0889)
		(layer "In4.Cu")
		(net "M_C_ECC<7>")
	)
	(arc
		(start 246.425974 -67.772788)
		(mid 246.313728 -68.076064)
		(end 246.308372 -68.399406)
		(width 0.0889)
		(layer "In4.Cu")
		(net "M_C_ECC<7>")
	)
	(arc
		(start 246.425974 -65.201038)
		(mid 246.505196 -65.490156)
		(end 246.432324 -65.78092)
		(width 0.0889)
		(layer "In4.Cu")
		(net "M_C_ECC<7>")
	)
	(arc
		(start 246.260874 -68.667884)
		(mid 246.23474 -68.718555)
		(end 246.21363 -68.771516)
		(width 0.0889)
		(layer "In4.Cu")
		(net "M_C_ECC<7>")
	)
	(arc
		(start 246.421148 -59.856624)
		(mid 246.372393 -60.052976)
		(end 246.425974 -60.248038)
		(width 0.0889)
		(layer "In4.Cu")
		(net "M_C_ECC<7>")
	)
	(segment
		(start 240.599722 -3.076956)
		(end 240.952528 -2.72415)
		(width 0.14224)
		(layer "In11.Cu")
		(net "M_C_ECC<7>")
	)
	(segment
		(start 240.066576 1.8796)
		(end 240.066576 2.198116)
		(width 0.14224)
		(layer "In11.Cu")
		(net "M_C_ECC<7>")
	)
	(segment
		(start 240.066576 2.198116)
		(end 239.749838 2.514854)
		(width 0.14224)
		(layer "In11.Cu")
		(net "M_C_ECC<7>")
	)
	(segment
		(start 241.107976 1.0922)
		(end 240.650776 1.5494)
		(width 0.14224)
		(layer "In11.Cu")
		(net "M_C_ECC<7>")
	)
	(segment
		(start 240.396776 1.5494)
		(end 240.066576 1.8796)
		(width 0.14224)
		(layer "In11.Cu")
		(net "M_C_ECC<7>")
	)
	(segment
		(start 241.107976 0.7366)
		(end 241.107976 1.0922)
		(width 0.14224)
		(layer "In11.Cu")
		(net "M_C_ECC<7>")
	)
	(segment
		(start 240.650776 1.5494)
		(end 240.396776 1.5494)
		(width 0.14224)
		(layer "In11.Cu")
		(net "M_C_ECC<7>")
	)
	(segment
		(start 240.952528 0.581152)
		(end 241.107976 0.7366)
		(width 0.14224)
		(layer "In11.Cu")
		(net "M_C_ECC<7>")
	)
	(segment
		(start 240.952528 -2.72415)
		(end 240.952528 0.581152)
		(width 0.14224)
		(layer "In11.Cu")
		(net "M_C_ECC<7>")
	)
	(segment
		(start 246.485664 -67.47764)
		(end 245.914164 -67.47764)
		(width 0.0889)
		(layer "F.Cu")
		(net "M_C_ECC<6>")
	)
	(segment
		(start 240.599976 0.939546)
		(end 240.599722 0.9398)
		(width 0.1651)
		(layer "F.Cu")
		(net "M_C_ECC<6>")
	)
	(segment
		(start 240.599976 -0.821182)
		(end 240.599976 0.1524)
		(width 0.1651)
		(layer "F.Cu")
		(net "M_C_ECC<6>")
	)
	(segment
		(start 240.732056 0.50292)
		(end 240.599976 0.635)
		(width 0.1651)
		(layer "F.Cu")
		(net "M_C_ECC<6>")
	)
	(segment
		(start 240.600484 -0.821182)
		(end 240.599976 -0.821182)
		(width 0.1651)
		(layer "F.Cu")
		(net "M_C_ECC<6>")
	)
	(segment
		(start 240.599976 0.635)
		(end 240.599976 0.939546)
		(width 0.1651)
		(layer "F.Cu")
		(net "M_C_ECC<6>")
	)
	(segment
		(start 240.599976 0.1524)
		(end 240.732056 0.28448)
		(width 0.1651)
		(layer "F.Cu")
		(net "M_C_ECC<6>")
	)
	(segment
		(start 240.732056 0.28448)
		(end 240.732056 0.50292)
		(width 0.1651)
		(layer "F.Cu")
		(net "M_C_ECC<6>")
	)
	(via
		(at 240.599722 0.9398)
		(size 0.508)
		(drill 0.254)
		(layers "F.Cu" "B.Cu")
		(net "M_C_ECC<6>")
	)
	(via
		(at 245.914164 -67.47764)
		(size 0.508)
		(drill 0.254)
		(layers "F.Cu" "B.Cu")
		(net "M_C_ECC<6>")
	)
	(via
		(at 239.749838 -4.357878)
		(size 0.508)
		(drill 0.254)
		(layers "F.Cu" "B.Cu")
		(net "M_C_ECC<6>")
	)
	(segment
		(start 239.750346 -5.621782)
		(end 239.749838 -5.621782)
		(width 0.1651)
		(layer "B.Cu")
		(net "M_C_ECC<6>")
	)
	(segment
		(start 239.749838 -5.621782)
		(end 239.749838 -4.357878)
		(width 0.1651)
		(layer "B.Cu")
		(net "M_C_ECC<6>")
	)
	(segment
		(start 243.047774 -36.785804)
		(end 243.202714 -36.630864)
		(width 0.14224)
		(layer "In4.Cu")
		(net "M_C_ECC<6>")
	)
	(segment
		(start 240.3602 -27.813)
		(end 240.072164 -27.524964)
		(width 0.14224)
		(layer "In4.Cu")
		(net "M_C_ECC<6>")
	)
	(segment
		(start 243.202714 -35.391344)
		(end 243.202714 -35.081464)
		(width 0.14224)
		(layer "In4.Cu")
		(net "M_C_ECC<6>")
	)
	(segment
		(start 243.047774 -35.546284)
		(end 243.202714 -35.391344)
		(width 0.14224)
		(layer "In4.Cu")
		(net "M_C_ECC<6>")
	)
	(segment
		(start 246.254524 -59.763406)
		(end 246.260874 -59.752738)
		(width 0.0889)
		(layer "In4.Cu")
		(net "M_C_ECC<6>")
	)
	(segment
		(start 239.749838 -4.545838)
		(end 239.749838 -4.357878)
		(width 0.14224)
		(layer "In4.Cu")
		(net "M_C_ECC<6>")
	)
	(segment
		(start 246.254524 -60.754006)
		(end 246.260874 -60.743338)
		(width 0.0889)
		(layer "In4.Cu")
		(net "M_C_ECC<6>")
	)
	(segment
		(start 242.5573 -42.966386)
		(end 242.5573 -38.180264)
		(width 0.14224)
		(layer "In4.Cu")
		(net "M_C_ECC<6>")
	)
	(segment
		(start 247.0658 -49.94529)
		(end 247.0658 -46.9646)
		(width 0.14224)
		(layer "In4.Cu")
		(net "M_C_ECC<6>")
	)
	(segment
		(start 240.114328 -18.422874)
		(end 240.114328 -16.992346)
		(width 0.14224)
		(layer "In4.Cu")
		(net "M_C_ECC<6>")
	)
	(segment
		(start 245.914164 -67.47764)
		(end 246.20728 -67.308476)
		(width 0.0889)
		(layer "In4.Cu")
		(net "M_C_ECC<6>")
	)
	(segment
		(start 246.746776 -51.279552)
		(end 246.746776 -50.852578)
		(width 0.0889)
		(layer "In4.Cu")
		(net "M_C_ECC<6>")
	)
	(segment
		(start 240.266728 -5.062728)
		(end 239.749838 -4.545838)
		(width 0.14224)
		(layer "In4.Cu")
		(net "M_C_ECC<6>")
	)
	(segment
		(start 246.254524 -56.791606)
		(end 246.260874 -56.780938)
		(width 0.0889)
		(layer "In4.Cu")
		(net "M_C_ECC<6>")
	)
	(segment
		(start 242.5573 -32.020764)
		(end 240.3602 -29.823664)
		(width 0.14224)
		(layer "In4.Cu")
		(net "M_C_ECC<6>")
	)
	(segment
		(start 240.215928 -16.890746)
		(end 240.215928 -13.668756)
		(width 0.14224)
		(layer "In4.Cu")
		(net "M_C_ECC<6>")
	)
	(segment
		(start 246.260874 -58.362088)
		(end 246.254524 -58.35142)
		(width 0.0889)
		(layer "In4.Cu")
		(net "M_C_ECC<6>")
	)
	(segment
		(start 240.114328 -8.821674)
		(end 240.114328 -7.391146)
		(width 0.14224)
		(layer "In4.Cu")
		(net "M_C_ECC<6>")
	)
	(segment
		(start 242.71224 -36.785804)
		(end 243.047774 -36.785804)
		(width 0.14224)
		(layer "In4.Cu")
		(net "M_C_ECC<6>")
	)
	(segment
		(start 247.0658 -46.9646)
		(end 246.227346 -46.126146)
		(width 0.14224)
		(layer "In4.Cu")
		(net "M_C_ECC<6>")
	)
	(segment
		(start 246.260874 -63.715138)
		(end 246.2657 -63.706502)
		(width 0.0889)
		(layer "In4.Cu")
		(net "M_C_ECC<6>")
	)
	(segment
		(start 246.260874 -65.696338)
		(end 246.2657 -65.687702)
		(width 0.0889)
		(layer "In4.Cu")
		(net "M_C_ECC<6>")
	)
	(segment
		(start 246.260874 -61.733938)
		(end 246.2657 -61.725302)
		(width 0.0889)
		(layer "In4.Cu")
		(net "M_C_ECC<6>")
	)
	(segment
		(start 242.5573 -38.180264)
		(end 242.71224 -38.025324)
		(width 0.14224)
		(layer "In4.Cu")
		(net "M_C_ECC<6>")
	)
	(segment
		(start 243.047774 -38.025324)
		(end 243.202714 -37.870384)
		(width 0.14224)
		(layer "In4.Cu")
		(net "M_C_ECC<6>")
	)
	(segment
		(start 246.260874 -56.780938)
		(end 246.2657 -56.772302)
		(width 0.0889)
		(layer "In4.Cu")
		(net "M_C_ECC<6>")
	)
	(segment
		(start 246.879618 -51.511454)
		(end 246.746776 -51.279552)
		(width 0.0889)
		(layer "In4.Cu")
		(net "M_C_ECC<6>")
	)
	(segment
		(start 240.03 -25.538938)
		(end 240.03 -24.948134)
		(width 0.14224)
		(layer "In4.Cu")
		(net "M_C_ECC<6>")
	)
	(segment
		(start 240.317528 -21.771356)
		(end 240.317528 -18.626074)
		(width 0.14224)
		(layer "In4.Cu")
		(net "M_C_ECC<6>")
	)
	(segment
		(start 243.202714 -36.320984)
		(end 243.047774 -36.166044)
		(width 0.14224)
		(layer "In4.Cu")
		(net "M_C_ECC<6>")
	)
	(segment
		(start 246.260874 -59.752738)
		(end 246.2657 -59.744102)
		(width 0.0889)
		(layer "In4.Cu")
		(net "M_C_ECC<6>")
	)
	(segment
		(start 240.114328 -21.974556)
		(end 240.317528 -21.771356)
		(width 0.14224)
		(layer "In4.Cu")
		(net "M_C_ECC<6>")
	)
	(segment
		(start 243.202714 -35.081464)
		(end 243.047774 -34.926524)
		(width 0.14224)
		(layer "In4.Cu")
		(net "M_C_ECC<6>")
	)
	(segment
		(start 240.114328 -13.567156)
		(end 240.114328 -12.373356)
		(width 0.14224)
		(layer "In4.Cu")
		(net "M_C_ECC<6>")
	)
	(segment
		(start 242.5573 -36.011104)
		(end 242.5573 -35.701224)
		(width 0.14224)
		(layer "In4.Cu")
		(net "M_C_ECC<6>")
	)
	(segment
		(start 246.254524 -55.225696)
		(end 246.254524 -53.06187)
		(width 0.0889)
		(layer "In4.Cu")
		(net "M_C_ECC<6>")
	)
	(segment
		(start 247.080024 -49.959514)
		(end 247.0658 -49.94529)
		(width 0.14224)
		(layer "In4.Cu")
		(net "M_C_ECC<6>")
	)
	(segment
		(start 246.314214 -55.592726)
		(end 246.314214 -55.285386)
		(width 0.0889)
		(layer "In4.Cu")
		(net "M_C_ECC<6>")
	)
	(segment
		(start 240.251996 -24.726138)
		(end 240.251996 -23.306024)
		(width 0.14224)
		(layer "In4.Cu")
		(net "M_C_ECC<6>")
	)
	(segment
		(start 240.03 -24.948134)
		(end 240.251996 -24.726138)
		(width 0.14224)
		(layer "In4.Cu")
		(net "M_C_ECC<6>")
	)
	(segment
		(start 240.251996 -26.295604)
		(end 240.251996 -25.760934)
		(width 0.14224)
		(layer "In4.Cu")
		(net "M_C_ECC<6>")
	)
	(segment
		(start 246.260874 -60.743338)
		(end 246.2657 -60.734702)
		(width 0.0889)
		(layer "In4.Cu")
		(net "M_C_ECC<6>")
	)
	(segment
		(start 243.047774 -36.166044)
		(end 242.71224 -36.166044)
		(width 0.14224)
		(layer "In4.Cu")
		(net "M_C_ECC<6>")
	)
	(segment
		(start 243.202714 -37.560504)
		(end 243.047774 -37.405564)
		(width 0.14224)
		(layer "In4.Cu")
		(net "M_C_ECC<6>")
	)
	(segment
		(start 243.047774 -34.926524)
		(end 242.71224 -34.926524)
		(width 0.14224)
		(layer "In4.Cu")
		(net "M_C_ECC<6>")
	)
	(segment
		(start 246.254524 -61.744606)
		(end 246.260874 -61.733938)
		(width 0.0889)
		(layer "In4.Cu")
		(net "M_C_ECC<6>")
	)
	(segment
		(start 246.260874 -62.724538)
		(end 246.2657 -62.715902)
		(width 0.0889)
		(layer "In4.Cu")
		(net "M_C_ECC<6>")
	)
	(segment
		(start 240.114328 -16.992346)
		(end 240.215928 -16.890746)
		(width 0.14224)
		(layer "In4.Cu")
		(net "M_C_ECC<6>")
	)
	(segment
		(start 242.5573 -34.771584)
		(end 242.5573 -32.020764)
		(width 0.14224)
		(layer "In4.Cu")
		(net "M_C_ECC<6>")
	)
	(segment
		(start 245.71706 -46.126146)
		(end 242.5573 -42.966386)
		(width 0.14224)
		(layer "In4.Cu")
		(net "M_C_ECC<6>")
	)
	(segment
		(start 246.746776 -50.852578)
		(end 247.2563 -50.343054)
		(width 0.0889)
		(layer "In4.Cu")
		(net "M_C_ECC<6>")
	)
	(segment
		(start 246.20728 -67.308476)
		(end 246.231156 -67.219068)
		(width 0.0889)
		(layer "In4.Cu")
		(net "M_C_ECC<6>")
	)
	(segment
		(start 246.254524 -65.707006)
		(end 246.260874 -65.696338)
		(width 0.0889)
		(layer "In4.Cu")
		(net "M_C_ECC<6>")
	)
	(segment
		(start 246.260874 -57.771538)
		(end 246.2657 -57.762902)
		(width 0.0889)
		(layer "In4.Cu")
		(net "M_C_ECC<6>")
	)
	(segment
		(start 242.71224 -35.546284)
		(end 243.047774 -35.546284)
		(width 0.14224)
		(layer "In4.Cu")
		(net "M_C_ECC<6>")
	)
	(segment
		(start 246.254524 -63.725806)
		(end 246.260874 -63.715138)
		(width 0.0889)
		(layer "In4.Cu")
		(net "M_C_ECC<6>")
	)
	(segment
		(start 240.317528 -9.024874)
		(end 240.114328 -8.821674)
		(width 0.14224)
		(layer "In4.Cu")
		(net "M_C_ECC<6>")
	)
	(segment
		(start 240.114328 -7.391146)
		(end 240.266728 -7.238746)
		(width 0.14224)
		(layer "In4.Cu")
		(net "M_C_ECC<6>")
	)
	(segment
		(start 242.5573 -37.250624)
		(end 242.5573 -36.940744)
		(width 0.14224)
		(layer "In4.Cu")
		(net "M_C_ECC<6>")
	)
	(segment
		(start 240.317528 -18.626074)
		(end 240.114328 -18.422874)
		(width 0.14224)
		(layer "In4.Cu")
		(net "M_C_ECC<6>")
	)
	(segment
		(start 246.254524 -64.716406)
		(end 246.260874 -64.705738)
		(width 0.0889)
		(layer "In4.Cu")
		(net "M_C_ECC<6>")
	)
	(segment
		(start 242.71224 -38.025324)
		(end 243.047774 -38.025324)
		(width 0.14224)
		(layer "In4.Cu")
		(net "M_C_ECC<6>")
	)
	(segment
		(start 242.5573 -35.701224)
		(end 242.71224 -35.546284)
		(width 0.14224)
		(layer "In4.Cu")
		(net "M_C_ECC<6>")
	)
	(segment
		(start 246.879618 -52.436776)
		(end 246.879618 -51.511454)
		(width 0.0889)
		(layer "In4.Cu")
		(net "M_C_ECC<6>")
	)
	(segment
		(start 240.114328 -23.168356)
		(end 240.114328 -21.974556)
		(width 0.14224)
		(layer "In4.Cu")
		(net "M_C_ECC<6>")
	)
	(segment
		(start 240.072164 -26.475436)
		(end 240.251996 -26.295604)
		(width 0.14224)
		(layer "In4.Cu")
		(net "M_C_ECC<6>")
	)
	(segment
		(start 247.2563 -50.343054)
		(end 247.2563 -50.13579)
		(width 0.0889)
		(layer "In4.Cu")
		(net "M_C_ECC<6>")
	)
	(segment
		(start 242.5573 -36.940744)
		(end 242.71224 -36.785804)
		(width 0.14224)
		(layer "In4.Cu")
		(net "M_C_ECC<6>")
	)
	(segment
		(start 246.254524 -62.735206)
		(end 246.260874 -62.724538)
		(width 0.0889)
		(layer "In4.Cu")
		(net "M_C_ECC<6>")
	)
	(segment
		(start 246.314214 -55.285386)
		(end 246.254524 -55.225696)
		(width 0.0889)
		(layer "In4.Cu")
		(net "M_C_ECC<6>")
	)
	(segment
		(start 247.2563 -50.13579)
		(end 247.080024 -49.959514)
		(width 0.0889)
		(layer "In4.Cu")
		(net "M_C_ECC<6>")
	)
	(segment
		(start 242.71224 -34.926524)
		(end 242.5573 -34.771584)
		(width 0.14224)
		(layer "In4.Cu")
		(net "M_C_ECC<6>")
	)
	(segment
		(start 243.047774 -37.405564)
		(end 242.71224 -37.405564)
		(width 0.14224)
		(layer "In4.Cu")
		(net "M_C_ECC<6>")
	)
	(segment
		(start 246.254524 -53.06187)
		(end 246.879618 -52.436776)
		(width 0.0889)
		(layer "In4.Cu")
		(net "M_C_ECC<6>")
	)
	(segment
		(start 246.227346 -46.126146)
		(end 245.71706 -46.126146)
		(width 0.14224)
		(layer "In4.Cu")
		(net "M_C_ECC<6>")
	)
	(segment
		(start 246.260874 -64.705738)
		(end 246.2657 -64.697102)
		(width 0.0889)
		(layer "In4.Cu")
		(net "M_C_ECC<6>")
	)
	(segment
		(start 240.266728 -7.238746)
		(end 240.266728 -5.062728)
		(width 0.14224)
		(layer "In4.Cu")
		(net "M_C_ECC<6>")
	)
	(segment
		(start 240.114328 -12.373356)
		(end 240.317528 -12.170156)
		(width 0.14224)
		(layer "In4.Cu")
		(net "M_C_ECC<6>")
	)
	(segment
		(start 242.71224 -36.166044)
		(end 242.5573 -36.011104)
		(width 0.14224)
		(layer "In4.Cu")
		(net "M_C_ECC<6>")
	)
	(segment
		(start 242.71224 -37.405564)
		(end 242.5573 -37.250624)
		(width 0.14224)
		(layer "In4.Cu")
		(net "M_C_ECC<6>")
	)
	(segment
		(start 240.251996 -25.760934)
		(end 240.03 -25.538938)
		(width 0.14224)
		(layer "In4.Cu")
		(net "M_C_ECC<6>")
	)
	(segment
		(start 240.251996 -23.306024)
		(end 240.114328 -23.168356)
		(width 0.14224)
		(layer "In4.Cu")
		(net "M_C_ECC<6>")
	)
	(segment
		(start 240.215928 -13.668756)
		(end 240.114328 -13.567156)
		(width 0.14224)
		(layer "In4.Cu")
		(net "M_C_ECC<6>")
	)
	(segment
		(start 240.317528 -12.170156)
		(end 240.317528 -9.024874)
		(width 0.14224)
		(layer "In4.Cu")
		(net "M_C_ECC<6>")
	)
	(segment
		(start 240.3602 -29.823664)
		(end 240.3602 -27.813)
		(width 0.14224)
		(layer "In4.Cu")
		(net "M_C_ECC<6>")
	)
	(segment
		(start 243.202714 -36.630864)
		(end 243.202714 -36.320984)
		(width 0.14224)
		(layer "In4.Cu")
		(net "M_C_ECC<6>")
	)
	(segment
		(start 243.202714 -37.870384)
		(end 243.202714 -37.560504)
		(width 0.14224)
		(layer "In4.Cu")
		(net "M_C_ECC<6>")
	)
	(segment
		(start 240.072164 -27.524964)
		(end 240.072164 -26.475436)
		(width 0.14224)
		(layer "In4.Cu")
		(net "M_C_ECC<6>")
	)
	(arc
		(start 246.260874 -57.371488)
		(mid 246.181652 -57.08237)
		(end 246.254524 -56.791606)
		(width 0.0889)
		(layer "In4.Cu")
		(net "M_C_ECC<6>")
	)
	(arc
		(start 246.2657 -59.744102)
		(mid 246.314455 -59.54775)
		(end 246.260874 -59.352688)
		(width 0.0889)
		(layer "In4.Cu")
		(net "M_C_ECC<6>")
	)
	(arc
		(start 246.260874 -65.296288)
		(mid 246.181652 -65.00717)
		(end 246.254524 -64.716406)
		(width 0.0889)
		(layer "In4.Cu")
		(net "M_C_ECC<6>")
	)
	(arc
		(start 246.2657 -57.762902)
		(mid 246.314455 -57.56655)
		(end 246.260874 -57.371488)
		(width 0.0889)
		(layer "In4.Cu")
		(net "M_C_ECC<6>")
	)
	(arc
		(start 246.2657 -61.725302)
		(mid 246.314455 -61.52895)
		(end 246.260874 -61.333888)
		(width 0.0889)
		(layer "In4.Cu")
		(net "M_C_ECC<6>")
	)
	(arc
		(start 246.260874 -64.305688)
		(mid 246.181652 -64.01657)
		(end 246.254524 -63.725806)
		(width 0.0889)
		(layer "In4.Cu")
		(net "M_C_ECC<6>")
	)
	(arc
		(start 246.2657 -60.734702)
		(mid 246.314455 -60.53835)
		(end 246.260874 -60.343288)
		(width 0.0889)
		(layer "In4.Cu")
		(net "M_C_ECC<6>")
	)
	(arc
		(start 246.254524 -55.801006)
		(mid 246.273649 -55.766421)
		(end 246.289322 -55.73014)
		(width 0.0889)
		(layer "In4.Cu")
		(net "M_C_ECC<6>")
	)
	(arc
		(start 246.260874 -60.343288)
		(mid 246.181652 -60.05417)
		(end 246.254524 -59.763406)
		(width 0.0889)
		(layer "In4.Cu")
		(net "M_C_ECC<6>")
	)
	(arc
		(start 246.254524 -58.35142)
		(mid 246.181726 -58.060657)
		(end 246.260874 -57.771538)
		(width 0.0889)
		(layer "In4.Cu")
		(net "M_C_ECC<6>")
	)
	(arc
		(start 246.2657 -62.715902)
		(mid 246.314455 -62.51955)
		(end 246.260874 -62.324488)
		(width 0.0889)
		(layer "In4.Cu")
		(net "M_C_ECC<6>")
	)
	(arc
		(start 246.2657 -56.772302)
		(mid 246.314455 -56.57595)
		(end 246.260874 -56.380888)
		(width 0.0889)
		(layer "In4.Cu")
		(net "M_C_ECC<6>")
	)
	(arc
		(start 246.289322 -55.73014)
		(mid 246.307944 -55.662552)
		(end 246.314214 -55.592726)
		(width 0.0889)
		(layer "In4.Cu")
		(net "M_C_ECC<6>")
	)
	(arc
		(start 246.2657 -64.697102)
		(mid 246.314455 -64.50075)
		(end 246.260874 -64.305688)
		(width 0.0889)
		(layer "In4.Cu")
		(net "M_C_ECC<6>")
	)
	(arc
		(start 246.260874 -66.286888)
		(mid 246.181754 -65.99777)
		(end 246.254524 -65.707006)
		(width 0.0889)
		(layer "In4.Cu")
		(net "M_C_ECC<6>")
	)
	(arc
		(start 246.260874 -56.380888)
		(mid 246.181652 -56.09177)
		(end 246.254524 -55.801006)
		(width 0.0889)
		(layer "In4.Cu")
		(net "M_C_ECC<6>")
	)
	(arc
		(start 246.254524 -66.697606)
		(mid 246.257632 -66.692106)
		(end 246.260874 -66.686684)
		(width 0.0889)
		(layer "In4.Cu")
		(net "M_C_ECC<6>")
	)
	(arc
		(start 246.260874 -59.352688)
		(mid 246.181743 -59.057286)
		(end 246.260874 -58.761884)
		(width 0.0889)
		(layer "In4.Cu")
		(net "M_C_ECC<6>")
	)
	(arc
		(start 246.231156 -67.219068)
		(mid 246.182144 -66.955619)
		(end 246.254524 -66.697606)
		(width 0.0889)
		(layer "In4.Cu")
		(net "M_C_ECC<6>")
	)
	(arc
		(start 246.260874 -61.333888)
		(mid 246.181652 -61.04477)
		(end 246.254524 -60.754006)
		(width 0.0889)
		(layer "In4.Cu")
		(net "M_C_ECC<6>")
	)
	(arc
		(start 246.260874 -66.686684)
		(mid 246.314373 -66.486786)
		(end 246.260874 -66.286888)
		(width 0.0889)
		(layer "In4.Cu")
		(net "M_C_ECC<6>")
	)
	(arc
		(start 246.260874 -63.315088)
		(mid 246.181652 -63.02597)
		(end 246.254524 -62.735206)
		(width 0.0889)
		(layer "In4.Cu")
		(net "M_C_ECC<6>")
	)
	(arc
		(start 246.2657 -65.687702)
		(mid 246.314455 -65.49135)
		(end 246.260874 -65.296288)
		(width 0.0889)
		(layer "In4.Cu")
		(net "M_C_ECC<6>")
	)
	(arc
		(start 246.260874 -62.324488)
		(mid 246.181652 -62.03537)
		(end 246.254524 -61.744606)
		(width 0.0889)
		(layer "In4.Cu")
		(net "M_C_ECC<6>")
	)
	(arc
		(start 246.260874 -58.761884)
		(mid 246.314373 -58.561986)
		(end 246.260874 -58.362088)
		(width 0.0889)
		(layer "In4.Cu")
		(net "M_C_ECC<6>")
	)
	(arc
		(start 246.2657 -63.706502)
		(mid 246.314455 -63.51015)
		(end 246.260874 -63.315088)
		(width 0.0889)
		(layer "In4.Cu")
		(net "M_C_ECC<6>")
	)
	(segment
		(start 239.749838 -4.357878)
		(end 239.431576 -4.039616)
		(width 0.14224)
		(layer "In11.Cu")
		(net "M_C_ECC<6>")
	)
	(segment
		(start 240.193576 0.533654)
		(end 240.599722 0.9398)
		(width 0.14224)
		(layer "In11.Cu")
		(net "M_C_ECC<6>")
	)
	(segment
		(start 240.193576 -2.8321)
		(end 240.193576 0.533654)
		(width 0.14224)
		(layer "In11.Cu")
		(net "M_C_ECC<6>")
	)
	(segment
		(start 239.431576 -4.039616)
		(end 239.431576 -3.5941)
		(width 0.14224)
		(layer "In11.Cu")
		(net "M_C_ECC<6>")
	)
	(segment
		(start 239.431576 -3.5941)
		(end 240.193576 -2.8321)
		(width 0.14224)
		(layer "In11.Cu")
		(net "M_C_ECC<6>")
	)
	(segment
		(start 243.910104 -68.963286)
		(end 243.338604 -68.963286)
		(width 0.1016)
		(layer "F.Cu")
		(net "M_C_ECC<5>")
	)
	(segment
		(start 233.800396 3.778758)
		(end 233.799888 3.778758)
		(width 0.1651)
		(layer "F.Cu")
		(net "M_C_ECC<5>")
	)
	(segment
		(start 233.799888 3.778758)
		(end 233.799888 2.514854)
		(width 0.1651)
		(layer "F.Cu")
		(net "M_C_ECC<5>")
	)
	(via
		(at 233.799888 2.514854)
		(size 0.508)
		(drill 0.254)
		(layers "F.Cu" "B.Cu")
		(net "M_C_ECC<5>")
	)
	(via
		(at 243.338604 -68.963286)
		(size 0.508)
		(drill 0.254)
		(layers "F.Cu" "B.Cu")
		(net "M_C_ECC<5>")
	)
	(via
		(at 234.573572 -3.076956)
		(size 0.508)
		(drill 0.254)
		(layers "F.Cu" "B.Cu")
		(net "M_C_ECC<5>")
	)
	(segment
		(start 234.649772 -3.000756)
		(end 234.573572 -3.076956)
		(width 0.1651)
		(layer "B.Cu")
		(net "M_C_ECC<5>")
	)
	(segment
		(start 234.65028 -1.021842)
		(end 234.649772 -1.021842)
		(width 0.1651)
		(layer "B.Cu")
		(net "M_C_ECC<5>")
	)
	(segment
		(start 234.649772 -1.021842)
		(end 234.649772 -3.000756)
		(width 0.1651)
		(layer "B.Cu")
		(net "M_C_ECC<5>")
	)
	(segment
		(start 242.992148 -65.791588)
		(end 243.001038 -65.776348)
		(width 0.0889)
		(layer "In4.Cu")
		(net "M_C_ECC<5>")
	)
	(segment
		(start 234.6452 -4.5212)
		(end 234.0864 -3.9624)
		(width 0.14224)
		(layer "In4.Cu")
		(net "M_C_ECC<5>")
	)
	(segment
		(start 242.992148 -59.847988)
		(end 243.001038 -59.832748)
		(width 0.0889)
		(layer "In4.Cu")
		(net "M_C_ECC<5>")
	)
	(segment
		(start 234.958128 -12.271756)
		(end 234.958128 -8.991346)
		(width 0.14224)
		(layer "In4.Cu")
		(net "M_C_ECC<5>")
	)
	(segment
		(start 234.0864 -3.9624)
		(end 234.0864 -3.564128)
		(width 0.14224)
		(layer "In4.Cu")
		(net "M_C_ECC<5>")
	)
	(segment
		(start 237.35284 -42.949876)
		(end 237.2106 -42.807636)
		(width 0.14224)
		(layer "In4.Cu")
		(net "M_C_ECC<5>")
	)
	(segment
		(start 235.044996 -28.125928)
		(end 235.044996 -26.841196)
		(width 0.14224)
		(layer "In4.Cu")
		(net "M_C_ECC<5>")
	)
	(segment
		(start 235.044996 -26.841196)
		(end 234.958128 -26.754328)
		(width 0.14224)
		(layer "In4.Cu")
		(net "M_C_ECC<5>")
	)
	(segment
		(start 235.047028 -13.617956)
		(end 235.047028 -12.360656)
		(width 0.14224)
		(layer "In4.Cu")
		(net "M_C_ECC<5>")
	)
	(segment
		(start 235.047028 -12.360656)
		(end 234.958128 -12.271756)
		(width 0.14224)
		(layer "In4.Cu")
		(net "M_C_ECC<5>")
	)
	(segment
		(start 234.983528 -13.681456)
		(end 235.047028 -13.617956)
		(width 0.14224)
		(layer "In4.Cu")
		(net "M_C_ECC<5>")
	)
	(segment
		(start 237.2106 -42.441876)
		(end 237.35284 -42.299636)
		(width 0.14224)
		(layer "In4.Cu")
		(net "M_C_ECC<5>")
	)
	(segment
		(start 242.992148 -55.885588)
		(end 243.001038 -55.870348)
		(width 0.0889)
		(layer "In4.Cu")
		(net "M_C_ECC<5>")
	)
	(segment
		(start 237.9218 -36.6268)
		(end 237.2106 -35.9156)
		(width 0.14224)
		(layer "In4.Cu")
		(net "M_C_ECC<5>")
	)
	(segment
		(start 234.983528 -16.865346)
		(end 234.983528 -13.681456)
		(width 0.14224)
		(layer "In4.Cu")
		(net "M_C_ECC<5>")
	)
	(segment
		(start 235.077 -28.871672)
		(end 234.958128 -28.7528)
		(width 0.14224)
		(layer "In4.Cu")
		(net "M_C_ECC<5>")
	)
	(segment
		(start 242.489736 -50.346102)
		(end 242.711224 -50.124614)
		(width 0.0889)
		(layer "In4.Cu")
		(net "M_C_ECC<5>")
	)
	(segment
		(start 243.071396 -53.60924)
		(end 243.071142 -53.298598)
		(width 0.0889)
		(layer "In4.Cu")
		(net "M_C_ECC<5>")
	)
	(segment
		(start 237.35284 -42.299636)
		(end 237.77956 -42.299636)
		(width 0.14224)
		(layer "In4.Cu")
		(net "M_C_ECC<5>")
	)
	(segment
		(start 242.992148 -61.829188)
		(end 243.001038 -61.813948)
		(width 0.0889)
		(layer "In4.Cu")
		(net "M_C_ECC<5>")
	)
	(segment
		(start 235.047028 -18.503646)
		(end 235.047028 -16.928846)
		(width 0.14224)
		(layer "In4.Cu")
		(net "M_C_ECC<5>")
	)
	(segment
		(start 237.2106 -32.588454)
		(end 235.077 -30.454854)
		(width 0.14224)
		(layer "In4.Cu")
		(net "M_C_ECC<5>")
	)
	(segment
		(start 242.992148 -63.810388)
		(end 243.001038 -63.795148)
		(width 0.0889)
		(layer "In4.Cu")
		(net "M_C_ECC<5>")
	)
	(segment
		(start 243.071142 -51.61026)
		(end 242.489736 -51.028854)
		(width 0.0889)
		(layer "In4.Cu")
		(net "M_C_ECC<5>")
	)
	(segment
		(start 242.489736 -51.028854)
		(end 242.489736 -50.346102)
		(width 0.0889)
		(layer "In4.Cu")
		(net "M_C_ECC<5>")
	)
	(segment
		(start 243.493036 -67.599052)
		(end 243.49075 -67.59829)
		(width 0.0889)
		(layer "In4.Cu")
		(net "M_C_ECC<5>")
	)
	(segment
		(start 234.958128 -21.872956)
		(end 234.958128 -18.592546)
		(width 0.14224)
		(layer "In4.Cu")
		(net "M_C_ECC<5>")
	)
	(segment
		(start 237.9218 -42.157396)
		(end 237.9218 -36.6268)
		(width 0.14224)
		(layer "In4.Cu")
		(net "M_C_ECC<5>")
	)
	(segment
		(start 237.2106 -35.9156)
		(end 237.2106 -32.588454)
		(width 0.14224)
		(layer "In4.Cu")
		(net "M_C_ECC<5>")
	)
	(segment
		(start 243.338604 -68.963286)
		(end 243.3828 -68.85051)
		(width 0.0889)
		(layer "In4.Cu")
		(net "M_C_ECC<5>")
	)
	(segment
		(start 243.071142 -53.298598)
		(end 243.071142 -51.61026)
		(width 0.0889)
		(layer "In4.Cu")
		(net "M_C_ECC<5>")
	)
	(segment
		(start 242.711224 -50.124614)
		(end 242.711224 -48.731424)
		(width 0.14224)
		(layer "In4.Cu")
		(net "M_C_ECC<5>")
	)
	(segment
		(start 234.983528 -7.264146)
		(end 234.983528 -6.662928)
		(width 0.14224)
		(layer "In4.Cu")
		(net "M_C_ECC<5>")
	)
	(segment
		(start 242.992148 -57.867042)
		(end 242.998498 -57.856374)
		(width 0.0889)
		(layer "In4.Cu")
		(net "M_C_ECC<5>")
	)
	(segment
		(start 235.047028 -7.327646)
		(end 234.983528 -7.264146)
		(width 0.14224)
		(layer "In4.Cu")
		(net "M_C_ECC<5>")
	)
	(segment
		(start 234.983528 -6.662928)
		(end 234.6452 -6.3246)
		(width 0.14224)
		(layer "In4.Cu")
		(net "M_C_ECC<5>")
	)
	(segment
		(start 242.998498 -58.277506)
		(end 242.992148 -58.266838)
		(width 0.0889)
		(layer "In4.Cu")
		(net "M_C_ECC<5>")
	)
	(segment
		(start 234.958128 -18.592546)
		(end 235.047028 -18.503646)
		(width 0.14224)
		(layer "In4.Cu")
		(net "M_C_ECC<5>")
	)
	(segment
		(start 242.711224 -48.731424)
		(end 237.9218 -43.942)
		(width 0.14224)
		(layer "In4.Cu")
		(net "M_C_ECC<5>")
	)
	(segment
		(start 234.6452 -6.3246)
		(end 234.6452 -4.5212)
		(width 0.14224)
		(layer "In4.Cu")
		(net "M_C_ECC<5>")
	)
	(segment
		(start 237.2106 -42.807636)
		(end 237.2106 -42.441876)
		(width 0.14224)
		(layer "In4.Cu")
		(net "M_C_ECC<5>")
	)
	(segment
		(start 242.992148 -64.800988)
		(end 243.001038 -64.785748)
		(width 0.0889)
		(layer "In4.Cu")
		(net "M_C_ECC<5>")
	)
	(segment
		(start 242.992148 -62.819788)
		(end 243.001038 -62.804548)
		(width 0.0889)
		(layer "In4.Cu")
		(net "M_C_ECC<5>")
	)
	(segment
		(start 242.992148 -53.904388)
		(end 243.001038 -53.889148)
		(width 0.0889)
		(layer "In4.Cu")
		(net "M_C_ECC<5>")
	)
	(segment
		(start 237.9218 -43.092116)
		(end 237.77956 -42.949876)
		(width 0.14224)
		(layer "In4.Cu")
		(net "M_C_ECC<5>")
	)
	(segment
		(start 234.958128 -8.991346)
		(end 235.047028 -8.902446)
		(width 0.14224)
		(layer "In4.Cu")
		(net "M_C_ECC<5>")
	)
	(segment
		(start 234.958128 -28.212796)
		(end 235.044996 -28.125928)
		(width 0.14224)
		(layer "In4.Cu")
		(net "M_C_ECC<5>")
	)
	(segment
		(start 234.958128 -26.754328)
		(end 234.958128 -23.308056)
		(width 0.14224)
		(layer "In4.Cu")
		(net "M_C_ECC<5>")
	)
	(segment
		(start 242.992148 -54.894988)
		(end 243.001038 -54.879748)
		(width 0.0889)
		(layer "In4.Cu")
		(net "M_C_ECC<5>")
	)
	(segment
		(start 234.0864 -3.564128)
		(end 234.573572 -3.076956)
		(width 0.14224)
		(layer "In4.Cu")
		(net "M_C_ECC<5>")
	)
	(segment
		(start 235.047028 -8.902446)
		(end 235.047028 -7.327646)
		(width 0.14224)
		(layer "In4.Cu")
		(net "M_C_ECC<5>")
	)
	(segment
		(start 237.77956 -42.299636)
		(end 237.9218 -42.157396)
		(width 0.14224)
		(layer "In4.Cu")
		(net "M_C_ECC<5>")
	)
	(segment
		(start 234.958128 -23.308056)
		(end 235.047028 -23.219156)
		(width 0.14224)
		(layer "In4.Cu")
		(net "M_C_ECC<5>")
	)
	(segment
		(start 234.958128 -28.7528)
		(end 234.958128 -28.212796)
		(width 0.14224)
		(layer "In4.Cu")
		(net "M_C_ECC<5>")
	)
	(segment
		(start 235.047028 -21.961856)
		(end 234.958128 -21.872956)
		(width 0.14224)
		(layer "In4.Cu")
		(net "M_C_ECC<5>")
	)
	(segment
		(start 235.047028 -16.928846)
		(end 234.983528 -16.865346)
		(width 0.14224)
		(layer "In4.Cu")
		(net "M_C_ECC<5>")
	)
	(segment
		(start 237.9218 -43.942)
		(end 237.9218 -43.092116)
		(width 0.14224)
		(layer "In4.Cu")
		(net "M_C_ECC<5>")
	)
	(segment
		(start 235.077 -30.454854)
		(end 235.077 -28.871672)
		(width 0.14224)
		(layer "In4.Cu")
		(net "M_C_ECC<5>")
	)
	(segment
		(start 242.992148 -56.876188)
		(end 243.001038 -56.860948)
		(width 0.0889)
		(layer "In4.Cu")
		(net "M_C_ECC<5>")
	)
	(segment
		(start 243.3828 -68.85051)
		(end 243.612924 -68.264024)
		(width 0.0889)
		(layer "In4.Cu")
		(net "M_C_ECC<5>")
	)
	(segment
		(start 237.77956 -42.949876)
		(end 237.35284 -42.949876)
		(width 0.14224)
		(layer "In4.Cu")
		(net "M_C_ECC<5>")
	)
	(segment
		(start 235.047028 -23.219156)
		(end 235.047028 -21.961856)
		(width 0.14224)
		(layer "In4.Cu")
		(net "M_C_ECC<5>")
	)
	(segment
		(start 242.992148 -60.838588)
		(end 243.001038 -60.823348)
		(width 0.0889)
		(layer "In4.Cu")
		(net "M_C_ECC<5>")
	)
	(arc
		(start 242.992148 -66.191384)
		(mid 242.938615 -65.991486)
		(end 242.992148 -65.791588)
		(width 0.0889)
		(layer "In4.Cu")
		(net "M_C_ECC<5>")
	)
	(arc
		(start 242.992148 -66.782188)
		(mid 243.071279 -66.486786)
		(end 242.992148 -66.191384)
		(width 0.0889)
		(layer "In4.Cu")
		(net "M_C_ECC<5>")
	)
	(arc
		(start 242.992148 -55.294784)
		(mid 242.938615 -55.094886)
		(end 242.992148 -54.894988)
		(width 0.0889)
		(layer "In4.Cu")
		(net "M_C_ECC<5>")
	)
	(arc
		(start 243.001038 -65.776348)
		(mid 243.071435 -65.487397)
		(end 242.992148 -65.200784)
		(width 0.0889)
		(layer "In4.Cu")
		(net "M_C_ECC<5>")
	)
	(arc
		(start 243.49075 -67.59829)
		(mid 243.203475 -67.435609)
		(end 242.992148 -67.181984)
		(width 0.0889)
		(layer "In4.Cu")
		(net "M_C_ECC<5>")
	)
	(arc
		(start 242.992148 -59.257184)
		(mid 242.938615 -59.057286)
		(end 242.992148 -58.857388)
		(width 0.0889)
		(layer "In4.Cu")
		(net "M_C_ECC<5>")
	)
	(arc
		(start 242.992148 -57.275984)
		(mid 242.938615 -57.076086)
		(end 242.992148 -56.876188)
		(width 0.0889)
		(layer "In4.Cu")
		(net "M_C_ECC<5>")
	)
	(arc
		(start 243.001038 -63.795148)
		(mid 243.071435 -63.506197)
		(end 242.992148 -63.219584)
		(width 0.0889)
		(layer "In4.Cu")
		(net "M_C_ECC<5>")
	)
	(arc
		(start 242.992148 -64.210184)
		(mid 242.938615 -64.010286)
		(end 242.992148 -63.810388)
		(width 0.0889)
		(layer "In4.Cu")
		(net "M_C_ECC<5>")
	)
	(arc
		(start 243.001038 -64.785748)
		(mid 243.071435 -64.496797)
		(end 242.992148 -64.210184)
		(width 0.0889)
		(layer "In4.Cu")
		(net "M_C_ECC<5>")
	)
	(arc
		(start 242.998498 -57.856374)
		(mid 243.071418 -57.565357)
		(end 242.992148 -57.275984)
		(width 0.0889)
		(layer "In4.Cu")
		(net "M_C_ECC<5>")
	)
	(arc
		(start 243.612924 -68.264024)
		(mid 243.733202 -67.899091)
		(end 243.493036 -67.599052)
		(width 0.0889)
		(layer "In4.Cu")
		(net "M_C_ECC<5>")
	)
	(arc
		(start 242.992148 -65.200784)
		(mid 242.938615 -65.000886)
		(end 242.992148 -64.800988)
		(width 0.0889)
		(layer "In4.Cu")
		(net "M_C_ECC<5>")
	)
	(arc
		(start 242.992148 -61.238384)
		(mid 242.938615 -61.038486)
		(end 242.992148 -60.838588)
		(width 0.0889)
		(layer "In4.Cu")
		(net "M_C_ECC<5>")
	)
	(arc
		(start 242.992148 -63.219584)
		(mid 242.938615 -63.019686)
		(end 242.992148 -62.819788)
		(width 0.0889)
		(layer "In4.Cu")
		(net "M_C_ECC<5>")
	)
	(arc
		(start 243.001038 -60.823348)
		(mid 243.071435 -60.534397)
		(end 242.992148 -60.247784)
		(width 0.0889)
		(layer "In4.Cu")
		(net "M_C_ECC<5>")
	)
	(arc
		(start 242.992148 -58.266838)
		(mid 242.938615 -58.06694)
		(end 242.992148 -57.867042)
		(width 0.0889)
		(layer "In4.Cu")
		(net "M_C_ECC<5>")
	)
	(arc
		(start 242.992148 -56.285384)
		(mid 242.938615 -56.085486)
		(end 242.992148 -55.885588)
		(width 0.0889)
		(layer "In4.Cu")
		(net "M_C_ECC<5>")
	)
	(arc
		(start 243.001038 -61.813948)
		(mid 243.071435 -61.524997)
		(end 242.992148 -61.238384)
		(width 0.0889)
		(layer "In4.Cu")
		(net "M_C_ECC<5>")
	)
	(arc
		(start 242.992148 -54.304184)
		(mid 242.938615 -54.104286)
		(end 242.992148 -53.904388)
		(width 0.0889)
		(layer "In4.Cu")
		(net "M_C_ECC<5>")
	)
	(arc
		(start 243.001038 -59.832748)
		(mid 243.071435 -59.543797)
		(end 242.992148 -59.257184)
		(width 0.0889)
		(layer "In4.Cu")
		(net "M_C_ECC<5>")
	)
	(arc
		(start 243.001038 -55.870348)
		(mid 243.071435 -55.581397)
		(end 242.992148 -55.294784)
		(width 0.0889)
		(layer "In4.Cu")
		(net "M_C_ECC<5>")
	)
	(arc
		(start 242.992148 -62.228984)
		(mid 242.938615 -62.029086)
		(end 242.992148 -61.829188)
		(width 0.0889)
		(layer "In4.Cu")
		(net "M_C_ECC<5>")
	)
	(arc
		(start 242.992148 -60.247784)
		(mid 242.938615 -60.047886)
		(end 242.992148 -59.847988)
		(width 0.0889)
		(layer "In4.Cu")
		(net "M_C_ECC<5>")
	)
	(arc
		(start 243.001038 -62.804548)
		(mid 243.071435 -62.515597)
		(end 242.992148 -62.228984)
		(width 0.0889)
		(layer "In4.Cu")
		(net "M_C_ECC<5>")
	)
	(arc
		(start 242.992148 -58.857388)
		(mid 243.07137 -58.56827)
		(end 242.998498 -58.277506)
		(width 0.0889)
		(layer "In4.Cu")
		(net "M_C_ECC<5>")
	)
	(arc
		(start 243.001038 -53.889148)
		(mid 243.053558 -53.753554)
		(end 243.071396 -53.60924)
		(width 0.0889)
		(layer "In4.Cu")
		(net "M_C_ECC<5>")
	)
	(arc
		(start 243.001038 -56.860948)
		(mid 243.071435 -56.571997)
		(end 242.992148 -56.285384)
		(width 0.0889)
		(layer "In4.Cu")
		(net "M_C_ECC<5>")
	)
	(arc
		(start 243.001038 -54.879748)
		(mid 243.071435 -54.590797)
		(end 242.992148 -54.304184)
		(width 0.0889)
		(layer "In4.Cu")
		(net "M_C_ECC<5>")
	)
	(arc
		(start 242.992148 -67.181984)
		(mid 242.938615 -66.982086)
		(end 242.992148 -66.782188)
		(width 0.0889)
		(layer "In4.Cu")
		(net "M_C_ECC<5>")
	)
	(segment
		(start 234.884976 -2.765552)
		(end 234.884976 0.53975)
		(width 0.14224)
		(layer "In11.Cu")
		(net "M_C_ECC<5>")
	)
	(segment
		(start 234.573572 -3.076956)
		(end 234.884976 -2.765552)
		(width 0.14224)
		(layer "In11.Cu")
		(net "M_C_ECC<5>")
	)
	(segment
		(start 235.081826 0.7366)
		(end 235.081826 1.149096)
		(width 0.14224)
		(layer "In11.Cu")
		(net "M_C_ECC<5>")
	)
	(segment
		(start 234.370626 1.5494)
		(end 233.799888 2.120138)
		(width 0.14224)
		(layer "In11.Cu")
		(net "M_C_ECC<5>")
	)
	(segment
		(start 235.081826 1.149096)
		(end 234.681522 1.5494)
		(width 0.14224)
		(layer "In11.Cu")
		(net "M_C_ECC<5>")
	)
	(segment
		(start 233.799888 2.120138)
		(end 233.799888 2.514854)
		(width 0.14224)
		(layer "In11.Cu")
		(net "M_C_ECC<5>")
	)
	(segment
		(start 234.884976 0.53975)
		(end 235.081826 0.7366)
		(width 0.14224)
		(layer "In11.Cu")
		(net "M_C_ECC<5>")
	)
	(segment
		(start 234.681522 1.5494)
		(end 234.370626 1.5494)
		(width 0.14224)
		(layer "In11.Cu")
		(net "M_C_ECC<5>")
	)
	(segment
		(start 234.649772 0.510032)
		(end 234.551728 1.0414)
		(width 0.1651)
		(layer "F.Cu")
		(net "M_C_ECC<4>")
	)
	(segment
		(start 234.649772 -0.821182)
		(end 234.649772 0.510032)
		(width 0.1651)
		(layer "F.Cu")
		(net "M_C_ECC<4>")
	)
	(segment
		(start 243.910104 -67.972686)
		(end 243.338604 -67.972686)
		(width 0.0889)
		(layer "F.Cu")
		(net "M_C_ECC<4>")
	)
	(segment
		(start 234.65028 -0.821182)
		(end 234.649772 -0.821182)
		(width 0.1651)
		(layer "F.Cu")
		(net "M_C_ECC<4>")
	)
	(via
		(at 233.799888 -4.357878)
		(size 0.508)
		(drill 0.254)
		(layers "F.Cu" "B.Cu")
		(net "M_C_ECC<4>")
	)
	(via
		(at 243.338604 -67.972686)
		(size 0.508)
		(drill 0.254)
		(layers "F.Cu" "B.Cu")
		(net "M_C_ECC<4>")
	)
	(via
		(at 234.551728 1.0414)
		(size 0.508)
		(drill 0.254)
		(layers "F.Cu" "B.Cu")
		(net "M_C_ECC<4>")
	)
	(segment
		(start 233.800396 -5.621782)
		(end 233.799888 -5.621782)
		(width 0.1651)
		(layer "B.Cu")
		(net "M_C_ECC<4>")
	)
	(segment
		(start 233.799888 -5.621782)
		(end 233.799888 -4.357878)
		(width 0.1651)
		(layer "B.Cu")
		(net "M_C_ECC<4>")
	)
	(segment
		(start 234.297728 -16.831818)
		(end 234.297728 -16.22679)
		(width 0.14224)
		(layer "In4.Cu")
		(net "M_C_ECC<4>")
	)
	(segment
		(start 234.297728 -23.396956)
		(end 234.069128 -23.168356)
		(width 0.14224)
		(layer "In4.Cu")
		(net "M_C_ECC<4>")
	)
	(segment
		(start 234.054396 -26.993596)
		(end 234.297728 -26.750264)
		(width 0.14224)
		(layer "In4.Cu")
		(net "M_C_ECC<4>")
	)
	(segment
		(start 234.297728 -16.22679)
		(end 234.0864 -16.015462)
		(width 0.14224)
		(layer "In4.Cu")
		(net "M_C_ECC<4>")
	)
	(segment
		(start 236.81944 -39.301674)
		(end 236.6772 -39.159434)
		(width 0.14224)
		(layer "In4.Cu")
		(net "M_C_ECC<4>")
	)
	(segment
		(start 236.6772 -39.159434)
		(end 236.6772 -36.524946)
		(width 0.14224)
		(layer "In4.Cu")
		(net "M_C_ECC<4>")
	)
	(segment
		(start 236.81944 -40.602154)
		(end 236.6772 -40.459914)
		(width 0.14224)
		(layer "In4.Cu")
		(net "M_C_ECC<4>")
	)
	(segment
		(start 234.069128 -18.313146)
		(end 234.069128 -17.060418)
		(width 0.14224)
		(layer "In4.Cu")
		(net "M_C_ECC<4>")
	)
	(segment
		(start 234.442 -29.1338)
		(end 234.297728 -28.989528)
		(width 0.14224)
		(layer "In4.Cu")
		(net "M_C_ECC<4>")
	)
	(segment
		(start 237.16996 -41.252394)
		(end 237.3122 -41.110154)
		(width 0.14224)
		(layer "In4.Cu")
		(net "M_C_ECC<4>")
	)
	(segment
		(start 237.3122 -39.809674)
		(end 237.3122 -39.443914)
		(width 0.14224)
		(layer "In4.Cu")
		(net "M_C_ECC<4>")
	)
	(segment
		(start 237.16996 -40.602154)
		(end 236.81944 -40.602154)
		(width 0.14224)
		(layer "In4.Cu")
		(net "M_C_ECC<4>")
	)
	(segment
		(start 236.5121 -36.359846)
		(end 236.5121 -33.019746)
		(width 0.14224)
		(layer "In4.Cu")
		(net "M_C_ECC<4>")
	)
	(segment
		(start 234.0864 -25.885648)
		(end 234.0864 -25.284176)
		(width 0.14224)
		(layer "In4.Cu")
		(net "M_C_ECC<4>")
	)
	(segment
		(start 242.826794 -58.362088)
		(end 242.820444 -58.35142)
		(width 0.0889)
		(layer "In4.Cu")
		(net "M_C_ECC<4>")
	)
	(segment
		(start 237.3122 -40.744394)
		(end 237.16996 -40.602154)
		(width 0.14224)
		(layer "In4.Cu")
		(net "M_C_ECC<4>")
	)
	(segment
		(start 234.054396 -28.121864)
		(end 234.054396 -26.993596)
		(width 0.14224)
		(layer "In4.Cu")
		(net "M_C_ECC<4>")
	)
	(segment
		(start 242.817904 -62.739778)
		(end 242.826794 -62.724538)
		(width 0.0889)
		(layer "In4.Cu")
		(net "M_C_ECC<4>")
	)
	(segment
		(start 233.799888 -6.419088)
		(end 233.799888 -4.357878)
		(width 0.14224)
		(layer "In4.Cu")
		(net "M_C_ECC<4>")
	)
	(segment
		(start 234.2642 -6.8834)
		(end 233.799888 -6.419088)
		(width 0.14224)
		(layer "In4.Cu")
		(net "M_C_ECC<4>")
	)
	(segment
		(start 234.1118 -20.720558)
		(end 234.1118 -20.119086)
		(width 0.14224)
		(layer "In4.Cu")
		(net "M_C_ECC<4>")
	)
	(segment
		(start 234.069128 -12.347956)
		(end 234.323128 -12.093956)
		(width 0.14224)
		(layer "In4.Cu")
		(net "M_C_ECC<4>")
	)
	(segment
		(start 242.817904 -63.730378)
		(end 242.826794 -63.715138)
		(width 0.0889)
		(layer "In4.Cu")
		(net "M_C_ECC<4>")
	)
	(segment
		(start 242.817904 -54.814978)
		(end 242.826794 -54.799738)
		(width 0.0889)
		(layer "In4.Cu")
		(net "M_C_ECC<4>")
	)
	(segment
		(start 242.820444 -58.772552)
		(end 242.826794 -58.761884)
		(width 0.0889)
		(layer "In4.Cu")
		(net "M_C_ECC<4>")
	)
	(segment
		(start 234.2642 -7.238746)
		(end 234.2642 -6.8834)
		(width 0.14224)
		(layer "In4.Cu")
		(net "M_C_ECC<4>")
	)
	(segment
		(start 242.817904 -53.824378)
		(end 242.826794 -53.809138)
		(width 0.0889)
		(layer "In4.Cu")
		(net "M_C_ECC<4>")
	)
	(segment
		(start 234.297728 -25.072848)
		(end 234.297728 -23.396956)
		(width 0.14224)
		(layer "In4.Cu")
		(net "M_C_ECC<4>")
	)
	(segment
		(start 242.1001 -49.0474)
		(end 236.6772 -43.6245)
		(width 0.14224)
		(layer "In4.Cu")
		(net "M_C_ECC<4>")
	)
	(segment
		(start 234.323128 -8.965946)
		(end 234.069128 -8.711946)
		(width 0.14224)
		(layer "In4.Cu")
		(net "M_C_ECC<4>")
	)
	(segment
		(start 236.6772 -36.524946)
		(end 236.5121 -36.359846)
		(width 0.14224)
		(layer "In4.Cu")
		(net "M_C_ECC<4>")
	)
	(segment
		(start 234.069128 -13.567156)
		(end 234.069128 -12.347956)
		(width 0.14224)
		(layer "In4.Cu")
		(net "M_C_ECC<4>")
	)
	(segment
		(start 243.338604 -67.972686)
		(end 243.27993 -67.90944)
		(width 0.0889)
		(layer "In4.Cu")
		(net "M_C_ECC<4>")
	)
	(segment
		(start 234.297728 -26.096976)
		(end 234.0864 -25.885648)
		(width 0.14224)
		(layer "In4.Cu")
		(net "M_C_ECC<4>")
	)
	(segment
		(start 236.81944 -39.951914)
		(end 237.16996 -39.951914)
		(width 0.14224)
		(layer "In4.Cu")
		(net "M_C_ECC<4>")
	)
	(segment
		(start 242.817904 -56.796178)
		(end 242.826794 -56.780938)
		(width 0.0889)
		(layer "In4.Cu")
		(net "M_C_ECC<4>")
	)
	(segment
		(start 236.5121 -33.019746)
		(end 234.442 -30.949646)
		(width 0.14224)
		(layer "In4.Cu")
		(net "M_C_ECC<4>")
	)
	(segment
		(start 242.817904 -60.758578)
		(end 242.826794 -60.743338)
		(width 0.0889)
		(layer "In4.Cu")
		(net "M_C_ECC<4>")
	)
	(segment
		(start 234.442 -30.949646)
		(end 234.442 -29.1338)
		(width 0.14224)
		(layer "In4.Cu")
		(net "M_C_ECC<4>")
	)
	(segment
		(start 234.323128 -21.695156)
		(end 234.323128 -20.931886)
		(width 0.14224)
		(layer "In4.Cu")
		(net "M_C_ECC<4>")
	)
	(segment
		(start 234.1118 -20.119086)
		(end 234.323128 -19.907758)
		(width 0.14224)
		(layer "In4.Cu")
		(net "M_C_ECC<4>")
	)
	(segment
		(start 234.323128 -19.907758)
		(end 234.323128 -18.567146)
		(width 0.14224)
		(layer "In4.Cu")
		(net "M_C_ECC<4>")
	)
	(segment
		(start 236.81944 -41.252394)
		(end 237.16996 -41.252394)
		(width 0.14224)
		(layer "In4.Cu")
		(net "M_C_ECC<4>")
	)
	(segment
		(start 242.830858 -67.2846)
		(end 242.826794 -67.277488)
		(width 0.0889)
		(layer "In4.Cu")
		(net "M_C_ECC<4>")
	)
	(segment
		(start 234.069128 -17.060418)
		(end 234.297728 -16.831818)
		(width 0.14224)
		(layer "In4.Cu")
		(net "M_C_ECC<4>")
	)
	(segment
		(start 234.323128 -20.931886)
		(end 234.1118 -20.720558)
		(width 0.14224)
		(layer "In4.Cu")
		(net "M_C_ECC<4>")
	)
	(segment
		(start 234.297728 -28.365196)
		(end 234.054396 -28.121864)
		(width 0.14224)
		(layer "In4.Cu")
		(net "M_C_ECC<4>")
	)
	(segment
		(start 234.0864 -25.284176)
		(end 234.297728 -25.072848)
		(width 0.14224)
		(layer "In4.Cu")
		(net "M_C_ECC<4>")
	)
	(segment
		(start 234.297728 -26.750264)
		(end 234.297728 -26.096976)
		(width 0.14224)
		(layer "In4.Cu")
		(net "M_C_ECC<4>")
	)
	(segment
		(start 242.880388 -51.689254)
		(end 242.299236 -51.108102)
		(width 0.0889)
		(layer "In4.Cu")
		(net "M_C_ECC<4>")
	)
	(segment
		(start 234.323128 -10.384028)
		(end 234.323128 -8.965946)
		(width 0.14224)
		(layer "In4.Cu")
		(net "M_C_ECC<4>")
	)
	(segment
		(start 234.0864 -15.41399)
		(end 234.297728 -15.202662)
		(width 0.14224)
		(layer "In4.Cu")
		(net "M_C_ECC<4>")
	)
	(segment
		(start 237.16996 -39.951914)
		(end 237.3122 -39.809674)
		(width 0.14224)
		(layer "In4.Cu")
		(net "M_C_ECC<4>")
	)
	(segment
		(start 234.069128 -23.168356)
		(end 234.069128 -21.949156)
		(width 0.14224)
		(layer "In4.Cu")
		(net "M_C_ECC<4>")
	)
	(segment
		(start 234.323128 -18.567146)
		(end 234.069128 -18.313146)
		(width 0.14224)
		(layer "In4.Cu")
		(net "M_C_ECC<4>")
	)
	(segment
		(start 237.3122 -41.110154)
		(end 237.3122 -40.744394)
		(width 0.14224)
		(layer "In4.Cu")
		(net "M_C_ECC<4>")
	)
	(segment
		(start 234.069128 -8.711946)
		(end 234.069128 -7.433818)
		(width 0.14224)
		(layer "In4.Cu")
		(net "M_C_ECC<4>")
	)
	(segment
		(start 234.0864 -16.015462)
		(end 234.0864 -15.41399)
		(width 0.14224)
		(layer "In4.Cu")
		(net "M_C_ECC<4>")
	)
	(segment
		(start 237.16996 -39.301674)
		(end 236.81944 -39.301674)
		(width 0.14224)
		(layer "In4.Cu")
		(net "M_C_ECC<4>")
	)
	(segment
		(start 234.069128 -21.949156)
		(end 234.323128 -21.695156)
		(width 0.14224)
		(layer "In4.Cu")
		(net "M_C_ECC<4>")
	)
	(segment
		(start 242.817904 -59.767978)
		(end 242.826794 -59.752738)
		(width 0.0889)
		(layer "In4.Cu")
		(net "M_C_ECC<4>")
	)
	(segment
		(start 234.297728 -28.989528)
		(end 234.297728 -28.365196)
		(width 0.14224)
		(layer "In4.Cu")
		(net "M_C_ECC<4>")
	)
	(segment
		(start 242.076224 -50.124614)
		(end 242.1001 -50.100738)
		(width 0.14224)
		(layer "In4.Cu")
		(net "M_C_ECC<4>")
	)
	(segment
		(start 242.880388 -53.60924)
		(end 242.880388 -51.689254)
		(width 0.0889)
		(layer "In4.Cu")
		(net "M_C_ECC<4>")
	)
	(segment
		(start 236.6772 -40.094154)
		(end 236.81944 -39.951914)
		(width 0.14224)
		(layer "In4.Cu")
		(net "M_C_ECC<4>")
	)
	(segment
		(start 242.817904 -55.805578)
		(end 242.826794 -55.790338)
		(width 0.0889)
		(layer "In4.Cu")
		(net "M_C_ECC<4>")
	)
	(segment
		(start 242.817904 -65.711578)
		(end 242.826794 -65.696338)
		(width 0.0889)
		(layer "In4.Cu")
		(net "M_C_ECC<4>")
	)
	(segment
		(start 234.297728 -13.795756)
		(end 234.069128 -13.567156)
		(width 0.14224)
		(layer "In4.Cu")
		(net "M_C_ECC<4>")
	)
	(segment
		(start 242.299236 -50.347626)
		(end 242.076224 -50.124614)
		(width 0.0889)
		(layer "In4.Cu")
		(net "M_C_ECC<4>")
	)
	(segment
		(start 242.817904 -61.749178)
		(end 242.826794 -61.733938)
		(width 0.0889)
		(layer "In4.Cu")
		(net "M_C_ECC<4>")
	)
	(segment
		(start 234.0864 -10.620756)
		(end 234.323128 -10.384028)
		(width 0.14224)
		(layer "In4.Cu")
		(net "M_C_ECC<4>")
	)
	(segment
		(start 234.323128 -12.093956)
		(end 234.323128 -11.433556)
		(width 0.14224)
		(layer "In4.Cu")
		(net "M_C_ECC<4>")
	)
	(segment
		(start 242.1001 -50.100738)
		(end 242.1001 -49.0474)
		(width 0.14224)
		(layer "In4.Cu")
		(net "M_C_ECC<4>")
	)
	(segment
		(start 234.323128 -11.433556)
		(end 234.0864 -11.196828)
		(width 0.14224)
		(layer "In4.Cu")
		(net "M_C_ECC<4>")
	)
	(segment
		(start 236.6772 -43.6245)
		(end 236.6772 -41.394634)
		(width 0.14224)
		(layer "In4.Cu")
		(net "M_C_ECC<4>")
	)
	(segment
		(start 234.069128 -7.433818)
		(end 234.2642 -7.238746)
		(width 0.14224)
		(layer "In4.Cu")
		(net "M_C_ECC<4>")
	)
	(segment
		(start 236.6772 -40.459914)
		(end 236.6772 -40.094154)
		(width 0.14224)
		(layer "In4.Cu")
		(net "M_C_ECC<4>")
	)
	(segment
		(start 242.299236 -51.108102)
		(end 242.299236 -50.347626)
		(width 0.0889)
		(layer "In4.Cu")
		(net "M_C_ECC<4>")
	)
	(segment
		(start 242.817904 -64.720978)
		(end 242.826794 -64.705738)
		(width 0.0889)
		(layer "In4.Cu")
		(net "M_C_ECC<4>")
	)
	(segment
		(start 234.0864 -11.196828)
		(end 234.0864 -10.620756)
		(width 0.14224)
		(layer "In4.Cu")
		(net "M_C_ECC<4>")
	)
	(segment
		(start 236.6772 -41.394634)
		(end 236.81944 -41.252394)
		(width 0.14224)
		(layer "In4.Cu")
		(net "M_C_ECC<4>")
	)
	(segment
		(start 234.297728 -15.202662)
		(end 234.297728 -13.795756)
		(width 0.14224)
		(layer "In4.Cu")
		(net "M_C_ECC<4>")
	)
	(segment
		(start 237.3122 -39.443914)
		(end 237.16996 -39.301674)
		(width 0.14224)
		(layer "In4.Cu")
		(net "M_C_ECC<4>")
	)
	(arc
		(start 242.826794 -58.761884)
		(mid 242.880327 -58.561986)
		(end 242.826794 -58.362088)
		(width 0.0889)
		(layer "In4.Cu")
		(net "M_C_ECC<4>")
	)
	(arc
		(start 242.826794 -57.771538)
		(mid 242.880327 -57.57164)
		(end 242.826794 -57.371742)
		(width 0.0889)
		(layer "In4.Cu")
		(net "M_C_ECC<4>")
	)
	(arc
		(start 242.820444 -58.35142)
		(mid 242.747646 -58.060657)
		(end 242.826794 -57.771538)
		(width 0.0889)
		(layer "In4.Cu")
		(net "M_C_ECC<4>")
	)
	(arc
		(start 242.826794 -60.743338)
		(mid 242.880327 -60.54344)
		(end 242.826794 -60.343542)
		(width 0.0889)
		(layer "In4.Cu")
		(net "M_C_ECC<4>")
	)
	(arc
		(start 242.826794 -66.286888)
		(mid 242.747674 -66.000385)
		(end 242.817904 -65.711578)
		(width 0.0889)
		(layer "In4.Cu")
		(net "M_C_ECC<4>")
	)
	(arc
		(start 242.826794 -64.305942)
		(mid 242.747605 -64.019327)
		(end 242.817904 -63.730378)
		(width 0.0889)
		(layer "In4.Cu")
		(net "M_C_ECC<4>")
	)
	(arc
		(start 242.826794 -53.809138)
		(mid 242.866712 -53.712711)
		(end 242.880388 -53.60924)
		(width 0.0889)
		(layer "In4.Cu")
		(net "M_C_ECC<4>")
	)
	(arc
		(start 242.826794 -56.381142)
		(mid 242.747605 -56.094527)
		(end 242.817904 -55.805578)
		(width 0.0889)
		(layer "In4.Cu")
		(net "M_C_ECC<4>")
	)
	(arc
		(start 242.826794 -57.371742)
		(mid 242.747605 -57.085127)
		(end 242.817904 -56.796178)
		(width 0.0889)
		(layer "In4.Cu")
		(net "M_C_ECC<4>")
	)
	(arc
		(start 242.826794 -66.686684)
		(mid 242.880327 -66.486786)
		(end 242.826794 -66.286888)
		(width 0.0889)
		(layer "In4.Cu")
		(net "M_C_ECC<4>")
	)
	(arc
		(start 242.826794 -54.399942)
		(mid 242.747605 -54.113327)
		(end 242.817904 -53.824378)
		(width 0.0889)
		(layer "In4.Cu")
		(net "M_C_ECC<4>")
	)
	(arc
		(start 242.826794 -60.343542)
		(mid 242.747605 -60.056927)
		(end 242.817904 -59.767978)
		(width 0.0889)
		(layer "In4.Cu")
		(net "M_C_ECC<4>")
	)
	(arc
		(start 242.826794 -56.780938)
		(mid 242.880327 -56.58104)
		(end 242.826794 -56.381142)
		(width 0.0889)
		(layer "In4.Cu")
		(net "M_C_ECC<4>")
	)
	(arc
		(start 242.826794 -65.696338)
		(mid 242.880327 -65.49644)
		(end 242.826794 -65.296542)
		(width 0.0889)
		(layer "In4.Cu")
		(net "M_C_ECC<4>")
	)
	(arc
		(start 242.826794 -61.334142)
		(mid 242.747605 -61.047527)
		(end 242.817904 -60.758578)
		(width 0.0889)
		(layer "In4.Cu")
		(net "M_C_ECC<4>")
	)
	(arc
		(start 242.826794 -65.296542)
		(mid 242.747605 -65.009927)
		(end 242.817904 -64.720978)
		(width 0.0889)
		(layer "In4.Cu")
		(net "M_C_ECC<4>")
	)
	(arc
		(start 242.826794 -61.733938)
		(mid 242.880327 -61.53404)
		(end 242.826794 -61.334142)
		(width 0.0889)
		(layer "In4.Cu")
		(net "M_C_ECC<4>")
	)
	(arc
		(start 242.826794 -62.324742)
		(mid 242.747605 -62.038127)
		(end 242.817904 -61.749178)
		(width 0.0889)
		(layer "In4.Cu")
		(net "M_C_ECC<4>")
	)
	(arc
		(start 242.826794 -64.705738)
		(mid 242.880327 -64.50584)
		(end 242.826794 -64.305942)
		(width 0.0889)
		(layer "In4.Cu")
		(net "M_C_ECC<4>")
	)
	(arc
		(start 242.826794 -55.790338)
		(mid 242.880327 -55.59044)
		(end 242.826794 -55.390542)
		(width 0.0889)
		(layer "In4.Cu")
		(net "M_C_ECC<4>")
	)
	(arc
		(start 242.826794 -62.724538)
		(mid 242.880327 -62.52464)
		(end 242.826794 -62.324742)
		(width 0.0889)
		(layer "In4.Cu")
		(net "M_C_ECC<4>")
	)
	(arc
		(start 242.826794 -59.352942)
		(mid 242.747445 -59.06357)
		(end 242.820444 -58.772552)
		(width 0.0889)
		(layer "In4.Cu")
		(net "M_C_ECC<4>")
	)
	(arc
		(start 242.826794 -63.715138)
		(mid 242.880327 -63.51524)
		(end 242.826794 -63.315342)
		(width 0.0889)
		(layer "In4.Cu")
		(net "M_C_ECC<4>")
	)
	(arc
		(start 242.826794 -67.277488)
		(mid 242.747663 -66.982086)
		(end 242.826794 -66.686684)
		(width 0.0889)
		(layer "In4.Cu")
		(net "M_C_ECC<4>")
	)
	(arc
		(start 242.826794 -55.390542)
		(mid 242.747605 -55.103927)
		(end 242.817904 -54.814978)
		(width 0.0889)
		(layer "In4.Cu")
		(net "M_C_ECC<4>")
	)
	(arc
		(start 242.826794 -54.799738)
		(mid 242.880327 -54.59984)
		(end 242.826794 -54.399942)
		(width 0.0889)
		(layer "In4.Cu")
		(net "M_C_ECC<4>")
	)
	(arc
		(start 243.27993 -67.90944)
		(mid 243.039783 -67.608239)
		(end 242.830858 -67.2846)
		(width 0.0889)
		(layer "In4.Cu")
		(net "M_C_ECC<4>")
	)
	(arc
		(start 242.826794 -59.752738)
		(mid 242.880327 -59.55284)
		(end 242.826794 -59.352942)
		(width 0.0889)
		(layer "In4.Cu")
		(net "M_C_ECC<4>")
	)
	(arc
		(start 242.826794 -63.315342)
		(mid 242.747605 -63.028727)
		(end 242.817904 -62.739778)
		(width 0.0889)
		(layer "In4.Cu")
		(net "M_C_ECC<4>")
	)
	(segment
		(start 234.275376 0.765048)
		(end 234.551728 1.0414)
		(width 0.14224)
		(layer "In11.Cu")
		(net "M_C_ECC<4>")
	)
	(segment
		(start 233.564176 -3.327654)
		(end 234.275376 -2.616454)
		(width 0.14224)
		(layer "In11.Cu")
		(net "M_C_ECC<4>")
	)
	(segment
		(start 233.564176 -4.122166)
		(end 233.564176 -3.327654)
		(width 0.14224)
		(layer "In11.Cu")
		(net "M_C_ECC<4>")
	)
	(segment
		(start 233.799888 -4.357878)
		(end 233.564176 -4.122166)
		(width 0.14224)
		(layer "In11.Cu")
		(net "M_C_ECC<4>")
	)
	(segment
		(start 234.275376 -2.616454)
		(end 234.275376 0.765048)
		(width 0.14224)
		(layer "In11.Cu")
		(net "M_C_ECC<4>")
	)
	(segment
		(start 241.44986 3.778758)
		(end 241.44986 2.514854)
		(width 0.1651)
		(layer "F.Cu")
		(net "M_C_ECC<3>")
	)
	(segment
		(start 241.450368 3.778758)
		(end 241.44986 3.778758)
		(width 0.1651)
		(layer "F.Cu")
		(net "M_C_ECC<3>")
	)
	(segment
		(start 247.344184 -68.963286)
		(end 246.772684 -68.963286)
		(width 0.0889)
		(layer "F.Cu")
		(net "M_C_ECC<3>")
	)
	(via
		(at 241.44986 2.514854)
		(size 0.508)
		(drill 0.254)
		(layers "F.Cu" "B.Cu")
		(net "M_C_ECC<3>")
	)
	(via
		(at 246.772684 -68.963286)
		(size 0.508)
		(drill 0.254)
		(layers "F.Cu" "B.Cu")
		(net "M_C_ECC<3>")
	)
	(via
		(at 242.299744 -3.076956)
		(size 0.508)
		(drill 0.254)
		(layers "F.Cu" "B.Cu")
		(net "M_C_ECC<3>")
	)
	(segment
		(start 242.300506 -3.076194)
		(end 242.299744 -3.076956)
		(width 0.1651)
		(layer "B.Cu")
		(net "M_C_ECC<3>")
	)
	(segment
		(start 242.300506 -1.021842)
		(end 242.300506 -3.076194)
		(width 0.1651)
		(layer "B.Cu")
		(net "M_C_ECC<3>")
	)
	(segment
		(start 242.667028 -4.796028)
		(end 242.667028 -7.289546)
		(width 0.14224)
		(layer "In4.Cu")
		(net "M_C_ECC<3>")
	)
	(segment
		(start 242.817396 -28.606496)
		(end 245.4148 -31.2039)
		(width 0.14224)
		(layer "In4.Cu")
		(net "M_C_ECC<3>")
	)
	(segment
		(start 242.806728 -7.429246)
		(end 242.806728 -8.831326)
		(width 0.14224)
		(layer "In4.Cu")
		(net "M_C_ECC<3>")
	)
	(segment
		(start 242.784122 -13.577062)
		(end 242.667028 -13.694156)
		(width 0.14224)
		(layer "In4.Cu")
		(net "M_C_ECC<3>")
	)
	(segment
		(start 242.667028 -13.694156)
		(end 242.667028 -16.890746)
		(width 0.14224)
		(layer "In4.Cu")
		(net "M_C_ECC<3>")
	)
	(segment
		(start 247.231408 -68.153534)
		(end 247.093994 -68.290948)
		(width 0.0889)
		(layer "In4.Cu")
		(net "M_C_ECC<3>")
	)
	(segment
		(start 247.284494 -64.705738)
		(end 247.290844 -64.716406)
		(width 0.0889)
		(layer "In4.Cu")
		(net "M_C_ECC<3>")
	)
	(segment
		(start 247.279668 -65.687702)
		(end 247.284494 -65.696338)
		(width 0.0889)
		(layer "In4.Cu")
		(net "M_C_ECC<3>")
	)
	(segment
		(start 248.9835 -50.11039)
		(end 248.985024 -50.111914)
		(width 0.14224)
		(layer "In4.Cu")
		(net "M_C_ECC<3>")
	)
	(segment
		(start 242.806728 -8.831326)
		(end 242.654328 -8.983726)
		(width 0.14224)
		(layer "In4.Cu")
		(net "M_C_ECC<3>")
	)
	(segment
		(start 247.284494 -65.696338)
		(end 247.290844 -65.707006)
		(width 0.0889)
		(layer "In4.Cu")
		(net "M_C_ECC<3>")
	)
	(segment
		(start 242.299744 -3.076956)
		(end 241.816128 -3.560572)
		(width 0.14224)
		(layer "In4.Cu")
		(net "M_C_ECC<3>")
	)
	(segment
		(start 242.654328 -21.822156)
		(end 242.781328 -21.949156)
		(width 0.14224)
		(layer "In4.Cu")
		(net "M_C_ECC<3>")
	)
	(segment
		(start 247.284494 -63.715138)
		(end 247.290844 -63.725806)
		(width 0.0889)
		(layer "In4.Cu")
		(net "M_C_ECC<3>")
	)
	(segment
		(start 248.743724 -50.468022)
		(end 248.145808 -51.065938)
		(width 0.0889)
		(layer "In4.Cu")
		(net "M_C_ECC<3>")
	)
	(segment
		(start 247.284494 -61.733938)
		(end 247.290844 -61.744606)
		(width 0.0889)
		(layer "In4.Cu")
		(net "M_C_ECC<3>")
	)
	(segment
		(start 247.093994 -68.290948)
		(end 246.772684 -68.963286)
		(width 0.0889)
		(layer "In4.Cu")
		(net "M_C_ECC<3>")
	)
	(segment
		(start 247.363742 -55.771796)
		(end 247.363742 -56.085486)
		(width 0.0889)
		(layer "In4.Cu")
		(net "M_C_ECC<3>")
	)
	(segment
		(start 247.290844 -58.35142)
		(end 247.284494 -58.362088)
		(width 0.0889)
		(layer "In4.Cu")
		(net "M_C_ECC<3>")
	)
	(segment
		(start 242.667028 -7.289546)
		(end 242.806728 -7.429246)
		(width 0.14224)
		(layer "In4.Cu")
		(net "M_C_ECC<3>")
	)
	(segment
		(start 247.279668 -59.744102)
		(end 247.284494 -59.752738)
		(width 0.0889)
		(layer "In4.Cu")
		(net "M_C_ECC<3>")
	)
	(segment
		(start 247.284494 -56.780938)
		(end 247.290844 -56.791606)
		(width 0.0889)
		(layer "In4.Cu")
		(net "M_C_ECC<3>")
	)
	(segment
		(start 247.279668 -61.725302)
		(end 247.284494 -61.733938)
		(width 0.0889)
		(layer "In4.Cu")
		(net "M_C_ECC<3>")
	)
	(segment
		(start 247.279668 -60.734702)
		(end 247.284494 -60.743338)
		(width 0.0889)
		(layer "In4.Cu")
		(net "M_C_ECC<3>")
	)
	(segment
		(start 247.279668 -63.706502)
		(end 247.284494 -63.715138)
		(width 0.0889)
		(layer "In4.Cu")
		(net "M_C_ECC<3>")
	)
	(segment
		(start 248.9835 -46.4185)
		(end 248.9835 -50.11039)
		(width 0.14224)
		(layer "In4.Cu")
		(net "M_C_ECC<3>")
	)
	(segment
		(start 242.817396 -26.383996)
		(end 242.817396 -28.606496)
		(width 0.14224)
		(layer "In4.Cu")
		(net "M_C_ECC<3>")
	)
	(segment
		(start 242.57 -26.1366)
		(end 242.817396 -26.383996)
		(width 0.14224)
		(layer "In4.Cu")
		(net "M_C_ECC<3>")
	)
	(segment
		(start 242.784122 -12.33805)
		(end 242.784122 -13.577062)
		(width 0.14224)
		(layer "In4.Cu")
		(net "M_C_ECC<3>")
	)
	(segment
		(start 248.145808 -52.526946)
		(end 247.212358 -53.460396)
		(width 0.0889)
		(layer "In4.Cu")
		(net "M_C_ECC<3>")
	)
	(segment
		(start 242.57 -23.445724)
		(end 242.57 -26.1366)
		(width 0.14224)
		(layer "In4.Cu")
		(net "M_C_ECC<3>")
	)
	(segment
		(start 242.654328 -8.983726)
		(end 242.654328 -12.208256)
		(width 0.14224)
		(layer "In4.Cu")
		(net "M_C_ECC<3>")
	)
	(segment
		(start 245.4148 -31.2039)
		(end 245.4148 -43.031156)
		(width 0.14224)
		(layer "In4.Cu")
		(net "M_C_ECC<3>")
	)
	(segment
		(start 245.4148 -43.031156)
		(end 246.849138 -44.465494)
		(width 0.14224)
		(layer "In4.Cu")
		(net "M_C_ECC<3>")
	)
	(segment
		(start 247.231408 -67.472052)
		(end 247.231408 -68.153534)
		(width 0.0889)
		(layer "In4.Cu")
		(net "M_C_ECC<3>")
	)
	(segment
		(start 247.284494 -60.743338)
		(end 247.290844 -60.754006)
		(width 0.0889)
		(layer "In4.Cu")
		(net "M_C_ECC<3>")
	)
	(segment
		(start 247.212358 -55.620412)
		(end 247.363742 -55.771796)
		(width 0.0889)
		(layer "In4.Cu")
		(net "M_C_ECC<3>")
	)
	(segment
		(start 241.816128 -3.945128)
		(end 242.667028 -4.796028)
		(width 0.14224)
		(layer "In4.Cu")
		(net "M_C_ECC<3>")
	)
	(segment
		(start 247.279668 -57.762902)
		(end 247.284494 -57.771538)
		(width 0.0889)
		(layer "In4.Cu")
		(net "M_C_ECC<3>")
	)
	(segment
		(start 246.849138 -44.465494)
		(end 247.030494 -44.465494)
		(width 0.14224)
		(layer "In4.Cu")
		(net "M_C_ECC<3>")
	)
	(segment
		(start 247.279668 -56.772302)
		(end 247.284494 -56.780938)
		(width 0.0889)
		(layer "In4.Cu")
		(net "M_C_ECC<3>")
	)
	(segment
		(start 241.816128 -3.560572)
		(end 241.816128 -3.945128)
		(width 0.14224)
		(layer "In4.Cu")
		(net "M_C_ECC<3>")
	)
	(segment
		(start 242.794028 -17.017746)
		(end 242.794028 -18.419318)
		(width 0.14224)
		(layer "In4.Cu")
		(net "M_C_ECC<3>")
	)
	(segment
		(start 247.279668 -64.697102)
		(end 247.284494 -64.705738)
		(width 0.0889)
		(layer "In4.Cu")
		(net "M_C_ECC<3>")
	)
	(segment
		(start 242.667028 -16.890746)
		(end 242.794028 -17.017746)
		(width 0.14224)
		(layer "In4.Cu")
		(net "M_C_ECC<3>")
	)
	(segment
		(start 242.654328 -12.208256)
		(end 242.784122 -12.33805)
		(width 0.14224)
		(layer "In4.Cu")
		(net "M_C_ECC<3>")
	)
	(segment
		(start 242.781328 -23.234396)
		(end 242.57 -23.445724)
		(width 0.14224)
		(layer "In4.Cu")
		(net "M_C_ECC<3>")
	)
	(segment
		(start 247.030494 -44.465494)
		(end 248.9835 -46.4185)
		(width 0.14224)
		(layer "In4.Cu")
		(net "M_C_ECC<3>")
	)
	(segment
		(start 242.654328 -18.559018)
		(end 242.654328 -21.822156)
		(width 0.14224)
		(layer "In4.Cu")
		(net "M_C_ECC<3>")
	)
	(segment
		(start 247.284494 -59.752738)
		(end 247.290844 -59.763406)
		(width 0.0889)
		(layer "In4.Cu")
		(net "M_C_ECC<3>")
	)
	(segment
		(start 247.284494 -62.724538)
		(end 247.290844 -62.735206)
		(width 0.0889)
		(layer "In4.Cu")
		(net "M_C_ECC<3>")
	)
	(segment
		(start 247.284494 -66.686938)
		(end 247.290844 -66.697606)
		(width 0.0889)
		(layer "In4.Cu")
		(net "M_C_ECC<3>")
	)
	(segment
		(start 242.794028 -18.419318)
		(end 242.654328 -18.559018)
		(width 0.14224)
		(layer "In4.Cu")
		(net "M_C_ECC<3>")
	)
	(segment
		(start 247.212358 -53.460396)
		(end 247.212358 -55.620412)
		(width 0.0889)
		(layer "In4.Cu")
		(net "M_C_ECC<3>")
	)
	(segment
		(start 247.279668 -62.715902)
		(end 247.284494 -62.724538)
		(width 0.0889)
		(layer "In4.Cu")
		(net "M_C_ECC<3>")
	)
	(segment
		(start 247.279668 -66.678302)
		(end 247.284494 -66.686938)
		(width 0.0889)
		(layer "In4.Cu")
		(net "M_C_ECC<3>")
	)
	(segment
		(start 248.145808 -51.065938)
		(end 248.145808 -52.526946)
		(width 0.0889)
		(layer "In4.Cu")
		(net "M_C_ECC<3>")
	)
	(segment
		(start 242.781328 -21.949156)
		(end 242.781328 -23.234396)
		(width 0.14224)
		(layer "In4.Cu")
		(net "M_C_ECC<3>")
	)
	(segment
		(start 248.985024 -50.111914)
		(end 248.743724 -50.353214)
		(width 0.0889)
		(layer "In4.Cu")
		(net "M_C_ECC<3>")
	)
	(segment
		(start 248.743724 -50.353214)
		(end 248.743724 -50.468022)
		(width 0.0889)
		(layer "In4.Cu")
		(net "M_C_ECC<3>")
	)
	(arc
		(start 247.284494 -60.343288)
		(mid 247.231024 -60.538351)
		(end 247.279668 -60.734702)
		(width 0.0889)
		(layer "In4.Cu")
		(net "M_C_ECC<3>")
	)
	(arc
		(start 247.290844 -56.791606)
		(mid 247.363642 -57.082369)
		(end 247.284494 -57.371488)
		(width 0.0889)
		(layer "In4.Cu")
		(net "M_C_ECC<3>")
	)
	(arc
		(start 247.290844 -64.716406)
		(mid 247.363642 -65.007169)
		(end 247.284494 -65.296288)
		(width 0.0889)
		(layer "In4.Cu")
		(net "M_C_ECC<3>")
	)
	(arc
		(start 247.284494 -65.296288)
		(mid 247.231024 -65.491351)
		(end 247.279668 -65.687702)
		(width 0.0889)
		(layer "In4.Cu")
		(net "M_C_ECC<3>")
	)
	(arc
		(start 247.284494 -61.333888)
		(mid 247.231024 -61.528951)
		(end 247.279668 -61.725302)
		(width 0.0889)
		(layer "In4.Cu")
		(net "M_C_ECC<3>")
	)
	(arc
		(start 247.290844 -63.725806)
		(mid 247.363642 -64.016569)
		(end 247.284494 -64.305688)
		(width 0.0889)
		(layer "In4.Cu")
		(net "M_C_ECC<3>")
	)
	(arc
		(start 247.284494 -62.324488)
		(mid 247.231024 -62.519551)
		(end 247.279668 -62.715902)
		(width 0.0889)
		(layer "In4.Cu")
		(net "M_C_ECC<3>")
	)
	(arc
		(start 247.284494 -64.305688)
		(mid 247.231024 -64.500751)
		(end 247.279668 -64.697102)
		(width 0.0889)
		(layer "In4.Cu")
		(net "M_C_ECC<3>")
	)
	(arc
		(start 247.363742 -56.085486)
		(mid 247.343551 -56.2384)
		(end 247.284494 -56.380888)
		(width 0.0889)
		(layer "In4.Cu")
		(net "M_C_ECC<3>")
	)
	(arc
		(start 247.284494 -58.362088)
		(mid 247.230995 -58.561986)
		(end 247.284494 -58.761884)
		(width 0.0889)
		(layer "In4.Cu")
		(net "M_C_ECC<3>")
	)
	(arc
		(start 247.284494 -67.277488)
		(mid 247.245593 -67.371396)
		(end 247.231408 -67.472052)
		(width 0.0889)
		(layer "In4.Cu")
		(net "M_C_ECC<3>")
	)
	(arc
		(start 247.284494 -57.371488)
		(mid 247.231024 -57.566551)
		(end 247.279668 -57.762902)
		(width 0.0889)
		(layer "In4.Cu")
		(net "M_C_ECC<3>")
	)
	(arc
		(start 247.284494 -59.352688)
		(mid 247.231024 -59.547751)
		(end 247.279668 -59.744102)
		(width 0.0889)
		(layer "In4.Cu")
		(net "M_C_ECC<3>")
	)
	(arc
		(start 247.290844 -59.763406)
		(mid 247.363642 -60.054169)
		(end 247.284494 -60.343288)
		(width 0.0889)
		(layer "In4.Cu")
		(net "M_C_ECC<3>")
	)
	(arc
		(start 247.290844 -65.707006)
		(mid 247.363642 -65.997769)
		(end 247.284494 -66.286888)
		(width 0.0889)
		(layer "In4.Cu")
		(net "M_C_ECC<3>")
	)
	(arc
		(start 247.284494 -58.761884)
		(mid 247.363625 -59.057286)
		(end 247.284494 -59.352688)
		(width 0.0889)
		(layer "In4.Cu")
		(net "M_C_ECC<3>")
	)
	(arc
		(start 247.284494 -57.771538)
		(mid 247.363716 -58.060656)
		(end 247.290844 -58.35142)
		(width 0.0889)
		(layer "In4.Cu")
		(net "M_C_ECC<3>")
	)
	(arc
		(start 247.284494 -56.380888)
		(mid 247.231024 -56.575951)
		(end 247.279668 -56.772302)
		(width 0.0889)
		(layer "In4.Cu")
		(net "M_C_ECC<3>")
	)
	(arc
		(start 247.290844 -62.735206)
		(mid 247.363642 -63.025969)
		(end 247.284494 -63.315088)
		(width 0.0889)
		(layer "In4.Cu")
		(net "M_C_ECC<3>")
	)
	(arc
		(start 247.290844 -61.744606)
		(mid 247.363642 -62.035369)
		(end 247.284494 -62.324488)
		(width 0.0889)
		(layer "In4.Cu")
		(net "M_C_ECC<3>")
	)
	(arc
		(start 247.284494 -66.286888)
		(mid 247.231024 -66.481951)
		(end 247.279668 -66.678302)
		(width 0.0889)
		(layer "In4.Cu")
		(net "M_C_ECC<3>")
	)
	(arc
		(start 247.290844 -60.754006)
		(mid 247.363642 -61.044769)
		(end 247.284494 -61.333888)
		(width 0.0889)
		(layer "In4.Cu")
		(net "M_C_ECC<3>")
	)
	(arc
		(start 247.290844 -66.697606)
		(mid 247.363642 -66.988369)
		(end 247.284494 -67.277488)
		(width 0.0889)
		(layer "In4.Cu")
		(net "M_C_ECC<3>")
	)
	(arc
		(start 247.284494 -63.315088)
		(mid 247.231024 -63.510151)
		(end 247.279668 -63.706502)
		(width 0.0889)
		(layer "In4.Cu")
		(net "M_C_ECC<3>")
	)
	(segment
		(start 242.350798 1.5494)
		(end 242.096798 1.5494)
		(width 0.14224)
		(layer "In11.Cu")
		(net "M_C_ECC<3>")
	)
	(segment
		(start 241.766598 1.8796)
		(end 241.766598 2.198116)
		(width 0.14224)
		(layer "In11.Cu")
		(net "M_C_ECC<3>")
	)
	(segment
		(start 242.299744 -3.076956)
		(end 242.65255 -2.72415)
		(width 0.14224)
		(layer "In11.Cu")
		(net "M_C_ECC<3>")
	)
	(segment
		(start 241.766598 2.198116)
		(end 241.44986 2.514854)
		(width 0.14224)
		(layer "In11.Cu")
		(net "M_C_ECC<3>")
	)
	(segment
		(start 242.807998 1.0922)
		(end 242.350798 1.5494)
		(width 0.14224)
		(layer "In11.Cu")
		(net "M_C_ECC<3>")
	)
	(segment
		(start 242.096798 1.5494)
		(end 241.766598 1.8796)
		(width 0.14224)
		(layer "In11.Cu")
		(net "M_C_ECC<3>")
	)
	(segment
		(start 242.65255 -2.72415)
		(end 242.65255 0.581152)
		(width 0.14224)
		(layer "In11.Cu")
		(net "M_C_ECC<3>")
	)
	(segment
		(start 242.807998 0.7366)
		(end 242.807998 1.0922)
		(width 0.14224)
		(layer "In11.Cu")
		(net "M_C_ECC<3>")
	)
	(segment
		(start 242.65255 0.581152)
		(end 242.807998 0.7366)
		(width 0.14224)
		(layer "In11.Cu")
		(net "M_C_ECC<3>")
	)
	(segment
		(start 242.299744 -0.82042)
		(end 242.299744 0.175768)
		(width 0.1651)
		(layer "F.Cu")
		(net "M_C_ECC<2>")
	)
	(segment
		(start 242.299744 0.175768)
		(end 242.431316 0.30734)
		(width 0.1651)
		(layer "F.Cu")
		(net "M_C_ECC<2>")
	)
	(segment
		(start 242.300506 -0.821182)
		(end 242.299744 -0.82042)
		(width 0.1651)
		(layer "F.Cu")
		(net "M_C_ECC<2>")
	)
	(segment
		(start 242.431316 0.30734)
		(end 242.431316 0.53086)
		(width 0.1651)
		(layer "F.Cu")
		(net "M_C_ECC<2>")
	)
	(segment
		(start 242.299744 0.662432)
		(end 242.299744 0.9398)
		(width 0.1651)
		(layer "F.Cu")
		(net "M_C_ECC<2>")
	)
	(segment
		(start 247.344184 -67.972686)
		(end 246.772684 -67.972686)
		(width 0.1016)
		(layer "F.Cu")
		(net "M_C_ECC<2>")
	)
	(segment
		(start 242.431316 0.53086)
		(end 242.299744 0.662432)
		(width 0.1651)
		(layer "F.Cu")
		(net "M_C_ECC<2>")
	)
	(via
		(at 241.44986 -4.357878)
		(size 0.508)
		(drill 0.254)
		(layers "F.Cu" "B.Cu")
		(net "M_C_ECC<2>")
	)
	(via
		(at 242.299744 0.9398)
		(size 0.508)
		(drill 0.254)
		(layers "F.Cu" "B.Cu")
		(net "M_C_ECC<2>")
	)
	(via
		(at 246.772684 -67.972686)
		(size 0.508)
		(drill 0.254)
		(layers "F.Cu" "B.Cu")
		(net "M_C_ECC<2>")
	)
	(segment
		(start 241.44986 -5.621782)
		(end 241.44986 -4.357878)
		(width 0.1651)
		(layer "B.Cu")
		(net "M_C_ECC<2>")
	)
	(segment
		(start 241.450368 -5.621782)
		(end 241.44986 -5.621782)
		(width 0.1651)
		(layer "B.Cu")
		(net "M_C_ECC<2>")
	)
	(segment
		(start 244.8814 -38.62578)
		(end 244.73916 -38.76802)
		(width 0.14224)
		(layer "In4.Cu")
		(net "M_C_ECC<2>")
	)
	(segment
		(start 247.10263 -67.21094)
		(end 246.772684 -67.972686)
		(width 0.0889)
		(layer "In4.Cu")
		(net "M_C_ECC<2>")
	)
	(segment
		(start 241.790728 -21.949156)
		(end 241.790728 -23.155656)
		(width 0.14224)
		(layer "In4.Cu")
		(net "M_C_ECC<2>")
	)
	(segment
		(start 247.119394 -58.857388)
		(end 247.12422 -58.866024)
		(width 0.0889)
		(layer "In4.Cu")
		(net "M_C_ECC<2>")
	)
	(segment
		(start 244.73916 -37.46754)
		(end 244.55247 -37.46754)
		(width 0.14224)
		(layer "In4.Cu")
		(net "M_C_ECC<2>")
	)
	(segment
		(start 247.021604 -53.371242)
		(end 247.021604 -55.717694)
		(width 0.0889)
		(layer "In4.Cu")
		(net "M_C_ECC<2>")
	)
	(segment
		(start 246.535194 -45.069252)
		(end 246.719852 -45.069252)
		(width 0.14224)
		(layer "In4.Cu")
		(net "M_C_ECC<2>")
	)
	(segment
		(start 247.119394 -67.182238)
		(end 247.10263 -67.21094)
		(width 0.0889)
		(layer "In4.Cu")
		(net "M_C_ECC<2>")
	)
	(segment
		(start 247.119394 -56.876188)
		(end 247.12422 -56.884824)
		(width 0.0889)
		(layer "In4.Cu")
		(net "M_C_ECC<2>")
	)
	(segment
		(start 244.55247 -32.91586)
		(end 244.73916 -32.91586)
		(width 0.14224)
		(layer "In4.Cu")
		(net "M_C_ECC<2>")
	)
	(segment
		(start 241.943128 -21.796756)
		(end 241.790728 -21.949156)
		(width 0.14224)
		(layer "In4.Cu")
		(net "M_C_ECC<2>")
	)
	(segment
		(start 244.73916 -34.86658)
		(end 244.55247 -34.86658)
		(width 0.14224)
		(layer "In4.Cu")
		(net "M_C_ECC<2>")
	)
	(segment
		(start 247.119394 -60.838588)
		(end 247.12422 -60.847224)
		(width 0.0889)
		(layer "In4.Cu")
		(net "M_C_ECC<2>")
	)
	(segment
		(start 247.119394 -65.791588)
		(end 247.12422 -65.800224)
		(width 0.0889)
		(layer "In4.Cu")
		(net "M_C_ECC<2>")
	)
	(segment
		(start 241.943128 -18.575274)
		(end 241.943128 -21.796756)
		(width 0.14224)
		(layer "In4.Cu")
		(net "M_C_ECC<2>")
	)
	(segment
		(start 244.55247 -38.11778)
		(end 244.73916 -38.11778)
		(width 0.14224)
		(layer "In4.Cu")
		(net "M_C_ECC<2>")
	)
	(segment
		(start 247.119394 -59.847988)
		(end 247.12422 -59.856624)
		(width 0.0889)
		(layer "In4.Cu")
		(net "M_C_ECC<2>")
	)
	(segment
		(start 241.816128 -18.448274)
		(end 241.943128 -18.575274)
		(width 0.14224)
		(layer "In4.Cu")
		(net "M_C_ECC<2>")
	)
	(segment
		(start 244.55247 -34.86658)
		(end 244.41023 -35.00882)
		(width 0.14224)
		(layer "In4.Cu")
		(net "M_C_ECC<2>")
	)
	(segment
		(start 244.8814 -38.26002)
		(end 244.8814 -38.62578)
		(width 0.14224)
		(layer "In4.Cu")
		(net "M_C_ECC<2>")
	)
	(segment
		(start 244.41023 -38.91026)
		(end 244.41023 -42.944288)
		(width 0.14224)
		(layer "In4.Cu")
		(net "M_C_ECC<2>")
	)
	(segment
		(start 244.73916 -38.11778)
		(end 244.8814 -38.26002)
		(width 0.14224)
		(layer "In4.Cu")
		(net "M_C_ECC<2>")
	)
	(segment
		(start 248.350024 -50.111914)
		(end 248.553224 -50.315114)
		(width 0.0889)
		(layer "In4.Cu")
		(net "M_C_ECC<2>")
	)
	(segment
		(start 248.553224 -50.315114)
		(end 248.553224 -50.378614)
		(width 0.0889)
		(layer "In4.Cu")
		(net "M_C_ECC<2>")
	)
	(segment
		(start 244.55247 -36.16706)
		(end 244.41023 -36.3093)
		(width 0.14224)
		(layer "In4.Cu")
		(net "M_C_ECC<2>")
	)
	(segment
		(start 241.816128 -16.966946)
		(end 241.816128 -18.448274)
		(width 0.14224)
		(layer "In4.Cu")
		(net "M_C_ECC<2>")
	)
	(segment
		(start 244.41023 -36.3093)
		(end 244.41023 -36.67506)
		(width 0.14224)
		(layer "In4.Cu")
		(net "M_C_ECC<2>")
	)
	(segment
		(start 241.801396 -27.552396)
		(end 241.935 -27.686)
		(width 0.14224)
		(layer "In4.Cu")
		(net "M_C_ECC<2>")
	)
	(segment
		(start 244.8814 -34.72434)
		(end 244.73916 -34.86658)
		(width 0.14224)
		(layer "In4.Cu")
		(net "M_C_ECC<2>")
	)
	(segment
		(start 247.955308 -52.437538)
		(end 247.021604 -53.371242)
		(width 0.0889)
		(layer "In4.Cu")
		(net "M_C_ECC<2>")
	)
	(segment
		(start 247.113044 -56.86552)
		(end 247.119394 -56.876188)
		(width 0.0889)
		(layer "In4.Cu")
		(net "M_C_ECC<2>")
	)
	(segment
		(start 244.73916 -34.21634)
		(end 244.8814 -34.35858)
		(width 0.14224)
		(layer "In4.Cu")
		(net "M_C_ECC<2>")
	)
	(segment
		(start 242.044728 -26.204672)
		(end 241.801396 -26.448004)
		(width 0.14224)
		(layer "In4.Cu")
		(net "M_C_ECC<2>")
	)
	(segment
		(start 247.113044 -66.77152)
		(end 247.119394 -66.782188)
		(width 0.0889)
		(layer "In4.Cu")
		(net "M_C_ECC<2>")
	)
	(segment
		(start 241.935 -27.686)
		(end 241.935 -29.4894)
		(width 0.14224)
		(layer "In4.Cu")
		(net "M_C_ECC<2>")
	)
	(segment
		(start 244.55247 -35.51682)
		(end 244.73916 -35.51682)
		(width 0.14224)
		(layer "In4.Cu")
		(net "M_C_ECC<2>")
	)
	(segment
		(start 248.553224 -50.378614)
		(end 247.955308 -50.97653)
		(width 0.0889)
		(layer "In4.Cu")
		(net "M_C_ECC<2>")
	)
	(segment
		(start 247.113044 -65.78092)
		(end 247.119394 -65.791588)
		(width 0.0889)
		(layer "In4.Cu")
		(net "M_C_ECC<2>")
	)
	(segment
		(start 247.119394 -58.266838)
		(end 247.113044 -58.277506)
		(width 0.0889)
		(layer "In4.Cu")
		(net "M_C_ECC<2>")
	)
	(segment
		(start 244.41023 -34.0741)
		(end 244.55247 -34.21634)
		(width 0.14224)
		(layer "In4.Cu")
		(net "M_C_ECC<2>")
	)
	(segment
		(start 244.41023 -32.77362)
		(end 244.55247 -32.91586)
		(width 0.14224)
		(layer "In4.Cu")
		(net "M_C_ECC<2>")
	)
	(segment
		(start 244.41023 -35.37458)
		(end 244.55247 -35.51682)
		(width 0.14224)
		(layer "In4.Cu")
		(net "M_C_ECC<2>")
	)
	(segment
		(start 244.73916 -35.51682)
		(end 244.8814 -35.65906)
		(width 0.14224)
		(layer "In4.Cu")
		(net "M_C_ECC<2>")
	)
	(segment
		(start 247.113044 -59.83732)
		(end 247.119394 -59.847988)
		(width 0.0889)
		(layer "In4.Cu")
		(net "M_C_ECC<2>")
	)
	(segment
		(start 247.113044 -63.79972)
		(end 247.119394 -63.810388)
		(width 0.0889)
		(layer "In4.Cu")
		(net "M_C_ECC<2>")
	)
	(segment
		(start 244.8814 -35.65906)
		(end 244.8814 -36.02482)
		(width 0.14224)
		(layer "In4.Cu")
		(net "M_C_ECC<2>")
	)
	(segment
		(start 241.816128 -7.365746)
		(end 241.816128 -8.847074)
		(width 0.14224)
		(layer "In4.Cu")
		(net "M_C_ECC<2>")
	)
	(segment
		(start 242.032028 -16.751046)
		(end 241.816128 -16.966946)
		(width 0.14224)
		(layer "In4.Cu")
		(net "M_C_ECC<2>")
	)
	(segment
		(start 244.73916 -36.8173)
		(end 244.8814 -36.95954)
		(width 0.14224)
		(layer "In4.Cu")
		(net "M_C_ECC<2>")
	)
	(segment
		(start 241.790728 -13.541756)
		(end 242.032028 -13.783056)
		(width 0.14224)
		(layer "In4.Cu")
		(net "M_C_ECC<2>")
	)
	(segment
		(start 244.8814 -36.95954)
		(end 244.8814 -37.3253)
		(width 0.14224)
		(layer "In4.Cu")
		(net "M_C_ECC<2>")
	)
	(segment
		(start 247.119394 -63.810388)
		(end 247.12422 -63.819024)
		(width 0.0889)
		(layer "In4.Cu")
		(net "M_C_ECC<2>")
	)
	(segment
		(start 241.943128 -8.974074)
		(end 241.943128 -12.195556)
		(width 0.14224)
		(layer "In4.Cu")
		(net "M_C_ECC<2>")
	)
	(segment
		(start 247.113044 -64.79032)
		(end 247.119394 -64.800988)
		(width 0.0889)
		(layer "In4.Cu")
		(net "M_C_ECC<2>")
	)
	(segment
		(start 247.113044 -60.82792)
		(end 247.119394 -60.838588)
		(width 0.0889)
		(layer "In4.Cu")
		(net "M_C_ECC<2>")
	)
	(segment
		(start 247.119394 -61.829188)
		(end 247.12422 -61.837824)
		(width 0.0889)
		(layer "In4.Cu")
		(net "M_C_ECC<2>")
	)
	(segment
		(start 244.73916 -38.76802)
		(end 244.55247 -38.76802)
		(width 0.14224)
		(layer "In4.Cu")
		(net "M_C_ECC<2>")
	)
	(segment
		(start 242.019328 -7.162546)
		(end 241.816128 -7.365746)
		(width 0.14224)
		(layer "In4.Cu")
		(net "M_C_ECC<2>")
	)
	(segment
		(start 244.41023 -31.96463)
		(end 244.41023 -32.77362)
		(width 0.14224)
		(layer "In4.Cu")
		(net "M_C_ECC<2>")
	)
	(segment
		(start 244.41023 -35.00882)
		(end 244.41023 -35.37458)
		(width 0.14224)
		(layer "In4.Cu")
		(net "M_C_ECC<2>")
	)
	(segment
		(start 244.41023 -37.97554)
		(end 244.55247 -38.11778)
		(width 0.14224)
		(layer "In4.Cu")
		(net "M_C_ECC<2>")
	)
	(segment
		(start 244.8814 -36.02482)
		(end 244.73916 -36.16706)
		(width 0.14224)
		(layer "In4.Cu")
		(net "M_C_ECC<2>")
	)
	(segment
		(start 244.55247 -38.76802)
		(end 244.41023 -38.91026)
		(width 0.14224)
		(layer "In4.Cu")
		(net "M_C_ECC<2>")
	)
	(segment
		(start 247.955308 -50.97653)
		(end 247.955308 -52.437538)
		(width 0.0889)
		(layer "In4.Cu")
		(net "M_C_ECC<2>")
	)
	(segment
		(start 244.41023 -33.70834)
		(end 244.41023 -34.0741)
		(width 0.14224)
		(layer "In4.Cu")
		(net "M_C_ECC<2>")
	)
	(segment
		(start 244.55247 -37.46754)
		(end 244.41023 -37.60978)
		(width 0.14224)
		(layer "In4.Cu")
		(net "M_C_ECC<2>")
	)
	(segment
		(start 248.350024 -46.699424)
		(end 248.350024 -50.111914)
		(width 0.14224)
		(layer "In4.Cu")
		(net "M_C_ECC<2>")
	)
	(segment
		(start 241.44986 -4.357878)
		(end 242.019328 -4.927346)
		(width 0.14224)
		(layer "In4.Cu")
		(net "M_C_ECC<2>")
	)
	(segment
		(start 244.55247 -34.21634)
		(end 244.73916 -34.21634)
		(width 0.14224)
		(layer "In4.Cu")
		(net "M_C_ECC<2>")
	)
	(segment
		(start 247.113044 -61.81852)
		(end 247.119394 -61.829188)
		(width 0.0889)
		(layer "In4.Cu")
		(net "M_C_ECC<2>")
	)
	(segment
		(start 241.790728 -12.347956)
		(end 241.790728 -13.541756)
		(width 0.14224)
		(layer "In4.Cu")
		(net "M_C_ECC<2>")
	)
	(segment
		(start 244.8814 -33.42386)
		(end 244.73916 -33.5661)
		(width 0.14224)
		(layer "In4.Cu")
		(net "M_C_ECC<2>")
	)
	(segment
		(start 244.55247 -33.5661)
		(end 244.41023 -33.70834)
		(width 0.14224)
		(layer "In4.Cu")
		(net "M_C_ECC<2>")
	)
	(segment
		(start 247.113044 -62.80912)
		(end 247.119394 -62.819788)
		(width 0.0889)
		(layer "In4.Cu")
		(net "M_C_ECC<2>")
	)
	(segment
		(start 244.55247 -36.8173)
		(end 244.73916 -36.8173)
		(width 0.14224)
		(layer "In4.Cu")
		(net "M_C_ECC<2>")
	)
	(segment
		(start 247.119394 -64.800988)
		(end 247.12422 -64.809624)
		(width 0.0889)
		(layer "In4.Cu")
		(net "M_C_ECC<2>")
	)
	(segment
		(start 244.41023 -42.944288)
		(end 246.535194 -45.069252)
		(width 0.14224)
		(layer "In4.Cu")
		(net "M_C_ECC<2>")
	)
	(segment
		(start 244.8814 -33.0581)
		(end 244.8814 -33.42386)
		(width 0.14224)
		(layer "In4.Cu")
		(net "M_C_ECC<2>")
	)
	(segment
		(start 244.73916 -32.91586)
		(end 244.8814 -33.0581)
		(width 0.14224)
		(layer "In4.Cu")
		(net "M_C_ECC<2>")
	)
	(segment
		(start 247.119394 -66.782188)
		(end 247.12422 -66.790824)
		(width 0.0889)
		(layer "In4.Cu")
		(net "M_C_ECC<2>")
	)
	(segment
		(start 242.044728 -23.409656)
		(end 242.044728 -26.204672)
		(width 0.14224)
		(layer "In4.Cu")
		(net "M_C_ECC<2>")
	)
	(segment
		(start 244.41023 -37.60978)
		(end 244.41023 -37.97554)
		(width 0.14224)
		(layer "In4.Cu")
		(net "M_C_ECC<2>")
	)
	(segment
		(start 242.019328 -4.927346)
		(end 242.019328 -7.162546)
		(width 0.14224)
		(layer "In4.Cu")
		(net "M_C_ECC<2>")
	)
	(segment
		(start 246.719852 -45.069252)
		(end 248.350024 -46.699424)
		(width 0.14224)
		(layer "In4.Cu")
		(net "M_C_ECC<2>")
	)
	(segment
		(start 241.935 -29.4894)
		(end 244.41023 -31.96463)
		(width 0.14224)
		(layer "In4.Cu")
		(net "M_C_ECC<2>")
	)
	(segment
		(start 241.816128 -8.847074)
		(end 241.943128 -8.974074)
		(width 0.14224)
		(layer "In4.Cu")
		(net "M_C_ECC<2>")
	)
	(segment
		(start 247.172988 -55.869078)
		(end 247.172988 -56.085486)
		(width 0.0889)
		(layer "In4.Cu")
		(net "M_C_ECC<2>")
	)
	(segment
		(start 242.032028 -13.783056)
		(end 242.032028 -16.751046)
		(width 0.14224)
		(layer "In4.Cu")
		(net "M_C_ECC<2>")
	)
	(segment
		(start 244.73916 -36.16706)
		(end 244.55247 -36.16706)
		(width 0.14224)
		(layer "In4.Cu")
		(net "M_C_ECC<2>")
	)
	(segment
		(start 244.41023 -36.67506)
		(end 244.55247 -36.8173)
		(width 0.14224)
		(layer "In4.Cu")
		(net "M_C_ECC<2>")
	)
	(segment
		(start 247.119394 -62.819788)
		(end 247.12422 -62.828424)
		(width 0.0889)
		(layer "In4.Cu")
		(net "M_C_ECC<2>")
	)
	(segment
		(start 241.801396 -26.448004)
		(end 241.801396 -27.552396)
		(width 0.14224)
		(layer "In4.Cu")
		(net "M_C_ECC<2>")
	)
	(segment
		(start 241.943128 -12.195556)
		(end 241.790728 -12.347956)
		(width 0.14224)
		(layer "In4.Cu")
		(net "M_C_ECC<2>")
	)
	(segment
		(start 244.73916 -33.5661)
		(end 244.55247 -33.5661)
		(width 0.14224)
		(layer "In4.Cu")
		(net "M_C_ECC<2>")
	)
	(segment
		(start 241.790728 -23.155656)
		(end 242.044728 -23.409656)
		(width 0.14224)
		(layer "In4.Cu")
		(net "M_C_ECC<2>")
	)
	(segment
		(start 244.8814 -37.3253)
		(end 244.73916 -37.46754)
		(width 0.14224)
		(layer "In4.Cu")
		(net "M_C_ECC<2>")
	)
	(segment
		(start 244.8814 -34.35858)
		(end 244.8814 -34.72434)
		(width 0.14224)
		(layer "In4.Cu")
		(net "M_C_ECC<2>")
	)
	(segment
		(start 247.021604 -55.717694)
		(end 247.172988 -55.869078)
		(width 0.0889)
		(layer "In4.Cu")
		(net "M_C_ECC<2>")
	)
	(arc
		(start 247.119394 -63.219838)
		(mid 247.040172 -63.508956)
		(end 247.113044 -63.79972)
		(width 0.0889)
		(layer "In4.Cu")
		(net "M_C_ECC<2>")
	)
	(arc
		(start 247.12422 -58.866024)
		(mid 247.172975 -59.062376)
		(end 247.119394 -59.257438)
		(width 0.0889)
		(layer "In4.Cu")
		(net "M_C_ECC<2>")
	)
	(arc
		(start 247.119394 -65.201038)
		(mid 247.040172 -65.490156)
		(end 247.113044 -65.78092)
		(width 0.0889)
		(layer "In4.Cu")
		(net "M_C_ECC<2>")
	)
	(arc
		(start 247.119394 -59.257438)
		(mid 247.040172 -59.546556)
		(end 247.113044 -59.83732)
		(width 0.0889)
		(layer "In4.Cu")
		(net "M_C_ECC<2>")
	)
	(arc
		(start 247.12422 -65.800224)
		(mid 247.172975 -65.996576)
		(end 247.119394 -66.191638)
		(width 0.0889)
		(layer "In4.Cu")
		(net "M_C_ECC<2>")
	)
	(arc
		(start 247.172988 -56.085486)
		(mid 247.159358 -56.189088)
		(end 247.119394 -56.285638)
		(width 0.0889)
		(layer "In4.Cu")
		(net "M_C_ECC<2>")
	)
	(arc
		(start 247.12422 -63.819024)
		(mid 247.172975 -64.015376)
		(end 247.119394 -64.210438)
		(width 0.0889)
		(layer "In4.Cu")
		(net "M_C_ECC<2>")
	)
	(arc
		(start 247.12422 -56.884824)
		(mid 247.172975 -57.081176)
		(end 247.119394 -57.276238)
		(width 0.0889)
		(layer "In4.Cu")
		(net "M_C_ECC<2>")
	)
	(arc
		(start 247.119394 -62.229238)
		(mid 247.040172 -62.518356)
		(end 247.113044 -62.80912)
		(width 0.0889)
		(layer "In4.Cu")
		(net "M_C_ECC<2>")
	)
	(arc
		(start 247.119394 -66.191638)
		(mid 247.040172 -66.480756)
		(end 247.113044 -66.77152)
		(width 0.0889)
		(layer "In4.Cu")
		(net "M_C_ECC<2>")
	)
	(arc
		(start 247.12422 -61.837824)
		(mid 247.172975 -62.034176)
		(end 247.119394 -62.229238)
		(width 0.0889)
		(layer "In4.Cu")
		(net "M_C_ECC<2>")
	)
	(arc
		(start 247.119394 -64.210438)
		(mid 247.040172 -64.499556)
		(end 247.113044 -64.79032)
		(width 0.0889)
		(layer "In4.Cu")
		(net "M_C_ECC<2>")
	)
	(arc
		(start 247.119394 -57.276238)
		(mid 247.040263 -57.57164)
		(end 247.119394 -57.867042)
		(width 0.0889)
		(layer "In4.Cu")
		(net "M_C_ECC<2>")
	)
	(arc
		(start 247.12422 -66.790824)
		(mid 247.172975 -66.987176)
		(end 247.119394 -67.182238)
		(width 0.0889)
		(layer "In4.Cu")
		(net "M_C_ECC<2>")
	)
	(arc
		(start 247.12422 -62.828424)
		(mid 247.172975 -63.024776)
		(end 247.119394 -63.219838)
		(width 0.0889)
		(layer "In4.Cu")
		(net "M_C_ECC<2>")
	)
	(arc
		(start 247.119394 -56.285638)
		(mid 247.040172 -56.574756)
		(end 247.113044 -56.86552)
		(width 0.0889)
		(layer "In4.Cu")
		(net "M_C_ECC<2>")
	)
	(arc
		(start 247.119394 -60.248038)
		(mid 247.040172 -60.537156)
		(end 247.113044 -60.82792)
		(width 0.0889)
		(layer "In4.Cu")
		(net "M_C_ECC<2>")
	)
	(arc
		(start 247.12422 -60.847224)
		(mid 247.172975 -61.043576)
		(end 247.119394 -61.238638)
		(width 0.0889)
		(layer "In4.Cu")
		(net "M_C_ECC<2>")
	)
	(arc
		(start 247.12422 -64.809624)
		(mid 247.172975 -65.005976)
		(end 247.119394 -65.201038)
		(width 0.0889)
		(layer "In4.Cu")
		(net "M_C_ECC<2>")
	)
	(arc
		(start 247.119394 -57.867042)
		(mid 247.172893 -58.06694)
		(end 247.119394 -58.266838)
		(width 0.0889)
		(layer "In4.Cu")
		(net "M_C_ECC<2>")
	)
	(arc
		(start 247.119394 -61.238638)
		(mid 247.040172 -61.527756)
		(end 247.113044 -61.81852)
		(width 0.0889)
		(layer "In4.Cu")
		(net "M_C_ECC<2>")
	)
	(arc
		(start 247.113044 -58.277506)
		(mid 247.040246 -58.568269)
		(end 247.119394 -58.857388)
		(width 0.0889)
		(layer "In4.Cu")
		(net "M_C_ECC<2>")
	)
	(arc
		(start 247.12422 -59.856624)
		(mid 247.172975 -60.052976)
		(end 247.119394 -60.248038)
		(width 0.0889)
		(layer "In4.Cu")
		(net "M_C_ECC<2>")
	)
	(segment
		(start 241.133376 -4.041394)
		(end 241.133376 -3.479546)
		(width 0.14224)
		(layer "In11.Cu")
		(net "M_C_ECC<2>")
	)
	(segment
		(start 241.44986 -4.357878)
		(end 241.133376 -4.041394)
		(width 0.14224)
		(layer "In11.Cu")
		(net "M_C_ECC<2>")
	)
	(segment
		(start 241.133376 -3.479546)
		(end 241.893598 -2.719324)
		(width 0.14224)
		(layer "In11.Cu")
		(net "M_C_ECC<2>")
	)
	(segment
		(start 241.893598 -2.719324)
		(end 241.893598 0.533654)
		(width 0.14224)
		(layer "In11.Cu")
		(net "M_C_ECC<2>")
	)
	(segment
		(start 241.893598 0.533654)
		(end 242.299744 0.9398)
		(width 0.14224)
		(layer "In11.Cu")
		(net "M_C_ECC<2>")
	)
	(segment
		(start 235.49991 3.778758)
		(end 235.49991 2.514854)
		(width 0.1651)
		(layer "F.Cu")
		(net "M_C_ECC<1>")
	)
	(segment
		(start 235.500418 3.778758)
		(end 235.49991 3.778758)
		(width 0.1651)
		(layer "F.Cu")
		(net "M_C_ECC<1>")
	)
	(segment
		(start 244.768624 -69.45884)
		(end 244.197124 -69.45884)
		(width 0.1016)
		(layer "F.Cu")
		(net "M_C_ECC<1>")
	)
	(via
		(at 236.171994 -3.076956)
		(size 0.508)
		(drill 0.254)
		(layers "F.Cu" "B.Cu")
		(net "M_C_ECC<1>")
	)
	(via
		(at 244.197124 -69.45884)
		(size 0.508)
		(drill 0.254)
		(layers "F.Cu" "B.Cu")
		(net "M_C_ECC<1>")
	)
	(via
		(at 235.49991 2.514854)
		(size 0.508)
		(drill 0.254)
		(layers "F.Cu" "B.Cu")
		(net "M_C_ECC<1>")
	)
	(segment
		(start 236.349794 -2.395982)
		(end 236.171994 -2.573782)
		(width 0.1651)
		(layer "B.Cu")
		(net "M_C_ECC<1>")
	)
	(segment
		(start 236.350302 -1.021842)
		(end 236.349794 -1.021842)
		(width 0.1651)
		(layer "B.Cu")
		(net "M_C_ECC<1>")
	)
	(segment
		(start 236.349794 -1.021842)
		(end 236.349794 -2.395982)
		(width 0.1651)
		(layer "B.Cu")
		(net "M_C_ECC<1>")
	)
	(segment
		(start 236.171994 -2.573782)
		(end 236.171994 -3.076956)
		(width 0.1651)
		(layer "B.Cu")
		(net "M_C_ECC<1>")
	)
	(segment
		(start 243.850414 -53.809138)
		(end 243.845588 -53.800502)
		(width 0.0889)
		(layer "In4.Cu")
		(net "M_C_ECC<1>")
	)
	(segment
		(start 236.024928 -5.977382)
		(end 236.024928 -4.249928)
		(width 0.14224)
		(layer "In4.Cu")
		(net "M_C_ECC<1>")
	)
	(segment
		(start 239.8649 -36.194746)
		(end 238.379 -34.708846)
		(width 0.14224)
		(layer "In4.Cu")
		(net "M_C_ECC<1>")
	)
	(segment
		(start 243.850414 -65.696338)
		(end 243.845588 -65.687702)
		(width 0.0889)
		(layer "In4.Cu")
		(net "M_C_ECC<1>")
	)
	(segment
		(start 243.856764 -60.754006)
		(end 243.850414 -60.743338)
		(width 0.0889)
		(layer "In4.Cu")
		(net "M_C_ECC<1>")
	)
	(segment
		(start 243.850414 -60.743338)
		(end 243.845588 -60.734702)
		(width 0.0889)
		(layer "In4.Cu")
		(net "M_C_ECC<1>")
	)
	(segment
		(start 238.379 -31.9024)
		(end 236.659928 -30.183328)
		(width 0.14224)
		(layer "In4.Cu")
		(net "M_C_ECC<1>")
	)
	(segment
		(start 243.856764 -64.716406)
		(end 243.850414 -64.705738)
		(width 0.0889)
		(layer "In4.Cu")
		(net "M_C_ECC<1>")
	)
	(segment
		(start 243.757704 -50.348134)
		(end 243.981224 -50.124614)
		(width 0.0889)
		(layer "In4.Cu")
		(net "M_C_ECC<1>")
	)
	(segment
		(start 243.850414 -58.362088)
		(end 243.856764 -58.35142)
		(width 0.0889)
		(layer "In4.Cu")
		(net "M_C_ECC<1>")
	)
	(segment
		(start 243.856764 -63.725806)
		(end 243.850414 -63.715138)
		(width 0.0889)
		(layer "In4.Cu")
		(net "M_C_ECC<1>")
	)
	(segment
		(start 236.024928 -4.249928)
		(end 235.645452 -3.870452)
		(width 0.14224)
		(layer "In4.Cu")
		(net "M_C_ECC<1>")
	)
	(segment
		(start 243.887752 -53.344318)
		(end 243.887752 -51.457098)
		(width 0.0889)
		(layer "In4.Cu")
		(net "M_C_ECC<1>")
	)
	(segment
		(start 244.197124 -69.45884)
		(end 243.850414 -68.667884)
		(width 0.0889)
		(layer "In4.Cu")
		(net "M_C_ECC<1>")
	)
	(segment
		(start 243.850414 -53.409088)
		(end 243.887752 -53.344318)
		(width 0.0889)
		(layer "In4.Cu")
		(net "M_C_ECC<1>")
	)
	(segment
		(start 243.887752 -51.457098)
		(end 243.931186 -51.413664)
		(width 0.0889)
		(layer "In4.Cu")
		(net "M_C_ECC<1>")
	)
	(segment
		(start 243.931186 -50.71364)
		(end 243.757704 -50.540158)
		(width 0.0889)
		(layer "In4.Cu")
		(net "M_C_ECC<1>")
	)
	(segment
		(start 243.856764 -65.707006)
		(end 243.850414 -65.696338)
		(width 0.0889)
		(layer "In4.Cu")
		(net "M_C_ECC<1>")
	)
	(segment
		(start 243.981224 -50.124614)
		(end 243.981224 -48.055022)
		(width 0.14224)
		(layer "In4.Cu")
		(net "M_C_ECC<1>")
	)
	(segment
		(start 235.645452 -3.603498)
		(end 236.171994 -3.076956)
		(width 0.14224)
		(layer "In4.Cu")
		(net "M_C_ECC<1>")
	)
	(segment
		(start 243.850414 -54.799738)
		(end 243.845588 -54.791102)
		(width 0.0889)
		(layer "In4.Cu")
		(net "M_C_ECC<1>")
	)
	(segment
		(start 243.931186 -51.413664)
		(end 243.931186 -50.71364)
		(width 0.0889)
		(layer "In4.Cu")
		(net "M_C_ECC<1>")
	)
	(segment
		(start 243.850414 -63.715138)
		(end 243.845588 -63.706502)
		(width 0.0889)
		(layer "In4.Cu")
		(net "M_C_ECC<1>")
	)
	(segment
		(start 243.850414 -59.752738)
		(end 243.845588 -59.744102)
		(width 0.0889)
		(layer "In4.Cu")
		(net "M_C_ECC<1>")
	)
	(segment
		(start 243.850414 -64.705738)
		(end 243.845588 -64.697102)
		(width 0.0889)
		(layer "In4.Cu")
		(net "M_C_ECC<1>")
	)
	(segment
		(start 243.856764 -55.801006)
		(end 243.850414 -55.790338)
		(width 0.0889)
		(layer "In4.Cu")
		(net "M_C_ECC<1>")
	)
	(segment
		(start 243.856764 -62.735206)
		(end 243.850414 -62.724538)
		(width 0.0889)
		(layer "In4.Cu")
		(net "M_C_ECC<1>")
	)
	(segment
		(start 239.8649 -43.938698)
		(end 239.8649 -36.194746)
		(width 0.14224)
		(layer "In4.Cu")
		(net "M_C_ECC<1>")
	)
	(segment
		(start 243.850414 -62.724538)
		(end 243.845588 -62.715902)
		(width 0.0889)
		(layer "In4.Cu")
		(net "M_C_ECC<1>")
	)
	(segment
		(start 243.981224 -48.055022)
		(end 239.8649 -43.938698)
		(width 0.14224)
		(layer "In4.Cu")
		(net "M_C_ECC<1>")
	)
	(segment
		(start 243.856764 -56.791606)
		(end 243.850414 -56.780938)
		(width 0.0889)
		(layer "In4.Cu")
		(net "M_C_ECC<1>")
	)
	(segment
		(start 235.645452 -3.870452)
		(end 235.645452 -3.603498)
		(width 0.14224)
		(layer "In4.Cu")
		(net "M_C_ECC<1>")
	)
	(segment
		(start 243.856764 -53.819806)
		(end 243.850414 -53.809138)
		(width 0.0889)
		(layer "In4.Cu")
		(net "M_C_ECC<1>")
	)
	(segment
		(start 236.659928 -30.183328)
		(end 236.659928 -6.612382)
		(width 0.14224)
		(layer "In4.Cu")
		(net "M_C_ECC<1>")
	)
	(segment
		(start 238.379 -34.708846)
		(end 238.379 -31.9024)
		(width 0.14224)
		(layer "In4.Cu")
		(net "M_C_ECC<1>")
	)
	(segment
		(start 243.850414 -57.771538)
		(end 243.845588 -57.762902)
		(width 0.0889)
		(layer "In4.Cu")
		(net "M_C_ECC<1>")
	)
	(segment
		(start 243.856764 -54.810406)
		(end 243.850414 -54.799738)
		(width 0.0889)
		(layer "In4.Cu")
		(net "M_C_ECC<1>")
	)
	(segment
		(start 243.850414 -61.733938)
		(end 243.845588 -61.725302)
		(width 0.0889)
		(layer "In4.Cu")
		(net "M_C_ECC<1>")
	)
	(segment
		(start 243.850414 -56.780938)
		(end 243.845588 -56.772302)
		(width 0.0889)
		(layer "In4.Cu")
		(net "M_C_ECC<1>")
	)
	(segment
		(start 243.850414 -55.790338)
		(end 243.845588 -55.781702)
		(width 0.0889)
		(layer "In4.Cu")
		(net "M_C_ECC<1>")
	)
	(segment
		(start 243.856764 -61.744606)
		(end 243.850414 -61.733938)
		(width 0.0889)
		(layer "In4.Cu")
		(net "M_C_ECC<1>")
	)
	(segment
		(start 236.659928 -6.612382)
		(end 236.024928 -5.977382)
		(width 0.14224)
		(layer "In4.Cu")
		(net "M_C_ECC<1>")
	)
	(segment
		(start 243.757704 -50.540158)
		(end 243.757704 -50.348134)
		(width 0.0889)
		(layer "In4.Cu")
		(net "M_C_ECC<1>")
	)
	(segment
		(start 243.856764 -59.763406)
		(end 243.850414 -59.752738)
		(width 0.0889)
		(layer "In4.Cu")
		(net "M_C_ECC<1>")
	)
	(arc
		(start 244.514624 -67.720972)
		(mid 244.582619 -67.369988)
		(end 244.34292 -67.104768)
		(width 0.0889)
		(layer "In4.Cu")
		(net "M_C_ECC<1>")
	)
	(arc
		(start 243.856764 -58.35142)
		(mid 243.929562 -58.060657)
		(end 243.850414 -57.771538)
		(width 0.0889)
		(layer "In4.Cu")
		(net "M_C_ECC<1>")
	)
	(arc
		(start 243.850414 -59.352688)
		(mid 243.929545 -59.057286)
		(end 243.850414 -58.761884)
		(width 0.0889)
		(layer "In4.Cu")
		(net "M_C_ECC<1>")
	)
	(arc
		(start 243.850414 -57.371488)
		(mid 243.929636 -57.08237)
		(end 243.856764 -56.791606)
		(width 0.0889)
		(layer "In4.Cu")
		(net "M_C_ECC<1>")
	)
	(arc
		(start 243.845588 -60.734702)
		(mid 243.796833 -60.53835)
		(end 243.850414 -60.343288)
		(width 0.0889)
		(layer "In4.Cu")
		(net "M_C_ECC<1>")
	)
	(arc
		(start 243.845588 -57.762902)
		(mid 243.796833 -57.56655)
		(end 243.850414 -57.371488)
		(width 0.0889)
		(layer "In4.Cu")
		(net "M_C_ECC<1>")
	)
	(arc
		(start 243.845588 -53.800502)
		(mid 243.796833 -53.60415)
		(end 243.850414 -53.409088)
		(width 0.0889)
		(layer "In4.Cu")
		(net "M_C_ECC<1>")
	)
	(arc
		(start 243.845588 -56.772302)
		(mid 243.796833 -56.57595)
		(end 243.850414 -56.380888)
		(width 0.0889)
		(layer "In4.Cu")
		(net "M_C_ECC<1>")
	)
	(arc
		(start 243.845588 -64.697102)
		(mid 243.796833 -64.50075)
		(end 243.850414 -64.305688)
		(width 0.0889)
		(layer "In4.Cu")
		(net "M_C_ECC<1>")
	)
	(arc
		(start 243.850414 -56.380888)
		(mid 243.929636 -56.09177)
		(end 243.856764 -55.801006)
		(width 0.0889)
		(layer "In4.Cu")
		(net "M_C_ECC<1>")
	)
	(arc
		(start 243.845588 -61.725302)
		(mid 243.796833 -61.52895)
		(end 243.850414 -61.333888)
		(width 0.0889)
		(layer "In4.Cu")
		(net "M_C_ECC<1>")
	)
	(arc
		(start 243.850414 -61.333888)
		(mid 243.929636 -61.04477)
		(end 243.856764 -60.754006)
		(width 0.0889)
		(layer "In4.Cu")
		(net "M_C_ECC<1>")
	)
	(arc
		(start 243.845588 -55.781702)
		(mid 243.796833 -55.58535)
		(end 243.850414 -55.390288)
		(width 0.0889)
		(layer "In4.Cu")
		(net "M_C_ECC<1>")
	)
	(arc
		(start 243.850414 -60.343288)
		(mid 243.929636 -60.05417)
		(end 243.856764 -59.763406)
		(width 0.0889)
		(layer "In4.Cu")
		(net "M_C_ECC<1>")
	)
	(arc
		(start 244.043708 -68.098416)
		(mid 244.305949 -67.943117)
		(end 244.514624 -67.720972)
		(width 0.0889)
		(layer "In4.Cu")
		(net "M_C_ECC<1>")
	)
	(arc
		(start 244.34292 -67.104768)
		(mid 244.060337 -66.938515)
		(end 243.850414 -66.686684)
		(width 0.0889)
		(layer "In4.Cu")
		(net "M_C_ECC<1>")
	)
	(arc
		(start 243.845588 -54.791102)
		(mid 243.796833 -54.59475)
		(end 243.850414 -54.399688)
		(width 0.0889)
		(layer "In4.Cu")
		(net "M_C_ECC<1>")
	)
	(arc
		(start 243.850414 -63.315088)
		(mid 243.929636 -63.02597)
		(end 243.856764 -62.735206)
		(width 0.0889)
		(layer "In4.Cu")
		(net "M_C_ECC<1>")
	)
	(arc
		(start 243.850414 -64.305688)
		(mid 243.929636 -64.01657)
		(end 243.856764 -63.725806)
		(width 0.0889)
		(layer "In4.Cu")
		(net "M_C_ECC<1>")
	)
	(arc
		(start 243.845588 -62.715902)
		(mid 243.796833 -62.51955)
		(end 243.850414 -62.324488)
		(width 0.0889)
		(layer "In4.Cu")
		(net "M_C_ECC<1>")
	)
	(arc
		(start 243.850414 -66.686684)
		(mid 243.796915 -66.486786)
		(end 243.850414 -66.286888)
		(width 0.0889)
		(layer "In4.Cu")
		(net "M_C_ECC<1>")
	)
	(arc
		(start 243.845588 -65.687702)
		(mid 243.796833 -65.49135)
		(end 243.850414 -65.296288)
		(width 0.0889)
		(layer "In4.Cu")
		(net "M_C_ECC<1>")
	)
	(arc
		(start 243.845588 -63.706502)
		(mid 243.796833 -63.51015)
		(end 243.850414 -63.315088)
		(width 0.0889)
		(layer "In4.Cu")
		(net "M_C_ECC<1>")
	)
	(arc
		(start 243.850414 -62.324488)
		(mid 243.929636 -62.03537)
		(end 243.856764 -61.744606)
		(width 0.0889)
		(layer "In4.Cu")
		(net "M_C_ECC<1>")
	)
	(arc
		(start 243.850414 -65.296288)
		(mid 243.929636 -65.00717)
		(end 243.856764 -64.716406)
		(width 0.0889)
		(layer "In4.Cu")
		(net "M_C_ECC<1>")
	)
	(arc
		(start 243.850414 -66.286888)
		(mid 243.929534 -65.99777)
		(end 243.856764 -65.707006)
		(width 0.0889)
		(layer "In4.Cu")
		(net "M_C_ECC<1>")
	)
	(arc
		(start 243.850414 -68.667884)
		(mid 243.818143 -68.339377)
		(end 244.043708 -68.098416)
		(width 0.0889)
		(layer "In4.Cu")
		(net "M_C_ECC<1>")
	)
	(arc
		(start 243.850414 -55.390288)
		(mid 243.929636 -55.10117)
		(end 243.856764 -54.810406)
		(width 0.0889)
		(layer "In4.Cu")
		(net "M_C_ECC<1>")
	)
	(arc
		(start 243.850414 -58.761884)
		(mid 243.796915 -58.561986)
		(end 243.850414 -58.362088)
		(width 0.0889)
		(layer "In4.Cu")
		(net "M_C_ECC<1>")
	)
	(arc
		(start 243.850414 -54.399688)
		(mid 243.929636 -54.11057)
		(end 243.856764 -53.819806)
		(width 0.0889)
		(layer "In4.Cu")
		(net "M_C_ECC<1>")
	)
	(arc
		(start 243.845588 -59.744102)
		(mid 243.796833 -59.54775)
		(end 243.850414 -59.352688)
		(width 0.0889)
		(layer "In4.Cu")
		(net "M_C_ECC<1>")
	)
	(segment
		(start 236.546136 0.630936)
		(end 236.7026 0.7874)
		(width 0.14224)
		(layer "In11.Cu")
		(net "M_C_ECC<1>")
	)
	(segment
		(start 236.332776 1.4986)
		(end 235.977176 1.4986)
		(width 0.14224)
		(layer "In11.Cu")
		(net "M_C_ECC<1>")
	)
	(segment
		(start 236.171994 -3.076956)
		(end 236.546136 -2.702814)
		(width 0.14224)
		(layer "In11.Cu")
		(net "M_C_ECC<1>")
	)
	(segment
		(start 236.7026 1.128776)
		(end 236.332776 1.4986)
		(width 0.14224)
		(layer "In11.Cu")
		(net "M_C_ECC<1>")
	)
	(segment
		(start 236.546136 -2.702814)
		(end 236.546136 0.630936)
		(width 0.14224)
		(layer "In11.Cu")
		(net "M_C_ECC<1>")
	)
	(segment
		(start 235.977176 1.4986)
		(end 235.49991 1.975866)
		(width 0.14224)
		(layer "In11.Cu")
		(net "M_C_ECC<1>")
	)
	(segment
		(start 236.7026 0.7874)
		(end 236.7026 1.128776)
		(width 0.14224)
		(layer "In11.Cu")
		(net "M_C_ECC<1>")
	)
	(segment
		(start 235.49991 1.975866)
		(end 235.49991 2.514854)
		(width 0.14224)
		(layer "In11.Cu")
		(net "M_C_ECC<1>")
	)
	(segment
		(start 236.350302 -0.821182)
		(end 236.349794 -0.821182)
		(width 0.1651)
		(layer "F.Cu")
		(net "M_C_ECC<0>")
	)
	(segment
		(start 244.768624 -67.47764)
		(end 244.197124 -67.47764)
		(width 0.0889)
		(layer "F.Cu")
		(net "M_C_ECC<0>")
	)
	(segment
		(start 236.349794 -0.821182)
		(end 236.171994 1.0414)
		(width 0.1651)
		(layer "F.Cu")
		(net "M_C_ECC<0>")
	)
	(via
		(at 244.197124 -67.47764)
		(size 0.508)
		(drill 0.254)
		(layers "F.Cu" "B.Cu")
		(net "M_C_ECC<0>")
	)
	(via
		(at 235.49991 -4.357878)
		(size 0.508)
		(drill 0.254)
		(layers "F.Cu" "B.Cu")
		(net "M_C_ECC<0>")
	)
	(via
		(at 236.171994 1.0414)
		(size 0.508)
		(drill 0.254)
		(layers "F.Cu" "B.Cu")
		(net "M_C_ECC<0>")
	)
	(segment
		(start 235.500418 -5.621782)
		(end 235.49991 -5.621782)
		(width 0.1651)
		(layer "B.Cu")
		(net "M_C_ECC<0>")
	)
	(segment
		(start 235.49991 -5.621782)
		(end 235.49991 -4.357878)
		(width 0.1651)
		(layer "B.Cu")
		(net "M_C_ECC<0>")
	)
	(segment
		(start 238.4679 -37.50183)
		(end 238.62284 -37.34689)
		(width 0.14224)
		(layer "In4.Cu")
		(net "M_C_ECC<0>")
	)
	(segment
		(start 238.62284 -37.34689)
		(end 239.07496 -37.34689)
		(width 0.14224)
		(layer "In4.Cu")
		(net "M_C_ECC<0>")
	)
	(segment
		(start 243.69014 -61.837824)
		(end 243.685314 -61.829188)
		(width 0.0889)
		(layer "In4.Cu")
		(net "M_C_ECC<0>")
	)
	(segment
		(start 243.69014 -55.894224)
		(end 243.685314 -55.885588)
		(width 0.0889)
		(layer "In4.Cu")
		(net "M_C_ECC<0>")
	)
	(segment
		(start 235.389928 -6.180582)
		(end 235.389928 -4.46786)
		(width 0.14224)
		(layer "In4.Cu")
		(net "M_C_ECC<0>")
	)
	(segment
		(start 236.024928 -12.081256)
		(end 236.024928 -9.025382)
		(width 0.14224)
		(layer "In4.Cu")
		(net "M_C_ECC<0>")
	)
	(segment
		(start 243.685314 -53.904388)
		(end 243.678964 -53.89372)
		(width 0.0889)
		(layer "In4.Cu")
		(net "M_C_ECC<0>")
	)
	(segment
		(start 235.682028 -23.109428)
		(end 235.682028 -22.025356)
		(width 0.14224)
		(layer "In4.Cu")
		(net "M_C_ECC<0>")
	)
	(segment
		(start 238.62284 -38.00983)
		(end 238.4679 -37.85489)
		(width 0.14224)
		(layer "In4.Cu")
		(net "M_C_ECC<0>")
	)
	(segment
		(start 238.4679 -38.82771)
		(end 238.62284 -38.67277)
		(width 0.14224)
		(layer "In4.Cu")
		(net "M_C_ECC<0>")
	)
	(segment
		(start 238.9632 -40.54983)
		(end 238.9632 -40.11041)
		(width 0.14224)
		(layer "In4.Cu")
		(net "M_C_ECC<0>")
	)
	(segment
		(start 239.2299 -36.702746)
		(end 237.7694 -35.242246)
		(width 0.14224)
		(layer "In4.Cu")
		(net "M_C_ECC<0>")
	)
	(segment
		(start 243.740686 -50.798476)
		(end 243.567204 -50.624994)
		(width 0.0889)
		(layer "In4.Cu")
		(net "M_C_ECC<0>")
	)
	(segment
		(start 239.07496 -39.33571)
		(end 238.62284 -39.33571)
		(width 0.14224)
		(layer "In4.Cu")
		(net "M_C_ECC<0>")
	)
	(segment
		(start 243.567204 -50.345594)
		(end 243.346224 -50.124614)
		(width 0.0889)
		(layer "In4.Cu")
		(net "M_C_ECC<0>")
	)
	(segment
		(start 236.024928 -26.623264)
		(end 236.024928 -23.452328)
		(width 0.14224)
		(layer "In4.Cu")
		(net "M_C_ECC<0>")
	)
	(segment
		(start 238.9632 -40.11041)
		(end 239.2299 -39.84371)
		(width 0.14224)
		(layer "In4.Cu")
		(net "M_C_ECC<0>")
	)
	(segment
		(start 239.07496 -37.34689)
		(end 239.2299 -37.19195)
		(width 0.14224)
		(layer "In4.Cu")
		(net "M_C_ECC<0>")
	)
	(segment
		(start 235.682028 -17.123918)
		(end 236.024928 -16.781018)
		(width 0.14224)
		(layer "In4.Cu")
		(net "M_C_ECC<0>")
	)
	(segment
		(start 239.2299 -38.16477)
		(end 239.07496 -38.00983)
		(width 0.14224)
		(layer "In4.Cu")
		(net "M_C_ECC<0>")
	)
	(segment
		(start 237.7694 -32.182054)
		(end 236.0168 -30.429454)
		(width 0.14224)
		(layer "In4.Cu")
		(net "M_C_ECC<0>")
	)
	(segment
		(start 238.4679 -37.85489)
		(end 238.4679 -37.50183)
		(width 0.14224)
		(layer "In4.Cu")
		(net "M_C_ECC<0>")
	)
	(segment
		(start 243.69014 -65.800224)
		(end 243.685314 -65.791588)
		(width 0.0889)
		(layer "In4.Cu")
		(net "M_C_ECC<0>")
	)
	(segment
		(start 243.697252 -51.378866)
		(end 243.740686 -51.335432)
		(width 0.0889)
		(layer "In4.Cu")
		(net "M_C_ECC<0>")
	)
	(segment
		(start 239.07496 -38.00983)
		(end 238.62284 -38.00983)
		(width 0.14224)
		(layer "In4.Cu")
		(net "M_C_ECC<0>")
	)
	(segment
		(start 236.024928 -13.851128)
		(end 235.682028 -13.508228)
		(width 0.14224)
		(layer "In4.Cu")
		(net "M_C_ECC<0>")
	)
	(segment
		(start 239.2299 -44.3992)
		(end 239.2299 -40.81653)
		(width 0.14224)
		(layer "In4.Cu")
		(net "M_C_ECC<0>")
	)
	(segment
		(start 235.682028 -13.508228)
		(end 235.682028 -12.424156)
		(width 0.14224)
		(layer "In4.Cu")
		(net "M_C_ECC<0>")
	)
	(segment
		(start 235.682028 -22.025356)
		(end 236.024928 -21.682456)
		(width 0.14224)
		(layer "In4.Cu")
		(net "M_C_ECC<0>")
	)
	(segment
		(start 235.974128 -6.764782)
		(end 235.389928 -6.180582)
		(width 0.14224)
		(layer "In4.Cu")
		(net "M_C_ECC<0>")
	)
	(segment
		(start 243.685314 -65.791588)
		(end 243.678964 -65.78092)
		(width 0.0889)
		(layer "In4.Cu")
		(net "M_C_ECC<0>")
	)
	(segment
		(start 243.685314 -64.800988)
		(end 243.678964 -64.79032)
		(width 0.0889)
		(layer "In4.Cu")
		(net "M_C_ECC<0>")
	)
	(segment
		(start 243.69014 -62.828424)
		(end 243.685314 -62.819788)
		(width 0.0889)
		(layer "In4.Cu")
		(net "M_C_ECC<0>")
	)
	(segment
		(start 243.69014 -59.856624)
		(end 243.685314 -59.847988)
		(width 0.0889)
		(layer "In4.Cu")
		(net "M_C_ECC<0>")
	)
	(segment
		(start 235.682028 -18.309082)
		(end 235.682028 -17.123918)
		(width 0.14224)
		(layer "In4.Cu")
		(net "M_C_ECC<0>")
	)
	(segment
		(start 235.682028 -8.682482)
		(end 235.682028 -7.522718)
		(width 0.14224)
		(layer "In4.Cu")
		(net "M_C_ECC<0>")
	)
	(segment
		(start 239.2299 -38.51783)
		(end 239.2299 -38.16477)
		(width 0.14224)
		(layer "In4.Cu")
		(net "M_C_ECC<0>")
	)
	(segment
		(start 237.7694 -35.242246)
		(end 237.7694 -32.182054)
		(width 0.14224)
		(layer "In4.Cu")
		(net "M_C_ECC<0>")
	)
	(segment
		(start 243.346224 -50.124614)
		(end 243.346224 -48.515524)
		(width 0.14224)
		(layer "In4.Cu")
		(net "M_C_ECC<0>")
	)
	(segment
		(start 239.2299 -40.81653)
		(end 238.9632 -40.54983)
		(width 0.14224)
		(layer "In4.Cu")
		(net "M_C_ECC<0>")
	)
	(segment
		(start 243.69014 -54.903624)
		(end 243.685314 -54.894988)
		(width 0.0889)
		(layer "In4.Cu")
		(net "M_C_ECC<0>")
	)
	(segment
		(start 243.69014 -58.866024)
		(end 243.685314 -58.857388)
		(width 0.0889)
		(layer "In4.Cu")
		(net "M_C_ECC<0>")
	)
	(segment
		(start 236.024928 -9.025382)
		(end 235.682028 -8.682482)
		(width 0.14224)
		(layer "In4.Cu")
		(net "M_C_ECC<0>")
	)
	(segment
		(start 239.2299 -39.84371)
		(end 239.2299 -39.49065)
		(width 0.14224)
		(layer "In4.Cu")
		(net "M_C_ECC<0>")
	)
	(segment
		(start 243.685314 -62.819788)
		(end 243.678964 -62.80912)
		(width 0.0889)
		(layer "In4.Cu")
		(net "M_C_ECC<0>")
	)
	(segment
		(start 243.685314 -59.847988)
		(end 243.678964 -59.83732)
		(width 0.0889)
		(layer "In4.Cu")
		(net "M_C_ECC<0>")
	)
	(segment
		(start 235.682028 -12.424156)
		(end 236.024928 -12.081256)
		(width 0.14224)
		(layer "In4.Cu")
		(net "M_C_ECC<0>")
	)
	(segment
		(start 243.685314 -55.885588)
		(end 243.678964 -55.87492)
		(width 0.0889)
		(layer "In4.Cu")
		(net "M_C_ECC<0>")
	)
	(segment
		(start 236.024928 -23.452328)
		(end 235.682028 -23.109428)
		(width 0.14224)
		(layer "In4.Cu")
		(net "M_C_ECC<0>")
	)
	(segment
		(start 243.689378 -66.7893)
		(end 243.685314 -66.782188)
		(width 0.0889)
		(layer "In4.Cu")
		(net "M_C_ECC<0>")
	)
	(segment
		(start 236.0168 -28.357068)
		(end 235.679996 -28.020264)
		(width 0.14224)
		(layer "In4.Cu")
		(net "M_C_ECC<0>")
	)
	(segment
		(start 243.69014 -53.913024)
		(end 243.685314 -53.904388)
		(width 0.0889)
		(layer "In4.Cu")
		(net "M_C_ECC<0>")
	)
	(segment
		(start 243.685314 -53.313838)
		(end 243.697252 -53.29301)
		(width 0.0889)
		(layer "In4.Cu")
		(net "M_C_ECC<0>")
	)
	(segment
		(start 235.679996 -28.020264)
		(end 235.679996 -26.968196)
		(width 0.14224)
		(layer "In4.Cu")
		(net "M_C_ECC<0>")
	)
	(segment
		(start 235.389928 -4.46786)
		(end 235.49991 -4.357878)
		(width 0.14224)
		(layer "In4.Cu")
		(net "M_C_ECC<0>")
	)
	(segment
		(start 243.567204 -50.624994)
		(end 243.567204 -50.345594)
		(width 0.0889)
		(layer "In4.Cu")
		(net "M_C_ECC<0>")
	)
	(segment
		(start 243.69014 -64.809624)
		(end 243.685314 -64.800988)
		(width 0.0889)
		(layer "In4.Cu")
		(net "M_C_ECC<0>")
	)
	(segment
		(start 235.974128 -7.230618)
		(end 235.974128 -6.764782)
		(width 0.14224)
		(layer "In4.Cu")
		(net "M_C_ECC<0>")
	)
	(segment
		(start 243.678964 -58.277506)
		(end 243.685314 -58.266838)
		(width 0.0889)
		(layer "In4.Cu")
		(net "M_C_ECC<0>")
	)
	(segment
		(start 236.024928 -16.781018)
		(end 236.024928 -13.851128)
		(width 0.14224)
		(layer "In4.Cu")
		(net "M_C_ECC<0>")
	)
	(segment
		(start 238.62284 -39.33571)
		(end 238.4679 -39.18077)
		(width 0.14224)
		(layer "In4.Cu")
		(net "M_C_ECC<0>")
	)
	(segment
		(start 236.024928 -18.651982)
		(end 235.682028 -18.309082)
		(width 0.14224)
		(layer "In4.Cu")
		(net "M_C_ECC<0>")
	)
	(segment
		(start 235.682028 -7.522718)
		(end 235.974128 -7.230618)
		(width 0.14224)
		(layer "In4.Cu")
		(net "M_C_ECC<0>")
	)
	(segment
		(start 235.679996 -26.968196)
		(end 236.024928 -26.623264)
		(width 0.14224)
		(layer "In4.Cu")
		(net "M_C_ECC<0>")
	)
	(segment
		(start 243.697252 -53.29301)
		(end 243.697252 -51.378866)
		(width 0.0889)
		(layer "In4.Cu")
		(net "M_C_ECC<0>")
	)
	(segment
		(start 236.0168 -30.429454)
		(end 236.0168 -28.357068)
		(width 0.14224)
		(layer "In4.Cu")
		(net "M_C_ECC<0>")
	)
	(segment
		(start 243.346224 -48.515524)
		(end 239.2299 -44.3992)
		(width 0.14224)
		(layer "In4.Cu")
		(net "M_C_ECC<0>")
	)
	(segment
		(start 243.685314 -56.876188)
		(end 243.678964 -56.86552)
		(width 0.0889)
		(layer "In4.Cu")
		(net "M_C_ECC<0>")
	)
	(segment
		(start 243.685314 -61.829188)
		(end 243.678964 -61.81852)
		(width 0.0889)
		(layer "In4.Cu")
		(net "M_C_ECC<0>")
	)
	(segment
		(start 239.2299 -39.49065)
		(end 239.07496 -39.33571)
		(width 0.14224)
		(layer "In4.Cu")
		(net "M_C_ECC<0>")
	)
	(segment
		(start 236.024928 -21.682456)
		(end 236.024928 -18.651982)
		(width 0.14224)
		(layer "In4.Cu")
		(net "M_C_ECC<0>")
	)
	(segment
		(start 243.69014 -56.884824)
		(end 243.685314 -56.876188)
		(width 0.0889)
		(layer "In4.Cu")
		(net "M_C_ECC<0>")
	)
	(segment
		(start 243.685314 -63.810388)
		(end 243.678964 -63.79972)
		(width 0.0889)
		(layer "In4.Cu")
		(net "M_C_ECC<0>")
	)
	(segment
		(start 243.740686 -51.335432)
		(end 243.740686 -50.798476)
		(width 0.0889)
		(layer "In4.Cu")
		(net "M_C_ECC<0>")
	)
	(segment
		(start 243.685314 -54.894988)
		(end 243.678964 -54.88432)
		(width 0.0889)
		(layer "In4.Cu")
		(net "M_C_ECC<0>")
	)
	(segment
		(start 238.4679 -39.18077)
		(end 238.4679 -38.82771)
		(width 0.14224)
		(layer "In4.Cu")
		(net "M_C_ECC<0>")
	)
	(segment
		(start 243.69014 -63.819024)
		(end 243.685314 -63.810388)
		(width 0.0889)
		(layer "In4.Cu")
		(net "M_C_ECC<0>")
	)
	(segment
		(start 243.69014 -60.847224)
		(end 243.685314 -60.838588)
		(width 0.0889)
		(layer "In4.Cu")
		(net "M_C_ECC<0>")
	)
	(segment
		(start 243.685314 -60.838588)
		(end 243.678964 -60.82792)
		(width 0.0889)
		(layer "In4.Cu")
		(net "M_C_ECC<0>")
	)
	(segment
		(start 238.62284 -38.67277)
		(end 239.07496 -38.67277)
		(width 0.14224)
		(layer "In4.Cu")
		(net "M_C_ECC<0>")
	)
	(segment
		(start 239.2299 -37.19195)
		(end 239.2299 -36.702746)
		(width 0.14224)
		(layer "In4.Cu")
		(net "M_C_ECC<0>")
	)
	(segment
		(start 239.07496 -38.67277)
		(end 239.2299 -38.51783)
		(width 0.14224)
		(layer "In4.Cu")
		(net "M_C_ECC<0>")
	)
	(arc
		(start 243.678964 -54.88432)
		(mid 243.606166 -54.593557)
		(end 243.685314 -54.304438)
		(width 0.0889)
		(layer "In4.Cu")
		(net "M_C_ECC<0>")
	)
	(arc
		(start 243.678964 -56.86552)
		(mid 243.606166 -56.574757)
		(end 243.685314 -56.285638)
		(width 0.0889)
		(layer "In4.Cu")
		(net "M_C_ECC<0>")
	)
	(arc
		(start 243.685314 -54.304438)
		(mid 243.738784 -54.109375)
		(end 243.69014 -53.913024)
		(width 0.0889)
		(layer "In4.Cu")
		(net "M_C_ECC<0>")
	)
	(arc
		(start 243.685314 -55.295038)
		(mid 243.738784 -55.099975)
		(end 243.69014 -54.903624)
		(width 0.0889)
		(layer "In4.Cu")
		(net "M_C_ECC<0>")
	)
	(arc
		(start 243.678964 -64.79032)
		(mid 243.606166 -64.499557)
		(end 243.685314 -64.210438)
		(width 0.0889)
		(layer "In4.Cu")
		(net "M_C_ECC<0>")
	)
	(arc
		(start 243.685314 -58.857388)
		(mid 243.606092 -58.56827)
		(end 243.678964 -58.277506)
		(width 0.0889)
		(layer "In4.Cu")
		(net "M_C_ECC<0>")
	)
	(arc
		(start 244.197124 -67.47764)
		(mid 244.078514 -67.343898)
		(end 243.966492 -67.20459)
		(width 0.0889)
		(layer "In4.Cu")
		(net "M_C_ECC<0>")
	)
	(arc
		(start 243.678964 -62.80912)
		(mid 243.606166 -62.518357)
		(end 243.685314 -62.229238)
		(width 0.0889)
		(layer "In4.Cu")
		(net "M_C_ECC<0>")
	)
	(arc
		(start 243.685314 -66.782188)
		(mid 243.606183 -66.486786)
		(end 243.685314 -66.191384)
		(width 0.0889)
		(layer "In4.Cu")
		(net "M_C_ECC<0>")
	)
	(arc
		(start 243.685314 -61.238638)
		(mid 243.738784 -61.043575)
		(end 243.69014 -60.847224)
		(width 0.0889)
		(layer "In4.Cu")
		(net "M_C_ECC<0>")
	)
	(arc
		(start 243.678964 -53.89372)
		(mid 243.606166 -53.602957)
		(end 243.685314 -53.313838)
		(width 0.0889)
		(layer "In4.Cu")
		(net "M_C_ECC<0>")
	)
	(arc
		(start 243.678964 -61.81852)
		(mid 243.606166 -61.527757)
		(end 243.685314 -61.238638)
		(width 0.0889)
		(layer "In4.Cu")
		(net "M_C_ECC<0>")
	)
	(arc
		(start 243.678964 -59.83732)
		(mid 243.606166 -59.546557)
		(end 243.685314 -59.257438)
		(width 0.0889)
		(layer "In4.Cu")
		(net "M_C_ECC<0>")
	)
	(arc
		(start 243.685314 -57.867042)
		(mid 243.606183 -57.57164)
		(end 243.685314 -57.276238)
		(width 0.0889)
		(layer "In4.Cu")
		(net "M_C_ECC<0>")
	)
	(arc
		(start 243.685314 -58.266838)
		(mid 243.738813 -58.06694)
		(end 243.685314 -57.867042)
		(width 0.0889)
		(layer "In4.Cu")
		(net "M_C_ECC<0>")
	)
	(arc
		(start 243.685314 -57.276238)
		(mid 243.738784 -57.081175)
		(end 243.69014 -56.884824)
		(width 0.0889)
		(layer "In4.Cu")
		(net "M_C_ECC<0>")
	)
	(arc
		(start 243.678964 -65.78092)
		(mid 243.606166 -65.490157)
		(end 243.685314 -65.201038)
		(width 0.0889)
		(layer "In4.Cu")
		(net "M_C_ECC<0>")
	)
	(arc
		(start 243.966492 -67.20459)
		(mid 243.821217 -67.001428)
		(end 243.689378 -66.7893)
		(width 0.0889)
		(layer "In4.Cu")
		(net "M_C_ECC<0>")
	)
	(arc
		(start 243.685314 -59.257438)
		(mid 243.738784 -59.062375)
		(end 243.69014 -58.866024)
		(width 0.0889)
		(layer "In4.Cu")
		(net "M_C_ECC<0>")
	)
	(arc
		(start 243.685314 -64.210438)
		(mid 243.738784 -64.015375)
		(end 243.69014 -63.819024)
		(width 0.0889)
		(layer "In4.Cu")
		(net "M_C_ECC<0>")
	)
	(arc
		(start 243.678964 -60.82792)
		(mid 243.606166 -60.537157)
		(end 243.685314 -60.248038)
		(width 0.0889)
		(layer "In4.Cu")
		(net "M_C_ECC<0>")
	)
	(arc
		(start 243.685314 -62.229238)
		(mid 243.738784 -62.034175)
		(end 243.69014 -61.837824)
		(width 0.0889)
		(layer "In4.Cu")
		(net "M_C_ECC<0>")
	)
	(arc
		(start 243.685314 -63.219838)
		(mid 243.738784 -63.024775)
		(end 243.69014 -62.828424)
		(width 0.0889)
		(layer "In4.Cu")
		(net "M_C_ECC<0>")
	)
	(arc
		(start 243.678964 -63.79972)
		(mid 243.606166 -63.508957)
		(end 243.685314 -63.219838)
		(width 0.0889)
		(layer "In4.Cu")
		(net "M_C_ECC<0>")
	)
	(arc
		(start 243.678964 -55.87492)
		(mid 243.606166 -55.584157)
		(end 243.685314 -55.295038)
		(width 0.0889)
		(layer "In4.Cu")
		(net "M_C_ECC<0>")
	)
	(arc
		(start 243.685314 -60.248038)
		(mid 243.738784 -60.052975)
		(end 243.69014 -59.856624)
		(width 0.0889)
		(layer "In4.Cu")
		(net "M_C_ECC<0>")
	)
	(arc
		(start 243.685314 -66.191384)
		(mid 243.73885 -65.996433)
		(end 243.69014 -65.800224)
		(width 0.0889)
		(layer "In4.Cu")
		(net "M_C_ECC<0>")
	)
	(arc
		(start 243.685314 -65.201038)
		(mid 243.738784 -65.005975)
		(end 243.69014 -64.809624)
		(width 0.0889)
		(layer "In4.Cu")
		(net "M_C_ECC<0>")
	)
	(arc
		(start 243.685314 -56.285638)
		(mid 243.738784 -56.090575)
		(end 243.69014 -55.894224)
		(width 0.0889)
		(layer "In4.Cu")
		(net "M_C_ECC<0>")
	)
	(segment
		(start 235.49991 -4.357878)
		(end 235.215176 -4.073144)
		(width 0.14224)
		(layer "In11.Cu")
		(net "M_C_ECC<0>")
	)
	(segment
		(start 235.215176 -4.073144)
		(end 235.215176 -3.3274)
		(width 0.14224)
		(layer "In11.Cu")
		(net "M_C_ECC<0>")
	)
	(segment
		(start 235.215176 -3.3274)
		(end 235.951776 -2.5908)
		(width 0.14224)
		(layer "In11.Cu")
		(net "M_C_ECC<0>")
	)
	(segment
		(start 235.951776 0.821182)
		(end 236.171994 1.0414)
		(width 0.14224)
		(layer "In11.Cu")
		(net "M_C_ECC<0>")
	)
	(segment
		(start 235.951776 -2.5908)
		(end 235.951776 0.821182)
		(width 0.14224)
		(layer "In11.Cu")
		(net "M_C_ECC<0>")
	)
	(segment
		(start 241.334798 -65.49644)
		(end 240.763298 -65.49644)
		(width 0.0889)
		(layer "F.Cu")
		(net "M_C_DQS_DP<9>")
	)
	(segment
		(start 199.36079 1.499616)
		(end 199.742552 1.117854)
		(width 0.1651)
		(layer "F.Cu")
		(net "M_C_DQS_DP<9>")
	)
	(segment
		(start 199.279256 2.542032)
		(end 199.279256 1.723898)
		(width 0.1651)
		(layer "F.Cu")
		(net "M_C_DQS_DP<9>")
	)
	(segment
		(start 199.799956 3.162046)
		(end 199.363838 2.725928)
		(width 0.1651)
		(layer "F.Cu")
		(net "M_C_DQS_DP<9>")
	)
	(segment
		(start 199.799956 3.778758)
		(end 199.799956 3.162046)
		(width 0.1651)
		(layer "F.Cu")
		(net "M_C_DQS_DP<9>")
	)
	(segment
		(start 199.363838 2.725928)
		(end 199.279256 2.542032)
		(width 0.1651)
		(layer "F.Cu")
		(net "M_C_DQS_DP<9>")
	)
	(segment
		(start 199.279256 1.723898)
		(end 199.36079 1.499616)
		(width 0.1651)
		(layer "F.Cu")
		(net "M_C_DQS_DP<9>")
	)
	(segment
		(start 199.800464 3.778758)
		(end 199.799956 3.778758)
		(width 0.1651)
		(layer "F.Cu")
		(net "M_C_DQS_DP<9>")
	)
	(via
		(at 240.763298 -65.49644)
		(size 0.508)
		(drill 0.254)
		(layers "F.Cu" "B.Cu")
		(net "M_C_DQS_DP<9>")
	)
	(via
		(at 199.742552 -2.9718)
		(size 0.508)
		(drill 0.254)
		(layers "F.Cu" "B.Cu")
		(net "M_C_DQS_DP<9>")
	)
	(via
		(at 199.742552 1.117854)
		(size 0.508)
		(drill 0.254)
		(layers "F.Cu" "B.Cu")
		(net "M_C_DQS_DP<9>")
	)
	(segment
		(start 199.799956 -5.621782)
		(end 199.799956 -5.004054)
		(width 0.1651)
		(layer "B.Cu")
		(net "M_C_DQS_DP<9>")
	)
	(segment
		(start 199.266556 -4.415536)
		(end 199.266556 -3.519932)
		(width 0.1651)
		(layer "B.Cu")
		(net "M_C_DQS_DP<9>")
	)
	(segment
		(start 199.343772 -4.54787)
		(end 199.266556 -4.415536)
		(width 0.1651)
		(layer "B.Cu")
		(net "M_C_DQS_DP<9>")
	)
	(segment
		(start 199.353932 -3.36042)
		(end 199.742552 -2.9718)
		(width 0.1651)
		(layer "B.Cu")
		(net "M_C_DQS_DP<9>")
	)
	(segment
		(start 199.800464 -5.621782)
		(end 199.799956 -5.621782)
		(width 0.1651)
		(layer "B.Cu")
		(net "M_C_DQS_DP<9>")
	)
	(segment
		(start 199.799956 -5.004054)
		(end 199.343772 -4.54787)
		(width 0.1651)
		(layer "B.Cu")
		(net "M_C_DQS_DP<9>")
	)
	(segment
		(start 199.266556 -3.519932)
		(end 199.353932 -3.36042)
		(width 0.1651)
		(layer "B.Cu")
		(net "M_C_DQS_DP<9>")
	)
	(segment
		(start 200.262236 -1.03632)
		(end 200.262236 -0.79248)
		(width 0.14224)
		(layer "In11.Cu")
		(net "M_C_DQS_DP<9>")
	)
	(segment
		(start 199.824848 -36.382706)
		(end 200.129394 -36.382706)
		(width 0.14224)
		(layer "In11.Cu")
		(net "M_C_DQS_DP<9>")
	)
	(segment
		(start 199.78751 -33.129982)
		(end 199.78751 -33.63849)
		(width 0.14224)
		(layer "In11.Cu")
		(net "M_C_DQS_DP<9>")
	)
	(segment
		(start 199.742552 -2.9718)
		(end 199.271636 -3.442716)
		(width 0.14224)
		(layer "In11.Cu")
		(net "M_C_DQS_DP<9>")
	)
	(segment
		(start 200.48728 -20.954238)
		(end 200.255632 -21.185886)
		(width 0.14224)
		(layer "In11.Cu")
		(net "M_C_DQS_DP<9>")
	)
	(segment
		(start 200.053956 -0.5842)
		(end 199.926956 -0.5842)
		(width 0.14224)
		(layer "In11.Cu")
		(net "M_C_DQS_DP<9>")
	)
	(segment
		(start 200.162668 -39.098728)
		(end 201.847196 -39.098728)
		(width 0.14224)
		(layer "In11.Cu")
		(net "M_C_DQS_DP<9>")
	)
	(segment
		(start 199.271636 -5.367274)
		(end 200.255632 -6.35127)
		(width 0.14224)
		(layer "In11.Cu")
		(net "M_C_DQS_DP<9>")
	)
	(segment
		(start 235.598462 -65.09639)
		(end 235.627164 -65.09639)
		(width 0.0889)
		(layer "In11.Cu")
		(net "M_C_DQS_DP<9>")
	)
	(segment
		(start 201.847196 -39.098728)
		(end 202.340464 -39.591996)
		(width 0.14224)
		(layer "In11.Cu")
		(net "M_C_DQS_DP<9>")
	)
	(segment
		(start 202.340464 -39.591996)
		(end 202.340464 -40.860472)
		(width 0.14224)
		(layer "In11.Cu")
		(net "M_C_DQS_DP<9>")
	)
	(segment
		(start 200.262236 1.145286)
		(end 200.081642 1.32588)
		(width 0.14224)
		(layer "In11.Cu")
		(net "M_C_DQS_DP<9>")
	)
	(segment
		(start 199.44588 -25.183592)
		(end 199.44588 -32.788352)
		(width 0.14224)
		(layer "In11.Cu")
		(net "M_C_DQS_DP<9>")
	)
	(segment
		(start 199.44588 -33.98012)
		(end 199.44588 -36.003738)
		(width 0.14224)
		(layer "In11.Cu")
		(net "M_C_DQS_DP<9>")
	)
	(segment
		(start 200.262236 -0.79248)
		(end 200.053956 -0.5842)
		(width 0.14224)
		(layer "In11.Cu")
		(net "M_C_DQS_DP<9>")
	)
	(segment
		(start 237.311438 -66.08699)
		(end 237.344204 -66.08699)
		(width 0.0889)
		(layer "In11.Cu")
		(net "M_C_DQS_DP<9>")
	)
	(segment
		(start 200.262236 -2.731262)
		(end 200.262236 -2.08788)
		(width 0.14224)
		(layer "In11.Cu")
		(net "M_C_DQS_DP<9>")
	)
	(segment
		(start 199.898508 -1.2192)
		(end 200.079356 -1.2192)
		(width 0.14224)
		(layer "In11.Cu")
		(net "M_C_DQS_DP<9>")
	)
	(segment
		(start 239.04575 -67.07759)
		(end 239.046766 -67.07759)
		(width 0.0889)
		(layer "In11.Cu")
		(net "M_C_DQS_DP<9>")
	)
	(segment
		(start 200.021698 -2.9718)
		(end 200.262236 -2.731262)
		(width 0.14224)
		(layer "In11.Cu")
		(net "M_C_DQS_DP<9>")
	)
	(segment
		(start 200.081642 1.32588)
		(end 199.950578 1.32588)
		(width 0.14224)
		(layer "In11.Cu")
		(net "M_C_DQS_DP<9>")
	)
	(segment
		(start 238.166148 -66.582036)
		(end 238.198914 -66.582036)
		(width 0.0889)
		(layer "In11.Cu")
		(net "M_C_DQS_DP<9>")
	)
	(segment
		(start 199.271636 -3.442716)
		(end 199.271636 -5.367274)
		(width 0.14224)
		(layer "In11.Cu")
		(net "M_C_DQS_DP<9>")
	)
	(segment
		(start 199.927464 -1.8415)
		(end 199.771 -1.685036)
		(width 0.14224)
		(layer "In11.Cu")
		(net "M_C_DQS_DP<9>")
	)
	(segment
		(start 199.876156 -37.680392)
		(end 199.876156 -38.812216)
		(width 0.14224)
		(layer "In11.Cu")
		(net "M_C_DQS_DP<9>")
	)
	(segment
		(start 199.44588 -32.788352)
		(end 199.78751 -33.129982)
		(width 0.14224)
		(layer "In11.Cu")
		(net "M_C_DQS_DP<9>")
	)
	(segment
		(start 202.340464 -40.860472)
		(end 202.751436 -41.271444)
		(width 0.14224)
		(layer "In11.Cu")
		(net "M_C_DQS_DP<9>")
	)
	(segment
		(start 200.262236 -2.08788)
		(end 200.015856 -1.8415)
		(width 0.14224)
		(layer "In11.Cu")
		(net "M_C_DQS_DP<9>")
	)
	(segment
		(start 200.255632 -24.37384)
		(end 199.44588 -25.183592)
		(width 0.14224)
		(layer "In11.Cu")
		(net "M_C_DQS_DP<9>")
	)
	(segment
		(start 200.262236 0.30988)
		(end 200.262236 1.145286)
		(width 0.14224)
		(layer "In11.Cu")
		(net "M_C_DQS_DP<9>")
	)
	(segment
		(start 199.771 -1.346708)
		(end 199.898508 -1.2192)
		(width 0.14224)
		(layer "In11.Cu")
		(net "M_C_DQS_DP<9>")
	)
	(segment
		(start 199.44588 -36.003738)
		(end 199.824848 -36.382706)
		(width 0.14224)
		(layer "In11.Cu")
		(net "M_C_DQS_DP<9>")
	)
	(segment
		(start 199.742552 -2.9718)
		(end 200.021698 -2.9718)
		(width 0.14224)
		(layer "In11.Cu")
		(net "M_C_DQS_DP<9>")
	)
	(segment
		(start 199.774556 -0.1778)
		(end 200.262236 0.30988)
		(width 0.14224)
		(layer "In11.Cu")
		(net "M_C_DQS_DP<9>")
	)
	(segment
		(start 199.950578 1.32588)
		(end 199.742552 1.117854)
		(width 0.14224)
		(layer "In11.Cu")
		(net "M_C_DQS_DP<9>")
	)
	(segment
		(start 203.85659 -41.271444)
		(end 204.247496 -41.66235)
		(width 0.14224)
		(layer "In11.Cu")
		(net "M_C_DQS_DP<9>")
	)
	(segment
		(start 204.247496 -41.66235)
		(end 204.247496 -43.316652)
		(width 0.14224)
		(layer "In11.Cu")
		(net "M_C_DQS_DP<9>")
	)
	(segment
		(start 202.751436 -41.271444)
		(end 203.85659 -41.271444)
		(width 0.14224)
		(layer "In11.Cu")
		(net "M_C_DQS_DP<9>")
	)
	(segment
		(start 234.752896 -64.60109)
		(end 234.75442 -64.60109)
		(width 0.0889)
		(layer "In11.Cu")
		(net "M_C_DQS_DP<9>")
	)
	(segment
		(start 200.015856 -1.8415)
		(end 199.927464 -1.8415)
		(width 0.14224)
		(layer "In11.Cu")
		(net "M_C_DQS_DP<9>")
	)
	(segment
		(start 200.255632 -20.060666)
		(end 200.48728 -20.292314)
		(width 0.14224)
		(layer "In11.Cu")
		(net "M_C_DQS_DP<9>")
	)
	(segment
		(start 233.894122 -65.096136)
		(end 233.896154 -65.096136)
		(width 0.0889)
		(layer "In11.Cu")
		(net "M_C_DQS_DP<9>")
	)
	(segment
		(start 200.255632 -21.185886)
		(end 200.255632 -24.37384)
		(width 0.14224)
		(layer "In11.Cu")
		(net "M_C_DQS_DP<9>")
	)
	(segment
		(start 199.78751 -33.63849)
		(end 199.44588 -33.98012)
		(width 0.14224)
		(layer "In11.Cu")
		(net "M_C_DQS_DP<9>")
	)
	(segment
		(start 230.7336 -65.13576)
		(end 230.77297 -65.09639)
		(width 0.0889)
		(layer "In11.Cu")
		(net "M_C_DQS_DP<9>")
	)
	(segment
		(start 200.413874 -37.142674)
		(end 199.876156 -37.680392)
		(width 0.14224)
		(layer "In11.Cu")
		(net "M_C_DQS_DP<9>")
	)
	(segment
		(start 230.77297 -65.09639)
		(end 232.191814 -65.09639)
		(width 0.0889)
		(layer "In11.Cu")
		(net "M_C_DQS_DP<9>")
	)
	(segment
		(start 199.771 -1.685036)
		(end 199.771 -1.346708)
		(width 0.14224)
		(layer "In11.Cu")
		(net "M_C_DQS_DP<9>")
	)
	(segment
		(start 226.066604 -65.13576)
		(end 230.7336 -65.13576)
		(width 0.14224)
		(layer "In11.Cu")
		(net "M_C_DQS_DP<9>")
	)
	(segment
		(start 200.079356 -1.2192)
		(end 200.262236 -1.03632)
		(width 0.14224)
		(layer "In11.Cu")
		(net "M_C_DQS_DP<9>")
	)
	(segment
		(start 204.247496 -43.316652)
		(end 226.066604 -65.13576)
		(width 0.14224)
		(layer "In11.Cu")
		(net "M_C_DQS_DP<9>")
	)
	(segment
		(start 200.413874 -36.667186)
		(end 200.413874 -37.142674)
		(width 0.14224)
		(layer "In11.Cu")
		(net "M_C_DQS_DP<9>")
	)
	(segment
		(start 240.268252 -66.162174)
		(end 240.763298 -65.49644)
		(width 0.0889)
		(layer "In11.Cu")
		(net "M_C_DQS_DP<9>")
	)
	(segment
		(start 199.774556 -0.4318)
		(end 199.774556 -0.1778)
		(width 0.14224)
		(layer "In11.Cu")
		(net "M_C_DQS_DP<9>")
	)
	(segment
		(start 239.649 -66.674238)
		(end 239.799368 -66.488056)
		(width 0.0889)
		(layer "In11.Cu")
		(net "M_C_DQS_DP<9>")
	)
	(segment
		(start 200.48728 -20.292314)
		(end 200.48728 -20.954238)
		(width 0.14224)
		(layer "In11.Cu")
		(net "M_C_DQS_DP<9>")
	)
	(segment
		(start 199.926956 -0.5842)
		(end 199.774556 -0.4318)
		(width 0.14224)
		(layer "In11.Cu")
		(net "M_C_DQS_DP<9>")
	)
	(segment
		(start 199.876156 -38.812216)
		(end 200.162668 -39.098728)
		(width 0.14224)
		(layer "In11.Cu")
		(net "M_C_DQS_DP<9>")
	)
	(segment
		(start 236.449108 -65.591436)
		(end 236.481874 -65.591436)
		(width 0.0889)
		(layer "In11.Cu")
		(net "M_C_DQS_DP<9>")
	)
	(segment
		(start 240.251488 -66.191638)
		(end 240.268252 -66.162174)
		(width 0.0889)
		(layer "In11.Cu")
		(net "M_C_DQS_DP<9>")
	)
	(segment
		(start 200.255632 -6.35127)
		(end 200.255632 -20.060666)
		(width 0.14224)
		(layer "In11.Cu")
		(net "M_C_DQS_DP<9>")
	)
	(segment
		(start 200.129394 -36.382706)
		(end 200.413874 -36.667186)
		(width 0.14224)
		(layer "In11.Cu")
		(net "M_C_DQS_DP<9>")
	)
	(segment
		(start 233.035856 -64.60109)
		(end 233.03738 -64.60109)
		(width 0.0889)
		(layer "In11.Cu")
		(net "M_C_DQS_DP<9>")
	)
	(arc
		(start 232.191814 -65.09639)
		(mid 232.479501 -65.013869)
		(end 232.689908 -64.800988)
		(width 0.0889)
		(layer "In11.Cu")
		(net "M_C_DQS_DP<9>")
	)
	(arc
		(start 237.675928 -66.286888)
		(mid 237.882932 -66.497752)
		(end 238.166148 -66.582036)
		(width 0.0889)
		(layer "In11.Cu")
		(net "M_C_DQS_DP<9>")
	)
	(arc
		(start 239.799368 -66.488056)
		(mid 239.85112 -66.429255)
		(end 239.919764 -66.391536)
		(width 0.0889)
		(layer "In11.Cu")
		(net "M_C_DQS_DP<9>")
	)
	(arc
		(start 233.896154 -65.096136)
		(mid 234.191148 -65.017062)
		(end 234.406948 -64.800988)
		(width 0.0889)
		(layer "In11.Cu")
		(net "M_C_DQS_DP<9>")
	)
	(arc
		(start 233.383328 -64.800988)
		(mid 233.599182 -65.016969)
		(end 233.894122 -65.096136)
		(width 0.0889)
		(layer "In11.Cu")
		(net "M_C_DQS_DP<9>")
	)
	(arc
		(start 239.046766 -67.07759)
		(mid 239.342029 -66.998439)
		(end 239.558068 -66.782188)
		(width 0.0889)
		(layer "In11.Cu")
		(net "M_C_DQS_DP<9>")
	)
	(arc
		(start 236.481874 -65.591436)
		(mid 236.675724 -65.647786)
		(end 236.817408 -65.791588)
		(width 0.0889)
		(layer "In11.Cu")
		(net "M_C_DQS_DP<9>")
	)
	(arc
		(start 236.817408 -65.791588)
		(mid 237.026016 -66.00352)
		(end 237.311438 -66.08699)
		(width 0.0889)
		(layer "In11.Cu")
		(net "M_C_DQS_DP<9>")
	)
	(arc
		(start 235.958888 -65.296288)
		(mid 236.165892 -65.507152)
		(end 236.449108 -65.591436)
		(width 0.0889)
		(layer "In11.Cu")
		(net "M_C_DQS_DP<9>")
	)
	(arc
		(start 233.03738 -64.60109)
		(mid 233.237153 -64.654659)
		(end 233.383328 -64.800988)
		(width 0.0889)
		(layer "In11.Cu")
		(net "M_C_DQS_DP<9>")
	)
	(arc
		(start 237.344204 -66.08699)
		(mid 237.535846 -66.144156)
		(end 237.675928 -66.286888)
		(width 0.0889)
		(layer "In11.Cu")
		(net "M_C_DQS_DP<9>")
	)
	(arc
		(start 238.198914 -66.582036)
		(mid 238.392764 -66.638386)
		(end 238.534448 -66.782188)
		(width 0.0889)
		(layer "In11.Cu")
		(net "M_C_DQS_DP<9>")
	)
	(arc
		(start 238.534448 -66.782188)
		(mid 238.750511 -66.998397)
		(end 239.04575 -67.07759)
		(width 0.0889)
		(layer "In11.Cu")
		(net "M_C_DQS_DP<9>")
	)
	(arc
		(start 239.558068 -66.782188)
		(mid 239.586109 -66.739858)
		(end 239.619282 -66.701416)
		(width 0.0889)
		(layer "In11.Cu")
		(net "M_C_DQS_DP<9>")
	)
	(arc
		(start 234.75442 -64.60109)
		(mid 234.954193 -64.654659)
		(end 235.100368 -64.800988)
		(width 0.0889)
		(layer "In11.Cu")
		(net "M_C_DQS_DP<9>")
	)
	(arc
		(start 234.406948 -64.800988)
		(mid 234.55312 -64.654653)
		(end 234.752896 -64.60109)
		(width 0.0889)
		(layer "In11.Cu")
		(net "M_C_DQS_DP<9>")
	)
	(arc
		(start 235.100368 -64.800988)
		(mid 235.310721 -65.01396)
		(end 235.598462 -65.09639)
		(width 0.0889)
		(layer "In11.Cu")
		(net "M_C_DQS_DP<9>")
	)
	(arc
		(start 232.689908 -64.800988)
		(mid 232.83608 -64.654653)
		(end 233.035856 -64.60109)
		(width 0.0889)
		(layer "In11.Cu")
		(net "M_C_DQS_DP<9>")
	)
	(arc
		(start 235.627164 -65.09639)
		(mid 235.818806 -65.153556)
		(end 235.958888 -65.296288)
		(width 0.0889)
		(layer "In11.Cu")
		(net "M_C_DQS_DP<9>")
	)
	(arc
		(start 239.619282 -66.701416)
		(mid 239.633797 -66.687451)
		(end 239.649 -66.674238)
		(width 0.0889)
		(layer "In11.Cu")
		(net "M_C_DQS_DP<9>")
	)
	(arc
		(start 239.919764 -66.391536)
		(mid 240.111406 -66.33437)
		(end 240.251488 -66.191638)
		(width 0.0889)
		(layer "In11.Cu")
		(net "M_C_DQS_DP<9>")
	)
	(segment
		(start 238.907574 1.455166)
		(end 238.71174 1.455166)
		(width 0.1651)
		(layer "F.Cu")
		(net "M_C_DQS_DP<8>")
	)
	(segment
		(start 238.8997 0.277368)
		(end 239.121442 0.49911)
		(width 0.1651)
		(layer "F.Cu")
		(net "M_C_DQS_DP<8>")
	)
	(segment
		(start 245.627144 -68.963286)
		(end 245.055644 -68.963286)
		(width 0.0889)
		(layer "F.Cu")
		(net "M_C_DQS_DP<8>")
	)
	(segment
		(start 238.8997 -0.82042)
		(end 238.8997 0.277368)
		(width 0.1651)
		(layer "F.Cu")
		(net "M_C_DQS_DP<8>")
	)
	(segment
		(start 238.71174 1.455166)
		(end 238.437928 1.181354)
		(width 0.1651)
		(layer "F.Cu")
		(net "M_C_DQS_DP<8>")
	)
	(segment
		(start 238.900462 -0.821182)
		(end 238.8997 -0.82042)
		(width 0.1651)
		(layer "F.Cu")
		(net "M_C_DQS_DP<8>")
	)
	(segment
		(start 239.121442 0.49911)
		(end 239.121442 1.241298)
		(width 0.1651)
		(layer "F.Cu")
		(net "M_C_DQS_DP<8>")
	)
	(segment
		(start 239.121442 1.241298)
		(end 238.907574 1.455166)
		(width 0.1651)
		(layer "F.Cu")
		(net "M_C_DQS_DP<8>")
	)
	(via
		(at 238.437928 -3.026156)
		(size 0.508)
		(drill 0.254)
		(layers "F.Cu" "B.Cu")
		(net "M_C_DQS_DP<8>")
	)
	(via
		(at 238.437928 1.181354)
		(size 0.508)
		(drill 0.254)
		(layers "F.Cu" "B.Cu")
		(net "M_C_DQS_DP<8>")
	)
	(via
		(at 245.055644 -68.963286)
		(size 0.508)
		(drill 0.254)
		(layers "F.Cu" "B.Cu")
		(net "M_C_DQS_DP<8>")
	)
	(segment
		(start 238.718852 -3.30708)
		(end 238.437928 -3.026156)
		(width 0.1651)
		(layer "B.Cu")
		(net "M_C_DQS_DP<8>")
	)
	(segment
		(start 238.899954 -2.537714)
		(end 238.8997 -2.537968)
		(width 0.1651)
		(layer "B.Cu")
		(net "M_C_DQS_DP<8>")
	)
	(segment
		(start 239.079532 -3.16738)
		(end 238.939832 -3.30708)
		(width 0.1651)
		(layer "B.Cu")
		(net "M_C_DQS_DP<8>")
	)
	(segment
		(start 238.939832 -3.30708)
		(end 238.718852 -3.30708)
		(width 0.1651)
		(layer "B.Cu")
		(net "M_C_DQS_DP<8>")
	)
	(segment
		(start 238.900462 -1.021842)
		(end 238.899954 -1.021842)
		(width 0.1651)
		(layer "B.Cu")
		(net "M_C_DQS_DP<8>")
	)
	(segment
		(start 238.899954 -1.021842)
		(end 238.899954 -2.537714)
		(width 0.1651)
		(layer "B.Cu")
		(net "M_C_DQS_DP<8>")
	)
	(segment
		(start 238.8997 -2.537968)
		(end 239.079532 -2.7178)
		(width 0.1651)
		(layer "B.Cu")
		(net "M_C_DQS_DP<8>")
	)
	(segment
		(start 239.079532 -2.7178)
		(end 239.079532 -3.16738)
		(width 0.1651)
		(layer "B.Cu")
		(net "M_C_DQS_DP<8>")
	)
	(segment
		(start 245.251732 -47.01794)
		(end 245.93804 -47.01794)
		(width 0.14224)
		(layer "In4.Cu")
		(net "M_C_DQS_DP<8>")
	)
	(segment
		(start 245.402354 -64.800988)
		(end 245.40718 -64.809624)
		(width 0.0889)
		(layer "In4.Cu")
		(net "M_C_DQS_DP<8>")
	)
	(segment
		(start 238.437928 -3.026156)
		(end 238.000032 -3.464052)
		(width 0.14224)
		(layer "In4.Cu")
		(net "M_C_DQS_DP<8>")
	)
	(segment
		(start 245.888764 -50.647092)
		(end 245.888764 -52.340002)
		(width 0.0889)
		(layer "In4.Cu")
		(net "M_C_DQS_DP<8>")
	)
	(segment
		(start 245.402354 -55.885588)
		(end 245.40718 -55.894224)
		(width 0.0889)
		(layer "In4.Cu")
		(net "M_C_DQS_DP<8>")
	)
	(segment
		(start 241.53876 -32.26562)
		(end 241.53876 -43.304968)
		(width 0.14224)
		(layer "In4.Cu")
		(net "M_C_DQS_DP<8>")
	)
	(segment
		(start 245.402354 -58.857388)
		(end 245.40718 -58.866024)
		(width 0.0889)
		(layer "In4.Cu")
		(net "M_C_DQS_DP<8>")
	)
	(segment
		(start 245.396004 -67.76212)
		(end 245.402354 -67.772788)
		(width 0.0889)
		(layer "In4.Cu")
		(net "M_C_DQS_DP<8>")
	)
	(segment
		(start 245.402354 -68.763388)
		(end 245.40718 -68.772024)
		(width 0.0889)
		(layer "In4.Cu")
		(net "M_C_DQS_DP<8>")
	)
	(segment
		(start 245.402354 -56.876188)
		(end 245.40718 -56.884824)
		(width 0.0889)
		(layer "In4.Cu")
		(net "M_C_DQS_DP<8>")
	)
	(segment
		(start 245.396004 -61.81852)
		(end 245.402354 -61.829188)
		(width 0.0889)
		(layer "In4.Cu")
		(net "M_C_DQS_DP<8>")
	)
	(segment
		(start 238.951008 -29.677868)
		(end 241.53876 -32.26562)
		(width 0.14224)
		(layer "In4.Cu")
		(net "M_C_DQS_DP<8>")
	)
	(segment
		(start 245.402354 -67.772788)
		(end 245.40718 -67.781424)
		(width 0.0889)
		(layer "In4.Cu")
		(net "M_C_DQS_DP<8>")
	)
	(segment
		(start 245.487444 -52.741322)
		(end 245.487444 -55.147972)
		(width 0.0889)
		(layer "In4.Cu")
		(net "M_C_DQS_DP<8>")
	)
	(segment
		(start 238.951008 -6.22427)
		(end 238.951008 -29.677868)
		(width 0.14224)
		(layer "In4.Cu")
		(net "M_C_DQS_DP<8>")
	)
	(segment
		(start 245.402354 -61.829188)
		(end 245.40718 -61.837824)
		(width 0.0889)
		(layer "In4.Cu")
		(net "M_C_DQS_DP<8>")
	)
	(segment
		(start 245.396004 -60.82792)
		(end 245.402354 -60.838588)
		(width 0.0889)
		(layer "In4.Cu")
		(net "M_C_DQS_DP<8>")
	)
	(segment
		(start 238.000032 -3.464052)
		(end 238.000032 -4.574286)
		(width 0.14224)
		(layer "In4.Cu")
		(net "M_C_DQS_DP<8>")
	)
	(segment
		(start 245.402354 -63.810388)
		(end 245.40718 -63.819024)
		(width 0.0889)
		(layer "In4.Cu")
		(net "M_C_DQS_DP<8>")
	)
	(segment
		(start 245.396004 -59.83732)
		(end 245.402354 -59.847988)
		(width 0.0889)
		(layer "In4.Cu")
		(net "M_C_DQS_DP<8>")
	)
	(segment
		(start 245.402354 -62.819788)
		(end 245.40718 -62.828424)
		(width 0.0889)
		(layer "In4.Cu")
		(net "M_C_DQS_DP<8>")
	)
	(segment
		(start 245.396004 -56.86552)
		(end 245.402354 -56.876188)
		(width 0.0889)
		(layer "In4.Cu")
		(net "M_C_DQS_DP<8>")
	)
	(segment
		(start 245.402354 -60.838588)
		(end 245.40718 -60.847224)
		(width 0.0889)
		(layer "In4.Cu")
		(net "M_C_DQS_DP<8>")
	)
	(segment
		(start 245.396004 -64.79032)
		(end 245.402354 -64.800988)
		(width 0.0889)
		(layer "In4.Cu")
		(net "M_C_DQS_DP<8>")
	)
	(segment
		(start 245.396004 -68.75272)
		(end 245.402354 -68.763388)
		(width 0.0889)
		(layer "In4.Cu")
		(net "M_C_DQS_DP<8>")
	)
	(segment
		(start 245.402354 -58.266838)
		(end 245.396004 -58.277506)
		(width 0.0889)
		(layer "In4.Cu")
		(net "M_C_DQS_DP<8>")
	)
	(segment
		(start 245.402354 -59.847988)
		(end 245.40718 -59.856624)
		(width 0.0889)
		(layer "In4.Cu")
		(net "M_C_DQS_DP<8>")
	)
	(segment
		(start 246.162576 -50.00117)
		(end 246.162576 -50.37328)
		(width 0.0889)
		(layer "In4.Cu")
		(net "M_C_DQS_DP<8>")
	)
	(segment
		(start 245.888764 -52.340002)
		(end 245.487444 -52.741322)
		(width 0.0889)
		(layer "In4.Cu")
		(net "M_C_DQS_DP<8>")
	)
	(segment
		(start 245.396004 -62.80912)
		(end 245.402354 -62.819788)
		(width 0.0889)
		(layer "In4.Cu")
		(net "M_C_DQS_DP<8>")
	)
	(segment
		(start 245.487444 -55.147972)
		(end 245.402354 -55.295292)
		(width 0.0889)
		(layer "In4.Cu")
		(net "M_C_DQS_DP<8>")
	)
	(segment
		(start 246.123206 -49.939702)
		(end 246.123206 -49.9618)
		(width 0.0889)
		(layer "In4.Cu")
		(net "M_C_DQS_DP<8>")
	)
	(segment
		(start 241.53876 -43.304968)
		(end 245.251732 -47.01794)
		(width 0.14224)
		(layer "In4.Cu")
		(net "M_C_DQS_DP<8>")
	)
	(segment
		(start 245.113556 -69.359272)
		(end 245.055644 -69.30136)
		(width 0.0889)
		(layer "In4.Cu")
		(net "M_C_DQS_DP<8>")
	)
	(segment
		(start 245.396004 -63.79972)
		(end 245.402354 -63.810388)
		(width 0.0889)
		(layer "In4.Cu")
		(net "M_C_DQS_DP<8>")
	)
	(segment
		(start 238.119412 -5.392674)
		(end 238.951008 -6.22427)
		(width 0.14224)
		(layer "In4.Cu")
		(net "M_C_DQS_DP<8>")
	)
	(segment
		(start 245.396004 -65.78092)
		(end 245.402354 -65.791588)
		(width 0.0889)
		(layer "In4.Cu")
		(net "M_C_DQS_DP<8>")
	)
	(segment
		(start 238.119412 -4.693666)
		(end 238.119412 -5.392674)
		(width 0.14224)
		(layer "In4.Cu")
		(net "M_C_DQS_DP<8>")
	)
	(segment
		(start 246.123206 -47.203106)
		(end 246.123206 -49.939702)
		(width 0.14224)
		(layer "In4.Cu")
		(net "M_C_DQS_DP<8>")
	)
	(segment
		(start 245.055644 -69.30136)
		(end 245.055644 -68.963286)
		(width 0.0889)
		(layer "In4.Cu")
		(net "M_C_DQS_DP<8>")
	)
	(segment
		(start 245.402354 -65.791588)
		(end 245.40718 -65.800224)
		(width 0.0889)
		(layer "In4.Cu")
		(net "M_C_DQS_DP<8>")
	)
	(segment
		(start 246.162576 -50.37328)
		(end 245.888764 -50.647092)
		(width 0.0889)
		(layer "In4.Cu")
		(net "M_C_DQS_DP<8>")
	)
	(segment
		(start 238.000032 -4.574286)
		(end 238.119412 -4.693666)
		(width 0.14224)
		(layer "In4.Cu")
		(net "M_C_DQS_DP<8>")
	)
	(segment
		(start 246.123206 -49.9618)
		(end 246.162576 -50.00117)
		(width 0.0889)
		(layer "In4.Cu")
		(net "M_C_DQS_DP<8>")
	)
	(segment
		(start 245.93804 -47.01794)
		(end 246.123206 -47.203106)
		(width 0.14224)
		(layer "In4.Cu")
		(net "M_C_DQS_DP<8>")
	)
	(arc
		(start 245.40718 -55.894224)
		(mid 245.455935 -56.090576)
		(end 245.402354 -56.285638)
		(width 0.0889)
		(layer "In4.Cu")
		(net "M_C_DQS_DP<8>")
	)
	(arc
		(start 245.402354 -65.201038)
		(mid 245.323132 -65.490156)
		(end 245.396004 -65.78092)
		(width 0.0889)
		(layer "In4.Cu")
		(net "M_C_DQS_DP<8>")
	)
	(arc
		(start 245.402354 -68.172838)
		(mid 245.323132 -68.461956)
		(end 245.396004 -68.75272)
		(width 0.0889)
		(layer "In4.Cu")
		(net "M_C_DQS_DP<8>")
	)
	(arc
		(start 245.402354 -61.238638)
		(mid 245.323132 -61.527756)
		(end 245.396004 -61.81852)
		(width 0.0889)
		(layer "In4.Cu")
		(net "M_C_DQS_DP<8>")
	)
	(arc
		(start 245.40718 -56.884824)
		(mid 245.455935 -57.081176)
		(end 245.402354 -57.276238)
		(width 0.0889)
		(layer "In4.Cu")
		(net "M_C_DQS_DP<8>")
	)
	(arc
		(start 245.402354 -64.210438)
		(mid 245.323132 -64.499556)
		(end 245.396004 -64.79032)
		(width 0.0889)
		(layer "In4.Cu")
		(net "M_C_DQS_DP<8>")
	)
	(arc
		(start 245.402354 -63.219838)
		(mid 245.323132 -63.508956)
		(end 245.396004 -63.79972)
		(width 0.0889)
		(layer "In4.Cu")
		(net "M_C_DQS_DP<8>")
	)
	(arc
		(start 245.402354 -56.285638)
		(mid 245.323132 -56.574756)
		(end 245.396004 -56.86552)
		(width 0.0889)
		(layer "In4.Cu")
		(net "M_C_DQS_DP<8>")
	)
	(arc
		(start 245.402354 -57.276238)
		(mid 245.323223 -57.57164)
		(end 245.402354 -57.867042)
		(width 0.0889)
		(layer "In4.Cu")
		(net "M_C_DQS_DP<8>")
	)
	(arc
		(start 245.40718 -67.781424)
		(mid 245.455935 -67.977776)
		(end 245.402354 -68.172838)
		(width 0.0889)
		(layer "In4.Cu")
		(net "M_C_DQS_DP<8>")
	)
	(arc
		(start 245.40718 -62.828424)
		(mid 245.455935 -63.024776)
		(end 245.402354 -63.219838)
		(width 0.0889)
		(layer "In4.Cu")
		(net "M_C_DQS_DP<8>")
	)
	(arc
		(start 245.40718 -59.856624)
		(mid 245.455935 -60.052976)
		(end 245.402354 -60.248038)
		(width 0.0889)
		(layer "In4.Cu")
		(net "M_C_DQS_DP<8>")
	)
	(arc
		(start 245.40718 -64.809624)
		(mid 245.455935 -65.005976)
		(end 245.402354 -65.201038)
		(width 0.0889)
		(layer "In4.Cu")
		(net "M_C_DQS_DP<8>")
	)
	(arc
		(start 245.402354 -57.867042)
		(mid 245.455853 -58.06694)
		(end 245.402354 -58.266838)
		(width 0.0889)
		(layer "In4.Cu")
		(net "M_C_DQS_DP<8>")
	)
	(arc
		(start 245.402354 -60.248038)
		(mid 245.323132 -60.537156)
		(end 245.396004 -60.82792)
		(width 0.0889)
		(layer "In4.Cu")
		(net "M_C_DQS_DP<8>")
	)
	(arc
		(start 245.40718 -63.819024)
		(mid 245.455935 -64.015376)
		(end 245.402354 -64.210438)
		(width 0.0889)
		(layer "In4.Cu")
		(net "M_C_DQS_DP<8>")
	)
	(arc
		(start 245.396004 -58.277506)
		(mid 245.323206 -58.568269)
		(end 245.402354 -58.857388)
		(width 0.0889)
		(layer "In4.Cu")
		(net "M_C_DQS_DP<8>")
	)
	(arc
		(start 245.402354 -66.782188)
		(mid 245.455853 -66.982086)
		(end 245.402354 -67.181984)
		(width 0.0889)
		(layer "In4.Cu")
		(net "M_C_DQS_DP<8>")
	)
	(arc
		(start 245.40718 -58.866024)
		(mid 245.455935 -59.062376)
		(end 245.402354 -59.257438)
		(width 0.0889)
		(layer "In4.Cu")
		(net "M_C_DQS_DP<8>")
	)
	(arc
		(start 245.40718 -65.800224)
		(mid 245.455874 -65.996432)
		(end 245.402354 -66.191384)
		(width 0.0889)
		(layer "In4.Cu")
		(net "M_C_DQS_DP<8>")
	)
	(arc
		(start 245.402354 -66.191384)
		(mid 245.323223 -66.486786)
		(end 245.402354 -66.782188)
		(width 0.0889)
		(layer "In4.Cu")
		(net "M_C_DQS_DP<8>")
	)
	(arc
		(start 245.402354 -62.229238)
		(mid 245.323132 -62.518356)
		(end 245.396004 -62.80912)
		(width 0.0889)
		(layer "In4.Cu")
		(net "M_C_DQS_DP<8>")
	)
	(arc
		(start 245.402354 -55.295292)
		(mid 245.323349 -55.59044)
		(end 245.402354 -55.885588)
		(width 0.0889)
		(layer "In4.Cu")
		(net "M_C_DQS_DP<8>")
	)
	(arc
		(start 245.402354 -59.257438)
		(mid 245.323132 -59.546556)
		(end 245.396004 -59.83732)
		(width 0.0889)
		(layer "In4.Cu")
		(net "M_C_DQS_DP<8>")
	)
	(arc
		(start 245.40718 -61.837824)
		(mid 245.455935 -62.034176)
		(end 245.402354 -62.229238)
		(width 0.0889)
		(layer "In4.Cu")
		(net "M_C_DQS_DP<8>")
	)
	(arc
		(start 245.402354 -67.181984)
		(mid 245.323164 -67.471213)
		(end 245.396004 -67.76212)
		(width 0.0889)
		(layer "In4.Cu")
		(net "M_C_DQS_DP<8>")
	)
	(arc
		(start 245.40718 -68.772024)
		(mid 245.413592 -69.14226)
		(end 245.113556 -69.359272)
		(width 0.0889)
		(layer "In4.Cu")
		(net "M_C_DQS_DP<8>")
	)
	(arc
		(start 245.40718 -60.847224)
		(mid 245.455935 -61.043576)
		(end 245.402354 -61.238638)
		(width 0.0889)
		(layer "In4.Cu")
		(net "M_C_DQS_DP<8>")
	)
	(segment
		(start 238.979456 -1.08712)
		(end 238.796576 -1.27)
		(width 0.14224)
		(layer "In11.Cu")
		(net "M_C_DQS_DP<8>")
	)
	(segment
		(start 238.979456 0.921512)
		(end 238.979456 0.255778)
		(width 0.14224)
		(layer "In11.Cu")
		(net "M_C_DQS_DP<8>")
	)
	(segment
		(start 238.979456 -2.763774)
		(end 238.71682 -3.02641)
		(width 0.14224)
		(layer "In11.Cu")
		(net "M_C_DQS_DP<8>")
	)
	(segment
		(start 238.437928 -3.02641)
		(end 238.437928 -3.026156)
		(width 0.14224)
		(layer "In11.Cu")
		(net "M_C_DQS_DP<8>")
	)
	(segment
		(start 238.796576 -1.27)
		(end 238.669576 -1.27)
		(width 0.14224)
		(layer "In11.Cu")
		(net "M_C_DQS_DP<8>")
	)
	(segment
		(start 238.979456 -0.738378)
		(end 238.979456 -1.08712)
		(width 0.14224)
		(layer "In11.Cu")
		(net "M_C_DQS_DP<8>")
	)
	(segment
		(start 238.444532 -0.076454)
		(end 238.444532 -0.380746)
		(width 0.14224)
		(layer "In11.Cu")
		(net "M_C_DQS_DP<8>")
	)
	(segment
		(start 238.979456 0.255778)
		(end 238.799878 0.0762)
		(width 0.14224)
		(layer "In11.Cu")
		(net "M_C_DQS_DP<8>")
	)
	(segment
		(start 238.774478 -0.5334)
		(end 238.979456 -0.738378)
		(width 0.14224)
		(layer "In11.Cu")
		(net "M_C_DQS_DP<8>")
	)
	(segment
		(start 238.669576 -1.8796)
		(end 238.800132 -1.8796)
		(width 0.14224)
		(layer "In11.Cu")
		(net "M_C_DQS_DP<8>")
	)
	(segment
		(start 238.597186 0.0762)
		(end 238.444532 -0.076454)
		(width 0.14224)
		(layer "In11.Cu")
		(net "M_C_DQS_DP<8>")
	)
	(segment
		(start 238.800132 -1.8796)
		(end 238.979456 -2.058924)
		(width 0.14224)
		(layer "In11.Cu")
		(net "M_C_DQS_DP<8>")
	)
	(segment
		(start 238.979456 -2.058924)
		(end 238.979456 -2.763774)
		(width 0.14224)
		(layer "In11.Cu")
		(net "M_C_DQS_DP<8>")
	)
	(segment
		(start 238.597186 -0.5334)
		(end 238.774478 -0.5334)
		(width 0.14224)
		(layer "In11.Cu")
		(net "M_C_DQS_DP<8>")
	)
	(segment
		(start 238.669576 -1.27)
		(end 238.491776 -1.4478)
		(width 0.14224)
		(layer "In11.Cu")
		(net "M_C_DQS_DP<8>")
	)
	(segment
		(start 238.799878 0.0762)
		(end 238.597186 0.0762)
		(width 0.14224)
		(layer "In11.Cu")
		(net "M_C_DQS_DP<8>")
	)
	(segment
		(start 238.719614 1.181354)
		(end 238.979456 0.921512)
		(width 0.14224)
		(layer "In11.Cu")
		(net "M_C_DQS_DP<8>")
	)
	(segment
		(start 238.491776 -1.4478)
		(end 238.491776 -1.7018)
		(width 0.14224)
		(layer "In11.Cu")
		(net "M_C_DQS_DP<8>")
	)
	(segment
		(start 238.71682 -3.02641)
		(end 238.437928 -3.02641)
		(width 0.14224)
		(layer "In11.Cu")
		(net "M_C_DQS_DP<8>")
	)
	(segment
		(start 238.444532 -0.380746)
		(end 238.597186 -0.5334)
		(width 0.14224)
		(layer "In11.Cu")
		(net "M_C_DQS_DP<8>")
	)
	(segment
		(start 238.491776 -1.7018)
		(end 238.669576 -1.8796)
		(width 0.14224)
		(layer "In11.Cu")
		(net "M_C_DQS_DP<8>")
	)
	(segment
		(start 238.437928 1.181354)
		(end 238.719614 1.181354)
		(width 0.14224)
		(layer "In11.Cu")
		(net "M_C_DQS_DP<8>")
	)
	(segment
		(start 313.07151 1.241298)
		(end 313.07151 0.49911)
		(width 0.1651)
		(layer "F.Cu")
		(net "M_C_DQS_DP<7>")
	)
	(segment
		(start 312.849768 -0.821182)
		(end 312.850276 -0.821182)
		(width 0.1651)
		(layer "F.Cu")
		(net "M_C_DQS_DP<7>")
	)
	(segment
		(start 312.387996 1.181354)
		(end 312.661808 1.455166)
		(width 0.1651)
		(layer "F.Cu")
		(net "M_C_DQS_DP<7>")
	)
	(segment
		(start 312.849768 0.277368)
		(end 312.849768 -0.821182)
		(width 0.1651)
		(layer "F.Cu")
		(net "M_C_DQS_DP<7>")
	)
	(segment
		(start 312.857642 1.455166)
		(end 313.07151 1.241298)
		(width 0.1651)
		(layer "F.Cu")
		(net "M_C_DQS_DP<7>")
	)
	(segment
		(start 313.07151 0.49911)
		(end 312.849768 0.277368)
		(width 0.1651)
		(layer "F.Cu")
		(net "M_C_DQS_DP<7>")
	)
	(segment
		(start 287.50514 -64.324738)
		(end 286.93364 -64.324738)
		(width 0.0889)
		(layer "F.Cu")
		(net "M_C_DQS_DP<7>")
	)
	(segment
		(start 312.661808 1.455166)
		(end 312.857642 1.455166)
		(width 0.1651)
		(layer "F.Cu")
		(net "M_C_DQS_DP<7>")
	)
	(via
		(at 286.93364 -64.324738)
		(size 0.508)
		(drill 0.254)
		(layers "F.Cu" "B.Cu")
		(net "M_C_DQS_DP<7>")
	)
	(via
		(at 312.387996 -3.026156)
		(size 0.508)
		(drill 0.254)
		(layers "F.Cu" "B.Cu")
		(net "M_C_DQS_DP<7>")
	)
	(via
		(at 312.387996 1.181354)
		(size 0.508)
		(drill 0.254)
		(layers "F.Cu" "B.Cu")
		(net "M_C_DQS_DP<7>")
	)
	(segment
		(start 313.0296 -3.16738)
		(end 312.8899 -3.30708)
		(width 0.1651)
		(layer "B.Cu")
		(net "M_C_DQS_DP<7>")
	)
	(segment
		(start 312.8899 -3.30708)
		(end 312.66892 -3.30708)
		(width 0.1651)
		(layer "B.Cu")
		(net "M_C_DQS_DP<7>")
	)
	(segment
		(start 312.849768 -1.021842)
		(end 312.849768 -2.537968)
		(width 0.1651)
		(layer "B.Cu")
		(net "M_C_DQS_DP<7>")
	)
	(segment
		(start 313.0296 -2.7178)
		(end 313.0296 -3.16738)
		(width 0.1651)
		(layer "B.Cu")
		(net "M_C_DQS_DP<7>")
	)
	(segment
		(start 312.850276 -1.021842)
		(end 312.849768 -1.021842)
		(width 0.1651)
		(layer "B.Cu")
		(net "M_C_DQS_DP<7>")
	)
	(segment
		(start 312.849768 -2.537968)
		(end 313.0296 -2.7178)
		(width 0.1651)
		(layer "B.Cu")
		(net "M_C_DQS_DP<7>")
	)
	(segment
		(start 312.66892 -3.30708)
		(end 312.387996 -3.026156)
		(width 0.1651)
		(layer "B.Cu")
		(net "M_C_DQS_DP<7>")
	)
	(segment
		(start 287.40227 -53.416962)
		(end 287.40227 -51.40833)
		(width 0.0889)
		(layer "In11.Cu")
		(net "M_C_DQS_DP<7>")
	)
	(segment
		(start 294.19677 -48.29683)
		(end 300.7106 -41.783)
		(width 0.14224)
		(layer "In11.Cu")
		(net "M_C_DQS_DP<7>")
	)
	(segment
		(start 292.86327 -48.18253)
		(end 292.97757 -48.29683)
		(width 0.14224)
		(layer "In11.Cu")
		(net "M_C_DQS_DP<7>")
	)
	(segment
		(start 312.929524 -0.738378)
		(end 312.724546 -0.5334)
		(width 0.14224)
		(layer "In11.Cu")
		(net "M_C_DQS_DP<7>")
	)
	(segment
		(start 301.625 -41.783)
		(end 312.901076 -30.506924)
		(width 0.14224)
		(layer "In11.Cu")
		(net "M_C_DQS_DP<7>")
	)
	(segment
		(start 287.28035 -54.618636)
		(end 287.285176 -54.61)
		(width 0.0889)
		(layer "In11.Cu")
		(net "M_C_DQS_DP<7>")
	)
	(segment
		(start 312.929524 -2.763774)
		(end 312.929524 -2.058924)
		(width 0.14224)
		(layer "In11.Cu")
		(net "M_C_DQS_DP<7>")
	)
	(segment
		(start 312.929524 -1.08712)
		(end 312.929524 -0.738378)
		(width 0.14224)
		(layer "In11.Cu")
		(net "M_C_DQS_DP<7>")
	)
	(segment
		(start 288.7091 -50.7111)
		(end 291.12337 -48.29683)
		(width 0.14224)
		(layer "In11.Cu")
		(net "M_C_DQS_DP<7>")
	)
	(segment
		(start 292.028372 -48.29683)
		(end 292.49497 -48.29683)
		(width 0.14224)
		(layer "In11.Cu")
		(net "M_C_DQS_DP<7>")
	)
	(segment
		(start 312.619644 -1.8796)
		(end 312.441844 -1.7018)
		(width 0.14224)
		(layer "In11.Cu")
		(net "M_C_DQS_DP<7>")
	)
	(segment
		(start 312.3946 -0.076454)
		(end 312.547254 0.0762)
		(width 0.14224)
		(layer "In11.Cu")
		(net "M_C_DQS_DP<7>")
	)
	(segment
		(start 312.06948 -4.754626)
		(end 311.9501 -4.635246)
		(width 0.14224)
		(layer "In11.Cu")
		(net "M_C_DQS_DP<7>")
	)
	(segment
		(start 312.387996 -3.026156)
		(end 312.387996 -3.02641)
		(width 0.14224)
		(layer "In11.Cu")
		(net "M_C_DQS_DP<7>")
	)
	(segment
		(start 287.28035 -55.609236)
		(end 287.285176 -55.6006)
		(width 0.0889)
		(layer "In11.Cu")
		(net "M_C_DQS_DP<7>")
	)
	(segment
		(start 312.929524 0.921512)
		(end 312.669682 1.181354)
		(width 0.14224)
		(layer "In11.Cu")
		(net "M_C_DQS_DP<7>")
	)
	(segment
		(start 312.547254 0.0762)
		(end 312.749946 0.0762)
		(width 0.14224)
		(layer "In11.Cu")
		(net "M_C_DQS_DP<7>")
	)
	(segment
		(start 287.40227 -51.40833)
		(end 287.8963 -50.9143)
		(width 0.0889)
		(layer "In11.Cu")
		(net "M_C_DQS_DP<7>")
	)
	(segment
		(start 311.9501 -3.464052)
		(end 312.387996 -3.026156)
		(width 0.14224)
		(layer "In11.Cu")
		(net "M_C_DQS_DP<7>")
	)
	(segment
		(start 312.06948 -5.392674)
		(end 312.06948 -4.754626)
		(width 0.14224)
		(layer "In11.Cu")
		(net "M_C_DQS_DP<7>")
	)
	(segment
		(start 287.274 -60.572904)
		(end 287.28035 -60.562236)
		(width 0.0889)
		(layer "In11.Cu")
		(net "M_C_DQS_DP<7>")
	)
	(segment
		(start 312.441844 -1.7018)
		(end 312.441844 -1.4478)
		(width 0.14224)
		(layer "In11.Cu")
		(net "M_C_DQS_DP<7>")
	)
	(segment
		(start 288.562034 -50.9143)
		(end 288.7091 -50.767234)
		(width 0.0889)
		(layer "In11.Cu")
		(net "M_C_DQS_DP<7>")
	)
	(segment
		(start 312.901076 -6.22427)
		(end 312.06948 -5.392674)
		(width 0.14224)
		(layer "In11.Cu")
		(net "M_C_DQS_DP<7>")
	)
	(segment
		(start 287.274 -55.619904)
		(end 287.28035 -55.609236)
		(width 0.0889)
		(layer "In11.Cu")
		(net "M_C_DQS_DP<7>")
	)
	(segment
		(start 287.8963 -50.9143)
		(end 288.562034 -50.9143)
		(width 0.0889)
		(layer "In11.Cu")
		(net "M_C_DQS_DP<7>")
	)
	(segment
		(start 312.547254 -0.5334)
		(end 312.3946 -0.380746)
		(width 0.14224)
		(layer "In11.Cu")
		(net "M_C_DQS_DP<7>")
	)
	(segment
		(start 287.28035 -56.599836)
		(end 287.285176 -56.5912)
		(width 0.0889)
		(layer "In11.Cu")
		(net "M_C_DQS_DP<7>")
	)
	(segment
		(start 312.387996 -3.02641)
		(end 312.666888 -3.02641)
		(width 0.14224)
		(layer "In11.Cu")
		(net "M_C_DQS_DP<7>")
	)
	(segment
		(start 287.28035 -62.543436)
		(end 287.285176 -62.5348)
		(width 0.0889)
		(layer "In11.Cu")
		(net "M_C_DQS_DP<7>")
	)
	(segment
		(start 312.7502 -1.8796)
		(end 312.619644 -1.8796)
		(width 0.14224)
		(layer "In11.Cu")
		(net "M_C_DQS_DP<7>")
	)
	(segment
		(start 312.929524 0.255778)
		(end 312.929524 0.921512)
		(width 0.14224)
		(layer "In11.Cu")
		(net "M_C_DQS_DP<7>")
	)
	(segment
		(start 287.274 -63.544704)
		(end 287.28035 -63.534036)
		(width 0.0889)
		(layer "In11.Cu")
		(net "M_C_DQS_DP<7>")
	)
	(segment
		(start 287.28035 -61.552836)
		(end 287.285176 -61.5442)
		(width 0.0889)
		(layer "In11.Cu")
		(net "M_C_DQS_DP<7>")
	)
	(segment
		(start 287.28035 -57.590436)
		(end 287.285176 -57.5818)
		(width 0.0889)
		(layer "In11.Cu")
		(net "M_C_DQS_DP<7>")
	)
	(segment
		(start 312.929524 -2.058924)
		(end 312.7502 -1.8796)
		(width 0.14224)
		(layer "In11.Cu")
		(net "M_C_DQS_DP<7>")
	)
	(segment
		(start 292.60927 -48.18253)
		(end 292.86327 -48.18253)
		(width 0.14224)
		(layer "In11.Cu")
		(net "M_C_DQS_DP<7>")
	)
	(segment
		(start 287.28035 -58.581036)
		(end 287.285176 -58.5724)
		(width 0.0889)
		(layer "In11.Cu")
		(net "M_C_DQS_DP<7>")
	)
	(segment
		(start 291.660072 -48.18253)
		(end 291.914072 -48.18253)
		(width 0.14224)
		(layer "In11.Cu")
		(net "M_C_DQS_DP<7>")
	)
	(segment
		(start 312.666888 -3.02641)
		(end 312.929524 -2.763774)
		(width 0.14224)
		(layer "In11.Cu")
		(net "M_C_DQS_DP<7>")
	)
	(segment
		(start 311.9501 -4.635246)
		(end 311.9501 -3.464052)
		(width 0.14224)
		(layer "In11.Cu")
		(net "M_C_DQS_DP<7>")
	)
	(segment
		(start 312.3946 -0.380746)
		(end 312.3946 -0.076454)
		(width 0.14224)
		(layer "In11.Cu")
		(net "M_C_DQS_DP<7>")
	)
	(segment
		(start 292.49497 -48.29683)
		(end 292.60927 -48.18253)
		(width 0.14224)
		(layer "In11.Cu")
		(net "M_C_DQS_DP<7>")
	)
	(segment
		(start 287.28035 -53.627782)
		(end 287.40227 -53.416962)
		(width 0.0889)
		(layer "In11.Cu")
		(net "M_C_DQS_DP<7>")
	)
	(segment
		(start 312.749946 0.0762)
		(end 312.929524 0.255778)
		(width 0.14224)
		(layer "In11.Cu")
		(net "M_C_DQS_DP<7>")
	)
	(segment
		(start 291.914072 -48.18253)
		(end 292.028372 -48.29683)
		(width 0.14224)
		(layer "In11.Cu")
		(net "M_C_DQS_DP<7>")
	)
	(segment
		(start 312.441844 -1.4478)
		(end 312.619644 -1.27)
		(width 0.14224)
		(layer "In11.Cu")
		(net "M_C_DQS_DP<7>")
	)
	(segment
		(start 286.93364 -64.662812)
		(end 286.991552 -64.720724)
		(width 0.0889)
		(layer "In11.Cu")
		(net "M_C_DQS_DP<7>")
	)
	(segment
		(start 312.724546 -0.5334)
		(end 312.547254 -0.5334)
		(width 0.14224)
		(layer "In11.Cu")
		(net "M_C_DQS_DP<7>")
	)
	(segment
		(start 312.669682 1.181354)
		(end 312.387996 1.181354)
		(width 0.14224)
		(layer "In11.Cu")
		(net "M_C_DQS_DP<7>")
	)
	(segment
		(start 287.28035 -60.562236)
		(end 287.285176 -60.5536)
		(width 0.0889)
		(layer "In11.Cu")
		(net "M_C_DQS_DP<7>")
	)
	(segment
		(start 291.545772 -48.29683)
		(end 291.660072 -48.18253)
		(width 0.14224)
		(layer "In11.Cu")
		(net "M_C_DQS_DP<7>")
	)
	(segment
		(start 287.274 -62.554104)
		(end 287.28035 -62.543436)
		(width 0.0889)
		(layer "In11.Cu")
		(net "M_C_DQS_DP<7>")
	)
	(segment
		(start 287.274 -61.563504)
		(end 287.28035 -61.552836)
		(width 0.0889)
		(layer "In11.Cu")
		(net "M_C_DQS_DP<7>")
	)
	(segment
		(start 287.28035 -63.534036)
		(end 287.285176 -63.5254)
		(width 0.0889)
		(layer "In11.Cu")
		(net "M_C_DQS_DP<7>")
	)
	(segment
		(start 292.97757 -48.29683)
		(end 294.19677 -48.29683)
		(width 0.14224)
		(layer "In11.Cu")
		(net "M_C_DQS_DP<7>")
	)
	(segment
		(start 300.7106 -41.783)
		(end 301.625 -41.783)
		(width 0.14224)
		(layer "In11.Cu")
		(net "M_C_DQS_DP<7>")
	)
	(segment
		(start 291.12337 -48.29683)
		(end 291.545772 -48.29683)
		(width 0.14224)
		(layer "In11.Cu")
		(net "M_C_DQS_DP<7>")
	)
	(segment
		(start 287.274 -57.601104)
		(end 287.28035 -57.590436)
		(width 0.0889)
		(layer "In11.Cu")
		(net "M_C_DQS_DP<7>")
	)
	(segment
		(start 287.274 -54.629304)
		(end 287.28035 -54.618636)
		(width 0.0889)
		(layer "In11.Cu")
		(net "M_C_DQS_DP<7>")
	)
	(segment
		(start 312.619644 -1.27)
		(end 312.746644 -1.27)
		(width 0.14224)
		(layer "In11.Cu")
		(net "M_C_DQS_DP<7>")
	)
	(segment
		(start 286.93364 -64.324738)
		(end 286.93364 -64.662812)
		(width 0.0889)
		(layer "In11.Cu")
		(net "M_C_DQS_DP<7>")
	)
	(segment
		(start 312.746644 -1.27)
		(end 312.929524 -1.08712)
		(width 0.14224)
		(layer "In11.Cu")
		(net "M_C_DQS_DP<7>")
	)
	(segment
		(start 287.274 -56.610504)
		(end 287.28035 -56.599836)
		(width 0.0889)
		(layer "In11.Cu")
		(net "M_C_DQS_DP<7>")
	)
	(segment
		(start 288.7091 -50.767234)
		(end 288.7091 -50.7111)
		(width 0.0889)
		(layer "In11.Cu")
		(net "M_C_DQS_DP<7>")
	)
	(segment
		(start 312.901076 -30.506924)
		(end 312.901076 -6.22427)
		(width 0.14224)
		(layer "In11.Cu")
		(net "M_C_DQS_DP<7>")
	)
	(segment
		(start 287.28035 -59.171586)
		(end 287.274 -59.160918)
		(width 0.0889)
		(layer "In11.Cu")
		(net "M_C_DQS_DP<7>")
	)
	(arc
		(start 287.28035 -54.218586)
		(mid 287.201219 -53.923184)
		(end 287.28035 -53.627782)
		(width 0.0889)
		(layer "In11.Cu")
		(net "M_C_DQS_DP<7>")
	)
	(arc
		(start 287.285176 -55.6006)
		(mid 287.333931 -55.404248)
		(end 287.28035 -55.209186)
		(width 0.0889)
		(layer "In11.Cu")
		(net "M_C_DQS_DP<7>")
	)
	(arc
		(start 287.28035 -61.152786)
		(mid 287.201128 -60.863668)
		(end 287.274 -60.572904)
		(width 0.0889)
		(layer "In11.Cu")
		(net "M_C_DQS_DP<7>")
	)
	(arc
		(start 287.285176 -60.5536)
		(mid 287.333931 -60.357248)
		(end 287.28035 -60.162186)
		(width 0.0889)
		(layer "In11.Cu")
		(net "M_C_DQS_DP<7>")
	)
	(arc
		(start 287.285176 -58.5724)
		(mid 287.333931 -58.376048)
		(end 287.28035 -58.180986)
		(width 0.0889)
		(layer "In11.Cu")
		(net "M_C_DQS_DP<7>")
	)
	(arc
		(start 287.285176 -57.5818)
		(mid 287.333931 -57.385448)
		(end 287.28035 -57.190386)
		(width 0.0889)
		(layer "In11.Cu")
		(net "M_C_DQS_DP<7>")
	)
	(arc
		(start 287.28035 -58.180986)
		(mid 287.201128 -57.891868)
		(end 287.274 -57.601104)
		(width 0.0889)
		(layer "In11.Cu")
		(net "M_C_DQS_DP<7>")
	)
	(arc
		(start 287.28035 -56.199786)
		(mid 287.201128 -55.910668)
		(end 287.274 -55.619904)
		(width 0.0889)
		(layer "In11.Cu")
		(net "M_C_DQS_DP<7>")
	)
	(arc
		(start 287.28035 -62.143386)
		(mid 287.201128 -61.854268)
		(end 287.274 -61.563504)
		(width 0.0889)
		(layer "In11.Cu")
		(net "M_C_DQS_DP<7>")
	)
	(arc
		(start 287.28035 -60.162186)
		(mid 287.201219 -59.866784)
		(end 287.28035 -59.571382)
		(width 0.0889)
		(layer "In11.Cu")
		(net "M_C_DQS_DP<7>")
	)
	(arc
		(start 287.285176 -61.5442)
		(mid 287.333931 -61.347848)
		(end 287.28035 -61.152786)
		(width 0.0889)
		(layer "In11.Cu")
		(net "M_C_DQS_DP<7>")
	)
	(arc
		(start 286.991552 -64.720724)
		(mid 287.293821 -64.499175)
		(end 287.28035 -64.124586)
		(width 0.0889)
		(layer "In11.Cu")
		(net "M_C_DQS_DP<7>")
	)
	(arc
		(start 287.285176 -62.5348)
		(mid 287.333931 -62.338448)
		(end 287.28035 -62.143386)
		(width 0.0889)
		(layer "In11.Cu")
		(net "M_C_DQS_DP<7>")
	)
	(arc
		(start 287.285176 -56.5912)
		(mid 287.333931 -56.394848)
		(end 287.28035 -56.199786)
		(width 0.0889)
		(layer "In11.Cu")
		(net "M_C_DQS_DP<7>")
	)
	(arc
		(start 287.28035 -63.133986)
		(mid 287.201128 -62.844868)
		(end 287.274 -62.554104)
		(width 0.0889)
		(layer "In11.Cu")
		(net "M_C_DQS_DP<7>")
	)
	(arc
		(start 287.28035 -59.571382)
		(mid 287.333849 -59.371484)
		(end 287.28035 -59.171586)
		(width 0.0889)
		(layer "In11.Cu")
		(net "M_C_DQS_DP<7>")
	)
	(arc
		(start 287.28035 -64.124586)
		(mid 287.201128 -63.835468)
		(end 287.274 -63.544704)
		(width 0.0889)
		(layer "In11.Cu")
		(net "M_C_DQS_DP<7>")
	)
	(arc
		(start 287.274 -59.160918)
		(mid 287.201202 -58.870155)
		(end 287.28035 -58.581036)
		(width 0.0889)
		(layer "In11.Cu")
		(net "M_C_DQS_DP<7>")
	)
	(arc
		(start 287.28035 -57.190386)
		(mid 287.201128 -56.901268)
		(end 287.274 -56.610504)
		(width 0.0889)
		(layer "In11.Cu")
		(net "M_C_DQS_DP<7>")
	)
	(arc
		(start 287.285176 -63.5254)
		(mid 287.333931 -63.329048)
		(end 287.28035 -63.133986)
		(width 0.0889)
		(layer "In11.Cu")
		(net "M_C_DQS_DP<7>")
	)
	(arc
		(start 287.285176 -54.61)
		(mid 287.333931 -54.413648)
		(end 287.28035 -54.218586)
		(width 0.0889)
		(layer "In11.Cu")
		(net "M_C_DQS_DP<7>")
	)
	(arc
		(start 287.28035 -55.209186)
		(mid 287.201128 -54.920068)
		(end 287.274 -54.629304)
		(width 0.0889)
		(layer "In11.Cu")
		(net "M_C_DQS_DP<7>")
	)
	(segment
		(start 303.311814 1.455166)
		(end 303.507648 1.455166)
		(width 0.1651)
		(layer "F.Cu")
		(net "M_C_DQS_DP<6>")
	)
	(segment
		(start 303.038002 1.181354)
		(end 303.311814 1.455166)
		(width 0.1651)
		(layer "F.Cu")
		(net "M_C_DQS_DP<6>")
	)
	(segment
		(start 303.499774 0.277368)
		(end 303.499774 -0.821182)
		(width 0.1651)
		(layer "F.Cu")
		(net "M_C_DQS_DP<6>")
	)
	(segment
		(start 303.721516 1.241298)
		(end 303.721516 0.49911)
		(width 0.1651)
		(layer "F.Cu")
		(net "M_C_DQS_DP<6>")
	)
	(segment
		(start 303.499774 -0.821182)
		(end 303.500282 -0.821182)
		(width 0.1651)
		(layer "F.Cu")
		(net "M_C_DQS_DP<6>")
	)
	(segment
		(start 303.721516 0.49911)
		(end 303.499774 0.277368)
		(width 0.1651)
		(layer "F.Cu")
		(net "M_C_DQS_DP<6>")
	)
	(segment
		(start 303.507648 1.455166)
		(end 303.721516 1.241298)
		(width 0.1651)
		(layer "F.Cu")
		(net "M_C_DQS_DP<6>")
	)
	(segment
		(start 282.354274 -64.324738)
		(end 281.782774 -64.324738)
		(width 0.0889)
		(layer "F.Cu")
		(net "M_C_DQS_DP<6>")
	)
	(via
		(at 303.038002 -3.026156)
		(size 0.508)
		(drill 0.254)
		(layers "F.Cu" "B.Cu")
		(net "M_C_DQS_DP<6>")
	)
	(via
		(at 281.782774 -64.324738)
		(size 0.508)
		(drill 0.254)
		(layers "F.Cu" "B.Cu")
		(net "M_C_DQS_DP<6>")
	)
	(via
		(at 303.038002 1.181354)
		(size 0.508)
		(drill 0.254)
		(layers "F.Cu" "B.Cu")
		(net "M_C_DQS_DP<6>")
	)
	(segment
		(start 303.679606 -3.16738)
		(end 303.539906 -3.30708)
		(width 0.1651)
		(layer "B.Cu")
		(net "M_C_DQS_DP<6>")
	)
	(segment
		(start 303.499774 -1.021842)
		(end 303.499774 -2.537968)
		(width 0.1651)
		(layer "B.Cu")
		(net "M_C_DQS_DP<6>")
	)
	(segment
		(start 303.499774 -2.537968)
		(end 303.679606 -2.7178)
		(width 0.1651)
		(layer "B.Cu")
		(net "M_C_DQS_DP<6>")
	)
	(segment
		(start 303.318926 -3.30708)
		(end 303.038002 -3.026156)
		(width 0.1651)
		(layer "B.Cu")
		(net "M_C_DQS_DP<6>")
	)
	(segment
		(start 303.679606 -2.7178)
		(end 303.679606 -3.16738)
		(width 0.1651)
		(layer "B.Cu")
		(net "M_C_DQS_DP<6>")
	)
	(segment
		(start 303.539906 -3.30708)
		(end 303.318926 -3.30708)
		(width 0.1651)
		(layer "B.Cu")
		(net "M_C_DQS_DP<6>")
	)
	(segment
		(start 303.500282 -1.021842)
		(end 303.499774 -1.021842)
		(width 0.1651)
		(layer "B.Cu")
		(net "M_C_DQS_DP<6>")
	)
	(segment
		(start 286.173418 -39.3573)
		(end 286.173418 -43.18762)
		(width 0.14224)
		(layer "In11.Cu")
		(net "M_C_DQS_DP<6>")
	)
	(segment
		(start 282.13431 -58.5724)
		(end 282.129484 -58.581036)
		(width 0.0889)
		(layer "In11.Cu")
		(net "M_C_DQS_DP<6>")
	)
	(segment
		(start 303.57953 -0.738378)
		(end 303.57953 -1.08712)
		(width 0.14224)
		(layer "In11.Cu")
		(net "M_C_DQS_DP<6>")
	)
	(segment
		(start 303.316894 -3.02641)
		(end 303.038002 -3.02641)
		(width 0.14224)
		(layer "In11.Cu")
		(net "M_C_DQS_DP<6>")
	)
	(segment
		(start 303.26965 -1.27)
		(end 303.09185 -1.4478)
		(width 0.14224)
		(layer "In11.Cu")
		(net "M_C_DQS_DP<6>")
	)
	(segment
		(start 281.955748 -50.907696)
		(end 281.955748 -51.12131)
		(width 0.0889)
		(layer "In11.Cu")
		(net "M_C_DQS_DP<6>")
	)
	(segment
		(start 283.736796 -45.624242)
		(end 283.574998 -45.624242)
		(width 0.14224)
		(layer "In11.Cu")
		(net "M_C_DQS_DP<6>")
	)
	(segment
		(start 282.215336 -54.208426)
		(end 282.215336 -54.469792)
		(width 0.0889)
		(layer "In11.Cu")
		(net "M_C_DQS_DP<6>")
	)
	(segment
		(start 286.173418 -43.18762)
		(end 285.48457 -43.876468)
		(width 0.14224)
		(layer "In11.Cu")
		(net "M_C_DQS_DP<6>")
	)
	(segment
		(start 282.13431 -62.5348)
		(end 282.129484 -62.543436)
		(width 0.0889)
		(layer "In11.Cu")
		(net "M_C_DQS_DP<6>")
	)
	(segment
		(start 282.13431 -60.5536)
		(end 282.129484 -60.562236)
		(width 0.0889)
		(layer "In11.Cu")
		(net "M_C_DQS_DP<6>")
	)
	(segment
		(start 282.091638 -51.2572)
		(end 282.091638 -54.084728)
		(width 0.0889)
		(layer "In11.Cu")
		(net "M_C_DQS_DP<6>")
	)
	(segment
		(start 282.834588 -48.212502)
		(end 281.763724 -49.283366)
		(width 0.0889)
		(layer "In11.Cu")
		(net "M_C_DQS_DP<6>")
	)
	(segment
		(start 282.129484 -55.609236)
		(end 282.123134 -55.619904)
		(width 0.0889)
		(layer "In11.Cu")
		(net "M_C_DQS_DP<6>")
	)
	(segment
		(start 281.763724 -49.283366)
		(end 281.763724 -50.523648)
		(width 0.0889)
		(layer "In11.Cu")
		(net "M_C_DQS_DP<6>")
	)
	(segment
		(start 282.13431 -57.5818)
		(end 282.129484 -57.590436)
		(width 0.0889)
		(layer "In11.Cu")
		(net "M_C_DQS_DP<6>")
	)
	(segment
		(start 281.782774 -64.662812)
		(end 281.782774 -64.324738)
		(width 0.0889)
		(layer "In11.Cu")
		(net "M_C_DQS_DP<6>")
	)
	(segment
		(start 284.01645 -45.18279)
		(end 284.01645 -45.344588)
		(width 0.14224)
		(layer "In11.Cu")
		(net "M_C_DQS_DP<6>")
	)
	(segment
		(start 303.39665 -1.27)
		(end 303.26965 -1.27)
		(width 0.14224)
		(layer "In11.Cu")
		(net "M_C_DQS_DP<6>")
	)
	(segment
		(start 303.038002 -3.026156)
		(end 302.592486 -3.471672)
		(width 0.14224)
		(layer "In11.Cu")
		(net "M_C_DQS_DP<6>")
	)
	(segment
		(start 303.319688 1.181354)
		(end 303.57953 0.921512)
		(width 0.14224)
		(layer "In11.Cu")
		(net "M_C_DQS_DP<6>")
	)
	(segment
		(start 303.26965 -1.8796)
		(end 303.400206 -1.8796)
		(width 0.14224)
		(layer "In11.Cu")
		(net "M_C_DQS_DP<6>")
	)
	(segment
		(start 282.795218 -47.221902)
		(end 282.795218 -47.244)
		(width 0.0889)
		(layer "In11.Cu")
		(net "M_C_DQS_DP<6>")
	)
	(segment
		(start 289.610038 -35.92068)
		(end 286.173418 -39.3573)
		(width 0.14224)
		(layer "In11.Cu")
		(net "M_C_DQS_DP<6>")
	)
	(segment
		(start 284.196282 -45.002958)
		(end 284.01645 -45.18279)
		(width 0.14224)
		(layer "In11.Cu")
		(net "M_C_DQS_DP<6>")
	)
	(segment
		(start 281.763724 -50.523648)
		(end 281.955748 -50.907696)
		(width 0.0889)
		(layer "In11.Cu")
		(net "M_C_DQS_DP<6>")
	)
	(segment
		(start 284.01645 -45.344588)
		(end 283.736796 -45.624242)
		(width 0.14224)
		(layer "In11.Cu")
		(net "M_C_DQS_DP<6>")
	)
	(segment
		(start 284.788864 -44.41063)
		(end 284.609032 -44.590462)
		(width 0.14224)
		(layer "In11.Cu")
		(net "M_C_DQS_DP<6>")
	)
	(segment
		(start 282.215336 -54.469792)
		(end 282.123134 -54.629304)
		(width 0.0889)
		(layer "In11.Cu")
		(net "M_C_DQS_DP<6>")
	)
	(segment
		(start 282.091638 -54.084728)
		(end 282.215336 -54.208426)
		(width 0.0889)
		(layer "In11.Cu")
		(net "M_C_DQS_DP<6>")
	)
	(segment
		(start 303.57953 0.921512)
		(end 303.57953 0.255778)
		(width 0.14224)
		(layer "In11.Cu")
		(net "M_C_DQS_DP<6>")
	)
	(segment
		(start 282.795218 -47.244)
		(end 282.834588 -47.28337)
		(width 0.0889)
		(layer "In11.Cu")
		(net "M_C_DQS_DP<6>")
	)
	(segment
		(start 283.395166 -45.804074)
		(end 283.395166 -45.965872)
		(width 0.14224)
		(layer "In11.Cu")
		(net "M_C_DQS_DP<6>")
	)
	(segment
		(start 302.592486 -3.471672)
		(end 302.592486 -5.343652)
		(width 0.14224)
		(layer "In11.Cu")
		(net "M_C_DQS_DP<6>")
	)
	(segment
		(start 282.834588 -47.28337)
		(end 282.834588 -48.212502)
		(width 0.0889)
		(layer "In11.Cu")
		(net "M_C_DQS_DP<6>")
	)
	(segment
		(start 281.840686 -64.720724)
		(end 281.782774 -64.662812)
		(width 0.0889)
		(layer "In11.Cu")
		(net "M_C_DQS_DP<6>")
	)
	(segment
		(start 284.35808 -45.002958)
		(end 284.196282 -45.002958)
		(width 0.14224)
		(layer "In11.Cu")
		(net "M_C_DQS_DP<6>")
	)
	(segment
		(start 303.57953 0.255778)
		(end 303.399952 0.0762)
		(width 0.14224)
		(layer "In11.Cu")
		(net "M_C_DQS_DP<6>")
	)
	(segment
		(start 303.57953 -1.08712)
		(end 303.39665 -1.27)
		(width 0.14224)
		(layer "In11.Cu")
		(net "M_C_DQS_DP<6>")
	)
	(segment
		(start 303.19726 -0.5334)
		(end 303.374552 -0.5334)
		(width 0.14224)
		(layer "In11.Cu")
		(net "M_C_DQS_DP<6>")
	)
	(segment
		(start 284.609032 -44.590462)
		(end 284.609032 -44.752006)
		(width 0.14224)
		(layer "In11.Cu")
		(net "M_C_DQS_DP<6>")
	)
	(segment
		(start 281.955748 -51.12131)
		(end 282.091638 -51.2572)
		(width 0.0889)
		(layer "In11.Cu")
		(net "M_C_DQS_DP<6>")
	)
	(segment
		(start 284.609032 -44.752006)
		(end 284.35808 -45.002958)
		(width 0.14224)
		(layer "In11.Cu")
		(net "M_C_DQS_DP<6>")
	)
	(segment
		(start 303.09185 -1.7018)
		(end 303.26965 -1.8796)
		(width 0.14224)
		(layer "In11.Cu")
		(net "M_C_DQS_DP<6>")
	)
	(segment
		(start 303.400206 -1.8796)
		(end 303.57953 -2.058924)
		(width 0.14224)
		(layer "In11.Cu")
		(net "M_C_DQS_DP<6>")
	)
	(segment
		(start 303.044606 -0.380746)
		(end 303.19726 -0.5334)
		(width 0.14224)
		(layer "In11.Cu")
		(net "M_C_DQS_DP<6>")
	)
	(segment
		(start 284.950408 -44.41063)
		(end 284.788864 -44.41063)
		(width 0.14224)
		(layer "In11.Cu")
		(net "M_C_DQS_DP<6>")
	)
	(segment
		(start 282.129484 -60.562236)
		(end 282.123134 -60.572904)
		(width 0.0889)
		(layer "In11.Cu")
		(net "M_C_DQS_DP<6>")
	)
	(segment
		(start 303.374552 -0.5334)
		(end 303.57953 -0.738378)
		(width 0.14224)
		(layer "In11.Cu")
		(net "M_C_DQS_DP<6>")
	)
	(segment
		(start 282.13431 -63.5254)
		(end 282.129484 -63.534036)
		(width 0.0889)
		(layer "In11.Cu")
		(net "M_C_DQS_DP<6>")
	)
	(segment
		(start 297.115992 -35.92068)
		(end 289.610038 -35.92068)
		(width 0.14224)
		(layer "In11.Cu")
		(net "M_C_DQS_DP<6>")
	)
	(segment
		(start 282.129484 -62.543436)
		(end 282.123134 -62.554104)
		(width 0.0889)
		(layer "In11.Cu")
		(net "M_C_DQS_DP<6>")
	)
	(segment
		(start 283.395166 -45.965872)
		(end 282.795218 -46.56582)
		(width 0.14224)
		(layer "In11.Cu")
		(net "M_C_DQS_DP<6>")
	)
	(segment
		(start 303.57953 -2.058924)
		(end 303.57953 -2.763774)
		(width 0.14224)
		(layer "In11.Cu")
		(net "M_C_DQS_DP<6>")
	)
	(segment
		(start 303.044606 -0.076454)
		(end 303.044606 -0.380746)
		(width 0.14224)
		(layer "In11.Cu")
		(net "M_C_DQS_DP<6>")
	)
	(segment
		(start 303.09185 -1.4478)
		(end 303.09185 -1.7018)
		(width 0.14224)
		(layer "In11.Cu")
		(net "M_C_DQS_DP<6>")
	)
	(segment
		(start 303.038002 1.181354)
		(end 303.319688 1.181354)
		(width 0.14224)
		(layer "In11.Cu")
		(net "M_C_DQS_DP<6>")
	)
	(segment
		(start 302.592486 -5.343652)
		(end 303.58588 -6.337046)
		(width 0.14224)
		(layer "In11.Cu")
		(net "M_C_DQS_DP<6>")
	)
	(segment
		(start 285.143194 -44.0563)
		(end 285.143194 -44.217844)
		(width 0.14224)
		(layer "In11.Cu")
		(net "M_C_DQS_DP<6>")
	)
	(segment
		(start 282.129484 -63.534036)
		(end 282.123134 -63.544704)
		(width 0.0889)
		(layer "In11.Cu")
		(net "M_C_DQS_DP<6>")
	)
	(segment
		(start 303.58588 -6.337046)
		(end 303.58588 -29.450792)
		(width 0.14224)
		(layer "In11.Cu")
		(net "M_C_DQS_DP<6>")
	)
	(segment
		(start 282.13431 -61.5442)
		(end 282.129484 -61.552836)
		(width 0.0889)
		(layer "In11.Cu")
		(net "M_C_DQS_DP<6>")
	)
	(segment
		(start 282.129484 -61.552836)
		(end 282.123134 -61.563504)
		(width 0.0889)
		(layer "In11.Cu")
		(net "M_C_DQS_DP<6>")
	)
	(segment
		(start 303.57953 -2.763774)
		(end 303.316894 -3.02641)
		(width 0.14224)
		(layer "In11.Cu")
		(net "M_C_DQS_DP<6>")
	)
	(segment
		(start 282.13431 -56.5912)
		(end 282.129484 -56.599836)
		(width 0.0889)
		(layer "In11.Cu")
		(net "M_C_DQS_DP<6>")
	)
	(segment
		(start 282.123134 -59.160918)
		(end 282.129484 -59.171586)
		(width 0.0889)
		(layer "In11.Cu")
		(net "M_C_DQS_DP<6>")
	)
	(segment
		(start 303.19726 0.0762)
		(end 303.044606 -0.076454)
		(width 0.14224)
		(layer "In11.Cu")
		(net "M_C_DQS_DP<6>")
	)
	(segment
		(start 285.48457 -43.876468)
		(end 285.323026 -43.876468)
		(width 0.14224)
		(layer "In11.Cu")
		(net "M_C_DQS_DP<6>")
	)
	(segment
		(start 285.323026 -43.876468)
		(end 285.143194 -44.0563)
		(width 0.14224)
		(layer "In11.Cu")
		(net "M_C_DQS_DP<6>")
	)
	(segment
		(start 283.574998 -45.624242)
		(end 283.395166 -45.804074)
		(width 0.14224)
		(layer "In11.Cu")
		(net "M_C_DQS_DP<6>")
	)
	(segment
		(start 303.399952 0.0762)
		(end 303.19726 0.0762)
		(width 0.14224)
		(layer "In11.Cu")
		(net "M_C_DQS_DP<6>")
	)
	(segment
		(start 282.13431 -55.6006)
		(end 282.129484 -55.609236)
		(width 0.0889)
		(layer "In11.Cu")
		(net "M_C_DQS_DP<6>")
	)
	(segment
		(start 303.038002 -3.02641)
		(end 303.038002 -3.026156)
		(width 0.14224)
		(layer "In11.Cu")
		(net "M_C_DQS_DP<6>")
	)
	(segment
		(start 285.143194 -44.217844)
		(end 284.950408 -44.41063)
		(width 0.14224)
		(layer "In11.Cu")
		(net "M_C_DQS_DP<6>")
	)
	(segment
		(start 282.129484 -56.599836)
		(end 282.123134 -56.610504)
		(width 0.0889)
		(layer "In11.Cu")
		(net "M_C_DQS_DP<6>")
	)
	(segment
		(start 303.58588 -29.450792)
		(end 297.115992 -35.92068)
		(width 0.14224)
		(layer "In11.Cu")
		(net "M_C_DQS_DP<6>")
	)
	(segment
		(start 282.795218 -46.56582)
		(end 282.795218 -47.221902)
		(width 0.14224)
		(layer "In11.Cu")
		(net "M_C_DQS_DP<6>")
	)
	(segment
		(start 282.129484 -57.590436)
		(end 282.123134 -57.601104)
		(width 0.0889)
		(layer "In11.Cu")
		(net "M_C_DQS_DP<6>")
	)
	(arc
		(start 282.123134 -56.610504)
		(mid 282.050336 -56.901267)
		(end 282.129484 -57.190386)
		(width 0.0889)
		(layer "In11.Cu")
		(net "M_C_DQS_DP<6>")
	)
	(arc
		(start 282.123134 -57.601104)
		(mid 282.050336 -57.891867)
		(end 282.129484 -58.180986)
		(width 0.0889)
		(layer "In11.Cu")
		(net "M_C_DQS_DP<6>")
	)
	(arc
		(start 282.129484 -63.133986)
		(mid 282.182954 -63.329049)
		(end 282.13431 -63.5254)
		(width 0.0889)
		(layer "In11.Cu")
		(net "M_C_DQS_DP<6>")
	)
	(arc
		(start 282.129484 -57.190386)
		(mid 282.182954 -57.385449)
		(end 282.13431 -57.5818)
		(width 0.0889)
		(layer "In11.Cu")
		(net "M_C_DQS_DP<6>")
	)
	(arc
		(start 282.123134 -55.619904)
		(mid 282.050336 -55.910667)
		(end 282.129484 -56.199786)
		(width 0.0889)
		(layer "In11.Cu")
		(net "M_C_DQS_DP<6>")
	)
	(arc
		(start 282.129484 -56.199786)
		(mid 282.182954 -56.394849)
		(end 282.13431 -56.5912)
		(width 0.0889)
		(layer "In11.Cu")
		(net "M_C_DQS_DP<6>")
	)
	(arc
		(start 282.129484 -55.209186)
		(mid 282.182954 -55.404249)
		(end 282.13431 -55.6006)
		(width 0.0889)
		(layer "In11.Cu")
		(net "M_C_DQS_DP<6>")
	)
	(arc
		(start 282.123134 -63.544704)
		(mid 282.050336 -63.835467)
		(end 282.129484 -64.124586)
		(width 0.0889)
		(layer "In11.Cu")
		(net "M_C_DQS_DP<6>")
	)
	(arc
		(start 282.129484 -59.171586)
		(mid 282.182983 -59.371484)
		(end 282.129484 -59.571382)
		(width 0.0889)
		(layer "In11.Cu")
		(net "M_C_DQS_DP<6>")
	)
	(arc
		(start 282.129484 -58.180986)
		(mid 282.182954 -58.376049)
		(end 282.13431 -58.5724)
		(width 0.0889)
		(layer "In11.Cu")
		(net "M_C_DQS_DP<6>")
	)
	(arc
		(start 282.123134 -61.563504)
		(mid 282.050336 -61.854267)
		(end 282.129484 -62.143386)
		(width 0.0889)
		(layer "In11.Cu")
		(net "M_C_DQS_DP<6>")
	)
	(arc
		(start 282.129484 -59.571382)
		(mid 282.050353 -59.866784)
		(end 282.129484 -60.162186)
		(width 0.0889)
		(layer "In11.Cu")
		(net "M_C_DQS_DP<6>")
	)
	(arc
		(start 282.129484 -61.152786)
		(mid 282.182954 -61.347849)
		(end 282.13431 -61.5442)
		(width 0.0889)
		(layer "In11.Cu")
		(net "M_C_DQS_DP<6>")
	)
	(arc
		(start 282.123134 -60.572904)
		(mid 282.050336 -60.863667)
		(end 282.129484 -61.152786)
		(width 0.0889)
		(layer "In11.Cu")
		(net "M_C_DQS_DP<6>")
	)
	(arc
		(start 282.123134 -62.554104)
		(mid 282.050336 -62.844867)
		(end 282.129484 -63.133986)
		(width 0.0889)
		(layer "In11.Cu")
		(net "M_C_DQS_DP<6>")
	)
	(arc
		(start 282.129484 -58.581036)
		(mid 282.050262 -58.870154)
		(end 282.123134 -59.160918)
		(width 0.0889)
		(layer "In11.Cu")
		(net "M_C_DQS_DP<6>")
	)
	(arc
		(start 282.129484 -60.162186)
		(mid 282.182954 -60.357249)
		(end 282.13431 -60.5536)
		(width 0.0889)
		(layer "In11.Cu")
		(net "M_C_DQS_DP<6>")
	)
	(arc
		(start 282.129484 -64.124586)
		(mid 282.143079 -64.499235)
		(end 281.840686 -64.720724)
		(width 0.0889)
		(layer "In11.Cu")
		(net "M_C_DQS_DP<6>")
	)
	(arc
		(start 282.123134 -54.629304)
		(mid 282.050336 -54.920067)
		(end 282.129484 -55.209186)
		(width 0.0889)
		(layer "In11.Cu")
		(net "M_C_DQS_DP<6>")
	)
	(arc
		(start 282.129484 -62.143386)
		(mid 282.182954 -62.338449)
		(end 282.13431 -62.5348)
		(width 0.0889)
		(layer "In11.Cu")
		(net "M_C_DQS_DP<6>")
	)
	(segment
		(start 293.96182 1.455166)
		(end 293.688008 1.181354)
		(width 0.1651)
		(layer "F.Cu")
		(net "M_C_DQS_DP<5>")
	)
	(segment
		(start 294.371522 1.241298)
		(end 294.157654 1.455166)
		(width 0.1651)
		(layer "F.Cu")
		(net "M_C_DQS_DP<5>")
	)
	(segment
		(start 294.14978 -0.821182)
		(end 294.14978 0.277368)
		(width 0.1651)
		(layer "F.Cu")
		(net "M_C_DQS_DP<5>")
	)
	(segment
		(start 294.150288 -0.821182)
		(end 294.14978 -0.821182)
		(width 0.1651)
		(layer "F.Cu")
		(net "M_C_DQS_DP<5>")
	)
	(segment
		(start 294.157654 1.455166)
		(end 293.96182 1.455166)
		(width 0.1651)
		(layer "F.Cu")
		(net "M_C_DQS_DP<5>")
	)
	(segment
		(start 294.14978 0.277368)
		(end 294.371522 0.49911)
		(width 0.1651)
		(layer "F.Cu")
		(net "M_C_DQS_DP<5>")
	)
	(segment
		(start 294.371522 0.49911)
		(end 294.371522 1.241298)
		(width 0.1651)
		(layer "F.Cu")
		(net "M_C_DQS_DP<5>")
	)
	(segment
		(start 279.778714 -60.857384)
		(end 279.207214 -60.857384)
		(width 0.0889)
		(layer "F.Cu")
		(net "M_C_DQS_DP<5>")
	)
	(via
		(at 293.688008 1.181354)
		(size 0.508)
		(drill 0.254)
		(layers "F.Cu" "B.Cu")
		(net "M_C_DQS_DP<5>")
	)
	(via
		(at 293.688008 -3.026156)
		(size 0.508)
		(drill 0.254)
		(layers "F.Cu" "B.Cu")
		(net "M_C_DQS_DP<5>")
	)
	(via
		(at 279.207214 -60.857384)
		(size 0.508)
		(drill 0.254)
		(layers "F.Cu" "B.Cu")
		(net "M_C_DQS_DP<5>")
	)
	(segment
		(start 294.189912 -3.30708)
		(end 293.968932 -3.30708)
		(width 0.1651)
		(layer "B.Cu")
		(net "M_C_DQS_DP<5>")
	)
	(segment
		(start 293.968932 -3.30708)
		(end 293.688008 -3.026156)
		(width 0.1651)
		(layer "B.Cu")
		(net "M_C_DQS_DP<5>")
	)
	(segment
		(start 294.14978 -2.537968)
		(end 294.329612 -2.7178)
		(width 0.1651)
		(layer "B.Cu")
		(net "M_C_DQS_DP<5>")
	)
	(segment
		(start 294.329612 -3.16738)
		(end 294.189912 -3.30708)
		(width 0.1651)
		(layer "B.Cu")
		(net "M_C_DQS_DP<5>")
	)
	(segment
		(start 294.14978 -1.021842)
		(end 294.14978 -2.537968)
		(width 0.1651)
		(layer "B.Cu")
		(net "M_C_DQS_DP<5>")
	)
	(segment
		(start 294.150288 -1.021842)
		(end 294.14978 -1.021842)
		(width 0.1651)
		(layer "B.Cu")
		(net "M_C_DQS_DP<5>")
	)
	(segment
		(start 294.329612 -2.7178)
		(end 294.329612 -3.16738)
		(width 0.1651)
		(layer "B.Cu")
		(net "M_C_DQS_DP<5>")
	)
	(segment
		(start 280.8732 -50.665126)
		(end 280.8732 -51.376326)
		(width 0.0889)
		(layer "In4.Cu")
		(net "M_C_DQS_DP<5>")
	)
	(segment
		(start 279.553924 -55.704486)
		(end 279.55875 -55.713122)
		(width 0.0889)
		(layer "In4.Cu")
		(net "M_C_DQS_DP<5>")
	)
	(segment
		(start 279.932892 -52.316634)
		(end 279.932892 -53.071014)
		(width 0.0889)
		(layer "In4.Cu")
		(net "M_C_DQS_DP<5>")
	)
	(segment
		(start 293.250112 -4.706366)
		(end 293.369492 -4.825746)
		(width 0.14224)
		(layer "In4.Cu")
		(net "M_C_DQS_DP<5>")
	)
	(segment
		(start 282.781248 -47.275496)
		(end 282.781248 -47.297594)
		(width 0.0889)
		(layer "In4.Cu")
		(net "M_C_DQS_DP<5>")
	)
	(segment
		(start 293.369492 -4.825746)
		(end 293.369492 -5.392674)
		(width 0.14224)
		(layer "In4.Cu")
		(net "M_C_DQS_DP<5>")
	)
	(segment
		(start 279.547574 -55.693818)
		(end 279.553924 -55.704486)
		(width 0.0889)
		(layer "In4.Cu")
		(net "M_C_DQS_DP<5>")
	)
	(segment
		(start 282.820618 -47.336964)
		(end 282.820618 -48.717708)
		(width 0.0889)
		(layer "In4.Cu")
		(net "M_C_DQS_DP<5>")
	)
	(segment
		(start 282.781248 -47.297594)
		(end 282.820618 -47.336964)
		(width 0.0889)
		(layer "In4.Cu")
		(net "M_C_DQS_DP<5>")
	)
	(segment
		(start 294.03548 -31.218886)
		(end 282.781248 -42.473118)
		(width 0.14224)
		(layer "In4.Cu")
		(net "M_C_DQS_DP<5>")
	)
	(segment
		(start 279.547574 -54.703218)
		(end 279.553924 -54.713886)
		(width 0.0889)
		(layer "In4.Cu")
		(net "M_C_DQS_DP<5>")
	)
	(segment
		(start 279.547574 -57.675018)
		(end 279.553924 -57.685686)
		(width 0.0889)
		(layer "In4.Cu")
		(net "M_C_DQS_DP<5>")
	)
	(segment
		(start 279.553924 -56.695086)
		(end 279.55875 -56.703722)
		(width 0.0889)
		(layer "In4.Cu")
		(net "M_C_DQS_DP<5>")
	)
	(segment
		(start 294.242998 -6.26618)
		(end 294.242998 -28.826714)
		(width 0.14224)
		(layer "In4.Cu")
		(net "M_C_DQS_DP<5>")
	)
	(segment
		(start 279.553924 -60.657486)
		(end 279.55875 -60.666122)
		(width 0.0889)
		(layer "In4.Cu")
		(net "M_C_DQS_DP<5>")
	)
	(segment
		(start 282.820618 -48.717708)
		(end 280.8732 -50.665126)
		(width 0.0889)
		(layer "In4.Cu")
		(net "M_C_DQS_DP<5>")
	)
	(segment
		(start 279.932892 -53.071014)
		(end 279.607264 -53.396642)
		(width 0.0889)
		(layer "In4.Cu")
		(net "M_C_DQS_DP<5>")
	)
	(segment
		(start 279.607264 -53.396642)
		(end 279.607264 -53.912262)
		(width 0.0889)
		(layer "In4.Cu")
		(net "M_C_DQS_DP<5>")
	)
	(segment
		(start 293.250112 -3.464052)
		(end 293.250112 -4.706366)
		(width 0.14224)
		(layer "In4.Cu")
		(net "M_C_DQS_DP<5>")
	)
	(segment
		(start 293.369492 -5.392674)
		(end 294.242998 -6.26618)
		(width 0.14224)
		(layer "In4.Cu")
		(net "M_C_DQS_DP<5>")
	)
	(segment
		(start 282.781248 -42.473118)
		(end 282.781248 -47.275496)
		(width 0.14224)
		(layer "In4.Cu")
		(net "M_C_DQS_DP<5>")
	)
	(segment
		(start 294.242998 -28.826714)
		(end 294.03548 -29.034232)
		(width 0.14224)
		(layer "In4.Cu")
		(net "M_C_DQS_DP<5>")
	)
	(segment
		(start 279.553924 -54.713886)
		(end 279.55875 -54.722522)
		(width 0.0889)
		(layer "In4.Cu")
		(net "M_C_DQS_DP<5>")
	)
	(segment
		(start 279.207214 -61.195458)
		(end 279.207214 -60.857384)
		(width 0.0889)
		(layer "In4.Cu")
		(net "M_C_DQS_DP<5>")
	)
	(segment
		(start 279.553924 -59.076336)
		(end 279.547574 -59.087004)
		(width 0.0889)
		(layer "In4.Cu")
		(net "M_C_DQS_DP<5>")
	)
	(segment
		(start 279.553924 -57.685686)
		(end 279.55875 -57.694322)
		(width 0.0889)
		(layer "In4.Cu")
		(net "M_C_DQS_DP<5>")
	)
	(segment
		(start 279.547574 -60.646818)
		(end 279.553924 -60.657486)
		(width 0.0889)
		(layer "In4.Cu")
		(net "M_C_DQS_DP<5>")
	)
	(segment
		(start 293.688008 -3.026156)
		(end 293.250112 -3.464052)
		(width 0.14224)
		(layer "In4.Cu")
		(net "M_C_DQS_DP<5>")
	)
	(segment
		(start 294.03548 -29.034232)
		(end 294.03548 -31.218886)
		(width 0.14224)
		(layer "In4.Cu")
		(net "M_C_DQS_DP<5>")
	)
	(segment
		(start 279.553924 -59.666886)
		(end 279.55875 -59.675522)
		(width 0.0889)
		(layer "In4.Cu")
		(net "M_C_DQS_DP<5>")
	)
	(segment
		(start 279.265126 -61.25337)
		(end 279.207214 -61.195458)
		(width 0.0889)
		(layer "In4.Cu")
		(net "M_C_DQS_DP<5>")
	)
	(segment
		(start 280.8732 -51.376326)
		(end 279.932892 -52.316634)
		(width 0.0889)
		(layer "In4.Cu")
		(net "M_C_DQS_DP<5>")
	)
	(segment
		(start 279.547574 -56.684418)
		(end 279.553924 -56.695086)
		(width 0.0889)
		(layer "In4.Cu")
		(net "M_C_DQS_DP<5>")
	)
	(arc
		(start 279.553924 -58.67654)
		(mid 279.607423 -58.876438)
		(end 279.553924 -59.076336)
		(width 0.0889)
		(layer "In4.Cu")
		(net "M_C_DQS_DP<5>")
	)
	(arc
		(start 279.553924 -56.104536)
		(mid 279.474702 -56.393654)
		(end 279.547574 -56.684418)
		(width 0.0889)
		(layer "In4.Cu")
		(net "M_C_DQS_DP<5>")
	)
	(arc
		(start 279.55367 -61.057536)
		(mid 279.431863 -61.188574)
		(end 279.265126 -61.25337)
		(width 0.0889)
		(layer "In4.Cu")
		(net "M_C_DQS_DP<5>")
	)
	(arc
		(start 279.553924 -60.066936)
		(mid 279.474702 -60.356054)
		(end 279.547574 -60.646818)
		(width 0.0889)
		(layer "In4.Cu")
		(net "M_C_DQS_DP<5>")
	)
	(arc
		(start 279.553924 -58.085736)
		(mid 279.474793 -58.381138)
		(end 279.553924 -58.67654)
		(width 0.0889)
		(layer "In4.Cu")
		(net "M_C_DQS_DP<5>")
	)
	(arc
		(start 279.55875 -54.722522)
		(mid 279.607505 -54.918874)
		(end 279.553924 -55.113936)
		(width 0.0889)
		(layer "In4.Cu")
		(net "M_C_DQS_DP<5>")
	)
	(arc
		(start 279.553924 -54.123336)
		(mid 279.474702 -54.412454)
		(end 279.547574 -54.703218)
		(width 0.0889)
		(layer "In4.Cu")
		(net "M_C_DQS_DP<5>")
	)
	(arc
		(start 279.553924 -57.095136)
		(mid 279.474702 -57.384254)
		(end 279.547574 -57.675018)
		(width 0.0889)
		(layer "In4.Cu")
		(net "M_C_DQS_DP<5>")
	)
	(arc
		(start 279.55875 -57.694322)
		(mid 279.607505 -57.890674)
		(end 279.553924 -58.085736)
		(width 0.0889)
		(layer "In4.Cu")
		(net "M_C_DQS_DP<5>")
	)
	(arc
		(start 279.55875 -55.713122)
		(mid 279.607505 -55.909474)
		(end 279.553924 -56.104536)
		(width 0.0889)
		(layer "In4.Cu")
		(net "M_C_DQS_DP<5>")
	)
	(arc
		(start 279.55875 -56.703722)
		(mid 279.607505 -56.900074)
		(end 279.553924 -57.095136)
		(width 0.0889)
		(layer "In4.Cu")
		(net "M_C_DQS_DP<5>")
	)
	(arc
		(start 279.607264 -53.912262)
		(mid 279.595221 -54.021495)
		(end 279.553924 -54.123336)
		(width 0.0889)
		(layer "In4.Cu")
		(net "M_C_DQS_DP<5>")
	)
	(arc
		(start 279.55875 -60.666122)
		(mid 279.60738 -60.862504)
		(end 279.55367 -61.057536)
		(width 0.0889)
		(layer "In4.Cu")
		(net "M_C_DQS_DP<5>")
	)
	(arc
		(start 279.55875 -59.675522)
		(mid 279.607505 -59.871874)
		(end 279.553924 -60.066936)
		(width 0.0889)
		(layer "In4.Cu")
		(net "M_C_DQS_DP<5>")
	)
	(arc
		(start 279.547574 -59.087004)
		(mid 279.474776 -59.377767)
		(end 279.553924 -59.666886)
		(width 0.0889)
		(layer "In4.Cu")
		(net "M_C_DQS_DP<5>")
	)
	(arc
		(start 279.553924 -55.113936)
		(mid 279.474702 -55.403054)
		(end 279.547574 -55.693818)
		(width 0.0889)
		(layer "In4.Cu")
		(net "M_C_DQS_DP<5>")
	)
	(segment
		(start 293.688008 -3.02641)
		(end 293.9669 -3.02641)
		(width 0.14224)
		(layer "In11.Cu")
		(net "M_C_DQS_DP<5>")
	)
	(segment
		(start 293.919656 -1.27)
		(end 294.046656 -1.27)
		(width 0.14224)
		(layer "In11.Cu")
		(net "M_C_DQS_DP<5>")
	)
	(segment
		(start 293.741856 -1.7018)
		(end 293.741856 -1.4478)
		(width 0.14224)
		(layer "In11.Cu")
		(net "M_C_DQS_DP<5>")
	)
	(segment
		(start 294.229536 -0.738378)
		(end 294.024558 -0.5334)
		(width 0.14224)
		(layer "In11.Cu")
		(net "M_C_DQS_DP<5>")
	)
	(segment
		(start 294.049958 0.0762)
		(end 294.229536 0.255778)
		(width 0.14224)
		(layer "In11.Cu")
		(net "M_C_DQS_DP<5>")
	)
	(segment
		(start 294.050212 -1.8796)
		(end 293.919656 -1.8796)
		(width 0.14224)
		(layer "In11.Cu")
		(net "M_C_DQS_DP<5>")
	)
	(segment
		(start 293.741856 -1.4478)
		(end 293.919656 -1.27)
		(width 0.14224)
		(layer "In11.Cu")
		(net "M_C_DQS_DP<5>")
	)
	(segment
		(start 293.694612 -0.380746)
		(end 293.694612 -0.076454)
		(width 0.14224)
		(layer "In11.Cu")
		(net "M_C_DQS_DP<5>")
	)
	(segment
		(start 294.024558 -0.5334)
		(end 293.847266 -0.5334)
		(width 0.14224)
		(layer "In11.Cu")
		(net "M_C_DQS_DP<5>")
	)
	(segment
		(start 293.847266 -0.5334)
		(end 293.694612 -0.380746)
		(width 0.14224)
		(layer "In11.Cu")
		(net "M_C_DQS_DP<5>")
	)
	(segment
		(start 293.694612 -0.076454)
		(end 293.847266 0.0762)
		(width 0.14224)
		(layer "In11.Cu")
		(net "M_C_DQS_DP<5>")
	)
	(segment
		(start 293.9669 -3.02641)
		(end 294.229536 -2.763774)
		(width 0.14224)
		(layer "In11.Cu")
		(net "M_C_DQS_DP<5>")
	)
	(segment
		(start 294.046656 -1.27)
		(end 294.229536 -1.08712)
		(width 0.14224)
		(layer "In11.Cu")
		(net "M_C_DQS_DP<5>")
	)
	(segment
		(start 294.229536 0.255778)
		(end 294.229536 0.921512)
		(width 0.14224)
		(layer "In11.Cu")
		(net "M_C_DQS_DP<5>")
	)
	(segment
		(start 294.229536 -2.763774)
		(end 294.229536 -2.058924)
		(width 0.14224)
		(layer "In11.Cu")
		(net "M_C_DQS_DP<5>")
	)
	(segment
		(start 293.919656 -1.8796)
		(end 293.741856 -1.7018)
		(width 0.14224)
		(layer "In11.Cu")
		(net "M_C_DQS_DP<5>")
	)
	(segment
		(start 293.688008 -3.026156)
		(end 293.688008 -3.02641)
		(width 0.14224)
		(layer "In11.Cu")
		(net "M_C_DQS_DP<5>")
	)
	(segment
		(start 294.229536 0.921512)
		(end 293.969694 1.181354)
		(width 0.14224)
		(layer "In11.Cu")
		(net "M_C_DQS_DP<5>")
	)
	(segment
		(start 294.229536 -1.08712)
		(end 294.229536 -0.738378)
		(width 0.14224)
		(layer "In11.Cu")
		(net "M_C_DQS_DP<5>")
	)
	(segment
		(start 294.229536 -2.058924)
		(end 294.050212 -1.8796)
		(width 0.14224)
		(layer "In11.Cu")
		(net "M_C_DQS_DP<5>")
	)
	(segment
		(start 293.969694 1.181354)
		(end 293.688008 1.181354)
		(width 0.14224)
		(layer "In11.Cu")
		(net "M_C_DQS_DP<5>")
	)
	(segment
		(start 293.847266 0.0762)
		(end 294.049958 0.0762)
		(width 0.14224)
		(layer "In11.Cu")
		(net "M_C_DQS_DP<5>")
	)
	(segment
		(start 284.807406 1.455166)
		(end 284.611572 1.455166)
		(width 0.1651)
		(layer "F.Cu")
		(net "M_C_DQS_DP<4>")
	)
	(segment
		(start 284.799532 -0.82042)
		(end 284.799532 0.277368)
		(width 0.1651)
		(layer "F.Cu")
		(net "M_C_DQS_DP<4>")
	)
	(segment
		(start 285.021274 1.241298)
		(end 284.807406 1.455166)
		(width 0.1651)
		(layer "F.Cu")
		(net "M_C_DQS_DP<4>")
	)
	(segment
		(start 284.611572 1.455166)
		(end 284.33776 1.181354)
		(width 0.1651)
		(layer "F.Cu")
		(net "M_C_DQS_DP<4>")
	)
	(segment
		(start 284.799532 0.277368)
		(end 285.021274 0.49911)
		(width 0.1651)
		(layer "F.Cu")
		(net "M_C_DQS_DP<4>")
	)
	(segment
		(start 284.800294 -0.821182)
		(end 284.799532 -0.82042)
		(width 0.1651)
		(layer "F.Cu")
		(net "M_C_DQS_DP<4>")
	)
	(segment
		(start 285.021274 0.49911)
		(end 285.021274 1.241298)
		(width 0.1651)
		(layer "F.Cu")
		(net "M_C_DQS_DP<4>")
	)
	(segment
		(start 274.627848 -60.857384)
		(end 274.056348 -60.857384)
		(width 0.0889)
		(layer "F.Cu")
		(net "M_C_DQS_DP<4>")
	)
	(via
		(at 284.33776 -3.026156)
		(size 0.508)
		(drill 0.254)
		(layers "F.Cu" "B.Cu")
		(net "M_C_DQS_DP<4>")
	)
	(via
		(at 284.33776 1.181354)
		(size 0.508)
		(drill 0.254)
		(layers "F.Cu" "B.Cu")
		(net "M_C_DQS_DP<4>")
	)
	(via
		(at 274.056348 -60.857384)
		(size 0.508)
		(drill 0.254)
		(layers "F.Cu" "B.Cu")
		(net "M_C_DQS_DP<4>")
	)
	(segment
		(start 284.839664 -3.30708)
		(end 284.618684 -3.30708)
		(width 0.1651)
		(layer "B.Cu")
		(net "M_C_DQS_DP<4>")
	)
	(segment
		(start 284.979364 -3.16738)
		(end 284.839664 -3.30708)
		(width 0.1651)
		(layer "B.Cu")
		(net "M_C_DQS_DP<4>")
	)
	(segment
		(start 284.799532 -1.021842)
		(end 284.799532 -2.537968)
		(width 0.1651)
		(layer "B.Cu")
		(net "M_C_DQS_DP<4>")
	)
	(segment
		(start 284.618684 -3.30708)
		(end 284.33776 -3.026156)
		(width 0.1651)
		(layer "B.Cu")
		(net "M_C_DQS_DP<4>")
	)
	(segment
		(start 284.979364 -2.7178)
		(end 284.979364 -3.16738)
		(width 0.1651)
		(layer "B.Cu")
		(net "M_C_DQS_DP<4>")
	)
	(segment
		(start 284.800294 -1.021842)
		(end 284.799532 -1.021842)
		(width 0.1651)
		(layer "B.Cu")
		(net "M_C_DQS_DP<4>")
	)
	(segment
		(start 284.799532 -2.537968)
		(end 284.979364 -2.7178)
		(width 0.1651)
		(layer "B.Cu")
		(net "M_C_DQS_DP<4>")
	)
	(segment
		(start 284.879288 0.255778)
		(end 284.69971 0.0762)
		(width 0.14224)
		(layer "In11.Cu")
		(net "M_C_DQS_DP<4>")
	)
	(segment
		(start 284.616652 -3.02641)
		(end 284.33776 -3.02641)
		(width 0.14224)
		(layer "In11.Cu")
		(net "M_C_DQS_DP<4>")
	)
	(segment
		(start 284.019244 -5.392674)
		(end 284.864048 -6.237478)
		(width 0.14224)
		(layer "In11.Cu")
		(net "M_C_DQS_DP<4>")
	)
	(segment
		(start 284.344364 -0.380746)
		(end 284.497018 -0.5334)
		(width 0.14224)
		(layer "In11.Cu")
		(net "M_C_DQS_DP<4>")
	)
	(segment
		(start 275.390864 -46.214538)
		(end 275.390864 -46.61281)
		(width 0.14224)
		(layer "In11.Cu")
		(net "M_C_DQS_DP<4>")
	)
	(segment
		(start 275.390864 -44.10964)
		(end 275.390864 -44.642278)
		(width 0.14224)
		(layer "In11.Cu")
		(net "M_C_DQS_DP<4>")
	)
	(segment
		(start 275.2598 -48.140366)
		(end 274.807172 -48.592994)
		(width 0.0889)
		(layer "In11.Cu")
		(net "M_C_DQS_DP<4>")
	)
	(segment
		(start 275.2598 -47.41037)
		(end 275.2598 -48.140366)
		(width 0.0889)
		(layer "In11.Cu")
		(net "M_C_DQS_DP<4>")
	)
	(segment
		(start 275.22043 -47.371)
		(end 275.2598 -47.41037)
		(width 0.0889)
		(layer "In11.Cu")
		(net "M_C_DQS_DP<4>")
	)
	(segment
		(start 284.699964 -1.8796)
		(end 284.879288 -2.058924)
		(width 0.14224)
		(layer "In11.Cu")
		(net "M_C_DQS_DP<4>")
	)
	(segment
		(start 284.019244 -4.746498)
		(end 284.019244 -5.392674)
		(width 0.14224)
		(layer "In11.Cu")
		(net "M_C_DQS_DP<4>")
	)
	(segment
		(start 275.22043 -46.783244)
		(end 275.22043 -47.348902)
		(width 0.14224)
		(layer "In11.Cu")
		(net "M_C_DQS_DP<4>")
	)
	(segment
		(start 284.391608 -1.4478)
		(end 284.391608 -1.7018)
		(width 0.14224)
		(layer "In11.Cu")
		(net "M_C_DQS_DP<4>")
	)
	(segment
		(start 284.33776 1.181354)
		(end 284.619446 1.181354)
		(width 0.14224)
		(layer "In11.Cu")
		(net "M_C_DQS_DP<4>")
	)
	(segment
		(start 283.899864 -3.464052)
		(end 283.899864 -4.627118)
		(width 0.14224)
		(layer "In11.Cu")
		(net "M_C_DQS_DP<4>")
	)
	(segment
		(start 284.879288 -1.08712)
		(end 284.696408 -1.27)
		(width 0.14224)
		(layer "In11.Cu")
		(net "M_C_DQS_DP<4>")
	)
	(segment
		(start 274.807172 -52.167028)
		(end 274.512278 -52.461922)
		(width 0.0889)
		(layer "In11.Cu")
		(net "M_C_DQS_DP<4>")
	)
	(segment
		(start 274.056348 -61.195458)
		(end 274.056348 -60.857384)
		(width 0.0889)
		(layer "In11.Cu")
		(net "M_C_DQS_DP<4>")
	)
	(segment
		(start 274.393914 -55.689246)
		(end 274.402804 -55.704486)
		(width 0.0889)
		(layer "In11.Cu")
		(net "M_C_DQS_DP<4>")
	)
	(segment
		(start 275.276564 -45.846238)
		(end 275.276564 -46.100238)
		(width 0.14224)
		(layer "In11.Cu")
		(net "M_C_DQS_DP<4>")
	)
	(segment
		(start 284.67431 -0.5334)
		(end 284.879288 -0.738378)
		(width 0.14224)
		(layer "In11.Cu")
		(net "M_C_DQS_DP<4>")
	)
	(segment
		(start 284.497018 -0.5334)
		(end 284.67431 -0.5334)
		(width 0.14224)
		(layer "In11.Cu")
		(net "M_C_DQS_DP<4>")
	)
	(segment
		(start 284.864048 -6.237478)
		(end 284.864048 -30.090618)
		(width 0.14224)
		(layer "In11.Cu")
		(net "M_C_DQS_DP<4>")
	)
	(segment
		(start 274.393914 -60.642246)
		(end 274.402804 -60.657486)
		(width 0.0889)
		(layer "In11.Cu")
		(net "M_C_DQS_DP<4>")
	)
	(segment
		(start 275.390864 -43.13555)
		(end 275.390864 -43.62704)
		(width 0.14224)
		(layer "In11.Cu")
		(net "M_C_DQS_DP<4>")
	)
	(segment
		(start 284.879288 0.921512)
		(end 284.879288 0.255778)
		(width 0.14224)
		(layer "In11.Cu")
		(net "M_C_DQS_DP<4>")
	)
	(segment
		(start 275.390864 -46.61281)
		(end 275.22043 -46.783244)
		(width 0.14224)
		(layer "In11.Cu")
		(net "M_C_DQS_DP<4>")
	)
	(segment
		(start 274.396454 -54.703218)
		(end 274.402804 -54.713886)
		(width 0.0889)
		(layer "In11.Cu")
		(net "M_C_DQS_DP<4>")
	)
	(segment
		(start 275.276564 -46.100238)
		(end 275.390864 -46.214538)
		(width 0.14224)
		(layer "In11.Cu")
		(net "M_C_DQS_DP<4>")
	)
	(segment
		(start 275.276564 -43.02125)
		(end 275.390864 -43.13555)
		(width 0.14224)
		(layer "In11.Cu")
		(net "M_C_DQS_DP<4>")
	)
	(segment
		(start 274.512278 -52.461922)
		(end 274.512278 -52.941982)
		(width 0.0889)
		(layer "In11.Cu")
		(net "M_C_DQS_DP<4>")
	)
	(segment
		(start 275.276564 -44.756578)
		(end 275.276564 -45.010578)
		(width 0.14224)
		(layer "In11.Cu")
		(net "M_C_DQS_DP<4>")
	)
	(segment
		(start 275.390864 -43.62704)
		(end 275.276564 -43.74134)
		(width 0.14224)
		(layer "In11.Cu")
		(net "M_C_DQS_DP<4>")
	)
	(segment
		(start 274.393914 -57.670446)
		(end 274.402804 -57.685686)
		(width 0.0889)
		(layer "In11.Cu")
		(net "M_C_DQS_DP<4>")
	)
	(segment
		(start 275.390864 -42.65295)
		(end 275.276564 -42.76725)
		(width 0.14224)
		(layer "In11.Cu")
		(net "M_C_DQS_DP<4>")
	)
	(segment
		(start 275.276564 -45.010578)
		(end 275.390864 -45.124878)
		(width 0.14224)
		(layer "In11.Cu")
		(net "M_C_DQS_DP<4>")
	)
	(segment
		(start 284.497018 0.0762)
		(end 284.344364 -0.076454)
		(width 0.14224)
		(layer "In11.Cu")
		(net "M_C_DQS_DP<4>")
	)
	(segment
		(start 275.276564 -43.74134)
		(end 275.276564 -43.99534)
		(width 0.14224)
		(layer "In11.Cu")
		(net "M_C_DQS_DP<4>")
	)
	(segment
		(start 275.390864 -44.642278)
		(end 275.276564 -44.756578)
		(width 0.14224)
		(layer "In11.Cu")
		(net "M_C_DQS_DP<4>")
	)
	(segment
		(start 275.390864 -45.124878)
		(end 275.390864 -45.731938)
		(width 0.14224)
		(layer "In11.Cu")
		(net "M_C_DQS_DP<4>")
	)
	(segment
		(start 274.40763 -54.1147)
		(end 274.402804 -54.123336)
		(width 0.0889)
		(layer "In11.Cu")
		(net "M_C_DQS_DP<4>")
	)
	(segment
		(start 284.344364 -0.076454)
		(end 284.344364 -0.380746)
		(width 0.14224)
		(layer "In11.Cu")
		(net "M_C_DQS_DP<4>")
	)
	(segment
		(start 284.69971 0.0762)
		(end 284.497018 0.0762)
		(width 0.14224)
		(layer "In11.Cu")
		(net "M_C_DQS_DP<4>")
	)
	(segment
		(start 284.696408 -1.27)
		(end 284.569408 -1.27)
		(width 0.14224)
		(layer "In11.Cu")
		(net "M_C_DQS_DP<4>")
	)
	(segment
		(start 274.393914 -56.679846)
		(end 274.402804 -56.695086)
		(width 0.0889)
		(layer "In11.Cu")
		(net "M_C_DQS_DP<4>")
	)
	(segment
		(start 274.402804 -59.076336)
		(end 274.396454 -59.087004)
		(width 0.0889)
		(layer "In11.Cu")
		(net "M_C_DQS_DP<4>")
	)
	(segment
		(start 284.33776 -3.026156)
		(end 283.899864 -3.464052)
		(width 0.14224)
		(layer "In11.Cu")
		(net "M_C_DQS_DP<4>")
	)
	(segment
		(start 284.391608 -1.7018)
		(end 284.569408 -1.8796)
		(width 0.14224)
		(layer "In11.Cu")
		(net "M_C_DQS_DP<4>")
	)
	(segment
		(start 274.114006 -61.253116)
		(end 274.056348 -61.195458)
		(width 0.0889)
		(layer "In11.Cu")
		(net "M_C_DQS_DP<4>")
	)
	(segment
		(start 275.390864 -39.563802)
		(end 275.390864 -42.65295)
		(width 0.14224)
		(layer "In11.Cu")
		(net "M_C_DQS_DP<4>")
	)
	(segment
		(start 284.864048 -30.090618)
		(end 275.390864 -39.563802)
		(width 0.14224)
		(layer "In11.Cu")
		(net "M_C_DQS_DP<4>")
	)
	(segment
		(start 284.33776 -3.02641)
		(end 284.33776 -3.026156)
		(width 0.14224)
		(layer "In11.Cu")
		(net "M_C_DQS_DP<4>")
	)
	(segment
		(start 275.276564 -42.76725)
		(end 275.276564 -43.02125)
		(width 0.14224)
		(layer "In11.Cu")
		(net "M_C_DQS_DP<4>")
	)
	(segment
		(start 275.22043 -47.348902)
		(end 275.22043 -47.371)
		(width 0.0889)
		(layer "In11.Cu")
		(net "M_C_DQS_DP<4>")
	)
	(segment
		(start 284.879288 -0.738378)
		(end 284.879288 -1.08712)
		(width 0.14224)
		(layer "In11.Cu")
		(net "M_C_DQS_DP<4>")
	)
	(segment
		(start 284.879288 -2.763774)
		(end 284.616652 -3.02641)
		(width 0.14224)
		(layer "In11.Cu")
		(net "M_C_DQS_DP<4>")
	)
	(segment
		(start 274.512278 -52.941982)
		(end 274.393914 -53.146706)
		(width 0.0889)
		(layer "In11.Cu")
		(net "M_C_DQS_DP<4>")
	)
	(segment
		(start 284.569408 -1.27)
		(end 284.391608 -1.4478)
		(width 0.14224)
		(layer "In11.Cu")
		(net "M_C_DQS_DP<4>")
	)
	(segment
		(start 274.807172 -48.592994)
		(end 274.807172 -52.167028)
		(width 0.0889)
		(layer "In11.Cu")
		(net "M_C_DQS_DP<4>")
	)
	(segment
		(start 283.899864 -4.627118)
		(end 284.019244 -4.746498)
		(width 0.14224)
		(layer "In11.Cu")
		(net "M_C_DQS_DP<4>")
	)
	(segment
		(start 284.879288 -2.058924)
		(end 284.879288 -2.763774)
		(width 0.14224)
		(layer "In11.Cu")
		(net "M_C_DQS_DP<4>")
	)
	(segment
		(start 274.396454 -58.665872)
		(end 274.402804 -58.67654)
		(width 0.0889)
		(layer "In11.Cu")
		(net "M_C_DQS_DP<4>")
	)
	(segment
		(start 275.390864 -45.731938)
		(end 275.276564 -45.846238)
		(width 0.14224)
		(layer "In11.Cu")
		(net "M_C_DQS_DP<4>")
	)
	(segment
		(start 284.619446 1.181354)
		(end 284.879288 0.921512)
		(width 0.14224)
		(layer "In11.Cu")
		(net "M_C_DQS_DP<4>")
	)
	(segment
		(start 284.569408 -1.8796)
		(end 284.699964 -1.8796)
		(width 0.14224)
		(layer "In11.Cu")
		(net "M_C_DQS_DP<4>")
	)
	(segment
		(start 275.276564 -43.99534)
		(end 275.390864 -44.10964)
		(width 0.14224)
		(layer "In11.Cu")
		(net "M_C_DQS_DP<4>")
	)
	(arc
		(start 274.402804 -55.704486)
		(mid 274.456337 -55.904384)
		(end 274.402804 -56.104282)
		(width 0.0889)
		(layer "In11.Cu")
		(net "M_C_DQS_DP<4>")
	)
	(arc
		(start 274.396454 -59.087004)
		(mid 274.323656 -59.377767)
		(end 274.402804 -59.666886)
		(width 0.0889)
		(layer "In11.Cu")
		(net "M_C_DQS_DP<4>")
	)
	(arc
		(start 274.402804 -60.066682)
		(mid 274.323615 -60.353297)
		(end 274.393914 -60.642246)
		(width 0.0889)
		(layer "In11.Cu")
		(net "M_C_DQS_DP<4>")
	)
	(arc
		(start 274.402804 -54.123336)
		(mid 274.323582 -54.412454)
		(end 274.396454 -54.703218)
		(width 0.0889)
		(layer "In11.Cu")
		(net "M_C_DQS_DP<4>")
	)
	(arc
		(start 274.402804 -54.713886)
		(mid 274.456337 -54.913784)
		(end 274.402804 -55.113682)
		(width 0.0889)
		(layer "In11.Cu")
		(net "M_C_DQS_DP<4>")
	)
	(arc
		(start 274.402804 -53.722778)
		(mid 274.4564 -53.918095)
		(end 274.40763 -54.1147)
		(width 0.0889)
		(layer "In11.Cu")
		(net "M_C_DQS_DP<4>")
	)
	(arc
		(start 274.402804 -57.094882)
		(mid 274.323615 -57.381497)
		(end 274.393914 -57.670446)
		(width 0.0889)
		(layer "In11.Cu")
		(net "M_C_DQS_DP<4>")
	)
	(arc
		(start 274.402804 -56.695086)
		(mid 274.456337 -56.894984)
		(end 274.402804 -57.094882)
		(width 0.0889)
		(layer "In11.Cu")
		(net "M_C_DQS_DP<4>")
	)
	(arc
		(start 274.402804 -57.685686)
		(mid 274.456337 -57.885584)
		(end 274.402804 -58.085482)
		(width 0.0889)
		(layer "In11.Cu")
		(net "M_C_DQS_DP<4>")
	)
	(arc
		(start 274.402804 -55.113682)
		(mid 274.323615 -55.400297)
		(end 274.393914 -55.689246)
		(width 0.0889)
		(layer "In11.Cu")
		(net "M_C_DQS_DP<4>")
	)
	(arc
		(start 274.402804 -59.666886)
		(mid 274.456337 -59.866784)
		(end 274.402804 -60.066682)
		(width 0.0889)
		(layer "In11.Cu")
		(net "M_C_DQS_DP<4>")
	)
	(arc
		(start 274.393914 -53.146706)
		(mid 274.323397 -53.435911)
		(end 274.402804 -53.722778)
		(width 0.0889)
		(layer "In11.Cu")
		(net "M_C_DQS_DP<4>")
	)
	(arc
		(start 274.402804 -56.104282)
		(mid 274.323615 -56.390897)
		(end 274.393914 -56.679846)
		(width 0.0889)
		(layer "In11.Cu")
		(net "M_C_DQS_DP<4>")
	)
	(arc
		(start 274.402804 -60.657486)
		(mid 274.416273 -61.031868)
		(end 274.114006 -61.253116)
		(width 0.0889)
		(layer "In11.Cu")
		(net "M_C_DQS_DP<4>")
	)
	(arc
		(start 274.402804 -58.67654)
		(mid 274.456337 -58.876438)
		(end 274.402804 -59.076336)
		(width 0.0889)
		(layer "In11.Cu")
		(net "M_C_DQS_DP<4>")
	)
	(arc
		(start 274.402804 -58.085482)
		(mid 274.323455 -58.374854)
		(end 274.396454 -58.665872)
		(width 0.0889)
		(layer "In11.Cu")
		(net "M_C_DQS_DP<4>")
	)
	(segment
		(start 229.54996 0.277622)
		(end 229.771448 0.49911)
		(width 0.1651)
		(layer "F.Cu")
		(net "M_C_DQS_DP<3>")
	)
	(segment
		(start 229.550468 -0.821182)
		(end 229.54996 -0.821182)
		(width 0.1651)
		(layer "F.Cu")
		(net "M_C_DQS_DP<3>")
	)
	(segment
		(start 249.919744 -66.48704)
		(end 249.348244 -66.48704)
		(width 0.0889)
		(layer "F.Cu")
		(net "M_C_DQS_DP<3>")
	)
	(segment
		(start 229.771448 0.49911)
		(end 229.771448 1.241298)
		(width 0.1651)
		(layer "F.Cu")
		(net "M_C_DQS_DP<3>")
	)
	(segment
		(start 229.54996 -0.821182)
		(end 229.54996 0.277622)
		(width 0.1651)
		(layer "F.Cu")
		(net "M_C_DQS_DP<3>")
	)
	(segment
		(start 229.55758 1.455166)
		(end 229.361746 1.455166)
		(width 0.1651)
		(layer "F.Cu")
		(net "M_C_DQS_DP<3>")
	)
	(segment
		(start 229.361746 1.455166)
		(end 229.087934 1.181354)
		(width 0.1651)
		(layer "F.Cu")
		(net "M_C_DQS_DP<3>")
	)
	(segment
		(start 229.771448 1.241298)
		(end 229.55758 1.455166)
		(width 0.1651)
		(layer "F.Cu")
		(net "M_C_DQS_DP<3>")
	)
	(via
		(at 229.087934 1.181354)
		(size 0.508)
		(drill 0.254)
		(layers "F.Cu" "B.Cu")
		(net "M_C_DQS_DP<3>")
	)
	(via
		(at 229.087934 -3.026156)
		(size 0.508)
		(drill 0.254)
		(layers "F.Cu" "B.Cu")
		(net "M_C_DQS_DP<3>")
	)
	(via
		(at 249.348244 -66.48704)
		(size 0.508)
		(drill 0.254)
		(layers "F.Cu" "B.Cu")
		(net "M_C_DQS_DP<3>")
	)
	(segment
		(start 229.729538 -2.7178)
		(end 229.729538 -3.16738)
		(width 0.1651)
		(layer "B.Cu")
		(net "M_C_DQS_DP<3>")
	)
	(segment
		(start 229.54996 -2.538222)
		(end 229.729538 -2.7178)
		(width 0.1651)
		(layer "B.Cu")
		(net "M_C_DQS_DP<3>")
	)
	(segment
		(start 229.368858 -3.30708)
		(end 229.087934 -3.026156)
		(width 0.1651)
		(layer "B.Cu")
		(net "M_C_DQS_DP<3>")
	)
	(segment
		(start 229.54996 -1.021842)
		(end 229.54996 -2.538222)
		(width 0.1651)
		(layer "B.Cu")
		(net "M_C_DQS_DP<3>")
	)
	(segment
		(start 229.729538 -3.16738)
		(end 229.589838 -3.30708)
		(width 0.1651)
		(layer "B.Cu")
		(net "M_C_DQS_DP<3>")
	)
	(segment
		(start 229.550468 -1.021842)
		(end 229.54996 -1.021842)
		(width 0.1651)
		(layer "B.Cu")
		(net "M_C_DQS_DP<3>")
	)
	(segment
		(start 229.589838 -3.30708)
		(end 229.368858 -3.30708)
		(width 0.1651)
		(layer "B.Cu")
		(net "M_C_DQS_DP<3>")
	)
	(segment
		(start 248.928636 -52.935886)
		(end 248.928636 -54.188106)
		(width 0.0889)
		(layer "In11.Cu")
		(net "M_C_DQS_DP<3>")
	)
	(segment
		(start 246.87022 -48.76927)
		(end 246.87022 -49.337722)
		(width 0.14224)
		(layer "In11.Cu")
		(net "M_C_DQS_DP<3>")
	)
	(segment
		(start 249.694954 -65.696338)
		(end 249.688604 -65.707006)
		(width 0.0889)
		(layer "In11.Cu")
		(net "M_C_DQS_DP<3>")
	)
	(segment
		(start 229.601014 -6.22427)
		(end 229.601014 -29.136086)
		(width 0.14224)
		(layer "In11.Cu")
		(net "M_C_DQS_DP<3>")
	)
	(segment
		(start 249.694954 -64.705738)
		(end 249.688604 -64.716406)
		(width 0.0889)
		(layer "In11.Cu")
		(net "M_C_DQS_DP<3>")
	)
	(segment
		(start 247.593866 -50.061114)
		(end 247.649238 -50.061114)
		(width 0.0889)
		(layer "In11.Cu")
		(net "M_C_DQS_DP<3>")
	)
	(segment
		(start 247.578372 -50.04562)
		(end 247.593866 -50.061114)
		(width 0.0889)
		(layer "In11.Cu")
		(net "M_C_DQS_DP<3>")
	)
	(segment
		(start 249.69978 -64.697102)
		(end 249.694954 -64.705738)
		(width 0.0889)
		(layer "In11.Cu")
		(net "M_C_DQS_DP<3>")
	)
	(segment
		(start 249.69978 -60.734702)
		(end 249.694954 -60.743338)
		(width 0.0889)
		(layer "In11.Cu")
		(net "M_C_DQS_DP<3>")
	)
	(segment
		(start 229.094538 -0.076454)
		(end 229.094538 -0.380746)
		(width 0.14224)
		(layer "In11.Cu")
		(net "M_C_DQS_DP<3>")
	)
	(segment
		(start 235.453682 -37.352732)
		(end 245.692422 -47.591472)
		(width 0.14224)
		(layer "In11.Cu")
		(net "M_C_DQS_DP<3>")
	)
	(segment
		(start 249.688604 -58.35142)
		(end 249.694954 -58.362088)
		(width 0.0889)
		(layer "In11.Cu")
		(net "M_C_DQS_DP<3>")
	)
	(segment
		(start 249.694954 -61.733938)
		(end 249.688604 -61.744606)
		(width 0.0889)
		(layer "In11.Cu")
		(net "M_C_DQS_DP<3>")
	)
	(segment
		(start 249.694954 -56.780938)
		(end 249.688604 -56.791606)
		(width 0.0889)
		(layer "In11.Cu")
		(net "M_C_DQS_DP<3>")
	)
	(segment
		(start 229.629462 -2.763774)
		(end 229.366826 -3.02641)
		(width 0.14224)
		(layer "In11.Cu")
		(net "M_C_DQS_DP<3>")
	)
	(segment
		(start 235.453682 -34.988754)
		(end 235.453682 -37.352732)
		(width 0.14224)
		(layer "In11.Cu")
		(net "M_C_DQS_DP<3>")
	)
	(segment
		(start 229.449884 0.0762)
		(end 229.247192 0.0762)
		(width 0.14224)
		(layer "In11.Cu")
		(net "M_C_DQS_DP<3>")
	)
	(segment
		(start 247.391174 -49.858676)
		(end 247.578372 -50.045874)
		(width 0.14224)
		(layer "In11.Cu")
		(net "M_C_DQS_DP<3>")
	)
	(segment
		(start 249.694954 -59.752738)
		(end 249.688604 -59.763406)
		(width 0.0889)
		(layer "In11.Cu")
		(net "M_C_DQS_DP<3>")
	)
	(segment
		(start 246.493792 -48.554386)
		(end 246.655336 -48.554386)
		(width 0.14224)
		(layer "In11.Cu")
		(net "M_C_DQS_DP<3>")
	)
	(segment
		(start 246.034052 -47.933102)
		(end 246.31396 -48.21301)
		(width 0.14224)
		(layer "In11.Cu")
		(net "M_C_DQS_DP<3>")
	)
	(segment
		(start 229.247192 0.0762)
		(end 229.094538 -0.076454)
		(width 0.14224)
		(layer "In11.Cu")
		(net "M_C_DQS_DP<3>")
	)
	(segment
		(start 249.694954 -60.743338)
		(end 249.688604 -60.754006)
		(width 0.0889)
		(layer "In11.Cu")
		(net "M_C_DQS_DP<3>")
	)
	(segment
		(start 229.601014 -29.136086)
		(end 235.453682 -34.988754)
		(width 0.14224)
		(layer "In11.Cu")
		(net "M_C_DQS_DP<3>")
	)
	(segment
		(start 246.655336 -48.554386)
		(end 246.87022 -48.76927)
		(width 0.14224)
		(layer "In11.Cu")
		(net "M_C_DQS_DP<3>")
	)
	(segment
		(start 248.928636 -54.188106)
		(end 249.193304 -54.452774)
		(width 0.0889)
		(layer "In11.Cu")
		(net "M_C_DQS_DP<3>")
	)
	(segment
		(start 247.747282 -51.754532)
		(end 248.928636 -52.935886)
		(width 0.0889)
		(layer "In11.Cu")
		(net "M_C_DQS_DP<3>")
	)
	(segment
		(start 229.629462 -1.08712)
		(end 229.446582 -1.27)
		(width 0.14224)
		(layer "In11.Cu")
		(net "M_C_DQS_DP<3>")
	)
	(segment
		(start 249.69978 -55.781702)
		(end 249.694954 -55.790338)
		(width 0.0889)
		(layer "In11.Cu")
		(net "M_C_DQS_DP<3>")
	)
	(segment
		(start 228.769418 -5.392674)
		(end 229.601014 -6.22427)
		(width 0.14224)
		(layer "In11.Cu")
		(net "M_C_DQS_DP<3>")
	)
	(segment
		(start 245.692422 -47.75327)
		(end 245.872254 -47.933102)
		(width 0.14224)
		(layer "In11.Cu")
		(net "M_C_DQS_DP<3>")
	)
	(segment
		(start 229.446582 -1.27)
		(end 229.319582 -1.27)
		(width 0.14224)
		(layer "In11.Cu")
		(net "M_C_DQS_DP<3>")
	)
	(segment
		(start 246.31396 -48.21301)
		(end 246.31396 -48.374554)
		(width 0.14224)
		(layer "In11.Cu")
		(net "M_C_DQS_DP<3>")
	)
	(segment
		(start 249.694954 -63.715138)
		(end 249.688604 -63.725806)
		(width 0.0889)
		(layer "In11.Cu")
		(net "M_C_DQS_DP<3>")
	)
	(segment
		(start 229.247192 -0.5334)
		(end 229.424484 -0.5334)
		(width 0.14224)
		(layer "In11.Cu")
		(net "M_C_DQS_DP<3>")
	)
	(segment
		(start 229.319582 -1.8796)
		(end 229.450138 -1.8796)
		(width 0.14224)
		(layer "In11.Cu")
		(net "M_C_DQS_DP<3>")
	)
	(segment
		(start 228.769418 -4.716018)
		(end 228.769418 -5.392674)
		(width 0.14224)
		(layer "In11.Cu")
		(net "M_C_DQS_DP<3>")
	)
	(segment
		(start 249.69978 -65.687702)
		(end 249.694954 -65.696338)
		(width 0.0889)
		(layer "In11.Cu")
		(net "M_C_DQS_DP<3>")
	)
	(segment
		(start 249.193304 -54.452774)
		(end 249.193304 -54.869334)
		(width 0.0889)
		(layer "In11.Cu")
		(net "M_C_DQS_DP<3>")
	)
	(segment
		(start 229.450138 -1.8796)
		(end 229.629462 -2.058924)
		(width 0.14224)
		(layer "In11.Cu")
		(net "M_C_DQS_DP<3>")
	)
	(segment
		(start 228.650038 -4.596638)
		(end 228.769418 -4.716018)
		(width 0.14224)
		(layer "In11.Cu")
		(net "M_C_DQS_DP<3>")
	)
	(segment
		(start 249.193304 -54.869334)
		(end 249.668538 -55.344568)
		(width 0.0889)
		(layer "In11.Cu")
		(net "M_C_DQS_DP<3>")
	)
	(segment
		(start 229.087934 -3.02641)
		(end 229.087934 -3.026156)
		(width 0.14224)
		(layer "In11.Cu")
		(net "M_C_DQS_DP<3>")
	)
	(segment
		(start 247.049798 -49.678844)
		(end 247.22963 -49.858676)
		(width 0.14224)
		(layer "In11.Cu")
		(net "M_C_DQS_DP<3>")
	)
	(segment
		(start 229.087934 1.181354)
		(end 229.36962 1.181354)
		(width 0.14224)
		(layer "In11.Cu")
		(net "M_C_DQS_DP<3>")
	)
	(segment
		(start 249.69978 -57.762902)
		(end 249.694954 -57.771538)
		(width 0.0889)
		(layer "In11.Cu")
		(net "M_C_DQS_DP<3>")
	)
	(segment
		(start 245.692422 -47.591472)
		(end 245.692422 -47.75327)
		(width 0.14224)
		(layer "In11.Cu")
		(net "M_C_DQS_DP<3>")
	)
	(segment
		(start 246.87022 -49.337722)
		(end 247.049798 -49.5173)
		(width 0.14224)
		(layer "In11.Cu")
		(net "M_C_DQS_DP<3>")
	)
	(segment
		(start 247.049798 -49.5173)
		(end 247.049798 -49.678844)
		(width 0.14224)
		(layer "In11.Cu")
		(net "M_C_DQS_DP<3>")
	)
	(segment
		(start 249.694954 -62.724538)
		(end 249.688604 -62.735206)
		(width 0.0889)
		(layer "In11.Cu")
		(net "M_C_DQS_DP<3>")
	)
	(segment
		(start 249.69978 -56.772302)
		(end 249.694954 -56.780938)
		(width 0.0889)
		(layer "In11.Cu")
		(net "M_C_DQS_DP<3>")
	)
	(segment
		(start 229.629462 0.255778)
		(end 229.449884 0.0762)
		(width 0.14224)
		(layer "In11.Cu")
		(net "M_C_DQS_DP<3>")
	)
	(segment
		(start 229.094538 -0.380746)
		(end 229.247192 -0.5334)
		(width 0.14224)
		(layer "In11.Cu")
		(net "M_C_DQS_DP<3>")
	)
	(segment
		(start 229.141782 -1.7018)
		(end 229.319582 -1.8796)
		(width 0.14224)
		(layer "In11.Cu")
		(net "M_C_DQS_DP<3>")
	)
	(segment
		(start 247.649238 -50.061114)
		(end 247.747282 -50.159158)
		(width 0.0889)
		(layer "In11.Cu")
		(net "M_C_DQS_DP<3>")
	)
	(segment
		(start 249.69978 -59.744102)
		(end 249.694954 -59.752738)
		(width 0.0889)
		(layer "In11.Cu")
		(net "M_C_DQS_DP<3>")
	)
	(segment
		(start 249.694954 -55.790338)
		(end 249.688604 -55.801006)
		(width 0.0889)
		(layer "In11.Cu")
		(net "M_C_DQS_DP<3>")
	)
	(segment
		(start 229.629462 -2.058924)
		(end 229.629462 -2.763774)
		(width 0.14224)
		(layer "In11.Cu")
		(net "M_C_DQS_DP<3>")
	)
	(segment
		(start 229.629462 -0.738378)
		(end 229.629462 -1.08712)
		(width 0.14224)
		(layer "In11.Cu")
		(net "M_C_DQS_DP<3>")
	)
	(segment
		(start 229.424484 -0.5334)
		(end 229.629462 -0.738378)
		(width 0.14224)
		(layer "In11.Cu")
		(net "M_C_DQS_DP<3>")
	)
	(segment
		(start 247.578372 -50.045874)
		(end 247.578372 -50.04562)
		(width 0.0889)
		(layer "In11.Cu")
		(net "M_C_DQS_DP<3>")
	)
	(segment
		(start 228.650038 -3.464052)
		(end 228.650038 -4.596638)
		(width 0.14224)
		(layer "In11.Cu")
		(net "M_C_DQS_DP<3>")
	)
	(segment
		(start 249.69978 -62.715902)
		(end 249.694954 -62.724538)
		(width 0.0889)
		(layer "In11.Cu")
		(net "M_C_DQS_DP<3>")
	)
	(segment
		(start 229.629462 0.921512)
		(end 229.629462 0.255778)
		(width 0.14224)
		(layer "In11.Cu")
		(net "M_C_DQS_DP<3>")
	)
	(segment
		(start 249.348244 -66.825114)
		(end 249.348244 -66.48704)
		(width 0.0889)
		(layer "In11.Cu")
		(net "M_C_DQS_DP<3>")
	)
	(segment
		(start 249.406156 -66.883026)
		(end 249.348244 -66.825114)
		(width 0.0889)
		(layer "In11.Cu")
		(net "M_C_DQS_DP<3>")
	)
	(segment
		(start 246.31396 -48.374554)
		(end 246.493792 -48.554386)
		(width 0.14224)
		(layer "In11.Cu")
		(net "M_C_DQS_DP<3>")
	)
	(segment
		(start 229.319582 -1.27)
		(end 229.141782 -1.4478)
		(width 0.14224)
		(layer "In11.Cu")
		(net "M_C_DQS_DP<3>")
	)
	(segment
		(start 247.22963 -49.858676)
		(end 247.391174 -49.858676)
		(width 0.14224)
		(layer "In11.Cu")
		(net "M_C_DQS_DP<3>")
	)
	(segment
		(start 229.087934 -3.026156)
		(end 228.650038 -3.464052)
		(width 0.14224)
		(layer "In11.Cu")
		(net "M_C_DQS_DP<3>")
	)
	(segment
		(start 229.366826 -3.02641)
		(end 229.087934 -3.02641)
		(width 0.14224)
		(layer "In11.Cu")
		(net "M_C_DQS_DP<3>")
	)
	(segment
		(start 249.668538 -55.344568)
		(end 249.694954 -55.390288)
		(width 0.0889)
		(layer "In11.Cu")
		(net "M_C_DQS_DP<3>")
	)
	(segment
		(start 245.872254 -47.933102)
		(end 246.034052 -47.933102)
		(width 0.14224)
		(layer "In11.Cu")
		(net "M_C_DQS_DP<3>")
	)
	(segment
		(start 247.747282 -50.159158)
		(end 247.747282 -51.754532)
		(width 0.0889)
		(layer "In11.Cu")
		(net "M_C_DQS_DP<3>")
	)
	(segment
		(start 249.69978 -61.725302)
		(end 249.694954 -61.733938)
		(width 0.0889)
		(layer "In11.Cu")
		(net "M_C_DQS_DP<3>")
	)
	(segment
		(start 249.69978 -63.706502)
		(end 249.694954 -63.715138)
		(width 0.0889)
		(layer "In11.Cu")
		(net "M_C_DQS_DP<3>")
	)
	(segment
		(start 229.36962 1.181354)
		(end 229.629462 0.921512)
		(width 0.14224)
		(layer "In11.Cu")
		(net "M_C_DQS_DP<3>")
	)
	(segment
		(start 229.141782 -1.4478)
		(end 229.141782 -1.7018)
		(width 0.14224)
		(layer "In11.Cu")
		(net "M_C_DQS_DP<3>")
	)
	(arc
		(start 249.688604 -59.763406)
		(mid 249.615806 -60.054169)
		(end 249.694954 -60.343288)
		(width 0.0889)
		(layer "In11.Cu")
		(net "M_C_DQS_DP<3>")
	)
	(arc
		(start 249.694954 -57.771538)
		(mid 249.615732 -58.060656)
		(end 249.688604 -58.35142)
		(width 0.0889)
		(layer "In11.Cu")
		(net "M_C_DQS_DP<3>")
	)
	(arc
		(start 249.688604 -56.791606)
		(mid 249.615806 -57.082369)
		(end 249.694954 -57.371488)
		(width 0.0889)
		(layer "In11.Cu")
		(net "M_C_DQS_DP<3>")
	)
	(arc
		(start 249.694954 -59.352688)
		(mid 249.748424 -59.547751)
		(end 249.69978 -59.744102)
		(width 0.0889)
		(layer "In11.Cu")
		(net "M_C_DQS_DP<3>")
	)
	(arc
		(start 249.694954 -62.324488)
		(mid 249.748424 -62.519551)
		(end 249.69978 -62.715902)
		(width 0.0889)
		(layer "In11.Cu")
		(net "M_C_DQS_DP<3>")
	)
	(arc
		(start 249.688604 -61.744606)
		(mid 249.615806 -62.035369)
		(end 249.694954 -62.324488)
		(width 0.0889)
		(layer "In11.Cu")
		(net "M_C_DQS_DP<3>")
	)
	(arc
		(start 249.694954 -58.362088)
		(mid 249.748453 -58.561986)
		(end 249.694954 -58.761884)
		(width 0.0889)
		(layer "In11.Cu")
		(net "M_C_DQS_DP<3>")
	)
	(arc
		(start 249.694954 -58.761884)
		(mid 249.615823 -59.057286)
		(end 249.694954 -59.352688)
		(width 0.0889)
		(layer "In11.Cu")
		(net "M_C_DQS_DP<3>")
	)
	(arc
		(start 249.694954 -66.286888)
		(mid 249.708549 -66.661537)
		(end 249.406156 -66.883026)
		(width 0.0889)
		(layer "In11.Cu")
		(net "M_C_DQS_DP<3>")
	)
	(arc
		(start 249.688604 -55.801006)
		(mid 249.615806 -56.091769)
		(end 249.694954 -56.380888)
		(width 0.0889)
		(layer "In11.Cu")
		(net "M_C_DQS_DP<3>")
	)
	(arc
		(start 249.694954 -65.296288)
		(mid 249.748424 -65.491351)
		(end 249.69978 -65.687702)
		(width 0.0889)
		(layer "In11.Cu")
		(net "M_C_DQS_DP<3>")
	)
	(arc
		(start 249.694954 -57.371488)
		(mid 249.748424 -57.566551)
		(end 249.69978 -57.762902)
		(width 0.0889)
		(layer "In11.Cu")
		(net "M_C_DQS_DP<3>")
	)
	(arc
		(start 249.688604 -64.716406)
		(mid 249.615806 -65.007169)
		(end 249.694954 -65.296288)
		(width 0.0889)
		(layer "In11.Cu")
		(net "M_C_DQS_DP<3>")
	)
	(arc
		(start 249.688604 -63.725806)
		(mid 249.615806 -64.016569)
		(end 249.694954 -64.305688)
		(width 0.0889)
		(layer "In11.Cu")
		(net "M_C_DQS_DP<3>")
	)
	(arc
		(start 249.694954 -64.305688)
		(mid 249.748424 -64.500751)
		(end 249.69978 -64.697102)
		(width 0.0889)
		(layer "In11.Cu")
		(net "M_C_DQS_DP<3>")
	)
	(arc
		(start 249.694954 -61.333888)
		(mid 249.748424 -61.528951)
		(end 249.69978 -61.725302)
		(width 0.0889)
		(layer "In11.Cu")
		(net "M_C_DQS_DP<3>")
	)
	(arc
		(start 249.688604 -62.735206)
		(mid 249.615806 -63.025969)
		(end 249.694954 -63.315088)
		(width 0.0889)
		(layer "In11.Cu")
		(net "M_C_DQS_DP<3>")
	)
	(arc
		(start 249.688604 -60.754006)
		(mid 249.615806 -61.044769)
		(end 249.694954 -61.333888)
		(width 0.0889)
		(layer "In11.Cu")
		(net "M_C_DQS_DP<3>")
	)
	(arc
		(start 249.694954 -55.390288)
		(mid 249.748424 -55.585351)
		(end 249.69978 -55.781702)
		(width 0.0889)
		(layer "In11.Cu")
		(net "M_C_DQS_DP<3>")
	)
	(arc
		(start 249.694954 -56.380888)
		(mid 249.748424 -56.575951)
		(end 249.69978 -56.772302)
		(width 0.0889)
		(layer "In11.Cu")
		(net "M_C_DQS_DP<3>")
	)
	(arc
		(start 249.694954 -60.343288)
		(mid 249.748424 -60.538351)
		(end 249.69978 -60.734702)
		(width 0.0889)
		(layer "In11.Cu")
		(net "M_C_DQS_DP<3>")
	)
	(arc
		(start 249.694954 -63.315088)
		(mid 249.748424 -63.510151)
		(end 249.69978 -63.706502)
		(width 0.0889)
		(layer "In11.Cu")
		(net "M_C_DQS_DP<3>")
	)
	(arc
		(start 249.688604 -65.707006)
		(mid 249.615806 -65.997769)
		(end 249.694954 -66.286888)
		(width 0.0889)
		(layer "In11.Cu")
		(net "M_C_DQS_DP<3>")
	)
	(segment
		(start 220.011752 1.455166)
		(end 219.73794 1.181354)
		(width 0.1651)
		(layer "F.Cu")
		(net "M_C_DQS_DP<2>")
	)
	(segment
		(start 220.199966 0.277622)
		(end 220.421454 0.49911)
		(width 0.1651)
		(layer "F.Cu")
		(net "M_C_DQS_DP<2>")
	)
	(segment
		(start 220.207586 1.455166)
		(end 220.011752 1.455166)
		(width 0.1651)
		(layer "F.Cu")
		(net "M_C_DQS_DP<2>")
	)
	(segment
		(start 220.200474 -0.821182)
		(end 220.199966 -0.821182)
		(width 0.1651)
		(layer "F.Cu")
		(net "M_C_DQS_DP<2>")
	)
	(segment
		(start 220.421454 0.49911)
		(end 220.421454 1.241298)
		(width 0.1651)
		(layer "F.Cu")
		(net "M_C_DQS_DP<2>")
	)
	(segment
		(start 246.485664 -58.561986)
		(end 245.914164 -58.561986)
		(width 0.0889)
		(layer "F.Cu")
		(net "M_C_DQS_DP<2>")
	)
	(segment
		(start 220.199966 -0.821182)
		(end 220.199966 0.277622)
		(width 0.1651)
		(layer "F.Cu")
		(net "M_C_DQS_DP<2>")
	)
	(segment
		(start 220.421454 1.241298)
		(end 220.207586 1.455166)
		(width 0.1651)
		(layer "F.Cu")
		(net "M_C_DQS_DP<2>")
	)
	(via
		(at 219.73794 1.181354)
		(size 0.508)
		(drill 0.254)
		(layers "F.Cu" "B.Cu")
		(net "M_C_DQS_DP<2>")
	)
	(via
		(at 245.914164 -58.561986)
		(size 0.508)
		(drill 0.254)
		(layers "F.Cu" "B.Cu")
		(net "M_C_DQS_DP<2>")
	)
	(via
		(at 219.73794 -3.026156)
		(size 0.508)
		(drill 0.254)
		(layers "F.Cu" "B.Cu")
		(net "M_C_DQS_DP<2>")
	)
	(segment
		(start 220.018864 -3.30708)
		(end 219.73794 -3.026156)
		(width 0.1651)
		(layer "B.Cu")
		(net "M_C_DQS_DP<2>")
	)
	(segment
		(start 220.379544 -2.7178)
		(end 220.379544 -3.16738)
		(width 0.1651)
		(layer "B.Cu")
		(net "M_C_DQS_DP<2>")
	)
	(segment
		(start 220.199966 -1.021842)
		(end 220.199966 -2.538222)
		(width 0.1651)
		(layer "B.Cu")
		(net "M_C_DQS_DP<2>")
	)
	(segment
		(start 220.239844 -3.30708)
		(end 220.018864 -3.30708)
		(width 0.1651)
		(layer "B.Cu")
		(net "M_C_DQS_DP<2>")
	)
	(segment
		(start 220.200474 -1.021842)
		(end 220.199966 -1.021842)
		(width 0.1651)
		(layer "B.Cu")
		(net "M_C_DQS_DP<2>")
	)
	(segment
		(start 220.379544 -3.16738)
		(end 220.239844 -3.30708)
		(width 0.1651)
		(layer "B.Cu")
		(net "M_C_DQS_DP<2>")
	)
	(segment
		(start 220.199966 -2.538222)
		(end 220.379544 -2.7178)
		(width 0.1651)
		(layer "B.Cu")
		(net "M_C_DQS_DP<2>")
	)
	(segment
		(start 220.100144 -1.8796)
		(end 220.279468 -2.058924)
		(width 0.14224)
		(layer "In11.Cu")
		(net "M_C_DQS_DP<2>")
	)
	(segment
		(start 220.279468 -1.08712)
		(end 220.096588 -1.27)
		(width 0.14224)
		(layer "In11.Cu")
		(net "M_C_DQS_DP<2>")
	)
	(segment
		(start 219.897198 0.0762)
		(end 219.744544 -0.076454)
		(width 0.14224)
		(layer "In11.Cu")
		(net "M_C_DQS_DP<2>")
	)
	(segment
		(start 236.652816 -50.637694)
		(end 236.82198 -50.940462)
		(width 0.0889)
		(layer "In11.Cu")
		(net "M_C_DQS_DP<2>")
	)
	(segment
		(start 245.892574 -58.16219)
		(end 245.932198 -58.16219)
		(width 0.0889)
		(layer "In11.Cu")
		(net "M_C_DQS_DP<2>")
	)
	(segment
		(start 235.712254 -49.753012)
		(end 236.217968 -50.258726)
		(width 0.14224)
		(layer "In11.Cu")
		(net "M_C_DQS_DP<2>")
	)
	(segment
		(start 220.279468 0.255778)
		(end 220.09989 0.0762)
		(width 0.14224)
		(layer "In11.Cu")
		(net "M_C_DQS_DP<2>")
	)
	(segment
		(start 219.791788 -1.4478)
		(end 219.791788 -1.7018)
		(width 0.14224)
		(layer "In11.Cu")
		(net "M_C_DQS_DP<2>")
	)
	(segment
		(start 220.279468 0.921512)
		(end 220.279468 0.255778)
		(width 0.14224)
		(layer "In11.Cu")
		(net "M_C_DQS_DP<2>")
	)
	(segment
		(start 219.300044 -4.64439)
		(end 219.419424 -4.76377)
		(width 0.14224)
		(layer "In11.Cu")
		(net "M_C_DQS_DP<2>")
	)
	(segment
		(start 220.09989 0.0762)
		(end 219.897198 0.0762)
		(width 0.14224)
		(layer "In11.Cu")
		(net "M_C_DQS_DP<2>")
	)
	(segment
		(start 220.096588 -1.27)
		(end 219.969588 -1.27)
		(width 0.14224)
		(layer "In11.Cu")
		(net "M_C_DQS_DP<2>")
	)
	(segment
		(start 242.462558 -56.18099)
		(end 242.480338 -56.18099)
		(width 0.0889)
		(layer "In11.Cu")
		(net "M_C_DQS_DP<2>")
	)
	(segment
		(start 219.419424 -4.76377)
		(end 219.419424 -5.392674)
		(width 0.14224)
		(layer "In11.Cu")
		(net "M_C_DQS_DP<2>")
	)
	(segment
		(start 220.279468 -2.763774)
		(end 220.016832 -3.02641)
		(width 0.14224)
		(layer "In11.Cu")
		(net "M_C_DQS_DP<2>")
	)
	(segment
		(start 244.179344 -57.17159)
		(end 244.21211 -57.17159)
		(width 0.0889)
		(layer "In11.Cu")
		(net "M_C_DQS_DP<2>")
	)
	(segment
		(start 220.25102 -33.613598)
		(end 232.428288 -45.790866)
		(width 0.14224)
		(layer "In11.Cu")
		(net "M_C_DQS_DP<2>")
	)
	(segment
		(start 220.016832 -3.02641)
		(end 219.73794 -3.02641)
		(width 0.14224)
		(layer "In11.Cu")
		(net "M_C_DQS_DP<2>")
	)
	(segment
		(start 241.600228 -55.685436)
		(end 241.632994 -55.685436)
		(width 0.0889)
		(layer "In11.Cu")
		(net "M_C_DQS_DP<2>")
	)
	(segment
		(start 219.300044 -3.464052)
		(end 219.300044 -4.64439)
		(width 0.14224)
		(layer "In11.Cu")
		(net "M_C_DQS_DP<2>")
	)
	(segment
		(start 243.313712 -56.676036)
		(end 243.34978 -56.676036)
		(width 0.0889)
		(layer "In11.Cu")
		(net "M_C_DQS_DP<2>")
	)
	(segment
		(start 245.04269 -57.66689)
		(end 245.06682 -57.66689)
		(width 0.0889)
		(layer "In11.Cu")
		(net "M_C_DQS_DP<2>")
	)
	(segment
		(start 234.122722 -48.472344)
		(end 235.712254 -49.753012)
		(width 0.14224)
		(layer "In11.Cu")
		(net "M_C_DQS_DP<2>")
	)
	(segment
		(start 236.289596 -50.274474)
		(end 236.652816 -50.637694)
		(width 0.0889)
		(layer "In11.Cu")
		(net "M_C_DQS_DP<2>")
	)
	(segment
		(start 236.233716 -50.274474)
		(end 236.289596 -50.274474)
		(width 0.0889)
		(layer "In11.Cu")
		(net "M_C_DQS_DP<2>")
	)
	(segment
		(start 246.28602 -58.70956)
		(end 246.20728 -58.730896)
		(width 0.0889)
		(layer "In11.Cu")
		(net "M_C_DQS_DP<2>")
	)
	(segment
		(start 237.316264 -53.20919)
		(end 237.344204 -53.20919)
		(width 0.0889)
		(layer "In11.Cu")
		(net "M_C_DQS_DP<2>")
	)
	(segment
		(start 219.73794 -3.02641)
		(end 219.73794 -3.026156)
		(width 0.14224)
		(layer "In11.Cu")
		(net "M_C_DQS_DP<2>")
	)
	(segment
		(start 232.428288 -46.77791)
		(end 234.122722 -48.472344)
		(width 0.14224)
		(layer "In11.Cu")
		(net "M_C_DQS_DP<2>")
	)
	(segment
		(start 220.25102 -6.22427)
		(end 220.25102 -33.613598)
		(width 0.14224)
		(layer "In11.Cu")
		(net "M_C_DQS_DP<2>")
	)
	(segment
		(start 219.73794 1.181354)
		(end 220.019626 1.181354)
		(width 0.14224)
		(layer "In11.Cu")
		(net "M_C_DQS_DP<2>")
	)
	(segment
		(start 239.028478 -54.19979)
		(end 239.061244 -54.19979)
		(width 0.0889)
		(layer "In11.Cu")
		(net "M_C_DQS_DP<2>")
	)
	(segment
		(start 220.019626 1.181354)
		(end 220.279468 0.921512)
		(width 0.14224)
		(layer "In11.Cu")
		(net "M_C_DQS_DP<2>")
	)
	(segment
		(start 236.217968 -50.258726)
		(end 236.233716 -50.274474)
		(width 0.0889)
		(layer "In11.Cu")
		(net "M_C_DQS_DP<2>")
	)
	(segment
		(start 240.745518 -55.19039)
		(end 240.778284 -55.19039)
		(width 0.0889)
		(layer "In11.Cu")
		(net "M_C_DQS_DP<2>")
	)
	(segment
		(start 238.166148 -53.704236)
		(end 238.198914 -53.704236)
		(width 0.0889)
		(layer "In11.Cu")
		(net "M_C_DQS_DP<2>")
	)
	(segment
		(start 239.883188 -54.694836)
		(end 239.915954 -54.694836)
		(width 0.0889)
		(layer "In11.Cu")
		(net "M_C_DQS_DP<2>")
	)
	(segment
		(start 219.897198 -0.5334)
		(end 220.07449 -0.5334)
		(width 0.14224)
		(layer "In11.Cu")
		(net "M_C_DQS_DP<2>")
	)
	(segment
		(start 219.744544 -0.076454)
		(end 219.744544 -0.380746)
		(width 0.14224)
		(layer "In11.Cu")
		(net "M_C_DQS_DP<2>")
	)
	(segment
		(start 219.73794 -3.026156)
		(end 219.300044 -3.464052)
		(width 0.14224)
		(layer "In11.Cu")
		(net "M_C_DQS_DP<2>")
	)
	(segment
		(start 232.428288 -45.790866)
		(end 232.428288 -46.77791)
		(width 0.14224)
		(layer "In11.Cu")
		(net "M_C_DQS_DP<2>")
	)
	(segment
		(start 236.817408 -52.323238)
		(end 236.811058 -52.333906)
		(width 0.0889)
		(layer "In11.Cu")
		(net "M_C_DQS_DP<2>")
	)
	(segment
		(start 220.07449 -0.5334)
		(end 220.279468 -0.738378)
		(width 0.14224)
		(layer "In11.Cu")
		(net "M_C_DQS_DP<2>")
	)
	(segment
		(start 219.744544 -0.380746)
		(end 219.897198 -0.5334)
		(width 0.14224)
		(layer "In11.Cu")
		(net "M_C_DQS_DP<2>")
	)
	(segment
		(start 242.823492 -56.3753)
		(end 242.826794 -56.381142)
		(width 0.0889)
		(layer "In11.Cu")
		(net "M_C_DQS_DP<2>")
	)
	(segment
		(start 220.279468 -0.738378)
		(end 220.279468 -1.08712)
		(width 0.14224)
		(layer "In11.Cu")
		(net "M_C_DQS_DP<2>")
	)
	(segment
		(start 219.419424 -5.392674)
		(end 220.25102 -6.22427)
		(width 0.14224)
		(layer "In11.Cu")
		(net "M_C_DQS_DP<2>")
	)
	(segment
		(start 219.791788 -1.7018)
		(end 219.969588 -1.8796)
		(width 0.14224)
		(layer "In11.Cu")
		(net "M_C_DQS_DP<2>")
	)
	(segment
		(start 246.20728 -58.730896)
		(end 245.914164 -58.561986)
		(width 0.0889)
		(layer "In11.Cu")
		(net "M_C_DQS_DP<2>")
	)
	(segment
		(start 220.279468 -2.058924)
		(end 220.279468 -2.763774)
		(width 0.14224)
		(layer "In11.Cu")
		(net "M_C_DQS_DP<2>")
	)
	(segment
		(start 219.969588 -1.27)
		(end 219.791788 -1.4478)
		(width 0.14224)
		(layer "In11.Cu")
		(net "M_C_DQS_DP<2>")
	)
	(segment
		(start 219.969588 -1.8796)
		(end 220.100144 -1.8796)
		(width 0.14224)
		(layer "In11.Cu")
		(net "M_C_DQS_DP<2>")
	)
	(arc
		(start 241.968528 -55.885588)
		(mid 242.177136 -56.09752)
		(end 242.462558 -56.18099)
		(width 0.0889)
		(layer "In11.Cu")
		(net "M_C_DQS_DP<2>")
	)
	(arc
		(start 241.632994 -55.685436)
		(mid 241.826844 -55.741786)
		(end 241.968528 -55.885588)
		(width 0.0889)
		(layer "In11.Cu")
		(net "M_C_DQS_DP<2>")
	)
	(arc
		(start 243.685314 -56.876188)
		(mid 243.893922 -57.08812)
		(end 244.179344 -57.17159)
		(width 0.0889)
		(layer "In11.Cu")
		(net "M_C_DQS_DP<2>")
	)
	(arc
		(start 244.543834 -57.371488)
		(mid 244.754547 -57.584567)
		(end 245.04269 -57.66689)
		(width 0.0889)
		(layer "In11.Cu")
		(net "M_C_DQS_DP<2>")
	)
	(arc
		(start 240.251488 -54.894988)
		(mid 240.460096 -55.10692)
		(end 240.745518 -55.19039)
		(width 0.0889)
		(layer "In11.Cu")
		(net "M_C_DQS_DP<2>")
	)
	(arc
		(start 237.344204 -53.20919)
		(mid 237.535846 -53.266356)
		(end 237.675928 -53.409088)
		(width 0.0889)
		(layer "In11.Cu")
		(net "M_C_DQS_DP<2>")
	)
	(arc
		(start 239.061244 -54.19979)
		(mid 239.252886 -54.256956)
		(end 239.392968 -54.399688)
		(width 0.0889)
		(layer "In11.Cu")
		(net "M_C_DQS_DP<2>")
	)
	(arc
		(start 238.534448 -53.904388)
		(mid 238.743056 -54.11632)
		(end 239.028478 -54.19979)
		(width 0.0889)
		(layer "In11.Cu")
		(net "M_C_DQS_DP<2>")
	)
	(arc
		(start 236.82198 -50.940462)
		(mid 236.871011 -51.137149)
		(end 236.817408 -51.332638)
		(width 0.0889)
		(layer "In11.Cu")
		(net "M_C_DQS_DP<2>")
	)
	(arc
		(start 245.06682 -57.66689)
		(mid 245.26067 -57.72324)
		(end 245.402354 -57.867042)
		(width 0.0889)
		(layer "In11.Cu")
		(net "M_C_DQS_DP<2>")
	)
	(arc
		(start 236.817408 -51.923442)
		(mid 236.870907 -52.12334)
		(end 236.817408 -52.323238)
		(width 0.0889)
		(layer "In11.Cu")
		(net "M_C_DQS_DP<2>")
	)
	(arc
		(start 237.675928 -53.409088)
		(mid 237.882932 -53.619952)
		(end 238.166148 -53.704236)
		(width 0.0889)
		(layer "In11.Cu")
		(net "M_C_DQS_DP<2>")
	)
	(arc
		(start 239.915954 -54.694836)
		(mid 240.109804 -54.751186)
		(end 240.251488 -54.894988)
		(width 0.0889)
		(layer "In11.Cu")
		(net "M_C_DQS_DP<2>")
	)
	(arc
		(start 236.817408 -51.332638)
		(mid 236.738277 -51.62804)
		(end 236.817408 -51.923442)
		(width 0.0889)
		(layer "In11.Cu")
		(net "M_C_DQS_DP<2>")
	)
	(arc
		(start 239.392968 -54.399688)
		(mid 239.599972 -54.610552)
		(end 239.883188 -54.694836)
		(width 0.0889)
		(layer "In11.Cu")
		(net "M_C_DQS_DP<2>")
	)
	(arc
		(start 245.932198 -58.16219)
		(mid 246.250237 -58.344691)
		(end 246.28602 -58.70956)
		(width 0.0889)
		(layer "In11.Cu")
		(net "M_C_DQS_DP<2>")
	)
	(arc
		(start 242.826794 -56.381142)
		(mid 243.032415 -56.591065)
		(end 243.313712 -56.676036)
		(width 0.0889)
		(layer "In11.Cu")
		(net "M_C_DQS_DP<2>")
	)
	(arc
		(start 241.110008 -55.390288)
		(mid 241.317012 -55.601152)
		(end 241.600228 -55.685436)
		(width 0.0889)
		(layer "In11.Cu")
		(net "M_C_DQS_DP<2>")
	)
	(arc
		(start 242.480338 -56.18099)
		(mid 242.677499 -56.232949)
		(end 242.823492 -56.3753)
		(width 0.0889)
		(layer "In11.Cu")
		(net "M_C_DQS_DP<2>")
	)
	(arc
		(start 245.402354 -57.867042)
		(mid 245.609358 -58.077906)
		(end 245.892574 -58.16219)
		(width 0.0889)
		(layer "In11.Cu")
		(net "M_C_DQS_DP<2>")
	)
	(arc
		(start 236.811058 -52.333906)
		(mid 236.817235 -52.913838)
		(end 237.316264 -53.20919)
		(width 0.0889)
		(layer "In11.Cu")
		(net "M_C_DQS_DP<2>")
	)
	(arc
		(start 238.198914 -53.704236)
		(mid 238.392764 -53.760586)
		(end 238.534448 -53.904388)
		(width 0.0889)
		(layer "In11.Cu")
		(net "M_C_DQS_DP<2>")
	)
	(arc
		(start 243.34978 -56.676036)
		(mid 243.54363 -56.732386)
		(end 243.685314 -56.876188)
		(width 0.0889)
		(layer "In11.Cu")
		(net "M_C_DQS_DP<2>")
	)
	(arc
		(start 244.21211 -57.17159)
		(mid 244.403752 -57.228756)
		(end 244.543834 -57.371488)
		(width 0.0889)
		(layer "In11.Cu")
		(net "M_C_DQS_DP<2>")
	)
	(arc
		(start 240.778284 -55.19039)
		(mid 240.969926 -55.247556)
		(end 241.110008 -55.390288)
		(width 0.0889)
		(layer "In11.Cu")
		(net "M_C_DQS_DP<2>")
	)
	(segment
		(start 210.85048 -0.821182)
		(end 210.849972 -0.821182)
		(width 0.1651)
		(layer "F.Cu")
		(net "M_C_DQS_DP<1>")
	)
	(segment
		(start 210.857592 1.455166)
		(end 210.661758 1.455166)
		(width 0.1651)
		(layer "F.Cu")
		(net "M_C_DQS_DP<1>")
	)
	(segment
		(start 211.07146 1.241298)
		(end 210.857592 1.455166)
		(width 0.1651)
		(layer "F.Cu")
		(net "M_C_DQS_DP<1>")
	)
	(segment
		(start 210.849972 -0.821182)
		(end 210.849972 0.277622)
		(width 0.1651)
		(layer "F.Cu")
		(net "M_C_DQS_DP<1>")
	)
	(segment
		(start 210.849972 0.277622)
		(end 211.07146 0.49911)
		(width 0.1651)
		(layer "F.Cu")
		(net "M_C_DQS_DP<1>")
	)
	(segment
		(start 242.193318 -60.047886)
		(end 241.621818 -60.047886)
		(width 0.0889)
		(layer "F.Cu")
		(net "M_C_DQS_DP<1>")
	)
	(segment
		(start 211.07146 0.49911)
		(end 211.07146 1.241298)
		(width 0.1651)
		(layer "F.Cu")
		(net "M_C_DQS_DP<1>")
	)
	(segment
		(start 210.661758 1.455166)
		(end 210.387946 1.181354)
		(width 0.1651)
		(layer "F.Cu")
		(net "M_C_DQS_DP<1>")
	)
	(via
		(at 241.621818 -60.047886)
		(size 0.508)
		(drill 0.254)
		(layers "F.Cu" "B.Cu")
		(net "M_C_DQS_DP<1>")
	)
	(via
		(at 210.387946 -3.026156)
		(size 0.508)
		(drill 0.254)
		(layers "F.Cu" "B.Cu")
		(net "M_C_DQS_DP<1>")
	)
	(via
		(at 210.387946 1.181354)
		(size 0.508)
		(drill 0.254)
		(layers "F.Cu" "B.Cu")
		(net "M_C_DQS_DP<1>")
	)
	(segment
		(start 211.02955 -3.16738)
		(end 210.88985 -3.30708)
		(width 0.1651)
		(layer "B.Cu")
		(net "M_C_DQS_DP<1>")
	)
	(segment
		(start 210.66887 -3.30708)
		(end 210.387946 -3.026156)
		(width 0.1651)
		(layer "B.Cu")
		(net "M_C_DQS_DP<1>")
	)
	(segment
		(start 210.849972 -1.021842)
		(end 210.849972 -2.538222)
		(width 0.1651)
		(layer "B.Cu")
		(net "M_C_DQS_DP<1>")
	)
	(segment
		(start 210.85048 -1.021842)
		(end 210.849972 -1.021842)
		(width 0.1651)
		(layer "B.Cu")
		(net "M_C_DQS_DP<1>")
	)
	(segment
		(start 210.88985 -3.30708)
		(end 210.66887 -3.30708)
		(width 0.1651)
		(layer "B.Cu")
		(net "M_C_DQS_DP<1>")
	)
	(segment
		(start 210.849972 -2.538222)
		(end 211.02955 -2.7178)
		(width 0.1651)
		(layer "B.Cu")
		(net "M_C_DQS_DP<1>")
	)
	(segment
		(start 211.02955 -2.7178)
		(end 211.02955 -3.16738)
		(width 0.1651)
		(layer "B.Cu")
		(net "M_C_DQS_DP<1>")
	)
	(segment
		(start 210.929474 -2.763774)
		(end 210.666838 -3.02641)
		(width 0.14224)
		(layer "In11.Cu")
		(net "M_C_DQS_DP<1>")
	)
	(segment
		(start 210.547204 0.0762)
		(end 210.39455 -0.076454)
		(width 0.14224)
		(layer "In11.Cu")
		(net "M_C_DQS_DP<1>")
	)
	(segment
		(start 218.520772 -43.555158)
		(end 218.520772 -44.548044)
		(width 0.14224)
		(layer "In11.Cu")
		(net "M_C_DQS_DP<1>")
	)
	(segment
		(start 210.487514 -31.905956)
		(end 210.188048 -31.905956)
		(width 0.14224)
		(layer "In11.Cu")
		(net "M_C_DQS_DP<1>")
	)
	(segment
		(start 210.669632 1.181354)
		(end 210.929474 0.921512)
		(width 0.14224)
		(layer "In11.Cu")
		(net "M_C_DQS_DP<1>")
	)
	(segment
		(start 210.387946 -3.026156)
		(end 209.95005 -3.464052)
		(width 0.14224)
		(layer "In11.Cu")
		(net "M_C_DQS_DP<1>")
	)
	(segment
		(start 230.458772 -56.191912)
		(end 230.49357 -56.157114)
		(width 0.0889)
		(layer "In11.Cu")
		(net "M_C_DQS_DP<1>")
	)
	(segment
		(start 232.440988 -56.157114)
		(end 233.950764 -57.66689)
		(width 0.0889)
		(layer "In11.Cu")
		(net "M_C_DQS_DP<1>")
	)
	(segment
		(start 210.39455 -0.076454)
		(end 210.39455 -0.380746)
		(width 0.14224)
		(layer "In11.Cu")
		(net "M_C_DQS_DP<1>")
	)
	(segment
		(start 210.06943 -4.76123)
		(end 210.06943 -5.392674)
		(width 0.14224)
		(layer "In11.Cu")
		(net "M_C_DQS_DP<1>")
	)
	(segment
		(start 210.619594 -1.8796)
		(end 210.75015 -1.8796)
		(width 0.14224)
		(layer "In11.Cu")
		(net "M_C_DQS_DP<1>")
	)
	(segment
		(start 241.936016 -59.800236)
		(end 241.93627 -59.799982)
		(width 0.0889)
		(layer "In11.Cu")
		(net "M_C_DQS_DP<1>")
	)
	(segment
		(start 210.547204 -0.5334)
		(end 210.724496 -0.5334)
		(width 0.14224)
		(layer "In11.Cu")
		(net "M_C_DQS_DP<1>")
	)
	(segment
		(start 239.883188 -60.638436)
		(end 239.926368 -60.638436)
		(width 0.0889)
		(layer "In11.Cu")
		(net "M_C_DQS_DP<1>")
	)
	(segment
		(start 210.929474 -2.058924)
		(end 210.929474 -2.763774)
		(width 0.14224)
		(layer "In11.Cu")
		(net "M_C_DQS_DP<1>")
	)
	(segment
		(start 210.387946 1.181354)
		(end 210.669632 1.181354)
		(width 0.14224)
		(layer "In11.Cu")
		(net "M_C_DQS_DP<1>")
	)
	(segment
		(start 210.77428 -34.025586)
		(end 210.77428 -36.504626)
		(width 0.14224)
		(layer "In11.Cu")
		(net "M_C_DQS_DP<1>")
	)
	(segment
		(start 209.75828 -27.053794)
		(end 209.75828 -30.45079)
		(width 0.14224)
		(layer "In11.Cu")
		(net "M_C_DQS_DP<1>")
	)
	(segment
		(start 218.520772 -44.548044)
		(end 230.16464 -56.191912)
		(width 0.14224)
		(layer "In11.Cu")
		(net "M_C_DQS_DP<1>")
	)
	(segment
		(start 210.746594 -1.27)
		(end 210.619594 -1.27)
		(width 0.14224)
		(layer "In11.Cu")
		(net "M_C_DQS_DP<1>")
	)
	(segment
		(start 230.16464 -56.191912)
		(end 230.458772 -56.191912)
		(width 0.14224)
		(layer "In11.Cu")
		(net "M_C_DQS_DP<1>")
	)
	(segment
		(start 210.619594 -1.27)
		(end 210.441794 -1.4478)
		(width 0.14224)
		(layer "In11.Cu")
		(net "M_C_DQS_DP<1>")
	)
	(segment
		(start 210.387946 -3.02641)
		(end 210.387946 -3.026156)
		(width 0.14224)
		(layer "In11.Cu")
		(net "M_C_DQS_DP<1>")
	)
	(segment
		(start 210.901026 -25.911048)
		(end 209.75828 -27.053794)
		(width 0.14224)
		(layer "In11.Cu")
		(net "M_C_DQS_DP<1>")
	)
	(segment
		(start 210.929474 0.921512)
		(end 210.929474 0.255778)
		(width 0.14224)
		(layer "In11.Cu")
		(net "M_C_DQS_DP<1>")
	)
	(segment
		(start 237.316264 -59.15279)
		(end 237.344204 -59.15279)
		(width 0.0889)
		(layer "In11.Cu")
		(net "M_C_DQS_DP<1>")
	)
	(segment
		(start 209.95005 -3.464052)
		(end 209.95005 -4.64185)
		(width 0.14224)
		(layer "In11.Cu")
		(net "M_C_DQS_DP<1>")
	)
	(segment
		(start 210.188048 -31.905956)
		(end 209.80908 -32.284924)
		(width 0.14224)
		(layer "In11.Cu")
		(net "M_C_DQS_DP<1>")
	)
	(segment
		(start 210.666838 -3.02641)
		(end 210.387946 -3.02641)
		(width 0.14224)
		(layer "In11.Cu")
		(net "M_C_DQS_DP<1>")
	)
	(segment
		(start 215.849708 -40.487854)
		(end 215.849708 -40.884094)
		(width 0.14224)
		(layer "In11.Cu")
		(net "M_C_DQS_DP<1>")
	)
	(segment
		(start 210.749896 0.0762)
		(end 210.547204 0.0762)
		(width 0.14224)
		(layer "In11.Cu")
		(net "M_C_DQS_DP<1>")
	)
	(segment
		(start 213.756494 -39.48684)
		(end 214.848694 -39.48684)
		(width 0.14224)
		(layer "In11.Cu")
		(net "M_C_DQS_DP<1>")
	)
	(segment
		(start 239.028478 -60.14339)
		(end 239.061244 -60.14339)
		(width 0.0889)
		(layer "In11.Cu")
		(net "M_C_DQS_DP<1>")
	)
	(segment
		(start 210.136486 -30.828996)
		(end 210.451954 -30.828996)
		(width 0.14224)
		(layer "In11.Cu")
		(net "M_C_DQS_DP<1>")
	)
	(segment
		(start 209.80908 -33.060386)
		(end 210.77428 -34.025586)
		(width 0.14224)
		(layer "In11.Cu")
		(net "M_C_DQS_DP<1>")
	)
	(segment
		(start 210.441794 -1.7018)
		(end 210.619594 -1.8796)
		(width 0.14224)
		(layer "In11.Cu")
		(net "M_C_DQS_DP<1>")
	)
	(segment
		(start 214.848694 -39.48684)
		(end 215.849708 -40.487854)
		(width 0.14224)
		(layer "In11.Cu")
		(net "M_C_DQS_DP<1>")
	)
	(segment
		(start 210.69808 -31.075122)
		(end 210.69808 -31.69539)
		(width 0.14224)
		(layer "In11.Cu")
		(net "M_C_DQS_DP<1>")
	)
	(segment
		(start 210.75015 -1.8796)
		(end 210.929474 -2.058924)
		(width 0.14224)
		(layer "In11.Cu")
		(net "M_C_DQS_DP<1>")
	)
	(segment
		(start 210.451954 -30.828996)
		(end 210.69808 -31.075122)
		(width 0.14224)
		(layer "In11.Cu")
		(net "M_C_DQS_DP<1>")
	)
	(segment
		(start 210.77428 -36.504626)
		(end 213.756494 -39.48684)
		(width 0.14224)
		(layer "In11.Cu")
		(net "M_C_DQS_DP<1>")
	)
	(segment
		(start 241.93627 -59.799982)
		(end 241.914934 -59.878976)
		(width 0.0889)
		(layer "In11.Cu")
		(net "M_C_DQS_DP<1>")
	)
	(segment
		(start 210.929474 -1.08712)
		(end 210.746594 -1.27)
		(width 0.14224)
		(layer "In11.Cu")
		(net "M_C_DQS_DP<1>")
	)
	(segment
		(start 209.95005 -4.64185)
		(end 210.06943 -4.76123)
		(width 0.14224)
		(layer "In11.Cu")
		(net "M_C_DQS_DP<1>")
	)
	(segment
		(start 209.75828 -30.45079)
		(end 210.136486 -30.828996)
		(width 0.14224)
		(layer "In11.Cu")
		(net "M_C_DQS_DP<1>")
	)
	(segment
		(start 210.39455 -0.380746)
		(end 210.547204 -0.5334)
		(width 0.14224)
		(layer "In11.Cu")
		(net "M_C_DQS_DP<1>")
	)
	(segment
		(start 235.590588 -58.16219)
		(end 235.630212 -58.16219)
		(width 0.0889)
		(layer "In11.Cu")
		(net "M_C_DQS_DP<1>")
	)
	(segment
		(start 210.929474 -0.738378)
		(end 210.929474 -1.08712)
		(width 0.14224)
		(layer "In11.Cu")
		(net "M_C_DQS_DP<1>")
	)
	(segment
		(start 210.724496 -0.5334)
		(end 210.929474 -0.738378)
		(width 0.14224)
		(layer "In11.Cu")
		(net "M_C_DQS_DP<1>")
	)
	(segment
		(start 210.441794 -1.4478)
		(end 210.441794 -1.7018)
		(width 0.14224)
		(layer "In11.Cu")
		(net "M_C_DQS_DP<1>")
	)
	(segment
		(start 238.166148 -59.647836)
		(end 238.198914 -59.647836)
		(width 0.0889)
		(layer "In11.Cu")
		(net "M_C_DQS_DP<1>")
	)
	(segment
		(start 210.929474 0.255778)
		(end 210.749896 0.0762)
		(width 0.14224)
		(layer "In11.Cu")
		(net "M_C_DQS_DP<1>")
	)
	(segment
		(start 236.452918 -58.65749)
		(end 236.488732 -58.65749)
		(width 0.0889)
		(layer "In11.Cu")
		(net "M_C_DQS_DP<1>")
	)
	(segment
		(start 233.950764 -57.66689)
		(end 234.764834 -57.66689)
		(width 0.0889)
		(layer "In11.Cu")
		(net "M_C_DQS_DP<1>")
	)
	(segment
		(start 210.06943 -5.392674)
		(end 210.901026 -6.22427)
		(width 0.14224)
		(layer "In11.Cu")
		(net "M_C_DQS_DP<1>")
	)
	(segment
		(start 215.849708 -40.884094)
		(end 218.520772 -43.555158)
		(width 0.14224)
		(layer "In11.Cu")
		(net "M_C_DQS_DP<1>")
	)
	(segment
		(start 209.80908 -32.284924)
		(end 209.80908 -33.060386)
		(width 0.14224)
		(layer "In11.Cu")
		(net "M_C_DQS_DP<1>")
	)
	(segment
		(start 241.914934 -59.878976)
		(end 241.621818 -60.047886)
		(width 0.0889)
		(layer "In11.Cu")
		(net "M_C_DQS_DP<1>")
	)
	(segment
		(start 210.901026 -6.22427)
		(end 210.901026 -25.911048)
		(width 0.14224)
		(layer "In11.Cu")
		(net "M_C_DQS_DP<1>")
	)
	(segment
		(start 210.69808 -31.69539)
		(end 210.487514 -31.905956)
		(width 0.14224)
		(layer "In11.Cu")
		(net "M_C_DQS_DP<1>")
	)
	(segment
		(start 240.748312 -60.14339)
		(end 240.781078 -60.14339)
		(width 0.0889)
		(layer "In11.Cu")
		(net "M_C_DQS_DP<1>")
	)
	(segment
		(start 230.49357 -56.157114)
		(end 232.440988 -56.157114)
		(width 0.0889)
		(layer "In11.Cu")
		(net "M_C_DQS_DP<1>")
	)
	(arc
		(start 235.630212 -58.16219)
		(mid 235.820141 -58.22006)
		(end 235.958888 -58.362088)
		(width 0.0889)
		(layer "In11.Cu")
		(net "M_C_DQS_DP<1>")
	)
	(arc
		(start 234.764834 -57.66689)
		(mid 234.958684 -57.72324)
		(end 235.100368 -57.867042)
		(width 0.0889)
		(layer "In11.Cu")
		(net "M_C_DQS_DP<1>")
	)
	(arc
		(start 237.675928 -59.352688)
		(mid 237.882932 -59.563552)
		(end 238.166148 -59.647836)
		(width 0.0889)
		(layer "In11.Cu")
		(net "M_C_DQS_DP<1>")
	)
	(arc
		(start 239.392968 -60.343288)
		(mid 239.599972 -60.554152)
		(end 239.883188 -60.638436)
		(width 0.0889)
		(layer "In11.Cu")
		(net "M_C_DQS_DP<1>")
	)
	(arc
		(start 240.416588 -60.343288)
		(mid 240.556667 -60.200552)
		(end 240.748312 -60.14339)
		(width 0.0889)
		(layer "In11.Cu")
		(net "M_C_DQS_DP<1>")
	)
	(arc
		(start 236.817408 -58.857388)
		(mid 237.028121 -59.070467)
		(end 237.316264 -59.15279)
		(width 0.0889)
		(layer "In11.Cu")
		(net "M_C_DQS_DP<1>")
	)
	(arc
		(start 235.958888 -58.362088)
		(mid 236.167496 -58.57402)
		(end 236.452918 -58.65749)
		(width 0.0889)
		(layer "In11.Cu")
		(net "M_C_DQS_DP<1>")
	)
	(arc
		(start 239.926368 -60.638436)
		(mid 240.209585 -60.554155)
		(end 240.416588 -60.343288)
		(width 0.0889)
		(layer "In11.Cu")
		(net "M_C_DQS_DP<1>")
	)
	(arc
		(start 240.781078 -60.14339)
		(mid 241.066502 -60.059923)
		(end 241.275108 -59.847988)
		(width 0.0889)
		(layer "In11.Cu")
		(net "M_C_DQS_DP<1>")
	)
	(arc
		(start 239.061244 -60.14339)
		(mid 239.252886 -60.200556)
		(end 239.392968 -60.343288)
		(width 0.0889)
		(layer "In11.Cu")
		(net "M_C_DQS_DP<1>")
	)
	(arc
		(start 237.344204 -59.15279)
		(mid 237.535846 -59.209956)
		(end 237.675928 -59.352688)
		(width 0.0889)
		(layer "In11.Cu")
		(net "M_C_DQS_DP<1>")
	)
	(arc
		(start 235.100368 -57.867042)
		(mid 235.307372 -58.077906)
		(end 235.590588 -58.16219)
		(width 0.0889)
		(layer "In11.Cu")
		(net "M_C_DQS_DP<1>")
	)
	(arc
		(start 238.198914 -59.647836)
		(mid 238.392764 -59.704186)
		(end 238.534448 -59.847988)
		(width 0.0889)
		(layer "In11.Cu")
		(net "M_C_DQS_DP<1>")
	)
	(arc
		(start 238.534448 -59.847988)
		(mid 238.743056 -60.05992)
		(end 239.028478 -60.14339)
		(width 0.0889)
		(layer "In11.Cu")
		(net "M_C_DQS_DP<1>")
	)
	(arc
		(start 241.275108 -59.847988)
		(mid 241.592928 -59.648721)
		(end 241.936016 -59.800236)
		(width 0.0889)
		(layer "In11.Cu")
		(net "M_C_DQS_DP<1>")
	)
	(arc
		(start 236.488732 -58.65749)
		(mid 236.678661 -58.71536)
		(end 236.817408 -58.857388)
		(width 0.0889)
		(layer "In11.Cu")
		(net "M_C_DQS_DP<1>")
	)
	(segment
		(start 236.763814 2.725928)
		(end 236.679232 2.542032)
		(width 0.1651)
		(layer "F.Cu")
		(net "M_C_DQS_DP<17>")
	)
	(segment
		(start 237.20044 3.778758)
		(end 237.199932 3.778758)
		(width 0.1651)
		(layer "F.Cu")
		(net "M_C_DQS_DP<17>")
	)
	(segment
		(start 237.199932 3.778758)
		(end 237.199932 3.162046)
		(width 0.1651)
		(layer "F.Cu")
		(net "M_C_DQS_DP<17>")
	)
	(segment
		(start 245.627144 -67.972686)
		(end 245.055644 -67.972686)
		(width 0.0889)
		(layer "F.Cu")
		(net "M_C_DQS_DP<17>")
	)
	(segment
		(start 236.679232 2.542032)
		(end 236.679232 1.723898)
		(width 0.1651)
		(layer "F.Cu")
		(net "M_C_DQS_DP<17>")
	)
	(segment
		(start 237.199932 3.162046)
		(end 236.763814 2.725928)
		(width 0.1651)
		(layer "F.Cu")
		(net "M_C_DQS_DP<17>")
	)
	(segment
		(start 236.679232 1.723898)
		(end 236.760766 1.499616)
		(width 0.1651)
		(layer "F.Cu")
		(net "M_C_DQS_DP<17>")
	)
	(segment
		(start 236.760766 1.499616)
		(end 237.142528 1.117854)
		(width 0.1651)
		(layer "F.Cu")
		(net "M_C_DQS_DP<17>")
	)
	(via
		(at 237.142528 1.117854)
		(size 0.508)
		(drill 0.254)
		(layers "F.Cu" "B.Cu")
		(net "M_C_DQS_DP<17>")
	)
	(via
		(at 245.055644 -67.972686)
		(size 0.508)
		(drill 0.254)
		(layers "F.Cu" "B.Cu")
		(net "M_C_DQS_DP<17>")
	)
	(via
		(at 237.142528 -2.9718)
		(size 0.508)
		(drill 0.254)
		(layers "F.Cu" "B.Cu")
		(net "M_C_DQS_DP<17>")
	)
	(segment
		(start 236.666532 -3.519932)
		(end 236.753908 -3.36042)
		(width 0.1651)
		(layer "B.Cu")
		(net "M_C_DQS_DP<17>")
	)
	(segment
		(start 236.743748 -4.54787)
		(end 236.666532 -4.415536)
		(width 0.1651)
		(layer "B.Cu")
		(net "M_C_DQS_DP<17>")
	)
	(segment
		(start 236.753908 -3.36042)
		(end 237.142528 -2.9718)
		(width 0.1651)
		(layer "B.Cu")
		(net "M_C_DQS_DP<17>")
	)
	(segment
		(start 237.199932 -5.621782)
		(end 237.199932 -5.004054)
		(width 0.1651)
		(layer "B.Cu")
		(net "M_C_DQS_DP<17>")
	)
	(segment
		(start 237.199932 -5.004054)
		(end 236.743748 -4.54787)
		(width 0.1651)
		(layer "B.Cu")
		(net "M_C_DQS_DP<17>")
	)
	(segment
		(start 236.666532 -4.415536)
		(end 236.666532 -3.519932)
		(width 0.1651)
		(layer "B.Cu")
		(net "M_C_DQS_DP<17>")
	)
	(segment
		(start 237.20044 -5.621782)
		(end 237.199932 -5.621782)
		(width 0.1651)
		(layer "B.Cu")
		(net "M_C_DQS_DP<17>")
	)
	(segment
		(start 244.537484 -60.754006)
		(end 244.543834 -60.743338)
		(width 0.0889)
		(layer "In4.Cu")
		(net "M_C_DQS_DP<17>")
	)
	(segment
		(start 244.543834 -64.705738)
		(end 244.54866 -64.697102)
		(width 0.0889)
		(layer "In4.Cu")
		(net "M_C_DQS_DP<17>")
	)
	(segment
		(start 244.543834 -60.743338)
		(end 244.54866 -60.734702)
		(width 0.0889)
		(layer "In4.Cu")
		(net "M_C_DQS_DP<17>")
	)
	(segment
		(start 244.881654 -51.949604)
		(end 244.773704 -51.841654)
		(width 0.0889)
		(layer "In4.Cu")
		(net "M_C_DQS_DP<17>")
	)
	(segment
		(start 244.537484 -62.735206)
		(end 244.543834 -62.724538)
		(width 0.0889)
		(layer "In4.Cu")
		(net "M_C_DQS_DP<17>")
	)
	(segment
		(start 244.537484 -64.716406)
		(end 244.543834 -64.705738)
		(width 0.0889)
		(layer "In4.Cu")
		(net "M_C_DQS_DP<17>")
	)
	(segment
		(start 244.537484 -53.819806)
		(end 244.543834 -53.809138)
		(width 0.0889)
		(layer "In4.Cu")
		(net "M_C_DQS_DP<17>")
	)
	(segment
		(start 240.4364 -33.458912)
		(end 240.4364 -32.68472)
		(width 0.14224)
		(layer "In4.Cu")
		(net "M_C_DQS_DP<17>")
	)
	(segment
		(start 244.543834 -62.724538)
		(end 244.54866 -62.715902)
		(width 0.0889)
		(layer "In4.Cu")
		(net "M_C_DQS_DP<17>")
	)
	(segment
		(start 244.537484 -59.763406)
		(end 244.543834 -59.752738)
		(width 0.0889)
		(layer "In4.Cu")
		(net "M_C_DQS_DP<17>")
	)
	(segment
		(start 237.655608 -29.903928)
		(end 237.655608 -6.57479)
		(width 0.14224)
		(layer "In4.Cu")
		(net "M_C_DQS_DP<17>")
	)
	(segment
		(start 244.543834 -59.752738)
		(end 244.54866 -59.744102)
		(width 0.0889)
		(layer "In4.Cu")
		(net "M_C_DQS_DP<17>")
	)
	(segment
		(start 244.543834 -63.715138)
		(end 244.54866 -63.706502)
		(width 0.0889)
		(layer "In4.Cu")
		(net "M_C_DQS_DP<17>")
	)
	(segment
		(start 244.537484 -61.744606)
		(end 244.543834 -61.733938)
		(width 0.0889)
		(layer "In4.Cu")
		(net "M_C_DQS_DP<17>")
	)
	(segment
		(start 244.543834 -53.409088)
		(end 244.463824 -53.270404)
		(width 0.0889)
		(layer "In4.Cu")
		(net "M_C_DQS_DP<17>")
	)
	(segment
		(start 244.537484 -63.725806)
		(end 244.543834 -63.715138)
		(width 0.0889)
		(layer "In4.Cu")
		(net "M_C_DQS_DP<17>")
	)
	(segment
		(start 240.4364 -43.7896)
		(end 240.4364 -34.920428)
		(width 0.14224)
		(layer "In4.Cu")
		(net "M_C_DQS_DP<17>")
	)
	(segment
		(start 244.773704 -49.400968)
		(end 244.734334 -49.361598)
		(width 0.0889)
		(layer "In4.Cu")
		(net "M_C_DQS_DP<17>")
	)
	(segment
		(start 244.543834 -65.696338)
		(end 244.54866 -65.687702)
		(width 0.0889)
		(layer "In4.Cu")
		(net "M_C_DQS_DP<17>")
	)
	(segment
		(start 244.537484 -55.801006)
		(end 244.543834 -55.790338)
		(width 0.0889)
		(layer "In4.Cu")
		(net "M_C_DQS_DP<17>")
	)
	(segment
		(start 244.543834 -55.790338)
		(end 244.54866 -55.781702)
		(width 0.0889)
		(layer "In4.Cu")
		(net "M_C_DQS_DP<17>")
	)
	(segment
		(start 239.0648 -34.523172)
		(end 239.0648 -33.856168)
		(width 0.14224)
		(layer "In4.Cu")
		(net "M_C_DQS_DP<17>")
	)
	(segment
		(start 240.4364 -32.68472)
		(end 237.655608 -29.903928)
		(width 0.14224)
		(layer "In4.Cu")
		(net "M_C_DQS_DP<17>")
	)
	(segment
		(start 244.543834 -53.809138)
		(end 244.54866 -53.800502)
		(width 0.0889)
		(layer "In4.Cu")
		(net "M_C_DQS_DP<17>")
	)
	(segment
		(start 244.463824 -52.783994)
		(end 244.881654 -52.366164)
		(width 0.0889)
		(layer "In4.Cu")
		(net "M_C_DQS_DP<17>")
	)
	(segment
		(start 236.671612 -5.590794)
		(end 236.671612 -3.442716)
		(width 0.14224)
		(layer "In4.Cu")
		(net "M_C_DQS_DP<17>")
	)
	(segment
		(start 244.543834 -61.733938)
		(end 244.54866 -61.725302)
		(width 0.0889)
		(layer "In4.Cu")
		(net "M_C_DQS_DP<17>")
	)
	(segment
		(start 244.734334 -48.087534)
		(end 240.4364 -43.7896)
		(width 0.14224)
		(layer "In4.Cu")
		(net "M_C_DQS_DP<17>")
	)
	(segment
		(start 244.734334 -49.361598)
		(end 244.734334 -49.3395)
		(width 0.0889)
		(layer "In4.Cu")
		(net "M_C_DQS_DP<17>")
	)
	(segment
		(start 240.316512 -33.5788)
		(end 240.4364 -33.458912)
		(width 0.14224)
		(layer "In4.Cu")
		(net "M_C_DQS_DP<17>")
	)
	(segment
		(start 244.543834 -57.771538)
		(end 244.54866 -57.762902)
		(width 0.0889)
		(layer "In4.Cu")
		(net "M_C_DQS_DP<17>")
	)
	(segment
		(start 240.4364 -34.920428)
		(end 240.316512 -34.80054)
		(width 0.14224)
		(layer "In4.Cu")
		(net "M_C_DQS_DP<17>")
	)
	(segment
		(start 237.655608 -6.57479)
		(end 236.671612 -5.590794)
		(width 0.14224)
		(layer "In4.Cu")
		(net "M_C_DQS_DP<17>")
	)
	(segment
		(start 244.537484 -56.791606)
		(end 244.543834 -56.780938)
		(width 0.0889)
		(layer "In4.Cu")
		(net "M_C_DQS_DP<17>")
	)
	(segment
		(start 239.0648 -33.856168)
		(end 239.342168 -33.5788)
		(width 0.14224)
		(layer "In4.Cu")
		(net "M_C_DQS_DP<17>")
	)
	(segment
		(start 244.734334 -49.3395)
		(end 244.734334 -48.087534)
		(width 0.14224)
		(layer "In4.Cu")
		(net "M_C_DQS_DP<17>")
	)
	(segment
		(start 244.543834 -54.799738)
		(end 244.54866 -54.791102)
		(width 0.0889)
		(layer "In4.Cu")
		(net "M_C_DQS_DP<17>")
	)
	(segment
		(start 244.463824 -53.270404)
		(end 244.463824 -52.783994)
		(width 0.0889)
		(layer "In4.Cu")
		(net "M_C_DQS_DP<17>")
	)
	(segment
		(start 236.671612 -3.442716)
		(end 237.142528 -2.9718)
		(width 0.14224)
		(layer "In4.Cu")
		(net "M_C_DQS_DP<17>")
	)
	(segment
		(start 244.543834 -58.362088)
		(end 244.537484 -58.35142)
		(width 0.0889)
		(layer "In4.Cu")
		(net "M_C_DQS_DP<17>")
	)
	(segment
		(start 239.342168 -33.5788)
		(end 240.316512 -33.5788)
		(width 0.14224)
		(layer "In4.Cu")
		(net "M_C_DQS_DP<17>")
	)
	(segment
		(start 239.342168 -34.80054)
		(end 239.0648 -34.523172)
		(width 0.14224)
		(layer "In4.Cu")
		(net "M_C_DQS_DP<17>")
	)
	(segment
		(start 240.316512 -34.80054)
		(end 239.342168 -34.80054)
		(width 0.14224)
		(layer "In4.Cu")
		(net "M_C_DQS_DP<17>")
	)
	(segment
		(start 244.537484 -65.707006)
		(end 244.543834 -65.696338)
		(width 0.0889)
		(layer "In4.Cu")
		(net "M_C_DQS_DP<17>")
	)
	(segment
		(start 245.055644 -67.972686)
		(end 245.053866 -67.968876)
		(width 0.0889)
		(layer "In4.Cu")
		(net "M_C_DQS_DP<17>")
	)
	(segment
		(start 244.537484 -54.810406)
		(end 244.543834 -54.799738)
		(width 0.0889)
		(layer "In4.Cu")
		(net "M_C_DQS_DP<17>")
	)
	(segment
		(start 244.881654 -52.366164)
		(end 244.881654 -51.949604)
		(width 0.0889)
		(layer "In4.Cu")
		(net "M_C_DQS_DP<17>")
	)
	(segment
		(start 244.773704 -51.841654)
		(end 244.773704 -49.400968)
		(width 0.0889)
		(layer "In4.Cu")
		(net "M_C_DQS_DP<17>")
	)
	(segment
		(start 244.543834 -56.780938)
		(end 244.54866 -56.772302)
		(width 0.0889)
		(layer "In4.Cu")
		(net "M_C_DQS_DP<17>")
	)
	(arc
		(start 244.54866 -64.697102)
		(mid 244.597415 -64.50075)
		(end 244.543834 -64.305688)
		(width 0.0889)
		(layer "In4.Cu")
		(net "M_C_DQS_DP<17>")
	)
	(arc
		(start 244.543834 -58.761884)
		(mid 244.597333 -58.561986)
		(end 244.543834 -58.362088)
		(width 0.0889)
		(layer "In4.Cu")
		(net "M_C_DQS_DP<17>")
	)
	(arc
		(start 244.66804 -66.882518)
		(mid 244.653642 -66.57476)
		(end 244.543834 -66.286888)
		(width 0.0889)
		(layer "In4.Cu")
		(net "M_C_DQS_DP<17>")
	)
	(arc
		(start 244.543834 -63.315088)
		(mid 244.464612 -63.02597)
		(end 244.537484 -62.735206)
		(width 0.0889)
		(layer "In4.Cu")
		(net "M_C_DQS_DP<17>")
	)
	(arc
		(start 244.54866 -61.725302)
		(mid 244.597415 -61.52895)
		(end 244.543834 -61.333888)
		(width 0.0889)
		(layer "In4.Cu")
		(net "M_C_DQS_DP<17>")
	)
	(arc
		(start 244.543834 -61.333888)
		(mid 244.464612 -61.04477)
		(end 244.537484 -60.754006)
		(width 0.0889)
		(layer "In4.Cu")
		(net "M_C_DQS_DP<17>")
	)
	(arc
		(start 244.543834 -55.390288)
		(mid 244.464612 -55.10117)
		(end 244.537484 -54.810406)
		(width 0.0889)
		(layer "In4.Cu")
		(net "M_C_DQS_DP<17>")
	)
	(arc
		(start 244.54866 -62.715902)
		(mid 244.597415 -62.51955)
		(end 244.543834 -62.324488)
		(width 0.0889)
		(layer "In4.Cu")
		(net "M_C_DQS_DP<17>")
	)
	(arc
		(start 244.537484 -58.35142)
		(mid 244.464686 -58.060657)
		(end 244.543834 -57.771538)
		(width 0.0889)
		(layer "In4.Cu")
		(net "M_C_DQS_DP<17>")
	)
	(arc
		(start 244.54866 -54.791102)
		(mid 244.597415 -54.59475)
		(end 244.543834 -54.399688)
		(width 0.0889)
		(layer "In4.Cu")
		(net "M_C_DQS_DP<17>")
	)
	(arc
		(start 244.54866 -65.687702)
		(mid 244.597415 -65.49135)
		(end 244.543834 -65.296288)
		(width 0.0889)
		(layer "In4.Cu")
		(net "M_C_DQS_DP<17>")
	)
	(arc
		(start 244.543834 -64.305688)
		(mid 244.464612 -64.01657)
		(end 244.537484 -63.725806)
		(width 0.0889)
		(layer "In4.Cu")
		(net "M_C_DQS_DP<17>")
	)
	(arc
		(start 244.54866 -63.706502)
		(mid 244.597415 -63.51015)
		(end 244.543834 -63.315088)
		(width 0.0889)
		(layer "In4.Cu")
		(net "M_C_DQS_DP<17>")
	)
	(arc
		(start 244.543834 -62.324488)
		(mid 244.464612 -62.03537)
		(end 244.537484 -61.744606)
		(width 0.0889)
		(layer "In4.Cu")
		(net "M_C_DQS_DP<17>")
	)
	(arc
		(start 244.543834 -54.399688)
		(mid 244.464612 -54.11057)
		(end 244.537484 -53.819806)
		(width 0.0889)
		(layer "In4.Cu")
		(net "M_C_DQS_DP<17>")
	)
	(arc
		(start 244.54866 -53.800502)
		(mid 244.597415 -53.60415)
		(end 244.543834 -53.409088)
		(width 0.0889)
		(layer "In4.Cu")
		(net "M_C_DQS_DP<17>")
	)
	(arc
		(start 244.543834 -65.296288)
		(mid 244.464612 -65.00717)
		(end 244.537484 -64.716406)
		(width 0.0889)
		(layer "In4.Cu")
		(net "M_C_DQS_DP<17>")
	)
	(arc
		(start 244.543834 -56.380888)
		(mid 244.464612 -56.09177)
		(end 244.537484 -55.801006)
		(width 0.0889)
		(layer "In4.Cu")
		(net "M_C_DQS_DP<17>")
	)
	(arc
		(start 244.708934 -67.181984)
		(mid 244.659119 -67.036259)
		(end 244.66804 -66.882518)
		(width 0.0889)
		(layer "In4.Cu")
		(net "M_C_DQS_DP<17>")
	)
	(arc
		(start 244.54866 -55.781702)
		(mid 244.597415 -55.58535)
		(end 244.543834 -55.390288)
		(width 0.0889)
		(layer "In4.Cu")
		(net "M_C_DQS_DP<17>")
	)
	(arc
		(start 244.54866 -59.744102)
		(mid 244.597415 -59.54775)
		(end 244.543834 -59.352688)
		(width 0.0889)
		(layer "In4.Cu")
		(net "M_C_DQS_DP<17>")
	)
	(arc
		(start 244.543834 -57.371488)
		(mid 244.464612 -57.08237)
		(end 244.537484 -56.791606)
		(width 0.0889)
		(layer "In4.Cu")
		(net "M_C_DQS_DP<17>")
	)
	(arc
		(start 245.053866 -67.968876)
		(mid 244.903048 -67.56594)
		(end 244.708934 -67.181984)
		(width 0.0889)
		(layer "In4.Cu")
		(net "M_C_DQS_DP<17>")
	)
	(arc
		(start 244.54866 -57.762902)
		(mid 244.597415 -57.56655)
		(end 244.543834 -57.371488)
		(width 0.0889)
		(layer "In4.Cu")
		(net "M_C_DQS_DP<17>")
	)
	(arc
		(start 244.543834 -60.343288)
		(mid 244.464612 -60.05417)
		(end 244.537484 -59.763406)
		(width 0.0889)
		(layer "In4.Cu")
		(net "M_C_DQS_DP<17>")
	)
	(arc
		(start 244.543834 -66.286888)
		(mid 244.464646 -65.99777)
		(end 244.537484 -65.707006)
		(width 0.0889)
		(layer "In4.Cu")
		(net "M_C_DQS_DP<17>")
	)
	(arc
		(start 244.54866 -56.772302)
		(mid 244.597415 -56.57595)
		(end 244.543834 -56.380888)
		(width 0.0889)
		(layer "In4.Cu")
		(net "M_C_DQS_DP<17>")
	)
	(arc
		(start 244.54866 -60.734702)
		(mid 244.597415 -60.53835)
		(end 244.543834 -60.343288)
		(width 0.0889)
		(layer "In4.Cu")
		(net "M_C_DQS_DP<17>")
	)
	(arc
		(start 244.543834 -59.352688)
		(mid 244.464703 -59.057286)
		(end 244.543834 -58.761884)
		(width 0.0889)
		(layer "In4.Cu")
		(net "M_C_DQS_DP<17>")
	)
	(segment
		(start 237.170976 -1.346708)
		(end 237.170976 -1.685036)
		(width 0.14224)
		(layer "In11.Cu")
		(net "M_C_DQS_DP<17>")
	)
	(segment
		(start 237.662212 0.30988)
		(end 237.174532 -0.1778)
		(width 0.14224)
		(layer "In11.Cu")
		(net "M_C_DQS_DP<17>")
	)
	(segment
		(start 237.326932 -0.5842)
		(end 237.453932 -0.5842)
		(width 0.14224)
		(layer "In11.Cu")
		(net "M_C_DQS_DP<17>")
	)
	(segment
		(start 237.170976 -1.685036)
		(end 237.32744 -1.8415)
		(width 0.14224)
		(layer "In11.Cu")
		(net "M_C_DQS_DP<17>")
	)
	(segment
		(start 237.662212 1.145286)
		(end 237.662212 0.30988)
		(width 0.14224)
		(layer "In11.Cu")
		(net "M_C_DQS_DP<17>")
	)
	(segment
		(start 237.142528 1.117854)
		(end 237.350554 1.32588)
		(width 0.14224)
		(layer "In11.Cu")
		(net "M_C_DQS_DP<17>")
	)
	(segment
		(start 237.174532 -0.4318)
		(end 237.326932 -0.5842)
		(width 0.14224)
		(layer "In11.Cu")
		(net "M_C_DQS_DP<17>")
	)
	(segment
		(start 237.662212 -0.79248)
		(end 237.662212 -1.03632)
		(width 0.14224)
		(layer "In11.Cu")
		(net "M_C_DQS_DP<17>")
	)
	(segment
		(start 237.174532 -0.1778)
		(end 237.174532 -0.4318)
		(width 0.14224)
		(layer "In11.Cu")
		(net "M_C_DQS_DP<17>")
	)
	(segment
		(start 237.350554 1.32588)
		(end 237.481618 1.32588)
		(width 0.14224)
		(layer "In11.Cu")
		(net "M_C_DQS_DP<17>")
	)
	(segment
		(start 237.479332 -1.2192)
		(end 237.298484 -1.2192)
		(width 0.14224)
		(layer "In11.Cu")
		(net "M_C_DQS_DP<17>")
	)
	(segment
		(start 237.662212 -2.08788)
		(end 237.662212 -2.731262)
		(width 0.14224)
		(layer "In11.Cu")
		(net "M_C_DQS_DP<17>")
	)
	(segment
		(start 237.298484 -1.2192)
		(end 237.170976 -1.346708)
		(width 0.14224)
		(layer "In11.Cu")
		(net "M_C_DQS_DP<17>")
	)
	(segment
		(start 237.481618 1.32588)
		(end 237.662212 1.145286)
		(width 0.14224)
		(layer "In11.Cu")
		(net "M_C_DQS_DP<17>")
	)
	(segment
		(start 237.32744 -1.8415)
		(end 237.415832 -1.8415)
		(width 0.14224)
		(layer "In11.Cu")
		(net "M_C_DQS_DP<17>")
	)
	(segment
		(start 237.415832 -1.8415)
		(end 237.662212 -2.08788)
		(width 0.14224)
		(layer "In11.Cu")
		(net "M_C_DQS_DP<17>")
	)
	(segment
		(start 237.662212 -2.731262)
		(end 237.421674 -2.9718)
		(width 0.14224)
		(layer "In11.Cu")
		(net "M_C_DQS_DP<17>")
	)
	(segment
		(start 237.662212 -1.03632)
		(end 237.479332 -1.2192)
		(width 0.14224)
		(layer "In11.Cu")
		(net "M_C_DQS_DP<17>")
	)
	(segment
		(start 237.453932 -0.5842)
		(end 237.662212 -0.79248)
		(width 0.14224)
		(layer "In11.Cu")
		(net "M_C_DQS_DP<17>")
	)
	(segment
		(start 237.421674 -2.9718)
		(end 237.142528 -2.9718)
		(width 0.14224)
		(layer "In11.Cu")
		(net "M_C_DQS_DP<17>")
	)
	(segment
		(start 311.15 3.162046)
		(end 310.713882 2.725928)
		(width 0.1651)
		(layer "F.Cu")
		(net "M_C_DQS_DP<16>")
	)
	(segment
		(start 310.6293 2.542032)
		(end 310.6293 1.723898)
		(width 0.1651)
		(layer "F.Cu")
		(net "M_C_DQS_DP<16>")
	)
	(segment
		(start 310.713882 2.725928)
		(end 310.6293 2.542032)
		(width 0.1651)
		(layer "F.Cu")
		(net "M_C_DQS_DP<16>")
	)
	(segment
		(start 311.150508 3.778758)
		(end 311.15 3.778758)
		(width 0.1651)
		(layer "F.Cu")
		(net "M_C_DQS_DP<16>")
	)
	(segment
		(start 287.50514 -63.334138)
		(end 286.93364 -63.334138)
		(width 0.0889)
		(layer "F.Cu")
		(net "M_C_DQS_DP<16>")
	)
	(segment
		(start 311.15 3.778758)
		(end 311.15 3.162046)
		(width 0.1651)
		(layer "F.Cu")
		(net "M_C_DQS_DP<16>")
	)
	(segment
		(start 310.6293 1.723898)
		(end 310.710834 1.499616)
		(width 0.1651)
		(layer "F.Cu")
		(net "M_C_DQS_DP<16>")
	)
	(segment
		(start 310.710834 1.499616)
		(end 311.092596 1.117854)
		(width 0.1651)
		(layer "F.Cu")
		(net "M_C_DQS_DP<16>")
	)
	(via
		(at 311.092596 -2.9718)
		(size 0.508)
		(drill 0.254)
		(layers "F.Cu" "B.Cu")
		(net "M_C_DQS_DP<16>")
	)
	(via
		(at 311.092596 1.117854)
		(size 0.508)
		(drill 0.254)
		(layers "F.Cu" "B.Cu")
		(net "M_C_DQS_DP<16>")
	)
	(via
		(at 286.93364 -63.334138)
		(size 0.508)
		(drill 0.254)
		(layers "F.Cu" "B.Cu")
		(net "M_C_DQS_DP<16>")
	)
	(segment
		(start 311.15 -5.621782)
		(end 311.15 -5.004054)
		(width 0.1651)
		(layer "B.Cu")
		(net "M_C_DQS_DP<16>")
	)
	(segment
		(start 310.693816 -4.54787)
		(end 310.6166 -4.415536)
		(width 0.1651)
		(layer "B.Cu")
		(net "M_C_DQS_DP<16>")
	)
	(segment
		(start 310.703976 -3.36042)
		(end 311.092596 -2.9718)
		(width 0.1651)
		(layer "B.Cu")
		(net "M_C_DQS_DP<16>")
	)
	(segment
		(start 310.6166 -4.415536)
		(end 310.6166 -3.519932)
		(width 0.1651)
		(layer "B.Cu")
		(net "M_C_DQS_DP<16>")
	)
	(segment
		(start 311.150508 -5.621782)
		(end 311.15 -5.621782)
		(width 0.1651)
		(layer "B.Cu")
		(net "M_C_DQS_DP<16>")
	)
	(segment
		(start 310.6166 -3.519932)
		(end 310.703976 -3.36042)
		(width 0.1651)
		(layer "B.Cu")
		(net "M_C_DQS_DP<16>")
	)
	(segment
		(start 311.15 -5.004054)
		(end 310.693816 -4.54787)
		(width 0.1651)
		(layer "B.Cu")
		(net "M_C_DQS_DP<16>")
	)
	(segment
		(start 311.277 -0.5842)
		(end 311.1246 -0.4318)
		(width 0.14224)
		(layer "In11.Cu")
		(net "M_C_DQS_DP<16>")
	)
	(segment
		(start 300.31944 -40.90416)
		(end 301.38624 -40.90416)
		(width 0.14224)
		(layer "In11.Cu")
		(net "M_C_DQS_DP<16>")
	)
	(segment
		(start 288.3916 -49.5808)
		(end 290.9824 -46.99)
		(width 0.14224)
		(layer "In11.Cu")
		(net "M_C_DQS_DP<16>")
	)
	(segment
		(start 286.426656 -54.722522)
		(end 286.42183 -54.713886)
		(width 0.0889)
		(layer "In11.Cu")
		(net "M_C_DQS_DP<16>")
	)
	(segment
		(start 311.00268 -27.824176)
		(end 311.00268 -26.965148)
		(width 0.14224)
		(layer "In11.Cu")
		(net "M_C_DQS_DP<16>")
	)
	(segment
		(start 311.380886 -28.202382)
		(end 311.00268 -27.824176)
		(width 0.14224)
		(layer "In11.Cu")
		(net "M_C_DQS_DP<16>")
	)
	(segment
		(start 286.426656 -59.675522)
		(end 286.42183 -59.666886)
		(width 0.0889)
		(layer "In11.Cu")
		(net "M_C_DQS_DP<16>")
	)
	(segment
		(start 295.49471 -45.72889)
		(end 295.49471 -45.728382)
		(width 0.14224)
		(layer "In11.Cu")
		(net "M_C_DQS_DP<16>")
	)
	(segment
		(start 286.41548 -59.087004)
		(end 286.42183 -59.076336)
		(width 0.0889)
		(layer "In11.Cu")
		(net "M_C_DQS_DP<16>")
	)
	(segment
		(start 311.61228 -1.03632)
		(end 311.61228 -0.79248)
		(width 0.14224)
		(layer "In11.Cu")
		(net "M_C_DQS_DP<16>")
	)
	(segment
		(start 311.431686 1.32588)
		(end 311.300622 1.32588)
		(width 0.14224)
		(layer "In11.Cu")
		(net "M_C_DQS_DP<16>")
	)
	(segment
		(start 286.410654 -53.705252)
		(end 286.343344 -53.601366)
		(width 0.0889)
		(layer "In11.Cu")
		(net "M_C_DQS_DP<16>")
	)
	(segment
		(start 311.277508 -1.8415)
		(end 311.121044 -1.685036)
		(width 0.14224)
		(layer "In11.Cu")
		(net "M_C_DQS_DP<16>")
	)
	(segment
		(start 311.380886 -26.586942)
		(end 311.670192 -26.586942)
		(width 0.14224)
		(layer "In11.Cu")
		(net "M_C_DQS_DP<16>")
	)
	(segment
		(start 311.817512 -29.279342)
		(end 312.039 -29.057854)
		(width 0.14224)
		(layer "In11.Cu")
		(net "M_C_DQS_DP<16>")
	)
	(segment
		(start 312.039 -29.057854)
		(end 312.039 -28.42387)
		(width 0.14224)
		(layer "In11.Cu")
		(net "M_C_DQS_DP<16>")
	)
	(segment
		(start 301.38624 -40.90416)
		(end 311.02808 -31.26232)
		(width 0.14224)
		(layer "In11.Cu")
		(net "M_C_DQS_DP<16>")
	)
	(segment
		(start 286.426656 -55.713122)
		(end 286.42183 -55.704486)
		(width 0.0889)
		(layer "In11.Cu")
		(net "M_C_DQS_DP<16>")
	)
	(segment
		(start 286.42183 -54.123336)
		(end 286.422084 -54.123082)
		(width 0.0889)
		(layer "In11.Cu")
		(net "M_C_DQS_DP<16>")
	)
	(segment
		(start 311.61228 -2.08788)
		(end 311.3659 -1.8415)
		(width 0.14224)
		(layer "In11.Cu")
		(net "M_C_DQS_DP<16>")
	)
	(segment
		(start 312.039 -28.42387)
		(end 311.817512 -28.202382)
		(width 0.14224)
		(layer "In11.Cu")
		(net "M_C_DQS_DP<16>")
	)
	(segment
		(start 311.61228 -2.731262)
		(end 311.61228 -2.08788)
		(width 0.14224)
		(layer "In11.Cu")
		(net "M_C_DQS_DP<16>")
	)
	(segment
		(start 286.426656 -60.666122)
		(end 286.42183 -60.657486)
		(width 0.0889)
		(layer "In11.Cu")
		(net "M_C_DQS_DP<16>")
	)
	(segment
		(start 311.817512 -28.202382)
		(end 311.380886 -28.202382)
		(width 0.14224)
		(layer "In11.Cu")
		(net "M_C_DQS_DP<16>")
	)
	(segment
		(start 287.553146 -50.165)
		(end 287.86328 -50.165)
		(width 0.0889)
		(layer "In11.Cu")
		(net "M_C_DQS_DP<16>")
	)
	(segment
		(start 311.1246 -0.4318)
		(end 311.1246 -0.1778)
		(width 0.14224)
		(layer "In11.Cu")
		(net "M_C_DQS_DP<16>")
	)
	(segment
		(start 311.605676 -6.35127)
		(end 310.62168 -5.367274)
		(width 0.14224)
		(layer "In11.Cu")
		(net "M_C_DQS_DP<16>")
	)
	(segment
		(start 311.380886 -24.888698)
		(end 311.88914 -24.380444)
		(width 0.14224)
		(layer "In11.Cu")
		(net "M_C_DQS_DP<16>")
	)
	(segment
		(start 311.371742 -2.9718)
		(end 311.61228 -2.731262)
		(width 0.14224)
		(layer "In11.Cu")
		(net "M_C_DQS_DP<16>")
	)
	(segment
		(start 286.410654 -53.705506)
		(end 286.410654 -53.705252)
		(width 0.0889)
		(layer "In11.Cu")
		(net "M_C_DQS_DP<16>")
	)
	(segment
		(start 311.3659 -1.8415)
		(end 311.277508 -1.8415)
		(width 0.14224)
		(layer "In11.Cu")
		(net "M_C_DQS_DP<16>")
	)
	(segment
		(start 286.42183 -60.657486)
		(end 286.41548 -60.646818)
		(width 0.0889)
		(layer "In11.Cu")
		(net "M_C_DQS_DP<16>")
	)
	(segment
		(start 311.300622 1.32588)
		(end 311.092596 1.117854)
		(width 0.14224)
		(layer "In11.Cu")
		(net "M_C_DQS_DP<16>")
	)
	(segment
		(start 311.121044 -1.685036)
		(end 311.121044 -1.346708)
		(width 0.14224)
		(layer "In11.Cu")
		(net "M_C_DQS_DP<16>")
	)
	(segment
		(start 286.426656 -57.694322)
		(end 286.42183 -57.685686)
		(width 0.0889)
		(layer "In11.Cu")
		(net "M_C_DQS_DP<16>")
	)
	(segment
		(start 311.91708 -26.340054)
		(end 311.91708 -26.09215)
		(width 0.14224)
		(layer "In11.Cu")
		(net "M_C_DQS_DP<16>")
	)
	(segment
		(start 311.406286 -29.279342)
		(end 311.817512 -29.279342)
		(width 0.14224)
		(layer "In11.Cu")
		(net "M_C_DQS_DP<16>")
	)
	(segment
		(start 311.00268 -26.965148)
		(end 311.380886 -26.586942)
		(width 0.14224)
		(layer "In11.Cu")
		(net "M_C_DQS_DP<16>")
	)
	(segment
		(start 286.42183 -56.695086)
		(end 286.41548 -56.684418)
		(width 0.0889)
		(layer "In11.Cu")
		(net "M_C_DQS_DP<16>")
	)
	(segment
		(start 311.670192 -26.586942)
		(end 311.91708 -26.340054)
		(width 0.14224)
		(layer "In11.Cu")
		(net "M_C_DQS_DP<16>")
	)
	(segment
		(start 311.1246 -0.1778)
		(end 311.61228 0.30988)
		(width 0.14224)
		(layer "In11.Cu")
		(net "M_C_DQS_DP<16>")
	)
	(segment
		(start 311.248552 -1.2192)
		(end 311.4294 -1.2192)
		(width 0.14224)
		(layer "In11.Cu")
		(net "M_C_DQS_DP<16>")
	)
	(segment
		(start 288.375852 -49.652428)
		(end 288.375852 -49.596548)
		(width 0.0889)
		(layer "In11.Cu")
		(net "M_C_DQS_DP<16>")
	)
	(segment
		(start 311.02808 -31.26232)
		(end 311.02808 -29.657548)
		(width 0.14224)
		(layer "In11.Cu")
		(net "M_C_DQS_DP<16>")
	)
	(segment
		(start 286.343344 -52.019962)
		(end 286.8803 -51.483006)
		(width 0.0889)
		(layer "In11.Cu")
		(net "M_C_DQS_DP<16>")
	)
	(segment
		(start 286.343344 -53.601366)
		(end 286.343344 -52.019962)
		(width 0.0889)
		(layer "In11.Cu")
		(net "M_C_DQS_DP<16>")
	)
	(segment
		(start 311.61228 -0.79248)
		(end 311.404 -0.5842)
		(width 0.14224)
		(layer "In11.Cu")
		(net "M_C_DQS_DP<16>")
	)
	(segment
		(start 286.42183 -54.713886)
		(end 286.41548 -54.703218)
		(width 0.0889)
		(layer "In11.Cu")
		(net "M_C_DQS_DP<16>")
	)
	(segment
		(start 286.426656 -56.703722)
		(end 286.42183 -56.695086)
		(width 0.0889)
		(layer "In11.Cu")
		(net "M_C_DQS_DP<16>")
	)
	(segment
		(start 295.49471 -45.728382)
		(end 300.31944 -40.90416)
		(width 0.14224)
		(layer "In11.Cu")
		(net "M_C_DQS_DP<16>")
	)
	(segment
		(start 310.62168 -5.367274)
		(end 310.62168 -3.442716)
		(width 0.14224)
		(layer "In11.Cu")
		(net "M_C_DQS_DP<16>")
	)
	(segment
		(start 286.42183 -57.685686)
		(end 286.41548 -57.675018)
		(width 0.0889)
		(layer "In11.Cu")
		(net "M_C_DQS_DP<16>")
	)
	(segment
		(start 311.605676 -23.91791)
		(end 311.605676 -6.35127)
		(width 0.14224)
		(layer "In11.Cu")
		(net "M_C_DQS_DP<16>")
	)
	(segment
		(start 311.61228 0.30988)
		(end 311.61228 1.145286)
		(width 0.14224)
		(layer "In11.Cu")
		(net "M_C_DQS_DP<16>")
	)
	(segment
		(start 294.2336 -46.99)
		(end 295.49471 -45.72889)
		(width 0.14224)
		(layer "In11.Cu")
		(net "M_C_DQS_DP<16>")
	)
	(segment
		(start 311.88914 -24.380444)
		(end 311.88914 -24.201374)
		(width 0.14224)
		(layer "In11.Cu")
		(net "M_C_DQS_DP<16>")
	)
	(segment
		(start 286.8803 -51.483006)
		(end 286.8803 -50.837846)
		(width 0.0889)
		(layer "In11.Cu")
		(net "M_C_DQS_DP<16>")
	)
	(segment
		(start 311.092596 -2.9718)
		(end 311.371742 -2.9718)
		(width 0.14224)
		(layer "In11.Cu")
		(net "M_C_DQS_DP<16>")
	)
	(segment
		(start 311.88914 -24.201374)
		(end 311.605676 -23.91791)
		(width 0.14224)
		(layer "In11.Cu")
		(net "M_C_DQS_DP<16>")
	)
	(segment
		(start 311.91708 -26.09215)
		(end 311.380886 -25.555956)
		(width 0.14224)
		(layer "In11.Cu")
		(net "M_C_DQS_DP<16>")
	)
	(segment
		(start 287.86328 -50.165)
		(end 288.375852 -49.652428)
		(width 0.0889)
		(layer "In11.Cu")
		(net "M_C_DQS_DP<16>")
	)
	(segment
		(start 288.375852 -49.596548)
		(end 288.3916 -49.5808)
		(width 0.0889)
		(layer "In11.Cu")
		(net "M_C_DQS_DP<16>")
	)
	(segment
		(start 286.42183 -55.704486)
		(end 286.41548 -55.693818)
		(width 0.0889)
		(layer "In11.Cu")
		(net "M_C_DQS_DP<16>")
	)
	(segment
		(start 286.93364 -63.334138)
		(end 286.931862 -63.330328)
		(width 0.0889)
		(layer "In11.Cu")
		(net "M_C_DQS_DP<16>")
	)
	(segment
		(start 290.9824 -46.99)
		(end 294.2336 -46.99)
		(width 0.14224)
		(layer "In11.Cu")
		(net "M_C_DQS_DP<16>")
	)
	(segment
		(start 311.380886 -25.555956)
		(end 311.380886 -24.888698)
		(width 0.14224)
		(layer "In11.Cu")
		(net "M_C_DQS_DP<16>")
	)
	(segment
		(start 311.61228 1.145286)
		(end 311.431686 1.32588)
		(width 0.14224)
		(layer "In11.Cu")
		(net "M_C_DQS_DP<16>")
	)
	(segment
		(start 310.62168 -3.442716)
		(end 311.092596 -2.9718)
		(width 0.14224)
		(layer "In11.Cu")
		(net "M_C_DQS_DP<16>")
	)
	(segment
		(start 311.404 -0.5842)
		(end 311.277 -0.5842)
		(width 0.14224)
		(layer "In11.Cu")
		(net "M_C_DQS_DP<16>")
	)
	(segment
		(start 311.121044 -1.346708)
		(end 311.248552 -1.2192)
		(width 0.14224)
		(layer "In11.Cu")
		(net "M_C_DQS_DP<16>")
	)
	(segment
		(start 311.02808 -29.657548)
		(end 311.406286 -29.279342)
		(width 0.14224)
		(layer "In11.Cu")
		(net "M_C_DQS_DP<16>")
	)
	(segment
		(start 286.8803 -50.837846)
		(end 287.553146 -50.165)
		(width 0.0889)
		(layer "In11.Cu")
		(net "M_C_DQS_DP<16>")
	)
	(segment
		(start 311.4294 -1.2192)
		(end 311.61228 -1.03632)
		(width 0.14224)
		(layer "In11.Cu")
		(net "M_C_DQS_DP<16>")
	)
	(arc
		(start 286.42183 -59.076336)
		(mid 286.475329 -58.876438)
		(end 286.42183 -58.67654)
		(width 0.0889)
		(layer "In11.Cu")
		(net "M_C_DQS_DP<16>")
	)
	(arc
		(start 286.42183 -55.113936)
		(mid 286.4753 -54.918873)
		(end 286.426656 -54.722522)
		(width 0.0889)
		(layer "In11.Cu")
		(net "M_C_DQS_DP<16>")
	)
	(arc
		(start 286.422084 -54.123082)
		(mid 286.475246 -53.912694)
		(end 286.410654 -53.705506)
		(width 0.0889)
		(layer "In11.Cu")
		(net "M_C_DQS_DP<16>")
	)
	(arc
		(start 286.42183 -61.64834)
		(mid 286.342699 -61.352938)
		(end 286.42183 -61.057536)
		(width 0.0889)
		(layer "In11.Cu")
		(net "M_C_DQS_DP<16>")
	)
	(arc
		(start 286.42183 -58.67654)
		(mid 286.342699 -58.381138)
		(end 286.42183 -58.085736)
		(width 0.0889)
		(layer "In11.Cu")
		(net "M_C_DQS_DP<16>")
	)
	(arc
		(start 286.41548 -57.675018)
		(mid 286.342682 -57.384255)
		(end 286.42183 -57.095136)
		(width 0.0889)
		(layer "In11.Cu")
		(net "M_C_DQS_DP<16>")
	)
	(arc
		(start 286.41548 -54.703218)
		(mid 286.342682 -54.412455)
		(end 286.42183 -54.123336)
		(width 0.0889)
		(layer "In11.Cu")
		(net "M_C_DQS_DP<16>")
	)
	(arc
		(start 286.41548 -60.646818)
		(mid 286.342682 -60.356055)
		(end 286.42183 -60.066936)
		(width 0.0889)
		(layer "In11.Cu")
		(net "M_C_DQS_DP<16>")
	)
	(arc
		(start 286.41548 -56.684418)
		(mid 286.342682 -56.393655)
		(end 286.42183 -56.104536)
		(width 0.0889)
		(layer "In11.Cu")
		(net "M_C_DQS_DP<16>")
	)
	(arc
		(start 286.42183 -60.066936)
		(mid 286.4753 -59.871873)
		(end 286.426656 -59.675522)
		(width 0.0889)
		(layer "In11.Cu")
		(net "M_C_DQS_DP<16>")
	)
	(arc
		(start 286.42183 -57.095136)
		(mid 286.4753 -56.900073)
		(end 286.426656 -56.703722)
		(width 0.0889)
		(layer "In11.Cu")
		(net "M_C_DQS_DP<16>")
	)
	(arc
		(start 286.42183 -59.666886)
		(mid 286.342608 -59.377768)
		(end 286.41548 -59.087004)
		(width 0.0889)
		(layer "In11.Cu")
		(net "M_C_DQS_DP<16>")
	)
	(arc
		(start 286.58693 -62.543436)
		(mid 286.537115 -62.397711)
		(end 286.546036 -62.24397)
		(width 0.0889)
		(layer "In11.Cu")
		(net "M_C_DQS_DP<16>")
	)
	(arc
		(start 286.42183 -56.104536)
		(mid 286.4753 -55.909473)
		(end 286.426656 -55.713122)
		(width 0.0889)
		(layer "In11.Cu")
		(net "M_C_DQS_DP<16>")
	)
	(arc
		(start 286.546036 -62.24397)
		(mid 286.531638 -61.936212)
		(end 286.42183 -61.64834)
		(width 0.0889)
		(layer "In11.Cu")
		(net "M_C_DQS_DP<16>")
	)
	(arc
		(start 286.41548 -55.693818)
		(mid 286.342682 -55.403055)
		(end 286.42183 -55.113936)
		(width 0.0889)
		(layer "In11.Cu")
		(net "M_C_DQS_DP<16>")
	)
	(arc
		(start 286.931862 -63.330328)
		(mid 286.781044 -62.927392)
		(end 286.58693 -62.543436)
		(width 0.0889)
		(layer "In11.Cu")
		(net "M_C_DQS_DP<16>")
	)
	(arc
		(start 286.42183 -58.085736)
		(mid 286.4753 -57.890673)
		(end 286.426656 -57.694322)
		(width 0.0889)
		(layer "In11.Cu")
		(net "M_C_DQS_DP<16>")
	)
	(arc
		(start 286.42183 -61.057536)
		(mid 286.4753 -60.862473)
		(end 286.426656 -60.666122)
		(width 0.0889)
		(layer "In11.Cu")
		(net "M_C_DQS_DP<16>")
	)
	(segment
		(start 301.800006 3.778758)
		(end 301.800006 3.162046)
		(width 0.1651)
		(layer "F.Cu")
		(net "M_C_DQS_DP<15>")
	)
	(segment
		(start 301.36084 1.499616)
		(end 301.742602 1.117854)
		(width 0.1651)
		(layer "F.Cu")
		(net "M_C_DQS_DP<15>")
	)
	(segment
		(start 301.800514 3.778758)
		(end 301.800006 3.778758)
		(width 0.1651)
		(layer "F.Cu")
		(net "M_C_DQS_DP<15>")
	)
	(segment
		(start 301.279306 1.723898)
		(end 301.36084 1.499616)
		(width 0.1651)
		(layer "F.Cu")
		(net "M_C_DQS_DP<15>")
	)
	(segment
		(start 282.354274 -63.334138)
		(end 281.782774 -63.334138)
		(width 0.0889)
		(layer "F.Cu")
		(net "M_C_DQS_DP<15>")
	)
	(segment
		(start 301.363888 2.725928)
		(end 301.279306 2.542032)
		(width 0.1651)
		(layer "F.Cu")
		(net "M_C_DQS_DP<15>")
	)
	(segment
		(start 301.800006 3.162046)
		(end 301.363888 2.725928)
		(width 0.1651)
		(layer "F.Cu")
		(net "M_C_DQS_DP<15>")
	)
	(segment
		(start 301.279306 2.542032)
		(end 301.279306 1.723898)
		(width 0.1651)
		(layer "F.Cu")
		(net "M_C_DQS_DP<15>")
	)
	(via
		(at 301.742602 -2.9718)
		(size 0.508)
		(drill 0.254)
		(layers "F.Cu" "B.Cu")
		(net "M_C_DQS_DP<15>")
	)
	(via
		(at 281.782774 -63.334138)
		(size 0.508)
		(drill 0.254)
		(layers "F.Cu" "B.Cu")
		(net "M_C_DQS_DP<15>")
	)
	(via
		(at 301.742602 1.117854)
		(size 0.508)
		(drill 0.254)
		(layers "F.Cu" "B.Cu")
		(net "M_C_DQS_DP<15>")
	)
	(segment
		(start 301.353982 -3.36042)
		(end 301.742602 -2.9718)
		(width 0.1651)
		(layer "B.Cu")
		(net "M_C_DQS_DP<15>")
	)
	(segment
		(start 301.800514 -5.621782)
		(end 301.800006 -5.621782)
		(width 0.1651)
		(layer "B.Cu")
		(net "M_C_DQS_DP<15>")
	)
	(segment
		(start 301.800006 -5.004054)
		(end 301.343822 -4.54787)
		(width 0.1651)
		(layer "B.Cu")
		(net "M_C_DQS_DP<15>")
	)
	(segment
		(start 301.266606 -4.415536)
		(end 301.266606 -3.519932)
		(width 0.1651)
		(layer "B.Cu")
		(net "M_C_DQS_DP<15>")
	)
	(segment
		(start 301.800006 -5.621782)
		(end 301.800006 -5.004054)
		(width 0.1651)
		(layer "B.Cu")
		(net "M_C_DQS_DP<15>")
	)
	(segment
		(start 301.266606 -3.519932)
		(end 301.353982 -3.36042)
		(width 0.1651)
		(layer "B.Cu")
		(net "M_C_DQS_DP<15>")
	)
	(segment
		(start 301.343822 -4.54787)
		(end 301.266606 -4.415536)
		(width 0.1651)
		(layer "B.Cu")
		(net "M_C_DQS_DP<15>")
	)
	(segment
		(start 302.262286 -1.03632)
		(end 302.079406 -1.2192)
		(width 0.14224)
		(layer "In11.Cu")
		(net "M_C_DQS_DP<15>")
	)
	(segment
		(start 294.563038 -33.96488)
		(end 294.184832 -34.343086)
		(width 0.14224)
		(layer "In11.Cu")
		(net "M_C_DQS_DP<15>")
	)
	(segment
		(start 291.300408 -34.408364)
		(end 291.300408 -34.793936)
		(width 0.14224)
		(layer "In11.Cu")
		(net "M_C_DQS_DP<15>")
	)
	(segment
		(start 291.300408 -34.793936)
		(end 291.138864 -34.95548)
		(width 0.14224)
		(layer "In11.Cu")
		(net "M_C_DQS_DP<15>")
	)
	(segment
		(start 301.77105 -1.685036)
		(end 301.927514 -1.8415)
		(width 0.14224)
		(layer "In11.Cu")
		(net "M_C_DQS_DP<15>")
	)
	(segment
		(start 281.270964 -56.695086)
		(end 281.27579 -56.703722)
		(width 0.0889)
		(layer "In11.Cu")
		(net "M_C_DQS_DP<15>")
	)
	(segment
		(start 281.869134 -47.458884)
		(end 281.042364 -48.285654)
		(width 0.0889)
		(layer "In11.Cu")
		(net "M_C_DQS_DP<15>")
	)
	(segment
		(start 293.107872 -34.733992)
		(end 293.107872 -34.343086)
		(width 0.14224)
		(layer "In11.Cu")
		(net "M_C_DQS_DP<15>")
	)
	(segment
		(start 280.900124 -50.741326)
		(end 280.900124 -51.209194)
		(width 0.0889)
		(layer "In11.Cu")
		(net "M_C_DQS_DP<15>")
	)
	(segment
		(start 302.262286 -2.08788)
		(end 302.262286 -2.731262)
		(width 0.14224)
		(layer "In11.Cu")
		(net "M_C_DQS_DP<15>")
	)
	(segment
		(start 294.184832 -34.733992)
		(end 293.963344 -34.95548)
		(width 0.14224)
		(layer "In11.Cu")
		(net "M_C_DQS_DP<15>")
	)
	(segment
		(start 281.829764 -46.732698)
		(end 281.869134 -46.772068)
		(width 0.0889)
		(layer "In11.Cu")
		(net "M_C_DQS_DP<15>")
	)
	(segment
		(start 281.264614 -55.693818)
		(end 281.270964 -55.704486)
		(width 0.0889)
		(layer "In11.Cu")
		(net "M_C_DQS_DP<15>")
	)
	(segment
		(start 302.262286 -2.731262)
		(end 302.021748 -2.9718)
		(width 0.14224)
		(layer "In11.Cu")
		(net "M_C_DQS_DP<15>")
	)
	(segment
		(start 301.898558 -1.2192)
		(end 301.77105 -1.346708)
		(width 0.14224)
		(layer "In11.Cu")
		(net "M_C_DQS_DP<15>")
	)
	(segment
		(start 281.829764 -45.863002)
		(end 281.829764 -46.7106)
		(width 0.14224)
		(layer "In11.Cu")
		(net "M_C_DQS_DP<15>")
	)
	(segment
		(start 294.184832 -34.343086)
		(end 294.184832 -34.733992)
		(width 0.14224)
		(layer "In11.Cu")
		(net "M_C_DQS_DP<15>")
	)
	(segment
		(start 302.081692 1.32588)
		(end 302.262286 1.145286)
		(width 0.14224)
		(layer "In11.Cu")
		(net "M_C_DQS_DP<15>")
	)
	(segment
		(start 281.264614 -54.703218)
		(end 281.270964 -54.713886)
		(width 0.0889)
		(layer "In11.Cu")
		(net "M_C_DQS_DP<15>")
	)
	(segment
		(start 301.927514 -1.8415)
		(end 302.015906 -1.8415)
		(width 0.14224)
		(layer "In11.Cu")
		(net "M_C_DQS_DP<15>")
	)
	(segment
		(start 291.138864 -34.95548)
		(end 289.203638 -34.95548)
		(width 0.14224)
		(layer "In11.Cu")
		(net "M_C_DQS_DP<15>")
	)
	(segment
		(start 293.963344 -34.95548)
		(end 293.32936 -34.95548)
		(width 0.14224)
		(layer "In11.Cu")
		(net "M_C_DQS_DP<15>")
	)
	(segment
		(start 281.270964 -57.685686)
		(end 281.27579 -57.694322)
		(width 0.0889)
		(layer "In11.Cu")
		(net "M_C_DQS_DP<15>")
	)
	(segment
		(start 301.742602 -2.9718)
		(end 301.271686 -3.442716)
		(width 0.14224)
		(layer "In11.Cu")
		(net "M_C_DQS_DP<15>")
	)
	(segment
		(start 302.015906 -1.8415)
		(end 302.262286 -2.08788)
		(width 0.14224)
		(layer "In11.Cu")
		(net "M_C_DQS_DP<15>")
	)
	(segment
		(start 284.727142 -42.965624)
		(end 281.829764 -45.863002)
		(width 0.14224)
		(layer "In11.Cu")
		(net "M_C_DQS_DP<15>")
	)
	(segment
		(start 295.800272 -34.24936)
		(end 295.515792 -33.96488)
		(width 0.14224)
		(layer "In11.Cu")
		(net "M_C_DQS_DP<15>")
	)
	(segment
		(start 302.255682 -6.541262)
		(end 302.255682 -29.308552)
		(width 0.14224)
		(layer "In11.Cu")
		(net "M_C_DQS_DP<15>")
	)
	(segment
		(start 280.900124 -51.209194)
		(end 281.324558 -51.633628)
		(width 0.0889)
		(layer "In11.Cu")
		(net "M_C_DQS_DP<15>")
	)
	(segment
		(start 281.270964 -59.076336)
		(end 281.264614 -59.087004)
		(width 0.0889)
		(layer "In11.Cu")
		(net "M_C_DQS_DP<15>")
	)
	(segment
		(start 293.32936 -34.95548)
		(end 293.107872 -34.733992)
		(width 0.14224)
		(layer "In11.Cu")
		(net "M_C_DQS_DP<15>")
	)
	(segment
		(start 296.608754 -34.95548)
		(end 295.927526 -34.95548)
		(width 0.14224)
		(layer "In11.Cu")
		(net "M_C_DQS_DP<15>")
	)
	(segment
		(start 281.264614 -60.646818)
		(end 281.270964 -60.657486)
		(width 0.0889)
		(layer "In11.Cu")
		(net "M_C_DQS_DP<15>")
	)
	(segment
		(start 281.270964 -54.713886)
		(end 281.27579 -54.722522)
		(width 0.0889)
		(layer "In11.Cu")
		(net "M_C_DQS_DP<15>")
	)
	(segment
		(start 301.774606 -0.1778)
		(end 301.774606 -0.4318)
		(width 0.14224)
		(layer "In11.Cu")
		(net "M_C_DQS_DP<15>")
	)
	(segment
		(start 301.950628 1.32588)
		(end 302.081692 1.32588)
		(width 0.14224)
		(layer "In11.Cu")
		(net "M_C_DQS_DP<15>")
	)
	(segment
		(start 281.270964 -59.666886)
		(end 281.27579 -59.675522)
		(width 0.0889)
		(layer "In11.Cu")
		(net "M_C_DQS_DP<15>")
	)
	(segment
		(start 302.262286 -0.79248)
		(end 302.262286 -1.03632)
		(width 0.14224)
		(layer "In11.Cu")
		(net "M_C_DQS_DP<15>")
	)
	(segment
		(start 301.77105 -1.346708)
		(end 301.77105 -1.685036)
		(width 0.14224)
		(layer "In11.Cu")
		(net "M_C_DQS_DP<15>")
	)
	(segment
		(start 281.271218 -54.123082)
		(end 281.270964 -54.123336)
		(width 0.0889)
		(layer "In11.Cu")
		(net "M_C_DQS_DP<15>")
	)
	(segment
		(start 281.264614 -56.684418)
		(end 281.270964 -56.695086)
		(width 0.0889)
		(layer "In11.Cu")
		(net "M_C_DQS_DP<15>")
	)
	(segment
		(start 292.729666 -33.96488)
		(end 291.743892 -33.96488)
		(width 0.14224)
		(layer "In11.Cu")
		(net "M_C_DQS_DP<15>")
	)
	(segment
		(start 281.270964 -60.657486)
		(end 281.27579 -60.666122)
		(width 0.0889)
		(layer "In11.Cu")
		(net "M_C_DQS_DP<15>")
	)
	(segment
		(start 281.324558 -51.633628)
		(end 281.324558 -53.921152)
		(width 0.0889)
		(layer "In11.Cu")
		(net "M_C_DQS_DP<15>")
	)
	(segment
		(start 302.021748 -2.9718)
		(end 301.742602 -2.9718)
		(width 0.14224)
		(layer "In11.Cu")
		(net "M_C_DQS_DP<15>")
	)
	(segment
		(start 301.271686 -3.442716)
		(end 301.271686 -5.557266)
		(width 0.14224)
		(layer "In11.Cu")
		(net "M_C_DQS_DP<15>")
	)
	(segment
		(start 281.829764 -46.7106)
		(end 281.829764 -46.732698)
		(width 0.0889)
		(layer "In11.Cu")
		(net "M_C_DQS_DP<15>")
	)
	(segment
		(start 281.270964 -55.704486)
		(end 281.27579 -55.713122)
		(width 0.0889)
		(layer "In11.Cu")
		(net "M_C_DQS_DP<15>")
	)
	(segment
		(start 301.742602 1.117854)
		(end 301.950628 1.32588)
		(width 0.14224)
		(layer "In11.Cu")
		(net "M_C_DQS_DP<15>")
	)
	(segment
		(start 284.727142 -39.432484)
		(end 284.727142 -42.965624)
		(width 0.14224)
		(layer "In11.Cu")
		(net "M_C_DQS_DP<15>")
	)
	(segment
		(start 302.079406 -1.2192)
		(end 301.898558 -1.2192)
		(width 0.14224)
		(layer "In11.Cu")
		(net "M_C_DQS_DP<15>")
	)
	(segment
		(start 281.264614 -57.675018)
		(end 281.270964 -57.685686)
		(width 0.0889)
		(layer "In11.Cu")
		(net "M_C_DQS_DP<15>")
	)
	(segment
		(start 291.743892 -33.96488)
		(end 291.300408 -34.408364)
		(width 0.14224)
		(layer "In11.Cu")
		(net "M_C_DQS_DP<15>")
	)
	(segment
		(start 302.262286 0.30988)
		(end 301.774606 -0.1778)
		(width 0.14224)
		(layer "In11.Cu")
		(net "M_C_DQS_DP<15>")
	)
	(segment
		(start 295.515792 -33.96488)
		(end 294.563038 -33.96488)
		(width 0.14224)
		(layer "In11.Cu")
		(net "M_C_DQS_DP<15>")
	)
	(segment
		(start 281.042364 -48.285654)
		(end 281.042364 -50.368962)
		(width 0.0889)
		(layer "In11.Cu")
		(net "M_C_DQS_DP<15>")
	)
	(segment
		(start 293.107872 -34.343086)
		(end 292.729666 -33.96488)
		(width 0.14224)
		(layer "In11.Cu")
		(net "M_C_DQS_DP<15>")
	)
	(segment
		(start 281.782774 -63.332106)
		(end 281.782774 -63.334138)
		(width 0.0889)
		(layer "In11.Cu")
		(net "M_C_DQS_DP<15>")
	)
	(segment
		(start 281.780996 -63.330328)
		(end 281.782774 -63.332106)
		(width 0.0889)
		(layer "In11.Cu")
		(net "M_C_DQS_DP<15>")
	)
	(segment
		(start 281.042364 -50.368962)
		(end 280.900124 -50.741326)
		(width 0.0889)
		(layer "In11.Cu")
		(net "M_C_DQS_DP<15>")
	)
	(segment
		(start 301.774606 -0.4318)
		(end 301.927006 -0.5842)
		(width 0.14224)
		(layer "In11.Cu")
		(net "M_C_DQS_DP<15>")
	)
	(segment
		(start 302.262286 1.145286)
		(end 302.262286 0.30988)
		(width 0.14224)
		(layer "In11.Cu")
		(net "M_C_DQS_DP<15>")
	)
	(segment
		(start 301.927006 -0.5842)
		(end 302.054006 -0.5842)
		(width 0.14224)
		(layer "In11.Cu")
		(net "M_C_DQS_DP<15>")
	)
	(segment
		(start 302.255682 -29.308552)
		(end 296.608754 -34.95548)
		(width 0.14224)
		(layer "In11.Cu")
		(net "M_C_DQS_DP<15>")
	)
	(segment
		(start 281.869134 -46.772068)
		(end 281.869134 -47.458884)
		(width 0.0889)
		(layer "In11.Cu")
		(net "M_C_DQS_DP<15>")
	)
	(segment
		(start 295.927526 -34.95548)
		(end 295.800272 -34.828226)
		(width 0.14224)
		(layer "In11.Cu")
		(net "M_C_DQS_DP<15>")
	)
	(segment
		(start 295.800272 -34.828226)
		(end 295.800272 -34.24936)
		(width 0.14224)
		(layer "In11.Cu")
		(net "M_C_DQS_DP<15>")
	)
	(segment
		(start 301.271686 -5.557266)
		(end 302.255682 -6.541262)
		(width 0.14224)
		(layer "In11.Cu")
		(net "M_C_DQS_DP<15>")
	)
	(segment
		(start 302.054006 -0.5842)
		(end 302.262286 -0.79248)
		(width 0.14224)
		(layer "In11.Cu")
		(net "M_C_DQS_DP<15>")
	)
	(segment
		(start 289.203638 -34.95548)
		(end 284.727142 -39.432484)
		(width 0.14224)
		(layer "In11.Cu")
		(net "M_C_DQS_DP<15>")
	)
	(arc
		(start 281.264614 -59.087004)
		(mid 281.191816 -59.377767)
		(end 281.270964 -59.666886)
		(width 0.0889)
		(layer "In11.Cu")
		(net "M_C_DQS_DP<15>")
	)
	(arc
		(start 281.270964 -58.67654)
		(mid 281.324463 -58.876438)
		(end 281.270964 -59.076336)
		(width 0.0889)
		(layer "In11.Cu")
		(net "M_C_DQS_DP<15>")
	)
	(arc
		(start 281.324558 -53.921152)
		(mid 281.311333 -54.025671)
		(end 281.271218 -54.123082)
		(width 0.0889)
		(layer "In11.Cu")
		(net "M_C_DQS_DP<15>")
	)
	(arc
		(start 281.270964 -54.123336)
		(mid 281.191742 -54.412454)
		(end 281.264614 -54.703218)
		(width 0.0889)
		(layer "In11.Cu")
		(net "M_C_DQS_DP<15>")
	)
	(arc
		(start 281.27579 -57.694322)
		(mid 281.324545 -57.890674)
		(end 281.270964 -58.085736)
		(width 0.0889)
		(layer "In11.Cu")
		(net "M_C_DQS_DP<15>")
	)
	(arc
		(start 281.270964 -60.066936)
		(mid 281.191742 -60.356054)
		(end 281.264614 -60.646818)
		(width 0.0889)
		(layer "In11.Cu")
		(net "M_C_DQS_DP<15>")
	)
	(arc
		(start 281.436064 -62.543436)
		(mid 281.630159 -62.9274)
		(end 281.780996 -63.330328)
		(width 0.0889)
		(layer "In11.Cu")
		(net "M_C_DQS_DP<15>")
	)
	(arc
		(start 281.27579 -55.713122)
		(mid 281.324545 -55.909474)
		(end 281.270964 -56.104536)
		(width 0.0889)
		(layer "In11.Cu")
		(net "M_C_DQS_DP<15>")
	)
	(arc
		(start 281.270964 -57.095136)
		(mid 281.191742 -57.384254)
		(end 281.264614 -57.675018)
		(width 0.0889)
		(layer "In11.Cu")
		(net "M_C_DQS_DP<15>")
	)
	(arc
		(start 281.27579 -56.703722)
		(mid 281.324545 -56.900074)
		(end 281.270964 -57.095136)
		(width 0.0889)
		(layer "In11.Cu")
		(net "M_C_DQS_DP<15>")
	)
	(arc
		(start 281.27579 -59.675522)
		(mid 281.324545 -59.871874)
		(end 281.270964 -60.066936)
		(width 0.0889)
		(layer "In11.Cu")
		(net "M_C_DQS_DP<15>")
	)
	(arc
		(start 281.39517 -62.24397)
		(mid 281.386269 -62.397709)
		(end 281.436064 -62.543436)
		(width 0.0889)
		(layer "In11.Cu")
		(net "M_C_DQS_DP<15>")
	)
	(arc
		(start 281.270964 -58.085736)
		(mid 281.191833 -58.381138)
		(end 281.270964 -58.67654)
		(width 0.0889)
		(layer "In11.Cu")
		(net "M_C_DQS_DP<15>")
	)
	(arc
		(start 281.27579 -60.666122)
		(mid 281.324545 -60.862474)
		(end 281.270964 -61.057536)
		(width 0.0889)
		(layer "In11.Cu")
		(net "M_C_DQS_DP<15>")
	)
	(arc
		(start 281.270964 -56.104536)
		(mid 281.191742 -56.393654)
		(end 281.264614 -56.684418)
		(width 0.0889)
		(layer "In11.Cu")
		(net "M_C_DQS_DP<15>")
	)
	(arc
		(start 281.270964 -61.057536)
		(mid 281.191833 -61.352938)
		(end 281.270964 -61.64834)
		(width 0.0889)
		(layer "In11.Cu")
		(net "M_C_DQS_DP<15>")
	)
	(arc
		(start 281.270964 -55.113936)
		(mid 281.191742 -55.403054)
		(end 281.264614 -55.693818)
		(width 0.0889)
		(layer "In11.Cu")
		(net "M_C_DQS_DP<15>")
	)
	(arc
		(start 281.270964 -61.64834)
		(mid 281.380834 -61.936199)
		(end 281.39517 -62.24397)
		(width 0.0889)
		(layer "In11.Cu")
		(net "M_C_DQS_DP<15>")
	)
	(arc
		(start 281.27579 -54.722522)
		(mid 281.324545 -54.918874)
		(end 281.270964 -55.113936)
		(width 0.0889)
		(layer "In11.Cu")
		(net "M_C_DQS_DP<15>")
	)
	(segment
		(start 292.450012 3.162046)
		(end 292.450012 3.778758)
		(width 0.1651)
		(layer "F.Cu")
		(net "M_C_DQS_DP<14>")
	)
	(segment
		(start 292.013894 2.725928)
		(end 292.450012 3.162046)
		(width 0.1651)
		(layer "F.Cu")
		(net "M_C_DQS_DP<14>")
	)
	(segment
		(start 292.010846 1.499616)
		(end 291.929312 1.723898)
		(width 0.1651)
		(layer "F.Cu")
		(net "M_C_DQS_DP<14>")
	)
	(segment
		(start 292.450012 3.778758)
		(end 292.45052 3.778758)
		(width 0.1651)
		(layer "F.Cu")
		(net "M_C_DQS_DP<14>")
	)
	(segment
		(start 279.778714 -59.866784)
		(end 279.207214 -59.866784)
		(width 0.0889)
		(layer "F.Cu")
		(net "M_C_DQS_DP<14>")
	)
	(segment
		(start 292.392608 1.117854)
		(end 292.010846 1.499616)
		(width 0.1651)
		(layer "F.Cu")
		(net "M_C_DQS_DP<14>")
	)
	(segment
		(start 291.929312 2.542032)
		(end 292.013894 2.725928)
		(width 0.1651)
		(layer "F.Cu")
		(net "M_C_DQS_DP<14>")
	)
	(segment
		(start 291.929312 1.723898)
		(end 291.929312 2.542032)
		(width 0.1651)
		(layer "F.Cu")
		(net "M_C_DQS_DP<14>")
	)
	(via
		(at 292.392608 -2.9718)
		(size 0.508)
		(drill 0.254)
		(layers "F.Cu" "B.Cu")
		(net "M_C_DQS_DP<14>")
	)
	(via
		(at 292.392608 1.117854)
		(size 0.508)
		(drill 0.254)
		(layers "F.Cu" "B.Cu")
		(net "M_C_DQS_DP<14>")
	)
	(via
		(at 279.207214 -59.866784)
		(size 0.508)
		(drill 0.254)
		(layers "F.Cu" "B.Cu")
		(net "M_C_DQS_DP<14>")
	)
	(segment
		(start 292.003988 -3.36042)
		(end 292.392608 -2.9718)
		(width 0.1651)
		(layer "B.Cu")
		(net "M_C_DQS_DP<14>")
	)
	(segment
		(start 292.450012 -5.621782)
		(end 292.450012 -5.004054)
		(width 0.1651)
		(layer "B.Cu")
		(net "M_C_DQS_DP<14>")
	)
	(segment
		(start 292.45052 -5.621782)
		(end 292.450012 -5.621782)
		(width 0.1651)
		(layer "B.Cu")
		(net "M_C_DQS_DP<14>")
	)
	(segment
		(start 291.916612 -3.519932)
		(end 292.003988 -3.36042)
		(width 0.1651)
		(layer "B.Cu")
		(net "M_C_DQS_DP<14>")
	)
	(segment
		(start 291.993828 -4.54787)
		(end 291.916612 -4.415536)
		(width 0.1651)
		(layer "B.Cu")
		(net "M_C_DQS_DP<14>")
	)
	(segment
		(start 291.916612 -4.415536)
		(end 291.916612 -3.519932)
		(width 0.1651)
		(layer "B.Cu")
		(net "M_C_DQS_DP<14>")
	)
	(segment
		(start 292.450012 -5.004054)
		(end 291.993828 -4.54787)
		(width 0.1651)
		(layer "B.Cu")
		(net "M_C_DQS_DP<14>")
	)
	(segment
		(start 279.20696 -51.975766)
		(end 280.0223 -51.160426)
		(width 0.0889)
		(layer "In4.Cu")
		(net "M_C_DQS_DP<14>")
	)
	(segment
		(start 280.0223 -51.160426)
		(end 280.0223 -49.989994)
		(width 0.0889)
		(layer "In4.Cu")
		(net "M_C_DQS_DP<14>")
	)
	(segment
		(start 278.689054 -54.629304)
		(end 278.695404 -54.618636)
		(width 0.0889)
		(layer "In4.Cu")
		(net "M_C_DQS_DP<14>")
	)
	(segment
		(start 278.689054 -55.619904)
		(end 278.695404 -55.609236)
		(width 0.0889)
		(layer "In4.Cu")
		(net "M_C_DQS_DP<14>")
	)
	(segment
		(start 293.049452 -30.7467)
		(end 293.049452 -30.404816)
		(width 0.14224)
		(layer "In4.Cu")
		(net "M_C_DQS_DP<14>")
	)
	(segment
		(start 281.788362 -47.275496)
		(end 281.788362 -42.095166)
		(width 0.14224)
		(layer "In4.Cu")
		(net "M_C_DQS_DP<14>")
	)
	(segment
		(start 292.629082 -31.16707)
		(end 293.049452 -30.7467)
		(width 0.14224)
		(layer "In4.Cu")
		(net "M_C_DQS_DP<14>")
	)
	(segment
		(start 291.921692 -5.367274)
		(end 291.921692 -3.442716)
		(width 0.14224)
		(layer "In4.Cu")
		(net "M_C_DQS_DP<14>")
	)
	(segment
		(start 280.0223 -49.989994)
		(end 281.827732 -48.184562)
		(width 0.0889)
		(layer "In4.Cu")
		(net "M_C_DQS_DP<14>")
	)
	(segment
		(start 281.827732 -48.184562)
		(end 281.827732 -47.336964)
		(width 0.0889)
		(layer "In4.Cu")
		(net "M_C_DQS_DP<14>")
	)
	(segment
		(start 279.117552 -59.528202)
		(end 278.958294 -59.248294)
		(width 0.0889)
		(layer "In4.Cu")
		(net "M_C_DQS_DP<14>")
	)
	(segment
		(start 291.921692 -3.442716)
		(end 292.392608 -2.9718)
		(width 0.14224)
		(layer "In4.Cu")
		(net "M_C_DQS_DP<14>")
	)
	(segment
		(start 291.772594 -30.652212)
		(end 292.287452 -31.16707)
		(width 0.14224)
		(layer "In4.Cu")
		(net "M_C_DQS_DP<14>")
	)
	(segment
		(start 278.749252 -53.429408)
		(end 278.749252 -53.235352)
		(width 0.0889)
		(layer "In4.Cu")
		(net "M_C_DQS_DP<14>")
	)
	(segment
		(start 278.689054 -57.601104)
		(end 278.695404 -57.590436)
		(width 0.0889)
		(layer "In4.Cu")
		(net "M_C_DQS_DP<14>")
	)
	(segment
		(start 292.905688 -30.261052)
		(end 292.905688 -6.35127)
		(width 0.14224)
		(layer "In4.Cu")
		(net "M_C_DQS_DP<14>")
	)
	(segment
		(start 291.28466 -30.652212)
		(end 291.772594 -30.652212)
		(width 0.14224)
		(layer "In4.Cu")
		(net "M_C_DQS_DP<14>")
	)
	(segment
		(start 278.749252 -53.235352)
		(end 279.20696 -52.777644)
		(width 0.0889)
		(layer "In4.Cu")
		(net "M_C_DQS_DP<14>")
	)
	(segment
		(start 279.20696 -52.777644)
		(end 279.20696 -51.975766)
		(width 0.0889)
		(layer "In4.Cu")
		(net "M_C_DQS_DP<14>")
	)
	(segment
		(start 278.695404 -57.590436)
		(end 278.70023 -57.5818)
		(width 0.0889)
		(layer "In4.Cu")
		(net "M_C_DQS_DP<14>")
	)
	(segment
		(start 278.695404 -55.609236)
		(end 278.70023 -55.6006)
		(width 0.0889)
		(layer "In4.Cu")
		(net "M_C_DQS_DP<14>")
	)
	(segment
		(start 292.287452 -31.16707)
		(end 292.629082 -31.16707)
		(width 0.14224)
		(layer "In4.Cu")
		(net "M_C_DQS_DP<14>")
	)
	(segment
		(start 293.049452 -30.404816)
		(end 292.905688 -30.261052)
		(width 0.14224)
		(layer "In4.Cu")
		(net "M_C_DQS_DP<14>")
	)
	(segment
		(start 291.190172 -32.354774)
		(end 290.653978 -31.81858)
		(width 0.14224)
		(layer "In4.Cu")
		(net "M_C_DQS_DP<14>")
	)
	(segment
		(start 281.788362 -42.095166)
		(end 291.190172 -32.693356)
		(width 0.14224)
		(layer "In4.Cu")
		(net "M_C_DQS_DP<14>")
	)
	(segment
		(start 281.788362 -47.297594)
		(end 281.788362 -47.275496)
		(width 0.0889)
		(layer "In4.Cu")
		(net "M_C_DQS_DP<14>")
	)
	(segment
		(start 290.653978 -31.282894)
		(end 291.28466 -30.652212)
		(width 0.14224)
		(layer "In4.Cu")
		(net "M_C_DQS_DP<14>")
	)
	(segment
		(start 290.653978 -31.81858)
		(end 290.653978 -31.282894)
		(width 0.14224)
		(layer "In4.Cu")
		(net "M_C_DQS_DP<14>")
	)
	(segment
		(start 281.827732 -47.336964)
		(end 281.788362 -47.297594)
		(width 0.0889)
		(layer "In4.Cu")
		(net "M_C_DQS_DP<14>")
	)
	(segment
		(start 278.695404 -56.599836)
		(end 278.70023 -56.5912)
		(width 0.0889)
		(layer "In4.Cu")
		(net "M_C_DQS_DP<14>")
	)
	(segment
		(start 291.190172 -32.693356)
		(end 291.190172 -32.354774)
		(width 0.14224)
		(layer "In4.Cu")
		(net "M_C_DQS_DP<14>")
	)
	(segment
		(start 278.748998 -53.429662)
		(end 278.749252 -53.429408)
		(width 0.0889)
		(layer "In4.Cu")
		(net "M_C_DQS_DP<14>")
	)
	(segment
		(start 278.958294 -59.248294)
		(end 278.84374 -59.046872)
		(width 0.0889)
		(layer "In4.Cu")
		(net "M_C_DQS_DP<14>")
	)
	(segment
		(start 292.905688 -6.35127)
		(end 291.921692 -5.367274)
		(width 0.14224)
		(layer "In4.Cu")
		(net "M_C_DQS_DP<14>")
	)
	(segment
		(start 278.689054 -56.610504)
		(end 278.695404 -56.599836)
		(width 0.0889)
		(layer "In4.Cu")
		(net "M_C_DQS_DP<14>")
	)
	(segment
		(start 278.695404 -54.618636)
		(end 278.70023 -54.61)
		(width 0.0889)
		(layer "In4.Cu")
		(net "M_C_DQS_DP<14>")
	)
	(arc
		(start 278.70023 -57.5818)
		(mid 278.748985 -57.385448)
		(end 278.695404 -57.190386)
		(width 0.0889)
		(layer "In4.Cu")
		(net "M_C_DQS_DP<14>")
	)
	(arc
		(start 278.70023 -56.5912)
		(mid 278.748985 -56.394848)
		(end 278.695404 -56.199786)
		(width 0.0889)
		(layer "In4.Cu")
		(net "M_C_DQS_DP<14>")
	)
	(arc
		(start 278.70023 -55.6006)
		(mid 278.748985 -55.404248)
		(end 278.695404 -55.209186)
		(width 0.0889)
		(layer "In4.Cu")
		(net "M_C_DQS_DP<14>")
	)
	(arc
		(start 278.695404 -53.627782)
		(mid 278.735127 -53.532217)
		(end 278.748998 -53.429662)
		(width 0.0889)
		(layer "In4.Cu")
		(net "M_C_DQS_DP<14>")
	)
	(arc
		(start 278.726138 -58.247534)
		(mid 278.712295 -58.213556)
		(end 278.695404 -58.180986)
		(width 0.0889)
		(layer "In4.Cu")
		(net "M_C_DQS_DP<14>")
	)
	(arc
		(start 278.84374 -59.046872)
		(mid 278.760536 -58.733667)
		(end 278.747982 -58.40984)
		(width 0.0889)
		(layer "In4.Cu")
		(net "M_C_DQS_DP<14>")
	)
	(arc
		(start 278.695404 -55.209186)
		(mid 278.616182 -54.920068)
		(end 278.689054 -54.629304)
		(width 0.0889)
		(layer "In4.Cu")
		(net "M_C_DQS_DP<14>")
	)
	(arc
		(start 278.695404 -54.218586)
		(mid 278.616273 -53.923184)
		(end 278.695404 -53.627782)
		(width 0.0889)
		(layer "In4.Cu")
		(net "M_C_DQS_DP<14>")
	)
	(arc
		(start 278.695404 -57.190386)
		(mid 278.616182 -56.901268)
		(end 278.689054 -56.610504)
		(width 0.0889)
		(layer "In4.Cu")
		(net "M_C_DQS_DP<14>")
	)
	(arc
		(start 278.70023 -54.61)
		(mid 278.748985 -54.413648)
		(end 278.695404 -54.218586)
		(width 0.0889)
		(layer "In4.Cu")
		(net "M_C_DQS_DP<14>")
	)
	(arc
		(start 278.695404 -56.199786)
		(mid 278.616182 -55.910668)
		(end 278.689054 -55.619904)
		(width 0.0889)
		(layer "In4.Cu")
		(net "M_C_DQS_DP<14>")
	)
	(arc
		(start 278.695404 -58.180986)
		(mid 278.616182 -57.891868)
		(end 278.689054 -57.601104)
		(width 0.0889)
		(layer "In4.Cu")
		(net "M_C_DQS_DP<14>")
	)
	(arc
		(start 278.747982 -58.40984)
		(mid 278.745463 -58.327555)
		(end 278.726138 -58.247534)
		(width 0.0889)
		(layer "In4.Cu")
		(net "M_C_DQS_DP<14>")
	)
	(arc
		(start 279.207214 -59.866784)
		(mid 279.184431 -59.691651)
		(end 279.117552 -59.528202)
		(width 0.0889)
		(layer "In4.Cu")
		(net "M_C_DQS_DP<14>")
	)
	(segment
		(start 292.912292 1.145286)
		(end 292.731698 1.32588)
		(width 0.14224)
		(layer "In11.Cu")
		(net "M_C_DQS_DP<14>")
	)
	(segment
		(start 292.704012 -0.5842)
		(end 292.577012 -0.5842)
		(width 0.14224)
		(layer "In11.Cu")
		(net "M_C_DQS_DP<14>")
	)
	(segment
		(start 292.421056 -1.346708)
		(end 292.548564 -1.2192)
		(width 0.14224)
		(layer "In11.Cu")
		(net "M_C_DQS_DP<14>")
	)
	(segment
		(start 292.912292 -0.79248)
		(end 292.704012 -0.5842)
		(width 0.14224)
		(layer "In11.Cu")
		(net "M_C_DQS_DP<14>")
	)
	(segment
		(start 292.548564 -1.2192)
		(end 292.729412 -1.2192)
		(width 0.14224)
		(layer "In11.Cu")
		(net "M_C_DQS_DP<14>")
	)
	(segment
		(start 292.729412 -1.2192)
		(end 292.912292 -1.03632)
		(width 0.14224)
		(layer "In11.Cu")
		(net "M_C_DQS_DP<14>")
	)
	(segment
		(start 292.421056 -1.685036)
		(end 292.421056 -1.346708)
		(width 0.14224)
		(layer "In11.Cu")
		(net "M_C_DQS_DP<14>")
	)
	(segment
		(start 292.912292 -2.08788)
		(end 292.665912 -1.8415)
		(width 0.14224)
		(layer "In11.Cu")
		(net "M_C_DQS_DP<14>")
	)
	(segment
		(start 292.671754 -2.9718)
		(end 292.912292 -2.731262)
		(width 0.14224)
		(layer "In11.Cu")
		(net "M_C_DQS_DP<14>")
	)
	(segment
		(start 292.912292 -2.731262)
		(end 292.912292 -2.08788)
		(width 0.14224)
		(layer "In11.Cu")
		(net "M_C_DQS_DP<14>")
	)
	(segment
		(start 292.392608 -2.9718)
		(end 292.671754 -2.9718)
		(width 0.14224)
		(layer "In11.Cu")
		(net "M_C_DQS_DP<14>")
	)
	(segment
		(start 292.424612 -0.4318)
		(end 292.424612 -0.1778)
		(width 0.14224)
		(layer "In11.Cu")
		(net "M_C_DQS_DP<14>")
	)
	(segment
		(start 292.577012 -0.5842)
		(end 292.424612 -0.4318)
		(width 0.14224)
		(layer "In11.Cu")
		(net "M_C_DQS_DP<14>")
	)
	(segment
		(start 292.912292 0.30988)
		(end 292.912292 1.145286)
		(width 0.14224)
		(layer "In11.Cu")
		(net "M_C_DQS_DP<14>")
	)
	(segment
		(start 292.57752 -1.8415)
		(end 292.421056 -1.685036)
		(width 0.14224)
		(layer "In11.Cu")
		(net "M_C_DQS_DP<14>")
	)
	(segment
		(start 292.912292 -1.03632)
		(end 292.912292 -0.79248)
		(width 0.14224)
		(layer "In11.Cu")
		(net "M_C_DQS_DP<14>")
	)
	(segment
		(start 292.600634 1.32588)
		(end 292.392608 1.117854)
		(width 0.14224)
		(layer "In11.Cu")
		(net "M_C_DQS_DP<14>")
	)
	(segment
		(start 292.665912 -1.8415)
		(end 292.57752 -1.8415)
		(width 0.14224)
		(layer "In11.Cu")
		(net "M_C_DQS_DP<14>")
	)
	(segment
		(start 292.424612 -0.1778)
		(end 292.912292 0.30988)
		(width 0.14224)
		(layer "In11.Cu")
		(net "M_C_DQS_DP<14>")
	)
	(segment
		(start 292.731698 1.32588)
		(end 292.600634 1.32588)
		(width 0.14224)
		(layer "In11.Cu")
		(net "M_C_DQS_DP<14>")
	)
	(segment
		(start 282.579064 2.542032)
		(end 282.579064 1.723898)
		(width 0.1651)
		(layer "F.Cu")
		(net "M_C_DQS_DP<13>")
	)
	(segment
		(start 282.579064 1.723898)
		(end 282.660598 1.499616)
		(width 0.1651)
		(layer "F.Cu")
		(net "M_C_DQS_DP<13>")
	)
	(segment
		(start 283.100272 3.778758)
		(end 283.099764 3.778758)
		(width 0.1651)
		(layer "F.Cu")
		(net "M_C_DQS_DP<13>")
	)
	(segment
		(start 283.099764 3.161792)
		(end 282.663646 2.725674)
		(width 0.1651)
		(layer "F.Cu")
		(net "M_C_DQS_DP<13>")
	)
	(segment
		(start 282.660598 1.499616)
		(end 283.04236 1.117854)
		(width 0.1651)
		(layer "F.Cu")
		(net "M_C_DQS_DP<13>")
	)
	(segment
		(start 282.663646 2.725674)
		(end 282.579064 2.542032)
		(width 0.1651)
		(layer "F.Cu")
		(net "M_C_DQS_DP<13>")
	)
	(segment
		(start 283.099764 3.778758)
		(end 283.099764 3.161792)
		(width 0.1651)
		(layer "F.Cu")
		(net "M_C_DQS_DP<13>")
	)
	(segment
		(start 274.056348 -59.866784)
		(end 274.627848 -59.866784)
		(width 0.0889)
		(layer "F.Cu")
		(net "M_C_DQS_DP<13>")
	)
	(via
		(at 283.04236 1.117854)
		(size 0.508)
		(drill 0.254)
		(layers "F.Cu" "B.Cu")
		(net "M_C_DQS_DP<13>")
	)
	(via
		(at 283.04236 -2.9718)
		(size 0.508)
		(drill 0.254)
		(layers "F.Cu" "B.Cu")
		(net "M_C_DQS_DP<13>")
	)
	(via
		(at 274.056348 -59.866784)
		(size 0.508)
		(drill 0.254)
		(layers "F.Cu" "B.Cu")
		(net "M_C_DQS_DP<13>")
	)
	(segment
		(start 282.566364 -3.519932)
		(end 282.65374 -3.36042)
		(width 0.1651)
		(layer "B.Cu")
		(net "M_C_DQS_DP<13>")
	)
	(segment
		(start 283.100272 -5.621782)
		(end 283.099764 -5.621782)
		(width 0.1651)
		(layer "B.Cu")
		(net "M_C_DQS_DP<13>")
	)
	(segment
		(start 283.099764 -5.004054)
		(end 282.64358 -4.54787)
		(width 0.1651)
		(layer "B.Cu")
		(net "M_C_DQS_DP<13>")
	)
	(segment
		(start 282.566364 -4.415536)
		(end 282.566364 -3.519932)
		(width 0.1651)
		(layer "B.Cu")
		(net "M_C_DQS_DP<13>")
	)
	(segment
		(start 283.099764 -5.621782)
		(end 283.099764 -5.004054)
		(width 0.1651)
		(layer "B.Cu")
		(net "M_C_DQS_DP<13>")
	)
	(segment
		(start 282.64358 -4.54787)
		(end 282.566364 -4.415536)
		(width 0.1651)
		(layer "B.Cu")
		(net "M_C_DQS_DP<13>")
	)
	(segment
		(start 282.65374 -3.36042)
		(end 283.04236 -2.9718)
		(width 0.1651)
		(layer "B.Cu")
		(net "M_C_DQS_DP<13>")
	)
	(segment
		(start 283.562044 -0.79248)
		(end 283.562044 -1.03632)
		(width 0.14224)
		(layer "In11.Cu")
		(net "M_C_DQS_DP<13>")
	)
	(segment
		(start 283.87548 -25.523952)
		(end 283.555694 -25.204166)
		(width 0.14224)
		(layer "In11.Cu")
		(net "M_C_DQS_DP<13>")
	)
	(segment
		(start 282.857448 -27.46629)
		(end 283.748226 -27.46629)
		(width 0.14224)
		(layer "In11.Cu")
		(net "M_C_DQS_DP<13>")
	)
	(segment
		(start 283.38145 1.32588)
		(end 283.562044 1.145286)
		(width 0.14224)
		(layer "In11.Cu")
		(net "M_C_DQS_DP<13>")
	)
	(segment
		(start 282.571444 -3.442716)
		(end 283.04236 -2.9718)
		(width 0.14224)
		(layer "In11.Cu")
		(net "M_C_DQS_DP<13>")
	)
	(segment
		(start 283.555694 -25.204166)
		(end 283.555694 -6.351524)
		(width 0.14224)
		(layer "In11.Cu")
		(net "M_C_DQS_DP<13>")
	)
	(segment
		(start 273.538188 -56.610504)
		(end 273.544538 -56.599836)
		(width 0.0889)
		(layer "In11.Cu")
		(net "M_C_DQS_DP<13>")
	)
	(segment
		(start 283.87548 -27.339036)
		(end 283.87548 -25.523952)
		(width 0.14224)
		(layer "In11.Cu")
		(net "M_C_DQS_DP<13>")
	)
	(segment
		(start 273.544538 -55.20944)
		(end 273.544538 -55.209186)
		(width 0.0889)
		(layer "In11.Cu")
		(net "M_C_DQS_DP<13>")
	)
	(segment
		(start 283.04236 1.117854)
		(end 283.250386 1.32588)
		(width 0.14224)
		(layer "In11.Cu")
		(net "M_C_DQS_DP<13>")
	)
	(segment
		(start 273.544538 -55.209186)
		(end 273.446494 -55.039006)
		(width 0.0889)
		(layer "In11.Cu")
		(net "M_C_DQS_DP<13>")
	)
	(segment
		(start 282.45308 -27.870658)
		(end 282.857448 -27.46629)
		(width 0.14224)
		(layer "In11.Cu")
		(net "M_C_DQS_DP<13>")
	)
	(segment
		(start 273.446494 -55.039006)
		(end 273.446494 -52.93995)
		(width 0.0889)
		(layer "In11.Cu")
		(net "M_C_DQS_DP<13>")
	)
	(segment
		(start 283.562044 -2.08788)
		(end 283.562044 -2.731262)
		(width 0.14224)
		(layer "In11.Cu")
		(net "M_C_DQS_DP<13>")
	)
	(segment
		(start 273.544538 -56.599836)
		(end 273.549364 -56.5912)
		(width 0.0889)
		(layer "In11.Cu")
		(net "M_C_DQS_DP<13>")
	)
	(segment
		(start 283.562044 0.30988)
		(end 283.074364 -0.1778)
		(width 0.14224)
		(layer "In11.Cu")
		(net "M_C_DQS_DP<13>")
	)
	(segment
		(start 274.32 -47.725838)
		(end 274.32 -47.30877)
		(width 0.0889)
		(layer "In11.Cu")
		(net "M_C_DQS_DP<13>")
	)
	(segment
		(start 273.64817 -52.107846)
		(end 274.040346 -51.71567)
		(width 0.0889)
		(layer "In11.Cu")
		(net "M_C_DQS_DP<13>")
	)
	(segment
		(start 283.250386 1.32588)
		(end 283.38145 1.32588)
		(width 0.14224)
		(layer "In11.Cu")
		(net "M_C_DQS_DP<13>")
	)
	(segment
		(start 274.32 -47.30877)
		(end 274.28063 -47.2694)
		(width 0.0889)
		(layer "In11.Cu")
		(net "M_C_DQS_DP<13>")
	)
	(segment
		(start 283.227272 -1.8415)
		(end 283.315664 -1.8415)
		(width 0.14224)
		(layer "In11.Cu")
		(net "M_C_DQS_DP<13>")
	)
	(segment
		(start 283.321506 -2.9718)
		(end 283.04236 -2.9718)
		(width 0.14224)
		(layer "In11.Cu")
		(net "M_C_DQS_DP<13>")
	)
	(segment
		(start 274.040346 -51.71567)
		(end 274.040346 -48.005492)
		(width 0.0889)
		(layer "In11.Cu")
		(net "M_C_DQS_DP<13>")
	)
	(segment
		(start 283.87548 -29.303218)
		(end 283.653992 -29.08173)
		(width 0.14224)
		(layer "In11.Cu")
		(net "M_C_DQS_DP<13>")
	)
	(segment
		(start 283.074364 -0.4318)
		(end 283.226764 -0.5842)
		(width 0.14224)
		(layer "In11.Cu")
		(net "M_C_DQS_DP<13>")
	)
	(segment
		(start 283.562044 1.145286)
		(end 283.562044 0.30988)
		(width 0.14224)
		(layer "In11.Cu")
		(net "M_C_DQS_DP<13>")
	)
	(segment
		(start 283.070808 -1.346708)
		(end 283.070808 -1.685036)
		(width 0.14224)
		(layer "In11.Cu")
		(net "M_C_DQS_DP<13>")
	)
	(segment
		(start 273.446494 -52.93995)
		(end 273.64817 -52.738274)
		(width 0.0889)
		(layer "In11.Cu")
		(net "M_C_DQS_DP<13>")
	)
	(segment
		(start 282.45308 -28.703524)
		(end 282.45308 -27.870658)
		(width 0.14224)
		(layer "In11.Cu")
		(net "M_C_DQS_DP<13>")
	)
	(segment
		(start 273.538188 -55.619904)
		(end 273.55038 -55.599584)
		(width 0.0889)
		(layer "In11.Cu")
		(net "M_C_DQS_DP<13>")
	)
	(segment
		(start 283.353764 -0.5842)
		(end 283.562044 -0.79248)
		(width 0.14224)
		(layer "In11.Cu")
		(net "M_C_DQS_DP<13>")
	)
	(segment
		(start 283.555694 -6.351524)
		(end 282.571444 -5.367274)
		(width 0.14224)
		(layer "In11.Cu")
		(net "M_C_DQS_DP<13>")
	)
	(segment
		(start 274.056348 -59.864752)
		(end 274.05457 -59.862974)
		(width 0.0889)
		(layer "In11.Cu")
		(net "M_C_DQS_DP<13>")
	)
	(segment
		(start 274.040346 -48.005492)
		(end 274.32 -47.725838)
		(width 0.0889)
		(layer "In11.Cu")
		(net "M_C_DQS_DP<13>")
	)
	(segment
		(start 283.748226 -27.46629)
		(end 283.87548 -27.339036)
		(width 0.14224)
		(layer "In11.Cu")
		(net "M_C_DQS_DP<13>")
	)
	(segment
		(start 274.28063 -47.247302)
		(end 274.28063 -39.26205)
		(width 0.14224)
		(layer "In11.Cu")
		(net "M_C_DQS_DP<13>")
	)
	(segment
		(start 274.28063 -47.2694)
		(end 274.28063 -47.247302)
		(width 0.0889)
		(layer "In11.Cu")
		(net "M_C_DQS_DP<13>")
	)
	(segment
		(start 282.571444 -5.367274)
		(end 282.571444 -3.442716)
		(width 0.14224)
		(layer "In11.Cu")
		(net "M_C_DQS_DP<13>")
	)
	(segment
		(start 283.198316 -1.2192)
		(end 283.070808 -1.346708)
		(width 0.14224)
		(layer "In11.Cu")
		(net "M_C_DQS_DP<13>")
	)
	(segment
		(start 283.653992 -29.08173)
		(end 282.831286 -29.08173)
		(width 0.14224)
		(layer "In11.Cu")
		(net "M_C_DQS_DP<13>")
	)
	(segment
		(start 283.562044 -1.03632)
		(end 283.379164 -1.2192)
		(width 0.14224)
		(layer "In11.Cu")
		(net "M_C_DQS_DP<13>")
	)
	(segment
		(start 283.070808 -1.685036)
		(end 283.227272 -1.8415)
		(width 0.14224)
		(layer "In11.Cu")
		(net "M_C_DQS_DP<13>")
	)
	(segment
		(start 274.056348 -59.866784)
		(end 274.056348 -59.864752)
		(width 0.0889)
		(layer "In11.Cu")
		(net "M_C_DQS_DP<13>")
	)
	(segment
		(start 282.831286 -29.08173)
		(end 282.45308 -28.703524)
		(width 0.14224)
		(layer "In11.Cu")
		(net "M_C_DQS_DP<13>")
	)
	(segment
		(start 283.226764 -0.5842)
		(end 283.353764 -0.5842)
		(width 0.14224)
		(layer "In11.Cu")
		(net "M_C_DQS_DP<13>")
	)
	(segment
		(start 273.544538 -57.590436)
		(end 273.549364 -57.5818)
		(width 0.0889)
		(layer "In11.Cu")
		(net "M_C_DQS_DP<13>")
	)
	(segment
		(start 283.562044 -2.731262)
		(end 283.321506 -2.9718)
		(width 0.14224)
		(layer "In11.Cu")
		(net "M_C_DQS_DP<13>")
	)
	(segment
		(start 283.379164 -1.2192)
		(end 283.198316 -1.2192)
		(width 0.14224)
		(layer "In11.Cu")
		(net "M_C_DQS_DP<13>")
	)
	(segment
		(start 283.87548 -29.6672)
		(end 283.87548 -29.303218)
		(width 0.14224)
		(layer "In11.Cu")
		(net "M_C_DQS_DP<13>")
	)
	(segment
		(start 283.315664 -1.8415)
		(end 283.562044 -2.08788)
		(width 0.14224)
		(layer "In11.Cu")
		(net "M_C_DQS_DP<13>")
	)
	(segment
		(start 274.28063 -39.26205)
		(end 283.87548 -29.6672)
		(width 0.14224)
		(layer "In11.Cu")
		(net "M_C_DQS_DP<13>")
	)
	(segment
		(start 283.074364 -0.1778)
		(end 283.074364 -0.4318)
		(width 0.14224)
		(layer "In11.Cu")
		(net "M_C_DQS_DP<13>")
	)
	(segment
		(start 273.64817 -52.738274)
		(end 273.64817 -52.107846)
		(width 0.0889)
		(layer "In11.Cu")
		(net "M_C_DQS_DP<13>")
	)
	(segment
		(start 273.538188 -57.601104)
		(end 273.544538 -57.590436)
		(width 0.0889)
		(layer "In11.Cu")
		(net "M_C_DQS_DP<13>")
	)
	(arc
		(start 273.544538 -57.190386)
		(mid 273.465316 -56.901268)
		(end 273.538188 -56.610504)
		(width 0.0889)
		(layer "In11.Cu")
		(net "M_C_DQS_DP<13>")
	)
	(arc
		(start 273.544538 -58.180986)
		(mid 273.465316 -57.891868)
		(end 273.538188 -57.601104)
		(width 0.0889)
		(layer "In11.Cu")
		(net "M_C_DQS_DP<13>")
	)
	(arc
		(start 273.709638 -59.076082)
		(mid 273.659823 -58.930357)
		(end 273.668744 -58.776616)
		(width 0.0889)
		(layer "In11.Cu")
		(net "M_C_DQS_DP<13>")
	)
	(arc
		(start 273.55038 -55.599584)
		(mid 273.598148 -55.403765)
		(end 273.544538 -55.20944)
		(width 0.0889)
		(layer "In11.Cu")
		(net "M_C_DQS_DP<13>")
	)
	(arc
		(start 273.544538 -56.199786)
		(mid 273.465316 -55.910668)
		(end 273.538188 -55.619904)
		(width 0.0889)
		(layer "In11.Cu")
		(net "M_C_DQS_DP<13>")
	)
	(arc
		(start 273.549364 -57.5818)
		(mid 273.598119 -57.385448)
		(end 273.544538 -57.190386)
		(width 0.0889)
		(layer "In11.Cu")
		(net "M_C_DQS_DP<13>")
	)
	(arc
		(start 273.549364 -56.5912)
		(mid 273.598119 -56.394848)
		(end 273.544538 -56.199786)
		(width 0.0889)
		(layer "In11.Cu")
		(net "M_C_DQS_DP<13>")
	)
	(arc
		(start 274.05457 -59.862974)
		(mid 273.903752 -59.460038)
		(end 273.709638 -59.076082)
		(width 0.0889)
		(layer "In11.Cu")
		(net "M_C_DQS_DP<13>")
	)
	(arc
		(start 273.668744 -58.776616)
		(mid 273.654346 -58.468858)
		(end 273.544538 -58.180986)
		(width 0.0889)
		(layer "In11.Cu")
		(net "M_C_DQS_DP<13>")
	)
	(segment
		(start 227.410772 1.499616)
		(end 227.792534 1.117854)
		(width 0.1651)
		(layer "F.Cu")
		(net "M_C_DQS_DP<12>")
	)
	(segment
		(start 227.329238 1.723898)
		(end 227.410772 1.499616)
		(width 0.1651)
		(layer "F.Cu")
		(net "M_C_DQS_DP<12>")
	)
	(segment
		(start 227.849938 3.162046)
		(end 227.41382 2.725928)
		(width 0.1651)
		(layer "F.Cu")
		(net "M_C_DQS_DP<12>")
	)
	(segment
		(start 249.919744 -65.49644)
		(end 249.348244 -65.49644)
		(width 0.0889)
		(layer "F.Cu")
		(net "M_C_DQS_DP<12>")
	)
	(segment
		(start 227.41382 2.725928)
		(end 227.329238 2.542032)
		(width 0.1651)
		(layer "F.Cu")
		(net "M_C_DQS_DP<12>")
	)
	(segment
		(start 227.849938 3.778758)
		(end 227.849938 3.162046)
		(width 0.1651)
		(layer "F.Cu")
		(net "M_C_DQS_DP<12>")
	)
	(segment
		(start 227.850446 3.778758)
		(end 227.849938 3.778758)
		(width 0.1651)
		(layer "F.Cu")
		(net "M_C_DQS_DP<12>")
	)
	(segment
		(start 227.329238 2.542032)
		(end 227.329238 1.723898)
		(width 0.1651)
		(layer "F.Cu")
		(net "M_C_DQS_DP<12>")
	)
	(via
		(at 227.792534 1.117854)
		(size 0.508)
		(drill 0.254)
		(layers "F.Cu" "B.Cu")
		(net "M_C_DQS_DP<12>")
	)
	(via
		(at 249.348244 -65.49644)
		(size 0.508)
		(drill 0.254)
		(layers "F.Cu" "B.Cu")
		(net "M_C_DQS_DP<12>")
	)
	(via
		(at 227.792534 -2.9718)
		(size 0.508)
		(drill 0.254)
		(layers "F.Cu" "B.Cu")
		(net "M_C_DQS_DP<12>")
	)
	(segment
		(start 227.849938 -5.004054)
		(end 227.393754 -4.54787)
		(width 0.1651)
		(layer "B.Cu")
		(net "M_C_DQS_DP<12>")
	)
	(segment
		(start 227.850446 -5.621782)
		(end 227.849938 -5.621782)
		(width 0.1651)
		(layer "B.Cu")
		(net "M_C_DQS_DP<12>")
	)
	(segment
		(start 227.849938 -5.621782)
		(end 227.849938 -5.004054)
		(width 0.1651)
		(layer "B.Cu")
		(net "M_C_DQS_DP<12>")
	)
	(segment
		(start 227.316538 -4.415536)
		(end 227.316538 -3.519932)
		(width 0.1651)
		(layer "B.Cu")
		(net "M_C_DQS_DP<12>")
	)
	(segment
		(start 227.316538 -3.519932)
		(end 227.403914 -3.36042)
		(width 0.1651)
		(layer "B.Cu")
		(net "M_C_DQS_DP<12>")
	)
	(segment
		(start 227.393754 -4.54787)
		(end 227.316538 -4.415536)
		(width 0.1651)
		(layer "B.Cu")
		(net "M_C_DQS_DP<12>")
	)
	(segment
		(start 227.403914 -3.36042)
		(end 227.792534 -2.9718)
		(width 0.1651)
		(layer "B.Cu")
		(net "M_C_DQS_DP<12>")
	)
	(segment
		(start 227.820982 -1.685036)
		(end 227.820982 -1.346708)
		(width 0.14224)
		(layer "In11.Cu")
		(net "M_C_DQS_DP<12>")
	)
	(segment
		(start 228.305614 -6.45287)
		(end 228.305614 -29.212286)
		(width 0.14224)
		(layer "In11.Cu")
		(net "M_C_DQS_DP<12>")
	)
	(segment
		(start 228.312218 0.30988)
		(end 228.312218 1.145286)
		(width 0.14224)
		(layer "In11.Cu")
		(net "M_C_DQS_DP<12>")
	)
	(segment
		(start 248.121424 -53.317394)
		(end 248.121424 -54.813708)
		(width 0.0889)
		(layer "In11.Cu")
		(net "M_C_DQS_DP<12>")
	)
	(segment
		(start 248.830084 -62.80912)
		(end 248.836434 -62.819788)
		(width 0.0889)
		(layer "In11.Cu")
		(net "M_C_DQS_DP<12>")
	)
	(segment
		(start 246.027448 -50.6222)
		(end 246.08282 -50.6222)
		(width 0.0889)
		(layer "In11.Cu")
		(net "M_C_DQS_DP<12>")
	)
	(segment
		(start 246.08282 -50.6222)
		(end 246.755412 -51.294792)
		(width 0.0889)
		(layer "In11.Cu")
		(net "M_C_DQS_DP<12>")
	)
	(segment
		(start 248.830084 -56.86552)
		(end 248.836434 -56.876188)
		(width 0.0889)
		(layer "In11.Cu")
		(net "M_C_DQS_DP<12>")
	)
	(segment
		(start 229.53091 -32.466026)
		(end 230.17099 -33.106106)
		(width 0.14224)
		(layer "In11.Cu")
		(net "M_C_DQS_DP<12>")
	)
	(segment
		(start 228.312218 -2.731262)
		(end 228.312218 -2.08788)
		(width 0.14224)
		(layer "In11.Cu")
		(net "M_C_DQS_DP<12>")
	)
	(segment
		(start 248.836434 -62.819788)
		(end 248.84126 -62.828424)
		(width 0.0889)
		(layer "In11.Cu")
		(net "M_C_DQS_DP<12>")
	)
	(segment
		(start 228.07168 -2.9718)
		(end 228.312218 -2.731262)
		(width 0.14224)
		(layer "In11.Cu")
		(net "M_C_DQS_DP<12>")
	)
	(segment
		(start 248.836434 -60.838588)
		(end 248.84126 -60.847224)
		(width 0.0889)
		(layer "In11.Cu")
		(net "M_C_DQS_DP<12>")
	)
	(segment
		(start 231.600756 -32.507428)
		(end 234.292394 -35.199066)
		(width 0.14224)
		(layer "In11.Cu")
		(net "M_C_DQS_DP<12>")
	)
	(segment
		(start 230.144828 -31.364428)
		(end 229.53091 -31.978346)
		(width 0.14224)
		(layer "In11.Cu")
		(net "M_C_DQS_DP<12>")
	)
	(segment
		(start 248.836434 -61.829188)
		(end 248.84126 -61.837824)
		(width 0.0889)
		(layer "In11.Cu")
		(net "M_C_DQS_DP<12>")
	)
	(segment
		(start 234.292394 -37.567616)
		(end 244.6528 -47.928022)
		(width 0.14224)
		(layer "In11.Cu")
		(net "M_C_DQS_DP<12>")
	)
	(segment
		(start 248.836434 -58.266838)
		(end 248.830084 -58.277506)
		(width 0.0889)
		(layer "In11.Cu")
		(net "M_C_DQS_DP<12>")
	)
	(segment
		(start 227.792534 -2.9718)
		(end 227.321618 -3.442716)
		(width 0.14224)
		(layer "In11.Cu")
		(net "M_C_DQS_DP<12>")
	)
	(segment
		(start 228.312218 1.145286)
		(end 228.131624 1.32588)
		(width 0.14224)
		(layer "In11.Cu")
		(net "M_C_DQS_DP<12>")
	)
	(segment
		(start 227.321618 -5.468874)
		(end 228.305614 -6.45287)
		(width 0.14224)
		(layer "In11.Cu")
		(net "M_C_DQS_DP<12>")
	)
	(segment
		(start 230.17099 -33.106106)
		(end 230.68915 -33.106106)
		(width 0.14224)
		(layer "In11.Cu")
		(net "M_C_DQS_DP<12>")
	)
	(segment
		(start 227.94849 -1.2192)
		(end 228.129338 -1.2192)
		(width 0.14224)
		(layer "In11.Cu")
		(net "M_C_DQS_DP<12>")
	)
	(segment
		(start 246.0117 -50.606452)
		(end 246.027448 -50.6222)
		(width 0.0889)
		(layer "In11.Cu")
		(net "M_C_DQS_DP<12>")
	)
	(segment
		(start 227.824538 -0.1778)
		(end 228.312218 0.30988)
		(width 0.14224)
		(layer "In11.Cu")
		(net "M_C_DQS_DP<12>")
	)
	(segment
		(start 248.383806 -55.07609)
		(end 248.841006 -55.893462)
		(width 0.0889)
		(layer "In11.Cu")
		(net "M_C_DQS_DP<12>")
	)
	(segment
		(start 228.312218 -2.08788)
		(end 228.065838 -1.8415)
		(width 0.14224)
		(layer "In11.Cu")
		(net "M_C_DQS_DP<12>")
	)
	(segment
		(start 244.6528 -47.928022)
		(end 244.6528 -49.247552)
		(width 0.14224)
		(layer "In11.Cu")
		(net "M_C_DQS_DP<12>")
	)
	(segment
		(start 231.287828 -32.507428)
		(end 231.600756 -32.507428)
		(width 0.14224)
		(layer "In11.Cu")
		(net "M_C_DQS_DP<12>")
	)
	(segment
		(start 227.820982 -1.346708)
		(end 227.94849 -1.2192)
		(width 0.14224)
		(layer "In11.Cu")
		(net "M_C_DQS_DP<12>")
	)
	(segment
		(start 230.144828 -31.0515)
		(end 230.144828 -31.364428)
		(width 0.14224)
		(layer "In11.Cu")
		(net "M_C_DQS_DP<12>")
	)
	(segment
		(start 228.103938 -0.5842)
		(end 227.976938 -0.5842)
		(width 0.14224)
		(layer "In11.Cu")
		(net "M_C_DQS_DP<12>")
	)
	(segment
		(start 228.131624 1.32588)
		(end 228.00056 1.32588)
		(width 0.14224)
		(layer "In11.Cu")
		(net "M_C_DQS_DP<12>")
	)
	(segment
		(start 228.065838 -1.8415)
		(end 227.977446 -1.8415)
		(width 0.14224)
		(layer "In11.Cu")
		(net "M_C_DQS_DP<12>")
	)
	(segment
		(start 229.53091 -31.978346)
		(end 229.53091 -32.466026)
		(width 0.14224)
		(layer "In11.Cu")
		(net "M_C_DQS_DP<12>")
	)
	(segment
		(start 248.836434 -59.847988)
		(end 248.84126 -59.856624)
		(width 0.0889)
		(layer "In11.Cu")
		(net "M_C_DQS_DP<12>")
	)
	(segment
		(start 248.830084 -59.83732)
		(end 248.836434 -59.847988)
		(width 0.0889)
		(layer "In11.Cu")
		(net "M_C_DQS_DP<12>")
	)
	(segment
		(start 249.346466 -65.49263)
		(end 249.348244 -65.494408)
		(width 0.0889)
		(layer "In11.Cu")
		(net "M_C_DQS_DP<12>")
	)
	(segment
		(start 227.824538 -0.4318)
		(end 227.824538 -0.1778)
		(width 0.14224)
		(layer "In11.Cu")
		(net "M_C_DQS_DP<12>")
	)
	(segment
		(start 228.312218 -1.03632)
		(end 228.312218 -0.79248)
		(width 0.14224)
		(layer "In11.Cu")
		(net "M_C_DQS_DP<12>")
	)
	(segment
		(start 228.312218 -0.79248)
		(end 228.103938 -0.5842)
		(width 0.14224)
		(layer "In11.Cu")
		(net "M_C_DQS_DP<12>")
	)
	(segment
		(start 227.792534 -2.9718)
		(end 228.07168 -2.9718)
		(width 0.14224)
		(layer "In11.Cu")
		(net "M_C_DQS_DP<12>")
	)
	(segment
		(start 244.6528 -49.247552)
		(end 246.0117 -50.606452)
		(width 0.14224)
		(layer "In11.Cu")
		(net "M_C_DQS_DP<12>")
	)
	(segment
		(start 248.830084 -63.79972)
		(end 248.835418 -63.809118)
		(width 0.0889)
		(layer "In11.Cu")
		(net "M_C_DQS_DP<12>")
	)
	(segment
		(start 246.894604 -51.535838)
		(end 246.894604 -52.090574)
		(width 0.0889)
		(layer "In11.Cu")
		(net "M_C_DQS_DP<12>")
	)
	(segment
		(start 248.121424 -54.813708)
		(end 248.383806 -55.07609)
		(width 0.0889)
		(layer "In11.Cu")
		(net "M_C_DQS_DP<12>")
	)
	(segment
		(start 234.292394 -35.199066)
		(end 234.292394 -37.567616)
		(width 0.14224)
		(layer "In11.Cu")
		(net "M_C_DQS_DP<12>")
	)
	(segment
		(start 230.68915 -33.106106)
		(end 231.287828 -32.507428)
		(width 0.14224)
		(layer "In11.Cu")
		(net "M_C_DQS_DP<12>")
	)
	(segment
		(start 228.00056 1.32588)
		(end 227.792534 1.117854)
		(width 0.14224)
		(layer "In11.Cu")
		(net "M_C_DQS_DP<12>")
	)
	(segment
		(start 228.305614 -29.212286)
		(end 230.144828 -31.0515)
		(width 0.14224)
		(layer "In11.Cu")
		(net "M_C_DQS_DP<12>")
	)
	(segment
		(start 249.348244 -65.494408)
		(end 249.348244 -65.49644)
		(width 0.0889)
		(layer "In11.Cu")
		(net "M_C_DQS_DP<12>")
	)
	(segment
		(start 248.836434 -56.876188)
		(end 248.84126 -56.884824)
		(width 0.0889)
		(layer "In11.Cu")
		(net "M_C_DQS_DP<12>")
	)
	(segment
		(start 228.129338 -1.2192)
		(end 228.312218 -1.03632)
		(width 0.14224)
		(layer "In11.Cu")
		(net "M_C_DQS_DP<12>")
	)
	(segment
		(start 227.321618 -3.442716)
		(end 227.321618 -5.468874)
		(width 0.14224)
		(layer "In11.Cu")
		(net "M_C_DQS_DP<12>")
	)
	(segment
		(start 248.830084 -60.82792)
		(end 248.836434 -60.838588)
		(width 0.0889)
		(layer "In11.Cu")
		(net "M_C_DQS_DP<12>")
	)
	(segment
		(start 248.830084 -61.81852)
		(end 248.836434 -61.829188)
		(width 0.0889)
		(layer "In11.Cu")
		(net "M_C_DQS_DP<12>")
	)
	(segment
		(start 248.836688 -56.285384)
		(end 248.836434 -56.285638)
		(width 0.0889)
		(layer "In11.Cu")
		(net "M_C_DQS_DP<12>")
	)
	(segment
		(start 248.835418 -63.809118)
		(end 248.836434 -63.810642)
		(width 0.0889)
		(layer "In11.Cu")
		(net "M_C_DQS_DP<12>")
	)
	(segment
		(start 227.976938 -0.5842)
		(end 227.824538 -0.4318)
		(width 0.14224)
		(layer "In11.Cu")
		(net "M_C_DQS_DP<12>")
	)
	(segment
		(start 246.755412 -51.294792)
		(end 246.894604 -51.535838)
		(width 0.0889)
		(layer "In11.Cu")
		(net "M_C_DQS_DP<12>")
	)
	(segment
		(start 248.836434 -58.857388)
		(end 248.84126 -58.866024)
		(width 0.0889)
		(layer "In11.Cu")
		(net "M_C_DQS_DP<12>")
	)
	(segment
		(start 246.894604 -52.090574)
		(end 248.121424 -53.317394)
		(width 0.0889)
		(layer "In11.Cu")
		(net "M_C_DQS_DP<12>")
	)
	(segment
		(start 227.977446 -1.8415)
		(end 227.820982 -1.685036)
		(width 0.14224)
		(layer "In11.Cu")
		(net "M_C_DQS_DP<12>")
	)
	(arc
		(start 248.836434 -59.257438)
		(mid 248.757212 -59.546556)
		(end 248.830084 -59.83732)
		(width 0.0889)
		(layer "In11.Cu")
		(net "M_C_DQS_DP<12>")
	)
	(arc
		(start 248.836434 -60.248038)
		(mid 248.757212 -60.537156)
		(end 248.830084 -60.82792)
		(width 0.0889)
		(layer "In11.Cu")
		(net "M_C_DQS_DP<12>")
	)
	(arc
		(start 248.84126 -56.884824)
		(mid 248.890015 -57.081176)
		(end 248.836434 -57.276238)
		(width 0.0889)
		(layer "In11.Cu")
		(net "M_C_DQS_DP<12>")
	)
	(arc
		(start 248.84126 -62.828424)
		(mid 248.890015 -63.024776)
		(end 248.836434 -63.219838)
		(width 0.0889)
		(layer "In11.Cu")
		(net "M_C_DQS_DP<12>")
	)
	(arc
		(start 248.836434 -63.219838)
		(mid 248.757212 -63.508956)
		(end 248.830084 -63.79972)
		(width 0.0889)
		(layer "In11.Cu")
		(net "M_C_DQS_DP<12>")
	)
	(arc
		(start 248.830084 -58.277506)
		(mid 248.757286 -58.568269)
		(end 248.836434 -58.857388)
		(width 0.0889)
		(layer "In11.Cu")
		(net "M_C_DQS_DP<12>")
	)
	(arc
		(start 248.96064 -64.406272)
		(mid 248.951739 -64.560011)
		(end 249.001534 -64.705738)
		(width 0.0889)
		(layer "In11.Cu")
		(net "M_C_DQS_DP<12>")
	)
	(arc
		(start 248.84126 -61.837824)
		(mid 248.890015 -62.034176)
		(end 248.836434 -62.229238)
		(width 0.0889)
		(layer "In11.Cu")
		(net "M_C_DQS_DP<12>")
	)
	(arc
		(start 248.841006 -55.893462)
		(mid 248.890039 -56.089975)
		(end 248.836688 -56.285384)
		(width 0.0889)
		(layer "In11.Cu")
		(net "M_C_DQS_DP<12>")
	)
	(arc
		(start 248.836434 -61.238638)
		(mid 248.757212 -61.527756)
		(end 248.830084 -61.81852)
		(width 0.0889)
		(layer "In11.Cu")
		(net "M_C_DQS_DP<12>")
	)
	(arc
		(start 249.001534 -64.705738)
		(mid 249.195629 -65.089702)
		(end 249.346466 -65.49263)
		(width 0.0889)
		(layer "In11.Cu")
		(net "M_C_DQS_DP<12>")
	)
	(arc
		(start 248.836434 -57.276238)
		(mid 248.757303 -57.57164)
		(end 248.836434 -57.867042)
		(width 0.0889)
		(layer "In11.Cu")
		(net "M_C_DQS_DP<12>")
	)
	(arc
		(start 248.84126 -58.866024)
		(mid 248.890015 -59.062376)
		(end 248.836434 -59.257438)
		(width 0.0889)
		(layer "In11.Cu")
		(net "M_C_DQS_DP<12>")
	)
	(arc
		(start 248.836434 -57.867042)
		(mid 248.889933 -58.06694)
		(end 248.836434 -58.266838)
		(width 0.0889)
		(layer "In11.Cu")
		(net "M_C_DQS_DP<12>")
	)
	(arc
		(start 248.836434 -56.285638)
		(mid 248.757212 -56.574756)
		(end 248.830084 -56.86552)
		(width 0.0889)
		(layer "In11.Cu")
		(net "M_C_DQS_DP<12>")
	)
	(arc
		(start 248.836434 -63.810642)
		(mid 248.946304 -64.098501)
		(end 248.96064 -64.406272)
		(width 0.0889)
		(layer "In11.Cu")
		(net "M_C_DQS_DP<12>")
	)
	(arc
		(start 248.836434 -62.229238)
		(mid 248.757212 -62.518356)
		(end 248.830084 -62.80912)
		(width 0.0889)
		(layer "In11.Cu")
		(net "M_C_DQS_DP<12>")
	)
	(arc
		(start 248.84126 -59.856624)
		(mid 248.890015 -60.052976)
		(end 248.836434 -60.248038)
		(width 0.0889)
		(layer "In11.Cu")
		(net "M_C_DQS_DP<12>")
	)
	(arc
		(start 248.84126 -60.847224)
		(mid 248.890015 -61.043576)
		(end 248.836434 -61.238638)
		(width 0.0889)
		(layer "In11.Cu")
		(net "M_C_DQS_DP<12>")
	)
	(segment
		(start 218.500452 3.778758)
		(end 218.499944 3.778758)
		(width 0.1651)
		(layer "F.Cu")
		(net "M_C_DQS_DP<11>")
	)
	(segment
		(start 217.979244 2.542032)
		(end 217.979244 1.723898)
		(width 0.1651)
		(layer "F.Cu")
		(net "M_C_DQS_DP<11>")
	)
	(segment
		(start 217.979244 1.723898)
		(end 218.060778 1.499616)
		(width 0.1651)
		(layer "F.Cu")
		(net "M_C_DQS_DP<11>")
	)
	(segment
		(start 218.499944 3.778758)
		(end 218.499944 3.162046)
		(width 0.1651)
		(layer "F.Cu")
		(net "M_C_DQS_DP<11>")
	)
	(segment
		(start 245.627144 -58.06694)
		(end 245.055644 -58.06694)
		(width 0.0889)
		(layer "F.Cu")
		(net "M_C_DQS_DP<11>")
	)
	(segment
		(start 218.060778 1.499616)
		(end 218.44254 1.117854)
		(width 0.1651)
		(layer "F.Cu")
		(net "M_C_DQS_DP<11>")
	)
	(segment
		(start 218.063826 2.725928)
		(end 217.979244 2.542032)
		(width 0.1651)
		(layer "F.Cu")
		(net "M_C_DQS_DP<11>")
	)
	(segment
		(start 218.499944 3.162046)
		(end 218.063826 2.725928)
		(width 0.1651)
		(layer "F.Cu")
		(net "M_C_DQS_DP<11>")
	)
	(via
		(at 245.055644 -58.06694)
		(size 0.508)
		(drill 0.254)
		(layers "F.Cu" "B.Cu")
		(net "M_C_DQS_DP<11>")
	)
	(via
		(at 218.44254 1.117854)
		(size 0.508)
		(drill 0.254)
		(layers "F.Cu" "B.Cu")
		(net "M_C_DQS_DP<11>")
	)
	(via
		(at 218.44254 -2.9718)
		(size 0.508)
		(drill 0.254)
		(layers "F.Cu" "B.Cu")
		(net "M_C_DQS_DP<11>")
	)
	(segment
		(start 218.500452 -5.621782)
		(end 218.499944 -5.621782)
		(width 0.1651)
		(layer "B.Cu")
		(net "M_C_DQS_DP<11>")
	)
	(segment
		(start 218.04376 -4.54787)
		(end 217.966544 -4.415536)
		(width 0.1651)
		(layer "B.Cu")
		(net "M_C_DQS_DP<11>")
	)
	(segment
		(start 218.499944 -5.004054)
		(end 218.04376 -4.54787)
		(width 0.1651)
		(layer "B.Cu")
		(net "M_C_DQS_DP<11>")
	)
	(segment
		(start 218.499944 -5.621782)
		(end 218.499944 -5.004054)
		(width 0.1651)
		(layer "B.Cu")
		(net "M_C_DQS_DP<11>")
	)
	(segment
		(start 217.966544 -4.415536)
		(end 217.966544 -3.519932)
		(width 0.1651)
		(layer "B.Cu")
		(net "M_C_DQS_DP<11>")
	)
	(segment
		(start 217.966544 -3.519932)
		(end 218.05392 -3.36042)
		(width 0.1651)
		(layer "B.Cu")
		(net "M_C_DQS_DP<11>")
	)
	(segment
		(start 218.05392 -3.36042)
		(end 218.44254 -2.9718)
		(width 0.1651)
		(layer "B.Cu")
		(net "M_C_DQS_DP<11>")
	)
	(segment
		(start 218.95562 -6.35127)
		(end 218.95562 -24.829262)
		(width 0.14224)
		(layer "In11.Cu")
		(net "M_C_DQS_DP<11>")
	)
	(segment
		(start 243.943886 -57.94502)
		(end 244.115844 -57.971944)
		(width 0.0889)
		(layer "In11.Cu")
		(net "M_C_DQS_DP<11>")
	)
	(segment
		(start 234.445048 -49.85131)
		(end 234.651804 -50.216562)
		(width 0.14224)
		(layer "In11.Cu")
		(net "M_C_DQS_DP<11>")
	)
	(segment
		(start 218.962224 -1.03632)
		(end 218.962224 -0.79248)
		(width 0.14224)
		(layer "In11.Cu")
		(net "M_C_DQS_DP<11>")
	)
	(segment
		(start 219.061792 -26.863548)
		(end 219.28328 -27.085036)
		(width 0.14224)
		(layer "In11.Cu")
		(net "M_C_DQS_DP<11>")
	)
	(segment
		(start 244.115844 -57.971944)
		(end 244.339872 -57.971944)
		(width 0.0889)
		(layer "In11.Cu")
		(net "M_C_DQS_DP<11>")
	)
	(segment
		(start 241.60353 -56.676036)
		(end 241.636296 -56.676036)
		(width 0.0889)
		(layer "In11.Cu")
		(net "M_C_DQS_DP<11>")
	)
	(segment
		(start 218.715844 -1.8415)
		(end 218.627452 -1.8415)
		(width 0.14224)
		(layer "In11.Cu")
		(net "M_C_DQS_DP<11>")
	)
	(segment
		(start 218.901518 -26.863548)
		(end 219.061792 -26.863548)
		(width 0.14224)
		(layer "In11.Cu")
		(net "M_C_DQS_DP<11>")
	)
	(segment
		(start 234.716066 -50.250598)
		(end 235.105194 -50.941224)
		(width 0.0889)
		(layer "In11.Cu")
		(net "M_C_DQS_DP<11>")
	)
	(segment
		(start 243.816124 -57.909714)
		(end 243.943886 -57.94502)
		(width 0.0889)
		(layer "In11.Cu")
		(net "M_C_DQS_DP<11>")
	)
	(segment
		(start 217.971624 -3.442716)
		(end 217.971624 -5.367274)
		(width 0.14224)
		(layer "In11.Cu")
		(net "M_C_DQS_DP<11>")
	)
	(segment
		(start 218.470988 -1.685036)
		(end 218.470988 -1.346708)
		(width 0.14224)
		(layer "In11.Cu")
		(net "M_C_DQS_DP<11>")
	)
	(segment
		(start 218.598496 -1.2192)
		(end 218.779344 -1.2192)
		(width 0.14224)
		(layer "In11.Cu")
		(net "M_C_DQS_DP<11>")
	)
	(segment
		(start 218.44254 -2.9718)
		(end 217.971624 -3.442716)
		(width 0.14224)
		(layer "In11.Cu")
		(net "M_C_DQS_DP<11>")
	)
	(segment
		(start 244.339872 -57.971944)
		(end 245.055644 -58.06694)
		(width 0.0889)
		(layer "In11.Cu")
		(net "M_C_DQS_DP<11>")
	)
	(segment
		(start 240.749582 -56.18099)
		(end 240.780824 -56.18099)
		(width 0.0889)
		(layer "In11.Cu")
		(net "M_C_DQS_DP<11>")
	)
	(segment
		(start 236.45241 -53.704236)
		(end 236.485176 -53.704236)
		(width 0.0889)
		(layer "In11.Cu")
		(net "M_C_DQS_DP<11>")
	)
	(segment
		(start 243.338604 -57.666636)
		(end 243.349272 -57.666636)
		(width 0.0889)
		(layer "In11.Cu")
		(net "M_C_DQS_DP<11>")
	)
	(segment
		(start 218.962224 -2.08788)
		(end 218.715844 -1.8415)
		(width 0.14224)
		(layer "In11.Cu")
		(net "M_C_DQS_DP<11>")
	)
	(segment
		(start 218.962224 1.145286)
		(end 218.78163 1.32588)
		(width 0.14224)
		(layer "In11.Cu")
		(net "M_C_DQS_DP<11>")
	)
	(segment
		(start 219.28328 -27.085036)
		(end 219.28328 -34.039048)
		(width 0.14224)
		(layer "In11.Cu")
		(net "M_C_DQS_DP<11>")
	)
	(segment
		(start 218.34348 -26.30551)
		(end 218.901518 -26.863548)
		(width 0.14224)
		(layer "In11.Cu")
		(net "M_C_DQS_DP<11>")
	)
	(segment
		(start 217.971624 -5.367274)
		(end 218.95562 -6.35127)
		(width 0.14224)
		(layer "In11.Cu")
		(net "M_C_DQS_DP<11>")
	)
	(segment
		(start 237.315502 -54.19979)
		(end 237.346744 -54.19979)
		(width 0.0889)
		(layer "In11.Cu")
		(net "M_C_DQS_DP<11>")
	)
	(segment
		(start 239.88649 -55.685436)
		(end 239.919256 -55.685436)
		(width 0.0889)
		(layer "In11.Cu")
		(net "M_C_DQS_DP<11>")
	)
	(segment
		(start 231.530652 -47.245778)
		(end 233.629708 -49.344834)
		(width 0.14224)
		(layer "In11.Cu")
		(net "M_C_DQS_DP<11>")
	)
	(segment
		(start 218.962224 0.30988)
		(end 218.962224 1.145286)
		(width 0.14224)
		(layer "In11.Cu")
		(net "M_C_DQS_DP<11>")
	)
	(segment
		(start 219.28328 -34.039048)
		(end 231.530652 -46.28642)
		(width 0.14224)
		(layer "In11.Cu")
		(net "M_C_DQS_DP<11>")
	)
	(segment
		(start 218.627452 -1.8415)
		(end 218.470988 -1.685036)
		(width 0.14224)
		(layer "In11.Cu")
		(net "M_C_DQS_DP<11>")
	)
	(segment
		(start 218.44254 -2.9718)
		(end 218.721686 -2.9718)
		(width 0.14224)
		(layer "In11.Cu")
		(net "M_C_DQS_DP<11>")
	)
	(segment
		(start 218.470988 -1.346708)
		(end 218.598496 -1.2192)
		(width 0.14224)
		(layer "In11.Cu")
		(net "M_C_DQS_DP<11>")
	)
	(segment
		(start 218.474544 -0.4318)
		(end 218.474544 -0.1778)
		(width 0.14224)
		(layer "In11.Cu")
		(net "M_C_DQS_DP<11>")
	)
	(segment
		(start 234.651804 -50.216562)
		(end 234.662726 -50.235866)
		(width 0.0889)
		(layer "In11.Cu")
		(net "M_C_DQS_DP<11>")
	)
	(segment
		(start 218.78163 1.32588)
		(end 218.650566 1.32588)
		(width 0.14224)
		(layer "In11.Cu")
		(net "M_C_DQS_DP<11>")
	)
	(segment
		(start 218.95562 -24.829262)
		(end 218.34348 -25.441402)
		(width 0.14224)
		(layer "In11.Cu")
		(net "M_C_DQS_DP<11>")
	)
	(segment
		(start 231.530652 -46.28642)
		(end 231.530652 -47.245778)
		(width 0.14224)
		(layer "In11.Cu")
		(net "M_C_DQS_DP<11>")
	)
	(segment
		(start 218.650566 1.32588)
		(end 218.44254 1.117854)
		(width 0.14224)
		(layer "In11.Cu")
		(net "M_C_DQS_DP<11>")
	)
	(segment
		(start 235.958126 -52.819554)
		(end 235.952284 -52.830222)
		(width 0.0889)
		(layer "In11.Cu")
		(net "M_C_DQS_DP<11>")
	)
	(segment
		(start 218.753944 -0.5842)
		(end 218.626944 -0.5842)
		(width 0.14224)
		(layer "In11.Cu")
		(net "M_C_DQS_DP<11>")
	)
	(segment
		(start 242.466622 -57.17159)
		(end 242.500658 -57.17159)
		(width 0.0889)
		(layer "In11.Cu")
		(net "M_C_DQS_DP<11>")
	)
	(segment
		(start 239.032542 -55.19039)
		(end 239.063784 -55.19039)
		(width 0.0889)
		(layer "In11.Cu")
		(net "M_C_DQS_DP<11>")
	)
	(segment
		(start 218.474544 -0.1778)
		(end 218.962224 0.30988)
		(width 0.14224)
		(layer "In11.Cu")
		(net "M_C_DQS_DP<11>")
	)
	(segment
		(start 218.779344 -1.2192)
		(end 218.962224 -1.03632)
		(width 0.14224)
		(layer "In11.Cu")
		(net "M_C_DQS_DP<11>")
	)
	(segment
		(start 218.34348 -25.441402)
		(end 218.34348 -26.30551)
		(width 0.14224)
		(layer "In11.Cu")
		(net "M_C_DQS_DP<11>")
	)
	(segment
		(start 235.958888 -52.818538)
		(end 235.958126 -52.819554)
		(width 0.0889)
		(layer "In11.Cu")
		(net "M_C_DQS_DP<11>")
	)
	(segment
		(start 218.962224 -0.79248)
		(end 218.753944 -0.5842)
		(width 0.14224)
		(layer "In11.Cu")
		(net "M_C_DQS_DP<11>")
	)
	(segment
		(start 238.16945 -54.694836)
		(end 238.202216 -54.694836)
		(width 0.0889)
		(layer "In11.Cu")
		(net "M_C_DQS_DP<11>")
	)
	(segment
		(start 218.962224 -2.731262)
		(end 218.962224 -2.08788)
		(width 0.14224)
		(layer "In11.Cu")
		(net "M_C_DQS_DP<11>")
	)
	(segment
		(start 235.59008 -52.218336)
		(end 235.626656 -52.218336)
		(width 0.0889)
		(layer "In11.Cu")
		(net "M_C_DQS_DP<11>")
	)
	(segment
		(start 218.626944 -0.5842)
		(end 218.474544 -0.4318)
		(width 0.14224)
		(layer "In11.Cu")
		(net "M_C_DQS_DP<11>")
	)
	(segment
		(start 242.82654 -57.370726)
		(end 242.830604 -57.377584)
		(width 0.0889)
		(layer "In11.Cu")
		(net "M_C_DQS_DP<11>")
	)
	(segment
		(start 233.629708 -49.344834)
		(end 234.445048 -49.85131)
		(width 0.14224)
		(layer "In11.Cu")
		(net "M_C_DQS_DP<11>")
	)
	(segment
		(start 218.721686 -2.9718)
		(end 218.962224 -2.731262)
		(width 0.14224)
		(layer "In11.Cu")
		(net "M_C_DQS_DP<11>")
	)
	(segment
		(start 234.662726 -50.235866)
		(end 234.716066 -50.250598)
		(width 0.0889)
		(layer "In11.Cu")
		(net "M_C_DQS_DP<11>")
	)
	(arc
		(start 238.534448 -54.894988)
		(mid 238.744801 -55.10796)
		(end 239.032542 -55.19039)
		(width 0.0889)
		(layer "In11.Cu")
		(net "M_C_DQS_DP<11>")
	)
	(arc
		(start 240.251488 -55.885588)
		(mid 240.461841 -56.09856)
		(end 240.749582 -56.18099)
		(width 0.0889)
		(layer "In11.Cu")
		(net "M_C_DQS_DP<11>")
	)
	(arc
		(start 242.830604 -57.377584)
		(mid 243.04635 -57.589355)
		(end 243.338604 -57.666636)
		(width 0.0889)
		(layer "In11.Cu")
		(net "M_C_DQS_DP<11>")
	)
	(arc
		(start 240.780824 -56.18099)
		(mid 240.971066 -56.238725)
		(end 241.110008 -56.380888)
		(width 0.0889)
		(layer "In11.Cu")
		(net "M_C_DQS_DP<11>")
	)
	(arc
		(start 243.64569 -57.8104)
		(mid 243.724471 -57.871102)
		(end 243.816124 -57.909714)
		(width 0.0889)
		(layer "In11.Cu")
		(net "M_C_DQS_DP<11>")
	)
	(arc
		(start 241.968528 -56.876188)
		(mid 242.178881 -57.08916)
		(end 242.466622 -57.17159)
		(width 0.0889)
		(layer "In11.Cu")
		(net "M_C_DQS_DP<11>")
	)
	(arc
		(start 241.110008 -56.380888)
		(mid 241.318427 -56.592601)
		(end 241.60353 -56.676036)
		(width 0.0889)
		(layer "In11.Cu")
		(net "M_C_DQS_DP<11>")
	)
	(arc
		(start 237.346744 -54.19979)
		(mid 237.536986 -54.257525)
		(end 237.675928 -54.399688)
		(width 0.0889)
		(layer "In11.Cu")
		(net "M_C_DQS_DP<11>")
	)
	(arc
		(start 236.817408 -53.904388)
		(mid 237.027761 -54.11736)
		(end 237.315502 -54.19979)
		(width 0.0889)
		(layer "In11.Cu")
		(net "M_C_DQS_DP<11>")
	)
	(arc
		(start 236.485176 -53.704236)
		(mid 236.677193 -53.761344)
		(end 236.817408 -53.904388)
		(width 0.0889)
		(layer "In11.Cu")
		(net "M_C_DQS_DP<11>")
	)
	(arc
		(start 239.063784 -55.19039)
		(mid 239.254026 -55.248125)
		(end 239.392968 -55.390288)
		(width 0.0889)
		(layer "In11.Cu")
		(net "M_C_DQS_DP<11>")
	)
	(arc
		(start 238.202216 -54.694836)
		(mid 238.394233 -54.751944)
		(end 238.534448 -54.894988)
		(width 0.0889)
		(layer "In11.Cu")
		(net "M_C_DQS_DP<11>")
	)
	(arc
		(start 239.919256 -55.685436)
		(mid 240.111273 -55.742544)
		(end 240.251488 -55.885588)
		(width 0.0889)
		(layer "In11.Cu")
		(net "M_C_DQS_DP<11>")
	)
	(arc
		(start 235.626656 -52.218336)
		(mid 235.962417 -52.424525)
		(end 235.958888 -52.818538)
		(width 0.0889)
		(layer "In11.Cu")
		(net "M_C_DQS_DP<11>")
	)
	(arc
		(start 242.500658 -57.17159)
		(mid 242.688891 -57.229788)
		(end 242.82654 -57.370726)
		(width 0.0889)
		(layer "In11.Cu")
		(net "M_C_DQS_DP<11>")
	)
	(arc
		(start 235.105194 -50.941224)
		(mid 235.153949 -51.137576)
		(end 235.100368 -51.332638)
		(width 0.0889)
		(layer "In11.Cu")
		(net "M_C_DQS_DP<11>")
	)
	(arc
		(start 235.952284 -52.830222)
		(mid 235.957867 -53.40713)
		(end 236.45241 -53.704236)
		(width 0.0889)
		(layer "In11.Cu")
		(net "M_C_DQS_DP<11>")
	)
	(arc
		(start 243.349272 -57.666636)
		(mid 243.512968 -57.706592)
		(end 243.64569 -57.8104)
		(width 0.0889)
		(layer "In11.Cu")
		(net "M_C_DQS_DP<11>")
	)
	(arc
		(start 237.675928 -54.399688)
		(mid 237.884347 -54.611401)
		(end 238.16945 -54.694836)
		(width 0.0889)
		(layer "In11.Cu")
		(net "M_C_DQS_DP<11>")
	)
	(arc
		(start 239.392968 -55.390288)
		(mid 239.601387 -55.602001)
		(end 239.88649 -55.685436)
		(width 0.0889)
		(layer "In11.Cu")
		(net "M_C_DQS_DP<11>")
	)
	(arc
		(start 235.100368 -51.332638)
		(mid 235.094958 -51.913869)
		(end 235.59008 -52.218336)
		(width 0.0889)
		(layer "In11.Cu")
		(net "M_C_DQS_DP<11>")
	)
	(arc
		(start 241.636296 -56.676036)
		(mid 241.828313 -56.733144)
		(end 241.968528 -56.876188)
		(width 0.0889)
		(layer "In11.Cu")
		(net "M_C_DQS_DP<11>")
	)
	(segment
		(start 208.710784 1.499616)
		(end 209.092546 1.117854)
		(width 0.1651)
		(layer "F.Cu")
		(net "M_C_DQS_DP<10>")
	)
	(segment
		(start 209.14995 3.778758)
		(end 209.14995 3.162046)
		(width 0.1651)
		(layer "F.Cu")
		(net "M_C_DQS_DP<10>")
	)
	(segment
		(start 209.150458 3.778758)
		(end 209.14995 3.778758)
		(width 0.1651)
		(layer "F.Cu")
		(net "M_C_DQS_DP<10>")
	)
	(segment
		(start 208.713832 2.725928)
		(end 208.62925 2.542032)
		(width 0.1651)
		(layer "F.Cu")
		(net "M_C_DQS_DP<10>")
	)
	(segment
		(start 241.334798 -60.54344)
		(end 240.763298 -60.54344)
		(width 0.0889)
		(layer "F.Cu")
		(net "M_C_DQS_DP<10>")
	)
	(segment
		(start 208.62925 1.723898)
		(end 208.710784 1.499616)
		(width 0.1651)
		(layer "F.Cu")
		(net "M_C_DQS_DP<10>")
	)
	(segment
		(start 208.62925 2.542032)
		(end 208.62925 1.723898)
		(width 0.1651)
		(layer "F.Cu")
		(net "M_C_DQS_DP<10>")
	)
	(segment
		(start 209.14995 3.162046)
		(end 208.713832 2.725928)
		(width 0.1651)
		(layer "F.Cu")
		(net "M_C_DQS_DP<10>")
	)
	(via
		(at 209.092546 -2.9718)
		(size 0.508)
		(drill 0.254)
		(layers "F.Cu" "B.Cu")
		(net "M_C_DQS_DP<10>")
	)
	(via
		(at 240.763298 -60.54344)
		(size 0.508)
		(drill 0.254)
		(layers "F.Cu" "B.Cu")
		(net "M_C_DQS_DP<10>")
	)
	(via
		(at 209.092546 1.117854)
		(size 0.508)
		(drill 0.254)
		(layers "F.Cu" "B.Cu")
		(net "M_C_DQS_DP<10>")
	)
	(segment
		(start 208.703926 -3.36042)
		(end 209.092546 -2.9718)
		(width 0.1651)
		(layer "B.Cu")
		(net "M_C_DQS_DP<10>")
	)
	(segment
		(start 208.61655 -3.519932)
		(end 208.703926 -3.36042)
		(width 0.1651)
		(layer "B.Cu")
		(net "M_C_DQS_DP<10>")
	)
	(segment
		(start 209.150458 -5.621782)
		(end 209.14995 -5.621782)
		(width 0.1651)
		(layer "B.Cu")
		(net "M_C_DQS_DP<10>")
	)
	(segment
		(start 208.61655 -4.415536)
		(end 208.61655 -3.519932)
		(width 0.1651)
		(layer "B.Cu")
		(net "M_C_DQS_DP<10>")
	)
	(segment
		(start 209.14995 -5.621782)
		(end 209.14995 -5.004054)
		(width 0.1651)
		(layer "B.Cu")
		(net "M_C_DQS_DP<10>")
	)
	(segment
		(start 208.693766 -4.54787)
		(end 208.61655 -4.415536)
		(width 0.1651)
		(layer "B.Cu")
		(net "M_C_DQS_DP<10>")
	)
	(segment
		(start 209.14995 -5.004054)
		(end 208.693766 -4.54787)
		(width 0.1651)
		(layer "B.Cu")
		(net "M_C_DQS_DP<10>")
	)
	(segment
		(start 208.79308 -33.873186)
		(end 208.79308 -26.519886)
		(width 0.14224)
		(layer "In11.Cu")
		(net "M_C_DQS_DP<10>")
	)
	(segment
		(start 238.198914 -60.638436)
		(end 238.166148 -60.638436)
		(width 0.0889)
		(layer "In11.Cu")
		(net "M_C_DQS_DP<10>")
	)
	(segment
		(start 237.344204 -60.14339)
		(end 237.311438 -60.14339)
		(width 0.0889)
		(layer "In11.Cu")
		(net "M_C_DQS_DP<10>")
	)
	(segment
		(start 209.171286 -34.251392)
		(end 208.79308 -33.873186)
		(width 0.14224)
		(layer "In11.Cu")
		(net "M_C_DQS_DP<10>")
	)
	(segment
		(start 229.761288 -57.21096)
		(end 216.866216 -44.315888)
		(width 0.14224)
		(layer "In11.Cu")
		(net "M_C_DQS_DP<10>")
	)
	(segment
		(start 209.605626 -25.70734)
		(end 209.605626 -6.35127)
		(width 0.14224)
		(layer "In11.Cu")
		(net "M_C_DQS_DP<10>")
	)
	(segment
		(start 209.120994 -1.685036)
		(end 209.277458 -1.8415)
		(width 0.14224)
		(layer "In11.Cu")
		(net "M_C_DQS_DP<10>")
	)
	(segment
		(start 209.61223 -1.03632)
		(end 209.42935 -1.2192)
		(width 0.14224)
		(layer "In11.Cu")
		(net "M_C_DQS_DP<10>")
	)
	(segment
		(start 209.27695 -0.5842)
		(end 209.40395 -0.5842)
		(width 0.14224)
		(layer "In11.Cu")
		(net "M_C_DQS_DP<10>")
	)
	(segment
		(start 208.79308 -26.519886)
		(end 209.605626 -25.70734)
		(width 0.14224)
		(layer "In11.Cu")
		(net "M_C_DQS_DP<10>")
	)
	(segment
		(start 236.481874 -59.647836)
		(end 236.449108 -59.647836)
		(width 0.0889)
		(layer "In11.Cu")
		(net "M_C_DQS_DP<10>")
	)
	(segment
		(start 209.605626 -6.35127)
		(end 208.62163 -5.367274)
		(width 0.14224)
		(layer "In11.Cu")
		(net "M_C_DQS_DP<10>")
	)
	(segment
		(start 208.76768 -35.68192)
		(end 209.121248 -35.328352)
		(width 0.14224)
		(layer "In11.Cu")
		(net "M_C_DQS_DP<10>")
	)
	(segment
		(start 209.121248 -35.328352)
		(end 209.552032 -35.328352)
		(width 0.14224)
		(layer "In11.Cu")
		(net "M_C_DQS_DP<10>")
	)
	(segment
		(start 230.54437 -57.17159)
		(end 230.505 -57.21096)
		(width 0.0889)
		(layer "In11.Cu")
		(net "M_C_DQS_DP<10>")
	)
	(segment
		(start 209.61223 1.145286)
		(end 209.61223 0.30988)
		(width 0.14224)
		(layer "In11.Cu")
		(net "M_C_DQS_DP<10>")
	)
	(segment
		(start 209.12455 -0.1778)
		(end 209.12455 -0.4318)
		(width 0.14224)
		(layer "In11.Cu")
		(net "M_C_DQS_DP<10>")
	)
	(segment
		(start 209.36585 -1.8415)
		(end 209.61223 -2.08788)
		(width 0.14224)
		(layer "In11.Cu")
		(net "M_C_DQS_DP<10>")
	)
	(segment
		(start 234.76839 -58.657236)
		(end 233.856022 -58.657236)
		(width 0.0889)
		(layer "In11.Cu")
		(net "M_C_DQS_DP<10>")
	)
	(segment
		(start 209.552032 -35.328352)
		(end 209.679032 -35.201352)
		(width 0.14224)
		(layer "In11.Cu")
		(net "M_C_DQS_DP<10>")
	)
	(segment
		(start 240.751614 -60.545218)
		(end 240.302034 -61.149738)
		(width 0.0889)
		(layer "In11.Cu")
		(net "M_C_DQS_DP<10>")
	)
	(segment
		(start 240.302034 -61.149738)
		(end 240.251488 -61.238638)
		(width 0.0889)
		(layer "In11.Cu")
		(net "M_C_DQS_DP<10>")
	)
	(segment
		(start 209.679032 -35.201352)
		(end 209.679032 -34.378392)
		(width 0.14224)
		(layer "In11.Cu")
		(net "M_C_DQS_DP<10>")
	)
	(segment
		(start 209.61223 -0.79248)
		(end 209.61223 -1.03632)
		(width 0.14224)
		(layer "In11.Cu")
		(net "M_C_DQS_DP<10>")
	)
	(segment
		(start 214.474552 -40.96004)
		(end 213.510368 -40.96004)
		(width 0.14224)
		(layer "In11.Cu")
		(net "M_C_DQS_DP<10>")
	)
	(segment
		(start 209.61223 -2.731262)
		(end 209.371692 -2.9718)
		(width 0.14224)
		(layer "In11.Cu")
		(net "M_C_DQS_DP<10>")
	)
	(segment
		(start 208.62163 -5.367274)
		(end 208.62163 -3.442716)
		(width 0.14224)
		(layer "In11.Cu")
		(net "M_C_DQS_DP<10>")
	)
	(segment
		(start 239.586008 -61.290454)
		(end 239.23752 -61.18225)
		(width 0.0889)
		(layer "In11.Cu")
		(net "M_C_DQS_DP<10>")
	)
	(segment
		(start 209.092546 1.117854)
		(end 209.300572 1.32588)
		(width 0.14224)
		(layer "In11.Cu")
		(net "M_C_DQS_DP<10>")
	)
	(segment
		(start 209.12455 -0.4318)
		(end 209.27695 -0.5842)
		(width 0.14224)
		(layer "In11.Cu")
		(net "M_C_DQS_DP<10>")
	)
	(segment
		(start 240.763298 -60.54344)
		(end 240.751614 -60.545218)
		(width 0.0889)
		(layer "In11.Cu")
		(net "M_C_DQS_DP<10>")
	)
	(segment
		(start 209.40395 -0.5842)
		(end 209.61223 -0.79248)
		(width 0.14224)
		(layer "In11.Cu")
		(net "M_C_DQS_DP<10>")
	)
	(segment
		(start 209.552032 -34.251392)
		(end 209.171286 -34.251392)
		(width 0.14224)
		(layer "In11.Cu")
		(net "M_C_DQS_DP<10>")
	)
	(segment
		(start 208.76768 -36.217352)
		(end 208.76768 -35.68192)
		(width 0.14224)
		(layer "In11.Cu")
		(net "M_C_DQS_DP<10>")
	)
	(segment
		(start 208.62163 -3.442716)
		(end 209.092546 -2.9718)
		(width 0.14224)
		(layer "In11.Cu")
		(net "M_C_DQS_DP<10>")
	)
	(segment
		(start 235.627164 -59.15279)
		(end 235.599224 -59.15279)
		(width 0.0889)
		(layer "In11.Cu")
		(net "M_C_DQS_DP<10>")
	)
	(segment
		(start 209.431636 1.32588)
		(end 209.61223 1.145286)
		(width 0.14224)
		(layer "In11.Cu")
		(net "M_C_DQS_DP<10>")
	)
	(segment
		(start 209.277458 -1.8415)
		(end 209.36585 -1.8415)
		(width 0.14224)
		(layer "In11.Cu")
		(net "M_C_DQS_DP<10>")
	)
	(segment
		(start 216.866216 -44.315888)
		(end 216.866216 -43.351704)
		(width 0.14224)
		(layer "In11.Cu")
		(net "M_C_DQS_DP<10>")
	)
	(segment
		(start 230.505 -57.21096)
		(end 229.761288 -57.21096)
		(width 0.14224)
		(layer "In11.Cu")
		(net "M_C_DQS_DP<10>")
	)
	(segment
		(start 209.42935 -1.2192)
		(end 209.248502 -1.2192)
		(width 0.14224)
		(layer "In11.Cu")
		(net "M_C_DQS_DP<10>")
	)
	(segment
		(start 209.300572 1.32588)
		(end 209.431636 1.32588)
		(width 0.14224)
		(layer "In11.Cu")
		(net "M_C_DQS_DP<10>")
	)
	(segment
		(start 209.371692 -2.9718)
		(end 209.092546 -2.9718)
		(width 0.14224)
		(layer "In11.Cu")
		(net "M_C_DQS_DP<10>")
	)
	(segment
		(start 209.61223 -2.08788)
		(end 209.61223 -2.731262)
		(width 0.14224)
		(layer "In11.Cu")
		(net "M_C_DQS_DP<10>")
	)
	(segment
		(start 209.61223 0.30988)
		(end 209.12455 -0.1778)
		(width 0.14224)
		(layer "In11.Cu")
		(net "M_C_DQS_DP<10>")
	)
	(segment
		(start 232.370376 -57.17159)
		(end 230.54437 -57.17159)
		(width 0.0889)
		(layer "In11.Cu")
		(net "M_C_DQS_DP<10>")
	)
	(segment
		(start 209.120994 -1.346708)
		(end 209.120994 -1.685036)
		(width 0.14224)
		(layer "In11.Cu")
		(net "M_C_DQS_DP<10>")
	)
	(segment
		(start 216.866216 -43.351704)
		(end 214.474552 -40.96004)
		(width 0.14224)
		(layer "In11.Cu")
		(net "M_C_DQS_DP<10>")
	)
	(segment
		(start 213.510368 -40.96004)
		(end 208.76768 -36.217352)
		(width 0.14224)
		(layer "In11.Cu")
		(net "M_C_DQS_DP<10>")
	)
	(segment
		(start 239.061244 -61.13399)
		(end 239.028478 -61.13399)
		(width 0.0889)
		(layer "In11.Cu")
		(net "M_C_DQS_DP<10>")
	)
	(segment
		(start 209.248502 -1.2192)
		(end 209.120994 -1.346708)
		(width 0.14224)
		(layer "In11.Cu")
		(net "M_C_DQS_DP<10>")
	)
	(segment
		(start 209.679032 -34.378392)
		(end 209.552032 -34.251392)
		(width 0.14224)
		(layer "In11.Cu")
		(net "M_C_DQS_DP<10>")
	)
	(segment
		(start 233.856022 -58.657236)
		(end 232.370376 -57.17159)
		(width 0.0889)
		(layer "In11.Cu")
		(net "M_C_DQS_DP<10>")
	)
	(segment
		(start 235.100368 -58.857388)
		(end 235.100368 -58.857134)
		(width 0.0889)
		(layer "In11.Cu")
		(net "M_C_DQS_DP<10>")
	)
	(segment
		(start 239.919764 -61.438536)
		(end 239.8395 -61.439044)
		(width 0.0889)
		(layer "In11.Cu")
		(net "M_C_DQS_DP<10>")
	)
	(arc
		(start 239.028478 -61.13399)
		(mid 238.743054 -61.050523)
		(end 238.534448 -60.838588)
		(width 0.0889)
		(layer "In11.Cu")
		(net "M_C_DQS_DP<10>")
	)
	(arc
		(start 239.192816 -61.161422)
		(mid 239.128189 -61.14215)
		(end 239.061244 -61.13399)
		(width 0.0889)
		(layer "In11.Cu")
		(net "M_C_DQS_DP<10>")
	)
	(arc
		(start 235.958888 -59.352688)
		(mid 235.818809 -59.209952)
		(end 235.627164 -59.15279)
		(width 0.0889)
		(layer "In11.Cu")
		(net "M_C_DQS_DP<10>")
	)
	(arc
		(start 238.534448 -60.838588)
		(mid 238.392765 -60.694784)
		(end 238.198914 -60.638436)
		(width 0.0889)
		(layer "In11.Cu")
		(net "M_C_DQS_DP<10>")
	)
	(arc
		(start 235.100368 -58.857134)
		(mid 234.96018 -58.714332)
		(end 234.76839 -58.657236)
		(width 0.0889)
		(layer "In11.Cu")
		(net "M_C_DQS_DP<10>")
	)
	(arc
		(start 240.251488 -61.238638)
		(mid 240.111409 -61.381374)
		(end 239.919764 -61.438536)
		(width 0.0889)
		(layer "In11.Cu")
		(net "M_C_DQS_DP<10>")
	)
	(arc
		(start 236.817408 -59.847988)
		(mid 236.675725 -59.704184)
		(end 236.481874 -59.647836)
		(width 0.0889)
		(layer "In11.Cu")
		(net "M_C_DQS_DP<10>")
	)
	(arc
		(start 239.23752 -61.18225)
		(mid 239.215487 -61.171152)
		(end 239.192816 -61.161422)
		(width 0.0889)
		(layer "In11.Cu")
		(net "M_C_DQS_DP<10>")
	)
	(arc
		(start 235.599224 -59.15279)
		(mid 235.311079 -59.070471)
		(end 235.100368 -58.857388)
		(width 0.0889)
		(layer "In11.Cu")
		(net "M_C_DQS_DP<10>")
	)
	(arc
		(start 239.8395 -61.439044)
		(mid 239.692577 -61.399163)
		(end 239.586008 -61.290454)
		(width 0.0889)
		(layer "In11.Cu")
		(net "M_C_DQS_DP<10>")
	)
	(arc
		(start 238.166148 -60.638436)
		(mid 237.882931 -60.554155)
		(end 237.675928 -60.343288)
		(width 0.0889)
		(layer "In11.Cu")
		(net "M_C_DQS_DP<10>")
	)
	(arc
		(start 236.449108 -59.647836)
		(mid 236.165891 -59.563555)
		(end 235.958888 -59.352688)
		(width 0.0889)
		(layer "In11.Cu")
		(net "M_C_DQS_DP<10>")
	)
	(arc
		(start 237.311438 -60.14339)
		(mid 237.026014 -60.059923)
		(end 236.817408 -59.847988)
		(width 0.0889)
		(layer "In11.Cu")
		(net "M_C_DQS_DP<10>")
	)
	(arc
		(start 237.675928 -60.343288)
		(mid 237.535849 -60.200552)
		(end 237.344204 -60.14339)
		(width 0.0889)
		(layer "In11.Cu")
		(net "M_C_DQS_DP<10>")
	)
	(segment
		(start 242.193318 -65.000886)
		(end 241.621818 -65.000886)
		(width 0.0889)
		(layer "F.Cu")
		(net "M_C_DQS_DP<0>")
	)
	(segment
		(start 201.507598 1.455166)
		(end 201.311764 1.455166)
		(width 0.1651)
		(layer "F.Cu")
		(net "M_C_DQS_DP<0>")
	)
	(segment
		(start 201.499978 0.277622)
		(end 201.721466 0.49911)
		(width 0.1651)
		(layer "F.Cu")
		(net "M_C_DQS_DP<0>")
	)
	(segment
		(start 201.721466 1.241298)
		(end 201.507598 1.455166)
		(width 0.1651)
		(layer "F.Cu")
		(net "M_C_DQS_DP<0>")
	)
	(segment
		(start 201.311764 1.455166)
		(end 201.037952 1.181354)
		(width 0.1651)
		(layer "F.Cu")
		(net "M_C_DQS_DP<0>")
	)
	(segment
		(start 201.500486 -0.821182)
		(end 201.499978 -0.821182)
		(width 0.1651)
		(layer "F.Cu")
		(net "M_C_DQS_DP<0>")
	)
	(segment
		(start 201.499978 -0.821182)
		(end 201.499978 0.277622)
		(width 0.1651)
		(layer "F.Cu")
		(net "M_C_DQS_DP<0>")
	)
	(segment
		(start 201.721466 0.49911)
		(end 201.721466 1.241298)
		(width 0.1651)
		(layer "F.Cu")
		(net "M_C_DQS_DP<0>")
	)
	(via
		(at 201.037952 1.181354)
		(size 0.508)
		(drill 0.254)
		(layers "F.Cu" "B.Cu")
		(net "M_C_DQS_DP<0>")
	)
	(via
		(at 241.621818 -65.000886)
		(size 0.508)
		(drill 0.254)
		(layers "F.Cu" "B.Cu")
		(net "M_C_DQS_DP<0>")
	)
	(via
		(at 201.037952 -3.026156)
		(size 0.508)
		(drill 0.254)
		(layers "F.Cu" "B.Cu")
		(net "M_C_DQS_DP<0>")
	)
	(segment
		(start 201.539856 -3.30708)
		(end 201.318876 -3.30708)
		(width 0.1651)
		(layer "B.Cu")
		(net "M_C_DQS_DP<0>")
	)
	(segment
		(start 201.499978 -1.021842)
		(end 201.499978 -2.538222)
		(width 0.1651)
		(layer "B.Cu")
		(net "M_C_DQS_DP<0>")
	)
	(segment
		(start 201.679556 -3.16738)
		(end 201.539856 -3.30708)
		(width 0.1651)
		(layer "B.Cu")
		(net "M_C_DQS_DP<0>")
	)
	(segment
		(start 201.318876 -3.30708)
		(end 201.037952 -3.026156)
		(width 0.1651)
		(layer "B.Cu")
		(net "M_C_DQS_DP<0>")
	)
	(segment
		(start 201.499978 -2.538222)
		(end 201.679556 -2.7178)
		(width 0.1651)
		(layer "B.Cu")
		(net "M_C_DQS_DP<0>")
	)
	(segment
		(start 201.500486 -1.021842)
		(end 201.499978 -1.021842)
		(width 0.1651)
		(layer "B.Cu")
		(net "M_C_DQS_DP<0>")
	)
	(segment
		(start 201.679556 -2.7178)
		(end 201.679556 -3.16738)
		(width 0.1651)
		(layer "B.Cu")
		(net "M_C_DQS_DP<0>")
	)
	(segment
		(start 201.57948 -2.058924)
		(end 201.400156 -1.8796)
		(width 0.14224)
		(layer "In11.Cu")
		(net "M_C_DQS_DP<0>")
	)
	(segment
		(start 201.037952 -3.026156)
		(end 200.600056 -3.464052)
		(width 0.14224)
		(layer "In11.Cu")
		(net "M_C_DQS_DP<0>")
	)
	(segment
		(start 201.0918 -1.7018)
		(end 201.0918 -1.4478)
		(width 0.14224)
		(layer "In11.Cu")
		(net "M_C_DQS_DP<0>")
	)
	(segment
		(start 231.297988 -64.14516)
		(end 231.320086 -64.14516)
		(width 0.0889)
		(layer "In11.Cu")
		(net "M_C_DQS_DP<0>")
	)
	(segment
		(start 200.719436 -4.78409)
		(end 200.719436 -5.392674)
		(width 0.14224)
		(layer "In11.Cu")
		(net "M_C_DQS_DP<0>")
	)
	(segment
		(start 201.551032 -24.88184)
		(end 200.41108 -26.021792)
		(width 0.14224)
		(layer "In11.Cu")
		(net "M_C_DQS_DP<0>")
	)
	(segment
		(start 201.2696 -1.27)
		(end 201.3966 -1.27)
		(width 0.14224)
		(layer "In11.Cu")
		(net "M_C_DQS_DP<0>")
	)
	(segment
		(start 201.819256 -33.810194)
		(end 200.980294 -33.810194)
		(width 0.14224)
		(layer "In11.Cu")
		(net "M_C_DQS_DP<0>")
	)
	(segment
		(start 201.044556 -0.076454)
		(end 201.19721 0.0762)
		(width 0.14224)
		(layer "In11.Cu")
		(net "M_C_DQS_DP<0>")
	)
	(segment
		(start 234.752896 -63.61049)
		(end 234.75442 -63.61049)
		(width 0.0889)
		(layer "In11.Cu")
		(net "M_C_DQS_DP<0>")
	)
	(segment
		(start 235.598462 -64.10579)
		(end 235.627164 -64.10579)
		(width 0.0889)
		(layer "In11.Cu")
		(net "M_C_DQS_DP<0>")
	)
	(segment
		(start 241.936016 -64.753236)
		(end 241.914934 -64.831976)
		(width 0.0889)
		(layer "In11.Cu")
		(net "M_C_DQS_DP<0>")
	)
	(segment
		(start 201.037952 -3.02641)
		(end 201.316844 -3.02641)
		(width 0.14224)
		(layer "In11.Cu")
		(net "M_C_DQS_DP<0>")
	)
	(segment
		(start 238.166148 -65.591436)
		(end 238.198914 -65.591436)
		(width 0.0889)
		(layer "In11.Cu")
		(net "M_C_DQS_DP<0>")
	)
	(segment
		(start 200.980294 -33.810194)
		(end 200.461372 -34.329116)
		(width 0.14224)
		(layer "In11.Cu")
		(net "M_C_DQS_DP<0>")
	)
	(segment
		(start 201.551032 -37.676328)
		(end 205.211426 -41.336722)
		(width 0.14224)
		(layer "In11.Cu")
		(net "M_C_DQS_DP<0>")
	)
	(segment
		(start 201.57948 0.921512)
		(end 201.319638 1.181354)
		(width 0.14224)
		(layer "In11.Cu")
		(net "M_C_DQS_DP<0>")
	)
	(segment
		(start 201.0918 -1.4478)
		(end 201.2696 -1.27)
		(width 0.14224)
		(layer "In11.Cu")
		(net "M_C_DQS_DP<0>")
	)
	(segment
		(start 201.316844 -3.02641)
		(end 201.57948 -2.763774)
		(width 0.14224)
		(layer "In11.Cu")
		(net "M_C_DQS_DP<0>")
	)
	(segment
		(start 201.57948 -2.763774)
		(end 201.57948 -2.058924)
		(width 0.14224)
		(layer "In11.Cu")
		(net "M_C_DQS_DP<0>")
	)
	(segment
		(start 241.914934 -64.831976)
		(end 241.621818 -65.000886)
		(width 0.0889)
		(layer "In11.Cu")
		(net "M_C_DQS_DP<0>")
	)
	(segment
		(start 200.719436 -5.392674)
		(end 201.551032 -6.22427)
		(width 0.14224)
		(layer "In11.Cu")
		(net "M_C_DQS_DP<0>")
	)
	(segment
		(start 241.610642 -64.600836)
		(end 241.632994 -64.600836)
		(width 0.0889)
		(layer "In11.Cu")
		(net "M_C_DQS_DP<0>")
	)
	(segment
		(start 231.320086 -64.14516)
		(end 231.359456 -64.10579)
		(width 0.0889)
		(layer "In11.Cu")
		(net "M_C_DQS_DP<0>")
	)
	(segment
		(start 201.57948 0.255778)
		(end 201.57948 0.921512)
		(width 0.14224)
		(layer "In11.Cu")
		(net "M_C_DQS_DP<0>")
	)
	(segment
		(start 237.311438 -65.09639)
		(end 237.344204 -65.09639)
		(width 0.0889)
		(layer "In11.Cu")
		(net "M_C_DQS_DP<0>")
	)
	(segment
		(start 201.319638 1.181354)
		(end 201.037952 1.181354)
		(width 0.14224)
		(layer "In11.Cu")
		(net "M_C_DQS_DP<0>")
	)
	(segment
		(start 201.374502 -0.5334)
		(end 201.19721 -0.5334)
		(width 0.14224)
		(layer "In11.Cu")
		(net "M_C_DQS_DP<0>")
	)
	(segment
		(start 233.894122 -64.105536)
		(end 233.896154 -64.105536)
		(width 0.0889)
		(layer "In11.Cu")
		(net "M_C_DQS_DP<0>")
	)
	(segment
		(start 240.748312 -65.09639)
		(end 240.781078 -65.09639)
		(width 0.0889)
		(layer "In11.Cu")
		(net "M_C_DQS_DP<0>")
	)
	(segment
		(start 205.211426 -42.898314)
		(end 226.458272 -64.14516)
		(width 0.14224)
		(layer "In11.Cu")
		(net "M_C_DQS_DP<0>")
	)
	(segment
		(start 201.2696 -1.8796)
		(end 201.0918 -1.7018)
		(width 0.14224)
		(layer "In11.Cu")
		(net "M_C_DQS_DP<0>")
	)
	(segment
		(start 231.359456 -64.10579)
		(end 232.191814 -64.10579)
		(width 0.0889)
		(layer "In11.Cu")
		(net "M_C_DQS_DP<0>")
	)
	(segment
		(start 226.458272 -64.14516)
		(end 231.297988 -64.14516)
		(width 0.14224)
		(layer "In11.Cu")
		(net "M_C_DQS_DP<0>")
	)
	(segment
		(start 200.847198 -35.42792)
		(end 201.395838 -35.42792)
		(width 0.14224)
		(layer "In11.Cu")
		(net "M_C_DQS_DP<0>")
	)
	(segment
		(start 200.461372 -34.329116)
		(end 200.461372 -35.042094)
		(width 0.14224)
		(layer "In11.Cu")
		(net "M_C_DQS_DP<0>")
	)
	(segment
		(start 201.19721 -0.5334)
		(end 201.044556 -0.380746)
		(width 0.14224)
		(layer "In11.Cu")
		(net "M_C_DQS_DP<0>")
	)
	(segment
		(start 201.044556 -0.380746)
		(end 201.044556 -0.076454)
		(width 0.14224)
		(layer "In11.Cu")
		(net "M_C_DQS_DP<0>")
	)
	(segment
		(start 205.211426 -41.336722)
		(end 205.211426 -42.898314)
		(width 0.14224)
		(layer "In11.Cu")
		(net "M_C_DQS_DP<0>")
	)
	(segment
		(start 201.037952 -3.026156)
		(end 201.037952 -3.02641)
		(width 0.14224)
		(layer "In11.Cu")
		(net "M_C_DQS_DP<0>")
	)
	(segment
		(start 239.893602 -65.591436)
		(end 239.926368 -65.591436)
		(width 0.0889)
		(layer "In11.Cu")
		(net "M_C_DQS_DP<0>")
	)
	(segment
		(start 202.066144 -32.954722)
		(end 202.066144 -33.563306)
		(width 0.14224)
		(layer "In11.Cu")
		(net "M_C_DQS_DP<0>")
	)
	(segment
		(start 200.461372 -35.042094)
		(end 200.847198 -35.42792)
		(width 0.14224)
		(layer "In11.Cu")
		(net "M_C_DQS_DP<0>")
	)
	(segment
		(start 201.399902 0.0762)
		(end 201.57948 0.255778)
		(width 0.14224)
		(layer "In11.Cu")
		(net "M_C_DQS_DP<0>")
	)
	(segment
		(start 201.57948 -1.08712)
		(end 201.57948 -0.738378)
		(width 0.14224)
		(layer "In11.Cu")
		(net "M_C_DQS_DP<0>")
	)
	(segment
		(start 233.035856 -63.61049)
		(end 233.03738 -63.61049)
		(width 0.0889)
		(layer "In11.Cu")
		(net "M_C_DQS_DP<0>")
	)
	(segment
		(start 201.400156 -1.8796)
		(end 201.2696 -1.8796)
		(width 0.14224)
		(layer "In11.Cu")
		(net "M_C_DQS_DP<0>")
	)
	(segment
		(start 201.395838 -35.42792)
		(end 201.551032 -35.583114)
		(width 0.14224)
		(layer "In11.Cu")
		(net "M_C_DQS_DP<0>")
	)
	(segment
		(start 200.41108 -26.021792)
		(end 200.41108 -32.355028)
		(width 0.14224)
		(layer "In11.Cu")
		(net "M_C_DQS_DP<0>")
	)
	(segment
		(start 201.551032 -6.22427)
		(end 201.551032 -24.88184)
		(width 0.14224)
		(layer "In11.Cu")
		(net "M_C_DQS_DP<0>")
	)
	(segment
		(start 200.41108 -32.355028)
		(end 200.789286 -32.733234)
		(width 0.14224)
		(layer "In11.Cu")
		(net "M_C_DQS_DP<0>")
	)
	(segment
		(start 236.449108 -64.600836)
		(end 236.481874 -64.600836)
		(width 0.0889)
		(layer "In11.Cu")
		(net "M_C_DQS_DP<0>")
	)
	(segment
		(start 201.551032 -35.583114)
		(end 201.551032 -37.676328)
		(width 0.14224)
		(layer "In11.Cu")
		(net "M_C_DQS_DP<0>")
	)
	(segment
		(start 201.844656 -32.733234)
		(end 202.066144 -32.954722)
		(width 0.14224)
		(layer "In11.Cu")
		(net "M_C_DQS_DP<0>")
	)
	(segment
		(start 200.789286 -32.733234)
		(end 201.844656 -32.733234)
		(width 0.14224)
		(layer "In11.Cu")
		(net "M_C_DQS_DP<0>")
	)
	(segment
		(start 201.19721 0.0762)
		(end 201.399902 0.0762)
		(width 0.14224)
		(layer "In11.Cu")
		(net "M_C_DQS_DP<0>")
	)
	(segment
		(start 201.3966 -1.27)
		(end 201.57948 -1.08712)
		(width 0.14224)
		(layer "In11.Cu")
		(net "M_C_DQS_DP<0>")
	)
	(segment
		(start 239.04575 -66.08699)
		(end 239.046766 -66.08699)
		(width 0.0889)
		(layer "In11.Cu")
		(net "M_C_DQS_DP<0>")
	)
	(segment
		(start 201.57948 -0.738378)
		(end 201.374502 -0.5334)
		(width 0.14224)
		(layer "In11.Cu")
		(net "M_C_DQS_DP<0>")
	)
	(segment
		(start 200.600056 -4.66471)
		(end 200.719436 -4.78409)
		(width 0.14224)
		(layer "In11.Cu")
		(net "M_C_DQS_DP<0>")
	)
	(segment
		(start 200.600056 -3.464052)
		(end 200.600056 -4.66471)
		(width 0.14224)
		(layer "In11.Cu")
		(net "M_C_DQS_DP<0>")
	)
	(segment
		(start 202.066144 -33.563306)
		(end 201.819256 -33.810194)
		(width 0.14224)
		(layer "In11.Cu")
		(net "M_C_DQS_DP<0>")
	)
	(arc
		(start 238.198914 -65.591436)
		(mid 238.392764 -65.647786)
		(end 238.534448 -65.791588)
		(width 0.0889)
		(layer "In11.Cu")
		(net "M_C_DQS_DP<0>")
	)
	(arc
		(start 235.958888 -64.305688)
		(mid 236.165892 -64.516552)
		(end 236.449108 -64.600836)
		(width 0.0889)
		(layer "In11.Cu")
		(net "M_C_DQS_DP<0>")
	)
	(arc
		(start 235.100368 -63.810388)
		(mid 235.310721 -64.02336)
		(end 235.598462 -64.10579)
		(width 0.0889)
		(layer "In11.Cu")
		(net "M_C_DQS_DP<0>")
	)
	(arc
		(start 232.689908 -63.810388)
		(mid 232.83608 -63.664053)
		(end 233.035856 -63.61049)
		(width 0.0889)
		(layer "In11.Cu")
		(net "M_C_DQS_DP<0>")
	)
	(arc
		(start 232.191814 -64.10579)
		(mid 232.479501 -64.023269)
		(end 232.689908 -63.810388)
		(width 0.0889)
		(layer "In11.Cu")
		(net "M_C_DQS_DP<0>")
	)
	(arc
		(start 241.632994 -64.600836)
		(mid 241.801431 -64.643369)
		(end 241.936016 -64.753236)
		(width 0.0889)
		(layer "In11.Cu")
		(net "M_C_DQS_DP<0>")
	)
	(arc
		(start 239.046766 -66.08699)
		(mid 239.342029 -66.007839)
		(end 239.558068 -65.791588)
		(width 0.0889)
		(layer "In11.Cu")
		(net "M_C_DQS_DP<0>")
	)
	(arc
		(start 240.416588 -65.296288)
		(mid 240.556667 -65.153552)
		(end 240.748312 -65.09639)
		(width 0.0889)
		(layer "In11.Cu")
		(net "M_C_DQS_DP<0>")
	)
	(arc
		(start 234.75442 -63.61049)
		(mid 234.954193 -63.664059)
		(end 235.100368 -63.810388)
		(width 0.0889)
		(layer "In11.Cu")
		(net "M_C_DQS_DP<0>")
	)
	(arc
		(start 241.275108 -64.800988)
		(mid 241.416791 -64.657184)
		(end 241.610642 -64.600836)
		(width 0.0889)
		(layer "In11.Cu")
		(net "M_C_DQS_DP<0>")
	)
	(arc
		(start 236.817408 -64.800988)
		(mid 237.026016 -65.01292)
		(end 237.311438 -65.09639)
		(width 0.0889)
		(layer "In11.Cu")
		(net "M_C_DQS_DP<0>")
	)
	(arc
		(start 234.406948 -63.810388)
		(mid 234.55312 -63.664053)
		(end 234.752896 -63.61049)
		(width 0.0889)
		(layer "In11.Cu")
		(net "M_C_DQS_DP<0>")
	)
	(arc
		(start 233.03738 -63.61049)
		(mid 233.237153 -63.664059)
		(end 233.383328 -63.810388)
		(width 0.0889)
		(layer "In11.Cu")
		(net "M_C_DQS_DP<0>")
	)
	(arc
		(start 233.896154 -64.105536)
		(mid 234.191148 -64.026462)
		(end 234.406948 -63.810388)
		(width 0.0889)
		(layer "In11.Cu")
		(net "M_C_DQS_DP<0>")
	)
	(arc
		(start 239.926368 -65.591436)
		(mid 240.209585 -65.507155)
		(end 240.416588 -65.296288)
		(width 0.0889)
		(layer "In11.Cu")
		(net "M_C_DQS_DP<0>")
	)
	(arc
		(start 238.534448 -65.791588)
		(mid 238.750511 -66.007797)
		(end 239.04575 -66.08699)
		(width 0.0889)
		(layer "In11.Cu")
		(net "M_C_DQS_DP<0>")
	)
	(arc
		(start 235.627164 -64.10579)
		(mid 235.818806 -64.162956)
		(end 235.958888 -64.305688)
		(width 0.0889)
		(layer "In11.Cu")
		(net "M_C_DQS_DP<0>")
	)
	(arc
		(start 233.383328 -63.810388)
		(mid 233.599182 -64.026369)
		(end 233.894122 -64.105536)
		(width 0.0889)
		(layer "In11.Cu")
		(net "M_C_DQS_DP<0>")
	)
	(arc
		(start 240.781078 -65.09639)
		(mid 241.066502 -65.012923)
		(end 241.275108 -64.800988)
		(width 0.0889)
		(layer "In11.Cu")
		(net "M_C_DQS_DP<0>")
	)
	(arc
		(start 237.675928 -65.296288)
		(mid 237.882932 -65.507152)
		(end 238.166148 -65.591436)
		(width 0.0889)
		(layer "In11.Cu")
		(net "M_C_DQS_DP<0>")
	)
	(arc
		(start 236.481874 -64.600836)
		(mid 236.675724 -64.657186)
		(end 236.817408 -64.800988)
		(width 0.0889)
		(layer "In11.Cu")
		(net "M_C_DQS_DP<0>")
	)
	(arc
		(start 239.558068 -65.791588)
		(mid 239.699751 -65.647784)
		(end 239.893602 -65.591436)
		(width 0.0889)
		(layer "In11.Cu")
		(net "M_C_DQS_DP<0>")
	)
	(arc
		(start 237.344204 -65.09639)
		(mid 237.535846 -65.153556)
		(end 237.675928 -65.296288)
		(width 0.0889)
		(layer "In11.Cu")
		(net "M_C_DQS_DP<0>")
	)
	(segment
		(start 240.476278 -65.991486)
		(end 239.904778 -65.991486)
		(width 0.0889)
		(layer "F.Cu")
		(net "M_C_DQS_DN<9>")
	)
	(segment
		(start 200.231756 2.518156)
		(end 200.231756 2.286)
		(width 0.1651)
		(layer "F.Cu")
		(net "M_C_DQS_DN<9>")
	)
	(segment
		(start 200.64984 2.93624)
		(end 200.231756 2.518156)
		(width 0.1651)
		(layer "F.Cu")
		(net "M_C_DQS_DN<9>")
	)
	(segment
		(start 200.417684 2.100072)
		(end 200.417684 1.853438)
		(width 0.1651)
		(layer "F.Cu")
		(net "M_C_DQS_DN<9>")
	)
	(segment
		(start 199.768206 1.7907)
		(end 199.749156 1.7907)
		(width 0.1651)
		(layer "F.Cu")
		(net "M_C_DQS_DN<9>")
	)
	(segment
		(start 200.231756 2.286)
		(end 200.417684 2.100072)
		(width 0.1651)
		(layer "F.Cu")
		(net "M_C_DQS_DN<9>")
	)
	(segment
		(start 200.165716 1.60147)
		(end 199.957436 1.60147)
		(width 0.1651)
		(layer "F.Cu")
		(net "M_C_DQS_DN<9>")
	)
	(segment
		(start 199.957436 1.60147)
		(end 199.768206 1.7907)
		(width 0.1651)
		(layer "F.Cu")
		(net "M_C_DQS_DN<9>")
	)
	(segment
		(start 200.417684 1.853438)
		(end 200.165716 1.60147)
		(width 0.1651)
		(layer "F.Cu")
		(net "M_C_DQS_DN<9>")
	)
	(segment
		(start 200.64984 3.778758)
		(end 200.64984 2.93624)
		(width 0.1651)
		(layer "F.Cu")
		(net "M_C_DQS_DN<9>")
	)
	(segment
		(start 200.650348 3.778758)
		(end 200.64984 3.778758)
		(width 0.1651)
		(layer "F.Cu")
		(net "M_C_DQS_DN<9>")
	)
	(via
		(at 239.904778 -65.991486)
		(size 0.508)
		(drill 0.254)
		(layers "F.Cu" "B.Cu")
		(net "M_C_DQS_DN<9>")
	)
	(via
		(at 199.749156 1.7907)
		(size 0.508)
		(drill 0.254)
		(layers "F.Cu" "B.Cu")
		(net "M_C_DQS_DN<9>")
	)
	(via
		(at 199.742552 -3.6322)
		(size 0.508)
		(drill 0.254)
		(layers "F.Cu" "B.Cu")
		(net "M_C_DQS_DN<9>")
	)
	(segment
		(start 200.650348 -5.621782)
		(end 200.64984 -5.621782)
		(width 0.1651)
		(layer "B.Cu")
		(net "M_C_DQS_DN<9>")
	)
	(segment
		(start 200.64984 -4.964938)
		(end 200.206356 -4.521454)
		(width 0.1651)
		(layer "B.Cu")
		(net "M_C_DQS_DN<9>")
	)
	(segment
		(start 200.384156 -3.6576)
		(end 200.164192 -3.437636)
		(width 0.1651)
		(layer "B.Cu")
		(net "M_C_DQS_DN<9>")
	)
	(segment
		(start 200.64984 -5.621782)
		(end 200.64984 -4.964938)
		(width 0.1651)
		(layer "B.Cu")
		(net "M_C_DQS_DN<9>")
	)
	(segment
		(start 200.384156 -3.9878)
		(end 200.384156 -3.6576)
		(width 0.1651)
		(layer "B.Cu")
		(net "M_C_DQS_DN<9>")
	)
	(segment
		(start 200.206356 -4.521454)
		(end 200.206356 -4.1656)
		(width 0.1651)
		(layer "B.Cu")
		(net "M_C_DQS_DN<9>")
	)
	(segment
		(start 200.206356 -4.1656)
		(end 200.384156 -3.9878)
		(width 0.1651)
		(layer "B.Cu")
		(net "M_C_DQS_DN<9>")
	)
	(segment
		(start 199.937116 -3.437636)
		(end 199.742552 -3.6322)
		(width 0.1651)
		(layer "B.Cu")
		(net "M_C_DQS_DN<9>")
	)
	(segment
		(start 200.164192 -3.437636)
		(end 199.937116 -3.437636)
		(width 0.1651)
		(layer "B.Cu")
		(net "M_C_DQS_DN<9>")
	)
	(segment
		(start 234.75315 -64.41059)
		(end 234.75442 -64.41059)
		(width 0.0889)
		(layer "In11.Cu")
		(net "M_C_DQS_DN<9>")
	)
	(segment
		(start 228.690932 -64.75222)
		(end 228.805232 -64.86652)
		(width 0.14224)
		(layer "In11.Cu")
		(net "M_C_DQS_DN<9>")
	)
	(segment
		(start 230.7336 -64.86652)
		(end 230.77297 -64.90589)
		(width 0.0889)
		(layer "In11.Cu")
		(net "M_C_DQS_DN<9>")
	)
	(segment
		(start 200.274428 -38.829488)
		(end 201.958956 -38.829488)
		(width 0.14224)
		(layer "In11.Cu")
		(net "M_C_DQS_DN<9>")
	)
	(segment
		(start 225.421444 -64.1096)
		(end 225.65741 -64.345566)
		(width 0.14224)
		(layer "In11.Cu")
		(net "M_C_DQS_DN<9>")
	)
	(segment
		(start 199.71512 -35.891978)
		(end 199.936608 -36.113466)
		(width 0.14224)
		(layer "In11.Cu")
		(net "M_C_DQS_DN<9>")
	)
	(segment
		(start 200.180956 -4.5974)
		(end 199.977756 -4.8006)
		(width 0.14224)
		(layer "In11.Cu")
		(net "M_C_DQS_DN<9>")
	)
	(segment
		(start 239.519968 -66.530728)
		(end 239.904778 -65.991486)
		(width 0.0889)
		(layer "In11.Cu")
		(net "M_C_DQS_DN<9>")
	)
	(segment
		(start 199.936608 -36.113466)
		(end 200.241154 -36.113466)
		(width 0.14224)
		(layer "In11.Cu")
		(net "M_C_DQS_DN<9>")
	)
	(segment
		(start 224.12071 -62.647068)
		(end 224.300542 -62.8269)
		(width 0.14224)
		(layer "In11.Cu")
		(net "M_C_DQS_DN<9>")
	)
	(segment
		(start 199.71512 -28.812744)
		(end 199.82942 -28.927044)
		(width 0.14224)
		(layer "In11.Cu")
		(net "M_C_DQS_DN<9>")
	)
	(segment
		(start 199.540876 -4.98348)
		(end 199.540876 -5.254752)
		(width 0.14224)
		(layer "In11.Cu")
		(net "M_C_DQS_DN<9>")
	)
	(segment
		(start 236.453172 -65.400936)
		(end 236.484414 -65.400936)
		(width 0.0889)
		(layer "In11.Cu")
		(net "M_C_DQS_DN<9>")
	)
	(segment
		(start 199.71512 -25.296114)
		(end 199.71512 -27.988006)
		(width 0.14224)
		(layer "In11.Cu")
		(net "M_C_DQS_DN<9>")
	)
	(segment
		(start 200.531476 -2.843276)
		(end 200.531476 1.257808)
		(width 0.14224)
		(layer "In11.Cu")
		(net "M_C_DQS_DN<9>")
	)
	(segment
		(start 229.427532 -64.75222)
		(end 229.541832 -64.86652)
		(width 0.14224)
		(layer "In11.Cu")
		(net "M_C_DQS_DN<9>")
	)
	(segment
		(start 200.524872 -10.16508)
		(end 200.524872 -10.35812)
		(width 0.14224)
		(layer "In11.Cu")
		(net "M_C_DQS_DN<9>")
	)
	(segment
		(start 200.683368 -14.301216)
		(end 200.683368 -14.553184)
		(width 0.14224)
		(layer "In11.Cu")
		(net "M_C_DQS_DN<9>")
	)
	(segment
		(start 200.145396 -38.700456)
		(end 200.274428 -38.829488)
		(width 0.14224)
		(layer "In11.Cu")
		(net "M_C_DQS_DN<9>")
	)
	(segment
		(start 199.82942 -31.538672)
		(end 199.71512 -31.652972)
		(width 0.14224)
		(layer "In11.Cu")
		(net "M_C_DQS_DN<9>")
	)
	(segment
		(start 235.601002 -64.90589)
		(end 235.630466 -64.90589)
		(width 0.0889)
		(layer "In11.Cu")
		(net "M_C_DQS_DN<9>")
	)
	(segment
		(start 199.71512 -30.41015)
		(end 199.71512 -31.170372)
		(width 0.14224)
		(layer "In11.Cu")
		(net "M_C_DQS_DN<9>")
	)
	(segment
		(start 200.683368 -10.768584)
		(end 200.524872 -10.92708)
		(width 0.14224)
		(layer "In11.Cu")
		(net "M_C_DQS_DN<9>")
	)
	(segment
		(start 200.75652 -21.06676)
		(end 200.524872 -21.298408)
		(width 0.14224)
		(layer "In11.Cu")
		(net "M_C_DQS_DN<9>")
	)
	(segment
		(start 200.524872 -14.14272)
		(end 200.683368 -14.301216)
		(width 0.14224)
		(layer "In11.Cu")
		(net "M_C_DQS_DN<9>")
	)
	(segment
		(start 199.71512 -32.676592)
		(end 200.05675 -33.018222)
		(width 0.14224)
		(layer "In11.Cu")
		(net "M_C_DQS_DN<9>")
	)
	(segment
		(start 199.71512 -29.92755)
		(end 199.82942 -30.04185)
		(width 0.14224)
		(layer "In11.Cu")
		(net "M_C_DQS_DN<9>")
	)
	(segment
		(start 230.1113 -64.75222)
		(end 230.3653 -64.75222)
		(width 0.14224)
		(layer "In11.Cu")
		(net "M_C_DQS_DN<9>")
	)
	(segment
		(start 229.059232 -64.86652)
		(end 229.173532 -64.75222)
		(width 0.14224)
		(layer "In11.Cu")
		(net "M_C_DQS_DN<9>")
	)
	(segment
		(start 200.194164 1.59512)
		(end 199.944736 1.59512)
		(width 0.14224)
		(layer "In11.Cu")
		(net "M_C_DQS_DN<9>")
	)
	(segment
		(start 199.977756 -4.8006)
		(end 199.723756 -4.8006)
		(width 0.14224)
		(layer "In11.Cu")
		(net "M_C_DQS_DN<9>")
	)
	(segment
		(start 200.524872 -14.71168)
		(end 200.524872 -19.948144)
		(width 0.14224)
		(layer "In11.Cu")
		(net "M_C_DQS_DN<9>")
	)
	(segment
		(start 200.683368 -11.278616)
		(end 200.683368 -11.530584)
		(width 0.14224)
		(layer "In11.Cu")
		(net "M_C_DQS_DN<9>")
	)
	(segment
		(start 226.827588 -64.75222)
		(end 227.081588 -64.75222)
		(width 0.14224)
		(layer "In11.Cu")
		(net "M_C_DQS_DN<9>")
	)
	(segment
		(start 200.524872 -24.486362)
		(end 199.71512 -25.296114)
		(width 0.14224)
		(layer "In11.Cu")
		(net "M_C_DQS_DN<9>")
	)
	(segment
		(start 228.436932 -64.75222)
		(end 228.690932 -64.75222)
		(width 0.14224)
		(layer "In11.Cu")
		(net "M_C_DQS_DN<9>")
	)
	(segment
		(start 226.178364 -64.86652)
		(end 226.713288 -64.86652)
		(width 0.14224)
		(layer "In11.Cu")
		(net "M_C_DQS_DN<9>")
	)
	(segment
		(start 227.617274 -64.75222)
		(end 227.871274 -64.75222)
		(width 0.14224)
		(layer "In11.Cu")
		(net "M_C_DQS_DN<9>")
	)
	(segment
		(start 227.195888 -64.86652)
		(end 227.502974 -64.86652)
		(width 0.14224)
		(layer "In11.Cu")
		(net "M_C_DQS_DN<9>")
	)
	(segment
		(start 200.683368 -10.516616)
		(end 200.683368 -10.768584)
		(width 0.14224)
		(layer "In11.Cu")
		(net "M_C_DQS_DN<9>")
	)
	(segment
		(start 229.541832 -64.86652)
		(end 229.997 -64.86652)
		(width 0.14224)
		(layer "In11.Cu")
		(net "M_C_DQS_DN<9>")
	)
	(segment
		(start 199.71512 -28.470606)
		(end 199.71512 -28.812744)
		(width 0.14224)
		(layer "In11.Cu")
		(net "M_C_DQS_DN<9>")
	)
	(segment
		(start 223.779334 -62.46749)
		(end 223.958912 -62.647068)
		(width 0.14224)
		(layer "In11.Cu")
		(net "M_C_DQS_DN<9>")
	)
	(segment
		(start 199.71512 -29.295344)
		(end 199.71512 -29.92755)
		(width 0.14224)
		(layer "In11.Cu")
		(net "M_C_DQS_DN<9>")
	)
	(segment
		(start 200.683368 -9.754616)
		(end 200.683368 -10.006584)
		(width 0.14224)
		(layer "In11.Cu")
		(net "M_C_DQS_DN<9>")
	)
	(segment
		(start 227.502974 -64.86652)
		(end 227.617274 -64.75222)
		(width 0.14224)
		(layer "In11.Cu")
		(net "M_C_DQS_DN<9>")
	)
	(segment
		(start 199.723756 -4.8006)
		(end 199.540876 -4.98348)
		(width 0.14224)
		(layer "In11.Cu")
		(net "M_C_DQS_DN<9>")
	)
	(segment
		(start 199.82942 -28.927044)
		(end 199.82942 -29.181044)
		(width 0.14224)
		(layer "In11.Cu")
		(net "M_C_DQS_DN<9>")
	)
	(segment
		(start 229.173532 -64.75222)
		(end 229.427532 -64.75222)
		(width 0.14224)
		(layer "In11.Cu")
		(net "M_C_DQS_DN<9>")
	)
	(segment
		(start 223.779334 -62.305946)
		(end 223.779334 -62.46749)
		(width 0.14224)
		(layer "In11.Cu")
		(net "M_C_DQS_DN<9>")
	)
	(segment
		(start 238.170212 -66.391536)
		(end 238.201454 -66.391536)
		(width 0.0889)
		(layer "In11.Cu")
		(net "M_C_DQS_DN<9>")
	)
	(segment
		(start 200.683368 -14.553184)
		(end 200.524872 -14.71168)
		(width 0.14224)
		(layer "In11.Cu")
		(net "M_C_DQS_DN<9>")
	)
	(segment
		(start 225.998786 -64.525398)
		(end 225.998786 -64.686942)
		(width 0.14224)
		(layer "In11.Cu")
		(net "M_C_DQS_DN<9>")
	)
	(segment
		(start 233.03611 -64.41059)
		(end 233.03738 -64.41059)
		(width 0.0889)
		(layer "In11.Cu")
		(net "M_C_DQS_DN<9>")
	)
	(segment
		(start 200.683368 -10.006584)
		(end 200.524872 -10.16508)
		(width 0.14224)
		(layer "In11.Cu")
		(net "M_C_DQS_DN<9>")
	)
	(segment
		(start 199.742552 -3.6322)
		(end 200.531476 -2.843276)
		(width 0.14224)
		(layer "In11.Cu")
		(net "M_C_DQS_DN<9>")
	)
	(segment
		(start 227.871274 -64.75222)
		(end 227.985574 -64.86652)
		(width 0.14224)
		(layer "In11.Cu")
		(net "M_C_DQS_DN<9>")
	)
	(segment
		(start 199.71512 -31.652972)
		(end 199.71512 -32.676592)
		(width 0.14224)
		(layer "In11.Cu")
		(net "M_C_DQS_DN<9>")
	)
	(segment
		(start 199.82942 -31.284672)
		(end 199.82942 -31.538672)
		(width 0.14224)
		(layer "In11.Cu")
		(net "M_C_DQS_DN<9>")
	)
	(segment
		(start 230.77297 -64.90589)
		(end 232.189274 -64.90589)
		(width 0.0889)
		(layer "In11.Cu")
		(net "M_C_DQS_DN<9>")
	)
	(segment
		(start 199.944736 1.59512)
		(end 199.749156 1.7907)
		(width 0.14224)
		(layer "In11.Cu")
		(net "M_C_DQS_DN<9>")
	)
	(segment
		(start 199.71512 -31.170372)
		(end 199.82942 -31.284672)
		(width 0.14224)
		(layer "In11.Cu")
		(net "M_C_DQS_DN<9>")
	)
	(segment
		(start 200.683368 -11.530584)
		(end 200.524872 -11.68908)
		(width 0.14224)
		(layer "In11.Cu")
		(net "M_C_DQS_DN<9>")
	)
	(segment
		(start 200.05675 -33.018222)
		(end 200.05675 -33.75025)
		(width 0.14224)
		(layer "In11.Cu")
		(net "M_C_DQS_DN<9>")
	)
	(segment
		(start 199.71512 -34.09188)
		(end 199.71512 -35.891978)
		(width 0.14224)
		(layer "In11.Cu")
		(net "M_C_DQS_DN<9>")
	)
	(segment
		(start 200.180956 -4.070604)
		(end 200.180956 -4.5974)
		(width 0.14224)
		(layer "In11.Cu")
		(net "M_C_DQS_DN<9>")
	)
	(segment
		(start 200.524872 -21.298408)
		(end 200.524872 -24.486362)
		(width 0.14224)
		(layer "In11.Cu")
		(net "M_C_DQS_DN<9>")
	)
	(segment
		(start 200.524872 -6.238748)
		(end 200.524872 -9.59612)
		(width 0.14224)
		(layer "In11.Cu")
		(net "M_C_DQS_DN<9>")
	)
	(segment
		(start 200.531476 1.257808)
		(end 200.194164 1.59512)
		(width 0.14224)
		(layer "In11.Cu")
		(net "M_C_DQS_DN<9>")
	)
	(segment
		(start 202.609704 -39.480236)
		(end 202.609704 -40.748712)
		(width 0.14224)
		(layer "In11.Cu")
		(net "M_C_DQS_DN<9>")
	)
	(segment
		(start 199.82942 -30.04185)
		(end 199.82942 -30.29585)
		(width 0.14224)
		(layer "In11.Cu")
		(net "M_C_DQS_DN<9>")
	)
	(segment
		(start 200.524872 -9.59612)
		(end 200.683368 -9.754616)
		(width 0.14224)
		(layer "In11.Cu")
		(net "M_C_DQS_DN<9>")
	)
	(segment
		(start 200.241154 -36.113466)
		(end 200.68413 -36.556442)
		(width 0.14224)
		(layer "In11.Cu")
		(net "M_C_DQS_DN<9>")
	)
	(segment
		(start 224.481644 -63.1698)
		(end 224.643442 -63.1698)
		(width 0.14224)
		(layer "In11.Cu")
		(net "M_C_DQS_DN<9>")
	)
	(segment
		(start 200.524872 -10.35812)
		(end 200.683368 -10.516616)
		(width 0.14224)
		(layer "In11.Cu")
		(net "M_C_DQS_DN<9>")
	)
	(segment
		(start 201.958956 -38.829488)
		(end 202.609704 -39.480236)
		(width 0.14224)
		(layer "In11.Cu")
		(net "M_C_DQS_DN<9>")
	)
	(segment
		(start 199.71512 -27.988006)
		(end 199.82942 -28.102306)
		(width 0.14224)
		(layer "In11.Cu")
		(net "M_C_DQS_DN<9>")
	)
	(segment
		(start 227.985574 -64.86652)
		(end 228.322632 -64.86652)
		(width 0.14224)
		(layer "In11.Cu")
		(net "M_C_DQS_DN<9>")
	)
	(segment
		(start 200.145396 -37.792152)
		(end 200.145396 -38.700456)
		(width 0.14224)
		(layer "In11.Cu")
		(net "M_C_DQS_DN<9>")
	)
	(segment
		(start 224.300542 -62.988698)
		(end 224.481644 -63.1698)
		(width 0.14224)
		(layer "In11.Cu")
		(net "M_C_DQS_DN<9>")
	)
	(segment
		(start 229.997 -64.86652)
		(end 230.1113 -64.75222)
		(width 0.14224)
		(layer "In11.Cu")
		(net "M_C_DQS_DN<9>")
	)
	(segment
		(start 230.3653 -64.75222)
		(end 230.4796 -64.86652)
		(width 0.14224)
		(layer "In11.Cu")
		(net "M_C_DQS_DN<9>")
	)
	(segment
		(start 223.599502 -62.126114)
		(end 223.779334 -62.305946)
		(width 0.14224)
		(layer "In11.Cu")
		(net "M_C_DQS_DN<9>")
	)
	(segment
		(start 199.82942 -29.181044)
		(end 199.71512 -29.295344)
		(width 0.14224)
		(layer "In11.Cu")
		(net "M_C_DQS_DN<9>")
	)
	(segment
		(start 228.805232 -64.86652)
		(end 229.059232 -64.86652)
		(width 0.14224)
		(layer "In11.Cu")
		(net "M_C_DQS_DN<9>")
	)
	(segment
		(start 224.823274 -63.349632)
		(end 224.823274 -63.51143)
		(width 0.14224)
		(layer "In11.Cu")
		(net "M_C_DQS_DN<9>")
	)
	(segment
		(start 225.65741 -64.345566)
		(end 225.818954 -64.345566)
		(width 0.14224)
		(layer "In11.Cu")
		(net "M_C_DQS_DN<9>")
	)
	(segment
		(start 223.437958 -62.126114)
		(end 223.599502 -62.126114)
		(width 0.14224)
		(layer "In11.Cu")
		(net "M_C_DQS_DN<9>")
	)
	(segment
		(start 202.609704 -40.748712)
		(end 202.863196 -41.002204)
		(width 0.14224)
		(layer "In11.Cu")
		(net "M_C_DQS_DN<9>")
	)
	(segment
		(start 199.742552 -3.6322)
		(end 200.180956 -4.070604)
		(width 0.14224)
		(layer "In11.Cu")
		(net "M_C_DQS_DN<9>")
	)
	(segment
		(start 204.516736 -41.55059)
		(end 204.516736 -43.204892)
		(width 0.14224)
		(layer "In11.Cu")
		(net "M_C_DQS_DN<9>")
	)
	(segment
		(start 204.516736 -43.204892)
		(end 223.437958 -62.126114)
		(width 0.14224)
		(layer "In11.Cu")
		(net "M_C_DQS_DN<9>")
	)
	(segment
		(start 200.75652 -20.179792)
		(end 200.75652 -21.06676)
		(width 0.14224)
		(layer "In11.Cu")
		(net "M_C_DQS_DN<9>")
	)
	(segment
		(start 200.524872 -11.68908)
		(end 200.524872 -14.14272)
		(width 0.14224)
		(layer "In11.Cu")
		(net "M_C_DQS_DN<9>")
	)
	(segment
		(start 200.524872 -10.92708)
		(end 200.524872 -11.12012)
		(width 0.14224)
		(layer "In11.Cu")
		(net "M_C_DQS_DN<9>")
	)
	(segment
		(start 199.82942 -30.29585)
		(end 199.71512 -30.41015)
		(width 0.14224)
		(layer "In11.Cu")
		(net "M_C_DQS_DN<9>")
	)
	(segment
		(start 200.524872 -19.948144)
		(end 200.75652 -20.179792)
		(width 0.14224)
		(layer "In11.Cu")
		(net "M_C_DQS_DN<9>")
	)
	(segment
		(start 230.4796 -64.86652)
		(end 230.7336 -64.86652)
		(width 0.14224)
		(layer "In11.Cu")
		(net "M_C_DQS_DN<9>")
	)
	(segment
		(start 200.524872 -11.12012)
		(end 200.683368 -11.278616)
		(width 0.14224)
		(layer "In11.Cu")
		(net "M_C_DQS_DN<9>")
	)
	(segment
		(start 199.82942 -28.356306)
		(end 199.71512 -28.470606)
		(width 0.14224)
		(layer "In11.Cu")
		(net "M_C_DQS_DN<9>")
	)
	(segment
		(start 200.05675 -33.75025)
		(end 199.71512 -34.09188)
		(width 0.14224)
		(layer "In11.Cu")
		(net "M_C_DQS_DN<9>")
	)
	(segment
		(start 237.31474 -65.89649)
		(end 237.347506 -65.89649)
		(width 0.0889)
		(layer "In11.Cu")
		(net "M_C_DQS_DN<9>")
	)
	(segment
		(start 225.818954 -64.345566)
		(end 225.998786 -64.525398)
		(width 0.14224)
		(layer "In11.Cu")
		(net "M_C_DQS_DN<9>")
	)
	(segment
		(start 199.540876 -5.254752)
		(end 200.524872 -6.238748)
		(width 0.14224)
		(layer "In11.Cu")
		(net "M_C_DQS_DN<9>")
	)
	(segment
		(start 224.300542 -62.8269)
		(end 224.300542 -62.988698)
		(width 0.14224)
		(layer "In11.Cu")
		(net "M_C_DQS_DN<9>")
	)
	(segment
		(start 225.241612 -63.76797)
		(end 225.421444 -63.947802)
		(width 0.14224)
		(layer "In11.Cu")
		(net "M_C_DQS_DN<9>")
	)
	(segment
		(start 224.823274 -63.51143)
		(end 225.079814 -63.76797)
		(width 0.14224)
		(layer "In11.Cu")
		(net "M_C_DQS_DN<9>")
	)
	(segment
		(start 233.894376 -64.905636)
		(end 233.8959 -64.905636)
		(width 0.0889)
		(layer "In11.Cu")
		(net "M_C_DQS_DN<9>")
	)
	(segment
		(start 227.081588 -64.75222)
		(end 227.195888 -64.86652)
		(width 0.14224)
		(layer "In11.Cu")
		(net "M_C_DQS_DN<9>")
	)
	(segment
		(start 224.643442 -63.1698)
		(end 224.823274 -63.349632)
		(width 0.14224)
		(layer "In11.Cu")
		(net "M_C_DQS_DN<9>")
	)
	(segment
		(start 200.68413 -36.556442)
		(end 200.68413 -37.253418)
		(width 0.14224)
		(layer "In11.Cu")
		(net "M_C_DQS_DN<9>")
	)
	(segment
		(start 203.96835 -41.002204)
		(end 204.516736 -41.55059)
		(width 0.14224)
		(layer "In11.Cu")
		(net "M_C_DQS_DN<9>")
	)
	(segment
		(start 223.958912 -62.647068)
		(end 224.12071 -62.647068)
		(width 0.14224)
		(layer "In11.Cu")
		(net "M_C_DQS_DN<9>")
	)
	(segment
		(start 225.421444 -63.947802)
		(end 225.421444 -64.1096)
		(width 0.14224)
		(layer "In11.Cu")
		(net "M_C_DQS_DN<9>")
	)
	(segment
		(start 239.046004 -66.88709)
		(end 239.046512 -66.88709)
		(width 0.0889)
		(layer "In11.Cu")
		(net "M_C_DQS_DN<9>")
	)
	(segment
		(start 200.68413 -37.253418)
		(end 200.145396 -37.792152)
		(width 0.14224)
		(layer "In11.Cu")
		(net "M_C_DQS_DN<9>")
	)
	(segment
		(start 239.511586 -66.541142)
		(end 239.519968 -66.530728)
		(width 0.0889)
		(layer "In11.Cu")
		(net "M_C_DQS_DN<9>")
	)
	(segment
		(start 228.322632 -64.86652)
		(end 228.436932 -64.75222)
		(width 0.14224)
		(layer "In11.Cu")
		(net "M_C_DQS_DN<9>")
	)
	(segment
		(start 202.863196 -41.002204)
		(end 203.96835 -41.002204)
		(width 0.14224)
		(layer "In11.Cu")
		(net "M_C_DQS_DN<9>")
	)
	(segment
		(start 225.079814 -63.76797)
		(end 225.241612 -63.76797)
		(width 0.14224)
		(layer "In11.Cu")
		(net "M_C_DQS_DN<9>")
	)
	(segment
		(start 226.713288 -64.86652)
		(end 226.827588 -64.75222)
		(width 0.14224)
		(layer "In11.Cu")
		(net "M_C_DQS_DN<9>")
	)
	(segment
		(start 225.998786 -64.686942)
		(end 226.178364 -64.86652)
		(width 0.14224)
		(layer "In11.Cu")
		(net "M_C_DQS_DN<9>")
	)
	(segment
		(start 199.82942 -28.102306)
		(end 199.82942 -28.356306)
		(width 0.14224)
		(layer "In11.Cu")
		(net "M_C_DQS_DN<9>")
	)
	(arc
		(start 235.265468 -64.705738)
		(mid 235.407151 -64.849542)
		(end 235.601002 -64.90589)
		(width 0.0889)
		(layer "In11.Cu")
		(net "M_C_DQS_DN<9>")
	)
	(arc
		(start 233.03738 -64.41059)
		(mid 233.332518 -64.489601)
		(end 233.548428 -64.705738)
		(width 0.0889)
		(layer "In11.Cu")
		(net "M_C_DQS_DN<9>")
	)
	(arc
		(start 237.841028 -66.191638)
		(mid 237.980021 -66.333718)
		(end 238.170212 -66.391536)
		(width 0.0889)
		(layer "In11.Cu")
		(net "M_C_DQS_DN<9>")
	)
	(arc
		(start 238.699548 -66.686938)
		(mid 238.84593 -66.833502)
		(end 239.046004 -66.88709)
		(width 0.0889)
		(layer "In11.Cu")
		(net "M_C_DQS_DN<9>")
	)
	(arc
		(start 239.392714 -66.686938)
		(mid 239.434257 -66.624365)
		(end 239.483392 -66.567558)
		(width 0.0889)
		(layer "In11.Cu")
		(net "M_C_DQS_DN<9>")
	)
	(arc
		(start 233.548428 -64.705738)
		(mid 233.6946 -64.852073)
		(end 233.894376 -64.905636)
		(width 0.0889)
		(layer "In11.Cu")
		(net "M_C_DQS_DN<9>")
	)
	(arc
		(start 236.123988 -65.201038)
		(mid 236.262981 -65.343118)
		(end 236.453172 -65.400936)
		(width 0.0889)
		(layer "In11.Cu")
		(net "M_C_DQS_DN<9>")
	)
	(arc
		(start 236.982508 -65.696338)
		(mid 237.122776 -65.839294)
		(end 237.31474 -65.89649)
		(width 0.0889)
		(layer "In11.Cu")
		(net "M_C_DQS_DN<9>")
	)
	(arc
		(start 233.8959 -64.905636)
		(mid 234.095673 -64.852067)
		(end 234.241848 -64.705738)
		(width 0.0889)
		(layer "In11.Cu")
		(net "M_C_DQS_DN<9>")
	)
	(arc
		(start 237.347506 -65.89649)
		(mid 237.632553 -65.980018)
		(end 237.841028 -66.191638)
		(width 0.0889)
		(layer "In11.Cu")
		(net "M_C_DQS_DN<9>")
	)
	(arc
		(start 236.484414 -65.400936)
		(mid 236.772101 -65.483457)
		(end 236.982508 -65.696338)
		(width 0.0889)
		(layer "In11.Cu")
		(net "M_C_DQS_DN<9>")
	)
	(arc
		(start 232.189274 -64.90589)
		(mid 232.383124 -64.84954)
		(end 232.524808 -64.705738)
		(width 0.0889)
		(layer "In11.Cu")
		(net "M_C_DQS_DN<9>")
	)
	(arc
		(start 235.630466 -64.90589)
		(mid 235.915513 -64.989418)
		(end 236.123988 -65.201038)
		(width 0.0889)
		(layer "In11.Cu")
		(net "M_C_DQS_DN<9>")
	)
	(arc
		(start 239.046512 -66.88709)
		(mid 239.246498 -66.833476)
		(end 239.392714 -66.686938)
		(width 0.0889)
		(layer "In11.Cu")
		(net "M_C_DQS_DN<9>")
	)
	(arc
		(start 232.524808 -64.705738)
		(mid 232.740881 -64.48963)
		(end 233.03611 -64.41059)
		(width 0.0889)
		(layer "In11.Cu")
		(net "M_C_DQS_DN<9>")
	)
	(arc
		(start 239.483392 -66.567558)
		(mid 239.497275 -66.554122)
		(end 239.511586 -66.541142)
		(width 0.0889)
		(layer "In11.Cu")
		(net "M_C_DQS_DN<9>")
	)
	(arc
		(start 238.201454 -66.391536)
		(mid 238.489141 -66.474057)
		(end 238.699548 -66.686938)
		(width 0.0889)
		(layer "In11.Cu")
		(net "M_C_DQS_DN<9>")
	)
	(arc
		(start 234.241848 -64.705738)
		(mid 234.457921 -64.48963)
		(end 234.75315 -64.41059)
		(width 0.0889)
		(layer "In11.Cu")
		(net "M_C_DQS_DN<9>")
	)
	(arc
		(start 234.75442 -64.41059)
		(mid 235.049558 -64.489601)
		(end 235.265468 -64.705738)
		(width 0.0889)
		(layer "In11.Cu")
		(net "M_C_DQS_DN<9>")
	)
	(segment
		(start 237.784132 0.457454)
		(end 237.784132 1.190244)
		(width 0.1651)
		(layer "F.Cu")
		(net "M_C_DQS_DN<8>")
	)
	(segment
		(start 238.049816 -0.821182)
		(end 238.049816 0.19177)
		(width 0.1651)
		(layer "F.Cu")
		(net "M_C_DQS_DN<8>")
	)
	(segment
		(start 238.050324 -0.821182)
		(end 238.049816 -0.821182)
		(width 0.1651)
		(layer "F.Cu")
		(net "M_C_DQS_DN<8>")
	)
	(segment
		(start 237.784132 1.190244)
		(end 238.437928 1.84404)
		(width 0.1651)
		(layer "F.Cu")
		(net "M_C_DQS_DN<8>")
	)
	(segment
		(start 238.049816 0.19177)
		(end 237.784132 0.457454)
		(width 0.1651)
		(layer "F.Cu")
		(net "M_C_DQS_DN<8>")
	)
	(segment
		(start 245.627144 -69.953886)
		(end 245.055644 -69.953886)
		(width 0.0889)
		(layer "F.Cu")
		(net "M_C_DQS_DN<8>")
	)
	(via
		(at 238.437928 -3.686556)
		(size 0.508)
		(drill 0.254)
		(layers "F.Cu" "B.Cu")
		(net "M_C_DQS_DN<8>")
	)
	(via
		(at 238.437928 1.84404)
		(size 0.508)
		(drill 0.254)
		(layers "F.Cu" "B.Cu")
		(net "M_C_DQS_DN<8>")
	)
	(via
		(at 245.055644 -69.953886)
		(size 0.508)
		(drill 0.254)
		(layers "F.Cu" "B.Cu")
		(net "M_C_DQS_DN<8>")
	)
	(segment
		(start 238.050324 -1.021842)
		(end 238.049816 -1.021842)
		(width 0.1651)
		(layer "B.Cu")
		(net "M_C_DQS_DN<8>")
	)
	(segment
		(start 238.049816 -1.021842)
		(end 238.049816 -1.91897)
		(width 0.1651)
		(layer "B.Cu")
		(net "M_C_DQS_DN<8>")
	)
	(segment
		(start 237.796832 -2.171954)
		(end 237.796832 -3.04546)
		(width 0.1651)
		(layer "B.Cu")
		(net "M_C_DQS_DN<8>")
	)
	(segment
		(start 238.049816 -1.91897)
		(end 237.796832 -2.171954)
		(width 0.1651)
		(layer "B.Cu")
		(net "M_C_DQS_DN<8>")
	)
	(segment
		(start 237.796832 -3.04546)
		(end 238.437928 -3.686556)
		(width 0.1651)
		(layer "B.Cu")
		(net "M_C_DQS_DN<8>")
	)
	(segment
		(start 239.220248 -6.111748)
		(end 239.038384 -5.929884)
		(width 0.14224)
		(layer "In4.Cu")
		(net "M_C_DQS_DN<8>")
	)
	(segment
		(start 239.038384 -5.929884)
		(end 239.038384 -5.70738)
		(width 0.14224)
		(layer "In4.Cu")
		(net "M_C_DQS_DN<8>")
	)
	(segment
		(start 245.573804 -56.791606)
		(end 245.567454 -56.780938)
		(width 0.0889)
		(layer "In4.Cu")
		(net "M_C_DQS_DN<8>")
	)
	(segment
		(start 245.567454 -67.677538)
		(end 245.562628 -67.668902)
		(width 0.0889)
		(layer "In4.Cu")
		(net "M_C_DQS_DN<8>")
	)
	(segment
		(start 246.392446 -49.9618)
		(end 246.392446 -49.939702)
		(width 0.0889)
		(layer "In4.Cu")
		(net "M_C_DQS_DN<8>")
	)
	(segment
		(start 246.353076 -50.452274)
		(end 246.353076 -50.00117)
		(width 0.0889)
		(layer "In4.Cu")
		(net "M_C_DQS_DN<8>")
	)
	(segment
		(start 246.0498 -46.7487)
		(end 245.363492 -46.7487)
		(width 0.14224)
		(layer "In4.Cu")
		(net "M_C_DQS_DN<8>")
	)
	(segment
		(start 246.353076 -50.00117)
		(end 246.392446 -49.9618)
		(width 0.0889)
		(layer "In4.Cu")
		(net "M_C_DQS_DN<8>")
	)
	(segment
		(start 238.858552 -5.527548)
		(end 238.636048 -5.527548)
		(width 0.14224)
		(layer "In4.Cu")
		(net "M_C_DQS_DN<8>")
	)
	(segment
		(start 245.573804 -68.678806)
		(end 245.567454 -68.668138)
		(width 0.0889)
		(layer "In4.Cu")
		(net "M_C_DQS_DN<8>")
	)
	(segment
		(start 245.677944 -55.199026)
		(end 245.677944 -52.820316)
		(width 0.0889)
		(layer "In4.Cu")
		(net "M_C_DQS_DN<8>")
	)
	(segment
		(start 238.388652 -5.05968)
		(end 238.901732 -4.5466)
		(width 0.14224)
		(layer "In4.Cu")
		(net "M_C_DQS_DN<8>")
	)
	(segment
		(start 245.573804 -63.725806)
		(end 245.567454 -63.715138)
		(width 0.0889)
		(layer "In4.Cu")
		(net "M_C_DQS_DN<8>")
	)
	(segment
		(start 238.901732 -4.15036)
		(end 238.437928 -3.686556)
		(width 0.14224)
		(layer "In4.Cu")
		(net "M_C_DQS_DN<8>")
	)
	(segment
		(start 245.573804 -55.801006)
		(end 245.567454 -55.790338)
		(width 0.0889)
		(layer "In4.Cu")
		(net "M_C_DQS_DN<8>")
	)
	(segment
		(start 245.567454 -60.743338)
		(end 245.562628 -60.734702)
		(width 0.0889)
		(layer "In4.Cu")
		(net "M_C_DQS_DN<8>")
	)
	(segment
		(start 245.573804 -62.735206)
		(end 245.567454 -62.724538)
		(width 0.0889)
		(layer "In4.Cu")
		(net "M_C_DQS_DN<8>")
	)
	(segment
		(start 245.573804 -65.707006)
		(end 245.567454 -65.696338)
		(width 0.0889)
		(layer "In4.Cu")
		(net "M_C_DQS_DN<8>")
	)
	(segment
		(start 245.567454 -68.668138)
		(end 245.562628 -68.659502)
		(width 0.0889)
		(layer "In4.Cu")
		(net "M_C_DQS_DN<8>")
	)
	(segment
		(start 239.038384 -5.70738)
		(end 238.858552 -5.527548)
		(width 0.14224)
		(layer "In4.Cu")
		(net "M_C_DQS_DN<8>")
	)
	(segment
		(start 238.636048 -5.527548)
		(end 238.388652 -5.280152)
		(width 0.14224)
		(layer "In4.Cu")
		(net "M_C_DQS_DN<8>")
	)
	(segment
		(start 238.901732 -4.5466)
		(end 238.901732 -4.15036)
		(width 0.14224)
		(layer "In4.Cu")
		(net "M_C_DQS_DN<8>")
	)
	(segment
		(start 239.220248 -29.566108)
		(end 239.220248 -6.111748)
		(width 0.14224)
		(layer "In4.Cu")
		(net "M_C_DQS_DN<8>")
	)
	(segment
		(start 241.808 -32.15386)
		(end 239.220248 -29.566108)
		(width 0.14224)
		(layer "In4.Cu")
		(net "M_C_DQS_DN<8>")
	)
	(segment
		(start 245.567454 -59.752738)
		(end 245.562628 -59.744102)
		(width 0.0889)
		(layer "In4.Cu")
		(net "M_C_DQS_DN<8>")
	)
	(segment
		(start 245.055644 -69.953886)
		(end 245.055644 -69.615812)
		(width 0.0889)
		(layer "In4.Cu")
		(net "M_C_DQS_DN<8>")
	)
	(segment
		(start 245.677944 -52.820316)
		(end 246.079264 -52.418996)
		(width 0.0889)
		(layer "In4.Cu")
		(net "M_C_DQS_DN<8>")
	)
	(segment
		(start 245.567454 -56.780938)
		(end 245.562628 -56.772302)
		(width 0.0889)
		(layer "In4.Cu")
		(net "M_C_DQS_DN<8>")
	)
	(segment
		(start 246.079264 -52.418996)
		(end 246.079264 -50.726086)
		(width 0.0889)
		(layer "In4.Cu")
		(net "M_C_DQS_DN<8>")
	)
	(segment
		(start 245.573804 -61.744606)
		(end 245.567454 -61.733938)
		(width 0.0889)
		(layer "In4.Cu")
		(net "M_C_DQS_DN<8>")
	)
	(segment
		(start 241.808 -43.193208)
		(end 241.808 -32.15386)
		(width 0.14224)
		(layer "In4.Cu")
		(net "M_C_DQS_DN<8>")
	)
	(segment
		(start 246.079264 -50.726086)
		(end 246.353076 -50.452274)
		(width 0.0889)
		(layer "In4.Cu")
		(net "M_C_DQS_DN<8>")
	)
	(segment
		(start 245.567454 -57.771538)
		(end 245.562628 -57.762902)
		(width 0.0889)
		(layer "In4.Cu")
		(net "M_C_DQS_DN<8>")
	)
	(segment
		(start 245.573804 -64.716406)
		(end 245.567454 -64.705738)
		(width 0.0889)
		(layer "In4.Cu")
		(net "M_C_DQS_DN<8>")
	)
	(segment
		(start 245.573804 -59.763406)
		(end 245.567454 -59.752738)
		(width 0.0889)
		(layer "In4.Cu")
		(net "M_C_DQS_DN<8>")
	)
	(segment
		(start 245.573804 -67.688206)
		(end 245.567454 -67.677538)
		(width 0.0889)
		(layer "In4.Cu")
		(net "M_C_DQS_DN<8>")
	)
	(segment
		(start 245.055644 -69.615812)
		(end 245.120668 -69.550788)
		(width 0.0889)
		(layer "In4.Cu")
		(net "M_C_DQS_DN<8>")
	)
	(segment
		(start 245.567454 -63.715138)
		(end 245.562628 -63.706502)
		(width 0.0889)
		(layer "In4.Cu")
		(net "M_C_DQS_DN<8>")
	)
	(segment
		(start 245.567454 -55.390542)
		(end 245.677944 -55.199026)
		(width 0.0889)
		(layer "In4.Cu")
		(net "M_C_DQS_DN<8>")
	)
	(segment
		(start 245.567454 -65.696338)
		(end 245.562628 -65.687702)
		(width 0.0889)
		(layer "In4.Cu")
		(net "M_C_DQS_DN<8>")
	)
	(segment
		(start 245.567454 -64.705738)
		(end 245.562628 -64.697102)
		(width 0.0889)
		(layer "In4.Cu")
		(net "M_C_DQS_DN<8>")
	)
	(segment
		(start 245.573804 -60.754006)
		(end 245.567454 -60.743338)
		(width 0.0889)
		(layer "In4.Cu")
		(net "M_C_DQS_DN<8>")
	)
	(segment
		(start 246.392446 -47.091346)
		(end 246.0498 -46.7487)
		(width 0.14224)
		(layer "In4.Cu")
		(net "M_C_DQS_DN<8>")
	)
	(segment
		(start 238.388652 -5.280152)
		(end 238.388652 -5.05968)
		(width 0.14224)
		(layer "In4.Cu")
		(net "M_C_DQS_DN<8>")
	)
	(segment
		(start 245.567454 -58.362088)
		(end 245.573804 -58.35142)
		(width 0.0889)
		(layer "In4.Cu")
		(net "M_C_DQS_DN<8>")
	)
	(segment
		(start 245.567454 -61.733938)
		(end 245.562628 -61.725302)
		(width 0.0889)
		(layer "In4.Cu")
		(net "M_C_DQS_DN<8>")
	)
	(segment
		(start 246.392446 -49.939702)
		(end 246.392446 -47.091346)
		(width 0.14224)
		(layer "In4.Cu")
		(net "M_C_DQS_DN<8>")
	)
	(segment
		(start 245.567454 -62.724538)
		(end 245.562628 -62.715902)
		(width 0.0889)
		(layer "In4.Cu")
		(net "M_C_DQS_DN<8>")
	)
	(segment
		(start 245.363492 -46.7487)
		(end 241.808 -43.193208)
		(width 0.14224)
		(layer "In4.Cu")
		(net "M_C_DQS_DN<8>")
	)
	(arc
		(start 245.562628 -56.772302)
		(mid 245.513873 -56.57595)
		(end 245.567454 -56.380888)
		(width 0.0889)
		(layer "In4.Cu")
		(net "M_C_DQS_DN<8>")
	)
	(arc
		(start 245.562628 -67.668902)
		(mid 245.513873 -67.47255)
		(end 245.567454 -67.277488)
		(width 0.0889)
		(layer "In4.Cu")
		(net "M_C_DQS_DN<8>")
	)
	(arc
		(start 245.562628 -64.697102)
		(mid 245.513873 -64.50075)
		(end 245.567454 -64.305688)
		(width 0.0889)
		(layer "In4.Cu")
		(net "M_C_DQS_DN<8>")
	)
	(arc
		(start 245.567454 -59.352688)
		(mid 245.646585 -59.057286)
		(end 245.567454 -58.761884)
		(width 0.0889)
		(layer "In4.Cu")
		(net "M_C_DQS_DN<8>")
	)
	(arc
		(start 245.567454 -66.286888)
		(mid 245.646574 -65.99777)
		(end 245.573804 -65.707006)
		(width 0.0889)
		(layer "In4.Cu")
		(net "M_C_DQS_DN<8>")
	)
	(arc
		(start 245.567454 -65.296288)
		(mid 245.646676 -65.00717)
		(end 245.573804 -64.716406)
		(width 0.0889)
		(layer "In4.Cu")
		(net "M_C_DQS_DN<8>")
	)
	(arc
		(start 245.567454 -63.315088)
		(mid 245.646676 -63.02597)
		(end 245.573804 -62.735206)
		(width 0.0889)
		(layer "In4.Cu")
		(net "M_C_DQS_DN<8>")
	)
	(arc
		(start 245.567454 -56.380888)
		(mid 245.646676 -56.09177)
		(end 245.573804 -55.801006)
		(width 0.0889)
		(layer "In4.Cu")
		(net "M_C_DQS_DN<8>")
	)
	(arc
		(start 245.562628 -63.706502)
		(mid 245.513873 -63.51015)
		(end 245.567454 -63.315088)
		(width 0.0889)
		(layer "In4.Cu")
		(net "M_C_DQS_DN<8>")
	)
	(arc
		(start 245.562628 -65.687702)
		(mid 245.513873 -65.49135)
		(end 245.567454 -65.296288)
		(width 0.0889)
		(layer "In4.Cu")
		(net "M_C_DQS_DN<8>")
	)
	(arc
		(start 245.567454 -55.790338)
		(mid 245.513955 -55.59044)
		(end 245.567454 -55.390542)
		(width 0.0889)
		(layer "In4.Cu")
		(net "M_C_DQS_DN<8>")
	)
	(arc
		(start 245.567454 -61.333888)
		(mid 245.646676 -61.04477)
		(end 245.573804 -60.754006)
		(width 0.0889)
		(layer "In4.Cu")
		(net "M_C_DQS_DN<8>")
	)
	(arc
		(start 245.562628 -57.762902)
		(mid 245.513873 -57.56655)
		(end 245.567454 -57.371488)
		(width 0.0889)
		(layer "In4.Cu")
		(net "M_C_DQS_DN<8>")
	)
	(arc
		(start 245.567454 -57.371488)
		(mid 245.646676 -57.08237)
		(end 245.573804 -56.791606)
		(width 0.0889)
		(layer "In4.Cu")
		(net "M_C_DQS_DN<8>")
	)
	(arc
		(start 245.562628 -60.734702)
		(mid 245.513873 -60.53835)
		(end 245.567454 -60.343288)
		(width 0.0889)
		(layer "In4.Cu")
		(net "M_C_DQS_DN<8>")
	)
	(arc
		(start 245.573804 -58.35142)
		(mid 245.646602 -58.060657)
		(end 245.567454 -57.771538)
		(width 0.0889)
		(layer "In4.Cu")
		(net "M_C_DQS_DN<8>")
	)
	(arc
		(start 245.567454 -60.343288)
		(mid 245.646676 -60.05417)
		(end 245.573804 -59.763406)
		(width 0.0889)
		(layer "In4.Cu")
		(net "M_C_DQS_DN<8>")
	)
	(arc
		(start 245.562628 -68.659502)
		(mid 245.513873 -68.46315)
		(end 245.567454 -68.268088)
		(width 0.0889)
		(layer "In4.Cu")
		(net "M_C_DQS_DN<8>")
	)
	(arc
		(start 245.562628 -62.715902)
		(mid 245.513873 -62.51955)
		(end 245.567454 -62.324488)
		(width 0.0889)
		(layer "In4.Cu")
		(net "M_C_DQS_DN<8>")
	)
	(arc
		(start 245.567454 -62.324488)
		(mid 245.646676 -62.03537)
		(end 245.573804 -61.744606)
		(width 0.0889)
		(layer "In4.Cu")
		(net "M_C_DQS_DN<8>")
	)
	(arc
		(start 245.567454 -67.277488)
		(mid 245.646585 -66.982086)
		(end 245.567454 -66.686684)
		(width 0.0889)
		(layer "In4.Cu")
		(net "M_C_DQS_DN<8>")
	)
	(arc
		(start 245.120668 -69.550788)
		(mid 245.580145 -69.235839)
		(end 245.573804 -68.678806)
		(width 0.0889)
		(layer "In4.Cu")
		(net "M_C_DQS_DN<8>")
	)
	(arc
		(start 245.567454 -66.686684)
		(mid 245.513955 -66.486786)
		(end 245.567454 -66.286888)
		(width 0.0889)
		(layer "In4.Cu")
		(net "M_C_DQS_DN<8>")
	)
	(arc
		(start 245.567454 -68.268088)
		(mid 245.646676 -67.97897)
		(end 245.573804 -67.688206)
		(width 0.0889)
		(layer "In4.Cu")
		(net "M_C_DQS_DN<8>")
	)
	(arc
		(start 245.562628 -61.725302)
		(mid 245.513873 -61.52895)
		(end 245.567454 -61.333888)
		(width 0.0889)
		(layer "In4.Cu")
		(net "M_C_DQS_DN<8>")
	)
	(arc
		(start 245.567454 -58.761884)
		(mid 245.513955 -58.561986)
		(end 245.567454 -58.362088)
		(width 0.0889)
		(layer "In4.Cu")
		(net "M_C_DQS_DN<8>")
	)
	(arc
		(start 245.562628 -59.744102)
		(mid 245.513873 -59.54775)
		(end 245.567454 -59.352688)
		(width 0.0889)
		(layer "In4.Cu")
		(net "M_C_DQS_DN<8>")
	)
	(arc
		(start 245.567454 -64.305688)
		(mid 245.646676 -64.01657)
		(end 245.573804 -63.725806)
		(width 0.0889)
		(layer "In4.Cu")
		(net "M_C_DQS_DN<8>")
	)
	(segment
		(start 239.248696 1.033272)
		(end 239.248696 -2.875788)
		(width 0.14224)
		(layer "In11.Cu")
		(net "M_C_DQS_DN<8>")
	)
	(segment
		(start 238.437928 1.84404)
		(end 239.248696 1.033272)
		(width 0.14224)
		(layer "In11.Cu")
		(net "M_C_DQS_DN<8>")
	)
	(segment
		(start 239.248696 -2.875788)
		(end 238.437928 -3.686556)
		(width 0.14224)
		(layer "In11.Cu")
		(net "M_C_DQS_DN<8>")
	)
	(segment
		(start 312.387996 1.84404)
		(end 311.7342 1.190244)
		(width 0.1651)
		(layer "F.Cu")
		(net "M_C_DQS_DN<7>")
	)
	(segment
		(start 311.999884 0.19177)
		(end 311.999884 -0.821182)
		(width 0.1651)
		(layer "F.Cu")
		(net "M_C_DQS_DN<7>")
	)
	(segment
		(start 311.999884 -0.821182)
		(end 312.000392 -0.821182)
		(width 0.1651)
		(layer "F.Cu")
		(net "M_C_DQS_DN<7>")
	)
	(segment
		(start 287.50514 -65.315338)
		(end 286.93364 -65.315338)
		(width 0.0889)
		(layer "F.Cu")
		(net "M_C_DQS_DN<7>")
	)
	(segment
		(start 311.7342 0.457454)
		(end 311.999884 0.19177)
		(width 0.1651)
		(layer "F.Cu")
		(net "M_C_DQS_DN<7>")
	)
	(segment
		(start 311.7342 1.190244)
		(end 311.7342 0.457454)
		(width 0.1651)
		(layer "F.Cu")
		(net "M_C_DQS_DN<7>")
	)
	(via
		(at 312.387996 -3.686556)
		(size 0.508)
		(drill 0.254)
		(layers "F.Cu" "B.Cu")
		(net "M_C_DQS_DN<7>")
	)
	(via
		(at 286.93364 -65.315338)
		(size 0.508)
		(drill 0.254)
		(layers "F.Cu" "B.Cu")
		(net "M_C_DQS_DN<7>")
	)
	(via
		(at 312.387996 1.84404)
		(size 0.508)
		(drill 0.254)
		(layers "F.Cu" "B.Cu")
		(net "M_C_DQS_DN<7>")
	)
	(segment
		(start 311.999884 -1.91897)
		(end 311.7469 -2.171954)
		(width 0.1651)
		(layer "B.Cu")
		(net "M_C_DQS_DN<7>")
	)
	(segment
		(start 311.7469 -2.171954)
		(end 311.7469 -3.04546)
		(width 0.1651)
		(layer "B.Cu")
		(net "M_C_DQS_DN<7>")
	)
	(segment
		(start 311.999884 -1.021842)
		(end 311.999884 -1.91897)
		(width 0.1651)
		(layer "B.Cu")
		(net "M_C_DQS_DN<7>")
	)
	(segment
		(start 311.7469 -3.04546)
		(end 312.387996 -3.686556)
		(width 0.1651)
		(layer "B.Cu")
		(net "M_C_DQS_DN<7>")
	)
	(segment
		(start 312.000392 -1.021842)
		(end 311.999884 -1.021842)
		(width 0.1651)
		(layer "B.Cu")
		(net "M_C_DQS_DN<7>")
	)
	(segment
		(start 287.440624 -61.656722)
		(end 287.44545 -61.648086)
		(width 0.0889)
		(layer "In11.Cu")
		(net "M_C_DQS_DN<7>")
	)
	(segment
		(start 287.440624 -54.722522)
		(end 287.44545 -54.713886)
		(width 0.0889)
		(layer "In11.Cu")
		(net "M_C_DQS_DN<7>")
	)
	(segment
		(start 286.93364 -65.315338)
		(end 286.93364 -64.977264)
		(width 0.0889)
		(layer "In11.Cu")
		(net "M_C_DQS_DN<7>")
	)
	(segment
		(start 287.440624 -56.703722)
		(end 287.44545 -56.695086)
		(width 0.0889)
		(layer "In11.Cu")
		(net "M_C_DQS_DN<7>")
	)
	(segment
		(start 312.33872 -5.280152)
		(end 312.33872 -5.05968)
		(width 0.14224)
		(layer "In11.Cu")
		(net "M_C_DQS_DN<7>")
	)
	(segment
		(start 287.59277 -53.46827)
		(end 287.59277 -51.487324)
		(width 0.0889)
		(layer "In11.Cu")
		(net "M_C_DQS_DN<7>")
	)
	(segment
		(start 287.44545 -62.638686)
		(end 287.4518 -62.628018)
		(width 0.0889)
		(layer "In11.Cu")
		(net "M_C_DQS_DN<7>")
	)
	(segment
		(start 312.988452 -5.70738)
		(end 312.80862 -5.527548)
		(width 0.14224)
		(layer "In11.Cu")
		(net "M_C_DQS_DN<7>")
	)
	(segment
		(start 288.641028 -51.1048)
		(end 288.82848 -50.917348)
		(width 0.0889)
		(layer "In11.Cu")
		(net "M_C_DQS_DN<7>")
	)
	(segment
		(start 287.4518 -59.087004)
		(end 287.44545 -59.076336)
		(width 0.0889)
		(layer "In11.Cu")
		(net "M_C_DQS_DN<7>")
	)
	(segment
		(start 313.327796 -6.480556)
		(end 313.327796 -6.269228)
		(width 0.14224)
		(layer "In11.Cu")
		(net "M_C_DQS_DN<7>")
	)
	(segment
		(start 313.170316 -30.618684)
		(end 313.170316 -6.638036)
		(width 0.14224)
		(layer "In11.Cu")
		(net "M_C_DQS_DN<7>")
	)
	(segment
		(start 312.988452 -5.929884)
		(end 312.988452 -5.70738)
		(width 0.14224)
		(layer "In11.Cu")
		(net "M_C_DQS_DN<7>")
	)
	(segment
		(start 313.198764 1.033272)
		(end 312.387996 1.84404)
		(width 0.14224)
		(layer "In11.Cu")
		(net "M_C_DQS_DN<7>")
	)
	(segment
		(start 287.440624 -57.694322)
		(end 287.44545 -57.685686)
		(width 0.0889)
		(layer "In11.Cu")
		(net "M_C_DQS_DN<7>")
	)
	(segment
		(start 313.327796 -6.269228)
		(end 312.988452 -5.929884)
		(width 0.14224)
		(layer "In11.Cu")
		(net "M_C_DQS_DN<7>")
	)
	(segment
		(start 287.44545 -56.695086)
		(end 287.4518 -56.684418)
		(width 0.0889)
		(layer "In11.Cu")
		(net "M_C_DQS_DN<7>")
	)
	(segment
		(start 287.440624 -63.637922)
		(end 287.44545 -63.629286)
		(width 0.0889)
		(layer "In11.Cu")
		(net "M_C_DQS_DN<7>")
	)
	(segment
		(start 287.440624 -60.666122)
		(end 287.44545 -60.657486)
		(width 0.0889)
		(layer "In11.Cu")
		(net "M_C_DQS_DN<7>")
	)
	(segment
		(start 287.440624 -59.675522)
		(end 287.44545 -59.666886)
		(width 0.0889)
		(layer "In11.Cu")
		(net "M_C_DQS_DN<7>")
	)
	(segment
		(start 287.440624 -55.713122)
		(end 287.44545 -55.704486)
		(width 0.0889)
		(layer "In11.Cu")
		(net "M_C_DQS_DN<7>")
	)
	(segment
		(start 312.8518 -4.15036)
		(end 312.387996 -3.686556)
		(width 0.14224)
		(layer "In11.Cu")
		(net "M_C_DQS_DN<7>")
	)
	(segment
		(start 287.44545 -61.648086)
		(end 287.4518 -61.637418)
		(width 0.0889)
		(layer "In11.Cu")
		(net "M_C_DQS_DN<7>")
	)
	(segment
		(start 312.586116 -5.527548)
		(end 312.33872 -5.280152)
		(width 0.14224)
		(layer "In11.Cu")
		(net "M_C_DQS_DN<7>")
	)
	(segment
		(start 286.93364 -64.977264)
		(end 286.998918 -64.911986)
		(width 0.0889)
		(layer "In11.Cu")
		(net "M_C_DQS_DN<7>")
	)
	(segment
		(start 287.44545 -55.704486)
		(end 287.4518 -55.693818)
		(width 0.0889)
		(layer "In11.Cu")
		(net "M_C_DQS_DN<7>")
	)
	(segment
		(start 287.59277 -51.487324)
		(end 287.975294 -51.1048)
		(width 0.0889)
		(layer "In11.Cu")
		(net "M_C_DQS_DN<7>")
	)
	(segment
		(start 313.170316 -6.638036)
		(end 313.327796 -6.480556)
		(width 0.14224)
		(layer "In11.Cu")
		(net "M_C_DQS_DN<7>")
	)
	(segment
		(start 287.44545 -54.713886)
		(end 287.4518 -54.703218)
		(width 0.0889)
		(layer "In11.Cu")
		(net "M_C_DQS_DN<7>")
	)
	(segment
		(start 291.23513 -48.56607)
		(end 294.30853 -48.56607)
		(width 0.14224)
		(layer "In11.Cu")
		(net "M_C_DQS_DN<7>")
	)
	(segment
		(start 287.44545 -57.685686)
		(end 287.4518 -57.675018)
		(width 0.0889)
		(layer "In11.Cu")
		(net "M_C_DQS_DN<7>")
	)
	(segment
		(start 312.80862 -5.527548)
		(end 312.586116 -5.527548)
		(width 0.14224)
		(layer "In11.Cu")
		(net "M_C_DQS_DN<7>")
	)
	(segment
		(start 312.387996 -3.686556)
		(end 313.198764 -2.875788)
		(width 0.14224)
		(layer "In11.Cu")
		(net "M_C_DQS_DN<7>")
	)
	(segment
		(start 301.73676 -42.05224)
		(end 313.170316 -30.618684)
		(width 0.14224)
		(layer "In11.Cu")
		(net "M_C_DQS_DN<7>")
	)
	(segment
		(start 294.30853 -48.56607)
		(end 300.82236 -42.05224)
		(width 0.14224)
		(layer "In11.Cu")
		(net "M_C_DQS_DN<7>")
	)
	(segment
		(start 288.883852 -50.917348)
		(end 288.8996 -50.9016)
		(width 0.0889)
		(layer "In11.Cu")
		(net "M_C_DQS_DN<7>")
	)
	(segment
		(start 287.440624 -53.731922)
		(end 287.59277 -53.46827)
		(width 0.0889)
		(layer "In11.Cu")
		(net "M_C_DQS_DN<7>")
	)
	(segment
		(start 313.198764 -2.875788)
		(end 313.198764 1.033272)
		(width 0.14224)
		(layer "In11.Cu")
		(net "M_C_DQS_DN<7>")
	)
	(segment
		(start 287.975294 -51.1048)
		(end 288.641028 -51.1048)
		(width 0.0889)
		(layer "In11.Cu")
		(net "M_C_DQS_DN<7>")
	)
	(segment
		(start 288.8996 -50.9016)
		(end 291.23513 -48.56607)
		(width 0.14224)
		(layer "In11.Cu")
		(net "M_C_DQS_DN<7>")
	)
	(segment
		(start 288.82848 -50.917348)
		(end 288.883852 -50.917348)
		(width 0.0889)
		(layer "In11.Cu")
		(net "M_C_DQS_DN<7>")
	)
	(segment
		(start 287.44545 -60.657486)
		(end 287.4518 -60.646818)
		(width 0.0889)
		(layer "In11.Cu")
		(net "M_C_DQS_DN<7>")
	)
	(segment
		(start 312.8518 -4.5466)
		(end 312.8518 -4.15036)
		(width 0.14224)
		(layer "In11.Cu")
		(net "M_C_DQS_DN<7>")
	)
	(segment
		(start 312.33872 -5.05968)
		(end 312.8518 -4.5466)
		(width 0.14224)
		(layer "In11.Cu")
		(net "M_C_DQS_DN<7>")
	)
	(segment
		(start 287.440624 -62.647322)
		(end 287.44545 -62.638686)
		(width 0.0889)
		(layer "In11.Cu")
		(net "M_C_DQS_DN<7>")
	)
	(segment
		(start 300.82236 -42.05224)
		(end 301.73676 -42.05224)
		(width 0.14224)
		(layer "In11.Cu")
		(net "M_C_DQS_DN<7>")
	)
	(segment
		(start 287.44545 -63.629286)
		(end 287.4518 -63.618618)
		(width 0.0889)
		(layer "In11.Cu")
		(net "M_C_DQS_DN<7>")
	)
	(arc
		(start 287.44545 -59.076336)
		(mid 287.391951 -58.876438)
		(end 287.44545 -58.67654)
		(width 0.0889)
		(layer "In11.Cu")
		(net "M_C_DQS_DN<7>")
	)
	(arc
		(start 287.44545 -59.666886)
		(mid 287.524672 -59.377768)
		(end 287.4518 -59.087004)
		(width 0.0889)
		(layer "In11.Cu")
		(net "M_C_DQS_DN<7>")
	)
	(arc
		(start 287.4518 -56.684418)
		(mid 287.524598 -56.393655)
		(end 287.44545 -56.104536)
		(width 0.0889)
		(layer "In11.Cu")
		(net "M_C_DQS_DN<7>")
	)
	(arc
		(start 287.44545 -63.038736)
		(mid 287.39198 -62.843673)
		(end 287.440624 -62.647322)
		(width 0.0889)
		(layer "In11.Cu")
		(net "M_C_DQS_DN<7>")
	)
	(arc
		(start 287.4518 -62.628018)
		(mid 287.524598 -62.337255)
		(end 287.44545 -62.048136)
		(width 0.0889)
		(layer "In11.Cu")
		(net "M_C_DQS_DN<7>")
	)
	(arc
		(start 287.44545 -57.095136)
		(mid 287.39198 -56.900073)
		(end 287.440624 -56.703722)
		(width 0.0889)
		(layer "In11.Cu")
		(net "M_C_DQS_DN<7>")
	)
	(arc
		(start 287.44545 -62.048136)
		(mid 287.39198 -61.853073)
		(end 287.440624 -61.656722)
		(width 0.0889)
		(layer "In11.Cu")
		(net "M_C_DQS_DN<7>")
	)
	(arc
		(start 286.998918 -64.911986)
		(mid 287.460887 -64.591444)
		(end 287.44545 -64.029336)
		(width 0.0889)
		(layer "In11.Cu")
		(net "M_C_DQS_DN<7>")
	)
	(arc
		(start 287.4518 -57.675018)
		(mid 287.524598 -57.384255)
		(end 287.44545 -57.095136)
		(width 0.0889)
		(layer "In11.Cu")
		(net "M_C_DQS_DN<7>")
	)
	(arc
		(start 287.44545 -55.113936)
		(mid 287.39198 -54.918873)
		(end 287.440624 -54.722522)
		(width 0.0889)
		(layer "In11.Cu")
		(net "M_C_DQS_DN<7>")
	)
	(arc
		(start 287.44545 -54.123336)
		(mid 287.39198 -53.928273)
		(end 287.440624 -53.731922)
		(width 0.0889)
		(layer "In11.Cu")
		(net "M_C_DQS_DN<7>")
	)
	(arc
		(start 287.44545 -60.066936)
		(mid 287.39198 -59.871873)
		(end 287.440624 -59.675522)
		(width 0.0889)
		(layer "In11.Cu")
		(net "M_C_DQS_DN<7>")
	)
	(arc
		(start 287.4518 -55.693818)
		(mid 287.524598 -55.403055)
		(end 287.44545 -55.113936)
		(width 0.0889)
		(layer "In11.Cu")
		(net "M_C_DQS_DN<7>")
	)
	(arc
		(start 287.44545 -64.029336)
		(mid 287.39198 -63.834273)
		(end 287.440624 -63.637922)
		(width 0.0889)
		(layer "In11.Cu")
		(net "M_C_DQS_DN<7>")
	)
	(arc
		(start 287.4518 -63.618618)
		(mid 287.524598 -63.327855)
		(end 287.44545 -63.038736)
		(width 0.0889)
		(layer "In11.Cu")
		(net "M_C_DQS_DN<7>")
	)
	(arc
		(start 287.44545 -61.057536)
		(mid 287.39198 -60.862473)
		(end 287.440624 -60.666122)
		(width 0.0889)
		(layer "In11.Cu")
		(net "M_C_DQS_DN<7>")
	)
	(arc
		(start 287.4518 -61.637418)
		(mid 287.524598 -61.346655)
		(end 287.44545 -61.057536)
		(width 0.0889)
		(layer "In11.Cu")
		(net "M_C_DQS_DN<7>")
	)
	(arc
		(start 287.44545 -58.67654)
		(mid 287.524581 -58.381138)
		(end 287.44545 -58.085736)
		(width 0.0889)
		(layer "In11.Cu")
		(net "M_C_DQS_DN<7>")
	)
	(arc
		(start 287.4518 -60.646818)
		(mid 287.524598 -60.356055)
		(end 287.44545 -60.066936)
		(width 0.0889)
		(layer "In11.Cu")
		(net "M_C_DQS_DN<7>")
	)
	(arc
		(start 287.4518 -54.703218)
		(mid 287.524598 -54.412455)
		(end 287.44545 -54.123336)
		(width 0.0889)
		(layer "In11.Cu")
		(net "M_C_DQS_DN<7>")
	)
	(arc
		(start 287.44545 -58.085736)
		(mid 287.39198 -57.890673)
		(end 287.440624 -57.694322)
		(width 0.0889)
		(layer "In11.Cu")
		(net "M_C_DQS_DN<7>")
	)
	(arc
		(start 287.44545 -56.104536)
		(mid 287.39198 -55.909473)
		(end 287.440624 -55.713122)
		(width 0.0889)
		(layer "In11.Cu")
		(net "M_C_DQS_DN<7>")
	)
	(segment
		(start 302.384206 0.457454)
		(end 302.384206 1.190244)
		(width 0.1651)
		(layer "F.Cu")
		(net "M_C_DQS_DN<6>")
	)
	(segment
		(start 302.650398 -0.821182)
		(end 302.64989 -0.821182)
		(width 0.1651)
		(layer "F.Cu")
		(net "M_C_DQS_DN<6>")
	)
	(segment
		(start 302.64989 0.19177)
		(end 302.384206 0.457454)
		(width 0.1651)
		(layer "F.Cu")
		(net "M_C_DQS_DN<6>")
	)
	(segment
		(start 302.64989 -0.821182)
		(end 302.64989 0.19177)
		(width 0.1651)
		(layer "F.Cu")
		(net "M_C_DQS_DN<6>")
	)
	(segment
		(start 282.354274 -65.315338)
		(end 281.782774 -65.315338)
		(width 0.0889)
		(layer "F.Cu")
		(net "M_C_DQS_DN<6>")
	)
	(segment
		(start 302.384206 1.190244)
		(end 303.038002 1.84404)
		(width 0.1651)
		(layer "F.Cu")
		(net "M_C_DQS_DN<6>")
	)
	(via
		(at 303.038002 -3.686556)
		(size 0.508)
		(drill 0.254)
		(layers "F.Cu" "B.Cu")
		(net "M_C_DQS_DN<6>")
	)
	(via
		(at 281.782774 -65.315338)
		(size 0.508)
		(drill 0.254)
		(layers "F.Cu" "B.Cu")
		(net "M_C_DQS_DN<6>")
	)
	(via
		(at 303.038002 1.84404)
		(size 0.508)
		(drill 0.254)
		(layers "F.Cu" "B.Cu")
		(net "M_C_DQS_DN<6>")
	)
	(segment
		(start 302.396906 -2.171954)
		(end 302.396906 -3.04546)
		(width 0.1651)
		(layer "B.Cu")
		(net "M_C_DQS_DN<6>")
	)
	(segment
		(start 302.64989 -1.021842)
		(end 302.64989 -1.91897)
		(width 0.1651)
		(layer "B.Cu")
		(net "M_C_DQS_DN<6>")
	)
	(segment
		(start 302.64989 -1.91897)
		(end 302.396906 -2.171954)
		(width 0.1651)
		(layer "B.Cu")
		(net "M_C_DQS_DN<6>")
	)
	(segment
		(start 302.650398 -1.021842)
		(end 302.64989 -1.021842)
		(width 0.1651)
		(layer "B.Cu")
		(net "M_C_DQS_DN<6>")
	)
	(segment
		(start 302.396906 -3.04546)
		(end 303.038002 -3.686556)
		(width 0.1651)
		(layer "B.Cu")
		(net "M_C_DQS_DN<6>")
	)
	(segment
		(start 282.294584 -55.704486)
		(end 282.289758 -55.713122)
		(width 0.0889)
		(layer "In11.Cu")
		(net "M_C_DQS_DN<6>")
	)
	(segment
		(start 282.29433 -55.113682)
		(end 282.294584 -55.113936)
		(width 0.0889)
		(layer "In11.Cu")
		(net "M_C_DQS_DN<6>")
	)
	(segment
		(start 281.848052 -64.911986)
		(end 281.782774 -64.977264)
		(width 0.0889)
		(layer "In11.Cu")
		(net "M_C_DQS_DN<6>")
	)
	(segment
		(start 282.294584 -61.648086)
		(end 282.289758 -61.656722)
		(width 0.0889)
		(layer "In11.Cu")
		(net "M_C_DQS_DN<6>")
	)
	(segment
		(start 303.9872 -7.8994)
		(end 303.85512 -8.03148)
		(width 0.14224)
		(layer "In11.Cu")
		(net "M_C_DQS_DN<6>")
	)
	(segment
		(start 303.85512 -7.46252)
		(end 303.9872 -7.5946)
		(width 0.14224)
		(layer "In11.Cu")
		(net "M_C_DQS_DN<6>")
	)
	(segment
		(start 303.352454 -4.826)
		(end 302.98898 -4.826)
		(width 0.14224)
		(layer "In11.Cu")
		(net "M_C_DQS_DN<6>")
	)
	(segment
		(start 286.442658 -43.29938)
		(end 283.064458 -46.67758)
		(width 0.14224)
		(layer "In11.Cu")
		(net "M_C_DQS_DN<6>")
	)
	(segment
		(start 282.300934 -55.693818)
		(end 282.294584 -55.704486)
		(width 0.0889)
		(layer "In11.Cu")
		(net "M_C_DQS_DN<6>")
	)
	(segment
		(start 303.85512 -8.03148)
		(end 303.85512 -29.563314)
		(width 0.14224)
		(layer "In11.Cu")
		(net "M_C_DQS_DN<6>")
	)
	(segment
		(start 302.861726 -4.953254)
		(end 302.861726 -5.231892)
		(width 0.14224)
		(layer "In11.Cu")
		(net "M_C_DQS_DN<6>")
	)
	(segment
		(start 282.300934 -56.684418)
		(end 282.294584 -56.695086)
		(width 0.0889)
		(layer "In11.Cu")
		(net "M_C_DQS_DN<6>")
	)
	(segment
		(start 286.442658 -39.46906)
		(end 286.442658 -43.29938)
		(width 0.14224)
		(layer "In11.Cu")
		(net "M_C_DQS_DN<6>")
	)
	(segment
		(start 303.85512 -6.225286)
		(end 303.85512 -7.46252)
		(width 0.14224)
		(layer "In11.Cu")
		(net "M_C_DQS_DN<6>")
	)
	(segment
		(start 303.84877 -2.875788)
		(end 303.038002 -3.686556)
		(width 0.14224)
		(layer "In11.Cu")
		(net "M_C_DQS_DN<6>")
	)
	(segment
		(start 283.025088 -48.291496)
		(end 281.954224 -49.36236)
		(width 0.0889)
		(layer "In11.Cu")
		(net "M_C_DQS_DN<6>")
	)
	(segment
		(start 303.84877 1.033272)
		(end 303.84877 -2.875788)
		(width 0.14224)
		(layer "In11.Cu")
		(net "M_C_DQS_DN<6>")
	)
	(segment
		(start 282.294584 -56.695086)
		(end 282.289758 -56.703722)
		(width 0.0889)
		(layer "In11.Cu")
		(net "M_C_DQS_DN<6>")
	)
	(segment
		(start 282.294584 -59.076336)
		(end 282.300934 -59.087004)
		(width 0.0889)
		(layer "In11.Cu")
		(net "M_C_DQS_DN<6>")
	)
	(segment
		(start 303.038002 -3.686556)
		(end 303.501806 -4.15036)
		(width 0.14224)
		(layer "In11.Cu")
		(net "M_C_DQS_DN<6>")
	)
	(segment
		(start 303.501806 -4.15036)
		(end 303.501806 -4.676648)
		(width 0.14224)
		(layer "In11.Cu")
		(net "M_C_DQS_DN<6>")
	)
	(segment
		(start 282.405836 -54.129432)
		(end 282.405836 -54.5211)
		(width 0.0889)
		(layer "In11.Cu")
		(net "M_C_DQS_DN<6>")
	)
	(segment
		(start 303.701958 -5.84962)
		(end 303.701958 -6.072124)
		(width 0.14224)
		(layer "In11.Cu")
		(net "M_C_DQS_DN<6>")
	)
	(segment
		(start 282.300934 -62.628018)
		(end 282.294584 -62.638686)
		(width 0.0889)
		(layer "In11.Cu")
		(net "M_C_DQS_DN<6>")
	)
	(segment
		(start 282.146248 -51.042316)
		(end 282.282138 -51.178206)
		(width 0.0889)
		(layer "In11.Cu")
		(net "M_C_DQS_DN<6>")
	)
	(segment
		(start 303.038002 1.84404)
		(end 303.84877 1.033272)
		(width 0.14224)
		(layer "In11.Cu")
		(net "M_C_DQS_DN<6>")
	)
	(segment
		(start 282.405836 -54.5211)
		(end 282.289504 -54.722776)
		(width 0.0889)
		(layer "In11.Cu")
		(net "M_C_DQS_DN<6>")
	)
	(segment
		(start 281.782774 -64.977264)
		(end 281.782774 -65.315338)
		(width 0.0889)
		(layer "In11.Cu")
		(net "M_C_DQS_DN<6>")
	)
	(segment
		(start 289.721798 -36.18992)
		(end 286.442658 -39.46906)
		(width 0.14224)
		(layer "In11.Cu")
		(net "M_C_DQS_DN<6>")
	)
	(segment
		(start 282.294584 -59.666886)
		(end 282.289758 -59.675522)
		(width 0.0889)
		(layer "In11.Cu")
		(net "M_C_DQS_DN<6>")
	)
	(segment
		(start 282.294584 -57.685686)
		(end 282.289758 -57.694322)
		(width 0.0889)
		(layer "In11.Cu")
		(net "M_C_DQS_DN<6>")
	)
	(segment
		(start 281.954224 -49.36236)
		(end 281.954224 -50.478436)
		(width 0.0889)
		(layer "In11.Cu")
		(net "M_C_DQS_DN<6>")
	)
	(segment
		(start 303.85512 -29.563314)
		(end 297.228514 -36.18992)
		(width 0.14224)
		(layer "In11.Cu")
		(net "M_C_DQS_DN<6>")
	)
	(segment
		(start 282.300934 -63.618618)
		(end 282.294584 -63.629286)
		(width 0.0889)
		(layer "In11.Cu")
		(net "M_C_DQS_DN<6>")
	)
	(segment
		(start 282.294584 -60.657486)
		(end 282.289758 -60.666122)
		(width 0.0889)
		(layer "In11.Cu")
		(net "M_C_DQS_DN<6>")
	)
	(segment
		(start 282.294584 -63.629286)
		(end 282.289758 -63.637922)
		(width 0.0889)
		(layer "In11.Cu")
		(net "M_C_DQS_DN<6>")
	)
	(segment
		(start 303.299876 -5.670042)
		(end 303.52238 -5.670042)
		(width 0.14224)
		(layer "In11.Cu")
		(net "M_C_DQS_DN<6>")
	)
	(segment
		(start 282.300934 -60.646818)
		(end 282.294584 -60.657486)
		(width 0.0889)
		(layer "In11.Cu")
		(net "M_C_DQS_DN<6>")
	)
	(segment
		(start 283.064458 -46.67758)
		(end 283.064458 -47.221902)
		(width 0.14224)
		(layer "In11.Cu")
		(net "M_C_DQS_DN<6>")
	)
	(segment
		(start 302.98898 -4.826)
		(end 302.861726 -4.953254)
		(width 0.14224)
		(layer "In11.Cu")
		(net "M_C_DQS_DN<6>")
	)
	(segment
		(start 303.501806 -4.676648)
		(end 303.352454 -4.826)
		(width 0.14224)
		(layer "In11.Cu")
		(net "M_C_DQS_DN<6>")
	)
	(segment
		(start 282.300934 -57.675018)
		(end 282.294584 -57.685686)
		(width 0.0889)
		(layer "In11.Cu")
		(net "M_C_DQS_DN<6>")
	)
	(segment
		(start 283.064458 -47.244)
		(end 283.025088 -47.28337)
		(width 0.0889)
		(layer "In11.Cu")
		(net "M_C_DQS_DN<6>")
	)
	(segment
		(start 281.954224 -50.478436)
		(end 282.146248 -50.862484)
		(width 0.0889)
		(layer "In11.Cu")
		(net "M_C_DQS_DN<6>")
	)
	(segment
		(start 297.228514 -36.18992)
		(end 289.721798 -36.18992)
		(width 0.14224)
		(layer "In11.Cu")
		(net "M_C_DQS_DN<6>")
	)
	(segment
		(start 283.025088 -47.28337)
		(end 283.025088 -48.291496)
		(width 0.0889)
		(layer "In11.Cu")
		(net "M_C_DQS_DN<6>")
	)
	(segment
		(start 303.9872 -7.5946)
		(end 303.9872 -7.8994)
		(width 0.14224)
		(layer "In11.Cu")
		(net "M_C_DQS_DN<6>")
	)
	(segment
		(start 303.52238 -5.670042)
		(end 303.701958 -5.84962)
		(width 0.14224)
		(layer "In11.Cu")
		(net "M_C_DQS_DN<6>")
	)
	(segment
		(start 303.701958 -6.072124)
		(end 303.85512 -6.225286)
		(width 0.14224)
		(layer "In11.Cu")
		(net "M_C_DQS_DN<6>")
	)
	(segment
		(start 302.861726 -5.231892)
		(end 303.299876 -5.670042)
		(width 0.14224)
		(layer "In11.Cu")
		(net "M_C_DQS_DN<6>")
	)
	(segment
		(start 282.300934 -61.637418)
		(end 282.294584 -61.648086)
		(width 0.0889)
		(layer "In11.Cu")
		(net "M_C_DQS_DN<6>")
	)
	(segment
		(start 282.294584 -62.638686)
		(end 282.289758 -62.647322)
		(width 0.0889)
		(layer "In11.Cu")
		(net "M_C_DQS_DN<6>")
	)
	(segment
		(start 282.282138 -54.005734)
		(end 282.405836 -54.129432)
		(width 0.0889)
		(layer "In11.Cu")
		(net "M_C_DQS_DN<6>")
	)
	(segment
		(start 282.282138 -51.178206)
		(end 282.282138 -54.005734)
		(width 0.0889)
		(layer "In11.Cu")
		(net "M_C_DQS_DN<6>")
	)
	(segment
		(start 282.146248 -50.862484)
		(end 282.146248 -51.042316)
		(width 0.0889)
		(layer "In11.Cu")
		(net "M_C_DQS_DN<6>")
	)
	(segment
		(start 283.064458 -47.221902)
		(end 283.064458 -47.244)
		(width 0.0889)
		(layer "In11.Cu")
		(net "M_C_DQS_DN<6>")
	)
	(arc
		(start 282.289504 -54.722776)
		(mid 282.240902 -54.918874)
		(end 282.29433 -55.113682)
		(width 0.0889)
		(layer "In11.Cu")
		(net "M_C_DQS_DN<6>")
	)
	(arc
		(start 282.294584 -56.104536)
		(mid 282.373806 -56.393654)
		(end 282.300934 -56.684418)
		(width 0.0889)
		(layer "In11.Cu")
		(net "M_C_DQS_DN<6>")
	)
	(arc
		(start 282.289758 -60.666122)
		(mid 282.241003 -60.862474)
		(end 282.294584 -61.057536)
		(width 0.0889)
		(layer "In11.Cu")
		(net "M_C_DQS_DN<6>")
	)
	(arc
		(start 282.289758 -57.694322)
		(mid 282.241003 -57.890674)
		(end 282.294584 -58.085736)
		(width 0.0889)
		(layer "In11.Cu")
		(net "M_C_DQS_DN<6>")
	)
	(arc
		(start 282.294584 -64.029336)
		(mid 282.310089 -64.591478)
		(end 281.848052 -64.911986)
		(width 0.0889)
		(layer "In11.Cu")
		(net "M_C_DQS_DN<6>")
	)
	(arc
		(start 282.289758 -63.637922)
		(mid 282.241003 -63.834274)
		(end 282.294584 -64.029336)
		(width 0.0889)
		(layer "In11.Cu")
		(net "M_C_DQS_DN<6>")
	)
	(arc
		(start 282.289758 -61.656722)
		(mid 282.241003 -61.853074)
		(end 282.294584 -62.048136)
		(width 0.0889)
		(layer "In11.Cu")
		(net "M_C_DQS_DN<6>")
	)
	(arc
		(start 282.294584 -57.095136)
		(mid 282.373806 -57.384254)
		(end 282.300934 -57.675018)
		(width 0.0889)
		(layer "In11.Cu")
		(net "M_C_DQS_DN<6>")
	)
	(arc
		(start 282.294584 -58.67654)
		(mid 282.241085 -58.876438)
		(end 282.294584 -59.076336)
		(width 0.0889)
		(layer "In11.Cu")
		(net "M_C_DQS_DN<6>")
	)
	(arc
		(start 282.289758 -62.647322)
		(mid 282.241003 -62.843674)
		(end 282.294584 -63.038736)
		(width 0.0889)
		(layer "In11.Cu")
		(net "M_C_DQS_DN<6>")
	)
	(arc
		(start 282.294584 -58.085736)
		(mid 282.373715 -58.381138)
		(end 282.294584 -58.67654)
		(width 0.0889)
		(layer "In11.Cu")
		(net "M_C_DQS_DN<6>")
	)
	(arc
		(start 282.289758 -55.713122)
		(mid 282.241003 -55.909474)
		(end 282.294584 -56.104536)
		(width 0.0889)
		(layer "In11.Cu")
		(net "M_C_DQS_DN<6>")
	)
	(arc
		(start 282.294584 -55.113936)
		(mid 282.373806 -55.403054)
		(end 282.300934 -55.693818)
		(width 0.0889)
		(layer "In11.Cu")
		(net "M_C_DQS_DN<6>")
	)
	(arc
		(start 282.294584 -60.066936)
		(mid 282.373806 -60.356054)
		(end 282.300934 -60.646818)
		(width 0.0889)
		(layer "In11.Cu")
		(net "M_C_DQS_DN<6>")
	)
	(arc
		(start 282.294584 -61.057536)
		(mid 282.373806 -61.346654)
		(end 282.300934 -61.637418)
		(width 0.0889)
		(layer "In11.Cu")
		(net "M_C_DQS_DN<6>")
	)
	(arc
		(start 282.294584 -63.038736)
		(mid 282.373806 -63.327854)
		(end 282.300934 -63.618618)
		(width 0.0889)
		(layer "In11.Cu")
		(net "M_C_DQS_DN<6>")
	)
	(arc
		(start 282.294584 -62.048136)
		(mid 282.373806 -62.337254)
		(end 282.300934 -62.628018)
		(width 0.0889)
		(layer "In11.Cu")
		(net "M_C_DQS_DN<6>")
	)
	(arc
		(start 282.289758 -56.703722)
		(mid 282.241003 -56.900074)
		(end 282.294584 -57.095136)
		(width 0.0889)
		(layer "In11.Cu")
		(net "M_C_DQS_DN<6>")
	)
	(arc
		(start 282.289758 -59.675522)
		(mid 282.241003 -59.871874)
		(end 282.294584 -60.066936)
		(width 0.0889)
		(layer "In11.Cu")
		(net "M_C_DQS_DN<6>")
	)
	(arc
		(start 282.300934 -59.087004)
		(mid 282.373732 -59.377767)
		(end 282.294584 -59.666886)
		(width 0.0889)
		(layer "In11.Cu")
		(net "M_C_DQS_DN<6>")
	)
	(segment
		(start 293.299896 -0.821182)
		(end 293.299896 0.19177)
		(width 0.1651)
		(layer "F.Cu")
		(net "M_C_DQS_DN<5>")
	)
	(segment
		(start 279.778714 -61.847984)
		(end 279.207214 -61.847984)
		(width 0.0889)
		(layer "F.Cu")
		(net "M_C_DQS_DN<5>")
	)
	(segment
		(start 293.300404 -0.821182)
		(end 293.299896 -0.821182)
		(width 0.1651)
		(layer "F.Cu")
		(net "M_C_DQS_DN<5>")
	)
	(segment
		(start 293.299896 0.19177)
		(end 293.034212 0.457454)
		(width 0.1651)
		(layer "F.Cu")
		(net "M_C_DQS_DN<5>")
	)
	(segment
		(start 293.034212 0.457454)
		(end 293.034212 1.190244)
		(width 0.1651)
		(layer "F.Cu")
		(net "M_C_DQS_DN<5>")
	)
	(segment
		(start 293.034212 1.190244)
		(end 293.688008 1.84404)
		(width 0.1651)
		(layer "F.Cu")
		(net "M_C_DQS_DN<5>")
	)
	(via
		(at 293.688008 -3.686556)
		(size 0.508)
		(drill 0.254)
		(layers "F.Cu" "B.Cu")
		(net "M_C_DQS_DN<5>")
	)
	(via
		(at 279.207214 -61.847984)
		(size 0.508)
		(drill 0.254)
		(layers "F.Cu" "B.Cu")
		(net "M_C_DQS_DN<5>")
	)
	(via
		(at 293.688008 1.84404)
		(size 0.508)
		(drill 0.254)
		(layers "F.Cu" "B.Cu")
		(net "M_C_DQS_DN<5>")
	)
	(segment
		(start 293.299896 -1.91897)
		(end 293.046912 -2.171954)
		(width 0.1651)
		(layer "B.Cu")
		(net "M_C_DQS_DN<5>")
	)
	(segment
		(start 293.046912 -2.171954)
		(end 293.046912 -3.04546)
		(width 0.1651)
		(layer "B.Cu")
		(net "M_C_DQS_DN<5>")
	)
	(segment
		(start 293.299896 -1.021842)
		(end 293.299896 -1.91897)
		(width 0.1651)
		(layer "B.Cu")
		(net "M_C_DQS_DN<5>")
	)
	(segment
		(start 293.046912 -3.04546)
		(end 293.688008 -3.686556)
		(width 0.1651)
		(layer "B.Cu")
		(net "M_C_DQS_DN<5>")
	)
	(segment
		(start 293.300404 -1.021842)
		(end 293.299896 -1.021842)
		(width 0.1651)
		(layer "B.Cu")
		(net "M_C_DQS_DN<5>")
	)
	(segment
		(start 283.050488 -47.275496)
		(end 283.050488 -47.297594)
		(width 0.0889)
		(layer "In4.Cu")
		(net "M_C_DQS_DN<5>")
	)
	(segment
		(start 279.714198 -60.5536)
		(end 279.719024 -60.562236)
		(width 0.0889)
		(layer "In4.Cu")
		(net "M_C_DQS_DN<5>")
	)
	(segment
		(start 281.0637 -50.74412)
		(end 281.0637 -51.45532)
		(width 0.0889)
		(layer "In4.Cu")
		(net "M_C_DQS_DN<5>")
	)
	(segment
		(start 294.512238 -9.41832)
		(end 294.669718 -9.5758)
		(width 0.14224)
		(layer "In4.Cu")
		(net "M_C_DQS_DN<5>")
	)
	(segment
		(start 279.714198 -57.5818)
		(end 279.719024 -57.590436)
		(width 0.0889)
		(layer "In4.Cu")
		(net "M_C_DQS_DN<5>")
	)
	(segment
		(start 279.719024 -61.152786)
		(end 279.65273 -61.26734)
		(width 0.0889)
		(layer "In4.Cu")
		(net "M_C_DQS_DN<5>")
	)
	(segment
		(start 279.719024 -60.562236)
		(end 279.725374 -60.572904)
		(width 0.0889)
		(layer "In4.Cu")
		(net "M_C_DQS_DN<5>")
	)
	(segment
		(start 294.288464 -5.70738)
		(end 294.288464 -5.929884)
		(width 0.14224)
		(layer "In4.Cu")
		(net "M_C_DQS_DN<5>")
	)
	(segment
		(start 294.512238 -28.939236)
		(end 294.30472 -29.146754)
		(width 0.14224)
		(layer "In4.Cu")
		(net "M_C_DQS_DN<5>")
	)
	(segment
		(start 294.30472 -31.331408)
		(end 283.050488 -42.58564)
		(width 0.14224)
		(layer "In4.Cu")
		(net "M_C_DQS_DN<5>")
	)
	(segment
		(start 293.638732 -5.05968)
		(end 293.638732 -5.280152)
		(width 0.14224)
		(layer "In4.Cu")
		(net "M_C_DQS_DN<5>")
	)
	(segment
		(start 279.719024 -54.618636)
		(end 279.725374 -54.629304)
		(width 0.0889)
		(layer "In4.Cu")
		(net "M_C_DQS_DN<5>")
	)
	(segment
		(start 283.050488 -42.58564)
		(end 283.050488 -47.275496)
		(width 0.14224)
		(layer "In4.Cu")
		(net "M_C_DQS_DN<5>")
	)
	(segment
		(start 293.886128 -5.527548)
		(end 294.108632 -5.527548)
		(width 0.14224)
		(layer "In4.Cu")
		(net "M_C_DQS_DN<5>")
	)
	(segment
		(start 281.0637 -51.45532)
		(end 280.123392 -52.395628)
		(width 0.0889)
		(layer "In4.Cu")
		(net "M_C_DQS_DN<5>")
	)
	(segment
		(start 294.288464 -5.929884)
		(end 294.512238 -6.153658)
		(width 0.14224)
		(layer "In4.Cu")
		(net "M_C_DQS_DN<5>")
	)
	(segment
		(start 279.714198 -55.6006)
		(end 279.719024 -55.609236)
		(width 0.0889)
		(layer "In4.Cu")
		(net "M_C_DQS_DN<5>")
	)
	(segment
		(start 293.638732 -5.280152)
		(end 293.886128 -5.527548)
		(width 0.14224)
		(layer "In4.Cu")
		(net "M_C_DQS_DN<5>")
	)
	(segment
		(start 294.151812 -4.15036)
		(end 294.151812 -4.5466)
		(width 0.14224)
		(layer "In4.Cu")
		(net "M_C_DQS_DN<5>")
	)
	(segment
		(start 283.011118 -48.796702)
		(end 281.0637 -50.74412)
		(width 0.0889)
		(layer "In4.Cu")
		(net "M_C_DQS_DN<5>")
	)
	(segment
		(start 279.714198 -56.5912)
		(end 279.719024 -56.599836)
		(width 0.0889)
		(layer "In4.Cu")
		(net "M_C_DQS_DN<5>")
	)
	(segment
		(start 294.669718 -9.8298)
		(end 294.512238 -9.98728)
		(width 0.14224)
		(layer "In4.Cu")
		(net "M_C_DQS_DN<5>")
	)
	(segment
		(start 279.719024 -56.599836)
		(end 279.725374 -56.610504)
		(width 0.0889)
		(layer "In4.Cu")
		(net "M_C_DQS_DN<5>")
	)
	(segment
		(start 283.011118 -47.336964)
		(end 283.011118 -48.796702)
		(width 0.0889)
		(layer "In4.Cu")
		(net "M_C_DQS_DN<5>")
	)
	(segment
		(start 294.151812 -4.5466)
		(end 293.638732 -5.05968)
		(width 0.14224)
		(layer "In4.Cu")
		(net "M_C_DQS_DN<5>")
	)
	(segment
		(start 294.108632 -5.527548)
		(end 294.288464 -5.70738)
		(width 0.14224)
		(layer "In4.Cu")
		(net "M_C_DQS_DN<5>")
	)
	(segment
		(start 283.050488 -47.297594)
		(end 283.011118 -47.336964)
		(width 0.0889)
		(layer "In4.Cu")
		(net "M_C_DQS_DN<5>")
	)
	(segment
		(start 279.719024 -55.609236)
		(end 279.725374 -55.619904)
		(width 0.0889)
		(layer "In4.Cu")
		(net "M_C_DQS_DN<5>")
	)
	(segment
		(start 280.123392 -53.150008)
		(end 279.797764 -53.475636)
		(width 0.0889)
		(layer "In4.Cu")
		(net "M_C_DQS_DN<5>")
	)
	(segment
		(start 279.714198 -58.5724)
		(end 279.719024 -58.581036)
		(width 0.0889)
		(layer "In4.Cu")
		(net "M_C_DQS_DN<5>")
	)
	(segment
		(start 279.714198 -54.61)
		(end 279.719024 -54.618636)
		(width 0.0889)
		(layer "In4.Cu")
		(net "M_C_DQS_DN<5>")
	)
	(segment
		(start 279.797764 -53.475636)
		(end 279.797764 -53.906928)
		(width 0.0889)
		(layer "In4.Cu")
		(net "M_C_DQS_DN<5>")
	)
	(segment
		(start 280.123392 -52.395628)
		(end 280.123392 -53.150008)
		(width 0.0889)
		(layer "In4.Cu")
		(net "M_C_DQS_DN<5>")
	)
	(segment
		(start 294.512238 -6.153658)
		(end 294.512238 -9.41832)
		(width 0.14224)
		(layer "In4.Cu")
		(net "M_C_DQS_DN<5>")
	)
	(segment
		(start 279.797764 -53.906928)
		(end 279.798018 -53.907182)
		(width 0.0889)
		(layer "In4.Cu")
		(net "M_C_DQS_DN<5>")
	)
	(segment
		(start 294.30472 -29.146754)
		(end 294.30472 -31.331408)
		(width 0.14224)
		(layer "In4.Cu")
		(net "M_C_DQS_DN<5>")
	)
	(segment
		(start 279.725374 -59.160918)
		(end 279.719024 -59.171586)
		(width 0.0889)
		(layer "In4.Cu")
		(net "M_C_DQS_DN<5>")
	)
	(segment
		(start 293.688008 -3.686556)
		(end 294.151812 -4.15036)
		(width 0.14224)
		(layer "In4.Cu")
		(net "M_C_DQS_DN<5>")
	)
	(segment
		(start 294.669718 -9.5758)
		(end 294.669718 -9.8298)
		(width 0.14224)
		(layer "In4.Cu")
		(net "M_C_DQS_DN<5>")
	)
	(segment
		(start 279.719024 -57.590436)
		(end 279.725374 -57.601104)
		(width 0.0889)
		(layer "In4.Cu")
		(net "M_C_DQS_DN<5>")
	)
	(segment
		(start 294.512238 -9.98728)
		(end 294.512238 -28.939236)
		(width 0.14224)
		(layer "In4.Cu")
		(net "M_C_DQS_DN<5>")
	)
	(arc
		(start 279.719024 -54.218586)
		(mid 279.665554 -54.413649)
		(end 279.714198 -54.61)
		(width 0.0889)
		(layer "In4.Cu")
		(net "M_C_DQS_DN<5>")
	)
	(arc
		(start 279.725374 -54.629304)
		(mid 279.798172 -54.920067)
		(end 279.719024 -55.209186)
		(width 0.0889)
		(layer "In4.Cu")
		(net "M_C_DQS_DN<5>")
	)
	(arc
		(start 279.719024 -58.180986)
		(mid 279.665554 -58.376049)
		(end 279.714198 -58.5724)
		(width 0.0889)
		(layer "In4.Cu")
		(net "M_C_DQS_DN<5>")
	)
	(arc
		(start 279.798018 -53.907182)
		(mid 279.78006 -54.068344)
		(end 279.719024 -54.218586)
		(width 0.0889)
		(layer "In4.Cu")
		(net "M_C_DQS_DN<5>")
	)
	(arc
		(start 279.65273 -61.26734)
		(mid 279.448983 -61.572249)
		(end 279.207214 -61.847984)
		(width 0.0889)
		(layer "In4.Cu")
		(net "M_C_DQS_DN<5>")
	)
	(arc
		(start 279.719024 -59.571382)
		(mid 279.798155 -59.866784)
		(end 279.719024 -60.162186)
		(width 0.0889)
		(layer "In4.Cu")
		(net "M_C_DQS_DN<5>")
	)
	(arc
		(start 279.719024 -58.581036)
		(mid 279.798246 -58.870154)
		(end 279.725374 -59.160918)
		(width 0.0889)
		(layer "In4.Cu")
		(net "M_C_DQS_DN<5>")
	)
	(arc
		(start 279.719024 -57.190386)
		(mid 279.665554 -57.385449)
		(end 279.714198 -57.5818)
		(width 0.0889)
		(layer "In4.Cu")
		(net "M_C_DQS_DN<5>")
	)
	(arc
		(start 279.725374 -60.572904)
		(mid 279.798172 -60.863667)
		(end 279.719024 -61.152786)
		(width 0.0889)
		(layer "In4.Cu")
		(net "M_C_DQS_DN<5>")
	)
	(arc
		(start 279.719024 -56.199786)
		(mid 279.665554 -56.394849)
		(end 279.714198 -56.5912)
		(width 0.0889)
		(layer "In4.Cu")
		(net "M_C_DQS_DN<5>")
	)
	(arc
		(start 279.719024 -59.171586)
		(mid 279.665525 -59.371484)
		(end 279.719024 -59.571382)
		(width 0.0889)
		(layer "In4.Cu")
		(net "M_C_DQS_DN<5>")
	)
	(arc
		(start 279.719024 -60.162186)
		(mid 279.665554 -60.357249)
		(end 279.714198 -60.5536)
		(width 0.0889)
		(layer "In4.Cu")
		(net "M_C_DQS_DN<5>")
	)
	(arc
		(start 279.725374 -57.601104)
		(mid 279.798172 -57.891867)
		(end 279.719024 -58.180986)
		(width 0.0889)
		(layer "In4.Cu")
		(net "M_C_DQS_DN<5>")
	)
	(arc
		(start 279.719024 -55.209186)
		(mid 279.665554 -55.404249)
		(end 279.714198 -55.6006)
		(width 0.0889)
		(layer "In4.Cu")
		(net "M_C_DQS_DN<5>")
	)
	(arc
		(start 279.725374 -55.619904)
		(mid 279.798172 -55.910667)
		(end 279.719024 -56.199786)
		(width 0.0889)
		(layer "In4.Cu")
		(net "M_C_DQS_DN<5>")
	)
	(arc
		(start 279.725374 -56.610504)
		(mid 279.798172 -56.901267)
		(end 279.719024 -57.190386)
		(width 0.0889)
		(layer "In4.Cu")
		(net "M_C_DQS_DN<5>")
	)
	(segment
		(start 294.498776 1.033272)
		(end 293.688008 1.84404)
		(width 0.14224)
		(layer "In11.Cu")
		(net "M_C_DQS_DN<5>")
	)
	(segment
		(start 293.688008 -3.686556)
		(end 294.498776 -2.875788)
		(width 0.14224)
		(layer "In11.Cu")
		(net "M_C_DQS_DN<5>")
	)
	(segment
		(start 294.498776 -2.875788)
		(end 294.498776 1.033272)
		(width 0.14224)
		(layer "In11.Cu")
		(net "M_C_DQS_DN<5>")
	)
	(segment
		(start 283.95041 0.191008)
		(end 283.683964 0.457454)
		(width 0.1651)
		(layer "F.Cu")
		(net "M_C_DQS_DN<4>")
	)
	(segment
		(start 283.683964 0.457454)
		(end 283.683964 1.190244)
		(width 0.1651)
		(layer "F.Cu")
		(net "M_C_DQS_DN<4>")
	)
	(segment
		(start 283.683964 1.190244)
		(end 284.33776 1.84404)
		(width 0.1651)
		(layer "F.Cu")
		(net "M_C_DQS_DN<4>")
	)
	(segment
		(start 283.95041 -0.821182)
		(end 283.95041 0.191008)
		(width 0.1651)
		(layer "F.Cu")
		(net "M_C_DQS_DN<4>")
	)
	(segment
		(start 274.627848 -61.847984)
		(end 274.056348 -61.847984)
		(width 0.0889)
		(layer "F.Cu")
		(net "M_C_DQS_DN<4>")
	)
	(via
		(at 274.056348 -61.847984)
		(size 0.508)
		(drill 0.254)
		(layers "F.Cu" "B.Cu")
		(net "M_C_DQS_DN<4>")
	)
	(via
		(at 284.33776 -3.686556)
		(size 0.508)
		(drill 0.254)
		(layers "F.Cu" "B.Cu")
		(net "M_C_DQS_DN<4>")
	)
	(via
		(at 284.33776 1.84404)
		(size 0.508)
		(drill 0.254)
		(layers "F.Cu" "B.Cu")
		(net "M_C_DQS_DN<4>")
	)
	(segment
		(start 283.696664 -3.04546)
		(end 284.33776 -3.686556)
		(width 0.1651)
		(layer "B.Cu")
		(net "M_C_DQS_DN<4>")
	)
	(segment
		(start 283.949902 -1.021842)
		(end 283.949902 -1.918716)
		(width 0.1651)
		(layer "B.Cu")
		(net "M_C_DQS_DN<4>")
	)
	(segment
		(start 283.95041 -1.021842)
		(end 283.949902 -1.021842)
		(width 0.1651)
		(layer "B.Cu")
		(net "M_C_DQS_DN<4>")
	)
	(segment
		(start 283.949902 -1.918716)
		(end 283.696664 -2.171954)
		(width 0.1651)
		(layer "B.Cu")
		(net "M_C_DQS_DN<4>")
	)
	(segment
		(start 283.696664 -2.171954)
		(end 283.696664 -3.04546)
		(width 0.1651)
		(layer "B.Cu")
		(net "M_C_DQS_DN<4>")
	)
	(segment
		(start 274.576794 -54.203346)
		(end 274.567904 -54.218586)
		(width 0.0889)
		(layer "In11.Cu")
		(net "M_C_DQS_DN<4>")
	)
	(segment
		(start 285.133288 -6.336284)
		(end 285.290768 -6.493764)
		(width 0.14224)
		(layer "In11.Cu")
		(net "M_C_DQS_DN<4>")
	)
	(segment
		(start 284.801564 -4.5466)
		(end 284.288484 -5.05968)
		(width 0.14224)
		(layer "In11.Cu")
		(net "M_C_DQS_DN<4>")
	)
	(segment
		(start 285.133288 -10.80008)
		(end 285.133288 -30.202378)
		(width 0.14224)
		(layer "In11.Cu")
		(net "M_C_DQS_DN<4>")
	)
	(segment
		(start 274.997672 -48.671988)
		(end 274.997672 -52.246022)
		(width 0.0889)
		(layer "In11.Cu")
		(net "M_C_DQS_DN<4>")
	)
	(segment
		(start 275.4503 -47.41037)
		(end 275.4503 -48.21936)
		(width 0.0889)
		(layer "In11.Cu")
		(net "M_C_DQS_DN<4>")
	)
	(segment
		(start 284.288484 -5.280152)
		(end 284.53588 -5.527548)
		(width 0.14224)
		(layer "In11.Cu")
		(net "M_C_DQS_DN<4>")
	)
	(segment
		(start 285.133288 -10.03808)
		(end 285.133288 -10.23112)
		(width 0.14224)
		(layer "In11.Cu")
		(net "M_C_DQS_DN<4>")
	)
	(segment
		(start 274.121372 -61.444886)
		(end 274.056348 -61.50991)
		(width 0.0889)
		(layer "In11.Cu")
		(net "M_C_DQS_DN<4>")
	)
	(segment
		(start 284.33776 -3.686556)
		(end 284.801564 -4.15036)
		(width 0.14224)
		(layer "In11.Cu")
		(net "M_C_DQS_DN<4>")
	)
	(segment
		(start 285.148528 -2.875788)
		(end 284.33776 -3.686556)
		(width 0.14224)
		(layer "In11.Cu")
		(net "M_C_DQS_DN<4>")
	)
	(segment
		(start 274.56003 -54.604412)
		(end 274.577048 -54.633876)
		(width 0.0889)
		(layer "In11.Cu")
		(net "M_C_DQS_DN<4>")
	)
	(segment
		(start 285.290768 -10.6426)
		(end 285.133288 -10.80008)
		(width 0.14224)
		(layer "In11.Cu")
		(net "M_C_DQS_DN<4>")
	)
	(segment
		(start 285.290768 -6.493764)
		(end 285.290768 -6.747764)
		(width 0.14224)
		(layer "In11.Cu")
		(net "M_C_DQS_DN<4>")
	)
	(segment
		(start 285.133288 -10.23112)
		(end 285.290768 -10.3886)
		(width 0.14224)
		(layer "In11.Cu")
		(net "M_C_DQS_DN<4>")
	)
	(segment
		(start 275.4503 -48.21936)
		(end 274.997672 -48.671988)
		(width 0.0889)
		(layer "In11.Cu")
		(net "M_C_DQS_DN<4>")
	)
	(segment
		(start 284.33776 1.84404)
		(end 285.148528 1.033272)
		(width 0.14224)
		(layer "In11.Cu")
		(net "M_C_DQS_DN<4>")
	)
	(segment
		(start 284.801564 -4.15036)
		(end 284.801564 -4.5466)
		(width 0.14224)
		(layer "In11.Cu")
		(net "M_C_DQS_DN<4>")
	)
	(segment
		(start 275.48967 -46.895004)
		(end 275.48967 -47.348902)
		(width 0.14224)
		(layer "In11.Cu")
		(net "M_C_DQS_DN<4>")
	)
	(segment
		(start 274.574508 -59.160918)
		(end 274.568158 -59.171586)
		(width 0.0889)
		(layer "In11.Cu")
		(net "M_C_DQS_DN<4>")
	)
	(segment
		(start 275.48967 -47.371)
		(end 275.4503 -47.41037)
		(width 0.0889)
		(layer "In11.Cu")
		(net "M_C_DQS_DN<4>")
	)
	(segment
		(start 285.133288 -9.46912)
		(end 285.290768 -9.6266)
		(width 0.14224)
		(layer "In11.Cu")
		(net "M_C_DQS_DN<4>")
	)
	(segment
		(start 285.133288 -30.202378)
		(end 275.660104 -39.675562)
		(width 0.14224)
		(layer "In11.Cu")
		(net "M_C_DQS_DN<4>")
	)
	(segment
		(start 285.290768 -9.6266)
		(end 285.290768 -9.8806)
		(width 0.14224)
		(layer "In11.Cu")
		(net "M_C_DQS_DN<4>")
	)
	(segment
		(start 274.568158 -57.590436)
		(end 274.577048 -57.605676)
		(width 0.0889)
		(layer "In11.Cu")
		(net "M_C_DQS_DN<4>")
	)
	(segment
		(start 275.48967 -47.348902)
		(end 275.48967 -47.371)
		(width 0.0889)
		(layer "In11.Cu")
		(net "M_C_DQS_DN<4>")
	)
	(segment
		(start 274.702778 -52.540916)
		(end 274.702778 -52.99329)
		(width 0.0889)
		(layer "In11.Cu")
		(net "M_C_DQS_DN<4>")
	)
	(segment
		(start 285.290768 -10.3886)
		(end 285.290768 -10.6426)
		(width 0.14224)
		(layer "In11.Cu")
		(net "M_C_DQS_DN<4>")
	)
	(segment
		(start 274.997672 -52.246022)
		(end 274.702778 -52.540916)
		(width 0.0889)
		(layer "In11.Cu")
		(net "M_C_DQS_DN<4>")
	)
	(segment
		(start 284.53588 -5.527548)
		(end 284.758384 -5.527548)
		(width 0.14224)
		(layer "In11.Cu")
		(net "M_C_DQS_DN<4>")
	)
	(segment
		(start 274.056348 -61.50991)
		(end 274.056348 -61.847984)
		(width 0.0889)
		(layer "In11.Cu")
		(net "M_C_DQS_DN<4>")
	)
	(segment
		(start 284.758384 -5.527548)
		(end 284.938216 -5.70738)
		(width 0.14224)
		(layer "In11.Cu")
		(net "M_C_DQS_DN<4>")
	)
	(segment
		(start 275.660104 -39.675562)
		(end 275.660104 -46.72457)
		(width 0.14224)
		(layer "In11.Cu")
		(net "M_C_DQS_DN<4>")
	)
	(segment
		(start 274.568158 -55.609236)
		(end 274.577048 -55.624476)
		(width 0.0889)
		(layer "In11.Cu")
		(net "M_C_DQS_DN<4>")
	)
	(segment
		(start 285.148528 1.033272)
		(end 285.148528 -2.875788)
		(width 0.14224)
		(layer "In11.Cu")
		(net "M_C_DQS_DN<4>")
	)
	(segment
		(start 285.133288 -6.905244)
		(end 285.133288 -9.46912)
		(width 0.14224)
		(layer "In11.Cu")
		(net "M_C_DQS_DN<4>")
	)
	(segment
		(start 285.290768 -9.8806)
		(end 285.133288 -10.03808)
		(width 0.14224)
		(layer "In11.Cu")
		(net "M_C_DQS_DN<4>")
	)
	(segment
		(start 274.568158 -59.571382)
		(end 274.574508 -59.58205)
		(width 0.0889)
		(layer "In11.Cu")
		(net "M_C_DQS_DN<4>")
	)
	(segment
		(start 284.938216 -5.70738)
		(end 284.938216 -5.929884)
		(width 0.14224)
		(layer "In11.Cu")
		(net "M_C_DQS_DN<4>")
	)
	(segment
		(start 285.290768 -6.747764)
		(end 285.133288 -6.905244)
		(width 0.14224)
		(layer "In11.Cu")
		(net "M_C_DQS_DN<4>")
	)
	(segment
		(start 274.568158 -56.599836)
		(end 274.577048 -56.615076)
		(width 0.0889)
		(layer "In11.Cu")
		(net "M_C_DQS_DN<4>")
	)
	(segment
		(start 285.133288 -6.124956)
		(end 285.133288 -6.336284)
		(width 0.14224)
		(layer "In11.Cu")
		(net "M_C_DQS_DN<4>")
	)
	(segment
		(start 284.938216 -5.929884)
		(end 285.133288 -6.124956)
		(width 0.14224)
		(layer "In11.Cu")
		(net "M_C_DQS_DN<4>")
	)
	(segment
		(start 274.702778 -52.99329)
		(end 274.560538 -53.239162)
		(width 0.0889)
		(layer "In11.Cu")
		(net "M_C_DQS_DN<4>")
	)
	(segment
		(start 275.660104 -46.72457)
		(end 275.48967 -46.895004)
		(width 0.14224)
		(layer "In11.Cu")
		(net "M_C_DQS_DN<4>")
	)
	(segment
		(start 274.568158 -60.562236)
		(end 274.577048 -60.577476)
		(width 0.0889)
		(layer "In11.Cu")
		(net "M_C_DQS_DN<4>")
	)
	(segment
		(start 284.288484 -5.05968)
		(end 284.288484 -5.280152)
		(width 0.14224)
		(layer "In11.Cu")
		(net "M_C_DQS_DN<4>")
	)
	(arc
		(start 274.577048 -60.577476)
		(mid 274.579706 -61.13229)
		(end 274.121372 -61.444886)
		(width 0.0889)
		(layer "In11.Cu")
		(net "M_C_DQS_DN<4>")
	)
	(arc
		(start 274.577048 -54.633876)
		(mid 274.647445 -54.922827)
		(end 274.568158 -55.20944)
		(width 0.0889)
		(layer "In11.Cu")
		(net "M_C_DQS_DN<4>")
	)
	(arc
		(start 274.577048 -56.615076)
		(mid 274.647445 -56.904027)
		(end 274.568158 -57.19064)
		(width 0.0889)
		(layer "In11.Cu")
		(net "M_C_DQS_DN<4>")
	)
	(arc
		(start 274.577048 -57.605676)
		(mid 274.647445 -57.894627)
		(end 274.568158 -58.18124)
		(width 0.0889)
		(layer "In11.Cu")
		(net "M_C_DQS_DN<4>")
	)
	(arc
		(start 274.558506 -53.243734)
		(mid 274.514296 -53.436699)
		(end 274.567904 -53.627274)
		(width 0.0889)
		(layer "In11.Cu")
		(net "M_C_DQS_DN<4>")
	)
	(arc
		(start 274.567904 -53.627274)
		(mid 274.64722 -53.914143)
		(end 274.576794 -54.203346)
		(width 0.0889)
		(layer "In11.Cu")
		(net "M_C_DQS_DN<4>")
	)
	(arc
		(start 274.568158 -55.20944)
		(mid 274.514625 -55.409338)
		(end 274.568158 -55.609236)
		(width 0.0889)
		(layer "In11.Cu")
		(net "M_C_DQS_DN<4>")
	)
	(arc
		(start 274.568158 -58.581036)
		(mid 274.64738 -58.870154)
		(end 274.574508 -59.160918)
		(width 0.0889)
		(layer "In11.Cu")
		(net "M_C_DQS_DN<4>")
	)
	(arc
		(start 274.568158 -60.16244)
		(mid 274.514625 -60.362338)
		(end 274.568158 -60.562236)
		(width 0.0889)
		(layer "In11.Cu")
		(net "M_C_DQS_DN<4>")
	)
	(arc
		(start 274.574508 -59.58205)
		(mid 274.647428 -59.873067)
		(end 274.568158 -60.16244)
		(width 0.0889)
		(layer "In11.Cu")
		(net "M_C_DQS_DN<4>")
	)
	(arc
		(start 274.567904 -54.218586)
		(mid 274.514363 -54.410497)
		(end 274.56003 -54.604412)
		(width 0.0889)
		(layer "In11.Cu")
		(net "M_C_DQS_DN<4>")
	)
	(arc
		(start 274.577048 -55.624476)
		(mid 274.647445 -55.913427)
		(end 274.568158 -56.20004)
		(width 0.0889)
		(layer "In11.Cu")
		(net "M_C_DQS_DN<4>")
	)
	(arc
		(start 274.568158 -59.171586)
		(mid 274.514625 -59.371484)
		(end 274.568158 -59.571382)
		(width 0.0889)
		(layer "In11.Cu")
		(net "M_C_DQS_DN<4>")
	)
	(arc
		(start 274.568158 -56.20004)
		(mid 274.514625 -56.399938)
		(end 274.568158 -56.599836)
		(width 0.0889)
		(layer "In11.Cu")
		(net "M_C_DQS_DN<4>")
	)
	(arc
		(start 274.560538 -53.239162)
		(mid 274.559515 -53.241445)
		(end 274.558506 -53.243734)
		(width 0.0889)
		(layer "In11.Cu")
		(net "M_C_DQS_DN<4>")
	)
	(arc
		(start 274.568158 -57.19064)
		(mid 274.514625 -57.390538)
		(end 274.568158 -57.590436)
		(width 0.0889)
		(layer "In11.Cu")
		(net "M_C_DQS_DN<4>")
	)
	(arc
		(start 274.568158 -58.18124)
		(mid 274.514625 -58.381138)
		(end 274.568158 -58.581036)
		(width 0.0889)
		(layer "In11.Cu")
		(net "M_C_DQS_DN<4>")
	)
	(segment
		(start 228.70033 -0.821182)
		(end 228.699822 -0.821182)
		(width 0.1651)
		(layer "F.Cu")
		(net "M_C_DQS_DN<3>")
	)
	(segment
		(start 228.434138 1.190244)
		(end 229.087934 1.84404)
		(width 0.1651)
		(layer "F.Cu")
		(net "M_C_DQS_DN<3>")
	)
	(segment
		(start 249.919744 -67.47764)
		(end 249.348244 -67.47764)
		(width 0.0889)
		(layer "F.Cu")
		(net "M_C_DQS_DN<3>")
	)
	(segment
		(start 228.699822 0.19177)
		(end 228.434138 0.457454)
		(width 0.1651)
		(layer "F.Cu")
		(net "M_C_DQS_DN<3>")
	)
	(segment
		(start 228.434138 0.457454)
		(end 228.434138 1.190244)
		(width 0.1651)
		(layer "F.Cu")
		(net "M_C_DQS_DN<3>")
	)
	(segment
		(start 228.699822 -0.821182)
		(end 228.699822 0.19177)
		(width 0.1651)
		(layer "F.Cu")
		(net "M_C_DQS_DN<3>")
	)
	(via
		(at 249.348244 -67.47764)
		(size 0.508)
		(drill 0.254)
		(layers "F.Cu" "B.Cu")
		(net "M_C_DQS_DN<3>")
	)
	(via
		(at 229.087934 -3.686556)
		(size 0.508)
		(drill 0.254)
		(layers "F.Cu" "B.Cu")
		(net "M_C_DQS_DN<3>")
	)
	(via
		(at 229.087934 1.84404)
		(size 0.508)
		(drill 0.254)
		(layers "F.Cu" "B.Cu")
		(net "M_C_DQS_DN<3>")
	)
	(segment
		(start 228.446838 -3.04546)
		(end 229.087934 -3.686556)
		(width 0.1651)
		(layer "B.Cu")
		(net "M_C_DQS_DN<3>")
	)
	(segment
		(start 228.699822 -1.021842)
		(end 228.699822 -1.91897)
		(width 0.1651)
		(layer "B.Cu")
		(net "M_C_DQS_DN<3>")
	)
	(segment
		(start 228.70033 -1.021842)
		(end 228.699822 -1.021842)
		(width 0.1651)
		(layer "B.Cu")
		(net "M_C_DQS_DN<3>")
	)
	(segment
		(start 228.446838 -2.171954)
		(end 228.446838 -3.04546)
		(width 0.1651)
		(layer "B.Cu")
		(net "M_C_DQS_DN<3>")
	)
	(segment
		(start 228.699822 -1.91897)
		(end 228.446838 -2.171954)
		(width 0.1651)
		(layer "B.Cu")
		(net "M_C_DQS_DN<3>")
	)
	(segment
		(start 249.860054 -62.819788)
		(end 249.855228 -62.828424)
		(width 0.0889)
		(layer "In11.Cu")
		(net "M_C_DQS_DN<3>")
	)
	(segment
		(start 247.13946 -49.225962)
		(end 247.768872 -49.855374)
		(width 0.14224)
		(layer "In11.Cu")
		(net "M_C_DQS_DN<3>")
	)
	(segment
		(start 229.551738 -4.5466)
		(end 229.038658 -5.05968)
		(width 0.14224)
		(layer "In11.Cu")
		(net "M_C_DQS_DN<3>")
	)
	(segment
		(start 230.0224 -8.610854)
		(end 229.870254 -8.763)
		(width 0.14224)
		(layer "In11.Cu")
		(net "M_C_DQS_DN<3>")
	)
	(segment
		(start 249.866404 -60.82792)
		(end 249.860054 -60.838588)
		(width 0.0889)
		(layer "In11.Cu")
		(net "M_C_DQS_DN<3>")
	)
	(segment
		(start 249.860054 -55.885588)
		(end 249.855228 -55.894224)
		(width 0.0889)
		(layer "In11.Cu")
		(net "M_C_DQS_DN<3>")
	)
	(segment
		(start 249.866404 -65.78092)
		(end 249.860054 -65.791588)
		(width 0.0889)
		(layer "In11.Cu")
		(net "M_C_DQS_DN<3>")
	)
	(segment
		(start 229.870254 -8.763)
		(end 229.870254 -9.39292)
		(width 0.14224)
		(layer "In11.Cu")
		(net "M_C_DQS_DN<3>")
	)
	(segment
		(start 230.027734 -10.5664)
		(end 229.870254 -10.72388)
		(width 0.14224)
		(layer "In11.Cu")
		(net "M_C_DQS_DN<3>")
	)
	(segment
		(start 249.866404 -62.80912)
		(end 249.860054 -62.819788)
		(width 0.0889)
		(layer "In11.Cu")
		(net "M_C_DQS_DN<3>")
	)
	(segment
		(start 229.870254 -10.15492)
		(end 230.027734 -10.3124)
		(width 0.14224)
		(layer "In11.Cu")
		(net "M_C_DQS_DN<3>")
	)
	(segment
		(start 230.027734 -9.5504)
		(end 230.027734 -9.8044)
		(width 0.14224)
		(layer "In11.Cu")
		(net "M_C_DQS_DN<3>")
	)
	(segment
		(start 247.78462 -49.927002)
		(end 247.937782 -50.080164)
		(width 0.0889)
		(layer "In11.Cu")
		(net "M_C_DQS_DN<3>")
	)
	(segment
		(start 229.087934 -3.686556)
		(end 229.898702 -2.875788)
		(width 0.14224)
		(layer "In11.Cu")
		(net "M_C_DQS_DN<3>")
	)
	(segment
		(start 229.870254 -8.255)
		(end 230.0224 -8.407146)
		(width 0.14224)
		(layer "In11.Cu")
		(net "M_C_DQS_DN<3>")
	)
	(segment
		(start 249.860054 -58.857388)
		(end 249.855228 -58.866024)
		(width 0.0889)
		(layer "In11.Cu")
		(net "M_C_DQS_DN<3>")
	)
	(segment
		(start 247.937782 -51.675538)
		(end 249.119136 -52.856892)
		(width 0.0889)
		(layer "In11.Cu")
		(net "M_C_DQS_DN<3>")
	)
	(segment
		(start 230.027734 -9.8044)
		(end 229.870254 -9.96188)
		(width 0.14224)
		(layer "In11.Cu")
		(net "M_C_DQS_DN<3>")
	)
	(segment
		(start 249.866404 -61.81852)
		(end 249.860054 -61.829188)
		(width 0.0889)
		(layer "In11.Cu")
		(net "M_C_DQS_DN<3>")
	)
	(segment
		(start 249.860054 -65.791588)
		(end 249.855228 -65.800224)
		(width 0.0889)
		(layer "In11.Cu")
		(net "M_C_DQS_DN<3>")
	)
	(segment
		(start 249.413522 -67.074288)
		(end 249.348244 -67.139566)
		(width 0.0889)
		(layer "In11.Cu")
		(net "M_C_DQS_DN<3>")
	)
	(segment
		(start 249.866404 -64.79032)
		(end 249.860054 -64.800988)
		(width 0.0889)
		(layer "In11.Cu")
		(net "M_C_DQS_DN<3>")
	)
	(segment
		(start 229.870254 -9.39292)
		(end 230.027734 -9.5504)
		(width 0.14224)
		(layer "In11.Cu")
		(net "M_C_DQS_DN<3>")
	)
	(segment
		(start 229.038658 -5.280152)
		(end 229.286054 -5.527548)
		(width 0.14224)
		(layer "In11.Cu")
		(net "M_C_DQS_DN<3>")
	)
	(segment
		(start 249.820938 -55.227474)
		(end 249.860054 -55.295038)
		(width 0.0889)
		(layer "In11.Cu")
		(net "M_C_DQS_DN<3>")
	)
	(segment
		(start 249.860054 -56.876188)
		(end 249.855228 -56.884824)
		(width 0.0889)
		(layer "In11.Cu")
		(net "M_C_DQS_DN<3>")
	)
	(segment
		(start 249.860054 -60.838588)
		(end 249.855228 -60.847224)
		(width 0.0889)
		(layer "In11.Cu")
		(net "M_C_DQS_DN<3>")
	)
	(segment
		(start 249.866404 -55.87492)
		(end 249.860054 -55.885588)
		(width 0.0889)
		(layer "In11.Cu")
		(net "M_C_DQS_DN<3>")
	)
	(segment
		(start 249.860054 -59.847988)
		(end 249.855228 -59.856624)
		(width 0.0889)
		(layer "In11.Cu")
		(net "M_C_DQS_DN<3>")
	)
	(segment
		(start 229.286054 -5.527548)
		(end 229.508558 -5.527548)
		(width 0.14224)
		(layer "In11.Cu")
		(net "M_C_DQS_DN<3>")
	)
	(segment
		(start 249.866404 -56.86552)
		(end 249.860054 -56.876188)
		(width 0.0889)
		(layer "In11.Cu")
		(net "M_C_DQS_DN<3>")
	)
	(segment
		(start 249.119136 -52.856892)
		(end 249.119136 -54.109112)
		(width 0.0889)
		(layer "In11.Cu")
		(net "M_C_DQS_DN<3>")
	)
	(segment
		(start 229.551738 -4.15036)
		(end 229.551738 -4.5466)
		(width 0.14224)
		(layer "In11.Cu")
		(net "M_C_DQS_DN<3>")
	)
	(segment
		(start 235.722922 -37.240972)
		(end 247.13946 -48.65751)
		(width 0.14224)
		(layer "In11.Cu")
		(net "M_C_DQS_DN<3>")
	)
	(segment
		(start 229.870254 -29.024326)
		(end 235.722922 -34.876994)
		(width 0.14224)
		(layer "In11.Cu")
		(net "M_C_DQS_DN<3>")
	)
	(segment
		(start 229.038658 -5.05968)
		(end 229.038658 -5.280152)
		(width 0.14224)
		(layer "In11.Cu")
		(net "M_C_DQS_DN<3>")
	)
	(segment
		(start 247.768872 -49.855374)
		(end 247.78462 -49.871122)
		(width 0.0889)
		(layer "In11.Cu")
		(net "M_C_DQS_DN<3>")
	)
	(segment
		(start 249.348244 -67.139566)
		(end 249.348244 -67.47764)
		(width 0.0889)
		(layer "In11.Cu")
		(net "M_C_DQS_DN<3>")
	)
	(segment
		(start 235.722922 -34.876994)
		(end 235.722922 -37.240972)
		(width 0.14224)
		(layer "In11.Cu")
		(net "M_C_DQS_DN<3>")
	)
	(segment
		(start 230.027734 -10.3124)
		(end 230.027734 -10.5664)
		(width 0.14224)
		(layer "In11.Cu")
		(net "M_C_DQS_DN<3>")
	)
	(segment
		(start 229.087934 -3.686556)
		(end 229.551738 -4.15036)
		(width 0.14224)
		(layer "In11.Cu")
		(net "M_C_DQS_DN<3>")
	)
	(segment
		(start 229.898702 -2.875788)
		(end 229.898702 1.033272)
		(width 0.14224)
		(layer "In11.Cu")
		(net "M_C_DQS_DN<3>")
	)
	(segment
		(start 230.0224 -8.407146)
		(end 230.0224 -8.610854)
		(width 0.14224)
		(layer "In11.Cu")
		(net "M_C_DQS_DN<3>")
	)
	(segment
		(start 249.866404 -63.79972)
		(end 249.860054 -63.810388)
		(width 0.0889)
		(layer "In11.Cu")
		(net "M_C_DQS_DN<3>")
	)
	(segment
		(start 229.870254 -6.111748)
		(end 229.870254 -8.255)
		(width 0.14224)
		(layer "In11.Cu")
		(net "M_C_DQS_DN<3>")
	)
	(segment
		(start 229.508558 -5.527548)
		(end 229.68839 -5.70738)
		(width 0.14224)
		(layer "In11.Cu")
		(net "M_C_DQS_DN<3>")
	)
	(segment
		(start 249.860054 -58.266838)
		(end 249.866404 -58.277506)
		(width 0.0889)
		(layer "In11.Cu")
		(net "M_C_DQS_DN<3>")
	)
	(segment
		(start 247.13946 -48.65751)
		(end 247.13946 -49.225962)
		(width 0.14224)
		(layer "In11.Cu")
		(net "M_C_DQS_DN<3>")
	)
	(segment
		(start 229.870254 -10.72388)
		(end 229.870254 -29.024326)
		(width 0.14224)
		(layer "In11.Cu")
		(net "M_C_DQS_DN<3>")
	)
	(segment
		(start 249.860054 -63.810388)
		(end 249.855228 -63.819024)
		(width 0.0889)
		(layer "In11.Cu")
		(net "M_C_DQS_DN<3>")
	)
	(segment
		(start 249.860054 -61.829188)
		(end 249.855228 -61.837824)
		(width 0.0889)
		(layer "In11.Cu")
		(net "M_C_DQS_DN<3>")
	)
	(segment
		(start 229.898702 1.033272)
		(end 229.087934 1.84404)
		(width 0.14224)
		(layer "In11.Cu")
		(net "M_C_DQS_DN<3>")
	)
	(segment
		(start 247.937782 -50.080164)
		(end 247.937782 -51.675538)
		(width 0.0889)
		(layer "In11.Cu")
		(net "M_C_DQS_DN<3>")
	)
	(segment
		(start 249.383804 -54.37378)
		(end 249.383804 -54.79034)
		(width 0.0889)
		(layer "In11.Cu")
		(net "M_C_DQS_DN<3>")
	)
	(segment
		(start 249.383804 -54.79034)
		(end 249.820938 -55.227474)
		(width 0.0889)
		(layer "In11.Cu")
		(net "M_C_DQS_DN<3>")
	)
	(segment
		(start 229.68839 -5.929884)
		(end 229.870254 -6.111748)
		(width 0.14224)
		(layer "In11.Cu")
		(net "M_C_DQS_DN<3>")
	)
	(segment
		(start 247.78462 -49.871122)
		(end 247.78462 -49.927002)
		(width 0.0889)
		(layer "In11.Cu")
		(net "M_C_DQS_DN<3>")
	)
	(segment
		(start 229.870254 -9.96188)
		(end 229.870254 -10.15492)
		(width 0.14224)
		(layer "In11.Cu")
		(net "M_C_DQS_DN<3>")
	)
	(segment
		(start 249.119136 -54.109112)
		(end 249.383804 -54.37378)
		(width 0.0889)
		(layer "In11.Cu")
		(net "M_C_DQS_DN<3>")
	)
	(segment
		(start 229.68839 -5.70738)
		(end 229.68839 -5.929884)
		(width 0.14224)
		(layer "In11.Cu")
		(net "M_C_DQS_DN<3>")
	)
	(segment
		(start 249.866404 -59.83732)
		(end 249.860054 -59.847988)
		(width 0.0889)
		(layer "In11.Cu")
		(net "M_C_DQS_DN<3>")
	)
	(segment
		(start 249.860054 -64.800988)
		(end 249.855228 -64.809624)
		(width 0.0889)
		(layer "In11.Cu")
		(net "M_C_DQS_DN<3>")
	)
	(arc
		(start 249.855228 -62.828424)
		(mid 249.806473 -63.024776)
		(end 249.860054 -63.219838)
		(width 0.0889)
		(layer "In11.Cu")
		(net "M_C_DQS_DN<3>")
	)
	(arc
		(start 249.855228 -63.819024)
		(mid 249.806473 -64.015376)
		(end 249.860054 -64.210438)
		(width 0.0889)
		(layer "In11.Cu")
		(net "M_C_DQS_DN<3>")
	)
	(arc
		(start 249.860054 -66.191638)
		(mid 249.875559 -66.75378)
		(end 249.413522 -67.074288)
		(width 0.0889)
		(layer "In11.Cu")
		(net "M_C_DQS_DN<3>")
	)
	(arc
		(start 249.860054 -60.248038)
		(mid 249.939276 -60.537156)
		(end 249.866404 -60.82792)
		(width 0.0889)
		(layer "In11.Cu")
		(net "M_C_DQS_DN<3>")
	)
	(arc
		(start 249.855228 -61.837824)
		(mid 249.806473 -62.034176)
		(end 249.860054 -62.229238)
		(width 0.0889)
		(layer "In11.Cu")
		(net "M_C_DQS_DN<3>")
	)
	(arc
		(start 249.860054 -65.201038)
		(mid 249.939276 -65.490156)
		(end 249.866404 -65.78092)
		(width 0.0889)
		(layer "In11.Cu")
		(net "M_C_DQS_DN<3>")
	)
	(arc
		(start 249.855228 -56.884824)
		(mid 249.806473 -57.081176)
		(end 249.860054 -57.276238)
		(width 0.0889)
		(layer "In11.Cu")
		(net "M_C_DQS_DN<3>")
	)
	(arc
		(start 249.860054 -55.295038)
		(mid 249.939276 -55.584156)
		(end 249.866404 -55.87492)
		(width 0.0889)
		(layer "In11.Cu")
		(net "M_C_DQS_DN<3>")
	)
	(arc
		(start 249.855228 -58.866024)
		(mid 249.806473 -59.062376)
		(end 249.860054 -59.257438)
		(width 0.0889)
		(layer "In11.Cu")
		(net "M_C_DQS_DN<3>")
	)
	(arc
		(start 249.866404 -58.277506)
		(mid 249.939202 -58.568269)
		(end 249.860054 -58.857388)
		(width 0.0889)
		(layer "In11.Cu")
		(net "M_C_DQS_DN<3>")
	)
	(arc
		(start 249.860054 -62.229238)
		(mid 249.939276 -62.518356)
		(end 249.866404 -62.80912)
		(width 0.0889)
		(layer "In11.Cu")
		(net "M_C_DQS_DN<3>")
	)
	(arc
		(start 249.860054 -56.285638)
		(mid 249.939276 -56.574756)
		(end 249.866404 -56.86552)
		(width 0.0889)
		(layer "In11.Cu")
		(net "M_C_DQS_DN<3>")
	)
	(arc
		(start 249.860054 -61.238638)
		(mid 249.939276 -61.527756)
		(end 249.866404 -61.81852)
		(width 0.0889)
		(layer "In11.Cu")
		(net "M_C_DQS_DN<3>")
	)
	(arc
		(start 249.855228 -55.894224)
		(mid 249.806473 -56.090576)
		(end 249.860054 -56.285638)
		(width 0.0889)
		(layer "In11.Cu")
		(net "M_C_DQS_DN<3>")
	)
	(arc
		(start 249.855228 -64.809624)
		(mid 249.806473 -65.005976)
		(end 249.860054 -65.201038)
		(width 0.0889)
		(layer "In11.Cu")
		(net "M_C_DQS_DN<3>")
	)
	(arc
		(start 249.860054 -63.219838)
		(mid 249.939276 -63.508956)
		(end 249.866404 -63.79972)
		(width 0.0889)
		(layer "In11.Cu")
		(net "M_C_DQS_DN<3>")
	)
	(arc
		(start 249.855228 -60.847224)
		(mid 249.806473 -61.043576)
		(end 249.860054 -61.238638)
		(width 0.0889)
		(layer "In11.Cu")
		(net "M_C_DQS_DN<3>")
	)
	(arc
		(start 249.860054 -64.210438)
		(mid 249.939276 -64.499556)
		(end 249.866404 -64.79032)
		(width 0.0889)
		(layer "In11.Cu")
		(net "M_C_DQS_DN<3>")
	)
	(arc
		(start 249.860054 -57.867042)
		(mid 249.806555 -58.06694)
		(end 249.860054 -58.266838)
		(width 0.0889)
		(layer "In11.Cu")
		(net "M_C_DQS_DN<3>")
	)
	(arc
		(start 249.860054 -59.257438)
		(mid 249.939276 -59.546556)
		(end 249.866404 -59.83732)
		(width 0.0889)
		(layer "In11.Cu")
		(net "M_C_DQS_DN<3>")
	)
	(arc
		(start 249.855228 -59.856624)
		(mid 249.806473 -60.052976)
		(end 249.860054 -60.248038)
		(width 0.0889)
		(layer "In11.Cu")
		(net "M_C_DQS_DN<3>")
	)
	(arc
		(start 249.855228 -65.800224)
		(mid 249.806473 -65.996576)
		(end 249.860054 -66.191638)
		(width 0.0889)
		(layer "In11.Cu")
		(net "M_C_DQS_DN<3>")
	)
	(arc
		(start 249.860054 -57.276238)
		(mid 249.939185 -57.57164)
		(end 249.860054 -57.867042)
		(width 0.0889)
		(layer "In11.Cu")
		(net "M_C_DQS_DN<3>")
	)
	(segment
		(start 247.344184 -59.057286)
		(end 246.772684 -59.057286)
		(width 0.0889)
		(layer "F.Cu")
		(net "M_C_DQS_DN<2>")
	)
	(segment
		(start 219.349828 -0.821182)
		(end 219.349828 0.19177)
		(width 0.1651)
		(layer "F.Cu")
		(net "M_C_DQS_DN<2>")
	)
	(segment
		(start 219.350336 -0.821182)
		(end 219.349828 -0.821182)
		(width 0.1651)
		(layer "F.Cu")
		(net "M_C_DQS_DN<2>")
	)
	(segment
		(start 219.084144 0.457454)
		(end 219.084144 1.190244)
		(width 0.1651)
		(layer "F.Cu")
		(net "M_C_DQS_DN<2>")
	)
	(segment
		(start 219.084144 1.190244)
		(end 219.73794 1.84404)
		(width 0.1651)
		(layer "F.Cu")
		(net "M_C_DQS_DN<2>")
	)
	(segment
		(start 219.349828 0.19177)
		(end 219.084144 0.457454)
		(width 0.1651)
		(layer "F.Cu")
		(net "M_C_DQS_DN<2>")
	)
	(via
		(at 219.73794 1.84404)
		(size 0.508)
		(drill 0.254)
		(layers "F.Cu" "B.Cu")
		(net "M_C_DQS_DN<2>")
	)
	(via
		(at 219.73794 -3.686556)
		(size 0.508)
		(drill 0.254)
		(layers "F.Cu" "B.Cu")
		(net "M_C_DQS_DN<2>")
	)
	(via
		(at 246.772684 -59.057286)
		(size 0.508)
		(drill 0.254)
		(layers "F.Cu" "B.Cu")
		(net "M_C_DQS_DN<2>")
	)
	(segment
		(start 219.096844 -3.04546)
		(end 219.73794 -3.686556)
		(width 0.1651)
		(layer "B.Cu")
		(net "M_C_DQS_DN<2>")
	)
	(segment
		(start 219.096844 -2.171954)
		(end 219.096844 -3.04546)
		(width 0.1651)
		(layer "B.Cu")
		(net "M_C_DQS_DN<2>")
	)
	(segment
		(start 219.350336 -1.021842)
		(end 219.349828 -1.021842)
		(width 0.1651)
		(layer "B.Cu")
		(net "M_C_DQS_DN<2>")
	)
	(segment
		(start 219.349828 -1.021842)
		(end 219.349828 -1.91897)
		(width 0.1651)
		(layer "B.Cu")
		(net "M_C_DQS_DN<2>")
	)
	(segment
		(start 219.349828 -1.91897)
		(end 219.096844 -2.171954)
		(width 0.1651)
		(layer "B.Cu")
		(net "M_C_DQS_DN<2>")
	)
	(segment
		(start 232.697528 -46.66615)
		(end 232.991406 -46.960028)
		(width 0.14224)
		(layer "In11.Cu")
		(net "M_C_DQS_DN<2>")
	)
	(segment
		(start 242.469162 -55.99049)
		(end 242.50523 -55.99049)
		(width 0.0889)
		(layer "In11.Cu")
		(net "M_C_DQS_DN<2>")
	)
	(segment
		(start 246.479568 -58.888376)
		(end 246.772684 -59.057286)
		(width 0.0889)
		(layer "In11.Cu")
		(net "M_C_DQS_DN<2>")
	)
	(segment
		(start 219.73794 -3.686556)
		(end 220.201744 -4.15036)
		(width 0.14224)
		(layer "In11.Cu")
		(net "M_C_DQS_DN<2>")
	)
	(segment
		(start 233.333036 -47.13986)
		(end 233.333036 -47.301658)
		(width 0.14224)
		(layer "In11.Cu")
		(net "M_C_DQS_DN<2>")
	)
	(segment
		(start 233.333036 -47.301658)
		(end 233.665014 -47.633636)
		(width 0.14224)
		(layer "In11.Cu")
		(net "M_C_DQS_DN<2>")
	)
	(segment
		(start 234.006644 -47.813468)
		(end 234.006644 -47.975266)
		(width 0.14224)
		(layer "In11.Cu")
		(net "M_C_DQS_DN<2>")
	)
	(segment
		(start 236.423962 -50.083974)
		(end 236.423962 -50.139346)
		(width 0.0889)
		(layer "In11.Cu")
		(net "M_C_DQS_DN<2>")
	)
	(segment
		(start 236.408214 -50.068226)
		(end 236.423962 -50.083974)
		(width 0.0889)
		(layer "In11.Cu")
		(net "M_C_DQS_DN<2>")
	)
	(segment
		(start 244.185948 -56.98109)
		(end 244.218714 -56.98109)
		(width 0.0889)
		(layer "In11.Cu")
		(net "M_C_DQS_DN<2>")
	)
	(segment
		(start 235.892594 -49.552352)
		(end 236.408214 -50.068226)
		(width 0.14224)
		(layer "In11.Cu")
		(net "M_C_DQS_DN<2>")
	)
	(segment
		(start 219.688664 -5.05968)
		(end 219.688664 -5.280152)
		(width 0.14224)
		(layer "In11.Cu")
		(net "M_C_DQS_DN<2>")
	)
	(segment
		(start 220.67774 -6.480556)
		(end 220.52026 -6.638036)
		(width 0.14224)
		(layer "In11.Cu")
		(net "M_C_DQS_DN<2>")
	)
	(segment
		(start 220.158564 -5.527548)
		(end 220.338396 -5.70738)
		(width 0.14224)
		(layer "In11.Cu")
		(net "M_C_DQS_DN<2>")
	)
	(segment
		(start 236.988858 -52.40782)
		(end 236.982508 -52.418488)
		(width 0.0889)
		(layer "In11.Cu")
		(net "M_C_DQS_DN<2>")
	)
	(segment
		(start 220.548708 -2.875788)
		(end 220.548708 1.033272)
		(width 0.14224)
		(layer "In11.Cu")
		(net "M_C_DQS_DN<2>")
	)
	(segment
		(start 233.665014 -47.633636)
		(end 233.826812 -47.633636)
		(width 0.14224)
		(layer "In11.Cu")
		(net "M_C_DQS_DN<2>")
	)
	(segment
		(start 240.752122 -54.99989)
		(end 240.784888 -54.99989)
		(width 0.0889)
		(layer "In11.Cu")
		(net "M_C_DQS_DN<2>")
	)
	(segment
		(start 241.606832 -55.494936)
		(end 241.639598 -55.494936)
		(width 0.0889)
		(layer "In11.Cu")
		(net "M_C_DQS_DN<2>")
	)
	(segment
		(start 239.035082 -54.00929)
		(end 239.067848 -54.00929)
		(width 0.0889)
		(layer "In11.Cu")
		(net "M_C_DQS_DN<2>")
	)
	(segment
		(start 236.806232 -50.521616)
		(end 236.988858 -50.848006)
		(width 0.0889)
		(layer "In11.Cu")
		(net "M_C_DQS_DN<2>")
	)
	(segment
		(start 245.040658 -57.476136)
		(end 245.068598 -57.476136)
		(width 0.0889)
		(layer "In11.Cu")
		(net "M_C_DQS_DN<2>")
	)
	(segment
		(start 220.548708 1.033272)
		(end 219.73794 1.84404)
		(width 0.14224)
		(layer "In11.Cu")
		(net "M_C_DQS_DN<2>")
	)
	(segment
		(start 220.201744 -4.15036)
		(end 220.201744 -4.5466)
		(width 0.14224)
		(layer "In11.Cu")
		(net "M_C_DQS_DN<2>")
	)
	(segment
		(start 237.318042 -53.018436)
		(end 237.342172 -53.018436)
		(width 0.0889)
		(layer "In11.Cu")
		(net "M_C_DQS_DN<2>")
	)
	(segment
		(start 238.172752 -53.513736)
		(end 238.205518 -53.513736)
		(width 0.0889)
		(layer "In11.Cu")
		(net "M_C_DQS_DN<2>")
	)
	(segment
		(start 219.688664 -5.280152)
		(end 219.93606 -5.527548)
		(width 0.14224)
		(layer "In11.Cu")
		(net "M_C_DQS_DN<2>")
	)
	(segment
		(start 219.73794 -3.686556)
		(end 220.548708 -2.875788)
		(width 0.14224)
		(layer "In11.Cu")
		(net "M_C_DQS_DN<2>")
	)
	(segment
		(start 220.338396 -5.929884)
		(end 220.67774 -6.269228)
		(width 0.14224)
		(layer "In11.Cu")
		(net "M_C_DQS_DN<2>")
	)
	(segment
		(start 220.52026 -33.501838)
		(end 232.697528 -45.679106)
		(width 0.14224)
		(layer "In11.Cu")
		(net "M_C_DQS_DN<2>")
	)
	(segment
		(start 245.89613 -57.971436)
		(end 245.931944 -57.971436)
		(width 0.0889)
		(layer "In11.Cu")
		(net "M_C_DQS_DN<2>")
	)
	(segment
		(start 220.338396 -5.70738)
		(end 220.338396 -5.929884)
		(width 0.14224)
		(layer "In11.Cu")
		(net "M_C_DQS_DN<2>")
	)
	(segment
		(start 219.93606 -5.527548)
		(end 220.158564 -5.527548)
		(width 0.14224)
		(layer "In11.Cu")
		(net "M_C_DQS_DN<2>")
	)
	(segment
		(start 220.52026 -6.638036)
		(end 220.52026 -33.501838)
		(width 0.14224)
		(layer "In11.Cu")
		(net "M_C_DQS_DN<2>")
	)
	(segment
		(start 236.977682 -51.819302)
		(end 236.982508 -51.827938)
		(width 0.0889)
		(layer "In11.Cu")
		(net "M_C_DQS_DN<2>")
	)
	(segment
		(start 232.991406 -46.960028)
		(end 233.153204 -46.960028)
		(width 0.14224)
		(layer "In11.Cu")
		(net "M_C_DQS_DN<2>")
	)
	(segment
		(start 220.201744 -4.5466)
		(end 219.688664 -5.05968)
		(width 0.14224)
		(layer "In11.Cu")
		(net "M_C_DQS_DN<2>")
	)
	(segment
		(start 243.338604 -56.485536)
		(end 243.356384 -56.485536)
		(width 0.0889)
		(layer "In11.Cu")
		(net "M_C_DQS_DN<2>")
	)
	(segment
		(start 246.455692 -58.798968)
		(end 246.479568 -58.888376)
		(width 0.0889)
		(layer "In11.Cu")
		(net "M_C_DQS_DN<2>")
	)
	(segment
		(start 232.697528 -45.679106)
		(end 232.697528 -46.66615)
		(width 0.14224)
		(layer "In11.Cu")
		(net "M_C_DQS_DN<2>")
	)
	(segment
		(start 242.992148 -56.285384)
		(end 242.99545 -56.291226)
		(width 0.0889)
		(layer "In11.Cu")
		(net "M_C_DQS_DN<2>")
	)
	(segment
		(start 239.889792 -54.504336)
		(end 239.922558 -54.504336)
		(width 0.0889)
		(layer "In11.Cu")
		(net "M_C_DQS_DN<2>")
	)
	(segment
		(start 234.006644 -47.975266)
		(end 234.303062 -48.271684)
		(width 0.14224)
		(layer "In11.Cu")
		(net "M_C_DQS_DN<2>")
	)
	(segment
		(start 233.826812 -47.633636)
		(end 234.006644 -47.813468)
		(width 0.14224)
		(layer "In11.Cu")
		(net "M_C_DQS_DN<2>")
	)
	(segment
		(start 236.423962 -50.139346)
		(end 236.806232 -50.521616)
		(width 0.0889)
		(layer "In11.Cu")
		(net "M_C_DQS_DN<2>")
	)
	(segment
		(start 233.153204 -46.960028)
		(end 233.333036 -47.13986)
		(width 0.14224)
		(layer "In11.Cu")
		(net "M_C_DQS_DN<2>")
	)
	(segment
		(start 234.303062 -48.271684)
		(end 235.892594 -49.552352)
		(width 0.14224)
		(layer "In11.Cu")
		(net "M_C_DQS_DN<2>")
	)
	(segment
		(start 220.67774 -6.269228)
		(end 220.67774 -6.480556)
		(width 0.14224)
		(layer "In11.Cu")
		(net "M_C_DQS_DN<2>")
	)
	(arc
		(start 239.067848 -54.00929)
		(mid 239.351065 -54.093571)
		(end 239.558068 -54.304438)
		(width 0.0889)
		(layer "In11.Cu")
		(net "M_C_DQS_DN<2>")
	)
	(arc
		(start 237.342172 -53.018436)
		(mid 237.630317 -53.100755)
		(end 237.841028 -53.313838)
		(width 0.0889)
		(layer "In11.Cu")
		(net "M_C_DQS_DN<2>")
	)
	(arc
		(start 245.931944 -57.971436)
		(mid 246.413655 -58.246045)
		(end 246.455692 -58.798968)
		(width 0.0889)
		(layer "In11.Cu")
		(net "M_C_DQS_DN<2>")
	)
	(arc
		(start 242.133628 -55.790338)
		(mid 242.275311 -55.934142)
		(end 242.469162 -55.99049)
		(width 0.0889)
		(layer "In11.Cu")
		(net "M_C_DQS_DN<2>")
	)
	(arc
		(start 236.982508 -52.418488)
		(mid 236.979925 -52.813735)
		(end 237.318042 -53.018436)
		(width 0.0889)
		(layer "In11.Cu")
		(net "M_C_DQS_DN<2>")
	)
	(arc
		(start 236.988858 -50.848006)
		(mid 237.061656 -51.138769)
		(end 236.982508 -51.427888)
		(width 0.0889)
		(layer "In11.Cu")
		(net "M_C_DQS_DN<2>")
	)
	(arc
		(start 240.784888 -54.99989)
		(mid 241.068105 -55.084171)
		(end 241.275108 -55.295038)
		(width 0.0889)
		(layer "In11.Cu")
		(net "M_C_DQS_DN<2>")
	)
	(arc
		(start 236.982508 -51.427888)
		(mid 236.929038 -51.622951)
		(end 236.977682 -51.819302)
		(width 0.0889)
		(layer "In11.Cu")
		(net "M_C_DQS_DN<2>")
	)
	(arc
		(start 238.699548 -53.809138)
		(mid 238.841231 -53.952942)
		(end 239.035082 -54.00929)
		(width 0.0889)
		(layer "In11.Cu")
		(net "M_C_DQS_DN<2>")
	)
	(arc
		(start 241.639598 -55.494936)
		(mid 241.925022 -55.578403)
		(end 242.133628 -55.790338)
		(width 0.0889)
		(layer "In11.Cu")
		(net "M_C_DQS_DN<2>")
	)
	(arc
		(start 243.850414 -56.780938)
		(mid 243.992097 -56.924742)
		(end 244.185948 -56.98109)
		(width 0.0889)
		(layer "In11.Cu")
		(net "M_C_DQS_DN<2>")
	)
	(arc
		(start 237.841028 -53.313838)
		(mid 237.981107 -53.456574)
		(end 238.172752 -53.513736)
		(width 0.0889)
		(layer "In11.Cu")
		(net "M_C_DQS_DN<2>")
	)
	(arc
		(start 242.50523 -55.99049)
		(mid 242.78653 -56.075456)
		(end 242.992148 -56.285384)
		(width 0.0889)
		(layer "In11.Cu")
		(net "M_C_DQS_DN<2>")
	)
	(arc
		(start 238.205518 -53.513736)
		(mid 238.490942 -53.597203)
		(end 238.699548 -53.809138)
		(width 0.0889)
		(layer "In11.Cu")
		(net "M_C_DQS_DN<2>")
	)
	(arc
		(start 245.567454 -57.771538)
		(mid 245.706198 -57.913571)
		(end 245.89613 -57.971436)
		(width 0.0889)
		(layer "In11.Cu")
		(net "M_C_DQS_DN<2>")
	)
	(arc
		(start 243.356384 -56.485536)
		(mid 243.641808 -56.569003)
		(end 243.850414 -56.780938)
		(width 0.0889)
		(layer "In11.Cu")
		(net "M_C_DQS_DN<2>")
	)
	(arc
		(start 239.558068 -54.304438)
		(mid 239.698147 -54.447174)
		(end 239.889792 -54.504336)
		(width 0.0889)
		(layer "In11.Cu")
		(net "M_C_DQS_DN<2>")
	)
	(arc
		(start 236.982508 -51.827938)
		(mid 237.06173 -52.117056)
		(end 236.988858 -52.40782)
		(width 0.0889)
		(layer "In11.Cu")
		(net "M_C_DQS_DN<2>")
	)
	(arc
		(start 241.275108 -55.295038)
		(mid 241.415187 -55.437774)
		(end 241.606832 -55.494936)
		(width 0.0889)
		(layer "In11.Cu")
		(net "M_C_DQS_DN<2>")
	)
	(arc
		(start 245.068598 -57.476136)
		(mid 245.356743 -57.558455)
		(end 245.567454 -57.771538)
		(width 0.0889)
		(layer "In11.Cu")
		(net "M_C_DQS_DN<2>")
	)
	(arc
		(start 240.416588 -54.799738)
		(mid 240.558271 -54.943542)
		(end 240.752122 -54.99989)
		(width 0.0889)
		(layer "In11.Cu")
		(net "M_C_DQS_DN<2>")
	)
	(arc
		(start 239.922558 -54.504336)
		(mid 240.207982 -54.587803)
		(end 240.416588 -54.799738)
		(width 0.0889)
		(layer "In11.Cu")
		(net "M_C_DQS_DN<2>")
	)
	(arc
		(start 242.99545 -56.291226)
		(mid 243.141416 -56.433625)
		(end 243.338604 -56.485536)
		(width 0.0889)
		(layer "In11.Cu")
		(net "M_C_DQS_DN<2>")
	)
	(arc
		(start 244.708934 -57.276238)
		(mid 244.849013 -57.418974)
		(end 245.040658 -57.476136)
		(width 0.0889)
		(layer "In11.Cu")
		(net "M_C_DQS_DN<2>")
	)
	(arc
		(start 244.218714 -56.98109)
		(mid 244.501931 -57.065371)
		(end 244.708934 -57.276238)
		(width 0.0889)
		(layer "In11.Cu")
		(net "M_C_DQS_DN<2>")
	)
	(segment
		(start 209.73415 0.457454)
		(end 209.73415 1.190244)
		(width 0.1651)
		(layer "F.Cu")
		(net "M_C_DQS_DN<1>")
	)
	(segment
		(start 209.999834 -0.821182)
		(end 209.999834 0.19177)
		(width 0.1651)
		(layer "F.Cu")
		(net "M_C_DQS_DN<1>")
	)
	(segment
		(start 210.000342 -0.821182)
		(end 209.999834 -0.821182)
		(width 0.1651)
		(layer "F.Cu")
		(net "M_C_DQS_DN<1>")
	)
	(segment
		(start 209.999834 0.19177)
		(end 209.73415 0.457454)
		(width 0.1651)
		(layer "F.Cu")
		(net "M_C_DQS_DN<1>")
	)
	(segment
		(start 243.051838 -59.55284)
		(end 242.480338 -59.55284)
		(width 0.0889)
		(layer "F.Cu")
		(net "M_C_DQS_DN<1>")
	)
	(segment
		(start 209.73415 1.190244)
		(end 210.387946 1.84404)
		(width 0.1651)
		(layer "F.Cu")
		(net "M_C_DQS_DN<1>")
	)
	(via
		(at 210.387946 -3.686556)
		(size 0.508)
		(drill 0.254)
		(layers "F.Cu" "B.Cu")
		(net "M_C_DQS_DN<1>")
	)
	(via
		(at 242.480338 -59.55284)
		(size 0.508)
		(drill 0.254)
		(layers "F.Cu" "B.Cu")
		(net "M_C_DQS_DN<1>")
	)
	(via
		(at 210.387946 1.84404)
		(size 0.508)
		(drill 0.254)
		(layers "F.Cu" "B.Cu")
		(net "M_C_DQS_DN<1>")
	)
	(segment
		(start 209.999834 -1.021842)
		(end 209.999834 -1.91897)
		(width 0.1651)
		(layer "B.Cu")
		(net "M_C_DQS_DN<1>")
	)
	(segment
		(start 210.000342 -1.021842)
		(end 209.999834 -1.021842)
		(width 0.1651)
		(layer "B.Cu")
		(net "M_C_DQS_DN<1>")
	)
	(segment
		(start 209.999834 -1.91897)
		(end 209.74685 -2.171954)
		(width 0.1651)
		(layer "B.Cu")
		(net "M_C_DQS_DN<1>")
	)
	(segment
		(start 209.74685 -3.04546)
		(end 210.387946 -3.686556)
		(width 0.1651)
		(layer "B.Cu")
		(net "M_C_DQS_DN<1>")
	)
	(segment
		(start 209.74685 -2.171954)
		(end 209.74685 -3.04546)
		(width 0.1651)
		(layer "B.Cu")
		(net "M_C_DQS_DN<1>")
	)
	(segment
		(start 210.07832 -32.948626)
		(end 211.04352 -33.913826)
		(width 0.14224)
		(layer "In11.Cu")
		(net "M_C_DQS_DN<1>")
	)
	(segment
		(start 210.387946 1.84404)
		(end 211.198714 1.033272)
		(width 0.14224)
		(layer "In11.Cu")
		(net "M_C_DQS_DN<1>")
	)
	(segment
		(start 228.189028 -53.8353)
		(end 228.350826 -53.8353)
		(width 0.14224)
		(layer "In11.Cu")
		(net "M_C_DQS_DN<1>")
	)
	(segment
		(start 226.74199 -52.226718)
		(end 226.74199 -52.388262)
		(width 0.14224)
		(layer "In11.Cu")
		(net "M_C_DQS_DN<1>")
	)
	(segment
		(start 230.469948 -55.922672)
		(end 230.481124 -55.933848)
		(width 0.0889)
		(layer "In11.Cu")
		(net "M_C_DQS_DN<1>")
	)
	(segment
		(start 228.530658 -54.015132)
		(end 228.530658 -54.17693)
		(width 0.14224)
		(layer "In11.Cu")
		(net "M_C_DQS_DN<1>")
	)
	(segment
		(start 230.2764 -55.922672)
		(end 230.458772 -55.922672)
		(width 0.14224)
		(layer "In11.Cu")
		(net "M_C_DQS_DN<1>")
	)
	(segment
		(start 238.172752 -59.457336)
		(end 238.205518 -59.457336)
		(width 0.0889)
		(layer "In11.Cu")
		(net "M_C_DQS_DN<1>")
	)
	(segment
		(start 230.49357 -55.966614)
		(end 232.519982 -55.966614)
		(width 0.0889)
		(layer "In11.Cu")
		(net "M_C_DQS_DN<1>")
	)
	(segment
		(start 234.029758 -57.47639)
		(end 234.76712 -57.47639)
		(width 0.0889)
		(layer "In11.Cu")
		(net "M_C_DQS_DN<1>")
	)
	(segment
		(start 218.790012 -43.443398)
		(end 218.790012 -44.436284)
		(width 0.14224)
		(layer "In11.Cu")
		(net "M_C_DQS_DN<1>")
	)
	(segment
		(start 230.481124 -55.954168)
		(end 230.49357 -55.966614)
		(width 0.0889)
		(layer "In11.Cu")
		(net "M_C_DQS_DN<1>")
	)
	(segment
		(start 216.118948 -40.376094)
		(end 216.118948 -40.772334)
		(width 0.14224)
		(layer "In11.Cu")
		(net "M_C_DQS_DN<1>")
	)
	(segment
		(start 228.530658 -54.17693)
		(end 228.891592 -54.537864)
		(width 0.14224)
		(layer "In11.Cu")
		(net "M_C_DQS_DN<1>")
	)
	(segment
		(start 211.170266 -26.022808)
		(end 210.02752 -27.165554)
		(width 0.14224)
		(layer "In11.Cu")
		(net "M_C_DQS_DN<1>")
	)
	(segment
		(start 210.85175 -4.15036)
		(end 210.85175 -4.5466)
		(width 0.14224)
		(layer "In11.Cu")
		(net "M_C_DQS_DN<1>")
	)
	(segment
		(start 210.07832 -32.396684)
		(end 210.07832 -32.948626)
		(width 0.14224)
		(layer "In11.Cu")
		(net "M_C_DQS_DN<1>")
	)
	(segment
		(start 210.988402 -5.929884)
		(end 211.327746 -6.269228)
		(width 0.14224)
		(layer "In11.Cu")
		(net "M_C_DQS_DN<1>")
	)
	(segment
		(start 210.02752 -27.165554)
		(end 210.02752 -30.338268)
		(width 0.14224)
		(layer "In11.Cu")
		(net "M_C_DQS_DN<1>")
	)
	(segment
		(start 228.350826 -53.8353)
		(end 228.530658 -54.015132)
		(width 0.14224)
		(layer "In11.Cu")
		(net "M_C_DQS_DN<1>")
	)
	(segment
		(start 229.05339 -54.537864)
		(end 229.233222 -54.717696)
		(width 0.14224)
		(layer "In11.Cu")
		(net "M_C_DQS_DN<1>")
	)
	(segment
		(start 211.198714 1.033272)
		(end 211.198714 -2.875788)
		(width 0.14224)
		(layer "In11.Cu")
		(net "M_C_DQS_DN<1>")
	)
	(segment
		(start 234.76712 -57.47639)
		(end 234.766612 -57.476136)
		(width 0.0889)
		(layer "In11.Cu")
		(net "M_C_DQS_DN<1>")
	)
	(segment
		(start 227.08489 -52.569364)
		(end 227.264722 -52.749196)
		(width 0.14224)
		(layer "In11.Cu")
		(net "M_C_DQS_DN<1>")
	)
	(segment
		(start 237.318042 -58.962036)
		(end 237.342172 -58.962036)
		(width 0.0889)
		(layer "In11.Cu")
		(net "M_C_DQS_DN<1>")
	)
	(segment
		(start 218.790012 -44.436284)
		(end 226.400614 -52.046886)
		(width 0.14224)
		(layer "In11.Cu")
		(net "M_C_DQS_DN<1>")
	)
	(segment
		(start 230.481124 -55.933848)
		(end 230.481124 -55.954168)
		(width 0.0889)
		(layer "In11.Cu")
		(net "M_C_DQS_DN<1>")
	)
	(segment
		(start 242.097814 -59.69762)
		(end 242.187222 -59.72175)
		(width 0.0889)
		(layer "In11.Cu")
		(net "M_C_DQS_DN<1>")
	)
	(segment
		(start 210.80857 -5.527548)
		(end 210.988402 -5.70738)
		(width 0.14224)
		(layer "In11.Cu")
		(net "M_C_DQS_DN<1>")
	)
	(segment
		(start 211.04352 -36.392866)
		(end 213.868254 -39.2176)
		(width 0.14224)
		(layer "In11.Cu")
		(net "M_C_DQS_DN<1>")
	)
	(segment
		(start 211.04352 -33.913826)
		(end 211.04352 -36.392866)
		(width 0.14224)
		(layer "In11.Cu")
		(net "M_C_DQS_DN<1>")
	)
	(segment
		(start 239.889792 -60.447936)
		(end 239.919764 -60.447936)
		(width 0.0889)
		(layer "In11.Cu")
		(net "M_C_DQS_DN<1>")
	)
	(segment
		(start 230.458772 -55.922672)
		(end 230.469948 -55.922672)
		(width 0.0889)
		(layer "In11.Cu")
		(net "M_C_DQS_DN<1>")
	)
	(segment
		(start 227.445824 -53.092096)
		(end 227.607368 -53.092096)
		(width 0.14224)
		(layer "In11.Cu")
		(net "M_C_DQS_DN<1>")
	)
	(segment
		(start 227.264722 -52.749196)
		(end 227.264722 -52.910994)
		(width 0.14224)
		(layer "In11.Cu")
		(net "M_C_DQS_DN<1>")
	)
	(segment
		(start 226.562158 -52.046886)
		(end 226.74199 -52.226718)
		(width 0.14224)
		(layer "In11.Cu")
		(net "M_C_DQS_DN<1>")
	)
	(segment
		(start 210.33867 -5.05968)
		(end 210.33867 -5.280152)
		(width 0.14224)
		(layer "In11.Cu")
		(net "M_C_DQS_DN<1>")
	)
	(segment
		(start 210.599274 -32.175196)
		(end 210.299808 -32.175196)
		(width 0.14224)
		(layer "In11.Cu")
		(net "M_C_DQS_DN<1>")
	)
	(segment
		(start 211.327746 -6.269228)
		(end 211.327746 -6.480556)
		(width 0.14224)
		(layer "In11.Cu")
		(net "M_C_DQS_DN<1>")
	)
	(segment
		(start 210.96732 -31.80715)
		(end 210.599274 -32.175196)
		(width 0.14224)
		(layer "In11.Cu")
		(net "M_C_DQS_DN<1>")
	)
	(segment
		(start 210.249008 -30.559756)
		(end 210.563714 -30.559756)
		(width 0.14224)
		(layer "In11.Cu")
		(net "M_C_DQS_DN<1>")
	)
	(segment
		(start 235.594144 -57.971436)
		(end 235.629958 -57.971436)
		(width 0.0889)
		(layer "In11.Cu")
		(net "M_C_DQS_DN<1>")
	)
	(segment
		(start 210.563714 -30.559756)
		(end 210.96732 -30.963362)
		(width 0.14224)
		(layer "In11.Cu")
		(net "M_C_DQS_DN<1>")
	)
	(segment
		(start 210.02752 -30.338268)
		(end 210.249008 -30.559756)
		(width 0.14224)
		(layer "In11.Cu")
		(net "M_C_DQS_DN<1>")
	)
	(segment
		(start 227.607368 -53.092096)
		(end 227.7872 -53.271928)
		(width 0.14224)
		(layer "In11.Cu")
		(net "M_C_DQS_DN<1>")
	)
	(segment
		(start 210.33867 -5.280152)
		(end 210.586066 -5.527548)
		(width 0.14224)
		(layer "In11.Cu")
		(net "M_C_DQS_DN<1>")
	)
	(segment
		(start 211.170266 -6.638036)
		(end 211.170266 -26.022808)
		(width 0.14224)
		(layer "In11.Cu")
		(net "M_C_DQS_DN<1>")
	)
	(segment
		(start 227.7872 -53.433472)
		(end 228.189028 -53.8353)
		(width 0.14224)
		(layer "In11.Cu")
		(net "M_C_DQS_DN<1>")
	)
	(segment
		(start 213.868254 -39.2176)
		(end 214.960454 -39.2176)
		(width 0.14224)
		(layer "In11.Cu")
		(net "M_C_DQS_DN<1>")
	)
	(segment
		(start 211.327746 -6.480556)
		(end 211.170266 -6.638036)
		(width 0.14224)
		(layer "In11.Cu")
		(net "M_C_DQS_DN<1>")
	)
	(segment
		(start 210.988402 -5.70738)
		(end 210.988402 -5.929884)
		(width 0.14224)
		(layer "In11.Cu")
		(net "M_C_DQS_DN<1>")
	)
	(segment
		(start 210.299808 -32.175196)
		(end 210.07832 -32.396684)
		(width 0.14224)
		(layer "In11.Cu")
		(net "M_C_DQS_DN<1>")
	)
	(segment
		(start 232.519982 -55.966614)
		(end 234.029758 -57.47639)
		(width 0.0889)
		(layer "In11.Cu")
		(net "M_C_DQS_DN<1>")
	)
	(segment
		(start 210.96732 -30.963362)
		(end 210.96732 -31.80715)
		(width 0.14224)
		(layer "In11.Cu")
		(net "M_C_DQS_DN<1>")
	)
	(segment
		(start 214.960454 -39.2176)
		(end 216.118948 -40.376094)
		(width 0.14224)
		(layer "In11.Cu")
		(net "M_C_DQS_DN<1>")
	)
	(segment
		(start 240.741708 -59.95289)
		(end 240.774474 -59.95289)
		(width 0.0889)
		(layer "In11.Cu")
		(net "M_C_DQS_DN<1>")
	)
	(segment
		(start 227.264722 -52.910994)
		(end 227.445824 -53.092096)
		(width 0.14224)
		(layer "In11.Cu")
		(net "M_C_DQS_DN<1>")
	)
	(segment
		(start 216.118948 -40.772334)
		(end 218.790012 -43.443398)
		(width 0.14224)
		(layer "In11.Cu")
		(net "M_C_DQS_DN<1>")
	)
	(segment
		(start 210.387946 -3.686556)
		(end 210.85175 -4.15036)
		(width 0.14224)
		(layer "In11.Cu")
		(net "M_C_DQS_DN<1>")
	)
	(segment
		(start 228.891592 -54.537864)
		(end 229.05339 -54.537864)
		(width 0.14224)
		(layer "In11.Cu")
		(net "M_C_DQS_DN<1>")
	)
	(segment
		(start 229.233222 -54.717696)
		(end 229.233222 -54.879494)
		(width 0.14224)
		(layer "In11.Cu")
		(net "M_C_DQS_DN<1>")
	)
	(segment
		(start 226.74199 -52.388262)
		(end 226.923092 -52.569364)
		(width 0.14224)
		(layer "In11.Cu")
		(net "M_C_DQS_DN<1>")
	)
	(segment
		(start 211.198714 -2.875788)
		(end 210.387946 -3.686556)
		(width 0.14224)
		(layer "In11.Cu")
		(net "M_C_DQS_DN<1>")
	)
	(segment
		(start 226.400614 -52.046886)
		(end 226.562158 -52.046886)
		(width 0.14224)
		(layer "In11.Cu")
		(net "M_C_DQS_DN<1>")
	)
	(segment
		(start 239.035082 -59.95289)
		(end 239.067848 -59.95289)
		(width 0.0889)
		(layer "In11.Cu")
		(net "M_C_DQS_DN<1>")
	)
	(segment
		(start 242.187222 -59.72175)
		(end 242.480338 -59.55284)
		(width 0.0889)
		(layer "In11.Cu")
		(net "M_C_DQS_DN<1>")
	)
	(segment
		(start 227.7872 -53.271928)
		(end 227.7872 -53.433472)
		(width 0.14224)
		(layer "In11.Cu")
		(net "M_C_DQS_DN<1>")
	)
	(segment
		(start 236.452664 -58.466736)
		(end 236.492288 -58.466736)
		(width 0.0889)
		(layer "In11.Cu")
		(net "M_C_DQS_DN<1>")
	)
	(segment
		(start 210.586066 -5.527548)
		(end 210.80857 -5.527548)
		(width 0.14224)
		(layer "In11.Cu")
		(net "M_C_DQS_DN<1>")
	)
	(segment
		(start 229.233222 -54.879494)
		(end 230.2764 -55.922672)
		(width 0.14224)
		(layer "In11.Cu")
		(net "M_C_DQS_DN<1>")
	)
	(segment
		(start 210.85175 -4.5466)
		(end 210.33867 -5.05968)
		(width 0.14224)
		(layer "In11.Cu")
		(net "M_C_DQS_DN<1>")
	)
	(segment
		(start 226.923092 -52.569364)
		(end 227.08489 -52.569364)
		(width 0.14224)
		(layer "In11.Cu")
		(net "M_C_DQS_DN<1>")
	)
	(arc
		(start 237.342172 -58.962036)
		(mid 237.630317 -59.044355)
		(end 237.841028 -59.257438)
		(width 0.0889)
		(layer "In11.Cu")
		(net "M_C_DQS_DN<1>")
	)
	(arc
		(start 236.982508 -58.761884)
		(mid 237.124191 -58.905688)
		(end 237.318042 -58.962036)
		(width 0.0889)
		(layer "In11.Cu")
		(net "M_C_DQS_DN<1>")
	)
	(arc
		(start 239.558068 -60.248038)
		(mid 239.698147 -60.390774)
		(end 239.889792 -60.447936)
		(width 0.0889)
		(layer "In11.Cu")
		(net "M_C_DQS_DN<1>")
	)
	(arc
		(start 238.205518 -59.457336)
		(mid 238.490942 -59.540803)
		(end 238.699548 -59.752738)
		(width 0.0889)
		(layer "In11.Cu")
		(net "M_C_DQS_DN<1>")
	)
	(arc
		(start 237.841028 -59.257438)
		(mid 237.981107 -59.400174)
		(end 238.172752 -59.457336)
		(width 0.0889)
		(layer "In11.Cu")
		(net "M_C_DQS_DN<1>")
	)
	(arc
		(start 238.699548 -59.752738)
		(mid 238.841231 -59.896542)
		(end 239.035082 -59.95289)
		(width 0.0889)
		(layer "In11.Cu")
		(net "M_C_DQS_DN<1>")
	)
	(arc
		(start 236.492288 -58.466736)
		(mid 236.775505 -58.551017)
		(end 236.982508 -58.761884)
		(width 0.0889)
		(layer "In11.Cu")
		(net "M_C_DQS_DN<1>")
	)
	(arc
		(start 240.774474 -59.95289)
		(mid 240.968324 -59.89654)
		(end 241.110008 -59.752738)
		(width 0.0889)
		(layer "In11.Cu")
		(net "M_C_DQS_DN<1>")
	)
	(arc
		(start 235.265468 -57.771538)
		(mid 235.404212 -57.913571)
		(end 235.594144 -57.971436)
		(width 0.0889)
		(layer "In11.Cu")
		(net "M_C_DQS_DN<1>")
	)
	(arc
		(start 240.251488 -60.248038)
		(mid 240.458492 -60.037174)
		(end 240.741708 -59.95289)
		(width 0.0889)
		(layer "In11.Cu")
		(net "M_C_DQS_DN<1>")
	)
	(arc
		(start 235.629958 -57.971436)
		(mid 235.915382 -58.054903)
		(end 236.123988 -58.266838)
		(width 0.0889)
		(layer "In11.Cu")
		(net "M_C_DQS_DN<1>")
	)
	(arc
		(start 234.766612 -57.476136)
		(mid 235.054757 -57.558455)
		(end 235.265468 -57.771538)
		(width 0.0889)
		(layer "In11.Cu")
		(net "M_C_DQS_DN<1>")
	)
	(arc
		(start 241.110008 -59.752738)
		(mid 241.588957 -59.457986)
		(end 242.097814 -59.69762)
		(width 0.0889)
		(layer "In11.Cu")
		(net "M_C_DQS_DN<1>")
	)
	(arc
		(start 239.067848 -59.95289)
		(mid 239.351065 -60.037171)
		(end 239.558068 -60.248038)
		(width 0.0889)
		(layer "In11.Cu")
		(net "M_C_DQS_DN<1>")
	)
	(arc
		(start 236.123988 -58.266838)
		(mid 236.262732 -58.408871)
		(end 236.452664 -58.466736)
		(width 0.0889)
		(layer "In11.Cu")
		(net "M_C_DQS_DN<1>")
	)
	(arc
		(start 239.919764 -60.447936)
		(mid 240.111406 -60.39077)
		(end 240.251488 -60.248038)
		(width 0.0889)
		(layer "In11.Cu")
		(net "M_C_DQS_DN<1>")
	)
	(segment
		(start 238.050324 3.778758)
		(end 238.049816 3.778758)
		(width 0.1651)
		(layer "F.Cu")
		(net "M_C_DQS_DN<17>")
	)
	(segment
		(start 237.631732 2.286)
		(end 237.81766 2.100072)
		(width 0.1651)
		(layer "F.Cu")
		(net "M_C_DQS_DN<17>")
	)
	(segment
		(start 237.81766 2.100072)
		(end 237.81766 1.853438)
		(width 0.1651)
		(layer "F.Cu")
		(net "M_C_DQS_DN<17>")
	)
	(segment
		(start 237.168182 1.7907)
		(end 237.149132 1.7907)
		(width 0.1651)
		(layer "F.Cu")
		(net "M_C_DQS_DN<17>")
	)
	(segment
		(start 238.049816 3.778758)
		(end 238.049816 2.93624)
		(width 0.1651)
		(layer "F.Cu")
		(net "M_C_DQS_DN<17>")
	)
	(segment
		(start 237.357412 1.60147)
		(end 237.168182 1.7907)
		(width 0.1651)
		(layer "F.Cu")
		(net "M_C_DQS_DN<17>")
	)
	(segment
		(start 238.049816 2.93624)
		(end 237.631732 2.518156)
		(width 0.1651)
		(layer "F.Cu")
		(net "M_C_DQS_DN<17>")
	)
	(segment
		(start 237.631732 2.518156)
		(end 237.631732 2.286)
		(width 0.1651)
		(layer "F.Cu")
		(net "M_C_DQS_DN<17>")
	)
	(segment
		(start 237.81766 1.853438)
		(end 237.565692 1.60147)
		(width 0.1651)
		(layer "F.Cu")
		(net "M_C_DQS_DN<17>")
	)
	(segment
		(start 245.627144 -66.982086)
		(end 245.055644 -66.982086)
		(width 0.0889)
		(layer "F.Cu")
		(net "M_C_DQS_DN<17>")
	)
	(segment
		(start 237.565692 1.60147)
		(end 237.357412 1.60147)
		(width 0.1651)
		(layer "F.Cu")
		(net "M_C_DQS_DN<17>")
	)
	(via
		(at 237.149132 1.7907)
		(size 0.508)
		(drill 0.254)
		(layers "F.Cu" "B.Cu")
		(net "M_C_DQS_DN<17>")
	)
	(via
		(at 237.142528 -3.6322)
		(size 0.508)
		(drill 0.254)
		(layers "F.Cu" "B.Cu")
		(net "M_C_DQS_DN<17>")
	)
	(via
		(at 245.055644 -66.982086)
		(size 0.508)
		(drill 0.254)
		(layers "F.Cu" "B.Cu")
		(net "M_C_DQS_DN<17>")
	)
	(segment
		(start 238.050324 -5.621782)
		(end 238.049816 -5.621782)
		(width 0.1651)
		(layer "B.Cu")
		(net "M_C_DQS_DN<17>")
	)
	(segment
		(start 237.606332 -4.521454)
		(end 237.606332 -4.1656)
		(width 0.1651)
		(layer "B.Cu")
		(net "M_C_DQS_DN<17>")
	)
	(segment
		(start 237.606332 -4.1656)
		(end 237.784132 -3.9878)
		(width 0.1651)
		(layer "B.Cu")
		(net "M_C_DQS_DN<17>")
	)
	(segment
		(start 237.784132 -3.6576)
		(end 237.564168 -3.437636)
		(width 0.1651)
		(layer "B.Cu")
		(net "M_C_DQS_DN<17>")
	)
	(segment
		(start 237.784132 -3.9878)
		(end 237.784132 -3.6576)
		(width 0.1651)
		(layer "B.Cu")
		(net "M_C_DQS_DN<17>")
	)
	(segment
		(start 238.049816 -5.621782)
		(end 238.049816 -4.964938)
		(width 0.1651)
		(layer "B.Cu")
		(net "M_C_DQS_DN<17>")
	)
	(segment
		(start 237.564168 -3.437636)
		(end 237.337092 -3.437636)
		(width 0.1651)
		(layer "B.Cu")
		(net "M_C_DQS_DN<17>")
	)
	(segment
		(start 238.049816 -4.964938)
		(end 237.606332 -4.521454)
		(width 0.1651)
		(layer "B.Cu")
		(net "M_C_DQS_DN<17>")
	)
	(segment
		(start 237.337092 -3.437636)
		(end 237.142528 -3.6322)
		(width 0.1651)
		(layer "B.Cu")
		(net "M_C_DQS_DN<17>")
	)
	(segment
		(start 243.980462 -46.952662)
		(end 243.818918 -46.791118)
		(width 0.14224)
		(layer "In4.Cu")
		(net "M_C_DQS_DN<17>")
	)
	(segment
		(start 245.003574 -49.3395)
		(end 245.003574 -49.0347)
		(width 0.14224)
		(layer "In4.Cu")
		(net "M_C_DQS_DN<17>")
	)
	(segment
		(start 237.580932 -4.070604)
		(end 237.142528 -3.6322)
		(width 0.14224)
		(layer "In4.Cu")
		(net "M_C_DQS_DN<17>")
	)
	(segment
		(start 237.924848 -6.462268)
		(end 236.940852 -5.478272)
		(width 0.14224)
		(layer "In4.Cu")
		(net "M_C_DQS_DN<17>")
	)
	(segment
		(start 239.33404 -34.411412)
		(end 239.33404 -33.967928)
		(width 0.14224)
		(layer "In4.Cu")
		(net "M_C_DQS_DN<17>")
	)
	(segment
		(start 243.315998 -46.288198)
		(end 243.315998 -46.108366)
		(width 0.14224)
		(layer "In4.Cu")
		(net "M_C_DQS_DN<17>")
	)
	(segment
		(start 244.704108 -61.837824)
		(end 244.708934 -61.829188)
		(width 0.0889)
		(layer "In4.Cu")
		(net "M_C_DQS_DN<17>")
	)
	(segment
		(start 237.924848 -14.71168)
		(end 238.082328 -14.5542)
		(width 0.14224)
		(layer "In4.Cu")
		(net "M_C_DQS_DN<17>")
	)
	(segment
		(start 244.708934 -62.819788)
		(end 244.715284 -62.80912)
		(width 0.0889)
		(layer "In4.Cu")
		(net "M_C_DQS_DN<17>")
	)
	(segment
		(start 244.708934 -65.791588)
		(end 244.715284 -65.78092)
		(width 0.0889)
		(layer "In4.Cu")
		(net "M_C_DQS_DN<17>")
	)
	(segment
		(start 245.130574 -48.9077)
		(end 245.130574 -48.6791)
		(width 0.14224)
		(layer "In4.Cu")
		(net "M_C_DQS_DN<17>")
	)
	(segment
		(start 244.964204 -51.76266)
		(end 244.964204 -49.400968)
		(width 0.0889)
		(layer "In4.Cu")
		(net "M_C_DQS_DN<17>")
	)
	(segment
		(start 244.964204 -49.400968)
		(end 245.003574 -49.361598)
		(width 0.0889)
		(layer "In4.Cu")
		(net "M_C_DQS_DN<17>")
	)
	(segment
		(start 244.715284 -58.277506)
		(end 244.708934 -58.266838)
		(width 0.0889)
		(layer "In4.Cu")
		(net "M_C_DQS_DN<17>")
	)
	(segment
		(start 241.636804 -44.429172)
		(end 241.456972 -44.429172)
		(width 0.14224)
		(layer "In4.Cu")
		(net "M_C_DQS_DN<17>")
	)
	(segment
		(start 240.428272 -33.84804)
		(end 240.70564 -33.570672)
		(width 0.14224)
		(layer "In4.Cu")
		(net "M_C_DQS_DN<17>")
	)
	(segment
		(start 244.704108 -54.903624)
		(end 244.708934 -54.894988)
		(width 0.0889)
		(layer "In4.Cu")
		(net "M_C_DQS_DN<17>")
	)
	(segment
		(start 240.70564 -33.570672)
		(end 240.70564 -32.57296)
		(width 0.14224)
		(layer "In4.Cu")
		(net "M_C_DQS_DN<17>")
	)
	(segment
		(start 239.453928 -33.84804)
		(end 240.428272 -33.84804)
		(width 0.14224)
		(layer "In4.Cu")
		(net "M_C_DQS_DN<17>")
	)
	(segment
		(start 244.321838 -47.114206)
		(end 244.160294 -46.952662)
		(width 0.14224)
		(layer "In4.Cu")
		(net "M_C_DQS_DN<17>")
	)
	(segment
		(start 244.708934 -53.313838)
		(end 244.654324 -53.219096)
		(width 0.0889)
		(layer "In4.Cu")
		(net "M_C_DQS_DN<17>")
	)
	(segment
		(start 244.954044 -52.683156)
		(end 245.072154 -52.565046)
		(width 0.0889)
		(layer "In4.Cu")
		(net "M_C_DQS_DN<17>")
	)
	(segment
		(start 242.301268 -45.093636)
		(end 242.139724 -44.932092)
		(width 0.14224)
		(layer "In4.Cu")
		(net "M_C_DQS_DN<17>")
	)
	(segment
		(start 240.428272 -34.5313)
		(end 239.453928 -34.5313)
		(width 0.14224)
		(layer "In4.Cu")
		(net "M_C_DQS_DN<17>")
	)
	(segment
		(start 236.940852 -4.98348)
		(end 237.123732 -4.8006)
		(width 0.14224)
		(layer "In4.Cu")
		(net "M_C_DQS_DN<17>")
	)
	(segment
		(start 242.804188 -45.596556)
		(end 242.642644 -45.435012)
		(width 0.14224)
		(layer "In4.Cu")
		(net "M_C_DQS_DN<17>")
	)
	(segment
		(start 237.123732 -4.8006)
		(end 237.377732 -4.8006)
		(width 0.14224)
		(layer "In4.Cu")
		(net "M_C_DQS_DN<17>")
	)
	(segment
		(start 242.642644 -45.435012)
		(end 242.462812 -45.435012)
		(width 0.14224)
		(layer "In4.Cu")
		(net "M_C_DQS_DN<17>")
	)
	(segment
		(start 244.160294 -46.952662)
		(end 243.980462 -46.952662)
		(width 0.14224)
		(layer "In4.Cu")
		(net "M_C_DQS_DN<17>")
	)
	(segment
		(start 238.082328 -14.3002)
		(end 237.924848 -14.14272)
		(width 0.14224)
		(layer "In4.Cu")
		(net "M_C_DQS_DN<17>")
	)
	(segment
		(start 236.940852 -5.478272)
		(end 236.940852 -4.98348)
		(width 0.14224)
		(layer "In4.Cu")
		(net "M_C_DQS_DN<17>")
	)
	(segment
		(start 244.321838 -47.294038)
		(end 244.321838 -47.114206)
		(width 0.14224)
		(layer "In4.Cu")
		(net "M_C_DQS_DN<17>")
	)
	(segment
		(start 241.456972 -44.429172)
		(end 241.295428 -44.267628)
		(width 0.14224)
		(layer "In4.Cu")
		(net "M_C_DQS_DN<17>")
	)
	(segment
		(start 243.657374 -46.449742)
		(end 243.477542 -46.449742)
		(width 0.14224)
		(layer "In4.Cu")
		(net "M_C_DQS_DN<17>")
	)
	(segment
		(start 244.704108 -60.847224)
		(end 244.708934 -60.838588)
		(width 0.0889)
		(layer "In4.Cu")
		(net "M_C_DQS_DN<17>")
	)
	(segment
		(start 243.154454 -45.946822)
		(end 242.974622 -45.946822)
		(width 0.14224)
		(layer "In4.Cu")
		(net "M_C_DQS_DN<17>")
	)
	(segment
		(start 245.072154 -51.87061)
		(end 244.964204 -51.76266)
		(width 0.0889)
		(layer "In4.Cu")
		(net "M_C_DQS_DN<17>")
	)
	(segment
		(start 242.139724 -44.932092)
		(end 241.959892 -44.932092)
		(width 0.14224)
		(layer "In4.Cu")
		(net "M_C_DQS_DN<17>")
	)
	(segment
		(start 238.082328 -15.3162)
		(end 238.082328 -15.0622)
		(width 0.14224)
		(layer "In4.Cu")
		(net "M_C_DQS_DN<17>")
	)
	(segment
		(start 241.798348 -44.590716)
		(end 241.636804 -44.429172)
		(width 0.14224)
		(layer "In4.Cu")
		(net "M_C_DQS_DN<17>")
	)
	(segment
		(start 244.704108 -65.800224)
		(end 244.708934 -65.791588)
		(width 0.0889)
		(layer "In4.Cu")
		(net "M_C_DQS_DN<17>")
	)
	(segment
		(start 243.818918 -46.791118)
		(end 243.818918 -46.611286)
		(width 0.14224)
		(layer "In4.Cu")
		(net "M_C_DQS_DN<17>")
	)
	(segment
		(start 244.708934 -55.885588)
		(end 244.715284 -55.87492)
		(width 0.0889)
		(layer "In4.Cu")
		(net "M_C_DQS_DN<17>")
	)
	(segment
		(start 242.974622 -45.946822)
		(end 242.804188 -45.776388)
		(width 0.14224)
		(layer "In4.Cu")
		(net "M_C_DQS_DN<17>")
	)
	(segment
		(start 240.70564 -34.808668)
		(end 240.428272 -34.5313)
		(width 0.14224)
		(layer "In4.Cu")
		(net "M_C_DQS_DN<17>")
	)
	(segment
		(start 243.477542 -46.449742)
		(end 243.315998 -46.288198)
		(width 0.14224)
		(layer "In4.Cu")
		(net "M_C_DQS_DN<17>")
	)
	(segment
		(start 242.804188 -45.776388)
		(end 242.804188 -45.596556)
		(width 0.14224)
		(layer "In4.Cu")
		(net "M_C_DQS_DN<17>")
	)
	(segment
		(start 241.959892 -44.932092)
		(end 241.798348 -44.770548)
		(width 0.14224)
		(layer "In4.Cu")
		(net "M_C_DQS_DN<17>")
	)
	(segment
		(start 237.580932 -4.5974)
		(end 237.580932 -4.070604)
		(width 0.14224)
		(layer "In4.Cu")
		(net "M_C_DQS_DN<17>")
	)
	(segment
		(start 239.33404 -33.967928)
		(end 239.453928 -33.84804)
		(width 0.14224)
		(layer "In4.Cu")
		(net "M_C_DQS_DN<17>")
	)
	(segment
		(start 244.708934 -53.904388)
		(end 244.715284 -53.89372)
		(width 0.0889)
		(layer "In4.Cu")
		(net "M_C_DQS_DN<17>")
	)
	(segment
		(start 244.708934 -59.847988)
		(end 244.715284 -59.83732)
		(width 0.0889)
		(layer "In4.Cu")
		(net "M_C_DQS_DN<17>")
	)
	(segment
		(start 242.462812 -45.435012)
		(end 242.301268 -45.273468)
		(width 0.14224)
		(layer "In4.Cu")
		(net "M_C_DQS_DN<17>")
	)
	(segment
		(start 240.70564 -43.67784)
		(end 240.70564 -34.808668)
		(width 0.14224)
		(layer "In4.Cu")
		(net "M_C_DQS_DN<17>")
	)
	(segment
		(start 240.70564 -32.57296)
		(end 237.924848 -29.792168)
		(width 0.14224)
		(layer "In4.Cu")
		(net "M_C_DQS_DN<17>")
	)
	(segment
		(start 244.680486 -47.472854)
		(end 244.500654 -47.472854)
		(width 0.14224)
		(layer "In4.Cu")
		(net "M_C_DQS_DN<17>")
	)
	(segment
		(start 245.072154 -52.565046)
		(end 245.072154 -51.87061)
		(width 0.0889)
		(layer "In4.Cu")
		(net "M_C_DQS_DN<17>")
	)
	(segment
		(start 244.708934 -54.894988)
		(end 244.715284 -54.88432)
		(width 0.0889)
		(layer "In4.Cu")
		(net "M_C_DQS_DN<17>")
	)
	(segment
		(start 243.818918 -46.611286)
		(end 243.657374 -46.449742)
		(width 0.14224)
		(layer "In4.Cu")
		(net "M_C_DQS_DN<17>")
	)
	(segment
		(start 244.704108 -58.866024)
		(end 244.708934 -58.857388)
		(width 0.0889)
		(layer "In4.Cu")
		(net "M_C_DQS_DN<17>")
	)
	(segment
		(start 245.055644 -66.982086)
		(end 245.053866 -66.978276)
		(width 0.0889)
		(layer "In4.Cu")
		(net "M_C_DQS_DN<17>")
	)
	(segment
		(start 245.003574 -49.0347)
		(end 245.130574 -48.9077)
		(width 0.14224)
		(layer "In4.Cu")
		(net "M_C_DQS_DN<17>")
	)
	(segment
		(start 237.924848 -14.90472)
		(end 237.924848 -14.71168)
		(width 0.14224)
		(layer "In4.Cu")
		(net "M_C_DQS_DN<17>")
	)
	(segment
		(start 244.704108 -59.856624)
		(end 244.708934 -59.847988)
		(width 0.0889)
		(layer "In4.Cu")
		(net "M_C_DQS_DN<17>")
	)
	(segment
		(start 244.708934 -64.800988)
		(end 244.715284 -64.79032)
		(width 0.0889)
		(layer "In4.Cu")
		(net "M_C_DQS_DN<17>")
	)
	(segment
		(start 237.924848 -15.47368)
		(end 238.082328 -15.3162)
		(width 0.14224)
		(layer "In4.Cu")
		(net "M_C_DQS_DN<17>")
	)
	(segment
		(start 244.708934 -60.838588)
		(end 244.715284 -60.82792)
		(width 0.0889)
		(layer "In4.Cu")
		(net "M_C_DQS_DN<17>")
	)
	(segment
		(start 245.130574 -48.6791)
		(end 245.003574 -48.5521)
		(width 0.14224)
		(layer "In4.Cu")
		(net "M_C_DQS_DN<17>")
	)
	(segment
		(start 240.954052 -43.926252)
		(end 240.70564 -43.67784)
		(width 0.14224)
		(layer "In4.Cu")
		(net "M_C_DQS_DN<17>")
	)
	(segment
		(start 244.500654 -47.472854)
		(end 244.321838 -47.294038)
		(width 0.14224)
		(layer "In4.Cu")
		(net "M_C_DQS_DN<17>")
	)
	(segment
		(start 238.082328 -15.0622)
		(end 237.924848 -14.90472)
		(width 0.14224)
		(layer "In4.Cu")
		(net "M_C_DQS_DN<17>")
	)
	(segment
		(start 241.295428 -44.087796)
		(end 241.133884 -43.926252)
		(width 0.14224)
		(layer "In4.Cu")
		(net "M_C_DQS_DN<17>")
	)
	(segment
		(start 243.315998 -46.108366)
		(end 243.154454 -45.946822)
		(width 0.14224)
		(layer "In4.Cu")
		(net "M_C_DQS_DN<17>")
	)
	(segment
		(start 244.84203 -47.634398)
		(end 244.680486 -47.472854)
		(width 0.14224)
		(layer "In4.Cu")
		(net "M_C_DQS_DN<17>")
	)
	(segment
		(start 245.003574 -49.361598)
		(end 245.003574 -49.3395)
		(width 0.0889)
		(layer "In4.Cu")
		(net "M_C_DQS_DN<17>")
	)
	(segment
		(start 237.377732 -4.8006)
		(end 237.580932 -4.5974)
		(width 0.14224)
		(layer "In4.Cu")
		(net "M_C_DQS_DN<17>")
	)
	(segment
		(start 237.924848 -14.14272)
		(end 237.924848 -6.462268)
		(width 0.14224)
		(layer "In4.Cu")
		(net "M_C_DQS_DN<17>")
	)
	(segment
		(start 244.704108 -55.894224)
		(end 244.708934 -55.885588)
		(width 0.0889)
		(layer "In4.Cu")
		(net "M_C_DQS_DN<17>")
	)
	(segment
		(start 244.704108 -64.809624)
		(end 244.708934 -64.800988)
		(width 0.0889)
		(layer "In4.Cu")
		(net "M_C_DQS_DN<17>")
	)
	(segment
		(start 244.708934 -63.810388)
		(end 244.715284 -63.79972)
		(width 0.0889)
		(layer "In4.Cu")
		(net "M_C_DQS_DN<17>")
	)
	(segment
		(start 239.453928 -34.5313)
		(end 239.33404 -34.411412)
		(width 0.14224)
		(layer "In4.Cu")
		(net "M_C_DQS_DN<17>")
	)
	(segment
		(start 245.003574 -48.5521)
		(end 245.003574 -47.975774)
		(width 0.14224)
		(layer "In4.Cu")
		(net "M_C_DQS_DN<17>")
	)
	(segment
		(start 244.654324 -53.219096)
		(end 244.654324 -52.862988)
		(width 0.0889)
		(layer "In4.Cu")
		(net "M_C_DQS_DN<17>")
	)
	(segment
		(start 244.704108 -53.913024)
		(end 244.708934 -53.904388)
		(width 0.0889)
		(layer "In4.Cu")
		(net "M_C_DQS_DN<17>")
	)
	(segment
		(start 244.654324 -52.862988)
		(end 244.834156 -52.683156)
		(width 0.0889)
		(layer "In4.Cu")
		(net "M_C_DQS_DN<17>")
	)
	(segment
		(start 244.708934 -61.829188)
		(end 244.715284 -61.81852)
		(width 0.0889)
		(layer "In4.Cu")
		(net "M_C_DQS_DN<17>")
	)
	(segment
		(start 244.834156 -52.683156)
		(end 244.954044 -52.683156)
		(width 0.0889)
		(layer "In4.Cu")
		(net "M_C_DQS_DN<17>")
	)
	(segment
		(start 244.704108 -62.828424)
		(end 244.708934 -62.819788)
		(width 0.0889)
		(layer "In4.Cu")
		(net "M_C_DQS_DN<17>")
	)
	(segment
		(start 244.704108 -63.819024)
		(end 244.708934 -63.810388)
		(width 0.0889)
		(layer "In4.Cu")
		(net "M_C_DQS_DN<17>")
	)
	(segment
		(start 241.133884 -43.926252)
		(end 240.954052 -43.926252)
		(width 0.14224)
		(layer "In4.Cu")
		(net "M_C_DQS_DN<17>")
	)
	(segment
		(start 238.082328 -14.5542)
		(end 238.082328 -14.3002)
		(width 0.14224)
		(layer "In4.Cu")
		(net "M_C_DQS_DN<17>")
	)
	(segment
		(start 244.84203 -47.81423)
		(end 244.84203 -47.634398)
		(width 0.14224)
		(layer "In4.Cu")
		(net "M_C_DQS_DN<17>")
	)
	(segment
		(start 244.704108 -56.884824)
		(end 244.708934 -56.876188)
		(width 0.0889)
		(layer "In4.Cu")
		(net "M_C_DQS_DN<17>")
	)
	(segment
		(start 241.798348 -44.770548)
		(end 241.798348 -44.590716)
		(width 0.14224)
		(layer "In4.Cu")
		(net "M_C_DQS_DN<17>")
	)
	(segment
		(start 244.708934 -56.876188)
		(end 244.715284 -56.86552)
		(width 0.0889)
		(layer "In4.Cu")
		(net "M_C_DQS_DN<17>")
	)
	(segment
		(start 241.295428 -44.267628)
		(end 241.295428 -44.087796)
		(width 0.14224)
		(layer "In4.Cu")
		(net "M_C_DQS_DN<17>")
	)
	(segment
		(start 242.301268 -45.273468)
		(end 242.301268 -45.093636)
		(width 0.14224)
		(layer "In4.Cu")
		(net "M_C_DQS_DN<17>")
	)
	(segment
		(start 245.003574 -47.975774)
		(end 244.84203 -47.81423)
		(width 0.14224)
		(layer "In4.Cu")
		(net "M_C_DQS_DN<17>")
	)
	(segment
		(start 237.924848 -29.792168)
		(end 237.924848 -15.47368)
		(width 0.14224)
		(layer "In4.Cu")
		(net "M_C_DQS_DN<17>")
	)
	(arc
		(start 244.708934 -57.867042)
		(mid 244.788065 -57.57164)
		(end 244.708934 -57.276238)
		(width 0.0889)
		(layer "In4.Cu")
		(net "M_C_DQS_DN<17>")
	)
	(arc
		(start 244.708934 -56.285638)
		(mid 244.655464 -56.090575)
		(end 244.704108 -55.894224)
		(width 0.0889)
		(layer "In4.Cu")
		(net "M_C_DQS_DN<17>")
	)
	(arc
		(start 244.715284 -53.89372)
		(mid 244.788082 -53.602957)
		(end 244.708934 -53.313838)
		(width 0.0889)
		(layer "In4.Cu")
		(net "M_C_DQS_DN<17>")
	)
	(arc
		(start 244.715284 -61.81852)
		(mid 244.788082 -61.527757)
		(end 244.708934 -61.238638)
		(width 0.0889)
		(layer "In4.Cu")
		(net "M_C_DQS_DN<17>")
	)
	(arc
		(start 244.708934 -65.201038)
		(mid 244.655464 -65.005975)
		(end 244.704108 -64.809624)
		(width 0.0889)
		(layer "In4.Cu")
		(net "M_C_DQS_DN<17>")
	)
	(arc
		(start 244.715284 -65.78092)
		(mid 244.788082 -65.490157)
		(end 244.708934 -65.201038)
		(width 0.0889)
		(layer "In4.Cu")
		(net "M_C_DQS_DN<17>")
	)
	(arc
		(start 244.708934 -58.266838)
		(mid 244.655435 -58.06694)
		(end 244.708934 -57.867042)
		(width 0.0889)
		(layer "In4.Cu")
		(net "M_C_DQS_DN<17>")
	)
	(arc
		(start 244.708934 -63.219838)
		(mid 244.655464 -63.024775)
		(end 244.704108 -62.828424)
		(width 0.0889)
		(layer "In4.Cu")
		(net "M_C_DQS_DN<17>")
	)
	(arc
		(start 244.708934 -62.229238)
		(mid 244.655464 -62.034175)
		(end 244.704108 -61.837824)
		(width 0.0889)
		(layer "In4.Cu")
		(net "M_C_DQS_DN<17>")
	)
	(arc
		(start 244.715284 -59.83732)
		(mid 244.788082 -59.546557)
		(end 244.708934 -59.257438)
		(width 0.0889)
		(layer "In4.Cu")
		(net "M_C_DQS_DN<17>")
	)
	(arc
		(start 244.708934 -54.304438)
		(mid 244.655464 -54.109375)
		(end 244.704108 -53.913024)
		(width 0.0889)
		(layer "In4.Cu")
		(net "M_C_DQS_DN<17>")
	)
	(arc
		(start 244.708934 -64.210438)
		(mid 244.655464 -64.015375)
		(end 244.704108 -63.819024)
		(width 0.0889)
		(layer "In4.Cu")
		(net "M_C_DQS_DN<17>")
	)
	(arc
		(start 244.708934 -57.276238)
		(mid 244.655464 -57.081175)
		(end 244.704108 -56.884824)
		(width 0.0889)
		(layer "In4.Cu")
		(net "M_C_DQS_DN<17>")
	)
	(arc
		(start 244.715284 -54.88432)
		(mid 244.788082 -54.593557)
		(end 244.708934 -54.304438)
		(width 0.0889)
		(layer "In4.Cu")
		(net "M_C_DQS_DN<17>")
	)
	(arc
		(start 244.708934 -61.238638)
		(mid 244.655464 -61.043575)
		(end 244.704108 -60.847224)
		(width 0.0889)
		(layer "In4.Cu")
		(net "M_C_DQS_DN<17>")
	)
	(arc
		(start 244.708934 -66.191384)
		(mid 244.655466 -65.996433)
		(end 244.704108 -65.800224)
		(width 0.0889)
		(layer "In4.Cu")
		(net "M_C_DQS_DN<17>")
	)
	(arc
		(start 244.715284 -62.80912)
		(mid 244.788082 -62.518357)
		(end 244.708934 -62.229238)
		(width 0.0889)
		(layer "In4.Cu")
		(net "M_C_DQS_DN<17>")
	)
	(arc
		(start 244.715284 -64.79032)
		(mid 244.788082 -64.499557)
		(end 244.708934 -64.210438)
		(width 0.0889)
		(layer "In4.Cu")
		(net "M_C_DQS_DN<17>")
	)
	(arc
		(start 244.715284 -56.86552)
		(mid 244.788082 -56.574757)
		(end 244.708934 -56.285638)
		(width 0.0889)
		(layer "In4.Cu")
		(net "M_C_DQS_DN<17>")
	)
	(arc
		(start 244.708934 -59.257438)
		(mid 244.655464 -59.062375)
		(end 244.704108 -58.866024)
		(width 0.0889)
		(layer "In4.Cu")
		(net "M_C_DQS_DN<17>")
	)
	(arc
		(start 244.708934 -55.295038)
		(mid 244.655464 -55.099975)
		(end 244.704108 -54.903624)
		(width 0.0889)
		(layer "In4.Cu")
		(net "M_C_DQS_DN<17>")
	)
	(arc
		(start 244.715284 -63.79972)
		(mid 244.788082 -63.508957)
		(end 244.708934 -63.219838)
		(width 0.0889)
		(layer "In4.Cu")
		(net "M_C_DQS_DN<17>")
	)
	(arc
		(start 244.715284 -55.87492)
		(mid 244.788082 -55.584157)
		(end 244.708934 -55.295038)
		(width 0.0889)
		(layer "In4.Cu")
		(net "M_C_DQS_DN<17>")
	)
	(arc
		(start 244.708934 -58.857388)
		(mid 244.788156 -58.56827)
		(end 244.715284 -58.277506)
		(width 0.0889)
		(layer "In4.Cu")
		(net "M_C_DQS_DN<17>")
	)
	(arc
		(start 245.053866 -66.978276)
		(mid 244.903048 -66.57534)
		(end 244.708934 -66.191384)
		(width 0.0889)
		(layer "In4.Cu")
		(net "M_C_DQS_DN<17>")
	)
	(arc
		(start 244.715284 -60.82792)
		(mid 244.788082 -60.537157)
		(end 244.708934 -60.248038)
		(width 0.0889)
		(layer "In4.Cu")
		(net "M_C_DQS_DN<17>")
	)
	(arc
		(start 244.708934 -60.248038)
		(mid 244.655464 -60.052975)
		(end 244.704108 -59.856624)
		(width 0.0889)
		(layer "In4.Cu")
		(net "M_C_DQS_DN<17>")
	)
	(segment
		(start 237.931452 1.257808)
		(end 237.931452 -2.843276)
		(width 0.14224)
		(layer "In11.Cu")
		(net "M_C_DQS_DN<17>")
	)
	(segment
		(start 237.344712 1.59512)
		(end 237.59414 1.59512)
		(width 0.14224)
		(layer "In11.Cu")
		(net "M_C_DQS_DN<17>")
	)
	(segment
		(start 237.149132 1.7907)
		(end 237.344712 1.59512)
		(width 0.14224)
		(layer "In11.Cu")
		(net "M_C_DQS_DN<17>")
	)
	(segment
		(start 237.931452 -2.843276)
		(end 237.142528 -3.6322)
		(width 0.14224)
		(layer "In11.Cu")
		(net "M_C_DQS_DN<17>")
	)
	(segment
		(start 237.59414 1.59512)
		(end 237.931452 1.257808)
		(width 0.14224)
		(layer "In11.Cu")
		(net "M_C_DQS_DN<17>")
	)
	(segment
		(start 311.999884 3.778758)
		(end 312.000392 3.778758)
		(width 0.1651)
		(layer "F.Cu")
		(net "M_C_DQS_DN<16>")
	)
	(segment
		(start 311.767728 2.100072)
		(end 311.5818 2.286)
		(width 0.1651)
		(layer "F.Cu")
		(net "M_C_DQS_DN<16>")
	)
	(segment
		(start 311.11825 1.7907)
		(end 311.30748 1.60147)
		(width 0.1651)
		(layer "F.Cu")
		(net "M_C_DQS_DN<16>")
	)
	(segment
		(start 311.5818 2.518156)
		(end 311.999884 2.93624)
		(width 0.1651)
		(layer "F.Cu")
		(net "M_C_DQS_DN<16>")
	)
	(segment
		(start 311.5818 2.286)
		(end 311.5818 2.518156)
		(width 0.1651)
		(layer "F.Cu")
		(net "M_C_DQS_DN<16>")
	)
	(segment
		(start 311.767728 1.853438)
		(end 311.767728 2.100072)
		(width 0.1651)
		(layer "F.Cu")
		(net "M_C_DQS_DN<16>")
	)
	(segment
		(start 311.51576 1.60147)
		(end 311.767728 1.853438)
		(width 0.1651)
		(layer "F.Cu")
		(net "M_C_DQS_DN<16>")
	)
	(segment
		(start 311.999884 2.93624)
		(end 311.999884 3.778758)
		(width 0.1651)
		(layer "F.Cu")
		(net "M_C_DQS_DN<16>")
	)
	(segment
		(start 311.30748 1.60147)
		(end 311.51576 1.60147)
		(width 0.1651)
		(layer "F.Cu")
		(net "M_C_DQS_DN<16>")
	)
	(segment
		(start 311.0992 1.7907)
		(end 311.11825 1.7907)
		(width 0.1651)
		(layer "F.Cu")
		(net "M_C_DQS_DN<16>")
	)
	(segment
		(start 287.50514 -62.343538)
		(end 286.93364 -62.343538)
		(width 0.0889)
		(layer "F.Cu")
		(net "M_C_DQS_DN<16>")
	)
	(via
		(at 311.092596 -3.6322)
		(size 0.508)
		(drill 0.254)
		(layers "F.Cu" "B.Cu")
		(net "M_C_DQS_DN<16>")
	)
	(via
		(at 286.93364 -62.343538)
		(size 0.508)
		(drill 0.254)
		(layers "F.Cu" "B.Cu")
		(net "M_C_DQS_DN<16>")
	)
	(via
		(at 311.0992 1.7907)
		(size 0.508)
		(drill 0.254)
		(layers "F.Cu" "B.Cu")
		(net "M_C_DQS_DN<16>")
	)
	(segment
		(start 311.7342 -3.6576)
		(end 311.7342 -3.9878)
		(width 0.1651)
		(layer "B.Cu")
		(net "M_C_DQS_DN<16>")
	)
	(segment
		(start 311.092596 -3.6322)
		(end 311.28716 -3.437636)
		(width 0.1651)
		(layer "B.Cu")
		(net "M_C_DQS_DN<16>")
	)
	(segment
		(start 311.5564 -4.521454)
		(end 311.999884 -4.964938)
		(width 0.1651)
		(layer "B.Cu")
		(net "M_C_DQS_DN<16>")
	)
	(segment
		(start 311.7342 -3.9878)
		(end 311.5564 -4.1656)
		(width 0.1651)
		(layer "B.Cu")
		(net "M_C_DQS_DN<16>")
	)
	(segment
		(start 311.5564 -4.1656)
		(end 311.5564 -4.521454)
		(width 0.1651)
		(layer "B.Cu")
		(net "M_C_DQS_DN<16>")
	)
	(segment
		(start 311.999884 -4.964938)
		(end 311.999884 -5.621782)
		(width 0.1651)
		(layer "B.Cu")
		(net "M_C_DQS_DN<16>")
	)
	(segment
		(start 311.28716 -3.437636)
		(end 311.514236 -3.437636)
		(width 0.1651)
		(layer "B.Cu")
		(net "M_C_DQS_DN<16>")
	)
	(segment
		(start 311.999884 -5.621782)
		(end 312.000392 -5.621782)
		(width 0.1651)
		(layer "B.Cu")
		(net "M_C_DQS_DN<16>")
	)
	(segment
		(start 311.514236 -3.437636)
		(end 311.7342 -3.6576)
		(width 0.1651)
		(layer "B.Cu")
		(net "M_C_DQS_DN<16>")
	)
	(segment
		(start 288.244026 -50.054002)
		(end 288.51098 -49.787048)
		(width 0.0889)
		(layer "In11.Cu")
		(net "M_C_DQS_DN<16>")
	)
	(segment
		(start 311.874916 -10.799572)
		(end 311.874916 -10.446004)
		(width 0.14224)
		(layer "In11.Cu")
		(net "M_C_DQS_DN<16>")
	)
	(segment
		(start 311.531 -4.5974)
		(end 311.531 -4.070604)
		(width 0.14224)
		(layer "In11.Cu")
		(net "M_C_DQS_DN<16>")
	)
	(segment
		(start 311.874916 -11.282172)
		(end 311.989216 -11.167872)
		(width 0.14224)
		(layer "In11.Cu")
		(net "M_C_DQS_DN<16>")
	)
	(segment
		(start 286.582104 -56.5912)
		(end 286.58693 -56.599836)
		(width 0.0889)
		(layer "In11.Cu")
		(net "M_C_DQS_DN<16>")
	)
	(segment
		(start 311.874916 -9.963404)
		(end 311.874916 -6.238748)
		(width 0.14224)
		(layer "In11.Cu")
		(net "M_C_DQS_DN<16>")
	)
	(segment
		(start 290.755832 -47.7774)
		(end 290.755832 -47.597568)
		(width 0.14224)
		(layer "In11.Cu")
		(net "M_C_DQS_DN<16>")
	)
	(segment
		(start 289.677856 -48.855376)
		(end 289.677856 -48.675544)
		(width 0.14224)
		(layer "In11.Cu")
		(net "M_C_DQS_DN<16>")
	)
	(segment
		(start 311.27192 -27.712416)
		(end 311.27192 -27.07767)
		(width 0.14224)
		(layer "In11.Cu")
		(net "M_C_DQS_DN<16>")
	)
	(segment
		(start 292.6334 -47.25924)
		(end 293.0144 -47.25924)
		(width 0.14224)
		(layer "In11.Cu")
		(net "M_C_DQS_DN<16>")
	)
	(segment
		(start 290.216844 -48.136556)
		(end 290.396422 -47.956978)
		(width 0.14224)
		(layer "In11.Cu")
		(net "M_C_DQS_DN<16>")
	)
	(segment
		(start 311.531 -4.070604)
		(end 311.092596 -3.6322)
		(width 0.14224)
		(layer "In11.Cu")
		(net "M_C_DQS_DN<16>")
	)
	(segment
		(start 291.09416 -47.25924)
		(end 291.34816 -47.25924)
		(width 0.14224)
		(layer "In11.Cu")
		(net "M_C_DQS_DN<16>")
	)
	(segment
		(start 311.929272 -27.933142)
		(end 311.492646 -27.933142)
		(width 0.14224)
		(layer "In11.Cu")
		(net "M_C_DQS_DN<16>")
	)
	(segment
		(start 294.934132 -46.8503)
		(end 294.934132 -46.670468)
		(width 0.14224)
		(layer "In11.Cu")
		(net "M_C_DQS_DN<16>")
	)
	(segment
		(start 292.1254 -47.25924)
		(end 292.2524 -47.38624)
		(width 0.14224)
		(layer "In11.Cu")
		(net "M_C_DQS_DN<16>")
	)
	(segment
		(start 286.582104 -57.5818)
		(end 286.58693 -57.590436)
		(width 0.0889)
		(layer "In11.Cu")
		(net "M_C_DQS_DN<16>")
	)
	(segment
		(start 288.5821 -49.7713)
		(end 288.797238 -49.556162)
		(width 0.14224)
		(layer "In11.Cu")
		(net "M_C_DQS_DN<16>")
	)
	(segment
		(start 289.498024 -49.034954)
		(end 289.677856 -48.855376)
		(width 0.14224)
		(layer "In11.Cu")
		(net "M_C_DQS_DN<16>")
	)
	(segment
		(start 300.4312 -41.1734)
		(end 301.498 -41.1734)
		(width 0.14224)
		(layer "In11.Cu")
		(net "M_C_DQS_DN<16>")
	)
	(segment
		(start 311.493408 -26.856182)
		(end 311.781952 -26.856182)
		(width 0.14224)
		(layer "In11.Cu")
		(net "M_C_DQS_DN<16>")
	)
	(segment
		(start 311.989216 -12.131802)
		(end 311.989216 -11.877802)
		(width 0.14224)
		(layer "In11.Cu")
		(net "M_C_DQS_DN<16>")
	)
	(segment
		(start 311.989216 -11.877802)
		(end 311.874916 -11.763502)
		(width 0.14224)
		(layer "In11.Cu")
		(net "M_C_DQS_DN<16>")
	)
	(segment
		(start 291.34816 -47.25924)
		(end 291.47516 -47.38624)
		(width 0.14224)
		(layer "In11.Cu")
		(net "M_C_DQS_DN<16>")
	)
	(segment
		(start 311.874916 -12.246102)
		(end 311.989216 -12.131802)
		(width 0.14224)
		(layer "In11.Cu")
		(net "M_C_DQS_DN<16>")
	)
	(segment
		(start 311.492646 -27.933142)
		(end 311.27192 -27.712416)
		(width 0.14224)
		(layer "In11.Cu")
		(net "M_C_DQS_DN<16>")
	)
	(segment
		(start 286.582104 -60.5536)
		(end 286.58693 -60.562236)
		(width 0.0889)
		(layer "In11.Cu")
		(net "M_C_DQS_DN<16>")
	)
	(segment
		(start 311.29478 1.59512)
		(end 311.0992 1.7907)
		(width 0.14224)
		(layer "In11.Cu")
		(net "M_C_DQS_DN<16>")
	)
	(segment
		(start 311.092596 -3.6322)
		(end 311.88152 -2.843276)
		(width 0.14224)
		(layer "In11.Cu")
		(net "M_C_DQS_DN<16>")
	)
	(segment
		(start 293.5224 -47.25924)
		(end 294.34536 -47.25924)
		(width 0.14224)
		(layer "In11.Cu")
		(net "M_C_DQS_DN<16>")
	)
	(segment
		(start 294.7543 -47.030132)
		(end 294.934132 -46.8503)
		(width 0.14224)
		(layer "In11.Cu")
		(net "M_C_DQS_DN<16>")
	)
	(segment
		(start 288.797238 -49.556162)
		(end 288.959036 -49.556162)
		(width 0.14224)
		(layer "In11.Cu")
		(net "M_C_DQS_DN<16>")
	)
	(segment
		(start 311.0738 -4.8006)
		(end 311.3278 -4.8006)
		(width 0.14224)
		(layer "In11.Cu")
		(net "M_C_DQS_DN<16>")
	)
	(segment
		(start 311.874916 -23.80615)
		(end 311.874916 -12.246102)
		(width 0.14224)
		(layer "In11.Cu")
		(net "M_C_DQS_DN<16>")
	)
	(segment
		(start 310.89092 -4.98348)
		(end 311.0738 -4.8006)
		(width 0.14224)
		(layer "In11.Cu")
		(net "M_C_DQS_DN<16>")
	)
	(segment
		(start 295.505632 -46.098968)
		(end 295.68521 -45.91939)
		(width 0.14224)
		(layer "In11.Cu")
		(net "M_C_DQS_DN<16>")
	)
	(segment
		(start 286.58693 -56.599836)
		(end 286.59328 -56.610504)
		(width 0.0889)
		(layer "In11.Cu")
		(net "M_C_DQS_DN<16>")
	)
	(segment
		(start 288.51098 -49.787048)
		(end 288.566352 -49.787048)
		(width 0.0889)
		(layer "In11.Cu")
		(net "M_C_DQS_DN<16>")
	)
	(segment
		(start 312.15838 -24.492204)
		(end 312.15838 -24.089614)
		(width 0.14224)
		(layer "In11.Cu")
		(net "M_C_DQS_DN<16>")
	)
	(segment
		(start 287.63214 -50.3555)
		(end 287.0708 -50.91684)
		(width 0.0889)
		(layer "In11.Cu")
		(net "M_C_DQS_DN<16>")
	)
	(segment
		(start 286.58693 -57.590436)
		(end 286.59328 -57.601104)
		(width 0.0889)
		(layer "In11.Cu")
		(net "M_C_DQS_DN<16>")
	)
	(segment
		(start 312.30824 -29.169614)
		(end 312.30824 -28.31211)
		(width 0.14224)
		(layer "In11.Cu")
		(net "M_C_DQS_DN<16>")
	)
	(segment
		(start 286.582104 -55.6006)
		(end 286.58693 -55.609236)
		(width 0.0889)
		(layer "In11.Cu")
		(net "M_C_DQS_DN<16>")
	)
	(segment
		(start 311.88152 -2.843276)
		(end 311.88152 1.257808)
		(width 0.14224)
		(layer "In11.Cu")
		(net "M_C_DQS_DN<16>")
	)
	(segment
		(start 311.874916 -6.238748)
		(end 310.89092 -5.254752)
		(width 0.14224)
		(layer "In11.Cu")
		(net "M_C_DQS_DN<16>")
	)
	(segment
		(start 295.3258 -46.458632)
		(end 295.505632 -46.2788)
		(width 0.14224)
		(layer "In11.Cu")
		(net "M_C_DQS_DN<16>")
	)
	(segment
		(start 286.533844 -52.098956)
		(end 286.533844 -53.544978)
		(width 0.0889)
		(layer "In11.Cu")
		(net "M_C_DQS_DN<16>")
	)
	(segment
		(start 289.677856 -48.675544)
		(end 289.857434 -48.495966)
		(width 0.14224)
		(layer "In11.Cu")
		(net "M_C_DQS_DN<16>")
	)
	(segment
		(start 289.138868 -49.37633)
		(end 289.138868 -49.214532)
		(width 0.14224)
		(layer "In11.Cu")
		(net "M_C_DQS_DN<16>")
	)
	(segment
		(start 311.27192 -27.07767)
		(end 311.493408 -26.856182)
		(width 0.14224)
		(layer "In11.Cu")
		(net "M_C_DQS_DN<16>")
	)
	(segment
		(start 291.47516 -47.38624)
		(end 291.72916 -47.38624)
		(width 0.14224)
		(layer "In11.Cu")
		(net "M_C_DQS_DN<16>")
	)
	(segment
		(start 312.15838 -24.089614)
		(end 311.874916 -23.80615)
		(width 0.14224)
		(layer "In11.Cu")
		(net "M_C_DQS_DN<16>")
	)
	(segment
		(start 312.18632 -26.451814)
		(end 312.18632 -25.98039)
		(width 0.14224)
		(layer "In11.Cu")
		(net "M_C_DQS_DN<16>")
	)
	(segment
		(start 294.34536 -47.25924)
		(end 294.574468 -47.030132)
		(width 0.14224)
		(layer "In11.Cu")
		(net "M_C_DQS_DN<16>")
	)
	(segment
		(start 286.58693 -54.618636)
		(end 286.59328 -54.629304)
		(width 0.0889)
		(layer "In11.Cu")
		(net "M_C_DQS_DN<16>")
	)
	(segment
		(start 311.29732 -31.37408)
		(end 311.29732 -29.769308)
		(width 0.14224)
		(layer "In11.Cu")
		(net "M_C_DQS_DN<16>")
	)
	(segment
		(start 286.533844 -53.544978)
		(end 286.57042 -53.601366)
		(width 0.0889)
		(layer "In11.Cu")
		(net "M_C_DQS_DN<16>")
	)
	(segment
		(start 291.72916 -47.38624)
		(end 291.85616 -47.25924)
		(width 0.14224)
		(layer "In11.Cu")
		(net "M_C_DQS_DN<16>")
	)
	(segment
		(start 311.874916 -10.446004)
		(end 311.989216 -10.331704)
		(width 0.14224)
		(layer "In11.Cu")
		(net "M_C_DQS_DN<16>")
	)
	(segment
		(start 290.755832 -47.597568)
		(end 291.09416 -47.25924)
		(width 0.14224)
		(layer "In11.Cu")
		(net "M_C_DQS_DN<16>")
	)
	(segment
		(start 311.989216 -10.913872)
		(end 311.874916 -10.799572)
		(width 0.14224)
		(layer "In11.Cu")
		(net "M_C_DQS_DN<16>")
	)
	(segment
		(start 311.650126 -25.000458)
		(end 312.15838 -24.492204)
		(width 0.14224)
		(layer "In11.Cu")
		(net "M_C_DQS_DN<16>")
	)
	(segment
		(start 294.574468 -47.030132)
		(end 294.7543 -47.030132)
		(width 0.14224)
		(layer "In11.Cu")
		(net "M_C_DQS_DN<16>")
	)
	(segment
		(start 291.85616 -47.25924)
		(end 292.1254 -47.25924)
		(width 0.14224)
		(layer "In11.Cu")
		(net "M_C_DQS_DN<16>")
	)
	(segment
		(start 288.566352 -49.787048)
		(end 288.5821 -49.7713)
		(width 0.0889)
		(layer "In11.Cu")
		(net "M_C_DQS_DN<16>")
	)
	(segment
		(start 311.544208 1.59512)
		(end 311.29478 1.59512)
		(width 0.14224)
		(layer "In11.Cu")
		(net "M_C_DQS_DN<16>")
	)
	(segment
		(start 295.505632 -46.2788)
		(end 295.505632 -46.098968)
		(width 0.14224)
		(layer "In11.Cu")
		(net "M_C_DQS_DN<16>")
	)
	(segment
		(start 290.037012 -48.495966)
		(end 290.216844 -48.316388)
		(width 0.14224)
		(layer "In11.Cu")
		(net "M_C_DQS_DN<16>")
	)
	(segment
		(start 311.518046 -29.548582)
		(end 311.929272 -29.548582)
		(width 0.14224)
		(layer "In11.Cu")
		(net "M_C_DQS_DN<16>")
	)
	(segment
		(start 311.989216 -10.077704)
		(end 311.874916 -9.963404)
		(width 0.14224)
		(layer "In11.Cu")
		(net "M_C_DQS_DN<16>")
	)
	(segment
		(start 311.781952 -26.856182)
		(end 312.18632 -26.451814)
		(width 0.14224)
		(layer "In11.Cu")
		(net "M_C_DQS_DN<16>")
	)
	(segment
		(start 286.582104 -58.5724)
		(end 286.58693 -58.581036)
		(width 0.0889)
		(layer "In11.Cu")
		(net "M_C_DQS_DN<16>")
	)
	(segment
		(start 287.0708 -51.562)
		(end 286.533844 -52.098956)
		(width 0.0889)
		(layer "In11.Cu")
		(net "M_C_DQS_DN<16>")
	)
	(segment
		(start 311.29732 -29.769308)
		(end 311.518046 -29.548582)
		(width 0.14224)
		(layer "In11.Cu")
		(net "M_C_DQS_DN<16>")
	)
	(segment
		(start 286.58693 -60.562236)
		(end 286.59328 -60.572904)
		(width 0.0889)
		(layer "In11.Cu")
		(net "M_C_DQS_DN<16>")
	)
	(segment
		(start 290.396422 -47.956978)
		(end 290.576 -47.956978)
		(width 0.14224)
		(layer "In11.Cu")
		(net "M_C_DQS_DN<16>")
	)
	(segment
		(start 293.0144 -47.25924)
		(end 293.1414 -47.38624)
		(width 0.14224)
		(layer "In11.Cu")
		(net "M_C_DQS_DN<16>")
	)
	(segment
		(start 289.318446 -49.034954)
		(end 289.498024 -49.034954)
		(width 0.14224)
		(layer "In11.Cu")
		(net "M_C_DQS_DN<16>")
	)
	(segment
		(start 290.576 -47.956978)
		(end 290.755832 -47.7774)
		(width 0.14224)
		(layer "In11.Cu")
		(net "M_C_DQS_DN<16>")
	)
	(segment
		(start 295.68521 -45.918882)
		(end 300.4312 -41.1734)
		(width 0.14224)
		(layer "In11.Cu")
		(net "M_C_DQS_DN<16>")
	)
	(segment
		(start 312.18632 -25.98039)
		(end 311.650126 -25.444196)
		(width 0.14224)
		(layer "In11.Cu")
		(net "M_C_DQS_DN<16>")
	)
	(segment
		(start 295.145968 -46.458632)
		(end 295.3258 -46.458632)
		(width 0.14224)
		(layer "In11.Cu")
		(net "M_C_DQS_DN<16>")
	)
	(segment
		(start 287.0708 -50.91684)
		(end 287.0708 -51.562)
		(width 0.0889)
		(layer "In11.Cu")
		(net "M_C_DQS_DN<16>")
	)
	(segment
		(start 288.244026 -50.054002)
		(end 287.942528 -50.3555)
		(width 0.0889)
		(layer "In11.Cu")
		(net "M_C_DQS_DN<16>")
	)
	(segment
		(start 292.2524 -47.38624)
		(end 292.5064 -47.38624)
		(width 0.14224)
		(layer "In11.Cu")
		(net "M_C_DQS_DN<16>")
	)
	(segment
		(start 293.1414 -47.38624)
		(end 293.3954 -47.38624)
		(width 0.14224)
		(layer "In11.Cu")
		(net "M_C_DQS_DN<16>")
	)
	(segment
		(start 286.582104 -54.61)
		(end 286.58693 -54.618636)
		(width 0.0889)
		(layer "In11.Cu")
		(net "M_C_DQS_DN<16>")
	)
	(segment
		(start 286.59328 -59.160918)
		(end 286.58693 -59.171586)
		(width 0.0889)
		(layer "In11.Cu")
		(net "M_C_DQS_DN<16>")
	)
	(segment
		(start 312.30824 -28.31211)
		(end 311.929272 -27.933142)
		(width 0.14224)
		(layer "In11.Cu")
		(net "M_C_DQS_DN<16>")
	)
	(segment
		(start 288.959036 -49.556162)
		(end 289.138868 -49.37633)
		(width 0.14224)
		(layer "In11.Cu")
		(net "M_C_DQS_DN<16>")
	)
	(segment
		(start 289.138868 -49.214532)
		(end 289.318446 -49.034954)
		(width 0.14224)
		(layer "In11.Cu")
		(net "M_C_DQS_DN<16>")
	)
	(segment
		(start 301.498 -41.1734)
		(end 311.29732 -31.37408)
		(width 0.14224)
		(layer "In11.Cu")
		(net "M_C_DQS_DN<16>")
	)
	(segment
		(start 311.989216 -11.167872)
		(end 311.989216 -10.913872)
		(width 0.14224)
		(layer "In11.Cu")
		(net "M_C_DQS_DN<16>")
	)
	(segment
		(start 292.5064 -47.38624)
		(end 292.6334 -47.25924)
		(width 0.14224)
		(layer "In11.Cu")
		(net "M_C_DQS_DN<16>")
	)
	(segment
		(start 289.857434 -48.495966)
		(end 290.037012 -48.495966)
		(width 0.14224)
		(layer "In11.Cu")
		(net "M_C_DQS_DN<16>")
	)
	(segment
		(start 294.934132 -46.670468)
		(end 295.145968 -46.458632)
		(width 0.14224)
		(layer "In11.Cu")
		(net "M_C_DQS_DN<16>")
	)
	(segment
		(start 287.942528 -50.3555)
		(end 287.63214 -50.3555)
		(width 0.0889)
		(layer "In11.Cu")
		(net "M_C_DQS_DN<16>")
	)
	(segment
		(start 293.3954 -47.38624)
		(end 293.5224 -47.25924)
		(width 0.14224)
		(layer "In11.Cu")
		(net "M_C_DQS_DN<16>")
	)
	(segment
		(start 286.58693 -55.609236)
		(end 286.59328 -55.619904)
		(width 0.0889)
		(layer "In11.Cu")
		(net "M_C_DQS_DN<16>")
	)
	(segment
		(start 310.89092 -5.254752)
		(end 310.89092 -4.98348)
		(width 0.14224)
		(layer "In11.Cu")
		(net "M_C_DQS_DN<16>")
	)
	(segment
		(start 290.216844 -48.316388)
		(end 290.216844 -48.136556)
		(width 0.14224)
		(layer "In11.Cu")
		(net "M_C_DQS_DN<16>")
	)
	(segment
		(start 286.931862 -62.339728)
		(end 286.93364 -62.343538)
		(width 0.0889)
		(layer "In11.Cu")
		(net "M_C_DQS_DN<16>")
	)
	(segment
		(start 311.929272 -29.548582)
		(end 312.30824 -29.169614)
		(width 0.14224)
		(layer "In11.Cu")
		(net "M_C_DQS_DN<16>")
	)
	(segment
		(start 311.88152 1.257808)
		(end 311.544208 1.59512)
		(width 0.14224)
		(layer "In11.Cu")
		(net "M_C_DQS_DN<16>")
	)
	(segment
		(start 311.989216 -10.331704)
		(end 311.989216 -10.077704)
		(width 0.14224)
		(layer "In11.Cu")
		(net "M_C_DQS_DN<16>")
	)
	(segment
		(start 311.650126 -25.444196)
		(end 311.650126 -25.000458)
		(width 0.14224)
		(layer "In11.Cu")
		(net "M_C_DQS_DN<16>")
	)
	(segment
		(start 311.3278 -4.8006)
		(end 311.531 -4.5974)
		(width 0.14224)
		(layer "In11.Cu")
		(net "M_C_DQS_DN<16>")
	)
	(segment
		(start 311.874916 -11.763502)
		(end 311.874916 -11.282172)
		(width 0.14224)
		(layer "In11.Cu")
		(net "M_C_DQS_DN<16>")
	)
	(segment
		(start 295.68521 -45.91939)
		(end 295.68521 -45.918882)
		(width 0.14224)
		(layer "In11.Cu")
		(net "M_C_DQS_DN<16>")
	)
	(arc
		(start 286.58693 -61.552836)
		(mid 286.781025 -61.9368)
		(end 286.931862 -62.339728)
		(width 0.0889)
		(layer "In11.Cu")
		(net "M_C_DQS_DN<16>")
	)
	(arc
		(start 286.59328 -56.610504)
		(mid 286.666078 -56.901267)
		(end 286.58693 -57.190386)
		(width 0.0889)
		(layer "In11.Cu")
		(net "M_C_DQS_DN<16>")
	)
	(arc
		(start 286.58693 -61.152786)
		(mid 286.533338 -61.352828)
		(end 286.58693 -61.552836)
		(width 0.0889)
		(layer "In11.Cu")
		(net "M_C_DQS_DN<16>")
	)
	(arc
		(start 286.59328 -57.601104)
		(mid 286.666078 -57.891867)
		(end 286.58693 -58.180986)
		(width 0.0889)
		(layer "In11.Cu")
		(net "M_C_DQS_DN<16>")
	)
	(arc
		(start 286.58693 -59.571382)
		(mid 286.666061 -59.866784)
		(end 286.58693 -60.162186)
		(width 0.0889)
		(layer "In11.Cu")
		(net "M_C_DQS_DN<16>")
	)
	(arc
		(start 286.58693 -56.199786)
		(mid 286.53346 -56.394849)
		(end 286.582104 -56.5912)
		(width 0.0889)
		(layer "In11.Cu")
		(net "M_C_DQS_DN<16>")
	)
	(arc
		(start 286.58693 -59.171586)
		(mid 286.533431 -59.371484)
		(end 286.58693 -59.571382)
		(width 0.0889)
		(layer "In11.Cu")
		(net "M_C_DQS_DN<16>")
	)
	(arc
		(start 286.58693 -55.209186)
		(mid 286.53346 -55.404249)
		(end 286.582104 -55.6006)
		(width 0.0889)
		(layer "In11.Cu")
		(net "M_C_DQS_DN<16>")
	)
	(arc
		(start 286.59328 -54.629304)
		(mid 286.666078 -54.920067)
		(end 286.58693 -55.209186)
		(width 0.0889)
		(layer "In11.Cu")
		(net "M_C_DQS_DN<16>")
	)
	(arc
		(start 286.57042 -53.601366)
		(mid 286.665839 -53.907646)
		(end 286.58693 -54.218586)
		(width 0.0889)
		(layer "In11.Cu")
		(net "M_C_DQS_DN<16>")
	)
	(arc
		(start 286.58693 -54.218586)
		(mid 286.53346 -54.413649)
		(end 286.582104 -54.61)
		(width 0.0889)
		(layer "In11.Cu")
		(net "M_C_DQS_DN<16>")
	)
	(arc
		(start 286.58693 -57.190386)
		(mid 286.53346 -57.385449)
		(end 286.582104 -57.5818)
		(width 0.0889)
		(layer "In11.Cu")
		(net "M_C_DQS_DN<16>")
	)
	(arc
		(start 286.58693 -58.581036)
		(mid 286.666152 -58.870154)
		(end 286.59328 -59.160918)
		(width 0.0889)
		(layer "In11.Cu")
		(net "M_C_DQS_DN<16>")
	)
	(arc
		(start 286.59328 -60.572904)
		(mid 286.666078 -60.863667)
		(end 286.58693 -61.152786)
		(width 0.0889)
		(layer "In11.Cu")
		(net "M_C_DQS_DN<16>")
	)
	(arc
		(start 286.58693 -58.180986)
		(mid 286.53346 -58.376049)
		(end 286.582104 -58.5724)
		(width 0.0889)
		(layer "In11.Cu")
		(net "M_C_DQS_DN<16>")
	)
	(arc
		(start 286.59328 -55.619904)
		(mid 286.666078 -55.910667)
		(end 286.58693 -56.199786)
		(width 0.0889)
		(layer "In11.Cu")
		(net "M_C_DQS_DN<16>")
	)
	(arc
		(start 286.58693 -60.162186)
		(mid 286.53346 -60.357249)
		(end 286.582104 -60.5536)
		(width 0.0889)
		(layer "In11.Cu")
		(net "M_C_DQS_DN<16>")
	)
	(segment
		(start 301.957486 1.60147)
		(end 302.165766 1.60147)
		(width 0.1651)
		(layer "F.Cu")
		(net "M_C_DQS_DN<15>")
	)
	(segment
		(start 302.231806 2.286)
		(end 302.231806 2.518156)
		(width 0.1651)
		(layer "F.Cu")
		(net "M_C_DQS_DN<15>")
	)
	(segment
		(start 282.354274 -62.343538)
		(end 281.782774 -62.343538)
		(width 0.0889)
		(layer "F.Cu")
		(net "M_C_DQS_DN<15>")
	)
	(segment
		(start 302.64989 2.93624)
		(end 302.64989 3.778758)
		(width 0.1651)
		(layer "F.Cu")
		(net "M_C_DQS_DN<15>")
	)
	(segment
		(start 301.749206 1.7907)
		(end 301.768256 1.7907)
		(width 0.1651)
		(layer "F.Cu")
		(net "M_C_DQS_DN<15>")
	)
	(segment
		(start 302.231806 2.518156)
		(end 302.64989 2.93624)
		(width 0.1651)
		(layer "F.Cu")
		(net "M_C_DQS_DN<15>")
	)
	(segment
		(start 302.64989 3.778758)
		(end 302.650398 3.778758)
		(width 0.1651)
		(layer "F.Cu")
		(net "M_C_DQS_DN<15>")
	)
	(segment
		(start 302.417734 1.853438)
		(end 302.417734 2.100072)
		(width 0.1651)
		(layer "F.Cu")
		(net "M_C_DQS_DN<15>")
	)
	(segment
		(start 301.768256 1.7907)
		(end 301.957486 1.60147)
		(width 0.1651)
		(layer "F.Cu")
		(net "M_C_DQS_DN<15>")
	)
	(segment
		(start 302.165766 1.60147)
		(end 302.417734 1.853438)
		(width 0.1651)
		(layer "F.Cu")
		(net "M_C_DQS_DN<15>")
	)
	(segment
		(start 302.417734 2.100072)
		(end 302.231806 2.286)
		(width 0.1651)
		(layer "F.Cu")
		(net "M_C_DQS_DN<15>")
	)
	(via
		(at 301.749206 1.7907)
		(size 0.508)
		(drill 0.254)
		(layers "F.Cu" "B.Cu")
		(net "M_C_DQS_DN<15>")
	)
	(via
		(at 281.782774 -62.343538)
		(size 0.508)
		(drill 0.254)
		(layers "F.Cu" "B.Cu")
		(net "M_C_DQS_DN<15>")
	)
	(via
		(at 301.742602 -3.6322)
		(size 0.508)
		(drill 0.254)
		(layers "F.Cu" "B.Cu")
		(net "M_C_DQS_DN<15>")
	)
	(segment
		(start 302.384206 -3.6576)
		(end 302.164242 -3.437636)
		(width 0.1651)
		(layer "B.Cu")
		(net "M_C_DQS_DN<15>")
	)
	(segment
		(start 302.64989 -4.964938)
		(end 302.206406 -4.521454)
		(width 0.1651)
		(layer "B.Cu")
		(net "M_C_DQS_DN<15>")
	)
	(segment
		(start 301.937166 -3.437636)
		(end 301.742602 -3.6322)
		(width 0.1651)
		(layer "B.Cu")
		(net "M_C_DQS_DN<15>")
	)
	(segment
		(start 302.650398 -5.621782)
		(end 302.64989 -5.621782)
		(width 0.1651)
		(layer "B.Cu")
		(net "M_C_DQS_DN<15>")
	)
	(segment
		(start 302.206406 -4.1656)
		(end 302.384206 -3.9878)
		(width 0.1651)
		(layer "B.Cu")
		(net "M_C_DQS_DN<15>")
	)
	(segment
		(start 302.64989 -5.621782)
		(end 302.64989 -4.964938)
		(width 0.1651)
		(layer "B.Cu")
		(net "M_C_DQS_DN<15>")
	)
	(segment
		(start 302.164242 -3.437636)
		(end 301.937166 -3.437636)
		(width 0.1651)
		(layer "B.Cu")
		(net "M_C_DQS_DN<15>")
	)
	(segment
		(start 302.384206 -3.9878)
		(end 302.384206 -3.6576)
		(width 0.1651)
		(layer "B.Cu")
		(net "M_C_DQS_DN<15>")
	)
	(segment
		(start 302.206406 -4.521454)
		(end 302.206406 -4.1656)
		(width 0.1651)
		(layer "B.Cu")
		(net "M_C_DQS_DN<15>")
	)
	(segment
		(start 285.110682 -42.422064)
		(end 285.110682 -42.676064)
		(width 0.14224)
		(layer "In11.Cu")
		(net "M_C_DQS_DN<15>")
	)
	(segment
		(start 291.569648 -34.905696)
		(end 291.250624 -35.22472)
		(width 0.14224)
		(layer "In11.Cu")
		(net "M_C_DQS_DN<15>")
	)
	(segment
		(start 281.431238 -54.61)
		(end 281.436064 -54.618636)
		(width 0.0889)
		(layer "In11.Cu")
		(net "M_C_DQS_DN<15>")
	)
	(segment
		(start 281.431238 -55.6006)
		(end 281.436064 -55.609236)
		(width 0.0889)
		(layer "In11.Cu")
		(net "M_C_DQS_DN<15>")
	)
	(segment
		(start 302.524922 -6.42874)
		(end 302.524922 -9.29132)
		(width 0.14224)
		(layer "In11.Cu")
		(net "M_C_DQS_DN<15>")
	)
	(segment
		(start 285.110682 -40.948864)
		(end 285.110682 -41.202864)
		(width 0.14224)
		(layer "In11.Cu")
		(net "M_C_DQS_DN<15>")
	)
	(segment
		(start 282.278582 -45.795184)
		(end 282.099004 -45.974762)
		(width 0.14224)
		(layer "In11.Cu")
		(net "M_C_DQS_DN<15>")
	)
	(segment
		(start 301.749206 1.7907)
		(end 301.944786 1.59512)
		(width 0.14224)
		(layer "In11.Cu")
		(net "M_C_DQS_DN<15>")
	)
	(segment
		(start 282.059634 -46.772068)
		(end 282.059634 -47.537878)
		(width 0.0889)
		(layer "In11.Cu")
		(net "M_C_DQS_DN<15>")
	)
	(segment
		(start 295.815766 -35.22472)
		(end 295.531032 -34.939986)
		(width 0.14224)
		(layer "In11.Cu")
		(net "M_C_DQS_DN<15>")
	)
	(segment
		(start 282.059634 -47.537878)
		(end 281.232864 -48.364648)
		(width 0.0889)
		(layer "In11.Cu")
		(net "M_C_DQS_DN<15>")
	)
	(segment
		(start 302.531526 -2.843276)
		(end 301.742602 -3.6322)
		(width 0.14224)
		(layer "In11.Cu")
		(net "M_C_DQS_DN<15>")
	)
	(segment
		(start 281.782774 -62.341506)
		(end 281.782774 -62.343538)
		(width 0.0889)
		(layer "In11.Cu")
		(net "M_C_DQS_DN<15>")
	)
	(segment
		(start 284.523942 -43.711368)
		(end 284.362398 -43.711368)
		(width 0.14224)
		(layer "In11.Cu")
		(net "M_C_DQS_DN<15>")
	)
	(segment
		(start 285.110682 -41.939464)
		(end 284.996382 -42.053764)
		(width 0.14224)
		(layer "In11.Cu")
		(net "M_C_DQS_DN<15>")
	)
	(segment
		(start 301.944786 1.59512)
		(end 302.194214 1.59512)
		(width 0.14224)
		(layer "In11.Cu")
		(net "M_C_DQS_DN<15>")
	)
	(segment
		(start 295.531032 -34.36112)
		(end 295.404032 -34.23412)
		(width 0.14224)
		(layer "In11.Cu")
		(net "M_C_DQS_DN<15>")
	)
	(segment
		(start 302.524922 -10.05332)
		(end 302.682402 -10.2108)
		(width 0.14224)
		(layer "In11.Cu")
		(net "M_C_DQS_DN<15>")
	)
	(segment
		(start 281.232864 -50.404268)
		(end 281.090624 -50.776632)
		(width 0.0889)
		(layer "In11.Cu")
		(net "M_C_DQS_DN<15>")
	)
	(segment
		(start 302.524922 -29.420312)
		(end 296.720514 -35.22472)
		(width 0.14224)
		(layer "In11.Cu")
		(net "M_C_DQS_DN<15>")
	)
	(segment
		(start 284.703774 -43.531536)
		(end 284.523942 -43.711368)
		(width 0.14224)
		(layer "In11.Cu")
		(net "M_C_DQS_DN<15>")
	)
	(segment
		(start 283.841444 -44.232322)
		(end 283.661866 -44.4119)
		(width 0.14224)
		(layer "In11.Cu")
		(net "M_C_DQS_DN<15>")
	)
	(segment
		(start 281.436318 -54.218332)
		(end 281.436064 -54.218586)
		(width 0.0889)
		(layer "In11.Cu")
		(net "M_C_DQS_DN<15>")
	)
	(segment
		(start 283.32049 -44.753276)
		(end 283.140912 -44.932854)
		(width 0.14224)
		(layer "In11.Cu")
		(net "M_C_DQS_DN<15>")
	)
	(segment
		(start 302.524922 -11.38428)
		(end 302.524922 -29.420312)
		(width 0.14224)
		(layer "In11.Cu")
		(net "M_C_DQS_DN<15>")
	)
	(segment
		(start 291.569648 -34.520124)
		(end 291.569648 -34.905696)
		(width 0.14224)
		(layer "In11.Cu")
		(net "M_C_DQS_DN<15>")
	)
	(segment
		(start 281.436064 -54.618636)
		(end 281.442414 -54.629304)
		(width 0.0889)
		(layer "In11.Cu")
		(net "M_C_DQS_DN<15>")
	)
	(segment
		(start 283.482034 -44.753276)
		(end 283.32049 -44.753276)
		(width 0.14224)
		(layer "In11.Cu")
		(net "M_C_DQS_DN<15>")
	)
	(segment
		(start 281.431238 -58.5724)
		(end 281.436064 -58.581036)
		(width 0.0889)
		(layer "In11.Cu")
		(net "M_C_DQS_DN<15>")
	)
	(segment
		(start 281.090624 -51.1302)
		(end 281.515058 -51.554634)
		(width 0.0889)
		(layer "In11.Cu")
		(net "M_C_DQS_DN<15>")
	)
	(segment
		(start 282.099004 -46.7106)
		(end 282.099004 -46.732698)
		(width 0.0889)
		(layer "In11.Cu")
		(net "M_C_DQS_DN<15>")
	)
	(segment
		(start 292.838632 -34.454846)
		(end 292.617906 -34.23412)
		(width 0.14224)
		(layer "In11.Cu")
		(net "M_C_DQS_DN<15>")
	)
	(segment
		(start 302.194214 1.59512)
		(end 302.531526 1.257808)
		(width 0.14224)
		(layer "In11.Cu")
		(net "M_C_DQS_DN<15>")
	)
	(segment
		(start 282.799536 -45.27423)
		(end 282.619958 -45.453808)
		(width 0.14224)
		(layer "In11.Cu")
		(net "M_C_DQS_DN<15>")
	)
	(segment
		(start 294.075866 -35.22472)
		(end 293.216838 -35.22472)
		(width 0.14224)
		(layer "In11.Cu")
		(net "M_C_DQS_DN<15>")
	)
	(segment
		(start 294.454072 -34.455608)
		(end 294.454072 -34.846514)
		(width 0.14224)
		(layer "In11.Cu")
		(net "M_C_DQS_DN<15>")
	)
	(segment
		(start 283.140912 -44.932854)
		(end 283.140912 -45.094398)
		(width 0.14224)
		(layer "In11.Cu")
		(net "M_C_DQS_DN<15>")
	)
	(segment
		(start 302.682402 -10.9728)
		(end 302.682402 -11.2268)
		(width 0.14224)
		(layer "In11.Cu")
		(net "M_C_DQS_DN<15>")
	)
	(segment
		(start 282.099004 -46.732698)
		(end 282.059634 -46.772068)
		(width 0.0889)
		(layer "In11.Cu")
		(net "M_C_DQS_DN<15>")
	)
	(segment
		(start 281.515058 -51.554634)
		(end 281.515058 -53.92039)
		(width 0.0889)
		(layer "In11.Cu")
		(net "M_C_DQS_DN<15>")
	)
	(segment
		(start 281.431238 -56.5912)
		(end 281.436064 -56.599836)
		(width 0.0889)
		(layer "In11.Cu")
		(net "M_C_DQS_DN<15>")
	)
	(segment
		(start 301.977806 -4.8006)
		(end 301.723806 -4.8006)
		(width 0.14224)
		(layer "In11.Cu")
		(net "M_C_DQS_DN<15>")
	)
	(segment
		(start 292.617906 -34.23412)
		(end 291.855652 -34.23412)
		(width 0.14224)
		(layer "In11.Cu")
		(net "M_C_DQS_DN<15>")
	)
	(segment
		(start 284.002988 -44.232322)
		(end 283.841444 -44.232322)
		(width 0.14224)
		(layer "In11.Cu")
		(net "M_C_DQS_DN<15>")
	)
	(segment
		(start 281.431238 -57.5818)
		(end 281.436064 -57.590436)
		(width 0.0889)
		(layer "In11.Cu")
		(net "M_C_DQS_DN<15>")
	)
	(segment
		(start 301.723806 -4.8006)
		(end 301.540926 -4.98348)
		(width 0.14224)
		(layer "In11.Cu")
		(net "M_C_DQS_DN<15>")
	)
	(segment
		(start 284.996382 -40.834564)
		(end 285.110682 -40.948864)
		(width 0.14224)
		(layer "In11.Cu")
		(net "M_C_DQS_DN<15>")
	)
	(segment
		(start 281.780996 -62.339728)
		(end 281.782774 -62.341506)
		(width 0.0889)
		(layer "In11.Cu")
		(net "M_C_DQS_DN<15>")
	)
	(segment
		(start 284.996382 -39.544244)
		(end 284.996382 -40.097964)
		(width 0.14224)
		(layer "In11.Cu")
		(net "M_C_DQS_DN<15>")
	)
	(segment
		(start 302.524922 -10.62228)
		(end 302.524922 -10.81532)
		(width 0.14224)
		(layer "In11.Cu")
		(net "M_C_DQS_DN<15>")
	)
	(segment
		(start 284.996382 -43.077384)
		(end 284.703774 -43.369992)
		(width 0.14224)
		(layer "In11.Cu")
		(net "M_C_DQS_DN<15>")
	)
	(segment
		(start 281.436064 -56.599836)
		(end 281.442414 -56.610504)
		(width 0.0889)
		(layer "In11.Cu")
		(net "M_C_DQS_DN<15>")
	)
	(segment
		(start 284.18282 -44.05249)
		(end 284.002988 -44.232322)
		(width 0.14224)
		(layer "In11.Cu")
		(net "M_C_DQS_DN<15>")
	)
	(segment
		(start 301.540926 -5.444744)
		(end 302.524922 -6.42874)
		(width 0.14224)
		(layer "In11.Cu")
		(net "M_C_DQS_DN<15>")
	)
	(segment
		(start 294.67556 -34.23412)
		(end 294.454072 -34.455608)
		(width 0.14224)
		(layer "In11.Cu")
		(net "M_C_DQS_DN<15>")
	)
	(segment
		(start 302.524922 -10.81532)
		(end 302.682402 -10.9728)
		(width 0.14224)
		(layer "In11.Cu")
		(net "M_C_DQS_DN<15>")
	)
	(segment
		(start 293.216838 -35.22472)
		(end 292.838632 -34.846514)
		(width 0.14224)
		(layer "In11.Cu")
		(net "M_C_DQS_DN<15>")
	)
	(segment
		(start 292.838632 -34.846514)
		(end 292.838632 -34.454846)
		(width 0.14224)
		(layer "In11.Cu")
		(net "M_C_DQS_DN<15>")
	)
	(segment
		(start 285.110682 -41.685464)
		(end 285.110682 -41.939464)
		(width 0.14224)
		(layer "In11.Cu")
		(net "M_C_DQS_DN<15>")
	)
	(segment
		(start 294.454072 -34.846514)
		(end 294.075866 -35.22472)
		(width 0.14224)
		(layer "In11.Cu")
		(net "M_C_DQS_DN<15>")
	)
	(segment
		(start 291.855652 -34.23412)
		(end 291.569648 -34.520124)
		(width 0.14224)
		(layer "In11.Cu")
		(net "M_C_DQS_DN<15>")
	)
	(segment
		(start 283.661866 -44.4119)
		(end 283.661866 -44.573444)
		(width 0.14224)
		(layer "In11.Cu")
		(net "M_C_DQS_DN<15>")
	)
	(segment
		(start 281.232864 -48.364648)
		(end 281.232864 -50.404268)
		(width 0.0889)
		(layer "In11.Cu")
		(net "M_C_DQS_DN<15>")
	)
	(segment
		(start 295.531032 -34.939986)
		(end 295.531032 -34.36112)
		(width 0.14224)
		(layer "In11.Cu")
		(net "M_C_DQS_DN<15>")
	)
	(segment
		(start 282.440126 -45.795184)
		(end 282.278582 -45.795184)
		(width 0.14224)
		(layer "In11.Cu")
		(net "M_C_DQS_DN<15>")
	)
	(segment
		(start 289.315398 -35.22472)
		(end 284.996382 -39.544244)
		(width 0.14224)
		(layer "In11.Cu")
		(net "M_C_DQS_DN<15>")
	)
	(segment
		(start 284.996382 -40.097964)
		(end 285.110682 -40.212264)
		(width 0.14224)
		(layer "In11.Cu")
		(net "M_C_DQS_DN<15>")
	)
	(segment
		(start 284.703774 -43.369992)
		(end 284.703774 -43.531536)
		(width 0.14224)
		(layer "In11.Cu")
		(net "M_C_DQS_DN<15>")
	)
	(segment
		(start 296.720514 -35.22472)
		(end 295.815766 -35.22472)
		(width 0.14224)
		(layer "In11.Cu")
		(net "M_C_DQS_DN<15>")
	)
	(segment
		(start 281.090624 -50.776632)
		(end 281.090624 -51.1302)
		(width 0.0889)
		(layer "In11.Cu")
		(net "M_C_DQS_DN<15>")
	)
	(segment
		(start 301.742602 -3.6322)
		(end 302.181006 -4.070604)
		(width 0.14224)
		(layer "In11.Cu")
		(net "M_C_DQS_DN<15>")
	)
	(segment
		(start 282.96108 -45.27423)
		(end 282.799536 -45.27423)
		(width 0.14224)
		(layer "In11.Cu")
		(net "M_C_DQS_DN<15>")
	)
	(segment
		(start 302.181006 -4.5974)
		(end 301.977806 -4.8006)
		(width 0.14224)
		(layer "In11.Cu")
		(net "M_C_DQS_DN<15>")
	)
	(segment
		(start 285.110682 -40.212264)
		(end 285.110682 -40.466264)
		(width 0.14224)
		(layer "In11.Cu")
		(net "M_C_DQS_DN<15>")
	)
	(segment
		(start 281.431238 -60.5536)
		(end 281.436064 -60.562236)
		(width 0.0889)
		(layer "In11.Cu")
		(net "M_C_DQS_DN<15>")
	)
	(segment
		(start 281.442414 -59.160918)
		(end 281.436064 -59.171586)
		(width 0.0889)
		(layer "In11.Cu")
		(net "M_C_DQS_DN<15>")
	)
	(segment
		(start 302.531526 1.257808)
		(end 302.531526 -2.843276)
		(width 0.14224)
		(layer "In11.Cu")
		(net "M_C_DQS_DN<15>")
	)
	(segment
		(start 302.524922 -9.86028)
		(end 302.524922 -10.05332)
		(width 0.14224)
		(layer "In11.Cu")
		(net "M_C_DQS_DN<15>")
	)
	(segment
		(start 301.540926 -4.98348)
		(end 301.540926 -5.444744)
		(width 0.14224)
		(layer "In11.Cu")
		(net "M_C_DQS_DN<15>")
	)
	(segment
		(start 302.524922 -9.29132)
		(end 302.682402 -9.4488)
		(width 0.14224)
		(layer "In11.Cu")
		(net "M_C_DQS_DN<15>")
	)
	(segment
		(start 302.181006 -4.070604)
		(end 302.181006 -4.5974)
		(width 0.14224)
		(layer "In11.Cu")
		(net "M_C_DQS_DN<15>")
	)
	(segment
		(start 302.682402 -9.7028)
		(end 302.524922 -9.86028)
		(width 0.14224)
		(layer "In11.Cu")
		(net "M_C_DQS_DN<15>")
	)
	(segment
		(start 285.110682 -40.466264)
		(end 284.996382 -40.580564)
		(width 0.14224)
		(layer "In11.Cu")
		(net "M_C_DQS_DN<15>")
	)
	(segment
		(start 284.996382 -42.790364)
		(end 284.996382 -43.077384)
		(width 0.14224)
		(layer "In11.Cu")
		(net "M_C_DQS_DN<15>")
	)
	(segment
		(start 302.682402 -10.4648)
		(end 302.524922 -10.62228)
		(width 0.14224)
		(layer "In11.Cu")
		(net "M_C_DQS_DN<15>")
	)
	(segment
		(start 295.404032 -34.23412)
		(end 294.67556 -34.23412)
		(width 0.14224)
		(layer "In11.Cu")
		(net "M_C_DQS_DN<15>")
	)
	(segment
		(start 285.110682 -41.202864)
		(end 284.996382 -41.317164)
		(width 0.14224)
		(layer "In11.Cu")
		(net "M_C_DQS_DN<15>")
	)
	(segment
		(start 281.436064 -55.609236)
		(end 281.442414 -55.619904)
		(width 0.0889)
		(layer "In11.Cu")
		(net "M_C_DQS_DN<15>")
	)
	(segment
		(start 282.099004 -45.974762)
		(end 282.099004 -46.7106)
		(width 0.14224)
		(layer "In11.Cu")
		(net "M_C_DQS_DN<15>")
	)
	(segment
		(start 284.996382 -41.317164)
		(end 284.996382 -41.571164)
		(width 0.14224)
		(layer "In11.Cu")
		(net "M_C_DQS_DN<15>")
	)
	(segment
		(start 302.682402 -9.4488)
		(end 302.682402 -9.7028)
		(width 0.14224)
		(layer "In11.Cu")
		(net "M_C_DQS_DN<15>")
	)
	(segment
		(start 285.110682 -42.676064)
		(end 284.996382 -42.790364)
		(width 0.14224)
		(layer "In11.Cu")
		(net "M_C_DQS_DN<15>")
	)
	(segment
		(start 281.436064 -60.562236)
		(end 281.442414 -60.572904)
		(width 0.0889)
		(layer "In11.Cu")
		(net "M_C_DQS_DN<15>")
	)
	(segment
		(start 283.661866 -44.573444)
		(end 283.482034 -44.753276)
		(width 0.14224)
		(layer "In11.Cu")
		(net "M_C_DQS_DN<15>")
	)
	(segment
		(start 291.250624 -35.22472)
		(end 289.315398 -35.22472)
		(width 0.14224)
		(layer "In11.Cu")
		(net "M_C_DQS_DN<15>")
	)
	(segment
		(start 284.18282 -43.890946)
		(end 284.18282 -44.05249)
		(width 0.14224)
		(layer "In11.Cu")
		(net "M_C_DQS_DN<15>")
	)
	(segment
		(start 284.996382 -42.053764)
		(end 284.996382 -42.307764)
		(width 0.14224)
		(layer "In11.Cu")
		(net "M_C_DQS_DN<15>")
	)
	(segment
		(start 282.619958 -45.453808)
		(end 282.619958 -45.615352)
		(width 0.14224)
		(layer "In11.Cu")
		(net "M_C_DQS_DN<15>")
	)
	(segment
		(start 302.682402 -10.2108)
		(end 302.682402 -10.4648)
		(width 0.14224)
		(layer "In11.Cu")
		(net "M_C_DQS_DN<15>")
	)
	(segment
		(start 284.996382 -40.580564)
		(end 284.996382 -40.834564)
		(width 0.14224)
		(layer "In11.Cu")
		(net "M_C_DQS_DN<15>")
	)
	(segment
		(start 284.996382 -42.307764)
		(end 285.110682 -42.422064)
		(width 0.14224)
		(layer "In11.Cu")
		(net "M_C_DQS_DN<15>")
	)
	(segment
		(start 282.619958 -45.615352)
		(end 282.440126 -45.795184)
		(width 0.14224)
		(layer "In11.Cu")
		(net "M_C_DQS_DN<15>")
	)
	(segment
		(start 283.140912 -45.094398)
		(end 282.96108 -45.27423)
		(width 0.14224)
		(layer "In11.Cu")
		(net "M_C_DQS_DN<15>")
	)
	(segment
		(start 281.436064 -57.590436)
		(end 281.442414 -57.601104)
		(width 0.0889)
		(layer "In11.Cu")
		(net "M_C_DQS_DN<15>")
	)
	(segment
		(start 284.996382 -41.571164)
		(end 285.110682 -41.685464)
		(width 0.14224)
		(layer "In11.Cu")
		(net "M_C_DQS_DN<15>")
	)
	(segment
		(start 302.682402 -11.2268)
		(end 302.524922 -11.38428)
		(width 0.14224)
		(layer "In11.Cu")
		(net "M_C_DQS_DN<15>")
	)
	(segment
		(start 284.362398 -43.711368)
		(end 284.18282 -43.890946)
		(width 0.14224)
		(layer "In11.Cu")
		(net "M_C_DQS_DN<15>")
	)
	(arc
		(start 281.436064 -60.162186)
		(mid 281.382594 -60.357249)
		(end 281.431238 -60.5536)
		(width 0.0889)
		(layer "In11.Cu")
		(net "M_C_DQS_DN<15>")
	)
	(arc
		(start 281.436064 -58.581036)
		(mid 281.515286 -58.870154)
		(end 281.442414 -59.160918)
		(width 0.0889)
		(layer "In11.Cu")
		(net "M_C_DQS_DN<15>")
	)
	(arc
		(start 281.442414 -55.619904)
		(mid 281.515212 -55.910667)
		(end 281.436064 -56.199786)
		(width 0.0889)
		(layer "In11.Cu")
		(net "M_C_DQS_DN<15>")
	)
	(arc
		(start 281.436064 -54.218586)
		(mid 281.382594 -54.413649)
		(end 281.431238 -54.61)
		(width 0.0889)
		(layer "In11.Cu")
		(net "M_C_DQS_DN<15>")
	)
	(arc
		(start 281.436064 -55.209186)
		(mid 281.382594 -55.404249)
		(end 281.431238 -55.6006)
		(width 0.0889)
		(layer "In11.Cu")
		(net "M_C_DQS_DN<15>")
	)
	(arc
		(start 281.436064 -57.190386)
		(mid 281.382594 -57.385449)
		(end 281.431238 -57.5818)
		(width 0.0889)
		(layer "In11.Cu")
		(net "M_C_DQS_DN<15>")
	)
	(arc
		(start 281.436064 -59.171586)
		(mid 281.382565 -59.371484)
		(end 281.436064 -59.571382)
		(width 0.0889)
		(layer "In11.Cu")
		(net "M_C_DQS_DN<15>")
	)
	(arc
		(start 281.436064 -61.152786)
		(mid 281.382472 -61.352828)
		(end 281.436064 -61.552836)
		(width 0.0889)
		(layer "In11.Cu")
		(net "M_C_DQS_DN<15>")
	)
	(arc
		(start 281.442414 -60.572904)
		(mid 281.515212 -60.863667)
		(end 281.436064 -61.152786)
		(width 0.0889)
		(layer "In11.Cu")
		(net "M_C_DQS_DN<15>")
	)
	(arc
		(start 281.442414 -56.610504)
		(mid 281.515212 -56.901267)
		(end 281.436064 -57.190386)
		(width 0.0889)
		(layer "In11.Cu")
		(net "M_C_DQS_DN<15>")
	)
	(arc
		(start 281.515058 -53.92039)
		(mid 281.495511 -54.074604)
		(end 281.436318 -54.218332)
		(width 0.0889)
		(layer "In11.Cu")
		(net "M_C_DQS_DN<15>")
	)
	(arc
		(start 281.436064 -56.199786)
		(mid 281.382594 -56.394849)
		(end 281.431238 -56.5912)
		(width 0.0889)
		(layer "In11.Cu")
		(net "M_C_DQS_DN<15>")
	)
	(arc
		(start 281.436064 -59.571382)
		(mid 281.515195 -59.866784)
		(end 281.436064 -60.162186)
		(width 0.0889)
		(layer "In11.Cu")
		(net "M_C_DQS_DN<15>")
	)
	(arc
		(start 281.442414 -57.601104)
		(mid 281.515212 -57.891867)
		(end 281.436064 -58.180986)
		(width 0.0889)
		(layer "In11.Cu")
		(net "M_C_DQS_DN<15>")
	)
	(arc
		(start 281.436064 -61.552836)
		(mid 281.630159 -61.9368)
		(end 281.780996 -62.339728)
		(width 0.0889)
		(layer "In11.Cu")
		(net "M_C_DQS_DN<15>")
	)
	(arc
		(start 281.442414 -54.629304)
		(mid 281.515212 -54.920067)
		(end 281.436064 -55.209186)
		(width 0.0889)
		(layer "In11.Cu")
		(net "M_C_DQS_DN<15>")
	)
	(arc
		(start 281.436064 -58.180986)
		(mid 281.382594 -58.376049)
		(end 281.431238 -58.5724)
		(width 0.0889)
		(layer "In11.Cu")
		(net "M_C_DQS_DN<15>")
	)
	(segment
		(start 292.815772 1.60147)
		(end 292.607492 1.60147)
		(width 0.1651)
		(layer "F.Cu")
		(net "M_C_DQS_DN<14>")
	)
	(segment
		(start 292.607492 1.60147)
		(end 292.418262 1.7907)
		(width 0.1651)
		(layer "F.Cu")
		(net "M_C_DQS_DN<14>")
	)
	(segment
		(start 293.300404 3.778758)
		(end 293.299896 3.778758)
		(width 0.1651)
		(layer "F.Cu")
		(net "M_C_DQS_DN<14>")
	)
	(segment
		(start 293.299896 2.93624)
		(end 292.881812 2.518156)
		(width 0.1651)
		(layer "F.Cu")
		(net "M_C_DQS_DN<14>")
	)
	(segment
		(start 293.06774 1.853438)
		(end 292.815772 1.60147)
		(width 0.1651)
		(layer "F.Cu")
		(net "M_C_DQS_DN<14>")
	)
	(segment
		(start 292.881812 2.518156)
		(end 292.881812 2.286)
		(width 0.1651)
		(layer "F.Cu")
		(net "M_C_DQS_DN<14>")
	)
	(segment
		(start 293.06774 2.100072)
		(end 293.06774 1.853438)
		(width 0.1651)
		(layer "F.Cu")
		(net "M_C_DQS_DN<14>")
	)
	(segment
		(start 292.418262 1.7907)
		(end 292.399212 1.7907)
		(width 0.1651)
		(layer "F.Cu")
		(net "M_C_DQS_DN<14>")
	)
	(segment
		(start 293.299896 3.778758)
		(end 293.299896 2.93624)
		(width 0.1651)
		(layer "F.Cu")
		(net "M_C_DQS_DN<14>")
	)
	(segment
		(start 279.778714 -58.876438)
		(end 279.207214 -58.876438)
		(width 0.0889)
		(layer "F.Cu")
		(net "M_C_DQS_DN<14>")
	)
	(segment
		(start 292.881812 2.286)
		(end 293.06774 2.100072)
		(width 0.1651)
		(layer "F.Cu")
		(net "M_C_DQS_DN<14>")
	)
	(via
		(at 292.399212 1.7907)
		(size 0.508)
		(drill 0.254)
		(layers "F.Cu" "B.Cu")
		(net "M_C_DQS_DN<14>")
	)
	(via
		(at 279.207214 -58.876438)
		(size 0.508)
		(drill 0.254)
		(layers "F.Cu" "B.Cu")
		(net "M_C_DQS_DN<14>")
	)
	(via
		(at 292.392608 -3.6322)
		(size 0.508)
		(drill 0.254)
		(layers "F.Cu" "B.Cu")
		(net "M_C_DQS_DN<14>")
	)
	(segment
		(start 292.856412 -4.1656)
		(end 293.034212 -3.9878)
		(width 0.1651)
		(layer "B.Cu")
		(net "M_C_DQS_DN<14>")
	)
	(segment
		(start 293.034212 -3.9878)
		(end 293.034212 -3.6576)
		(width 0.1651)
		(layer "B.Cu")
		(net "M_C_DQS_DN<14>")
	)
	(segment
		(start 293.300404 -5.621782)
		(end 293.299896 -5.621782)
		(width 0.1651)
		(layer "B.Cu")
		(net "M_C_DQS_DN<14>")
	)
	(segment
		(start 293.299896 -5.621782)
		(end 293.299896 -4.964938)
		(width 0.1651)
		(layer "B.Cu")
		(net "M_C_DQS_DN<14>")
	)
	(segment
		(start 292.814248 -3.437636)
		(end 292.587172 -3.437636)
		(width 0.1651)
		(layer "B.Cu")
		(net "M_C_DQS_DN<14>")
	)
	(segment
		(start 292.587172 -3.437636)
		(end 292.392608 -3.6322)
		(width 0.1651)
		(layer "B.Cu")
		(net "M_C_DQS_DN<14>")
	)
	(segment
		(start 292.856412 -4.521454)
		(end 292.856412 -4.1656)
		(width 0.1651)
		(layer "B.Cu")
		(net "M_C_DQS_DN<14>")
	)
	(segment
		(start 293.034212 -3.6576)
		(end 292.814248 -3.437636)
		(width 0.1651)
		(layer "B.Cu")
		(net "M_C_DQS_DN<14>")
	)
	(segment
		(start 293.299896 -4.964938)
		(end 292.856412 -4.521454)
		(width 0.1651)
		(layer "B.Cu")
		(net "M_C_DQS_DN<14>")
	)
	(segment
		(start 278.860504 -54.713886)
		(end 278.855678 -54.722522)
		(width 0.0889)
		(layer "In4.Cu")
		(net "M_C_DQS_DN<14>")
	)
	(segment
		(start 292.831012 -4.5974)
		(end 292.627812 -4.8006)
		(width 0.14224)
		(layer "In4.Cu")
		(net "M_C_DQS_DN<14>")
	)
	(segment
		(start 282.171902 -45.049948)
		(end 282.057602 -45.164248)
		(width 0.14224)
		(layer "In4.Cu")
		(net "M_C_DQS_DN<14>")
	)
	(segment
		(start 282.057602 -43.945048)
		(end 282.171902 -44.059348)
		(width 0.14224)
		(layer "In4.Cu")
		(net "M_C_DQS_DN<14>")
	)
	(segment
		(start 291.39642 -30.921452)
		(end 290.923218 -31.394654)
		(width 0.14224)
		(layer "In4.Cu")
		(net "M_C_DQS_DN<14>")
	)
	(segment
		(start 290.923218 -31.394654)
		(end 290.923218 -31.70682)
		(width 0.14224)
		(layer "In4.Cu")
		(net "M_C_DQS_DN<14>")
	)
	(segment
		(start 292.373812 -4.8006)
		(end 292.190932 -4.98348)
		(width 0.14224)
		(layer "In4.Cu")
		(net "M_C_DQS_DN<14>")
	)
	(segment
		(start 282.171902 -45.532548)
		(end 282.171902 -45.786548)
		(width 0.14224)
		(layer "In4.Cu")
		(net "M_C_DQS_DN<14>")
	)
	(segment
		(start 282.057602 -45.418248)
		(end 282.171902 -45.532548)
		(width 0.14224)
		(layer "In4.Cu")
		(net "M_C_DQS_DN<14>")
	)
	(segment
		(start 292.627812 -4.8006)
		(end 292.373812 -4.8006)
		(width 0.14224)
		(layer "In4.Cu")
		(net "M_C_DQS_DN<14>")
	)
	(segment
		(start 282.398724 -42.027348)
		(end 282.23718 -42.027348)
		(width 0.14224)
		(layer "In4.Cu")
		(net "M_C_DQS_DN<14>")
	)
	(segment
		(start 284.470602 -39.793926)
		(end 284.291024 -39.973504)
		(width 0.14224)
		(layer "In4.Cu")
		(net "M_C_DQS_DN<14>")
	)
	(segment
		(start 282.171902 -43.576748)
		(end 282.057602 -43.691048)
		(width 0.14224)
		(layer "In4.Cu")
		(net "M_C_DQS_DN<14>")
	)
	(segment
		(start 282.057602 -44.681648)
		(end 282.171902 -44.795948)
		(width 0.14224)
		(layer "In4.Cu")
		(net "M_C_DQS_DN<14>")
	)
	(segment
		(start 282.057602 -45.900848)
		(end 282.057602 -46.260258)
		(width 0.14224)
		(layer "In4.Cu")
		(net "M_C_DQS_DN<14>")
	)
	(segment
		(start 293.332408 -10.4648)
		(end 293.174928 -10.62228)
		(width 0.14224)
		(layer "In4.Cu")
		(net "M_C_DQS_DN<14>")
	)
	(segment
		(start 278.938228 -58.423556)
		(end 278.935434 -58.489342)
		(width 0.0889)
		(layer "In4.Cu")
		(net "M_C_DQS_DN<14>")
	)
	(segment
		(start 283.533342 -40.89273)
		(end 283.371798 -40.89273)
		(width 0.14224)
		(layer "In4.Cu")
		(net "M_C_DQS_DN<14>")
	)
	(segment
		(start 290.923218 -31.70682)
		(end 291.459412 -32.243014)
		(width 0.14224)
		(layer "In4.Cu")
		(net "M_C_DQS_DN<14>")
	)
	(segment
		(start 291.660834 -30.921452)
		(end 291.39642 -30.921452)
		(width 0.14224)
		(layer "In4.Cu")
		(net "M_C_DQS_DN<14>")
	)
	(segment
		(start 293.332408 -9.7028)
		(end 293.174928 -9.86028)
		(width 0.14224)
		(layer "In4.Cu")
		(net "M_C_DQS_DN<14>")
	)
	(segment
		(start 293.318692 -30.85846)
		(end 292.740842 -31.43631)
		(width 0.14224)
		(layer "In4.Cu")
		(net "M_C_DQS_DN<14>")
	)
	(segment
		(start 283.949648 -40.31488)
		(end 283.713174 -40.551354)
		(width 0.14224)
		(layer "In4.Cu")
		(net "M_C_DQS_DN<14>")
	)
	(segment
		(start 292.190932 -5.254752)
		(end 293.174928 -6.238748)
		(width 0.14224)
		(layer "In4.Cu")
		(net "M_C_DQS_DN<14>")
	)
	(segment
		(start 278.866854 -56.684418)
		(end 278.860504 -56.695086)
		(width 0.0889)
		(layer "In4.Cu")
		(net "M_C_DQS_DN<14>")
	)
	(segment
		(start 282.171902 -44.059348)
		(end 282.171902 -44.313348)
		(width 0.14224)
		(layer "In4.Cu")
		(net "M_C_DQS_DN<14>")
	)
	(segment
		(start 282.578556 -41.847516)
		(end 282.398724 -42.027348)
		(width 0.14224)
		(layer "In4.Cu")
		(net "M_C_DQS_DN<14>")
	)
	(segment
		(start 293.318692 -30.292294)
		(end 293.318692 -30.85846)
		(width 0.14224)
		(layer "In4.Cu")
		(net "M_C_DQS_DN<14>")
	)
	(segment
		(start 282.018232 -47.336964)
		(end 282.018232 -48.263556)
		(width 0.0889)
		(layer "In4.Cu")
		(net "M_C_DQS_DN<14>")
	)
	(segment
		(start 283.005022 -41.42105)
		(end 282.843478 -41.42105)
		(width 0.14224)
		(layer "In4.Cu")
		(net "M_C_DQS_DN<14>")
	)
	(segment
		(start 283.184854 -41.079674)
		(end 283.184854 -41.241218)
		(width 0.14224)
		(layer "In4.Cu")
		(net "M_C_DQS_DN<14>")
	)
	(segment
		(start 279.39746 -52.05476)
		(end 279.39746 -52.856638)
		(width 0.0889)
		(layer "In4.Cu")
		(net "M_C_DQS_DN<14>")
	)
	(segment
		(start 283.713174 -40.712898)
		(end 283.533342 -40.89273)
		(width 0.14224)
		(layer "In4.Cu")
		(net "M_C_DQS_DN<14>")
	)
	(segment
		(start 293.332408 -9.4488)
		(end 293.332408 -9.7028)
		(width 0.14224)
		(layer "In4.Cu")
		(net "M_C_DQS_DN<14>")
	)
	(segment
		(start 282.057602 -47.275496)
		(end 282.057602 -47.297594)
		(width 0.0889)
		(layer "In4.Cu")
		(net "M_C_DQS_DN<14>")
	)
	(segment
		(start 282.057602 -46.260258)
		(end 282.171902 -46.374558)
		(width 0.14224)
		(layer "In4.Cu")
		(net "M_C_DQS_DN<14>")
	)
	(segment
		(start 292.831012 -4.070604)
		(end 292.831012 -4.5974)
		(width 0.14224)
		(layer "In4.Cu")
		(net "M_C_DQS_DN<14>")
	)
	(segment
		(start 284.632146 -39.793926)
		(end 284.470602 -39.793926)
		(width 0.14224)
		(layer "In4.Cu")
		(net "M_C_DQS_DN<14>")
	)
	(segment
		(start 278.860504 -56.695086)
		(end 278.855678 -56.703722)
		(width 0.0889)
		(layer "In4.Cu")
		(net "M_C_DQS_DN<14>")
	)
	(segment
		(start 282.843478 -41.42105)
		(end 282.578556 -41.685972)
		(width 0.14224)
		(layer "In4.Cu")
		(net "M_C_DQS_DN<14>")
	)
	(segment
		(start 292.740842 -31.43631)
		(end 292.175692 -31.43631)
		(width 0.14224)
		(layer "In4.Cu")
		(net "M_C_DQS_DN<14>")
	)
	(segment
		(start 283.713174 -40.551354)
		(end 283.713174 -40.712898)
		(width 0.14224)
		(layer "In4.Cu")
		(net "M_C_DQS_DN<14>")
	)
	(segment
		(start 282.171902 -44.795948)
		(end 282.171902 -45.049948)
		(width 0.14224)
		(layer "In4.Cu")
		(net "M_C_DQS_DN<14>")
	)
	(segment
		(start 293.332408 -10.2108)
		(end 293.332408 -10.4648)
		(width 0.14224)
		(layer "In4.Cu")
		(net "M_C_DQS_DN<14>")
	)
	(segment
		(start 292.190932 -4.98348)
		(end 292.190932 -5.254752)
		(width 0.14224)
		(layer "In4.Cu")
		(net "M_C_DQS_DN<14>")
	)
	(segment
		(start 282.057602 -47.297594)
		(end 282.018232 -47.336964)
		(width 0.0889)
		(layer "In4.Cu")
		(net "M_C_DQS_DN<14>")
	)
	(segment
		(start 282.23718 -42.027348)
		(end 282.057602 -42.206926)
		(width 0.14224)
		(layer "In4.Cu")
		(net "M_C_DQS_DN<14>")
	)
	(segment
		(start 283.371798 -40.89273)
		(end 283.184854 -41.079674)
		(width 0.14224)
		(layer "In4.Cu")
		(net "M_C_DQS_DN<14>")
	)
	(segment
		(start 278.939752 -53.314346)
		(end 278.939752 -53.430424)
		(width 0.0889)
		(layer "In4.Cu")
		(net "M_C_DQS_DN<14>")
	)
	(segment
		(start 282.057602 -43.208448)
		(end 282.171902 -43.322748)
		(width 0.14224)
		(layer "In4.Cu")
		(net "M_C_DQS_DN<14>")
	)
	(segment
		(start 284.291024 -40.135048)
		(end 284.111192 -40.31488)
		(width 0.14224)
		(layer "In4.Cu")
		(net "M_C_DQS_DN<14>")
	)
	(segment
		(start 278.994108 -58.663332)
		(end 279.207214 -58.876438)
		(width 0.0889)
		(layer "In4.Cu")
		(net "M_C_DQS_DN<14>")
	)
	(segment
		(start 282.171902 -44.313348)
		(end 282.057602 -44.427648)
		(width 0.14224)
		(layer "In4.Cu")
		(net "M_C_DQS_DN<14>")
	)
	(segment
		(start 282.171902 -46.374558)
		(end 282.171902 -46.628558)
		(width 0.14224)
		(layer "In4.Cu")
		(net "M_C_DQS_DN<14>")
	)
	(segment
		(start 293.174928 -9.29132)
		(end 293.332408 -9.4488)
		(width 0.14224)
		(layer "In4.Cu")
		(net "M_C_DQS_DN<14>")
	)
	(segment
		(start 284.811978 -39.614094)
		(end 284.632146 -39.793926)
		(width 0.14224)
		(layer "In4.Cu")
		(net "M_C_DQS_DN<14>")
	)
	(segment
		(start 280.2128 -51.23942)
		(end 279.39746 -52.05476)
		(width 0.0889)
		(layer "In4.Cu")
		(net "M_C_DQS_DN<14>")
	)
	(segment
		(start 282.057602 -44.427648)
		(end 282.057602 -44.681648)
		(width 0.14224)
		(layer "In4.Cu")
		(net "M_C_DQS_DN<14>")
	)
	(segment
		(start 278.866854 -55.693818)
		(end 278.860504 -55.704486)
		(width 0.0889)
		(layer "In4.Cu")
		(net "M_C_DQS_DN<14>")
	)
	(segment
		(start 282.057602 -45.164248)
		(end 282.057602 -45.418248)
		(width 0.14224)
		(layer "In4.Cu")
		(net "M_C_DQS_DN<14>")
	)
	(segment
		(start 293.174928 -10.05332)
		(end 293.332408 -10.2108)
		(width 0.14224)
		(layer "In4.Cu")
		(net "M_C_DQS_DN<14>")
	)
	(segment
		(start 292.392608 -3.6322)
		(end 292.831012 -4.070604)
		(width 0.14224)
		(layer "In4.Cu")
		(net "M_C_DQS_DN<14>")
	)
	(segment
		(start 291.459412 -32.805116)
		(end 284.811978 -39.45255)
		(width 0.14224)
		(layer "In4.Cu")
		(net "M_C_DQS_DN<14>")
	)
	(segment
		(start 278.866854 -54.703218)
		(end 278.860504 -54.713886)
		(width 0.0889)
		(layer "In4.Cu")
		(net "M_C_DQS_DN<14>")
	)
	(segment
		(start 293.174928 -6.238748)
		(end 293.174928 -9.29132)
		(width 0.14224)
		(layer "In4.Cu")
		(net "M_C_DQS_DN<14>")
	)
	(segment
		(start 279.39746 -52.856638)
		(end 278.939752 -53.314346)
		(width 0.0889)
		(layer "In4.Cu")
		(net "M_C_DQS_DN<14>")
	)
	(segment
		(start 282.171902 -46.628558)
		(end 282.057602 -46.742858)
		(width 0.14224)
		(layer "In4.Cu")
		(net "M_C_DQS_DN<14>")
	)
	(segment
		(start 293.174928 -10.62228)
		(end 293.174928 -30.14853)
		(width 0.14224)
		(layer "In4.Cu")
		(net "M_C_DQS_DN<14>")
	)
	(segment
		(start 282.057602 -42.206926)
		(end 282.057602 -43.208448)
		(width 0.14224)
		(layer "In4.Cu")
		(net "M_C_DQS_DN<14>")
	)
	(segment
		(start 282.578556 -41.685972)
		(end 282.578556 -41.847516)
		(width 0.14224)
		(layer "In4.Cu")
		(net "M_C_DQS_DN<14>")
	)
	(segment
		(start 282.018232 -48.263556)
		(end 280.2128 -50.068988)
		(width 0.0889)
		(layer "In4.Cu")
		(net "M_C_DQS_DN<14>")
	)
	(segment
		(start 284.111192 -40.31488)
		(end 283.949648 -40.31488)
		(width 0.14224)
		(layer "In4.Cu")
		(net "M_C_DQS_DN<14>")
	)
	(segment
		(start 293.174928 -30.14853)
		(end 293.318692 -30.292294)
		(width 0.14224)
		(layer "In4.Cu")
		(net "M_C_DQS_DN<14>")
	)
	(segment
		(start 291.459412 -32.243014)
		(end 291.459412 -32.805116)
		(width 0.14224)
		(layer "In4.Cu")
		(net "M_C_DQS_DN<14>")
	)
	(segment
		(start 282.057602 -46.742858)
		(end 282.057602 -47.275496)
		(width 0.14224)
		(layer "In4.Cu")
		(net "M_C_DQS_DN<14>")
	)
	(segment
		(start 282.171902 -45.786548)
		(end 282.057602 -45.900848)
		(width 0.14224)
		(layer "In4.Cu")
		(net "M_C_DQS_DN<14>")
	)
	(segment
		(start 284.811978 -39.45255)
		(end 284.811978 -39.614094)
		(width 0.14224)
		(layer "In4.Cu")
		(net "M_C_DQS_DN<14>")
	)
	(segment
		(start 284.291024 -39.973504)
		(end 284.291024 -40.135048)
		(width 0.14224)
		(layer "In4.Cu")
		(net "M_C_DQS_DN<14>")
	)
	(segment
		(start 292.175692 -31.43631)
		(end 291.660834 -30.921452)
		(width 0.14224)
		(layer "In4.Cu")
		(net "M_C_DQS_DN<14>")
	)
	(segment
		(start 278.860504 -57.685686)
		(end 278.855678 -57.694322)
		(width 0.0889)
		(layer "In4.Cu")
		(net "M_C_DQS_DN<14>")
	)
	(segment
		(start 283.184854 -41.241218)
		(end 283.005022 -41.42105)
		(width 0.14224)
		(layer "In4.Cu")
		(net "M_C_DQS_DN<14>")
	)
	(segment
		(start 278.93518 -58.50128)
		(end 278.93518 -58.521092)
		(width 0.0889)
		(layer "In4.Cu")
		(net "M_C_DQS_DN<14>")
	)
	(segment
		(start 282.057602 -43.691048)
		(end 282.057602 -43.945048)
		(width 0.14224)
		(layer "In4.Cu")
		(net "M_C_DQS_DN<14>")
	)
	(segment
		(start 293.174928 -9.86028)
		(end 293.174928 -10.05332)
		(width 0.14224)
		(layer "In4.Cu")
		(net "M_C_DQS_DN<14>")
	)
	(segment
		(start 278.860504 -53.723286)
		(end 278.855678 -53.731922)
		(width 0.0889)
		(layer "In4.Cu")
		(net "M_C_DQS_DN<14>")
	)
	(segment
		(start 278.860504 -55.704486)
		(end 278.855678 -55.713122)
		(width 0.0889)
		(layer "In4.Cu")
		(net "M_C_DQS_DN<14>")
	)
	(segment
		(start 278.866854 -57.675018)
		(end 278.860504 -57.685686)
		(width 0.0889)
		(layer "In4.Cu")
		(net "M_C_DQS_DN<14>")
	)
	(segment
		(start 280.2128 -50.068988)
		(end 280.2128 -51.23942)
		(width 0.0889)
		(layer "In4.Cu")
		(net "M_C_DQS_DN<14>")
	)
	(segment
		(start 282.171902 -43.322748)
		(end 282.171902 -43.576748)
		(width 0.14224)
		(layer "In4.Cu")
		(net "M_C_DQS_DN<14>")
	)
	(arc
		(start 278.855678 -55.713122)
		(mid 278.806923 -55.909474)
		(end 278.860504 -56.104536)
		(width 0.0889)
		(layer "In4.Cu")
		(net "M_C_DQS_DN<14>")
	)
	(arc
		(start 278.860504 -55.113936)
		(mid 278.939726 -55.403054)
		(end 278.866854 -55.693818)
		(width 0.0889)
		(layer "In4.Cu")
		(net "M_C_DQS_DN<14>")
	)
	(arc
		(start 278.860504 -57.095136)
		(mid 278.939726 -57.384254)
		(end 278.866854 -57.675018)
		(width 0.0889)
		(layer "In4.Cu")
		(net "M_C_DQS_DN<14>")
	)
	(arc
		(start 278.855678 -54.722522)
		(mid 278.806923 -54.918874)
		(end 278.860504 -55.113936)
		(width 0.0889)
		(layer "In4.Cu")
		(net "M_C_DQS_DN<14>")
	)
	(arc
		(start 278.93518 -58.521092)
		(mid 278.950493 -58.598076)
		(end 278.994108 -58.663332)
		(width 0.0889)
		(layer "In4.Cu")
		(net "M_C_DQS_DN<14>")
	)
	(arc
		(start 278.935434 -58.489342)
		(mid 278.935244 -58.49531)
		(end 278.93518 -58.50128)
		(width 0.0889)
		(layer "In4.Cu")
		(net "M_C_DQS_DN<14>")
	)
	(arc
		(start 278.860504 -56.104536)
		(mid 278.939726 -56.393654)
		(end 278.866854 -56.684418)
		(width 0.0889)
		(layer "In4.Cu")
		(net "M_C_DQS_DN<14>")
	)
	(arc
		(start 278.855678 -53.731922)
		(mid 278.806923 -53.928274)
		(end 278.860504 -54.123336)
		(width 0.0889)
		(layer "In4.Cu")
		(net "M_C_DQS_DN<14>")
	)
	(arc
		(start 278.939752 -53.430424)
		(mid 278.919237 -53.582026)
		(end 278.860504 -53.723286)
		(width 0.0889)
		(layer "In4.Cu")
		(net "M_C_DQS_DN<14>")
	)
	(arc
		(start 278.860504 -54.123336)
		(mid 278.939726 -54.412454)
		(end 278.866854 -54.703218)
		(width 0.0889)
		(layer "In4.Cu")
		(net "M_C_DQS_DN<14>")
	)
	(arc
		(start 278.855678 -56.703722)
		(mid 278.806923 -56.900074)
		(end 278.860504 -57.095136)
		(width 0.0889)
		(layer "In4.Cu")
		(net "M_C_DQS_DN<14>")
	)
	(arc
		(start 278.860504 -58.085736)
		(mid 278.885482 -58.133717)
		(end 278.90597 -58.18378)
		(width 0.0889)
		(layer "In4.Cu")
		(net "M_C_DQS_DN<14>")
	)
	(arc
		(start 278.855678 -57.694322)
		(mid 278.806923 -57.890674)
		(end 278.860504 -58.085736)
		(width 0.0889)
		(layer "In4.Cu")
		(net "M_C_DQS_DN<14>")
	)
	(arc
		(start 278.90597 -58.18378)
		(mid 278.934513 -58.301999)
		(end 278.938228 -58.423556)
		(width 0.0889)
		(layer "In4.Cu")
		(net "M_C_DQS_DN<14>")
	)
	(segment
		(start 292.84422 1.59512)
		(end 292.594792 1.59512)
		(width 0.14224)
		(layer "In11.Cu")
		(net "M_C_DQS_DN<14>")
	)
	(segment
		(start 293.181532 1.257808)
		(end 292.84422 1.59512)
		(width 0.14224)
		(layer "In11.Cu")
		(net "M_C_DQS_DN<14>")
	)
	(segment
		(start 292.594792 1.59512)
		(end 292.399212 1.7907)
		(width 0.14224)
		(layer "In11.Cu")
		(net "M_C_DQS_DN<14>")
	)
	(segment
		(start 292.392608 -3.6322)
		(end 293.181532 -2.843276)
		(width 0.14224)
		(layer "In11.Cu")
		(net "M_C_DQS_DN<14>")
	)
	(segment
		(start 293.181532 -2.843276)
		(end 293.181532 1.257808)
		(width 0.14224)
		(layer "In11.Cu")
		(net "M_C_DQS_DN<14>")
	)
	(segment
		(start 283.257244 1.60147)
		(end 283.068014 1.7907)
		(width 0.1651)
		(layer "F.Cu")
		(net "M_C_DQS_DN<13>")
	)
	(segment
		(start 283.068014 1.7907)
		(end 283.048964 1.7907)
		(width 0.1651)
		(layer "F.Cu")
		(net "M_C_DQS_DN<13>")
	)
	(segment
		(start 283.531564 2.286)
		(end 283.717492 2.100072)
		(width 0.1651)
		(layer "F.Cu")
		(net "M_C_DQS_DN<13>")
	)
	(segment
		(start 283.717492 2.100072)
		(end 283.717492 1.853438)
		(width 0.1651)
		(layer "F.Cu")
		(net "M_C_DQS_DN<13>")
	)
	(segment
		(start 283.531564 2.518156)
		(end 283.531564 2.286)
		(width 0.1651)
		(layer "F.Cu")
		(net "M_C_DQS_DN<13>")
	)
	(segment
		(start 283.95041 3.778758)
		(end 283.949902 3.778758)
		(width 0.1651)
		(layer "F.Cu")
		(net "M_C_DQS_DN<13>")
	)
	(segment
		(start 283.949902 3.778758)
		(end 283.949902 2.936494)
		(width 0.1651)
		(layer "F.Cu")
		(net "M_C_DQS_DN<13>")
	)
	(segment
		(start 283.465524 1.60147)
		(end 283.257244 1.60147)
		(width 0.1651)
		(layer "F.Cu")
		(net "M_C_DQS_DN<13>")
	)
	(segment
		(start 283.717492 1.853438)
		(end 283.465524 1.60147)
		(width 0.1651)
		(layer "F.Cu")
		(net "M_C_DQS_DN<13>")
	)
	(segment
		(start 274.627848 -58.876438)
		(end 274.056348 -58.876438)
		(width 0.0889)
		(layer "F.Cu")
		(net "M_C_DQS_DN<13>")
	)
	(segment
		(start 283.949902 2.936494)
		(end 283.531564 2.518156)
		(width 0.1651)
		(layer "F.Cu")
		(net "M_C_DQS_DN<13>")
	)
	(via
		(at 283.048964 1.7907)
		(size 0.508)
		(drill 0.254)
		(layers "F.Cu" "B.Cu")
		(net "M_C_DQS_DN<13>")
	)
	(via
		(at 283.04236 -3.6322)
		(size 0.508)
		(drill 0.254)
		(layers "F.Cu" "B.Cu")
		(net "M_C_DQS_DN<13>")
	)
	(via
		(at 274.056348 -58.876438)
		(size 0.508)
		(drill 0.254)
		(layers "F.Cu" "B.Cu")
		(net "M_C_DQS_DN<13>")
	)
	(segment
		(start 283.236924 -3.437636)
		(end 283.04236 -3.6322)
		(width 0.1651)
		(layer "B.Cu")
		(net "M_C_DQS_DN<13>")
	)
	(segment
		(start 283.95041 -5.621782)
		(end 283.949902 -5.621782)
		(width 0.1651)
		(layer "B.Cu")
		(net "M_C_DQS_DN<13>")
	)
	(segment
		(start 283.464 -3.437636)
		(end 283.236924 -3.437636)
		(width 0.1651)
		(layer "B.Cu")
		(net "M_C_DQS_DN<13>")
	)
	(segment
		(start 283.683964 -3.6576)
		(end 283.464 -3.437636)
		(width 0.1651)
		(layer "B.Cu")
		(net "M_C_DQS_DN<13>")
	)
	(segment
		(start 283.949902 -4.965192)
		(end 283.506164 -4.521454)
		(width 0.1651)
		(layer "B.Cu")
		(net "M_C_DQS_DN<13>")
	)
	(segment
		(start 283.949902 -5.621782)
		(end 283.949902 -4.965192)
		(width 0.1651)
		(layer "B.Cu")
		(net "M_C_DQS_DN<13>")
	)
	(segment
		(start 283.506164 -4.521454)
		(end 283.506164 -4.1656)
		(width 0.1651)
		(layer "B.Cu")
		(net "M_C_DQS_DN<13>")
	)
	(segment
		(start 283.683964 -3.9878)
		(end 283.683964 -3.6576)
		(width 0.1651)
		(layer "B.Cu")
		(net "M_C_DQS_DN<13>")
	)
	(segment
		(start 283.506164 -4.1656)
		(end 283.683964 -3.9878)
		(width 0.1651)
		(layer "B.Cu")
		(net "M_C_DQS_DN<13>")
	)
	(segment
		(start 283.277564 -4.8006)
		(end 283.023564 -4.8006)
		(width 0.14224)
		(layer "In11.Cu")
		(net "M_C_DQS_DN<13>")
	)
	(segment
		(start 283.824934 -14.68628)
		(end 283.824934 -14.87932)
		(width 0.14224)
		(layer "In11.Cu")
		(net "M_C_DQS_DN<13>")
	)
	(segment
		(start 274.54987 -42.931588)
		(end 274.66417 -43.045888)
		(width 0.14224)
		(layer "In11.Cu")
		(net "M_C_DQS_DN<13>")
	)
	(segment
		(start 282.840684 -4.98348)
		(end 282.840684 -5.254752)
		(width 0.14224)
		(layer "In11.Cu")
		(net "M_C_DQS_DN<13>")
	)
	(segment
		(start 273.83867 -52.817268)
		(end 273.636994 -53.018944)
		(width 0.0889)
		(layer "In11.Cu")
		(net "M_C_DQS_DN<13>")
	)
	(segment
		(start 284.14472 -29.190696)
		(end 284.14472 -29.77896)
		(width 0.14224)
		(layer "In11.Cu")
		(net "M_C_DQS_DN<13>")
	)
	(segment
		(start 274.5105 -47.804832)
		(end 274.230846 -48.084486)
		(width 0.0889)
		(layer "In11.Cu")
		(net "M_C_DQS_DN<13>")
	)
	(segment
		(start 274.54987 -42.194988)
		(end 274.66417 -42.309288)
		(width 0.14224)
		(layer "In11.Cu")
		(net "M_C_DQS_DN<13>")
	)
	(segment
		(start 274.54987 -46.004226)
		(end 274.66417 -46.118526)
		(width 0.14224)
		(layer "In11.Cu")
		(net "M_C_DQS_DN<13>")
	)
	(segment
		(start 274.5105 -47.30877)
		(end 274.5105 -47.804832)
		(width 0.0889)
		(layer "In11.Cu")
		(net "M_C_DQS_DN<13>")
	)
	(segment
		(start 273.709638 -55.704486)
		(end 273.704812 -55.713122)
		(width 0.0889)
		(layer "In11.Cu")
		(net "M_C_DQS_DN<13>")
	)
	(segment
		(start 274.66417 -46.118526)
		(end 274.66417 -46.372526)
		(width 0.14224)
		(layer "In11.Cu")
		(net "M_C_DQS_DN<13>")
	)
	(segment
		(start 274.729448 -39.194232)
		(end 274.54987 -39.37381)
		(width 0.14224)
		(layer "In11.Cu")
		(net "M_C_DQS_DN<13>")
	)
	(segment
		(start 274.54987 -41.1607)
		(end 274.54987 -41.4147)
		(width 0.14224)
		(layer "In11.Cu")
		(net "M_C_DQS_DN<13>")
	)
	(segment
		(start 274.54987 -40.6781)
		(end 274.66417 -40.7924)
		(width 0.14224)
		(layer "In11.Cu")
		(net "M_C_DQS_DN<13>")
	)
	(segment
		(start 274.54987 -43.414188)
		(end 274.54987 -43.668188)
		(width 0.14224)
		(layer "In11.Cu")
		(net "M_C_DQS_DN<13>")
	)
	(segment
		(start 274.54987 -46.486826)
		(end 274.54987 -47.247302)
		(width 0.14224)
		(layer "In11.Cu")
		(net "M_C_DQS_DN<13>")
	)
	(segment
		(start 283.480764 -4.5974)
		(end 283.277564 -4.8006)
		(width 0.14224)
		(layer "In11.Cu")
		(net "M_C_DQS_DN<13>")
	)
	(segment
		(start 282.72232 -28.591002)
		(end 282.943808 -28.81249)
		(width 0.14224)
		(layer "In11.Cu")
		(net "M_C_DQS_DN<13>")
	)
	(segment
		(start 283.480764 -4.070604)
		(end 283.480764 -4.5974)
		(width 0.14224)
		(layer "In11.Cu")
		(net "M_C_DQS_DN<13>")
	)
	(segment
		(start 273.636994 -53.018944)
		(end 273.636994 -54.987952)
		(width 0.0889)
		(layer "In11.Cu")
		(net "M_C_DQS_DN<13>")
	)
	(segment
		(start 283.824934 -14.11732)
		(end 283.982414 -14.2748)
		(width 0.14224)
		(layer "In11.Cu")
		(net "M_C_DQS_DN<13>")
	)
	(segment
		(start 274.66417 -42.563288)
		(end 274.54987 -42.677588)
		(width 0.14224)
		(layer "In11.Cu")
		(net "M_C_DQS_DN<13>")
	)
	(segment
		(start 283.824934 -14.87932)
		(end 283.982414 -15.0368)
		(width 0.14224)
		(layer "In11.Cu")
		(net "M_C_DQS_DN<13>")
	)
	(segment
		(start 274.66417 -44.533566)
		(end 274.66417 -44.787566)
		(width 0.14224)
		(layer "In11.Cu")
		(net "M_C_DQS_DN<13>")
	)
	(segment
		(start 274.66417 -40.0558)
		(end 274.66417 -40.3098)
		(width 0.14224)
		(layer "In11.Cu")
		(net "M_C_DQS_DN<13>")
	)
	(segment
		(start 273.715988 -57.675018)
		(end 273.709638 -57.685686)
		(width 0.0889)
		(layer "In11.Cu")
		(net "M_C_DQS_DN<13>")
	)
	(segment
		(start 283.023564 -4.8006)
		(end 282.840684 -4.98348)
		(width 0.14224)
		(layer "In11.Cu")
		(net "M_C_DQS_DN<13>")
	)
	(segment
		(start 283.244544 1.59512)
		(end 283.493972 1.59512)
		(width 0.14224)
		(layer "In11.Cu")
		(net "M_C_DQS_DN<13>")
	)
	(segment
		(start 283.982414 -14.2748)
		(end 283.982414 -14.5288)
		(width 0.14224)
		(layer "In11.Cu")
		(net "M_C_DQS_DN<13>")
	)
	(segment
		(start 274.66417 -43.782488)
		(end 274.66417 -44.036488)
		(width 0.14224)
		(layer "In11.Cu")
		(net "M_C_DQS_DN<13>")
	)
	(segment
		(start 284.14472 -25.412192)
		(end 284.14472 -27.450796)
		(width 0.14224)
		(layer "In11.Cu")
		(net "M_C_DQS_DN<13>")
	)
	(segment
		(start 274.66417 -44.787566)
		(end 274.54987 -44.901866)
		(width 0.14224)
		(layer "In11.Cu")
		(net "M_C_DQS_DN<13>")
	)
	(segment
		(start 274.66417 -43.045888)
		(end 274.66417 -43.299888)
		(width 0.14224)
		(layer "In11.Cu")
		(net "M_C_DQS_DN<13>")
	)
	(segment
		(start 274.230846 -51.794664)
		(end 273.83867 -52.18684)
		(width 0.0889)
		(layer "In11.Cu")
		(net "M_C_DQS_DN<13>")
	)
	(segment
		(start 275.599652 -38.485572)
		(end 275.41982 -38.665404)
		(width 0.14224)
		(layer "In11.Cu")
		(net "M_C_DQS_DN<13>")
	)
	(segment
		(start 274.66417 -41.783)
		(end 274.54987 -41.8973)
		(width 0.14224)
		(layer "In11.Cu")
		(net "M_C_DQS_DN<13>")
	)
	(segment
		(start 275.41982 -38.665404)
		(end 275.258276 -38.665404)
		(width 0.14224)
		(layer "In11.Cu")
		(net "M_C_DQS_DN<13>")
	)
	(segment
		(start 275.258276 -38.665404)
		(end 275.070824 -38.852856)
		(width 0.14224)
		(layer "In11.Cu")
		(net "M_C_DQS_DN<13>")
	)
	(segment
		(start 274.230846 -48.084486)
		(end 274.230846 -51.794664)
		(width 0.0889)
		(layer "In11.Cu")
		(net "M_C_DQS_DN<13>")
	)
	(segment
		(start 274.056348 -58.874406)
		(end 274.056348 -58.876438)
		(width 0.0889)
		(layer "In11.Cu")
		(net "M_C_DQS_DN<13>")
	)
	(segment
		(start 273.715988 -55.693818)
		(end 273.709638 -55.704486)
		(width 0.0889)
		(layer "In11.Cu")
		(net "M_C_DQS_DN<13>")
	)
	(segment
		(start 273.709638 -57.685686)
		(end 273.704812 -57.694322)
		(width 0.0889)
		(layer "In11.Cu")
		(net "M_C_DQS_DN<13>")
	)
	(segment
		(start 275.070824 -38.852856)
		(end 275.070824 -39.0144)
		(width 0.14224)
		(layer "In11.Cu")
		(net "M_C_DQS_DN<13>")
	)
	(segment
		(start 274.54987 -41.8973)
		(end 274.54987 -42.194988)
		(width 0.14224)
		(layer "In11.Cu")
		(net "M_C_DQS_DN<13>")
	)
	(segment
		(start 273.636994 -54.987952)
		(end 273.709638 -55.113936)
		(width 0.0889)
		(layer "In11.Cu")
		(net "M_C_DQS_DN<13>")
	)
	(segment
		(start 274.54987 -43.668188)
		(end 274.66417 -43.782488)
		(width 0.14224)
		(layer "In11.Cu")
		(net "M_C_DQS_DN<13>")
	)
	(segment
		(start 274.890992 -39.194232)
		(end 274.729448 -39.194232)
		(width 0.14224)
		(layer "In11.Cu")
		(net "M_C_DQS_DN<13>")
	)
	(segment
		(start 283.824934 -25.092406)
		(end 284.14472 -25.412192)
		(width 0.14224)
		(layer "In11.Cu")
		(net "M_C_DQS_DN<13>")
	)
	(segment
		(start 274.54987 -47.247302)
		(end 274.54987 -47.2694)
		(width 0.0889)
		(layer "In11.Cu")
		(net "M_C_DQS_DN<13>")
	)
	(segment
		(start 283.824934 -15.44828)
		(end 283.824934 -25.092406)
		(width 0.14224)
		(layer "In11.Cu")
		(net "M_C_DQS_DN<13>")
	)
	(segment
		(start 275.599652 -38.324028)
		(end 275.599652 -38.485572)
		(width 0.14224)
		(layer "In11.Cu")
		(net "M_C_DQS_DN<13>")
	)
	(segment
		(start 274.66417 -43.299888)
		(end 274.54987 -43.414188)
		(width 0.14224)
		(layer "In11.Cu")
		(net "M_C_DQS_DN<13>")
	)
	(segment
		(start 283.859986 -27.73553)
		(end 282.969208 -27.73553)
		(width 0.14224)
		(layer "In11.Cu")
		(net "M_C_DQS_DN<13>")
	)
	(segment
		(start 274.54987 -44.419266)
		(end 274.66417 -44.533566)
		(width 0.14224)
		(layer "In11.Cu")
		(net "M_C_DQS_DN<13>")
	)
	(segment
		(start 274.54987 -45.750226)
		(end 274.54987 -46.004226)
		(width 0.14224)
		(layer "In11.Cu")
		(net "M_C_DQS_DN<13>")
	)
	(segment
		(start 274.66417 -46.372526)
		(end 274.54987 -46.486826)
		(width 0.14224)
		(layer "In11.Cu")
		(net "M_C_DQS_DN<13>")
	)
	(segment
		(start 274.66417 -42.309288)
		(end 274.66417 -42.563288)
		(width 0.14224)
		(layer "In11.Cu")
		(net "M_C_DQS_DN<13>")
	)
	(segment
		(start 282.969208 -27.73553)
		(end 282.72232 -27.982418)
		(width 0.14224)
		(layer "In11.Cu")
		(net "M_C_DQS_DN<13>")
	)
	(segment
		(start 274.66417 -40.3098)
		(end 274.54987 -40.4241)
		(width 0.14224)
		(layer "In11.Cu")
		(net "M_C_DQS_DN<13>")
	)
	(segment
		(start 273.83867 -52.18684)
		(end 273.83867 -52.817268)
		(width 0.0889)
		(layer "In11.Cu")
		(net "M_C_DQS_DN<13>")
	)
	(segment
		(start 274.54987 -44.901866)
		(end 274.54987 -45.267626)
		(width 0.14224)
		(layer "In11.Cu")
		(net "M_C_DQS_DN<13>")
	)
	(segment
		(start 283.048964 1.7907)
		(end 283.244544 1.59512)
		(width 0.14224)
		(layer "In11.Cu")
		(net "M_C_DQS_DN<13>")
	)
	(segment
		(start 274.54987 -42.677588)
		(end 274.54987 -42.931588)
		(width 0.14224)
		(layer "In11.Cu")
		(net "M_C_DQS_DN<13>")
	)
	(segment
		(start 274.66417 -41.0464)
		(end 274.54987 -41.1607)
		(width 0.14224)
		(layer "In11.Cu")
		(net "M_C_DQS_DN<13>")
	)
	(segment
		(start 274.66417 -45.381926)
		(end 274.66417 -45.635926)
		(width 0.14224)
		(layer "In11.Cu")
		(net "M_C_DQS_DN<13>")
	)
	(segment
		(start 283.982414 -15.0368)
		(end 283.982414 -15.2908)
		(width 0.14224)
		(layer "In11.Cu")
		(net "M_C_DQS_DN<13>")
	)
	(segment
		(start 274.66417 -44.036488)
		(end 274.54987 -44.150788)
		(width 0.14224)
		(layer "In11.Cu")
		(net "M_C_DQS_DN<13>")
	)
	(segment
		(start 282.72232 -27.982418)
		(end 282.72232 -28.591002)
		(width 0.14224)
		(layer "In11.Cu")
		(net "M_C_DQS_DN<13>")
	)
	(segment
		(start 282.943808 -28.81249)
		(end 283.766514 -28.81249)
		(width 0.14224)
		(layer "In11.Cu")
		(net "M_C_DQS_DN<13>")
	)
	(segment
		(start 274.54987 -40.4241)
		(end 274.54987 -40.6781)
		(width 0.14224)
		(layer "In11.Cu")
		(net "M_C_DQS_DN<13>")
	)
	(segment
		(start 283.982414 -14.5288)
		(end 283.824934 -14.68628)
		(width 0.14224)
		(layer "In11.Cu")
		(net "M_C_DQS_DN<13>")
	)
	(segment
		(start 273.715988 -56.684418)
		(end 273.709638 -56.695086)
		(width 0.0889)
		(layer "In11.Cu")
		(net "M_C_DQS_DN<13>")
	)
	(segment
		(start 274.54987 -45.267626)
		(end 274.66417 -45.381926)
		(width 0.14224)
		(layer "In11.Cu")
		(net "M_C_DQS_DN<13>")
	)
	(segment
		(start 283.831284 1.257808)
		(end 283.831284 -2.843276)
		(width 0.14224)
		(layer "In11.Cu")
		(net "M_C_DQS_DN<13>")
	)
	(segment
		(start 274.54987 -47.2694)
		(end 274.5105 -47.30877)
		(width 0.0889)
		(layer "In11.Cu")
		(net "M_C_DQS_DN<13>")
	)
	(segment
		(start 283.493972 1.59512)
		(end 283.831284 1.257808)
		(width 0.14224)
		(layer "In11.Cu")
		(net "M_C_DQS_DN<13>")
	)
	(segment
		(start 283.04236 -3.6322)
		(end 283.480764 -4.070604)
		(width 0.14224)
		(layer "In11.Cu")
		(net "M_C_DQS_DN<13>")
	)
	(segment
		(start 273.709638 -56.695086)
		(end 273.704812 -56.703722)
		(width 0.0889)
		(layer "In11.Cu")
		(net "M_C_DQS_DN<13>")
	)
	(segment
		(start 284.14472 -29.77896)
		(end 275.599652 -38.324028)
		(width 0.14224)
		(layer "In11.Cu")
		(net "M_C_DQS_DN<13>")
	)
	(segment
		(start 274.54987 -39.9415)
		(end 274.66417 -40.0558)
		(width 0.14224)
		(layer "In11.Cu")
		(net "M_C_DQS_DN<13>")
	)
	(segment
		(start 274.66417 -40.7924)
		(end 274.66417 -41.0464)
		(width 0.14224)
		(layer "In11.Cu")
		(net "M_C_DQS_DN<13>")
	)
	(segment
		(start 274.05457 -58.872628)
		(end 274.056348 -58.874406)
		(width 0.0889)
		(layer "In11.Cu")
		(net "M_C_DQS_DN<13>")
	)
	(segment
		(start 283.831284 -2.843276)
		(end 283.04236 -3.6322)
		(width 0.14224)
		(layer "In11.Cu")
		(net "M_C_DQS_DN<13>")
	)
	(segment
		(start 275.070824 -39.0144)
		(end 274.890992 -39.194232)
		(width 0.14224)
		(layer "In11.Cu")
		(net "M_C_DQS_DN<13>")
	)
	(segment
		(start 283.824934 -6.239002)
		(end 283.824934 -14.11732)
		(width 0.14224)
		(layer "In11.Cu")
		(net "M_C_DQS_DN<13>")
	)
	(segment
		(start 282.840684 -5.254752)
		(end 283.824934 -6.239002)
		(width 0.14224)
		(layer "In11.Cu")
		(net "M_C_DQS_DN<13>")
	)
	(segment
		(start 274.54987 -39.37381)
		(end 274.54987 -39.9415)
		(width 0.14224)
		(layer "In11.Cu")
		(net "M_C_DQS_DN<13>")
	)
	(segment
		(start 274.66417 -41.529)
		(end 274.66417 -41.783)
		(width 0.14224)
		(layer "In11.Cu")
		(net "M_C_DQS_DN<13>")
	)
	(segment
		(start 283.982414 -15.2908)
		(end 283.824934 -15.44828)
		(width 0.14224)
		(layer "In11.Cu")
		(net "M_C_DQS_DN<13>")
	)
	(segment
		(start 283.766514 -28.81249)
		(end 284.14472 -29.190696)
		(width 0.14224)
		(layer "In11.Cu")
		(net "M_C_DQS_DN<13>")
	)
	(segment
		(start 284.14472 -27.450796)
		(end 283.859986 -27.73553)
		(width 0.14224)
		(layer "In11.Cu")
		(net "M_C_DQS_DN<13>")
	)
	(segment
		(start 274.54987 -44.150788)
		(end 274.54987 -44.419266)
		(width 0.14224)
		(layer "In11.Cu")
		(net "M_C_DQS_DN<13>")
	)
	(segment
		(start 274.66417 -45.635926)
		(end 274.54987 -45.750226)
		(width 0.14224)
		(layer "In11.Cu")
		(net "M_C_DQS_DN<13>")
	)
	(segment
		(start 274.54987 -41.4147)
		(end 274.66417 -41.529)
		(width 0.14224)
		(layer "In11.Cu")
		(net "M_C_DQS_DN<13>")
	)
	(arc
		(start 273.704812 -57.694322)
		(mid 273.656057 -57.890674)
		(end 273.709638 -58.085736)
		(width 0.0889)
		(layer "In11.Cu")
		(net "M_C_DQS_DN<13>")
	)
	(arc
		(start 273.704812 -55.713122)
		(mid 273.656057 -55.909474)
		(end 273.709638 -56.104536)
		(width 0.0889)
		(layer "In11.Cu")
		(net "M_C_DQS_DN<13>")
	)
	(arc
		(start 273.709638 -58.085736)
		(mid 273.903733 -58.4697)
		(end 274.05457 -58.872628)
		(width 0.0889)
		(layer "In11.Cu")
		(net "M_C_DQS_DN<13>")
	)
	(arc
		(start 273.709638 -56.104536)
		(mid 273.78886 -56.393654)
		(end 273.715988 -56.684418)
		(width 0.0889)
		(layer "In11.Cu")
		(net "M_C_DQS_DN<13>")
	)
	(arc
		(start 273.709638 -55.113936)
		(mid 273.78886 -55.403054)
		(end 273.715988 -55.693818)
		(width 0.0889)
		(layer "In11.Cu")
		(net "M_C_DQS_DN<13>")
	)
	(arc
		(start 273.704812 -56.703722)
		(mid 273.656057 -56.900074)
		(end 273.709638 -57.095136)
		(width 0.0889)
		(layer "In11.Cu")
		(net "M_C_DQS_DN<13>")
	)
	(arc
		(start 273.709638 -57.095136)
		(mid 273.78886 -57.384254)
		(end 273.715988 -57.675018)
		(width 0.0889)
		(layer "In11.Cu")
		(net "M_C_DQS_DN<13>")
	)
	(segment
		(start 249.919744 -64.50584)
		(end 249.348244 -64.50584)
		(width 0.0889)
		(layer "F.Cu")
		(net "M_C_DQS_DN<12>")
	)
	(segment
		(start 228.007418 1.60147)
		(end 227.818188 1.7907)
		(width 0.1651)
		(layer "F.Cu")
		(net "M_C_DQS_DN<12>")
	)
	(segment
		(start 228.699822 3.778758)
		(end 228.699822 2.93624)
		(width 0.1651)
		(layer "F.Cu")
		(net "M_C_DQS_DN<12>")
	)
	(segment
		(start 228.215698 1.60147)
		(end 228.007418 1.60147)
		(width 0.1651)
		(layer "F.Cu")
		(net "M_C_DQS_DN<12>")
	)
	(segment
		(start 227.818188 1.7907)
		(end 227.799138 1.7907)
		(width 0.1651)
		(layer "F.Cu")
		(net "M_C_DQS_DN<12>")
	)
	(segment
		(start 228.467666 1.853438)
		(end 228.215698 1.60147)
		(width 0.1651)
		(layer "F.Cu")
		(net "M_C_DQS_DN<12>")
	)
	(segment
		(start 228.467666 2.100072)
		(end 228.467666 1.853438)
		(width 0.1651)
		(layer "F.Cu")
		(net "M_C_DQS_DN<12>")
	)
	(segment
		(start 228.699822 2.93624)
		(end 228.281738 2.518156)
		(width 0.1651)
		(layer "F.Cu")
		(net "M_C_DQS_DN<12>")
	)
	(segment
		(start 228.281738 2.286)
		(end 228.467666 2.100072)
		(width 0.1651)
		(layer "F.Cu")
		(net "M_C_DQS_DN<12>")
	)
	(segment
		(start 228.70033 3.778758)
		(end 228.699822 3.778758)
		(width 0.1651)
		(layer "F.Cu")
		(net "M_C_DQS_DN<12>")
	)
	(segment
		(start 228.281738 2.518156)
		(end 228.281738 2.286)
		(width 0.1651)
		(layer "F.Cu")
		(net "M_C_DQS_DN<12>")
	)
	(via
		(at 249.348244 -64.50584)
		(size 0.508)
		(drill 0.254)
		(layers "F.Cu" "B.Cu")
		(net "M_C_DQS_DN<12>")
	)
	(via
		(at 227.799138 1.7907)
		(size 0.508)
		(drill 0.254)
		(layers "F.Cu" "B.Cu")
		(net "M_C_DQS_DN<12>")
	)
	(via
		(at 227.792534 -3.6322)
		(size 0.508)
		(drill 0.254)
		(layers "F.Cu" "B.Cu")
		(net "M_C_DQS_DN<12>")
	)
	(segment
		(start 228.70033 -5.621782)
		(end 228.699822 -5.621782)
		(width 0.1651)
		(layer "B.Cu")
		(net "M_C_DQS_DN<12>")
	)
	(segment
		(start 228.256338 -4.1656)
		(end 228.434138 -3.9878)
		(width 0.1651)
		(layer "B.Cu")
		(net "M_C_DQS_DN<12>")
	)
	(segment
		(start 228.256338 -4.521454)
		(end 228.256338 -4.1656)
		(width 0.1651)
		(layer "B.Cu")
		(net "M_C_DQS_DN<12>")
	)
	(segment
		(start 228.699822 -5.621782)
		(end 228.699822 -4.964938)
		(width 0.1651)
		(layer "B.Cu")
		(net "M_C_DQS_DN<12>")
	)
	(segment
		(start 228.434138 -3.6576)
		(end 228.214174 -3.437636)
		(width 0.1651)
		(layer "B.Cu")
		(net "M_C_DQS_DN<12>")
	)
	(segment
		(start 228.434138 -3.9878)
		(end 228.434138 -3.6576)
		(width 0.1651)
		(layer "B.Cu")
		(net "M_C_DQS_DN<12>")
	)
	(segment
		(start 227.987098 -3.437636)
		(end 227.792534 -3.6322)
		(width 0.1651)
		(layer "B.Cu")
		(net "M_C_DQS_DN<12>")
	)
	(segment
		(start 228.699822 -4.964938)
		(end 228.256338 -4.521454)
		(width 0.1651)
		(layer "B.Cu")
		(net "M_C_DQS_DN<12>")
	)
	(segment
		(start 228.214174 -3.437636)
		(end 227.987098 -3.437636)
		(width 0.1651)
		(layer "B.Cu")
		(net "M_C_DQS_DN<12>")
	)
	(segment
		(start 248.996708 -62.715902)
		(end 249.001534 -62.724538)
		(width 0.0889)
		(layer "In11.Cu")
		(net "M_C_DQS_DN<12>")
	)
	(segment
		(start 242.39093 -45.123608)
		(end 242.570762 -45.30344)
		(width 0.14224)
		(layer "In11.Cu")
		(net "M_C_DQS_DN<12>")
	)
	(segment
		(start 248.996708 -59.744102)
		(end 249.001534 -59.752738)
		(width 0.0889)
		(layer "In11.Cu")
		(net "M_C_DQS_DN<12>")
	)
	(segment
		(start 248.996708 -57.762902)
		(end 249.001534 -57.771538)
		(width 0.0889)
		(layer "In11.Cu")
		(net "M_C_DQS_DN<12>")
	)
	(segment
		(start 248.537222 -54.960012)
		(end 249.007884 -55.801006)
		(width 0.0889)
		(layer "In11.Cu")
		(net "M_C_DQS_DN<12>")
	)
	(segment
		(start 243.459508 -46.192186)
		(end 243.63934 -46.372018)
		(width 0.14224)
		(layer "In11.Cu")
		(net "M_C_DQS_DN<12>")
	)
	(segment
		(start 231.712516 -32.238188)
		(end 234.561634 -35.087306)
		(width 0.14224)
		(layer "In11.Cu")
		(net "M_C_DQS_DN<12>")
	)
	(segment
		(start 248.999248 -63.71082)
		(end 249.000772 -63.713868)
		(width 0.0889)
		(layer "In11.Cu")
		(net "M_C_DQS_DN<12>")
	)
	(segment
		(start 245.03634 -48.715422)
		(end 244.92204 -48.829722)
		(width 0.14224)
		(layer "In11.Cu")
		(net "M_C_DQS_DN<12>")
	)
	(segment
		(start 228.574854 -11.43508)
		(end 228.574854 -14.19352)
		(width 0.14224)
		(layer "In11.Cu")
		(net "M_C_DQS_DN<12>")
	)
	(segment
		(start 228.230938 -4.070604)
		(end 228.230938 -4.509008)
		(width 0.14224)
		(layer "In11.Cu")
		(net "M_C_DQS_DN<12>")
	)
	(segment
		(start 242.570762 -45.30344)
		(end 242.570762 -45.464984)
		(width 0.14224)
		(layer "In11.Cu")
		(net "M_C_DQS_DN<12>")
	)
	(segment
		(start 241.262916 -43.995594)
		(end 241.442748 -44.175426)
		(width 0.14224)
		(layer "In11.Cu")
		(net "M_C_DQS_DN<12>")
	)
	(segment
		(start 228.732334 -11.2776)
		(end 228.574854 -11.43508)
		(width 0.14224)
		(layer "In11.Cu")
		(net "M_C_DQS_DN<12>")
	)
	(segment
		(start 229.80015 -32.090106)
		(end 229.80015 -32.354266)
		(width 0.14224)
		(layer "In11.Cu")
		(net "M_C_DQS_DN<12>")
	)
	(segment
		(start 242.912138 -45.644562)
		(end 243.09197 -45.824394)
		(width 0.14224)
		(layer "In11.Cu")
		(net "M_C_DQS_DN<12>")
	)
	(segment
		(start 249.007884 -58.35142)
		(end 249.001534 -58.362088)
		(width 0.0889)
		(layer "In11.Cu")
		(net "M_C_DQS_DN<12>")
	)
	(segment
		(start 245.03634 -48.461422)
		(end 245.03634 -48.715422)
		(width 0.14224)
		(layer "In11.Cu")
		(net "M_C_DQS_DN<12>")
	)
	(segment
		(start 241.80292 -44.535344)
		(end 241.982752 -44.715176)
		(width 0.14224)
		(layer "In11.Cu")
		(net "M_C_DQS_DN<12>")
	)
	(segment
		(start 228.581458 1.257808)
		(end 228.244146 1.59512)
		(width 0.14224)
		(layer "In11.Cu")
		(net "M_C_DQS_DN<12>")
	)
	(segment
		(start 231.176068 -32.238188)
		(end 231.712516 -32.238188)
		(width 0.14224)
		(layer "In11.Cu")
		(net "M_C_DQS_DN<12>")
	)
	(segment
		(start 241.101372 -43.995594)
		(end 241.262916 -43.995594)
		(width 0.14224)
		(layer "In11.Cu")
		(net "M_C_DQS_DN<12>")
	)
	(segment
		(start 248.311924 -53.2384)
		(end 248.311924 -54.734714)
		(width 0.0889)
		(layer "In11.Cu")
		(net "M_C_DQS_DN<12>")
	)
	(segment
		(start 248.996708 -60.734702)
		(end 249.001534 -60.743338)
		(width 0.0889)
		(layer "In11.Cu")
		(net "M_C_DQS_DN<12>")
	)
	(segment
		(start 249.000772 -63.713868)
		(end 249.007884 -63.725806)
		(width 0.0889)
		(layer "In11.Cu")
		(net "M_C_DQS_DN<12>")
	)
	(segment
		(start 230.28275 -32.836866)
		(end 230.57739 -32.836866)
		(width 0.14224)
		(layer "In11.Cu")
		(net "M_C_DQS_DN<12>")
	)
	(segment
		(start 227.773738 -4.8006)
		(end 227.590858 -4.98348)
		(width 0.14224)
		(layer "In11.Cu")
		(net "M_C_DQS_DN<12>")
	)
	(segment
		(start 243.297964 -46.192186)
		(end 243.459508 -46.192186)
		(width 0.14224)
		(layer "In11.Cu")
		(net "M_C_DQS_DN<12>")
	)
	(segment
		(start 249.35815 -64.501522)
		(end 249.348244 -64.50584)
		(width 0.0889)
		(layer "In11.Cu")
		(net "M_C_DQS_DN<12>")
	)
	(segment
		(start 244.73535 -47.629572)
		(end 244.92204 -47.816262)
		(width 0.14224)
		(layer "In11.Cu")
		(net "M_C_DQS_DN<12>")
	)
	(segment
		(start 228.574854 -14.19352)
		(end 228.732334 -14.351)
		(width 0.14224)
		(layer "In11.Cu")
		(net "M_C_DQS_DN<12>")
	)
	(segment
		(start 249.001534 -62.724538)
		(end 249.007884 -62.735206)
		(width 0.0889)
		(layer "In11.Cu")
		(net "M_C_DQS_DN<12>")
	)
	(segment
		(start 234.561634 -35.087306)
		(end 234.561634 -37.455856)
		(width 0.14224)
		(layer "In11.Cu")
		(net "M_C_DQS_DN<12>")
	)
	(segment
		(start 228.732334 -10.2616)
		(end 228.732334 -10.5156)
		(width 0.14224)
		(layer "In11.Cu")
		(net "M_C_DQS_DN<12>")
	)
	(segment
		(start 228.574854 -14.76248)
		(end 228.574854 -29.100526)
		(width 0.14224)
		(layer "In11.Cu")
		(net "M_C_DQS_DN<12>")
	)
	(segment
		(start 249.001534 -60.743338)
		(end 249.007884 -60.754006)
		(width 0.0889)
		(layer "In11.Cu")
		(net "M_C_DQS_DN<12>")
	)
	(segment
		(start 230.414068 -31.476188)
		(end 229.80015 -32.090106)
		(width 0.14224)
		(layer "In11.Cu")
		(net "M_C_DQS_DN<12>")
	)
	(segment
		(start 249.13209 -63.979298)
		(end 249.35815 -64.501522)
		(width 0.0889)
		(layer "In11.Cu")
		(net "M_C_DQS_DN<12>")
	)
	(segment
		(start 248.99747 -63.707772)
		(end 248.997978 -63.708788)
		(width 0.0889)
		(layer "In11.Cu")
		(net "M_C_DQS_DN<12>")
	)
	(segment
		(start 230.57739 -32.836866)
		(end 231.176068 -32.238188)
		(width 0.14224)
		(layer "In11.Cu")
		(net "M_C_DQS_DN<12>")
	)
	(segment
		(start 248.311924 -54.734714)
		(end 248.537222 -54.960012)
		(width 0.0889)
		(layer "In11.Cu")
		(net "M_C_DQS_DN<12>")
	)
	(segment
		(start 244.39372 -47.287942)
		(end 244.555518 -47.287942)
		(width 0.14224)
		(layer "In11.Cu")
		(net "M_C_DQS_DN<12>")
	)
	(segment
		(start 228.574854 -10.86612)
		(end 228.732334 -11.0236)
		(width 0.14224)
		(layer "In11.Cu")
		(net "M_C_DQS_DN<12>")
	)
	(segment
		(start 243.09197 -45.824394)
		(end 243.09197 -45.986192)
		(width 0.14224)
		(layer "In11.Cu")
		(net "M_C_DQS_DN<12>")
	)
	(segment
		(start 242.570762 -45.464984)
		(end 242.75034 -45.644562)
		(width 0.14224)
		(layer "In11.Cu")
		(net "M_C_DQS_DN<12>")
	)
	(segment
		(start 241.442748 -44.175426)
		(end 241.442748 -44.33697)
		(width 0.14224)
		(layer "In11.Cu")
		(net "M_C_DQS_DN<12>")
	)
	(segment
		(start 228.732334 -10.5156)
		(end 228.574854 -10.67308)
		(width 0.14224)
		(layer "In11.Cu")
		(net "M_C_DQS_DN<12>")
	)
	(segment
		(start 241.442748 -44.33697)
		(end 241.641122 -44.535344)
		(width 0.14224)
		(layer "In11.Cu")
		(net "M_C_DQS_DN<12>")
	)
	(segment
		(start 244.92204 -48.347122)
		(end 245.03634 -48.461422)
		(width 0.14224)
		(layer "In11.Cu")
		(net "M_C_DQS_DN<12>")
	)
	(segment
		(start 248.996708 -61.725302)
		(end 249.001534 -61.733938)
		(width 0.0889)
		(layer "In11.Cu")
		(net "M_C_DQS_DN<12>")
	)
	(segment
		(start 227.792534 -3.6322)
		(end 228.581458 -2.843276)
		(width 0.14224)
		(layer "In11.Cu")
		(net "M_C_DQS_DN<12>")
	)
	(segment
		(start 249.001534 -56.780938)
		(end 249.007884 -56.791606)
		(width 0.0889)
		(layer "In11.Cu")
		(net "M_C_DQS_DN<12>")
	)
	(segment
		(start 243.09197 -45.986192)
		(end 243.297964 -46.192186)
		(width 0.14224)
		(layer "In11.Cu")
		(net "M_C_DQS_DN<12>")
	)
	(segment
		(start 228.732334 -14.605)
		(end 228.574854 -14.76248)
		(width 0.14224)
		(layer "In11.Cu")
		(net "M_C_DQS_DN<12>")
	)
	(segment
		(start 228.732334 -14.351)
		(end 228.732334 -14.605)
		(width 0.14224)
		(layer "In11.Cu")
		(net "M_C_DQS_DN<12>")
	)
	(segment
		(start 248.996708 -56.772302)
		(end 249.001534 -56.780938)
		(width 0.0889)
		(layer "In11.Cu")
		(net "M_C_DQS_DN<12>")
	)
	(segment
		(start 240.741962 -43.47464)
		(end 240.921794 -43.654472)
		(width 0.14224)
		(layer "In11.Cu")
		(net "M_C_DQS_DN<12>")
	)
	(segment
		(start 246.217948 -50.48758)
		(end 246.908066 -51.177698)
		(width 0.0889)
		(layer "In11.Cu")
		(net "M_C_DQS_DN<12>")
	)
	(segment
		(start 228.244146 1.59512)
		(end 227.994718 1.59512)
		(width 0.14224)
		(layer "In11.Cu")
		(net "M_C_DQS_DN<12>")
	)
	(segment
		(start 249.001534 -61.733938)
		(end 249.007884 -61.744606)
		(width 0.0889)
		(layer "In11.Cu")
		(net "M_C_DQS_DN<12>")
	)
	(segment
		(start 248.997978 -63.708788)
		(end 248.998486 -63.70955)
		(width 0.0889)
		(layer "In11.Cu")
		(net "M_C_DQS_DN<12>")
	)
	(segment
		(start 243.63934 -46.533562)
		(end 243.818918 -46.71314)
		(width 0.14224)
		(layer "In11.Cu")
		(net "M_C_DQS_DN<12>")
	)
	(segment
		(start 228.574854 -6.340348)
		(end 228.574854 -9.34212)
		(width 0.14224)
		(layer "In11.Cu")
		(net "M_C_DQS_DN<12>")
	)
	(segment
		(start 244.555518 -47.287942)
		(end 244.73535 -47.467774)
		(width 0.14224)
		(layer "In11.Cu")
		(net "M_C_DQS_DN<12>")
	)
	(segment
		(start 244.92204 -48.829722)
		(end 244.92204 -49.135792)
		(width 0.14224)
		(layer "In11.Cu")
		(net "M_C_DQS_DN<12>")
	)
	(segment
		(start 227.590858 -5.356352)
		(end 228.574854 -6.340348)
		(width 0.14224)
		(layer "In11.Cu")
		(net "M_C_DQS_DN<12>")
	)
	(segment
		(start 234.561634 -37.455856)
		(end 240.580418 -43.47464)
		(width 0.14224)
		(layer "In11.Cu")
		(net "M_C_DQS_DN<12>")
	)
	(segment
		(start 247.085104 -52.01158)
		(end 248.311924 -53.2384)
		(width 0.0889)
		(layer "In11.Cu")
		(net "M_C_DQS_DN<12>")
	)
	(segment
		(start 244.92204 -49.135792)
		(end 246.2022 -50.415952)
		(width 0.14224)
		(layer "In11.Cu")
		(net "M_C_DQS_DN<12>")
	)
	(segment
		(start 228.574854 -10.10412)
		(end 228.732334 -10.2616)
		(width 0.14224)
		(layer "In11.Cu")
		(net "M_C_DQS_DN<12>")
	)
	(segment
		(start 227.792534 -3.6322)
		(end 228.230938 -4.070604)
		(width 0.14224)
		(layer "In11.Cu")
		(net "M_C_DQS_DN<12>")
	)
	(segment
		(start 246.908066 -51.177698)
		(end 247.085104 -51.484784)
		(width 0.0889)
		(layer "In11.Cu")
		(net "M_C_DQS_DN<12>")
	)
	(segment
		(start 240.921794 -43.816016)
		(end 241.101372 -43.995594)
		(width 0.14224)
		(layer "In11.Cu")
		(net "M_C_DQS_DN<12>")
	)
	(segment
		(start 228.574854 -10.67308)
		(end 228.574854 -10.86612)
		(width 0.14224)
		(layer "In11.Cu")
		(net "M_C_DQS_DN<12>")
	)
	(segment
		(start 243.980462 -46.71314)
		(end 244.160294 -46.892972)
		(width 0.14224)
		(layer "In11.Cu")
		(net "M_C_DQS_DN<12>")
	)
	(segment
		(start 228.230938 -4.509008)
		(end 227.939346 -4.8006)
		(width 0.14224)
		(layer "In11.Cu")
		(net "M_C_DQS_DN<12>")
	)
	(segment
		(start 228.581458 -2.843276)
		(end 228.581458 1.257808)
		(width 0.14224)
		(layer "In11.Cu")
		(net "M_C_DQS_DN<12>")
	)
	(segment
		(start 244.92204 -47.816262)
		(end 244.92204 -48.347122)
		(width 0.14224)
		(layer "In11.Cu")
		(net "M_C_DQS_DN<12>")
	)
	(segment
		(start 228.732334 -9.4996)
		(end 228.732334 -9.7536)
		(width 0.14224)
		(layer "In11.Cu")
		(net "M_C_DQS_DN<12>")
	)
	(segment
		(start 241.641122 -44.535344)
		(end 241.80292 -44.535344)
		(width 0.14224)
		(layer "In11.Cu")
		(net "M_C_DQS_DN<12>")
	)
	(segment
		(start 229.80015 -32.354266)
		(end 230.28275 -32.836866)
		(width 0.14224)
		(layer "In11.Cu")
		(net "M_C_DQS_DN<12>")
	)
	(segment
		(start 243.63934 -46.372018)
		(end 243.63934 -46.533562)
		(width 0.14224)
		(layer "In11.Cu")
		(net "M_C_DQS_DN<12>")
	)
	(segment
		(start 242.75034 -45.644562)
		(end 242.912138 -45.644562)
		(width 0.14224)
		(layer "In11.Cu")
		(net "M_C_DQS_DN<12>")
	)
	(segment
		(start 228.732334 -11.0236)
		(end 228.732334 -11.2776)
		(width 0.14224)
		(layer "In11.Cu")
		(net "M_C_DQS_DN<12>")
	)
	(segment
		(start 247.085104 -51.484784)
		(end 247.085104 -52.01158)
		(width 0.0889)
		(layer "In11.Cu")
		(net "M_C_DQS_DN<12>")
	)
	(segment
		(start 244.160294 -46.892972)
		(end 244.160294 -47.054516)
		(width 0.14224)
		(layer "In11.Cu")
		(net "M_C_DQS_DN<12>")
	)
	(segment
		(start 248.998486 -63.70955)
		(end 248.999248 -63.71082)
		(width 0.0889)
		(layer "In11.Cu")
		(net "M_C_DQS_DN<12>")
	)
	(segment
		(start 242.229386 -45.123608)
		(end 242.39093 -45.123608)
		(width 0.14224)
		(layer "In11.Cu")
		(net "M_C_DQS_DN<12>")
	)
	(segment
		(start 244.73535 -47.467774)
		(end 244.73535 -47.629572)
		(width 0.14224)
		(layer "In11.Cu")
		(net "M_C_DQS_DN<12>")
	)
	(segment
		(start 227.994718 1.59512)
		(end 227.799138 1.7907)
		(width 0.14224)
		(layer "In11.Cu")
		(net "M_C_DQS_DN<12>")
	)
	(segment
		(start 228.574854 -29.100526)
		(end 230.414068 -30.93974)
		(width 0.14224)
		(layer "In11.Cu")
		(net "M_C_DQS_DN<12>")
	)
	(segment
		(start 228.574854 -9.91108)
		(end 228.574854 -10.10412)
		(width 0.14224)
		(layer "In11.Cu")
		(net "M_C_DQS_DN<12>")
	)
	(segment
		(start 248.996708 -63.706502)
		(end 248.99747 -63.707772)
		(width 0.0889)
		(layer "In11.Cu")
		(net "M_C_DQS_DN<12>")
	)
	(segment
		(start 227.590858 -4.98348)
		(end 227.590858 -5.356352)
		(width 0.14224)
		(layer "In11.Cu")
		(net "M_C_DQS_DN<12>")
	)
	(segment
		(start 246.2022 -50.415952)
		(end 246.217948 -50.4317)
		(width 0.0889)
		(layer "In11.Cu")
		(net "M_C_DQS_DN<12>")
	)
	(segment
		(start 240.580418 -43.47464)
		(end 240.741962 -43.47464)
		(width 0.14224)
		(layer "In11.Cu")
		(net "M_C_DQS_DN<12>")
	)
	(segment
		(start 227.939346 -4.8006)
		(end 227.773738 -4.8006)
		(width 0.14224)
		(layer "In11.Cu")
		(net "M_C_DQS_DN<12>")
	)
	(segment
		(start 243.818918 -46.71314)
		(end 243.980462 -46.71314)
		(width 0.14224)
		(layer "In11.Cu")
		(net "M_C_DQS_DN<12>")
	)
	(segment
		(start 241.982752 -44.715176)
		(end 241.982752 -44.876974)
		(width 0.14224)
		(layer "In11.Cu")
		(net "M_C_DQS_DN<12>")
	)
	(segment
		(start 241.982752 -44.876974)
		(end 242.229386 -45.123608)
		(width 0.14224)
		(layer "In11.Cu")
		(net "M_C_DQS_DN<12>")
	)
	(segment
		(start 244.160294 -47.054516)
		(end 244.39372 -47.287942)
		(width 0.14224)
		(layer "In11.Cu")
		(net "M_C_DQS_DN<12>")
	)
	(segment
		(start 246.217948 -50.4317)
		(end 246.217948 -50.48758)
		(width 0.0889)
		(layer "In11.Cu")
		(net "M_C_DQS_DN<12>")
	)
	(segment
		(start 240.921794 -43.654472)
		(end 240.921794 -43.816016)
		(width 0.14224)
		(layer "In11.Cu")
		(net "M_C_DQS_DN<12>")
	)
	(segment
		(start 230.414068 -30.93974)
		(end 230.414068 -31.476188)
		(width 0.14224)
		(layer "In11.Cu")
		(net "M_C_DQS_DN<12>")
	)
	(segment
		(start 228.574854 -9.34212)
		(end 228.732334 -9.4996)
		(width 0.14224)
		(layer "In11.Cu")
		(net "M_C_DQS_DN<12>")
	)
	(segment
		(start 228.732334 -9.7536)
		(end 228.574854 -9.91108)
		(width 0.14224)
		(layer "In11.Cu")
		(net "M_C_DQS_DN<12>")
	)
	(segment
		(start 249.001534 -59.752738)
		(end 249.007884 -59.763406)
		(width 0.0889)
		(layer "In11.Cu")
		(net "M_C_DQS_DN<12>")
	)
	(arc
		(start 249.007884 -59.763406)
		(mid 249.080682 -60.054169)
		(end 249.001534 -60.343288)
		(width 0.0889)
		(layer "In11.Cu")
		(net "M_C_DQS_DN<12>")
	)
	(arc
		(start 249.007884 -60.754006)
		(mid 249.080682 -61.044769)
		(end 249.001534 -61.333888)
		(width 0.0889)
		(layer "In11.Cu")
		(net "M_C_DQS_DN<12>")
	)
	(arc
		(start 249.007884 -63.725806)
		(mid 249.072966 -63.851092)
		(end 249.13209 -63.979298)
		(width 0.0889)
		(layer "In11.Cu")
		(net "M_C_DQS_DN<12>")
	)
	(arc
		(start 249.001534 -60.343288)
		(mid 248.948064 -60.538351)
		(end 248.996708 -60.734702)
		(width 0.0889)
		(layer "In11.Cu")
		(net "M_C_DQS_DN<12>")
	)
	(arc
		(start 249.001534 -63.315088)
		(mid 248.948064 -63.510151)
		(end 248.996708 -63.706502)
		(width 0.0889)
		(layer "In11.Cu")
		(net "M_C_DQS_DN<12>")
	)
	(arc
		(start 249.001534 -59.352688)
		(mid 248.948064 -59.547751)
		(end 248.996708 -59.744102)
		(width 0.0889)
		(layer "In11.Cu")
		(net "M_C_DQS_DN<12>")
	)
	(arc
		(start 249.001534 -62.324488)
		(mid 248.948064 -62.519551)
		(end 248.996708 -62.715902)
		(width 0.0889)
		(layer "In11.Cu")
		(net "M_C_DQS_DN<12>")
	)
	(arc
		(start 249.007884 -62.735206)
		(mid 249.080682 -63.025969)
		(end 249.001534 -63.315088)
		(width 0.0889)
		(layer "In11.Cu")
		(net "M_C_DQS_DN<12>")
	)
	(arc
		(start 249.007884 -61.744606)
		(mid 249.080682 -62.035369)
		(end 249.001534 -62.324488)
		(width 0.0889)
		(layer "In11.Cu")
		(net "M_C_DQS_DN<12>")
	)
	(arc
		(start 249.001534 -58.362088)
		(mid 248.948035 -58.561986)
		(end 249.001534 -58.761884)
		(width 0.0889)
		(layer "In11.Cu")
		(net "M_C_DQS_DN<12>")
	)
	(arc
		(start 249.007884 -55.801006)
		(mid 249.080682 -56.091769)
		(end 249.001534 -56.380888)
		(width 0.0889)
		(layer "In11.Cu")
		(net "M_C_DQS_DN<12>")
	)
	(arc
		(start 249.001534 -58.761884)
		(mid 249.080665 -59.057286)
		(end 249.001534 -59.352688)
		(width 0.0889)
		(layer "In11.Cu")
		(net "M_C_DQS_DN<12>")
	)
	(arc
		(start 249.001534 -57.371488)
		(mid 248.948064 -57.566551)
		(end 248.996708 -57.762902)
		(width 0.0889)
		(layer "In11.Cu")
		(net "M_C_DQS_DN<12>")
	)
	(arc
		(start 249.001534 -56.380888)
		(mid 248.948064 -56.575951)
		(end 248.996708 -56.772302)
		(width 0.0889)
		(layer "In11.Cu")
		(net "M_C_DQS_DN<12>")
	)
	(arc
		(start 249.001534 -57.771538)
		(mid 249.080756 -58.060656)
		(end 249.007884 -58.35142)
		(width 0.0889)
		(layer "In11.Cu")
		(net "M_C_DQS_DN<12>")
	)
	(arc
		(start 249.007884 -56.791606)
		(mid 249.080682 -57.082369)
		(end 249.001534 -57.371488)
		(width 0.0889)
		(layer "In11.Cu")
		(net "M_C_DQS_DN<12>")
	)
	(arc
		(start 249.001534 -61.333888)
		(mid 248.948064 -61.528951)
		(end 248.996708 -61.725302)
		(width 0.0889)
		(layer "In11.Cu")
		(net "M_C_DQS_DN<12>")
	)
	(segment
		(start 219.349828 2.93624)
		(end 218.931744 2.518156)
		(width 0.1651)
		(layer "F.Cu")
		(net "M_C_DQS_DN<11>")
	)
	(segment
		(start 244.768624 -57.57164)
		(end 244.197124 -57.57164)
		(width 0.0889)
		(layer "F.Cu")
		(net "M_C_DQS_DN<11>")
	)
	(segment
		(start 218.931744 2.286)
		(end 219.117672 2.100072)
		(width 0.1651)
		(layer "F.Cu")
		(net "M_C_DQS_DN<11>")
	)
	(segment
		(start 218.865704 1.60147)
		(end 218.657424 1.60147)
		(width 0.1651)
		(layer "F.Cu")
		(net "M_C_DQS_DN<11>")
	)
	(segment
		(start 218.468194 1.7907)
		(end 218.449144 1.7907)
		(width 0.1651)
		(layer "F.Cu")
		(net "M_C_DQS_DN<11>")
	)
	(segment
		(start 219.117672 1.853438)
		(end 218.865704 1.60147)
		(width 0.1651)
		(layer "F.Cu")
		(net "M_C_DQS_DN<11>")
	)
	(segment
		(start 219.349828 3.778758)
		(end 219.349828 2.93624)
		(width 0.1651)
		(layer "F.Cu")
		(net "M_C_DQS_DN<11>")
	)
	(segment
		(start 219.117672 2.100072)
		(end 219.117672 1.853438)
		(width 0.1651)
		(layer "F.Cu")
		(net "M_C_DQS_DN<11>")
	)
	(segment
		(start 219.350336 3.778758)
		(end 219.349828 3.778758)
		(width 0.1651)
		(layer "F.Cu")
		(net "M_C_DQS_DN<11>")
	)
	(segment
		(start 218.931744 2.518156)
		(end 218.931744 2.286)
		(width 0.1651)
		(layer "F.Cu")
		(net "M_C_DQS_DN<11>")
	)
	(segment
		(start 218.657424 1.60147)
		(end 218.468194 1.7907)
		(width 0.1651)
		(layer "F.Cu")
		(net "M_C_DQS_DN<11>")
	)
	(via
		(at 218.449144 1.7907)
		(size 0.508)
		(drill 0.254)
		(layers "F.Cu" "B.Cu")
		(net "M_C_DQS_DN<11>")
	)
	(via
		(at 218.44254 -3.6322)
		(size 0.508)
		(drill 0.254)
		(layers "F.Cu" "B.Cu")
		(net "M_C_DQS_DN<11>")
	)
	(via
		(at 244.197124 -57.57164)
		(size 0.508)
		(drill 0.254)
		(layers "F.Cu" "B.Cu")
		(net "M_C_DQS_DN<11>")
	)
	(segment
		(start 218.637104 -3.437636)
		(end 218.44254 -3.6322)
		(width 0.1651)
		(layer "B.Cu")
		(net "M_C_DQS_DN<11>")
	)
	(segment
		(start 219.349828 -5.621782)
		(end 219.349828 -4.964938)
		(width 0.1651)
		(layer "B.Cu")
		(net "M_C_DQS_DN<11>")
	)
	(segment
		(start 219.084144 -3.6576)
		(end 218.86418 -3.437636)
		(width 0.1651)
		(layer "B.Cu")
		(net "M_C_DQS_DN<11>")
	)
	(segment
		(start 219.350336 -5.621782)
		(end 219.349828 -5.621782)
		(width 0.1651)
		(layer "B.Cu")
		(net "M_C_DQS_DN<11>")
	)
	(segment
		(start 219.349828 -4.964938)
		(end 218.906344 -4.521454)
		(width 0.1651)
		(layer "B.Cu")
		(net "M_C_DQS_DN<11>")
	)
	(segment
		(start 218.86418 -3.437636)
		(end 218.637104 -3.437636)
		(width 0.1651)
		(layer "B.Cu")
		(net "M_C_DQS_DN<11>")
	)
	(segment
		(start 218.906344 -4.1656)
		(end 219.084144 -3.9878)
		(width 0.1651)
		(layer "B.Cu")
		(net "M_C_DQS_DN<11>")
	)
	(segment
		(start 219.084144 -3.9878)
		(end 219.084144 -3.6576)
		(width 0.1651)
		(layer "B.Cu")
		(net "M_C_DQS_DN<11>")
	)
	(segment
		(start 218.906344 -4.521454)
		(end 218.906344 -4.1656)
		(width 0.1651)
		(layer "B.Cu")
		(net "M_C_DQS_DN<11>")
	)
	(segment
		(start 239.035082 -54.99989)
		(end 239.067848 -54.99989)
		(width 0.0889)
		(layer "In11.Cu")
		(net "M_C_DQS_DN<11>")
	)
	(segment
		(start 231.261158 -45.635926)
		(end 231.422702 -45.635926)
		(width 0.14224)
		(layer "In11.Cu")
		(net "M_C_DQS_DN<11>")
	)
	(segment
		(start 239.889792 -55.494936)
		(end 239.922558 -55.494936)
		(width 0.0889)
		(layer "In11.Cu")
		(net "M_C_DQS_DN<11>")
	)
	(segment
		(start 237.318042 -54.00929)
		(end 237.350808 -54.00929)
		(width 0.0889)
		(layer "In11.Cu")
		(net "M_C_DQS_DN<11>")
	)
	(segment
		(start 227.652326 -41.86555)
		(end 227.832158 -42.045382)
		(width 0.14224)
		(layer "In11.Cu")
		(net "M_C_DQS_DN<11>")
	)
	(segment
		(start 233.798364 -49.132236)
		(end 234.645708 -49.658778)
		(width 0.14224)
		(layer "In11.Cu")
		(net "M_C_DQS_DN<11>")
	)
	(segment
		(start 229.736142 -43.949366)
		(end 229.915974 -44.129198)
		(width 0.14224)
		(layer "In11.Cu")
		(net "M_C_DQS_DN<11>")
	)
	(segment
		(start 230.436928 -44.811696)
		(end 230.616506 -44.991274)
		(width 0.14224)
		(layer "In11.Cu")
		(net "M_C_DQS_DN<11>")
	)
	(segment
		(start 234.645708 -49.658778)
		(end 234.886246 -50.083974)
		(width 0.14224)
		(layer "In11.Cu")
		(net "M_C_DQS_DN<11>")
	)
	(segment
		(start 219.38234 -9.4996)
		(end 219.38234 -9.7536)
		(width 0.14224)
		(layer "In11.Cu")
		(net "M_C_DQS_DN<11>")
	)
	(segment
		(start 218.44254 -3.6322)
		(end 218.880944 -4.070604)
		(width 0.14224)
		(layer "In11.Cu")
		(net "M_C_DQS_DN<11>")
	)
	(segment
		(start 232.825544 -48.159416)
		(end 232.987342 -48.159416)
		(width 0.14224)
		(layer "In11.Cu")
		(net "M_C_DQS_DN<11>")
	)
	(segment
		(start 219.231464 -2.843276)
		(end 219.231464 1.257808)
		(width 0.14224)
		(layer "In11.Cu")
		(net "M_C_DQS_DN<11>")
	)
	(segment
		(start 229.915974 -44.290742)
		(end 230.095552 -44.47032)
		(width 0.14224)
		(layer "In11.Cu")
		(net "M_C_DQS_DN<11>")
	)
	(segment
		(start 234.897168 -50.103278)
		(end 234.882182 -50.157126)
		(width 0.0889)
		(layer "In11.Cu")
		(net "M_C_DQS_DN<11>")
	)
	(segment
		(start 235.594144 -52.027836)
		(end 235.629958 -52.027836)
		(width 0.0889)
		(layer "In11.Cu")
		(net "M_C_DQS_DN<11>")
	)
	(segment
		(start 231.799892 -47.134018)
		(end 232.204006 -47.538132)
		(width 0.14224)
		(layer "In11.Cu")
		(net "M_C_DQS_DN<11>")
	)
	(segment
		(start 229.39502 -43.769788)
		(end 229.574598 -43.949366)
		(width 0.14224)
		(layer "In11.Cu")
		(net "M_C_DQS_DN<11>")
	)
	(segment
		(start 231.422702 -45.635926)
		(end 231.602534 -45.815758)
		(width 0.14224)
		(layer "In11.Cu")
		(net "M_C_DQS_DN<11>")
	)
	(segment
		(start 228.874066 -43.08729)
		(end 228.874066 -43.248834)
		(width 0.14224)
		(layer "In11.Cu")
		(net "M_C_DQS_DN<11>")
	)
	(segment
		(start 218.240864 -5.254752)
		(end 219.22486 -6.238748)
		(width 0.14224)
		(layer "In11.Cu")
		(net "M_C_DQS_DN<11>")
	)
	(segment
		(start 229.215188 -43.428412)
		(end 229.39502 -43.608244)
		(width 0.14224)
		(layer "In11.Cu")
		(net "M_C_DQS_DN<11>")
	)
	(segment
		(start 227.079302 -41.292526)
		(end 227.259134 -41.472358)
		(width 0.14224)
		(layer "In11.Cu")
		(net "M_C_DQS_DN<11>")
	)
	(segment
		(start 218.423744 -4.8006)
		(end 218.240864 -4.98348)
		(width 0.14224)
		(layer "In11.Cu")
		(net "M_C_DQS_DN<11>")
	)
	(segment
		(start 219.38234 -14.3764)
		(end 219.38234 -14.6304)
		(width 0.14224)
		(layer "In11.Cu")
		(net "M_C_DQS_DN<11>")
	)
	(segment
		(start 218.880944 -4.5974)
		(end 218.677744 -4.8006)
		(width 0.14224)
		(layer "In11.Cu")
		(net "M_C_DQS_DN<11>")
	)
	(segment
		(start 219.22486 -10.67308)
		(end 219.22486 -10.86612)
		(width 0.14224)
		(layer "In11.Cu")
		(net "M_C_DQS_DN<11>")
	)
	(segment
		(start 218.240864 -4.98348)
		(end 218.240864 -5.254752)
		(width 0.14224)
		(layer "In11.Cu")
		(net "M_C_DQS_DN<11>")
	)
	(segment
		(start 228.011736 -42.386504)
		(end 228.17328 -42.386504)
		(width 0.14224)
		(layer "In11.Cu")
		(net "M_C_DQS_DN<11>")
	)
	(segment
		(start 219.38234 -10.2616)
		(end 219.38234 -10.5156)
		(width 0.14224)
		(layer "In11.Cu")
		(net "M_C_DQS_DN<11>")
	)
	(segment
		(start 231.602534 -45.815758)
		(end 231.602534 -45.977302)
		(width 0.14224)
		(layer "In11.Cu")
		(net "M_C_DQS_DN<11>")
	)
	(segment
		(start 236.455712 -53.513736)
		(end 236.488478 -53.513736)
		(width 0.0889)
		(layer "In11.Cu")
		(net "M_C_DQS_DN<11>")
	)
	(segment
		(start 242.469162 -56.98109)
		(end 242.50523 -56.98109)
		(width 0.0889)
		(layer "In11.Cu")
		(net "M_C_DQS_DN<11>")
	)
	(segment
		(start 219.38234 -9.7536)
		(end 219.22486 -9.91108)
		(width 0.14224)
		(layer "In11.Cu")
		(net "M_C_DQS_DN<11>")
	)
	(segment
		(start 219.38234 -14.6304)
		(end 219.22486 -14.78788)
		(width 0.14224)
		(layer "In11.Cu")
		(net "M_C_DQS_DN<11>")
	)
	(segment
		(start 232.204006 -47.538132)
		(end 232.366058 -47.538132)
		(width 0.14224)
		(layer "In11.Cu")
		(net "M_C_DQS_DN<11>")
	)
	(segment
		(start 242.992148 -57.275984)
		(end 242.99545 -57.281826)
		(width 0.0889)
		(layer "In11.Cu")
		(net "M_C_DQS_DN<11>")
	)
	(segment
		(start 219.38234 -11.0236)
		(end 219.38234 -11.2776)
		(width 0.14224)
		(layer "In11.Cu")
		(net "M_C_DQS_DN<11>")
	)
	(segment
		(start 219.22486 -9.91108)
		(end 219.22486 -10.10412)
		(width 0.14224)
		(layer "In11.Cu")
		(net "M_C_DQS_DN<11>")
	)
	(segment
		(start 227.490782 -41.86555)
		(end 227.652326 -41.86555)
		(width 0.14224)
		(layer "In11.Cu")
		(net "M_C_DQS_DN<11>")
	)
	(segment
		(start 240.752122 -55.99049)
		(end 240.784888 -55.99049)
		(width 0.0889)
		(layer "In11.Cu")
		(net "M_C_DQS_DN<11>")
	)
	(segment
		(start 228.53269 -42.907458)
		(end 228.694234 -42.907458)
		(width 0.14224)
		(layer "In11.Cu")
		(net "M_C_DQS_DN<11>")
	)
	(segment
		(start 219.22486 -11.43508)
		(end 219.22486 -14.21892)
		(width 0.14224)
		(layer "In11.Cu")
		(net "M_C_DQS_DN<11>")
	)
	(segment
		(start 219.22486 -24.941022)
		(end 218.61272 -25.553162)
		(width 0.14224)
		(layer "In11.Cu")
		(net "M_C_DQS_DN<11>")
	)
	(segment
		(start 230.095552 -44.47032)
		(end 230.257096 -44.47032)
		(width 0.14224)
		(layer "In11.Cu")
		(net "M_C_DQS_DN<11>")
	)
	(segment
		(start 227.259134 -41.633902)
		(end 227.490782 -41.86555)
		(width 0.14224)
		(layer "In11.Cu")
		(net "M_C_DQS_DN<11>")
	)
	(segment
		(start 219.38234 -10.5156)
		(end 219.22486 -10.67308)
		(width 0.14224)
		(layer "In11.Cu")
		(net "M_C_DQS_DN<11>")
	)
	(segment
		(start 218.61272 -26.19375)
		(end 219.013278 -26.594308)
		(width 0.14224)
		(layer "In11.Cu")
		(net "M_C_DQS_DN<11>")
	)
	(segment
		(start 231.602534 -45.977302)
		(end 231.799892 -46.17466)
		(width 0.14224)
		(layer "In11.Cu")
		(net "M_C_DQS_DN<11>")
	)
	(segment
		(start 233.167174 -48.339248)
		(end 233.167174 -48.501046)
		(width 0.14224)
		(layer "In11.Cu")
		(net "M_C_DQS_DN<11>")
	)
	(segment
		(start 228.874066 -43.248834)
		(end 229.053644 -43.428412)
		(width 0.14224)
		(layer "In11.Cu")
		(net "M_C_DQS_DN<11>")
	)
	(segment
		(start 218.677744 -4.8006)
		(end 218.423744 -4.8006)
		(width 0.14224)
		(layer "In11.Cu")
		(net "M_C_DQS_DN<11>")
	)
	(segment
		(start 219.38234 -11.2776)
		(end 219.22486 -11.43508)
		(width 0.14224)
		(layer "In11.Cu")
		(net "M_C_DQS_DN<11>")
	)
	(segment
		(start 228.353112 -42.566336)
		(end 228.353112 -42.72788)
		(width 0.14224)
		(layer "In11.Cu")
		(net "M_C_DQS_DN<11>")
	)
	(segment
		(start 219.22486 -14.21892)
		(end 219.38234 -14.3764)
		(width 0.14224)
		(layer "In11.Cu")
		(net "M_C_DQS_DN<11>")
	)
	(segment
		(start 241.606832 -56.485536)
		(end 241.639598 -56.485536)
		(width 0.0889)
		(layer "In11.Cu")
		(net "M_C_DQS_DN<11>")
	)
	(segment
		(start 232.987342 -48.159416)
		(end 233.167174 -48.339248)
		(width 0.14224)
		(layer "In11.Cu")
		(net "M_C_DQS_DN<11>")
	)
	(segment
		(start 219.231464 1.257808)
		(end 218.894152 1.59512)
		(width 0.14224)
		(layer "In11.Cu")
		(net "M_C_DQS_DN<11>")
	)
	(segment
		(start 219.22486 -10.10412)
		(end 219.38234 -10.2616)
		(width 0.14224)
		(layer "In11.Cu")
		(net "M_C_DQS_DN<11>")
	)
	(segment
		(start 219.55252 -33.927288)
		(end 226.917758 -41.292526)
		(width 0.14224)
		(layer "In11.Cu")
		(net "M_C_DQS_DN<11>")
	)
	(segment
		(start 230.436928 -44.650152)
		(end 230.436928 -44.811696)
		(width 0.14224)
		(layer "In11.Cu")
		(net "M_C_DQS_DN<11>")
	)
	(segment
		(start 232.54589 -47.879762)
		(end 232.825544 -48.159416)
		(width 0.14224)
		(layer "In11.Cu")
		(net "M_C_DQS_DN<11>")
	)
	(segment
		(start 227.832158 -42.045382)
		(end 227.832158 -42.206926)
		(width 0.14224)
		(layer "In11.Cu")
		(net "M_C_DQS_DN<11>")
	)
	(segment
		(start 229.915974 -44.129198)
		(end 229.915974 -44.290742)
		(width 0.14224)
		(layer "In11.Cu")
		(net "M_C_DQS_DN<11>")
	)
	(segment
		(start 219.22486 -6.238748)
		(end 219.22486 -9.34212)
		(width 0.14224)
		(layer "In11.Cu")
		(net "M_C_DQS_DN<11>")
	)
	(segment
		(start 232.54589 -47.717964)
		(end 232.54589 -47.879762)
		(width 0.14224)
		(layer "In11.Cu")
		(net "M_C_DQS_DN<11>")
	)
	(segment
		(start 229.574598 -43.949366)
		(end 229.736142 -43.949366)
		(width 0.14224)
		(layer "In11.Cu")
		(net "M_C_DQS_DN<11>")
	)
	(segment
		(start 229.39502 -43.608244)
		(end 229.39502 -43.769788)
		(width 0.14224)
		(layer "In11.Cu")
		(net "M_C_DQS_DN<11>")
	)
	(segment
		(start 229.053644 -43.428412)
		(end 229.215188 -43.428412)
		(width 0.14224)
		(layer "In11.Cu")
		(net "M_C_DQS_DN<11>")
	)
	(segment
		(start 228.353112 -42.72788)
		(end 228.53269 -42.907458)
		(width 0.14224)
		(layer "In11.Cu")
		(net "M_C_DQS_DN<11>")
	)
	(segment
		(start 218.880944 -4.070604)
		(end 218.880944 -4.5974)
		(width 0.14224)
		(layer "In11.Cu")
		(net "M_C_DQS_DN<11>")
	)
	(segment
		(start 243.465096 -57.489598)
		(end 244.197124 -57.57164)
		(width 0.0889)
		(layer "In11.Cu")
		(net "M_C_DQS_DN<11>")
	)
	(segment
		(start 230.958136 -45.332904)
		(end 231.261158 -45.635926)
		(width 0.14224)
		(layer "In11.Cu")
		(net "M_C_DQS_DN<11>")
	)
	(segment
		(start 228.17328 -42.386504)
		(end 228.353112 -42.566336)
		(width 0.14224)
		(layer "In11.Cu")
		(net "M_C_DQS_DN<11>")
	)
	(segment
		(start 233.167174 -48.501046)
		(end 233.798364 -49.132236)
		(width 0.14224)
		(layer "In11.Cu")
		(net "M_C_DQS_DN<11>")
	)
	(segment
		(start 231.799892 -46.17466)
		(end 231.799892 -47.134018)
		(width 0.14224)
		(layer "In11.Cu")
		(net "M_C_DQS_DN<11>")
	)
	(segment
		(start 218.44254 -3.6322)
		(end 219.231464 -2.843276)
		(width 0.14224)
		(layer "In11.Cu")
		(net "M_C_DQS_DN<11>")
	)
	(segment
		(start 236.123988 -52.913788)
		(end 236.119162 -52.922424)
		(width 0.0889)
		(layer "In11.Cu")
		(net "M_C_DQS_DN<11>")
	)
	(segment
		(start 219.22486 -10.86612)
		(end 219.38234 -11.0236)
		(width 0.14224)
		(layer "In11.Cu")
		(net "M_C_DQS_DN<11>")
	)
	(segment
		(start 218.61272 -25.553162)
		(end 218.61272 -26.19375)
		(width 0.14224)
		(layer "In11.Cu")
		(net "M_C_DQS_DN<11>")
	)
	(segment
		(start 230.616506 -44.991274)
		(end 230.778304 -44.991274)
		(width 0.14224)
		(layer "In11.Cu")
		(net "M_C_DQS_DN<11>")
	)
	(segment
		(start 219.173552 -26.594308)
		(end 219.55252 -26.973276)
		(width 0.14224)
		(layer "In11.Cu")
		(net "M_C_DQS_DN<11>")
	)
	(segment
		(start 218.894152 1.59512)
		(end 218.644724 1.59512)
		(width 0.14224)
		(layer "In11.Cu")
		(net "M_C_DQS_DN<11>")
	)
	(segment
		(start 230.778304 -44.991274)
		(end 230.958136 -45.171106)
		(width 0.14224)
		(layer "In11.Cu")
		(net "M_C_DQS_DN<11>")
	)
	(segment
		(start 230.257096 -44.47032)
		(end 230.436928 -44.650152)
		(width 0.14224)
		(layer "In11.Cu")
		(net "M_C_DQS_DN<11>")
	)
	(segment
		(start 219.22486 -14.78788)
		(end 219.22486 -24.941022)
		(width 0.14224)
		(layer "In11.Cu")
		(net "M_C_DQS_DN<11>")
	)
	(segment
		(start 230.958136 -45.171106)
		(end 230.958136 -45.332904)
		(width 0.14224)
		(layer "In11.Cu")
		(net "M_C_DQS_DN<11>")
	)
	(segment
		(start 219.22486 -9.34212)
		(end 219.38234 -9.4996)
		(width 0.14224)
		(layer "In11.Cu")
		(net "M_C_DQS_DN<11>")
	)
	(segment
		(start 227.259134 -41.472358)
		(end 227.259134 -41.633902)
		(width 0.14224)
		(layer "In11.Cu")
		(net "M_C_DQS_DN<11>")
	)
	(segment
		(start 219.55252 -26.973276)
		(end 219.55252 -33.927288)
		(width 0.14224)
		(layer "In11.Cu")
		(net "M_C_DQS_DN<11>")
	)
	(segment
		(start 219.013278 -26.594308)
		(end 219.173552 -26.594308)
		(width 0.14224)
		(layer "In11.Cu")
		(net "M_C_DQS_DN<11>")
	)
	(segment
		(start 218.644724 1.59512)
		(end 218.449144 1.7907)
		(width 0.14224)
		(layer "In11.Cu")
		(net "M_C_DQS_DN<11>")
	)
	(segment
		(start 227.832158 -42.206926)
		(end 228.011736 -42.386504)
		(width 0.14224)
		(layer "In11.Cu")
		(net "M_C_DQS_DN<11>")
	)
	(segment
		(start 234.882182 -50.157126)
		(end 235.271818 -50.848768)
		(width 0.0889)
		(layer "In11.Cu")
		(net "M_C_DQS_DN<11>")
	)
	(segment
		(start 234.886246 -50.083974)
		(end 234.897168 -50.103278)
		(width 0.0889)
		(layer "In11.Cu")
		(net "M_C_DQS_DN<11>")
	)
	(segment
		(start 228.694234 -42.907458)
		(end 228.874066 -43.08729)
		(width 0.14224)
		(layer "In11.Cu")
		(net "M_C_DQS_DN<11>")
	)
	(segment
		(start 232.366058 -47.538132)
		(end 232.54589 -47.717964)
		(width 0.14224)
		(layer "In11.Cu")
		(net "M_C_DQS_DN<11>")
	)
	(segment
		(start 243.338604 -57.476136)
		(end 243.351558 -57.476136)
		(width 0.0889)
		(layer "In11.Cu")
		(net "M_C_DQS_DN<11>")
	)
	(segment
		(start 226.917758 -41.292526)
		(end 227.079302 -41.292526)
		(width 0.14224)
		(layer "In11.Cu")
		(net "M_C_DQS_DN<11>")
	)
	(segment
		(start 238.172752 -54.504336)
		(end 238.205518 -54.504336)
		(width 0.0889)
		(layer "In11.Cu")
		(net "M_C_DQS_DN<11>")
	)
	(arc
		(start 239.922558 -55.494936)
		(mid 240.207982 -55.578403)
		(end 240.416588 -55.790338)
		(width 0.0889)
		(layer "In11.Cu")
		(net "M_C_DQS_DN<11>")
	)
	(arc
		(start 242.99545 -57.281826)
		(mid 243.141416 -57.424225)
		(end 243.338604 -57.476136)
		(width 0.0889)
		(layer "In11.Cu")
		(net "M_C_DQS_DN<11>")
	)
	(arc
		(start 235.629958 -52.027836)
		(mid 236.128209 -52.330676)
		(end 236.123988 -52.913788)
		(width 0.0889)
		(layer "In11.Cu")
		(net "M_C_DQS_DN<11>")
	)
	(arc
		(start 236.982508 -53.809138)
		(mid 237.124191 -53.952942)
		(end 237.318042 -54.00929)
		(width 0.0889)
		(layer "In11.Cu")
		(net "M_C_DQS_DN<11>")
	)
	(arc
		(start 236.488478 -53.513736)
		(mid 236.773902 -53.597203)
		(end 236.982508 -53.809138)
		(width 0.0889)
		(layer "In11.Cu")
		(net "M_C_DQS_DN<11>")
	)
	(arc
		(start 242.50523 -56.98109)
		(mid 242.78653 -57.066056)
		(end 242.992148 -57.275984)
		(width 0.0889)
		(layer "In11.Cu")
		(net "M_C_DQS_DN<11>")
	)
	(arc
		(start 235.271818 -50.848768)
		(mid 235.344495 -51.139167)
		(end 235.265468 -51.427888)
		(width 0.0889)
		(layer "In11.Cu")
		(net "M_C_DQS_DN<11>")
	)
	(arc
		(start 237.841028 -54.304438)
		(mid 237.981107 -54.447174)
		(end 238.172752 -54.504336)
		(width 0.0889)
		(layer "In11.Cu")
		(net "M_C_DQS_DN<11>")
	)
	(arc
		(start 239.558068 -55.295038)
		(mid 239.698147 -55.437774)
		(end 239.889792 -55.494936)
		(width 0.0889)
		(layer "In11.Cu")
		(net "M_C_DQS_DN<11>")
	)
	(arc
		(start 235.265468 -51.427888)
		(mid 235.261058 -51.820351)
		(end 235.594144 -52.027836)
		(width 0.0889)
		(layer "In11.Cu")
		(net "M_C_DQS_DN<11>")
	)
	(arc
		(start 236.119162 -52.922424)
		(mid 236.122909 -53.31168)
		(end 236.455712 -53.513736)
		(width 0.0889)
		(layer "In11.Cu")
		(net "M_C_DQS_DN<11>")
	)
	(arc
		(start 243.351558 -57.476136)
		(mid 243.408654 -57.480111)
		(end 243.465096 -57.489598)
		(width 0.0889)
		(layer "In11.Cu")
		(net "M_C_DQS_DN<11>")
	)
	(arc
		(start 241.639598 -56.485536)
		(mid 241.925022 -56.569003)
		(end 242.133628 -56.780938)
		(width 0.0889)
		(layer "In11.Cu")
		(net "M_C_DQS_DN<11>")
	)
	(arc
		(start 238.699548 -54.799738)
		(mid 238.841231 -54.943542)
		(end 239.035082 -54.99989)
		(width 0.0889)
		(layer "In11.Cu")
		(net "M_C_DQS_DN<11>")
	)
	(arc
		(start 238.205518 -54.504336)
		(mid 238.490942 -54.587803)
		(end 238.699548 -54.799738)
		(width 0.0889)
		(layer "In11.Cu")
		(net "M_C_DQS_DN<11>")
	)
	(arc
		(start 237.350808 -54.00929)
		(mid 237.634025 -54.093571)
		(end 237.841028 -54.304438)
		(width 0.0889)
		(layer "In11.Cu")
		(net "M_C_DQS_DN<11>")
	)
	(arc
		(start 240.784888 -55.99049)
		(mid 241.068105 -56.074771)
		(end 241.275108 -56.285638)
		(width 0.0889)
		(layer "In11.Cu")
		(net "M_C_DQS_DN<11>")
	)
	(arc
		(start 239.067848 -54.99989)
		(mid 239.351065 -55.084171)
		(end 239.558068 -55.295038)
		(width 0.0889)
		(layer "In11.Cu")
		(net "M_C_DQS_DN<11>")
	)
	(arc
		(start 242.133628 -56.780938)
		(mid 242.275311 -56.924742)
		(end 242.469162 -56.98109)
		(width 0.0889)
		(layer "In11.Cu")
		(net "M_C_DQS_DN<11>")
	)
	(arc
		(start 241.275108 -56.285638)
		(mid 241.415187 -56.428374)
		(end 241.606832 -56.485536)
		(width 0.0889)
		(layer "In11.Cu")
		(net "M_C_DQS_DN<11>")
	)
	(arc
		(start 240.416588 -55.790338)
		(mid 240.558271 -55.934142)
		(end 240.752122 -55.99049)
		(width 0.0889)
		(layer "In11.Cu")
		(net "M_C_DQS_DN<11>")
	)
	(segment
		(start 209.30743 1.60147)
		(end 209.1182 1.7907)
		(width 0.1651)
		(layer "F.Cu")
		(net "M_C_DQS_DN<10>")
	)
	(segment
		(start 210.000342 3.778758)
		(end 209.999834 3.778758)
		(width 0.1651)
		(layer "F.Cu")
		(net "M_C_DQS_DN<10>")
	)
	(segment
		(start 209.767678 2.100072)
		(end 209.767678 1.853438)
		(width 0.1651)
		(layer "F.Cu")
		(net "M_C_DQS_DN<10>")
	)
	(segment
		(start 209.51571 1.60147)
		(end 209.30743 1.60147)
		(width 0.1651)
		(layer "F.Cu")
		(net "M_C_DQS_DN<10>")
	)
	(segment
		(start 240.476278 -61.038486)
		(end 239.904778 -61.038486)
		(width 0.0889)
		(layer "F.Cu")
		(net "M_C_DQS_DN<10>")
	)
	(segment
		(start 209.58175 2.518156)
		(end 209.58175 2.286)
		(width 0.1651)
		(layer "F.Cu")
		(net "M_C_DQS_DN<10>")
	)
	(segment
		(start 209.1182 1.7907)
		(end 209.09915 1.7907)
		(width 0.1651)
		(layer "F.Cu")
		(net "M_C_DQS_DN<10>")
	)
	(segment
		(start 209.58175 2.286)
		(end 209.767678 2.100072)
		(width 0.1651)
		(layer "F.Cu")
		(net "M_C_DQS_DN<10>")
	)
	(segment
		(start 209.999834 2.93624)
		(end 209.58175 2.518156)
		(width 0.1651)
		(layer "F.Cu")
		(net "M_C_DQS_DN<10>")
	)
	(segment
		(start 209.767678 1.853438)
		(end 209.51571 1.60147)
		(width 0.1651)
		(layer "F.Cu")
		(net "M_C_DQS_DN<10>")
	)
	(segment
		(start 209.999834 3.778758)
		(end 209.999834 2.93624)
		(width 0.1651)
		(layer "F.Cu")
		(net "M_C_DQS_DN<10>")
	)
	(via
		(at 239.904778 -61.038486)
		(size 0.508)
		(drill 0.254)
		(layers "F.Cu" "B.Cu")
		(net "M_C_DQS_DN<10>")
	)
	(via
		(at 209.09915 1.7907)
		(size 0.508)
		(drill 0.254)
		(layers "F.Cu" "B.Cu")
		(net "M_C_DQS_DN<10>")
	)
	(via
		(at 209.092546 -3.6322)
		(size 0.508)
		(drill 0.254)
		(layers "F.Cu" "B.Cu")
		(net "M_C_DQS_DN<10>")
	)
	(segment
		(start 210.000342 -5.621782)
		(end 209.999834 -5.621782)
		(width 0.1651)
		(layer "B.Cu")
		(net "M_C_DQS_DN<10>")
	)
	(segment
		(start 209.55635 -4.1656)
		(end 209.73415 -3.9878)
		(width 0.1651)
		(layer "B.Cu")
		(net "M_C_DQS_DN<10>")
	)
	(segment
		(start 209.73415 -3.9878)
		(end 209.73415 -3.6576)
		(width 0.1651)
		(layer "B.Cu")
		(net "M_C_DQS_DN<10>")
	)
	(segment
		(start 209.999834 -4.964938)
		(end 209.55635 -4.521454)
		(width 0.1651)
		(layer "B.Cu")
		(net "M_C_DQS_DN<10>")
	)
	(segment
		(start 209.55635 -4.521454)
		(end 209.55635 -4.1656)
		(width 0.1651)
		(layer "B.Cu")
		(net "M_C_DQS_DN<10>")
	)
	(segment
		(start 209.999834 -5.621782)
		(end 209.999834 -4.964938)
		(width 0.1651)
		(layer "B.Cu")
		(net "M_C_DQS_DN<10>")
	)
	(segment
		(start 209.73415 -3.6576)
		(end 209.514186 -3.437636)
		(width 0.1651)
		(layer "B.Cu")
		(net "M_C_DQS_DN<10>")
	)
	(segment
		(start 209.28711 -3.437636)
		(end 209.092546 -3.6322)
		(width 0.1651)
		(layer "B.Cu")
		(net "M_C_DQS_DN<10>")
	)
	(segment
		(start 209.514186 -3.437636)
		(end 209.28711 -3.437636)
		(width 0.1651)
		(layer "B.Cu")
		(net "M_C_DQS_DN<10>")
	)
	(segment
		(start 224.907602 -51.814476)
		(end 224.745804 -51.814476)
		(width 0.14224)
		(layer "In11.Cu")
		(net "M_C_DQS_DN<10>")
	)
	(segment
		(start 223.949006 -50.856134)
		(end 223.769174 -50.676302)
		(width 0.14224)
		(layer "In11.Cu")
		(net "M_C_DQS_DN<10>")
	)
	(segment
		(start 232.44937 -56.98109)
		(end 230.54437 -56.98109)
		(width 0.0889)
		(layer "In11.Cu")
		(net "M_C_DQS_DN<10>")
	)
	(segment
		(start 227.446078 -54.51475)
		(end 227.224336 -54.293008)
		(width 0.14224)
		(layer "In11.Cu")
		(net "M_C_DQS_DN<10>")
	)
	(segment
		(start 221.527624 -48.596296)
		(end 221.527624 -48.434752)
		(width 0.14224)
		(layer "In11.Cu")
		(net "M_C_DQS_DN<10>")
	)
	(segment
		(start 209.03692 -36.105592)
		(end 209.03692 -35.79368)
		(width 0.14224)
		(layer "In11.Cu")
		(net "M_C_DQS_DN<10>")
	)
	(segment
		(start 220.013022 -47.081694)
		(end 217.135456 -44.204128)
		(width 0.14224)
		(layer "In11.Cu")
		(net "M_C_DQS_DN<10>")
	)
	(segment
		(start 225.954336 -52.861464)
		(end 225.792792 -52.861464)
		(width 0.14224)
		(layer "In11.Cu")
		(net "M_C_DQS_DN<10>")
	)
	(segment
		(start 209.283808 -33.982152)
		(end 209.06232 -33.760664)
		(width 0.14224)
		(layer "In11.Cu")
		(net "M_C_DQS_DN<10>")
	)
	(segment
		(start 223.769174 -50.676302)
		(end 223.60763 -50.676302)
		(width 0.14224)
		(layer "In11.Cu")
		(net "M_C_DQS_DN<10>")
	)
	(segment
		(start 209.53095 -4.5974)
		(end 209.53095 -4.070604)
		(width 0.14224)
		(layer "In11.Cu")
		(net "M_C_DQS_DN<10>")
	)
	(segment
		(start 224.564702 -51.633374)
		(end 224.564702 -51.47183)
		(width 0.14224)
		(layer "In11.Cu")
		(net "M_C_DQS_DN<10>")
	)
	(segment
		(start 209.88147 1.257808)
		(end 209.88147 -2.843276)
		(width 0.14224)
		(layer "In11.Cu")
		(net "M_C_DQS_DN<10>")
	)
	(segment
		(start 230.505 -56.94172)
		(end 229.873048 -56.94172)
		(width 0.14224)
		(layer "In11.Cu")
		(net "M_C_DQS_DN<10>")
	)
	(segment
		(start 209.07375 -4.8006)
		(end 209.32775 -4.8006)
		(width 0.14224)
		(layer "In11.Cu")
		(net "M_C_DQS_DN<10>")
	)
	(segment
		(start 220.576394 -47.645066)
		(end 220.354652 -47.423324)
		(width 0.14224)
		(layer "In11.Cu")
		(net "M_C_DQS_DN<10>")
	)
	(segment
		(start 223.089724 -49.996852)
		(end 222.92818 -49.996852)
		(width 0.14224)
		(layer "In11.Cu")
		(net "M_C_DQS_DN<10>")
	)
	(segment
		(start 224.745804 -51.814476)
		(end 224.564702 -51.633374)
		(width 0.14224)
		(layer "In11.Cu")
		(net "M_C_DQS_DN<10>")
	)
	(segment
		(start 234.775248 -58.466736)
		(end 233.935016 -58.466736)
		(width 0.0889)
		(layer "In11.Cu")
		(net "M_C_DQS_DN<10>")
	)
	(segment
		(start 227.224336 -54.13121)
		(end 227.044504 -53.951378)
		(width 0.14224)
		(layer "In11.Cu")
		(net "M_C_DQS_DN<10>")
	)
	(segment
		(start 230.54437 -56.98109)
		(end 230.527352 -56.964072)
		(width 0.0889)
		(layer "In11.Cu")
		(net "M_C_DQS_DN<10>")
	)
	(segment
		(start 237.350808 -59.95289)
		(end 237.318042 -59.95289)
		(width 0.0889)
		(layer "In11.Cu")
		(net "M_C_DQS_DN<10>")
	)
	(segment
		(start 223.949006 -51.017678)
		(end 223.949006 -50.856134)
		(width 0.14224)
		(layer "In11.Cu")
		(net "M_C_DQS_DN<10>")
	)
	(segment
		(start 226.134168 -53.041296)
		(end 225.954336 -52.861464)
		(width 0.14224)
		(layer "In11.Cu")
		(net "M_C_DQS_DN<10>")
	)
	(segment
		(start 209.874866 -9.44372)
		(end 209.874866 -6.888988)
		(width 0.14224)
		(layer "In11.Cu")
		(net "M_C_DQS_DN<10>")
	)
	(segment
		(start 217.135456 -43.239944)
		(end 214.586312 -40.6908)
		(width 0.14224)
		(layer "In11.Cu")
		(net "M_C_DQS_DN<10>")
	)
	(segment
		(start 217.135456 -44.204128)
		(end 217.135456 -43.239944)
		(width 0.14224)
		(layer "In11.Cu")
		(net "M_C_DQS_DN<10>")
	)
	(segment
		(start 238.205518 -60.447936)
		(end 238.172752 -60.447936)
		(width 0.0889)
		(layer "In11.Cu")
		(net "M_C_DQS_DN<10>")
	)
	(segment
		(start 225.613214 -52.681886)
		(end 225.613214 -52.520342)
		(width 0.14224)
		(layer "In11.Cu")
		(net "M_C_DQS_DN<10>")
	)
	(segment
		(start 227.607622 -54.51475)
		(end 227.446078 -54.51475)
		(width 0.14224)
		(layer "In11.Cu")
		(net "M_C_DQS_DN<10>")
	)
	(segment
		(start 209.88147 -2.843276)
		(end 209.092546 -3.6322)
		(width 0.14224)
		(layer "In11.Cu")
		(net "M_C_DQS_DN<10>")
	)
	(segment
		(start 209.874866 -10.01268)
		(end 210.032346 -9.8552)
		(width 0.14224)
		(layer "In11.Cu")
		(net "M_C_DQS_DN<10>")
	)
	(segment
		(start 229.227888 -56.134762)
		(end 229.06609 -56.134762)
		(width 0.14224)
		(layer "In11.Cu")
		(net "M_C_DQS_DN<10>")
	)
	(segment
		(start 228.886512 -55.955184)
		(end 228.886512 -55.79364)
		(width 0.14224)
		(layer "In11.Cu")
		(net "M_C_DQS_DN<10>")
	)
	(segment
		(start 228.545136 -55.613808)
		(end 228.310186 -55.378858)
		(width 0.14224)
		(layer "In11.Cu")
		(net "M_C_DQS_DN<10>")
	)
	(segment
		(start 230.527352 -56.964072)
		(end 230.527352 -56.952896)
		(width 0.0889)
		(layer "In11.Cu")
		(net "M_C_DQS_DN<10>")
	)
	(segment
		(start 222.659956 -49.728628)
		(end 222.659956 -49.56683)
		(width 0.14224)
		(layer "In11.Cu")
		(net "M_C_DQS_DN<10>")
	)
	(segment
		(start 209.874866 -11.53668)
		(end 210.032346 -11.3792)
		(width 0.14224)
		(layer "In11.Cu")
		(net "M_C_DQS_DN<10>")
	)
	(segment
		(start 225.613214 -52.520342)
		(end 225.433382 -52.34051)
		(width 0.14224)
		(layer "In11.Cu")
		(net "M_C_DQS_DN<10>")
	)
	(segment
		(start 209.233008 -35.597592)
		(end 209.663792 -35.597592)
		(width 0.14224)
		(layer "In11.Cu")
		(net "M_C_DQS_DN<10>")
	)
	(segment
		(start 233.935016 -58.466736)
		(end 232.44937 -56.98109)
		(width 0.0889)
		(layer "In11.Cu")
		(net "M_C_DQS_DN<10>")
	)
	(segment
		(start 230.516176 -56.94172)
		(end 230.505 -56.94172)
		(width 0.0889)
		(layer "In11.Cu")
		(net "M_C_DQS_DN<10>")
	)
	(segment
		(start 209.06232 -26.632408)
		(end 209.874866 -25.819862)
		(width 0.14224)
		(layer "In11.Cu")
		(net "M_C_DQS_DN<10>")
	)
	(segment
		(start 208.89087 -5.254752)
		(end 208.89087 -4.98348)
		(width 0.14224)
		(layer "In11.Cu")
		(net "M_C_DQS_DN<10>")
	)
	(segment
		(start 226.47529 -53.382418)
		(end 226.313746 -53.382418)
		(width 0.14224)
		(layer "In11.Cu")
		(net "M_C_DQS_DN<10>")
	)
	(segment
		(start 220.918024 -47.824898)
		(end 220.738192 -47.645066)
		(width 0.14224)
		(layer "In11.Cu")
		(net "M_C_DQS_DN<10>")
	)
	(segment
		(start 209.874866 -25.819862)
		(end 209.874866 -11.53668)
		(width 0.14224)
		(layer "In11.Cu")
		(net "M_C_DQS_DN<10>")
	)
	(segment
		(start 210.001866 -6.365748)
		(end 208.89087 -5.254752)
		(width 0.14224)
		(layer "In11.Cu")
		(net "M_C_DQS_DN<10>")
	)
	(segment
		(start 209.874866 -10.96772)
		(end 209.874866 -10.77468)
		(width 0.14224)
		(layer "In11.Cu")
		(net "M_C_DQS_DN<10>")
	)
	(segment
		(start 227.968556 -55.037228)
		(end 227.787454 -54.856126)
		(width 0.14224)
		(layer "In11.Cu")
		(net "M_C_DQS_DN<10>")
	)
	(segment
		(start 221.527624 -48.434752)
		(end 221.347792 -48.25492)
		(width 0.14224)
		(layer "In11.Cu")
		(net "M_C_DQS_DN<10>")
	)
	(segment
		(start 209.06232 -33.760664)
		(end 209.06232 -26.632408)
		(width 0.14224)
		(layer "In11.Cu")
		(net "M_C_DQS_DN<10>")
	)
	(segment
		(start 226.655122 -53.723794)
		(end 226.655122 -53.56225)
		(width 0.14224)
		(layer "In11.Cu")
		(net "M_C_DQS_DN<10>")
	)
	(segment
		(start 225.433382 -52.34051)
		(end 225.271838 -52.34051)
		(width 0.14224)
		(layer "In11.Cu")
		(net "M_C_DQS_DN<10>")
	)
	(segment
		(start 229.873048 -56.94172)
		(end 229.40772 -56.476392)
		(width 0.14224)
		(layer "In11.Cu")
		(net "M_C_DQS_DN<10>")
	)
	(segment
		(start 209.948272 -34.266632)
		(end 209.663792 -33.982152)
		(width 0.14224)
		(layer "In11.Cu")
		(net "M_C_DQS_DN<10>")
	)
	(segment
		(start 209.874866 -10.20572)
		(end 209.874866 -10.01268)
		(width 0.14224)
		(layer "In11.Cu")
		(net "M_C_DQS_DN<10>")
	)
	(segment
		(start 228.886512 -55.79364)
		(end 228.70668 -55.613808)
		(width 0.14224)
		(layer "In11.Cu")
		(net "M_C_DQS_DN<10>")
	)
	(segment
		(start 220.354652 -47.423324)
		(end 220.354652 -47.261526)
		(width 0.14224)
		(layer "In11.Cu")
		(net "M_C_DQS_DN<10>")
	)
	(segment
		(start 221.186248 -48.25492)
		(end 220.918024 -47.986696)
		(width 0.14224)
		(layer "In11.Cu")
		(net "M_C_DQS_DN<10>")
	)
	(segment
		(start 227.787454 -54.856126)
		(end 227.787454 -54.694582)
		(width 0.14224)
		(layer "In11.Cu")
		(net "M_C_DQS_DN<10>")
	)
	(segment
		(start 225.271838 -52.34051)
		(end 225.087434 -52.156106)
		(width 0.14224)
		(layer "In11.Cu")
		(net "M_C_DQS_DN<10>")
	)
	(segment
		(start 221.347792 -48.25492)
		(end 221.186248 -48.25492)
		(width 0.14224)
		(layer "In11.Cu")
		(net "M_C_DQS_DN<10>")
	)
	(segment
		(start 239.904778 -61.038486)
		(end 239.262666 -60.98413)
		(width 0.0889)
		(layer "In11.Cu")
		(net "M_C_DQS_DN<10>")
	)
	(segment
		(start 228.70668 -55.613808)
		(end 228.545136 -55.613808)
		(width 0.14224)
		(layer "In11.Cu")
		(net "M_C_DQS_DN<10>")
	)
	(segment
		(start 224.564702 -51.47183)
		(end 224.38487 -51.291998)
		(width 0.14224)
		(layer "In11.Cu")
		(net "M_C_DQS_DN<10>")
	)
	(segment
		(start 225.087434 -51.994308)
		(end 224.907602 -51.814476)
		(width 0.14224)
		(layer "In11.Cu")
		(net "M_C_DQS_DN<10>")
	)
	(segment
		(start 209.29473 1.59512)
		(end 209.544158 1.59512)
		(width 0.14224)
		(layer "In11.Cu")
		(net "M_C_DQS_DN<10>")
	)
	(segment
		(start 208.89087 -4.98348)
		(end 209.07375 -4.8006)
		(width 0.14224)
		(layer "In11.Cu")
		(net "M_C_DQS_DN<10>")
	)
	(segment
		(start 236.488478 -59.457336)
		(end 236.455712 -59.457336)
		(width 0.0889)
		(layer "In11.Cu")
		(net "M_C_DQS_DN<10>")
	)
	(segment
		(start 226.134168 -53.20284)
		(end 226.134168 -53.041296)
		(width 0.14224)
		(layer "In11.Cu")
		(net "M_C_DQS_DN<10>")
	)
	(segment
		(start 220.738192 -47.645066)
		(end 220.576394 -47.645066)
		(width 0.14224)
		(layer "In11.Cu")
		(net "M_C_DQS_DN<10>")
	)
	(segment
		(start 222.480124 -49.386998)
		(end 222.318326 -49.386998)
		(width 0.14224)
		(layer "In11.Cu")
		(net "M_C_DQS_DN<10>")
	)
	(segment
		(start 209.09915 1.7907)
		(end 209.29473 1.59512)
		(width 0.14224)
		(layer "In11.Cu")
		(net "M_C_DQS_DN<10>")
	)
	(segment
		(start 229.06609 -56.134762)
		(end 228.886512 -55.955184)
		(width 0.14224)
		(layer "In11.Cu")
		(net "M_C_DQS_DN<10>")
	)
	(segment
		(start 213.622128 -40.6908)
		(end 209.03692 -36.105592)
		(width 0.14224)
		(layer "In11.Cu")
		(net "M_C_DQS_DN<10>")
	)
	(segment
		(start 227.044504 -53.951378)
		(end 226.882706 -53.951378)
		(width 0.14224)
		(layer "In11.Cu")
		(net "M_C_DQS_DN<10>")
	)
	(segment
		(start 209.03692 -35.79368)
		(end 209.233008 -35.597592)
		(width 0.14224)
		(layer "In11.Cu")
		(net "M_C_DQS_DN<10>")
	)
	(segment
		(start 210.001866 -6.761988)
		(end 210.001866 -6.365748)
		(width 0.14224)
		(layer "In11.Cu")
		(net "M_C_DQS_DN<10>")
	)
	(segment
		(start 209.544158 1.59512)
		(end 209.88147 1.257808)
		(width 0.14224)
		(layer "In11.Cu")
		(net "M_C_DQS_DN<10>")
	)
	(segment
		(start 210.032346 -10.3632)
		(end 209.874866 -10.20572)
		(width 0.14224)
		(layer "In11.Cu")
		(net "M_C_DQS_DN<10>")
	)
	(segment
		(start 230.527352 -56.952896)
		(end 230.516176 -56.94172)
		(width 0.0889)
		(layer "In11.Cu")
		(net "M_C_DQS_DN<10>")
	)
	(segment
		(start 214.586312 -40.6908)
		(end 213.622128 -40.6908)
		(width 0.14224)
		(layer "In11.Cu")
		(net "M_C_DQS_DN<10>")
	)
	(segment
		(start 209.663792 -33.982152)
		(end 209.283808 -33.982152)
		(width 0.14224)
		(layer "In11.Cu")
		(net "M_C_DQS_DN<10>")
	)
	(segment
		(start 209.874866 -10.77468)
		(end 210.032346 -10.6172)
		(width 0.14224)
		(layer "In11.Cu")
		(net "M_C_DQS_DN<10>")
	)
	(segment
		(start 210.032346 -11.3792)
		(end 210.032346 -11.1252)
		(width 0.14224)
		(layer "In11.Cu")
		(net "M_C_DQS_DN<10>")
	)
	(segment
		(start 209.53095 -4.070604)
		(end 209.092546 -3.6322)
		(width 0.14224)
		(layer "In11.Cu")
		(net "M_C_DQS_DN<10>")
	)
	(segment
		(start 220.354652 -47.261526)
		(end 220.17482 -47.081694)
		(width 0.14224)
		(layer "In11.Cu")
		(net "M_C_DQS_DN<10>")
	)
	(segment
		(start 210.032346 -10.6172)
		(end 210.032346 -10.3632)
		(width 0.14224)
		(layer "In11.Cu")
		(net "M_C_DQS_DN<10>")
	)
	(segment
		(start 227.787454 -54.694582)
		(end 227.607622 -54.51475)
		(width 0.14224)
		(layer "In11.Cu")
		(net "M_C_DQS_DN<10>")
	)
	(segment
		(start 220.17482 -47.081694)
		(end 220.013022 -47.081694)
		(width 0.14224)
		(layer "In11.Cu")
		(net "M_C_DQS_DN<10>")
	)
	(segment
		(start 226.655122 -53.56225)
		(end 226.47529 -53.382418)
		(width 0.14224)
		(layer "In11.Cu")
		(net "M_C_DQS_DN<10>")
	)
	(segment
		(start 239.067848 -60.94349)
		(end 239.035082 -60.94349)
		(width 0.0889)
		(layer "In11.Cu")
		(net "M_C_DQS_DN<10>")
	)
	(segment
		(start 224.38487 -51.291998)
		(end 224.223326 -51.291998)
		(width 0.14224)
		(layer "In11.Cu")
		(net "M_C_DQS_DN<10>")
	)
	(segment
		(start 209.663792 -35.597592)
		(end 209.948272 -35.313112)
		(width 0.14224)
		(layer "In11.Cu")
		(net "M_C_DQS_DN<10>")
	)
	(segment
		(start 228.310186 -55.21706)
		(end 228.130354 -55.037228)
		(width 0.14224)
		(layer "In11.Cu")
		(net "M_C_DQS_DN<10>")
	)
	(segment
		(start 224.223326 -51.291998)
		(end 223.949006 -51.017678)
		(width 0.14224)
		(layer "In11.Cu")
		(net "M_C_DQS_DN<10>")
	)
	(segment
		(start 223.60763 -50.676302)
		(end 223.269556 -50.338228)
		(width 0.14224)
		(layer "In11.Cu")
		(net "M_C_DQS_DN<10>")
	)
	(segment
		(start 227.224336 -54.293008)
		(end 227.224336 -54.13121)
		(width 0.14224)
		(layer "In11.Cu")
		(net "M_C_DQS_DN<10>")
	)
	(segment
		(start 220.918024 -47.986696)
		(end 220.918024 -47.824898)
		(width 0.14224)
		(layer "In11.Cu")
		(net "M_C_DQS_DN<10>")
	)
	(segment
		(start 210.032346 -11.1252)
		(end 209.874866 -10.96772)
		(width 0.14224)
		(layer "In11.Cu")
		(net "M_C_DQS_DN<10>")
	)
	(segment
		(start 225.792792 -52.861464)
		(end 225.613214 -52.681886)
		(width 0.14224)
		(layer "In11.Cu")
		(net "M_C_DQS_DN<10>")
	)
	(segment
		(start 209.32775 -4.8006)
		(end 209.53095 -4.5974)
		(width 0.14224)
		(layer "In11.Cu")
		(net "M_C_DQS_DN<10>")
	)
	(segment
		(start 221.928436 -48.83531)
		(end 221.766638 -48.83531)
		(width 0.14224)
		(layer "In11.Cu")
		(net "M_C_DQS_DN<10>")
	)
	(segment
		(start 222.92818 -49.996852)
		(end 222.659956 -49.728628)
		(width 0.14224)
		(layer "In11.Cu")
		(net "M_C_DQS_DN<10>")
	)
	(segment
		(start 209.874866 -6.888988)
		(end 210.001866 -6.761988)
		(width 0.14224)
		(layer "In11.Cu")
		(net "M_C_DQS_DN<10>")
	)
	(segment
		(start 223.269556 -50.338228)
		(end 223.269556 -50.176684)
		(width 0.14224)
		(layer "In11.Cu")
		(net "M_C_DQS_DN<10>")
	)
	(segment
		(start 210.032346 -9.6012)
		(end 209.874866 -9.44372)
		(width 0.14224)
		(layer "In11.Cu")
		(net "M_C_DQS_DN<10>")
	)
	(segment
		(start 226.313746 -53.382418)
		(end 226.134168 -53.20284)
		(width 0.14224)
		(layer "In11.Cu")
		(net "M_C_DQS_DN<10>")
	)
	(segment
		(start 209.948272 -35.313112)
		(end 209.948272 -34.266632)
		(width 0.14224)
		(layer "In11.Cu")
		(net "M_C_DQS_DN<10>")
	)
	(segment
		(start 228.130354 -55.037228)
		(end 227.968556 -55.037228)
		(width 0.14224)
		(layer "In11.Cu")
		(net "M_C_DQS_DN<10>")
	)
	(segment
		(start 222.108268 -49.17694)
		(end 222.108268 -49.015142)
		(width 0.14224)
		(layer "In11.Cu")
		(net "M_C_DQS_DN<10>")
	)
	(segment
		(start 223.269556 -50.176684)
		(end 223.089724 -49.996852)
		(width 0.14224)
		(layer "In11.Cu")
		(net "M_C_DQS_DN<10>")
	)
	(segment
		(start 229.40772 -56.314594)
		(end 229.227888 -56.134762)
		(width 0.14224)
		(layer "In11.Cu")
		(net "M_C_DQS_DN<10>")
	)
	(segment
		(start 226.882706 -53.951378)
		(end 226.655122 -53.723794)
		(width 0.14224)
		(layer "In11.Cu")
		(net "M_C_DQS_DN<10>")
	)
	(segment
		(start 235.625132 -58.962036)
		(end 235.601002 -58.962036)
		(width 0.0889)
		(layer "In11.Cu")
		(net "M_C_DQS_DN<10>")
	)
	(segment
		(start 210.032346 -9.8552)
		(end 210.032346 -9.6012)
		(width 0.14224)
		(layer "In11.Cu")
		(net "M_C_DQS_DN<10>")
	)
	(segment
		(start 221.766638 -48.83531)
		(end 221.527624 -48.596296)
		(width 0.14224)
		(layer "In11.Cu")
		(net "M_C_DQS_DN<10>")
	)
	(segment
		(start 228.310186 -55.378858)
		(end 228.310186 -55.21706)
		(width 0.14224)
		(layer "In11.Cu")
		(net "M_C_DQS_DN<10>")
	)
	(segment
		(start 225.087434 -52.156106)
		(end 225.087434 -51.994308)
		(width 0.14224)
		(layer "In11.Cu")
		(net "M_C_DQS_DN<10>")
	)
	(segment
		(start 222.659956 -49.56683)
		(end 222.480124 -49.386998)
		(width 0.14224)
		(layer "In11.Cu")
		(net "M_C_DQS_DN<10>")
	)
	(segment
		(start 229.40772 -56.476392)
		(end 229.40772 -56.314594)
		(width 0.14224)
		(layer "In11.Cu")
		(net "M_C_DQS_DN<10>")
	)
	(segment
		(start 222.318326 -49.386998)
		(end 222.108268 -49.17694)
		(width 0.14224)
		(layer "In11.Cu")
		(net "M_C_DQS_DN<10>")
	)
	(segment
		(start 222.108268 -49.015142)
		(end 221.928436 -48.83531)
		(width 0.14224)
		(layer "In11.Cu")
		(net "M_C_DQS_DN<10>")
	)
	(arc
		(start 239.035082 -60.94349)
		(mid 238.841232 -60.88714)
		(end 238.699548 -60.743338)
		(width 0.0889)
		(layer "In11.Cu")
		(net "M_C_DQS_DN<10>")
	)
	(arc
		(start 235.601002 -58.962036)
		(mid 235.407152 -58.905686)
		(end 235.265468 -58.761884)
		(width 0.0889)
		(layer "In11.Cu")
		(net "M_C_DQS_DN<10>")
	)
	(arc
		(start 239.262666 -60.98413)
		(mid 239.166981 -60.955542)
		(end 239.067848 -60.94349)
		(width 0.0889)
		(layer "In11.Cu")
		(net "M_C_DQS_DN<10>")
	)
	(arc
		(start 236.123988 -59.257438)
		(mid 235.913275 -59.044359)
		(end 235.625132 -58.962036)
		(width 0.0889)
		(layer "In11.Cu")
		(net "M_C_DQS_DN<10>")
	)
	(arc
		(start 236.982508 -59.752738)
		(mid 236.7739 -59.540806)
		(end 236.488478 -59.457336)
		(width 0.0889)
		(layer "In11.Cu")
		(net "M_C_DQS_DN<10>")
	)
	(arc
		(start 237.318042 -59.95289)
		(mid 237.124192 -59.89654)
		(end 236.982508 -59.752738)
		(width 0.0889)
		(layer "In11.Cu")
		(net "M_C_DQS_DN<10>")
	)
	(arc
		(start 236.455712 -59.457336)
		(mid 236.26407 -59.40017)
		(end 236.123988 -59.257438)
		(width 0.0889)
		(layer "In11.Cu")
		(net "M_C_DQS_DN<10>")
	)
	(arc
		(start 235.265468 -58.761884)
		(mid 235.058464 -58.55102)
		(end 234.775248 -58.466736)
		(width 0.0889)
		(layer "In11.Cu")
		(net "M_C_DQS_DN<10>")
	)
	(arc
		(start 238.172752 -60.447936)
		(mid 237.98111 -60.39077)
		(end 237.841028 -60.248038)
		(width 0.0889)
		(layer "In11.Cu")
		(net "M_C_DQS_DN<10>")
	)
	(arc
		(start 238.699548 -60.743338)
		(mid 238.49094 -60.531406)
		(end 238.205518 -60.447936)
		(width 0.0889)
		(layer "In11.Cu")
		(net "M_C_DQS_DN<10>")
	)
	(arc
		(start 237.841028 -60.248038)
		(mid 237.634024 -60.037174)
		(end 237.350808 -59.95289)
		(width 0.0889)
		(layer "In11.Cu")
		(net "M_C_DQS_DN<10>")
	)
	(segment
		(start 243.051838 -64.50584)
		(end 242.480338 -64.50584)
		(width 0.0889)
		(layer "F.Cu")
		(net "M_C_DQS_DN<0>")
	)
	(segment
		(start 200.64984 0.19177)
		(end 200.384156 0.457454)
		(width 0.1651)
		(layer "F.Cu")
		(net "M_C_DQS_DN<0>")
	)
	(segment
		(start 200.64984 -0.821182)
		(end 200.64984 0.19177)
		(width 0.1651)
		(layer "F.Cu")
		(net "M_C_DQS_DN<0>")
	)
	(segment
		(start 200.650348 -0.821182)
		(end 200.64984 -0.821182)
		(width 0.1651)
		(layer "F.Cu")
		(net "M_C_DQS_DN<0>")
	)
	(segment
		(start 200.384156 0.457454)
		(end 200.384156 1.190244)
		(width 0.1651)
		(layer "F.Cu")
		(net "M_C_DQS_DN<0>")
	)
	(segment
		(start 200.384156 1.190244)
		(end 201.037952 1.84404)
		(width 0.1651)
		(layer "F.Cu")
		(net "M_C_DQS_DN<0>")
	)
	(via
		(at 201.037952 1.84404)
		(size 0.508)
		(drill 0.254)
		(layers "F.Cu" "B.Cu")
		(net "M_C_DQS_DN<0>")
	)
	(via
		(at 201.037952 -3.686556)
		(size 0.508)
		(drill 0.254)
		(layers "F.Cu" "B.Cu")
		(net "M_C_DQS_DN<0>")
	)
	(via
		(at 242.480338 -64.50584)
		(size 0.508)
		(drill 0.254)
		(layers "F.Cu" "B.Cu")
		(net "M_C_DQS_DN<0>")
	)
	(segment
		(start 200.64984 -1.021842)
		(end 200.64984 -1.91897)
		(width 0.1651)
		(layer "B.Cu")
		(net "M_C_DQS_DN<0>")
	)
	(segment
		(start 200.650348 -1.021842)
		(end 200.64984 -1.021842)
		(width 0.1651)
		(layer "B.Cu")
		(net "M_C_DQS_DN<0>")
	)
	(segment
		(start 200.64984 -1.91897)
		(end 200.396856 -2.171954)
		(width 0.1651)
		(layer "B.Cu")
		(net "M_C_DQS_DN<0>")
	)
	(segment
		(start 200.396856 -2.171954)
		(end 200.396856 -3.04546)
		(width 0.1651)
		(layer "B.Cu")
		(net "M_C_DQS_DN<0>")
	)
	(segment
		(start 200.396856 -3.04546)
		(end 201.037952 -3.686556)
		(width 0.1651)
		(layer "B.Cu")
		(net "M_C_DQS_DN<0>")
	)
	(segment
		(start 240.741708 -64.90589)
		(end 240.774474 -64.90589)
		(width 0.0889)
		(layer "In11.Cu")
		(net "M_C_DQS_DN<0>")
	)
	(segment
		(start 226.390454 -63.534798)
		(end 226.390454 -63.696342)
		(width 0.14224)
		(layer "In11.Cu")
		(net "M_C_DQS_DN<0>")
	)
	(segment
		(start 201.037952 -3.686556)
		(end 201.84872 -2.875788)
		(width 0.14224)
		(layer "In11.Cu")
		(net "M_C_DQS_DN<0>")
	)
	(segment
		(start 229.872286 -63.87592)
		(end 229.986586 -63.76162)
		(width 0.14224)
		(layer "In11.Cu")
		(net "M_C_DQS_DN<0>")
	)
	(segment
		(start 201.820272 -35.471354)
		(end 201.820272 -37.564568)
		(width 0.14224)
		(layer "In11.Cu")
		(net "M_C_DQS_DN<0>")
	)
	(segment
		(start 234.75315 -63.41999)
		(end 234.754674 -63.41999)
		(width 0.0889)
		(layer "In11.Cu")
		(net "M_C_DQS_DN<0>")
	)
	(segment
		(start 201.820272 -24.994362)
		(end 200.68032 -26.134314)
		(width 0.14224)
		(layer "In11.Cu")
		(net "M_C_DQS_DN<0>")
	)
	(segment
		(start 226.049078 -63.354966)
		(end 226.210622 -63.354966)
		(width 0.14224)
		(layer "In11.Cu")
		(net "M_C_DQS_DN<0>")
	)
	(segment
		(start 224.846642 -61.990986)
		(end 225.026474 -62.170818)
		(width 0.14224)
		(layer "In11.Cu")
		(net "M_C_DQS_DN<0>")
	)
	(segment
		(start 201.501756 -4.5466)
		(end 200.988676 -5.05968)
		(width 0.14224)
		(layer "In11.Cu")
		(net "M_C_DQS_DN<0>")
	)
	(segment
		(start 242.187222 -64.67475)
		(end 242.480338 -64.50584)
		(width 0.0889)
		(layer "In11.Cu")
		(net "M_C_DQS_DN<0>")
	)
	(segment
		(start 201.037952 -3.686556)
		(end 201.501756 -4.15036)
		(width 0.14224)
		(layer "In11.Cu")
		(net "M_C_DQS_DN<0>")
	)
	(segment
		(start 224.104454 -61.410342)
		(end 224.265998 -61.410342)
		(width 0.14224)
		(layer "In11.Cu")
		(net "M_C_DQS_DN<0>")
	)
	(segment
		(start 201.956416 -32.463994)
		(end 202.335384 -32.842962)
		(width 0.14224)
		(layer "In11.Cu")
		(net "M_C_DQS_DN<0>")
	)
	(segment
		(start 226.390454 -63.696342)
		(end 226.570032 -63.87592)
		(width 0.14224)
		(layer "In11.Cu")
		(net "M_C_DQS_DN<0>")
	)
	(segment
		(start 242.097814 -64.65062)
		(end 242.187222 -64.67475)
		(width 0.0889)
		(layer "In11.Cu")
		(net "M_C_DQS_DN<0>")
	)
	(segment
		(start 229.986586 -63.76162)
		(end 230.240586 -63.76162)
		(width 0.14224)
		(layer "In11.Cu")
		(net "M_C_DQS_DN<0>")
	)
	(segment
		(start 200.901808 -32.463994)
		(end 201.956416 -32.463994)
		(width 0.14224)
		(layer "In11.Cu")
		(net "M_C_DQS_DN<0>")
	)
	(segment
		(start 200.988676 -5.05968)
		(end 200.988676 -5.280152)
		(width 0.14224)
		(layer "In11.Cu")
		(net "M_C_DQS_DN<0>")
	)
	(segment
		(start 228.815392 -63.87592)
		(end 228.929692 -63.76162)
		(width 0.14224)
		(layer "In11.Cu")
		(net "M_C_DQS_DN<0>")
	)
	(segment
		(start 230.240586 -63.76162)
		(end 230.354886 -63.87592)
		(width 0.14224)
		(layer "In11.Cu")
		(net "M_C_DQS_DN<0>")
	)
	(segment
		(start 225.671126 -62.977014)
		(end 226.049078 -63.354966)
		(width 0.14224)
		(layer "In11.Cu")
		(net "M_C_DQS_DN<0>")
	)
	(segment
		(start 201.820272 -37.564568)
		(end 205.480666 -41.224962)
		(width 0.14224)
		(layer "In11.Cu")
		(net "M_C_DQS_DN<0>")
	)
	(segment
		(start 227.627434 -63.76162)
		(end 227.741734 -63.87592)
		(width 0.14224)
		(layer "In11.Cu")
		(net "M_C_DQS_DN<0>")
	)
	(segment
		(start 235.601002 -63.91529)
		(end 235.633768 -63.91529)
		(width 0.0889)
		(layer "In11.Cu")
		(net "M_C_DQS_DN<0>")
	)
	(segment
		(start 224.685098 -61.990986)
		(end 224.846642 -61.990986)
		(width 0.14224)
		(layer "In11.Cu")
		(net "M_C_DQS_DN<0>")
	)
	(segment
		(start 227.741734 -63.87592)
		(end 228.03739 -63.87592)
		(width 0.14224)
		(layer "In11.Cu")
		(net "M_C_DQS_DN<0>")
	)
	(segment
		(start 200.958958 -35.15868)
		(end 201.507598 -35.15868)
		(width 0.14224)
		(layer "In11.Cu")
		(net "M_C_DQS_DN<0>")
	)
	(segment
		(start 225.026474 -62.170818)
		(end 225.026474 -62.332362)
		(width 0.14224)
		(layer "In11.Cu")
		(net "M_C_DQS_DN<0>")
	)
	(segment
		(start 227.259134 -63.87592)
		(end 227.373434 -63.76162)
		(width 0.14224)
		(layer "In11.Cu")
		(net "M_C_DQS_DN<0>")
	)
	(segment
		(start 230.354886 -63.87592)
		(end 231.297988 -63.87592)
		(width 0.14224)
		(layer "In11.Cu")
		(net "M_C_DQS_DN<0>")
	)
	(segment
		(start 202.335384 -33.675066)
		(end 201.931016 -34.079434)
		(width 0.14224)
		(layer "In11.Cu")
		(net "M_C_DQS_DN<0>")
	)
	(segment
		(start 228.40569 -63.76162)
		(end 228.51999 -63.87592)
		(width 0.14224)
		(layer "In11.Cu")
		(net "M_C_DQS_DN<0>")
	)
	(segment
		(start 229.183692 -63.76162)
		(end 229.297992 -63.87592)
		(width 0.14224)
		(layer "In11.Cu")
		(net "M_C_DQS_DN<0>")
	)
	(segment
		(start 224.265998 -61.410342)
		(end 224.44583 -61.590174)
		(width 0.14224)
		(layer "In11.Cu")
		(net "M_C_DQS_DN<0>")
	)
	(segment
		(start 205.480666 -41.224962)
		(end 205.480666 -42.786554)
		(width 0.14224)
		(layer "In11.Cu")
		(net "M_C_DQS_DN<0>")
	)
	(segment
		(start 201.092054 -34.079434)
		(end 200.730612 -34.440876)
		(width 0.14224)
		(layer "In11.Cu")
		(net "M_C_DQS_DN<0>")
	)
	(segment
		(start 228.51999 -63.87592)
		(end 228.815392 -63.87592)
		(width 0.14224)
		(layer "In11.Cu")
		(net "M_C_DQS_DN<0>")
	)
	(segment
		(start 228.929692 -63.76162)
		(end 229.183692 -63.76162)
		(width 0.14224)
		(layer "In11.Cu")
		(net "M_C_DQS_DN<0>")
	)
	(segment
		(start 224.44583 -61.751718)
		(end 224.685098 -61.990986)
		(width 0.14224)
		(layer "In11.Cu")
		(net "M_C_DQS_DN<0>")
	)
	(segment
		(start 202.335384 -32.842962)
		(end 202.335384 -33.675066)
		(width 0.14224)
		(layer "In11.Cu")
		(net "M_C_DQS_DN<0>")
	)
	(segment
		(start 225.026474 -62.332362)
		(end 225.329496 -62.635384)
		(width 0.14224)
		(layer "In11.Cu")
		(net "M_C_DQS_DN<0>")
	)
	(segment
		(start 205.480666 -42.786554)
		(end 224.104454 -61.410342)
		(width 0.14224)
		(layer "In11.Cu")
		(net "M_C_DQS_DN<0>")
	)
	(segment
		(start 200.988676 -5.280152)
		(end 201.820272 -6.111748)
		(width 0.14224)
		(layer "In11.Cu")
		(net "M_C_DQS_DN<0>")
	)
	(segment
		(start 201.931016 -34.079434)
		(end 201.092054 -34.079434)
		(width 0.14224)
		(layer "In11.Cu")
		(net "M_C_DQS_DN<0>")
	)
	(segment
		(start 201.501756 -4.15036)
		(end 201.501756 -4.5466)
		(width 0.14224)
		(layer "In11.Cu")
		(net "M_C_DQS_DN<0>")
	)
	(segment
		(start 200.68032 -26.134314)
		(end 200.68032 -32.242506)
		(width 0.14224)
		(layer "In11.Cu")
		(net "M_C_DQS_DN<0>")
	)
	(segment
		(start 228.03739 -63.87592)
		(end 228.15169 -63.76162)
		(width 0.14224)
		(layer "In11.Cu")
		(net "M_C_DQS_DN<0>")
	)
	(segment
		(start 236.455712 -64.410336)
		(end 236.488478 -64.410336)
		(width 0.0889)
		(layer "In11.Cu")
		(net "M_C_DQS_DN<0>")
	)
	(segment
		(start 237.318042 -64.90589)
		(end 237.350808 -64.90589)
		(width 0.0889)
		(layer "In11.Cu")
		(net "M_C_DQS_DN<0>")
	)
	(segment
		(start 201.820272 -6.111748)
		(end 201.820272 -24.994362)
		(width 0.14224)
		(layer "In11.Cu")
		(net "M_C_DQS_DN<0>")
	)
	(segment
		(start 225.491294 -62.635384)
		(end 225.671126 -62.815216)
		(width 0.14224)
		(layer "In11.Cu")
		(net "M_C_DQS_DN<0>")
	)
	(segment
		(start 201.84872 -2.875788)
		(end 201.84872 1.033272)
		(width 0.14224)
		(layer "In11.Cu")
		(net "M_C_DQS_DN<0>")
	)
	(segment
		(start 224.44583 -61.590174)
		(end 224.44583 -61.751718)
		(width 0.14224)
		(layer "In11.Cu")
		(net "M_C_DQS_DN<0>")
	)
	(segment
		(start 231.320086 -63.87592)
		(end 231.359456 -63.91529)
		(width 0.0889)
		(layer "In11.Cu")
		(net "M_C_DQS_DN<0>")
	)
	(segment
		(start 238.172752 -65.400936)
		(end 238.201454 -65.400936)
		(width 0.0889)
		(layer "In11.Cu")
		(net "M_C_DQS_DN<0>")
	)
	(segment
		(start 231.297988 -63.87592)
		(end 231.320086 -63.87592)
		(width 0.0889)
		(layer "In11.Cu")
		(net "M_C_DQS_DN<0>")
	)
	(segment
		(start 226.210622 -63.354966)
		(end 226.390454 -63.534798)
		(width 0.14224)
		(layer "In11.Cu")
		(net "M_C_DQS_DN<0>")
	)
	(segment
		(start 228.15169 -63.76162)
		(end 228.40569 -63.76162)
		(width 0.14224)
		(layer "In11.Cu")
		(net "M_C_DQS_DN<0>")
	)
	(segment
		(start 241.604038 -64.410336)
		(end 241.639598 -64.410336)
		(width 0.0889)
		(layer "In11.Cu")
		(net "M_C_DQS_DN<0>")
	)
	(segment
		(start 225.329496 -62.635384)
		(end 225.491294 -62.635384)
		(width 0.14224)
		(layer "In11.Cu")
		(net "M_C_DQS_DN<0>")
	)
	(segment
		(start 239.046004 -65.89649)
		(end 239.046512 -65.89649)
		(width 0.0889)
		(layer "In11.Cu")
		(net "M_C_DQS_DN<0>")
	)
	(segment
		(start 200.730612 -34.930334)
		(end 200.958958 -35.15868)
		(width 0.14224)
		(layer "In11.Cu")
		(net "M_C_DQS_DN<0>")
	)
	(segment
		(start 226.570032 -63.87592)
		(end 227.259134 -63.87592)
		(width 0.14224)
		(layer "In11.Cu")
		(net "M_C_DQS_DN<0>")
	)
	(segment
		(start 201.84872 1.033272)
		(end 201.037952 1.84404)
		(width 0.14224)
		(layer "In11.Cu")
		(net "M_C_DQS_DN<0>")
	)
	(segment
		(start 233.894376 -63.915036)
		(end 233.8959 -63.915036)
		(width 0.0889)
		(layer "In11.Cu")
		(net "M_C_DQS_DN<0>")
	)
	(segment
		(start 231.359456 -63.91529)
		(end 232.189274 -63.91529)
		(width 0.0889)
		(layer "In11.Cu")
		(net "M_C_DQS_DN<0>")
	)
	(segment
		(start 239.891062 -65.400936)
		(end 239.919764 -65.400936)
		(width 0.0889)
		(layer "In11.Cu")
		(net "M_C_DQS_DN<0>")
	)
	(segment
		(start 229.297992 -63.87592)
		(end 229.872286 -63.87592)
		(width 0.14224)
		(layer "In11.Cu")
		(net "M_C_DQS_DN<0>")
	)
	(segment
		(start 201.507598 -35.15868)
		(end 201.820272 -35.471354)
		(width 0.14224)
		(layer "In11.Cu")
		(net "M_C_DQS_DN<0>")
	)
	(segment
		(start 233.035602 -63.41999)
		(end 233.03738 -63.41999)
		(width 0.0889)
		(layer "In11.Cu")
		(net "M_C_DQS_DN<0>")
	)
	(segment
		(start 227.373434 -63.76162)
		(end 227.627434 -63.76162)
		(width 0.14224)
		(layer "In11.Cu")
		(net "M_C_DQS_DN<0>")
	)
	(segment
		(start 225.671126 -62.815216)
		(end 225.671126 -62.977014)
		(width 0.14224)
		(layer "In11.Cu")
		(net "M_C_DQS_DN<0>")
	)
	(segment
		(start 200.730612 -34.440876)
		(end 200.730612 -34.930334)
		(width 0.14224)
		(layer "In11.Cu")
		(net "M_C_DQS_DN<0>")
	)
	(segment
		(start 200.68032 -32.242506)
		(end 200.901808 -32.463994)
		(width 0.14224)
		(layer "In11.Cu")
		(net "M_C_DQS_DN<0>")
	)
	(arc
		(start 232.524808 -63.715138)
		(mid 232.740662 -63.499157)
		(end 233.035602 -63.41999)
		(width 0.0889)
		(layer "In11.Cu")
		(net "M_C_DQS_DN<0>")
	)
	(arc
		(start 234.241848 -63.715138)
		(mid 234.457921 -63.49903)
		(end 234.75315 -63.41999)
		(width 0.0889)
		(layer "In11.Cu")
		(net "M_C_DQS_DN<0>")
	)
	(arc
		(start 233.8959 -63.915036)
		(mid 234.095673 -63.861467)
		(end 234.241848 -63.715138)
		(width 0.0889)
		(layer "In11.Cu")
		(net "M_C_DQS_DN<0>")
	)
	(arc
		(start 238.699548 -65.696338)
		(mid 238.84593 -65.842902)
		(end 239.046004 -65.89649)
		(width 0.0889)
		(layer "In11.Cu")
		(net "M_C_DQS_DN<0>")
	)
	(arc
		(start 232.189274 -63.91529)
		(mid 232.383124 -63.85894)
		(end 232.524808 -63.715138)
		(width 0.0889)
		(layer "In11.Cu")
		(net "M_C_DQS_DN<0>")
	)
	(arc
		(start 236.982508 -64.705738)
		(mid 237.124191 -64.849542)
		(end 237.318042 -64.90589)
		(width 0.0889)
		(layer "In11.Cu")
		(net "M_C_DQS_DN<0>")
	)
	(arc
		(start 235.265468 -63.715138)
		(mid 235.407151 -63.858942)
		(end 235.601002 -63.91529)
		(width 0.0889)
		(layer "In11.Cu")
		(net "M_C_DQS_DN<0>")
	)
	(arc
		(start 233.548428 -63.715138)
		(mid 233.6946 -63.861473)
		(end 233.894376 -63.915036)
		(width 0.0889)
		(layer "In11.Cu")
		(net "M_C_DQS_DN<0>")
	)
	(arc
		(start 233.03738 -63.41999)
		(mid 233.332518 -63.499001)
		(end 233.548428 -63.715138)
		(width 0.0889)
		(layer "In11.Cu")
		(net "M_C_DQS_DN<0>")
	)
	(arc
		(start 239.046512 -65.89649)
		(mid 239.246553 -65.842845)
		(end 239.392968 -65.696338)
		(width 0.0889)
		(layer "In11.Cu")
		(net "M_C_DQS_DN<0>")
	)
	(arc
		(start 236.123988 -64.210438)
		(mid 236.264067 -64.353174)
		(end 236.455712 -64.410336)
		(width 0.0889)
		(layer "In11.Cu")
		(net "M_C_DQS_DN<0>")
	)
	(arc
		(start 237.350808 -64.90589)
		(mid 237.634025 -64.990171)
		(end 237.841028 -65.201038)
		(width 0.0889)
		(layer "In11.Cu")
		(net "M_C_DQS_DN<0>")
	)
	(arc
		(start 239.919764 -65.400936)
		(mid 240.111406 -65.34377)
		(end 240.251488 -65.201038)
		(width 0.0889)
		(layer "In11.Cu")
		(net "M_C_DQS_DN<0>")
	)
	(arc
		(start 240.251488 -65.201038)
		(mid 240.458492 -64.990174)
		(end 240.741708 -64.90589)
		(width 0.0889)
		(layer "In11.Cu")
		(net "M_C_DQS_DN<0>")
	)
	(arc
		(start 239.392968 -65.696338)
		(mid 239.603321 -65.483366)
		(end 239.891062 -65.400936)
		(width 0.0889)
		(layer "In11.Cu")
		(net "M_C_DQS_DN<0>")
	)
	(arc
		(start 236.488478 -64.410336)
		(mid 236.773902 -64.493803)
		(end 236.982508 -64.705738)
		(width 0.0889)
		(layer "In11.Cu")
		(net "M_C_DQS_DN<0>")
	)
	(arc
		(start 240.774474 -64.90589)
		(mid 240.968324 -64.84954)
		(end 241.110008 -64.705738)
		(width 0.0889)
		(layer "In11.Cu")
		(net "M_C_DQS_DN<0>")
	)
	(arc
		(start 241.639598 -64.410336)
		(mid 241.89642 -64.477637)
		(end 242.097814 -64.65062)
		(width 0.0889)
		(layer "In11.Cu")
		(net "M_C_DQS_DN<0>")
	)
	(arc
		(start 235.633768 -63.91529)
		(mid 235.916985 -63.999571)
		(end 236.123988 -64.210438)
		(width 0.0889)
		(layer "In11.Cu")
		(net "M_C_DQS_DN<0>")
	)
	(arc
		(start 241.110008 -64.705738)
		(mid 241.318616 -64.493806)
		(end 241.604038 -64.410336)
		(width 0.0889)
		(layer "In11.Cu")
		(net "M_C_DQS_DN<0>")
	)
	(arc
		(start 238.201454 -65.400936)
		(mid 238.489141 -65.483457)
		(end 238.699548 -65.696338)
		(width 0.0889)
		(layer "In11.Cu")
		(net "M_C_DQS_DN<0>")
	)
	(arc
		(start 234.754674 -63.41999)
		(mid 235.049668 -63.499064)
		(end 235.265468 -63.715138)
		(width 0.0889)
		(layer "In11.Cu")
		(net "M_C_DQS_DN<0>")
	)
	(arc
		(start 237.841028 -65.201038)
		(mid 237.981107 -65.343774)
		(end 238.172752 -65.400936)
		(width 0.0889)
		(layer "In11.Cu")
		(net "M_C_DQS_DN<0>")
	)
	(segment
		(start 243.051838 -60.54344)
		(end 242.480338 -60.54344)
		(width 0.0889)
		(layer "F.Cu")
		(net "M_C_DQ<9>")
	)
	(segment
		(start 207.449928 3.778758)
		(end 207.449928 2.514854)
		(width 0.1651)
		(layer "F.Cu")
		(net "M_C_DQ<9>")
	)
	(segment
		(start 207.450436 3.778758)
		(end 207.449928 3.778758)
		(width 0.1651)
		(layer "F.Cu")
		(net "M_C_DQ<9>")
	)
	(via
		(at 208.122012 -3.076956)
		(size 0.508)
		(drill 0.254)
		(layers "F.Cu" "B.Cu")
		(net "M_C_DQ<9>")
	)
	(via
		(at 207.449928 2.514854)
		(size 0.508)
		(drill 0.254)
		(layers "F.Cu" "B.Cu")
		(net "M_C_DQ<9>")
	)
	(via
		(at 242.480338 -60.54344)
		(size 0.508)
		(drill 0.254)
		(layers "F.Cu" "B.Cu")
		(net "M_C_DQ<9>")
	)
	(segment
		(start 208.30032 -1.021842)
		(end 208.299812 -1.021842)
		(width 0.1651)
		(layer "B.Cu")
		(net "M_C_DQ<9>")
	)
	(segment
		(start 208.122012 -2.573782)
		(end 208.122012 -3.076956)
		(width 0.1651)
		(layer "B.Cu")
		(net "M_C_DQ<9>")
	)
	(segment
		(start 208.299812 -2.395982)
		(end 208.122012 -2.573782)
		(width 0.1651)
		(layer "B.Cu")
		(net "M_C_DQ<9>")
	)
	(segment
		(start 208.299812 -1.021842)
		(end 208.299812 -2.395982)
		(width 0.1651)
		(layer "B.Cu")
		(net "M_C_DQ<9>")
	)
	(segment
		(start 208.244694 -36.635944)
		(end 213.21395 -41.6052)
		(width 0.14224)
		(layer "In11.Cu")
		(net "M_C_DQ<9>")
	)
	(segment
		(start 241.606832 -61.438536)
		(end 241.636804 -61.438536)
		(width 0.0889)
		(layer "In11.Cu")
		(net "M_C_DQ<9>")
	)
	(segment
		(start 230.310944 -58.176668)
		(end 230.54691 -58.412634)
		(width 0.0889)
		(layer "In11.Cu")
		(net "M_C_DQ<9>")
	)
	(segment
		(start 208.609946 -11.747754)
		(end 208.609946 -18.998946)
		(width 0.14224)
		(layer "In11.Cu")
		(net "M_C_DQ<9>")
	)
	(segment
		(start 208.7626 -9.601454)
		(end 208.7626 -11.5951)
		(width 0.14224)
		(layer "In11.Cu")
		(net "M_C_DQ<9>")
	)
	(segment
		(start 230.54691 -58.412634)
		(end 232.722166 -58.412634)
		(width 0.0889)
		(layer "In11.Cu")
		(net "M_C_DQ<9>")
	)
	(segment
		(start 233.766868 -59.457336)
		(end 234.771438 -59.457336)
		(width 0.0889)
		(layer "In11.Cu")
		(net "M_C_DQ<9>")
	)
	(segment
		(start 239.893602 -61.629036)
		(end 239.926368 -61.629036)
		(width 0.0889)
		(layer "In11.Cu")
		(net "M_C_DQ<9>")
	)
	(segment
		(start 208.7626 -11.5951)
		(end 208.609946 -11.747754)
		(width 0.14224)
		(layer "In11.Cu")
		(net "M_C_DQ<9>")
	)
	(segment
		(start 232.722166 -58.412634)
		(end 233.766868 -59.457336)
		(width 0.0889)
		(layer "In11.Cu")
		(net "M_C_DQ<9>")
	)
	(segment
		(start 208.609946 -9.4488)
		(end 208.7626 -9.601454)
		(width 0.14224)
		(layer "In11.Cu")
		(net "M_C_DQ<9>")
	)
	(segment
		(start 238.172752 -61.438536)
		(end 238.205518 -61.438536)
		(width 0.0889)
		(layer "In11.Cu")
		(net "M_C_DQ<9>")
	)
	(segment
		(start 229.785418 -58.176668)
		(end 230.310944 -58.176668)
		(width 0.14224)
		(layer "In11.Cu")
		(net "M_C_DQ<9>")
	)
	(segment
		(start 241.968528 -61.238638)
		(end 241.985292 -61.209174)
		(width 0.0889)
		(layer "In11.Cu")
		(net "M_C_DQ<9>")
	)
	(segment
		(start 208.7626 -19.1516)
		(end 208.7626 -21.132546)
		(width 0.14224)
		(layer "In11.Cu")
		(net "M_C_DQ<9>")
	)
	(segment
		(start 208.652618 1.128776)
		(end 208.282794 1.4986)
		(width 0.14224)
		(layer "In11.Cu")
		(net "M_C_DQ<9>")
	)
	(segment
		(start 207.974946 -4.241292)
		(end 207.974946 -5.841746)
		(width 0.14224)
		(layer "In11.Cu")
		(net "M_C_DQ<9>")
	)
	(segment
		(start 207.59547 -3.603498)
		(end 207.59547 -3.861816)
		(width 0.14224)
		(layer "In11.Cu")
		(net "M_C_DQ<9>")
	)
	(segment
		(start 240.849404 -61.13399)
		(end 241.400838 -61.372496)
		(width 0.0889)
		(layer "In11.Cu")
		(net "M_C_DQ<9>")
	)
	(segment
		(start 207.927194 1.4986)
		(end 207.449928 1.975866)
		(width 0.14224)
		(layer "In11.Cu")
		(net "M_C_DQ<9>")
	)
	(segment
		(start 208.244694 -26.150316)
		(end 208.244694 -36.635944)
		(width 0.14224)
		(layer "In11.Cu")
		(net "M_C_DQ<9>")
	)
	(segment
		(start 208.609946 -18.998946)
		(end 208.7626 -19.1516)
		(width 0.14224)
		(layer "In11.Cu")
		(net "M_C_DQ<9>")
	)
	(segment
		(start 207.449928 1.975866)
		(end 207.449928 2.514854)
		(width 0.14224)
		(layer "In11.Cu")
		(net "M_C_DQ<9>")
	)
	(segment
		(start 239.035082 -61.93409)
		(end 239.236504 -61.93409)
		(width 0.0889)
		(layer "In11.Cu")
		(net "M_C_DQ<9>")
	)
	(segment
		(start 208.609946 -25.785064)
		(end 208.244694 -26.150316)
		(width 0.14224)
		(layer "In11.Cu")
		(net "M_C_DQ<9>")
	)
	(segment
		(start 208.7626 -21.132546)
		(end 208.609946 -21.2852)
		(width 0.14224)
		(layer "In11.Cu")
		(net "M_C_DQ<9>")
	)
	(segment
		(start 214.19947 -41.6052)
		(end 216.015316 -43.421046)
		(width 0.14224)
		(layer "In11.Cu")
		(net "M_C_DQ<9>")
	)
	(segment
		(start 240.748312 -61.13399)
		(end 240.849404 -61.13399)
		(width 0.0889)
		(layer "In11.Cu")
		(net "M_C_DQ<9>")
	)
	(segment
		(start 208.652618 0.7874)
		(end 208.652618 1.128776)
		(width 0.14224)
		(layer "In11.Cu")
		(net "M_C_DQ<9>")
	)
	(segment
		(start 207.59547 -3.861816)
		(end 207.974946 -4.241292)
		(width 0.14224)
		(layer "In11.Cu")
		(net "M_C_DQ<9>")
	)
	(segment
		(start 207.974946 -5.841746)
		(end 208.609946 -6.476746)
		(width 0.14224)
		(layer "In11.Cu")
		(net "M_C_DQ<9>")
	)
	(segment
		(start 235.601002 -59.95289)
		(end 235.633768 -59.95289)
		(width 0.0889)
		(layer "In11.Cu")
		(net "M_C_DQ<9>")
	)
	(segment
		(start 216.015316 -43.421046)
		(end 216.015316 -44.406566)
		(width 0.14224)
		(layer "In11.Cu")
		(net "M_C_DQ<9>")
	)
	(segment
		(start 208.282794 1.4986)
		(end 207.927194 1.4986)
		(width 0.14224)
		(layer "In11.Cu")
		(net "M_C_DQ<9>")
	)
	(segment
		(start 216.015316 -44.406566)
		(end 229.785418 -58.176668)
		(width 0.14224)
		(layer "In11.Cu")
		(net "M_C_DQ<9>")
	)
	(segment
		(start 208.496154 0.630936)
		(end 208.652618 0.7874)
		(width 0.14224)
		(layer "In11.Cu")
		(net "M_C_DQ<9>")
	)
	(segment
		(start 236.455712 -60.447936)
		(end 236.488478 -60.447936)
		(width 0.0889)
		(layer "In11.Cu")
		(net "M_C_DQ<9>")
	)
	(segment
		(start 208.122012 -3.076956)
		(end 208.496154 -2.702814)
		(width 0.14224)
		(layer "In11.Cu")
		(net "M_C_DQ<9>")
	)
	(segment
		(start 239.236504 -61.93409)
		(end 239.627918 -61.740034)
		(width 0.0889)
		(layer "In11.Cu")
		(net "M_C_DQ<9>")
	)
	(segment
		(start 208.609946 -6.476746)
		(end 208.609946 -9.4488)
		(width 0.14224)
		(layer "In11.Cu")
		(net "M_C_DQ<9>")
	)
	(segment
		(start 208.609946 -21.2852)
		(end 208.609946 -25.785064)
		(width 0.14224)
		(layer "In11.Cu")
		(net "M_C_DQ<9>")
	)
	(segment
		(start 241.985292 -61.209174)
		(end 242.480338 -60.54344)
		(width 0.0889)
		(layer "In11.Cu")
		(net "M_C_DQ<9>")
	)
	(segment
		(start 237.318042 -60.94349)
		(end 237.350808 -60.94349)
		(width 0.0889)
		(layer "In11.Cu")
		(net "M_C_DQ<9>")
	)
	(segment
		(start 208.496154 -2.702814)
		(end 208.496154 0.630936)
		(width 0.14224)
		(layer "In11.Cu")
		(net "M_C_DQ<9>")
	)
	(segment
		(start 208.122012 -3.076956)
		(end 207.59547 -3.603498)
		(width 0.14224)
		(layer "In11.Cu")
		(net "M_C_DQ<9>")
	)
	(segment
		(start 213.21395 -41.6052)
		(end 214.19947 -41.6052)
		(width 0.14224)
		(layer "In11.Cu")
		(net "M_C_DQ<9>")
	)
	(arc
		(start 235.265468 -59.752738)
		(mid 235.407151 -59.896542)
		(end 235.601002 -59.95289)
		(width 0.0889)
		(layer "In11.Cu")
		(net "M_C_DQ<9>")
	)
	(arc
		(start 241.400838 -61.372496)
		(mid 241.499287 -61.419709)
		(end 241.606832 -61.438536)
		(width 0.0889)
		(layer "In11.Cu")
		(net "M_C_DQ<9>")
	)
	(arc
		(start 237.841028 -61.238638)
		(mid 237.981107 -61.381374)
		(end 238.172752 -61.438536)
		(width 0.0889)
		(layer "In11.Cu")
		(net "M_C_DQ<9>")
	)
	(arc
		(start 238.205518 -61.438536)
		(mid 238.490942 -61.522003)
		(end 238.699548 -61.733938)
		(width 0.0889)
		(layer "In11.Cu")
		(net "M_C_DQ<9>")
	)
	(arc
		(start 236.982508 -60.743338)
		(mid 237.124191 -60.887142)
		(end 237.318042 -60.94349)
		(width 0.0889)
		(layer "In11.Cu")
		(net "M_C_DQ<9>")
	)
	(arc
		(start 238.699548 -61.733938)
		(mid 238.841231 -61.877742)
		(end 239.035082 -61.93409)
		(width 0.0889)
		(layer "In11.Cu")
		(net "M_C_DQ<9>")
	)
	(arc
		(start 239.926368 -61.629036)
		(mid 240.209585 -61.544755)
		(end 240.416588 -61.333888)
		(width 0.0889)
		(layer "In11.Cu")
		(net "M_C_DQ<9>")
	)
	(arc
		(start 239.627918 -61.740034)
		(mid 239.750427 -61.659792)
		(end 239.893602 -61.629036)
		(width 0.0889)
		(layer "In11.Cu")
		(net "M_C_DQ<9>")
	)
	(arc
		(start 237.350808 -60.94349)
		(mid 237.634025 -61.027771)
		(end 237.841028 -61.238638)
		(width 0.0889)
		(layer "In11.Cu")
		(net "M_C_DQ<9>")
	)
	(arc
		(start 241.636804 -61.438536)
		(mid 241.828446 -61.38137)
		(end 241.968528 -61.238638)
		(width 0.0889)
		(layer "In11.Cu")
		(net "M_C_DQ<9>")
	)
	(arc
		(start 234.771438 -59.457336)
		(mid 235.056862 -59.540803)
		(end 235.265468 -59.752738)
		(width 0.0889)
		(layer "In11.Cu")
		(net "M_C_DQ<9>")
	)
	(arc
		(start 236.488478 -60.447936)
		(mid 236.773902 -60.531403)
		(end 236.982508 -60.743338)
		(width 0.0889)
		(layer "In11.Cu")
		(net "M_C_DQ<9>")
	)
	(arc
		(start 236.123988 -60.248038)
		(mid 236.264067 -60.390774)
		(end 236.455712 -60.447936)
		(width 0.0889)
		(layer "In11.Cu")
		(net "M_C_DQ<9>")
	)
	(arc
		(start 235.633768 -59.95289)
		(mid 235.916985 -60.037171)
		(end 236.123988 -60.248038)
		(width 0.0889)
		(layer "In11.Cu")
		(net "M_C_DQ<9>")
	)
	(arc
		(start 240.416588 -61.333888)
		(mid 240.556667 -61.191152)
		(end 240.748312 -61.13399)
		(width 0.0889)
		(layer "In11.Cu")
		(net "M_C_DQ<9>")
	)
	(segment
		(start 241.334798 -61.53404)
		(end 240.763298 -61.53404)
		(width 0.0889)
		(layer "F.Cu")
		(net "M_C_DQ<8>")
	)
	(segment
		(start 208.299812 -0.821182)
		(end 208.122012 1.0414)
		(width 0.1651)
		(layer "F.Cu")
		(net "M_C_DQ<8>")
	)
	(segment
		(start 208.30032 -0.821182)
		(end 208.299812 -0.821182)
		(width 0.1651)
		(layer "F.Cu")
		(net "M_C_DQ<8>")
	)
	(via
		(at 240.763298 -61.53404)
		(size 0.508)
		(drill 0.254)
		(layers "F.Cu" "B.Cu")
		(net "M_C_DQ<8>")
	)
	(via
		(at 207.449928 -4.357878)
		(size 0.508)
		(drill 0.254)
		(layers "F.Cu" "B.Cu")
		(net "M_C_DQ<8>")
	)
	(via
		(at 208.122012 1.0414)
		(size 0.508)
		(drill 0.254)
		(layers "F.Cu" "B.Cu")
		(net "M_C_DQ<8>")
	)
	(segment
		(start 207.450436 -5.621782)
		(end 207.449928 -5.621782)
		(width 0.1651)
		(layer "B.Cu")
		(net "M_C_DQ<8>")
	)
	(segment
		(start 207.449928 -5.621782)
		(end 207.449928 -4.357878)
		(width 0.1651)
		(layer "B.Cu")
		(net "M_C_DQ<8>")
	)
	(segment
		(start 207.772 -11.557)
		(end 207.974946 -11.759946)
		(width 0.14224)
		(layer "In11.Cu")
		(net "M_C_DQ<8>")
	)
	(segment
		(start 207.9244 -23.405846)
		(end 207.9244 -25.518872)
		(width 0.14224)
		(layer "In11.Cu")
		(net "M_C_DQ<8>")
	)
	(segment
		(start 240.268252 -62.199774)
		(end 240.763298 -61.53404)
		(width 0.0889)
		(layer "In11.Cu")
		(net "M_C_DQ<8>")
	)
	(segment
		(start 207.632046 -17.119854)
		(end 207.632046 -18.325846)
		(width 0.14224)
		(layer "In11.Cu")
		(net "M_C_DQ<8>")
	)
	(segment
		(start 207.165194 -4.073144)
		(end 207.165194 -3.3274)
		(width 0.14224)
		(layer "In11.Cu")
		(net "M_C_DQ<8>")
	)
	(segment
		(start 207.165194 -3.3274)
		(end 207.901794 -2.5908)
		(width 0.14224)
		(layer "In11.Cu")
		(net "M_C_DQ<8>")
	)
	(segment
		(start 214.91702 -43.304968)
		(end 215.135968 -43.304968)
		(width 0.14224)
		(layer "In11.Cu")
		(net "M_C_DQ<8>")
	)
	(segment
		(start 207.772 -9.550146)
		(end 207.772 -11.557)
		(width 0.14224)
		(layer "In11.Cu")
		(net "M_C_DQ<8>")
	)
	(segment
		(start 215.014302 -44.084748)
		(end 215.014302 -44.303696)
		(width 0.14224)
		(layer "In11.Cu")
		(net "M_C_DQ<8>")
	)
	(segment
		(start 229.522274 -58.811668)
		(end 230.310944 -58.811668)
		(width 0.14224)
		(layer "In11.Cu")
		(net "M_C_DQ<8>")
	)
	(segment
		(start 207.901794 -2.5908)
		(end 207.901794 -2.090928)
		(width 0.14224)
		(layer "In11.Cu")
		(net "M_C_DQ<8>")
	)
	(segment
		(start 207.974946 -18.948654)
		(end 207.7974 -19.1262)
		(width 0.14224)
		(layer "In11.Cu")
		(net "M_C_DQ<8>")
	)
	(segment
		(start 207.632046 -13.524992)
		(end 207.974946 -13.867892)
		(width 0.14224)
		(layer "In11.Cu")
		(net "M_C_DQ<8>")
	)
	(segment
		(start 214.027766 -42.44086)
		(end 214.24646 -42.44086)
		(width 0.14224)
		(layer "In11.Cu")
		(net "M_C_DQ<8>")
	)
	(segment
		(start 207.829912 -0.8509)
		(end 207.487012 -0.508)
		(width 0.14224)
		(layer "In11.Cu")
		(net "M_C_DQ<8>")
	)
	(segment
		(start 207.487012 -0.508)
		(end 207.487012 -0.178054)
		(width 0.14224)
		(layer "In11.Cu")
		(net "M_C_DQ<8>")
	)
	(segment
		(start 207.974946 -12.081256)
		(end 207.632046 -12.424156)
		(width 0.14224)
		(layer "In11.Cu")
		(net "M_C_DQ<8>")
	)
	(segment
		(start 207.632046 -7.518654)
		(end 207.632046 -8.699246)
		(width 0.14224)
		(layer "In11.Cu")
		(net "M_C_DQ<8>")
	)
	(segment
		(start 207.449928 -6.281928)
		(end 207.924146 -6.756146)
		(width 0.14224)
		(layer "In11.Cu")
		(net "M_C_DQ<8>")
	)
	(segment
		(start 240.251488 -62.229238)
		(end 240.268252 -62.199774)
		(width 0.0889)
		(layer "In11.Cu")
		(net "M_C_DQ<8>")
	)
	(segment
		(start 233.687874 -59.647836)
		(end 234.764834 -59.647836)
		(width 0.0889)
		(layer "In11.Cu")
		(net "M_C_DQ<8>")
	)
	(segment
		(start 207.449928 -4.357878)
		(end 207.449928 -6.281928)
		(width 0.14224)
		(layer "In11.Cu")
		(net "M_C_DQ<8>")
	)
	(segment
		(start 214.24646 -42.44086)
		(end 214.465916 -42.660316)
		(width 0.14224)
		(layer "In11.Cu")
		(net "M_C_DQ<8>")
	)
	(segment
		(start 207.632046 -8.699246)
		(end 207.974946 -9.042146)
		(width 0.14224)
		(layer "In11.Cu")
		(net "M_C_DQ<8>")
	)
	(segment
		(start 207.924146 -6.756146)
		(end 207.924146 -7.226554)
		(width 0.14224)
		(layer "In11.Cu")
		(net "M_C_DQ<8>")
	)
	(segment
		(start 214.575644 -43.646344)
		(end 214.91702 -43.304968)
		(width 0.14224)
		(layer "In11.Cu")
		(net "M_C_DQ<8>")
	)
	(segment
		(start 207.512412 -1.397)
		(end 207.829912 -1.0795)
		(width 0.14224)
		(layer "In11.Cu")
		(net "M_C_DQ<8>")
	)
	(segment
		(start 215.014302 -44.303696)
		(end 229.522274 -58.811668)
		(width 0.14224)
		(layer "In11.Cu")
		(net "M_C_DQ<8>")
	)
	(segment
		(start 207.449928 -4.357878)
		(end 207.165194 -4.073144)
		(width 0.14224)
		(layer "In11.Cu")
		(net "M_C_DQ<8>")
	)
	(segment
		(start 235.594398 -60.14339)
		(end 235.627164 -60.14339)
		(width 0.0889)
		(layer "In11.Cu")
		(net "M_C_DQ<8>")
	)
	(segment
		(start 232.643172 -58.603134)
		(end 233.687874 -59.647836)
		(width 0.0889)
		(layer "In11.Cu")
		(net "M_C_DQ<8>")
	)
	(segment
		(start 214.137494 -43.207686)
		(end 214.137494 -43.426888)
		(width 0.14224)
		(layer "In11.Cu")
		(net "M_C_DQ<8>")
	)
	(segment
		(start 207.632046 -12.424156)
		(end 207.632046 -13.524992)
		(width 0.14224)
		(layer "In11.Cu")
		(net "M_C_DQ<8>")
	)
	(segment
		(start 207.974946 -9.3472)
		(end 207.772 -9.550146)
		(width 0.14224)
		(layer "In11.Cu")
		(net "M_C_DQ<8>")
	)
	(segment
		(start 207.632046 -23.113492)
		(end 207.9244 -23.405846)
		(width 0.14224)
		(layer "In11.Cu")
		(net "M_C_DQ<8>")
	)
	(segment
		(start 237.311438 -61.13399)
		(end 237.344204 -61.13399)
		(width 0.0889)
		(layer "In11.Cu")
		(net "M_C_DQ<8>")
	)
	(segment
		(start 207.901794 0.821182)
		(end 208.122012 1.0414)
		(width 0.14224)
		(layer "In11.Cu")
		(net "M_C_DQ<8>")
	)
	(segment
		(start 207.974946 -16.776954)
		(end 207.632046 -17.119854)
		(width 0.14224)
		(layer "In11.Cu")
		(net "M_C_DQ<8>")
	)
	(segment
		(start 207.974946 -9.042146)
		(end 207.974946 -9.3472)
		(width 0.14224)
		(layer "In11.Cu")
		(net "M_C_DQ<8>")
	)
	(segment
		(start 207.901794 -2.090928)
		(end 207.512412 -1.701546)
		(width 0.14224)
		(layer "In11.Cu")
		(net "M_C_DQ<8>")
	)
	(segment
		(start 207.512412 -1.701546)
		(end 207.512412 -1.397)
		(width 0.14224)
		(layer "In11.Cu")
		(net "M_C_DQ<8>")
	)
	(segment
		(start 207.974946 -21.4122)
		(end 207.974946 -21.682456)
		(width 0.14224)
		(layer "In11.Cu")
		(net "M_C_DQ<8>")
	)
	(segment
		(start 213.480142 -42.769536)
		(end 213.69909 -42.769536)
		(width 0.14224)
		(layer "In11.Cu")
		(net "M_C_DQ<8>")
	)
	(segment
		(start 207.733646 -25.709626)
		(end 207.733646 -37.02304)
		(width 0.14224)
		(layer "In11.Cu")
		(net "M_C_DQ<8>")
	)
	(segment
		(start 207.7974 -19.1262)
		(end 207.7974 -21.234654)
		(width 0.14224)
		(layer "In11.Cu")
		(net "M_C_DQ<8>")
	)
	(segment
		(start 207.974946 -18.668746)
		(end 207.974946 -18.948654)
		(width 0.14224)
		(layer "In11.Cu")
		(net "M_C_DQ<8>")
	)
	(segment
		(start 215.355424 -43.524424)
		(end 215.355424 -43.743626)
		(width 0.14224)
		(layer "In11.Cu")
		(net "M_C_DQ<8>")
	)
	(segment
		(start 207.7974 -21.234654)
		(end 207.974946 -21.4122)
		(width 0.14224)
		(layer "In11.Cu")
		(net "M_C_DQ<8>")
	)
	(segment
		(start 230.310944 -58.811668)
		(end 230.519478 -58.603134)
		(width 0.0889)
		(layer "In11.Cu")
		(net "M_C_DQ<8>")
	)
	(segment
		(start 207.733646 -37.02304)
		(end 213.480142 -42.769536)
		(width 0.14224)
		(layer "In11.Cu")
		(net "M_C_DQ<8>")
	)
	(segment
		(start 207.901794 0.236728)
		(end 207.901794 0.821182)
		(width 0.14224)
		(layer "In11.Cu")
		(net "M_C_DQ<8>")
	)
	(segment
		(start 214.465916 -42.879264)
		(end 214.137494 -43.207686)
		(width 0.14224)
		(layer "In11.Cu")
		(net "M_C_DQ<8>")
	)
	(segment
		(start 207.632046 -18.325846)
		(end 207.974946 -18.668746)
		(width 0.14224)
		(layer "In11.Cu")
		(net "M_C_DQ<8>")
	)
	(segment
		(start 215.135968 -43.304968)
		(end 215.355424 -43.524424)
		(width 0.14224)
		(layer "In11.Cu")
		(net "M_C_DQ<8>")
	)
	(segment
		(start 215.355424 -43.743626)
		(end 215.014302 -44.084748)
		(width 0.14224)
		(layer "In11.Cu")
		(net "M_C_DQ<8>")
	)
	(segment
		(start 214.465916 -42.660316)
		(end 214.465916 -42.879264)
		(width 0.14224)
		(layer "In11.Cu")
		(net "M_C_DQ<8>")
	)
	(segment
		(start 239.889792 -62.429136)
		(end 239.919764 -62.429136)
		(width 0.0889)
		(layer "In11.Cu")
		(net "M_C_DQ<8>")
	)
	(segment
		(start 214.35695 -43.646344)
		(end 214.575644 -43.646344)
		(width 0.14224)
		(layer "In11.Cu")
		(net "M_C_DQ<8>")
	)
	(segment
		(start 207.9244 -25.518872)
		(end 207.733646 -25.709626)
		(width 0.14224)
		(layer "In11.Cu")
		(net "M_C_DQ<8>")
	)
	(segment
		(start 207.974946 -13.867892)
		(end 207.974946 -16.776954)
		(width 0.14224)
		(layer "In11.Cu")
		(net "M_C_DQ<8>")
	)
	(segment
		(start 207.974946 -11.759946)
		(end 207.974946 -12.081256)
		(width 0.14224)
		(layer "In11.Cu")
		(net "M_C_DQ<8>")
	)
	(segment
		(start 207.487012 -0.178054)
		(end 207.901794 0.236728)
		(width 0.14224)
		(layer "In11.Cu")
		(net "M_C_DQ<8>")
	)
	(segment
		(start 207.632046 -22.025356)
		(end 207.632046 -23.113492)
		(width 0.14224)
		(layer "In11.Cu")
		(net "M_C_DQ<8>")
	)
	(segment
		(start 214.137494 -43.426888)
		(end 214.35695 -43.646344)
		(width 0.14224)
		(layer "In11.Cu")
		(net "M_C_DQ<8>")
	)
	(segment
		(start 239.028478 -62.12459)
		(end 239.211104 -62.12459)
		(width 0.0889)
		(layer "In11.Cu")
		(net "M_C_DQ<8>")
	)
	(segment
		(start 239.211104 -62.12459)
		(end 239.666018 -62.350396)
		(width 0.0889)
		(layer "In11.Cu")
		(net "M_C_DQ<8>")
	)
	(segment
		(start 207.974946 -21.682456)
		(end 207.632046 -22.025356)
		(width 0.14224)
		(layer "In11.Cu")
		(net "M_C_DQ<8>")
	)
	(segment
		(start 238.166148 -61.629036)
		(end 238.198914 -61.629036)
		(width 0.0889)
		(layer "In11.Cu")
		(net "M_C_DQ<8>")
	)
	(segment
		(start 236.449108 -60.638436)
		(end 236.481874 -60.638436)
		(width 0.0889)
		(layer "In11.Cu")
		(net "M_C_DQ<8>")
	)
	(segment
		(start 230.519478 -58.603134)
		(end 232.643172 -58.603134)
		(width 0.0889)
		(layer "In11.Cu")
		(net "M_C_DQ<8>")
	)
	(segment
		(start 213.69909 -42.769536)
		(end 214.027766 -42.44086)
		(width 0.14224)
		(layer "In11.Cu")
		(net "M_C_DQ<8>")
	)
	(segment
		(start 207.829912 -1.0795)
		(end 207.829912 -0.8509)
		(width 0.14224)
		(layer "In11.Cu")
		(net "M_C_DQ<8>")
	)
	(segment
		(start 207.924146 -7.226554)
		(end 207.632046 -7.518654)
		(width 0.14224)
		(layer "In11.Cu")
		(net "M_C_DQ<8>")
	)
	(arc
		(start 236.817408 -60.838588)
		(mid 237.026016 -61.05052)
		(end 237.311438 -61.13399)
		(width 0.0889)
		(layer "In11.Cu")
		(net "M_C_DQ<8>")
	)
	(arc
		(start 234.764834 -59.647836)
		(mid 234.958684 -59.704186)
		(end 235.100368 -59.847988)
		(width 0.0889)
		(layer "In11.Cu")
		(net "M_C_DQ<8>")
	)
	(arc
		(start 238.198914 -61.629036)
		(mid 238.392764 -61.685386)
		(end 238.534448 -61.829188)
		(width 0.0889)
		(layer "In11.Cu")
		(net "M_C_DQ<8>")
	)
	(arc
		(start 238.534448 -61.829188)
		(mid 238.743056 -62.04112)
		(end 239.028478 -62.12459)
		(width 0.0889)
		(layer "In11.Cu")
		(net "M_C_DQ<8>")
	)
	(arc
		(start 235.100368 -59.847988)
		(mid 235.308976 -60.05992)
		(end 235.594398 -60.14339)
		(width 0.0889)
		(layer "In11.Cu")
		(net "M_C_DQ<8>")
	)
	(arc
		(start 237.675928 -61.333888)
		(mid 237.882932 -61.544752)
		(end 238.166148 -61.629036)
		(width 0.0889)
		(layer "In11.Cu")
		(net "M_C_DQ<8>")
	)
	(arc
		(start 235.958888 -60.343288)
		(mid 236.165892 -60.554152)
		(end 236.449108 -60.638436)
		(width 0.0889)
		(layer "In11.Cu")
		(net "M_C_DQ<8>")
	)
	(arc
		(start 237.344204 -61.13399)
		(mid 237.535846 -61.191156)
		(end 237.675928 -61.333888)
		(width 0.0889)
		(layer "In11.Cu")
		(net "M_C_DQ<8>")
	)
	(arc
		(start 239.666018 -62.350396)
		(mid 239.771941 -62.406711)
		(end 239.889792 -62.429136)
		(width 0.0889)
		(layer "In11.Cu")
		(net "M_C_DQ<8>")
	)
	(arc
		(start 239.919764 -62.429136)
		(mid 240.111406 -62.37197)
		(end 240.251488 -62.229238)
		(width 0.0889)
		(layer "In11.Cu")
		(net "M_C_DQ<8>")
	)
	(arc
		(start 236.481874 -60.638436)
		(mid 236.675724 -60.694786)
		(end 236.817408 -60.838588)
		(width 0.0889)
		(layer "In11.Cu")
		(net "M_C_DQ<8>")
	)
	(arc
		(start 235.627164 -60.14339)
		(mid 235.818806 -60.200556)
		(end 235.958888 -60.343288)
		(width 0.0889)
		(layer "In11.Cu")
		(net "M_C_DQ<8>")
	)
	(segment
		(start 202.35037 3.778758)
		(end 202.349862 3.778758)
		(width 0.1651)
		(layer "F.Cu")
		(net "M_C_DQ<7>")
	)
	(segment
		(start 242.193318 -64.010286)
		(end 241.621818 -64.010286)
		(width 0.0889)
		(layer "F.Cu")
		(net "M_C_DQ<7>")
	)
	(segment
		(start 202.349862 3.778758)
		(end 202.349862 2.514854)
		(width 0.1651)
		(layer "F.Cu")
		(net "M_C_DQ<7>")
	)
	(via
		(at 202.349862 2.514854)
		(size 0.508)
		(drill 0.254)
		(layers "F.Cu" "B.Cu")
		(net "M_C_DQ<7>")
	)
	(via
		(at 203.199746 -3.076956)
		(size 0.508)
		(drill 0.254)
		(layers "F.Cu" "B.Cu")
		(net "M_C_DQ<7>")
	)
	(via
		(at 241.621818 -64.010286)
		(size 0.508)
		(drill 0.254)
		(layers "F.Cu" "B.Cu")
		(net "M_C_DQ<7>")
	)
	(segment
		(start 203.200508 -3.076194)
		(end 203.199746 -3.076956)
		(width 0.1651)
		(layer "B.Cu")
		(net "M_C_DQ<7>")
	)
	(segment
		(start 203.200508 -1.021842)
		(end 203.200508 -3.076194)
		(width 0.1651)
		(layer "B.Cu")
		(net "M_C_DQ<7>")
	)
	(segment
		(start 238.172752 -64.410336)
		(end 238.205518 -64.410336)
		(width 0.0889)
		(layer "In11.Cu")
		(net "M_C_DQ<7>")
	)
	(segment
		(start 211.171282 -46.63821)
		(end 223.852232 -59.31916)
		(width 0.14224)
		(layer "In11.Cu")
		(net "M_C_DQ<7>")
	)
	(segment
		(start 209.617818 -44.725082)
		(end 209.617818 -44.94403)
		(width 0.14224)
		(layer "In11.Cu")
		(net "M_C_DQ<7>")
	)
	(segment
		(start 203.36256 -27.3812)
		(end 203.5048 -27.52344)
		(width 0.14224)
		(layer "In11.Cu")
		(net "M_C_DQ<7>")
	)
	(segment
		(start 230.92029 -62.92469)
		(end 232.189274 -62.92469)
		(width 0.0889)
		(layer "In11.Cu")
		(net "M_C_DQ<7>")
	)
	(segment
		(start 227.663248 -62.47892)
		(end 230.47452 -62.47892)
		(width 0.14224)
		(layer "In11.Cu")
		(net "M_C_DQ<7>")
	)
	(segment
		(start 209.617818 -44.94403)
		(end 209.837274 -45.163486)
		(width 0.14224)
		(layer "In11.Cu")
		(net "M_C_DQ<7>")
	)
	(segment
		(start 203.552552 -11.763248)
		(end 203.552552 -12.170156)
		(width 0.14224)
		(layer "In11.Cu")
		(net "M_C_DQ<7>")
	)
	(segment
		(start 203.552552 -9.3726)
		(end 203.7334 -9.553448)
		(width 0.14224)
		(layer "In11.Cu")
		(net "M_C_DQ<7>")
	)
	(segment
		(start 204.226414 -36.60394)
		(end 204.084174 -36.74618)
		(width 0.14224)
		(layer "In11.Cu")
		(net "M_C_DQ<7>")
	)
	(segment
		(start 209.837274 -45.163486)
		(end 210.056222 -45.163486)
		(width 0.14224)
		(layer "In11.Cu")
		(net "M_C_DQ<7>")
	)
	(segment
		(start 203.552552 -21.771356)
		(end 203.755752 -21.974556)
		(width 0.14224)
		(layer "In11.Cu")
		(net "M_C_DQ<7>")
	)
	(segment
		(start 236.455712 -63.419736)
		(end 236.488478 -63.419736)
		(width 0.0889)
		(layer "In11.Cu")
		(net "M_C_DQ<7>")
	)
	(segment
		(start 203.581 -4.826)
		(end 203.581 -7.238746)
		(width 0.14224)
		(layer "In11.Cu")
		(net "M_C_DQ<7>")
	)
	(segment
		(start 203.64704 -36.74618)
		(end 203.5048 -36.88842)
		(width 0.14224)
		(layer "In11.Cu")
		(net "M_C_DQ<7>")
	)
	(segment
		(start 209.726784 -43.739308)
		(end 209.945732 -43.739308)
		(width 0.14224)
		(layer "In11.Cu")
		(net "M_C_DQ<7>")
	)
	(segment
		(start 203.552552 -18.570194)
		(end 203.552552 -18.996152)
		(width 0.14224)
		(layer "In11.Cu")
		(net "M_C_DQ<7>")
	)
	(segment
		(start 201.9808 -26.8986)
		(end 201.9808 -27.167078)
		(width 0.14224)
		(layer "In11.Cu")
		(net "M_C_DQ<7>")
	)
	(segment
		(start 203.64704 -37.39642)
		(end 204.084174 -37.39642)
		(width 0.14224)
		(layer "In11.Cu")
		(net "M_C_DQ<7>")
	)
	(segment
		(start 204.226414 -35.30346)
		(end 204.084174 -35.4457)
		(width 0.14224)
		(layer "In11.Cu")
		(net "M_C_DQ<7>")
	)
	(segment
		(start 210.056222 -45.163486)
		(end 210.603592 -44.616116)
		(width 0.14224)
		(layer "In11.Cu")
		(net "M_C_DQ<7>")
	)
	(segment
		(start 202.6666 2.198116)
		(end 202.6666 1.8796)
		(width 0.14224)
		(layer "In11.Cu")
		(net "M_C_DQ<7>")
	)
	(segment
		(start 203.577952 -16.890746)
		(end 203.781152 -17.093946)
		(width 0.14224)
		(layer "In11.Cu")
		(net "M_C_DQ<7>")
	)
	(segment
		(start 202.184 -26.6954)
		(end 201.9808 -26.8986)
		(width 0.14224)
		(layer "In11.Cu")
		(net "M_C_DQ<7>")
	)
	(segment
		(start 203.552552 -21.3106)
		(end 203.552552 -21.771356)
		(width 0.14224)
		(layer "In11.Cu")
		(net "M_C_DQ<7>")
	)
	(segment
		(start 203.5048 -36.88842)
		(end 203.5048 -37.25418)
		(width 0.14224)
		(layer "In11.Cu")
		(net "M_C_DQ<7>")
	)
	(segment
		(start 237.318042 -63.91529)
		(end 237.350808 -63.91529)
		(width 0.0889)
		(layer "In11.Cu")
		(net "M_C_DQ<7>")
	)
	(segment
		(start 203.755752 -23.117556)
		(end 203.577952 -23.295356)
		(width 0.14224)
		(layer "In11.Cu")
		(net "M_C_DQ<7>")
	)
	(segment
		(start 210.165188 -44.177712)
		(end 209.617818 -44.725082)
		(width 0.14224)
		(layer "In11.Cu")
		(net "M_C_DQ<7>")
	)
	(segment
		(start 203.5048 -35.58794)
		(end 203.5048 -35.9537)
		(width 0.14224)
		(layer "In11.Cu")
		(net "M_C_DQ<7>")
	)
	(segment
		(start 203.552552 -9.019794)
		(end 203.552552 -9.3726)
		(width 0.14224)
		(layer "In11.Cu")
		(net "M_C_DQ<7>")
	)
	(segment
		(start 204.226414 -37.53866)
		(end 204.226414 -38.01999)
		(width 0.14224)
		(layer "In11.Cu")
		(net "M_C_DQ<7>")
	)
	(segment
		(start 201.9808 -27.167078)
		(end 202.194922 -27.3812)
		(width 0.14224)
		(layer "In11.Cu")
		(net "M_C_DQ<7>")
	)
	(segment
		(start 209.28838 -43.081956)
		(end 209.28838 -43.300904)
		(width 0.14224)
		(layer "In11.Cu")
		(net "M_C_DQ<7>")
	)
	(segment
		(start 202.7301 -3.9751)
		(end 203.581 -4.826)
		(width 0.14224)
		(layer "In11.Cu")
		(net "M_C_DQ<7>")
	)
	(segment
		(start 203.581 -7.238746)
		(end 203.781152 -7.438898)
		(width 0.14224)
		(layer "In11.Cu")
		(net "M_C_DQ<7>")
	)
	(segment
		(start 203.708 0.7366)
		(end 203.552552 0.581152)
		(width 0.14224)
		(layer "In11.Cu")
		(net "M_C_DQ<7>")
	)
	(segment
		(start 202.7301 -3.546602)
		(end 202.7301 -3.9751)
		(width 0.14224)
		(layer "In11.Cu")
		(net "M_C_DQ<7>")
	)
	(segment
		(start 203.755752 -13.516356)
		(end 203.577952 -13.694156)
		(width 0.14224)
		(layer "In11.Cu")
		(net "M_C_DQ<7>")
	)
	(segment
		(start 203.5048 -35.9537)
		(end 203.64704 -36.09594)
		(width 0.14224)
		(layer "In11.Cu")
		(net "M_C_DQ<7>")
	)
	(segment
		(start 203.708 1.0922)
		(end 203.708 0.7366)
		(width 0.14224)
		(layer "In11.Cu")
		(net "M_C_DQ<7>")
	)
	(segment
		(start 208.74101 -43.848274)
		(end 208.74101 -44.067222)
		(width 0.14224)
		(layer "In11.Cu")
		(net "M_C_DQ<7>")
	)
	(segment
		(start 203.552552 0.581152)
		(end 203.552552 -2.72415)
		(width 0.14224)
		(layer "In11.Cu")
		(net "M_C_DQ<7>")
	)
	(segment
		(start 230.47452 -62.47892)
		(end 230.92029 -62.92469)
		(width 0.0889)
		(layer "In11.Cu")
		(net "M_C_DQ<7>")
	)
	(segment
		(start 203.2508 1.5494)
		(end 203.708 1.0922)
		(width 0.14224)
		(layer "In11.Cu")
		(net "M_C_DQ<7>")
	)
	(segment
		(start 203.450952 -26.6954)
		(end 202.184 -26.6954)
		(width 0.14224)
		(layer "In11.Cu")
		(net "M_C_DQ<7>")
	)
	(segment
		(start 203.781152 -17.093946)
		(end 203.781152 -18.341594)
		(width 0.14224)
		(layer "In11.Cu")
		(net "M_C_DQ<7>")
	)
	(segment
		(start 224.503488 -59.31916)
		(end 227.663248 -62.47892)
		(width 0.14224)
		(layer "In11.Cu")
		(net "M_C_DQ<7>")
	)
	(segment
		(start 233.018838 -62.429136)
		(end 233.054398 -62.429136)
		(width 0.0889)
		(layer "In11.Cu")
		(net "M_C_DQ<7>")
	)
	(segment
		(start 210.603592 -44.616116)
		(end 210.82254 -44.616116)
		(width 0.14224)
		(layer "In11.Cu")
		(net "M_C_DQ<7>")
	)
	(segment
		(start 208.960466 -44.286678)
		(end 209.179414 -44.286678)
		(width 0.14224)
		(layer "In11.Cu")
		(net "M_C_DQ<7>")
	)
	(segment
		(start 202.9968 1.5494)
		(end 203.2508 1.5494)
		(width 0.14224)
		(layer "In11.Cu")
		(net "M_C_DQ<7>")
	)
	(segment
		(start 203.64704 -35.4457)
		(end 203.5048 -35.58794)
		(width 0.14224)
		(layer "In11.Cu")
		(net "M_C_DQ<7>")
	)
	(segment
		(start 203.577952 -26.5684)
		(end 203.450952 -26.6954)
		(width 0.14224)
		(layer "In11.Cu")
		(net "M_C_DQ<7>")
	)
	(segment
		(start 203.577952 -13.694156)
		(end 203.577952 -16.890746)
		(width 0.14224)
		(layer "In11.Cu")
		(net "M_C_DQ<7>")
	)
	(segment
		(start 202.6666 1.8796)
		(end 202.9968 1.5494)
		(width 0.14224)
		(layer "In11.Cu")
		(net "M_C_DQ<7>")
	)
	(segment
		(start 203.5048 -34.0868)
		(end 204.226414 -34.808414)
		(width 0.14224)
		(layer "In11.Cu")
		(net "M_C_DQ<7>")
	)
	(segment
		(start 202.194922 -27.3812)
		(end 203.36256 -27.3812)
		(width 0.14224)
		(layer "In11.Cu")
		(net "M_C_DQ<7>")
	)
	(segment
		(start 203.6826 -21.180552)
		(end 203.552552 -21.3106)
		(width 0.14224)
		(layer "In11.Cu")
		(net "M_C_DQ<7>")
	)
	(segment
		(start 210.165188 -43.958764)
		(end 210.165188 -44.177712)
		(width 0.14224)
		(layer "In11.Cu")
		(net "M_C_DQ<7>")
	)
	(segment
		(start 204.084174 -37.39642)
		(end 204.226414 -37.53866)
		(width 0.14224)
		(layer "In11.Cu")
		(net "M_C_DQ<7>")
	)
	(segment
		(start 203.755752 -12.373356)
		(end 203.755752 -13.516356)
		(width 0.14224)
		(layer "In11.Cu")
		(net "M_C_DQ<7>")
	)
	(segment
		(start 210.82254 -44.616116)
		(end 211.171282 -44.964858)
		(width 0.14224)
		(layer "In11.Cu")
		(net "M_C_DQ<7>")
	)
	(segment
		(start 239.886998 -64.410336)
		(end 239.919764 -64.410336)
		(width 0.0889)
		(layer "In11.Cu")
		(net "M_C_DQ<7>")
	)
	(segment
		(start 203.781152 -7.438898)
		(end 203.781152 -8.791194)
		(width 0.14224)
		(layer "In11.Cu")
		(net "M_C_DQ<7>")
	)
	(segment
		(start 202.349862 2.514854)
		(end 202.6666 2.198116)
		(width 0.14224)
		(layer "In11.Cu")
		(net "M_C_DQ<7>")
	)
	(segment
		(start 223.852232 -59.31916)
		(end 224.503488 -59.31916)
		(width 0.14224)
		(layer "In11.Cu")
		(net "M_C_DQ<7>")
	)
	(segment
		(start 203.7334 -9.553448)
		(end 203.7334 -11.5824)
		(width 0.14224)
		(layer "In11.Cu")
		(net "M_C_DQ<7>")
	)
	(segment
		(start 204.226414 -38.01999)
		(end 209.28838 -43.081956)
		(width 0.14224)
		(layer "In11.Cu")
		(net "M_C_DQ<7>")
	)
	(segment
		(start 203.552552 -2.72415)
		(end 203.199746 -3.076956)
		(width 0.14224)
		(layer "In11.Cu")
		(net "M_C_DQ<7>")
	)
	(segment
		(start 203.64704 -36.09594)
		(end 204.084174 -36.09594)
		(width 0.14224)
		(layer "In11.Cu")
		(net "M_C_DQ<7>")
	)
	(segment
		(start 204.084174 -36.74618)
		(end 203.64704 -36.74618)
		(width 0.14224)
		(layer "In11.Cu")
		(net "M_C_DQ<7>")
	)
	(segment
		(start 235.601002 -62.92469)
		(end 235.633768 -62.92469)
		(width 0.0889)
		(layer "In11.Cu")
		(net "M_C_DQ<7>")
	)
	(segment
		(start 209.28838 -43.300904)
		(end 208.74101 -43.848274)
		(width 0.14224)
		(layer "In11.Cu")
		(net "M_C_DQ<7>")
	)
	(segment
		(start 203.755752 -21.974556)
		(end 203.755752 -23.117556)
		(width 0.14224)
		(layer "In11.Cu")
		(net "M_C_DQ<7>")
	)
	(segment
		(start 203.199746 -3.076956)
		(end 202.7301 -3.546602)
		(width 0.14224)
		(layer "In11.Cu")
		(net "M_C_DQ<7>")
	)
	(segment
		(start 203.7334 -11.5824)
		(end 203.552552 -11.763248)
		(width 0.14224)
		(layer "In11.Cu")
		(net "M_C_DQ<7>")
	)
	(segment
		(start 234.735878 -62.429136)
		(end 234.771438 -62.429136)
		(width 0.0889)
		(layer "In11.Cu")
		(net "M_C_DQ<7>")
	)
	(segment
		(start 203.5048 -37.25418)
		(end 203.64704 -37.39642)
		(width 0.14224)
		(layer "In11.Cu")
		(net "M_C_DQ<7>")
	)
	(segment
		(start 204.226414 -34.808414)
		(end 204.226414 -35.30346)
		(width 0.14224)
		(layer "In11.Cu")
		(net "M_C_DQ<7>")
	)
	(segment
		(start 204.226414 -36.23818)
		(end 204.226414 -36.60394)
		(width 0.14224)
		(layer "In11.Cu")
		(net "M_C_DQ<7>")
	)
	(segment
		(start 203.781152 -8.791194)
		(end 203.552552 -9.019794)
		(width 0.14224)
		(layer "In11.Cu")
		(net "M_C_DQ<7>")
	)
	(segment
		(start 203.552552 -12.170156)
		(end 203.755752 -12.373356)
		(width 0.14224)
		(layer "In11.Cu")
		(net "M_C_DQ<7>")
	)
	(segment
		(start 240.741708 -63.91529)
		(end 240.800382 -63.91529)
		(width 0.0889)
		(layer "In11.Cu")
		(net "M_C_DQ<7>")
	)
	(segment
		(start 203.6826 -19.1262)
		(end 203.6826 -21.180552)
		(width 0.14224)
		(layer "In11.Cu")
		(net "M_C_DQ<7>")
	)
	(segment
		(start 203.552552 -18.996152)
		(end 203.6826 -19.1262)
		(width 0.14224)
		(layer "In11.Cu")
		(net "M_C_DQ<7>")
	)
	(segment
		(start 203.577952 -23.295356)
		(end 203.577952 -26.5684)
		(width 0.14224)
		(layer "In11.Cu")
		(net "M_C_DQ<7>")
	)
	(segment
		(start 203.5048 -27.52344)
		(end 203.5048 -34.0868)
		(width 0.14224)
		(layer "In11.Cu")
		(net "M_C_DQ<7>")
	)
	(segment
		(start 211.171282 -44.964858)
		(end 211.171282 -46.63821)
		(width 0.14224)
		(layer "In11.Cu")
		(net "M_C_DQ<7>")
	)
	(segment
		(start 204.084174 -36.09594)
		(end 204.226414 -36.23818)
		(width 0.14224)
		(layer "In11.Cu")
		(net "M_C_DQ<7>")
	)
	(segment
		(start 203.781152 -18.341594)
		(end 203.552552 -18.570194)
		(width 0.14224)
		(layer "In11.Cu")
		(net "M_C_DQ<7>")
	)
	(segment
		(start 240.800382 -63.91529)
		(end 241.621818 -64.010286)
		(width 0.0889)
		(layer "In11.Cu")
		(net "M_C_DQ<7>")
	)
	(segment
		(start 208.74101 -44.067222)
		(end 208.960466 -44.286678)
		(width 0.14224)
		(layer "In11.Cu")
		(net "M_C_DQ<7>")
	)
	(segment
		(start 209.179414 -44.286678)
		(end 209.726784 -43.739308)
		(width 0.14224)
		(layer "In11.Cu")
		(net "M_C_DQ<7>")
	)
	(segment
		(start 209.945732 -43.739308)
		(end 210.165188 -43.958764)
		(width 0.14224)
		(layer "In11.Cu")
		(net "M_C_DQ<7>")
	)
	(segment
		(start 204.084174 -35.4457)
		(end 203.64704 -35.4457)
		(width 0.14224)
		(layer "In11.Cu")
		(net "M_C_DQ<7>")
	)
	(arc
		(start 232.524808 -62.724538)
		(mid 232.733416 -62.512606)
		(end 233.018838 -62.429136)
		(width 0.0889)
		(layer "In11.Cu")
		(net "M_C_DQ<7>")
	)
	(arc
		(start 233.548428 -62.724538)
		(mid 233.895138 -62.924849)
		(end 234.241848 -62.724538)
		(width 0.0889)
		(layer "In11.Cu")
		(net "M_C_DQ<7>")
	)
	(arc
		(start 238.205518 -64.410336)
		(mid 238.490942 -64.493803)
		(end 238.699548 -64.705738)
		(width 0.0889)
		(layer "In11.Cu")
		(net "M_C_DQ<7>")
	)
	(arc
		(start 236.982508 -63.715138)
		(mid 237.124191 -63.858942)
		(end 237.318042 -63.91529)
		(width 0.0889)
		(layer "In11.Cu")
		(net "M_C_DQ<7>")
	)
	(arc
		(start 240.251488 -64.210438)
		(mid 240.458492 -63.999574)
		(end 240.741708 -63.91529)
		(width 0.0889)
		(layer "In11.Cu")
		(net "M_C_DQ<7>")
	)
	(arc
		(start 234.771438 -62.429136)
		(mid 235.056862 -62.512603)
		(end 235.265468 -62.724538)
		(width 0.0889)
		(layer "In11.Cu")
		(net "M_C_DQ<7>")
	)
	(arc
		(start 233.054398 -62.429136)
		(mid 233.339822 -62.512603)
		(end 233.548428 -62.724538)
		(width 0.0889)
		(layer "In11.Cu")
		(net "M_C_DQ<7>")
	)
	(arc
		(start 239.919764 -64.410336)
		(mid 240.111406 -64.35317)
		(end 240.251488 -64.210438)
		(width 0.0889)
		(layer "In11.Cu")
		(net "M_C_DQ<7>")
	)
	(arc
		(start 235.265468 -62.724538)
		(mid 235.407151 -62.868342)
		(end 235.601002 -62.92469)
		(width 0.0889)
		(layer "In11.Cu")
		(net "M_C_DQ<7>")
	)
	(arc
		(start 239.392968 -64.705738)
		(mid 239.601576 -64.493806)
		(end 239.886998 -64.410336)
		(width 0.0889)
		(layer "In11.Cu")
		(net "M_C_DQ<7>")
	)
	(arc
		(start 237.350808 -63.91529)
		(mid 237.634025 -63.999571)
		(end 237.841028 -64.210438)
		(width 0.0889)
		(layer "In11.Cu")
		(net "M_C_DQ<7>")
	)
	(arc
		(start 237.841028 -64.210438)
		(mid 237.981107 -64.353174)
		(end 238.172752 -64.410336)
		(width 0.0889)
		(layer "In11.Cu")
		(net "M_C_DQ<7>")
	)
	(arc
		(start 236.123988 -63.219838)
		(mid 236.264067 -63.362574)
		(end 236.455712 -63.419736)
		(width 0.0889)
		(layer "In11.Cu")
		(net "M_C_DQ<7>")
	)
	(arc
		(start 234.241848 -62.724538)
		(mid 234.450456 -62.512606)
		(end 234.735878 -62.429136)
		(width 0.0889)
		(layer "In11.Cu")
		(net "M_C_DQ<7>")
	)
	(arc
		(start 235.633768 -62.92469)
		(mid 235.916985 -63.008971)
		(end 236.123988 -63.219838)
		(width 0.0889)
		(layer "In11.Cu")
		(net "M_C_DQ<7>")
	)
	(arc
		(start 238.699548 -64.705738)
		(mid 239.046258 -64.906049)
		(end 239.392968 -64.705738)
		(width 0.0889)
		(layer "In11.Cu")
		(net "M_C_DQ<7>")
	)
	(arc
		(start 232.189274 -62.92469)
		(mid 232.383124 -62.86834)
		(end 232.524808 -62.724538)
		(width 0.0889)
		(layer "In11.Cu")
		(net "M_C_DQ<7>")
	)
	(arc
		(start 236.488478 -63.419736)
		(mid 236.773902 -63.503203)
		(end 236.982508 -63.715138)
		(width 0.0889)
		(layer "In11.Cu")
		(net "M_C_DQ<7>")
	)
	(segment
		(start 203.33208 0.50292)
		(end 203.2 0.635)
		(width 0.1651)
		(layer "F.Cu")
		(net "M_C_DQ<6>")
	)
	(segment
		(start 240.476278 -65.000886)
		(end 239.904778 -65.000886)
		(width 0.0889)
		(layer "F.Cu")
		(net "M_C_DQ<6>")
	)
	(segment
		(start 203.2 0.635)
		(end 203.2 0.939546)
		(width 0.1651)
		(layer "F.Cu")
		(net "M_C_DQ<6>")
	)
	(segment
		(start 203.33208 0.28448)
		(end 203.33208 0.50292)
		(width 0.1651)
		(layer "F.Cu")
		(net "M_C_DQ<6>")
	)
	(segment
		(start 203.2 0.1524)
		(end 203.33208 0.28448)
		(width 0.1651)
		(layer "F.Cu")
		(net "M_C_DQ<6>")
	)
	(segment
		(start 203.200508 -0.821182)
		(end 203.2 -0.821182)
		(width 0.1651)
		(layer "F.Cu")
		(net "M_C_DQ<6>")
	)
	(segment
		(start 203.2 -0.821182)
		(end 203.2 0.1524)
		(width 0.1651)
		(layer "F.Cu")
		(net "M_C_DQ<6>")
	)
	(segment
		(start 203.2 0.939546)
		(end 203.199746 0.9398)
		(width 0.1651)
		(layer "F.Cu")
		(net "M_C_DQ<6>")
	)
	(via
		(at 203.199746 0.9398)
		(size 0.508)
		(drill 0.254)
		(layers "F.Cu" "B.Cu")
		(net "M_C_DQ<6>")
	)
	(via
		(at 202.349862 -4.357878)
		(size 0.508)
		(drill 0.254)
		(layers "F.Cu" "B.Cu")
		(net "M_C_DQ<6>")
	)
	(via
		(at 239.904778 -65.000886)
		(size 0.508)
		(drill 0.254)
		(layers "F.Cu" "B.Cu")
		(net "M_C_DQ<6>")
	)
	(segment
		(start 202.349862 -5.621782)
		(end 202.349862 -4.357878)
		(width 0.1651)
		(layer "B.Cu")
		(net "M_C_DQ<6>")
	)
	(segment
		(start 202.35037 -5.621782)
		(end 202.349862 -5.621782)
		(width 0.1651)
		(layer "B.Cu")
		(net "M_C_DQ<6>")
	)
	(segment
		(start 202.917552 -9.115298)
		(end 202.917552 -9.401048)
		(width 0.14224)
		(layer "In11.Cu")
		(net "M_C_DQ<6>")
	)
	(segment
		(start 202.7174 -21.161248)
		(end 202.917552 -21.3614)
		(width 0.14224)
		(layer "In11.Cu")
		(net "M_C_DQ<6>")
	)
	(segment
		(start 224.225104 -60.1091)
		(end 227.231194 -63.11519)
		(width 0.14224)
		(layer "In11.Cu")
		(net "M_C_DQ<6>")
	)
	(segment
		(start 233.877358 -63.11519)
		(end 233.912918 -63.11519)
		(width 0.0889)
		(layer "In11.Cu")
		(net "M_C_DQ<6>")
	)
	(segment
		(start 201.549 -31.7754)
		(end 201.9554 -31.7754)
		(width 0.14224)
		(layer "In11.Cu")
		(net "M_C_DQ<6>")
	)
	(segment
		(start 202.917552 -18.976848)
		(end 202.7174 -19.177)
		(width 0.14224)
		(layer "In11.Cu")
		(net "M_C_DQ<6>")
	)
	(segment
		(start 207.919574 -42.68851)
		(end 207.919574 -44.284646)
		(width 0.14224)
		(layer "In11.Cu")
		(net "M_C_DQ<6>")
	)
	(segment
		(start 202.917552 -21.771356)
		(end 202.714352 -21.974556)
		(width 0.14224)
		(layer "In11.Cu")
		(net "M_C_DQ<6>")
	)
	(segment
		(start 206.808832 -41.796716)
		(end 206.191612 -42.413936)
		(width 0.14224)
		(layer "In11.Cu")
		(net "M_C_DQ<6>")
	)
	(segment
		(start 202.7174 -19.177)
		(end 202.7174 -21.161248)
		(width 0.14224)
		(layer "In11.Cu")
		(net "M_C_DQ<6>")
	)
	(segment
		(start 239.028478 -65.09639)
		(end 239.082326 -65.09639)
		(width 0.0889)
		(layer "In11.Cu")
		(net "M_C_DQ<6>")
	)
	(segment
		(start 202.349862 -4.357878)
		(end 202.866752 -4.874768)
		(width 0.14224)
		(layer "In11.Cu")
		(net "M_C_DQ<6>")
	)
	(segment
		(start 206.191612 -42.632884)
		(end 206.411068 -42.85234)
		(width 0.14224)
		(layer "In11.Cu")
		(net "M_C_DQ<6>")
	)
	(segment
		(start 202.866752 -7.190994)
		(end 202.714352 -7.343394)
		(width 0.14224)
		(layer "In11.Cu")
		(net "M_C_DQ<6>")
	)
	(segment
		(start 202.842368 -0.768096)
		(end 202.842368 -1.111504)
		(width 0.14224)
		(layer "In11.Cu")
		(net "M_C_DQ<6>")
	)
	(segment
		(start 236.449108 -63.610236)
		(end 236.481874 -63.610236)
		(width 0.0889)
		(layer "In11.Cu")
		(net "M_C_DQ<6>")
	)
	(segment
		(start 202.1586 -28.4226)
		(end 202.3872 -28.194)
		(width 0.14224)
		(layer "In11.Cu")
		(net "M_C_DQ<6>")
	)
	(segment
		(start 202.815952 -13.668756)
		(end 202.815952 -16.890746)
		(width 0.14224)
		(layer "In11.Cu")
		(net "M_C_DQ<6>")
	)
	(segment
		(start 202.917552 -11.7602)
		(end 202.917552 -12.170156)
		(width 0.14224)
		(layer "In11.Cu")
		(net "M_C_DQ<6>")
	)
	(segment
		(start 202.714352 -16.992346)
		(end 202.714352 -18.462498)
		(width 0.14224)
		(layer "In11.Cu")
		(net "M_C_DQ<6>")
	)
	(segment
		(start 206.630016 -42.85234)
		(end 207.247236 -42.23512)
		(width 0.14224)
		(layer "In11.Cu")
		(net "M_C_DQ<6>")
	)
	(segment
		(start 202.1586 -31.5722)
		(end 202.1586 -28.4226)
		(width 0.14224)
		(layer "In11.Cu")
		(net "M_C_DQ<6>")
	)
	(segment
		(start 202.917552 -21.3614)
		(end 202.917552 -21.771356)
		(width 0.14224)
		(layer "In11.Cu")
		(net "M_C_DQ<6>")
	)
	(segment
		(start 202.886818 -2.203196)
		(end 202.886818 -2.554986)
		(width 0.14224)
		(layer "In11.Cu")
		(net "M_C_DQ<6>")
	)
	(segment
		(start 202.461368 -0.076454)
		(end 202.461368 -0.387096)
		(width 0.14224)
		(layer "In11.Cu")
		(net "M_C_DQ<6>")
	)
	(segment
		(start 239.082326 -65.09639)
		(end 239.904778 -65.000886)
		(width 0.0889)
		(layer "In11.Cu")
		(net "M_C_DQ<6>")
	)
	(segment
		(start 202.714352 -7.343394)
		(end 202.714352 -8.912098)
		(width 0.14224)
		(layer "In11.Cu")
		(net "M_C_DQ<6>")
	)
	(segment
		(start 202.3872 -28.194)
		(end 202.7682 -28.194)
		(width 0.14224)
		(layer "In11.Cu")
		(net "M_C_DQ<6>")
	)
	(segment
		(start 202.714352 -18.462498)
		(end 202.917552 -18.665698)
		(width 0.14224)
		(layer "In11.Cu")
		(net "M_C_DQ<6>")
	)
	(segment
		(start 202.82535 0.287528)
		(end 202.461368 -0.076454)
		(width 0.14224)
		(layer "In11.Cu")
		(net "M_C_DQ<6>")
	)
	(segment
		(start 202.9714 -37.740336)
		(end 206.808832 -41.577768)
		(width 0.14224)
		(layer "In11.Cu")
		(net "M_C_DQ<6>")
	)
	(segment
		(start 237.311438 -64.10579)
		(end 237.344204 -64.10579)
		(width 0.0889)
		(layer "In11.Cu")
		(net "M_C_DQ<6>")
	)
	(segment
		(start 202.714352 -8.912098)
		(end 202.917552 -9.115298)
		(width 0.14224)
		(layer "In11.Cu")
		(net "M_C_DQ<6>")
	)
	(segment
		(start 202.9714 -28.3972)
		(end 202.9714 -37.740336)
		(width 0.14224)
		(layer "In11.Cu")
		(net "M_C_DQ<6>")
	)
	(segment
		(start 202.917552 -9.401048)
		(end 202.7682 -9.5504)
		(width 0.14224)
		(layer "In11.Cu")
		(net "M_C_DQ<6>")
	)
	(segment
		(start 207.919574 -44.284646)
		(end 223.744028 -60.1091)
		(width 0.14224)
		(layer "In11.Cu")
		(net "M_C_DQ<6>")
	)
	(segment
		(start 206.808832 -41.577768)
		(end 206.808832 -41.796716)
		(width 0.14224)
		(layer "In11.Cu")
		(net "M_C_DQ<6>")
	)
	(segment
		(start 206.411068 -42.85234)
		(end 206.630016 -42.85234)
		(width 0.14224)
		(layer "In11.Cu")
		(net "M_C_DQ<6>")
	)
	(segment
		(start 202.82535 0.565404)
		(end 202.82535 0.287528)
		(width 0.14224)
		(layer "In11.Cu")
		(net "M_C_DQ<6>")
	)
	(segment
		(start 202.866752 -4.874768)
		(end 202.866752 -7.190994)
		(width 0.14224)
		(layer "In11.Cu")
		(net "M_C_DQ<6>")
	)
	(segment
		(start 202.11415 -3.327654)
		(end 202.11415 -4.122166)
		(width 0.14224)
		(layer "In11.Cu")
		(net "M_C_DQ<6>")
	)
	(segment
		(start 223.744028 -60.1091)
		(end 224.225104 -60.1091)
		(width 0.14224)
		(layer "In11.Cu")
		(net "M_C_DQ<6>")
	)
	(segment
		(start 202.815952 -16.890746)
		(end 202.714352 -16.992346)
		(width 0.14224)
		(layer "In11.Cu")
		(net "M_C_DQ<6>")
	)
	(segment
		(start 202.815952 -23.269956)
		(end 202.815952 -25.098248)
		(width 0.14224)
		(layer "In11.Cu")
		(net "M_C_DQ<6>")
	)
	(segment
		(start 207.466184 -42.23512)
		(end 207.919574 -42.68851)
		(width 0.14224)
		(layer "In11.Cu")
		(net "M_C_DQ<6>")
	)
	(segment
		(start 203.199746 0.9398)
		(end 202.82535 0.565404)
		(width 0.14224)
		(layer "In11.Cu")
		(net "M_C_DQ<6>")
	)
	(segment
		(start 202.815952 -25.098248)
		(end 201.3458 -26.5684)
		(width 0.14224)
		(layer "In11.Cu")
		(net "M_C_DQ<6>")
	)
	(segment
		(start 202.461368 -1.492504)
		(end 202.461368 -1.777746)
		(width 0.14224)
		(layer "In11.Cu")
		(net "M_C_DQ<6>")
	)
	(segment
		(start 202.7682 -28.194)
		(end 202.9714 -28.3972)
		(width 0.14224)
		(layer "In11.Cu")
		(net "M_C_DQ<6>")
	)
	(segment
		(start 201.3458 -31.5722)
		(end 201.549 -31.7754)
		(width 0.14224)
		(layer "In11.Cu")
		(net "M_C_DQ<6>")
	)
	(segment
		(start 202.714352 -12.373356)
		(end 202.714352 -13.567156)
		(width 0.14224)
		(layer "In11.Cu")
		(net "M_C_DQ<6>")
	)
	(segment
		(start 201.9554 -31.7754)
		(end 202.1586 -31.5722)
		(width 0.14224)
		(layer "In11.Cu")
		(net "M_C_DQ<6>")
	)
	(segment
		(start 206.191612 -42.413936)
		(end 206.191612 -42.632884)
		(width 0.14224)
		(layer "In11.Cu")
		(net "M_C_DQ<6>")
	)
	(segment
		(start 202.714352 -21.974556)
		(end 202.714352 -23.168356)
		(width 0.14224)
		(layer "In11.Cu")
		(net "M_C_DQ<6>")
	)
	(segment
		(start 202.7682 -9.5504)
		(end 202.7682 -11.610848)
		(width 0.14224)
		(layer "In11.Cu")
		(net "M_C_DQ<6>")
	)
	(segment
		(start 202.917552 -18.665698)
		(end 202.917552 -18.976848)
		(width 0.14224)
		(layer "In11.Cu")
		(net "M_C_DQ<6>")
	)
	(segment
		(start 202.7682 -11.610848)
		(end 202.917552 -11.7602)
		(width 0.14224)
		(layer "In11.Cu")
		(net "M_C_DQ<6>")
	)
	(segment
		(start 202.714352 -23.168356)
		(end 202.815952 -23.269956)
		(width 0.14224)
		(layer "In11.Cu")
		(net "M_C_DQ<6>")
	)
	(segment
		(start 202.461368 -1.777746)
		(end 202.886818 -2.203196)
		(width 0.14224)
		(layer "In11.Cu")
		(net "M_C_DQ<6>")
	)
	(segment
		(start 202.917552 -12.170156)
		(end 202.714352 -12.373356)
		(width 0.14224)
		(layer "In11.Cu")
		(net "M_C_DQ<6>")
	)
	(segment
		(start 207.247236 -42.23512)
		(end 207.466184 -42.23512)
		(width 0.14224)
		(layer "In11.Cu")
		(net "M_C_DQ<6>")
	)
	(segment
		(start 230.660956 -63.11519)
		(end 232.195878 -63.11519)
		(width 0.0889)
		(layer "In11.Cu")
		(net "M_C_DQ<6>")
	)
	(segment
		(start 202.714352 -13.567156)
		(end 202.815952 -13.668756)
		(width 0.14224)
		(layer "In11.Cu")
		(net "M_C_DQ<6>")
	)
	(segment
		(start 227.231194 -63.11519)
		(end 230.660956 -63.11519)
		(width 0.14224)
		(layer "In11.Cu")
		(net "M_C_DQ<6>")
	)
	(segment
		(start 202.461368 -0.387096)
		(end 202.842368 -0.768096)
		(width 0.14224)
		(layer "In11.Cu")
		(net "M_C_DQ<6>")
	)
	(segment
		(start 202.11415 -4.122166)
		(end 202.349862 -4.357878)
		(width 0.14224)
		(layer "In11.Cu")
		(net "M_C_DQ<6>")
	)
	(segment
		(start 202.842368 -1.111504)
		(end 202.461368 -1.492504)
		(width 0.14224)
		(layer "In11.Cu")
		(net "M_C_DQ<6>")
	)
	(segment
		(start 238.166148 -64.600836)
		(end 238.198914 -64.600836)
		(width 0.0889)
		(layer "In11.Cu")
		(net "M_C_DQ<6>")
	)
	(segment
		(start 235.594398 -63.11519)
		(end 235.627164 -63.11519)
		(width 0.0889)
		(layer "In11.Cu")
		(net "M_C_DQ<6>")
	)
	(segment
		(start 202.886818 -2.554986)
		(end 202.11415 -3.327654)
		(width 0.14224)
		(layer "In11.Cu")
		(net "M_C_DQ<6>")
	)
	(segment
		(start 201.3458 -26.5684)
		(end 201.3458 -31.5722)
		(width 0.14224)
		(layer "In11.Cu")
		(net "M_C_DQ<6>")
	)
	(arc
		(start 237.344204 -64.10579)
		(mid 237.535846 -64.162956)
		(end 237.675928 -64.305688)
		(width 0.0889)
		(layer "In11.Cu")
		(net "M_C_DQ<6>")
	)
	(arc
		(start 238.198914 -64.600836)
		(mid 238.392764 -64.657186)
		(end 238.534448 -64.800988)
		(width 0.0889)
		(layer "In11.Cu")
		(net "M_C_DQ<6>")
	)
	(arc
		(start 236.817408 -63.810388)
		(mid 237.026016 -64.02232)
		(end 237.311438 -64.10579)
		(width 0.0889)
		(layer "In11.Cu")
		(net "M_C_DQ<6>")
	)
	(arc
		(start 238.534448 -64.800988)
		(mid 238.743056 -65.01292)
		(end 239.028478 -65.09639)
		(width 0.0889)
		(layer "In11.Cu")
		(net "M_C_DQ<6>")
	)
	(arc
		(start 236.481874 -63.610236)
		(mid 236.675724 -63.666586)
		(end 236.817408 -63.810388)
		(width 0.0889)
		(layer "In11.Cu")
		(net "M_C_DQ<6>")
	)
	(arc
		(start 232.689908 -62.819788)
		(mid 233.036618 -62.619477)
		(end 233.383328 -62.819788)
		(width 0.0889)
		(layer "In11.Cu")
		(net "M_C_DQ<6>")
	)
	(arc
		(start 232.195878 -63.11519)
		(mid 232.481302 -63.031723)
		(end 232.689908 -62.819788)
		(width 0.0889)
		(layer "In11.Cu")
		(net "M_C_DQ<6>")
	)
	(arc
		(start 237.675928 -64.305688)
		(mid 237.882932 -64.516552)
		(end 238.166148 -64.600836)
		(width 0.0889)
		(layer "In11.Cu")
		(net "M_C_DQ<6>")
	)
	(arc
		(start 235.100368 -62.819788)
		(mid 235.308976 -63.03172)
		(end 235.594398 -63.11519)
		(width 0.0889)
		(layer "In11.Cu")
		(net "M_C_DQ<6>")
	)
	(arc
		(start 234.406948 -62.819788)
		(mid 234.753658 -62.619477)
		(end 235.100368 -62.819788)
		(width 0.0889)
		(layer "In11.Cu")
		(net "M_C_DQ<6>")
	)
	(arc
		(start 235.627164 -63.11519)
		(mid 235.818806 -63.172356)
		(end 235.958888 -63.315088)
		(width 0.0889)
		(layer "In11.Cu")
		(net "M_C_DQ<6>")
	)
	(arc
		(start 233.383328 -62.819788)
		(mid 233.591936 -63.03172)
		(end 233.877358 -63.11519)
		(width 0.0889)
		(layer "In11.Cu")
		(net "M_C_DQ<6>")
	)
	(arc
		(start 235.958888 -63.315088)
		(mid 236.165892 -63.525952)
		(end 236.449108 -63.610236)
		(width 0.0889)
		(layer "In11.Cu")
		(net "M_C_DQ<6>")
	)
	(arc
		(start 233.912918 -63.11519)
		(mid 234.198342 -63.031723)
		(end 234.406948 -62.819788)
		(width 0.0889)
		(layer "In11.Cu")
		(net "M_C_DQ<6>")
	)
	(segment
		(start 287.79216 -64.819784)
		(end 288.36366 -64.819784)
		(width 0.0889)
		(layer "F.Cu")
		(net "M_C_DQ<63>")
	)
	(segment
		(start 313.699906 3.778758)
		(end 313.699906 2.514854)
		(width 0.1651)
		(layer "F.Cu")
		(net "M_C_DQ<63>")
	)
	(segment
		(start 313.700414 3.778758)
		(end 313.699906 3.778758)
		(width 0.1651)
		(layer "F.Cu")
		(net "M_C_DQ<63>")
	)
	(via
		(at 287.79216 -64.819784)
		(size 0.508)
		(drill 0.254)
		(layers "F.Cu" "B.Cu")
		(net "M_C_DQ<63>")
	)
	(via
		(at 313.699906 2.514854)
		(size 0.508)
		(drill 0.254)
		(layers "F.Cu" "B.Cu")
		(net "M_C_DQ<63>")
	)
	(via
		(at 314.54979 -3.076956)
		(size 0.508)
		(drill 0.254)
		(layers "F.Cu" "B.Cu")
		(net "M_C_DQ<63>")
	)
	(segment
		(start 314.54979 -1.021842)
		(end 314.54979 -3.076956)
		(width 0.1651)
		(layer "B.Cu")
		(net "M_C_DQ<63>")
	)
	(segment
		(start 314.550298 -1.021842)
		(end 314.54979 -1.021842)
		(width 0.1651)
		(layer "B.Cu")
		(net "M_C_DQ<63>")
	)
	(segment
		(start 314.929774 -23.793196)
		(end 314.929774 -23.335996)
		(width 0.14224)
		(layer "In11.Cu")
		(net "M_C_DQ<63>")
	)
	(segment
		(start 287.79216 -64.819784)
		(end 288.13887 -64.029336)
		(width 0.0889)
		(layer "In11.Cu")
		(net "M_C_DQ<63>")
	)
	(segment
		(start 314.066174 -3.560572)
		(end 314.54979 -3.076956)
		(width 0.14224)
		(layer "In11.Cu")
		(net "M_C_DQ<63>")
	)
	(segment
		(start 315.056774 -8.795258)
		(end 315.056774 -7.429246)
		(width 0.14224)
		(layer "In11.Cu")
		(net "M_C_DQ<63>")
	)
	(segment
		(start 315.056774 -7.429246)
		(end 314.917074 -7.289546)
		(width 0.14224)
		(layer "In11.Cu")
		(net "M_C_DQ<63>")
	)
	(segment
		(start 315.114178 -11.5316)
		(end 315.114178 -9.582404)
		(width 0.14224)
		(layer "In11.Cu")
		(net "M_C_DQ<63>")
	)
	(segment
		(start 314.904374 -19.017996)
		(end 314.904374 -18.574258)
		(width 0.14224)
		(layer "In11.Cu")
		(net "M_C_DQ<63>")
	)
	(segment
		(start 315.1124 -23.975822)
		(end 314.929774 -23.793196)
		(width 0.14224)
		(layer "In11.Cu")
		(net "M_C_DQ<63>")
	)
	(segment
		(start 314.904374 -12.176252)
		(end 314.904374 -11.741404)
		(width 0.14224)
		(layer "In11.Cu")
		(net "M_C_DQ<63>")
	)
	(segment
		(start 314.917074 -13.681456)
		(end 315.082174 -13.516356)
		(width 0.14224)
		(layer "In11.Cu")
		(net "M_C_DQ<63>")
	)
	(segment
		(start 315.082174 -23.183596)
		(end 315.082174 -21.999956)
		(width 0.14224)
		(layer "In11.Cu")
		(net "M_C_DQ<63>")
	)
	(segment
		(start 294.868346 -49.6824)
		(end 300.9646 -43.586146)
		(width 0.14224)
		(layer "In11.Cu")
		(net "M_C_DQ<63>")
	)
	(segment
		(start 315.082174 -12.354052)
		(end 314.904374 -12.176252)
		(width 0.14224)
		(layer "In11.Cu")
		(net "M_C_DQ<63>")
	)
	(segment
		(start 315.114178 -9.582404)
		(end 314.904374 -9.3726)
		(width 0.14224)
		(layer "In11.Cu")
		(net "M_C_DQ<63>")
	)
	(segment
		(start 314.902596 0.581152)
		(end 315.058044 0.7366)
		(width 0.14224)
		(layer "In11.Cu")
		(net "M_C_DQ<63>")
	)
	(segment
		(start 288.30397 -58.581036)
		(end 288.299144 -58.5724)
		(width 0.0889)
		(layer "In11.Cu")
		(net "M_C_DQ<63>")
	)
	(segment
		(start 315.1124 -30.403546)
		(end 315.1124 -23.975822)
		(width 0.14224)
		(layer "In11.Cu")
		(net "M_C_DQ<63>")
	)
	(segment
		(start 314.600844 1.5494)
		(end 314.346844 1.5494)
		(width 0.14224)
		(layer "In11.Cu")
		(net "M_C_DQ<63>")
	)
	(segment
		(start 288.31032 -57.601104)
		(end 288.30397 -57.590436)
		(width 0.0889)
		(layer "In11.Cu")
		(net "M_C_DQ<63>")
	)
	(segment
		(start 314.904374 -18.574258)
		(end 315.056774 -18.421858)
		(width 0.14224)
		(layer "In11.Cu")
		(net "M_C_DQ<63>")
	)
	(segment
		(start 314.016644 2.198116)
		(end 313.699906 2.514854)
		(width 0.14224)
		(layer "In11.Cu")
		(net "M_C_DQ<63>")
	)
	(segment
		(start 288.31032 -56.610504)
		(end 288.30397 -56.599836)
		(width 0.0889)
		(layer "In11.Cu")
		(net "M_C_DQ<63>")
	)
	(segment
		(start 288.30397 -54.618636)
		(end 288.299144 -54.61)
		(width 0.0889)
		(layer "In11.Cu")
		(net "M_C_DQ<63>")
	)
	(segment
		(start 290.1188 -51.5112)
		(end 291.9476 -49.6824)
		(width 0.14224)
		(layer "In11.Cu")
		(net "M_C_DQ<63>")
	)
	(segment
		(start 314.904374 -21.822156)
		(end 314.904374 -21.3614)
		(width 0.14224)
		(layer "In11.Cu")
		(net "M_C_DQ<63>")
	)
	(segment
		(start 315.082174 -21.999956)
		(end 314.904374 -21.822156)
		(width 0.14224)
		(layer "In11.Cu")
		(net "M_C_DQ<63>")
	)
	(segment
		(start 288.30397 -53.227732)
		(end 288.303462 -53.227478)
		(width 0.0889)
		(layer "In11.Cu")
		(net "M_C_DQ<63>")
	)
	(segment
		(start 288.30397 -59.171586)
		(end 288.31032 -59.160918)
		(width 0.0889)
		(layer "In11.Cu")
		(net "M_C_DQ<63>")
	)
	(segment
		(start 314.016644 1.8796)
		(end 314.016644 2.198116)
		(width 0.14224)
		(layer "In11.Cu")
		(net "M_C_DQ<63>")
	)
	(segment
		(start 314.066174 -3.965956)
		(end 314.066174 -3.560572)
		(width 0.14224)
		(layer "In11.Cu")
		(net "M_C_DQ<63>")
	)
	(segment
		(start 289.592004 -51.5112)
		(end 290.1188 -51.5112)
		(width 0.0889)
		(layer "In11.Cu")
		(net "M_C_DQ<63>")
	)
	(segment
		(start 291.9476 -49.6824)
		(end 294.868346 -49.6824)
		(width 0.14224)
		(layer "In11.Cu")
		(net "M_C_DQ<63>")
	)
	(segment
		(start 315.056774 -18.421858)
		(end 315.056774 -17.030446)
		(width 0.14224)
		(layer "In11.Cu")
		(net "M_C_DQ<63>")
	)
	(segment
		(start 288.626804 -52.4764)
		(end 289.592004 -51.5112)
		(width 0.0889)
		(layer "In11.Cu")
		(net "M_C_DQ<63>")
	)
	(segment
		(start 288.30397 -56.599836)
		(end 288.299144 -56.5912)
		(width 0.0889)
		(layer "In11.Cu")
		(net "M_C_DQ<63>")
	)
	(segment
		(start 315.037978 -19.1516)
		(end 314.904374 -19.017996)
		(width 0.14224)
		(layer "In11.Cu")
		(net "M_C_DQ<63>")
	)
	(segment
		(start 315.058044 0.7366)
		(end 315.058044 1.0922)
		(width 0.14224)
		(layer "In11.Cu")
		(net "M_C_DQ<63>")
	)
	(segment
		(start 314.917074 -16.890746)
		(end 314.917074 -13.681456)
		(width 0.14224)
		(layer "In11.Cu")
		(net "M_C_DQ<63>")
	)
	(segment
		(start 288.30397 -57.590436)
		(end 288.299144 -57.5818)
		(width 0.0889)
		(layer "In11.Cu")
		(net "M_C_DQ<63>")
	)
	(segment
		(start 314.904374 -8.947658)
		(end 315.056774 -8.795258)
		(width 0.14224)
		(layer "In11.Cu")
		(net "M_C_DQ<63>")
	)
	(segment
		(start 288.626804 -52.656994)
		(end 288.626804 -52.4764)
		(width 0.0889)
		(layer "In11.Cu")
		(net "M_C_DQ<63>")
	)
	(segment
		(start 314.346844 1.5494)
		(end 314.016644 1.8796)
		(width 0.14224)
		(layer "In11.Cu")
		(net "M_C_DQ<63>")
	)
	(segment
		(start 314.904374 -9.3726)
		(end 314.904374 -8.947658)
		(width 0.14224)
		(layer "In11.Cu")
		(net "M_C_DQ<63>")
	)
	(segment
		(start 314.929774 -23.335996)
		(end 315.082174 -23.183596)
		(width 0.14224)
		(layer "In11.Cu")
		(net "M_C_DQ<63>")
	)
	(segment
		(start 314.917074 -7.289546)
		(end 314.917074 -4.816856)
		(width 0.14224)
		(layer "In11.Cu")
		(net "M_C_DQ<63>")
	)
	(segment
		(start 315.058044 1.0922)
		(end 314.600844 1.5494)
		(width 0.14224)
		(layer "In11.Cu")
		(net "M_C_DQ<63>")
	)
	(segment
		(start 288.30397 -60.562236)
		(end 288.299144 -60.5536)
		(width 0.0889)
		(layer "In11.Cu")
		(net "M_C_DQ<63>")
	)
	(segment
		(start 314.54979 -3.076956)
		(end 314.902596 -2.72415)
		(width 0.14224)
		(layer "In11.Cu")
		(net "M_C_DQ<63>")
	)
	(segment
		(start 315.037978 -21.227796)
		(end 315.037978 -19.1516)
		(width 0.14224)
		(layer "In11.Cu")
		(net "M_C_DQ<63>")
	)
	(segment
		(start 288.30397 -55.609236)
		(end 288.299144 -55.6006)
		(width 0.0889)
		(layer "In11.Cu")
		(net "M_C_DQ<63>")
	)
	(segment
		(start 288.31032 -60.572904)
		(end 288.30397 -60.562236)
		(width 0.0889)
		(layer "In11.Cu")
		(net "M_C_DQ<63>")
	)
	(segment
		(start 314.902596 -2.72415)
		(end 314.902596 0.581152)
		(width 0.14224)
		(layer "In11.Cu")
		(net "M_C_DQ<63>")
	)
	(segment
		(start 314.904374 -11.741404)
		(end 315.114178 -11.5316)
		(width 0.14224)
		(layer "In11.Cu")
		(net "M_C_DQ<63>")
	)
	(segment
		(start 288.31032 -54.629304)
		(end 288.30397 -54.618636)
		(width 0.0889)
		(layer "In11.Cu")
		(net "M_C_DQ<63>")
	)
	(segment
		(start 288.31032 -55.619904)
		(end 288.30397 -55.609236)
		(width 0.0889)
		(layer "In11.Cu")
		(net "M_C_DQ<63>")
	)
	(segment
		(start 300.9646 -43.586146)
		(end 301.9298 -43.586146)
		(width 0.14224)
		(layer "In11.Cu")
		(net "M_C_DQ<63>")
	)
	(segment
		(start 315.082174 -13.516356)
		(end 315.082174 -12.354052)
		(width 0.14224)
		(layer "In11.Cu")
		(net "M_C_DQ<63>")
	)
	(segment
		(start 314.917074 -4.816856)
		(end 314.066174 -3.965956)
		(width 0.14224)
		(layer "In11.Cu")
		(net "M_C_DQ<63>")
	)
	(segment
		(start 301.9298 -43.586146)
		(end 315.1124 -30.403546)
		(width 0.14224)
		(layer "In11.Cu")
		(net "M_C_DQ<63>")
	)
	(segment
		(start 315.056774 -17.030446)
		(end 314.917074 -16.890746)
		(width 0.14224)
		(layer "In11.Cu")
		(net "M_C_DQ<63>")
	)
	(segment
		(start 314.904374 -21.3614)
		(end 315.037978 -21.227796)
		(width 0.14224)
		(layer "In11.Cu")
		(net "M_C_DQ<63>")
	)
	(arc
		(start 288.30397 -63.13424)
		(mid 288.383101 -62.838838)
		(end 288.30397 -62.543436)
		(width 0.0889)
		(layer "In11.Cu")
		(net "M_C_DQ<63>")
	)
	(arc
		(start 288.30397 -62.14364)
		(mid 288.383101 -61.848238)
		(end 288.30397 -61.552836)
		(width 0.0889)
		(layer "In11.Cu")
		(net "M_C_DQ<63>")
	)
	(arc
		(start 288.299144 -54.61)
		(mid 288.250389 -54.413648)
		(end 288.30397 -54.218586)
		(width 0.0889)
		(layer "In11.Cu")
		(net "M_C_DQ<63>")
	)
	(arc
		(start 288.299144 -55.6006)
		(mid 288.250389 -55.404248)
		(end 288.30397 -55.209186)
		(width 0.0889)
		(layer "In11.Cu")
		(net "M_C_DQ<63>")
	)
	(arc
		(start 288.186368 -63.760858)
		(mid 288.191699 -63.437512)
		(end 288.30397 -63.13424)
		(width 0.0889)
		(layer "In11.Cu")
		(net "M_C_DQ<63>")
	)
	(arc
		(start 288.31032 -59.160918)
		(mid 288.383118 -58.870155)
		(end 288.30397 -58.581036)
		(width 0.0889)
		(layer "In11.Cu")
		(net "M_C_DQ<63>")
	)
	(arc
		(start 288.30397 -55.209186)
		(mid 288.383192 -54.920068)
		(end 288.31032 -54.629304)
		(width 0.0889)
		(layer "In11.Cu")
		(net "M_C_DQ<63>")
	)
	(arc
		(start 288.30397 -61.552836)
		(mid 288.250437 -61.352828)
		(end 288.30397 -61.152786)
		(width 0.0889)
		(layer "In11.Cu")
		(net "M_C_DQ<63>")
	)
	(arc
		(start 288.299144 -56.5912)
		(mid 288.250389 -56.394848)
		(end 288.30397 -56.199786)
		(width 0.0889)
		(layer "In11.Cu")
		(net "M_C_DQ<63>")
	)
	(arc
		(start 288.30397 -56.199786)
		(mid 288.383192 -55.910668)
		(end 288.31032 -55.619904)
		(width 0.0889)
		(layer "In11.Cu")
		(net "M_C_DQ<63>")
	)
	(arc
		(start 288.30397 -60.162186)
		(mid 288.383101 -59.866784)
		(end 288.30397 -59.571382)
		(width 0.0889)
		(layer "In11.Cu")
		(net "M_C_DQ<63>")
	)
	(arc
		(start 288.30397 -61.152786)
		(mid 288.383192 -60.863668)
		(end 288.31032 -60.572904)
		(width 0.0889)
		(layer "In11.Cu")
		(net "M_C_DQ<63>")
	)
	(arc
		(start 288.299144 -58.5724)
		(mid 288.250389 -58.376048)
		(end 288.30397 -58.180986)
		(width 0.0889)
		(layer "In11.Cu")
		(net "M_C_DQ<63>")
	)
	(arc
		(start 288.30397 -54.218586)
		(mid 288.383101 -53.923184)
		(end 288.30397 -53.627782)
		(width 0.0889)
		(layer "In11.Cu")
		(net "M_C_DQ<63>")
	)
	(arc
		(start 288.30397 -57.190386)
		(mid 288.383192 -56.901268)
		(end 288.31032 -56.610504)
		(width 0.0889)
		(layer "In11.Cu")
		(net "M_C_DQ<63>")
	)
	(arc
		(start 288.299144 -57.5818)
		(mid 288.250389 -57.385448)
		(end 288.30397 -57.190386)
		(width 0.0889)
		(layer "In11.Cu")
		(net "M_C_DQ<63>")
	)
	(arc
		(start 288.303462 -53.227478)
		(mid 288.348257 -53.164905)
		(end 288.4043 -53.112162)
		(width 0.0889)
		(layer "In11.Cu")
		(net "M_C_DQ<63>")
	)
	(arc
		(start 288.30397 -62.543436)
		(mid 288.250471 -62.343538)
		(end 288.30397 -62.14364)
		(width 0.0889)
		(layer "In11.Cu")
		(net "M_C_DQ<63>")
	)
	(arc
		(start 288.4043 -53.112162)
		(mid 288.568766 -52.910585)
		(end 288.626804 -52.656994)
		(width 0.0889)
		(layer "In11.Cu")
		(net "M_C_DQ<63>")
	)
	(arc
		(start 288.13887 -64.029336)
		(mid 288.18623 -63.899267)
		(end 288.186368 -63.760858)
		(width 0.0889)
		(layer "In11.Cu")
		(net "M_C_DQ<63>")
	)
	(arc
		(start 288.30397 -59.571382)
		(mid 288.250471 -59.371484)
		(end 288.30397 -59.171586)
		(width 0.0889)
		(layer "In11.Cu")
		(net "M_C_DQ<63>")
	)
	(arc
		(start 288.299144 -60.5536)
		(mid 288.250389 -60.357248)
		(end 288.30397 -60.162186)
		(width 0.0889)
		(layer "In11.Cu")
		(net "M_C_DQ<63>")
	)
	(arc
		(start 288.30397 -58.180986)
		(mid 288.383192 -57.891868)
		(end 288.31032 -57.601104)
		(width 0.0889)
		(layer "In11.Cu")
		(net "M_C_DQ<63>")
	)
	(arc
		(start 288.30397 -53.627782)
		(mid 288.250437 -53.427774)
		(end 288.30397 -53.227732)
		(width 0.0889)
		(layer "In11.Cu")
		(net "M_C_DQ<63>")
	)
	(segment
		(start 314.550044 -0.820928)
		(end 314.550044 0.1524)
		(width 0.1651)
		(layer "F.Cu")
		(net "M_C_DQ<62>")
	)
	(segment
		(start 314.550044 0.635)
		(end 314.550044 0.939546)
		(width 0.1651)
		(layer "F.Cu")
		(net "M_C_DQ<62>")
	)
	(segment
		(start 314.550298 -0.821182)
		(end 314.550044 -0.820928)
		(width 0.1651)
		(layer "F.Cu")
		(net "M_C_DQ<62>")
	)
	(segment
		(start 314.550044 0.1524)
		(end 314.682124 0.28448)
		(width 0.1651)
		(layer "F.Cu")
		(net "M_C_DQ<62>")
	)
	(segment
		(start 314.550044 0.939546)
		(end 314.54979 0.9398)
		(width 0.1651)
		(layer "F.Cu")
		(net "M_C_DQ<62>")
	)
	(segment
		(start 287.79216 -62.838584)
		(end 288.36366 -62.838584)
		(width 0.0889)
		(layer "F.Cu")
		(net "M_C_DQ<62>")
	)
	(segment
		(start 314.682124 0.50292)
		(end 314.550044 0.635)
		(width 0.1651)
		(layer "F.Cu")
		(net "M_C_DQ<62>")
	)
	(segment
		(start 314.682124 0.28448)
		(end 314.682124 0.50292)
		(width 0.1651)
		(layer "F.Cu")
		(net "M_C_DQ<62>")
	)
	(via
		(at 287.79216 -62.838584)
		(size 0.508)
		(drill 0.254)
		(layers "F.Cu" "B.Cu")
		(net "M_C_DQ<62>")
	)
	(via
		(at 313.699906 -4.357878)
		(size 0.508)
		(drill 0.254)
		(layers "F.Cu" "B.Cu")
		(net "M_C_DQ<62>")
	)
	(via
		(at 314.54979 0.9398)
		(size 0.508)
		(drill 0.254)
		(layers "F.Cu" "B.Cu")
		(net "M_C_DQ<62>")
	)
	(segment
		(start 313.700414 -5.621782)
		(end 313.699906 -5.621782)
		(width 0.1651)
		(layer "B.Cu")
		(net "M_C_DQ<62>")
	)
	(segment
		(start 313.699906 -5.621782)
		(end 313.699906 -4.357878)
		(width 0.1651)
		(layer "B.Cu")
		(net "M_C_DQ<62>")
	)
	(segment
		(start 314.6044 -26.867358)
		(end 314.46216 -26.725118)
		(width 0.14224)
		(layer "In11.Cu")
		(net "M_C_DQ<62>")
	)
	(segment
		(start 314.267596 -11.7856)
		(end 314.071 -11.589004)
		(width 0.14224)
		(layer "In11.Cu")
		(net "M_C_DQ<62>")
	)
	(segment
		(start 313.464194 -3.327654)
		(end 314.236862 -2.554986)
		(width 0.14224)
		(layer "In11.Cu")
		(net "M_C_DQ<62>")
	)
	(segment
		(start 314.267596 -18.63725)
		(end 314.064396 -18.43405)
		(width 0.14224)
		(layer "In11.Cu")
		(net "M_C_DQ<62>")
	)
	(segment
		(start 314.165996 -23.269956)
		(end 314.064396 -23.168356)
		(width 0.14224)
		(layer "In11.Cu")
		(net "M_C_DQ<62>")
	)
	(segment
		(start 302.066452 -42.662348)
		(end 313.835796 -30.893004)
		(width 0.14224)
		(layer "In11.Cu")
		(net "M_C_DQ<62>")
	)
	(segment
		(start 301.025052 -42.662348)
		(end 302.066452 -42.662348)
		(width 0.14224)
		(layer "In11.Cu")
		(net "M_C_DQ<62>")
	)
	(segment
		(start 314.192412 -1.111504)
		(end 314.192412 -0.768096)
		(width 0.14224)
		(layer "In11.Cu")
		(net "M_C_DQ<62>")
	)
	(segment
		(start 314.267596 -8.991854)
		(end 314.064396 -8.788654)
		(width 0.14224)
		(layer "In11.Cu")
		(net "M_C_DQ<62>")
	)
	(segment
		(start 314.071 -9.5504)
		(end 314.267596 -9.353804)
		(width 0.14224)
		(layer "In11.Cu")
		(net "M_C_DQ<62>")
	)
	(segment
		(start 314.064396 -7.391146)
		(end 314.216796 -7.238746)
		(width 0.14224)
		(layer "In11.Cu")
		(net "M_C_DQ<62>")
	)
	(segment
		(start 314.236862 -2.554986)
		(end 314.236862 -2.203196)
		(width 0.14224)
		(layer "In11.Cu")
		(net "M_C_DQ<62>")
	)
	(segment
		(start 313.835796 -29.183838)
		(end 313.835796 -28.818078)
		(width 0.14224)
		(layer "In11.Cu")
		(net "M_C_DQ<62>")
	)
	(segment
		(start 287.79216 -62.838584)
		(end 288.085276 -62.669674)
		(width 0.0889)
		(layer "In11.Cu")
		(net "M_C_DQ<62>")
	)
	(segment
		(start 313.811412 -1.492504)
		(end 314.192412 -1.111504)
		(width 0.14224)
		(layer "In11.Cu")
		(net "M_C_DQ<62>")
	)
	(segment
		(start 314.071 -11.589004)
		(end 314.071 -9.5504)
		(width 0.14224)
		(layer "In11.Cu")
		(net "M_C_DQ<62>")
	)
	(segment
		(start 288.435288 -52.656994)
		(end 288.435288 -52.396898)
		(width 0.0889)
		(layer "In11.Cu")
		(net "M_C_DQ<62>")
	)
	(segment
		(start 289.917886 -50.9143)
		(end 289.9283 -50.9143)
		(width 0.0889)
		(layer "In11.Cu")
		(net "M_C_DQ<62>")
	)
	(segment
		(start 314.46216 -28.675838)
		(end 314.6044 -28.533598)
		(width 0.14224)
		(layer "In11.Cu")
		(net "M_C_DQ<62>")
	)
	(segment
		(start 313.978036 -28.025598)
		(end 313.835796 -27.883358)
		(width 0.14224)
		(layer "In11.Cu")
		(net "M_C_DQ<62>")
	)
	(segment
		(start 313.978036 -29.976318)
		(end 314.46216 -29.976318)
		(width 0.14224)
		(layer "In11.Cu")
		(net "M_C_DQ<62>")
	)
	(segment
		(start 314.064396 -12.373356)
		(end 314.267596 -12.170156)
		(width 0.14224)
		(layer "In11.Cu")
		(net "M_C_DQ<62>")
	)
	(segment
		(start 314.6044 -28.167838)
		(end 314.46216 -28.025598)
		(width 0.14224)
		(layer "In11.Cu")
		(net "M_C_DQ<62>")
	)
	(segment
		(start 288.13887 -54.713886)
		(end 288.13252 -54.703218)
		(width 0.0889)
		(layer "In11.Cu")
		(net "M_C_DQ<62>")
	)
	(segment
		(start 314.6044 -29.468318)
		(end 314.46216 -29.326078)
		(width 0.14224)
		(layer "In11.Cu")
		(net "M_C_DQ<62>")
	)
	(segment
		(start 288.143696 -60.666122)
		(end 288.13887 -60.657486)
		(width 0.0889)
		(layer "In11.Cu")
		(net "M_C_DQ<62>")
	)
	(segment
		(start 314.175394 0.565404)
		(end 314.54979 0.9398)
		(width 0.14224)
		(layer "In11.Cu")
		(net "M_C_DQ<62>")
	)
	(segment
		(start 314.267596 -21.3614)
		(end 314.1218 -21.215604)
		(width 0.14224)
		(layer "In11.Cu")
		(net "M_C_DQ<62>")
	)
	(segment
		(start 313.835796 -30.893004)
		(end 313.835796 -30.118558)
		(width 0.14224)
		(layer "In11.Cu")
		(net "M_C_DQ<62>")
	)
	(segment
		(start 288.143696 -57.694322)
		(end 288.13887 -57.685686)
		(width 0.0889)
		(layer "In11.Cu")
		(net "M_C_DQ<62>")
	)
	(segment
		(start 314.064396 -8.788654)
		(end 314.064396 -7.391146)
		(width 0.14224)
		(layer "In11.Cu")
		(net "M_C_DQ<62>")
	)
	(segment
		(start 314.46216 -28.025598)
		(end 313.978036 -28.025598)
		(width 0.14224)
		(layer "In11.Cu")
		(net "M_C_DQ<62>")
	)
	(segment
		(start 291.7698 -49.0728)
		(end 294.6146 -49.0728)
		(width 0.14224)
		(layer "In11.Cu")
		(net "M_C_DQ<62>")
	)
	(segment
		(start 314.216796 -4.874768)
		(end 313.699906 -4.357878)
		(width 0.14224)
		(layer "In11.Cu")
		(net "M_C_DQ<62>")
	)
	(segment
		(start 313.978036 -29.326078)
		(end 313.835796 -29.183838)
		(width 0.14224)
		(layer "In11.Cu")
		(net "M_C_DQ<62>")
	)
	(segment
		(start 288.13887 -57.685686)
		(end 288.13252 -57.675018)
		(width 0.0889)
		(layer "In11.Cu")
		(net "M_C_DQ<62>")
	)
	(segment
		(start 288.13887 -56.695086)
		(end 288.13252 -56.684418)
		(width 0.0889)
		(layer "In11.Cu")
		(net "M_C_DQ<62>")
	)
	(segment
		(start 288.143696 -56.703722)
		(end 288.13887 -56.695086)
		(width 0.0889)
		(layer "In11.Cu")
		(net "M_C_DQ<62>")
	)
	(segment
		(start 313.835796 -26.582878)
		(end 313.835796 -25.940258)
		(width 0.14224)
		(layer "In11.Cu")
		(net "M_C_DQ<62>")
	)
	(segment
		(start 288.13887 -60.657486)
		(end 288.13252 -60.646818)
		(width 0.0889)
		(layer "In11.Cu")
		(net "M_C_DQ<62>")
	)
	(segment
		(start 313.978036 -27.375358)
		(end 314.46216 -27.375358)
		(width 0.14224)
		(layer "In11.Cu")
		(net "M_C_DQ<62>")
	)
	(segment
		(start 314.165996 -13.668756)
		(end 314.064396 -13.567156)
		(width 0.14224)
		(layer "In11.Cu")
		(net "M_C_DQ<62>")
	)
	(segment
		(start 294.6146 -49.0728)
		(end 301.025052 -42.662348)
		(width 0.14224)
		(layer "In11.Cu")
		(net "M_C_DQ<62>")
	)
	(segment
		(start 314.064396 -23.168356)
		(end 314.064396 -21.974556)
		(width 0.14224)
		(layer "In11.Cu")
		(net "M_C_DQ<62>")
	)
	(segment
		(start 313.811412 -0.076454)
		(end 314.175394 0.287528)
		(width 0.14224)
		(layer "In11.Cu")
		(net "M_C_DQ<62>")
	)
	(segment
		(start 314.064396 -21.974556)
		(end 314.267596 -21.771356)
		(width 0.14224)
		(layer "In11.Cu")
		(net "M_C_DQ<62>")
	)
	(segment
		(start 313.978036 -28.675838)
		(end 314.46216 -28.675838)
		(width 0.14224)
		(layer "In11.Cu")
		(net "M_C_DQ<62>")
	)
	(segment
		(start 314.46216 -27.375358)
		(end 314.6044 -27.233118)
		(width 0.14224)
		(layer "In11.Cu")
		(net "M_C_DQ<62>")
	)
	(segment
		(start 288.435288 -52.396898)
		(end 289.917886 -50.9143)
		(width 0.0889)
		(layer "In11.Cu")
		(net "M_C_DQ<62>")
	)
	(segment
		(start 314.6044 -29.834078)
		(end 314.6044 -29.468318)
		(width 0.14224)
		(layer "In11.Cu")
		(net "M_C_DQ<62>")
	)
	(segment
		(start 314.267596 -19.031204)
		(end 314.267596 -18.63725)
		(width 0.14224)
		(layer "In11.Cu")
		(net "M_C_DQ<62>")
	)
	(segment
		(start 314.064396 -18.43405)
		(end 314.064396 -17.01165)
		(width 0.14224)
		(layer "In11.Cu")
		(net "M_C_DQ<62>")
	)
	(segment
		(start 314.6044 -27.233118)
		(end 314.6044 -26.867358)
		(width 0.14224)
		(layer "In11.Cu")
		(net "M_C_DQ<62>")
	)
	(segment
		(start 288.143696 -59.675522)
		(end 288.13887 -59.666886)
		(width 0.0889)
		(layer "In11.Cu")
		(net "M_C_DQ<62>")
	)
	(segment
		(start 314.165996 -16.91005)
		(end 314.165996 -13.668756)
		(width 0.14224)
		(layer "In11.Cu")
		(net "M_C_DQ<62>")
	)
	(segment
		(start 313.978036 -26.725118)
		(end 313.835796 -26.582878)
		(width 0.14224)
		(layer "In11.Cu")
		(net "M_C_DQ<62>")
	)
	(segment
		(start 288.13252 -59.087004)
		(end 288.13887 -59.076336)
		(width 0.0889)
		(layer "In11.Cu")
		(net "M_C_DQ<62>")
	)
	(segment
		(start 313.464194 -4.122166)
		(end 313.464194 -3.327654)
		(width 0.14224)
		(layer "In11.Cu")
		(net "M_C_DQ<62>")
	)
	(segment
		(start 314.267596 -9.353804)
		(end 314.267596 -8.991854)
		(width 0.14224)
		(layer "In11.Cu")
		(net "M_C_DQ<62>")
	)
	(segment
		(start 289.9283 -50.9143)
		(end 291.7698 -49.0728)
		(width 0.14224)
		(layer "In11.Cu")
		(net "M_C_DQ<62>")
	)
	(segment
		(start 314.267596 -12.170156)
		(end 314.267596 -11.7856)
		(width 0.14224)
		(layer "In11.Cu")
		(net "M_C_DQ<62>")
	)
	(segment
		(start 288.143696 -54.722522)
		(end 288.13887 -54.713886)
		(width 0.0889)
		(layer "In11.Cu")
		(net "M_C_DQ<62>")
	)
	(segment
		(start 314.267596 -21.771356)
		(end 314.267596 -21.3614)
		(width 0.14224)
		(layer "In11.Cu")
		(net "M_C_DQ<62>")
	)
	(segment
		(start 314.6044 -28.533598)
		(end 314.6044 -28.167838)
		(width 0.14224)
		(layer "In11.Cu")
		(net "M_C_DQ<62>")
	)
	(segment
		(start 288.143696 -55.713122)
		(end 288.13887 -55.704486)
		(width 0.0889)
		(layer "In11.Cu")
		(net "M_C_DQ<62>")
	)
	(segment
		(start 314.236862 -2.203196)
		(end 313.811412 -1.777746)
		(width 0.14224)
		(layer "In11.Cu")
		(net "M_C_DQ<62>")
	)
	(segment
		(start 314.064396 -17.01165)
		(end 314.165996 -16.91005)
		(width 0.14224)
		(layer "In11.Cu")
		(net "M_C_DQ<62>")
	)
	(segment
		(start 313.811412 -0.387096)
		(end 313.811412 -0.076454)
		(width 0.14224)
		(layer "In11.Cu")
		(net "M_C_DQ<62>")
	)
	(segment
		(start 288.085276 -62.669674)
		(end 288.109152 -62.58052)
		(width 0.0889)
		(layer "In11.Cu")
		(net "M_C_DQ<62>")
	)
	(segment
		(start 313.811412 -1.777746)
		(end 313.811412 -1.492504)
		(width 0.14224)
		(layer "In11.Cu")
		(net "M_C_DQ<62>")
	)
	(segment
		(start 314.165996 -25.610058)
		(end 314.165996 -23.269956)
		(width 0.14224)
		(layer "In11.Cu")
		(net "M_C_DQ<62>")
	)
	(segment
		(start 288.13887 -55.704486)
		(end 288.13252 -55.693818)
		(width 0.0889)
		(layer "In11.Cu")
		(net "M_C_DQ<62>")
	)
	(segment
		(start 313.835796 -27.883358)
		(end 313.835796 -27.517598)
		(width 0.14224)
		(layer "In11.Cu")
		(net "M_C_DQ<62>")
	)
	(segment
		(start 314.46216 -29.976318)
		(end 314.6044 -29.834078)
		(width 0.14224)
		(layer "In11.Cu")
		(net "M_C_DQ<62>")
	)
	(segment
		(start 314.064396 -13.567156)
		(end 314.064396 -12.373356)
		(width 0.14224)
		(layer "In11.Cu")
		(net "M_C_DQ<62>")
	)
	(segment
		(start 313.835796 -28.818078)
		(end 313.978036 -28.675838)
		(width 0.14224)
		(layer "In11.Cu")
		(net "M_C_DQ<62>")
	)
	(segment
		(start 314.192412 -0.768096)
		(end 313.811412 -0.387096)
		(width 0.14224)
		(layer "In11.Cu")
		(net "M_C_DQ<62>")
	)
	(segment
		(start 314.46216 -26.725118)
		(end 313.978036 -26.725118)
		(width 0.14224)
		(layer "In11.Cu")
		(net "M_C_DQ<62>")
	)
	(segment
		(start 314.216796 -7.238746)
		(end 314.216796 -4.874768)
		(width 0.14224)
		(layer "In11.Cu")
		(net "M_C_DQ<62>")
	)
	(segment
		(start 313.699906 -4.357878)
		(end 313.464194 -4.122166)
		(width 0.14224)
		(layer "In11.Cu")
		(net "M_C_DQ<62>")
	)
	(segment
		(start 314.46216 -29.326078)
		(end 313.978036 -29.326078)
		(width 0.14224)
		(layer "In11.Cu")
		(net "M_C_DQ<62>")
	)
	(segment
		(start 313.835796 -30.118558)
		(end 313.978036 -29.976318)
		(width 0.14224)
		(layer "In11.Cu")
		(net "M_C_DQ<62>")
	)
	(segment
		(start 314.1218 -21.215604)
		(end 314.1218 -19.177)
		(width 0.14224)
		(layer "In11.Cu")
		(net "M_C_DQ<62>")
	)
	(segment
		(start 313.835796 -25.940258)
		(end 314.165996 -25.610058)
		(width 0.14224)
		(layer "In11.Cu")
		(net "M_C_DQ<62>")
	)
	(segment
		(start 313.835796 -27.517598)
		(end 313.978036 -27.375358)
		(width 0.14224)
		(layer "In11.Cu")
		(net "M_C_DQ<62>")
	)
	(segment
		(start 314.1218 -19.177)
		(end 314.267596 -19.031204)
		(width 0.14224)
		(layer "In11.Cu")
		(net "M_C_DQ<62>")
	)
	(segment
		(start 314.175394 0.287528)
		(end 314.175394 0.565404)
		(width 0.14224)
		(layer "In11.Cu")
		(net "M_C_DQ<62>")
	)
	(arc
		(start 288.143696 -53.731922)
		(mid 288.059812 -53.432864)
		(end 288.13887 -53.132482)
		(width 0.0889)
		(layer "In11.Cu")
		(net "M_C_DQ<62>")
	)
	(arc
		(start 288.13887 -56.104536)
		(mid 288.19234 -55.909473)
		(end 288.143696 -55.713122)
		(width 0.0889)
		(layer "In11.Cu")
		(net "M_C_DQ<62>")
	)
	(arc
		(start 288.13887 -55.113936)
		(mid 288.19234 -54.918873)
		(end 288.143696 -54.722522)
		(width 0.0889)
		(layer "In11.Cu")
		(net "M_C_DQ<62>")
	)
	(arc
		(start 288.13887 -59.666886)
		(mid 288.059648 -59.377768)
		(end 288.13252 -59.087004)
		(width 0.0889)
		(layer "In11.Cu")
		(net "M_C_DQ<62>")
	)
	(arc
		(start 288.13887 -57.095136)
		(mid 288.19234 -56.900073)
		(end 288.143696 -56.703722)
		(width 0.0889)
		(layer "In11.Cu")
		(net "M_C_DQ<62>")
	)
	(arc
		(start 288.13887 -53.132482)
		(mid 288.204328 -53.040641)
		(end 288.28619 -52.963064)
		(width 0.0889)
		(layer "In11.Cu")
		(net "M_C_DQ<62>")
	)
	(arc
		(start 288.13887 -59.076336)
		(mid 288.192369 -58.876438)
		(end 288.13887 -58.67654)
		(width 0.0889)
		(layer "In11.Cu")
		(net "M_C_DQ<62>")
	)
	(arc
		(start 288.109152 -62.58052)
		(mid 288.060592 -62.310795)
		(end 288.13887 -62.048136)
		(width 0.0889)
		(layer "In11.Cu")
		(net "M_C_DQ<62>")
	)
	(arc
		(start 288.13252 -54.703218)
		(mid 288.059722 -54.412455)
		(end 288.13887 -54.123336)
		(width 0.0889)
		(layer "In11.Cu")
		(net "M_C_DQ<62>")
	)
	(arc
		(start 288.13252 -56.684418)
		(mid 288.059722 -56.393655)
		(end 288.13887 -56.104536)
		(width 0.0889)
		(layer "In11.Cu")
		(net "M_C_DQ<62>")
	)
	(arc
		(start 288.13887 -62.048136)
		(mid 288.192369 -61.848238)
		(end 288.13887 -61.64834)
		(width 0.0889)
		(layer "In11.Cu")
		(net "M_C_DQ<62>")
	)
	(arc
		(start 288.13887 -61.057536)
		(mid 288.19234 -60.862473)
		(end 288.143696 -60.666122)
		(width 0.0889)
		(layer "In11.Cu")
		(net "M_C_DQ<62>")
	)
	(arc
		(start 288.13887 -58.085736)
		(mid 288.19234 -57.890673)
		(end 288.143696 -57.694322)
		(width 0.0889)
		(layer "In11.Cu")
		(net "M_C_DQ<62>")
	)
	(arc
		(start 288.13252 -55.693818)
		(mid 288.059722 -55.403055)
		(end 288.13887 -55.113936)
		(width 0.0889)
		(layer "In11.Cu")
		(net "M_C_DQ<62>")
	)
	(arc
		(start 288.13887 -54.123336)
		(mid 288.19234 -53.928273)
		(end 288.143696 -53.731922)
		(width 0.0889)
		(layer "In11.Cu")
		(net "M_C_DQ<62>")
	)
	(arc
		(start 288.13252 -57.675018)
		(mid 288.059722 -57.384255)
		(end 288.13887 -57.095136)
		(width 0.0889)
		(layer "In11.Cu")
		(net "M_C_DQ<62>")
	)
	(arc
		(start 288.13887 -60.066936)
		(mid 288.19234 -59.871873)
		(end 288.143696 -59.675522)
		(width 0.0889)
		(layer "In11.Cu")
		(net "M_C_DQ<62>")
	)
	(arc
		(start 288.13887 -61.64834)
		(mid 288.059807 -61.352938)
		(end 288.13887 -61.057536)
		(width 0.0889)
		(layer "In11.Cu")
		(net "M_C_DQ<62>")
	)
	(arc
		(start 288.13252 -60.646818)
		(mid 288.059722 -60.356055)
		(end 288.13887 -60.066936)
		(width 0.0889)
		(layer "In11.Cu")
		(net "M_C_DQ<62>")
	)
	(arc
		(start 288.13887 -58.67654)
		(mid 288.059739 -58.381138)
		(end 288.13887 -58.085736)
		(width 0.0889)
		(layer "In11.Cu")
		(net "M_C_DQ<62>")
	)
	(arc
		(start 288.28619 -52.963064)
		(mid 288.396271 -52.827323)
		(end 288.435288 -52.656994)
		(width 0.0889)
		(layer "In11.Cu")
		(net "M_C_DQ<62>")
	)
	(segment
		(start 307.750464 3.778758)
		(end 307.749956 3.778758)
		(width 0.1651)
		(layer "F.Cu")
		(net "M_C_DQ<61>")
	)
	(segment
		(start 285.2166 -64.324738)
		(end 285.7881 -64.324738)
		(width 0.0889)
		(layer "F.Cu")
		(net "M_C_DQ<61>")
	)
	(segment
		(start 307.749956 3.778758)
		(end 307.749956 2.514854)
		(width 0.1651)
		(layer "F.Cu")
		(net "M_C_DQ<61>")
	)
	(via
		(at 307.749956 2.514854)
		(size 0.508)
		(drill 0.254)
		(layers "F.Cu" "B.Cu")
		(net "M_C_DQ<61>")
	)
	(via
		(at 285.2166 -64.324738)
		(size 0.508)
		(drill 0.254)
		(layers "F.Cu" "B.Cu")
		(net "M_C_DQ<61>")
	)
	(via
		(at 308.52364 -3.076956)
		(size 0.508)
		(drill 0.254)
		(layers "F.Cu" "B.Cu")
		(net "M_C_DQ<61>")
	)
	(segment
		(start 308.59984 -1.021842)
		(end 308.59984 -3.000756)
		(width 0.1651)
		(layer "B.Cu")
		(net "M_C_DQ<61>")
	)
	(segment
		(start 308.59984 -3.000756)
		(end 308.52364 -3.076956)
		(width 0.1651)
		(layer "B.Cu")
		(net "M_C_DQ<61>")
	)
	(segment
		(start 308.600348 -1.021842)
		(end 308.59984 -1.021842)
		(width 0.1651)
		(layer "B.Cu")
		(net "M_C_DQ<61>")
	)
	(segment
		(start 309.039768 -18.378678)
		(end 308.9402 -18.478246)
		(width 0.14224)
		(layer "In11.Cu")
		(net "M_C_DQ<61>")
	)
	(segment
		(start 308.036722 -31.84017)
		(end 307.777642 -32.09925)
		(width 0.14224)
		(layer "In11.Cu")
		(net "M_C_DQ<61>")
	)
	(segment
		(start 308.9148 -4.83616)
		(end 308.9148 -7.24535)
		(width 0.14224)
		(layer "In11.Cu")
		(net "M_C_DQ<61>")
	)
	(segment
		(start 284.870144 -62.543436)
		(end 284.873446 -62.549278)
		(width 0.0889)
		(layer "In11.Cu")
		(net "M_C_DQ<61>")
	)
	(segment
		(start 309.031894 1.149096)
		(end 309.031894 0.7366)
		(width 0.14224)
		(layer "In11.Cu")
		(net "M_C_DQ<61>")
	)
	(segment
		(start 308.954678 -11.695176)
		(end 308.954678 -12.318238)
		(width 0.14224)
		(layer "In11.Cu")
		(net "M_C_DQ<61>")
	)
	(segment
		(start 308.049168 -3.551428)
		(end 308.049168 -3.970528)
		(width 0.14224)
		(layer "In11.Cu")
		(net "M_C_DQ<61>")
	)
	(segment
		(start 307.743098 -31.143956)
		(end 307.742844 -31.345124)
		(width 0.14224)
		(layer "In11.Cu")
		(net "M_C_DQ<61>")
	)
	(segment
		(start 284.876494 -59.160918)
		(end 284.870144 -59.171586)
		(width 0.0889)
		(layer "In11.Cu")
		(net "M_C_DQ<61>")
	)
	(segment
		(start 309.0418 -21.9456)
		(end 309.0418 -23.024592)
		(width 0.14224)
		(layer "In11.Cu")
		(net "M_C_DQ<61>")
	)
	(segment
		(start 309.098696 -9.632696)
		(end 309.098696 -11.551158)
		(width 0.14224)
		(layer "In11.Cu")
		(net "M_C_DQ<61>")
	)
	(segment
		(start 308.963568 -23.102824)
		(end 308.963568 -25.931368)
		(width 0.14224)
		(layer "In11.Cu")
		(net "M_C_DQ<61>")
	)
	(segment
		(start 307.749956 2.120138)
		(end 308.320694 1.5494)
		(width 0.14224)
		(layer "In11.Cu")
		(net "M_C_DQ<61>")
	)
	(segment
		(start 308.9402 -21.3106)
		(end 308.9402 -21.844)
		(width 0.14224)
		(layer "In11.Cu")
		(net "M_C_DQ<61>")
	)
	(segment
		(start 308.963568 -25.931368)
		(end 309.090568 -26.058368)
		(width 0.14224)
		(layer "In11.Cu")
		(net "M_C_DQ<61>")
	)
	(segment
		(start 309.0926 -19.2024)
		(end 309.0926 -21.1582)
		(width 0.14224)
		(layer "In11.Cu")
		(net "M_C_DQ<61>")
	)
	(segment
		(start 309.090568 -29.796486)
		(end 308.663086 -30.223968)
		(width 0.14224)
		(layer "In11.Cu")
		(net "M_C_DQ<61>")
	)
	(segment
		(start 306.822602 -32.445198)
		(end 306.542694 -32.725106)
		(width 0.14224)
		(layer "In11.Cu")
		(net "M_C_DQ<61>")
	)
	(segment
		(start 308.001924 -30.88513)
		(end 307.743098 -31.143956)
		(width 0.14224)
		(layer "In11.Cu")
		(net "M_C_DQ<61>")
	)
	(segment
		(start 309.039768 -13.575284)
		(end 308.991 -13.624052)
		(width 0.14224)
		(layer "In11.Cu")
		(net "M_C_DQ<61>")
	)
	(segment
		(start 287.007808 -48.653192)
		(end 287.007808 -48.654208)
		(width 0.0889)
		(layer "In11.Cu")
		(net "M_C_DQ<61>")
	)
	(segment
		(start 308.835044 0.53975)
		(end 308.835044 -2.765552)
		(width 0.14224)
		(layer "In11.Cu")
		(net "M_C_DQ<61>")
	)
	(segment
		(start 308.049168 -3.970528)
		(end 308.9148 -4.83616)
		(width 0.14224)
		(layer "In11.Cu")
		(net "M_C_DQ<61>")
	)
	(segment
		(start 284.870144 -57.590436)
		(end 284.879034 -57.605676)
		(width 0.0889)
		(layer "In11.Cu")
		(net "M_C_DQ<61>")
	)
	(segment
		(start 290.9316 -44.7294)
		(end 287.2105 -48.4505)
		(width 0.14224)
		(layer "In11.Cu")
		(net "M_C_DQ<61>")
	)
	(segment
		(start 308.997096 -7.327646)
		(end 308.997096 -8.902446)
		(width 0.14224)
		(layer "In11.Cu")
		(net "M_C_DQ<61>")
	)
	(segment
		(start 308.997096 -8.902446)
		(end 308.954678 -8.944864)
		(width 0.14224)
		(layer "In11.Cu")
		(net "M_C_DQ<61>")
	)
	(segment
		(start 306.542694 -32.725106)
		(end 306.161948 -32.725106)
		(width 0.14224)
		(layer "In11.Cu")
		(net "M_C_DQ<61>")
	)
	(segment
		(start 285.498794 -63.61811)
		(end 285.383732 -63.9064)
		(width 0.0889)
		(layer "In11.Cu")
		(net "M_C_DQ<61>")
	)
	(segment
		(start 307.283104 -31.805118)
		(end 307.081936 -31.805118)
		(width 0.14224)
		(layer "In11.Cu")
		(net "M_C_DQ<61>")
	)
	(segment
		(start 285.4325 -62.99073)
		(end 285.454852 -63.012574)
		(width 0.0889)
		(layer "In11.Cu")
		(net "M_C_DQ<61>")
	)
	(segment
		(start 285.383732 -63.9064)
		(end 285.2166 -64.324738)
		(width 0.0889)
		(layer "In11.Cu")
		(net "M_C_DQ<61>")
	)
	(segment
		(start 306.161948 -32.725106)
		(end 294.157654 -44.7294)
		(width 0.14224)
		(layer "In11.Cu")
		(net "M_C_DQ<61>")
	)
	(segment
		(start 308.203092 -30.88513)
		(end 308.001924 -30.88513)
		(width 0.14224)
		(layer "In11.Cu")
		(net "M_C_DQ<61>")
	)
	(segment
		(start 284.870144 -56.599836)
		(end 284.879034 -56.615076)
		(width 0.0889)
		(layer "In11.Cu")
		(net "M_C_DQ<61>")
	)
	(segment
		(start 307.576982 -32.098996)
		(end 307.283104 -31.805118)
		(width 0.14224)
		(layer "In11.Cu")
		(net "M_C_DQ<61>")
	)
	(segment
		(start 308.95671 -30.920182)
		(end 308.69763 -31.179262)
		(width 0.14224)
		(layer "In11.Cu")
		(net "M_C_DQ<61>")
	)
	(segment
		(start 309.0418 -23.024592)
		(end 308.963568 -23.102824)
		(width 0.14224)
		(layer "In11.Cu")
		(net "M_C_DQ<61>")
	)
	(segment
		(start 308.9402 -19.05)
		(end 309.0926 -19.2024)
		(width 0.14224)
		(layer "In11.Cu")
		(net "M_C_DQ<61>")
	)
	(segment
		(start 307.777642 -32.09925)
		(end 307.6956 -32.09925)
		(width 0.14224)
		(layer "In11.Cu")
		(net "M_C_DQ<61>")
	)
	(segment
		(start 308.036722 -31.639002)
		(end 308.036722 -31.84017)
		(width 0.14224)
		(layer "In11.Cu")
		(net "M_C_DQ<61>")
	)
	(segment
		(start 284.870144 -59.571382)
		(end 284.876494 -59.58205)
		(width 0.0889)
		(layer "In11.Cu")
		(net "M_C_DQ<61>")
	)
	(segment
		(start 308.9402 -21.844)
		(end 309.0418 -21.9456)
		(width 0.14224)
		(layer "In11.Cu")
		(net "M_C_DQ<61>")
	)
	(segment
		(start 285.000192 -50.661824)
		(end 285.000192 -52.856892)
		(width 0.0889)
		(layer "In11.Cu")
		(net "M_C_DQ<61>")
	)
	(segment
		(start 287.2105 -48.4505)
		(end 287.007808 -48.653192)
		(width 0.0889)
		(layer "In11.Cu")
		(net "M_C_DQ<61>")
	)
	(segment
		(start 308.835044 -2.765552)
		(end 308.52364 -3.076956)
		(width 0.14224)
		(layer "In11.Cu")
		(net "M_C_DQ<61>")
	)
	(segment
		(start 308.9148 -7.24535)
		(end 308.997096 -7.327646)
		(width 0.14224)
		(layer "In11.Cu")
		(net "M_C_DQ<61>")
	)
	(segment
		(start 308.320694 1.5494)
		(end 308.63159 1.5494)
		(width 0.14224)
		(layer "In11.Cu")
		(net "M_C_DQ<61>")
	)
	(segment
		(start 309.098696 -11.551158)
		(end 308.954678 -11.695176)
		(width 0.14224)
		(layer "In11.Cu")
		(net "M_C_DQ<61>")
	)
	(segment
		(start 308.954678 -12.318238)
		(end 309.039768 -12.403328)
		(width 0.14224)
		(layer "In11.Cu")
		(net "M_C_DQ<61>")
	)
	(segment
		(start 309.039768 -17.159478)
		(end 309.039768 -18.378678)
		(width 0.14224)
		(layer "In11.Cu")
		(net "M_C_DQ<61>")
	)
	(segment
		(start 308.9402 -18.478246)
		(end 308.9402 -19.05)
		(width 0.14224)
		(layer "In11.Cu")
		(net "M_C_DQ<61>")
	)
	(segment
		(start 307.6956 -32.09925)
		(end 307.576982 -32.098996)
		(width 0.14224)
		(layer "In11.Cu")
		(net "M_C_DQ<61>")
	)
	(segment
		(start 308.95671 -30.719014)
		(end 308.95671 -30.920182)
		(width 0.14224)
		(layer "In11.Cu")
		(net "M_C_DQ<61>")
	)
	(segment
		(start 285.08071 -62.767464)
		(end 285.4325 -62.99073)
		(width 0.0889)
		(layer "In11.Cu")
		(net "M_C_DQ<61>")
	)
	(segment
		(start 284.870144 -55.609236)
		(end 284.879034 -55.624476)
		(width 0.0889)
		(layer "In11.Cu")
		(net "M_C_DQ<61>")
	)
	(segment
		(start 294.157654 -44.7294)
		(end 290.9316 -44.7294)
		(width 0.14224)
		(layer "In11.Cu")
		(net "M_C_DQ<61>")
	)
	(segment
		(start 308.662832 -30.425136)
		(end 308.95671 -30.719014)
		(width 0.14224)
		(layer "In11.Cu")
		(net "M_C_DQ<61>")
	)
	(segment
		(start 308.954678 -8.944864)
		(end 308.954678 -9.488678)
		(width 0.14224)
		(layer "In11.Cu")
		(net "M_C_DQ<61>")
	)
	(segment
		(start 308.663086 -30.223968)
		(end 308.662832 -30.425136)
		(width 0.14224)
		(layer "In11.Cu")
		(net "M_C_DQ<61>")
	)
	(segment
		(start 309.090568 -26.058368)
		(end 309.090568 -29.796486)
		(width 0.14224)
		(layer "In11.Cu")
		(net "M_C_DQ<61>")
	)
	(segment
		(start 308.991 -13.624052)
		(end 308.991 -17.11071)
		(width 0.14224)
		(layer "In11.Cu")
		(net "M_C_DQ<61>")
	)
	(segment
		(start 308.52364 -3.076956)
		(end 308.049168 -3.551428)
		(width 0.14224)
		(layer "In11.Cu")
		(net "M_C_DQ<61>")
	)
	(segment
		(start 308.69763 -31.179262)
		(end 308.49697 -31.179008)
		(width 0.14224)
		(layer "In11.Cu")
		(net "M_C_DQ<61>")
	)
	(segment
		(start 309.039768 -12.403328)
		(end 309.039768 -13.575284)
		(width 0.14224)
		(layer "In11.Cu")
		(net "M_C_DQ<61>")
	)
	(segment
		(start 284.862016 -54.604412)
		(end 284.879034 -54.633876)
		(width 0.0889)
		(layer "In11.Cu")
		(net "M_C_DQ<61>")
	)
	(segment
		(start 287.007808 -48.654208)
		(end 285.000192 -50.661824)
		(width 0.0889)
		(layer "In11.Cu")
		(net "M_C_DQ<61>")
	)
	(segment
		(start 284.949646 -52.907438)
		(end 284.949646 -53.922676)
		(width 0.0889)
		(layer "In11.Cu")
		(net "M_C_DQ<61>")
	)
	(segment
		(start 306.82311 -32.063944)
		(end 306.822602 -32.445198)
		(width 0.14224)
		(layer "In11.Cu")
		(net "M_C_DQ<61>")
	)
	(segment
		(start 307.742844 -31.345124)
		(end 308.036722 -31.639002)
		(width 0.14224)
		(layer "In11.Cu")
		(net "M_C_DQ<61>")
	)
	(segment
		(start 308.991 -17.11071)
		(end 309.039768 -17.159478)
		(width 0.14224)
		(layer "In11.Cu")
		(net "M_C_DQ<61>")
	)
	(segment
		(start 309.0926 -21.1582)
		(end 308.9402 -21.3106)
		(width 0.14224)
		(layer "In11.Cu")
		(net "M_C_DQ<61>")
	)
	(segment
		(start 309.031894 0.7366)
		(end 308.835044 0.53975)
		(width 0.14224)
		(layer "In11.Cu")
		(net "M_C_DQ<61>")
	)
	(segment
		(start 307.749956 2.514854)
		(end 307.749956 2.120138)
		(width 0.14224)
		(layer "In11.Cu")
		(net "M_C_DQ<61>")
	)
	(segment
		(start 285.000192 -52.856892)
		(end 284.949646 -52.907438)
		(width 0.0889)
		(layer "In11.Cu")
		(net "M_C_DQ<61>")
	)
	(segment
		(start 308.63159 1.5494)
		(end 309.031894 1.149096)
		(width 0.14224)
		(layer "In11.Cu")
		(net "M_C_DQ<61>")
	)
	(segment
		(start 308.49697 -31.179008)
		(end 308.203092 -30.88513)
		(width 0.14224)
		(layer "In11.Cu")
		(net "M_C_DQ<61>")
	)
	(segment
		(start 284.870144 -60.562236)
		(end 284.879034 -60.577476)
		(width 0.0889)
		(layer "In11.Cu")
		(net "M_C_DQ<61>")
	)
	(segment
		(start 308.954678 -9.488678)
		(end 309.098696 -9.632696)
		(width 0.14224)
		(layer "In11.Cu")
		(net "M_C_DQ<61>")
	)
	(segment
		(start 307.081936 -31.805118)
		(end 306.82311 -32.063944)
		(width 0.14224)
		(layer "In11.Cu")
		(net "M_C_DQ<61>")
	)
	(arc
		(start 284.870144 -54.218586)
		(mid 284.816448 -54.410467)
		(end 284.862016 -54.604412)
		(width 0.0889)
		(layer "In11.Cu")
		(net "M_C_DQ<61>")
	)
	(arc
		(start 284.949646 -53.922676)
		(mid 284.929389 -54.075868)
		(end 284.870144 -54.218586)
		(width 0.0889)
		(layer "In11.Cu")
		(net "M_C_DQ<61>")
	)
	(arc
		(start 284.879034 -54.633876)
		(mid 284.949431 -54.922827)
		(end 284.870144 -55.20944)
		(width 0.0889)
		(layer "In11.Cu")
		(net "M_C_DQ<61>")
	)
	(arc
		(start 284.870144 -57.19064)
		(mid 284.816611 -57.390538)
		(end 284.870144 -57.590436)
		(width 0.0889)
		(layer "In11.Cu")
		(net "M_C_DQ<61>")
	)
	(arc
		(start 284.870144 -59.171586)
		(mid 284.816611 -59.371484)
		(end 284.870144 -59.571382)
		(width 0.0889)
		(layer "In11.Cu")
		(net "M_C_DQ<61>")
	)
	(arc
		(start 284.870144 -58.581036)
		(mid 284.949366 -58.870154)
		(end 284.876494 -59.160918)
		(width 0.0889)
		(layer "In11.Cu")
		(net "M_C_DQ<61>")
	)
	(arc
		(start 284.879034 -60.577476)
		(mid 284.949431 -60.866427)
		(end 284.870144 -61.15304)
		(width 0.0889)
		(layer "In11.Cu")
		(net "M_C_DQ<61>")
	)
	(arc
		(start 284.873446 -62.549278)
		(mid 284.963627 -62.671146)
		(end 285.08071 -62.767464)
		(width 0.0889)
		(layer "In11.Cu")
		(net "M_C_DQ<61>")
	)
	(arc
		(start 284.879034 -56.615076)
		(mid 284.949431 -56.904027)
		(end 284.870144 -57.19064)
		(width 0.0889)
		(layer "In11.Cu")
		(net "M_C_DQ<61>")
	)
	(arc
		(start 284.879034 -57.605676)
		(mid 284.949431 -57.894627)
		(end 284.870144 -58.18124)
		(width 0.0889)
		(layer "In11.Cu")
		(net "M_C_DQ<61>")
	)
	(arc
		(start 284.879034 -55.624476)
		(mid 284.949431 -55.913427)
		(end 284.870144 -56.20004)
		(width 0.0889)
		(layer "In11.Cu")
		(net "M_C_DQ<61>")
	)
	(arc
		(start 284.876494 -59.58205)
		(mid 284.949414 -59.873067)
		(end 284.870144 -60.16244)
		(width 0.0889)
		(layer "In11.Cu")
		(net "M_C_DQ<61>")
	)
	(arc
		(start 284.870144 -61.15304)
		(mid 284.816611 -61.352938)
		(end 284.870144 -61.552836)
		(width 0.0889)
		(layer "In11.Cu")
		(net "M_C_DQ<61>")
	)
	(arc
		(start 285.454852 -63.012574)
		(mid 285.615764 -63.305229)
		(end 285.498794 -63.61811)
		(width 0.0889)
		(layer "In11.Cu")
		(net "M_C_DQ<61>")
	)
	(arc
		(start 284.870144 -56.20004)
		(mid 284.816611 -56.399938)
		(end 284.870144 -56.599836)
		(width 0.0889)
		(layer "In11.Cu")
		(net "M_C_DQ<61>")
	)
	(arc
		(start 284.870144 -62.14364)
		(mid 284.816611 -62.343538)
		(end 284.870144 -62.543436)
		(width 0.0889)
		(layer "In11.Cu")
		(net "M_C_DQ<61>")
	)
	(arc
		(start 284.870144 -58.18124)
		(mid 284.816611 -58.381138)
		(end 284.870144 -58.581036)
		(width 0.0889)
		(layer "In11.Cu")
		(net "M_C_DQ<61>")
	)
	(arc
		(start 284.870144 -61.552836)
		(mid 284.949275 -61.848238)
		(end 284.870144 -62.14364)
		(width 0.0889)
		(layer "In11.Cu")
		(net "M_C_DQ<61>")
	)
	(arc
		(start 284.870144 -60.16244)
		(mid 284.816611 -60.362338)
		(end 284.870144 -60.562236)
		(width 0.0889)
		(layer "In11.Cu")
		(net "M_C_DQ<61>")
	)
	(arc
		(start 284.870144 -55.20944)
		(mid 284.816611 -55.409338)
		(end 284.870144 -55.609236)
		(width 0.0889)
		(layer "In11.Cu")
		(net "M_C_DQ<61>")
	)
	(segment
		(start 308.600348 -0.821182)
		(end 308.59984 -0.821182)
		(width 0.1651)
		(layer "F.Cu")
		(net "M_C_DQ<60>")
	)
	(segment
		(start 308.59984 -0.821182)
		(end 308.59984 0.510032)
		(width 0.1651)
		(layer "F.Cu")
		(net "M_C_DQ<60>")
	)
	(segment
		(start 308.59984 0.510032)
		(end 308.501796 1.0414)
		(width 0.1651)
		(layer "F.Cu")
		(net "M_C_DQ<60>")
	)
	(segment
		(start 285.2166 -63.334138)
		(end 285.7881 -63.334138)
		(width 0.0889)
		(layer "F.Cu")
		(net "M_C_DQ<60>")
	)
	(via
		(at 285.2166 -63.334138)
		(size 0.508)
		(drill 0.254)
		(layers "F.Cu" "B.Cu")
		(net "M_C_DQ<60>")
	)
	(via
		(at 307.749956 -4.357878)
		(size 0.508)
		(drill 0.254)
		(layers "F.Cu" "B.Cu")
		(net "M_C_DQ<60>")
	)
	(via
		(at 308.501796 1.0414)
		(size 0.508)
		(drill 0.254)
		(layers "F.Cu" "B.Cu")
		(net "M_C_DQ<60>")
	)
	(segment
		(start 307.750464 -5.621782)
		(end 307.749956 -5.621782)
		(width 0.1651)
		(layer "B.Cu")
		(net "M_C_DQ<60>")
	)
	(segment
		(start 307.749956 -5.621782)
		(end 307.749956 -4.357878)
		(width 0.1651)
		(layer "B.Cu")
		(net "M_C_DQ<60>")
	)
	(segment
		(start 285.157926 -63.270892)
		(end 285.2166 -63.334138)
		(width 0.0889)
		(layer "In11.Cu")
		(net "M_C_DQ<60>")
	)
	(segment
		(start 294.8178 -42.469054)
		(end 293.065454 -44.2214)
		(width 0.14224)
		(layer "In11.Cu")
		(net "M_C_DQ<60>")
	)
	(segment
		(start 295.566846 -40.65524)
		(end 295.424606 -40.513)
		(width 0.14224)
		(layer "In11.Cu")
		(net "M_C_DQ<60>")
	)
	(segment
		(start 308.501796 1.0414)
		(end 308.225444 0.765048)
		(width 0.14224)
		(layer "In11.Cu")
		(net "M_C_DQ<60>")
	)
	(segment
		(start 295.709086 -41.7322)
		(end 295.566846 -41.58996)
		(width 0.14224)
		(layer "In11.Cu")
		(net "M_C_DQ<60>")
	)
	(segment
		(start 308.102 -19.1008)
		(end 308.102 -21.209)
		(width 0.14224)
		(layer "In11.Cu")
		(net "M_C_DQ<60>")
	)
	(segment
		(start 308.3052 -18.63471)
		(end 308.3052 -18.8976)
		(width 0.14224)
		(layer "In11.Cu")
		(net "M_C_DQ<60>")
	)
	(segment
		(start 308.3052 -21.4122)
		(end 308.3052 -21.754592)
		(width 0.14224)
		(layer "In11.Cu")
		(net "M_C_DQ<60>")
	)
	(segment
		(start 308.120796 -23.149052)
		(end 308.3052 -23.333456)
		(width 0.14224)
		(layer "In11.Cu")
		(net "M_C_DQ<60>")
	)
	(segment
		(start 284.809692 -50.58283)
		(end 284.809692 -52.777898)
		(width 0.0889)
		(layer "In11.Cu")
		(net "M_C_DQ<60>")
	)
	(segment
		(start 308.0512 -5.715)
		(end 308.250336 -5.914136)
		(width 0.14224)
		(layer "In11.Cu")
		(net "M_C_DQ<60>")
	)
	(segment
		(start 308.05374 -12.44346)
		(end 308.05374 -13.6017)
		(width 0.14224)
		(layer "In11.Cu")
		(net "M_C_DQ<60>")
	)
	(segment
		(start 295.566846 -41.58996)
		(end 295.566846 -40.65524)
		(width 0.14224)
		(layer "In11.Cu")
		(net "M_C_DQ<60>")
	)
	(segment
		(start 308.3052 -26.2382)
		(end 308.455568 -26.388568)
		(width 0.14224)
		(layer "In11.Cu")
		(net "M_C_DQ<60>")
	)
	(segment
		(start 296.217086 -41.58996)
		(end 296.074846 -41.7322)
		(width 0.14224)
		(layer "In11.Cu")
		(net "M_C_DQ<60>")
	)
	(segment
		(start 308.019196 -7.449058)
		(end 308.019196 -8.711946)
		(width 0.14224)
		(layer "In11.Cu")
		(net "M_C_DQ<60>")
	)
	(segment
		(start 308.2544 -7.213854)
		(end 308.019196 -7.449058)
		(width 0.14224)
		(layer "In11.Cu")
		(net "M_C_DQ<60>")
	)
	(segment
		(start 308.0512 -5.439156)
		(end 308.0512 -5.715)
		(width 0.14224)
		(layer "In11.Cu")
		(net "M_C_DQ<60>")
	)
	(segment
		(start 307.514244 -3.327654)
		(end 307.514244 -4.122166)
		(width 0.14224)
		(layer "In11.Cu")
		(net "M_C_DQ<60>")
	)
	(segment
		(start 290.6522 -44.2214)
		(end 286.8676 -48.006)
		(width 0.14224)
		(layer "In11.Cu")
		(net "M_C_DQ<60>")
	)
	(segment
		(start 308.120796 -21.938996)
		(end 308.120796 -23.149052)
		(width 0.14224)
		(layer "In11.Cu")
		(net "M_C_DQ<60>")
	)
	(segment
		(start 308.455568 -29.771086)
		(end 298.272454 -39.9542)
		(width 0.14224)
		(layer "In11.Cu")
		(net "M_C_DQ<60>")
	)
	(segment
		(start 308.067964 -6.384036)
		(end 308.067964 -6.671564)
		(width 0.14224)
		(layer "In11.Cu")
		(net "M_C_DQ<60>")
	)
	(segment
		(start 284.6959 -60.642246)
		(end 284.70479 -60.657486)
		(width 0.0889)
		(layer "In11.Cu")
		(net "M_C_DQ<60>")
	)
	(segment
		(start 307.749956 -4.357878)
		(end 308.2798 -4.887722)
		(width 0.14224)
		(layer "In11.Cu")
		(net "M_C_DQ<60>")
	)
	(segment
		(start 308.3052 -11.7348)
		(end 308.3052 -12.192)
		(width 0.14224)
		(layer "In11.Cu")
		(net "M_C_DQ<60>")
	)
	(segment
		(start 308.250336 -6.201664)
		(end 308.067964 -6.384036)
		(width 0.14224)
		(layer "In11.Cu")
		(net "M_C_DQ<60>")
	)
	(segment
		(start 294.8178 -40.65524)
		(end 294.8178 -42.469054)
		(width 0.14224)
		(layer "In11.Cu")
		(net "M_C_DQ<60>")
	)
	(segment
		(start 308.3052 -18.8976)
		(end 308.102 -19.1008)
		(width 0.14224)
		(layer "In11.Cu")
		(net "M_C_DQ<60>")
	)
	(segment
		(start 286.8168 -48.1838)
		(end 286.8168 -48.575722)
		(width 0.0889)
		(layer "In11.Cu")
		(net "M_C_DQ<60>")
	)
	(segment
		(start 307.861462 -0.381)
		(end 308.242462 -0.762)
		(width 0.14224)
		(layer "In11.Cu")
		(net "M_C_DQ<60>")
	)
	(segment
		(start 296.074846 -41.7322)
		(end 295.709086 -41.7322)
		(width 0.14224)
		(layer "In11.Cu")
		(net "M_C_DQ<60>")
	)
	(segment
		(start 307.874162 -1.4351)
		(end 307.874162 -1.790446)
		(width 0.14224)
		(layer "In11.Cu")
		(net "M_C_DQ<60>")
	)
	(segment
		(start 308.225444 -2.616454)
		(end 307.514244 -3.327654)
		(width 0.14224)
		(layer "In11.Cu")
		(net "M_C_DQ<60>")
	)
	(segment
		(start 295.424606 -40.513)
		(end 294.96004 -40.513)
		(width 0.14224)
		(layer "In11.Cu")
		(net "M_C_DQ<60>")
	)
	(segment
		(start 308.05374 -13.6017)
		(end 308.3306 -13.87856)
		(width 0.14224)
		(layer "In11.Cu")
		(net "M_C_DQ<60>")
	)
	(segment
		(start 308.455568 -26.388568)
		(end 308.455568 -29.771086)
		(width 0.14224)
		(layer "In11.Cu")
		(net "M_C_DQ<60>")
	)
	(segment
		(start 308.225444 0.765048)
		(end 308.225444 0.287528)
		(width 0.14224)
		(layer "In11.Cu")
		(net "M_C_DQ<60>")
	)
	(segment
		(start 308.225444 -2.141728)
		(end 308.225444 -2.616454)
		(width 0.14224)
		(layer "In11.Cu")
		(net "M_C_DQ<60>")
	)
	(segment
		(start 286.8168 -48.575722)
		(end 284.809692 -50.58283)
		(width 0.0889)
		(layer "In11.Cu")
		(net "M_C_DQ<60>")
	)
	(segment
		(start 284.69844 -58.665872)
		(end 284.70479 -58.67654)
		(width 0.0889)
		(layer "In11.Cu")
		(net "M_C_DQ<60>")
	)
	(segment
		(start 308.242462 -1.0668)
		(end 307.874162 -1.4351)
		(width 0.14224)
		(layer "In11.Cu")
		(net "M_C_DQ<60>")
	)
	(segment
		(start 308.242462 -0.762)
		(end 308.242462 -1.0668)
		(width 0.14224)
		(layer "In11.Cu")
		(net "M_C_DQ<60>")
	)
	(segment
		(start 308.225444 0.287528)
		(end 307.861462 -0.076454)
		(width 0.14224)
		(layer "In11.Cu")
		(net "M_C_DQ<60>")
	)
	(segment
		(start 307.861462 -0.076454)
		(end 307.861462 -0.381)
		(width 0.14224)
		(layer "In11.Cu")
		(net "M_C_DQ<60>")
	)
	(segment
		(start 284.6959 -56.679846)
		(end 284.70479 -56.695086)
		(width 0.0889)
		(layer "In11.Cu")
		(net "M_C_DQ<60>")
	)
	(segment
		(start 293.065454 -44.2214)
		(end 290.6522 -44.2214)
		(width 0.14224)
		(layer "In11.Cu")
		(net "M_C_DQ<60>")
	)
	(segment
		(start 284.758384 -52.829206)
		(end 284.758384 -53.922676)
		(width 0.0889)
		(layer "In11.Cu")
		(net "M_C_DQ<60>")
	)
	(segment
		(start 308.3052 -9.4742)
		(end 308.1274 -9.652)
		(width 0.14224)
		(layer "In11.Cu")
		(net "M_C_DQ<60>")
	)
	(segment
		(start 308.067964 -6.671564)
		(end 308.2544 -6.858)
		(width 0.14224)
		(layer "In11.Cu")
		(net "M_C_DQ<60>")
	)
	(segment
		(start 284.809692 -52.777898)
		(end 284.758384 -52.829206)
		(width 0.0889)
		(layer "In11.Cu")
		(net "M_C_DQ<60>")
	)
	(segment
		(start 308.1274 -9.652)
		(end 308.1274 -11.557)
		(width 0.14224)
		(layer "In11.Cu")
		(net "M_C_DQ<60>")
	)
	(segment
		(start 296.359326 -39.9542)
		(end 296.217086 -40.09644)
		(width 0.14224)
		(layer "In11.Cu")
		(net "M_C_DQ<60>")
	)
	(segment
		(start 294.96004 -40.513)
		(end 294.8178 -40.65524)
		(width 0.14224)
		(layer "In11.Cu")
		(net "M_C_DQ<60>")
	)
	(segment
		(start 284.694122 -54.695344)
		(end 284.70479 -54.713886)
		(width 0.0889)
		(layer "In11.Cu")
		(net "M_C_DQ<60>")
	)
	(segment
		(start 308.2798 -5.210556)
		(end 308.0512 -5.439156)
		(width 0.14224)
		(layer "In11.Cu")
		(net "M_C_DQ<60>")
	)
	(segment
		(start 308.3052 -21.754592)
		(end 308.120796 -21.938996)
		(width 0.14224)
		(layer "In11.Cu")
		(net "M_C_DQ<60>")
	)
	(segment
		(start 308.2544 -6.858)
		(end 308.2544 -7.213854)
		(width 0.14224)
		(layer "In11.Cu")
		(net "M_C_DQ<60>")
	)
	(segment
		(start 307.514244 -4.122166)
		(end 307.749956 -4.357878)
		(width 0.14224)
		(layer "In11.Cu")
		(net "M_C_DQ<60>")
	)
	(segment
		(start 308.250336 -5.914136)
		(end 308.250336 -6.201664)
		(width 0.14224)
		(layer "In11.Cu")
		(net "M_C_DQ<60>")
	)
	(segment
		(start 308.3306 -16.764254)
		(end 308.019196 -17.075658)
		(width 0.14224)
		(layer "In11.Cu")
		(net "M_C_DQ<60>")
	)
	(segment
		(start 307.874162 -1.790446)
		(end 308.225444 -2.141728)
		(width 0.14224)
		(layer "In11.Cu")
		(net "M_C_DQ<60>")
	)
	(segment
		(start 284.6959 -55.689246)
		(end 284.70479 -55.704486)
		(width 0.0889)
		(layer "In11.Cu")
		(net "M_C_DQ<60>")
	)
	(segment
		(start 308.019196 -18.348706)
		(end 308.3052 -18.63471)
		(width 0.14224)
		(layer "In11.Cu")
		(net "M_C_DQ<60>")
	)
	(segment
		(start 308.3052 -8.99795)
		(end 308.3052 -9.4742)
		(width 0.14224)
		(layer "In11.Cu")
		(net "M_C_DQ<60>")
	)
	(segment
		(start 308.3306 -13.87856)
		(end 308.3306 -16.764254)
		(width 0.14224)
		(layer "In11.Cu")
		(net "M_C_DQ<60>")
	)
	(segment
		(start 284.6959 -57.670446)
		(end 284.70479 -57.685686)
		(width 0.0889)
		(layer "In11.Cu")
		(net "M_C_DQ<60>")
	)
	(segment
		(start 308.3052 -23.333456)
		(end 308.3052 -26.2382)
		(width 0.14224)
		(layer "In11.Cu")
		(net "M_C_DQ<60>")
	)
	(segment
		(start 308.102 -21.209)
		(end 308.3052 -21.4122)
		(width 0.14224)
		(layer "In11.Cu")
		(net "M_C_DQ<60>")
	)
	(segment
		(start 308.019196 -17.075658)
		(end 308.019196 -18.348706)
		(width 0.14224)
		(layer "In11.Cu")
		(net "M_C_DQ<60>")
	)
	(segment
		(start 308.2798 -4.887722)
		(end 308.2798 -5.210556)
		(width 0.14224)
		(layer "In11.Cu")
		(net "M_C_DQ<60>")
	)
	(segment
		(start 286.8676 -48.133)
		(end 286.8168 -48.1838)
		(width 0.0889)
		(layer "In11.Cu")
		(net "M_C_DQ<60>")
	)
	(segment
		(start 296.217086 -40.09644)
		(end 296.217086 -41.58996)
		(width 0.14224)
		(layer "In11.Cu")
		(net "M_C_DQ<60>")
	)
	(segment
		(start 308.3052 -12.192)
		(end 308.05374 -12.44346)
		(width 0.14224)
		(layer "In11.Cu")
		(net "M_C_DQ<60>")
	)
	(segment
		(start 284.70479 -59.076336)
		(end 284.69844 -59.087004)
		(width 0.0889)
		(layer "In11.Cu")
		(net "M_C_DQ<60>")
	)
	(segment
		(start 284.70479 -62.63894)
		(end 284.708854 -62.646052)
		(width 0.0889)
		(layer "In11.Cu")
		(net "M_C_DQ<60>")
	)
	(segment
		(start 308.019196 -8.711946)
		(end 308.3052 -8.99795)
		(width 0.14224)
		(layer "In11.Cu")
		(net "M_C_DQ<60>")
	)
	(segment
		(start 298.272454 -39.9542)
		(end 296.359326 -39.9542)
		(width 0.14224)
		(layer "In11.Cu")
		(net "M_C_DQ<60>")
	)
	(segment
		(start 308.1274 -11.557)
		(end 308.3052 -11.7348)
		(width 0.14224)
		(layer "In11.Cu")
		(net "M_C_DQ<60>")
	)
	(segment
		(start 286.8676 -48.006)
		(end 286.8676 -48.133)
		(width 0.14224)
		(layer "In11.Cu")
		(net "M_C_DQ<60>")
	)
	(arc
		(start 284.70479 -54.713886)
		(mid 284.758323 -54.913784)
		(end 284.70479 -55.113682)
		(width 0.0889)
		(layer "In11.Cu")
		(net "M_C_DQ<60>")
	)
	(arc
		(start 284.70479 -58.67654)
		(mid 284.758323 -58.876438)
		(end 284.70479 -59.076336)
		(width 0.0889)
		(layer "In11.Cu")
		(net "M_C_DQ<60>")
	)
	(arc
		(start 284.70479 -57.094882)
		(mid 284.625601 -57.381497)
		(end 284.6959 -57.670446)
		(width 0.0889)
		(layer "In11.Cu")
		(net "M_C_DQ<60>")
	)
	(arc
		(start 284.70479 -56.695086)
		(mid 284.758323 -56.894984)
		(end 284.70479 -57.094882)
		(width 0.0889)
		(layer "In11.Cu")
		(net "M_C_DQ<60>")
	)
	(arc
		(start 284.70479 -56.104282)
		(mid 284.625601 -56.390897)
		(end 284.6959 -56.679846)
		(width 0.0889)
		(layer "In11.Cu")
		(net "M_C_DQ<60>")
	)
	(arc
		(start 284.70479 -57.685686)
		(mid 284.758323 -57.885584)
		(end 284.70479 -58.085482)
		(width 0.0889)
		(layer "In11.Cu")
		(net "M_C_DQ<60>")
	)
	(arc
		(start 284.70479 -60.066682)
		(mid 284.625601 -60.353297)
		(end 284.6959 -60.642246)
		(width 0.0889)
		(layer "In11.Cu")
		(net "M_C_DQ<60>")
	)
	(arc
		(start 284.708854 -62.646052)
		(mid 284.917796 -62.969679)
		(end 285.157926 -63.270892)
		(width 0.0889)
		(layer "In11.Cu")
		(net "M_C_DQ<60>")
	)
	(arc
		(start 284.70479 -61.64834)
		(mid 284.758323 -61.848238)
		(end 284.70479 -62.048136)
		(width 0.0889)
		(layer "In11.Cu")
		(net "M_C_DQ<60>")
	)
	(arc
		(start 284.70479 -58.085482)
		(mid 284.625441 -58.374854)
		(end 284.69844 -58.665872)
		(width 0.0889)
		(layer "In11.Cu")
		(net "M_C_DQ<60>")
	)
	(arc
		(start 284.758384 -53.922676)
		(mid 284.744739 -54.026269)
		(end 284.70479 -54.122828)
		(width 0.0889)
		(layer "In11.Cu")
		(net "M_C_DQ<60>")
	)
	(arc
		(start 284.70479 -62.048136)
		(mid 284.625659 -62.343538)
		(end 284.70479 -62.63894)
		(width 0.0889)
		(layer "In11.Cu")
		(net "M_C_DQ<60>")
	)
	(arc
		(start 284.70479 -55.704486)
		(mid 284.758323 -55.904384)
		(end 284.70479 -56.104282)
		(width 0.0889)
		(layer "In11.Cu")
		(net "M_C_DQ<60>")
	)
	(arc
		(start 284.70479 -54.122828)
		(mid 284.625507 -54.40771)
		(end 284.694122 -54.695344)
		(width 0.0889)
		(layer "In11.Cu")
		(net "M_C_DQ<60>")
	)
	(arc
		(start 284.70479 -61.057282)
		(mid 284.6256 -61.352828)
		(end 284.70479 -61.64834)
		(width 0.0889)
		(layer "In11.Cu")
		(net "M_C_DQ<60>")
	)
	(arc
		(start 284.70479 -59.666886)
		(mid 284.758323 -59.866784)
		(end 284.70479 -60.066682)
		(width 0.0889)
		(layer "In11.Cu")
		(net "M_C_DQ<60>")
	)
	(arc
		(start 284.69844 -59.087004)
		(mid 284.625642 -59.377767)
		(end 284.70479 -59.666886)
		(width 0.0889)
		(layer "In11.Cu")
		(net "M_C_DQ<60>")
	)
	(arc
		(start 284.70479 -60.657486)
		(mid 284.758323 -60.857384)
		(end 284.70479 -61.057282)
		(width 0.0889)
		(layer "In11.Cu")
		(net "M_C_DQ<60>")
	)
	(arc
		(start 284.70479 -55.113682)
		(mid 284.625601 -55.400297)
		(end 284.6959 -55.689246)
		(width 0.0889)
		(layer "In11.Cu")
		(net "M_C_DQ<60>")
	)
	(segment
		(start 196.399912 3.778758)
		(end 196.399912 2.514854)
		(width 0.1651)
		(layer "F.Cu")
		(net "M_C_DQ<5>")
	)
	(segment
		(start 243.051838 -66.48704)
		(end 242.480338 -66.48704)
		(width 0.0889)
		(layer "F.Cu")
		(net "M_C_DQ<5>")
	)
	(segment
		(start 196.40042 3.778758)
		(end 196.399912 3.778758)
		(width 0.1651)
		(layer "F.Cu")
		(net "M_C_DQ<5>")
	)
	(via
		(at 196.399912 2.514854)
		(size 0.508)
		(drill 0.254)
		(layers "F.Cu" "B.Cu")
		(net "M_C_DQ<5>")
	)
	(via
		(at 197.173596 -3.076956)
		(size 0.508)
		(drill 0.254)
		(layers "F.Cu" "B.Cu")
		(net "M_C_DQ<5>")
	)
	(via
		(at 242.480338 -66.48704)
		(size 0.508)
		(drill 0.254)
		(layers "F.Cu" "B.Cu")
		(net "M_C_DQ<5>")
	)
	(segment
		(start 197.249796 -1.021842)
		(end 197.249796 -3.000756)
		(width 0.1651)
		(layer "B.Cu")
		(net "M_C_DQ<5>")
	)
	(segment
		(start 197.249796 -3.000756)
		(end 197.173596 -3.076956)
		(width 0.1651)
		(layer "B.Cu")
		(net "M_C_DQ<5>")
	)
	(segment
		(start 197.250304 -1.021842)
		(end 197.249796 -1.021842)
		(width 0.1651)
		(layer "B.Cu")
		(net "M_C_DQ<5>")
	)
	(segment
		(start 197.281546 1.5494)
		(end 196.97065 1.5494)
		(width 0.14224)
		(layer "In11.Cu")
		(net "M_C_DQ<5>")
	)
	(segment
		(start 241.184176 -67.074542)
		(end 241.235992 -66.850006)
		(width 0.0889)
		(layer "In11.Cu")
		(net "M_C_DQ<5>")
	)
	(segment
		(start 197.68185 0.7366)
		(end 197.68185 1.149096)
		(width 0.14224)
		(layer "In11.Cu")
		(net "M_C_DQ<5>")
	)
	(segment
		(start 197.7136 -9.6012)
		(end 197.7136 -11.6078)
		(width 0.14224)
		(layer "In11.Cu")
		(net "M_C_DQ<5>")
	)
	(segment
		(start 196.6976 -3.552952)
		(end 196.6976 -3.969004)
		(width 0.14224)
		(layer "In11.Cu")
		(net "M_C_DQ<5>")
	)
	(segment
		(start 197.647052 -22.225)
		(end 197.647052 -22.95144)
		(width 0.14224)
		(layer "In11.Cu")
		(net "M_C_DQ<5>")
	)
	(segment
		(start 231.133904 -67.08902)
		(end 231.397556 -67.08902)
		(width 0.0889)
		(layer "In11.Cu")
		(net "M_C_DQ<5>")
	)
	(segment
		(start 197.5104 -39.114222)
		(end 201.740516 -43.344338)
		(width 0.14224)
		(layer "In11.Cu")
		(net "M_C_DQ<5>")
	)
	(segment
		(start 197.558152 -21.5646)
		(end 197.638924 -22.165564)
		(width 0.14224)
		(layer "In11.Cu")
		(net "M_C_DQ<5>")
	)
	(segment
		(start 196.968364 -4.239768)
		(end 197.612 -7.151624)
		(width 0.14224)
		(layer "In11.Cu")
		(net "M_C_DQ<5>")
	)
	(segment
		(start 202.322176 -43.344338)
		(end 202.464416 -43.486578)
		(width 0.14224)
		(layer "In11.Cu")
		(net "M_C_DQ<5>")
	)
	(segment
		(start 197.485 -2.765552)
		(end 197.485 0.53975)
		(width 0.14224)
		(layer "In11.Cu")
		(net "M_C_DQ<5>")
	)
	(segment
		(start 197.612 -21.282152)
		(end 197.558152 -21.336)
		(width 0.14224)
		(layer "In11.Cu")
		(net "M_C_DQ<5>")
	)
	(segment
		(start 197.173596 -3.076956)
		(end 197.485 -2.765552)
		(width 0.14224)
		(layer "In11.Cu")
		(net "M_C_DQ<5>")
	)
	(segment
		(start 225.485198 -67.08902)
		(end 231.133904 -67.08902)
		(width 0.14224)
		(layer "In11.Cu")
		(net "M_C_DQ<5>")
	)
	(segment
		(start 197.5104 -23.66264)
		(end 197.5104 -39.114222)
		(width 0.14224)
		(layer "In11.Cu")
		(net "M_C_DQ<5>")
	)
	(segment
		(start 197.647052 -22.95144)
		(end 197.5104 -23.66264)
		(width 0.14224)
		(layer "In11.Cu")
		(net "M_C_DQ<5>")
	)
	(segment
		(start 197.485 0.53975)
		(end 197.68185 0.7366)
		(width 0.14224)
		(layer "In11.Cu")
		(net "M_C_DQ<5>")
	)
	(segment
		(start 197.583552 -13.681456)
		(end 197.583552 -16.4592)
		(width 0.14224)
		(layer "In11.Cu")
		(net "M_C_DQ<5>")
	)
	(segment
		(start 197.6374 -12.351004)
		(end 197.6374 -13.627608)
		(width 0.14224)
		(layer "In11.Cu")
		(net "M_C_DQ<5>")
	)
	(segment
		(start 197.7136 -11.6078)
		(end 197.5866 -11.7348)
		(width 0.14224)
		(layer "In11.Cu")
		(net "M_C_DQ<5>")
	)
	(segment
		(start 197.5866 -11.7348)
		(end 197.5866 -12.300204)
		(width 0.14224)
		(layer "In11.Cu")
		(net "M_C_DQ<5>")
	)
	(segment
		(start 197.558152 -21.336)
		(end 197.558152 -21.5646)
		(width 0.14224)
		(layer "In11.Cu")
		(net "M_C_DQ<5>")
	)
	(segment
		(start 238.172752 -68.372736)
		(end 238.205518 -68.372736)
		(width 0.0889)
		(layer "In11.Cu")
		(net "M_C_DQ<5>")
	)
	(segment
		(start 197.612 -9.4996)
		(end 197.7136 -9.6012)
		(width 0.14224)
		(layer "In11.Cu")
		(net "M_C_DQ<5>")
	)
	(segment
		(start 236.455712 -67.382136)
		(end 236.488478 -67.382136)
		(width 0.0889)
		(layer "In11.Cu")
		(net "M_C_DQ<5>")
	)
	(segment
		(start 197.612 -7.151624)
		(end 197.612 -9.4996)
		(width 0.14224)
		(layer "In11.Cu")
		(net "M_C_DQ<5>")
	)
	(segment
		(start 197.612 -16.800576)
		(end 197.612 -21.282152)
		(width 0.14224)
		(layer "In11.Cu")
		(net "M_C_DQ<5>")
	)
	(segment
		(start 196.6976 -3.969004)
		(end 196.968364 -4.239768)
		(width 0.14224)
		(layer "In11.Cu")
		(net "M_C_DQ<5>")
	)
	(segment
		(start 241.658902 -66.582036)
		(end 242.480338 -66.48704)
		(width 0.0889)
		(layer "In11.Cu")
		(net "M_C_DQ<5>")
	)
	(segment
		(start 235.601002 -66.88709)
		(end 235.633768 -66.88709)
		(width 0.0889)
		(layer "In11.Cu")
		(net "M_C_DQ<5>")
	)
	(segment
		(start 196.399912 2.120138)
		(end 196.399912 2.514854)
		(width 0.14224)
		(layer "In11.Cu")
		(net "M_C_DQ<5>")
	)
	(segment
		(start 239.886998 -68.372736)
		(end 239.919764 -68.372736)
		(width 0.0889)
		(layer "In11.Cu")
		(net "M_C_DQ<5>")
	)
	(segment
		(start 197.638924 -22.165564)
		(end 197.647052 -22.225)
		(width 0.14224)
		(layer "In11.Cu")
		(net "M_C_DQ<5>")
	)
	(segment
		(start 201.740516 -43.344338)
		(end 202.322176 -43.344338)
		(width 0.14224)
		(layer "In11.Cu")
		(net "M_C_DQ<5>")
	)
	(segment
		(start 197.68185 1.149096)
		(end 197.281546 1.5494)
		(width 0.14224)
		(layer "In11.Cu")
		(net "M_C_DQ<5>")
	)
	(segment
		(start 241.235992 -66.850006)
		(end 241.275108 -66.782188)
		(width 0.0889)
		(layer "In11.Cu")
		(net "M_C_DQ<5>")
	)
	(segment
		(start 197.583552 -16.4592)
		(end 197.612 -16.800576)
		(width 0.14224)
		(layer "In11.Cu")
		(net "M_C_DQ<5>")
	)
	(segment
		(start 202.464416 -43.486578)
		(end 202.464416 -44.068238)
		(width 0.14224)
		(layer "In11.Cu")
		(net "M_C_DQ<5>")
	)
	(segment
		(start 197.173596 -3.076956)
		(end 196.6976 -3.552952)
		(width 0.14224)
		(layer "In11.Cu")
		(net "M_C_DQ<5>")
	)
	(segment
		(start 231.397556 -67.08902)
		(end 231.599486 -66.88709)
		(width 0.0889)
		(layer "In11.Cu")
		(net "M_C_DQ<5>")
	)
	(segment
		(start 240.741708 -67.87769)
		(end 240.774474 -67.87769)
		(width 0.0889)
		(layer "In11.Cu")
		(net "M_C_DQ<5>")
	)
	(segment
		(start 233.018838 -66.391536)
		(end 233.054398 -66.391536)
		(width 0.0889)
		(layer "In11.Cu")
		(net "M_C_DQ<5>")
	)
	(segment
		(start 241.610642 -66.582036)
		(end 241.658902 -66.582036)
		(width 0.0889)
		(layer "In11.Cu")
		(net "M_C_DQ<5>")
	)
	(segment
		(start 197.6374 -13.627608)
		(end 197.583552 -13.681456)
		(width 0.14224)
		(layer "In11.Cu")
		(net "M_C_DQ<5>")
	)
	(segment
		(start 231.599486 -66.88709)
		(end 232.189274 -66.88709)
		(width 0.0889)
		(layer "In11.Cu")
		(net "M_C_DQ<5>")
	)
	(segment
		(start 196.97065 1.5494)
		(end 196.399912 2.120138)
		(width 0.14224)
		(layer "In11.Cu")
		(net "M_C_DQ<5>")
	)
	(segment
		(start 237.318042 -67.87769)
		(end 237.350808 -67.87769)
		(width 0.0889)
		(layer "In11.Cu")
		(net "M_C_DQ<5>")
	)
	(segment
		(start 241.16284 -67.454018)
		(end 241.184176 -67.074542)
		(width 0.0889)
		(layer "In11.Cu")
		(net "M_C_DQ<5>")
	)
	(segment
		(start 234.735878 -66.391536)
		(end 234.771438 -66.391536)
		(width 0.0889)
		(layer "In11.Cu")
		(net "M_C_DQ<5>")
	)
	(segment
		(start 197.5866 -12.300204)
		(end 197.6374 -12.351004)
		(width 0.14224)
		(layer "In11.Cu")
		(net "M_C_DQ<5>")
	)
	(segment
		(start 202.464416 -44.068238)
		(end 225.485198 -67.08902)
		(width 0.14224)
		(layer "In11.Cu")
		(net "M_C_DQ<5>")
	)
	(arc
		(start 237.350808 -67.87769)
		(mid 237.634025 -67.961971)
		(end 237.841028 -68.172838)
		(width 0.0889)
		(layer "In11.Cu")
		(net "M_C_DQ<5>")
	)
	(arc
		(start 240.774474 -67.87769)
		(mid 241.058323 -67.748057)
		(end 241.16284 -67.454018)
		(width 0.0889)
		(layer "In11.Cu")
		(net "M_C_DQ<5>")
	)
	(arc
		(start 233.054398 -66.391536)
		(mid 233.339822 -66.475003)
		(end 233.548428 -66.686938)
		(width 0.0889)
		(layer "In11.Cu")
		(net "M_C_DQ<5>")
	)
	(arc
		(start 240.251488 -68.172838)
		(mid 240.458492 -67.961974)
		(end 240.741708 -67.87769)
		(width 0.0889)
		(layer "In11.Cu")
		(net "M_C_DQ<5>")
	)
	(arc
		(start 238.699548 -68.668138)
		(mid 239.046258 -68.868449)
		(end 239.392968 -68.668138)
		(width 0.0889)
		(layer "In11.Cu")
		(net "M_C_DQ<5>")
	)
	(arc
		(start 236.488478 -67.382136)
		(mid 236.773902 -67.465603)
		(end 236.982508 -67.677538)
		(width 0.0889)
		(layer "In11.Cu")
		(net "M_C_DQ<5>")
	)
	(arc
		(start 235.633768 -66.88709)
		(mid 235.916985 -66.971371)
		(end 236.123988 -67.182238)
		(width 0.0889)
		(layer "In11.Cu")
		(net "M_C_DQ<5>")
	)
	(arc
		(start 239.919764 -68.372736)
		(mid 240.111406 -68.31557)
		(end 240.251488 -68.172838)
		(width 0.0889)
		(layer "In11.Cu")
		(net "M_C_DQ<5>")
	)
	(arc
		(start 234.771438 -66.391536)
		(mid 235.056862 -66.475003)
		(end 235.265468 -66.686938)
		(width 0.0889)
		(layer "In11.Cu")
		(net "M_C_DQ<5>")
	)
	(arc
		(start 232.189274 -66.88709)
		(mid 232.383124 -66.83074)
		(end 232.524808 -66.686938)
		(width 0.0889)
		(layer "In11.Cu")
		(net "M_C_DQ<5>")
	)
	(arc
		(start 238.205518 -68.372736)
		(mid 238.490942 -68.456203)
		(end 238.699548 -68.668138)
		(width 0.0889)
		(layer "In11.Cu")
		(net "M_C_DQ<5>")
	)
	(arc
		(start 237.841028 -68.172838)
		(mid 237.981107 -68.315574)
		(end 238.172752 -68.372736)
		(width 0.0889)
		(layer "In11.Cu")
		(net "M_C_DQ<5>")
	)
	(arc
		(start 239.392968 -68.668138)
		(mid 239.601576 -68.456206)
		(end 239.886998 -68.372736)
		(width 0.0889)
		(layer "In11.Cu")
		(net "M_C_DQ<5>")
	)
	(arc
		(start 236.982508 -67.677538)
		(mid 237.124191 -67.821342)
		(end 237.318042 -67.87769)
		(width 0.0889)
		(layer "In11.Cu")
		(net "M_C_DQ<5>")
	)
	(arc
		(start 236.123988 -67.182238)
		(mid 236.264067 -67.324974)
		(end 236.455712 -67.382136)
		(width 0.0889)
		(layer "In11.Cu")
		(net "M_C_DQ<5>")
	)
	(arc
		(start 241.275108 -66.782188)
		(mid 241.416791 -66.638384)
		(end 241.610642 -66.582036)
		(width 0.0889)
		(layer "In11.Cu")
		(net "M_C_DQ<5>")
	)
	(arc
		(start 235.265468 -66.686938)
		(mid 235.407151 -66.830742)
		(end 235.601002 -66.88709)
		(width 0.0889)
		(layer "In11.Cu")
		(net "M_C_DQ<5>")
	)
	(arc
		(start 234.241848 -66.686938)
		(mid 234.450456 -66.475006)
		(end 234.735878 -66.391536)
		(width 0.0889)
		(layer "In11.Cu")
		(net "M_C_DQ<5>")
	)
	(arc
		(start 233.548428 -66.686938)
		(mid 233.895138 -66.887249)
		(end 234.241848 -66.686938)
		(width 0.0889)
		(layer "In11.Cu")
		(net "M_C_DQ<5>")
	)
	(arc
		(start 232.524808 -66.686938)
		(mid 232.733416 -66.475006)
		(end 233.018838 -66.391536)
		(width 0.0889)
		(layer "In11.Cu")
		(net "M_C_DQ<5>")
	)
	(segment
		(start 315.400436 3.778758)
		(end 315.399928 3.778758)
		(width 0.1651)
		(layer "F.Cu")
		(net "M_C_DQ<59>")
	)
	(segment
		(start 289.22218 -64.324738)
		(end 288.65068 -64.324738)
		(width 0.0889)
		(layer "F.Cu")
		(net "M_C_DQ<59>")
	)
	(segment
		(start 315.399928 3.778758)
		(end 315.399928 2.514854)
		(width 0.1651)
		(layer "F.Cu")
		(net "M_C_DQ<59>")
	)
	(via
		(at 288.65068 -64.324738)
		(size 0.508)
		(drill 0.254)
		(layers "F.Cu" "B.Cu")
		(net "M_C_DQ<59>")
	)
	(via
		(at 315.399928 2.514854)
		(size 0.508)
		(drill 0.254)
		(layers "F.Cu" "B.Cu")
		(net "M_C_DQ<59>")
	)
	(via
		(at 316.249812 -3.076956)
		(size 0.508)
		(drill 0.254)
		(layers "F.Cu" "B.Cu")
		(net "M_C_DQ<59>")
	)
	(segment
		(start 316.25032 -1.021842)
		(end 316.249812 -1.021842)
		(width 0.1651)
		(layer "B.Cu")
		(net "M_C_DQ<59>")
	)
	(segment
		(start 316.249812 -1.021842)
		(end 316.249812 -3.076956)
		(width 0.1651)
		(layer "B.Cu")
		(net "M_C_DQ<59>")
	)
	(segment
		(start 317.0936 -30.1244)
		(end 317.0936 -24.257)
		(width 0.14224)
		(layer "In11.Cu")
		(net "M_C_DQ<59>")
	)
	(segment
		(start 316.782196 -23.183596)
		(end 316.782196 -21.999956)
		(width 0.14224)
		(layer "In11.Cu")
		(net "M_C_DQ<59>")
	)
	(segment
		(start 300.7868 -45.339)
		(end 301.879 -45.339)
		(width 0.14224)
		(layer "In11.Cu")
		(net "M_C_DQ<59>")
	)
	(segment
		(start 288.65068 -64.324738)
		(end 288.94151 -63.9064)
		(width 0.0889)
		(layer "In11.Cu")
		(net "M_C_DQ<59>")
	)
	(segment
		(start 316.249812 -3.076956)
		(end 316.602618 -2.72415)
		(width 0.14224)
		(layer "In11.Cu")
		(net "M_C_DQ<59>")
	)
	(segment
		(start 316.756796 -8.795258)
		(end 316.756796 -7.429246)
		(width 0.14224)
		(layer "In11.Cu")
		(net "M_C_DQ<59>")
	)
	(segment
		(start 316.758066 0.7366)
		(end 316.758066 1.0922)
		(width 0.14224)
		(layer "In11.Cu")
		(net "M_C_DQ<59>")
	)
	(segment
		(start 316.738 -21.227796)
		(end 316.738 -19.1516)
		(width 0.14224)
		(layer "In11.Cu")
		(net "M_C_DQ<59>")
	)
	(segment
		(start 316.8142 -9.582404)
		(end 316.604396 -9.3726)
		(width 0.14224)
		(layer "In11.Cu")
		(net "M_C_DQ<59>")
	)
	(segment
		(start 301.879 -45.339)
		(end 317.0936 -30.1244)
		(width 0.14224)
		(layer "In11.Cu")
		(net "M_C_DQ<59>")
	)
	(segment
		(start 295.2496 -50.8762)
		(end 300.7868 -45.339)
		(width 0.14224)
		(layer "In11.Cu")
		(net "M_C_DQ<59>")
	)
	(segment
		(start 316.046866 1.5494)
		(end 315.716666 1.8796)
		(width 0.14224)
		(layer "In11.Cu")
		(net "M_C_DQ<59>")
	)
	(segment
		(start 316.617096 -7.289546)
		(end 316.617096 -4.816856)
		(width 0.14224)
		(layer "In11.Cu")
		(net "M_C_DQ<59>")
	)
	(segment
		(start 316.604396 -9.3726)
		(end 316.604396 -8.947658)
		(width 0.14224)
		(layer "In11.Cu")
		(net "M_C_DQ<59>")
	)
	(segment
		(start 292.1508 -50.8762)
		(end 295.2496 -50.8762)
		(width 0.14224)
		(layer "In11.Cu")
		(net "M_C_DQ<59>")
	)
	(segment
		(start 316.604396 -11.741404)
		(end 316.8142 -11.5316)
		(width 0.14224)
		(layer "In11.Cu")
		(net "M_C_DQ<59>")
	)
	(segment
		(start 289.157664 -54.722522)
		(end 289.16249 -54.713886)
		(width 0.0889)
		(layer "In11.Cu")
		(net "M_C_DQ<59>")
	)
	(segment
		(start 289.16249 -55.704486)
		(end 289.16884 -55.693818)
		(width 0.0889)
		(layer "In11.Cu")
		(net "M_C_DQ<59>")
	)
	(segment
		(start 290.83 -52.197)
		(end 292.1508 -50.8762)
		(width 0.14224)
		(layer "In11.Cu")
		(net "M_C_DQ<59>")
	)
	(segment
		(start 316.8142 -11.5316)
		(end 316.8142 -9.582404)
		(width 0.14224)
		(layer "In11.Cu")
		(net "M_C_DQ<59>")
	)
	(segment
		(start 289.1536 -61.74359)
		(end 289.191954 -61.666374)
		(width 0.0889)
		(layer "In11.Cu")
		(net "M_C_DQ<59>")
	)
	(segment
		(start 317.0936 -24.257)
		(end 316.629796 -23.793196)
		(width 0.14224)
		(layer "In11.Cu")
		(net "M_C_DQ<59>")
	)
	(segment
		(start 316.604396 -8.947658)
		(end 316.756796 -8.795258)
		(width 0.14224)
		(layer "In11.Cu")
		(net "M_C_DQ<59>")
	)
	(segment
		(start 289.350704 -53.4416)
		(end 290.595304 -52.197)
		(width 0.0889)
		(layer "In11.Cu")
		(net "M_C_DQ<59>")
	)
	(segment
		(start 316.617096 -16.890746)
		(end 316.617096 -13.681456)
		(width 0.14224)
		(layer "In11.Cu")
		(net "M_C_DQ<59>")
	)
	(segment
		(start 289.157664 -56.703722)
		(end 289.16249 -56.695086)
		(width 0.0889)
		(layer "In11.Cu")
		(net "M_C_DQ<59>")
	)
	(segment
		(start 289.157664 -57.694322)
		(end 289.16249 -57.685686)
		(width 0.0889)
		(layer "In11.Cu")
		(net "M_C_DQ<59>")
	)
	(segment
		(start 289.157664 -59.675522)
		(end 289.16249 -59.666886)
		(width 0.0889)
		(layer "In11.Cu")
		(net "M_C_DQ<59>")
	)
	(segment
		(start 316.629796 -23.335996)
		(end 316.782196 -23.183596)
		(width 0.14224)
		(layer "In11.Cu")
		(net "M_C_DQ<59>")
	)
	(segment
		(start 289.16249 -54.713886)
		(end 289.16884 -54.703218)
		(width 0.0889)
		(layer "In11.Cu")
		(net "M_C_DQ<59>")
	)
	(segment
		(start 316.738 -19.1516)
		(end 316.604396 -19.017996)
		(width 0.14224)
		(layer "In11.Cu")
		(net "M_C_DQ<59>")
	)
	(segment
		(start 316.300866 1.5494)
		(end 316.046866 1.5494)
		(width 0.14224)
		(layer "In11.Cu")
		(net "M_C_DQ<59>")
	)
	(segment
		(start 315.716666 1.8796)
		(end 315.716666 2.198116)
		(width 0.14224)
		(layer "In11.Cu")
		(net "M_C_DQ<59>")
	)
	(segment
		(start 315.716666 2.198116)
		(end 315.399928 2.514854)
		(width 0.14224)
		(layer "In11.Cu")
		(net "M_C_DQ<59>")
	)
	(segment
		(start 316.758066 1.0922)
		(end 316.300866 1.5494)
		(width 0.14224)
		(layer "In11.Cu")
		(net "M_C_DQ<59>")
	)
	(segment
		(start 289.16249 -57.685686)
		(end 289.16884 -57.675018)
		(width 0.0889)
		(layer "In11.Cu")
		(net "M_C_DQ<59>")
	)
	(segment
		(start 316.782196 -12.354052)
		(end 316.604396 -12.176252)
		(width 0.14224)
		(layer "In11.Cu")
		(net "M_C_DQ<59>")
	)
	(segment
		(start 289.16249 -60.657486)
		(end 289.16884 -60.646818)
		(width 0.0889)
		(layer "In11.Cu")
		(net "M_C_DQ<59>")
	)
	(segment
		(start 316.756796 -18.421858)
		(end 316.756796 -17.030446)
		(width 0.14224)
		(layer "In11.Cu")
		(net "M_C_DQ<59>")
	)
	(segment
		(start 289.350704 -53.63337)
		(end 289.350704 -53.4416)
		(width 0.0889)
		(layer "In11.Cu")
		(net "M_C_DQ<59>")
	)
	(segment
		(start 290.595304 -52.197)
		(end 290.83 -52.197)
		(width 0.0889)
		(layer "In11.Cu")
		(net "M_C_DQ<59>")
	)
	(segment
		(start 289.05073 -63.749174)
		(end 289.116262 -63.683642)
		(width 0.0889)
		(layer "In11.Cu")
		(net "M_C_DQ<59>")
	)
	(segment
		(start 316.782196 -21.999956)
		(end 316.604396 -21.822156)
		(width 0.14224)
		(layer "In11.Cu")
		(net "M_C_DQ<59>")
	)
	(segment
		(start 316.604396 -21.3614)
		(end 316.738 -21.227796)
		(width 0.14224)
		(layer "In11.Cu")
		(net "M_C_DQ<59>")
	)
	(segment
		(start 289.165792 -62.65291)
		(end 289.172904 -62.640972)
		(width 0.0889)
		(layer "In11.Cu")
		(net "M_C_DQ<59>")
	)
	(segment
		(start 316.604396 -19.017996)
		(end 316.604396 -18.574258)
		(width 0.14224)
		(layer "In11.Cu")
		(net "M_C_DQ<59>")
	)
	(segment
		(start 315.766196 -3.965956)
		(end 315.766196 -3.560572)
		(width 0.14224)
		(layer "In11.Cu")
		(net "M_C_DQ<59>")
	)
	(segment
		(start 316.782196 -13.516356)
		(end 316.782196 -12.354052)
		(width 0.14224)
		(layer "In11.Cu")
		(net "M_C_DQ<59>")
	)
	(segment
		(start 316.604396 -21.822156)
		(end 316.604396 -21.3614)
		(width 0.14224)
		(layer "In11.Cu")
		(net "M_C_DQ<59>")
	)
	(segment
		(start 316.602618 -2.72415)
		(end 316.602618 0.581152)
		(width 0.14224)
		(layer "In11.Cu")
		(net "M_C_DQ<59>")
	)
	(segment
		(start 316.617096 -13.681456)
		(end 316.782196 -13.516356)
		(width 0.14224)
		(layer "In11.Cu")
		(net "M_C_DQ<59>")
	)
	(segment
		(start 289.157664 -55.713122)
		(end 289.16249 -55.704486)
		(width 0.0889)
		(layer "In11.Cu")
		(net "M_C_DQ<59>")
	)
	(segment
		(start 289.16884 -59.087004)
		(end 289.16249 -59.076336)
		(width 0.0889)
		(layer "In11.Cu")
		(net "M_C_DQ<59>")
	)
	(segment
		(start 316.602618 0.581152)
		(end 316.758066 0.7366)
		(width 0.14224)
		(layer "In11.Cu")
		(net "M_C_DQ<59>")
	)
	(segment
		(start 288.94151 -63.9064)
		(end 289.05073 -63.749174)
		(width 0.0889)
		(layer "In11.Cu")
		(net "M_C_DQ<59>")
	)
	(segment
		(start 289.172904 -62.051692)
		(end 289.16249 -62.033658)
		(width 0.0889)
		(layer "In11.Cu")
		(net "M_C_DQ<59>")
	)
	(segment
		(start 316.604396 -12.176252)
		(end 316.604396 -11.741404)
		(width 0.14224)
		(layer "In11.Cu")
		(net "M_C_DQ<59>")
	)
	(segment
		(start 316.756796 -7.429246)
		(end 316.617096 -7.289546)
		(width 0.14224)
		(layer "In11.Cu")
		(net "M_C_DQ<59>")
	)
	(segment
		(start 289.112198 -53.871876)
		(end 289.350704 -53.63337)
		(width 0.0889)
		(layer "In11.Cu")
		(net "M_C_DQ<59>")
	)
	(segment
		(start 316.604396 -18.574258)
		(end 316.756796 -18.421858)
		(width 0.14224)
		(layer "In11.Cu")
		(net "M_C_DQ<59>")
	)
	(segment
		(start 315.766196 -3.560572)
		(end 316.249812 -3.076956)
		(width 0.14224)
		(layer "In11.Cu")
		(net "M_C_DQ<59>")
	)
	(segment
		(start 289.173412 -61.019182)
		(end 289.164522 -61.003688)
		(width 0.0889)
		(layer "In11.Cu")
		(net "M_C_DQ<59>")
	)
	(segment
		(start 316.756796 -17.030446)
		(end 316.617096 -16.890746)
		(width 0.14224)
		(layer "In11.Cu")
		(net "M_C_DQ<59>")
	)
	(segment
		(start 316.629796 -23.793196)
		(end 316.629796 -23.335996)
		(width 0.14224)
		(layer "In11.Cu")
		(net "M_C_DQ<59>")
	)
	(segment
		(start 289.16249 -56.695086)
		(end 289.16884 -56.684418)
		(width 0.0889)
		(layer "In11.Cu")
		(net "M_C_DQ<59>")
	)
	(segment
		(start 316.617096 -4.816856)
		(end 315.766196 -3.965956)
		(width 0.14224)
		(layer "In11.Cu")
		(net "M_C_DQ<59>")
	)
	(arc
		(start 289.16249 -59.666886)
		(mid 289.241712 -59.377768)
		(end 289.16884 -59.087004)
		(width 0.0889)
		(layer "In11.Cu")
		(net "M_C_DQ<59>")
	)
	(arc
		(start 289.16249 -56.104536)
		(mid 289.10902 -55.909473)
		(end 289.157664 -55.713122)
		(width 0.0889)
		(layer "In11.Cu")
		(net "M_C_DQ<59>")
	)
	(arc
		(start 289.16884 -54.703218)
		(mid 289.241638 -54.412455)
		(end 289.16249 -54.123336)
		(width 0.0889)
		(layer "In11.Cu")
		(net "M_C_DQ<59>")
	)
	(arc
		(start 289.16249 -59.076336)
		(mid 289.108991 -58.876438)
		(end 289.16249 -58.67654)
		(width 0.0889)
		(layer "In11.Cu")
		(net "M_C_DQ<59>")
	)
	(arc
		(start 289.16884 -60.646818)
		(mid 289.241638 -60.356055)
		(end 289.16249 -60.066936)
		(width 0.0889)
		(layer "In11.Cu")
		(net "M_C_DQ<59>")
	)
	(arc
		(start 289.116262 -63.683642)
		(mid 289.240205 -63.361014)
		(end 289.16249 -63.024258)
		(width 0.0889)
		(layer "In11.Cu")
		(net "M_C_DQ<59>")
	)
	(arc
		(start 289.164522 -61.003688)
		(mid 289.117826 -60.830841)
		(end 289.16249 -60.657486)
		(width 0.0889)
		(layer "In11.Cu")
		(net "M_C_DQ<59>")
	)
	(arc
		(start 289.16249 -54.123336)
		(mid 289.116648 -54.001743)
		(end 289.112198 -53.871876)
		(width 0.0889)
		(layer "In11.Cu")
		(net "M_C_DQ<59>")
	)
	(arc
		(start 289.191954 -61.666374)
		(mid 289.263694 -61.340446)
		(end 289.173412 -61.019182)
		(width 0.0889)
		(layer "In11.Cu")
		(net "M_C_DQ<59>")
	)
	(arc
		(start 289.16884 -56.684418)
		(mid 289.241638 -56.393655)
		(end 289.16249 -56.104536)
		(width 0.0889)
		(layer "In11.Cu")
		(net "M_C_DQ<59>")
	)
	(arc
		(start 289.16249 -55.113936)
		(mid 289.10902 -54.918873)
		(end 289.157664 -54.722522)
		(width 0.0889)
		(layer "In11.Cu")
		(net "M_C_DQ<59>")
	)
	(arc
		(start 289.16884 -55.693818)
		(mid 289.241638 -55.403055)
		(end 289.16249 -55.113936)
		(width 0.0889)
		(layer "In11.Cu")
		(net "M_C_DQ<59>")
	)
	(arc
		(start 289.16884 -57.675018)
		(mid 289.241638 -57.384255)
		(end 289.16249 -57.095136)
		(width 0.0889)
		(layer "In11.Cu")
		(net "M_C_DQ<59>")
	)
	(arc
		(start 289.16249 -58.67654)
		(mid 289.241621 -58.381138)
		(end 289.16249 -58.085736)
		(width 0.0889)
		(layer "In11.Cu")
		(net "M_C_DQ<59>")
	)
	(arc
		(start 289.16249 -63.024258)
		(mid 289.113567 -62.838133)
		(end 289.165792 -62.65291)
		(width 0.0889)
		(layer "In11.Cu")
		(net "M_C_DQ<59>")
	)
	(arc
		(start 289.172904 -62.640972)
		(mid 289.251825 -62.346332)
		(end 289.172904 -62.051692)
		(width 0.0889)
		(layer "In11.Cu")
		(net "M_C_DQ<59>")
	)
	(arc
		(start 289.16249 -57.095136)
		(mid 289.10902 -56.900073)
		(end 289.157664 -56.703722)
		(width 0.0889)
		(layer "In11.Cu")
		(net "M_C_DQ<59>")
	)
	(arc
		(start 289.16249 -60.066936)
		(mid 289.10902 -59.871873)
		(end 289.157664 -59.675522)
		(width 0.0889)
		(layer "In11.Cu")
		(net "M_C_DQ<59>")
	)
	(arc
		(start 289.16249 -58.085736)
		(mid 289.10902 -57.890673)
		(end 289.157664 -57.694322)
		(width 0.0889)
		(layer "In11.Cu")
		(net "M_C_DQ<59>")
	)
	(arc
		(start 289.16249 -62.033658)
		(mid 289.121591 -61.889731)
		(end 289.1536 -61.74359)
		(width 0.0889)
		(layer "In11.Cu")
		(net "M_C_DQ<59>")
	)
	(segment
		(start 316.25032 -0.821182)
		(end 316.249812 -0.821182)
		(width 0.1651)
		(layer "F.Cu")
		(net "M_C_DQ<58>")
	)
	(segment
		(start 316.249812 0.662432)
		(end 316.249812 0.9398)
		(width 0.1651)
		(layer "F.Cu")
		(net "M_C_DQ<58>")
	)
	(segment
		(start 289.22218 -63.334138)
		(end 288.65068 -63.334138)
		(width 0.0889)
		(layer "F.Cu")
		(net "M_C_DQ<58>")
	)
	(segment
		(start 316.249812 0.175768)
		(end 316.381384 0.30734)
		(width 0.1651)
		(layer "F.Cu")
		(net "M_C_DQ<58>")
	)
	(segment
		(start 316.381384 0.30734)
		(end 316.381384 0.53086)
		(width 0.1651)
		(layer "F.Cu")
		(net "M_C_DQ<58>")
	)
	(segment
		(start 316.381384 0.53086)
		(end 316.249812 0.662432)
		(width 0.1651)
		(layer "F.Cu")
		(net "M_C_DQ<58>")
	)
	(segment
		(start 316.249812 -0.821182)
		(end 316.249812 0.175768)
		(width 0.1651)
		(layer "F.Cu")
		(net "M_C_DQ<58>")
	)
	(via
		(at 316.249812 0.9398)
		(size 0.508)
		(drill 0.254)
		(layers "F.Cu" "B.Cu")
		(net "M_C_DQ<58>")
	)
	(via
		(at 315.399928 -4.357878)
		(size 0.508)
		(drill 0.254)
		(layers "F.Cu" "B.Cu")
		(net "M_C_DQ<58>")
	)
	(via
		(at 288.65068 -63.334138)
		(size 0.508)
		(drill 0.254)
		(layers "F.Cu" "B.Cu")
		(net "M_C_DQ<58>")
	)
	(segment
		(start 315.399928 -5.621782)
		(end 315.399928 -4.357878)
		(width 0.1651)
		(layer "B.Cu")
		(net "M_C_DQ<58>")
	)
	(segment
		(start 315.400436 -5.621782)
		(end 315.399928 -5.621782)
		(width 0.1651)
		(layer "B.Cu")
		(net "M_C_DQ<58>")
	)
	(segment
		(start 315.115194 -4.073144)
		(end 315.115194 -3.3274)
		(width 0.14224)
		(layer "In11.Cu")
		(net "M_C_DQ<58>")
	)
	(segment
		(start 290.3982 -52.12461)
		(end 290.3982 -51.943)
		(width 0.0889)
		(layer "In11.Cu")
		(net "M_C_DQ<58>")
	)
	(segment
		(start 300.576996 -44.736004)
		(end 301.592996 -44.736004)
		(width 0.14224)
		(layer "In11.Cu")
		(net "M_C_DQ<58>")
	)
	(segment
		(start 315.740796 -23.174452)
		(end 315.740796 -21.949156)
		(width 0.14224)
		(layer "In11.Cu")
		(net "M_C_DQ<58>")
	)
	(segment
		(start 289.160204 -53.362606)
		(end 290.3982 -52.12461)
		(width 0.0889)
		(layer "In11.Cu")
		(net "M_C_DQ<58>")
	)
	(segment
		(start 316.3824 -26.64079)
		(end 316.3824 -26.27503)
		(width 0.14224)
		(layer "In11.Cu")
		(net "M_C_DQ<58>")
	)
	(segment
		(start 315.7474 -26.92527)
		(end 315.88964 -26.78303)
		(width 0.14224)
		(layer "In11.Cu")
		(net "M_C_DQ<58>")
	)
	(segment
		(start 315.964062 -2.478532)
		(end 315.964062 -2.2098)
		(width 0.14224)
		(layer "In11.Cu")
		(net "M_C_DQ<58>")
	)
	(segment
		(start 315.766196 -18.45945)
		(end 315.766196 -17.03705)
		(width 0.14224)
		(layer "In11.Cu")
		(net "M_C_DQ<58>")
	)
	(segment
		(start 315.740796 -21.949156)
		(end 315.893196 -21.796756)
		(width 0.14224)
		(layer "In11.Cu")
		(net "M_C_DQ<58>")
	)
	(segment
		(start 315.994796 -23.428452)
		(end 315.740796 -23.174452)
		(width 0.14224)
		(layer "In11.Cu")
		(net "M_C_DQ<58>")
	)
	(segment
		(start 290.3982 -51.943)
		(end 292.0746 -50.2666)
		(width 0.14224)
		(layer "In11.Cu")
		(net "M_C_DQ<58>")
	)
	(segment
		(start 315.506862 -1.35255)
		(end 315.811662 -1.04775)
		(width 0.14224)
		(layer "In11.Cu")
		(net "M_C_DQ<58>")
	)
	(segment
		(start 315.964062 -2.2098)
		(end 315.506862 -1.7526)
		(width 0.14224)
		(layer "In11.Cu")
		(net "M_C_DQ<58>")
	)
	(segment
		(start 288.99739 -58.581036)
		(end 289.002216 -58.5724)
		(width 0.0889)
		(layer "In11.Cu")
		(net "M_C_DQ<58>")
	)
	(segment
		(start 288.942272 -53.756052)
		(end 289.160204 -53.53812)
		(width 0.0889)
		(layer "In11.Cu")
		(net "M_C_DQ<58>")
	)
	(segment
		(start 315.506862 -1.7526)
		(end 315.506862 -1.35255)
		(width 0.14224)
		(layer "In11.Cu")
		(net "M_C_DQ<58>")
	)
	(segment
		(start 301.592996 -44.736004)
		(end 315.7474 -30.5816)
		(width 0.14224)
		(layer "In11.Cu")
		(net "M_C_DQ<58>")
	)
	(segment
		(start 288.99104 -56.610504)
		(end 288.99739 -56.599836)
		(width 0.0889)
		(layer "In11.Cu")
		(net "M_C_DQ<58>")
	)
	(segment
		(start 288.99739 -60.562236)
		(end 289.002216 -60.5536)
		(width 0.0889)
		(layer "In11.Cu")
		(net "M_C_DQ<58>")
	)
	(segment
		(start 315.7474 -25.62479)
		(end 315.88964 -25.48255)
		(width 0.14224)
		(layer "In11.Cu")
		(net "M_C_DQ<58>")
	)
	(segment
		(start 315.766196 -8.80745)
		(end 315.766196 -7.365746)
		(width 0.14224)
		(layer "In11.Cu")
		(net "M_C_DQ<58>")
	)
	(segment
		(start 315.88964 -26.78303)
		(end 316.24016 -26.78303)
		(width 0.14224)
		(layer "In11.Cu")
		(net "M_C_DQ<58>")
	)
	(segment
		(start 316.24016 -26.78303)
		(end 316.3824 -26.64079)
		(width 0.14224)
		(layer "In11.Cu")
		(net "M_C_DQ<58>")
	)
	(segment
		(start 316.24016 -28.08351)
		(end 316.3824 -27.94127)
		(width 0.14224)
		(layer "In11.Cu")
		(net "M_C_DQ<58>")
	)
	(segment
		(start 316.3824 -24.97455)
		(end 316.24016 -24.83231)
		(width 0.14224)
		(layer "In11.Cu")
		(net "M_C_DQ<58>")
	)
	(segment
		(start 315.7474 -24.269192)
		(end 315.994796 -24.021796)
		(width 0.14224)
		(layer "In11.Cu")
		(net "M_C_DQ<58>")
	)
	(segment
		(start 288.99739 -57.590436)
		(end 289.002216 -57.5818)
		(width 0.0889)
		(layer "In11.Cu")
		(net "M_C_DQ<58>")
	)
	(segment
		(start 315.811662 -1.04775)
		(end 315.811662 -0.761746)
		(width 0.14224)
		(layer "In11.Cu")
		(net "M_C_DQ<58>")
	)
	(segment
		(start 288.99739 -59.171586)
		(end 288.99104 -59.160918)
		(width 0.0889)
		(layer "In11.Cu")
		(net "M_C_DQ<58>")
	)
	(segment
		(start 315.811662 -0.761746)
		(end 315.506862 -0.456946)
		(width 0.14224)
		(layer "In11.Cu")
		(net "M_C_DQ<58>")
	)
	(segment
		(start 315.506862 -0.456946)
		(end 315.506862 -0.108204)
		(width 0.14224)
		(layer "In11.Cu")
		(net "M_C_DQ<58>")
	)
	(segment
		(start 288.99104 -55.619904)
		(end 288.99739 -55.609236)
		(width 0.0889)
		(layer "In11.Cu")
		(net "M_C_DQ<58>")
	)
	(segment
		(start 316.3824 -26.27503)
		(end 316.24016 -26.13279)
		(width 0.14224)
		(layer "In11.Cu")
		(net "M_C_DQ<58>")
	)
	(segment
		(start 315.740796 -12.286996)
		(end 315.893196 -12.134596)
		(width 0.14224)
		(layer "In11.Cu")
		(net "M_C_DQ<58>")
	)
	(segment
		(start 316.3824 -27.57551)
		(end 316.24016 -27.43327)
		(width 0.14224)
		(layer "In11.Cu")
		(net "M_C_DQ<58>")
	)
	(segment
		(start 292.0746 -50.2666)
		(end 295.0464 -50.2666)
		(width 0.14224)
		(layer "In11.Cu")
		(net "M_C_DQ<58>")
	)
	(segment
		(start 316.24016 -27.43327)
		(end 315.88964 -27.43327)
		(width 0.14224)
		(layer "In11.Cu")
		(net "M_C_DQ<58>")
	)
	(segment
		(start 315.893196 -12.134596)
		(end 315.893196 -11.728196)
		(width 0.14224)
		(layer "In11.Cu")
		(net "M_C_DQ<58>")
	)
	(segment
		(start 315.851794 0.541782)
		(end 316.249812 0.9398)
		(width 0.14224)
		(layer "In11.Cu")
		(net "M_C_DQ<58>")
	)
	(segment
		(start 315.893196 -9.4234)
		(end 315.893196 -8.93445)
		(width 0.14224)
		(layer "In11.Cu")
		(net "M_C_DQ<58>")
	)
	(segment
		(start 315.7474 -24.69007)
		(end 315.7474 -24.269192)
		(width 0.14224)
		(layer "In11.Cu")
		(net "M_C_DQ<58>")
	)
	(segment
		(start 315.851794 0.236728)
		(end 315.851794 0.541782)
		(width 0.14224)
		(layer "In11.Cu")
		(net "M_C_DQ<58>")
	)
	(segment
		(start 315.969396 -7.162546)
		(end 315.969396 -4.927346)
		(width 0.14224)
		(layer "In11.Cu")
		(net "M_C_DQ<58>")
	)
	(segment
		(start 288.99104 -54.629304)
		(end 288.99739 -54.618636)
		(width 0.0889)
		(layer "In11.Cu")
		(net "M_C_DQ<58>")
	)
	(segment
		(start 295.0464 -50.2666)
		(end 300.576996 -44.736004)
		(width 0.14224)
		(layer "In11.Cu")
		(net "M_C_DQ<58>")
	)
	(segment
		(start 315.969396 -4.927346)
		(end 315.399928 -4.357878)
		(width 0.14224)
		(layer "In11.Cu")
		(net "M_C_DQ<58>")
	)
	(segment
		(start 288.65068 -63.334138)
		(end 288.943796 -63.164974)
		(width 0.0889)
		(layer "In11.Cu")
		(net "M_C_DQ<58>")
	)
	(segment
		(start 288.943796 -63.164974)
		(end 288.967672 -63.075566)
		(width 0.0889)
		(layer "In11.Cu")
		(net "M_C_DQ<58>")
	)
	(segment
		(start 315.399928 -4.357878)
		(end 315.115194 -4.073144)
		(width 0.14224)
		(layer "In11.Cu")
		(net "M_C_DQ<58>")
	)
	(segment
		(start 315.893196 -11.728196)
		(end 315.7728 -11.6078)
		(width 0.14224)
		(layer "In11.Cu")
		(net "M_C_DQ<58>")
	)
	(segment
		(start 315.115194 -3.3274)
		(end 315.964062 -2.478532)
		(width 0.14224)
		(layer "In11.Cu")
		(net "M_C_DQ<58>")
	)
	(segment
		(start 316.24016 -24.83231)
		(end 315.88964 -24.83231)
		(width 0.14224)
		(layer "In11.Cu")
		(net "M_C_DQ<58>")
	)
	(segment
		(start 315.7474 -28.22575)
		(end 315.88964 -28.08351)
		(width 0.14224)
		(layer "In11.Cu")
		(net "M_C_DQ<58>")
	)
	(segment
		(start 315.994796 -24.021796)
		(end 315.994796 -23.428452)
		(width 0.14224)
		(layer "In11.Cu")
		(net "M_C_DQ<58>")
	)
	(segment
		(start 315.982096 -13.783056)
		(end 315.740796 -13.541756)
		(width 0.14224)
		(layer "In11.Cu")
		(net "M_C_DQ<58>")
	)
	(segment
		(start 316.24016 -25.48255)
		(end 316.3824 -25.34031)
		(width 0.14224)
		(layer "In11.Cu")
		(net "M_C_DQ<58>")
	)
	(segment
		(start 288.99104 -62.554104)
		(end 288.99739 -62.543436)
		(width 0.0889)
		(layer "In11.Cu")
		(net "M_C_DQ<58>")
	)
	(segment
		(start 315.893196 -21.3614)
		(end 315.7728 -21.241004)
		(width 0.14224)
		(layer "In11.Cu")
		(net "M_C_DQ<58>")
	)
	(segment
		(start 315.766196 -17.03705)
		(end 315.982096 -16.82115)
		(width 0.14224)
		(layer "In11.Cu")
		(net "M_C_DQ<58>")
	)
	(segment
		(start 316.24016 -26.13279)
		(end 315.88964 -26.13279)
		(width 0.14224)
		(layer "In11.Cu")
		(net "M_C_DQ<58>")
	)
	(segment
		(start 315.893196 -21.796756)
		(end 315.893196 -21.3614)
		(width 0.14224)
		(layer "In11.Cu")
		(net "M_C_DQ<58>")
	)
	(segment
		(start 288.99739 -55.609236)
		(end 289.002216 -55.6006)
		(width 0.0889)
		(layer "In11.Cu")
		(net "M_C_DQ<58>")
	)
	(segment
		(start 289.160204 -53.53812)
		(end 289.160204 -53.362606)
		(width 0.0889)
		(layer "In11.Cu")
		(net "M_C_DQ<58>")
	)
	(segment
		(start 315.982096 -16.82115)
		(end 315.982096 -13.783056)
		(width 0.14224)
		(layer "In11.Cu")
		(net "M_C_DQ<58>")
	)
	(segment
		(start 315.7474 -25.99055)
		(end 315.7474 -25.62479)
		(width 0.14224)
		(layer "In11.Cu")
		(net "M_C_DQ<58>")
	)
	(segment
		(start 315.88964 -25.48255)
		(end 316.24016 -25.48255)
		(width 0.14224)
		(layer "In11.Cu")
		(net "M_C_DQ<58>")
	)
	(segment
		(start 315.7728 -19.0754)
		(end 315.893196 -18.955004)
		(width 0.14224)
		(layer "In11.Cu")
		(net "M_C_DQ<58>")
	)
	(segment
		(start 315.893196 -18.58645)
		(end 315.766196 -18.45945)
		(width 0.14224)
		(layer "In11.Cu")
		(net "M_C_DQ<58>")
	)
	(segment
		(start 315.766196 -7.365746)
		(end 315.969396 -7.162546)
		(width 0.14224)
		(layer "In11.Cu")
		(net "M_C_DQ<58>")
	)
	(segment
		(start 315.893196 -18.955004)
		(end 315.893196 -18.58645)
		(width 0.14224)
		(layer "In11.Cu")
		(net "M_C_DQ<58>")
	)
	(segment
		(start 315.7728 -9.543796)
		(end 315.893196 -9.4234)
		(width 0.14224)
		(layer "In11.Cu")
		(net "M_C_DQ<58>")
	)
	(segment
		(start 315.7728 -11.6078)
		(end 315.7728 -9.543796)
		(width 0.14224)
		(layer "In11.Cu")
		(net "M_C_DQ<58>")
	)
	(segment
		(start 289.020758 -61.155072)
		(end 289.015678 -61.147706)
		(width 0.0889)
		(layer "In11.Cu")
		(net "M_C_DQ<58>")
	)
	(segment
		(start 315.893196 -8.93445)
		(end 315.766196 -8.80745)
		(width 0.14224)
		(layer "In11.Cu")
		(net "M_C_DQ<58>")
	)
	(segment
		(start 315.7474 -30.5816)
		(end 315.7474 -28.22575)
		(width 0.14224)
		(layer "In11.Cu")
		(net "M_C_DQ<58>")
	)
	(segment
		(start 315.506862 -0.108204)
		(end 315.851794 0.236728)
		(width 0.14224)
		(layer "In11.Cu")
		(net "M_C_DQ<58>")
	)
	(segment
		(start 315.88964 -27.43327)
		(end 315.7474 -27.29103)
		(width 0.14224)
		(layer "In11.Cu")
		(net "M_C_DQ<58>")
	)
	(segment
		(start 288.99739 -54.618636)
		(end 289.002216 -54.61)
		(width 0.0889)
		(layer "In11.Cu")
		(net "M_C_DQ<58>")
	)
	(segment
		(start 288.99104 -57.601104)
		(end 288.99739 -57.590436)
		(width 0.0889)
		(layer "In11.Cu")
		(net "M_C_DQ<58>")
	)
	(segment
		(start 315.88964 -28.08351)
		(end 316.24016 -28.08351)
		(width 0.14224)
		(layer "In11.Cu")
		(net "M_C_DQ<58>")
	)
	(segment
		(start 315.7728 -21.241004)
		(end 315.7728 -19.0754)
		(width 0.14224)
		(layer "In11.Cu")
		(net "M_C_DQ<58>")
	)
	(segment
		(start 288.99104 -60.572904)
		(end 288.99739 -60.562236)
		(width 0.0889)
		(layer "In11.Cu")
		(net "M_C_DQ<58>")
	)
	(segment
		(start 288.99739 -61.566552)
		(end 289.020504 -61.52642)
		(width 0.0889)
		(layer "In11.Cu")
		(net "M_C_DQ<58>")
	)
	(segment
		(start 315.740796 -13.541756)
		(end 315.740796 -12.286996)
		(width 0.14224)
		(layer "In11.Cu")
		(net "M_C_DQ<58>")
	)
	(segment
		(start 315.88964 -24.83231)
		(end 315.7474 -24.69007)
		(width 0.14224)
		(layer "In11.Cu")
		(net "M_C_DQ<58>")
	)
	(segment
		(start 315.88964 -26.13279)
		(end 315.7474 -25.99055)
		(width 0.14224)
		(layer "In11.Cu")
		(net "M_C_DQ<58>")
	)
	(segment
		(start 288.99739 -56.599836)
		(end 289.002216 -56.5912)
		(width 0.0889)
		(layer "In11.Cu")
		(net "M_C_DQ<58>")
	)
	(segment
		(start 316.3824 -27.94127)
		(end 316.3824 -27.57551)
		(width 0.14224)
		(layer "In11.Cu")
		(net "M_C_DQ<58>")
	)
	(segment
		(start 315.7474 -27.29103)
		(end 315.7474 -26.92527)
		(width 0.14224)
		(layer "In11.Cu")
		(net "M_C_DQ<58>")
	)
	(segment
		(start 316.3824 -25.34031)
		(end 316.3824 -24.97455)
		(width 0.14224)
		(layer "In11.Cu")
		(net "M_C_DQ<58>")
	)
	(arc
		(start 288.99739 -54.218586)
		(mid 288.922296 -53.992974)
		(end 288.942272 -53.756052)
		(width 0.0889)
		(layer "In11.Cu")
		(net "M_C_DQ<58>")
	)
	(arc
		(start 289.020504 -61.52642)
		(mid 289.070318 -61.340775)
		(end 289.020758 -61.155072)
		(width 0.0889)
		(layer "In11.Cu")
		(net "M_C_DQ<58>")
	)
	(arc
		(start 289.002216 -55.6006)
		(mid 289.050971 -55.404248)
		(end 288.99739 -55.209186)
		(width 0.0889)
		(layer "In11.Cu")
		(net "M_C_DQ<58>")
	)
	(arc
		(start 289.002216 -60.5536)
		(mid 289.050971 -60.357248)
		(end 288.99739 -60.162186)
		(width 0.0889)
		(layer "In11.Cu")
		(net "M_C_DQ<58>")
	)
	(arc
		(start 288.99739 -58.180986)
		(mid 288.918168 -57.891868)
		(end 288.99104 -57.601104)
		(width 0.0889)
		(layer "In11.Cu")
		(net "M_C_DQ<58>")
	)
	(arc
		(start 288.99739 -56.199786)
		(mid 288.918168 -55.910668)
		(end 288.99104 -55.619904)
		(width 0.0889)
		(layer "In11.Cu")
		(net "M_C_DQ<58>")
	)
	(arc
		(start 289.002216 -57.5818)
		(mid 289.050971 -57.385448)
		(end 288.99739 -57.190386)
		(width 0.0889)
		(layer "In11.Cu")
		(net "M_C_DQ<58>")
	)
	(arc
		(start 288.99739 -57.190386)
		(mid 288.918168 -56.901268)
		(end 288.99104 -56.610504)
		(width 0.0889)
		(layer "In11.Cu")
		(net "M_C_DQ<58>")
	)
	(arc
		(start 289.04438 -62.444376)
		(mid 289.05084 -62.2823)
		(end 288.99739 -62.129162)
		(width 0.0889)
		(layer "In11.Cu")
		(net "M_C_DQ<58>")
	)
	(arc
		(start 288.99739 -62.129162)
		(mid 288.922104 -61.847874)
		(end 288.99739 -61.566552)
		(width 0.0889)
		(layer "In11.Cu")
		(net "M_C_DQ<58>")
	)
	(arc
		(start 288.99739 -59.571382)
		(mid 289.050889 -59.371484)
		(end 288.99739 -59.171586)
		(width 0.0889)
		(layer "In11.Cu")
		(net "M_C_DQ<58>")
	)
	(arc
		(start 288.99739 -60.162186)
		(mid 288.918259 -59.866784)
		(end 288.99739 -59.571382)
		(width 0.0889)
		(layer "In11.Cu")
		(net "M_C_DQ<58>")
	)
	(arc
		(start 289.002216 -54.61)
		(mid 289.050971 -54.413648)
		(end 288.99739 -54.218586)
		(width 0.0889)
		(layer "In11.Cu")
		(net "M_C_DQ<58>")
	)
	(arc
		(start 288.967672 -63.075566)
		(mid 288.91866 -62.812117)
		(end 288.99104 -62.554104)
		(width 0.0889)
		(layer "In11.Cu")
		(net "M_C_DQ<58>")
	)
	(arc
		(start 288.99739 -55.209186)
		(mid 288.918168 -54.920068)
		(end 288.99104 -54.629304)
		(width 0.0889)
		(layer "In11.Cu")
		(net "M_C_DQ<58>")
	)
	(arc
		(start 289.002216 -56.5912)
		(mid 289.050971 -56.394848)
		(end 288.99739 -56.199786)
		(width 0.0889)
		(layer "In11.Cu")
		(net "M_C_DQ<58>")
	)
	(arc
		(start 288.99104 -59.160918)
		(mid 288.918242 -58.870155)
		(end 288.99739 -58.581036)
		(width 0.0889)
		(layer "In11.Cu")
		(net "M_C_DQ<58>")
	)
	(arc
		(start 288.99739 -62.543436)
		(mid 289.026243 -62.496447)
		(end 289.04438 -62.444376)
		(width 0.0889)
		(layer "In11.Cu")
		(net "M_C_DQ<58>")
	)
	(arc
		(start 289.015678 -61.147706)
		(mid 288.923114 -60.863763)
		(end 288.99104 -60.572904)
		(width 0.0889)
		(layer "In11.Cu")
		(net "M_C_DQ<58>")
	)
	(arc
		(start 289.002216 -58.5724)
		(mid 289.050971 -58.376048)
		(end 288.99739 -58.180986)
		(width 0.0889)
		(layer "In11.Cu")
		(net "M_C_DQ<58>")
	)
	(segment
		(start 309.449978 3.778758)
		(end 309.449978 2.514854)
		(width 0.1651)
		(layer "F.Cu")
		(net "M_C_DQ<57>")
	)
	(segment
		(start 309.450486 3.778758)
		(end 309.449978 3.778758)
		(width 0.1651)
		(layer "F.Cu")
		(net "M_C_DQ<57>")
	)
	(segment
		(start 286.64662 -64.819784)
		(end 286.07512 -64.819784)
		(width 0.0889)
		(layer "F.Cu")
		(net "M_C_DQ<57>")
	)
	(via
		(at 309.449978 2.514854)
		(size 0.508)
		(drill 0.254)
		(layers "F.Cu" "B.Cu")
		(net "M_C_DQ<57>")
	)
	(via
		(at 310.122062 -3.076956)
		(size 0.508)
		(drill 0.254)
		(layers "F.Cu" "B.Cu")
		(net "M_C_DQ<57>")
	)
	(via
		(at 286.07512 -64.819784)
		(size 0.508)
		(drill 0.254)
		(layers "F.Cu" "B.Cu")
		(net "M_C_DQ<57>")
	)
	(segment
		(start 310.299862 -1.021842)
		(end 310.299862 -2.395982)
		(width 0.1651)
		(layer "B.Cu")
		(net "M_C_DQ<57>")
	)
	(segment
		(start 310.30037 -1.021842)
		(end 310.299862 -1.021842)
		(width 0.1651)
		(layer "B.Cu")
		(net "M_C_DQ<57>")
	)
	(segment
		(start 310.122062 -2.573782)
		(end 310.122062 -3.076956)
		(width 0.1651)
		(layer "B.Cu")
		(net "M_C_DQ<57>")
	)
	(segment
		(start 310.299862 -2.395982)
		(end 310.122062 -2.573782)
		(width 0.1651)
		(layer "B.Cu")
		(net "M_C_DQ<57>")
	)
	(segment
		(start 309.59552 -3.85572)
		(end 309.59552 -3.603498)
		(width 0.14224)
		(layer "In11.Cu")
		(net "M_C_DQ<57>")
	)
	(segment
		(start 285.723584 -60.666122)
		(end 285.72841 -60.657486)
		(width 0.0889)
		(layer "In11.Cu")
		(net "M_C_DQ<57>")
	)
	(segment
		(start 286.4612 -50.468784)
		(end 286.4485 -50.456084)
		(width 0.0889)
		(layer "In11.Cu")
		(net "M_C_DQ<57>")
	)
	(segment
		(start 287.8074 -49.3268)
		(end 290.6776 -46.4566)
		(width 0.14224)
		(layer "In11.Cu")
		(net "M_C_DQ<57>")
	)
	(segment
		(start 310.609996 -9.4488)
		(end 310.609996 -6.520942)
		(width 0.14224)
		(layer "In11.Cu")
		(net "M_C_DQ<57>")
	)
	(segment
		(start 310.609996 -21.342858)
		(end 310.8452 -21.107654)
		(width 0.14224)
		(layer "In11.Cu")
		(net "M_C_DQ<57>")
	)
	(segment
		(start 310.7944 -11.5062)
		(end 310.7944 -9.633204)
		(width 0.14224)
		(layer "In11.Cu")
		(net "M_C_DQ<57>")
	)
	(segment
		(start 310.652668 1.128776)
		(end 310.282844 1.4986)
		(width 0.14224)
		(layer "In11.Cu")
		(net "M_C_DQ<57>")
	)
	(segment
		(start 285.802324 -64.198246)
		(end 285.72841 -64.029336)
		(width 0.0889)
		(layer "In11.Cu")
		(net "M_C_DQ<57>")
	)
	(segment
		(start 286.4612 -50.997612)
		(end 286.4612 -50.468784)
		(width 0.0889)
		(layer "In11.Cu")
		(net "M_C_DQ<57>")
	)
	(segment
		(start 285.766764 -53.604922)
		(end 285.766764 -51.692048)
		(width 0.0889)
		(layer "In11.Cu")
		(net "M_C_DQ<57>")
	)
	(segment
		(start 285.723584 -59.675522)
		(end 285.72841 -59.666886)
		(width 0.0889)
		(layer "In11.Cu")
		(net "M_C_DQ<57>")
	)
	(segment
		(start 310.360568 -26.189432)
		(end 310.609996 -25.940004)
		(width 0.14224)
		(layer "In11.Cu")
		(net "M_C_DQ<57>")
	)
	(segment
		(start 285.704534 -53.754528)
		(end 285.766764 -53.604922)
		(width 0.0889)
		(layer "In11.Cu")
		(net "M_C_DQ<57>")
	)
	(segment
		(start 285.72841 -54.713886)
		(end 285.73476 -54.703218)
		(width 0.0889)
		(layer "In11.Cu")
		(net "M_C_DQ<57>")
	)
	(segment
		(start 286.07512 -64.819784)
		(end 285.802324 -64.198246)
		(width 0.0889)
		(layer "In11.Cu")
		(net "M_C_DQ<57>")
	)
	(segment
		(start 285.72841 -55.704486)
		(end 285.73476 -55.693818)
		(width 0.0889)
		(layer "In11.Cu")
		(net "M_C_DQ<57>")
	)
	(segment
		(start 309.449978 1.975866)
		(end 309.449978 2.514854)
		(width 0.14224)
		(layer "In11.Cu")
		(net "M_C_DQ<57>")
	)
	(segment
		(start 309.974996 -5.885942)
		(end 309.974996 -4.235196)
		(width 0.14224)
		(layer "In11.Cu")
		(net "M_C_DQ<57>")
	)
	(segment
		(start 310.8452 -21.107654)
		(end 310.8452 -19.209004)
		(width 0.14224)
		(layer "In11.Cu")
		(net "M_C_DQ<57>")
	)
	(segment
		(start 285.723584 -55.713122)
		(end 285.72841 -55.704486)
		(width 0.0889)
		(layer "In11.Cu")
		(net "M_C_DQ<57>")
	)
	(segment
		(start 310.360568 -30.973014)
		(end 310.360568 -26.189432)
		(width 0.14224)
		(layer "In11.Cu")
		(net "M_C_DQ<57>")
	)
	(segment
		(start 285.72841 -57.685686)
		(end 285.73476 -57.675018)
		(width 0.0889)
		(layer "In11.Cu")
		(net "M_C_DQ<57>")
	)
	(segment
		(start 285.73476 -59.087004)
		(end 285.72841 -59.076336)
		(width 0.0889)
		(layer "In11.Cu")
		(net "M_C_DQ<57>")
	)
	(segment
		(start 285.723584 -56.703722)
		(end 285.72841 -56.695086)
		(width 0.0889)
		(layer "In11.Cu")
		(net "M_C_DQ<57>")
	)
	(segment
		(start 309.927244 1.4986)
		(end 309.449978 1.975866)
		(width 0.14224)
		(layer "In11.Cu")
		(net "M_C_DQ<57>")
	)
	(segment
		(start 310.609996 -6.520942)
		(end 309.974996 -5.885942)
		(width 0.14224)
		(layer "In11.Cu")
		(net "M_C_DQ<57>")
	)
	(segment
		(start 310.282844 1.4986)
		(end 309.927244 1.4986)
		(width 0.14224)
		(layer "In11.Cu")
		(net "M_C_DQ<57>")
	)
	(segment
		(start 310.7944 -9.633204)
		(end 310.609996 -9.4488)
		(width 0.14224)
		(layer "In11.Cu")
		(net "M_C_DQ<57>")
	)
	(segment
		(start 310.496204 0.630936)
		(end 310.652668 0.7874)
		(width 0.14224)
		(layer "In11.Cu")
		(net "M_C_DQ<57>")
	)
	(segment
		(start 310.609996 -11.690604)
		(end 310.7944 -11.5062)
		(width 0.14224)
		(layer "In11.Cu")
		(net "M_C_DQ<57>")
	)
	(segment
		(start 285.723584 -54.722522)
		(end 285.72841 -54.713886)
		(width 0.0889)
		(layer "In11.Cu")
		(net "M_C_DQ<57>")
	)
	(segment
		(start 286.4485 -50.456084)
		(end 286.4485 -50.32502)
		(width 0.0889)
		(layer "In11.Cu")
		(net "M_C_DQ<57>")
	)
	(segment
		(start 310.609996 -18.9738)
		(end 310.609996 -11.690604)
		(width 0.14224)
		(layer "In11.Cu")
		(net "M_C_DQ<57>")
	)
	(segment
		(start 285.72841 -60.657486)
		(end 285.73476 -60.646818)
		(width 0.0889)
		(layer "In11.Cu")
		(net "M_C_DQ<57>")
	)
	(segment
		(start 293.903146 -46.4566)
		(end 300.329346 -40.0304)
		(width 0.14224)
		(layer "In11.Cu")
		(net "M_C_DQ<57>")
	)
	(segment
		(start 287.44672 -49.3268)
		(end 287.8074 -49.3268)
		(width 0.0889)
		(layer "In11.Cu")
		(net "M_C_DQ<57>")
	)
	(segment
		(start 309.59552 -3.603498)
		(end 310.122062 -3.076956)
		(width 0.14224)
		(layer "In11.Cu")
		(net "M_C_DQ<57>")
	)
	(segment
		(start 285.766764 -51.692048)
		(end 286.4612 -50.997612)
		(width 0.0889)
		(layer "In11.Cu")
		(net "M_C_DQ<57>")
	)
	(segment
		(start 301.303182 -40.0304)
		(end 310.360568 -30.973014)
		(width 0.14224)
		(layer "In11.Cu")
		(net "M_C_DQ<57>")
	)
	(segment
		(start 310.609996 -25.940004)
		(end 310.609996 -21.342858)
		(width 0.14224)
		(layer "In11.Cu")
		(net "M_C_DQ<57>")
	)
	(segment
		(start 300.329346 -40.0304)
		(end 301.303182 -40.0304)
		(width 0.14224)
		(layer "In11.Cu")
		(net "M_C_DQ<57>")
	)
	(segment
		(start 286.4485 -50.32502)
		(end 287.44672 -49.3268)
		(width 0.0889)
		(layer "In11.Cu")
		(net "M_C_DQ<57>")
	)
	(segment
		(start 310.8452 -19.209004)
		(end 310.609996 -18.9738)
		(width 0.14224)
		(layer "In11.Cu")
		(net "M_C_DQ<57>")
	)
	(segment
		(start 309.974996 -4.235196)
		(end 309.59552 -3.85572)
		(width 0.14224)
		(layer "In11.Cu")
		(net "M_C_DQ<57>")
	)
	(segment
		(start 310.122062 -3.076956)
		(end 310.496204 -2.702814)
		(width 0.14224)
		(layer "In11.Cu")
		(net "M_C_DQ<57>")
	)
	(segment
		(start 285.72841 -56.695086)
		(end 285.73476 -56.684418)
		(width 0.0889)
		(layer "In11.Cu")
		(net "M_C_DQ<57>")
	)
	(segment
		(start 285.723584 -57.694322)
		(end 285.72841 -57.685686)
		(width 0.0889)
		(layer "In11.Cu")
		(net "M_C_DQ<57>")
	)
	(segment
		(start 310.652668 0.7874)
		(end 310.652668 1.128776)
		(width 0.14224)
		(layer "In11.Cu")
		(net "M_C_DQ<57>")
	)
	(segment
		(start 290.6776 -46.4566)
		(end 293.903146 -46.4566)
		(width 0.14224)
		(layer "In11.Cu")
		(net "M_C_DQ<57>")
	)
	(segment
		(start 310.496204 -2.702814)
		(end 310.496204 0.630936)
		(width 0.14224)
		(layer "In11.Cu")
		(net "M_C_DQ<57>")
	)
	(arc
		(start 286.39262 -63.082424)
		(mid 286.460615 -62.73144)
		(end 286.220916 -62.46622)
		(width 0.0889)
		(layer "In11.Cu")
		(net "M_C_DQ<57>")
	)
	(arc
		(start 285.921704 -63.459868)
		(mid 286.183945 -63.304569)
		(end 286.39262 -63.082424)
		(width 0.0889)
		(layer "In11.Cu")
		(net "M_C_DQ<57>")
	)
	(arc
		(start 285.72841 -56.104536)
		(mid 285.67494 -55.909473)
		(end 285.723584 -55.713122)
		(width 0.0889)
		(layer "In11.Cu")
		(net "M_C_DQ<57>")
	)
	(arc
		(start 285.73476 -54.703218)
		(mid 285.807558 -54.412455)
		(end 285.72841 -54.123336)
		(width 0.0889)
		(layer "In11.Cu")
		(net "M_C_DQ<57>")
	)
	(arc
		(start 285.72841 -60.066936)
		(mid 285.67494 -59.871873)
		(end 285.723584 -59.675522)
		(width 0.0889)
		(layer "In11.Cu")
		(net "M_C_DQ<57>")
	)
	(arc
		(start 285.73476 -57.675018)
		(mid 285.807558 -57.384255)
		(end 285.72841 -57.095136)
		(width 0.0889)
		(layer "In11.Cu")
		(net "M_C_DQ<57>")
	)
	(arc
		(start 285.72841 -59.666886)
		(mid 285.807632 -59.377768)
		(end 285.73476 -59.087004)
		(width 0.0889)
		(layer "In11.Cu")
		(net "M_C_DQ<57>")
	)
	(arc
		(start 286.220916 -62.46622)
		(mid 285.938333 -62.299967)
		(end 285.72841 -62.048136)
		(width 0.0889)
		(layer "In11.Cu")
		(net "M_C_DQ<57>")
	)
	(arc
		(start 285.72841 -57.095136)
		(mid 285.67494 -56.900073)
		(end 285.723584 -56.703722)
		(width 0.0889)
		(layer "In11.Cu")
		(net "M_C_DQ<57>")
	)
	(arc
		(start 285.73476 -55.693818)
		(mid 285.807558 -55.403055)
		(end 285.72841 -55.113936)
		(width 0.0889)
		(layer "In11.Cu")
		(net "M_C_DQ<57>")
	)
	(arc
		(start 285.73476 -56.684418)
		(mid 285.807558 -56.393655)
		(end 285.72841 -56.104536)
		(width 0.0889)
		(layer "In11.Cu")
		(net "M_C_DQ<57>")
	)
	(arc
		(start 285.72841 -64.029336)
		(mid 285.696139 -63.700829)
		(end 285.921704 -63.459868)
		(width 0.0889)
		(layer "In11.Cu")
		(net "M_C_DQ<57>")
	)
	(arc
		(start 285.72841 -61.057536)
		(mid 285.67494 -60.862473)
		(end 285.723584 -60.666122)
		(width 0.0889)
		(layer "In11.Cu")
		(net "M_C_DQ<57>")
	)
	(arc
		(start 285.72841 -55.113936)
		(mid 285.67494 -54.918873)
		(end 285.723584 -54.722522)
		(width 0.0889)
		(layer "In11.Cu")
		(net "M_C_DQ<57>")
	)
	(arc
		(start 285.72841 -59.076336)
		(mid 285.674911 -58.876438)
		(end 285.72841 -58.67654)
		(width 0.0889)
		(layer "In11.Cu")
		(net "M_C_DQ<57>")
	)
	(arc
		(start 285.73476 -60.646818)
		(mid 285.807558 -60.356055)
		(end 285.72841 -60.066936)
		(width 0.0889)
		(layer "In11.Cu")
		(net "M_C_DQ<57>")
	)
	(arc
		(start 285.72841 -61.64834)
		(mid 285.807473 -61.352938)
		(end 285.72841 -61.057536)
		(width 0.0889)
		(layer "In11.Cu")
		(net "M_C_DQ<57>")
	)
	(arc
		(start 285.72841 -54.123336)
		(mid 285.673436 -53.941722)
		(end 285.704534 -53.754528)
		(width 0.0889)
		(layer "In11.Cu")
		(net "M_C_DQ<57>")
	)
	(arc
		(start 285.72841 -62.048136)
		(mid 285.674911 -61.848238)
		(end 285.72841 -61.64834)
		(width 0.0889)
		(layer "In11.Cu")
		(net "M_C_DQ<57>")
	)
	(arc
		(start 285.72841 -58.67654)
		(mid 285.807541 -58.381138)
		(end 285.72841 -58.085736)
		(width 0.0889)
		(layer "In11.Cu")
		(net "M_C_DQ<57>")
	)
	(arc
		(start 285.72841 -58.085736)
		(mid 285.67494 -57.890673)
		(end 285.723584 -57.694322)
		(width 0.0889)
		(layer "In11.Cu")
		(net "M_C_DQ<57>")
	)
	(segment
		(start 310.299862 -0.821182)
		(end 310.122062 1.0414)
		(width 0.1651)
		(layer "F.Cu")
		(net "M_C_DQ<56>")
	)
	(segment
		(start 286.64662 -62.838584)
		(end 286.07512 -62.838584)
		(width 0.0889)
		(layer "F.Cu")
		(net "M_C_DQ<56>")
	)
	(segment
		(start 310.30037 -0.821182)
		(end 310.299862 -0.821182)
		(width 0.1651)
		(layer "F.Cu")
		(net "M_C_DQ<56>")
	)
	(via
		(at 309.449978 -4.357878)
		(size 0.508)
		(drill 0.254)
		(layers "F.Cu" "B.Cu")
		(net "M_C_DQ<56>")
	)
	(via
		(at 286.07512 -62.838584)
		(size 0.508)
		(drill 0.254)
		(layers "F.Cu" "B.Cu")
		(net "M_C_DQ<56>")
	)
	(via
		(at 310.122062 1.0414)
		(size 0.508)
		(drill 0.254)
		(layers "F.Cu" "B.Cu")
		(net "M_C_DQ<56>")
	)
	(segment
		(start 309.450486 -5.621782)
		(end 309.449978 -5.621782)
		(width 0.1651)
		(layer "B.Cu")
		(net "M_C_DQ<56>")
	)
	(segment
		(start 309.449978 -5.621782)
		(end 309.449978 -4.357878)
		(width 0.1651)
		(layer "B.Cu")
		(net "M_C_DQ<56>")
	)
	(segment
		(start 305.047904 -35.314128)
		(end 305.249072 -35.314128)
		(width 0.14224)
		(layer "In11.Cu")
		(net "M_C_DQ<56>")
	)
	(segment
		(start 301.85614 -37.84346)
		(end 302.057308 -37.84346)
		(width 0.14224)
		(layer "In11.Cu")
		(net "M_C_DQ<56>")
	)
	(segment
		(start 285.567374 -62.150752)
		(end 285.56331 -62.14364)
		(width 0.0889)
		(layer "In11.Cu")
		(net "M_C_DQ<56>")
	)
	(segment
		(start 309.6514 -10.778236)
		(end 309.8292 -10.600436)
		(width 0.14224)
		(layer "In11.Cu")
		(net "M_C_DQ<56>")
	)
	(segment
		(start 301.13732 -38.763448)
		(end 301.266352 -38.89248)
		(width 0.14224)
		(layer "In11.Cu")
		(net "M_C_DQ<56>")
	)
	(segment
		(start 285.56331 -54.618636)
		(end 285.568136 -54.61)
		(width 0.0889)
		(layer "In11.Cu")
		(net "M_C_DQ<56>")
	)
	(segment
		(start 309.6514 -21.932392)
		(end 309.9308 -21.652992)
		(width 0.14224)
		(layer "In11.Cu")
		(net "M_C_DQ<56>")
	)
	(segment
		(start 303.409096 -37.154104)
		(end 303.667922 -36.895278)
		(width 0.14224)
		(layer "In11.Cu")
		(net "M_C_DQ<56>")
	)
	(segment
		(start 309.9308 -6.806946)
		(end 309.449978 -6.326124)
		(width 0.14224)
		(layer "In11.Cu")
		(net "M_C_DQ<56>")
	)
	(segment
		(start 301.597314 -38.102286)
		(end 301.85614 -37.84346)
		(width 0.14224)
		(layer "In11.Cu")
		(net "M_C_DQ<56>")
	)
	(segment
		(start 309.6006 -9.906)
		(end 309.6006 -9.7028)
		(width 0.14224)
		(layer "In11.Cu")
		(net "M_C_DQ<56>")
	)
	(segment
		(start 309.6006 -9.7028)
		(end 309.9308 -9.3726)
		(width 0.14224)
		(layer "In11.Cu")
		(net "M_C_DQ<56>")
	)
	(segment
		(start 309.9308 -18.617946)
		(end 309.632096 -18.319242)
		(width 0.14224)
		(layer "In11.Cu")
		(net "M_C_DQ<56>")
	)
	(segment
		(start 285.56331 -57.590436)
		(end 285.568136 -57.5818)
		(width 0.0889)
		(layer "In11.Cu")
		(net "M_C_DQ<56>")
	)
	(segment
		(start 309.449978 -4.357878)
		(end 309.165244 -4.073144)
		(width 0.14224)
		(layer "In11.Cu")
		(net "M_C_DQ<56>")
	)
	(segment
		(start 285.56331 -56.599836)
		(end 285.568136 -56.5912)
		(width 0.0889)
		(layer "In11.Cu")
		(net "M_C_DQ<56>")
	)
	(segment
		(start 302.977296 -36.923472)
		(end 303.207928 -37.154104)
		(width 0.14224)
		(layer "In11.Cu")
		(net "M_C_DQ<56>")
	)
	(segment
		(start 303.667922 -36.69411)
		(end 303.43729 -36.463478)
		(width 0.14224)
		(layer "In11.Cu")
		(net "M_C_DQ<56>")
	)
	(segment
		(start 309.688992 -13.465048)
		(end 309.632096 -13.408152)
		(width 0.14224)
		(layer "In11.Cu")
		(net "M_C_DQ<56>")
	)
	(segment
		(start 303.43729 -36.463478)
		(end 303.43729 -36.26231)
		(width 0.14224)
		(layer "In11.Cu")
		(net "M_C_DQ<56>")
	)
	(segment
		(start 309.512462 -1.701546)
		(end 309.512462 -1.397)
		(width 0.14224)
		(layer "In11.Cu")
		(net "M_C_DQ<56>")
	)
	(segment
		(start 285.55696 -54.629304)
		(end 285.56331 -54.618636)
		(width 0.0889)
		(layer "In11.Cu")
		(net "M_C_DQ<56>")
	)
	(segment
		(start 287.3248 -49.0982)
		(end 290.9824 -45.4406)
		(width 0.14224)
		(layer "In11.Cu")
		(net "M_C_DQ<56>")
	)
	(segment
		(start 303.897284 -36.003484)
		(end 304.127916 -36.234116)
		(width 0.14224)
		(layer "In11.Cu")
		(net "M_C_DQ<56>")
	)
	(segment
		(start 304.127916 -36.234116)
		(end 304.329084 -36.234116)
		(width 0.14224)
		(layer "In11.Cu")
		(net "M_C_DQ<56>")
	)
	(segment
		(start 309.632096 -7.516876)
		(end 309.9308 -7.218172)
		(width 0.14224)
		(layer "In11.Cu")
		(net "M_C_DQ<56>")
	)
	(segment
		(start 305.507898 -35.055302)
		(end 305.508152 -35.055302)
		(width 0.14224)
		(layer "In11.Cu")
		(net "M_C_DQ<56>")
	)
	(segment
		(start 300.936152 -38.763448)
		(end 301.13732 -38.763448)
		(width 0.14224)
		(layer "In11.Cu")
		(net "M_C_DQ<56>")
	)
	(segment
		(start 309.725568 -30.837886)
		(end 309.725568 -25.960578)
		(width 0.14224)
		(layer "In11.Cu")
		(net "M_C_DQ<56>")
	)
	(segment
		(start 309.632096 -12.424156)
		(end 309.9308 -12.125452)
		(width 0.14224)
		(layer "In11.Cu")
		(net "M_C_DQ<56>")
	)
	(segment
		(start 302.747934 -37.815266)
		(end 302.747934 -37.614098)
		(width 0.14224)
		(layer "In11.Cu")
		(net "M_C_DQ<56>")
	)
	(segment
		(start 309.487062 -0.178054)
		(end 309.901844 0.236728)
		(width 0.14224)
		(layer "In11.Cu")
		(net "M_C_DQ<56>")
	)
	(segment
		(start 301.46752 -38.89248)
		(end 301.726346 -38.633654)
		(width 0.14224)
		(layer "In11.Cu")
		(net "M_C_DQ<56>")
	)
	(segment
		(start 302.057308 -37.84346)
		(end 302.28794 -38.074092)
		(width 0.14224)
		(layer "In11.Cu")
		(net "M_C_DQ<56>")
	)
	(segment
		(start 309.829962 -0.8509)
		(end 309.487062 -0.508)
		(width 0.14224)
		(layer "In11.Cu")
		(net "M_C_DQ<56>")
	)
	(segment
		(start 304.357278 -35.342322)
		(end 304.616104 -35.083496)
		(width 0.14224)
		(layer "In11.Cu")
		(net "M_C_DQ<56>")
	)
	(segment
		(start 304.58791 -35.97529)
		(end 304.58791 -35.774122)
		(width 0.14224)
		(layer "In11.Cu")
		(net "M_C_DQ<56>")
	)
	(segment
		(start 302.489108 -38.074092)
		(end 302.747934 -37.815266)
		(width 0.14224)
		(layer "In11.Cu")
		(net "M_C_DQ<56>")
	)
	(segment
		(start 302.517302 -37.383466)
		(end 302.517302 -37.182298)
		(width 0.14224)
		(layer "In11.Cu")
		(net "M_C_DQ<56>")
	)
	(segment
		(start 302.517302 -37.182298)
		(end 302.776128 -36.923472)
		(width 0.14224)
		(layer "In11.Cu")
		(net "M_C_DQ<56>")
	)
	(segment
		(start 309.9308 -13.785342)
		(end 309.688992 -13.543534)
		(width 0.14224)
		(layer "In11.Cu")
		(net "M_C_DQ<56>")
	)
	(segment
		(start 285.495238 -53.78069)
		(end 285.576518 -53.407564)
		(width 0.0889)
		(layer "In11.Cu")
		(net "M_C_DQ<56>")
	)
	(segment
		(start 301.597314 -38.303454)
		(end 301.597314 -38.102286)
		(width 0.14224)
		(layer "In11.Cu")
		(net "M_C_DQ<56>")
	)
	(segment
		(start 309.9308 -9.3726)
		(end 309.9308 -8.981186)
		(width 0.14224)
		(layer "In11.Cu")
		(net "M_C_DQ<56>")
	)
	(segment
		(start 309.632096 -18.319242)
		(end 309.632096 -17.118076)
		(width 0.14224)
		(layer "In11.Cu")
		(net "M_C_DQ<56>")
	)
	(segment
		(start 304.616104 -35.083496)
		(end 304.817272 -35.083496)
		(width 0.14224)
		(layer "In11.Cu")
		(net "M_C_DQ<56>")
	)
	(segment
		(start 309.9308 -12.125452)
		(end 309.9308 -11.641836)
		(width 0.14224)
		(layer "In11.Cu")
		(net "M_C_DQ<56>")
	)
	(segment
		(start 285.56331 -58.581036)
		(end 285.568136 -58.5724)
		(width 0.0889)
		(layer "In11.Cu")
		(net "M_C_DQ<56>")
	)
	(segment
		(start 309.9308 -21.652992)
		(end 309.9308 -21.361146)
		(width 0.14224)
		(layer "In11.Cu")
		(net "M_C_DQ<56>")
	)
	(segment
		(start 309.9308 -21.361146)
		(end 309.7276 -21.157946)
		(width 0.14224)
		(layer "In11.Cu")
		(net "M_C_DQ<56>")
	)
	(segment
		(start 309.165244 -3.3274)
		(end 309.901844 -2.5908)
		(width 0.14224)
		(layer "In11.Cu")
		(net "M_C_DQ<56>")
	)
	(segment
		(start 309.632096 -17.118076)
		(end 309.9308 -16.819372)
		(width 0.14224)
		(layer "In11.Cu")
		(net "M_C_DQ<56>")
	)
	(segment
		(start 309.632096 -13.408152)
		(end 309.632096 -12.424156)
		(width 0.14224)
		(layer "In11.Cu")
		(net "M_C_DQ<56>")
	)
	(segment
		(start 304.357278 -35.54349)
		(end 304.357278 -35.342322)
		(width 0.14224)
		(layer "In11.Cu")
		(net "M_C_DQ<56>")
	)
	(segment
		(start 309.9308 -8.981186)
		(end 309.632096 -8.682482)
		(width 0.14224)
		(layer "In11.Cu")
		(net "M_C_DQ<56>")
	)
	(segment
		(start 309.8292 -10.600436)
		(end 309.8292 -10.1346)
		(width 0.14224)
		(layer "In11.Cu")
		(net "M_C_DQ<56>")
	)
	(segment
		(start 305.249072 -35.314128)
		(end 305.507898 -35.055302)
		(width 0.14224)
		(layer "In11.Cu")
		(net "M_C_DQ<56>")
	)
	(segment
		(start 309.901844 -2.090928)
		(end 309.512462 -1.701546)
		(width 0.14224)
		(layer "In11.Cu")
		(net "M_C_DQ<56>")
	)
	(segment
		(start 285.55696 -56.610504)
		(end 285.56331 -56.599836)
		(width 0.0889)
		(layer "In11.Cu")
		(net "M_C_DQ<56>")
	)
	(segment
		(start 309.829962 -1.0795)
		(end 309.829962 -0.8509)
		(width 0.14224)
		(layer "In11.Cu")
		(net "M_C_DQ<56>")
	)
	(segment
		(start 309.725568 -25.960578)
		(end 309.907178 -25.778968)
		(width 0.14224)
		(layer "In11.Cu")
		(net "M_C_DQ<56>")
	)
	(segment
		(start 303.696116 -36.003484)
		(end 303.897284 -36.003484)
		(width 0.14224)
		(layer "In11.Cu")
		(net "M_C_DQ<56>")
	)
	(segment
		(start 285.56331 -60.562236)
		(end 285.568136 -60.5536)
		(width 0.0889)
		(layer "In11.Cu")
		(net "M_C_DQ<56>")
	)
	(segment
		(start 285.56331 -55.609236)
		(end 285.568136 -55.6006)
		(width 0.0889)
		(layer "In11.Cu")
		(net "M_C_DQ<56>")
	)
	(segment
		(start 309.632096 -8.682482)
		(end 309.632096 -7.516876)
		(width 0.14224)
		(layer "In11.Cu")
		(net "M_C_DQ<56>")
	)
	(segment
		(start 309.688992 -13.543534)
		(end 309.688992 -13.465048)
		(width 0.14224)
		(layer "In11.Cu")
		(net "M_C_DQ<56>")
	)
	(segment
		(start 287.3248 -49.17821)
		(end 287.3248 -49.0982)
		(width 0.0889)
		(layer "In11.Cu")
		(net "M_C_DQ<56>")
	)
	(segment
		(start 285.56331 -59.171586)
		(end 285.55696 -59.160918)
		(width 0.0889)
		(layer "In11.Cu")
		(net "M_C_DQ<56>")
	)
	(segment
		(start 309.165244 -4.073144)
		(end 309.165244 -3.3274)
		(width 0.14224)
		(layer "In11.Cu")
		(net "M_C_DQ<56>")
	)
	(segment
		(start 285.576518 -51.6128)
		(end 286.258 -50.931318)
		(width 0.0889)
		(layer "In11.Cu")
		(net "M_C_DQ<56>")
	)
	(segment
		(start 309.449978 -6.326124)
		(end 309.449978 -4.357878)
		(width 0.14224)
		(layer "In11.Cu")
		(net "M_C_DQ<56>")
	)
	(segment
		(start 303.667922 -36.895278)
		(end 303.667922 -36.69411)
		(width 0.14224)
		(layer "In11.Cu")
		(net "M_C_DQ<56>")
	)
	(segment
		(start 309.6514 -11.362436)
		(end 309.6514 -10.778236)
		(width 0.14224)
		(layer "In11.Cu")
		(net "M_C_DQ<56>")
	)
	(segment
		(start 290.9824 -45.4406)
		(end 294.259 -45.4406)
		(width 0.14224)
		(layer "In11.Cu")
		(net "M_C_DQ<56>")
	)
	(segment
		(start 309.9308 -11.641836)
		(end 309.6514 -11.362436)
		(width 0.14224)
		(layer "In11.Cu")
		(net "M_C_DQ<56>")
	)
	(segment
		(start 309.907178 -25.778968)
		(end 309.907178 -23.395178)
		(width 0.14224)
		(layer "In11.Cu")
		(net "M_C_DQ<56>")
	)
	(segment
		(start 304.817272 -35.083496)
		(end 305.047904 -35.314128)
		(width 0.14224)
		(layer "In11.Cu")
		(net "M_C_DQ<56>")
	)
	(segment
		(start 309.9308 -18.9738)
		(end 309.9308 -18.617946)
		(width 0.14224)
		(layer "In11.Cu")
		(net "M_C_DQ<56>")
	)
	(segment
		(start 285.55696 -57.601104)
		(end 285.56331 -57.590436)
		(width 0.0889)
		(layer "In11.Cu")
		(net "M_C_DQ<56>")
	)
	(segment
		(start 301.726346 -38.633654)
		(end 301.726346 -38.432486)
		(width 0.14224)
		(layer "In11.Cu")
		(net "M_C_DQ<56>")
	)
	(segment
		(start 309.9308 -16.819372)
		(end 309.9308 -13.785342)
		(width 0.14224)
		(layer "In11.Cu")
		(net "M_C_DQ<56>")
	)
	(segment
		(start 304.58791 -35.774122)
		(end 304.357278 -35.54349)
		(width 0.14224)
		(layer "In11.Cu")
		(net "M_C_DQ<56>")
	)
	(segment
		(start 301.266352 -38.89248)
		(end 301.46752 -38.89248)
		(width 0.14224)
		(layer "In11.Cu")
		(net "M_C_DQ<56>")
	)
	(segment
		(start 309.487062 -0.508)
		(end 309.487062 -0.178054)
		(width 0.14224)
		(layer "In11.Cu")
		(net "M_C_DQ<56>")
	)
	(segment
		(start 303.43729 -36.26231)
		(end 303.696116 -36.003484)
		(width 0.14224)
		(layer "In11.Cu")
		(net "M_C_DQ<56>")
	)
	(segment
		(start 309.7276 -19.177)
		(end 309.9308 -18.9738)
		(width 0.14224)
		(layer "In11.Cu")
		(net "M_C_DQ<56>")
	)
	(segment
		(start 309.901844 0.821182)
		(end 310.122062 1.0414)
		(width 0.14224)
		(layer "In11.Cu")
		(net "M_C_DQ<56>")
	)
	(segment
		(start 309.907178 -23.395178)
		(end 309.6514 -23.1394)
		(width 0.14224)
		(layer "In11.Cu")
		(net "M_C_DQ<56>")
	)
	(segment
		(start 285.55696 -55.619904)
		(end 285.56331 -55.609236)
		(width 0.0889)
		(layer "In11.Cu")
		(net "M_C_DQ<56>")
	)
	(segment
		(start 301.726346 -38.432486)
		(end 301.597314 -38.303454)
		(width 0.14224)
		(layer "In11.Cu")
		(net "M_C_DQ<56>")
	)
	(segment
		(start 305.508152 -35.055302)
		(end 309.725568 -30.837886)
		(width 0.14224)
		(layer "In11.Cu")
		(net "M_C_DQ<56>")
	)
	(segment
		(start 294.259 -45.4406)
		(end 300.936152 -38.763448)
		(width 0.14224)
		(layer "In11.Cu")
		(net "M_C_DQ<56>")
	)
	(segment
		(start 304.329084 -36.234116)
		(end 304.58791 -35.97529)
		(width 0.14224)
		(layer "In11.Cu")
		(net "M_C_DQ<56>")
	)
	(segment
		(start 286.258 -50.24501)
		(end 287.3248 -49.17821)
		(width 0.0889)
		(layer "In11.Cu")
		(net "M_C_DQ<56>")
	)
	(segment
		(start 309.9308 -7.218172)
		(end 309.9308 -6.806946)
		(width 0.14224)
		(layer "In11.Cu")
		(net "M_C_DQ<56>")
	)
	(segment
		(start 309.7276 -21.157946)
		(end 309.7276 -19.177)
		(width 0.14224)
		(layer "In11.Cu")
		(net "M_C_DQ<56>")
	)
	(segment
		(start 285.55696 -60.572904)
		(end 285.56331 -60.562236)
		(width 0.0889)
		(layer "In11.Cu")
		(net "M_C_DQ<56>")
	)
	(segment
		(start 285.576518 -53.407564)
		(end 285.576518 -51.6128)
		(width 0.0889)
		(layer "In11.Cu")
		(net "M_C_DQ<56>")
	)
	(segment
		(start 286.258 -50.931318)
		(end 286.258 -50.24501)
		(width 0.0889)
		(layer "In11.Cu")
		(net "M_C_DQ<56>")
	)
	(segment
		(start 302.747934 -37.614098)
		(end 302.517302 -37.383466)
		(width 0.14224)
		(layer "In11.Cu")
		(net "M_C_DQ<56>")
	)
	(segment
		(start 309.901844 0.236728)
		(end 309.901844 0.821182)
		(width 0.14224)
		(layer "In11.Cu")
		(net "M_C_DQ<56>")
	)
	(segment
		(start 309.6514 -23.1394)
		(end 309.6514 -21.932392)
		(width 0.14224)
		(layer "In11.Cu")
		(net "M_C_DQ<56>")
	)
	(segment
		(start 303.207928 -37.154104)
		(end 303.409096 -37.154104)
		(width 0.14224)
		(layer "In11.Cu")
		(net "M_C_DQ<56>")
	)
	(segment
		(start 286.07512 -62.838584)
		(end 286.032956 -62.79388)
		(width 0.0889)
		(layer "In11.Cu")
		(net "M_C_DQ<56>")
	)
	(segment
		(start 302.776128 -36.923472)
		(end 302.977296 -36.923472)
		(width 0.14224)
		(layer "In11.Cu")
		(net "M_C_DQ<56>")
	)
	(segment
		(start 309.901844 -2.5908)
		(end 309.901844 -2.090928)
		(width 0.14224)
		(layer "In11.Cu")
		(net "M_C_DQ<56>")
	)
	(segment
		(start 309.8292 -10.1346)
		(end 309.6006 -9.906)
		(width 0.14224)
		(layer "In11.Cu")
		(net "M_C_DQ<56>")
	)
	(segment
		(start 309.512462 -1.397)
		(end 309.829962 -1.0795)
		(width 0.14224)
		(layer "In11.Cu")
		(net "M_C_DQ<56>")
	)
	(segment
		(start 302.28794 -38.074092)
		(end 302.489108 -38.074092)
		(width 0.14224)
		(layer "In11.Cu")
		(net "M_C_DQ<56>")
	)
	(arc
		(start 285.568136 -60.5536)
		(mid 285.616891 -60.357248)
		(end 285.56331 -60.162186)
		(width 0.0889)
		(layer "In11.Cu")
		(net "M_C_DQ<56>")
	)
	(arc
		(start 285.56331 -59.571382)
		(mid 285.616809 -59.371484)
		(end 285.56331 -59.171586)
		(width 0.0889)
		(layer "In11.Cu")
		(net "M_C_DQ<56>")
	)
	(arc
		(start 285.56331 -54.218586)
		(mid 285.488396 -54.005996)
		(end 285.495238 -53.78069)
		(width 0.0889)
		(layer "In11.Cu")
		(net "M_C_DQ<56>")
	)
	(arc
		(start 285.56331 -56.199786)
		(mid 285.484088 -55.910668)
		(end 285.55696 -55.619904)
		(width 0.0889)
		(layer "In11.Cu")
		(net "M_C_DQ<56>")
	)
	(arc
		(start 285.56331 -58.180986)
		(mid 285.484088 -57.891868)
		(end 285.55696 -57.601104)
		(width 0.0889)
		(layer "In11.Cu")
		(net "M_C_DQ<56>")
	)
	(arc
		(start 285.568136 -57.5818)
		(mid 285.616891 -57.385448)
		(end 285.56331 -57.190386)
		(width 0.0889)
		(layer "In11.Cu")
		(net "M_C_DQ<56>")
	)
	(arc
		(start 285.56331 -62.14364)
		(mid 285.484179 -61.848238)
		(end 285.56331 -61.552836)
		(width 0.0889)
		(layer "In11.Cu")
		(net "M_C_DQ<56>")
	)
	(arc
		(start 285.56331 -60.162186)
		(mid 285.484179 -59.866784)
		(end 285.56331 -59.571382)
		(width 0.0889)
		(layer "In11.Cu")
		(net "M_C_DQ<56>")
	)
	(arc
		(start 285.568136 -54.61)
		(mid 285.616891 -54.413648)
		(end 285.56331 -54.218586)
		(width 0.0889)
		(layer "In11.Cu")
		(net "M_C_DQ<56>")
	)
	(arc
		(start 285.56331 -57.190386)
		(mid 285.484088 -56.901268)
		(end 285.55696 -56.610504)
		(width 0.0889)
		(layer "In11.Cu")
		(net "M_C_DQ<56>")
	)
	(arc
		(start 285.55696 -59.160918)
		(mid 285.484162 -58.870155)
		(end 285.56331 -58.581036)
		(width 0.0889)
		(layer "In11.Cu")
		(net "M_C_DQ<56>")
	)
	(arc
		(start 285.568136 -58.5724)
		(mid 285.616891 -58.376048)
		(end 285.56331 -58.180986)
		(width 0.0889)
		(layer "In11.Cu")
		(net "M_C_DQ<56>")
	)
	(arc
		(start 285.56331 -61.552836)
		(mid 285.616843 -61.352828)
		(end 285.56331 -61.152786)
		(width 0.0889)
		(layer "In11.Cu")
		(net "M_C_DQ<56>")
	)
	(arc
		(start 285.568136 -55.6006)
		(mid 285.616891 -55.404248)
		(end 285.56331 -55.209186)
		(width 0.0889)
		(layer "In11.Cu")
		(net "M_C_DQ<56>")
	)
	(arc
		(start 286.032956 -62.79388)
		(mid 285.783589 -62.484316)
		(end 285.567374 -62.150752)
		(width 0.0889)
		(layer "In11.Cu")
		(net "M_C_DQ<56>")
	)
	(arc
		(start 285.56331 -61.152786)
		(mid 285.484088 -60.863668)
		(end 285.55696 -60.572904)
		(width 0.0889)
		(layer "In11.Cu")
		(net "M_C_DQ<56>")
	)
	(arc
		(start 285.56331 -55.209186)
		(mid 285.484088 -54.920068)
		(end 285.55696 -54.629304)
		(width 0.0889)
		(layer "In11.Cu")
		(net "M_C_DQ<56>")
	)
	(arc
		(start 285.568136 -56.5912)
		(mid 285.616891 -56.394848)
		(end 285.56331 -56.199786)
		(width 0.0889)
		(layer "In11.Cu")
		(net "M_C_DQ<56>")
	)
	(segment
		(start 304.349912 3.778758)
		(end 304.349912 2.514854)
		(width 0.1651)
		(layer "F.Cu")
		(net "M_C_DQ<55>")
	)
	(segment
		(start 283.212794 -64.819784)
		(end 282.641294 -64.819784)
		(width 0.0889)
		(layer "F.Cu")
		(net "M_C_DQ<55>")
	)
	(segment
		(start 304.35042 3.778758)
		(end 304.349912 3.778758)
		(width 0.1651)
		(layer "F.Cu")
		(net "M_C_DQ<55>")
	)
	(via
		(at 282.641294 -64.819784)
		(size 0.508)
		(drill 0.254)
		(layers "F.Cu" "B.Cu")
		(net "M_C_DQ<55>")
	)
	(via
		(at 305.199796 -3.076956)
		(size 0.508)
		(drill 0.254)
		(layers "F.Cu" "B.Cu")
		(net "M_C_DQ<55>")
	)
	(via
		(at 304.349912 2.514854)
		(size 0.508)
		(drill 0.254)
		(layers "F.Cu" "B.Cu")
		(net "M_C_DQ<55>")
	)
	(segment
		(start 305.199796 -1.021842)
		(end 305.199796 -3.076956)
		(width 0.1651)
		(layer "B.Cu")
		(net "M_C_DQ<55>")
	)
	(segment
		(start 305.200304 -1.021842)
		(end 305.199796 -1.021842)
		(width 0.1651)
		(layer "B.Cu")
		(net "M_C_DQ<55>")
	)
	(segment
		(start 305.755802 -13.534644)
		(end 305.578002 -13.712444)
		(width 0.14224)
		(layer "In11.Cu")
		(net "M_C_DQ<55>")
	)
	(segment
		(start 283.334968 -49.068736)
		(end 283.334968 -51.211226)
		(width 0.0889)
		(layer "In11.Cu")
		(net "M_C_DQ<55>")
	)
	(segment
		(start 283.153104 -60.16244)
		(end 283.148278 -60.171076)
		(width 0.0889)
		(layer "In11.Cu")
		(net "M_C_DQ<55>")
	)
	(segment
		(start 283.334968 -51.211226)
		(end 283.049218 -51.496976)
		(width 0.0889)
		(layer "In11.Cu")
		(net "M_C_DQ<55>")
	)
	(segment
		(start 297.963082 -37.338)
		(end 290.8554 -37.338)
		(width 0.14224)
		(layer "In11.Cu")
		(net "M_C_DQ<55>")
	)
	(segment
		(start 305.70805 1.0922)
		(end 305.70805 0.7366)
		(width 0.14224)
		(layer "In11.Cu")
		(net "M_C_DQ<55>")
	)
	(segment
		(start 284.14472 -48.258984)
		(end 283.334968 -49.068736)
		(width 0.0889)
		(layer "In11.Cu")
		(net "M_C_DQ<55>")
	)
	(segment
		(start 305.552602 -2.72415)
		(end 305.199796 -3.076956)
		(width 0.14224)
		(layer "In11.Cu")
		(net "M_C_DQ<55>")
	)
	(segment
		(start 305.689 -9.525)
		(end 305.689 -11.598402)
		(width 0.14224)
		(layer "In11.Cu")
		(net "M_C_DQ<55>")
	)
	(segment
		(start 305.552602 -9.388602)
		(end 305.689 -9.525)
		(width 0.14224)
		(layer "In11.Cu")
		(net "M_C_DQ<55>")
	)
	(segment
		(start 305.592734 -4.80568)
		(end 305.592734 -7.304278)
		(width 0.14224)
		(layer "In11.Cu")
		(net "M_C_DQ<55>")
	)
	(segment
		(start 305.555396 -23.285196)
		(end 305.555396 -26.781252)
		(width 0.14224)
		(layer "In11.Cu")
		(net "M_C_DQ<55>")
	)
	(segment
		(start 283.153104 -59.17184)
		(end 283.148278 -59.180476)
		(width 0.0889)
		(layer "In11.Cu")
		(net "M_C_DQ<55>")
	)
	(segment
		(start 290.8554 -37.338)
		(end 287.782 -40.4114)
		(width 0.14224)
		(layer "In11.Cu")
		(net "M_C_DQ<55>")
	)
	(segment
		(start 305.552602 -9.000998)
		(end 305.552602 -9.388602)
		(width 0.14224)
		(layer "In11.Cu")
		(net "M_C_DQ<55>")
	)
	(segment
		(start 284.367224 -47.51197)
		(end 284.14472 -47.734474)
		(width 0.0889)
		(layer "In11.Cu")
		(net "M_C_DQ<55>")
	)
	(segment
		(start 305.552602 -12.170156)
		(end 305.755802 -12.373356)
		(width 0.14224)
		(layer "In11.Cu")
		(net "M_C_DQ<55>")
	)
	(segment
		(start 283.159454 -58.170572)
		(end 283.153104 -58.18124)
		(width 0.0889)
		(layer "In11.Cu")
		(net "M_C_DQ<55>")
	)
	(segment
		(start 305.72202 -17.07261)
		(end 305.72202 -18.382234)
		(width 0.14224)
		(layer "In11.Cu")
		(net "M_C_DQ<55>")
	)
	(segment
		(start 304.99685 1.5494)
		(end 305.25085 1.5494)
		(width 0.14224)
		(layer "In11.Cu")
		(net "M_C_DQ<55>")
	)
	(segment
		(start 305.25085 1.5494)
		(end 305.70805 1.0922)
		(width 0.14224)
		(layer "In11.Cu")
		(net "M_C_DQ<55>")
	)
	(segment
		(start 305.555396 -26.781252)
		(end 305.69916 -26.925016)
		(width 0.14224)
		(layer "In11.Cu")
		(net "M_C_DQ<55>")
	)
	(segment
		(start 305.534568 -29.766514)
		(end 297.963082 -37.338)
		(width 0.14224)
		(layer "In11.Cu")
		(net "M_C_DQ<55>")
	)
	(segment
		(start 305.689 -7.400544)
		(end 305.689 -8.8646)
		(width 0.14224)
		(layer "In11.Cu")
		(net "M_C_DQ<55>")
	)
	(segment
		(start 304.66665 2.198116)
		(end 304.66665 1.8796)
		(width 0.14224)
		(layer "In11.Cu")
		(net "M_C_DQ<55>")
	)
	(segment
		(start 305.72202 -18.382234)
		(end 305.5366 -18.567654)
		(width 0.14224)
		(layer "In11.Cu")
		(net "M_C_DQ<55>")
	)
	(segment
		(start 305.592734 -7.304278)
		(end 305.689 -7.400544)
		(width 0.14224)
		(layer "In11.Cu")
		(net "M_C_DQ<55>")
	)
	(segment
		(start 305.733196 -23.107396)
		(end 305.555396 -23.285196)
		(width 0.14224)
		(layer "In11.Cu")
		(net "M_C_DQ<55>")
	)
	(segment
		(start 283.049218 -54.325266)
		(end 283.232352 -54.5084)
		(width 0.0889)
		(layer "In11.Cu")
		(net "M_C_DQ<55>")
	)
	(segment
		(start 305.70805 0.7366)
		(end 305.552602 0.581152)
		(width 0.14224)
		(layer "In11.Cu")
		(net "M_C_DQ<55>")
	)
	(segment
		(start 284.14472 -47.734474)
		(end 284.14472 -48.258984)
		(width 0.0889)
		(layer "In11.Cu")
		(net "M_C_DQ<55>")
	)
	(segment
		(start 283.159454 -59.161172)
		(end 283.153104 -59.17184)
		(width 0.0889)
		(layer "In11.Cu")
		(net "M_C_DQ<55>")
	)
	(segment
		(start 282.641294 -64.819784)
		(end 282.988004 -64.029336)
		(width 0.0889)
		(layer "In11.Cu")
		(net "M_C_DQ<55>")
	)
	(segment
		(start 305.689 -11.598402)
		(end 305.552602 -11.7348)
		(width 0.14224)
		(layer "In11.Cu")
		(net "M_C_DQ<55>")
	)
	(segment
		(start 305.578002 -13.712444)
		(end 305.578002 -16.928592)
		(width 0.14224)
		(layer "In11.Cu")
		(net "M_C_DQ<55>")
	)
	(segment
		(start 284.367224 -47.06112)
		(end 284.367224 -47.51197)
		(width 0.14224)
		(layer "In11.Cu")
		(net "M_C_DQ<55>")
	)
	(segment
		(start 304.739802 -3.952748)
		(end 305.592734 -4.80568)
		(width 0.14224)
		(layer "In11.Cu")
		(net "M_C_DQ<55>")
	)
	(segment
		(start 305.733196 -21.879052)
		(end 305.733196 -23.107396)
		(width 0.14224)
		(layer "In11.Cu")
		(net "M_C_DQ<55>")
	)
	(segment
		(start 305.69916 -28.145232)
		(end 305.534568 -28.309824)
		(width 0.14224)
		(layer "In11.Cu")
		(net "M_C_DQ<55>")
	)
	(segment
		(start 287.782 -43.646344)
		(end 284.367224 -47.06112)
		(width 0.14224)
		(layer "In11.Cu")
		(net "M_C_DQ<55>")
	)
	(segment
		(start 305.755802 -12.373356)
		(end 305.755802 -13.534644)
		(width 0.14224)
		(layer "In11.Cu")
		(net "M_C_DQ<55>")
	)
	(segment
		(start 287.782 -40.4114)
		(end 287.782 -43.646344)
		(width 0.14224)
		(layer "In11.Cu")
		(net "M_C_DQ<55>")
	)
	(segment
		(start 283.232352 -54.5084)
		(end 283.232352 -54.913784)
		(width 0.0889)
		(layer "In11.Cu")
		(net "M_C_DQ<55>")
	)
	(segment
		(start 305.5366 -21.682456)
		(end 305.733196 -21.879052)
		(width 0.14224)
		(layer "In11.Cu")
		(net "M_C_DQ<55>")
	)
	(segment
		(start 283.153104 -58.18124)
		(end 283.148278 -58.189876)
		(width 0.0889)
		(layer "In11.Cu")
		(net "M_C_DQ<55>")
	)
	(segment
		(start 283.049218 -51.496976)
		(end 283.049218 -54.325266)
		(width 0.0889)
		(layer "In11.Cu")
		(net "M_C_DQ<55>")
	)
	(segment
		(start 304.739802 -3.53695)
		(end 304.739802 -3.952748)
		(width 0.14224)
		(layer "In11.Cu")
		(net "M_C_DQ<55>")
	)
	(segment
		(start 305.534568 -28.309824)
		(end 305.534568 -29.766514)
		(width 0.14224)
		(layer "In11.Cu")
		(net "M_C_DQ<55>")
	)
	(segment
		(start 304.66665 1.8796)
		(end 304.99685 1.5494)
		(width 0.14224)
		(layer "In11.Cu")
		(net "M_C_DQ<55>")
	)
	(segment
		(start 304.349912 2.514854)
		(end 304.66665 2.198116)
		(width 0.14224)
		(layer "In11.Cu")
		(net "M_C_DQ<55>")
	)
	(segment
		(start 283.159454 -60.151772)
		(end 283.153104 -60.16244)
		(width 0.0889)
		(layer "In11.Cu")
		(net "M_C_DQ<55>")
	)
	(segment
		(start 305.689 -8.8646)
		(end 305.552602 -9.000998)
		(width 0.14224)
		(layer "In11.Cu")
		(net "M_C_DQ<55>")
	)
	(segment
		(start 305.552602 0.581152)
		(end 305.552602 -2.72415)
		(width 0.14224)
		(layer "In11.Cu")
		(net "M_C_DQ<55>")
	)
	(segment
		(start 305.199796 -3.076956)
		(end 304.739802 -3.53695)
		(width 0.14224)
		(layer "In11.Cu")
		(net "M_C_DQ<55>")
	)
	(segment
		(start 283.153104 -61.15304)
		(end 283.148278 -61.161676)
		(width 0.0889)
		(layer "In11.Cu")
		(net "M_C_DQ<55>")
	)
	(segment
		(start 305.578002 -16.928592)
		(end 305.72202 -17.07261)
		(width 0.14224)
		(layer "In11.Cu")
		(net "M_C_DQ<55>")
	)
	(segment
		(start 305.5366 -18.567654)
		(end 305.5366 -21.682456)
		(width 0.14224)
		(layer "In11.Cu")
		(net "M_C_DQ<55>")
	)
	(segment
		(start 305.69916 -26.925016)
		(end 305.69916 -28.145232)
		(width 0.14224)
		(layer "In11.Cu")
		(net "M_C_DQ<55>")
	)
	(segment
		(start 305.552602 -11.7348)
		(end 305.552602 -12.170156)
		(width 0.14224)
		(layer "In11.Cu")
		(net "M_C_DQ<55>")
	)
	(segment
		(start 283.159454 -61.142372)
		(end 283.153104 -61.15304)
		(width 0.0889)
		(layer "In11.Cu")
		(net "M_C_DQ<55>")
	)
	(arc
		(start 283.153104 -60.56249)
		(mid 283.232326 -60.851608)
		(end 283.159454 -61.142372)
		(width 0.0889)
		(layer "In11.Cu")
		(net "M_C_DQ<55>")
	)
	(arc
		(start 283.153104 -61.552836)
		(mid 283.232235 -61.848238)
		(end 283.153104 -62.14364)
		(width 0.0889)
		(layer "In11.Cu")
		(net "M_C_DQ<55>")
	)
	(arc
		(start 283.153104 -57.190386)
		(mid 283.099478 -57.390538)
		(end 283.153104 -57.59069)
		(width 0.0889)
		(layer "In11.Cu")
		(net "M_C_DQ<55>")
	)
	(arc
		(start 282.988004 -64.029336)
		(mid 283.035364 -63.899267)
		(end 283.035502 -63.760858)
		(width 0.0889)
		(layer "In11.Cu")
		(net "M_C_DQ<55>")
	)
	(arc
		(start 283.148278 -58.189876)
		(mid 283.099523 -58.386228)
		(end 283.153104 -58.58129)
		(width 0.0889)
		(layer "In11.Cu")
		(net "M_C_DQ<55>")
	)
	(arc
		(start 283.153104 -59.57189)
		(mid 283.232326 -59.861008)
		(end 283.159454 -60.151772)
		(width 0.0889)
		(layer "In11.Cu")
		(net "M_C_DQ<55>")
	)
	(arc
		(start 283.153104 -56.199278)
		(mid 283.099478 -56.39943)
		(end 283.153104 -56.599582)
		(width 0.0889)
		(layer "In11.Cu")
		(net "M_C_DQ<55>")
	)
	(arc
		(start 283.148278 -55.6006)
		(mid 283.15074 -55.604507)
		(end 283.153104 -55.608474)
		(width 0.0889)
		(layer "In11.Cu")
		(net "M_C_DQ<55>")
	)
	(arc
		(start 283.153104 -55.209186)
		(mid 283.099634 -55.404249)
		(end 283.148278 -55.6006)
		(width 0.0889)
		(layer "In11.Cu")
		(net "M_C_DQ<55>")
	)
	(arc
		(start 283.153104 -62.543436)
		(mid 283.232235 -62.838838)
		(end 283.153104 -63.13424)
		(width 0.0889)
		(layer "In11.Cu")
		(net "M_C_DQ<55>")
	)
	(arc
		(start 283.232352 -54.913784)
		(mid 283.212161 -55.066698)
		(end 283.153104 -55.209186)
		(width 0.0889)
		(layer "In11.Cu")
		(net "M_C_DQ<55>")
	)
	(arc
		(start 283.153104 -55.608474)
		(mid 283.232235 -55.903876)
		(end 283.153104 -56.199278)
		(width 0.0889)
		(layer "In11.Cu")
		(net "M_C_DQ<55>")
	)
	(arc
		(start 283.153104 -58.58129)
		(mid 283.232326 -58.870408)
		(end 283.159454 -59.161172)
		(width 0.0889)
		(layer "In11.Cu")
		(net "M_C_DQ<55>")
	)
	(arc
		(start 283.153104 -56.599582)
		(mid 283.232235 -56.894984)
		(end 283.153104 -57.190386)
		(width 0.0889)
		(layer "In11.Cu")
		(net "M_C_DQ<55>")
	)
	(arc
		(start 283.148278 -59.180476)
		(mid 283.099523 -59.376828)
		(end 283.153104 -59.57189)
		(width 0.0889)
		(layer "In11.Cu")
		(net "M_C_DQ<55>")
	)
	(arc
		(start 283.153104 -57.59069)
		(mid 283.232326 -57.879808)
		(end 283.159454 -58.170572)
		(width 0.0889)
		(layer "In11.Cu")
		(net "M_C_DQ<55>")
	)
	(arc
		(start 283.148278 -61.161676)
		(mid 283.099584 -61.357884)
		(end 283.153104 -61.552836)
		(width 0.0889)
		(layer "In11.Cu")
		(net "M_C_DQ<55>")
	)
	(arc
		(start 283.148278 -60.171076)
		(mid 283.099523 -60.367428)
		(end 283.153104 -60.56249)
		(width 0.0889)
		(layer "In11.Cu")
		(net "M_C_DQ<55>")
	)
	(arc
		(start 283.153104 -62.14364)
		(mid 283.099605 -62.343538)
		(end 283.153104 -62.543436)
		(width 0.0889)
		(layer "In11.Cu")
		(net "M_C_DQ<55>")
	)
	(arc
		(start 283.153104 -63.13424)
		(mid 283.040858 -63.437516)
		(end 283.035502 -63.760858)
		(width 0.0889)
		(layer "In11.Cu")
		(net "M_C_DQ<55>")
	)
	(segment
		(start 305.20005 0.635)
		(end 305.20005 0.939546)
		(width 0.1651)
		(layer "F.Cu")
		(net "M_C_DQ<54>")
	)
	(segment
		(start 305.20005 -0.820928)
		(end 305.20005 0.1524)
		(width 0.1651)
		(layer "F.Cu")
		(net "M_C_DQ<54>")
	)
	(segment
		(start 305.33213 0.50292)
		(end 305.20005 0.635)
		(width 0.1651)
		(layer "F.Cu")
		(net "M_C_DQ<54>")
	)
	(segment
		(start 305.20005 0.939546)
		(end 305.199796 0.9398)
		(width 0.1651)
		(layer "F.Cu")
		(net "M_C_DQ<54>")
	)
	(segment
		(start 305.33213 0.28448)
		(end 305.33213 0.50292)
		(width 0.1651)
		(layer "F.Cu")
		(net "M_C_DQ<54>")
	)
	(segment
		(start 283.212794 -62.838584)
		(end 282.641294 -62.838584)
		(width 0.0889)
		(layer "F.Cu")
		(net "M_C_DQ<54>")
	)
	(segment
		(start 305.20005 0.1524)
		(end 305.33213 0.28448)
		(width 0.1651)
		(layer "F.Cu")
		(net "M_C_DQ<54>")
	)
	(segment
		(start 305.200304 -0.821182)
		(end 305.20005 -0.820928)
		(width 0.1651)
		(layer "F.Cu")
		(net "M_C_DQ<54>")
	)
	(via
		(at 282.641294 -62.838584)
		(size 0.508)
		(drill 0.254)
		(layers "F.Cu" "B.Cu")
		(net "M_C_DQ<54>")
	)
	(via
		(at 305.199796 0.9398)
		(size 0.508)
		(drill 0.254)
		(layers "F.Cu" "B.Cu")
		(net "M_C_DQ<54>")
	)
	(via
		(at 304.349912 -4.357878)
		(size 0.508)
		(drill 0.254)
		(layers "F.Cu" "B.Cu")
		(net "M_C_DQ<54>")
	)
	(segment
		(start 304.35042 -5.621782)
		(end 304.349912 -5.621782)
		(width 0.1651)
		(layer "B.Cu")
		(net "M_C_DQ<54>")
	)
	(segment
		(start 304.349912 -5.621782)
		(end 304.349912 -4.357878)
		(width 0.1651)
		(layer "B.Cu")
		(net "M_C_DQ<54>")
	)
	(segment
		(start 304.886868 -2.203196)
		(end 304.886868 -2.554986)
		(width 0.14224)
		(layer "In11.Cu")
		(net "M_C_DQ<54>")
	)
	(segment
		(start 304.842418 -0.768096)
		(end 304.842418 -1.111504)
		(width 0.14224)
		(layer "In11.Cu")
		(net "M_C_DQ<54>")
	)
	(segment
		(start 282.988004 -59.07659)
		(end 282.981654 -59.087258)
		(width 0.0889)
		(layer "In11.Cu")
		(net "M_C_DQ<54>")
	)
	(segment
		(start 304.461418 -0.387096)
		(end 304.842418 -0.768096)
		(width 0.14224)
		(layer "In11.Cu")
		(net "M_C_DQ<54>")
	)
	(segment
		(start 304.842418 -1.111504)
		(end 304.461418 -1.492504)
		(width 0.14224)
		(layer "In11.Cu")
		(net "M_C_DQ<54>")
	)
	(segment
		(start 304.714402 -8.829802)
		(end 304.917602 -9.033002)
		(width 0.14224)
		(layer "In11.Cu")
		(net "M_C_DQ<54>")
	)
	(segment
		(start 304.869596 -21.390356)
		(end 304.869596 -21.684996)
		(width 0.14224)
		(layer "In11.Cu")
		(net "M_C_DQ<54>")
	)
	(segment
		(start 283.95422 -48.17999)
		(end 283.144468 -48.989742)
		(width 0.0889)
		(layer "In11.Cu")
		(net "M_C_DQ<54>")
	)
	(segment
		(start 304.714402 -7.391146)
		(end 304.714402 -8.829802)
		(width 0.14224)
		(layer "In11.Cu")
		(net "M_C_DQ<54>")
	)
	(segment
		(start 282.99283 -58.077354)
		(end 282.988004 -58.08599)
		(width 0.0889)
		(layer "In11.Cu")
		(net "M_C_DQ<54>")
	)
	(segment
		(start 304.349912 -4.357878)
		(end 304.866802 -4.874768)
		(width 0.14224)
		(layer "In11.Cu")
		(net "M_C_DQ<54>")
	)
	(segment
		(start 297.50385 -36.8554)
		(end 289.8394 -36.8554)
		(width 0.14224)
		(layer "In11.Cu")
		(net "M_C_DQ<54>")
	)
	(segment
		(start 304.807112 -29.552138)
		(end 297.50385 -36.8554)
		(width 0.14224)
		(layer "In11.Cu")
		(net "M_C_DQ<54>")
	)
	(segment
		(start 304.546 -21.06676)
		(end 304.869596 -21.390356)
		(width 0.14224)
		(layer "In11.Cu")
		(net "M_C_DQ<54>")
	)
	(segment
		(start 304.1142 -4.122166)
		(end 304.349912 -4.357878)
		(width 0.14224)
		(layer "In11.Cu")
		(net "M_C_DQ<54>")
	)
	(segment
		(start 304.7238 -11.591798)
		(end 304.917602 -11.7856)
		(width 0.14224)
		(layer "In11.Cu")
		(net "M_C_DQ<54>")
	)
	(segment
		(start 282.858718 -54.404768)
		(end 283.041598 -54.587648)
		(width 0.0889)
		(layer "In11.Cu")
		(net "M_C_DQ<54>")
	)
	(segment
		(start 304.917602 -9.407398)
		(end 304.7238 -9.6012)
		(width 0.14224)
		(layer "In11.Cu")
		(net "M_C_DQ<54>")
	)
	(segment
		(start 282.988004 -58.08599)
		(end 282.981654 -58.096658)
		(width 0.0889)
		(layer "In11.Cu")
		(net "M_C_DQ<54>")
	)
	(segment
		(start 288.74847 -38.147498)
		(end 288.547302 -38.147498)
		(width 0.14224)
		(layer "In11.Cu")
		(net "M_C_DQ<54>")
	)
	(segment
		(start 283.732224 -46.906434)
		(end 283.732224 -47.51197)
		(width 0.14224)
		(layer "In11.Cu")
		(net "M_C_DQ<54>")
	)
	(segment
		(start 304.917602 -11.7856)
		(end 304.917602 -12.170156)
		(width 0.14224)
		(layer "In11.Cu")
		(net "M_C_DQ<54>")
	)
	(segment
		(start 283.95422 -47.733966)
		(end 283.95422 -48.17999)
		(width 0.0889)
		(layer "In11.Cu")
		(net "M_C_DQ<54>")
	)
	(segment
		(start 288.247582 -39.285418)
		(end 288.046414 -39.285418)
		(width 0.14224)
		(layer "In11.Cu")
		(net "M_C_DQ<54>")
	)
	(segment
		(start 304.894996 -16.829786)
		(end 304.717196 -17.007586)
		(width 0.14224)
		(layer "In11.Cu")
		(net "M_C_DQ<54>")
	)
	(segment
		(start 304.7238 -9.6012)
		(end 304.7238 -11.591798)
		(width 0.14224)
		(layer "In11.Cu")
		(net "M_C_DQ<54>")
	)
	(segment
		(start 304.866802 -7.238746)
		(end 304.714402 -7.391146)
		(width 0.14224)
		(layer "In11.Cu")
		(net "M_C_DQ<54>")
	)
	(segment
		(start 289.426396 -38.106604)
		(end 289.16757 -38.36543)
		(width 0.14224)
		(layer "In11.Cu")
		(net "M_C_DQ<54>")
	)
	(segment
		(start 283.144468 -51.129946)
		(end 282.858718 -51.415696)
		(width 0.0889)
		(layer "In11.Cu")
		(net "M_C_DQ<54>")
	)
	(segment
		(start 305.199796 0.9398)
		(end 304.8254 0.565404)
		(width 0.14224)
		(layer "In11.Cu")
		(net "M_C_DQ<54>")
	)
	(segment
		(start 288.506408 -39.026592)
		(end 288.247582 -39.285418)
		(width 0.14224)
		(layer "In11.Cu")
		(net "M_C_DQ<54>")
	)
	(segment
		(start 282.958286 -62.58052)
		(end 282.93441 -62.669674)
		(width 0.0889)
		(layer "In11.Cu")
		(net "M_C_DQ<54>")
	)
	(segment
		(start 304.869596 -18.8849)
		(end 304.546 -19.208496)
		(width 0.14224)
		(layer "In11.Cu")
		(net "M_C_DQ<54>")
	)
	(segment
		(start 304.714402 -12.373356)
		(end 304.714402 -13.595604)
		(width 0.14224)
		(layer "In11.Cu")
		(net "M_C_DQ<54>")
	)
	(segment
		(start 289.208464 -37.687504)
		(end 289.426396 -37.905436)
		(width 0.14224)
		(layer "In11.Cu")
		(net "M_C_DQ<54>")
	)
	(segment
		(start 304.666396 -23.098252)
		(end 304.869596 -23.301452)
		(width 0.14224)
		(layer "In11.Cu")
		(net "M_C_DQ<54>")
	)
	(segment
		(start 283.732224 -47.51197)
		(end 283.95422 -47.733966)
		(width 0.0889)
		(layer "In11.Cu")
		(net "M_C_DQ<54>")
	)
	(segment
		(start 304.461418 -0.076454)
		(end 304.461418 -0.387096)
		(width 0.14224)
		(layer "In11.Cu")
		(net "M_C_DQ<54>")
	)
	(segment
		(start 304.866802 -4.874768)
		(end 304.866802 -7.238746)
		(width 0.14224)
		(layer "In11.Cu")
		(net "M_C_DQ<54>")
	)
	(segment
		(start 304.816002 -16.369792)
		(end 304.894996 -16.448786)
		(width 0.14224)
		(layer "In11.Cu")
		(net "M_C_DQ<54>")
	)
	(segment
		(start 282.99283 -60.058554)
		(end 282.988004 -60.06719)
		(width 0.0889)
		(layer "In11.Cu")
		(net "M_C_DQ<54>")
	)
	(segment
		(start 288.288476 -38.406324)
		(end 288.288476 -38.607492)
		(width 0.14224)
		(layer "In11.Cu")
		(net "M_C_DQ<54>")
	)
	(segment
		(start 283.041598 -54.587648)
		(end 283.041598 -54.913784)
		(width 0.0889)
		(layer "In11.Cu")
		(net "M_C_DQ<54>")
	)
	(segment
		(start 282.93441 -62.669674)
		(end 282.641294 -62.838584)
		(width 0.0889)
		(layer "In11.Cu")
		(net "M_C_DQ<54>")
	)
	(segment
		(start 304.717196 -17.007586)
		(end 304.717196 -18.43405)
		(width 0.14224)
		(layer "In11.Cu")
		(net "M_C_DQ<54>")
	)
	(segment
		(start 304.869596 -21.684996)
		(end 304.666396 -21.888196)
		(width 0.14224)
		(layer "In11.Cu")
		(net "M_C_DQ<54>")
	)
	(segment
		(start 304.869596 -26.815796)
		(end 304.691796 -26.993596)
		(width 0.14224)
		(layer "In11.Cu")
		(net "M_C_DQ<54>")
	)
	(segment
		(start 288.547302 -38.147498)
		(end 288.288476 -38.406324)
		(width 0.14224)
		(layer "In11.Cu")
		(net "M_C_DQ<54>")
	)
	(segment
		(start 288.506408 -38.825424)
		(end 288.506408 -39.026592)
		(width 0.14224)
		(layer "In11.Cu")
		(net "M_C_DQ<54>")
	)
	(segment
		(start 304.807112 -28.251912)
		(end 304.807112 -29.552138)
		(width 0.14224)
		(layer "In11.Cu")
		(net "M_C_DQ<54>")
	)
	(segment
		(start 287.627314 -39.067486)
		(end 287.093152 -39.601648)
		(width 0.14224)
		(layer "In11.Cu")
		(net "M_C_DQ<54>")
	)
	(segment
		(start 282.99283 -59.067954)
		(end 282.988004 -59.07659)
		(width 0.0889)
		(layer "In11.Cu")
		(net "M_C_DQ<54>")
	)
	(segment
		(start 282.99283 -61.049154)
		(end 282.988004 -61.05779)
		(width 0.0889)
		(layer "In11.Cu")
		(net "M_C_DQ<54>")
	)
	(segment
		(start 288.288476 -38.607492)
		(end 288.506408 -38.825424)
		(width 0.14224)
		(layer "In11.Cu")
		(net "M_C_DQ<54>")
	)
	(segment
		(start 304.8254 0.287528)
		(end 304.461418 -0.076454)
		(width 0.14224)
		(layer "In11.Cu")
		(net "M_C_DQ<54>")
	)
	(segment
		(start 282.988004 -60.06719)
		(end 282.981654 -60.077858)
		(width 0.0889)
		(layer "In11.Cu")
		(net "M_C_DQ<54>")
	)
	(segment
		(start 304.546 -19.208496)
		(end 304.546 -21.06676)
		(width 0.14224)
		(layer "In11.Cu")
		(net "M_C_DQ<54>")
	)
	(segment
		(start 304.461418 -1.492504)
		(end 304.461418 -1.777746)
		(width 0.14224)
		(layer "In11.Cu")
		(net "M_C_DQ<54>")
	)
	(segment
		(start 304.816002 -13.697204)
		(end 304.816002 -16.369792)
		(width 0.14224)
		(layer "In11.Cu")
		(net "M_C_DQ<54>")
	)
	(segment
		(start 304.917602 -12.170156)
		(end 304.714402 -12.373356)
		(width 0.14224)
		(layer "In11.Cu")
		(net "M_C_DQ<54>")
	)
	(segment
		(start 287.093152 -39.601648)
		(end 287.093152 -43.545506)
		(width 0.14224)
		(layer "In11.Cu")
		(net "M_C_DQ<54>")
	)
	(segment
		(start 282.988004 -61.05779)
		(end 282.981654 -61.068458)
		(width 0.0889)
		(layer "In11.Cu")
		(net "M_C_DQ<54>")
	)
	(segment
		(start 304.714402 -13.595604)
		(end 304.816002 -13.697204)
		(width 0.14224)
		(layer "In11.Cu")
		(net "M_C_DQ<54>")
	)
	(segment
		(start 287.093152 -43.545506)
		(end 283.732224 -46.906434)
		(width 0.14224)
		(layer "In11.Cu")
		(net "M_C_DQ<54>")
	)
	(segment
		(start 289.426396 -37.905436)
		(end 289.426396 -38.106604)
		(width 0.14224)
		(layer "In11.Cu")
		(net "M_C_DQ<54>")
	)
	(segment
		(start 304.869596 -18.58645)
		(end 304.869596 -18.8849)
		(width 0.14224)
		(layer "In11.Cu")
		(net "M_C_DQ<54>")
	)
	(segment
		(start 304.717196 -18.43405)
		(end 304.869596 -18.58645)
		(width 0.14224)
		(layer "In11.Cu")
		(net "M_C_DQ<54>")
	)
	(segment
		(start 304.691796 -28.136596)
		(end 304.807112 -28.251912)
		(width 0.14224)
		(layer "In11.Cu")
		(net "M_C_DQ<54>")
	)
	(segment
		(start 304.8254 0.565404)
		(end 304.8254 0.287528)
		(width 0.14224)
		(layer "In11.Cu")
		(net "M_C_DQ<54>")
	)
	(segment
		(start 282.858718 -51.415696)
		(end 282.858718 -54.404768)
		(width 0.0889)
		(layer "In11.Cu")
		(net "M_C_DQ<54>")
	)
	(segment
		(start 288.966402 -38.36543)
		(end 288.74847 -38.147498)
		(width 0.14224)
		(layer "In11.Cu")
		(net "M_C_DQ<54>")
	)
	(segment
		(start 288.046414 -39.285418)
		(end 287.828482 -39.067486)
		(width 0.14224)
		(layer "In11.Cu")
		(net "M_C_DQ<54>")
	)
	(segment
		(start 304.666396 -21.888196)
		(end 304.666396 -23.098252)
		(width 0.14224)
		(layer "In11.Cu")
		(net "M_C_DQ<54>")
	)
	(segment
		(start 287.828482 -39.067486)
		(end 287.627314 -39.067486)
		(width 0.14224)
		(layer "In11.Cu")
		(net "M_C_DQ<54>")
	)
	(segment
		(start 304.461418 -1.777746)
		(end 304.886868 -2.203196)
		(width 0.14224)
		(layer "In11.Cu")
		(net "M_C_DQ<54>")
	)
	(segment
		(start 304.917602 -9.033002)
		(end 304.917602 -9.407398)
		(width 0.14224)
		(layer "In11.Cu")
		(net "M_C_DQ<54>")
	)
	(segment
		(start 304.894996 -16.448786)
		(end 304.894996 -16.829786)
		(width 0.14224)
		(layer "In11.Cu")
		(net "M_C_DQ<54>")
	)
	(segment
		(start 304.869596 -23.301452)
		(end 304.869596 -26.815796)
		(width 0.14224)
		(layer "In11.Cu")
		(net "M_C_DQ<54>")
	)
	(segment
		(start 289.8394 -36.8554)
		(end 289.208464 -37.486336)
		(width 0.14224)
		(layer "In11.Cu")
		(net "M_C_DQ<54>")
	)
	(segment
		(start 289.16757 -38.36543)
		(end 288.966402 -38.36543)
		(width 0.14224)
		(layer "In11.Cu")
		(net "M_C_DQ<54>")
	)
	(segment
		(start 283.144468 -48.989742)
		(end 283.144468 -51.129946)
		(width 0.0889)
		(layer "In11.Cu")
		(net "M_C_DQ<54>")
	)
	(segment
		(start 304.691796 -26.993596)
		(end 304.691796 -28.136596)
		(width 0.14224)
		(layer "In11.Cu")
		(net "M_C_DQ<54>")
	)
	(segment
		(start 304.886868 -2.554986)
		(end 304.1142 -3.327654)
		(width 0.14224)
		(layer "In11.Cu")
		(net "M_C_DQ<54>")
	)
	(segment
		(start 289.208464 -37.486336)
		(end 289.208464 -37.687504)
		(width 0.14224)
		(layer "In11.Cu")
		(net "M_C_DQ<54>")
	)
	(segment
		(start 304.1142 -3.327654)
		(end 304.1142 -4.122166)
		(width 0.14224)
		(layer "In11.Cu")
		(net "M_C_DQ<54>")
	)
	(arc
		(start 282.981654 -55.693818)
		(mid 282.984661 -55.698879)
		(end 282.988004 -55.703724)
		(width 0.0889)
		(layer "In11.Cu")
		(net "M_C_DQ<54>")
	)
	(arc
		(start 282.981654 -59.087258)
		(mid 282.908856 -59.378021)
		(end 282.988004 -59.66714)
		(width 0.0889)
		(layer "In11.Cu")
		(net "M_C_DQ<54>")
	)
	(arc
		(start 282.988004 -55.703724)
		(mid 283.04163 -55.903876)
		(end 282.988004 -56.104028)
		(width 0.0889)
		(layer "In11.Cu")
		(net "M_C_DQ<54>")
	)
	(arc
		(start 282.988004 -55.113936)
		(mid 282.908782 -55.403054)
		(end 282.981654 -55.693818)
		(width 0.0889)
		(layer "In11.Cu")
		(net "M_C_DQ<54>")
	)
	(arc
		(start 282.988004 -59.66714)
		(mid 283.041474 -59.862203)
		(end 282.99283 -60.058554)
		(width 0.0889)
		(layer "In11.Cu")
		(net "M_C_DQ<54>")
	)
	(arc
		(start 282.988004 -56.104028)
		(mid 282.908873 -56.39943)
		(end 282.988004 -56.694832)
		(width 0.0889)
		(layer "In11.Cu")
		(net "M_C_DQ<54>")
	)
	(arc
		(start 282.988004 -58.67654)
		(mid 283.041474 -58.871603)
		(end 282.99283 -59.067954)
		(width 0.0889)
		(layer "In11.Cu")
		(net "M_C_DQ<54>")
	)
	(arc
		(start 282.981654 -61.068458)
		(mid 282.90895 -61.359221)
		(end 282.988004 -61.64834)
		(width 0.0889)
		(layer "In11.Cu")
		(net "M_C_DQ<54>")
	)
	(arc
		(start 282.988004 -61.64834)
		(mid 283.041503 -61.848238)
		(end 282.988004 -62.048136)
		(width 0.0889)
		(layer "In11.Cu")
		(net "M_C_DQ<54>")
	)
	(arc
		(start 282.981654 -58.096658)
		(mid 282.908856 -58.387421)
		(end 282.988004 -58.67654)
		(width 0.0889)
		(layer "In11.Cu")
		(net "M_C_DQ<54>")
	)
	(arc
		(start 282.981654 -60.077858)
		(mid 282.908856 -60.368621)
		(end 282.988004 -60.65774)
		(width 0.0889)
		(layer "In11.Cu")
		(net "M_C_DQ<54>")
	)
	(arc
		(start 282.988004 -56.694832)
		(mid 283.04163 -56.894984)
		(end 282.988004 -57.095136)
		(width 0.0889)
		(layer "In11.Cu")
		(net "M_C_DQ<54>")
	)
	(arc
		(start 283.041598 -54.913784)
		(mid 283.027968 -55.017386)
		(end 282.988004 -55.113936)
		(width 0.0889)
		(layer "In11.Cu")
		(net "M_C_DQ<54>")
	)
	(arc
		(start 282.988004 -57.095136)
		(mid 282.908873 -57.390538)
		(end 282.988004 -57.68594)
		(width 0.0889)
		(layer "In11.Cu")
		(net "M_C_DQ<54>")
	)
	(arc
		(start 282.988004 -60.65774)
		(mid 283.041474 -60.852803)
		(end 282.99283 -61.049154)
		(width 0.0889)
		(layer "In11.Cu")
		(net "M_C_DQ<54>")
	)
	(arc
		(start 282.988004 -57.68594)
		(mid 283.041474 -57.881003)
		(end 282.99283 -58.077354)
		(width 0.0889)
		(layer "In11.Cu")
		(net "M_C_DQ<54>")
	)
	(arc
		(start 282.988004 -62.048136)
		(mid 282.909667 -62.310792)
		(end 282.958286 -62.58052)
		(width 0.0889)
		(layer "In11.Cu")
		(net "M_C_DQ<54>")
	)
	(segment
		(start 298.40047 3.778758)
		(end 298.399962 3.778758)
		(width 0.1651)
		(layer "F.Cu")
		(net "M_C_DQ<53>")
	)
	(segment
		(start 298.399962 3.778758)
		(end 298.399962 2.514854)
		(width 0.1651)
		(layer "F.Cu")
		(net "M_C_DQ<53>")
	)
	(segment
		(start 280.637234 -64.324738)
		(end 280.065734 -64.324738)
		(width 0.0889)
		(layer "F.Cu")
		(net "M_C_DQ<53>")
	)
	(via
		(at 299.173646 -3.076956)
		(size 0.508)
		(drill 0.254)
		(layers "F.Cu" "B.Cu")
		(net "M_C_DQ<53>")
	)
	(via
		(at 298.399962 2.514854)
		(size 0.508)
		(drill 0.254)
		(layers "F.Cu" "B.Cu")
		(net "M_C_DQ<53>")
	)
	(via
		(at 280.065734 -64.324738)
		(size 0.508)
		(drill 0.254)
		(layers "F.Cu" "B.Cu")
		(net "M_C_DQ<53>")
	)
	(segment
		(start 299.249846 -3.000756)
		(end 299.173646 -3.076956)
		(width 0.1651)
		(layer "B.Cu")
		(net "M_C_DQ<53>")
	)
	(segment
		(start 299.250354 -1.021842)
		(end 299.249846 -1.021842)
		(width 0.1651)
		(layer "B.Cu")
		(net "M_C_DQ<53>")
	)
	(segment
		(start 299.249846 -1.021842)
		(end 299.249846 -3.000756)
		(width 0.1651)
		(layer "B.Cu")
		(net "M_C_DQ<53>")
	)
	(segment
		(start 299.569632 -18.975832)
		(end 299.7454 -19.1516)
		(width 0.14224)
		(layer "In11.Cu")
		(net "M_C_DQ<53>")
	)
	(segment
		(start 299.569632 -21.3614)
		(end 299.569632 -21.786088)
		(width 0.14224)
		(layer "In11.Cu")
		(net "M_C_DQ<53>")
	)
	(segment
		(start 299.764196 -23.183596)
		(end 299.586396 -23.361396)
		(width 0.14224)
		(layer "In11.Cu")
		(net "M_C_DQ<53>")
	)
	(segment
		(start 299.560996 -17.007586)
		(end 299.713396 -17.159986)
		(width 0.14224)
		(layer "In11.Cu")
		(net "M_C_DQ<53>")
	)
	(segment
		(start 279.470104 -47.394622)
		(end 279.470104 -53.178964)
		(width 0.0889)
		(layer "In11.Cu")
		(net "M_C_DQ<53>")
	)
	(segment
		(start 299.713396 -17.159986)
		(end 299.713396 -18.33245)
		(width 0.14224)
		(layer "In11.Cu")
		(net "M_C_DQ<53>")
	)
	(segment
		(start 279.719024 -56.599836)
		(end 279.725374 -56.610504)
		(width 0.0889)
		(layer "In11.Cu")
		(net "M_C_DQ<53>")
	)
	(segment
		(start 299.6819 0.7366)
		(end 299.48505 0.53975)
		(width 0.14224)
		(layer "In11.Cu")
		(net "M_C_DQ<53>")
	)
	(segment
		(start 279.798272 -53.507132)
		(end 279.798272 -53.922676)
		(width 0.0889)
		(layer "In11.Cu")
		(net "M_C_DQ<53>")
	)
	(segment
		(start 299.764196 -21.980652)
		(end 299.764196 -23.183596)
		(width 0.14224)
		(layer "In11.Cu")
		(net "M_C_DQ<53>")
	)
	(segment
		(start 299.738796 -13.531596)
		(end 299.560996 -13.709396)
		(width 0.14224)
		(layer "In11.Cu")
		(net "M_C_DQ<53>")
	)
	(segment
		(start 280.395172 -63.563754)
		(end 280.41727 -63.5254)
		(width 0.0889)
		(layer "In11.Cu")
		(net "M_C_DQ<53>")
	)
	(segment
		(start 293.561516 -32.0548)
		(end 289.366706 -32.0548)
		(width 0.14224)
		(layer "In11.Cu")
		(net "M_C_DQ<53>")
	)
	(segment
		(start 299.560996 -13.709396)
		(end 299.560996 -17.007586)
		(width 0.14224)
		(layer "In11.Cu")
		(net "M_C_DQ<53>")
	)
	(segment
		(start 280.246836 -63.9064)
		(end 280.378662 -63.6016)
		(width 0.0889)
		(layer "In11.Cu")
		(net "M_C_DQ<53>")
	)
	(segment
		(start 299.590968 -29.234892)
		(end 298.52366 -30.3022)
		(width 0.14224)
		(layer "In11.Cu")
		(net "M_C_DQ<53>")
	)
	(segment
		(start 299.569632 -21.786088)
		(end 299.764196 -21.980652)
		(width 0.14224)
		(layer "In11.Cu")
		(net "M_C_DQ<53>")
	)
	(segment
		(start 279.913842 -62.71387)
		(end 280.358596 -63.040768)
		(width 0.0889)
		(layer "In11.Cu")
		(net "M_C_DQ<53>")
	)
	(segment
		(start 280.065734 -64.324738)
		(end 280.246836 -63.9064)
		(width 0.0889)
		(layer "In11.Cu")
		(net "M_C_DQ<53>")
	)
	(segment
		(start 279.725374 -59.160918)
		(end 279.719024 -59.171586)
		(width 0.0889)
		(layer "In11.Cu")
		(net "M_C_DQ<53>")
	)
	(segment
		(start 299.7454 -21.185632)
		(end 299.569632 -21.3614)
		(width 0.14224)
		(layer "In11.Cu")
		(net "M_C_DQ<53>")
	)
	(segment
		(start 298.957746 -3.292856)
		(end 298.957746 -3.293872)
		(width 0.14224)
		(layer "In11.Cu")
		(net "M_C_DQ<53>")
	)
	(segment
		(start 299.558202 -8.991346)
		(end 299.558202 -12.198858)
		(width 0.14224)
		(layer "In11.Cu")
		(net "M_C_DQ<53>")
	)
	(segment
		(start 299.590968 -28.259024)
		(end 299.590968 -29.234892)
		(width 0.14224)
		(layer "In11.Cu")
		(net "M_C_DQ<53>")
	)
	(segment
		(start 279.719024 -54.618636)
		(end 279.725374 -54.629304)
		(width 0.0889)
		(layer "In11.Cu")
		(net "M_C_DQ<53>")
	)
	(segment
		(start 299.212 -6.2992)
		(end 299.583602 -6.670802)
		(width 0.14224)
		(layer "In11.Cu")
		(net "M_C_DQ<53>")
	)
	(segment
		(start 282.800806 -38.6207)
		(end 282.800806 -42.233596)
		(width 0.14224)
		(layer "In11.Cu")
		(net "M_C_DQ<53>")
	)
	(segment
		(start 280.378662 -63.6016)
		(end 280.395172 -63.563754)
		(width 0.0889)
		(layer "In11.Cu")
		(net "M_C_DQ<53>")
	)
	(segment
		(start 289.366706 -32.0548)
		(end 282.800806 -38.6207)
		(width 0.14224)
		(layer "In11.Cu")
		(net "M_C_DQ<53>")
	)
	(segment
		(start 279.719024 -60.562236)
		(end 279.725374 -60.572904)
		(width 0.0889)
		(layer "In11.Cu")
		(net "M_C_DQ<53>")
	)
	(segment
		(start 299.583602 -7.264146)
		(end 299.647102 -7.327646)
		(width 0.14224)
		(layer "In11.Cu")
		(net "M_C_DQ<53>")
	)
	(segment
		(start 299.647102 -8.902446)
		(end 299.558202 -8.991346)
		(width 0.14224)
		(layer "In11.Cu")
		(net "M_C_DQ<53>")
	)
	(segment
		(start 295.695116 -30.0228)
		(end 295.288716 -30.0228)
		(width 0.14224)
		(layer "In11.Cu")
		(net "M_C_DQ<53>")
	)
	(segment
		(start 295.085516 -30.226)
		(end 295.085516 -30.5308)
		(width 0.14224)
		(layer "In11.Cu")
		(net "M_C_DQ<53>")
	)
	(segment
		(start 279.714198 -60.5536)
		(end 279.719024 -60.562236)
		(width 0.0889)
		(layer "In11.Cu")
		(net "M_C_DQ<53>")
	)
	(segment
		(start 279.7048 -47.159926)
		(end 279.470104 -47.394622)
		(width 0.0889)
		(layer "In11.Cu")
		(net "M_C_DQ<53>")
	)
	(segment
		(start 299.586396 -26.781252)
		(end 299.667168 -26.862024)
		(width 0.14224)
		(layer "In11.Cu")
		(net "M_C_DQ<53>")
	)
	(segment
		(start 295.974516 -30.3022)
		(end 295.695116 -30.0228)
		(width 0.14224)
		(layer "In11.Cu")
		(net "M_C_DQ<53>")
	)
	(segment
		(start 299.647102 -7.327646)
		(end 299.647102 -8.902446)
		(width 0.14224)
		(layer "In11.Cu")
		(net "M_C_DQ<53>")
	)
	(segment
		(start 299.212 -4.483354)
		(end 299.212 -6.2992)
		(width 0.14224)
		(layer "In11.Cu")
		(net "M_C_DQ<53>")
	)
	(segment
		(start 298.52366 -30.3022)
		(end 295.974516 -30.3022)
		(width 0.14224)
		(layer "In11.Cu")
		(net "M_C_DQ<53>")
	)
	(segment
		(start 299.738796 -12.379452)
		(end 299.738796 -13.531596)
		(width 0.14224)
		(layer "In11.Cu")
		(net "M_C_DQ<53>")
	)
	(segment
		(start 279.714198 -54.61)
		(end 279.719024 -54.618636)
		(width 0.0889)
		(layer "In11.Cu")
		(net "M_C_DQ<53>")
	)
	(segment
		(start 298.9707 1.5494)
		(end 299.281596 1.5494)
		(width 0.14224)
		(layer "In11.Cu")
		(net "M_C_DQ<53>")
	)
	(segment
		(start 279.714198 -58.5724)
		(end 279.719024 -58.581036)
		(width 0.0889)
		(layer "In11.Cu")
		(net "M_C_DQ<53>")
	)
	(segment
		(start 299.558202 -12.198858)
		(end 299.738796 -12.379452)
		(width 0.14224)
		(layer "In11.Cu")
		(net "M_C_DQ<53>")
	)
	(segment
		(start 299.667168 -28.182824)
		(end 299.590968 -28.259024)
		(width 0.14224)
		(layer "In11.Cu")
		(net "M_C_DQ<53>")
	)
	(segment
		(start 299.48505 0.53975)
		(end 299.48505 -2.765552)
		(width 0.14224)
		(layer "In11.Cu")
		(net "M_C_DQ<53>")
	)
	(segment
		(start 299.173646 -3.076956)
		(end 298.957746 -3.292856)
		(width 0.14224)
		(layer "In11.Cu")
		(net "M_C_DQ<53>")
	)
	(segment
		(start 298.399962 2.514854)
		(end 298.399962 2.120138)
		(width 0.14224)
		(layer "In11.Cu")
		(net "M_C_DQ<53>")
	)
	(segment
		(start 279.714198 -56.5912)
		(end 279.719024 -56.599836)
		(width 0.0889)
		(layer "In11.Cu")
		(net "M_C_DQ<53>")
	)
	(segment
		(start 298.669202 -3.940556)
		(end 299.212 -4.483354)
		(width 0.14224)
		(layer "In11.Cu")
		(net "M_C_DQ<53>")
	)
	(segment
		(start 282.800806 -42.233596)
		(end 279.7048 -45.329602)
		(width 0.14224)
		(layer "In11.Cu")
		(net "M_C_DQ<53>")
	)
	(segment
		(start 298.399962 2.120138)
		(end 298.9707 1.5494)
		(width 0.14224)
		(layer "In11.Cu")
		(net "M_C_DQ<53>")
	)
	(segment
		(start 299.7454 -19.1516)
		(end 299.7454 -21.185632)
		(width 0.14224)
		(layer "In11.Cu")
		(net "M_C_DQ<53>")
	)
	(segment
		(start 295.085516 -30.5308)
		(end 293.561516 -32.0548)
		(width 0.14224)
		(layer "In11.Cu")
		(net "M_C_DQ<53>")
	)
	(segment
		(start 298.669202 -3.582416)
		(end 298.669202 -3.940556)
		(width 0.14224)
		(layer "In11.Cu")
		(net "M_C_DQ<53>")
	)
	(segment
		(start 279.714198 -55.6006)
		(end 279.719024 -55.609236)
		(width 0.0889)
		(layer "In11.Cu")
		(net "M_C_DQ<53>")
	)
	(segment
		(start 279.714198 -57.5818)
		(end 279.719024 -57.590436)
		(width 0.0889)
		(layer "In11.Cu")
		(net "M_C_DQ<53>")
	)
	(segment
		(start 279.719024 -57.590436)
		(end 279.725374 -57.601104)
		(width 0.0889)
		(layer "In11.Cu")
		(net "M_C_DQ<53>")
	)
	(segment
		(start 279.7048 -45.329602)
		(end 279.7048 -47.159926)
		(width 0.14224)
		(layer "In11.Cu")
		(net "M_C_DQ<53>")
	)
	(segment
		(start 299.667168 -26.862024)
		(end 299.667168 -28.182824)
		(width 0.14224)
		(layer "In11.Cu")
		(net "M_C_DQ<53>")
	)
	(segment
		(start 299.569632 -18.476214)
		(end 299.569632 -18.975832)
		(width 0.14224)
		(layer "In11.Cu")
		(net "M_C_DQ<53>")
	)
	(segment
		(start 299.48505 -2.765552)
		(end 299.173646 -3.076956)
		(width 0.14224)
		(layer "In11.Cu")
		(net "M_C_DQ<53>")
	)
	(segment
		(start 279.470104 -53.178964)
		(end 279.798272 -53.507132)
		(width 0.0889)
		(layer "In11.Cu")
		(net "M_C_DQ<53>")
	)
	(segment
		(start 295.288716 -30.0228)
		(end 295.085516 -30.226)
		(width 0.14224)
		(layer "In11.Cu")
		(net "M_C_DQ<53>")
	)
	(segment
		(start 299.583602 -6.670802)
		(end 299.583602 -7.264146)
		(width 0.14224)
		(layer "In11.Cu")
		(net "M_C_DQ<53>")
	)
	(segment
		(start 279.719024 -61.552836)
		(end 279.725374 -61.563504)
		(width 0.0889)
		(layer "In11.Cu")
		(net "M_C_DQ<53>")
	)
	(segment
		(start 280.412444 -63.133986)
		(end 280.358596 -63.040768)
		(width 0.0889)
		(layer "In11.Cu")
		(net "M_C_DQ<53>")
	)
	(segment
		(start 298.957746 -3.293872)
		(end 298.669202 -3.582416)
		(width 0.14224)
		(layer "In11.Cu")
		(net "M_C_DQ<53>")
	)
	(segment
		(start 279.719024 -55.609236)
		(end 279.725374 -55.619904)
		(width 0.0889)
		(layer "In11.Cu")
		(net "M_C_DQ<53>")
	)
	(segment
		(start 299.281596 1.5494)
		(end 299.6819 1.149096)
		(width 0.14224)
		(layer "In11.Cu")
		(net "M_C_DQ<53>")
	)
	(segment
		(start 299.6819 1.149096)
		(end 299.6819 0.7366)
		(width 0.14224)
		(layer "In11.Cu")
		(net "M_C_DQ<53>")
	)
	(segment
		(start 299.586396 -23.361396)
		(end 299.586396 -26.781252)
		(width 0.14224)
		(layer "In11.Cu")
		(net "M_C_DQ<53>")
	)
	(segment
		(start 299.713396 -18.33245)
		(end 299.569632 -18.476214)
		(width 0.14224)
		(layer "In11.Cu")
		(net "M_C_DQ<53>")
	)
	(segment
		(start 279.714198 -61.5442)
		(end 279.719024 -61.552836)
		(width 0.0889)
		(layer "In11.Cu")
		(net "M_C_DQ<53>")
	)
	(arc
		(start 279.725374 -54.629304)
		(mid 279.798172 -54.920067)
		(end 279.719024 -55.209186)
		(width 0.0889)
		(layer "In11.Cu")
		(net "M_C_DQ<53>")
	)
	(arc
		(start 279.719024 -59.171586)
		(mid 279.665525 -59.371484)
		(end 279.719024 -59.571382)
		(width 0.0889)
		(layer "In11.Cu")
		(net "M_C_DQ<53>")
	)
	(arc
		(start 279.719024 -58.180986)
		(mid 279.665554 -58.376049)
		(end 279.714198 -58.5724)
		(width 0.0889)
		(layer "In11.Cu")
		(net "M_C_DQ<53>")
	)
	(arc
		(start 279.719024 -60.162186)
		(mid 279.665554 -60.357249)
		(end 279.714198 -60.5536)
		(width 0.0889)
		(layer "In11.Cu")
		(net "M_C_DQ<53>")
	)
	(arc
		(start 279.719024 -59.571382)
		(mid 279.798155 -59.866784)
		(end 279.719024 -60.162186)
		(width 0.0889)
		(layer "In11.Cu")
		(net "M_C_DQ<53>")
	)
	(arc
		(start 279.719024 -58.581036)
		(mid 279.798246 -58.870154)
		(end 279.725374 -59.160918)
		(width 0.0889)
		(layer "In11.Cu")
		(net "M_C_DQ<53>")
	)
	(arc
		(start 279.719024 -56.199786)
		(mid 279.665554 -56.394849)
		(end 279.714198 -56.5912)
		(width 0.0889)
		(layer "In11.Cu")
		(net "M_C_DQ<53>")
	)
	(arc
		(start 279.725374 -56.610504)
		(mid 279.798172 -56.901267)
		(end 279.719024 -57.190386)
		(width 0.0889)
		(layer "In11.Cu")
		(net "M_C_DQ<53>")
	)
	(arc
		(start 279.725374 -55.619904)
		(mid 279.798172 -55.910667)
		(end 279.719024 -56.199786)
		(width 0.0889)
		(layer "In11.Cu")
		(net "M_C_DQ<53>")
	)
	(arc
		(start 279.725374 -60.572904)
		(mid 279.798172 -60.863667)
		(end 279.719024 -61.152786)
		(width 0.0889)
		(layer "In11.Cu")
		(net "M_C_DQ<53>")
	)
	(arc
		(start 279.719024 -54.218586)
		(mid 279.665554 -54.413649)
		(end 279.714198 -54.61)
		(width 0.0889)
		(layer "In11.Cu")
		(net "M_C_DQ<53>")
	)
	(arc
		(start 279.719024 -62.143386)
		(mid 279.686871 -62.472888)
		(end 279.913842 -62.71387)
		(width 0.0889)
		(layer "In11.Cu")
		(net "M_C_DQ<53>")
	)
	(arc
		(start 279.725374 -61.563504)
		(mid 279.798172 -61.854267)
		(end 279.719024 -62.143386)
		(width 0.0889)
		(layer "In11.Cu")
		(net "M_C_DQ<53>")
	)
	(arc
		(start 279.719024 -55.209186)
		(mid 279.665554 -55.404249)
		(end 279.714198 -55.6006)
		(width 0.0889)
		(layer "In11.Cu")
		(net "M_C_DQ<53>")
	)
	(arc
		(start 279.719024 -57.190386)
		(mid 279.665554 -57.385449)
		(end 279.714198 -57.5818)
		(width 0.0889)
		(layer "In11.Cu")
		(net "M_C_DQ<53>")
	)
	(arc
		(start 280.41727 -63.5254)
		(mid 280.466025 -63.329048)
		(end 280.412444 -63.133986)
		(width 0.0889)
		(layer "In11.Cu")
		(net "M_C_DQ<53>")
	)
	(arc
		(start 279.798272 -53.922676)
		(mid 279.778147 -54.075852)
		(end 279.719024 -54.218586)
		(width 0.0889)
		(layer "In11.Cu")
		(net "M_C_DQ<53>")
	)
	(arc
		(start 279.719024 -61.152786)
		(mid 279.665554 -61.347849)
		(end 279.714198 -61.5442)
		(width 0.0889)
		(layer "In11.Cu")
		(net "M_C_DQ<53>")
	)
	(arc
		(start 279.725374 -57.601104)
		(mid 279.798172 -57.891867)
		(end 279.719024 -58.180986)
		(width 0.0889)
		(layer "In11.Cu")
		(net "M_C_DQ<53>")
	)
	(segment
		(start 299.249846 0.510032)
		(end 299.151802 1.0414)
		(width 0.1651)
		(layer "F.Cu")
		(net "M_C_DQ<52>")
	)
	(segment
		(start 280.637234 -63.334138)
		(end 280.065734 -63.334138)
		(width 0.0889)
		(layer "F.Cu")
		(net "M_C_DQ<52>")
	)
	(segment
		(start 299.249846 -0.821182)
		(end 299.249846 0.510032)
		(width 0.1651)
		(layer "F.Cu")
		(net "M_C_DQ<52>")
	)
	(segment
		(start 299.250354 -0.821182)
		(end 299.249846 -0.821182)
		(width 0.1651)
		(layer "F.Cu")
		(net "M_C_DQ<52>")
	)
	(via
		(at 299.151802 1.0414)
		(size 0.508)
		(drill 0.254)
		(layers "F.Cu" "B.Cu")
		(net "M_C_DQ<52>")
	)
	(via
		(at 298.399962 -4.357878)
		(size 0.508)
		(drill 0.254)
		(layers "F.Cu" "B.Cu")
		(net "M_C_DQ<52>")
	)
	(via
		(at 280.065734 -63.334138)
		(size 0.508)
		(drill 0.254)
		(layers "F.Cu" "B.Cu")
		(net "M_C_DQ<52>")
	)
	(segment
		(start 298.40047 -5.621782)
		(end 298.399962 -5.621782)
		(width 0.1651)
		(layer "B.Cu")
		(net "M_C_DQ<52>")
	)
	(segment
		(start 298.399962 -5.621782)
		(end 298.399962 -4.357878)
		(width 0.1651)
		(layer "B.Cu")
		(net "M_C_DQ<52>")
	)
	(segment
		(start 298.875196 -21.811996)
		(end 298.671996 -22.015196)
		(width 0.14224)
		(layer "In11.Cu")
		(net "M_C_DQ<52>")
	)
	(segment
		(start 298.897802 -6.874002)
		(end 298.897802 -7.248398)
		(width 0.14224)
		(layer "In11.Cu")
		(net "M_C_DQ<52>")
	)
	(segment
		(start 298.671996 -23.107396)
		(end 298.900596 -23.335996)
		(width 0.14224)
		(layer "In11.Cu")
		(net "M_C_DQ<52>")
	)
	(segment
		(start 279.547574 -62.628018)
		(end 279.553924 -62.638686)
		(width 0.0889)
		(layer "In11.Cu")
		(net "M_C_DQ<52>")
	)
	(segment
		(start 279.146 -44.963842)
		(end 279.146 -47.205392)
		(width 0.14224)
		(layer "In11.Cu")
		(net "M_C_DQ<52>")
	)
	(segment
		(start 298.875196 -21.3106)
		(end 298.875196 -21.811996)
		(width 0.14224)
		(layer "In11.Cu")
		(net "M_C_DQ<52>")
	)
	(segment
		(start 298.697396 -28.152852)
		(end 298.8818 -28.337256)
		(width 0.14224)
		(layer "In11.Cu")
		(net "M_C_DQ<52>")
	)
	(segment
		(start 290.551362 -29.972)
		(end 282.288996 -38.234366)
		(width 0.14224)
		(layer "In11.Cu")
		(net "M_C_DQ<52>")
	)
	(segment
		(start 279.553924 -61.648086)
		(end 279.55875 -61.656722)
		(width 0.0889)
		(layer "In11.Cu")
		(net "M_C_DQ<52>")
	)
	(segment
		(start 298.892468 -0.762)
		(end 298.892468 -1.0668)
		(width 0.14224)
		(layer "In11.Cu")
		(net "M_C_DQ<52>")
	)
	(segment
		(start 279.547574 -57.675018)
		(end 279.553924 -57.685686)
		(width 0.0889)
		(layer "In11.Cu")
		(net "M_C_DQ<52>")
	)
	(segment
		(start 292.095174 -31.1912)
		(end 292.095174 -30.1752)
		(width 0.14224)
		(layer "In11.Cu")
		(net "M_C_DQ<52>")
	)
	(segment
		(start 279.547574 -61.637418)
		(end 279.553924 -61.648086)
		(width 0.0889)
		(layer "In11.Cu")
		(net "M_C_DQ<52>")
	)
	(segment
		(start 279.553924 -59.666886)
		(end 279.55875 -59.675522)
		(width 0.0889)
		(layer "In11.Cu")
		(net "M_C_DQ<52>")
	)
	(segment
		(start 298.669202 -7.476998)
		(end 298.669202 -8.711946)
		(width 0.14224)
		(layer "In11.Cu")
		(net "M_C_DQ<52>")
	)
	(segment
		(start 279.279604 -53.257958)
		(end 279.607518 -53.585872)
		(width 0.0889)
		(layer "In11.Cu")
		(net "M_C_DQ<52>")
	)
	(segment
		(start 298.892468 -1.0668)
		(end 298.524168 -1.4351)
		(width 0.14224)
		(layer "In11.Cu")
		(net "M_C_DQ<52>")
	)
	(segment
		(start 298.511468 -0.076454)
		(end 298.511468 -0.381)
		(width 0.14224)
		(layer "In11.Cu")
		(net "M_C_DQ<52>")
	)
	(segment
		(start 292.907974 -31.1912)
		(end 292.704774 -31.3944)
		(width 0.14224)
		(layer "In11.Cu")
		(net "M_C_DQ<52>")
	)
	(segment
		(start 298.669202 -8.711946)
		(end 298.923202 -8.965946)
		(width 0.14224)
		(layer "In11.Cu")
		(net "M_C_DQ<52>")
	)
	(segment
		(start 298.875196 -19.005804)
		(end 298.7802 -19.1008)
		(width 0.14224)
		(layer "In11.Cu")
		(net "M_C_DQ<52>")
	)
	(segment
		(start 298.7802 -19.1008)
		(end 298.7802 -21.215604)
		(width 0.14224)
		(layer "In11.Cu")
		(net "M_C_DQ<52>")
	)
	(segment
		(start 279.146 -47.205392)
		(end 279.279604 -47.338996)
		(width 0.0889)
		(layer "In11.Cu")
		(net "M_C_DQ<52>")
	)
	(segment
		(start 298.87545 -2.141728)
		(end 298.87545 -2.616454)
		(width 0.14224)
		(layer "In11.Cu")
		(net "M_C_DQ<52>")
	)
	(segment
		(start 298.697396 -13.522452)
		(end 298.925996 -13.751052)
		(width 0.14224)
		(layer "In11.Cu")
		(net "M_C_DQ<52>")
	)
	(segment
		(start 298.524168 -1.4351)
		(end 298.524168 -1.790446)
		(width 0.14224)
		(layer "In11.Cu")
		(net "M_C_DQ<52>")
	)
	(segment
		(start 282.288996 -41.820846)
		(end 279.146 -44.963842)
		(width 0.14224)
		(layer "In11.Cu")
		(net "M_C_DQ<52>")
	)
	(segment
		(start 279.547574 -55.693818)
		(end 279.553924 -55.704486)
		(width 0.0889)
		(layer "In11.Cu")
		(net "M_C_DQ<52>")
	)
	(segment
		(start 298.900596 -26.764996)
		(end 298.697396 -26.968196)
		(width 0.14224)
		(layer "In11.Cu")
		(net "M_C_DQ<52>")
	)
	(segment
		(start 298.16425 -4.122166)
		(end 298.399962 -4.357878)
		(width 0.14224)
		(layer "In11.Cu")
		(net "M_C_DQ<52>")
	)
	(segment
		(start 298.925996 -13.751052)
		(end 298.925996 -16.821404)
		(width 0.14224)
		(layer "In11.Cu")
		(net "M_C_DQ<52>")
	)
	(segment
		(start 298.671996 -22.015196)
		(end 298.671996 -23.107396)
		(width 0.14224)
		(layer "In11.Cu")
		(net "M_C_DQ<52>")
	)
	(segment
		(start 298.697396 -26.968196)
		(end 298.697396 -28.152852)
		(width 0.14224)
		(layer "In11.Cu")
		(net "M_C_DQ<52>")
	)
	(segment
		(start 298.923202 -8.965946)
		(end 298.923202 -12.16279)
		(width 0.14224)
		(layer "In11.Cu")
		(net "M_C_DQ<52>")
	)
	(segment
		(start 292.095174 -30.1752)
		(end 291.891974 -29.972)
		(width 0.14224)
		(layer "In11.Cu")
		(net "M_C_DQ<52>")
	)
	(segment
		(start 279.547574 -56.684418)
		(end 279.553924 -56.695086)
		(width 0.0889)
		(layer "In11.Cu")
		(net "M_C_DQ<52>")
	)
	(segment
		(start 298.399962 -4.357878)
		(end 298.399962 -6.376162)
		(width 0.14224)
		(layer "In11.Cu")
		(net "M_C_DQ<52>")
	)
	(segment
		(start 293.050214 -29.3878)
		(end 292.907974 -29.53004)
		(width 0.14224)
		(layer "In11.Cu")
		(net "M_C_DQ<52>")
	)
	(segment
		(start 298.925996 -16.821404)
		(end 298.646596 -17.100804)
		(width 0.14224)
		(layer "In11.Cu")
		(net "M_C_DQ<52>")
	)
	(segment
		(start 298.646596 -17.100804)
		(end 298.646596 -18.277586)
		(width 0.14224)
		(layer "In11.Cu")
		(net "M_C_DQ<52>")
	)
	(segment
		(start 298.8818 -29.045916)
		(end 298.539916 -29.3878)
		(width 0.14224)
		(layer "In11.Cu")
		(net "M_C_DQ<52>")
	)
	(segment
		(start 279.657556 -62.770512)
		(end 280.065734 -63.334138)
		(width 0.0889)
		(layer "In11.Cu")
		(net "M_C_DQ<52>")
	)
	(segment
		(start 298.900596 -23.335996)
		(end 298.900596 -26.764996)
		(width 0.14224)
		(layer "In11.Cu")
		(net "M_C_DQ<52>")
	)
	(segment
		(start 298.8818 -28.337256)
		(end 298.8818 -29.045916)
		(width 0.14224)
		(layer "In11.Cu")
		(net "M_C_DQ<52>")
	)
	(segment
		(start 298.399962 -6.376162)
		(end 298.897802 -6.874002)
		(width 0.14224)
		(layer "In11.Cu")
		(net "M_C_DQ<52>")
	)
	(segment
		(start 298.87545 -2.616454)
		(end 298.16425 -3.327654)
		(width 0.14224)
		(layer "In11.Cu")
		(net "M_C_DQ<52>")
	)
	(segment
		(start 279.547574 -54.703218)
		(end 279.553924 -54.713886)
		(width 0.0889)
		(layer "In11.Cu")
		(net "M_C_DQ<52>")
	)
	(segment
		(start 292.298374 -31.3944)
		(end 292.095174 -31.1912)
		(width 0.14224)
		(layer "In11.Cu")
		(net "M_C_DQ<52>")
	)
	(segment
		(start 279.279604 -47.338996)
		(end 279.279604 -53.257958)
		(width 0.0889)
		(layer "In11.Cu")
		(net "M_C_DQ<52>")
	)
	(segment
		(start 279.553924 -60.657486)
		(end 279.55875 -60.666122)
		(width 0.0889)
		(layer "In11.Cu")
		(net "M_C_DQ<52>")
	)
	(segment
		(start 298.923202 -12.16279)
		(end 298.697396 -12.388596)
		(width 0.14224)
		(layer "In11.Cu")
		(net "M_C_DQ<52>")
	)
	(segment
		(start 298.697396 -12.388596)
		(end 298.697396 -13.522452)
		(width 0.14224)
		(layer "In11.Cu")
		(net "M_C_DQ<52>")
	)
	(segment
		(start 292.907974 -29.53004)
		(end 292.907974 -31.1912)
		(width 0.14224)
		(layer "In11.Cu")
		(net "M_C_DQ<52>")
	)
	(segment
		(start 279.553924 -56.695086)
		(end 279.55875 -56.703722)
		(width 0.0889)
		(layer "In11.Cu")
		(net "M_C_DQ<52>")
	)
	(segment
		(start 279.607518 -53.585872)
		(end 279.607518 -53.922676)
		(width 0.0889)
		(layer "In11.Cu")
		(net "M_C_DQ<52>")
	)
	(segment
		(start 282.288996 -38.234366)
		(end 282.288996 -41.820846)
		(width 0.14224)
		(layer "In11.Cu")
		(net "M_C_DQ<52>")
	)
	(segment
		(start 298.87545 0.287528)
		(end 298.511468 -0.076454)
		(width 0.14224)
		(layer "In11.Cu")
		(net "M_C_DQ<52>")
	)
	(segment
		(start 298.875196 -18.506186)
		(end 298.875196 -19.005804)
		(width 0.14224)
		(layer "In11.Cu")
		(net "M_C_DQ<52>")
	)
	(segment
		(start 298.646596 -18.277586)
		(end 298.875196 -18.506186)
		(width 0.14224)
		(layer "In11.Cu")
		(net "M_C_DQ<52>")
	)
	(segment
		(start 298.87545 0.765048)
		(end 298.87545 0.287528)
		(width 0.14224)
		(layer "In11.Cu")
		(net "M_C_DQ<52>")
	)
	(segment
		(start 279.553924 -59.076336)
		(end 279.547574 -59.087004)
		(width 0.0889)
		(layer "In11.Cu")
		(net "M_C_DQ<52>")
	)
	(segment
		(start 279.547574 -60.646818)
		(end 279.553924 -60.657486)
		(width 0.0889)
		(layer "In11.Cu")
		(net "M_C_DQ<52>")
	)
	(segment
		(start 298.539916 -29.3878)
		(end 293.050214 -29.3878)
		(width 0.14224)
		(layer "In11.Cu")
		(net "M_C_DQ<52>")
	)
	(segment
		(start 298.511468 -0.381)
		(end 298.892468 -0.762)
		(width 0.14224)
		(layer "In11.Cu")
		(net "M_C_DQ<52>")
	)
	(segment
		(start 279.553924 -57.685686)
		(end 279.55875 -57.694322)
		(width 0.0889)
		(layer "In11.Cu")
		(net "M_C_DQ<52>")
	)
	(segment
		(start 279.553924 -55.704486)
		(end 279.55875 -55.713122)
		(width 0.0889)
		(layer "In11.Cu")
		(net "M_C_DQ<52>")
	)
	(segment
		(start 298.16425 -3.327654)
		(end 298.16425 -4.122166)
		(width 0.14224)
		(layer "In11.Cu")
		(net "M_C_DQ<52>")
	)
	(segment
		(start 291.891974 -29.972)
		(end 290.551362 -29.972)
		(width 0.14224)
		(layer "In11.Cu")
		(net "M_C_DQ<52>")
	)
	(segment
		(start 298.897802 -7.248398)
		(end 298.669202 -7.476998)
		(width 0.14224)
		(layer "In11.Cu")
		(net "M_C_DQ<52>")
	)
	(segment
		(start 292.704774 -31.3944)
		(end 292.298374 -31.3944)
		(width 0.14224)
		(layer "In11.Cu")
		(net "M_C_DQ<52>")
	)
	(segment
		(start 298.524168 -1.790446)
		(end 298.87545 -2.141728)
		(width 0.14224)
		(layer "In11.Cu")
		(net "M_C_DQ<52>")
	)
	(segment
		(start 279.553924 -54.713886)
		(end 279.55875 -54.722522)
		(width 0.0889)
		(layer "In11.Cu")
		(net "M_C_DQ<52>")
	)
	(segment
		(start 298.7802 -21.215604)
		(end 298.875196 -21.3106)
		(width 0.14224)
		(layer "In11.Cu")
		(net "M_C_DQ<52>")
	)
	(segment
		(start 299.151802 1.0414)
		(end 298.87545 0.765048)
		(width 0.14224)
		(layer "In11.Cu")
		(net "M_C_DQ<52>")
	)
	(arc
		(start 279.55875 -60.666122)
		(mid 279.607505 -60.862474)
		(end 279.553924 -61.057536)
		(width 0.0889)
		(layer "In11.Cu")
		(net "M_C_DQ<52>")
	)
	(arc
		(start 279.55875 -54.722522)
		(mid 279.607505 -54.918874)
		(end 279.553924 -55.113936)
		(width 0.0889)
		(layer "In11.Cu")
		(net "M_C_DQ<52>")
	)
	(arc
		(start 279.55875 -61.656722)
		(mid 279.607505 -61.853074)
		(end 279.553924 -62.048136)
		(width 0.0889)
		(layer "In11.Cu")
		(net "M_C_DQ<52>")
	)
	(arc
		(start 279.553924 -58.67654)
		(mid 279.607423 -58.876438)
		(end 279.553924 -59.076336)
		(width 0.0889)
		(layer "In11.Cu")
		(net "M_C_DQ<52>")
	)
	(arc
		(start 279.553924 -57.095136)
		(mid 279.474702 -57.384254)
		(end 279.547574 -57.675018)
		(width 0.0889)
		(layer "In11.Cu")
		(net "M_C_DQ<52>")
	)
	(arc
		(start 279.553924 -62.638686)
		(mid 279.60103 -62.708302)
		(end 279.657556 -62.770512)
		(width 0.0889)
		(layer "In11.Cu")
		(net "M_C_DQ<52>")
	)
	(arc
		(start 279.55875 -59.675522)
		(mid 279.607505 -59.871874)
		(end 279.553924 -60.066936)
		(width 0.0889)
		(layer "In11.Cu")
		(net "M_C_DQ<52>")
	)
	(arc
		(start 279.553924 -58.085736)
		(mid 279.474793 -58.381138)
		(end 279.553924 -58.67654)
		(width 0.0889)
		(layer "In11.Cu")
		(net "M_C_DQ<52>")
	)
	(arc
		(start 279.55875 -57.694322)
		(mid 279.607505 -57.890674)
		(end 279.553924 -58.085736)
		(width 0.0889)
		(layer "In11.Cu")
		(net "M_C_DQ<52>")
	)
	(arc
		(start 279.553924 -62.048136)
		(mid 279.474702 -62.337254)
		(end 279.547574 -62.628018)
		(width 0.0889)
		(layer "In11.Cu")
		(net "M_C_DQ<52>")
	)
	(arc
		(start 279.547574 -59.087004)
		(mid 279.474776 -59.377767)
		(end 279.553924 -59.666886)
		(width 0.0889)
		(layer "In11.Cu")
		(net "M_C_DQ<52>")
	)
	(arc
		(start 279.607518 -53.922676)
		(mid 279.593946 -54.026536)
		(end 279.553924 -54.123336)
		(width 0.0889)
		(layer "In11.Cu")
		(net "M_C_DQ<52>")
	)
	(arc
		(start 279.55875 -56.703722)
		(mid 279.607505 -56.900074)
		(end 279.553924 -57.095136)
		(width 0.0889)
		(layer "In11.Cu")
		(net "M_C_DQ<52>")
	)
	(arc
		(start 279.55875 -55.713122)
		(mid 279.607505 -55.909474)
		(end 279.553924 -56.104536)
		(width 0.0889)
		(layer "In11.Cu")
		(net "M_C_DQ<52>")
	)
	(arc
		(start 279.553924 -61.057536)
		(mid 279.474702 -61.346654)
		(end 279.547574 -61.637418)
		(width 0.0889)
		(layer "In11.Cu")
		(net "M_C_DQ<52>")
	)
	(arc
		(start 279.553924 -56.104536)
		(mid 279.474702 -56.393654)
		(end 279.547574 -56.684418)
		(width 0.0889)
		(layer "In11.Cu")
		(net "M_C_DQ<52>")
	)
	(arc
		(start 279.553924 -55.113936)
		(mid 279.474702 -55.403054)
		(end 279.547574 -55.693818)
		(width 0.0889)
		(layer "In11.Cu")
		(net "M_C_DQ<52>")
	)
	(arc
		(start 279.553924 -54.123336)
		(mid 279.474702 -54.412454)
		(end 279.547574 -54.703218)
		(width 0.0889)
		(layer "In11.Cu")
		(net "M_C_DQ<52>")
	)
	(arc
		(start 279.553924 -60.066936)
		(mid 279.474702 -60.356054)
		(end 279.547574 -60.646818)
		(width 0.0889)
		(layer "In11.Cu")
		(net "M_C_DQ<52>")
	)
	(segment
		(start 306.050442 3.778758)
		(end 306.049934 3.778758)
		(width 0.1651)
		(layer "F.Cu")
		(net "M_C_DQ<51>")
	)
	(segment
		(start 284.071314 -64.324738)
		(end 283.499814 -64.324738)
		(width 0.0889)
		(layer "F.Cu")
		(net "M_C_DQ<51>")
	)
	(segment
		(start 306.049934 3.778758)
		(end 306.049934 2.514854)
		(width 0.1651)
		(layer "F.Cu")
		(net "M_C_DQ<51>")
	)
	(via
		(at 283.499814 -64.324738)
		(size 0.508)
		(drill 0.254)
		(layers "F.Cu" "B.Cu")
		(net "M_C_DQ<51>")
	)
	(via
		(at 306.899818 -3.076956)
		(size 0.508)
		(drill 0.254)
		(layers "F.Cu" "B.Cu")
		(net "M_C_DQ<51>")
	)
	(via
		(at 306.049934 2.514854)
		(size 0.508)
		(drill 0.254)
		(layers "F.Cu" "B.Cu")
		(net "M_C_DQ<51>")
	)
	(segment
		(start 306.899818 -1.021842)
		(end 306.899818 -3.076956)
		(width 0.1651)
		(layer "B.Cu")
		(net "M_C_DQ<51>")
	)
	(segment
		(start 306.900326 -1.021842)
		(end 306.899818 -1.021842)
		(width 0.1651)
		(layer "B.Cu")
		(net "M_C_DQ<51>")
	)
	(segment
		(start 306.366672 2.198116)
		(end 306.366672 1.8796)
		(width 0.14224)
		(layer "In11.Cu")
		(net "M_C_DQ<51>")
	)
	(segment
		(start 307.384196 -17.032986)
		(end 307.384196 -18.447258)
		(width 0.14224)
		(layer "In11.Cu")
		(net "M_C_DQ<51>")
	)
	(segment
		(start 306.366672 1.8796)
		(end 306.696872 1.5494)
		(width 0.14224)
		(layer "In11.Cu")
		(net "M_C_DQ<51>")
	)
	(segment
		(start 283.980636 -63.6778)
		(end 283.727906 -64.017906)
		(width 0.0889)
		(layer "In11.Cu")
		(net "M_C_DQ<51>")
	)
	(segment
		(start 307.357018 -21.835618)
		(end 307.357018 -23.185374)
		(width 0.14224)
		(layer "In11.Cu")
		(net "M_C_DQ<51>")
	)
	(segment
		(start 284.011624 -55.704486)
		(end 284.006798 -55.713122)
		(width 0.0889)
		(layer "In11.Cu")
		(net "M_C_DQ<51>")
	)
	(segment
		(start 284.017974 -55.693818)
		(end 284.011624 -55.704486)
		(width 0.0889)
		(layer "In11.Cu")
		(net "M_C_DQ<51>")
	)
	(segment
		(start 306.049934 2.514854)
		(end 306.366672 2.198116)
		(width 0.14224)
		(layer "In11.Cu")
		(net "M_C_DQ<51>")
	)
	(segment
		(start 284.017974 -56.684418)
		(end 284.011624 -56.695086)
		(width 0.0889)
		(layer "In11.Cu")
		(net "M_C_DQ<51>")
	)
	(segment
		(start 284.017974 -62.628018)
		(end 284.011624 -62.638686)
		(width 0.0889)
		(layer "In11.Cu")
		(net "M_C_DQ<51>")
	)
	(segment
		(start 285.414212 -47.734982)
		(end 285.414212 -48.075088)
		(width 0.0889)
		(layer "In11.Cu")
		(net "M_C_DQ<51>")
	)
	(segment
		(start 307.408072 1.0922)
		(end 307.408072 0.7366)
		(width 0.14224)
		(layer "In11.Cu")
		(net "M_C_DQ<51>")
	)
	(segment
		(start 307.254402 -8.950198)
		(end 307.254402 -9.398)
		(width 0.14224)
		(layer "In11.Cu")
		(net "M_C_DQ<51>")
	)
	(segment
		(start 284.103572 -52.897024)
		(end 283.958284 -53.042312)
		(width 0.0889)
		(layer "In11.Cu")
		(net "M_C_DQ<51>")
	)
	(segment
		(start 307.267102 -13.694156)
		(end 307.267102 -16.915892)
		(width 0.14224)
		(layer "In11.Cu")
		(net "M_C_DQ<51>")
	)
	(segment
		(start 306.899818 -3.076956)
		(end 306.416202 -3.560572)
		(width 0.14224)
		(layer "In11.Cu")
		(net "M_C_DQ<51>")
	)
	(segment
		(start 307.384196 -12.33805)
		(end 307.384196 -13.577062)
		(width 0.14224)
		(layer "In11.Cu")
		(net "M_C_DQ<51>")
	)
	(segment
		(start 284.011624 -56.695086)
		(end 284.006798 -56.703722)
		(width 0.0889)
		(layer "In11.Cu")
		(net "M_C_DQ<51>")
	)
	(segment
		(start 307.254402 -12.208256)
		(end 307.384196 -12.33805)
		(width 0.14224)
		(layer "In11.Cu")
		(net "M_C_DQ<51>")
	)
	(segment
		(start 307.408072 0.7366)
		(end 307.252624 0.581152)
		(width 0.14224)
		(layer "In11.Cu")
		(net "M_C_DQ<51>")
	)
	(segment
		(start 306.416202 -3.560572)
		(end 306.416202 -3.965956)
		(width 0.14224)
		(layer "In11.Cu")
		(net "M_C_DQ<51>")
	)
	(segment
		(start 307.2892 -26.0604)
		(end 307.4162 -26.1874)
		(width 0.14224)
		(layer "In11.Cu")
		(net "M_C_DQ<51>")
	)
	(segment
		(start 307.2892 -23.253192)
		(end 307.2892 -26.0604)
		(width 0.14224)
		(layer "In11.Cu")
		(net "M_C_DQ<51>")
	)
	(segment
		(start 307.254402 -9.398)
		(end 307.4416 -9.585198)
		(width 0.14224)
		(layer "In11.Cu")
		(net "M_C_DQ<51>")
	)
	(segment
		(start 283.727906 -64.017906)
		(end 283.499814 -64.324738)
		(width 0.0889)
		(layer "In11.Cu")
		(net "M_C_DQ<51>")
	)
	(segment
		(start 307.406802 -7.429246)
		(end 307.406802 -8.797798)
		(width 0.14224)
		(layer "In11.Cu")
		(net "M_C_DQ<51>")
	)
	(segment
		(start 307.236368 -18.595086)
		(end 307.236368 -18.946368)
		(width 0.14224)
		(layer "In11.Cu")
		(net "M_C_DQ<51>")
	)
	(segment
		(start 307.384196 -18.447258)
		(end 307.236368 -18.595086)
		(width 0.14224)
		(layer "In11.Cu")
		(net "M_C_DQ<51>")
	)
	(segment
		(start 284.017974 -60.646818)
		(end 284.011624 -60.657486)
		(width 0.0889)
		(layer "In11.Cu")
		(net "M_C_DQ<51>")
	)
	(segment
		(start 307.267102 -16.915892)
		(end 307.384196 -17.032986)
		(width 0.14224)
		(layer "In11.Cu")
		(net "M_C_DQ<51>")
	)
	(segment
		(start 306.950872 1.5494)
		(end 307.408072 1.0922)
		(width 0.14224)
		(layer "In11.Cu")
		(net "M_C_DQ<51>")
	)
	(segment
		(start 307.252624 0.581152)
		(end 307.252624 -2.72415)
		(width 0.14224)
		(layer "In11.Cu")
		(net "M_C_DQ<51>")
	)
	(segment
		(start 284.103572 -49.385728)
		(end 284.103572 -52.897024)
		(width 0.0889)
		(layer "In11.Cu")
		(net "M_C_DQ<51>")
	)
	(segment
		(start 284.011624 -61.648086)
		(end 284.006798 -61.656722)
		(width 0.0889)
		(layer "In11.Cu")
		(net "M_C_DQ<51>")
	)
	(segment
		(start 284.017974 -57.675018)
		(end 284.011624 -57.685686)
		(width 0.0889)
		(layer "In11.Cu")
		(net "M_C_DQ<51>")
	)
	(segment
		(start 307.236368 -18.946368)
		(end 307.3908 -19.1008)
		(width 0.14224)
		(layer "In11.Cu")
		(net "M_C_DQ<51>")
	)
	(segment
		(start 307.4162 -26.1874)
		(end 307.4162 -29.68117)
		(width 0.14224)
		(layer "In11.Cu")
		(net "M_C_DQ<51>")
	)
	(segment
		(start 285.637224 -47.51197)
		(end 285.414212 -47.734982)
		(width 0.0889)
		(layer "In11.Cu")
		(net "M_C_DQ<51>")
	)
	(segment
		(start 307.254402 -11.693398)
		(end 307.254402 -12.208256)
		(width 0.14224)
		(layer "In11.Cu")
		(net "M_C_DQ<51>")
	)
	(segment
		(start 307.4162 -29.68117)
		(end 297.98137 -39.116)
		(width 0.14224)
		(layer "In11.Cu")
		(net "M_C_DQ<51>")
	)
	(segment
		(start 307.3908 -19.1008)
		(end 307.3908 -21.206968)
		(width 0.14224)
		(layer "In11.Cu")
		(net "M_C_DQ<51>")
	)
	(segment
		(start 307.267102 -7.289546)
		(end 307.406802 -7.429246)
		(width 0.14224)
		(layer "In11.Cu")
		(net "M_C_DQ<51>")
	)
	(segment
		(start 285.637224 -47.23892)
		(end 285.637224 -47.51197)
		(width 0.14224)
		(layer "In11.Cu")
		(net "M_C_DQ<51>")
	)
	(segment
		(start 306.696872 1.5494)
		(end 306.950872 1.5494)
		(width 0.14224)
		(layer "In11.Cu")
		(net "M_C_DQ<51>")
	)
	(segment
		(start 284.011624 -57.685686)
		(end 284.006798 -57.694322)
		(width 0.0889)
		(layer "In11.Cu")
		(net "M_C_DQ<51>")
	)
	(segment
		(start 307.384196 -13.577062)
		(end 307.267102 -13.694156)
		(width 0.14224)
		(layer "In11.Cu")
		(net "M_C_DQ<51>")
	)
	(segment
		(start 306.416202 -3.965956)
		(end 307.267102 -4.816856)
		(width 0.14224)
		(layer "In11.Cu")
		(net "M_C_DQ<51>")
	)
	(segment
		(start 289.048952 -40.897048)
		(end 289.048952 -43.827192)
		(width 0.14224)
		(layer "In11.Cu")
		(net "M_C_DQ<51>")
	)
	(segment
		(start 307.236368 -21.714968)
		(end 307.357018 -21.835618)
		(width 0.14224)
		(layer "In11.Cu")
		(net "M_C_DQ<51>")
	)
	(segment
		(start 307.4416 -9.585198)
		(end 307.4416 -11.5062)
		(width 0.14224)
		(layer "In11.Cu")
		(net "M_C_DQ<51>")
	)
	(segment
		(start 285.414212 -48.075088)
		(end 284.103572 -49.385728)
		(width 0.0889)
		(layer "In11.Cu")
		(net "M_C_DQ<51>")
	)
	(segment
		(start 307.236368 -21.3614)
		(end 307.236368 -21.714968)
		(width 0.14224)
		(layer "In11.Cu")
		(net "M_C_DQ<51>")
	)
	(segment
		(start 307.406802 -8.797798)
		(end 307.254402 -8.950198)
		(width 0.14224)
		(layer "In11.Cu")
		(net "M_C_DQ<51>")
	)
	(segment
		(start 290.83 -39.116)
		(end 289.048952 -40.897048)
		(width 0.14224)
		(layer "In11.Cu")
		(net "M_C_DQ<51>")
	)
	(segment
		(start 284.017974 -61.637418)
		(end 284.011624 -61.648086)
		(width 0.0889)
		(layer "In11.Cu")
		(net "M_C_DQ<51>")
	)
	(segment
		(start 307.357018 -23.185374)
		(end 307.2892 -23.253192)
		(width 0.14224)
		(layer "In11.Cu")
		(net "M_C_DQ<51>")
	)
	(segment
		(start 283.958284 -55.02148)
		(end 284.011624 -55.113936)
		(width 0.0889)
		(layer "In11.Cu")
		(net "M_C_DQ<51>")
	)
	(segment
		(start 307.252624 -2.72415)
		(end 306.899818 -3.076956)
		(width 0.14224)
		(layer "In11.Cu")
		(net "M_C_DQ<51>")
	)
	(segment
		(start 307.4416 -11.5062)
		(end 307.254402 -11.693398)
		(width 0.14224)
		(layer "In11.Cu")
		(net "M_C_DQ<51>")
	)
	(segment
		(start 307.267102 -4.816856)
		(end 307.267102 -7.289546)
		(width 0.14224)
		(layer "In11.Cu")
		(net "M_C_DQ<51>")
	)
	(segment
		(start 307.3908 -21.206968)
		(end 307.236368 -21.3614)
		(width 0.14224)
		(layer "In11.Cu")
		(net "M_C_DQ<51>")
	)
	(segment
		(start 284.011624 -59.076336)
		(end 284.017974 -59.087004)
		(width 0.0889)
		(layer "In11.Cu")
		(net "M_C_DQ<51>")
	)
	(segment
		(start 289.048952 -43.827192)
		(end 285.637224 -47.23892)
		(width 0.14224)
		(layer "In11.Cu")
		(net "M_C_DQ<51>")
	)
	(segment
		(start 284.011624 -62.638686)
		(end 284.006798 -62.647322)
		(width 0.0889)
		(layer "In11.Cu")
		(net "M_C_DQ<51>")
	)
	(segment
		(start 297.98137 -39.116)
		(end 290.83 -39.116)
		(width 0.14224)
		(layer "In11.Cu")
		(net "M_C_DQ<51>")
	)
	(segment
		(start 284.011624 -60.657486)
		(end 284.006798 -60.666122)
		(width 0.0889)
		(layer "In11.Cu")
		(net "M_C_DQ<51>")
	)
	(segment
		(start 284.011624 -59.666886)
		(end 284.006798 -59.675522)
		(width 0.0889)
		(layer "In11.Cu")
		(net "M_C_DQ<51>")
	)
	(segment
		(start 283.958284 -53.042312)
		(end 283.958284 -55.02148)
		(width 0.0889)
		(layer "In11.Cu")
		(net "M_C_DQ<51>")
	)
	(arc
		(start 284.006798 -61.656722)
		(mid 283.958043 -61.853074)
		(end 284.011624 -62.048136)
		(width 0.0889)
		(layer "In11.Cu")
		(net "M_C_DQ<51>")
	)
	(arc
		(start 284.017974 -59.087004)
		(mid 284.090772 -59.377767)
		(end 284.011624 -59.666886)
		(width 0.0889)
		(layer "In11.Cu")
		(net "M_C_DQ<51>")
	)
	(arc
		(start 284.011624 -58.67654)
		(mid 283.958125 -58.876438)
		(end 284.011624 -59.076336)
		(width 0.0889)
		(layer "In11.Cu")
		(net "M_C_DQ<51>")
	)
	(arc
		(start 284.011624 -58.085736)
		(mid 284.090755 -58.381138)
		(end 284.011624 -58.67654)
		(width 0.0889)
		(layer "In11.Cu")
		(net "M_C_DQ<51>")
	)
	(arc
		(start 284.011624 -63.038736)
		(mid 284.090059 -63.362812)
		(end 283.980636 -63.6778)
		(width 0.0889)
		(layer "In11.Cu")
		(net "M_C_DQ<51>")
	)
	(arc
		(start 284.006798 -60.666122)
		(mid 283.958043 -60.862474)
		(end 284.011624 -61.057536)
		(width 0.0889)
		(layer "In11.Cu")
		(net "M_C_DQ<51>")
	)
	(arc
		(start 284.006798 -55.713122)
		(mid 283.958043 -55.909474)
		(end 284.011624 -56.104536)
		(width 0.0889)
		(layer "In11.Cu")
		(net "M_C_DQ<51>")
	)
	(arc
		(start 284.011624 -62.048136)
		(mid 284.090846 -62.337254)
		(end 284.017974 -62.628018)
		(width 0.0889)
		(layer "In11.Cu")
		(net "M_C_DQ<51>")
	)
	(arc
		(start 284.006798 -59.675522)
		(mid 283.958043 -59.871874)
		(end 284.011624 -60.066936)
		(width 0.0889)
		(layer "In11.Cu")
		(net "M_C_DQ<51>")
	)
	(arc
		(start 284.006798 -57.694322)
		(mid 283.958043 -57.890674)
		(end 284.011624 -58.085736)
		(width 0.0889)
		(layer "In11.Cu")
		(net "M_C_DQ<51>")
	)
	(arc
		(start 284.006798 -56.703722)
		(mid 283.958043 -56.900074)
		(end 284.011624 -57.095136)
		(width 0.0889)
		(layer "In11.Cu")
		(net "M_C_DQ<51>")
	)
	(arc
		(start 284.011624 -60.066936)
		(mid 284.090846 -60.356054)
		(end 284.017974 -60.646818)
		(width 0.0889)
		(layer "In11.Cu")
		(net "M_C_DQ<51>")
	)
	(arc
		(start 284.011624 -56.104536)
		(mid 284.090846 -56.393654)
		(end 284.017974 -56.684418)
		(width 0.0889)
		(layer "In11.Cu")
		(net "M_C_DQ<51>")
	)
	(arc
		(start 284.011624 -57.095136)
		(mid 284.090846 -57.384254)
		(end 284.017974 -57.675018)
		(width 0.0889)
		(layer "In11.Cu")
		(net "M_C_DQ<51>")
	)
	(arc
		(start 284.011624 -61.057536)
		(mid 284.090846 -61.346654)
		(end 284.017974 -61.637418)
		(width 0.0889)
		(layer "In11.Cu")
		(net "M_C_DQ<51>")
	)
	(arc
		(start 284.011624 -55.113936)
		(mid 284.090846 -55.403054)
		(end 284.017974 -55.693818)
		(width 0.0889)
		(layer "In11.Cu")
		(net "M_C_DQ<51>")
	)
	(arc
		(start 284.006798 -62.647322)
		(mid 283.958043 -62.843674)
		(end 284.011624 -63.038736)
		(width 0.0889)
		(layer "In11.Cu")
		(net "M_C_DQ<51>")
	)
	(segment
		(start 306.899818 0.175768)
		(end 307.03139 0.30734)
		(width 0.1651)
		(layer "F.Cu")
		(net "M_C_DQ<50>")
	)
	(segment
		(start 306.899818 -0.821182)
		(end 306.899818 0.175768)
		(width 0.1651)
		(layer "F.Cu")
		(net "M_C_DQ<50>")
	)
	(segment
		(start 307.03139 0.53086)
		(end 306.899818 0.662432)
		(width 0.1651)
		(layer "F.Cu")
		(net "M_C_DQ<50>")
	)
	(segment
		(start 307.03139 0.30734)
		(end 307.03139 0.53086)
		(width 0.1651)
		(layer "F.Cu")
		(net "M_C_DQ<50>")
	)
	(segment
		(start 284.071314 -63.334138)
		(end 283.499814 -63.334138)
		(width 0.0889)
		(layer "F.Cu")
		(net "M_C_DQ<50>")
	)
	(segment
		(start 306.900326 -0.821182)
		(end 306.899818 -0.821182)
		(width 0.1651)
		(layer "F.Cu")
		(net "M_C_DQ<50>")
	)
	(segment
		(start 306.899818 0.662432)
		(end 306.899818 0.9398)
		(width 0.1651)
		(layer "F.Cu")
		(net "M_C_DQ<50>")
	)
	(via
		(at 306.899818 0.9398)
		(size 0.508)
		(drill 0.254)
		(layers "F.Cu" "B.Cu")
		(net "M_C_DQ<50>")
	)
	(via
		(at 283.499814 -63.334138)
		(size 0.508)
		(drill 0.254)
		(layers "F.Cu" "B.Cu")
		(net "M_C_DQ<50>")
	)
	(via
		(at 306.049934 -4.357878)
		(size 0.508)
		(drill 0.254)
		(layers "F.Cu" "B.Cu")
		(net "M_C_DQ<50>")
	)
	(segment
		(start 306.050442 -5.621782)
		(end 306.049934 -5.621782)
		(width 0.1651)
		(layer "B.Cu")
		(net "M_C_DQ<50>")
	)
	(segment
		(start 306.049934 -5.621782)
		(end 306.049934 -4.357878)
		(width 0.1651)
		(layer "B.Cu")
		(net "M_C_DQ<50>")
	)
	(segment
		(start 306.543202 -9.3472)
		(end 306.3748 -9.515602)
		(width 0.14224)
		(layer "In11.Cu")
		(net "M_C_DQ<50>")
	)
	(segment
		(start 306.619402 -4.927346)
		(end 306.619402 -7.172198)
		(width 0.14224)
		(layer "In11.Cu")
		(net "M_C_DQ<50>")
	)
	(segment
		(start 306.3748 -9.515602)
		(end 306.3748 -11.5316)
		(width 0.14224)
		(layer "In11.Cu")
		(net "M_C_DQ<50>")
	)
	(segment
		(start 283.846524 -61.552836)
		(end 283.840174 -61.563504)
		(width 0.0889)
		(layer "In11.Cu")
		(net "M_C_DQ<50>")
	)
	(segment
		(start 291.421312 -38.41496)
		(end 291.279072 -38.5572)
		(width 0.14224)
		(layer "In11.Cu")
		(net "M_C_DQ<50>")
	)
	(segment
		(start 292.721792 -38.08984)
		(end 292.721792 -38.41496)
		(width 0.14224)
		(layer "In11.Cu")
		(net "M_C_DQ<50>")
	)
	(segment
		(start 283.846524 -56.599836)
		(end 283.840174 -56.610504)
		(width 0.0889)
		(layer "In11.Cu")
		(net "M_C_DQ<50>")
	)
	(segment
		(start 306.5526 -23.282656)
		(end 306.5526 -26.162)
		(width 0.14224)
		(layer "In11.Cu")
		(net "M_C_DQ<50>")
	)
	(segment
		(start 306.368196 -18.38325)
		(end 306.545996 -18.56105)
		(width 0.14224)
		(layer "In11.Cu")
		(net "M_C_DQ<50>")
	)
	(segment
		(start 306.368196 -17.032986)
		(end 306.368196 -18.38325)
		(width 0.14224)
		(layer "In11.Cu")
		(net "M_C_DQ<50>")
	)
	(segment
		(start 283.767784 -55.072534)
		(end 283.846524 -55.209186)
		(width 0.0889)
		(layer "In11.Cu")
		(net "M_C_DQ<50>")
	)
	(segment
		(start 306.543202 -12.195556)
		(end 306.390802 -12.347956)
		(width 0.14224)
		(layer "In11.Cu")
		(net "M_C_DQ<50>")
	)
	(segment
		(start 306.543202 -8.982202)
		(end 306.543202 -9.3472)
		(width 0.14224)
		(layer "In11.Cu")
		(net "M_C_DQ<50>")
	)
	(segment
		(start 306.545996 -18.56105)
		(end 306.545996 -18.9992)
		(width 0.14224)
		(layer "In11.Cu")
		(net "M_C_DQ<50>")
	)
	(segment
		(start 283.85135 -60.5536)
		(end 283.846524 -60.562236)
		(width 0.0889)
		(layer "In11.Cu")
		(net "M_C_DQ<50>")
	)
	(segment
		(start 283.846524 -60.562236)
		(end 283.840174 -60.572904)
		(width 0.0889)
		(layer "In11.Cu")
		(net "M_C_DQ<50>")
	)
	(segment
		(start 291.421312 -38.08984)
		(end 291.421312 -38.41496)
		(width 0.14224)
		(layer "In11.Cu")
		(net "M_C_DQ<50>")
	)
	(segment
		(start 306.156868 -0.108204)
		(end 306.156868 -0.456946)
		(width 0.14224)
		(layer "In11.Cu")
		(net "M_C_DQ<50>")
	)
	(segment
		(start 306.5526 -26.162)
		(end 306.732432 -26.341832)
		(width 0.14224)
		(layer "In11.Cu")
		(net "M_C_DQ<50>")
	)
	(segment
		(start 306.156868 -1.7526)
		(end 306.614068 -2.2098)
		(width 0.14224)
		(layer "In11.Cu")
		(net "M_C_DQ<50>")
	)
	(segment
		(start 305.7652 -3.3274)
		(end 305.7652 -4.073144)
		(width 0.14224)
		(layer "In11.Cu")
		(net "M_C_DQ<50>")
	)
	(segment
		(start 291.563552 -37.9476)
		(end 291.421312 -38.08984)
		(width 0.14224)
		(layer "In11.Cu")
		(net "M_C_DQ<50>")
	)
	(segment
		(start 288.544 -40.608504)
		(end 288.544 -43.569636)
		(width 0.14224)
		(layer "In11.Cu")
		(net "M_C_DQ<50>")
	)
	(segment
		(start 306.619402 -7.172198)
		(end 306.4256 -7.366)
		(width 0.14224)
		(layer "In11.Cu")
		(net "M_C_DQ<50>")
	)
	(segment
		(start 306.545996 -18.9992)
		(end 306.3748 -19.170396)
		(width 0.14224)
		(layer "In11.Cu")
		(net "M_C_DQ<50>")
	)
	(segment
		(start 285.002224 -47.51197)
		(end 285.223712 -47.733458)
		(width 0.0889)
		(layer "In11.Cu")
		(net "M_C_DQ<50>")
	)
	(segment
		(start 306.7812 -28.540456)
		(end 306.7812 -29.418026)
		(width 0.14224)
		(layer "In11.Cu")
		(net "M_C_DQ<50>")
	)
	(segment
		(start 283.846524 -57.590436)
		(end 283.840174 -57.601104)
		(width 0.0889)
		(layer "In11.Cu")
		(net "M_C_DQ<50>")
	)
	(segment
		(start 306.461668 -0.761746)
		(end 306.461668 -1.04775)
		(width 0.14224)
		(layer "In11.Cu")
		(net "M_C_DQ<50>")
	)
	(segment
		(start 291.279072 -38.5572)
		(end 290.595304 -38.5572)
		(width 0.14224)
		(layer "In11.Cu")
		(net "M_C_DQ<50>")
	)
	(segment
		(start 285.223712 -47.733458)
		(end 285.223712 -47.996094)
		(width 0.0889)
		(layer "In11.Cu")
		(net "M_C_DQ<50>")
	)
	(segment
		(start 306.156868 -1.35255)
		(end 306.156868 -1.7526)
		(width 0.14224)
		(layer "In11.Cu")
		(net "M_C_DQ<50>")
	)
	(segment
		(start 283.913072 -49.306734)
		(end 283.913072 -52.81803)
		(width 0.0889)
		(layer "In11.Cu")
		(net "M_C_DQ<50>")
	)
	(segment
		(start 306.390802 -12.347956)
		(end 306.390802 -13.595604)
		(width 0.14224)
		(layer "In11.Cu")
		(net "M_C_DQ<50>")
	)
	(segment
		(start 306.578 -13.782802)
		(end 306.578 -16.823182)
		(width 0.14224)
		(layer "In11.Cu")
		(net "M_C_DQ<50>")
	)
	(segment
		(start 306.614068 -2.478532)
		(end 305.7652 -3.3274)
		(width 0.14224)
		(layer "In11.Cu")
		(net "M_C_DQ<50>")
	)
	(segment
		(start 306.545996 -21.329396)
		(end 306.545996 -21.761196)
		(width 0.14224)
		(layer "In11.Cu")
		(net "M_C_DQ<50>")
	)
	(segment
		(start 292.721792 -38.41496)
		(end 292.579552 -38.5572)
		(width 0.14224)
		(layer "In11.Cu")
		(net "M_C_DQ<50>")
	)
	(segment
		(start 306.342796 -28.102052)
		(end 306.7812 -28.540456)
		(width 0.14224)
		(layer "In11.Cu")
		(net "M_C_DQ<50>")
	)
	(segment
		(start 306.461668 -1.04775)
		(end 306.156868 -1.35255)
		(width 0.14224)
		(layer "In11.Cu")
		(net "M_C_DQ<50>")
	)
	(segment
		(start 292.071552 -38.41496)
		(end 292.071552 -38.08984)
		(width 0.14224)
		(layer "In11.Cu")
		(net "M_C_DQ<50>")
	)
	(segment
		(start 305.7652 -4.073144)
		(end 306.049934 -4.357878)
		(width 0.14224)
		(layer "In11.Cu")
		(net "M_C_DQ<50>")
	)
	(segment
		(start 288.544 -43.569636)
		(end 285.002224 -47.111412)
		(width 0.14224)
		(layer "In11.Cu")
		(net "M_C_DQ<50>")
	)
	(segment
		(start 283.767784 -52.963318)
		(end 283.767784 -55.072534)
		(width 0.0889)
		(layer "In11.Cu")
		(net "M_C_DQ<50>")
	)
	(segment
		(start 283.85135 -61.5442)
		(end 283.846524 -61.552836)
		(width 0.0889)
		(layer "In11.Cu")
		(net "M_C_DQ<50>")
	)
	(segment
		(start 291.929312 -37.9476)
		(end 291.563552 -37.9476)
		(width 0.14224)
		(layer "In11.Cu")
		(net "M_C_DQ<50>")
	)
	(segment
		(start 306.732432 -26.62936)
		(end 306.342796 -27.018996)
		(width 0.14224)
		(layer "In11.Cu")
		(net "M_C_DQ<50>")
	)
	(segment
		(start 283.816806 -63.075566)
		(end 283.79293 -63.164974)
		(width 0.0889)
		(layer "In11.Cu")
		(net "M_C_DQ<50>")
	)
	(segment
		(start 306.5018 0.236728)
		(end 306.156868 -0.108204)
		(width 0.14224)
		(layer "In11.Cu")
		(net "M_C_DQ<50>")
	)
	(segment
		(start 283.840174 -59.160918)
		(end 283.846524 -59.171586)
		(width 0.0889)
		(layer "In11.Cu")
		(net "M_C_DQ<50>")
	)
	(segment
		(start 298.023026 -38.1762)
		(end 293.458392 -38.1762)
		(width 0.14224)
		(layer "In11.Cu")
		(net "M_C_DQ<50>")
	)
	(segment
		(start 306.342796 -27.018996)
		(end 306.342796 -28.102052)
		(width 0.14224)
		(layer "In11.Cu")
		(net "M_C_DQ<50>")
	)
	(segment
		(start 283.85135 -56.5912)
		(end 283.846524 -56.599836)
		(width 0.0889)
		(layer "In11.Cu")
		(net "M_C_DQ<50>")
	)
	(segment
		(start 293.229792 -37.9476)
		(end 292.864032 -37.9476)
		(width 0.14224)
		(layer "In11.Cu")
		(net "M_C_DQ<50>")
	)
	(segment
		(start 283.85135 -55.6006)
		(end 283.846524 -55.609236)
		(width 0.0889)
		(layer "In11.Cu")
		(net "M_C_DQ<50>")
	)
	(segment
		(start 306.368196 -23.098252)
		(end 306.5526 -23.282656)
		(width 0.14224)
		(layer "In11.Cu")
		(net "M_C_DQ<50>")
	)
	(segment
		(start 293.458392 -38.1762)
		(end 293.229792 -37.9476)
		(width 0.14224)
		(layer "In11.Cu")
		(net "M_C_DQ<50>")
	)
	(segment
		(start 306.899818 0.9398)
		(end 306.5018 0.541782)
		(width 0.14224)
		(layer "In11.Cu")
		(net "M_C_DQ<50>")
	)
	(segment
		(start 292.213792 -38.5572)
		(end 292.071552 -38.41496)
		(width 0.14224)
		(layer "In11.Cu")
		(net "M_C_DQ<50>")
	)
	(segment
		(start 306.614068 -2.2098)
		(end 306.614068 -2.478532)
		(width 0.14224)
		(layer "In11.Cu")
		(net "M_C_DQ<50>")
	)
	(segment
		(start 292.071552 -38.08984)
		(end 291.929312 -37.9476)
		(width 0.14224)
		(layer "In11.Cu")
		(net "M_C_DQ<50>")
	)
	(segment
		(start 283.85135 -58.5724)
		(end 283.846524 -58.581036)
		(width 0.0889)
		(layer "In11.Cu")
		(net "M_C_DQ<50>")
	)
	(segment
		(start 306.390802 -13.595604)
		(end 306.578 -13.782802)
		(width 0.14224)
		(layer "In11.Cu")
		(net "M_C_DQ<50>")
	)
	(segment
		(start 306.578 -16.823182)
		(end 306.368196 -17.032986)
		(width 0.14224)
		(layer "In11.Cu")
		(net "M_C_DQ<50>")
	)
	(segment
		(start 283.79293 -63.164974)
		(end 283.499814 -63.334138)
		(width 0.0889)
		(layer "In11.Cu")
		(net "M_C_DQ<50>")
	)
	(segment
		(start 306.3748 -19.170396)
		(end 306.3748 -21.1582)
		(width 0.14224)
		(layer "In11.Cu")
		(net "M_C_DQ<50>")
	)
	(segment
		(start 290.595304 -38.5572)
		(end 288.544 -40.608504)
		(width 0.14224)
		(layer "In11.Cu")
		(net "M_C_DQ<50>")
	)
	(segment
		(start 283.913072 -52.81803)
		(end 283.767784 -52.963318)
		(width 0.0889)
		(layer "In11.Cu")
		(net "M_C_DQ<50>")
	)
	(segment
		(start 292.864032 -37.9476)
		(end 292.721792 -38.08984)
		(width 0.14224)
		(layer "In11.Cu")
		(net "M_C_DQ<50>")
	)
	(segment
		(start 306.4256 -7.366)
		(end 306.4256 -8.8646)
		(width 0.14224)
		(layer "In11.Cu")
		(net "M_C_DQ<50>")
	)
	(segment
		(start 306.049934 -4.357878)
		(end 306.619402 -4.927346)
		(width 0.14224)
		(layer "In11.Cu")
		(net "M_C_DQ<50>")
	)
	(segment
		(start 306.732432 -26.341832)
		(end 306.732432 -26.62936)
		(width 0.14224)
		(layer "In11.Cu")
		(net "M_C_DQ<50>")
	)
	(segment
		(start 306.543202 -11.700002)
		(end 306.543202 -12.195556)
		(width 0.14224)
		(layer "In11.Cu")
		(net "M_C_DQ<50>")
	)
	(segment
		(start 306.4256 -8.8646)
		(end 306.543202 -8.982202)
		(width 0.14224)
		(layer "In11.Cu")
		(net "M_C_DQ<50>")
	)
	(segment
		(start 285.223712 -47.996094)
		(end 283.913072 -49.306734)
		(width 0.0889)
		(layer "In11.Cu")
		(net "M_C_DQ<50>")
	)
	(segment
		(start 306.545996 -21.761196)
		(end 306.368196 -21.938996)
		(width 0.14224)
		(layer "In11.Cu")
		(net "M_C_DQ<50>")
	)
	(segment
		(start 306.368196 -21.938996)
		(end 306.368196 -23.098252)
		(width 0.14224)
		(layer "In11.Cu")
		(net "M_C_DQ<50>")
	)
	(segment
		(start 306.7812 -29.418026)
		(end 298.023026 -38.1762)
		(width 0.14224)
		(layer "In11.Cu")
		(net "M_C_DQ<50>")
	)
	(segment
		(start 292.579552 -38.5572)
		(end 292.213792 -38.5572)
		(width 0.14224)
		(layer "In11.Cu")
		(net "M_C_DQ<50>")
	)
	(segment
		(start 306.3748 -21.1582)
		(end 306.545996 -21.329396)
		(width 0.14224)
		(layer "In11.Cu")
		(net "M_C_DQ<50>")
	)
	(segment
		(start 306.156868 -0.456946)
		(end 306.461668 -0.761746)
		(width 0.14224)
		(layer "In11.Cu")
		(net "M_C_DQ<50>")
	)
	(segment
		(start 283.846524 -55.609236)
		(end 283.840174 -55.619904)
		(width 0.0889)
		(layer "In11.Cu")
		(net "M_C_DQ<50>")
	)
	(segment
		(start 285.002224 -47.111412)
		(end 285.002224 -47.51197)
		(width 0.14224)
		(layer "In11.Cu")
		(net "M_C_DQ<50>")
	)
	(segment
		(start 306.5018 0.541782)
		(end 306.5018 0.236728)
		(width 0.14224)
		(layer "In11.Cu")
		(net "M_C_DQ<50>")
	)
	(segment
		(start 283.85135 -57.5818)
		(end 283.846524 -57.590436)
		(width 0.0889)
		(layer "In11.Cu")
		(net "M_C_DQ<50>")
	)
	(segment
		(start 283.846524 -62.543436)
		(end 283.840174 -62.554104)
		(width 0.0889)
		(layer "In11.Cu")
		(net "M_C_DQ<50>")
	)
	(segment
		(start 306.3748 -11.5316)
		(end 306.543202 -11.700002)
		(width 0.14224)
		(layer "In11.Cu")
		(net "M_C_DQ<50>")
	)
	(arc
		(start 283.846524 -58.581036)
		(mid 283.767302 -58.870154)
		(end 283.840174 -59.160918)
		(width 0.0889)
		(layer "In11.Cu")
		(net "M_C_DQ<50>")
	)
	(arc
		(start 283.85135 -62.5348)
		(mid 283.848995 -62.539151)
		(end 283.846524 -62.543436)
		(width 0.0889)
		(layer "In11.Cu")
		(net "M_C_DQ<50>")
	)
	(arc
		(start 283.840174 -60.572904)
		(mid 283.767376 -60.863667)
		(end 283.846524 -61.152786)
		(width 0.0889)
		(layer "In11.Cu")
		(net "M_C_DQ<50>")
	)
	(arc
		(start 283.840174 -57.601104)
		(mid 283.767376 -57.891867)
		(end 283.846524 -58.180986)
		(width 0.0889)
		(layer "In11.Cu")
		(net "M_C_DQ<50>")
	)
	(arc
		(start 283.846524 -58.180986)
		(mid 283.899994 -58.376049)
		(end 283.85135 -58.5724)
		(width 0.0889)
		(layer "In11.Cu")
		(net "M_C_DQ<50>")
	)
	(arc
		(start 283.846524 -59.171586)
		(mid 283.900023 -59.371484)
		(end 283.846524 -59.571382)
		(width 0.0889)
		(layer "In11.Cu")
		(net "M_C_DQ<50>")
	)
	(arc
		(start 283.840174 -55.619904)
		(mid 283.767376 -55.910667)
		(end 283.846524 -56.199786)
		(width 0.0889)
		(layer "In11.Cu")
		(net "M_C_DQ<50>")
	)
	(arc
		(start 283.840174 -61.563504)
		(mid 283.767376 -61.854267)
		(end 283.846524 -62.143386)
		(width 0.0889)
		(layer "In11.Cu")
		(net "M_C_DQ<50>")
	)
	(arc
		(start 283.846524 -56.199786)
		(mid 283.899994 -56.394849)
		(end 283.85135 -56.5912)
		(width 0.0889)
		(layer "In11.Cu")
		(net "M_C_DQ<50>")
	)
	(arc
		(start 283.846524 -59.571382)
		(mid 283.767393 -59.866784)
		(end 283.846524 -60.162186)
		(width 0.0889)
		(layer "In11.Cu")
		(net "M_C_DQ<50>")
	)
	(arc
		(start 283.840174 -62.554104)
		(mid 283.767779 -62.812116)
		(end 283.816806 -63.075566)
		(width 0.0889)
		(layer "In11.Cu")
		(net "M_C_DQ<50>")
	)
	(arc
		(start 283.846524 -55.209186)
		(mid 283.899994 -55.404249)
		(end 283.85135 -55.6006)
		(width 0.0889)
		(layer "In11.Cu")
		(net "M_C_DQ<50>")
	)
	(arc
		(start 283.846524 -57.190386)
		(mid 283.899994 -57.385449)
		(end 283.85135 -57.5818)
		(width 0.0889)
		(layer "In11.Cu")
		(net "M_C_DQ<50>")
	)
	(arc
		(start 283.846524 -62.143386)
		(mid 283.899994 -62.338449)
		(end 283.85135 -62.5348)
		(width 0.0889)
		(layer "In11.Cu")
		(net "M_C_DQ<50>")
	)
	(arc
		(start 283.846524 -61.152786)
		(mid 283.899994 -61.347849)
		(end 283.85135 -61.5442)
		(width 0.0889)
		(layer "In11.Cu")
		(net "M_C_DQ<50>")
	)
	(arc
		(start 283.840174 -56.610504)
		(mid 283.767376 -56.901267)
		(end 283.846524 -57.190386)
		(width 0.0889)
		(layer "In11.Cu")
		(net "M_C_DQ<50>")
	)
	(arc
		(start 283.846524 -60.162186)
		(mid 283.899994 -60.357249)
		(end 283.85135 -60.5536)
		(width 0.0889)
		(layer "In11.Cu")
		(net "M_C_DQ<50>")
	)
	(segment
		(start 197.250304 -0.821182)
		(end 197.249796 -0.821182)
		(width 0.1651)
		(layer "F.Cu")
		(net "M_C_DQ<4>")
	)
	(segment
		(start 197.249796 -0.821182)
		(end 197.249796 0.510032)
		(width 0.1651)
		(layer "F.Cu")
		(net "M_C_DQ<4>")
	)
	(segment
		(start 242.193318 -66.982086)
		(end 241.621818 -66.982086)
		(width 0.0889)
		(layer "F.Cu")
		(net "M_C_DQ<4>")
	)
	(segment
		(start 197.249796 0.510032)
		(end 197.151752 1.0414)
		(width 0.1651)
		(layer "F.Cu")
		(net "M_C_DQ<4>")
	)
	(via
		(at 197.151752 1.0414)
		(size 0.508)
		(drill 0.254)
		(layers "F.Cu" "B.Cu")
		(net "M_C_DQ<4>")
	)
	(via
		(at 196.399912 -4.357878)
		(size 0.508)
		(drill 0.254)
		(layers "F.Cu" "B.Cu")
		(net "M_C_DQ<4>")
	)
	(via
		(at 241.621818 -66.982086)
		(size 0.508)
		(drill 0.254)
		(layers "F.Cu" "B.Cu")
		(net "M_C_DQ<4>")
	)
	(segment
		(start 196.399912 -5.621782)
		(end 196.399912 -4.357878)
		(width 0.1651)
		(layer "B.Cu")
		(net "M_C_DQ<4>")
	)
	(segment
		(start 196.40042 -5.621782)
		(end 196.399912 -5.621782)
		(width 0.1651)
		(layer "B.Cu")
		(net "M_C_DQ<4>")
	)
	(segment
		(start 196.8754 -2.141728)
		(end 196.524118 -1.790446)
		(width 0.14224)
		(layer "In11.Cu")
		(net "M_C_DQ<4>")
	)
	(segment
		(start 231.889554 -67.07759)
		(end 232.195878 -67.07759)
		(width 0.0889)
		(layer "In11.Cu")
		(net "M_C_DQ<4>")
	)
	(segment
		(start 196.923152 -9.426448)
		(end 196.7484 -9.6012)
		(width 0.14224)
		(layer "In11.Cu")
		(net "M_C_DQ<4>")
	)
	(segment
		(start 233.877358 -67.07759)
		(end 233.912918 -67.07759)
		(width 0.0889)
		(layer "In11.Cu")
		(net "M_C_DQ<4>")
	)
	(segment
		(start 231.641904 -67.32524)
		(end 231.889554 -67.07759)
		(width 0.0889)
		(layer "In11.Cu")
		(net "M_C_DQ<4>")
	)
	(segment
		(start 196.892418 -0.762)
		(end 196.511418 -0.381)
		(width 0.14224)
		(layer "In11.Cu")
		(net "M_C_DQ<4>")
	)
	(segment
		(start 225.406966 -67.72402)
		(end 230.867966 -67.72402)
		(width 0.14224)
		(layer "In11.Cu")
		(net "M_C_DQ<4>")
	)
	(segment
		(start 196.511418 -0.076454)
		(end 196.8754 0.287528)
		(width 0.14224)
		(layer "In11.Cu")
		(net "M_C_DQ<4>")
	)
	(segment
		(start 236.449108 -67.572636)
		(end 236.481874 -67.572636)
		(width 0.0889)
		(layer "In11.Cu")
		(net "M_C_DQ<4>")
	)
	(segment
		(start 196.669152 -21.949156)
		(end 196.669152 -23.168356)
		(width 0.14224)
		(layer "In11.Cu")
		(net "M_C_DQ<4>")
	)
	(segment
		(start 196.669152 -8.785098)
		(end 196.923152 -9.039098)
		(width 0.14224)
		(layer "In11.Cu")
		(net "M_C_DQ<4>")
	)
	(segment
		(start 196.1642 -3.327654)
		(end 196.8754 -2.616454)
		(width 0.14224)
		(layer "In11.Cu")
		(net "M_C_DQ<4>")
	)
	(segment
		(start 196.892418 -1.0668)
		(end 196.892418 -0.762)
		(width 0.14224)
		(layer "In11.Cu")
		(net "M_C_DQ<4>")
	)
	(segment
		(start 196.669152 -7.470394)
		(end 196.669152 -8.785098)
		(width 0.14224)
		(layer "In11.Cu")
		(net "M_C_DQ<4>")
	)
	(segment
		(start 196.8754 -23.374604)
		(end 196.8754 -39.192454)
		(width 0.14224)
		(layer "In11.Cu")
		(net "M_C_DQ<4>")
	)
	(segment
		(start 241.31651 -67.68592)
		(end 241.621818 -66.982086)
		(width 0.0889)
		(layer "In11.Cu")
		(net "M_C_DQ<4>")
	)
	(segment
		(start 196.7484 -21.1582)
		(end 196.923152 -21.332952)
		(width 0.14224)
		(layer "In11.Cu")
		(net "M_C_DQ<4>")
	)
	(segment
		(start 239.893602 -68.563236)
		(end 239.926368 -68.563236)
		(width 0.0889)
		(layer "In11.Cu")
		(net "M_C_DQ<4>")
	)
	(segment
		(start 196.7484 -19.1516)
		(end 196.7484 -21.1582)
		(width 0.14224)
		(layer "In11.Cu")
		(net "M_C_DQ<4>")
	)
	(segment
		(start 196.923152 -12.093956)
		(end 196.669152 -12.347956)
		(width 0.14224)
		(layer "In11.Cu")
		(net "M_C_DQ<4>")
	)
	(segment
		(start 196.7484 -11.585448)
		(end 196.923152 -11.7602)
		(width 0.14224)
		(layer "In11.Cu")
		(net "M_C_DQ<4>")
	)
	(segment
		(start 196.923152 -21.695156)
		(end 196.669152 -21.949156)
		(width 0.14224)
		(layer "In11.Cu")
		(net "M_C_DQ<4>")
	)
	(segment
		(start 231.346502 -67.72402)
		(end 231.641904 -67.428618)
		(width 0.0889)
		(layer "In11.Cu")
		(net "M_C_DQ<4>")
	)
	(segment
		(start 237.311438 -68.06819)
		(end 237.344204 -68.06819)
		(width 0.0889)
		(layer "In11.Cu")
		(net "M_C_DQ<4>")
	)
	(segment
		(start 196.669152 -23.168356)
		(end 196.8754 -23.374604)
		(width 0.14224)
		(layer "In11.Cu")
		(net "M_C_DQ<4>")
	)
	(segment
		(start 196.399912 -6.382258)
		(end 196.897752 -6.880098)
		(width 0.14224)
		(layer "In11.Cu")
		(net "M_C_DQ<4>")
	)
	(segment
		(start 235.594398 -67.07759)
		(end 235.627164 -67.07759)
		(width 0.0889)
		(layer "In11.Cu")
		(net "M_C_DQ<4>")
	)
	(segment
		(start 196.8754 0.765048)
		(end 197.151752 1.0414)
		(width 0.14224)
		(layer "In11.Cu")
		(net "M_C_DQ<4>")
	)
	(segment
		(start 196.8754 0.287528)
		(end 196.8754 0.765048)
		(width 0.14224)
		(layer "In11.Cu")
		(net "M_C_DQ<4>")
	)
	(segment
		(start 230.867966 -67.72402)
		(end 231.346502 -67.72402)
		(width 0.0889)
		(layer "In11.Cu")
		(net "M_C_DQ<4>")
	)
	(segment
		(start 196.524118 -1.790446)
		(end 196.524118 -1.4351)
		(width 0.14224)
		(layer "In11.Cu")
		(net "M_C_DQ<4>")
	)
	(segment
		(start 196.511418 -0.381)
		(end 196.511418 -0.076454)
		(width 0.14224)
		(layer "In11.Cu")
		(net "M_C_DQ<4>")
	)
	(segment
		(start 196.897752 -7.241794)
		(end 196.669152 -7.470394)
		(width 0.14224)
		(layer "In11.Cu")
		(net "M_C_DQ<4>")
	)
	(segment
		(start 238.166148 -68.563236)
		(end 238.198914 -68.563236)
		(width 0.0889)
		(layer "In11.Cu")
		(net "M_C_DQ<4>")
	)
	(segment
		(start 196.669152 -13.567156)
		(end 196.897752 -13.795756)
		(width 0.14224)
		(layer "In11.Cu")
		(net "M_C_DQ<4>")
	)
	(segment
		(start 196.897752 -16.817594)
		(end 196.669152 -17.046194)
		(width 0.14224)
		(layer "In11.Cu")
		(net "M_C_DQ<4>")
	)
	(segment
		(start 196.1642 -4.122166)
		(end 196.1642 -3.327654)
		(width 0.14224)
		(layer "In11.Cu")
		(net "M_C_DQ<4>")
	)
	(segment
		(start 196.669152 -12.347956)
		(end 196.669152 -13.567156)
		(width 0.14224)
		(layer "In11.Cu")
		(net "M_C_DQ<4>")
	)
	(segment
		(start 196.897752 -13.795756)
		(end 196.897752 -16.817594)
		(width 0.14224)
		(layer "In11.Cu")
		(net "M_C_DQ<4>")
	)
	(segment
		(start 196.923152 -11.7602)
		(end 196.923152 -12.093956)
		(width 0.14224)
		(layer "In11.Cu")
		(net "M_C_DQ<4>")
	)
	(segment
		(start 231.641904 -67.428618)
		(end 231.641904 -67.32524)
		(width 0.0889)
		(layer "In11.Cu")
		(net "M_C_DQ<4>")
	)
	(segment
		(start 240.748312 -68.06819)
		(end 240.781078 -68.06819)
		(width 0.0889)
		(layer "In11.Cu")
		(net "M_C_DQ<4>")
	)
	(segment
		(start 196.7484 -9.6012)
		(end 196.7484 -11.585448)
		(width 0.14224)
		(layer "In11.Cu")
		(net "M_C_DQ<4>")
	)
	(segment
		(start 196.8754 -39.192454)
		(end 225.406966 -67.72402)
		(width 0.14224)
		(layer "In11.Cu")
		(net "M_C_DQ<4>")
	)
	(segment
		(start 196.923152 -18.567146)
		(end 196.923152 -18.976848)
		(width 0.14224)
		(layer "In11.Cu")
		(net "M_C_DQ<4>")
	)
	(segment
		(start 196.923152 -9.039098)
		(end 196.923152 -9.426448)
		(width 0.14224)
		(layer "In11.Cu")
		(net "M_C_DQ<4>")
	)
	(segment
		(start 196.399912 -4.357878)
		(end 196.1642 -4.122166)
		(width 0.14224)
		(layer "In11.Cu")
		(net "M_C_DQ<4>")
	)
	(segment
		(start 196.8754 -2.616454)
		(end 196.8754 -2.141728)
		(width 0.14224)
		(layer "In11.Cu")
		(net "M_C_DQ<4>")
	)
	(segment
		(start 196.669152 -18.313146)
		(end 196.923152 -18.567146)
		(width 0.14224)
		(layer "In11.Cu")
		(net "M_C_DQ<4>")
	)
	(segment
		(start 196.399912 -4.357878)
		(end 196.399912 -6.382258)
		(width 0.14224)
		(layer "In11.Cu")
		(net "M_C_DQ<4>")
	)
	(segment
		(start 196.669152 -17.046194)
		(end 196.669152 -18.313146)
		(width 0.14224)
		(layer "In11.Cu")
		(net "M_C_DQ<4>")
	)
	(segment
		(start 196.923152 -18.976848)
		(end 196.7484 -19.1516)
		(width 0.14224)
		(layer "In11.Cu")
		(net "M_C_DQ<4>")
	)
	(segment
		(start 239.028478 -69.05879)
		(end 239.064038 -69.05879)
		(width 0.0889)
		(layer "In11.Cu")
		(net "M_C_DQ<4>")
	)
	(segment
		(start 196.897752 -6.880098)
		(end 196.897752 -7.241794)
		(width 0.14224)
		(layer "In11.Cu")
		(net "M_C_DQ<4>")
	)
	(segment
		(start 196.923152 -21.332952)
		(end 196.923152 -21.695156)
		(width 0.14224)
		(layer "In11.Cu")
		(net "M_C_DQ<4>")
	)
	(segment
		(start 196.524118 -1.4351)
		(end 196.892418 -1.0668)
		(width 0.14224)
		(layer "In11.Cu")
		(net "M_C_DQ<4>")
	)
	(arc
		(start 232.195878 -67.07759)
		(mid 232.481302 -66.994123)
		(end 232.689908 -66.782188)
		(width 0.0889)
		(layer "In11.Cu")
		(net "M_C_DQ<4>")
	)
	(arc
		(start 237.344204 -68.06819)
		(mid 237.535846 -68.125356)
		(end 237.675928 -68.268088)
		(width 0.0889)
		(layer "In11.Cu")
		(net "M_C_DQ<4>")
	)
	(arc
		(start 239.926368 -68.563236)
		(mid 240.209585 -68.478955)
		(end 240.416588 -68.268088)
		(width 0.0889)
		(layer "In11.Cu")
		(net "M_C_DQ<4>")
	)
	(arc
		(start 232.689908 -66.782188)
		(mid 233.036618 -66.581877)
		(end 233.383328 -66.782188)
		(width 0.0889)
		(layer "In11.Cu")
		(net "M_C_DQ<4>")
	)
	(arc
		(start 235.100368 -66.782188)
		(mid 235.308976 -66.99412)
		(end 235.594398 -67.07759)
		(width 0.0889)
		(layer "In11.Cu")
		(net "M_C_DQ<4>")
	)
	(arc
		(start 238.198914 -68.563236)
		(mid 238.392764 -68.619586)
		(end 238.534448 -68.763388)
		(width 0.0889)
		(layer "In11.Cu")
		(net "M_C_DQ<4>")
	)
	(arc
		(start 239.064038 -69.05879)
		(mid 239.349462 -68.975323)
		(end 239.558068 -68.763388)
		(width 0.0889)
		(layer "In11.Cu")
		(net "M_C_DQ<4>")
	)
	(arc
		(start 239.558068 -68.763388)
		(mid 239.699751 -68.619584)
		(end 239.893602 -68.563236)
		(width 0.0889)
		(layer "In11.Cu")
		(net "M_C_DQ<4>")
	)
	(arc
		(start 233.383328 -66.782188)
		(mid 233.591936 -66.99412)
		(end 233.877358 -67.07759)
		(width 0.0889)
		(layer "In11.Cu")
		(net "M_C_DQ<4>")
	)
	(arc
		(start 240.781078 -68.06819)
		(mid 241.106938 -67.958471)
		(end 241.31651 -67.68592)
		(width 0.0889)
		(layer "In11.Cu")
		(net "M_C_DQ<4>")
	)
	(arc
		(start 240.416588 -68.268088)
		(mid 240.556667 -68.125352)
		(end 240.748312 -68.06819)
		(width 0.0889)
		(layer "In11.Cu")
		(net "M_C_DQ<4>")
	)
	(arc
		(start 236.817408 -67.772788)
		(mid 237.026016 -67.98472)
		(end 237.311438 -68.06819)
		(width 0.0889)
		(layer "In11.Cu")
		(net "M_C_DQ<4>")
	)
	(arc
		(start 238.534448 -68.763388)
		(mid 238.743056 -68.97532)
		(end 239.028478 -69.05879)
		(width 0.0889)
		(layer "In11.Cu")
		(net "M_C_DQ<4>")
	)
	(arc
		(start 235.627164 -67.07759)
		(mid 235.818806 -67.134756)
		(end 235.958888 -67.277488)
		(width 0.0889)
		(layer "In11.Cu")
		(net "M_C_DQ<4>")
	)
	(arc
		(start 237.675928 -68.268088)
		(mid 237.882932 -68.478952)
		(end 238.166148 -68.563236)
		(width 0.0889)
		(layer "In11.Cu")
		(net "M_C_DQ<4>")
	)
	(arc
		(start 235.958888 -67.277488)
		(mid 236.165892 -67.488352)
		(end 236.449108 -67.572636)
		(width 0.0889)
		(layer "In11.Cu")
		(net "M_C_DQ<4>")
	)
	(arc
		(start 234.406948 -66.782188)
		(mid 234.753658 -66.581877)
		(end 235.100368 -66.782188)
		(width 0.0889)
		(layer "In11.Cu")
		(net "M_C_DQ<4>")
	)
	(arc
		(start 233.912918 -67.07759)
		(mid 234.198342 -66.994123)
		(end 234.406948 -66.782188)
		(width 0.0889)
		(layer "In11.Cu")
		(net "M_C_DQ<4>")
	)
	(arc
		(start 236.481874 -67.572636)
		(mid 236.675724 -67.628986)
		(end 236.817408 -67.772788)
		(width 0.0889)
		(layer "In11.Cu")
		(net "M_C_DQ<4>")
	)
	(segment
		(start 300.100492 3.778758)
		(end 300.099984 3.778758)
		(width 0.1651)
		(layer "F.Cu")
		(net "M_C_DQ<49>")
	)
	(segment
		(start 300.099984 3.778758)
		(end 300.099984 2.514854)
		(width 0.1651)
		(layer "F.Cu")
		(net "M_C_DQ<49>")
	)
	(segment
		(start 281.495754 -64.819784)
		(end 280.924254 -64.819784)
		(width 0.0889)
		(layer "F.Cu")
		(net "M_C_DQ<49>")
	)
	(via
		(at 300.099984 2.514854)
		(size 0.508)
		(drill 0.254)
		(layers "F.Cu" "B.Cu")
		(net "M_C_DQ<49>")
	)
	(via
		(at 300.772068 -3.076956)
		(size 0.508)
		(drill 0.254)
		(layers "F.Cu" "B.Cu")
		(net "M_C_DQ<49>")
	)
	(via
		(at 280.924254 -64.819784)
		(size 0.508)
		(drill 0.254)
		(layers "F.Cu" "B.Cu")
		(net "M_C_DQ<49>")
	)
	(segment
		(start 300.772068 -2.573782)
		(end 300.772068 -3.076956)
		(width 0.1651)
		(layer "B.Cu")
		(net "M_C_DQ<49>")
	)
	(segment
		(start 300.949868 -1.021842)
		(end 300.949868 -2.395982)
		(width 0.1651)
		(layer "B.Cu")
		(net "M_C_DQ<49>")
	)
	(segment
		(start 300.950376 -1.021842)
		(end 300.949868 -1.021842)
		(width 0.1651)
		(layer "B.Cu")
		(net "M_C_DQ<49>")
	)
	(segment
		(start 300.949868 -2.395982)
		(end 300.772068 -2.573782)
		(width 0.1651)
		(layer "B.Cu")
		(net "M_C_DQ<49>")
	)
	(segment
		(start 280.761948 -62.213998)
		(end 281.032204 -62.39256)
		(width 0.0889)
		(layer "In11.Cu")
		(net "M_C_DQ<49>")
	)
	(segment
		(start 300.099984 2.514854)
		(end 300.099984 1.975866)
		(width 0.14224)
		(layer "In11.Cu")
		(net "M_C_DQ<49>")
	)
	(segment
		(start 301.260002 -6.569202)
		(end 301.260002 -19.015202)
		(width 0.14224)
		(layer "In11.Cu")
		(net "M_C_DQ<49>")
	)
	(segment
		(start 280.577544 -63.629286)
		(end 280.572718 -63.637922)
		(width 0.0889)
		(layer "In11.Cu")
		(net "M_C_DQ<49>")
	)
	(segment
		(start 281.239722 -63.092838)
		(end 281.13228 -63.200026)
		(width 0.0889)
		(layer "In11.Cu")
		(net "M_C_DQ<49>")
	)
	(segment
		(start 300.245526 -3.603498)
		(end 300.245526 -3.852672)
		(width 0.14224)
		(layer "In11.Cu")
		(net "M_C_DQ<49>")
	)
	(segment
		(start 280.577544 -59.076336)
		(end 280.583894 -59.087004)
		(width 0.0889)
		(layer "In11.Cu")
		(net "M_C_DQ<49>")
	)
	(segment
		(start 301.14621 -2.702814)
		(end 300.772068 -3.076956)
		(width 0.14224)
		(layer "In11.Cu")
		(net "M_C_DQ<49>")
	)
	(segment
		(start 280.577036 -54.12359)
		(end 280.577544 -54.123336)
		(width 0.0889)
		(layer "In11.Cu")
		(net "M_C_DQ<49>")
	)
	(segment
		(start 280.583894 -55.693818)
		(end 280.577544 -55.704486)
		(width 0.0889)
		(layer "In11.Cu")
		(net "M_C_DQ<49>")
	)
	(segment
		(start 280.577544 -56.695086)
		(end 280.572718 -56.703722)
		(width 0.0889)
		(layer "In11.Cu")
		(net "M_C_DQ<49>")
	)
	(segment
		(start 300.57725 1.4986)
		(end 300.93285 1.4986)
		(width 0.14224)
		(layer "In11.Cu")
		(net "M_C_DQ<49>")
	)
	(segment
		(start 281.270964 -63.038736)
		(end 281.239722 -63.092838)
		(width 0.0889)
		(layer "In11.Cu")
		(net "M_C_DQ<49>")
	)
	(segment
		(start 280.9494 -47.0916)
		(end 280.237184 -47.803816)
		(width 0.0889)
		(layer "In11.Cu")
		(net "M_C_DQ<49>")
	)
	(segment
		(start 301.260002 -21.3106)
		(end 301.260002 -29.3624)
		(width 0.14224)
		(layer "In11.Cu")
		(net "M_C_DQ<49>")
	)
	(segment
		(start 280.524204 -53.442362)
		(end 280.524204 -54.03215)
		(width 0.0889)
		(layer "In11.Cu")
		(net "M_C_DQ<49>")
	)
	(segment
		(start 280.577544 -59.666886)
		(end 280.572718 -59.675522)
		(width 0.0889)
		(layer "In11.Cu")
		(net "M_C_DQ<49>")
	)
	(segment
		(start 301.4218 -19.177)
		(end 301.4218 -21.148802)
		(width 0.14224)
		(layer "In11.Cu")
		(net "M_C_DQ<49>")
	)
	(segment
		(start 300.772068 -3.076956)
		(end 300.245526 -3.603498)
		(width 0.14224)
		(layer "In11.Cu")
		(net "M_C_DQ<49>")
	)
	(segment
		(start 280.577544 -60.657486)
		(end 280.572718 -60.666122)
		(width 0.0889)
		(layer "In11.Cu")
		(net "M_C_DQ<49>")
	)
	(segment
		(start 301.4218 -21.148802)
		(end 301.260002 -21.3106)
		(width 0.14224)
		(layer "In11.Cu")
		(net "M_C_DQ<49>")
	)
	(segment
		(start 280.577544 -61.648086)
		(end 280.572718 -61.656722)
		(width 0.0889)
		(layer "In11.Cu")
		(net "M_C_DQ<49>")
	)
	(segment
		(start 280.594308 -64.058038)
		(end 280.924254 -64.819784)
		(width 0.0889)
		(layer "In11.Cu")
		(net "M_C_DQ<49>")
	)
	(segment
		(start 281.032204 -62.39256)
		(end 281.229816 -62.567312)
		(width 0.0889)
		(layer "In11.Cu")
		(net "M_C_DQ<49>")
	)
	(segment
		(start 280.237184 -47.803816)
		(end 280.237184 -53.155342)
		(width 0.0889)
		(layer "In11.Cu")
		(net "M_C_DQ<49>")
	)
	(segment
		(start 300.099984 1.975866)
		(end 300.57725 1.4986)
		(width 0.14224)
		(layer "In11.Cu")
		(net "M_C_DQ<49>")
	)
	(segment
		(start 280.583894 -61.637418)
		(end 280.577544 -61.648086)
		(width 0.0889)
		(layer "In11.Cu")
		(net "M_C_DQ<49>")
	)
	(segment
		(start 280.583894 -57.675018)
		(end 280.577544 -57.685686)
		(width 0.0889)
		(layer "In11.Cu")
		(net "M_C_DQ<49>")
	)
	(segment
		(start 300.245526 -3.852672)
		(end 300.625002 -4.232148)
		(width 0.14224)
		(layer "In11.Cu")
		(net "M_C_DQ<49>")
	)
	(segment
		(start 284.039056 -39.178992)
		(end 284.039056 -42.679112)
		(width 0.14224)
		(layer "In11.Cu")
		(net "M_C_DQ<49>")
	)
	(segment
		(start 290.370768 -33.803844)
		(end 289.414204 -33.803844)
		(width 0.14224)
		(layer "In11.Cu")
		(net "M_C_DQ<49>")
	)
	(segment
		(start 281.13228 -63.200026)
		(end 280.738834 -63.474346)
		(width 0.0889)
		(layer "In11.Cu")
		(net "M_C_DQ<49>")
	)
	(segment
		(start 280.577544 -57.685686)
		(end 280.572718 -57.694322)
		(width 0.0889)
		(layer "In11.Cu")
		(net "M_C_DQ<49>")
	)
	(segment
		(start 281.229816 -62.567312)
		(end 281.27579 -62.647322)
		(width 0.0889)
		(layer "In11.Cu")
		(net "M_C_DQ<49>")
	)
	(segment
		(start 301.260002 -19.015202)
		(end 301.4218 -19.177)
		(width 0.14224)
		(layer "In11.Cu")
		(net "M_C_DQ<49>")
	)
	(segment
		(start 280.577544 -64.029336)
		(end 280.594308 -64.058038)
		(width 0.0889)
		(layer "In11.Cu")
		(net "M_C_DQ<49>")
	)
	(segment
		(start 300.93285 1.4986)
		(end 301.302674 1.128776)
		(width 0.14224)
		(layer "In11.Cu")
		(net "M_C_DQ<49>")
	)
	(segment
		(start 280.583894 -60.646818)
		(end 280.577544 -60.657486)
		(width 0.0889)
		(layer "In11.Cu")
		(net "M_C_DQ<49>")
	)
	(segment
		(start 290.875212 -33.2994)
		(end 290.370768 -33.803844)
		(width 0.14224)
		(layer "In11.Cu")
		(net "M_C_DQ<49>")
	)
	(segment
		(start 280.237184 -53.155342)
		(end 280.524204 -53.442362)
		(width 0.0889)
		(layer "In11.Cu")
		(net "M_C_DQ<49>")
	)
	(segment
		(start 280.583894 -54.703218)
		(end 280.577544 -54.713886)
		(width 0.0889)
		(layer "In11.Cu")
		(net "M_C_DQ<49>")
	)
	(segment
		(start 280.577544 -55.704486)
		(end 280.572718 -55.713122)
		(width 0.0889)
		(layer "In11.Cu")
		(net "M_C_DQ<49>")
	)
	(segment
		(start 284.039056 -42.679112)
		(end 280.9494 -45.768768)
		(width 0.14224)
		(layer "In11.Cu")
		(net "M_C_DQ<49>")
	)
	(segment
		(start 301.302674 0.7874)
		(end 301.14621 0.630936)
		(width 0.14224)
		(layer "In11.Cu")
		(net "M_C_DQ<49>")
	)
	(segment
		(start 301.302674 1.128776)
		(end 301.302674 0.7874)
		(width 0.14224)
		(layer "In11.Cu")
		(net "M_C_DQ<49>")
	)
	(segment
		(start 297.323002 -33.2994)
		(end 290.875212 -33.2994)
		(width 0.14224)
		(layer "In11.Cu")
		(net "M_C_DQ<49>")
	)
	(segment
		(start 300.625002 -4.232148)
		(end 300.625002 -5.934202)
		(width 0.14224)
		(layer "In11.Cu")
		(net "M_C_DQ<49>")
	)
	(segment
		(start 280.524204 -54.03215)
		(end 280.577036 -54.12359)
		(width 0.0889)
		(layer "In11.Cu")
		(net "M_C_DQ<49>")
	)
	(segment
		(start 289.414204 -33.803844)
		(end 284.039056 -39.178992)
		(width 0.14224)
		(layer "In11.Cu")
		(net "M_C_DQ<49>")
	)
	(segment
		(start 300.625002 -5.934202)
		(end 301.260002 -6.569202)
		(width 0.14224)
		(layer "In11.Cu")
		(net "M_C_DQ<49>")
	)
	(segment
		(start 280.583894 -56.684418)
		(end 280.577544 -56.695086)
		(width 0.0889)
		(layer "In11.Cu")
		(net "M_C_DQ<49>")
	)
	(segment
		(start 280.9494 -45.768768)
		(end 280.9494 -47.0916)
		(width 0.14224)
		(layer "In11.Cu")
		(net "M_C_DQ<49>")
	)
	(segment
		(start 301.260002 -29.3624)
		(end 297.323002 -33.2994)
		(width 0.14224)
		(layer "In11.Cu")
		(net "M_C_DQ<49>")
	)
	(segment
		(start 280.577544 -54.713886)
		(end 280.572718 -54.722522)
		(width 0.0889)
		(layer "In11.Cu")
		(net "M_C_DQ<49>")
	)
	(segment
		(start 301.14621 0.630936)
		(end 301.14621 -2.702814)
		(width 0.14224)
		(layer "In11.Cu")
		(net "M_C_DQ<49>")
	)
	(arc
		(start 280.572718 -63.637922)
		(mid 280.523963 -63.834274)
		(end 280.577544 -64.029336)
		(width 0.0889)
		(layer "In11.Cu")
		(net "M_C_DQ<49>")
	)
	(arc
		(start 280.572718 -61.656722)
		(mid 280.545335 -61.976743)
		(end 280.761948 -62.213998)
		(width 0.0889)
		(layer "In11.Cu")
		(net "M_C_DQ<49>")
	)
	(arc
		(start 280.577544 -57.095136)
		(mid 280.656766 -57.384254)
		(end 280.583894 -57.675018)
		(width 0.0889)
		(layer "In11.Cu")
		(net "M_C_DQ<49>")
	)
	(arc
		(start 280.572718 -57.694322)
		(mid 280.523963 -57.890674)
		(end 280.577544 -58.085736)
		(width 0.0889)
		(layer "In11.Cu")
		(net "M_C_DQ<49>")
	)
	(arc
		(start 280.577544 -60.066936)
		(mid 280.656766 -60.356054)
		(end 280.583894 -60.646818)
		(width 0.0889)
		(layer "In11.Cu")
		(net "M_C_DQ<49>")
	)
	(arc
		(start 280.572718 -55.713122)
		(mid 280.523963 -55.909474)
		(end 280.577544 -56.104536)
		(width 0.0889)
		(layer "In11.Cu")
		(net "M_C_DQ<49>")
	)
	(arc
		(start 280.577544 -58.085736)
		(mid 280.656675 -58.381138)
		(end 280.577544 -58.67654)
		(width 0.0889)
		(layer "In11.Cu")
		(net "M_C_DQ<49>")
	)
	(arc
		(start 280.572718 -54.722522)
		(mid 280.523963 -54.918874)
		(end 280.577544 -55.113936)
		(width 0.0889)
		(layer "In11.Cu")
		(net "M_C_DQ<49>")
	)
	(arc
		(start 280.572718 -60.666122)
		(mid 280.523963 -60.862474)
		(end 280.577544 -61.057536)
		(width 0.0889)
		(layer "In11.Cu")
		(net "M_C_DQ<49>")
	)
	(arc
		(start 280.583894 -59.087004)
		(mid 280.656692 -59.377767)
		(end 280.577544 -59.666886)
		(width 0.0889)
		(layer "In11.Cu")
		(net "M_C_DQ<49>")
	)
	(arc
		(start 280.572718 -59.675522)
		(mid 280.523963 -59.871874)
		(end 280.577544 -60.066936)
		(width 0.0889)
		(layer "In11.Cu")
		(net "M_C_DQ<49>")
	)
	(arc
		(start 281.27579 -62.647322)
		(mid 281.324545 -62.843674)
		(end 281.270964 -63.038736)
		(width 0.0889)
		(layer "In11.Cu")
		(net "M_C_DQ<49>")
	)
	(arc
		(start 280.577544 -54.123336)
		(mid 280.656766 -54.412454)
		(end 280.583894 -54.703218)
		(width 0.0889)
		(layer "In11.Cu")
		(net "M_C_DQ<49>")
	)
	(arc
		(start 280.572718 -56.703722)
		(mid 280.523963 -56.900074)
		(end 280.577544 -57.095136)
		(width 0.0889)
		(layer "In11.Cu")
		(net "M_C_DQ<49>")
	)
	(arc
		(start 280.738834 -63.474346)
		(mid 280.647166 -63.540337)
		(end 280.577544 -63.629286)
		(width 0.0889)
		(layer "In11.Cu")
		(net "M_C_DQ<49>")
	)
	(arc
		(start 280.577544 -55.113936)
		(mid 280.656766 -55.403054)
		(end 280.583894 -55.693818)
		(width 0.0889)
		(layer "In11.Cu")
		(net "M_C_DQ<49>")
	)
	(arc
		(start 280.577544 -61.057536)
		(mid 280.656766 -61.346654)
		(end 280.583894 -61.637418)
		(width 0.0889)
		(layer "In11.Cu")
		(net "M_C_DQ<49>")
	)
	(arc
		(start 280.577544 -58.67654)
		(mid 280.524045 -58.876438)
		(end 280.577544 -59.076336)
		(width 0.0889)
		(layer "In11.Cu")
		(net "M_C_DQ<49>")
	)
	(arc
		(start 280.577544 -56.104536)
		(mid 280.656766 -56.393654)
		(end 280.583894 -56.684418)
		(width 0.0889)
		(layer "In11.Cu")
		(net "M_C_DQ<49>")
	)
	(segment
		(start 281.495754 -62.838584)
		(end 280.924254 -62.838584)
		(width 0.0889)
		(layer "F.Cu")
		(net "M_C_DQ<48>")
	)
	(segment
		(start 300.949868 -0.821182)
		(end 300.772068 1.0414)
		(width 0.1651)
		(layer "F.Cu")
		(net "M_C_DQ<48>")
	)
	(segment
		(start 300.950376 -0.821182)
		(end 300.949868 -0.821182)
		(width 0.1651)
		(layer "F.Cu")
		(net "M_C_DQ<48>")
	)
	(via
		(at 300.772068 1.0414)
		(size 0.508)
		(drill 0.254)
		(layers "F.Cu" "B.Cu")
		(net "M_C_DQ<48>")
	)
	(via
		(at 300.099984 -4.357878)
		(size 0.508)
		(drill 0.254)
		(layers "F.Cu" "B.Cu")
		(net "M_C_DQ<48>")
	)
	(via
		(at 280.924254 -62.838584)
		(size 0.508)
		(drill 0.254)
		(layers "F.Cu" "B.Cu")
		(net "M_C_DQ<48>")
	)
	(segment
		(start 300.100492 -5.621782)
		(end 300.099984 -5.621782)
		(width 0.1651)
		(layer "B.Cu")
		(net "M_C_DQ<48>")
	)
	(segment
		(start 300.099984 -5.621782)
		(end 300.099984 -4.357878)
		(width 0.1651)
		(layer "B.Cu")
		(net "M_C_DQ<48>")
	)
	(segment
		(start 300.55185 -2.090928)
		(end 300.162468 -1.701546)
		(width 0.14224)
		(layer "In11.Cu")
		(net "M_C_DQ<48>")
	)
	(segment
		(start 300.576996 -23.386796)
		(end 300.576996 -26.663396)
		(width 0.14224)
		(layer "In11.Cu")
		(net "M_C_DQ<48>")
	)
	(segment
		(start 300.297596 -18.33245)
		(end 300.627796 -18.66265)
		(width 0.14224)
		(layer "In11.Cu")
		(net "M_C_DQ<48>")
	)
	(segment
		(start 296.429176 -31.440628)
		(end 296.429176 -31.8008)
		(width 0.14224)
		(layer "In11.Cu")
		(net "M_C_DQ<48>")
	)
	(segment
		(start 300.297596 -12.355576)
		(end 300.297596 -13.502132)
		(width 0.14224)
		(layer "In11.Cu")
		(net "M_C_DQ<48>")
	)
	(segment
		(start 300.282102 -8.690102)
		(end 300.625002 -9.033002)
		(width 0.14224)
		(layer "In11.Cu")
		(net "M_C_DQ<48>")
	)
	(segment
		(start 280.412444 -62.143386)
		(end 280.429208 -62.17285)
		(width 0.0889)
		(layer "In11.Cu")
		(net "M_C_DQ<48>")
	)
	(segment
		(start 300.162468 -1.701546)
		(end 300.162468 -1.397)
		(width 0.14224)
		(layer "In11.Cu")
		(net "M_C_DQ<48>")
	)
	(segment
		(start 300.099984 -6.298184)
		(end 300.574202 -6.772402)
		(width 0.14224)
		(layer "In11.Cu")
		(net "M_C_DQ<48>")
	)
	(segment
		(start 300.627796 -18.66265)
		(end 300.627796 -19.005804)
		(width 0.14224)
		(layer "In11.Cu")
		(net "M_C_DQ<48>")
	)
	(segment
		(start 297.038776 -31.237428)
		(end 296.632376 -31.237428)
		(width 0.14224)
		(layer "In11.Cu")
		(net "M_C_DQ<48>")
	)
	(segment
		(start 300.533054 -16.867124)
		(end 300.297596 -17.102582)
		(width 0.14224)
		(layer "In11.Cu")
		(net "M_C_DQ<48>")
	)
	(segment
		(start 297.241976 -31.8008)
		(end 297.241976 -31.440628)
		(width 0.14224)
		(layer "In11.Cu")
		(net "M_C_DQ<48>")
	)
	(segment
		(start 294.3606 -32.7914)
		(end 289.52825 -32.7914)
		(width 0.14224)
		(layer "In11.Cu")
		(net "M_C_DQ<48>")
	)
	(segment
		(start 295.616376 -31.8008)
		(end 295.616376 -31.63824)
		(width 0.14224)
		(layer "In11.Cu")
		(net "M_C_DQ<48>")
	)
	(segment
		(start 280.046684 -47.707042)
		(end 280.046684 -53.235606)
		(width 0.0889)
		(layer "In11.Cu")
		(net "M_C_DQ<48>")
	)
	(segment
		(start 300.137068 -0.508)
		(end 300.137068 -0.178054)
		(width 0.14224)
		(layer "In11.Cu")
		(net "M_C_DQ<48>")
	)
	(segment
		(start 300.574202 -6.772402)
		(end 300.574202 -7.224776)
		(width 0.14224)
		(layer "In11.Cu")
		(net "M_C_DQ<48>")
	)
	(segment
		(start 296.632376 -31.237428)
		(end 296.429176 -31.440628)
		(width 0.14224)
		(layer "In11.Cu")
		(net "M_C_DQ<48>")
	)
	(segment
		(start 300.55185 0.236728)
		(end 300.55185 0.821182)
		(width 0.14224)
		(layer "In11.Cu")
		(net "M_C_DQ<48>")
	)
	(segment
		(start 280.388568 -47.167038)
		(end 280.246328 -47.309278)
		(width 0.0889)
		(layer "In11.Cu")
		(net "M_C_DQ<48>")
	)
	(segment
		(start 296.225976 -32.004)
		(end 295.819576 -32.004)
		(width 0.14224)
		(layer "In11.Cu")
		(net "M_C_DQ<48>")
	)
	(segment
		(start 280.333704 -53.522626)
		(end 280.333704 -54.108604)
		(width 0.0889)
		(layer "In11.Cu")
		(net "M_C_DQ<48>")
	)
	(segment
		(start 280.41727 -56.5912)
		(end 280.412444 -56.599836)
		(width 0.0889)
		(layer "In11.Cu")
		(net "M_C_DQ<48>")
	)
	(segment
		(start 300.576996 -16.821658)
		(end 300.533054 -16.8656)
		(width 0.14224)
		(layer "In11.Cu")
		(net "M_C_DQ<48>")
	)
	(segment
		(start 300.282102 -7.516876)
		(end 300.282102 -8.690102)
		(width 0.14224)
		(layer "In11.Cu")
		(net "M_C_DQ<48>")
	)
	(segment
		(start 280.246328 -47.507398)
		(end 280.046684 -47.707042)
		(width 0.0889)
		(layer "In11.Cu")
		(net "M_C_DQ<48>")
	)
	(segment
		(start 280.41727 -60.5536)
		(end 280.412444 -60.562236)
		(width 0.0889)
		(layer "In11.Cu")
		(net "M_C_DQ<48>")
	)
	(segment
		(start 300.297596 -17.102582)
		(end 300.297596 -18.33245)
		(width 0.14224)
		(layer "In11.Cu")
		(net "M_C_DQ<48>")
	)
	(segment
		(start 280.412444 -56.599836)
		(end 280.406094 -56.610504)
		(width 0.0889)
		(layer "In11.Cu")
		(net "M_C_DQ<48>")
	)
	(segment
		(start 300.581568 -29.142436)
		(end 297.720004 -32.004)
		(width 0.14224)
		(layer "In11.Cu")
		(net "M_C_DQ<48>")
	)
	(segment
		(start 297.445176 -32.004)
		(end 297.241976 -31.8008)
		(width 0.14224)
		(layer "In11.Cu")
		(net "M_C_DQ<48>")
	)
	(segment
		(start 300.297596 -23.107396)
		(end 300.576996 -23.386796)
		(width 0.14224)
		(layer "In11.Cu")
		(net "M_C_DQ<48>")
	)
	(segment
		(start 300.627796 -19.005804)
		(end 300.4566 -19.177)
		(width 0.14224)
		(layer "In11.Cu")
		(net "M_C_DQ<48>")
	)
	(segment
		(start 295.819576 -32.004)
		(end 295.616376 -31.8008)
		(width 0.14224)
		(layer "In11.Cu")
		(net "M_C_DQ<48>")
	)
	(segment
		(start 280.429208 -62.17285)
		(end 280.924254 -62.838584)
		(width 0.0889)
		(layer "In11.Cu")
		(net "M_C_DQ<48>")
	)
	(segment
		(start 300.625002 -12.02817)
		(end 300.297596 -12.355576)
		(width 0.14224)
		(layer "In11.Cu")
		(net "M_C_DQ<48>")
	)
	(segment
		(start 300.4566 -21.215604)
		(end 300.627796 -21.3868)
		(width 0.14224)
		(layer "In11.Cu")
		(net "M_C_DQ<48>")
	)
	(segment
		(start 280.41727 -54.61)
		(end 280.412444 -54.618636)
		(width 0.0889)
		(layer "In11.Cu")
		(net "M_C_DQ<48>")
	)
	(segment
		(start 300.4566 -19.177)
		(end 300.4566 -21.215604)
		(width 0.14224)
		(layer "In11.Cu")
		(net "M_C_DQ<48>")
	)
	(segment
		(start 280.412444 -61.552836)
		(end 280.406094 -61.563504)
		(width 0.0889)
		(layer "In11.Cu")
		(net "M_C_DQ<48>")
	)
	(segment
		(start 283.428186 -38.891464)
		(end 283.428186 -42.382186)
		(width 0.14224)
		(layer "In11.Cu")
		(net "M_C_DQ<48>")
	)
	(segment
		(start 300.576996 -13.781532)
		(end 300.576996 -16.821658)
		(width 0.14224)
		(layer "In11.Cu")
		(net "M_C_DQ<48>")
	)
	(segment
		(start 300.55185 0.821182)
		(end 300.772068 1.0414)
		(width 0.14224)
		(layer "In11.Cu")
		(net "M_C_DQ<48>")
	)
	(segment
		(start 300.297596 -26.942796)
		(end 300.297596 -28.051252)
		(width 0.14224)
		(layer "In11.Cu")
		(net "M_C_DQ<48>")
	)
	(segment
		(start 280.41727 -58.5724)
		(end 280.412444 -58.581036)
		(width 0.0889)
		(layer "In11.Cu")
		(net "M_C_DQ<48>")
	)
	(segment
		(start 300.099984 -4.357878)
		(end 300.099984 -6.298184)
		(width 0.14224)
		(layer "In11.Cu")
		(net "M_C_DQ<48>")
	)
	(segment
		(start 300.137068 -0.178054)
		(end 300.55185 0.236728)
		(width 0.14224)
		(layer "In11.Cu")
		(net "M_C_DQ<48>")
	)
	(segment
		(start 294.803576 -31.63824)
		(end 294.803576 -32.348424)
		(width 0.14224)
		(layer "In11.Cu")
		(net "M_C_DQ<48>")
	)
	(segment
		(start 280.388568 -45.421804)
		(end 280.388568 -47.167038)
		(width 0.14224)
		(layer "In11.Cu")
		(net "M_C_DQ<48>")
	)
	(segment
		(start 295.616376 -31.63824)
		(end 295.474136 -31.496)
		(width 0.14224)
		(layer "In11.Cu")
		(net "M_C_DQ<48>")
	)
	(segment
		(start 300.55185 -2.5908)
		(end 300.55185 -2.090928)
		(width 0.14224)
		(layer "In11.Cu")
		(net "M_C_DQ<48>")
	)
	(segment
		(start 280.41727 -57.5818)
		(end 280.412444 -57.590436)
		(width 0.0889)
		(layer "In11.Cu")
		(net "M_C_DQ<48>")
	)
	(segment
		(start 294.945816 -31.496)
		(end 294.803576 -31.63824)
		(width 0.14224)
		(layer "In11.Cu")
		(net "M_C_DQ<48>")
	)
	(segment
		(start 297.720004 -32.004)
		(end 297.445176 -32.004)
		(width 0.14224)
		(layer "In11.Cu")
		(net "M_C_DQ<48>")
	)
	(segment
		(start 294.803576 -32.348424)
		(end 294.3606 -32.7914)
		(width 0.14224)
		(layer "In11.Cu")
		(net "M_C_DQ<48>")
	)
	(segment
		(start 283.428186 -42.382186)
		(end 280.388568 -45.421804)
		(width 0.14224)
		(layer "In11.Cu")
		(net "M_C_DQ<48>")
	)
	(segment
		(start 289.52825 -32.7914)
		(end 283.428186 -38.891464)
		(width 0.14224)
		(layer "In11.Cu")
		(net "M_C_DQ<48>")
	)
	(segment
		(start 297.241976 -31.440628)
		(end 297.038776 -31.237428)
		(width 0.14224)
		(layer "In11.Cu")
		(net "M_C_DQ<48>")
	)
	(segment
		(start 280.41727 -61.5442)
		(end 280.412444 -61.552836)
		(width 0.0889)
		(layer "In11.Cu")
		(net "M_C_DQ<48>")
	)
	(segment
		(start 280.333704 -54.108604)
		(end 280.369772 -54.144672)
		(width 0.0889)
		(layer "In11.Cu")
		(net "M_C_DQ<48>")
	)
	(segment
		(start 299.81525 -4.073144)
		(end 299.81525 -3.3274)
		(width 0.14224)
		(layer "In11.Cu")
		(net "M_C_DQ<48>")
	)
	(segment
		(start 300.297596 -21.964396)
		(end 300.297596 -23.107396)
		(width 0.14224)
		(layer "In11.Cu")
		(net "M_C_DQ<48>")
	)
	(segment
		(start 300.581568 -28.335224)
		(end 300.581568 -29.142436)
		(width 0.14224)
		(layer "In11.Cu")
		(net "M_C_DQ<48>")
	)
	(segment
		(start 299.81525 -3.3274)
		(end 300.55185 -2.5908)
		(width 0.14224)
		(layer "In11.Cu")
		(net "M_C_DQ<48>")
	)
	(segment
		(start 280.369772 -54.144672)
		(end 280.412444 -54.218586)
		(width 0.0889)
		(layer "In11.Cu")
		(net "M_C_DQ<48>")
	)
	(segment
		(start 280.412444 -54.618636)
		(end 280.406094 -54.629304)
		(width 0.0889)
		(layer "In11.Cu")
		(net "M_C_DQ<48>")
	)
	(segment
		(start 300.627796 -21.3868)
		(end 300.627796 -21.634196)
		(width 0.14224)
		(layer "In11.Cu")
		(net "M_C_DQ<48>")
	)
	(segment
		(start 300.162468 -1.397)
		(end 300.479968 -1.0795)
		(width 0.14224)
		(layer "In11.Cu")
		(net "M_C_DQ<48>")
	)
	(segment
		(start 280.046684 -53.235606)
		(end 280.333704 -53.522626)
		(width 0.0889)
		(layer "In11.Cu")
		(net "M_C_DQ<48>")
	)
	(segment
		(start 280.41727 -55.6006)
		(end 280.412444 -55.609236)
		(width 0.0889)
		(layer "In11.Cu")
		(net "M_C_DQ<48>")
	)
	(segment
		(start 280.412444 -55.609236)
		(end 280.406094 -55.619904)
		(width 0.0889)
		(layer "In11.Cu")
		(net "M_C_DQ<48>")
	)
	(segment
		(start 280.246328 -47.309278)
		(end 280.246328 -47.507398)
		(width 0.0889)
		(layer "In11.Cu")
		(net "M_C_DQ<48>")
	)
	(segment
		(start 280.406094 -59.160918)
		(end 280.412444 -59.171586)
		(width 0.0889)
		(layer "In11.Cu")
		(net "M_C_DQ<48>")
	)
	(segment
		(start 300.627796 -21.634196)
		(end 300.297596 -21.964396)
		(width 0.14224)
		(layer "In11.Cu")
		(net "M_C_DQ<48>")
	)
	(segment
		(start 280.412444 -57.590436)
		(end 280.406094 -57.601104)
		(width 0.0889)
		(layer "In11.Cu")
		(net "M_C_DQ<48>")
	)
	(segment
		(start 300.625002 -9.033002)
		(end 300.625002 -12.02817)
		(width 0.14224)
		(layer "In11.Cu")
		(net "M_C_DQ<48>")
	)
	(segment
		(start 300.479968 -1.0795)
		(end 300.479968 -0.8509)
		(width 0.14224)
		(layer "In11.Cu")
		(net "M_C_DQ<48>")
	)
	(segment
		(start 300.297596 -13.502132)
		(end 300.576996 -13.781532)
		(width 0.14224)
		(layer "In11.Cu")
		(net "M_C_DQ<48>")
	)
	(segment
		(start 300.574202 -7.224776)
		(end 300.282102 -7.516876)
		(width 0.14224)
		(layer "In11.Cu")
		(net "M_C_DQ<48>")
	)
	(segment
		(start 296.429176 -31.8008)
		(end 296.225976 -32.004)
		(width 0.14224)
		(layer "In11.Cu")
		(net "M_C_DQ<48>")
	)
	(segment
		(start 295.474136 -31.496)
		(end 294.945816 -31.496)
		(width 0.14224)
		(layer "In11.Cu")
		(net "M_C_DQ<48>")
	)
	(segment
		(start 300.099984 -4.357878)
		(end 299.81525 -4.073144)
		(width 0.14224)
		(layer "In11.Cu")
		(net "M_C_DQ<48>")
	)
	(segment
		(start 300.533054 -16.8656)
		(end 300.533054 -16.867124)
		(width 0.14224)
		(layer "In11.Cu")
		(net "M_C_DQ<48>")
	)
	(segment
		(start 280.412444 -60.562236)
		(end 280.406094 -60.572904)
		(width 0.0889)
		(layer "In11.Cu")
		(net "M_C_DQ<48>")
	)
	(segment
		(start 300.479968 -0.8509)
		(end 300.137068 -0.508)
		(width 0.14224)
		(layer "In11.Cu")
		(net "M_C_DQ<48>")
	)
	(segment
		(start 300.576996 -26.663396)
		(end 300.297596 -26.942796)
		(width 0.14224)
		(layer "In11.Cu")
		(net "M_C_DQ<48>")
	)
	(segment
		(start 300.297596 -28.051252)
		(end 300.581568 -28.335224)
		(width 0.14224)
		(layer "In11.Cu")
		(net "M_C_DQ<48>")
	)
	(arc
		(start 280.412444 -60.162186)
		(mid 280.465914 -60.357249)
		(end 280.41727 -60.5536)
		(width 0.0889)
		(layer "In11.Cu")
		(net "M_C_DQ<48>")
	)
	(arc
		(start 280.406094 -56.610504)
		(mid 280.333296 -56.901267)
		(end 280.412444 -57.190386)
		(width 0.0889)
		(layer "In11.Cu")
		(net "M_C_DQ<48>")
	)
	(arc
		(start 280.406094 -60.572904)
		(mid 280.333296 -60.863667)
		(end 280.412444 -61.152786)
		(width 0.0889)
		(layer "In11.Cu")
		(net "M_C_DQ<48>")
	)
	(arc
		(start 280.412444 -58.180986)
		(mid 280.465914 -58.376049)
		(end 280.41727 -58.5724)
		(width 0.0889)
		(layer "In11.Cu")
		(net "M_C_DQ<48>")
	)
	(arc
		(start 280.412444 -58.581036)
		(mid 280.333222 -58.870154)
		(end 280.406094 -59.160918)
		(width 0.0889)
		(layer "In11.Cu")
		(net "M_C_DQ<48>")
	)
	(arc
		(start 280.412444 -59.571382)
		(mid 280.333313 -59.866784)
		(end 280.412444 -60.162186)
		(width 0.0889)
		(layer "In11.Cu")
		(net "M_C_DQ<48>")
	)
	(arc
		(start 280.412444 -55.209186)
		(mid 280.465914 -55.404249)
		(end 280.41727 -55.6006)
		(width 0.0889)
		(layer "In11.Cu")
		(net "M_C_DQ<48>")
	)
	(arc
		(start 280.406094 -54.629304)
		(mid 280.333296 -54.920067)
		(end 280.412444 -55.209186)
		(width 0.0889)
		(layer "In11.Cu")
		(net "M_C_DQ<48>")
	)
	(arc
		(start 280.406094 -61.563504)
		(mid 280.333296 -61.854267)
		(end 280.412444 -62.143386)
		(width 0.0889)
		(layer "In11.Cu")
		(net "M_C_DQ<48>")
	)
	(arc
		(start 280.412444 -54.218586)
		(mid 280.465914 -54.413649)
		(end 280.41727 -54.61)
		(width 0.0889)
		(layer "In11.Cu")
		(net "M_C_DQ<48>")
	)
	(arc
		(start 280.406094 -55.619904)
		(mid 280.333296 -55.910667)
		(end 280.412444 -56.199786)
		(width 0.0889)
		(layer "In11.Cu")
		(net "M_C_DQ<48>")
	)
	(arc
		(start 280.406094 -57.601104)
		(mid 280.333296 -57.891867)
		(end 280.412444 -58.180986)
		(width 0.0889)
		(layer "In11.Cu")
		(net "M_C_DQ<48>")
	)
	(arc
		(start 280.412444 -56.199786)
		(mid 280.465914 -56.394849)
		(end 280.41727 -56.5912)
		(width 0.0889)
		(layer "In11.Cu")
		(net "M_C_DQ<48>")
	)
	(arc
		(start 280.412444 -61.152786)
		(mid 280.465914 -61.347849)
		(end 280.41727 -61.5442)
		(width 0.0889)
		(layer "In11.Cu")
		(net "M_C_DQ<48>")
	)
	(arc
		(start 280.412444 -57.190386)
		(mid 280.465914 -57.385449)
		(end 280.41727 -57.5818)
		(width 0.0889)
		(layer "In11.Cu")
		(net "M_C_DQ<48>")
	)
	(arc
		(start 280.412444 -59.171586)
		(mid 280.465943 -59.371484)
		(end 280.412444 -59.571382)
		(width 0.0889)
		(layer "In11.Cu")
		(net "M_C_DQ<48>")
	)
	(segment
		(start 295.000426 3.778758)
		(end 294.999918 3.778758)
		(width 0.1651)
		(layer "F.Cu")
		(net "M_C_DQ<47>")
	)
	(segment
		(start 280.637234 -61.352938)
		(end 280.065734 -61.352938)
		(width 0.0889)
		(layer "F.Cu")
		(net "M_C_DQ<47>")
	)
	(segment
		(start 294.999918 3.778758)
		(end 294.999918 2.514854)
		(width 0.1651)
		(layer "F.Cu")
		(net "M_C_DQ<47>")
	)
	(via
		(at 294.999918 2.514854)
		(size 0.508)
		(drill 0.254)
		(layers "F.Cu" "B.Cu")
		(net "M_C_DQ<47>")
	)
	(via
		(at 280.065734 -61.352938)
		(size 0.508)
		(drill 0.254)
		(layers "F.Cu" "B.Cu")
		(net "M_C_DQ<47>")
	)
	(via
		(at 295.849802 -3.076956)
		(size 0.508)
		(drill 0.254)
		(layers "F.Cu" "B.Cu")
		(net "M_C_DQ<47>")
	)
	(segment
		(start 295.849802 -1.021842)
		(end 295.849802 -3.076956)
		(width 0.1651)
		(layer "B.Cu")
		(net "M_C_DQ<47>")
	)
	(segment
		(start 295.85031 -1.021842)
		(end 295.849802 -1.021842)
		(width 0.1651)
		(layer "B.Cu")
		(net "M_C_DQ<47>")
	)
	(segment
		(start 296.431208 -8.749538)
		(end 296.202608 -8.978138)
		(width 0.14224)
		(layer "In4.Cu")
		(net "M_C_DQ<47>")
	)
	(segment
		(start 296.405808 -13.516356)
		(end 296.228008 -13.694156)
		(width 0.14224)
		(layer "In4.Cu")
		(net "M_C_DQ<47>")
	)
	(segment
		(start 284.16758 -47.27702)
		(end 284.16758 -48.74768)
		(width 0.0889)
		(layer "In4.Cu")
		(net "M_C_DQ<47>")
	)
	(segment
		(start 296.405808 -21.974556)
		(end 296.405808 -23.117556)
		(width 0.14224)
		(layer "In4.Cu")
		(net "M_C_DQ<47>")
	)
	(segment
		(start 280.577544 -54.713886)
		(end 280.572718 -54.722522)
		(width 0.0889)
		(layer "In4.Cu")
		(net "M_C_DQ<47>")
	)
	(segment
		(start 295.849802 -3.076956)
		(end 295.364408 -3.56235)
		(width 0.14224)
		(layer "In4.Cu")
		(net "M_C_DQ<47>")
	)
	(segment
		(start 280.577544 -56.695086)
		(end 280.572718 -56.703722)
		(width 0.0889)
		(layer "In4.Cu")
		(net "M_C_DQ<47>")
	)
	(segment
		(start 280.583894 -55.693818)
		(end 280.577544 -55.704486)
		(width 0.0889)
		(layer "In4.Cu")
		(net "M_C_DQ<47>")
	)
	(segment
		(start 282.98902 -49.92624)
		(end 282.98902 -50.63744)
		(width 0.0889)
		(layer "In4.Cu")
		(net "M_C_DQ<47>")
	)
	(segment
		(start 280.583894 -60.646818)
		(end 280.577544 -60.657486)
		(width 0.0889)
		(layer "In4.Cu")
		(net "M_C_DQ<47>")
	)
	(segment
		(start 296.202608 -21.771356)
		(end 296.405808 -21.974556)
		(width 0.14224)
		(layer "In4.Cu")
		(net "M_C_DQ<47>")
	)
	(segment
		(start 296.202608 -12.170156)
		(end 296.405808 -12.373356)
		(width 0.14224)
		(layer "In4.Cu")
		(net "M_C_DQ<47>")
	)
	(segment
		(start 296.164 -23.359364)
		(end 296.164 -26.7716)
		(width 0.14224)
		(layer "In4.Cu")
		(net "M_C_DQ<47>")
	)
	(segment
		(start 296.405808 -12.373356)
		(end 296.405808 -13.516356)
		(width 0.14224)
		(layer "In4.Cu")
		(net "M_C_DQ<47>")
	)
	(segment
		(start 280.583894 -56.684418)
		(end 280.577544 -56.695086)
		(width 0.0889)
		(layer "In4.Cu")
		(net "M_C_DQ<47>")
	)
	(segment
		(start 296.385996 -26.993596)
		(end 296.385996 -28.136596)
		(width 0.14224)
		(layer "In4.Cu")
		(net "M_C_DQ<47>")
	)
	(segment
		(start 280.577544 -57.685686)
		(end 280.572718 -57.694322)
		(width 0.0889)
		(layer "In4.Cu")
		(net "M_C_DQ<47>")
	)
	(segment
		(start 280.577544 -59.076336)
		(end 280.583894 -59.087004)
		(width 0.0889)
		(layer "In4.Cu")
		(net "M_C_DQ<47>")
	)
	(segment
		(start 296.164 -26.7716)
		(end 296.385996 -26.993596)
		(width 0.14224)
		(layer "In4.Cu")
		(net "M_C_DQ<47>")
	)
	(segment
		(start 296.431208 -7.492746)
		(end 296.431208 -8.749538)
		(width 0.14224)
		(layer "In4.Cu")
		(net "M_C_DQ<47>")
	)
	(segment
		(start 284.350968 -43.138344)
		(end 284.350968 -47.093632)
		(width 0.14224)
		(layer "In4.Cu")
		(net "M_C_DQ<47>")
	)
	(segment
		(start 280.8986 -53.162454)
		(end 280.572718 -53.731922)
		(width 0.0889)
		(layer "In4.Cu")
		(net "M_C_DQ<47>")
	)
	(segment
		(start 296.418 -29.0322)
		(end 296.418 -31.071312)
		(width 0.14224)
		(layer "In4.Cu")
		(net "M_C_DQ<47>")
	)
	(segment
		(start 296.418 -31.071312)
		(end 284.350968 -43.138344)
		(width 0.14224)
		(layer "In4.Cu")
		(net "M_C_DQ<47>")
	)
	(segment
		(start 296.385996 -28.136596)
		(end 296.164 -28.358592)
		(width 0.14224)
		(layer "In4.Cu")
		(net "M_C_DQ<47>")
	)
	(segment
		(start 296.431208 -17.093946)
		(end 296.431208 -18.299938)
		(width 0.14224)
		(layer "In4.Cu")
		(net "M_C_DQ<47>")
	)
	(segment
		(start 296.431208 -18.299938)
		(end 296.202608 -18.528538)
		(width 0.14224)
		(layer "In4.Cu")
		(net "M_C_DQ<47>")
	)
	(segment
		(start 296.151808 -7.213346)
		(end 296.431208 -7.492746)
		(width 0.14224)
		(layer "In4.Cu")
		(net "M_C_DQ<47>")
	)
	(segment
		(start 296.164 -28.7782)
		(end 296.418 -29.0322)
		(width 0.14224)
		(layer "In4.Cu")
		(net "M_C_DQ<47>")
	)
	(segment
		(start 280.577544 -60.657486)
		(end 280.56078 -60.68695)
		(width 0.0889)
		(layer "In4.Cu")
		(net "M_C_DQ<47>")
	)
	(segment
		(start 280.8986 -52.72786)
		(end 280.8986 -53.162454)
		(width 0.0889)
		(layer "In4.Cu")
		(net "M_C_DQ<47>")
	)
	(segment
		(start 280.56078 -60.68695)
		(end 280.065734 -61.352938)
		(width 0.0889)
		(layer "In4.Cu")
		(net "M_C_DQ<47>")
	)
	(segment
		(start 296.151808 -4.773168)
		(end 296.151808 -7.213346)
		(width 0.14224)
		(layer "In4.Cu")
		(net "M_C_DQ<47>")
	)
	(segment
		(start 296.202608 -8.978138)
		(end 296.202608 -12.170156)
		(width 0.14224)
		(layer "In4.Cu")
		(net "M_C_DQ<47>")
	)
	(segment
		(start 296.228008 -13.694156)
		(end 296.228008 -16.890746)
		(width 0.14224)
		(layer "In4.Cu")
		(net "M_C_DQ<47>")
	)
	(segment
		(start 280.583894 -57.675018)
		(end 280.577544 -57.685686)
		(width 0.0889)
		(layer "In4.Cu")
		(net "M_C_DQ<47>")
	)
	(segment
		(start 296.202608 -18.528538)
		(end 296.202608 -21.771356)
		(width 0.14224)
		(layer "In4.Cu")
		(net "M_C_DQ<47>")
	)
	(segment
		(start 295.364408 -3.985768)
		(end 296.151808 -4.773168)
		(width 0.14224)
		(layer "In4.Cu")
		(net "M_C_DQ<47>")
	)
	(segment
		(start 295.364408 -3.56235)
		(end 295.364408 -3.985768)
		(width 0.14224)
		(layer "In4.Cu")
		(net "M_C_DQ<47>")
	)
	(segment
		(start 280.577544 -55.704486)
		(end 280.572718 -55.713122)
		(width 0.0889)
		(layer "In4.Cu")
		(net "M_C_DQ<47>")
	)
	(segment
		(start 284.350968 -47.093632)
		(end 284.16758 -47.27702)
		(width 0.0889)
		(layer "In4.Cu")
		(net "M_C_DQ<47>")
	)
	(segment
		(start 282.98902 -50.63744)
		(end 280.8986 -52.72786)
		(width 0.0889)
		(layer "In4.Cu")
		(net "M_C_DQ<47>")
	)
	(segment
		(start 280.583894 -54.703218)
		(end 280.577544 -54.713886)
		(width 0.0889)
		(layer "In4.Cu")
		(net "M_C_DQ<47>")
	)
	(segment
		(start 296.405808 -23.117556)
		(end 296.164 -23.359364)
		(width 0.14224)
		(layer "In4.Cu")
		(net "M_C_DQ<47>")
	)
	(segment
		(start 296.228008 -16.890746)
		(end 296.431208 -17.093946)
		(width 0.14224)
		(layer "In4.Cu")
		(net "M_C_DQ<47>")
	)
	(segment
		(start 280.577544 -59.666886)
		(end 280.572718 -59.675522)
		(width 0.0889)
		(layer "In4.Cu")
		(net "M_C_DQ<47>")
	)
	(segment
		(start 284.16758 -48.74768)
		(end 282.98902 -49.92624)
		(width 0.0889)
		(layer "In4.Cu")
		(net "M_C_DQ<47>")
	)
	(segment
		(start 296.164 -28.358592)
		(end 296.164 -28.7782)
		(width 0.14224)
		(layer "In4.Cu")
		(net "M_C_DQ<47>")
	)
	(arc
		(start 280.577544 -54.123336)
		(mid 280.656766 -54.412454)
		(end 280.583894 -54.703218)
		(width 0.0889)
		(layer "In4.Cu")
		(net "M_C_DQ<47>")
	)
	(arc
		(start 280.577544 -56.104536)
		(mid 280.656766 -56.393654)
		(end 280.583894 -56.684418)
		(width 0.0889)
		(layer "In4.Cu")
		(net "M_C_DQ<47>")
	)
	(arc
		(start 280.577544 -55.113936)
		(mid 280.656766 -55.403054)
		(end 280.583894 -55.693818)
		(width 0.0889)
		(layer "In4.Cu")
		(net "M_C_DQ<47>")
	)
	(arc
		(start 280.572718 -56.703722)
		(mid 280.523963 -56.900074)
		(end 280.577544 -57.095136)
		(width 0.0889)
		(layer "In4.Cu")
		(net "M_C_DQ<47>")
	)
	(arc
		(start 280.577544 -57.095136)
		(mid 280.656766 -57.384254)
		(end 280.583894 -57.675018)
		(width 0.0889)
		(layer "In4.Cu")
		(net "M_C_DQ<47>")
	)
	(arc
		(start 280.572718 -54.722522)
		(mid 280.523963 -54.918874)
		(end 280.577544 -55.113936)
		(width 0.0889)
		(layer "In4.Cu")
		(net "M_C_DQ<47>")
	)
	(arc
		(start 280.572718 -57.694322)
		(mid 280.523963 -57.890674)
		(end 280.577544 -58.085736)
		(width 0.0889)
		(layer "In4.Cu")
		(net "M_C_DQ<47>")
	)
	(arc
		(start 280.577544 -58.085736)
		(mid 280.656675 -58.381138)
		(end 280.577544 -58.67654)
		(width 0.0889)
		(layer "In4.Cu")
		(net "M_C_DQ<47>")
	)
	(arc
		(start 280.577544 -60.066936)
		(mid 280.656766 -60.356054)
		(end 280.583894 -60.646818)
		(width 0.0889)
		(layer "In4.Cu")
		(net "M_C_DQ<47>")
	)
	(arc
		(start 280.577544 -58.67654)
		(mid 280.524045 -58.876438)
		(end 280.577544 -59.076336)
		(width 0.0889)
		(layer "In4.Cu")
		(net "M_C_DQ<47>")
	)
	(arc
		(start 280.583894 -59.087004)
		(mid 280.656692 -59.377767)
		(end 280.577544 -59.666886)
		(width 0.0889)
		(layer "In4.Cu")
		(net "M_C_DQ<47>")
	)
	(arc
		(start 280.572718 -53.731922)
		(mid 280.523963 -53.928274)
		(end 280.577544 -54.123336)
		(width 0.0889)
		(layer "In4.Cu")
		(net "M_C_DQ<47>")
	)
	(arc
		(start 280.572718 -59.675522)
		(mid 280.523963 -59.871874)
		(end 280.577544 -60.066936)
		(width 0.0889)
		(layer "In4.Cu")
		(net "M_C_DQ<47>")
	)
	(arc
		(start 280.572718 -55.713122)
		(mid 280.523963 -55.909474)
		(end 280.577544 -56.104536)
		(width 0.0889)
		(layer "In4.Cu")
		(net "M_C_DQ<47>")
	)
	(segment
		(start 296.358056 0.7366)
		(end 296.358056 1.0922)
		(width 0.14224)
		(layer "In11.Cu")
		(net "M_C_DQ<47>")
	)
	(segment
		(start 296.202608 0.581152)
		(end 296.358056 0.7366)
		(width 0.14224)
		(layer "In11.Cu")
		(net "M_C_DQ<47>")
	)
	(segment
		(start 296.202608 -2.72415)
		(end 296.202608 0.581152)
		(width 0.14224)
		(layer "In11.Cu")
		(net "M_C_DQ<47>")
	)
	(segment
		(start 295.646856 1.5494)
		(end 295.316656 1.8796)
		(width 0.14224)
		(layer "In11.Cu")
		(net "M_C_DQ<47>")
	)
	(segment
		(start 295.316656 2.198116)
		(end 294.999918 2.514854)
		(width 0.14224)
		(layer "In11.Cu")
		(net "M_C_DQ<47>")
	)
	(segment
		(start 295.849802 -3.076956)
		(end 296.202608 -2.72415)
		(width 0.14224)
		(layer "In11.Cu")
		(net "M_C_DQ<47>")
	)
	(segment
		(start 295.316656 1.8796)
		(end 295.316656 2.198116)
		(width 0.14224)
		(layer "In11.Cu")
		(net "M_C_DQ<47>")
	)
	(segment
		(start 295.900856 1.5494)
		(end 295.646856 1.5494)
		(width 0.14224)
		(layer "In11.Cu")
		(net "M_C_DQ<47>")
	)
	(segment
		(start 296.358056 1.0922)
		(end 295.900856 1.5494)
		(width 0.14224)
		(layer "In11.Cu")
		(net "M_C_DQ<47>")
	)
	(segment
		(start 295.850056 0.635)
		(end 295.982136 0.50292)
		(width 0.1651)
		(layer "F.Cu")
		(net "M_C_DQ<46>")
	)
	(segment
		(start 295.982136 0.50292)
		(end 295.982136 0.28448)
		(width 0.1651)
		(layer "F.Cu")
		(net "M_C_DQ<46>")
	)
	(segment
		(start 295.850056 -0.820928)
		(end 295.85031 -0.821182)
		(width 0.1651)
		(layer "F.Cu")
		(net "M_C_DQ<46>")
	)
	(segment
		(start 295.849802 0.9398)
		(end 295.850056 0.939546)
		(width 0.1651)
		(layer "F.Cu")
		(net "M_C_DQ<46>")
	)
	(segment
		(start 295.850056 0.939546)
		(end 295.850056 0.635)
		(width 0.1651)
		(layer "F.Cu")
		(net "M_C_DQ<46>")
	)
	(segment
		(start 280.637234 -59.371484)
		(end 280.065734 -59.371484)
		(width 0.0889)
		(layer "F.Cu")
		(net "M_C_DQ<46>")
	)
	(segment
		(start 295.850056 0.1524)
		(end 295.850056 -0.820928)
		(width 0.1651)
		(layer "F.Cu")
		(net "M_C_DQ<46>")
	)
	(segment
		(start 295.982136 0.28448)
		(end 295.850056 0.1524)
		(width 0.1651)
		(layer "F.Cu")
		(net "M_C_DQ<46>")
	)
	(via
		(at 280.065734 -59.371484)
		(size 0.508)
		(drill 0.254)
		(layers "F.Cu" "B.Cu")
		(net "M_C_DQ<46>")
	)
	(via
		(at 294.999918 -4.357878)
		(size 0.508)
		(drill 0.254)
		(layers "F.Cu" "B.Cu")
		(net "M_C_DQ<46>")
	)
	(via
		(at 295.849802 0.9398)
		(size 0.508)
		(drill 0.254)
		(layers "F.Cu" "B.Cu")
		(net "M_C_DQ<46>")
	)
	(segment
		(start 295.000426 -5.621782)
		(end 294.999918 -5.621782)
		(width 0.1651)
		(layer "B.Cu")
		(net "M_C_DQ<46>")
	)
	(segment
		(start 294.999918 -5.621782)
		(end 294.999918 -4.357878)
		(width 0.1651)
		(layer "B.Cu")
		(net "M_C_DQ<46>")
	)
	(segment
		(start 283.715968 -42.8752)
		(end 283.715968 -47.038768)
		(width 0.14224)
		(layer "In4.Cu")
		(net "M_C_DQ<46>")
	)
	(segment
		(start 295.005252 -29.251148)
		(end 295.005252 -29.516324)
		(width 0.14224)
		(layer "In4.Cu")
		(net "M_C_DQ<46>")
	)
	(segment
		(start 280.412444 -57.590436)
		(end 280.406094 -57.601104)
		(width 0.0889)
		(layer "In4.Cu")
		(net "M_C_DQ<46>")
	)
	(segment
		(start 295.364408 -23.168356)
		(end 295.529 -23.332948)
		(width 0.14224)
		(layer "In4.Cu")
		(net "M_C_DQ<46>")
	)
	(segment
		(start 295.567608 -12.170156)
		(end 295.364408 -12.373356)
		(width 0.14224)
		(layer "In4.Cu")
		(net "M_C_DQ<46>")
	)
	(segment
		(start 295.2496 -20.049744)
		(end 295.2496 -20.544536)
		(width 0.14224)
		(layer "In4.Cu")
		(net "M_C_DQ<46>")
	)
	(segment
		(start 295.466008 -13.668756)
		(end 295.466008 -14.997938)
		(width 0.14224)
		(layer "In4.Cu")
		(net "M_C_DQ<46>")
	)
	(segment
		(start 295.567608 -10.520934)
		(end 295.2242 -10.864342)
		(width 0.14224)
		(layer "In4.Cu")
		(net "M_C_DQ<46>")
	)
	(segment
		(start 295.2496 -20.544536)
		(end 295.567608 -20.862544)
		(width 0.14224)
		(layer "In4.Cu")
		(net "M_C_DQ<46>")
	)
	(segment
		(start 295.516808 -7.238746)
		(end 295.364408 -7.391146)
		(width 0.14224)
		(layer "In4.Cu")
		(net "M_C_DQ<46>")
	)
	(segment
		(start 295.364408 -8.826754)
		(end 295.567608 -9.029954)
		(width 0.14224)
		(layer "In4.Cu")
		(net "M_C_DQ<46>")
	)
	(segment
		(start 295.192704 -29.703776)
		(end 295.79316 -29.703776)
		(width 0.14224)
		(layer "In4.Cu")
		(net "M_C_DQ<46>")
	)
	(segment
		(start 295.364408 -12.373356)
		(end 295.364408 -13.567156)
		(width 0.14224)
		(layer "In4.Cu")
		(net "M_C_DQ<46>")
	)
	(segment
		(start 295.1734 -30.516576)
		(end 294.9702 -30.719776)
		(width 0.14224)
		(layer "In4.Cu")
		(net "M_C_DQ<46>")
	)
	(segment
		(start 280.412444 -56.599836)
		(end 280.406094 -56.610504)
		(width 0.0889)
		(layer "In4.Cu")
		(net "M_C_DQ<46>")
	)
	(segment
		(start 295.364408 -21.974556)
		(end 295.364408 -23.168356)
		(width 0.14224)
		(layer "In4.Cu")
		(net "M_C_DQ<46>")
	)
	(segment
		(start 295.466008 -16.103346)
		(end 295.466008 -16.890746)
		(width 0.14224)
		(layer "In4.Cu")
		(net "M_C_DQ<46>")
	)
	(segment
		(start 295.364408 -18.402554)
		(end 295.567608 -18.605754)
		(width 0.14224)
		(layer "In4.Cu")
		(net "M_C_DQ<46>")
	)
	(segment
		(start 295.529 -26.67)
		(end 295.2496 -26.9494)
		(width 0.14224)
		(layer "In4.Cu")
		(net "M_C_DQ<46>")
	)
	(segment
		(start 295.79316 -29.703776)
		(end 295.9354 -29.846016)
		(width 0.14224)
		(layer "In4.Cu")
		(net "M_C_DQ<46>")
	)
	(segment
		(start 280.41727 -58.5724)
		(end 280.395934 -58.609484)
		(width 0.0889)
		(layer "In4.Cu")
		(net "M_C_DQ<46>")
	)
	(segment
		(start 295.529 -23.332948)
		(end 295.529 -26.67)
		(width 0.14224)
		(layer "In4.Cu")
		(net "M_C_DQ<46>")
	)
	(segment
		(start 280.41727 -54.61)
		(end 280.412444 -54.618636)
		(width 0.0889)
		(layer "In4.Cu")
		(net "M_C_DQ<46>")
	)
	(segment
		(start 282.78074 -50.527966)
		(end 280.687526 -52.62118)
		(width 0.0889)
		(layer "In4.Cu")
		(net "M_C_DQ<46>")
	)
	(segment
		(start 280.41727 -55.6006)
		(end 280.412444 -55.609236)
		(width 0.0889)
		(layer "In4.Cu")
		(net "M_C_DQ<46>")
	)
	(segment
		(start 295.2496 -28.0162)
		(end 295.529 -28.2956)
		(width 0.14224)
		(layer "In4.Cu")
		(net "M_C_DQ<46>")
	)
	(segment
		(start 295.466008 -14.997938)
		(end 295.1734 -15.290546)
		(width 0.14224)
		(layer "In4.Cu")
		(net "M_C_DQ<46>")
	)
	(segment
		(start 294.999918 -4.357878)
		(end 294.999918 -4.576318)
		(width 0.14224)
		(layer "In4.Cu")
		(net "M_C_DQ<46>")
	)
	(segment
		(start 294.9702 -31.0134)
		(end 295.1734 -31.2166)
		(width 0.14224)
		(layer "In4.Cu")
		(net "M_C_DQ<46>")
	)
	(segment
		(start 295.1734 -15.810738)
		(end 295.466008 -16.103346)
		(width 0.14224)
		(layer "In4.Cu")
		(net "M_C_DQ<46>")
	)
	(segment
		(start 295.567608 -11.677142)
		(end 295.567608 -12.170156)
		(width 0.14224)
		(layer "In4.Cu")
		(net "M_C_DQ<46>")
	)
	(segment
		(start 280.41727 -56.5912)
		(end 280.412444 -56.599836)
		(width 0.0889)
		(layer "In4.Cu")
		(net "M_C_DQ<46>")
	)
	(segment
		(start 295.516808 -5.093208)
		(end 295.516808 -7.238746)
		(width 0.14224)
		(layer "In4.Cu")
		(net "M_C_DQ<46>")
	)
	(segment
		(start 295.79316 -30.516576)
		(end 295.1734 -30.516576)
		(width 0.14224)
		(layer "In4.Cu")
		(net "M_C_DQ<46>")
	)
	(segment
		(start 295.364408 -16.992346)
		(end 295.364408 -18.402554)
		(width 0.14224)
		(layer "In4.Cu")
		(net "M_C_DQ<46>")
	)
	(segment
		(start 283.715968 -47.038768)
		(end 283.97708 -47.29988)
		(width 0.0889)
		(layer "In4.Cu")
		(net "M_C_DQ<46>")
	)
	(segment
		(start 295.9354 -29.846016)
		(end 295.9354 -30.374336)
		(width 0.14224)
		(layer "In4.Cu")
		(net "M_C_DQ<46>")
	)
	(segment
		(start 295.567608 -19.731736)
		(end 295.2496 -20.049744)
		(width 0.14224)
		(layer "In4.Cu")
		(net "M_C_DQ<46>")
	)
	(segment
		(start 295.364408 -7.391146)
		(end 295.364408 -8.826754)
		(width 0.14224)
		(layer "In4.Cu")
		(net "M_C_DQ<46>")
	)
	(segment
		(start 283.97708 -48.668432)
		(end 282.78074 -49.864772)
		(width 0.0889)
		(layer "In4.Cu")
		(net "M_C_DQ<46>")
	)
	(segment
		(start 295.567608 -9.029954)
		(end 295.567608 -10.520934)
		(width 0.14224)
		(layer "In4.Cu")
		(net "M_C_DQ<46>")
	)
	(segment
		(start 295.9354 -30.374336)
		(end 295.79316 -30.516576)
		(width 0.14224)
		(layer "In4.Cu")
		(net "M_C_DQ<46>")
	)
	(segment
		(start 280.687526 -52.62118)
		(end 280.687526 -53.125624)
		(width 0.0889)
		(layer "In4.Cu")
		(net "M_C_DQ<46>")
	)
	(segment
		(start 295.2242 -10.864342)
		(end 295.2242 -11.333734)
		(width 0.14224)
		(layer "In4.Cu")
		(net "M_C_DQ<46>")
	)
	(segment
		(start 295.364408 -13.567156)
		(end 295.466008 -13.668756)
		(width 0.14224)
		(layer "In4.Cu")
		(net "M_C_DQ<46>")
	)
	(segment
		(start 295.1734 -31.2166)
		(end 295.1734 -31.417768)
		(width 0.14224)
		(layer "In4.Cu")
		(net "M_C_DQ<46>")
	)
	(segment
		(start 295.529 -28.2956)
		(end 295.529 -28.7274)
		(width 0.14224)
		(layer "In4.Cu")
		(net "M_C_DQ<46>")
	)
	(segment
		(start 294.999918 -4.576318)
		(end 295.516808 -5.093208)
		(width 0.14224)
		(layer "In4.Cu")
		(net "M_C_DQ<46>")
	)
	(segment
		(start 280.412444 -54.618636)
		(end 280.406094 -54.629304)
		(width 0.0889)
		(layer "In4.Cu")
		(net "M_C_DQ<46>")
	)
	(segment
		(start 282.78074 -49.864772)
		(end 282.78074 -50.527966)
		(width 0.0889)
		(layer "In4.Cu")
		(net "M_C_DQ<46>")
	)
	(segment
		(start 295.1734 -15.290546)
		(end 295.1734 -15.810738)
		(width 0.14224)
		(layer "In4.Cu")
		(net "M_C_DQ<46>")
	)
	(segment
		(start 280.687526 -53.125624)
		(end 280.406094 -53.638704)
		(width 0.0889)
		(layer "In4.Cu")
		(net "M_C_DQ<46>")
	)
	(segment
		(start 295.1734 -31.417768)
		(end 283.715968 -42.8752)
		(width 0.14224)
		(layer "In4.Cu")
		(net "M_C_DQ<46>")
	)
	(segment
		(start 295.005252 -29.516324)
		(end 295.192704 -29.703776)
		(width 0.14224)
		(layer "In4.Cu")
		(net "M_C_DQ<46>")
	)
	(segment
		(start 295.567608 -20.862544)
		(end 295.567608 -21.771356)
		(width 0.14224)
		(layer "In4.Cu")
		(net "M_C_DQ<46>")
	)
	(segment
		(start 280.412444 -55.609236)
		(end 280.406094 -55.619904)
		(width 0.0889)
		(layer "In4.Cu")
		(net "M_C_DQ<46>")
	)
	(segment
		(start 280.41727 -57.5818)
		(end 280.412444 -57.590436)
		(width 0.0889)
		(layer "In4.Cu")
		(net "M_C_DQ<46>")
	)
	(segment
		(start 295.2242 -11.333734)
		(end 295.567608 -11.677142)
		(width 0.14224)
		(layer "In4.Cu")
		(net "M_C_DQ<46>")
	)
	(segment
		(start 280.395934 -58.609484)
		(end 280.065734 -59.371484)
		(width 0.0889)
		(layer "In4.Cu")
		(net "M_C_DQ<46>")
	)
	(segment
		(start 295.567608 -18.605754)
		(end 295.567608 -19.731736)
		(width 0.14224)
		(layer "In4.Cu")
		(net "M_C_DQ<46>")
	)
	(segment
		(start 283.97708 -47.29988)
		(end 283.97708 -48.668432)
		(width 0.0889)
		(layer "In4.Cu")
		(net "M_C_DQ<46>")
	)
	(segment
		(start 295.466008 -16.890746)
		(end 295.364408 -16.992346)
		(width 0.14224)
		(layer "In4.Cu")
		(net "M_C_DQ<46>")
	)
	(segment
		(start 295.2496 -26.9494)
		(end 295.2496 -28.0162)
		(width 0.14224)
		(layer "In4.Cu")
		(net "M_C_DQ<46>")
	)
	(segment
		(start 295.529 -28.7274)
		(end 295.005252 -29.251148)
		(width 0.14224)
		(layer "In4.Cu")
		(net "M_C_DQ<46>")
	)
	(segment
		(start 294.9702 -30.719776)
		(end 294.9702 -31.0134)
		(width 0.14224)
		(layer "In4.Cu")
		(net "M_C_DQ<46>")
	)
	(segment
		(start 295.567608 -21.771356)
		(end 295.364408 -21.974556)
		(width 0.14224)
		(layer "In4.Cu")
		(net "M_C_DQ<46>")
	)
	(arc
		(start 280.406094 -55.619904)
		(mid 280.333296 -55.910667)
		(end 280.412444 -56.199786)
		(width 0.0889)
		(layer "In4.Cu")
		(net "M_C_DQ<46>")
	)
	(arc
		(start 280.406094 -53.638704)
		(mid 280.333296 -53.929467)
		(end 280.412444 -54.218586)
		(width 0.0889)
		(layer "In4.Cu")
		(net "M_C_DQ<46>")
	)
	(arc
		(start 280.412444 -54.218586)
		(mid 280.465914 -54.413649)
		(end 280.41727 -54.61)
		(width 0.0889)
		(layer "In4.Cu")
		(net "M_C_DQ<46>")
	)
	(arc
		(start 280.406094 -57.601104)
		(mid 280.333296 -57.891867)
		(end 280.412444 -58.180986)
		(width 0.0889)
		(layer "In4.Cu")
		(net "M_C_DQ<46>")
	)
	(arc
		(start 280.412444 -56.199786)
		(mid 280.465914 -56.394849)
		(end 280.41727 -56.5912)
		(width 0.0889)
		(layer "In4.Cu")
		(net "M_C_DQ<46>")
	)
	(arc
		(start 280.406094 -56.610504)
		(mid 280.333296 -56.901267)
		(end 280.412444 -57.190386)
		(width 0.0889)
		(layer "In4.Cu")
		(net "M_C_DQ<46>")
	)
	(arc
		(start 280.406094 -54.629304)
		(mid 280.333296 -54.920067)
		(end 280.412444 -55.209186)
		(width 0.0889)
		(layer "In4.Cu")
		(net "M_C_DQ<46>")
	)
	(arc
		(start 280.412444 -55.209186)
		(mid 280.465914 -55.404249)
		(end 280.41727 -55.6006)
		(width 0.0889)
		(layer "In4.Cu")
		(net "M_C_DQ<46>")
	)
	(arc
		(start 280.412444 -57.190386)
		(mid 280.465914 -57.385449)
		(end 280.41727 -57.5818)
		(width 0.0889)
		(layer "In4.Cu")
		(net "M_C_DQ<46>")
	)
	(arc
		(start 280.412444 -58.180986)
		(mid 280.465914 -58.376049)
		(end 280.41727 -58.5724)
		(width 0.0889)
		(layer "In4.Cu")
		(net "M_C_DQ<46>")
	)
	(segment
		(start 295.111424 -0.387096)
		(end 295.111424 -0.076454)
		(width 0.14224)
		(layer "In11.Cu")
		(net "M_C_DQ<46>")
	)
	(segment
		(start 295.111424 -1.492504)
		(end 295.492424 -1.111504)
		(width 0.14224)
		(layer "In11.Cu")
		(net "M_C_DQ<46>")
	)
	(segment
		(start 294.764206 -3.327654)
		(end 295.536874 -2.554986)
		(width 0.14224)
		(layer "In11.Cu")
		(net "M_C_DQ<46>")
	)
	(segment
		(start 294.999918 -4.357878)
		(end 294.764206 -4.122166)
		(width 0.14224)
		(layer "In11.Cu")
		(net "M_C_DQ<46>")
	)
	(segment
		(start 295.492424 -1.111504)
		(end 295.492424 -0.768096)
		(width 0.14224)
		(layer "In11.Cu")
		(net "M_C_DQ<46>")
	)
	(segment
		(start 295.536874 -2.554986)
		(end 295.536874 -2.203196)
		(width 0.14224)
		(layer "In11.Cu")
		(net "M_C_DQ<46>")
	)
	(segment
		(start 295.111424 -1.777746)
		(end 295.111424 -1.492504)
		(width 0.14224)
		(layer "In11.Cu")
		(net "M_C_DQ<46>")
	)
	(segment
		(start 295.111424 -0.076454)
		(end 295.475406 0.287528)
		(width 0.14224)
		(layer "In11.Cu")
		(net "M_C_DQ<46>")
	)
	(segment
		(start 295.475406 0.565404)
		(end 295.849802 0.9398)
		(width 0.14224)
		(layer "In11.Cu")
		(net "M_C_DQ<46>")
	)
	(segment
		(start 294.764206 -4.122166)
		(end 294.764206 -3.327654)
		(width 0.14224)
		(layer "In11.Cu")
		(net "M_C_DQ<46>")
	)
	(segment
		(start 295.536874 -2.203196)
		(end 295.111424 -1.777746)
		(width 0.14224)
		(layer "In11.Cu")
		(net "M_C_DQ<46>")
	)
	(segment
		(start 295.492424 -0.768096)
		(end 295.111424 -0.387096)
		(width 0.14224)
		(layer "In11.Cu")
		(net "M_C_DQ<46>")
	)
	(segment
		(start 295.475406 0.287528)
		(end 295.475406 0.565404)
		(width 0.14224)
		(layer "In11.Cu")
		(net "M_C_DQ<46>")
	)
	(segment
		(start 278.061674 -60.857384)
		(end 277.490174 -60.857384)
		(width 0.0889)
		(layer "F.Cu")
		(net "M_C_DQ<45>")
	)
	(segment
		(start 289.050476 3.778758)
		(end 289.049968 3.778758)
		(width 0.1651)
		(layer "F.Cu")
		(net "M_C_DQ<45>")
	)
	(segment
		(start 289.049968 3.778758)
		(end 289.049968 2.514854)
		(width 0.1651)
		(layer "F.Cu")
		(net "M_C_DQ<45>")
	)
	(via
		(at 277.490174 -60.857384)
		(size 0.508)
		(drill 0.254)
		(layers "F.Cu" "B.Cu")
		(net "M_C_DQ<45>")
	)
	(via
		(at 289.823652 -3.076956)
		(size 0.508)
		(drill 0.254)
		(layers "F.Cu" "B.Cu")
		(net "M_C_DQ<45>")
	)
	(via
		(at 289.049968 2.514854)
		(size 0.508)
		(drill 0.254)
		(layers "F.Cu" "B.Cu")
		(net "M_C_DQ<45>")
	)
	(segment
		(start 289.899852 -1.021842)
		(end 289.899852 -3.000756)
		(width 0.1651)
		(layer "B.Cu")
		(net "M_C_DQ<45>")
	)
	(segment
		(start 289.899852 -3.000756)
		(end 289.823652 -3.076956)
		(width 0.1651)
		(layer "B.Cu")
		(net "M_C_DQ<45>")
	)
	(segment
		(start 289.90036 -1.021842)
		(end 289.899852 -1.021842)
		(width 0.1651)
		(layer "B.Cu")
		(net "M_C_DQ<45>")
	)
	(segment
		(start 289.823652 -3.076956)
		(end 289.319208 -3.5814)
		(width 0.14224)
		(layer "In4.Cu")
		(net "M_C_DQ<45>")
	)
	(segment
		(start 277.143464 -54.123336)
		(end 277.149814 -54.134004)
		(width 0.0889)
		(layer "In4.Cu")
		(net "M_C_DQ<45>")
	)
	(segment
		(start 279.8572 -41.288208)
		(end 279.8572 -46.736)
		(width 0.14224)
		(layer "In4.Cu")
		(net "M_C_DQ<45>")
	)
	(segment
		(start 277.0124 -52.070254)
		(end 277.0124 -52.898802)
		(width 0.0889)
		(layer "In4.Cu")
		(net "M_C_DQ<45>")
	)
	(segment
		(start 283.04871 -37.065458)
		(end 283.420566 -37.437314)
		(width 0.14224)
		(layer "In4.Cu")
		(net "M_C_DQ<45>")
	)
	(segment
		(start 283.422344 -36.490656)
		(end 283.04871 -36.86429)
		(width 0.14224)
		(layer "In4.Cu")
		(net "M_C_DQ<45>")
	)
	(segment
		(start 290.208208 -8.991346)
		(end 290.208208 -12.271756)
		(width 0.14224)
		(layer "In4.Cu")
		(net "M_C_DQ<45>")
	)
	(segment
		(start 290.280852 -21.9456)
		(end 290.280852 -23.235412)
		(width 0.14224)
		(layer "In4.Cu")
		(net "M_C_DQ<45>")
	)
	(segment
		(start 289.319208 -3.5814)
		(end 289.319208 -3.940556)
		(width 0.14224)
		(layer "In4.Cu")
		(net "M_C_DQ<45>")
	)
	(segment
		(start 279.8572 -46.736)
		(end 279.680416 -46.912784)
		(width 0.0889)
		(layer "In4.Cu")
		(net "M_C_DQ<45>")
	)
	(segment
		(start 290.25469 -26.914094)
		(end 290.2966 -26.956004)
		(width 0.14224)
		(layer "In4.Cu")
		(net "M_C_DQ<45>")
	)
	(segment
		(start 290.297108 -16.928846)
		(end 290.297108 -18.503646)
		(width 0.14224)
		(layer "In4.Cu")
		(net "M_C_DQ<45>")
	)
	(segment
		(start 290.208208 -18.592546)
		(end 290.208208 -21.872956)
		(width 0.14224)
		(layer "In4.Cu")
		(net "M_C_DQ<45>")
	)
	(segment
		(start 283.04871 -36.86429)
		(end 283.04871 -37.065458)
		(width 0.14224)
		(layer "In4.Cu")
		(net "M_C_DQ<45>")
	)
	(segment
		(start 290.280852 -23.235412)
		(end 290.25469 -23.261574)
		(width 0.14224)
		(layer "In4.Cu")
		(net "M_C_DQ<45>")
	)
	(segment
		(start 277.01367 -52.900072)
		(end 277.149814 -53.143404)
		(width 0.0889)
		(layer "In4.Cu")
		(net "M_C_DQ<45>")
	)
	(segment
		(start 290.2966 -28.194)
		(end 290.2204 -28.2702)
		(width 0.14224)
		(layer "In4.Cu")
		(net "M_C_DQ<45>")
	)
	(segment
		(start 283.995368 -36.862512)
		(end 283.623512 -36.490656)
		(width 0.14224)
		(layer "In4.Cu")
		(net "M_C_DQ<45>")
	)
	(segment
		(start 290.2204 -28.965144)
		(end 283.972 -35.213544)
		(width 0.14224)
		(layer "In4.Cu")
		(net "M_C_DQ<45>")
	)
	(segment
		(start 290.2966 -26.956004)
		(end 290.2966 -28.194)
		(width 0.14224)
		(layer "In4.Cu")
		(net "M_C_DQ<45>")
	)
	(segment
		(start 290.233608 -16.865346)
		(end 290.297108 -16.928846)
		(width 0.14224)
		(layer "In4.Cu")
		(net "M_C_DQ<45>")
	)
	(segment
		(start 284.282896 -36.862512)
		(end 283.995368 -36.862512)
		(width 0.14224)
		(layer "In4.Cu")
		(net "M_C_DQ<45>")
	)
	(segment
		(start 290.297108 -7.327646)
		(end 290.297108 -8.902446)
		(width 0.14224)
		(layer "In4.Cu")
		(net "M_C_DQ<45>")
	)
	(segment
		(start 277.0124 -52.898802)
		(end 277.01367 -52.900072)
		(width 0.0889)
		(layer "In4.Cu")
		(net "M_C_DQ<45>")
	)
	(segment
		(start 290.233608 -13.681456)
		(end 290.233608 -16.865346)
		(width 0.14224)
		(layer "In4.Cu")
		(net "M_C_DQ<45>")
	)
	(segment
		(start 277.836884 -60.066936)
		(end 277.82012 -60.095638)
		(width 0.0889)
		(layer "In4.Cu")
		(net "M_C_DQ<45>")
	)
	(segment
		(start 284.589728 -36.212272)
		(end 284.589728 -36.55568)
		(width 0.14224)
		(layer "In4.Cu")
		(net "M_C_DQ<45>")
	)
	(segment
		(start 290.2204 -28.2702)
		(end 290.2204 -28.965144)
		(width 0.14224)
		(layer "In4.Cu")
		(net "M_C_DQ<45>")
	)
	(segment
		(start 277.746968 -59.498484)
		(end 277.76424 -59.515756)
		(width 0.0889)
		(layer "In4.Cu")
		(net "M_C_DQ<45>")
	)
	(segment
		(start 277.155148 -59.096656)
		(end 277.29815 -59.28868)
		(width 0.0889)
		(layer "In4.Cu")
		(net "M_C_DQ<45>")
	)
	(segment
		(start 289.7632 -4.384548)
		(end 289.7632 -6.189472)
		(width 0.14224)
		(layer "In4.Cu")
		(net "M_C_DQ<45>")
	)
	(segment
		(start 283.420566 -37.724842)
		(end 279.8572 -41.288208)
		(width 0.14224)
		(layer "In4.Cu")
		(net "M_C_DQ<45>")
	)
	(segment
		(start 290.25469 -23.261574)
		(end 290.25469 -26.914094)
		(width 0.14224)
		(layer "In4.Cu")
		(net "M_C_DQ<45>")
	)
	(segment
		(start 283.623512 -36.490656)
		(end 283.422344 -36.490656)
		(width 0.14224)
		(layer "In4.Cu")
		(net "M_C_DQ<45>")
	)
	(segment
		(start 277.143464 -54.713886)
		(end 277.138638 -54.722522)
		(width 0.0889)
		(layer "In4.Cu")
		(net "M_C_DQ<45>")
	)
	(segment
		(start 290.297108 -18.503646)
		(end 290.208208 -18.592546)
		(width 0.14224)
		(layer "In4.Cu")
		(net "M_C_DQ<45>")
	)
	(segment
		(start 290.208208 -21.872956)
		(end 290.280852 -21.9456)
		(width 0.14224)
		(layer "In4.Cu")
		(net "M_C_DQ<45>")
	)
	(segment
		(start 290.29279 -6.719062)
		(end 290.29279 -7.323328)
		(width 0.14224)
		(layer "In4.Cu")
		(net "M_C_DQ<45>")
	)
	(segment
		(start 289.7632 -6.189472)
		(end 290.29279 -6.719062)
		(width 0.14224)
		(layer "In4.Cu")
		(net "M_C_DQ<45>")
	)
	(segment
		(start 279.680416 -48.383952)
		(end 278.6888 -49.375568)
		(width 0.0889)
		(layer "In4.Cu")
		(net "M_C_DQ<45>")
	)
	(segment
		(start 277.138638 -54.1147)
		(end 277.143464 -54.123336)
		(width 0.0889)
		(layer "In4.Cu")
		(net "M_C_DQ<45>")
	)
	(segment
		(start 290.297108 -8.902446)
		(end 290.208208 -8.991346)
		(width 0.14224)
		(layer "In4.Cu")
		(net "M_C_DQ<45>")
	)
	(segment
		(start 277.143464 -57.685686)
		(end 277.138638 -57.694322)
		(width 0.0889)
		(layer "In4.Cu")
		(net "M_C_DQ<45>")
	)
	(segment
		(start 278.6888 -49.375568)
		(end 278.6888 -50.393854)
		(width 0.0889)
		(layer "In4.Cu")
		(net "M_C_DQ<45>")
	)
	(segment
		(start 279.680416 -46.912784)
		(end 279.680416 -48.383952)
		(width 0.0889)
		(layer "In4.Cu")
		(net "M_C_DQ<45>")
	)
	(segment
		(start 277.82012 -60.095638)
		(end 277.490174 -60.857384)
		(width 0.0889)
		(layer "In4.Cu")
		(net "M_C_DQ<45>")
	)
	(segment
		(start 290.208208 -12.271756)
		(end 290.297108 -12.360656)
		(width 0.14224)
		(layer "In4.Cu")
		(net "M_C_DQ<45>")
	)
	(segment
		(start 289.319208 -3.940556)
		(end 289.7632 -4.384548)
		(width 0.14224)
		(layer "In4.Cu")
		(net "M_C_DQ<45>")
	)
	(segment
		(start 283.972 -35.594544)
		(end 284.589728 -36.212272)
		(width 0.14224)
		(layer "In4.Cu")
		(net "M_C_DQ<45>")
	)
	(segment
		(start 290.297108 -12.360656)
		(end 290.297108 -13.617956)
		(width 0.14224)
		(layer "In4.Cu")
		(net "M_C_DQ<45>")
	)
	(segment
		(start 277.149814 -56.684418)
		(end 277.143464 -56.695086)
		(width 0.0889)
		(layer "In4.Cu")
		(net "M_C_DQ<45>")
	)
	(segment
		(start 277.149814 -55.693818)
		(end 277.143464 -55.704486)
		(width 0.0889)
		(layer "In4.Cu")
		(net "M_C_DQ<45>")
	)
	(segment
		(start 278.6888 -50.393854)
		(end 277.0124 -52.070254)
		(width 0.0889)
		(layer "In4.Cu")
		(net "M_C_DQ<45>")
	)
	(segment
		(start 283.420566 -37.437314)
		(end 283.420566 -37.724842)
		(width 0.14224)
		(layer "In4.Cu")
		(net "M_C_DQ<45>")
	)
	(segment
		(start 277.143464 -59.076336)
		(end 277.155148 -59.096656)
		(width 0.0889)
		(layer "In4.Cu")
		(net "M_C_DQ<45>")
	)
	(segment
		(start 290.297108 -13.617956)
		(end 290.233608 -13.681456)
		(width 0.14224)
		(layer "In4.Cu")
		(net "M_C_DQ<45>")
	)
	(segment
		(start 277.149814 -57.675018)
		(end 277.143464 -57.685686)
		(width 0.0889)
		(layer "In4.Cu")
		(net "M_C_DQ<45>")
	)
	(segment
		(start 283.972 -35.213544)
		(end 283.972 -35.594544)
		(width 0.14224)
		(layer "In4.Cu")
		(net "M_C_DQ<45>")
	)
	(segment
		(start 290.29279 -7.323328)
		(end 290.297108 -7.327646)
		(width 0.14224)
		(layer "In4.Cu")
		(net "M_C_DQ<45>")
	)
	(segment
		(start 277.143464 -56.695086)
		(end 277.138638 -56.703722)
		(width 0.0889)
		(layer "In4.Cu")
		(net "M_C_DQ<45>")
	)
	(segment
		(start 284.589728 -36.55568)
		(end 284.282896 -36.862512)
		(width 0.14224)
		(layer "In4.Cu")
		(net "M_C_DQ<45>")
	)
	(segment
		(start 277.143464 -55.704486)
		(end 277.138638 -55.713122)
		(width 0.0889)
		(layer "In4.Cu")
		(net "M_C_DQ<45>")
	)
	(arc
		(start 277.138638 -56.703722)
		(mid 277.089883 -56.900074)
		(end 277.143464 -57.095136)
		(width 0.0889)
		(layer "In4.Cu")
		(net "M_C_DQ<45>")
	)
	(arc
		(start 277.143464 -56.104536)
		(mid 277.222686 -56.393654)
		(end 277.149814 -56.684418)
		(width 0.0889)
		(layer "In4.Cu")
		(net "M_C_DQ<45>")
	)
	(arc
		(start 277.149814 -54.134004)
		(mid 277.222612 -54.424767)
		(end 277.143464 -54.713886)
		(width 0.0889)
		(layer "In4.Cu")
		(net "M_C_DQ<45>")
	)
	(arc
		(start 277.76424 -59.515756)
		(mid 277.893985 -59.779007)
		(end 277.836884 -60.066936)
		(width 0.0889)
		(layer "In4.Cu")
		(net "M_C_DQ<45>")
	)
	(arc
		(start 277.29815 -59.28868)
		(mid 277.417522 -59.388877)
		(end 277.569168 -59.424824)
		(width 0.0889)
		(layer "In4.Cu")
		(net "M_C_DQ<45>")
	)
	(arc
		(start 277.143464 -55.113936)
		(mid 277.222686 -55.403054)
		(end 277.149814 -55.693818)
		(width 0.0889)
		(layer "In4.Cu")
		(net "M_C_DQ<45>")
	)
	(arc
		(start 277.143464 -58.67654)
		(mid 277.089965 -58.876438)
		(end 277.143464 -59.076336)
		(width 0.0889)
		(layer "In4.Cu")
		(net "M_C_DQ<45>")
	)
	(arc
		(start 277.143464 -53.723286)
		(mid 277.089994 -53.918349)
		(end 277.138638 -54.1147)
		(width 0.0889)
		(layer "In4.Cu")
		(net "M_C_DQ<45>")
	)
	(arc
		(start 277.138638 -54.722522)
		(mid 277.089883 -54.918874)
		(end 277.143464 -55.113936)
		(width 0.0889)
		(layer "In4.Cu")
		(net "M_C_DQ<45>")
	)
	(arc
		(start 277.138638 -55.713122)
		(mid 277.089883 -55.909474)
		(end 277.143464 -56.104536)
		(width 0.0889)
		(layer "In4.Cu")
		(net "M_C_DQ<45>")
	)
	(arc
		(start 277.138638 -57.694322)
		(mid 277.089883 -57.890674)
		(end 277.143464 -58.085736)
		(width 0.0889)
		(layer "In4.Cu")
		(net "M_C_DQ<45>")
	)
	(arc
		(start 277.143464 -57.095136)
		(mid 277.222686 -57.384254)
		(end 277.149814 -57.675018)
		(width 0.0889)
		(layer "In4.Cu")
		(net "M_C_DQ<45>")
	)
	(arc
		(start 277.143464 -58.085736)
		(mid 277.222595 -58.381138)
		(end 277.143464 -58.67654)
		(width 0.0889)
		(layer "In4.Cu")
		(net "M_C_DQ<45>")
	)
	(arc
		(start 277.569168 -59.424824)
		(mid 277.665398 -59.443965)
		(end 277.746968 -59.498484)
		(width 0.0889)
		(layer "In4.Cu")
		(net "M_C_DQ<45>")
	)
	(arc
		(start 277.149814 -53.143404)
		(mid 277.222612 -53.434167)
		(end 277.143464 -53.723286)
		(width 0.0889)
		(layer "In4.Cu")
		(net "M_C_DQ<45>")
	)
	(segment
		(start 290.135056 -2.765552)
		(end 290.135056 0.53975)
		(width 0.14224)
		(layer "In11.Cu")
		(net "M_C_DQ<45>")
	)
	(segment
		(start 290.135056 0.53975)
		(end 290.331906 0.7366)
		(width 0.14224)
		(layer "In11.Cu")
		(net "M_C_DQ<45>")
	)
	(segment
		(start 289.931602 1.5494)
		(end 289.620706 1.5494)
		(width 0.14224)
		(layer "In11.Cu")
		(net "M_C_DQ<45>")
	)
	(segment
		(start 290.331906 0.7366)
		(end 290.331906 1.149096)
		(width 0.14224)
		(layer "In11.Cu")
		(net "M_C_DQ<45>")
	)
	(segment
		(start 289.620706 1.5494)
		(end 289.049968 2.120138)
		(width 0.14224)
		(layer "In11.Cu")
		(net "M_C_DQ<45>")
	)
	(segment
		(start 290.331906 1.149096)
		(end 289.931602 1.5494)
		(width 0.14224)
		(layer "In11.Cu")
		(net "M_C_DQ<45>")
	)
	(segment
		(start 289.823652 -3.076956)
		(end 290.135056 -2.765552)
		(width 0.14224)
		(layer "In11.Cu")
		(net "M_C_DQ<45>")
	)
	(segment
		(start 289.049968 2.120138)
		(end 289.049968 2.514854)
		(width 0.14224)
		(layer "In11.Cu")
		(net "M_C_DQ<45>")
	)
	(segment
		(start 289.90036 -0.821182)
		(end 289.899852 -0.821182)
		(width 0.1651)
		(layer "F.Cu")
		(net "M_C_DQ<44>")
	)
	(segment
		(start 289.899852 0.510032)
		(end 289.801808 1.0414)
		(width 0.1651)
		(layer "F.Cu")
		(net "M_C_DQ<44>")
	)
	(segment
		(start 289.899852 -0.821182)
		(end 289.899852 0.510032)
		(width 0.1651)
		(layer "F.Cu")
		(net "M_C_DQ<44>")
	)
	(segment
		(start 278.061674 -59.866784)
		(end 277.490174 -59.866784)
		(width 0.0889)
		(layer "F.Cu")
		(net "M_C_DQ<44>")
	)
	(via
		(at 289.049968 -4.357878)
		(size 0.508)
		(drill 0.254)
		(layers "F.Cu" "B.Cu")
		(net "M_C_DQ<44>")
	)
	(via
		(at 277.490174 -59.866784)
		(size 0.508)
		(drill 0.254)
		(layers "F.Cu" "B.Cu")
		(net "M_C_DQ<44>")
	)
	(via
		(at 289.801808 1.0414)
		(size 0.508)
		(drill 0.254)
		(layers "F.Cu" "B.Cu")
		(net "M_C_DQ<44>")
	)
	(segment
		(start 289.050476 -5.621782)
		(end 289.049968 -5.621782)
		(width 0.1651)
		(layer "B.Cu")
		(net "M_C_DQ<44>")
	)
	(segment
		(start 289.049968 -5.621782)
		(end 289.049968 -4.357878)
		(width 0.1651)
		(layer "B.Cu")
		(net "M_C_DQ<44>")
	)
	(segment
		(start 276.8092 -52.93614)
		(end 276.982936 -53.23586)
		(width 0.0889)
		(layer "In4.Cu")
		(net "M_C_DQ<44>")
	)
	(segment
		(start 280.394156 -38.831012)
		(end 280.192988 -38.831012)
		(width 0.14224)
		(layer "In4.Cu")
		(net "M_C_DQ<44>")
	)
	(segment
		(start 279.819354 -39.405814)
		(end 280.186638 -39.773098)
		(width 0.14224)
		(layer "In4.Cu")
		(net "M_C_DQ<44>")
	)
	(segment
		(start 282.522422 -37.724842)
		(end 282.198572 -38.048692)
		(width 0.14224)
		(layer "In4.Cu")
		(net "M_C_DQ<44>")
	)
	(segment
		(start 280.192988 -38.831012)
		(end 279.819354 -39.204646)
		(width 0.14224)
		(layer "In4.Cu")
		(net "M_C_DQ<44>")
	)
	(segment
		(start 279.2222 -41.025064)
		(end 279.2222 -46.6598)
		(width 0.14224)
		(layer "In4.Cu")
		(net "M_C_DQ<44>")
	)
	(segment
		(start 276.972014 -59.160918)
		(end 276.978364 -59.171586)
		(width 0.0889)
		(layer "In4.Cu")
		(net "M_C_DQ<44>")
	)
	(segment
		(start 281.8892 -36.3982)
		(end 281.8892 -36.804092)
		(width 0.14224)
		(layer "In4.Cu")
		(net "M_C_DQ<44>")
	)
	(segment
		(start 289.319208 -18.313146)
		(end 289.573208 -18.567146)
		(width 0.14224)
		(layer "In4.Cu")
		(net "M_C_DQ<44>")
	)
	(segment
		(start 289.319208 -13.567156)
		(end 289.547808 -13.795756)
		(width 0.14224)
		(layer "In4.Cu")
		(net "M_C_DQ<44>")
	)
	(segment
		(start 289.1536 -29.1846)
		(end 289.1028 -29.1846)
		(width 0.14224)
		(layer "In4.Cu")
		(net "M_C_DQ<44>")
	)
	(segment
		(start 276.98319 -55.6006)
		(end 276.978364 -55.609236)
		(width 0.0889)
		(layer "In4.Cu")
		(net "M_C_DQ<44>")
	)
	(segment
		(start 289.049968 -6.415024)
		(end 289.547808 -6.912864)
		(width 0.14224)
		(layer "In4.Cu")
		(net "M_C_DQ<44>")
	)
	(segment
		(start 281.911044 -38.048692)
		(end 281.49296 -37.630608)
		(width 0.14224)
		(layer "In4.Cu")
		(net "M_C_DQ<44>")
	)
	(segment
		(start 282.198572 -38.048692)
		(end 281.911044 -38.048692)
		(width 0.14224)
		(layer "In4.Cu")
		(net "M_C_DQ<44>")
	)
	(segment
		(start 276.978364 -55.609236)
		(end 276.972014 -55.619904)
		(width 0.0889)
		(layer "In4.Cu")
		(net "M_C_DQ<44>")
	)
	(segment
		(start 289.1028 -29.1846)
		(end 281.8892 -36.3982)
		(width 0.14224)
		(layer "In4.Cu")
		(net "M_C_DQ<44>")
	)
	(segment
		(start 289.319208 -12.347956)
		(end 289.319208 -13.567156)
		(width 0.14224)
		(layer "In4.Cu")
		(net "M_C_DQ<44>")
	)
	(segment
		(start 289.547808 -7.225538)
		(end 289.319208 -7.454138)
		(width 0.14224)
		(layer "In4.Cu")
		(net "M_C_DQ<44>")
	)
	(segment
		(start 289.547808 -6.912864)
		(end 289.547808 -7.225538)
		(width 0.14224)
		(layer "In4.Cu")
		(net "M_C_DQ<44>")
	)
	(segment
		(start 276.978364 -54.618636)
		(end 276.972014 -54.629304)
		(width 0.0889)
		(layer "In4.Cu")
		(net "M_C_DQ<44>")
	)
	(segment
		(start 282.522422 -37.437314)
		(end 282.522422 -37.724842)
		(width 0.14224)
		(layer "In4.Cu")
		(net "M_C_DQ<44>")
	)
	(segment
		(start 289.547808 -13.795756)
		(end 289.547808 -16.826738)
		(width 0.14224)
		(layer "In4.Cu")
		(net "M_C_DQ<44>")
	)
	(segment
		(start 279.819354 -39.204646)
		(end 279.819354 -39.405814)
		(width 0.14224)
		(layer "In4.Cu")
		(net "M_C_DQ<44>")
	)
	(segment
		(start 289.573208 -21.695156)
		(end 289.319208 -21.949156)
		(width 0.14224)
		(layer "In4.Cu")
		(net "M_C_DQ<44>")
	)
	(segment
		(start 289.319208 -17.055338)
		(end 289.319208 -18.313146)
		(width 0.14224)
		(layer "In4.Cu")
		(net "M_C_DQ<44>")
	)
	(segment
		(start 289.573208 -12.093956)
		(end 289.319208 -12.347956)
		(width 0.14224)
		(layer "In4.Cu")
		(net "M_C_DQ<44>")
	)
	(segment
		(start 281.336242 -38.623494)
		(end 281.336242 -38.911022)
		(width 0.14224)
		(layer "In4.Cu")
		(net "M_C_DQ<44>")
	)
	(segment
		(start 289.319208 -23.168356)
		(end 289.5854 -23.434548)
		(width 0.14224)
		(layer "In4.Cu")
		(net "M_C_DQ<44>")
	)
	(segment
		(start 289.5854 -28.7528)
		(end 289.1536 -29.1846)
		(width 0.14224)
		(layer "In4.Cu")
		(net "M_C_DQ<44>")
	)
	(segment
		(start 289.547808 -16.826738)
		(end 289.319208 -17.055338)
		(width 0.14224)
		(layer "In4.Cu")
		(net "M_C_DQ<44>")
	)
	(segment
		(start 278.4983 -50.31486)
		(end 276.8092 -52.00396)
		(width 0.0889)
		(layer "In4.Cu")
		(net "M_C_DQ<44>")
	)
	(segment
		(start 289.5854 -26.7208)
		(end 289.306 -27.0002)
		(width 0.14224)
		(layer "In4.Cu")
		(net "M_C_DQ<44>")
	)
	(segment
		(start 280.186638 -40.060626)
		(end 279.2222 -41.025064)
		(width 0.14224)
		(layer "In4.Cu")
		(net "M_C_DQ<44>")
	)
	(segment
		(start 281.291792 -37.630608)
		(end 280.918158 -38.004242)
		(width 0.14224)
		(layer "In4.Cu")
		(net "M_C_DQ<44>")
	)
	(segment
		(start 281.49296 -37.630608)
		(end 281.291792 -37.630608)
		(width 0.14224)
		(layer "In4.Cu")
		(net "M_C_DQ<44>")
	)
	(segment
		(start 289.319208 -8.711946)
		(end 289.573208 -8.965946)
		(width 0.14224)
		(layer "In4.Cu")
		(net "M_C_DQ<44>")
	)
	(segment
		(start 289.5854 -28.2956)
		(end 289.5854 -28.7528)
		(width 0.14224)
		(layer "In4.Cu")
		(net "M_C_DQ<44>")
	)
	(segment
		(start 279.2222 -46.6598)
		(end 279.45842 -46.89602)
		(width 0.0889)
		(layer "In4.Cu")
		(net "M_C_DQ<44>")
	)
	(segment
		(start 280.186638 -39.773098)
		(end 280.186638 -40.060626)
		(width 0.14224)
		(layer "In4.Cu")
		(net "M_C_DQ<44>")
	)
	(segment
		(start 279.45842 -46.89602)
		(end 279.45842 -48.3362)
		(width 0.0889)
		(layer "In4.Cu")
		(net "M_C_DQ<44>")
	)
	(segment
		(start 280.918158 -38.20541)
		(end 281.336242 -38.623494)
		(width 0.14224)
		(layer "In4.Cu")
		(net "M_C_DQ<44>")
	)
	(segment
		(start 281.336242 -38.911022)
		(end 281.048968 -39.198296)
		(width 0.14224)
		(layer "In4.Cu")
		(net "M_C_DQ<44>")
	)
	(segment
		(start 276.978364 -54.218586)
		(end 276.98319 -54.227222)
		(width 0.0889)
		(layer "In4.Cu")
		(net "M_C_DQ<44>")
	)
	(segment
		(start 276.978364 -59.171586)
		(end 276.995128 -59.20105)
		(width 0.0889)
		(layer "In4.Cu")
		(net "M_C_DQ<44>")
	)
	(segment
		(start 276.98319 -57.5818)
		(end 276.978364 -57.590436)
		(width 0.0889)
		(layer "In4.Cu")
		(net "M_C_DQ<44>")
	)
	(segment
		(start 289.573208 -8.965946)
		(end 289.573208 -12.093956)
		(width 0.14224)
		(layer "In4.Cu")
		(net "M_C_DQ<44>")
	)
	(segment
		(start 276.978364 -56.599836)
		(end 276.972014 -56.610504)
		(width 0.0889)
		(layer "In4.Cu")
		(net "M_C_DQ<44>")
	)
	(segment
		(start 280.76144 -39.198296)
		(end 280.394156 -38.831012)
		(width 0.14224)
		(layer "In4.Cu")
		(net "M_C_DQ<44>")
	)
	(segment
		(start 281.048968 -39.198296)
		(end 280.76144 -39.198296)
		(width 0.14224)
		(layer "In4.Cu")
		(net "M_C_DQ<44>")
	)
	(segment
		(start 289.049968 -4.357878)
		(end 289.049968 -6.415024)
		(width 0.14224)
		(layer "In4.Cu")
		(net "M_C_DQ<44>")
	)
	(segment
		(start 289.5854 -23.434548)
		(end 289.5854 -26.7208)
		(width 0.14224)
		(layer "In4.Cu")
		(net "M_C_DQ<44>")
	)
	(segment
		(start 276.972014 -54.207918)
		(end 276.978364 -54.218586)
		(width 0.0889)
		(layer "In4.Cu")
		(net "M_C_DQ<44>")
	)
	(segment
		(start 276.98319 -56.5912)
		(end 276.978364 -56.599836)
		(width 0.0889)
		(layer "In4.Cu")
		(net "M_C_DQ<44>")
	)
	(segment
		(start 279.45842 -48.3362)
		(end 278.4983 -49.29632)
		(width 0.0889)
		(layer "In4.Cu")
		(net "M_C_DQ<44>")
	)
	(segment
		(start 276.8092 -52.00396)
		(end 276.8092 -52.93614)
		(width 0.0889)
		(layer "In4.Cu")
		(net "M_C_DQ<44>")
	)
	(segment
		(start 289.306 -27.0002)
		(end 289.306 -28.0162)
		(width 0.14224)
		(layer "In4.Cu")
		(net "M_C_DQ<44>")
	)
	(segment
		(start 280.918158 -38.004242)
		(end 280.918158 -38.20541)
		(width 0.14224)
		(layer "In4.Cu")
		(net "M_C_DQ<44>")
	)
	(segment
		(start 289.306 -28.0162)
		(end 289.5854 -28.2956)
		(width 0.14224)
		(layer "In4.Cu")
		(net "M_C_DQ<44>")
	)
	(segment
		(start 276.978364 -57.590436)
		(end 276.972014 -57.601104)
		(width 0.0889)
		(layer "In4.Cu")
		(net "M_C_DQ<44>")
	)
	(segment
		(start 289.573208 -18.567146)
		(end 289.573208 -21.695156)
		(width 0.14224)
		(layer "In4.Cu")
		(net "M_C_DQ<44>")
	)
	(segment
		(start 276.98319 -58.5724)
		(end 276.978364 -58.581036)
		(width 0.0889)
		(layer "In4.Cu")
		(net "M_C_DQ<44>")
	)
	(segment
		(start 281.8892 -36.804092)
		(end 282.522422 -37.437314)
		(width 0.14224)
		(layer "In4.Cu")
		(net "M_C_DQ<44>")
	)
	(segment
		(start 278.4983 -49.29632)
		(end 278.4983 -50.31486)
		(width 0.0889)
		(layer "In4.Cu")
		(net "M_C_DQ<44>")
	)
	(segment
		(start 289.319208 -21.949156)
		(end 289.319208 -23.168356)
		(width 0.14224)
		(layer "In4.Cu")
		(net "M_C_DQ<44>")
	)
	(segment
		(start 276.995128 -59.20105)
		(end 277.490174 -59.866784)
		(width 0.0889)
		(layer "In4.Cu")
		(net "M_C_DQ<44>")
	)
	(segment
		(start 289.319208 -7.454138)
		(end 289.319208 -8.711946)
		(width 0.14224)
		(layer "In4.Cu")
		(net "M_C_DQ<44>")
	)
	(arc
		(start 276.978364 -53.628036)
		(mid 276.899142 -53.917154)
		(end 276.972014 -54.207918)
		(width 0.0889)
		(layer "In4.Cu")
		(net "M_C_DQ<44>")
	)
	(arc
		(start 276.978364 -58.581036)
		(mid 276.899142 -58.870154)
		(end 276.972014 -59.160918)
		(width 0.0889)
		(layer "In4.Cu")
		(net "M_C_DQ<44>")
	)
	(arc
		(start 276.972014 -56.610504)
		(mid 276.899216 -56.901267)
		(end 276.978364 -57.190386)
		(width 0.0889)
		(layer "In4.Cu")
		(net "M_C_DQ<44>")
	)
	(arc
		(start 276.98319 -54.227222)
		(mid 277.031945 -54.423574)
		(end 276.978364 -54.618636)
		(width 0.0889)
		(layer "In4.Cu")
		(net "M_C_DQ<44>")
	)
	(arc
		(start 276.978364 -55.209186)
		(mid 277.031834 -55.404249)
		(end 276.98319 -55.6006)
		(width 0.0889)
		(layer "In4.Cu")
		(net "M_C_DQ<44>")
	)
	(arc
		(start 276.978364 -56.199786)
		(mid 277.031834 -56.394849)
		(end 276.98319 -56.5912)
		(width 0.0889)
		(layer "In4.Cu")
		(net "M_C_DQ<44>")
	)
	(arc
		(start 276.978364 -58.180986)
		(mid 277.031834 -58.376049)
		(end 276.98319 -58.5724)
		(width 0.0889)
		(layer "In4.Cu")
		(net "M_C_DQ<44>")
	)
	(arc
		(start 276.972014 -57.601104)
		(mid 276.899216 -57.891867)
		(end 276.978364 -58.180986)
		(width 0.0889)
		(layer "In4.Cu")
		(net "M_C_DQ<44>")
	)
	(arc
		(start 276.972014 -55.619904)
		(mid 276.899216 -55.910667)
		(end 276.978364 -56.199786)
		(width 0.0889)
		(layer "In4.Cu")
		(net "M_C_DQ<44>")
	)
	(arc
		(start 276.972014 -54.629304)
		(mid 276.899216 -54.920067)
		(end 276.978364 -55.209186)
		(width 0.0889)
		(layer "In4.Cu")
		(net "M_C_DQ<44>")
	)
	(arc
		(start 276.982936 -53.23586)
		(mid 277.031967 -53.432547)
		(end 276.978364 -53.628036)
		(width 0.0889)
		(layer "In4.Cu")
		(net "M_C_DQ<44>")
	)
	(arc
		(start 276.978364 -57.190386)
		(mid 277.031834 -57.385449)
		(end 276.98319 -57.5818)
		(width 0.0889)
		(layer "In4.Cu")
		(net "M_C_DQ<44>")
	)
	(segment
		(start 289.525456 0.287528)
		(end 289.525456 0.765048)
		(width 0.14224)
		(layer "In11.Cu")
		(net "M_C_DQ<44>")
	)
	(segment
		(start 289.161474 -0.381)
		(end 289.161474 -0.076454)
		(width 0.14224)
		(layer "In11.Cu")
		(net "M_C_DQ<44>")
	)
	(segment
		(start 289.174174 -1.4351)
		(end 289.542474 -1.0668)
		(width 0.14224)
		(layer "In11.Cu")
		(net "M_C_DQ<44>")
	)
	(segment
		(start 289.174174 -1.790446)
		(end 289.174174 -1.4351)
		(width 0.14224)
		(layer "In11.Cu")
		(net "M_C_DQ<44>")
	)
	(segment
		(start 289.542474 -1.0668)
		(end 289.542474 -0.762)
		(width 0.14224)
		(layer "In11.Cu")
		(net "M_C_DQ<44>")
	)
	(segment
		(start 289.525456 -2.616454)
		(end 289.525456 -2.141728)
		(width 0.14224)
		(layer "In11.Cu")
		(net "M_C_DQ<44>")
	)
	(segment
		(start 289.542474 -0.762)
		(end 289.161474 -0.381)
		(width 0.14224)
		(layer "In11.Cu")
		(net "M_C_DQ<44>")
	)
	(segment
		(start 289.049968 -4.357878)
		(end 288.814256 -4.122166)
		(width 0.14224)
		(layer "In11.Cu")
		(net "M_C_DQ<44>")
	)
	(segment
		(start 289.161474 -0.076454)
		(end 289.525456 0.287528)
		(width 0.14224)
		(layer "In11.Cu")
		(net "M_C_DQ<44>")
	)
	(segment
		(start 289.525456 0.765048)
		(end 289.801808 1.0414)
		(width 0.14224)
		(layer "In11.Cu")
		(net "M_C_DQ<44>")
	)
	(segment
		(start 288.814256 -3.327654)
		(end 289.525456 -2.616454)
		(width 0.14224)
		(layer "In11.Cu")
		(net "M_C_DQ<44>")
	)
	(segment
		(start 289.525456 -2.141728)
		(end 289.174174 -1.790446)
		(width 0.14224)
		(layer "In11.Cu")
		(net "M_C_DQ<44>")
	)
	(segment
		(start 288.814256 -4.122166)
		(end 288.814256 -3.327654)
		(width 0.14224)
		(layer "In11.Cu")
		(net "M_C_DQ<44>")
	)
	(segment
		(start 296.700448 3.778758)
		(end 296.69994 3.778758)
		(width 0.1651)
		(layer "F.Cu")
		(net "M_C_DQ<43>")
	)
	(segment
		(start 296.69994 3.778758)
		(end 296.69994 2.514854)
		(width 0.1651)
		(layer "F.Cu")
		(net "M_C_DQ<43>")
	)
	(segment
		(start 281.495754 -60.857384)
		(end 280.924254 -60.857384)
		(width 0.0889)
		(layer "F.Cu")
		(net "M_C_DQ<43>")
	)
	(via
		(at 296.69994 2.514854)
		(size 0.508)
		(drill 0.254)
		(layers "F.Cu" "B.Cu")
		(net "M_C_DQ<43>")
	)
	(via
		(at 280.924254 -60.857384)
		(size 0.508)
		(drill 0.254)
		(layers "F.Cu" "B.Cu")
		(net "M_C_DQ<43>")
	)
	(via
		(at 297.549824 -3.076956)
		(size 0.508)
		(drill 0.254)
		(layers "F.Cu" "B.Cu")
		(net "M_C_DQ<43>")
	)
	(segment
		(start 297.550332 -1.021842)
		(end 297.549824 -1.021842)
		(width 0.1651)
		(layer "B.Cu")
		(net "M_C_DQ<43>")
	)
	(segment
		(start 297.549824 -1.021842)
		(end 297.549824 -3.076956)
		(width 0.1651)
		(layer "B.Cu")
		(net "M_C_DQ<43>")
	)
	(segment
		(start 298.011596 -26.917396)
		(end 298.011596 -28.187396)
		(width 0.14224)
		(layer "In4.Cu")
		(net "M_C_DQ<43>")
	)
	(segment
		(start 297.833796 -28.365196)
		(end 297.833796 -28.695396)
		(width 0.14224)
		(layer "In4.Cu")
		(net "M_C_DQ<43>")
	)
	(segment
		(start 283.7307 -50.295048)
		(end 283.7307 -51.02352)
		(width 0.0889)
		(layer "In4.Cu")
		(net "M_C_DQ<43>")
	)
	(segment
		(start 297.549824 -3.076956)
		(end 297.066208 -3.560572)
		(width 0.14224)
		(layer "In4.Cu")
		(net "M_C_DQ<43>")
	)
	(segment
		(start 281.436064 -54.618636)
		(end 281.442414 -54.629304)
		(width 0.0889)
		(layer "In4.Cu")
		(net "M_C_DQ<43>")
	)
	(segment
		(start 298.056808 -18.401538)
		(end 297.904408 -18.553938)
		(width 0.14224)
		(layer "In4.Cu")
		(net "M_C_DQ<43>")
	)
	(segment
		(start 297.066208 -3.965956)
		(end 297.917108 -4.816856)
		(width 0.14224)
		(layer "In4.Cu")
		(net "M_C_DQ<43>")
	)
	(segment
		(start 297.904408 -12.220956)
		(end 298.082208 -12.398756)
		(width 0.14224)
		(layer "In4.Cu")
		(net "M_C_DQ<43>")
	)
	(segment
		(start 297.917108 -13.681456)
		(end 297.917108 -16.890746)
		(width 0.14224)
		(layer "In4.Cu")
		(net "M_C_DQ<43>")
	)
	(segment
		(start 281.424126 -53.330094)
		(end 281.424126 -53.583332)
		(width 0.0889)
		(layer "In4.Cu")
		(net "M_C_DQ<43>")
	)
	(segment
		(start 297.917108 -4.816856)
		(end 297.917108 -7.289546)
		(width 0.14224)
		(layer "In4.Cu")
		(net "M_C_DQ<43>")
	)
	(segment
		(start 281.436064 -57.590436)
		(end 281.442414 -57.601104)
		(width 0.0889)
		(layer "In4.Cu")
		(net "M_C_DQ<43>")
	)
	(segment
		(start 281.442414 -59.160918)
		(end 281.436064 -59.171586)
		(width 0.0889)
		(layer "In4.Cu")
		(net "M_C_DQ<43>")
	)
	(segment
		(start 281.431238 -54.61)
		(end 281.436064 -54.618636)
		(width 0.0889)
		(layer "In4.Cu")
		(net "M_C_DQ<43>")
	)
	(segment
		(start 297.917108 -7.289546)
		(end 298.056808 -7.429246)
		(width 0.14224)
		(layer "In4.Cu")
		(net "M_C_DQ<43>")
	)
	(segment
		(start 297.904408 -8.927338)
		(end 297.904408 -12.220956)
		(width 0.14224)
		(layer "In4.Cu")
		(net "M_C_DQ<43>")
	)
	(segment
		(start 281.4193 -60.19165)
		(end 280.924254 -60.857384)
		(width 0.0889)
		(layer "In4.Cu")
		(net "M_C_DQ<43>")
	)
	(segment
		(start 294.8686 -35.3568)
		(end 294.399208 -35.3568)
		(width 0.14224)
		(layer "In4.Cu")
		(net "M_C_DQ<43>")
	)
	(segment
		(start 285.44012 -48.585628)
		(end 283.7307 -50.295048)
		(width 0.0889)
		(layer "In4.Cu")
		(net "M_C_DQ<43>")
	)
	(segment
		(start 297.904408 -21.822156)
		(end 298.082208 -21.999956)
		(width 0.14224)
		(layer "In4.Cu")
		(net "M_C_DQ<43>")
	)
	(segment
		(start 298.082208 -12.398756)
		(end 298.082208 -13.516356)
		(width 0.14224)
		(layer "In4.Cu")
		(net "M_C_DQ<43>")
	)
	(segment
		(start 298.082208 -23.183596)
		(end 297.9166 -23.349204)
		(width 0.14224)
		(layer "In4.Cu")
		(net "M_C_DQ<43>")
	)
	(segment
		(start 298.011596 -28.187396)
		(end 297.833796 -28.365196)
		(width 0.14224)
		(layer "In4.Cu")
		(net "M_C_DQ<43>")
	)
	(segment
		(start 298.082208 -13.516356)
		(end 297.917108 -13.681456)
		(width 0.14224)
		(layer "In4.Cu")
		(net "M_C_DQ<43>")
	)
	(segment
		(start 281.436064 -60.162186)
		(end 281.4193 -60.19165)
		(width 0.0889)
		(layer "In4.Cu")
		(net "M_C_DQ<43>")
	)
	(segment
		(start 297.833796 -28.695396)
		(end 298.2468 -29.1084)
		(width 0.14224)
		(layer "In4.Cu")
		(net "M_C_DQ<43>")
	)
	(segment
		(start 298.2468 -31.9786)
		(end 294.8686 -35.3568)
		(width 0.14224)
		(layer "In4.Cu")
		(net "M_C_DQ<43>")
	)
	(segment
		(start 281.436064 -56.599836)
		(end 281.442414 -56.610504)
		(width 0.0889)
		(layer "In4.Cu")
		(net "M_C_DQ<43>")
	)
	(segment
		(start 298.056808 -7.429246)
		(end 298.056808 -8.774938)
		(width 0.14224)
		(layer "In4.Cu")
		(net "M_C_DQ<43>")
	)
	(segment
		(start 298.082208 -21.999956)
		(end 298.082208 -23.183596)
		(width 0.14224)
		(layer "In4.Cu")
		(net "M_C_DQ<43>")
	)
	(segment
		(start 283.7307 -51.02352)
		(end 281.424126 -53.330094)
		(width 0.0889)
		(layer "In4.Cu")
		(net "M_C_DQ<43>")
	)
	(segment
		(start 297.9166 -26.8224)
		(end 298.011596 -26.917396)
		(width 0.14224)
		(layer "In4.Cu")
		(net "M_C_DQ<43>")
	)
	(segment
		(start 298.056808 -8.774938)
		(end 297.904408 -8.927338)
		(width 0.14224)
		(layer "In4.Cu")
		(net "M_C_DQ<43>")
	)
	(segment
		(start 298.056808 -17.030446)
		(end 298.056808 -18.401538)
		(width 0.14224)
		(layer "In4.Cu")
		(net "M_C_DQ<43>")
	)
	(segment
		(start 285.620968 -44.13504)
		(end 285.620968 -47.284132)
		(width 0.14224)
		(layer "In4.Cu")
		(net "M_C_DQ<43>")
	)
	(segment
		(start 285.44012 -47.46498)
		(end 285.44012 -48.585628)
		(width 0.0889)
		(layer "In4.Cu")
		(net "M_C_DQ<43>")
	)
	(segment
		(start 297.904408 -18.553938)
		(end 297.904408 -21.822156)
		(width 0.14224)
		(layer "In4.Cu")
		(net "M_C_DQ<43>")
	)
	(segment
		(start 298.2468 -29.1084)
		(end 298.2468 -31.9786)
		(width 0.14224)
		(layer "In4.Cu")
		(net "M_C_DQ<43>")
	)
	(segment
		(start 281.431238 -58.5724)
		(end 281.436064 -58.581036)
		(width 0.0889)
		(layer "In4.Cu")
		(net "M_C_DQ<43>")
	)
	(segment
		(start 297.066208 -3.560572)
		(end 297.066208 -3.965956)
		(width 0.14224)
		(layer "In4.Cu")
		(net "M_C_DQ<43>")
	)
	(segment
		(start 281.431238 -55.6006)
		(end 281.436064 -55.609236)
		(width 0.0889)
		(layer "In4.Cu")
		(net "M_C_DQ<43>")
	)
	(segment
		(start 285.620968 -47.284132)
		(end 285.44012 -47.46498)
		(width 0.0889)
		(layer "In4.Cu")
		(net "M_C_DQ<43>")
	)
	(segment
		(start 281.436064 -55.609236)
		(end 281.442414 -55.619904)
		(width 0.0889)
		(layer "In4.Cu")
		(net "M_C_DQ<43>")
	)
	(segment
		(start 281.431238 -57.5818)
		(end 281.436064 -57.590436)
		(width 0.0889)
		(layer "In4.Cu")
		(net "M_C_DQ<43>")
	)
	(segment
		(start 297.917108 -16.890746)
		(end 298.056808 -17.030446)
		(width 0.14224)
		(layer "In4.Cu")
		(net "M_C_DQ<43>")
	)
	(segment
		(start 297.9166 -23.349204)
		(end 297.9166 -26.8224)
		(width 0.14224)
		(layer "In4.Cu")
		(net "M_C_DQ<43>")
	)
	(segment
		(start 281.431238 -56.5912)
		(end 281.436064 -56.599836)
		(width 0.0889)
		(layer "In4.Cu")
		(net "M_C_DQ<43>")
	)
	(segment
		(start 294.399208 -35.3568)
		(end 285.620968 -44.13504)
		(width 0.14224)
		(layer "In4.Cu")
		(net "M_C_DQ<43>")
	)
	(arc
		(start 281.436064 -53.627782)
		(mid 281.515195 -53.923184)
		(end 281.436064 -54.218586)
		(width 0.0889)
		(layer "In4.Cu")
		(net "M_C_DQ<43>")
	)
	(arc
		(start 281.442414 -57.601104)
		(mid 281.515212 -57.891867)
		(end 281.436064 -58.180986)
		(width 0.0889)
		(layer "In4.Cu")
		(net "M_C_DQ<43>")
	)
	(arc
		(start 281.442414 -56.610504)
		(mid 281.515212 -56.901267)
		(end 281.436064 -57.190386)
		(width 0.0889)
		(layer "In4.Cu")
		(net "M_C_DQ<43>")
	)
	(arc
		(start 281.424126 -53.583332)
		(mid 281.427149 -53.606352)
		(end 281.436064 -53.627782)
		(width 0.0889)
		(layer "In4.Cu")
		(net "M_C_DQ<43>")
	)
	(arc
		(start 281.436064 -58.581036)
		(mid 281.515286 -58.870154)
		(end 281.442414 -59.160918)
		(width 0.0889)
		(layer "In4.Cu")
		(net "M_C_DQ<43>")
	)
	(arc
		(start 281.436064 -58.180986)
		(mid 281.382594 -58.376049)
		(end 281.431238 -58.5724)
		(width 0.0889)
		(layer "In4.Cu")
		(net "M_C_DQ<43>")
	)
	(arc
		(start 281.436064 -59.171586)
		(mid 281.382565 -59.371484)
		(end 281.436064 -59.571382)
		(width 0.0889)
		(layer "In4.Cu")
		(net "M_C_DQ<43>")
	)
	(arc
		(start 281.436064 -56.199786)
		(mid 281.382594 -56.394849)
		(end 281.431238 -56.5912)
		(width 0.0889)
		(layer "In4.Cu")
		(net "M_C_DQ<43>")
	)
	(arc
		(start 281.436064 -57.190386)
		(mid 281.382594 -57.385449)
		(end 281.431238 -57.5818)
		(width 0.0889)
		(layer "In4.Cu")
		(net "M_C_DQ<43>")
	)
	(arc
		(start 281.436064 -55.209186)
		(mid 281.382594 -55.404249)
		(end 281.431238 -55.6006)
		(width 0.0889)
		(layer "In4.Cu")
		(net "M_C_DQ<43>")
	)
	(arc
		(start 281.442414 -55.619904)
		(mid 281.515212 -55.910667)
		(end 281.436064 -56.199786)
		(width 0.0889)
		(layer "In4.Cu")
		(net "M_C_DQ<43>")
	)
	(arc
		(start 281.436064 -59.571382)
		(mid 281.515195 -59.866784)
		(end 281.436064 -60.162186)
		(width 0.0889)
		(layer "In4.Cu")
		(net "M_C_DQ<43>")
	)
	(arc
		(start 281.442414 -54.629304)
		(mid 281.515212 -54.920067)
		(end 281.436064 -55.209186)
		(width 0.0889)
		(layer "In4.Cu")
		(net "M_C_DQ<43>")
	)
	(arc
		(start 281.436064 -54.218586)
		(mid 281.382594 -54.413649)
		(end 281.431238 -54.61)
		(width 0.0889)
		(layer "In4.Cu")
		(net "M_C_DQ<43>")
	)
	(segment
		(start 297.600878 1.5494)
		(end 297.346878 1.5494)
		(width 0.14224)
		(layer "In11.Cu")
		(net "M_C_DQ<43>")
	)
	(segment
		(start 297.90263 -2.72415)
		(end 297.90263 0.581152)
		(width 0.14224)
		(layer "In11.Cu")
		(net "M_C_DQ<43>")
	)
	(segment
		(start 298.058078 1.0922)
		(end 297.600878 1.5494)
		(width 0.14224)
		(layer "In11.Cu")
		(net "M_C_DQ<43>")
	)
	(segment
		(start 297.90263 0.581152)
		(end 298.058078 0.7366)
		(width 0.14224)
		(layer "In11.Cu")
		(net "M_C_DQ<43>")
	)
	(segment
		(start 297.016678 2.198116)
		(end 296.69994 2.514854)
		(width 0.14224)
		(layer "In11.Cu")
		(net "M_C_DQ<43>")
	)
	(segment
		(start 297.346878 1.5494)
		(end 297.016678 1.8796)
		(width 0.14224)
		(layer "In11.Cu")
		(net "M_C_DQ<43>")
	)
	(segment
		(start 297.549824 -3.076956)
		(end 297.90263 -2.72415)
		(width 0.14224)
		(layer "In11.Cu")
		(net "M_C_DQ<43>")
	)
	(segment
		(start 297.016678 1.8796)
		(end 297.016678 2.198116)
		(width 0.14224)
		(layer "In11.Cu")
		(net "M_C_DQ<43>")
	)
	(segment
		(start 298.058078 0.7366)
		(end 298.058078 1.0922)
		(width 0.14224)
		(layer "In11.Cu")
		(net "M_C_DQ<43>")
	)
	(segment
		(start 297.549824 0.175768)
		(end 297.681396 0.30734)
		(width 0.1651)
		(layer "F.Cu")
		(net "M_C_DQ<42>")
	)
	(segment
		(start 297.550332 -0.821182)
		(end 297.549824 -0.821182)
		(width 0.1651)
		(layer "F.Cu")
		(net "M_C_DQ<42>")
	)
	(segment
		(start 297.681396 0.53086)
		(end 297.549824 0.662432)
		(width 0.1651)
		(layer "F.Cu")
		(net "M_C_DQ<42>")
	)
	(segment
		(start 297.681396 0.30734)
		(end 297.681396 0.53086)
		(width 0.1651)
		(layer "F.Cu")
		(net "M_C_DQ<42>")
	)
	(segment
		(start 297.549824 0.662432)
		(end 297.549824 0.9398)
		(width 0.1651)
		(layer "F.Cu")
		(net "M_C_DQ<42>")
	)
	(segment
		(start 297.549824 -0.821182)
		(end 297.549824 0.175768)
		(width 0.1651)
		(layer "F.Cu")
		(net "M_C_DQ<42>")
	)
	(segment
		(start 281.495754 -59.866784)
		(end 280.924254 -59.866784)
		(width 0.0889)
		(layer "F.Cu")
		(net "M_C_DQ<42>")
	)
	(via
		(at 280.924254 -59.866784)
		(size 0.508)
		(drill 0.254)
		(layers "F.Cu" "B.Cu")
		(net "M_C_DQ<42>")
	)
	(via
		(at 297.549824 0.9398)
		(size 0.508)
		(drill 0.254)
		(layers "F.Cu" "B.Cu")
		(net "M_C_DQ<42>")
	)
	(via
		(at 296.69994 -4.357878)
		(size 0.508)
		(drill 0.254)
		(layers "F.Cu" "B.Cu")
		(net "M_C_DQ<42>")
	)
	(segment
		(start 296.700448 -5.621782)
		(end 296.69994 -5.621782)
		(width 0.1651)
		(layer "B.Cu")
		(net "M_C_DQ<42>")
	)
	(segment
		(start 296.69994 -5.621782)
		(end 296.69994 -4.357878)
		(width 0.1651)
		(layer "B.Cu")
		(net "M_C_DQ<42>")
	)
	(segment
		(start 297.0784 -18.440146)
		(end 297.193208 -18.554954)
		(width 0.14224)
		(layer "In4.Cu")
		(net "M_C_DQ<42>")
	)
	(segment
		(start 297.294808 -23.396956)
		(end 297.294808 -26.555192)
		(width 0.14224)
		(layer "In4.Cu")
		(net "M_C_DQ<42>")
	)
	(segment
		(start 297.294808 -26.555192)
		(end 296.8498 -27.0002)
		(width 0.14224)
		(layer "In4.Cu")
		(net "M_C_DQ<42>")
	)
	(segment
		(start 297.193208 -8.979154)
		(end 297.193208 -10.019538)
		(width 0.14224)
		(layer "In4.Cu")
		(net "M_C_DQ<42>")
	)
	(segment
		(start 281.264614 -56.684418)
		(end 281.270964 -56.695086)
		(width 0.0889)
		(layer "In4.Cu")
		(net "M_C_DQ<42>")
	)
	(segment
		(start 297.193208 -10.019538)
		(end 296.8244 -10.388346)
		(width 0.14224)
		(layer "In4.Cu")
		(net "M_C_DQ<42>")
	)
	(segment
		(start 281.270964 -55.704486)
		(end 281.27579 -55.713122)
		(width 0.0889)
		(layer "In4.Cu")
		(net "M_C_DQ<42>")
	)
	(segment
		(start 297.269408 -7.162546)
		(end 297.066208 -7.365746)
		(width 0.14224)
		(layer "In4.Cu")
		(net "M_C_DQ<42>")
	)
	(segment
		(start 281.270964 -56.695086)
		(end 281.27579 -56.703722)
		(width 0.0889)
		(layer "In4.Cu")
		(net "M_C_DQ<42>")
	)
	(segment
		(start 296.8244 -10.832338)
		(end 297.193208 -11.201146)
		(width 0.14224)
		(layer "In4.Cu")
		(net "M_C_DQ<42>")
	)
	(segment
		(start 297.6118 -30.775656)
		(end 295.86936 -32.518096)
		(width 0.14224)
		(layer "In4.Cu")
		(net "M_C_DQ<42>")
	)
	(segment
		(start 297.040808 -21.949156)
		(end 297.040808 -23.142956)
		(width 0.14224)
		(layer "In4.Cu")
		(net "M_C_DQ<42>")
	)
	(segment
		(start 281.270964 -57.685686)
		(end 281.27579 -57.694322)
		(width 0.0889)
		(layer "In4.Cu")
		(net "M_C_DQ<42>")
	)
	(segment
		(start 297.040808 -12.347956)
		(end 297.040808 -13.541756)
		(width 0.14224)
		(layer "In4.Cu")
		(net "M_C_DQ<42>")
	)
	(segment
		(start 283.5402 -50.91684)
		(end 281.2288 -53.22824)
		(width 0.0889)
		(layer "In4.Cu")
		(net "M_C_DQ<42>")
	)
	(segment
		(start 296.8498 -27.0002)
		(end 296.8498 -28.0416)
		(width 0.14224)
		(layer "In4.Cu")
		(net "M_C_DQ<42>")
	)
	(segment
		(start 281.270964 -59.076336)
		(end 281.253946 -59.105546)
		(width 0.0889)
		(layer "In4.Cu")
		(net "M_C_DQ<42>")
	)
	(segment
		(start 295.86936 -32.518096)
		(end 295.86936 -32.805624)
		(width 0.14224)
		(layer "In4.Cu")
		(net "M_C_DQ<42>")
	)
	(segment
		(start 295.468802 -33.55467)
		(end 295.294558 -33.380426)
		(width 0.14224)
		(layer "In4.Cu")
		(net "M_C_DQ<42>")
	)
	(segment
		(start 294.894 -34.417)
		(end 294.606726 -34.704274)
		(width 0.14224)
		(layer "In4.Cu")
		(net "M_C_DQ<42>")
	)
	(segment
		(start 296.8498 -28.0416)
		(end 297.198796 -28.390596)
		(width 0.14224)
		(layer "In4.Cu")
		(net "M_C_DQ<42>")
	)
	(segment
		(start 297.193208 -12.195556)
		(end 297.040808 -12.347956)
		(width 0.14224)
		(layer "In4.Cu")
		(net "M_C_DQ<42>")
	)
	(segment
		(start 297.193208 -21.796756)
		(end 297.040808 -21.949156)
		(width 0.14224)
		(layer "In4.Cu")
		(net "M_C_DQ<42>")
	)
	(segment
		(start 297.198796 -28.390596)
		(end 297.198796 -28.898596)
		(width 0.14224)
		(layer "In4.Cu")
		(net "M_C_DQ<42>")
	)
	(segment
		(start 297.269408 -4.927346)
		(end 297.269408 -7.162546)
		(width 0.14224)
		(layer "In4.Cu")
		(net "M_C_DQ<42>")
	)
	(segment
		(start 294.144954 -34.53003)
		(end 293.857426 -34.53003)
		(width 0.14224)
		(layer "In4.Cu")
		(net "M_C_DQ<42>")
	)
	(segment
		(start 293.857426 -34.53003)
		(end 284.985968 -43.401488)
		(width 0.14224)
		(layer "In4.Cu")
		(net "M_C_DQ<42>")
	)
	(segment
		(start 297.0784 -16.954754)
		(end 297.0784 -18.440146)
		(width 0.14224)
		(layer "In4.Cu")
		(net "M_C_DQ<42>")
	)
	(segment
		(start 295.75633 -33.55467)
		(end 295.468802 -33.55467)
		(width 0.14224)
		(layer "In4.Cu")
		(net "M_C_DQ<42>")
	)
	(segment
		(start 281.264614 -57.675018)
		(end 281.270964 -57.685686)
		(width 0.0889)
		(layer "In4.Cu")
		(net "M_C_DQ<42>")
	)
	(segment
		(start 297.040808 -23.142956)
		(end 297.294808 -23.396956)
		(width 0.14224)
		(layer "In4.Cu")
		(net "M_C_DQ<42>")
	)
	(segment
		(start 297.6118 -29.3116)
		(end 297.6118 -30.775656)
		(width 0.14224)
		(layer "In4.Cu")
		(net "M_C_DQ<42>")
	)
	(segment
		(start 297.193208 -18.554954)
		(end 297.193208 -21.796756)
		(width 0.14224)
		(layer "In4.Cu")
		(net "M_C_DQ<42>")
	)
	(segment
		(start 294.719756 -33.6677)
		(end 294.719756 -33.955228)
		(width 0.14224)
		(layer "In4.Cu")
		(net "M_C_DQ<42>")
	)
	(segment
		(start 296.043604 -32.979868)
		(end 296.043604 -33.267396)
		(width 0.14224)
		(layer "In4.Cu")
		(net "M_C_DQ<42>")
	)
	(segment
		(start 296.043604 -33.267396)
		(end 295.75633 -33.55467)
		(width 0.14224)
		(layer "In4.Cu")
		(net "M_C_DQ<42>")
	)
	(segment
		(start 295.86936 -32.805624)
		(end 296.043604 -32.979868)
		(width 0.14224)
		(layer "In4.Cu")
		(net "M_C_DQ<42>")
	)
	(segment
		(start 295.00703 -33.380426)
		(end 294.719756 -33.6677)
		(width 0.14224)
		(layer "In4.Cu")
		(net "M_C_DQ<42>")
	)
	(segment
		(start 296.69994 -4.357878)
		(end 297.269408 -4.927346)
		(width 0.14224)
		(layer "In4.Cu")
		(net "M_C_DQ<42>")
	)
	(segment
		(start 294.894 -34.129472)
		(end 294.894 -34.417)
		(width 0.14224)
		(layer "In4.Cu")
		(net "M_C_DQ<42>")
	)
	(segment
		(start 281.264614 -54.703218)
		(end 281.270964 -54.713886)
		(width 0.0889)
		(layer "In4.Cu")
		(net "M_C_DQ<42>")
	)
	(segment
		(start 281.2288 -53.22824)
		(end 281.2288 -53.565806)
		(width 0.0889)
		(layer "In4.Cu")
		(net "M_C_DQ<42>")
	)
	(segment
		(start 284.985968 -43.401488)
		(end 284.985968 -47.141892)
		(width 0.14224)
		(layer "In4.Cu")
		(net "M_C_DQ<42>")
	)
	(segment
		(start 284.985968 -47.141892)
		(end 285.22676 -47.382684)
		(width 0.0889)
		(layer "In4.Cu")
		(net "M_C_DQ<42>")
	)
	(segment
		(start 297.282108 -16.751046)
		(end 297.0784 -16.954754)
		(width 0.14224)
		(layer "In4.Cu")
		(net "M_C_DQ<42>")
	)
	(segment
		(start 281.270964 -53.723286)
		(end 281.27579 -53.731922)
		(width 0.0889)
		(layer "In4.Cu")
		(net "M_C_DQ<42>")
	)
	(segment
		(start 285.22676 -47.382684)
		(end 285.22676 -48.52924)
		(width 0.0889)
		(layer "In4.Cu")
		(net "M_C_DQ<42>")
	)
	(segment
		(start 294.319198 -34.704274)
		(end 294.144954 -34.53003)
		(width 0.14224)
		(layer "In4.Cu")
		(net "M_C_DQ<42>")
	)
	(segment
		(start 297.282108 -13.783056)
		(end 297.282108 -16.751046)
		(width 0.14224)
		(layer "In4.Cu")
		(net "M_C_DQ<42>")
	)
	(segment
		(start 295.294558 -33.380426)
		(end 295.00703 -33.380426)
		(width 0.14224)
		(layer "In4.Cu")
		(net "M_C_DQ<42>")
	)
	(segment
		(start 294.719756 -33.955228)
		(end 294.894 -34.129472)
		(width 0.14224)
		(layer "In4.Cu")
		(net "M_C_DQ<42>")
	)
	(segment
		(start 297.040808 -13.541756)
		(end 297.282108 -13.783056)
		(width 0.14224)
		(layer "In4.Cu")
		(net "M_C_DQ<42>")
	)
	(segment
		(start 297.066208 -8.852154)
		(end 297.193208 -8.979154)
		(width 0.14224)
		(layer "In4.Cu")
		(net "M_C_DQ<42>")
	)
	(segment
		(start 297.198796 -28.898596)
		(end 297.6118 -29.3116)
		(width 0.14224)
		(layer "In4.Cu")
		(net "M_C_DQ<42>")
	)
	(segment
		(start 281.253946 -59.105546)
		(end 280.924254 -59.866784)
		(width 0.0889)
		(layer "In4.Cu")
		(net "M_C_DQ<42>")
	)
	(segment
		(start 297.193208 -11.201146)
		(end 297.193208 -12.195556)
		(width 0.14224)
		(layer "In4.Cu")
		(net "M_C_DQ<42>")
	)
	(segment
		(start 281.270964 -54.713886)
		(end 281.27579 -54.722522)
		(width 0.0889)
		(layer "In4.Cu")
		(net "M_C_DQ<42>")
	)
	(segment
		(start 281.264614 -55.693818)
		(end 281.270964 -55.704486)
		(width 0.0889)
		(layer "In4.Cu")
		(net "M_C_DQ<42>")
	)
	(segment
		(start 285.22676 -48.52924)
		(end 283.5402 -50.2158)
		(width 0.0889)
		(layer "In4.Cu")
		(net "M_C_DQ<42>")
	)
	(segment
		(start 297.066208 -7.365746)
		(end 297.066208 -8.852154)
		(width 0.14224)
		(layer "In4.Cu")
		(net "M_C_DQ<42>")
	)
	(segment
		(start 283.5402 -50.2158)
		(end 283.5402 -50.91684)
		(width 0.0889)
		(layer "In4.Cu")
		(net "M_C_DQ<42>")
	)
	(segment
		(start 294.606726 -34.704274)
		(end 294.319198 -34.704274)
		(width 0.14224)
		(layer "In4.Cu")
		(net "M_C_DQ<42>")
	)
	(segment
		(start 296.8244 -10.388346)
		(end 296.8244 -10.832338)
		(width 0.14224)
		(layer "In4.Cu")
		(net "M_C_DQ<42>")
	)
	(arc
		(start 281.270964 -57.095136)
		(mid 281.191742 -57.384254)
		(end 281.264614 -57.675018)
		(width 0.0889)
		(layer "In4.Cu")
		(net "M_C_DQ<42>")
	)
	(arc
		(start 281.27579 -57.694322)
		(mid 281.324545 -57.890674)
		(end 281.270964 -58.085736)
		(width 0.0889)
		(layer "In4.Cu")
		(net "M_C_DQ<42>")
	)
	(arc
		(start 281.270964 -58.085736)
		(mid 281.191833 -58.381138)
		(end 281.270964 -58.67654)
		(width 0.0889)
		(layer "In4.Cu")
		(net "M_C_DQ<42>")
	)
	(arc
		(start 281.270964 -54.123336)
		(mid 281.191742 -54.412454)
		(end 281.264614 -54.703218)
		(width 0.0889)
		(layer "In4.Cu")
		(net "M_C_DQ<42>")
	)
	(arc
		(start 281.27579 -53.731922)
		(mid 281.324545 -53.928274)
		(end 281.270964 -54.123336)
		(width 0.0889)
		(layer "In4.Cu")
		(net "M_C_DQ<42>")
	)
	(arc
		(start 281.270964 -55.113936)
		(mid 281.191742 -55.403054)
		(end 281.264614 -55.693818)
		(width 0.0889)
		(layer "In4.Cu")
		(net "M_C_DQ<42>")
	)
	(arc
		(start 281.270964 -56.104536)
		(mid 281.191742 -56.393654)
		(end 281.264614 -56.684418)
		(width 0.0889)
		(layer "In4.Cu")
		(net "M_C_DQ<42>")
	)
	(arc
		(start 281.2288 -53.565806)
		(mid 281.23953 -53.647316)
		(end 281.270964 -53.723286)
		(width 0.0889)
		(layer "In4.Cu")
		(net "M_C_DQ<42>")
	)
	(arc
		(start 281.27579 -54.722522)
		(mid 281.324545 -54.918874)
		(end 281.270964 -55.113936)
		(width 0.0889)
		(layer "In4.Cu")
		(net "M_C_DQ<42>")
	)
	(arc
		(start 281.270964 -58.67654)
		(mid 281.324463 -58.876438)
		(end 281.270964 -59.076336)
		(width 0.0889)
		(layer "In4.Cu")
		(net "M_C_DQ<42>")
	)
	(arc
		(start 281.27579 -55.713122)
		(mid 281.324545 -55.909474)
		(end 281.270964 -56.104536)
		(width 0.0889)
		(layer "In4.Cu")
		(net "M_C_DQ<42>")
	)
	(arc
		(start 281.27579 -56.703722)
		(mid 281.324545 -56.900074)
		(end 281.270964 -57.095136)
		(width 0.0889)
		(layer "In4.Cu")
		(net "M_C_DQ<42>")
	)
	(segment
		(start 297.151806 0.541782)
		(end 297.549824 0.9398)
		(width 0.14224)
		(layer "In11.Cu")
		(net "M_C_DQ<42>")
	)
	(segment
		(start 296.806874 -1.35255)
		(end 297.111674 -1.04775)
		(width 0.14224)
		(layer "In11.Cu")
		(net "M_C_DQ<42>")
	)
	(segment
		(start 297.111674 -0.761746)
		(end 296.806874 -0.456946)
		(width 0.14224)
		(layer "In11.Cu")
		(net "M_C_DQ<42>")
	)
	(segment
		(start 297.264074 -2.2098)
		(end 296.806874 -1.7526)
		(width 0.14224)
		(layer "In11.Cu")
		(net "M_C_DQ<42>")
	)
	(segment
		(start 296.806874 -0.456946)
		(end 296.806874 -0.108204)
		(width 0.14224)
		(layer "In11.Cu")
		(net "M_C_DQ<42>")
	)
	(segment
		(start 297.151806 0.236728)
		(end 297.151806 0.541782)
		(width 0.14224)
		(layer "In11.Cu")
		(net "M_C_DQ<42>")
	)
	(segment
		(start 296.69994 -4.357878)
		(end 296.415206 -4.073144)
		(width 0.14224)
		(layer "In11.Cu")
		(net "M_C_DQ<42>")
	)
	(segment
		(start 296.806874 -0.108204)
		(end 297.151806 0.236728)
		(width 0.14224)
		(layer "In11.Cu")
		(net "M_C_DQ<42>")
	)
	(segment
		(start 296.806874 -1.7526)
		(end 296.806874 -1.35255)
		(width 0.14224)
		(layer "In11.Cu")
		(net "M_C_DQ<42>")
	)
	(segment
		(start 297.111674 -1.04775)
		(end 297.111674 -0.761746)
		(width 0.14224)
		(layer "In11.Cu")
		(net "M_C_DQ<42>")
	)
	(segment
		(start 297.264074 -2.478532)
		(end 297.264074 -2.2098)
		(width 0.14224)
		(layer "In11.Cu")
		(net "M_C_DQ<42>")
	)
	(segment
		(start 296.415206 -3.3274)
		(end 297.264074 -2.478532)
		(width 0.14224)
		(layer "In11.Cu")
		(net "M_C_DQ<42>")
	)
	(segment
		(start 296.415206 -4.073144)
		(end 296.415206 -3.3274)
		(width 0.14224)
		(layer "In11.Cu")
		(net "M_C_DQ<42>")
	)
	(segment
		(start 290.74999 3.778758)
		(end 290.74999 2.514854)
		(width 0.1651)
		(layer "F.Cu")
		(net "M_C_DQ<41>")
	)
	(segment
		(start 278.920194 -61.352938)
		(end 278.348694 -61.352938)
		(width 0.0889)
		(layer "F.Cu")
		(net "M_C_DQ<41>")
	)
	(segment
		(start 290.750498 3.778758)
		(end 290.74999 3.778758)
		(width 0.1651)
		(layer "F.Cu")
		(net "M_C_DQ<41>")
	)
	(via
		(at 291.422074 -3.076956)
		(size 0.508)
		(drill 0.254)
		(layers "F.Cu" "B.Cu")
		(net "M_C_DQ<41>")
	)
	(via
		(at 278.348694 -61.352938)
		(size 0.508)
		(drill 0.254)
		(layers "F.Cu" "B.Cu")
		(net "M_C_DQ<41>")
	)
	(via
		(at 290.74999 2.514854)
		(size 0.508)
		(drill 0.254)
		(layers "F.Cu" "B.Cu")
		(net "M_C_DQ<41>")
	)
	(segment
		(start 291.599874 -1.021842)
		(end 291.599874 -2.395982)
		(width 0.1651)
		(layer "B.Cu")
		(net "M_C_DQ<41>")
	)
	(segment
		(start 291.600382 -1.021842)
		(end 291.599874 -1.021842)
		(width 0.1651)
		(layer "B.Cu")
		(net "M_C_DQ<41>")
	)
	(segment
		(start 291.599874 -2.395982)
		(end 291.422074 -2.573782)
		(width 0.1651)
		(layer "B.Cu")
		(net "M_C_DQ<41>")
	)
	(segment
		(start 291.422074 -2.573782)
		(end 291.422074 -3.076956)
		(width 0.1651)
		(layer "B.Cu")
		(net "M_C_DQ<41>")
	)
	(segment
		(start 278.695404 -59.571382)
		(end 278.67864 -59.600338)
		(width 0.0889)
		(layer "In4.Cu")
		(net "M_C_DQ<41>")
	)
	(segment
		(start 280.92908 -47.16272)
		(end 280.92908 -48.237648)
		(width 0.0889)
		(layer "In4.Cu")
		(net "M_C_DQ<41>")
	)
	(segment
		(start 288.955226 -33.98647)
		(end 281.1272 -41.814496)
		(width 0.14224)
		(layer "In4.Cu")
		(net "M_C_DQ<41>")
	)
	(segment
		(start 291.910008 -6.566662)
		(end 291.910008 -29.071824)
		(width 0.14224)
		(layer "In4.Cu")
		(net "M_C_DQ<41>")
	)
	(segment
		(start 289.817556 -33.12414)
		(end 289.37966 -33.12414)
		(width 0.14224)
		(layer "In4.Cu")
		(net "M_C_DQ<41>")
	)
	(segment
		(start 289.56 -31.421832)
		(end 289.56 -31.9024)
		(width 0.14224)
		(layer "In4.Cu")
		(net "M_C_DQ<41>")
	)
	(segment
		(start 291.422074 -3.076956)
		(end 290.949126 -3.549904)
		(width 0.14224)
		(layer "In4.Cu")
		(net "M_C_DQ<41>")
	)
	(segment
		(start 278.001984 -55.609236)
		(end 278.008334 -55.619904)
		(width 0.0889)
		(layer "In4.Cu")
		(net "M_C_DQ<41>")
	)
	(segment
		(start 291.910008 -29.071824)
		(end 289.56 -31.421832)
		(width 0.14224)
		(layer "In4.Cu")
		(net "M_C_DQ<41>")
	)
	(segment
		(start 280.92908 -48.237648)
		(end 279.4889 -49.677828)
		(width 0.0889)
		(layer "In4.Cu")
		(net "M_C_DQ<41>")
	)
	(segment
		(start 288.955226 -33.548574)
		(end 288.955226 -33.98647)
		(width 0.14224)
		(layer "In4.Cu")
		(net "M_C_DQ<41>")
	)
	(segment
		(start 278.008334 -54.229254)
		(end 278.003508 -54.23789)
		(width 0.0889)
		(layer "In4.Cu")
		(net "M_C_DQ<41>")
	)
	(segment
		(start 278.361648 -59.962288)
		(end 278.333708 -59.962288)
		(width 0.0889)
		(layer "In4.Cu")
		(net "M_C_DQ<41>")
	)
	(segment
		(start 277.888954 -53.425344)
		(end 278.008334 -53.638704)
		(width 0.0889)
		(layer "In4.Cu")
		(net "M_C_DQ<41>")
	)
	(segment
		(start 289.37966 -33.12414)
		(end 288.955226 -33.548574)
		(width 0.14224)
		(layer "In4.Cu")
		(net "M_C_DQ<41>")
	)
	(segment
		(start 277.888954 -52.30114)
		(end 277.888954 -53.425344)
		(width 0.0889)
		(layer "In4.Cu")
		(net "M_C_DQ<41>")
	)
	(segment
		(start 277.997158 -55.6006)
		(end 278.001984 -55.609236)
		(width 0.0889)
		(layer "In4.Cu")
		(net "M_C_DQ<41>")
	)
	(segment
		(start 290.1442 -32.797496)
		(end 289.817556 -33.12414)
		(width 0.14224)
		(layer "In4.Cu")
		(net "M_C_DQ<41>")
	)
	(segment
		(start 277.997158 -60.5536)
		(end 278.019256 -60.591954)
		(width 0.0889)
		(layer "In4.Cu")
		(net "M_C_DQ<41>")
	)
	(segment
		(start 281.1272 -46.9646)
		(end 280.92908 -47.16272)
		(width 0.0889)
		(layer "In4.Cu")
		(net "M_C_DQ<41>")
	)
	(segment
		(start 278.018748 -58.152284)
		(end 278.001984 -58.180986)
		(width 0.0889)
		(layer "In4.Cu")
		(net "M_C_DQ<41>")
	)
	(segment
		(start 278.001984 -56.599836)
		(end 278.008334 -56.610504)
		(width 0.0889)
		(layer "In4.Cu")
		(net "M_C_DQ<41>")
	)
	(segment
		(start 279.4889 -49.677828)
		(end 279.4889 -50.701194)
		(width 0.0889)
		(layer "In4.Cu")
		(net "M_C_DQ<41>")
	)
	(segment
		(start 278.001984 -57.590436)
		(end 278.008334 -57.601104)
		(width 0.0889)
		(layer "In4.Cu")
		(net "M_C_DQ<41>")
	)
	(segment
		(start 291.285168 -4.239768)
		(end 291.285168 -5.941822)
		(width 0.14224)
		(layer "In4.Cu")
		(net "M_C_DQ<41>")
	)
	(segment
		(start 290.1442 -32.4866)
		(end 290.1442 -32.797496)
		(width 0.14224)
		(layer "In4.Cu")
		(net "M_C_DQ<41>")
	)
	(segment
		(start 281.1272 -41.814496)
		(end 281.1272 -46.9646)
		(width 0.14224)
		(layer "In4.Cu")
		(net "M_C_DQ<41>")
	)
	(segment
		(start 289.56 -31.9024)
		(end 290.1442 -32.4866)
		(width 0.14224)
		(layer "In4.Cu")
		(net "M_C_DQ<41>")
	)
	(segment
		(start 278.019256 -60.591954)
		(end 278.348694 -61.352938)
		(width 0.0889)
		(layer "In4.Cu")
		(net "M_C_DQ<41>")
	)
	(segment
		(start 277.997158 -57.5818)
		(end 278.001984 -57.590436)
		(width 0.0889)
		(layer "In4.Cu")
		(net "M_C_DQ<41>")
	)
	(segment
		(start 278.014684 -54.218586)
		(end 278.008334 -54.229254)
		(width 0.0889)
		(layer "In4.Cu")
		(net "M_C_DQ<41>")
	)
	(segment
		(start 291.285168 -5.941822)
		(end 291.910008 -6.566662)
		(width 0.14224)
		(layer "In4.Cu")
		(net "M_C_DQ<41>")
	)
	(segment
		(start 290.949126 -3.549904)
		(end 290.949126 -3.903726)
		(width 0.14224)
		(layer "In4.Cu")
		(net "M_C_DQ<41>")
	)
	(segment
		(start 279.4889 -50.701194)
		(end 277.888954 -52.30114)
		(width 0.0889)
		(layer "In4.Cu")
		(net "M_C_DQ<41>")
	)
	(segment
		(start 277.997158 -56.5912)
		(end 278.001984 -56.599836)
		(width 0.0889)
		(layer "In4.Cu")
		(net "M_C_DQ<41>")
	)
	(segment
		(start 290.949126 -3.903726)
		(end 291.285168 -4.239768)
		(width 0.14224)
		(layer "In4.Cu")
		(net "M_C_DQ<41>")
	)
	(arc
		(start 278.055578 -58.057542)
		(mid 278.038943 -58.105605)
		(end 278.018748 -58.152284)
		(width 0.0889)
		(layer "In4.Cu")
		(net "M_C_DQ<41>")
	)
	(arc
		(start 278.001984 -56.199786)
		(mid 277.948514 -56.394849)
		(end 277.997158 -56.5912)
		(width 0.0889)
		(layer "In4.Cu")
		(net "M_C_DQ<41>")
	)
	(arc
		(start 278.623014 -59.079892)
		(mid 278.662586 -59.123075)
		(end 278.695404 -59.171586)
		(width 0.0889)
		(layer "In4.Cu")
		(net "M_C_DQ<41>")
	)
	(arc
		(start 278.008334 -57.601104)
		(mid 278.078034 -57.824548)
		(end 278.055578 -58.057542)
		(width 0.0889)
		(layer "In4.Cu")
		(net "M_C_DQ<41>")
	)
	(arc
		(start 278.008334 -56.610504)
		(mid 278.081132 -56.901267)
		(end 278.001984 -57.190386)
		(width 0.0889)
		(layer "In4.Cu")
		(net "M_C_DQ<41>")
	)
	(arc
		(start 278.001984 -58.180986)
		(mid 277.973758 -58.521465)
		(end 278.218646 -58.759598)
		(width 0.0889)
		(layer "In4.Cu")
		(net "M_C_DQ<41>")
	)
	(arc
		(start 278.008334 -55.619904)
		(mid 278.081132 -55.910667)
		(end 278.001984 -56.199786)
		(width 0.0889)
		(layer "In4.Cu")
		(net "M_C_DQ<41>")
	)
	(arc
		(start 278.333708 -59.962288)
		(mid 278.00079 -60.164279)
		(end 277.997158 -60.5536)
		(width 0.0889)
		(layer "In4.Cu")
		(net "M_C_DQ<41>")
	)
	(arc
		(start 278.001984 -57.190386)
		(mid 277.948514 -57.385449)
		(end 277.997158 -57.5818)
		(width 0.0889)
		(layer "In4.Cu")
		(net "M_C_DQ<41>")
	)
	(arc
		(start 278.008334 -53.638704)
		(mid 278.087556 -53.927822)
		(end 278.014684 -54.218586)
		(width 0.0889)
		(layer "In4.Cu")
		(net "M_C_DQ<41>")
	)
	(arc
		(start 278.003508 -54.23789)
		(mid 277.954753 -54.434242)
		(end 278.008334 -54.629304)
		(width 0.0889)
		(layer "In4.Cu")
		(net "M_C_DQ<41>")
	)
	(arc
		(start 278.56307 -59.03341)
		(mid 278.594148 -59.055225)
		(end 278.623014 -59.079892)
		(width 0.0889)
		(layer "In4.Cu")
		(net "M_C_DQ<41>")
	)
	(arc
		(start 278.67864 -59.600338)
		(mid 278.537806 -59.796782)
		(end 278.361648 -59.962288)
		(width 0.0889)
		(layer "In4.Cu")
		(net "M_C_DQ<41>")
	)
	(arc
		(start 278.001984 -55.209186)
		(mid 277.948514 -55.404249)
		(end 277.997158 -55.6006)
		(width 0.0889)
		(layer "In4.Cu")
		(net "M_C_DQ<41>")
	)
	(arc
		(start 278.008334 -54.629304)
		(mid 278.081132 -54.920067)
		(end 278.001984 -55.209186)
		(width 0.0889)
		(layer "In4.Cu")
		(net "M_C_DQ<41>")
	)
	(arc
		(start 278.695404 -59.171586)
		(mid 278.748903 -59.371484)
		(end 278.695404 -59.571382)
		(width 0.0889)
		(layer "In4.Cu")
		(net "M_C_DQ<41>")
	)
	(arc
		(start 278.218646 -58.759598)
		(mid 278.38352 -58.905734)
		(end 278.56307 -59.03341)
		(width 0.0889)
		(layer "In4.Cu")
		(net "M_C_DQ<41>")
	)
	(segment
		(start 291.227256 1.4986)
		(end 290.74999 1.975866)
		(width 0.14224)
		(layer "In11.Cu")
		(net "M_C_DQ<41>")
	)
	(segment
		(start 291.95268 1.128776)
		(end 291.582856 1.4986)
		(width 0.14224)
		(layer "In11.Cu")
		(net "M_C_DQ<41>")
	)
	(segment
		(start 291.796216 -2.702814)
		(end 291.796216 0.630936)
		(width 0.14224)
		(layer "In11.Cu")
		(net "M_C_DQ<41>")
	)
	(segment
		(start 290.74999 1.975866)
		(end 290.74999 2.514854)
		(width 0.14224)
		(layer "In11.Cu")
		(net "M_C_DQ<41>")
	)
	(segment
		(start 291.95268 0.7874)
		(end 291.95268 1.128776)
		(width 0.14224)
		(layer "In11.Cu")
		(net "M_C_DQ<41>")
	)
	(segment
		(start 291.422074 -3.076956)
		(end 291.796216 -2.702814)
		(width 0.14224)
		(layer "In11.Cu")
		(net "M_C_DQ<41>")
	)
	(segment
		(start 291.582856 1.4986)
		(end 291.227256 1.4986)
		(width 0.14224)
		(layer "In11.Cu")
		(net "M_C_DQ<41>")
	)
	(segment
		(start 291.796216 0.630936)
		(end 291.95268 0.7874)
		(width 0.14224)
		(layer "In11.Cu")
		(net "M_C_DQ<41>")
	)
	(segment
		(start 278.920194 -59.371484)
		(end 278.348694 -59.371484)
		(width 0.0889)
		(layer "F.Cu")
		(net "M_C_DQ<40>")
	)
	(segment
		(start 291.599874 -0.821182)
		(end 291.422074 1.0414)
		(width 0.1651)
		(layer "F.Cu")
		(net "M_C_DQ<40>")
	)
	(segment
		(start 291.600382 -0.821182)
		(end 291.599874 -0.821182)
		(width 0.1651)
		(layer "F.Cu")
		(net "M_C_DQ<40>")
	)
	(via
		(at 290.74999 -4.357878)
		(size 0.508)
		(drill 0.254)
		(layers "F.Cu" "B.Cu")
		(net "M_C_DQ<40>")
	)
	(via
		(at 278.348694 -59.371484)
		(size 0.508)
		(drill 0.254)
		(layers "F.Cu" "B.Cu")
		(net "M_C_DQ<40>")
	)
	(via
		(at 291.422074 1.0414)
		(size 0.508)
		(drill 0.254)
		(layers "F.Cu" "B.Cu")
		(net "M_C_DQ<40>")
	)
	(segment
		(start 290.750498 -5.621782)
		(end 290.74999 -5.621782)
		(width 0.1651)
		(layer "B.Cu")
		(net "M_C_DQ<40>")
	)
	(segment
		(start 290.74999 -5.621782)
		(end 290.74999 -4.357878)
		(width 0.1651)
		(layer "B.Cu")
		(net "M_C_DQ<40>")
	)
	(segment
		(start 277.836884 -57.685686)
		(end 277.84171 -57.694322)
		(width 0.0889)
		(layer "In4.Cu")
		(net "M_C_DQ<40>")
	)
	(segment
		(start 286.689292 -35.306508)
		(end 286.402018 -35.593782)
		(width 0.14224)
		(layer "In4.Cu")
		(net "M_C_DQ<40>")
	)
	(segment
		(start 286.689292 -35.01898)
		(end 286.689292 -35.306508)
		(width 0.14224)
		(layer "In4.Cu")
		(net "M_C_DQ<40>")
	)
	(segment
		(start 291.275008 -21.682456)
		(end 290.932108 -22.025356)
		(width 0.14224)
		(layer "In4.Cu")
		(net "M_C_DQ<40>")
	)
	(segment
		(start 286.402018 -35.593782)
		(end 286.11449 -35.593782)
		(width 0.14224)
		(layer "In4.Cu")
		(net "M_C_DQ<40>")
	)
	(segment
		(start 284.999684 -35.724084)
		(end 285.515812 -36.240212)
		(width 0.14224)
		(layer "In4.Cu")
		(net "M_C_DQ<40>")
	)
	(segment
		(start 287.003236 -34.126932)
		(end 286.802068 -34.126932)
		(width 0.14224)
		(layer "In4.Cu")
		(net "M_C_DQ<40>")
	)
	(segment
		(start 291.275008 -18.657062)
		(end 291.275008 -21.682456)
		(width 0.14224)
		(layer "In4.Cu")
		(net "M_C_DQ<40>")
	)
	(segment
		(start 285.622238 -35.10153)
		(end 285.42107 -35.10153)
		(width 0.14224)
		(layer "In4.Cu")
		(net "M_C_DQ<40>")
	)
	(segment
		(start 277.830534 -56.684418)
		(end 277.836884 -56.695086)
		(width 0.0889)
		(layer "In4.Cu")
		(net "M_C_DQ<40>")
	)
	(segment
		(start 290.932108 -22.025356)
		(end 290.932108 -23.092156)
		(width 0.14224)
		(layer "In4.Cu")
		(net "M_C_DQ<40>")
	)
	(segment
		(start 290.74999 -6.295644)
		(end 291.224208 -6.769862)
		(width 0.14224)
		(layer "In4.Cu")
		(net "M_C_DQ<40>")
	)
	(segment
		(start 287.198562 -33.172654)
		(end 287.86709 -33.841182)
		(width 0.14224)
		(layer "In4.Cu")
		(net "M_C_DQ<40>")
	)
	(segment
		(start 287.198562 -32.885126)
		(end 287.198562 -33.172654)
		(width 0.14224)
		(layer "In4.Cu")
		(net "M_C_DQ<40>")
	)
	(segment
		(start 291.2618 -28.3718)
		(end 291.2618 -28.821888)
		(width 0.14224)
		(layer "In4.Cu")
		(net "M_C_DQ<40>")
	)
	(segment
		(start 291.224208 -7.225538)
		(end 290.932108 -7.517638)
		(width 0.14224)
		(layer "In4.Cu")
		(net "M_C_DQ<40>")
	)
	(segment
		(start 285.42107 -35.10153)
		(end 284.999684 -35.522916)
		(width 0.14224)
		(layer "In4.Cu")
		(net "M_C_DQ<40>")
	)
	(segment
		(start 279.2984 -49.59858)
		(end 279.2984 -50.6222)
		(width 0.0889)
		(layer "In4.Cu")
		(net "M_C_DQ<40>")
	)
	(segment
		(start 277.836884 -55.704486)
		(end 277.84171 -55.713122)
		(width 0.0889)
		(layer "In4.Cu")
		(net "M_C_DQ<40>")
	)
	(segment
		(start 280.4922 -41.551352)
		(end 280.4922 -46.9392)
		(width 0.14224)
		(layer "In4.Cu")
		(net "M_C_DQ<40>")
	)
	(segment
		(start 290.932108 -12.424156)
		(end 290.932108 -13.487908)
		(width 0.14224)
		(layer "In4.Cu")
		(net "M_C_DQ<40>")
	)
	(segment
		(start 287.86709 -34.12871)
		(end 287.579816 -34.415984)
		(width 0.14224)
		(layer "In4.Cu")
		(net "M_C_DQ<40>")
	)
	(segment
		(start 284.999684 -35.522916)
		(end 284.999684 -35.724084)
		(width 0.14224)
		(layer "In4.Cu")
		(net "M_C_DQ<40>")
	)
	(segment
		(start 286.40024 -34.52876)
		(end 286.40024 -34.729928)
		(width 0.14224)
		(layer "In4.Cu")
		(net "M_C_DQ<40>")
	)
	(segment
		(start 290.74999 -4.357878)
		(end 290.74999 -6.295644)
		(width 0.14224)
		(layer "In4.Cu")
		(net "M_C_DQ<40>")
	)
	(segment
		(start 290.924996 -26.968196)
		(end 290.924996 -28.034996)
		(width 0.14224)
		(layer "In4.Cu")
		(net "M_C_DQ<40>")
	)
	(segment
		(start 280.4922 -46.9392)
		(end 280.73858 -47.18558)
		(width 0.0889)
		(layer "In4.Cu")
		(net "M_C_DQ<40>")
	)
	(segment
		(start 277.846536 -54.123336)
		(end 277.84171 -54.131972)
		(width 0.0889)
		(layer "In4.Cu")
		(net "M_C_DQ<40>")
	)
	(segment
		(start 290.932108 -8.687562)
		(end 291.275008 -9.030462)
		(width 0.14224)
		(layer "In4.Cu")
		(net "M_C_DQ<40>")
	)
	(segment
		(start 290.932108 -23.092156)
		(end 291.275008 -23.435056)
		(width 0.14224)
		(layer "In4.Cu")
		(net "M_C_DQ<40>")
	)
	(segment
		(start 291.275008 -23.435056)
		(end 291.275008 -26.618184)
		(width 0.14224)
		(layer "In4.Cu")
		(net "M_C_DQ<40>")
	)
	(segment
		(start 277.836884 -58.67654)
		(end 277.853394 -58.705496)
		(width 0.0889)
		(layer "In4.Cu")
		(net "M_C_DQ<40>")
	)
	(segment
		(start 279.2984 -50.6222)
		(end 277.698454 -52.222146)
		(width 0.0889)
		(layer "In4.Cu")
		(net "M_C_DQ<40>")
	)
	(segment
		(start 291.275008 -16.775938)
		(end 290.932108 -17.118838)
		(width 0.14224)
		(layer "In4.Cu")
		(net "M_C_DQ<40>")
	)
	(segment
		(start 291.2618 -28.821888)
		(end 287.198562 -32.885126)
		(width 0.14224)
		(layer "In4.Cu")
		(net "M_C_DQ<40>")
	)
	(segment
		(start 280.73858 -47.18558)
		(end 280.73858 -48.1584)
		(width 0.0889)
		(layer "In4.Cu")
		(net "M_C_DQ<40>")
	)
	(segment
		(start 286.802068 -34.126932)
		(end 286.40024 -34.52876)
		(width 0.14224)
		(layer "In4.Cu")
		(net "M_C_DQ<40>")
	)
	(segment
		(start 290.932108 -7.517638)
		(end 290.932108 -8.687562)
		(width 0.14224)
		(layer "In4.Cu")
		(net "M_C_DQ<40>")
	)
	(segment
		(start 291.275008 -9.030462)
		(end 291.275008 -12.081256)
		(width 0.14224)
		(layer "In4.Cu")
		(net "M_C_DQ<40>")
	)
	(segment
		(start 291.275008 -26.618184)
		(end 290.924996 -26.968196)
		(width 0.14224)
		(layer "In4.Cu")
		(net "M_C_DQ<40>")
	)
	(segment
		(start 277.84171 -54.131972)
		(end 277.83536 -54.14264)
		(width 0.0889)
		(layer "In4.Cu")
		(net "M_C_DQ<40>")
	)
	(segment
		(start 290.932108 -17.118838)
		(end 290.932108 -18.314162)
		(width 0.14224)
		(layer "In4.Cu")
		(net "M_C_DQ<40>")
	)
	(segment
		(start 287.292288 -34.415984)
		(end 287.003236 -34.126932)
		(width 0.14224)
		(layer "In4.Cu")
		(net "M_C_DQ<40>")
	)
	(segment
		(start 290.924996 -28.034996)
		(end 291.2618 -28.3718)
		(width 0.14224)
		(layer "In4.Cu")
		(net "M_C_DQ<40>")
	)
	(segment
		(start 285.515812 -36.240212)
		(end 285.515812 -36.52774)
		(width 0.14224)
		(layer "In4.Cu")
		(net "M_C_DQ<40>")
	)
	(segment
		(start 277.698454 -53.475128)
		(end 277.84171 -53.731922)
		(width 0.0889)
		(layer "In4.Cu")
		(net "M_C_DQ<40>")
	)
	(segment
		(start 277.836884 -56.695086)
		(end 277.84171 -56.703722)
		(width 0.0889)
		(layer "In4.Cu")
		(net "M_C_DQ<40>")
	)
	(segment
		(start 291.224208 -6.769862)
		(end 291.224208 -7.225538)
		(width 0.14224)
		(layer "In4.Cu")
		(net "M_C_DQ<40>")
	)
	(segment
		(start 277.830534 -57.675018)
		(end 277.836884 -57.685686)
		(width 0.0889)
		(layer "In4.Cu")
		(net "M_C_DQ<40>")
	)
	(segment
		(start 280.73858 -48.1584)
		(end 279.2984 -49.59858)
		(width 0.0889)
		(layer "In4.Cu")
		(net "M_C_DQ<40>")
	)
	(segment
		(start 291.275008 -12.081256)
		(end 290.932108 -12.424156)
		(width 0.14224)
		(layer "In4.Cu")
		(net "M_C_DQ<40>")
	)
	(segment
		(start 285.515812 -36.52774)
		(end 280.4922 -41.551352)
		(width 0.14224)
		(layer "In4.Cu")
		(net "M_C_DQ<40>")
	)
	(segment
		(start 286.40024 -34.729928)
		(end 286.689292 -35.01898)
		(width 0.14224)
		(layer "In4.Cu")
		(net "M_C_DQ<40>")
	)
	(segment
		(start 277.853394 -58.705496)
		(end 278.348694 -59.371484)
		(width 0.0889)
		(layer "In4.Cu")
		(net "M_C_DQ<40>")
	)
	(segment
		(start 291.275008 -13.830808)
		(end 291.275008 -16.775938)
		(width 0.14224)
		(layer "In4.Cu")
		(net "M_C_DQ<40>")
	)
	(segment
		(start 277.830534 -55.693818)
		(end 277.836884 -55.704486)
		(width 0.0889)
		(layer "In4.Cu")
		(net "M_C_DQ<40>")
	)
	(segment
		(start 287.86709 -33.841182)
		(end 287.86709 -34.12871)
		(width 0.14224)
		(layer "In4.Cu")
		(net "M_C_DQ<40>")
	)
	(segment
		(start 290.932108 -18.314162)
		(end 291.275008 -18.657062)
		(width 0.14224)
		(layer "In4.Cu")
		(net "M_C_DQ<40>")
	)
	(segment
		(start 286.11449 -35.593782)
		(end 285.622238 -35.10153)
		(width 0.14224)
		(layer "In4.Cu")
		(net "M_C_DQ<40>")
	)
	(segment
		(start 287.579816 -34.415984)
		(end 287.292288 -34.415984)
		(width 0.14224)
		(layer "In4.Cu")
		(net "M_C_DQ<40>")
	)
	(segment
		(start 277.698454 -52.222146)
		(end 277.698454 -53.475128)
		(width 0.0889)
		(layer "In4.Cu")
		(net "M_C_DQ<40>")
	)
	(segment
		(start 290.932108 -13.487908)
		(end 291.275008 -13.830808)
		(width 0.14224)
		(layer "In4.Cu")
		(net "M_C_DQ<40>")
	)
	(arc
		(start 277.84171 -54.722522)
		(mid 277.890465 -54.918874)
		(end 277.836884 -55.113936)
		(width 0.0889)
		(layer "In4.Cu")
		(net "M_C_DQ<40>")
	)
	(arc
		(start 277.84171 -53.731922)
		(mid 277.89518 -53.926985)
		(end 277.846536 -54.123336)
		(width 0.0889)
		(layer "In4.Cu")
		(net "M_C_DQ<40>")
	)
	(arc
		(start 277.83536 -54.14264)
		(mid 277.762562 -54.433403)
		(end 277.84171 -54.722522)
		(width 0.0889)
		(layer "In4.Cu")
		(net "M_C_DQ<40>")
	)
	(arc
		(start 277.84171 -57.694322)
		(mid 277.890465 -57.890674)
		(end 277.836884 -58.085736)
		(width 0.0889)
		(layer "In4.Cu")
		(net "M_C_DQ<40>")
	)
	(arc
		(start 277.84171 -55.713122)
		(mid 277.890465 -55.909474)
		(end 277.836884 -56.104536)
		(width 0.0889)
		(layer "In4.Cu")
		(net "M_C_DQ<40>")
	)
	(arc
		(start 277.84171 -56.703722)
		(mid 277.890465 -56.900074)
		(end 277.836884 -57.095136)
		(width 0.0889)
		(layer "In4.Cu")
		(net "M_C_DQ<40>")
	)
	(arc
		(start 277.836884 -57.095136)
		(mid 277.757662 -57.384254)
		(end 277.830534 -57.675018)
		(width 0.0889)
		(layer "In4.Cu")
		(net "M_C_DQ<40>")
	)
	(arc
		(start 277.836884 -55.113936)
		(mid 277.757662 -55.403054)
		(end 277.830534 -55.693818)
		(width 0.0889)
		(layer "In4.Cu")
		(net "M_C_DQ<40>")
	)
	(arc
		(start 277.836884 -58.085736)
		(mid 277.757753 -58.381138)
		(end 277.836884 -58.67654)
		(width 0.0889)
		(layer "In4.Cu")
		(net "M_C_DQ<40>")
	)
	(arc
		(start 277.836884 -56.104536)
		(mid 277.757662 -56.393654)
		(end 277.830534 -56.684418)
		(width 0.0889)
		(layer "In4.Cu")
		(net "M_C_DQ<40>")
	)
	(segment
		(start 290.465256 -3.3274)
		(end 291.201856 -2.5908)
		(width 0.14224)
		(layer "In11.Cu")
		(net "M_C_DQ<40>")
	)
	(segment
		(start 291.201856 -2.5908)
		(end 291.201856 -2.090928)
		(width 0.14224)
		(layer "In11.Cu")
		(net "M_C_DQ<40>")
	)
	(segment
		(start 291.201856 0.821182)
		(end 291.422074 1.0414)
		(width 0.14224)
		(layer "In11.Cu")
		(net "M_C_DQ<40>")
	)
	(segment
		(start 291.201856 -2.090928)
		(end 290.812474 -1.701546)
		(width 0.14224)
		(layer "In11.Cu")
		(net "M_C_DQ<40>")
	)
	(segment
		(start 290.787074 -0.178054)
		(end 291.201856 0.236728)
		(width 0.14224)
		(layer "In11.Cu")
		(net "M_C_DQ<40>")
	)
	(segment
		(start 290.465256 -4.073144)
		(end 290.465256 -3.3274)
		(width 0.14224)
		(layer "In11.Cu")
		(net "M_C_DQ<40>")
	)
	(segment
		(start 290.787074 -0.508)
		(end 290.787074 -0.178054)
		(width 0.14224)
		(layer "In11.Cu")
		(net "M_C_DQ<40>")
	)
	(segment
		(start 290.812474 -1.701546)
		(end 290.812474 -1.397)
		(width 0.14224)
		(layer "In11.Cu")
		(net "M_C_DQ<40>")
	)
	(segment
		(start 291.129974 -1.0795)
		(end 291.129974 -0.8509)
		(width 0.14224)
		(layer "In11.Cu")
		(net "M_C_DQ<40>")
	)
	(segment
		(start 291.201856 0.236728)
		(end 291.201856 0.821182)
		(width 0.14224)
		(layer "In11.Cu")
		(net "M_C_DQ<40>")
	)
	(segment
		(start 290.812474 -1.397)
		(end 291.129974 -1.0795)
		(width 0.14224)
		(layer "In11.Cu")
		(net "M_C_DQ<40>")
	)
	(segment
		(start 290.74999 -4.357878)
		(end 290.465256 -4.073144)
		(width 0.14224)
		(layer "In11.Cu")
		(net "M_C_DQ<40>")
	)
	(segment
		(start 291.129974 -0.8509)
		(end 290.787074 -0.508)
		(width 0.14224)
		(layer "In11.Cu")
		(net "M_C_DQ<40>")
	)
	(segment
		(start 204.049884 3.778758)
		(end 204.049884 2.514854)
		(width 0.1651)
		(layer "F.Cu")
		(net "M_C_DQ<3>")
	)
	(segment
		(start 204.050392 3.778758)
		(end 204.049884 3.778758)
		(width 0.1651)
		(layer "F.Cu")
		(net "M_C_DQ<3>")
	)
	(segment
		(start 241.334798 -63.51524)
		(end 240.763298 -63.51524)
		(width 0.0889)
		(layer "F.Cu")
		(net "M_C_DQ<3>")
	)
	(via
		(at 204.899768 -3.076956)
		(size 0.508)
		(drill 0.254)
		(layers "F.Cu" "B.Cu")
		(net "M_C_DQ<3>")
	)
	(via
		(at 240.763298 -63.51524)
		(size 0.508)
		(drill 0.254)
		(layers "F.Cu" "B.Cu")
		(net "M_C_DQ<3>")
	)
	(via
		(at 204.049884 2.514854)
		(size 0.508)
		(drill 0.254)
		(layers "F.Cu" "B.Cu")
		(net "M_C_DQ<3>")
	)
	(segment
		(start 204.899768 -1.021842)
		(end 204.899768 -3.076956)
		(width 0.1651)
		(layer "B.Cu")
		(net "M_C_DQ<3>")
	)
	(segment
		(start 204.900276 -1.021842)
		(end 204.899768 -1.021842)
		(width 0.1651)
		(layer "B.Cu")
		(net "M_C_DQ<3>")
	)
	(segment
		(start 222.149162 -55.653686)
		(end 222.149162 -55.872634)
		(width 0.14224)
		(layer "In11.Cu")
		(net "M_C_DQ<3>")
	)
	(segment
		(start 220.72346 -52.914296)
		(end 220.942916 -53.133752)
		(width 0.14224)
		(layer "In11.Cu")
		(net "M_C_DQ<3>")
	)
	(segment
		(start 234.735878 -61.438536)
		(end 234.771438 -61.438536)
		(width 0.0889)
		(layer "In11.Cu")
		(net "M_C_DQ<3>")
	)
	(segment
		(start 205.267052 -6.512052)
		(end 205.267052 -7.289546)
		(width 0.14224)
		(layer "In11.Cu")
		(net "M_C_DQ<3>")
	)
	(segment
		(start 221.819724 -54.01056)
		(end 221.819724 -54.229508)
		(width 0.14224)
		(layer "In11.Cu")
		(net "M_C_DQ<3>")
	)
	(segment
		(start 205.267052 -7.289546)
		(end 205.406752 -7.429246)
		(width 0.14224)
		(layer "In11.Cu")
		(net "M_C_DQ<3>")
	)
	(segment
		(start 205.384146 -13.577062)
		(end 205.267052 -13.694156)
		(width 0.14224)
		(layer "In11.Cu")
		(net "M_C_DQ<3>")
	)
	(segment
		(start 231.038146 -61.438536)
		(end 231.415336 -61.438536)
		(width 0.0889)
		(layer "In11.Cu")
		(net "M_C_DQ<3>")
	)
	(segment
		(start 205.406752 -8.867394)
		(end 205.254352 -9.019794)
		(width 0.14224)
		(layer "In11.Cu")
		(net "M_C_DQ<3>")
	)
	(segment
		(start 219.738194 -53.461666)
		(end 219.957142 -53.461666)
		(width 0.14224)
		(layer "In11.Cu")
		(net "M_C_DQ<3>")
	)
	(segment
		(start 224.011744 -56.421528)
		(end 224.230692 -56.421528)
		(width 0.14224)
		(layer "In11.Cu")
		(net "M_C_DQ<3>")
	)
	(segment
		(start 204.049884 2.514854)
		(end 204.366622 2.198116)
		(width 0.14224)
		(layer "In11.Cu")
		(net "M_C_DQ<3>")
	)
	(segment
		(start 239.893602 -63.610236)
		(end 239.941862 -63.610236)
		(width 0.0889)
		(layer "In11.Cu")
		(net "M_C_DQ<3>")
	)
	(segment
		(start 205.252574 0.581152)
		(end 205.252574 -2.72415)
		(width 0.14224)
		(layer "In11.Cu")
		(net "M_C_DQ<3>")
	)
	(segment
		(start 221.819724 -54.229508)
		(end 221.272354 -54.776878)
		(width 0.14224)
		(layer "In11.Cu")
		(net "M_C_DQ<3>")
	)
	(segment
		(start 219.518738 -53.023262)
		(end 219.518738 -53.24221)
		(width 0.14224)
		(layer "In11.Cu")
		(net "M_C_DQ<3>")
	)
	(segment
		(start 205.254352 -9.019794)
		(end 205.254352 -9.4234)
		(width 0.14224)
		(layer "In11.Cu")
		(net "M_C_DQ<3>")
	)
	(segment
		(start 205.267052 -13.694156)
		(end 205.267052 -16.890746)
		(width 0.14224)
		(layer "In11.Cu")
		(net "M_C_DQ<3>")
	)
	(segment
		(start 220.066108 -52.475892)
		(end 219.518738 -53.023262)
		(width 0.14224)
		(layer "In11.Cu")
		(net "M_C_DQ<3>")
	)
	(segment
		(start 224.230692 -56.421528)
		(end 224.450148 -56.640984)
		(width 0.14224)
		(layer "In11.Cu")
		(net "M_C_DQ<3>")
	)
	(segment
		(start 220.615002 -54.338474)
		(end 220.83395 -54.338474)
		(width 0.14224)
		(layer "In11.Cu")
		(net "M_C_DQ<3>")
	)
	(segment
		(start 220.83395 -54.338474)
		(end 221.38132 -53.791104)
		(width 0.14224)
		(layer "In11.Cu")
		(net "M_C_DQ<3>")
	)
	(segment
		(start 219.518738 -53.24221)
		(end 219.738194 -53.461666)
		(width 0.14224)
		(layer "In11.Cu")
		(net "M_C_DQ<3>")
	)
	(segment
		(start 204.416152 -3.965956)
		(end 205.267052 -4.816856)
		(width 0.14224)
		(layer "In11.Cu")
		(net "M_C_DQ<3>")
	)
	(segment
		(start 220.066108 -52.256944)
		(end 220.066108 -52.475892)
		(width 0.14224)
		(layer "In11.Cu")
		(net "M_C_DQ<3>")
	)
	(segment
		(start 221.38132 -53.791104)
		(end 221.600268 -53.791104)
		(width 0.14224)
		(layer "In11.Cu")
		(net "M_C_DQ<3>")
	)
	(segment
		(start 205.254352 -21.339048)
		(end 205.254352 -21.822156)
		(width 0.14224)
		(layer "In11.Cu")
		(net "M_C_DQ<3>")
	)
	(segment
		(start 205.252574 -2.72415)
		(end 204.899768 -3.076956)
		(width 0.14224)
		(layer "In11.Cu")
		(net "M_C_DQ<3>")
	)
	(segment
		(start 223.464374 -56.968898)
		(end 224.011744 -56.421528)
		(width 0.14224)
		(layer "In11.Cu")
		(net "M_C_DQ<3>")
	)
	(segment
		(start 220.504512 -52.914296)
		(end 220.72346 -52.914296)
		(width 0.14224)
		(layer "In11.Cu")
		(net "M_C_DQ<3>")
	)
	(segment
		(start 229.018084 -61.20892)
		(end 230.80853 -61.20892)
		(width 0.14224)
		(layer "In11.Cu")
		(net "M_C_DQ<3>")
	)
	(segment
		(start 205.254352 -11.712448)
		(end 205.254352 -12.208256)
		(width 0.14224)
		(layer "In11.Cu")
		(net "M_C_DQ<3>")
	)
	(segment
		(start 205.406752 -7.429246)
		(end 205.406752 -8.867394)
		(width 0.14224)
		(layer "In11.Cu")
		(net "M_C_DQ<3>")
	)
	(segment
		(start 205.4098 -11.557)
		(end 205.254352 -11.712448)
		(width 0.14224)
		(layer "In11.Cu")
		(net "M_C_DQ<3>")
	)
	(segment
		(start 205.434184 -37.62502)
		(end 220.066108 -52.256944)
		(width 0.14224)
		(layer "In11.Cu")
		(net "M_C_DQ<3>")
	)
	(segment
		(start 205.359 -21.2344)
		(end 205.254352 -21.339048)
		(width 0.14224)
		(layer "In11.Cu")
		(net "M_C_DQ<3>")
	)
	(segment
		(start 204.950822 1.5494)
		(end 205.408022 1.0922)
		(width 0.14224)
		(layer "In11.Cu")
		(net "M_C_DQ<3>")
	)
	(segment
		(start 225.1075 -57.298336)
		(end 229.018084 -61.20892)
		(width 0.14224)
		(layer "In11.Cu")
		(net "M_C_DQ<3>")
	)
	(segment
		(start 223.02597 -56.749442)
		(end 223.245426 -56.968898)
		(width 0.14224)
		(layer "In11.Cu")
		(net "M_C_DQ<3>")
	)
	(segment
		(start 223.245426 -56.968898)
		(end 223.464374 -56.968898)
		(width 0.14224)
		(layer "In11.Cu")
		(net "M_C_DQ<3>")
	)
	(segment
		(start 204.978 -6.223)
		(end 205.267052 -6.512052)
		(width 0.14224)
		(layer "In11.Cu")
		(net "M_C_DQ<3>")
	)
	(segment
		(start 222.368618 -56.09209)
		(end 222.587566 -56.09209)
		(width 0.14224)
		(layer "In11.Cu")
		(net "M_C_DQ<3>")
	)
	(segment
		(start 204.366622 2.198116)
		(end 204.366622 1.8796)
		(width 0.14224)
		(layer "In11.Cu")
		(net "M_C_DQ<3>")
	)
	(segment
		(start 223.353884 -55.54472)
		(end 223.57334 -55.764176)
		(width 0.14224)
		(layer "In11.Cu")
		(net "M_C_DQ<3>")
	)
	(segment
		(start 204.978 -5.8928)
		(end 204.978 -6.223)
		(width 0.14224)
		(layer "In11.Cu")
		(net "M_C_DQ<3>")
	)
	(segment
		(start 232.833926 -61.438536)
		(end 233.054398 -61.438536)
		(width 0.0889)
		(layer "In11.Cu")
		(net "M_C_DQ<3>")
	)
	(segment
		(start 219.957142 -53.461666)
		(end 220.504512 -52.914296)
		(width 0.14224)
		(layer "In11.Cu")
		(net "M_C_DQ<3>")
	)
	(segment
		(start 221.272354 -54.995826)
		(end 221.49181 -55.215282)
		(width 0.14224)
		(layer "In11.Cu")
		(net "M_C_DQ<3>")
	)
	(segment
		(start 222.477076 -54.667912)
		(end 222.696532 -54.887368)
		(width 0.14224)
		(layer "In11.Cu")
		(net "M_C_DQ<3>")
	)
	(segment
		(start 204.416152 -3.560572)
		(end 204.416152 -3.965956)
		(width 0.14224)
		(layer "In11.Cu")
		(net "M_C_DQ<3>")
	)
	(segment
		(start 222.258128 -54.667912)
		(end 222.477076 -54.667912)
		(width 0.14224)
		(layer "In11.Cu")
		(net "M_C_DQ<3>")
	)
	(segment
		(start 236.455712 -62.429136)
		(end 236.488478 -62.429136)
		(width 0.0889)
		(layer "In11.Cu")
		(net "M_C_DQ<3>")
	)
	(segment
		(start 224.450148 -56.859932)
		(end 223.902778 -57.407302)
		(width 0.14224)
		(layer "In11.Cu")
		(net "M_C_DQ<3>")
	)
	(segment
		(start 205.267052 -4.816856)
		(end 205.267052 -5.603748)
		(width 0.14224)
		(layer "In11.Cu")
		(net "M_C_DQ<3>")
	)
	(segment
		(start 237.318042 -62.92469)
		(end 237.350808 -62.92469)
		(width 0.0889)
		(layer "In11.Cu")
		(net "M_C_DQ<3>")
	)
	(segment
		(start 223.02597 -56.530494)
		(end 223.02597 -56.749442)
		(width 0.14224)
		(layer "In11.Cu")
		(net "M_C_DQ<3>")
	)
	(segment
		(start 222.587566 -56.09209)
		(end 223.134936 -55.54472)
		(width 0.14224)
		(layer "In11.Cu")
		(net "M_C_DQ<3>")
	)
	(segment
		(start 224.341182 -57.845706)
		(end 224.888552 -57.298336)
		(width 0.14224)
		(layer "In11.Cu")
		(net "M_C_DQ<3>")
	)
	(segment
		(start 223.57334 -55.764176)
		(end 223.57334 -55.983124)
		(width 0.14224)
		(layer "In11.Cu")
		(net "M_C_DQ<3>")
	)
	(segment
		(start 204.366622 1.8796)
		(end 204.696822 1.5494)
		(width 0.14224)
		(layer "In11.Cu")
		(net "M_C_DQ<3>")
	)
	(segment
		(start 223.902778 -57.407302)
		(end 223.902778 -57.62625)
		(width 0.14224)
		(layer "In11.Cu")
		(net "M_C_DQ<3>")
	)
	(segment
		(start 224.450148 -56.640984)
		(end 224.450148 -56.859932)
		(width 0.14224)
		(layer "In11.Cu")
		(net "M_C_DQ<3>")
	)
	(segment
		(start 205.4098 -9.578848)
		(end 205.4098 -11.557)
		(width 0.14224)
		(layer "In11.Cu")
		(net "M_C_DQ<3>")
	)
	(segment
		(start 205.1812 -23.911306)
		(end 205.434184 -24.16429)
		(width 0.14224)
		(layer "In11.Cu")
		(net "M_C_DQ<3>")
	)
	(segment
		(start 224.888552 -57.298336)
		(end 225.1075 -57.298336)
		(width 0.14224)
		(layer "In11.Cu")
		(net "M_C_DQ<3>")
	)
	(segment
		(start 205.254352 -9.4234)
		(end 205.4098 -9.578848)
		(width 0.14224)
		(layer "In11.Cu")
		(net "M_C_DQ<3>")
	)
	(segment
		(start 205.408022 1.0922)
		(end 205.408022 0.7366)
		(width 0.14224)
		(layer "In11.Cu")
		(net "M_C_DQ<3>")
	)
	(segment
		(start 205.432152 -23.183596)
		(end 205.1812 -23.434548)
		(width 0.14224)
		(layer "In11.Cu")
		(net "M_C_DQ<3>")
	)
	(segment
		(start 231.91089 -61.93409)
		(end 232.268268 -61.93409)
		(width 0.0889)
		(layer "In11.Cu")
		(net "M_C_DQ<3>")
	)
	(segment
		(start 205.267052 -5.603748)
		(end 204.978 -5.8928)
		(width 0.14224)
		(layer "In11.Cu")
		(net "M_C_DQ<3>")
	)
	(segment
		(start 205.254352 -18.544794)
		(end 205.254352 -19.1008)
		(width 0.14224)
		(layer "In11.Cu")
		(net "M_C_DQ<3>")
	)
	(segment
		(start 231.415336 -61.438536)
		(end 231.91089 -61.93409)
		(width 0.0889)
		(layer "In11.Cu")
		(net "M_C_DQ<3>")
	)
	(segment
		(start 205.267052 -16.890746)
		(end 205.394052 -17.017746)
		(width 0.14224)
		(layer "In11.Cu")
		(net "M_C_DQ<3>")
	)
	(segment
		(start 205.394052 -17.017746)
		(end 205.394052 -18.405094)
		(width 0.14224)
		(layer "In11.Cu")
		(net "M_C_DQ<3>")
	)
	(segment
		(start 205.434184 -24.16429)
		(end 205.434184 -37.62502)
		(width 0.14224)
		(layer "In11.Cu")
		(net "M_C_DQ<3>")
	)
	(segment
		(start 205.254352 -19.1008)
		(end 205.359 -19.205448)
		(width 0.14224)
		(layer "In11.Cu")
		(net "M_C_DQ<3>")
	)
	(segment
		(start 205.359 -19.205448)
		(end 205.359 -21.2344)
		(width 0.14224)
		(layer "In11.Cu")
		(net "M_C_DQ<3>")
	)
	(segment
		(start 220.942916 -53.3527)
		(end 220.395546 -53.90007)
		(width 0.14224)
		(layer "In11.Cu")
		(net "M_C_DQ<3>")
	)
	(segment
		(start 205.254352 -21.822156)
		(end 205.432152 -21.999956)
		(width 0.14224)
		(layer "In11.Cu")
		(net "M_C_DQ<3>")
	)
	(segment
		(start 239.168432 -63.91529)
		(end 239.666272 -63.688976)
		(width 0.0889)
		(layer "In11.Cu")
		(net "M_C_DQ<3>")
	)
	(segment
		(start 205.384146 -12.33805)
		(end 205.384146 -13.577062)
		(width 0.14224)
		(layer "In11.Cu")
		(net "M_C_DQ<3>")
	)
	(segment
		(start 205.432152 -21.999956)
		(end 205.432152 -23.183596)
		(width 0.14224)
		(layer "In11.Cu")
		(net "M_C_DQ<3>")
	)
	(segment
		(start 230.80853 -61.20892)
		(end 231.038146 -61.438536)
		(width 0.0889)
		(layer "In11.Cu")
		(net "M_C_DQ<3>")
	)
	(segment
		(start 221.600268 -53.791104)
		(end 221.819724 -54.01056)
		(width 0.14224)
		(layer "In11.Cu")
		(net "M_C_DQ<3>")
	)
	(segment
		(start 221.272354 -54.776878)
		(end 221.272354 -54.995826)
		(width 0.14224)
		(layer "In11.Cu")
		(net "M_C_DQ<3>")
	)
	(segment
		(start 221.710758 -55.215282)
		(end 222.258128 -54.667912)
		(width 0.14224)
		(layer "In11.Cu")
		(net "M_C_DQ<3>")
	)
	(segment
		(start 223.57334 -55.983124)
		(end 223.02597 -56.530494)
		(width 0.14224)
		(layer "In11.Cu")
		(net "M_C_DQ<3>")
	)
	(segment
		(start 220.395546 -53.90007)
		(end 220.395546 -54.119018)
		(width 0.14224)
		(layer "In11.Cu")
		(net "M_C_DQ<3>")
	)
	(segment
		(start 223.134936 -55.54472)
		(end 223.353884 -55.54472)
		(width 0.14224)
		(layer "In11.Cu")
		(net "M_C_DQ<3>")
	)
	(segment
		(start 239.941862 -63.610236)
		(end 240.763298 -63.51524)
		(width 0.0889)
		(layer "In11.Cu")
		(net "M_C_DQ<3>")
	)
	(segment
		(start 204.696822 1.5494)
		(end 204.950822 1.5494)
		(width 0.14224)
		(layer "In11.Cu")
		(net "M_C_DQ<3>")
	)
	(segment
		(start 205.1812 -23.434548)
		(end 205.1812 -23.911306)
		(width 0.14224)
		(layer "In11.Cu")
		(net "M_C_DQ<3>")
	)
	(segment
		(start 220.942916 -53.133752)
		(end 220.942916 -53.3527)
		(width 0.14224)
		(layer "In11.Cu")
		(net "M_C_DQ<3>")
	)
	(segment
		(start 221.49181 -55.215282)
		(end 221.710758 -55.215282)
		(width 0.14224)
		(layer "In11.Cu")
		(net "M_C_DQ<3>")
	)
	(segment
		(start 235.601002 -61.93409)
		(end 235.633768 -61.93409)
		(width 0.0889)
		(layer "In11.Cu")
		(net "M_C_DQ<3>")
	)
	(segment
		(start 238.172752 -63.419736)
		(end 238.205518 -63.419736)
		(width 0.0889)
		(layer "In11.Cu")
		(net "M_C_DQ<3>")
	)
	(segment
		(start 205.408022 0.7366)
		(end 205.252574 0.581152)
		(width 0.14224)
		(layer "In11.Cu")
		(net "M_C_DQ<3>")
	)
	(segment
		(start 205.254352 -12.208256)
		(end 205.384146 -12.33805)
		(width 0.14224)
		(layer "In11.Cu")
		(net "M_C_DQ<3>")
	)
	(segment
		(start 205.394052 -18.405094)
		(end 205.254352 -18.544794)
		(width 0.14224)
		(layer "In11.Cu")
		(net "M_C_DQ<3>")
	)
	(segment
		(start 222.696532 -55.106316)
		(end 222.149162 -55.653686)
		(width 0.14224)
		(layer "In11.Cu")
		(net "M_C_DQ<3>")
	)
	(segment
		(start 222.696532 -54.887368)
		(end 222.696532 -55.106316)
		(width 0.14224)
		(layer "In11.Cu")
		(net "M_C_DQ<3>")
	)
	(segment
		(start 239.035082 -63.91529)
		(end 239.168432 -63.91529)
		(width 0.0889)
		(layer "In11.Cu")
		(net "M_C_DQ<3>")
	)
	(segment
		(start 204.899768 -3.076956)
		(end 204.416152 -3.560572)
		(width 0.14224)
		(layer "In11.Cu")
		(net "M_C_DQ<3>")
	)
	(segment
		(start 223.902778 -57.62625)
		(end 224.122234 -57.845706)
		(width 0.14224)
		(layer "In11.Cu")
		(net "M_C_DQ<3>")
	)
	(segment
		(start 220.395546 -54.119018)
		(end 220.615002 -54.338474)
		(width 0.14224)
		(layer "In11.Cu")
		(net "M_C_DQ<3>")
	)
	(segment
		(start 222.149162 -55.872634)
		(end 222.368618 -56.09209)
		(width 0.14224)
		(layer "In11.Cu")
		(net "M_C_DQ<3>")
	)
	(segment
		(start 224.122234 -57.845706)
		(end 224.341182 -57.845706)
		(width 0.14224)
		(layer "In11.Cu")
		(net "M_C_DQ<3>")
	)
	(arc
		(start 237.841028 -63.219838)
		(mid 237.981107 -63.362574)
		(end 238.172752 -63.419736)
		(width 0.0889)
		(layer "In11.Cu")
		(net "M_C_DQ<3>")
	)
	(arc
		(start 233.054398 -61.438536)
		(mid 233.339822 -61.522003)
		(end 233.548428 -61.733938)
		(width 0.0889)
		(layer "In11.Cu")
		(net "M_C_DQ<3>")
	)
	(arc
		(start 234.771438 -61.438536)
		(mid 235.056862 -61.522003)
		(end 235.265468 -61.733938)
		(width 0.0889)
		(layer "In11.Cu")
		(net "M_C_DQ<3>")
	)
	(arc
		(start 232.48493 -61.736732)
		(mid 232.63103 -61.554398)
		(end 232.833926 -61.438536)
		(width 0.0889)
		(layer "In11.Cu")
		(net "M_C_DQ<3>")
	)
	(arc
		(start 238.699548 -63.715138)
		(mid 238.841231 -63.858942)
		(end 239.035082 -63.91529)
		(width 0.0889)
		(layer "In11.Cu")
		(net "M_C_DQ<3>")
	)
	(arc
		(start 233.548428 -61.733938)
		(mid 233.895138 -61.934249)
		(end 234.241848 -61.733938)
		(width 0.0889)
		(layer "In11.Cu")
		(net "M_C_DQ<3>")
	)
	(arc
		(start 239.666272 -63.688976)
		(mid 239.773884 -63.632143)
		(end 239.893602 -63.610236)
		(width 0.0889)
		(layer "In11.Cu")
		(net "M_C_DQ<3>")
	)
	(arc
		(start 236.123988 -62.229238)
		(mid 236.264067 -62.371974)
		(end 236.455712 -62.429136)
		(width 0.0889)
		(layer "In11.Cu")
		(net "M_C_DQ<3>")
	)
	(arc
		(start 236.488478 -62.429136)
		(mid 236.773902 -62.512603)
		(end 236.982508 -62.724538)
		(width 0.0889)
		(layer "In11.Cu")
		(net "M_C_DQ<3>")
	)
	(arc
		(start 232.268268 -61.93409)
		(mid 232.393755 -61.854257)
		(end 232.48493 -61.736732)
		(width 0.0889)
		(layer "In11.Cu")
		(net "M_C_DQ<3>")
	)
	(arc
		(start 235.265468 -61.733938)
		(mid 235.407151 -61.877742)
		(end 235.601002 -61.93409)
		(width 0.0889)
		(layer "In11.Cu")
		(net "M_C_DQ<3>")
	)
	(arc
		(start 236.982508 -62.724538)
		(mid 237.124191 -62.868342)
		(end 237.318042 -62.92469)
		(width 0.0889)
		(layer "In11.Cu")
		(net "M_C_DQ<3>")
	)
	(arc
		(start 237.350808 -62.92469)
		(mid 237.634025 -63.008971)
		(end 237.841028 -63.219838)
		(width 0.0889)
		(layer "In11.Cu")
		(net "M_C_DQ<3>")
	)
	(arc
		(start 238.205518 -63.419736)
		(mid 238.490942 -63.503203)
		(end 238.699548 -63.715138)
		(width 0.0889)
		(layer "In11.Cu")
		(net "M_C_DQ<3>")
	)
	(arc
		(start 234.241848 -61.733938)
		(mid 234.450456 -61.522006)
		(end 234.735878 -61.438536)
		(width 0.0889)
		(layer "In11.Cu")
		(net "M_C_DQ<3>")
	)
	(arc
		(start 235.633768 -61.93409)
		(mid 235.916985 -62.018371)
		(end 236.123988 -62.229238)
		(width 0.0889)
		(layer "In11.Cu")
		(net "M_C_DQ<3>")
	)
	(segment
		(start 285.649924 3.778758)
		(end 285.649924 2.514854)
		(width 0.1651)
		(layer "F.Cu")
		(net "M_C_DQ<39>")
	)
	(segment
		(start 275.486114 -61.352938)
		(end 274.914614 -61.352938)
		(width 0.0889)
		(layer "F.Cu")
		(net "M_C_DQ<39>")
	)
	(segment
		(start 285.650432 3.778758)
		(end 285.649924 3.778758)
		(width 0.1651)
		(layer "F.Cu")
		(net "M_C_DQ<39>")
	)
	(via
		(at 286.499808 -3.076956)
		(size 0.508)
		(drill 0.254)
		(layers "F.Cu" "B.Cu")
		(net "M_C_DQ<39>")
	)
	(via
		(at 285.649924 2.514854)
		(size 0.508)
		(drill 0.254)
		(layers "F.Cu" "B.Cu")
		(net "M_C_DQ<39>")
	)
	(via
		(at 274.914614 -61.352938)
		(size 0.508)
		(drill 0.254)
		(layers "F.Cu" "B.Cu")
		(net "M_C_DQ<39>")
	)
	(segment
		(start 286.499808 -1.021842)
		(end 286.499808 -3.076956)
		(width 0.1651)
		(layer "B.Cu")
		(net "M_C_DQ<39>")
	)
	(segment
		(start 286.500316 -1.021842)
		(end 286.499808 -1.021842)
		(width 0.1651)
		(layer "B.Cu")
		(net "M_C_DQ<39>")
	)
	(segment
		(start 275.426424 -57.685686)
		(end 275.421598 -57.694322)
		(width 0.0889)
		(layer "In11.Cu")
		(net "M_C_DQ<39>")
	)
	(segment
		(start 287.081214 -17.093946)
		(end 287.081214 -18.353786)
		(width 0.14224)
		(layer "In11.Cu")
		(net "M_C_DQ<39>")
	)
	(segment
		(start 286.296862 1.5494)
		(end 286.550862 1.5494)
		(width 0.14224)
		(layer "In11.Cu")
		(net "M_C_DQ<39>")
	)
	(segment
		(start 275.426424 -55.704486)
		(end 275.422106 -55.712106)
		(width 0.0889)
		(layer "In11.Cu")
		(net "M_C_DQ<39>")
	)
	(segment
		(start 275.373084 -52.820316)
		(end 275.373084 -53.9242)
		(width 0.0889)
		(layer "In11.Cu")
		(net "M_C_DQ<39>")
	)
	(segment
		(start 287.274 -30.016196)
		(end 278.111712 -39.178484)
		(width 0.14224)
		(layer "In11.Cu")
		(net "M_C_DQ<39>")
	)
	(segment
		(start 286.878014 -13.694156)
		(end 286.878014 -16.890746)
		(width 0.14224)
		(layer "In11.Cu")
		(net "M_C_DQ<39>")
	)
	(segment
		(start 286.8676 -24.095456)
		(end 287.274 -24.501856)
		(width 0.14224)
		(layer "In11.Cu")
		(net "M_C_DQ<39>")
	)
	(segment
		(start 286.878014 -16.890746)
		(end 287.081214 -17.093946)
		(width 0.14224)
		(layer "In11.Cu")
		(net "M_C_DQ<39>")
	)
	(segment
		(start 276.829266 -47.274734)
		(end 276.589744 -47.514256)
		(width 0.0889)
		(layer "In11.Cu")
		(net "M_C_DQ<39>")
	)
	(segment
		(start 287.055814 -23.117556)
		(end 286.8676 -23.30577)
		(width 0.14224)
		(layer "In11.Cu")
		(net "M_C_DQ<39>")
	)
	(segment
		(start 276.829266 -44.275756)
		(end 276.829266 -47.274734)
		(width 0.14224)
		(layer "In11.Cu")
		(net "M_C_DQ<39>")
	)
	(segment
		(start 287.274 -24.501856)
		(end 287.274 -30.016196)
		(width 0.14224)
		(layer "In11.Cu")
		(net "M_C_DQ<39>")
	)
	(segment
		(start 286.852614 -18.984214)
		(end 286.9438 -19.0754)
		(width 0.14224)
		(layer "In11.Cu")
		(net "M_C_DQ<39>")
	)
	(segment
		(start 286.852614 -11.749786)
		(end 286.852614 -12.170156)
		(width 0.14224)
		(layer "In11.Cu")
		(net "M_C_DQ<39>")
	)
	(segment
		(start 287.02 -9.499346)
		(end 287.02 -11.5824)
		(width 0.14224)
		(layer "In11.Cu")
		(net "M_C_DQ<39>")
	)
	(segment
		(start 276.076156 -52.117244)
		(end 275.373084 -52.820316)
		(width 0.0889)
		(layer "In11.Cu")
		(net "M_C_DQ<39>")
	)
	(segment
		(start 275.432774 -57.675018)
		(end 275.426424 -57.685686)
		(width 0.0889)
		(layer "In11.Cu")
		(net "M_C_DQ<39>")
	)
	(segment
		(start 285.966662 1.8796)
		(end 286.296862 1.5494)
		(width 0.14224)
		(layer "In11.Cu")
		(net "M_C_DQ<39>")
	)
	(segment
		(start 286.499808 -3.076956)
		(end 286.039814 -3.53695)
		(width 0.14224)
		(layer "In11.Cu")
		(net "M_C_DQ<39>")
	)
	(segment
		(start 286.039814 -3.53695)
		(end 286.039814 -3.9497)
		(width 0.14224)
		(layer "In11.Cu")
		(net "M_C_DQ<39>")
	)
	(segment
		(start 286.9438 -21.194014)
		(end 286.852614 -21.2852)
		(width 0.14224)
		(layer "In11.Cu")
		(net "M_C_DQ<39>")
	)
	(segment
		(start 275.432774 -56.684418)
		(end 275.426424 -56.695086)
		(width 0.0889)
		(layer "In11.Cu")
		(net "M_C_DQ<39>")
	)
	(segment
		(start 286.9438 -19.0754)
		(end 286.9438 -21.194014)
		(width 0.14224)
		(layer "In11.Cu")
		(net "M_C_DQ<39>")
	)
	(segment
		(start 286.852614 -18.582386)
		(end 286.852614 -18.984214)
		(width 0.14224)
		(layer "In11.Cu")
		(net "M_C_DQ<39>")
	)
	(segment
		(start 275.422106 -55.712106)
		(end 275.421598 -55.713122)
		(width 0.0889)
		(layer "In11.Cu")
		(net "M_C_DQ<39>")
	)
	(segment
		(start 276.076156 -48.74006)
		(end 276.076156 -52.117244)
		(width 0.0889)
		(layer "In11.Cu")
		(net "M_C_DQ<39>")
	)
	(segment
		(start 286.8676 -23.30577)
		(end 286.8676 -24.095456)
		(width 0.14224)
		(layer "In11.Cu")
		(net "M_C_DQ<39>")
	)
	(segment
		(start 286.8676 -7.279132)
		(end 287.081214 -7.492746)
		(width 0.14224)
		(layer "In11.Cu")
		(net "M_C_DQ<39>")
	)
	(segment
		(start 286.852614 0.581152)
		(end 286.852614 -2.72415)
		(width 0.14224)
		(layer "In11.Cu")
		(net "M_C_DQ<39>")
	)
	(segment
		(start 286.550862 1.5494)
		(end 287.008062 1.0922)
		(width 0.14224)
		(layer "In11.Cu")
		(net "M_C_DQ<39>")
	)
	(segment
		(start 286.852614 -21.771356)
		(end 287.055814 -21.974556)
		(width 0.14224)
		(layer "In11.Cu")
		(net "M_C_DQ<39>")
	)
	(segment
		(start 287.008062 0.7366)
		(end 286.852614 0.581152)
		(width 0.14224)
		(layer "In11.Cu")
		(net "M_C_DQ<39>")
	)
	(segment
		(start 275.432774 -54.703218)
		(end 275.426424 -54.713886)
		(width 0.0889)
		(layer "In11.Cu")
		(net "M_C_DQ<39>")
	)
	(segment
		(start 276.589744 -47.514256)
		(end 276.589744 -48.226472)
		(width 0.0889)
		(layer "In11.Cu")
		(net "M_C_DQ<39>")
	)
	(segment
		(start 286.852614 -2.72415)
		(end 286.499808 -3.076956)
		(width 0.14224)
		(layer "In11.Cu")
		(net "M_C_DQ<39>")
	)
	(segment
		(start 285.649924 2.514854)
		(end 285.966662 2.198116)
		(width 0.14224)
		(layer "In11.Cu")
		(net "M_C_DQ<39>")
	)
	(segment
		(start 286.852614 -9.33196)
		(end 287.02 -9.499346)
		(width 0.14224)
		(layer "In11.Cu")
		(net "M_C_DQ<39>")
	)
	(segment
		(start 286.852614 -8.955786)
		(end 286.852614 -9.33196)
		(width 0.14224)
		(layer "In11.Cu")
		(net "M_C_DQ<39>")
	)
	(segment
		(start 276.589744 -48.226472)
		(end 276.076156 -48.74006)
		(width 0.0889)
		(layer "In11.Cu")
		(net "M_C_DQ<39>")
	)
	(segment
		(start 275.426424 -54.713886)
		(end 275.421598 -54.722522)
		(width 0.0889)
		(layer "In11.Cu")
		(net "M_C_DQ<39>")
	)
	(segment
		(start 287.02 -11.5824)
		(end 286.852614 -11.749786)
		(width 0.14224)
		(layer "In11.Cu")
		(net "M_C_DQ<39>")
	)
	(segment
		(start 287.081214 -18.353786)
		(end 286.852614 -18.582386)
		(width 0.14224)
		(layer "In11.Cu")
		(net "M_C_DQ<39>")
	)
	(segment
		(start 286.852614 -21.2852)
		(end 286.852614 -21.771356)
		(width 0.14224)
		(layer "In11.Cu")
		(net "M_C_DQ<39>")
	)
	(segment
		(start 286.8676 -4.777486)
		(end 286.8676 -7.279132)
		(width 0.14224)
		(layer "In11.Cu")
		(net "M_C_DQ<39>")
	)
	(segment
		(start 275.261324 -60.561982)
		(end 274.914614 -61.352938)
		(width 0.0889)
		(layer "In11.Cu")
		(net "M_C_DQ<39>")
	)
	(segment
		(start 286.987996 -12.305538)
		(end 286.987996 -13.584174)
		(width 0.14224)
		(layer "In11.Cu")
		(net "M_C_DQ<39>")
	)
	(segment
		(start 278.111712 -42.99331)
		(end 276.829266 -44.275756)
		(width 0.14224)
		(layer "In11.Cu")
		(net "M_C_DQ<39>")
	)
	(segment
		(start 287.081214 -7.492746)
		(end 287.081214 -8.727186)
		(width 0.14224)
		(layer "In11.Cu")
		(net "M_C_DQ<39>")
	)
	(segment
		(start 278.111712 -39.178484)
		(end 278.111712 -42.99331)
		(width 0.14224)
		(layer "In11.Cu")
		(net "M_C_DQ<39>")
	)
	(segment
		(start 275.426424 -56.695086)
		(end 275.421598 -56.703722)
		(width 0.0889)
		(layer "In11.Cu")
		(net "M_C_DQ<39>")
	)
	(segment
		(start 275.432774 -55.693818)
		(end 275.426424 -55.704486)
		(width 0.0889)
		(layer "In11.Cu")
		(net "M_C_DQ<39>")
	)
	(segment
		(start 287.055814 -21.974556)
		(end 287.055814 -23.117556)
		(width 0.14224)
		(layer "In11.Cu")
		(net "M_C_DQ<39>")
	)
	(segment
		(start 285.966662 2.198116)
		(end 285.966662 1.8796)
		(width 0.14224)
		(layer "In11.Cu")
		(net "M_C_DQ<39>")
	)
	(segment
		(start 287.008062 1.0922)
		(end 287.008062 0.7366)
		(width 0.14224)
		(layer "In11.Cu")
		(net "M_C_DQ<39>")
	)
	(segment
		(start 286.039814 -3.9497)
		(end 286.8676 -4.777486)
		(width 0.14224)
		(layer "In11.Cu")
		(net "M_C_DQ<39>")
	)
	(segment
		(start 287.081214 -8.727186)
		(end 286.852614 -8.955786)
		(width 0.14224)
		(layer "In11.Cu")
		(net "M_C_DQ<39>")
	)
	(segment
		(start 286.852614 -12.170156)
		(end 286.987996 -12.305538)
		(width 0.14224)
		(layer "In11.Cu")
		(net "M_C_DQ<39>")
	)
	(segment
		(start 286.987996 -13.584174)
		(end 286.878014 -13.694156)
		(width 0.14224)
		(layer "In11.Cu")
		(net "M_C_DQ<39>")
	)
	(arc
		(start 275.426424 -55.113936)
		(mid 275.505646 -55.403054)
		(end 275.432774 -55.693818)
		(width 0.0889)
		(layer "In11.Cu")
		(net "M_C_DQ<39>")
	)
	(arc
		(start 275.308822 -60.293504)
		(mid 275.308605 -60.431899)
		(end 275.261324 -60.561982)
		(width 0.0889)
		(layer "In11.Cu")
		(net "M_C_DQ<39>")
	)
	(arc
		(start 275.421598 -56.703722)
		(mid 275.372843 -56.900074)
		(end 275.426424 -57.095136)
		(width 0.0889)
		(layer "In11.Cu")
		(net "M_C_DQ<39>")
	)
	(arc
		(start 275.421598 -57.694322)
		(mid 275.372904 -57.89053)
		(end 275.426424 -58.085482)
		(width 0.0889)
		(layer "In11.Cu")
		(net "M_C_DQ<39>")
	)
	(arc
		(start 275.426424 -58.085482)
		(mid 275.505555 -58.380884)
		(end 275.426424 -58.676286)
		(width 0.0889)
		(layer "In11.Cu")
		(net "M_C_DQ<39>")
	)
	(arc
		(start 275.373084 -53.9242)
		(mid 275.386646 -54.02728)
		(end 275.426424 -54.123336)
		(width 0.0889)
		(layer "In11.Cu")
		(net "M_C_DQ<39>")
	)
	(arc
		(start 275.426424 -59.076082)
		(mid 275.505555 -59.371484)
		(end 275.426424 -59.666886)
		(width 0.0889)
		(layer "In11.Cu")
		(net "M_C_DQ<39>")
	)
	(arc
		(start 275.421598 -55.713122)
		(mid 275.372843 -55.909474)
		(end 275.426424 -56.104536)
		(width 0.0889)
		(layer "In11.Cu")
		(net "M_C_DQ<39>")
	)
	(arc
		(start 275.426424 -58.676286)
		(mid 275.372925 -58.876184)
		(end 275.426424 -59.076082)
		(width 0.0889)
		(layer "In11.Cu")
		(net "M_C_DQ<39>")
	)
	(arc
		(start 275.426424 -56.104536)
		(mid 275.505646 -56.393654)
		(end 275.432774 -56.684418)
		(width 0.0889)
		(layer "In11.Cu")
		(net "M_C_DQ<39>")
	)
	(arc
		(start 275.426424 -59.666886)
		(mid 275.314178 -59.970162)
		(end 275.308822 -60.293504)
		(width 0.0889)
		(layer "In11.Cu")
		(net "M_C_DQ<39>")
	)
	(arc
		(start 275.421598 -54.722522)
		(mid 275.372843 -54.918874)
		(end 275.426424 -55.113936)
		(width 0.0889)
		(layer "In11.Cu")
		(net "M_C_DQ<39>")
	)
	(arc
		(start 275.426424 -57.095136)
		(mid 275.505646 -57.384254)
		(end 275.432774 -57.675018)
		(width 0.0889)
		(layer "In11.Cu")
		(net "M_C_DQ<39>")
	)
	(arc
		(start 275.426424 -54.123336)
		(mid 275.505646 -54.412454)
		(end 275.432774 -54.703218)
		(width 0.0889)
		(layer "In11.Cu")
		(net "M_C_DQ<39>")
	)
	(segment
		(start 286.500062 0.635)
		(end 286.500062 0.939546)
		(width 0.1651)
		(layer "F.Cu")
		(net "M_C_DQ<38>")
	)
	(segment
		(start 286.500062 -0.820928)
		(end 286.500062 0.1524)
		(width 0.1651)
		(layer "F.Cu")
		(net "M_C_DQ<38>")
	)
	(segment
		(start 286.632142 0.50292)
		(end 286.500062 0.635)
		(width 0.1651)
		(layer "F.Cu")
		(net "M_C_DQ<38>")
	)
	(segment
		(start 275.486114 -59.371484)
		(end 274.914614 -59.371484)
		(width 0.0889)
		(layer "F.Cu")
		(net "M_C_DQ<38>")
	)
	(segment
		(start 286.500062 0.1524)
		(end 286.632142 0.28448)
		(width 0.1651)
		(layer "F.Cu")
		(net "M_C_DQ<38>")
	)
	(segment
		(start 286.500316 -0.821182)
		(end 286.500062 -0.820928)
		(width 0.1651)
		(layer "F.Cu")
		(net "M_C_DQ<38>")
	)
	(segment
		(start 286.500062 0.939546)
		(end 286.499808 0.9398)
		(width 0.1651)
		(layer "F.Cu")
		(net "M_C_DQ<38>")
	)
	(segment
		(start 286.632142 0.28448)
		(end 286.632142 0.50292)
		(width 0.1651)
		(layer "F.Cu")
		(net "M_C_DQ<38>")
	)
	(via
		(at 274.914614 -59.371484)
		(size 0.508)
		(drill 0.254)
		(layers "F.Cu" "B.Cu")
		(net "M_C_DQ<38>")
	)
	(via
		(at 286.499808 0.9398)
		(size 0.508)
		(drill 0.254)
		(layers "F.Cu" "B.Cu")
		(net "M_C_DQ<38>")
	)
	(via
		(at 285.649924 -4.357878)
		(size 0.508)
		(drill 0.254)
		(layers "F.Cu" "B.Cu")
		(net "M_C_DQ<38>")
	)
	(segment
		(start 285.650432 -5.621782)
		(end 285.649924 -5.621782)
		(width 0.1651)
		(layer "B.Cu")
		(net "M_C_DQ<38>")
	)
	(segment
		(start 285.649924 -5.621782)
		(end 285.649924 -4.357878)
		(width 0.1651)
		(layer "B.Cu")
		(net "M_C_DQ<38>")
	)
	(segment
		(start 276.194266 -47.213266)
		(end 276.399244 -47.418244)
		(width 0.0889)
		(layer "In11.Cu")
		(net "M_C_DQ<38>")
	)
	(segment
		(start 275.26615 -57.5818)
		(end 275.261324 -57.590436)
		(width 0.0889)
		(layer "In11.Cu")
		(net "M_C_DQ<38>")
	)
	(segment
		(start 285.76143 -1.777746)
		(end 286.18688 -2.203196)
		(width 0.14224)
		(layer "In11.Cu")
		(net "M_C_DQ<38>")
	)
	(segment
		(start 275.20773 -59.202574)
		(end 274.914614 -59.371484)
		(width 0.0889)
		(layer "In11.Cu")
		(net "M_C_DQ<38>")
	)
	(segment
		(start 285.9532 -19.177)
		(end 285.9532 -21.1582)
		(width 0.14224)
		(layer "In11.Cu")
		(net "M_C_DQ<38>")
	)
	(segment
		(start 285.9278 -23.081742)
		(end 286.131 -23.284942)
		(width 0.14224)
		(layer "In11.Cu")
		(net "M_C_DQ<38>")
	)
	(segment
		(start 286.004 -26.480008)
		(end 286.2834 -26.480008)
		(width 0.14224)
		(layer "In11.Cu")
		(net "M_C_DQ<38>")
	)
	(segment
		(start 285.8008 -27.496008)
		(end 285.8008 -27.902408)
		(width 0.14224)
		(layer "In11.Cu")
		(net "M_C_DQ<38>")
	)
	(segment
		(start 276.349206 -42.39514)
		(end 276.71776 -42.39514)
		(width 0.14224)
		(layer "In11.Cu")
		(net "M_C_DQ<38>")
	)
	(segment
		(start 286.217614 -18.628614)
		(end 286.217614 -18.912586)
		(width 0.14224)
		(layer "In11.Cu")
		(net "M_C_DQ<38>")
	)
	(segment
		(start 285.9278 -22.06117)
		(end 285.9278 -23.081742)
		(width 0.14224)
		(layer "In11.Cu")
		(net "M_C_DQ<38>")
	)
	(segment
		(start 276.399244 -47.418244)
		(end 276.399244 -48.147478)
		(width 0.0889)
		(layer "In11.Cu")
		(net "M_C_DQ<38>")
	)
	(segment
		(start 285.8008 -26.276808)
		(end 286.004 -26.480008)
		(width 0.14224)
		(layer "In11.Cu")
		(net "M_C_DQ<38>")
	)
	(segment
		(start 286.131 -25.7556)
		(end 285.8008 -26.0858)
		(width 0.14224)
		(layer "In11.Cu")
		(net "M_C_DQ<38>")
	)
	(segment
		(start 276.194266 -40.197786)
		(end 276.194266 -42.2402)
		(width 0.14224)
		(layer "In11.Cu")
		(net "M_C_DQ<38>")
	)
	(segment
		(start 285.9532 -21.1582)
		(end 286.217614 -21.422614)
		(width 0.14224)
		(layer "In11.Cu")
		(net "M_C_DQ<38>")
	)
	(segment
		(start 285.76143 -0.387096)
		(end 285.81604 -0.44196)
		(width 0.14224)
		(layer "In11.Cu")
		(net "M_C_DQ<38>")
	)
	(segment
		(start 286.217614 -9.41324)
		(end 286.004 -9.626854)
		(width 0.14224)
		(layer "In11.Cu")
		(net "M_C_DQ<38>")
	)
	(segment
		(start 286.217614 -12.170156)
		(end 286.014414 -12.373356)
		(width 0.14224)
		(layer "In11.Cu")
		(net "M_C_DQ<38>")
	)
	(segment
		(start 285.9532 -17.05356)
		(end 285.9532 -18.3642)
		(width 0.14224)
		(layer "In11.Cu")
		(net "M_C_DQ<38>")
	)
	(segment
		(start 285.9278 -8.7376)
		(end 286.217614 -9.027414)
		(width 0.14224)
		(layer "In11.Cu")
		(net "M_C_DQ<38>")
	)
	(segment
		(start 275.261324 -58.580782)
		(end 275.261324 -58.581036)
		(width 0.0889)
		(layer "In11.Cu")
		(net "M_C_DQ<38>")
	)
	(segment
		(start 275.261324 -54.618636)
		(end 275.254974 -54.629304)
		(width 0.0889)
		(layer "In11.Cu")
		(net "M_C_DQ<38>")
	)
	(segment
		(start 276.349206 -43.18508)
		(end 276.194266 -43.34002)
		(width 0.14224)
		(layer "In11.Cu")
		(net "M_C_DQ<38>")
	)
	(segment
		(start 275.886164 -48.660558)
		(end 275.886164 -52.038504)
		(width 0.0889)
		(layer "In11.Cu")
		(net "M_C_DQ<38>")
	)
	(segment
		(start 285.414212 -4.122166)
		(end 285.649924 -4.357878)
		(width 0.14224)
		(layer "In11.Cu")
		(net "M_C_DQ<38>")
	)
	(segment
		(start 286.131 -23.284942)
		(end 286.131 -25.7556)
		(width 0.14224)
		(layer "In11.Cu")
		(net "M_C_DQ<38>")
	)
	(segment
		(start 286.125412 0.565404)
		(end 286.125412 0.287528)
		(width 0.14224)
		(layer "In11.Cu")
		(net "M_C_DQ<38>")
	)
	(segment
		(start 286.499808 0.9398)
		(end 286.125412 0.565404)
		(width 0.14224)
		(layer "In11.Cu")
		(net "M_C_DQ<38>")
	)
	(segment
		(start 286.004 -27.292808)
		(end 285.8008 -27.496008)
		(width 0.14224)
		(layer "In11.Cu")
		(net "M_C_DQ<38>")
	)
	(segment
		(start 275.261324 -57.590436)
		(end 275.254974 -57.601104)
		(width 0.0889)
		(layer "In11.Cu")
		(net "M_C_DQ<38>")
	)
	(segment
		(start 275.26615 -56.5912)
		(end 275.261324 -56.599836)
		(width 0.0889)
		(layer "In11.Cu")
		(net "M_C_DQ<38>")
	)
	(segment
		(start 276.399244 -48.147478)
		(end 275.886164 -48.660558)
		(width 0.0889)
		(layer "In11.Cu")
		(net "M_C_DQ<38>")
	)
	(segment
		(start 285.8008 -26.0858)
		(end 285.8008 -26.276808)
		(width 0.14224)
		(layer "In11.Cu")
		(net "M_C_DQ<38>")
	)
	(segment
		(start 286.4866 -26.683208)
		(end 286.4866 -27.089608)
		(width 0.14224)
		(layer "In11.Cu")
		(net "M_C_DQ<38>")
	)
	(segment
		(start 286.217614 -21.771356)
		(end 285.9278 -22.06117)
		(width 0.14224)
		(layer "In11.Cu")
		(net "M_C_DQ<38>")
	)
	(segment
		(start 275.26615 -54.61)
		(end 275.261324 -54.618636)
		(width 0.0889)
		(layer "In11.Cu")
		(net "M_C_DQ<38>")
	)
	(segment
		(start 285.414212 -3.327654)
		(end 285.414212 -4.122166)
		(width 0.14224)
		(layer "In11.Cu")
		(net "M_C_DQ<38>")
	)
	(segment
		(start 276.194266 -43.34002)
		(end 276.194266 -47.213266)
		(width 0.14224)
		(layer "In11.Cu")
		(net "M_C_DQ<38>")
	)
	(segment
		(start 285.76143 -0.076454)
		(end 285.76143 -0.387096)
		(width 0.14224)
		(layer "In11.Cu")
		(net "M_C_DQ<38>")
	)
	(segment
		(start 276.71776 -43.18508)
		(end 276.349206 -43.18508)
		(width 0.14224)
		(layer "In11.Cu")
		(net "M_C_DQ<38>")
	)
	(segment
		(start 275.886164 -52.038504)
		(end 275.182584 -52.742084)
		(width 0.0889)
		(layer "In11.Cu")
		(net "M_C_DQ<38>")
	)
	(segment
		(start 286.18688 -2.554986)
		(end 285.414212 -3.327654)
		(width 0.14224)
		(layer "In11.Cu")
		(net "M_C_DQ<38>")
	)
	(segment
		(start 286.18688 -2.203196)
		(end 286.18688 -2.554986)
		(width 0.14224)
		(layer "In11.Cu")
		(net "M_C_DQ<38>")
	)
	(segment
		(start 286.14243 -1.111504)
		(end 285.76143 -1.492504)
		(width 0.14224)
		(layer "In11.Cu")
		(net "M_C_DQ<38>")
	)
	(segment
		(start 286.217614 -18.912586)
		(end 285.9532 -19.177)
		(width 0.14224)
		(layer "In11.Cu")
		(net "M_C_DQ<38>")
	)
	(segment
		(start 286.746442 -28.308808)
		(end 286.746442 -28.715208)
		(width 0.14224)
		(layer "In11.Cu")
		(net "M_C_DQ<38>")
	)
	(segment
		(start 286.014414 -13.567156)
		(end 286.116014 -13.668756)
		(width 0.14224)
		(layer "In11.Cu")
		(net "M_C_DQ<38>")
	)
	(segment
		(start 285.8008 -29.121608)
		(end 285.8008 -29.337)
		(width 0.14224)
		(layer "In11.Cu")
		(net "M_C_DQ<38>")
	)
	(segment
		(start 285.9532 -18.3642)
		(end 286.217614 -18.628614)
		(width 0.14224)
		(layer "In11.Cu")
		(net "M_C_DQ<38>")
	)
	(segment
		(start 276.71776 -42.39514)
		(end 276.86 -42.53738)
		(width 0.14224)
		(layer "In11.Cu")
		(net "M_C_DQ<38>")
	)
	(segment
		(start 286.217614 -9.027414)
		(end 286.217614 -9.41324)
		(width 0.14224)
		(layer "In11.Cu")
		(net "M_C_DQ<38>")
	)
	(segment
		(start 285.649924 -4.357878)
		(end 286.2834 -4.991354)
		(width 0.14224)
		(layer "In11.Cu")
		(net "M_C_DQ<38>")
	)
	(segment
		(start 285.76143 -1.492504)
		(end 285.76143 -1.777746)
		(width 0.14224)
		(layer "In11.Cu")
		(net "M_C_DQ<38>")
	)
	(segment
		(start 275.182584 -52.742084)
		(end 275.182584 -53.924962)
		(width 0.0889)
		(layer "In11.Cu")
		(net "M_C_DQ<38>")
	)
	(segment
		(start 286.2834 -26.480008)
		(end 286.4866 -26.683208)
		(width 0.14224)
		(layer "In11.Cu")
		(net "M_C_DQ<38>")
	)
	(segment
		(start 286.543242 -28.918408)
		(end 286.004 -28.918408)
		(width 0.14224)
		(layer "In11.Cu")
		(net "M_C_DQ<38>")
	)
	(segment
		(start 286.2834 -7.12216)
		(end 285.9278 -7.47776)
		(width 0.14224)
		(layer "In11.Cu")
		(net "M_C_DQ<38>")
	)
	(segment
		(start 286.116014 -13.668756)
		(end 286.116014 -16.890746)
		(width 0.14224)
		(layer "In11.Cu")
		(net "M_C_DQ<38>")
	)
	(segment
		(start 286.014414 -12.373356)
		(end 286.014414 -13.567156)
		(width 0.14224)
		(layer "In11.Cu")
		(net "M_C_DQ<38>")
	)
	(segment
		(start 276.194266 -42.2402)
		(end 276.349206 -42.39514)
		(width 0.14224)
		(layer "In11.Cu")
		(net "M_C_DQ<38>")
	)
	(segment
		(start 285.81604 -0.44196)
		(end 286.14243 -0.768096)
		(width 0.14224)
		(layer "In11.Cu")
		(net "M_C_DQ<38>")
	)
	(segment
		(start 286.004 -28.918408)
		(end 285.8008 -29.121608)
		(width 0.14224)
		(layer "In11.Cu")
		(net "M_C_DQ<38>")
	)
	(segment
		(start 286.217614 -11.821414)
		(end 286.217614 -12.170156)
		(width 0.14224)
		(layer "In11.Cu")
		(net "M_C_DQ<38>")
	)
	(segment
		(start 285.8008 -29.337)
		(end 286.2326 -29.7688)
		(width 0.14224)
		(layer "In11.Cu")
		(net "M_C_DQ<38>")
	)
	(segment
		(start 275.261324 -55.609236)
		(end 275.254974 -55.619904)
		(width 0.0889)
		(layer "In11.Cu")
		(net "M_C_DQ<38>")
	)
	(segment
		(start 286.217614 -21.422614)
		(end 286.217614 -21.771356)
		(width 0.14224)
		(layer "In11.Cu")
		(net "M_C_DQ<38>")
	)
	(segment
		(start 285.9278 -7.47776)
		(end 285.9278 -8.7376)
		(width 0.14224)
		(layer "In11.Cu")
		(net "M_C_DQ<38>")
	)
	(segment
		(start 275.261324 -56.599836)
		(end 275.254974 -56.610504)
		(width 0.0889)
		(layer "In11.Cu")
		(net "M_C_DQ<38>")
	)
	(segment
		(start 286.2326 -29.7688)
		(end 286.2326 -30.159452)
		(width 0.14224)
		(layer "In11.Cu")
		(net "M_C_DQ<38>")
	)
	(segment
		(start 286.004 -9.626854)
		(end 286.004 -11.6078)
		(width 0.14224)
		(layer "In11.Cu")
		(net "M_C_DQ<38>")
	)
	(segment
		(start 286.116014 -16.890746)
		(end 285.9532 -17.05356)
		(width 0.14224)
		(layer "In11.Cu")
		(net "M_C_DQ<38>")
	)
	(segment
		(start 275.231606 -59.11342)
		(end 275.20773 -59.202574)
		(width 0.0889)
		(layer "In11.Cu")
		(net "M_C_DQ<38>")
	)
	(segment
		(start 286.2834 -27.292808)
		(end 286.004 -27.292808)
		(width 0.14224)
		(layer "In11.Cu")
		(net "M_C_DQ<38>")
	)
	(segment
		(start 286.4866 -27.089608)
		(end 286.2834 -27.292808)
		(width 0.14224)
		(layer "In11.Cu")
		(net "M_C_DQ<38>")
	)
	(segment
		(start 286.004 -11.6078)
		(end 286.217614 -11.821414)
		(width 0.14224)
		(layer "In11.Cu")
		(net "M_C_DQ<38>")
	)
	(segment
		(start 286.2326 -30.159452)
		(end 276.194266 -40.197786)
		(width 0.14224)
		(layer "In11.Cu")
		(net "M_C_DQ<38>")
	)
	(segment
		(start 286.004 -28.105608)
		(end 286.543242 -28.105608)
		(width 0.14224)
		(layer "In11.Cu")
		(net "M_C_DQ<38>")
	)
	(segment
		(start 285.8008 -27.902408)
		(end 286.004 -28.105608)
		(width 0.14224)
		(layer "In11.Cu")
		(net "M_C_DQ<38>")
	)
	(segment
		(start 286.125412 0.287528)
		(end 285.76143 -0.076454)
		(width 0.14224)
		(layer "In11.Cu")
		(net "M_C_DQ<38>")
	)
	(segment
		(start 276.86 -42.53738)
		(end 276.86 -43.04284)
		(width 0.14224)
		(layer "In11.Cu")
		(net "M_C_DQ<38>")
	)
	(segment
		(start 286.14243 -0.768096)
		(end 286.14243 -1.111504)
		(width 0.14224)
		(layer "In11.Cu")
		(net "M_C_DQ<38>")
	)
	(segment
		(start 286.2834 -4.991354)
		(end 286.2834 -7.12216)
		(width 0.14224)
		(layer "In11.Cu")
		(net "M_C_DQ<38>")
	)
	(segment
		(start 275.26615 -55.6006)
		(end 275.261324 -55.609236)
		(width 0.0889)
		(layer "In11.Cu")
		(net "M_C_DQ<38>")
	)
	(segment
		(start 286.543242 -28.105608)
		(end 286.746442 -28.308808)
		(width 0.14224)
		(layer "In11.Cu")
		(net "M_C_DQ<38>")
	)
	(segment
		(start 276.86 -43.04284)
		(end 276.71776 -43.18508)
		(width 0.14224)
		(layer "In11.Cu")
		(net "M_C_DQ<38>")
	)
	(segment
		(start 286.746442 -28.715208)
		(end 286.543242 -28.918408)
		(width 0.14224)
		(layer "In11.Cu")
		(net "M_C_DQ<38>")
	)
	(arc
		(start 275.261324 -58.581036)
		(mid 275.182987 -58.843692)
		(end 275.231606 -59.11342)
		(width 0.0889)
		(layer "In11.Cu")
		(net "M_C_DQ<38>")
	)
	(arc
		(start 275.261324 -54.218586)
		(mid 275.314794 -54.413649)
		(end 275.26615 -54.61)
		(width 0.0889)
		(layer "In11.Cu")
		(net "M_C_DQ<38>")
	)
	(arc
		(start 275.182584 -53.924962)
		(mid 275.202598 -54.076968)
		(end 275.261324 -54.218586)
		(width 0.0889)
		(layer "In11.Cu")
		(net "M_C_DQ<38>")
	)
	(arc
		(start 275.254974 -54.629304)
		(mid 275.182176 -54.920067)
		(end 275.261324 -55.209186)
		(width 0.0889)
		(layer "In11.Cu")
		(net "M_C_DQ<38>")
	)
	(arc
		(start 275.254974 -56.610504)
		(mid 275.182176 -56.901267)
		(end 275.261324 -57.190386)
		(width 0.0889)
		(layer "In11.Cu")
		(net "M_C_DQ<38>")
	)
	(arc
		(start 275.261324 -58.180986)
		(mid 275.314823 -58.380884)
		(end 275.261324 -58.580782)
		(width 0.0889)
		(layer "In11.Cu")
		(net "M_C_DQ<38>")
	)
	(arc
		(start 275.254974 -55.619904)
		(mid 275.182176 -55.910667)
		(end 275.261324 -56.199786)
		(width 0.0889)
		(layer "In11.Cu")
		(net "M_C_DQ<38>")
	)
	(arc
		(start 275.261324 -56.199786)
		(mid 275.314794 -56.394849)
		(end 275.26615 -56.5912)
		(width 0.0889)
		(layer "In11.Cu")
		(net "M_C_DQ<38>")
	)
	(arc
		(start 275.254974 -57.601104)
		(mid 275.18227 -57.891867)
		(end 275.261324 -58.180986)
		(width 0.0889)
		(layer "In11.Cu")
		(net "M_C_DQ<38>")
	)
	(arc
		(start 275.261324 -55.209186)
		(mid 275.314794 -55.404249)
		(end 275.26615 -55.6006)
		(width 0.0889)
		(layer "In11.Cu")
		(net "M_C_DQ<38>")
	)
	(arc
		(start 275.261324 -57.190386)
		(mid 275.314794 -57.385449)
		(end 275.26615 -57.5818)
		(width 0.0889)
		(layer "In11.Cu")
		(net "M_C_DQ<38>")
	)
	(segment
		(start 279.700482 3.778758)
		(end 279.699974 3.778758)
		(width 0.1651)
		(layer "F.Cu")
		(net "M_C_DQ<37>")
	)
	(segment
		(start 272.910808 -60.857384)
		(end 272.339308 -60.857384)
		(width 0.0889)
		(layer "F.Cu")
		(net "M_C_DQ<37>")
	)
	(segment
		(start 279.699974 3.778758)
		(end 279.699974 2.514854)
		(width 0.1651)
		(layer "F.Cu")
		(net "M_C_DQ<37>")
	)
	(via
		(at 280.473658 -3.076956)
		(size 0.508)
		(drill 0.254)
		(layers "F.Cu" "B.Cu")
		(net "M_C_DQ<37>")
	)
	(via
		(at 272.339308 -60.857384)
		(size 0.508)
		(drill 0.254)
		(layers "F.Cu" "B.Cu")
		(net "M_C_DQ<37>")
	)
	(via
		(at 279.699974 2.514854)
		(size 0.508)
		(drill 0.254)
		(layers "F.Cu" "B.Cu")
		(net "M_C_DQ<37>")
	)
	(segment
		(start 280.550366 -1.021842)
		(end 280.549858 -1.021842)
		(width 0.1651)
		(layer "B.Cu")
		(net "M_C_DQ<37>")
	)
	(segment
		(start 280.473658 -2.355342)
		(end 280.473658 -3.076956)
		(width 0.1651)
		(layer "B.Cu")
		(net "M_C_DQ<37>")
	)
	(segment
		(start 280.549858 -2.279142)
		(end 280.473658 -2.355342)
		(width 0.1651)
		(layer "B.Cu")
		(net "M_C_DQ<37>")
	)
	(segment
		(start 280.549858 -1.021842)
		(end 280.549858 -2.279142)
		(width 0.1651)
		(layer "B.Cu")
		(net "M_C_DQ<37>")
	)
	(segment
		(start 281.0256 -9.5504)
		(end 280.858214 -9.383014)
		(width 0.14224)
		(layer "In11.Cu")
		(net "M_C_DQ<37>")
	)
	(segment
		(start 275.650198 -33.795716)
		(end 276.212046 -34.357564)
		(width 0.14224)
		(layer "In11.Cu")
		(net "M_C_DQ<37>")
	)
	(segment
		(start 280.947114 -16.928846)
		(end 280.924 -16.905732)
		(width 0.14224)
		(layer "In11.Cu")
		(net "M_C_DQ<37>")
	)
	(segment
		(start 272.452846 -59.48299)
		(end 272.034 -59.147964)
		(width 0.0889)
		(layer "In11.Cu")
		(net "M_C_DQ<37>")
	)
	(segment
		(start 280.924 -13.64107)
		(end 280.947114 -13.617956)
		(width 0.14224)
		(layer "In11.Cu")
		(net "M_C_DQ<37>")
	)
	(segment
		(start 272.696432 -51.160426)
		(end 272.696432 -49.220628)
		(width 0.0889)
		(layer "In11.Cu")
		(net "M_C_DQ<37>")
	)
	(segment
		(start 272.30451 -48.152558)
		(end 272.260568 -48.108616)
		(width 0.14224)
		(layer "In11.Cu")
		(net "M_C_DQ<37>")
	)
	(segment
		(start 271.987772 -57.694322)
		(end 271.992598 -57.685686)
		(width 0.0889)
		(layer "In11.Cu")
		(net "M_C_DQ<37>")
	)
	(segment
		(start 280.947114 -13.617956)
		(end 280.947114 -12.113768)
		(width 0.14224)
		(layer "In11.Cu")
		(net "M_C_DQ<37>")
	)
	(segment
		(start 280.981912 1.149096)
		(end 280.581608 1.5494)
		(width 0.14224)
		(layer "In11.Cu")
		(net "M_C_DQ<37>")
	)
	(segment
		(start 281.0256 -11.567414)
		(end 281.0256 -9.5504)
		(width 0.14224)
		(layer "In11.Cu")
		(net "M_C_DQ<37>")
	)
	(segment
		(start 280.80335 -21.43125)
		(end 281.0002 -21.2344)
		(width 0.14224)
		(layer "In11.Cu")
		(net "M_C_DQ<37>")
	)
	(segment
		(start 272.124424 -48.332644)
		(end 272.30451 -48.152558)
		(width 0.0889)
		(layer "In11.Cu")
		(net "M_C_DQ<37>")
	)
	(segment
		(start 280.883614 -7.264146)
		(end 280.883614 -6.563614)
		(width 0.14224)
		(layer "In11.Cu")
		(net "M_C_DQ<37>")
	)
	(segment
		(start 280.947114 -18.273268)
		(end 280.947114 -16.928846)
		(width 0.14224)
		(layer "In11.Cu")
		(net "M_C_DQ<37>")
	)
	(segment
		(start 272.071338 -54.57698)
		(end 272.071338 -53.592476)
		(width 0.0889)
		(layer "In11.Cu")
		(net "M_C_DQ<37>")
	)
	(segment
		(start 271.987772 -56.703722)
		(end 271.992598 -56.695086)
		(width 0.0889)
		(layer "In11.Cu")
		(net "M_C_DQ<37>")
	)
	(segment
		(start 280.947114 -12.113768)
		(end 280.858214 -12.024868)
		(width 0.14224)
		(layer "In11.Cu")
		(net "M_C_DQ<37>")
	)
	(segment
		(start 271.992598 -57.685686)
		(end 271.998948 -57.675018)
		(width 0.0889)
		(layer "In11.Cu")
		(net "M_C_DQ<37>")
	)
	(segment
		(start 280.416 -26.4668)
		(end 280.871168 -26.011632)
		(width 0.14224)
		(layer "In11.Cu")
		(net "M_C_DQ<37>")
	)
	(segment
		(start 281.0002 -18.9992)
		(end 280.80335 -18.80235)
		(width 0.14224)
		(layer "In11.Cu")
		(net "M_C_DQ<37>")
	)
	(segment
		(start 280.858214 -9.383014)
		(end 280.858214 -8.991346)
		(width 0.14224)
		(layer "In11.Cu")
		(net "M_C_DQ<37>")
	)
	(segment
		(start 280.80335 -21.82495)
		(end 280.80335 -21.43125)
		(width 0.14224)
		(layer "In11.Cu")
		(net "M_C_DQ<37>")
	)
	(segment
		(start 280.968196 -23.234396)
		(end 280.968196 -21.989796)
		(width 0.14224)
		(layer "In11.Cu")
		(net "M_C_DQ<37>")
	)
	(segment
		(start 280.883614 -6.563614)
		(end 280.3652 -6.0452)
		(width 0.14224)
		(layer "In11.Cu")
		(net "M_C_DQ<37>")
	)
	(segment
		(start 280.858214 -8.991346)
		(end 280.947114 -8.902446)
		(width 0.14224)
		(layer "In11.Cu")
		(net "M_C_DQ<37>")
	)
	(segment
		(start 280.947114 -8.902446)
		(end 280.947114 -7.327646)
		(width 0.14224)
		(layer "In11.Cu")
		(net "M_C_DQ<37>")
	)
	(segment
		(start 275.091398 -34.153348)
		(end 275.44903 -33.795716)
		(width 0.14224)
		(layer "In11.Cu")
		(net "M_C_DQ<37>")
	)
	(segment
		(start 272.071338 -53.592476)
		(end 272.01241 -53.533548)
		(width 0.0889)
		(layer "In11.Cu")
		(net "M_C_DQ<37>")
	)
	(segment
		(start 275.653246 -34.916364)
		(end 275.091398 -34.354516)
		(width 0.14224)
		(layer "In11.Cu")
		(net "M_C_DQ<37>")
	)
	(segment
		(start 280.80335 -18.80235)
		(end 280.80335 -18.417032)
		(width 0.14224)
		(layer "In11.Cu")
		(net "M_C_DQ<37>")
	)
	(segment
		(start 280.416 -28.257246)
		(end 280.416 -26.4668)
		(width 0.14224)
		(layer "In11.Cu")
		(net "M_C_DQ<37>")
	)
	(segment
		(start 272.339308 -60.857384)
		(end 272.669254 -60.095638)
		(width 0.0889)
		(layer "In11.Cu")
		(net "M_C_DQ<37>")
	)
	(segment
		(start 280.3652 -6.0452)
		(end 280.3652 -4.336542)
		(width 0.14224)
		(layer "In11.Cu")
		(net "M_C_DQ<37>")
	)
	(segment
		(start 280.581608 1.5494)
		(end 280.270712 1.5494)
		(width 0.14224)
		(layer "In11.Cu")
		(net "M_C_DQ<37>")
	)
	(segment
		(start 271.987772 -54.722522)
		(end 272.071338 -54.57698)
		(width 0.0889)
		(layer "In11.Cu")
		(net "M_C_DQ<37>")
	)
	(segment
		(start 272.01241 -51.844448)
		(end 272.696432 -51.160426)
		(width 0.0889)
		(layer "In11.Cu")
		(net "M_C_DQ<37>")
	)
	(segment
		(start 276.212046 -34.357564)
		(end 276.430994 -34.357564)
		(width 0.14224)
		(layer "In11.Cu")
		(net "M_C_DQ<37>")
	)
	(segment
		(start 279.699974 2.120138)
		(end 279.699974 2.514854)
		(width 0.14224)
		(layer "In11.Cu")
		(net "M_C_DQ<37>")
	)
	(segment
		(start 276.724872 -31.948374)
		(end 280.416 -28.257246)
		(width 0.14224)
		(layer "In11.Cu")
		(net "M_C_DQ<37>")
	)
	(segment
		(start 272.260568 -48.108616)
		(end 272.260568 -38.52799)
		(width 0.14224)
		(layer "In11.Cu")
		(net "M_C_DQ<37>")
	)
	(segment
		(start 279.969214 -3.940556)
		(end 279.969214 -3.5814)
		(width 0.14224)
		(layer "In11.Cu")
		(net "M_C_DQ<37>")
	)
	(segment
		(start 272.260568 -38.52799)
		(end 275.653246 -35.135312)
		(width 0.14224)
		(layer "In11.Cu")
		(net "M_C_DQ<37>")
	)
	(segment
		(start 272.124424 -48.64862)
		(end 272.124424 -48.332644)
		(width 0.0889)
		(layer "In11.Cu")
		(net "M_C_DQ<37>")
	)
	(segment
		(start 271.992598 -55.704486)
		(end 271.998948 -55.693818)
		(width 0.0889)
		(layer "In11.Cu")
		(net "M_C_DQ<37>")
	)
	(segment
		(start 280.858214 -11.7348)
		(end 281.0256 -11.567414)
		(width 0.14224)
		(layer "In11.Cu")
		(net "M_C_DQ<37>")
	)
	(segment
		(start 279.969214 -3.5814)
		(end 280.473658 -3.076956)
		(width 0.14224)
		(layer "In11.Cu")
		(net "M_C_DQ<37>")
	)
	(segment
		(start 280.80335 -18.417032)
		(end 280.947114 -18.273268)
		(width 0.14224)
		(layer "In11.Cu")
		(net "M_C_DQ<37>")
	)
	(segment
		(start 275.653246 -35.135312)
		(end 275.653246 -34.916364)
		(width 0.14224)
		(layer "In11.Cu")
		(net "M_C_DQ<37>")
	)
	(segment
		(start 275.44903 -33.795716)
		(end 275.650198 -33.795716)
		(width 0.14224)
		(layer "In11.Cu")
		(net "M_C_DQ<37>")
	)
	(segment
		(start 272.696432 -49.220628)
		(end 272.124424 -48.64862)
		(width 0.0889)
		(layer "In11.Cu")
		(net "M_C_DQ<37>")
	)
	(segment
		(start 280.871168 -26.011632)
		(end 280.871168 -23.331424)
		(width 0.14224)
		(layer "In11.Cu")
		(net "M_C_DQ<37>")
	)
	(segment
		(start 272.669254 -60.095638)
		(end 272.686018 -60.066936)
		(width 0.0889)
		(layer "In11.Cu")
		(net "M_C_DQ<37>")
	)
	(segment
		(start 281.0002 -21.2344)
		(end 281.0002 -18.9992)
		(width 0.14224)
		(layer "In11.Cu")
		(net "M_C_DQ<37>")
	)
	(segment
		(start 276.724872 -34.063686)
		(end 276.724872 -31.948374)
		(width 0.14224)
		(layer "In11.Cu")
		(net "M_C_DQ<37>")
	)
	(segment
		(start 271.992598 -56.695086)
		(end 271.998948 -56.684418)
		(width 0.0889)
		(layer "In11.Cu")
		(net "M_C_DQ<37>")
	)
	(segment
		(start 271.987772 -55.713122)
		(end 271.992598 -55.704486)
		(width 0.0889)
		(layer "In11.Cu")
		(net "M_C_DQ<37>")
	)
	(segment
		(start 280.924 -16.905732)
		(end 280.924 -13.64107)
		(width 0.14224)
		(layer "In11.Cu")
		(net "M_C_DQ<37>")
	)
	(segment
		(start 280.968196 -21.989796)
		(end 280.80335 -21.82495)
		(width 0.14224)
		(layer "In11.Cu")
		(net "M_C_DQ<37>")
	)
	(segment
		(start 280.858214 -12.024868)
		(end 280.858214 -11.7348)
		(width 0.14224)
		(layer "In11.Cu")
		(net "M_C_DQ<37>")
	)
	(segment
		(start 280.981912 0.7366)
		(end 280.981912 1.149096)
		(width 0.14224)
		(layer "In11.Cu")
		(net "M_C_DQ<37>")
	)
	(segment
		(start 272.01241 -53.533548)
		(end 272.01241 -51.844448)
		(width 0.0889)
		(layer "In11.Cu")
		(net "M_C_DQ<37>")
	)
	(segment
		(start 280.785062 -2.765552)
		(end 280.785062 0.53975)
		(width 0.14224)
		(layer "In11.Cu")
		(net "M_C_DQ<37>")
	)
	(segment
		(start 272.034 -59.147964)
		(end 271.992598 -59.076082)
		(width 0.0889)
		(layer "In11.Cu")
		(net "M_C_DQ<37>")
	)
	(segment
		(start 280.3652 -4.336542)
		(end 279.969214 -3.940556)
		(width 0.14224)
		(layer "In11.Cu")
		(net "M_C_DQ<37>")
	)
	(segment
		(start 276.430994 -34.357564)
		(end 276.724872 -34.063686)
		(width 0.14224)
		(layer "In11.Cu")
		(net "M_C_DQ<37>")
	)
	(segment
		(start 280.785062 0.53975)
		(end 280.981912 0.7366)
		(width 0.14224)
		(layer "In11.Cu")
		(net "M_C_DQ<37>")
	)
	(segment
		(start 280.871168 -23.331424)
		(end 280.968196 -23.234396)
		(width 0.14224)
		(layer "In11.Cu")
		(net "M_C_DQ<37>")
	)
	(segment
		(start 275.091398 -34.354516)
		(end 275.091398 -34.153348)
		(width 0.14224)
		(layer "In11.Cu")
		(net "M_C_DQ<37>")
	)
	(segment
		(start 280.947114 -7.327646)
		(end 280.883614 -7.264146)
		(width 0.14224)
		(layer "In11.Cu")
		(net "M_C_DQ<37>")
	)
	(segment
		(start 280.270712 1.5494)
		(end 279.699974 2.120138)
		(width 0.14224)
		(layer "In11.Cu")
		(net "M_C_DQ<37>")
	)
	(segment
		(start 280.473658 -3.076956)
		(end 280.785062 -2.765552)
		(width 0.14224)
		(layer "In11.Cu")
		(net "M_C_DQ<37>")
	)
	(arc
		(start 271.998948 -57.675018)
		(mid 272.071746 -57.384255)
		(end 271.992598 -57.095136)
		(width 0.0889)
		(layer "In11.Cu")
		(net "M_C_DQ<37>")
	)
	(arc
		(start 271.992598 -59.076082)
		(mid 271.939065 -58.876184)
		(end 271.992598 -58.676286)
		(width 0.0889)
		(layer "In11.Cu")
		(net "M_C_DQ<37>")
	)
	(arc
		(start 271.998948 -56.684418)
		(mid 272.071746 -56.393655)
		(end 271.992598 -56.104536)
		(width 0.0889)
		(layer "In11.Cu")
		(net "M_C_DQ<37>")
	)
	(arc
		(start 271.992598 -58.085482)
		(mid 271.939062 -57.890531)
		(end 271.987772 -57.694322)
		(width 0.0889)
		(layer "In11.Cu")
		(net "M_C_DQ<37>")
	)
	(arc
		(start 271.992598 -58.676286)
		(mid 272.071729 -58.380884)
		(end 271.992598 -58.085482)
		(width 0.0889)
		(layer "In11.Cu")
		(net "M_C_DQ<37>")
	)
	(arc
		(start 271.992598 -56.104536)
		(mid 271.939128 -55.909473)
		(end 271.987772 -55.713122)
		(width 0.0889)
		(layer "In11.Cu")
		(net "M_C_DQ<37>")
	)
	(arc
		(start 272.686018 -60.066936)
		(mid 272.711114 -59.718363)
		(end 272.452846 -59.48299)
		(width 0.0889)
		(layer "In11.Cu")
		(net "M_C_DQ<37>")
	)
	(arc
		(start 271.992598 -55.113936)
		(mid 271.939128 -54.918873)
		(end 271.987772 -54.722522)
		(width 0.0889)
		(layer "In11.Cu")
		(net "M_C_DQ<37>")
	)
	(arc
		(start 271.998948 -55.693818)
		(mid 272.071746 -55.403055)
		(end 271.992598 -55.113936)
		(width 0.0889)
		(layer "In11.Cu")
		(net "M_C_DQ<37>")
	)
	(arc
		(start 271.992598 -57.095136)
		(mid 271.939128 -56.900073)
		(end 271.987772 -56.703722)
		(width 0.0889)
		(layer "In11.Cu")
		(net "M_C_DQ<37>")
	)
	(segment
		(start 280.549858 0.510032)
		(end 280.451814 1.0414)
		(width 0.1651)
		(layer "F.Cu")
		(net "M_C_DQ<36>")
	)
	(segment
		(start 280.550366 -0.821182)
		(end 280.549858 -0.821182)
		(width 0.1651)
		(layer "F.Cu")
		(net "M_C_DQ<36>")
	)
	(segment
		(start 272.910808 -59.866784)
		(end 272.339308 -59.866784)
		(width 0.0889)
		(layer "F.Cu")
		(net "M_C_DQ<36>")
	)
	(segment
		(start 280.549858 -0.821182)
		(end 280.549858 0.510032)
		(width 0.1651)
		(layer "F.Cu")
		(net "M_C_DQ<36>")
	)
	(via
		(at 272.339308 -59.866784)
		(size 0.508)
		(drill 0.254)
		(layers "F.Cu" "B.Cu")
		(net "M_C_DQ<36>")
	)
	(via
		(at 280.451814 1.0414)
		(size 0.508)
		(drill 0.254)
		(layers "F.Cu" "B.Cu")
		(net "M_C_DQ<36>")
	)
	(via
		(at 279.699974 -4.357878)
		(size 0.508)
		(drill 0.254)
		(layers "F.Cu" "B.Cu")
		(net "M_C_DQ<36>")
	)
	(segment
		(start 279.699974 -5.621782)
		(end 279.699974 -4.357878)
		(width 0.1651)
		(layer "B.Cu")
		(net "M_C_DQ<36>")
	)
	(segment
		(start 279.700482 -5.621782)
		(end 279.699974 -5.621782)
		(width 0.1651)
		(layer "B.Cu")
		(net "M_C_DQ<36>")
	)
	(segment
		(start 271.880838 -54.520846)
		(end 271.880838 -53.670708)
		(width 0.0889)
		(layer "In11.Cu")
		(net "M_C_DQ<36>")
	)
	(segment
		(start 279.969214 -8.748014)
		(end 279.969214 -7.457186)
		(width 0.14224)
		(layer "In11.Cu")
		(net "M_C_DQ<36>")
	)
	(segment
		(start 272.634202 -35.312858)
		(end 273.00682 -34.94024)
		(width 0.14224)
		(layer "In11.Cu")
		(net "M_C_DQ<36>")
	)
	(segment
		(start 271.625568 -38.229032)
		(end 273.300444 -36.554156)
		(width 0.14224)
		(layer "In11.Cu")
		(net "M_C_DQ<36>")
	)
	(segment
		(start 272.037302 -59.539124)
		(end 271.827244 -59.171586)
		(width 0.0889)
		(layer "In11.Cu")
		(net "M_C_DQ<36>")
	)
	(segment
		(start 279.969214 -17.058386)
		(end 280.3906 -16.637)
		(width 0.14224)
		(layer "In11.Cu")
		(net "M_C_DQ<36>")
	)
	(segment
		(start 280.2382 -11.7348)
		(end 280.0604 -11.557)
		(width 0.14224)
		(layer "In11.Cu")
		(net "M_C_DQ<36>")
	)
	(segment
		(start 280.2128 -7.2136)
		(end 280.2128 -6.8072)
		(width 0.14224)
		(layer "In11.Cu")
		(net "M_C_DQ<36>")
	)
	(segment
		(start 279.464262 -3.327654)
		(end 280.175462 -2.616454)
		(width 0.14224)
		(layer "In11.Cu")
		(net "M_C_DQ<36>")
	)
	(segment
		(start 280.3906 -13.894054)
		(end 280.003758 -13.507212)
		(width 0.14224)
		(layer "In11.Cu")
		(net "M_C_DQ<36>")
	)
	(segment
		(start 280.0096 -21.17725)
		(end 280.0096 -19.1516)
		(width 0.14224)
		(layer "In11.Cu")
		(net "M_C_DQ<36>")
	)
	(segment
		(start 271.625568 -48.108616)
		(end 271.625568 -38.229032)
		(width 0.14224)
		(layer "In11.Cu")
		(net "M_C_DQ<36>")
	)
	(segment
		(start 280.0604 -9.5504)
		(end 280.2382 -9.3726)
		(width 0.14224)
		(layer "In11.Cu")
		(net "M_C_DQ<36>")
	)
	(segment
		(start 273.925284 -33.92297)
		(end 279.7556 -28.092654)
		(width 0.14224)
		(layer "In11.Cu")
		(net "M_C_DQ<36>")
	)
	(segment
		(start 271.827498 -57.590436)
		(end 271.832324 -57.5818)
		(width 0.0889)
		(layer "In11.Cu")
		(net "M_C_DQ<36>")
	)
	(segment
		(start 280.2382 -12.039346)
		(end 280.2382 -11.7348)
		(width 0.14224)
		(layer "In11.Cu")
		(net "M_C_DQ<36>")
	)
	(segment
		(start 272.505932 -51.081686)
		(end 272.505932 -49.299622)
		(width 0.0889)
		(layer "In11.Cu")
		(net "M_C_DQ<36>")
	)
	(segment
		(start 279.81148 -0.076454)
		(end 280.175462 0.287528)
		(width 0.14224)
		(layer "In11.Cu")
		(net "M_C_DQ<36>")
	)
	(segment
		(start 280.2382 -9.017)
		(end 279.969214 -8.748014)
		(width 0.14224)
		(layer "In11.Cu")
		(net "M_C_DQ<36>")
	)
	(segment
		(start 280.175462 0.287528)
		(end 280.175462 0.765048)
		(width 0.14224)
		(layer "In11.Cu")
		(net "M_C_DQ<36>")
	)
	(segment
		(start 274.248118 -35.606482)
		(end 274.579842 -35.274758)
		(width 0.14224)
		(layer "In11.Cu")
		(net "M_C_DQ<36>")
	)
	(segment
		(start 271.821148 -56.610504)
		(end 271.827498 -56.599836)
		(width 0.0889)
		(layer "In11.Cu")
		(net "M_C_DQ<36>")
	)
	(segment
		(start 280.175462 -2.616454)
		(end 280.175462 -2.141728)
		(width 0.14224)
		(layer "In11.Cu")
		(net "M_C_DQ<36>")
	)
	(segment
		(start 271.933924 -48.416972)
		(end 271.66951 -48.152558)
		(width 0.0889)
		(layer "In11.Cu")
		(net "M_C_DQ<36>")
	)
	(segment
		(start 280.0096 -19.1516)
		(end 280.16835 -18.99285)
		(width 0.14224)
		(layer "In11.Cu")
		(net "M_C_DQ<36>")
	)
	(segment
		(start 272.634202 -35.600386)
		(end 272.634202 -35.312858)
		(width 0.14224)
		(layer "In11.Cu")
		(net "M_C_DQ<36>")
	)
	(segment
		(start 280.2382 -9.3726)
		(end 280.2382 -9.017)
		(width 0.14224)
		(layer "In11.Cu")
		(net "M_C_DQ<36>")
	)
	(segment
		(start 279.699974 -6.294374)
		(end 279.699974 -4.357878)
		(width 0.14224)
		(layer "In11.Cu")
		(net "M_C_DQ<36>")
	)
	(segment
		(start 271.821148 -57.601104)
		(end 271.827498 -57.590436)
		(width 0.0889)
		(layer "In11.Cu")
		(net "M_C_DQ<36>")
	)
	(segment
		(start 280.003758 -13.507212)
		(end 280.003758 -12.273788)
		(width 0.14224)
		(layer "In11.Cu")
		(net "M_C_DQ<36>")
	)
	(segment
		(start 280.179526 -25.670764)
		(end 280.179526 -23.309326)
		(width 0.14224)
		(layer "In11.Cu")
		(net "M_C_DQ<36>")
	)
	(segment
		(start 272.505932 -49.299622)
		(end 271.933924 -48.727614)
		(width 0.0889)
		(layer "In11.Cu")
		(net "M_C_DQ<36>")
	)
	(segment
		(start 280.175462 -2.141728)
		(end 279.82418 -1.790446)
		(width 0.14224)
		(layer "In11.Cu")
		(net "M_C_DQ<36>")
	)
	(segment
		(start 273.300444 -36.554156)
		(end 273.300444 -36.266628)
		(width 0.14224)
		(layer "In11.Cu")
		(net "M_C_DQ<36>")
	)
	(segment
		(start 280.003758 -12.273788)
		(end 280.2382 -12.039346)
		(width 0.14224)
		(layer "In11.Cu")
		(net "M_C_DQ<36>")
	)
	(segment
		(start 271.822164 -53.612034)
		(end 271.822164 -51.765454)
		(width 0.0889)
		(layer "In11.Cu")
		(net "M_C_DQ<36>")
	)
	(segment
		(start 271.66951 -48.152558)
		(end 271.625568 -48.108616)
		(width 0.14224)
		(layer "In11.Cu")
		(net "M_C_DQ<36>")
	)
	(segment
		(start 273.96059 -35.606482)
		(end 274.248118 -35.606482)
		(width 0.14224)
		(layer "In11.Cu")
		(net "M_C_DQ<36>")
	)
	(segment
		(start 271.821148 -55.619904)
		(end 271.827498 -55.609236)
		(width 0.0889)
		(layer "In11.Cu")
		(net "M_C_DQ<36>")
	)
	(segment
		(start 279.82418 -1.790446)
		(end 279.82418 -1.4351)
		(width 0.14224)
		(layer "In11.Cu")
		(net "M_C_DQ<36>")
	)
	(segment
		(start 280.19248 -1.0668)
		(end 280.19248 -0.762)
		(width 0.14224)
		(layer "In11.Cu")
		(net "M_C_DQ<36>")
	)
	(segment
		(start 280.175462 0.765048)
		(end 280.451814 1.0414)
		(width 0.14224)
		(layer "In11.Cu")
		(net "M_C_DQ<36>")
	)
	(segment
		(start 279.82418 -1.4351)
		(end 280.19248 -1.0668)
		(width 0.14224)
		(layer "In11.Cu")
		(net "M_C_DQ<36>")
	)
	(segment
		(start 279.969214 -7.457186)
		(end 280.2128 -7.2136)
		(width 0.14224)
		(layer "In11.Cu")
		(net "M_C_DQ<36>")
	)
	(segment
		(start 273.00682 -34.94024)
		(end 273.294348 -34.94024)
		(width 0.14224)
		(layer "In11.Cu")
		(net "M_C_DQ<36>")
	)
	(segment
		(start 274.579842 -34.98723)
		(end 273.925284 -34.332672)
		(width 0.14224)
		(layer "In11.Cu")
		(net "M_C_DQ<36>")
	)
	(segment
		(start 271.827498 -56.599836)
		(end 271.832324 -56.5912)
		(width 0.0889)
		(layer "In11.Cu")
		(net "M_C_DQ<36>")
	)
	(segment
		(start 271.933924 -48.727614)
		(end 271.933924 -48.416972)
		(width 0.0889)
		(layer "In11.Cu")
		(net "M_C_DQ<36>")
	)
	(segment
		(start 274.579842 -35.274758)
		(end 274.579842 -34.98723)
		(width 0.14224)
		(layer "In11.Cu")
		(net "M_C_DQ<36>")
	)
	(segment
		(start 279.7556 -28.092654)
		(end 279.7556 -26.09469)
		(width 0.14224)
		(layer "In11.Cu")
		(net "M_C_DQ<36>")
	)
	(segment
		(start 279.81148 -0.381)
		(end 279.81148 -0.076454)
		(width 0.14224)
		(layer "In11.Cu")
		(net "M_C_DQ<36>")
	)
	(segment
		(start 279.699974 -4.357878)
		(end 279.464262 -4.122166)
		(width 0.14224)
		(layer "In11.Cu")
		(net "M_C_DQ<36>")
	)
	(segment
		(start 280.002996 -23.132796)
		(end 280.002996 -21.964396)
		(width 0.14224)
		(layer "In11.Cu")
		(net "M_C_DQ<36>")
	)
	(segment
		(start 271.821148 -54.629304)
		(end 271.827498 -54.618636)
		(width 0.0889)
		(layer "In11.Cu")
		(net "M_C_DQ<36>")
	)
	(segment
		(start 271.822164 -51.765454)
		(end 272.505932 -51.081686)
		(width 0.0889)
		(layer "In11.Cu")
		(net "M_C_DQ<36>")
	)
	(segment
		(start 271.827498 -54.618636)
		(end 271.880838 -54.520846)
		(width 0.0889)
		(layer "In11.Cu")
		(net "M_C_DQ<36>")
	)
	(segment
		(start 280.179526 -23.309326)
		(end 280.002996 -23.132796)
		(width 0.14224)
		(layer "In11.Cu")
		(net "M_C_DQ<36>")
	)
	(segment
		(start 280.16835 -18.556986)
		(end 279.969214 -18.35785)
		(width 0.14224)
		(layer "In11.Cu")
		(net "M_C_DQ<36>")
	)
	(segment
		(start 271.827498 -55.609236)
		(end 271.832324 -55.6006)
		(width 0.0889)
		(layer "In11.Cu")
		(net "M_C_DQ<36>")
	)
	(segment
		(start 280.002996 -21.964396)
		(end 280.16835 -21.799042)
		(width 0.14224)
		(layer "In11.Cu")
		(net "M_C_DQ<36>")
	)
	(segment
		(start 273.300444 -36.266628)
		(end 272.634202 -35.600386)
		(width 0.14224)
		(layer "In11.Cu")
		(net "M_C_DQ<36>")
	)
	(segment
		(start 279.7556 -26.09469)
		(end 280.179526 -25.670764)
		(width 0.14224)
		(layer "In11.Cu")
		(net "M_C_DQ<36>")
	)
	(segment
		(start 280.0604 -11.557)
		(end 280.0604 -9.5504)
		(width 0.14224)
		(layer "In11.Cu")
		(net "M_C_DQ<36>")
	)
	(segment
		(start 280.2128 -6.8072)
		(end 279.699974 -6.294374)
		(width 0.14224)
		(layer "In11.Cu")
		(net "M_C_DQ<36>")
	)
	(segment
		(start 271.880838 -53.670708)
		(end 271.822164 -53.612034)
		(width 0.0889)
		(layer "In11.Cu")
		(net "M_C_DQ<36>")
	)
	(segment
		(start 279.464262 -4.122166)
		(end 279.464262 -3.327654)
		(width 0.14224)
		(layer "In11.Cu")
		(net "M_C_DQ<36>")
	)
	(segment
		(start 280.19248 -0.762)
		(end 279.81148 -0.381)
		(width 0.14224)
		(layer "In11.Cu")
		(net "M_C_DQ<36>")
	)
	(segment
		(start 280.16835 -21.799042)
		(end 280.16835 -21.336)
		(width 0.14224)
		(layer "In11.Cu")
		(net "M_C_DQ<36>")
	)
	(segment
		(start 272.339308 -59.866784)
		(end 272.049494 -59.555634)
		(width 0.0889)
		(layer "In11.Cu")
		(net "M_C_DQ<36>")
	)
	(segment
		(start 273.294348 -34.94024)
		(end 273.96059 -35.606482)
		(width 0.14224)
		(layer "In11.Cu")
		(net "M_C_DQ<36>")
	)
	(segment
		(start 279.969214 -18.35785)
		(end 279.969214 -17.058386)
		(width 0.14224)
		(layer "In11.Cu")
		(net "M_C_DQ<36>")
	)
	(segment
		(start 280.3906 -16.637)
		(end 280.3906 -13.894054)
		(width 0.14224)
		(layer "In11.Cu")
		(net "M_C_DQ<36>")
	)
	(segment
		(start 273.925284 -34.332672)
		(end 273.925284 -33.92297)
		(width 0.14224)
		(layer "In11.Cu")
		(net "M_C_DQ<36>")
	)
	(segment
		(start 280.16835 -21.336)
		(end 280.0096 -21.17725)
		(width 0.14224)
		(layer "In11.Cu")
		(net "M_C_DQ<36>")
	)
	(segment
		(start 280.16835 -18.99285)
		(end 280.16835 -18.556986)
		(width 0.14224)
		(layer "In11.Cu")
		(net "M_C_DQ<36>")
	)
	(arc
		(start 271.827244 -58.180986)
		(mid 271.748146 -57.891838)
		(end 271.821148 -57.601104)
		(width 0.0889)
		(layer "In11.Cu")
		(net "M_C_DQ<36>")
	)
	(arc
		(start 271.827244 -59.171586)
		(mid 271.748113 -58.876184)
		(end 271.827244 -58.580782)
		(width 0.0889)
		(layer "In11.Cu")
		(net "M_C_DQ<36>")
	)
	(arc
		(start 271.827498 -56.199786)
		(mid 271.748276 -55.910668)
		(end 271.821148 -55.619904)
		(width 0.0889)
		(layer "In11.Cu")
		(net "M_C_DQ<36>")
	)
	(arc
		(start 271.827244 -58.580782)
		(mid 271.880777 -58.380884)
		(end 271.827244 -58.180986)
		(width 0.0889)
		(layer "In11.Cu")
		(net "M_C_DQ<36>")
	)
	(arc
		(start 271.832324 -56.5912)
		(mid 271.881079 -56.394848)
		(end 271.827498 -56.199786)
		(width 0.0889)
		(layer "In11.Cu")
		(net "M_C_DQ<36>")
	)
	(arc
		(start 271.832324 -55.6006)
		(mid 271.881079 -55.404248)
		(end 271.827498 -55.209186)
		(width 0.0889)
		(layer "In11.Cu")
		(net "M_C_DQ<36>")
	)
	(arc
		(start 271.827498 -55.209186)
		(mid 271.748276 -54.920068)
		(end 271.821148 -54.629304)
		(width 0.0889)
		(layer "In11.Cu")
		(net "M_C_DQ<36>")
	)
	(arc
		(start 271.827498 -57.190386)
		(mid 271.748276 -56.901268)
		(end 271.821148 -56.610504)
		(width 0.0889)
		(layer "In11.Cu")
		(net "M_C_DQ<36>")
	)
	(arc
		(start 271.832324 -57.5818)
		(mid 271.881079 -57.385448)
		(end 271.827498 -57.190386)
		(width 0.0889)
		(layer "In11.Cu")
		(net "M_C_DQ<36>")
	)
	(arc
		(start 272.049494 -59.555634)
		(mid 272.042926 -59.547728)
		(end 272.037302 -59.539124)
		(width 0.0889)
		(layer "In11.Cu")
		(net "M_C_DQ<36>")
	)
	(segment
		(start 287.350454 3.778758)
		(end 287.349946 3.778758)
		(width 0.1651)
		(layer "F.Cu")
		(net "M_C_DQ<35>")
	)
	(segment
		(start 276.344634 -60.857384)
		(end 275.773134 -60.857384)
		(width 0.0889)
		(layer "F.Cu")
		(net "M_C_DQ<35>")
	)
	(segment
		(start 287.349946 3.778758)
		(end 287.349946 2.514854)
		(width 0.1651)
		(layer "F.Cu")
		(net "M_C_DQ<35>")
	)
	(via
		(at 275.773134 -60.857384)
		(size 0.508)
		(drill 0.254)
		(layers "F.Cu" "B.Cu")
		(net "M_C_DQ<35>")
	)
	(via
		(at 287.349946 2.514854)
		(size 0.508)
		(drill 0.254)
		(layers "F.Cu" "B.Cu")
		(net "M_C_DQ<35>")
	)
	(via
		(at 288.19983 -3.076956)
		(size 0.508)
		(drill 0.254)
		(layers "F.Cu" "B.Cu")
		(net "M_C_DQ<35>")
	)
	(segment
		(start 288.200338 -1.021842)
		(end 288.19983 -1.021842)
		(width 0.1651)
		(layer "B.Cu")
		(net "M_C_DQ<35>")
	)
	(segment
		(start 288.19983 -1.021842)
		(end 288.19983 -3.076956)
		(width 0.1651)
		(layer "B.Cu")
		(net "M_C_DQ<35>")
	)
	(segment
		(start 288.5186 -16.842232)
		(end 288.706814 -17.030446)
		(width 0.14224)
		(layer "In11.Cu")
		(net "M_C_DQ<35>")
	)
	(segment
		(start 278.099266 -47.898558)
		(end 277.847044 -48.15078)
		(width 0.0889)
		(layer "In11.Cu")
		(net "M_C_DQ<35>")
	)
	(segment
		(start 280.3906 -39.150798)
		(end 280.3906 -39.516558)
		(width 0.14224)
		(layer "In11.Cu")
		(net "M_C_DQ<35>")
	)
	(segment
		(start 288.554414 -18.582386)
		(end 288.554414 -18.958814)
		(width 0.14224)
		(layer "In11.Cu")
		(net "M_C_DQ<35>")
	)
	(segment
		(start 287.716214 -3.965956)
		(end 288.567114 -4.816856)
		(width 0.14224)
		(layer "In11.Cu")
		(net "M_C_DQ<35>")
	)
	(segment
		(start 281.166062 -39.801038)
		(end 281.166062 -41.837356)
		(width 0.14224)
		(layer "In11.Cu")
		(net "M_C_DQ<35>")
	)
	(segment
		(start 278.099266 -44.904152)
		(end 278.099266 -47.898558)
		(width 0.14224)
		(layer "In11.Cu")
		(net "M_C_DQ<35>")
	)
	(segment
		(start 276.280118 -53.619146)
		(end 276.284944 -53.627782)
		(width 0.0889)
		(layer "In11.Cu")
		(net "M_C_DQ<35>")
	)
	(segment
		(start 288.732214 -23.183596)
		(end 288.544 -23.37181)
		(width 0.14224)
		(layer "In11.Cu")
		(net "M_C_DQ<35>")
	)
	(segment
		(start 288.567114 -4.816856)
		(end 288.567114 -7.289546)
		(width 0.14224)
		(layer "In11.Cu")
		(net "M_C_DQ<35>")
	)
	(segment
		(start 287.716214 -3.560572)
		(end 287.716214 -3.965956)
		(width 0.14224)
		(layer "In11.Cu")
		(net "M_C_DQ<35>")
	)
	(segment
		(start 288.552636 0.581152)
		(end 288.552636 -2.72415)
		(width 0.14224)
		(layer "In11.Cu")
		(net "M_C_DQ<35>")
	)
	(segment
		(start 288.554414 -21.822156)
		(end 288.732214 -21.999956)
		(width 0.14224)
		(layer "In11.Cu")
		(net "M_C_DQ<35>")
	)
	(segment
		(start 276.280118 -57.5818)
		(end 276.284944 -57.590436)
		(width 0.0889)
		(layer "In11.Cu")
		(net "M_C_DQ<35>")
	)
	(segment
		(start 276.291294 -59.160918)
		(end 276.284944 -59.171586)
		(width 0.0889)
		(layer "In11.Cu")
		(net "M_C_DQ<35>")
	)
	(segment
		(start 276.23135 -53.047646)
		(end 276.23135 -53.427884)
		(width 0.0889)
		(layer "In11.Cu")
		(net "M_C_DQ<35>")
	)
	(segment
		(start 280.3906 -39.516558)
		(end 280.53284 -39.658798)
		(width 0.14224)
		(layer "In11.Cu")
		(net "M_C_DQ<35>")
	)
	(segment
		(start 288.552636 -2.72415)
		(end 288.19983 -3.076956)
		(width 0.14224)
		(layer "In11.Cu")
		(net "M_C_DQ<35>")
	)
	(segment
		(start 288.544 -30.542484)
		(end 281.166062 -37.920422)
		(width 0.14224)
		(layer "In11.Cu")
		(net "M_C_DQ<35>")
	)
	(segment
		(start 288.706814 -17.030446)
		(end 288.706814 -18.429986)
		(width 0.14224)
		(layer "In11.Cu")
		(net "M_C_DQ<35>")
	)
	(segment
		(start 288.6964 -19.1008)
		(end 288.6964 -21.194014)
		(width 0.14224)
		(layer "In11.Cu")
		(net "M_C_DQ<35>")
	)
	(segment
		(start 276.284944 -60.162186)
		(end 276.26818 -60.19165)
		(width 0.0889)
		(layer "In11.Cu")
		(net "M_C_DQ<35>")
	)
	(segment
		(start 281.166062 -38.866318)
		(end 281.023822 -39.008558)
		(width 0.14224)
		(layer "In11.Cu")
		(net "M_C_DQ<35>")
	)
	(segment
		(start 277.847044 -48.15078)
		(end 277.847044 -48.43526)
		(width 0.0889)
		(layer "In11.Cu")
		(net "M_C_DQ<35>")
	)
	(segment
		(start 276.284944 -57.590436)
		(end 276.291294 -57.601104)
		(width 0.0889)
		(layer "In11.Cu")
		(net "M_C_DQ<35>")
	)
	(segment
		(start 276.280118 -54.61)
		(end 276.284944 -54.618636)
		(width 0.0889)
		(layer "In11.Cu")
		(net "M_C_DQ<35>")
	)
	(segment
		(start 288.417 -9.1186)
		(end 288.417 -12.083542)
		(width 0.14224)
		(layer "In11.Cu")
		(net "M_C_DQ<35>")
	)
	(segment
		(start 276.26818 -60.19165)
		(end 275.773134 -60.857384)
		(width 0.0889)
		(layer "In11.Cu")
		(net "M_C_DQ<35>")
	)
	(segment
		(start 288.567114 -7.289546)
		(end 288.706814 -7.429246)
		(width 0.14224)
		(layer "In11.Cu")
		(net "M_C_DQ<35>")
	)
	(segment
		(start 288.5186 -13.72997)
		(end 288.5186 -16.842232)
		(width 0.14224)
		(layer "In11.Cu")
		(net "M_C_DQ<35>")
	)
	(segment
		(start 276.284944 -55.609236)
		(end 276.291294 -55.619904)
		(width 0.0889)
		(layer "In11.Cu")
		(net "M_C_DQ<35>")
	)
	(segment
		(start 276.800564 -49.48174)
		(end 276.800564 -52.478432)
		(width 0.0889)
		(layer "In11.Cu")
		(net "M_C_DQ<35>")
	)
	(segment
		(start 287.666684 1.8796)
		(end 287.996884 1.5494)
		(width 0.14224)
		(layer "In11.Cu")
		(net "M_C_DQ<35>")
	)
	(segment
		(start 288.664396 -13.584174)
		(end 288.5186 -13.72997)
		(width 0.14224)
		(layer "In11.Cu")
		(net "M_C_DQ<35>")
	)
	(segment
		(start 276.280118 -56.5912)
		(end 276.284944 -56.599836)
		(width 0.0889)
		(layer "In11.Cu")
		(net "M_C_DQ<35>")
	)
	(segment
		(start 288.250884 1.5494)
		(end 288.708084 1.0922)
		(width 0.14224)
		(layer "In11.Cu")
		(net "M_C_DQ<35>")
	)
	(segment
		(start 280.53284 -39.008558)
		(end 280.3906 -39.150798)
		(width 0.14224)
		(layer "In11.Cu")
		(net "M_C_DQ<35>")
	)
	(segment
		(start 288.708084 0.7366)
		(end 288.552636 0.581152)
		(width 0.14224)
		(layer "In11.Cu")
		(net "M_C_DQ<35>")
	)
	(segment
		(start 288.708084 1.0922)
		(end 288.708084 0.7366)
		(width 0.14224)
		(layer "In11.Cu")
		(net "M_C_DQ<35>")
	)
	(segment
		(start 288.732214 -21.999956)
		(end 288.732214 -23.183596)
		(width 0.14224)
		(layer "In11.Cu")
		(net "M_C_DQ<35>")
	)
	(segment
		(start 276.280118 -58.5724)
		(end 276.284944 -58.581036)
		(width 0.0889)
		(layer "In11.Cu")
		(net "M_C_DQ<35>")
	)
	(segment
		(start 288.6964 -21.194014)
		(end 288.554414 -21.336)
		(width 0.14224)
		(layer "In11.Cu")
		(net "M_C_DQ<35>")
	)
	(segment
		(start 288.706814 -7.429246)
		(end 288.706814 -8.828786)
		(width 0.14224)
		(layer "In11.Cu")
		(net "M_C_DQ<35>")
	)
	(segment
		(start 276.284944 -54.618636)
		(end 276.291294 -54.629304)
		(width 0.0889)
		(layer "In11.Cu")
		(net "M_C_DQ<35>")
	)
	(segment
		(start 288.544 -23.37181)
		(end 288.544 -30.542484)
		(width 0.14224)
		(layer "In11.Cu")
		(net "M_C_DQ<35>")
	)
	(segment
		(start 281.166062 -37.920422)
		(end 281.166062 -38.866318)
		(width 0.14224)
		(layer "In11.Cu")
		(net "M_C_DQ<35>")
	)
	(segment
		(start 288.19983 -3.076956)
		(end 287.716214 -3.560572)
		(width 0.14224)
		(layer "In11.Cu")
		(net "M_C_DQ<35>")
	)
	(segment
		(start 276.800564 -52.478432)
		(end 276.23135 -53.047646)
		(width 0.0889)
		(layer "In11.Cu")
		(net "M_C_DQ<35>")
	)
	(segment
		(start 280.53284 -39.658798)
		(end 281.023822 -39.658798)
		(width 0.14224)
		(layer "In11.Cu")
		(net "M_C_DQ<35>")
	)
	(segment
		(start 287.349946 2.514854)
		(end 287.666684 2.198116)
		(width 0.14224)
		(layer "In11.Cu")
		(net "M_C_DQ<35>")
	)
	(segment
		(start 276.280118 -55.6006)
		(end 276.284944 -55.609236)
		(width 0.0889)
		(layer "In11.Cu")
		(net "M_C_DQ<35>")
	)
	(segment
		(start 277.847044 -48.43526)
		(end 276.800564 -49.48174)
		(width 0.0889)
		(layer "In11.Cu")
		(net "M_C_DQ<35>")
	)
	(segment
		(start 288.417 -12.083542)
		(end 288.664396 -12.330938)
		(width 0.14224)
		(layer "In11.Cu")
		(net "M_C_DQ<35>")
	)
	(segment
		(start 287.666684 2.198116)
		(end 287.666684 1.8796)
		(width 0.14224)
		(layer "In11.Cu")
		(net "M_C_DQ<35>")
	)
	(segment
		(start 288.554414 -21.336)
		(end 288.554414 -21.822156)
		(width 0.14224)
		(layer "In11.Cu")
		(net "M_C_DQ<35>")
	)
	(segment
		(start 288.664396 -12.330938)
		(end 288.664396 -13.584174)
		(width 0.14224)
		(layer "In11.Cu")
		(net "M_C_DQ<35>")
	)
	(segment
		(start 288.706814 -18.429986)
		(end 288.554414 -18.582386)
		(width 0.14224)
		(layer "In11.Cu")
		(net "M_C_DQ<35>")
	)
	(segment
		(start 281.023822 -39.008558)
		(end 280.53284 -39.008558)
		(width 0.14224)
		(layer "In11.Cu")
		(net "M_C_DQ<35>")
	)
	(segment
		(start 281.166062 -41.837356)
		(end 278.099266 -44.904152)
		(width 0.14224)
		(layer "In11.Cu")
		(net "M_C_DQ<35>")
	)
	(segment
		(start 281.023822 -39.658798)
		(end 281.166062 -39.801038)
		(width 0.14224)
		(layer "In11.Cu")
		(net "M_C_DQ<35>")
	)
	(segment
		(start 287.996884 1.5494)
		(end 288.250884 1.5494)
		(width 0.14224)
		(layer "In11.Cu")
		(net "M_C_DQ<35>")
	)
	(segment
		(start 288.554414 -18.958814)
		(end 288.6964 -19.1008)
		(width 0.14224)
		(layer "In11.Cu")
		(net "M_C_DQ<35>")
	)
	(segment
		(start 288.706814 -8.828786)
		(end 288.417 -9.1186)
		(width 0.14224)
		(layer "In11.Cu")
		(net "M_C_DQ<35>")
	)
	(segment
		(start 276.284944 -56.599836)
		(end 276.291294 -56.610504)
		(width 0.0889)
		(layer "In11.Cu")
		(net "M_C_DQ<35>")
	)
	(arc
		(start 276.284944 -59.571382)
		(mid 276.364075 -59.866784)
		(end 276.284944 -60.162186)
		(width 0.0889)
		(layer "In11.Cu")
		(net "M_C_DQ<35>")
	)
	(arc
		(start 276.291294 -55.619904)
		(mid 276.364092 -55.910667)
		(end 276.284944 -56.199786)
		(width 0.0889)
		(layer "In11.Cu")
		(net "M_C_DQ<35>")
	)
	(arc
		(start 276.284944 -55.209186)
		(mid 276.231474 -55.404249)
		(end 276.280118 -55.6006)
		(width 0.0889)
		(layer "In11.Cu")
		(net "M_C_DQ<35>")
	)
	(arc
		(start 276.291294 -56.610504)
		(mid 276.364092 -56.901267)
		(end 276.284944 -57.190386)
		(width 0.0889)
		(layer "In11.Cu")
		(net "M_C_DQ<35>")
	)
	(arc
		(start 276.284944 -58.581036)
		(mid 276.364166 -58.870154)
		(end 276.291294 -59.160918)
		(width 0.0889)
		(layer "In11.Cu")
		(net "M_C_DQ<35>")
	)
	(arc
		(start 276.284944 -59.171586)
		(mid 276.231445 -59.371484)
		(end 276.284944 -59.571382)
		(width 0.0889)
		(layer "In11.Cu")
		(net "M_C_DQ<35>")
	)
	(arc
		(start 276.291294 -57.601104)
		(mid 276.364092 -57.891867)
		(end 276.284944 -58.180986)
		(width 0.0889)
		(layer "In11.Cu")
		(net "M_C_DQ<35>")
	)
	(arc
		(start 276.291294 -54.629304)
		(mid 276.364092 -54.920067)
		(end 276.284944 -55.209186)
		(width 0.0889)
		(layer "In11.Cu")
		(net "M_C_DQ<35>")
	)
	(arc
		(start 276.284944 -56.199786)
		(mid 276.231474 -56.394849)
		(end 276.280118 -56.5912)
		(width 0.0889)
		(layer "In11.Cu")
		(net "M_C_DQ<35>")
	)
	(arc
		(start 276.284944 -57.190386)
		(mid 276.231474 -57.385449)
		(end 276.280118 -57.5818)
		(width 0.0889)
		(layer "In11.Cu")
		(net "M_C_DQ<35>")
	)
	(arc
		(start 276.23135 -53.427884)
		(mid 276.243768 -53.526565)
		(end 276.280118 -53.619146)
		(width 0.0889)
		(layer "In11.Cu")
		(net "M_C_DQ<35>")
	)
	(arc
		(start 276.284944 -53.627782)
		(mid 276.364075 -53.923184)
		(end 276.284944 -54.218586)
		(width 0.0889)
		(layer "In11.Cu")
		(net "M_C_DQ<35>")
	)
	(arc
		(start 276.284944 -58.180986)
		(mid 276.231474 -58.376049)
		(end 276.280118 -58.5724)
		(width 0.0889)
		(layer "In11.Cu")
		(net "M_C_DQ<35>")
	)
	(arc
		(start 276.284944 -54.218586)
		(mid 276.231474 -54.413649)
		(end 276.280118 -54.61)
		(width 0.0889)
		(layer "In11.Cu")
		(net "M_C_DQ<35>")
	)
	(segment
		(start 288.19983 0.662432)
		(end 288.19983 0.9398)
		(width 0.1651)
		(layer "F.Cu")
		(net "M_C_DQ<34>")
	)
	(segment
		(start 288.331402 0.30734)
		(end 288.331402 0.53086)
		(width 0.1651)
		(layer "F.Cu")
		(net "M_C_DQ<34>")
	)
	(segment
		(start 288.19983 -0.821182)
		(end 288.19983 0.175768)
		(width 0.1651)
		(layer "F.Cu")
		(net "M_C_DQ<34>")
	)
	(segment
		(start 288.19983 0.175768)
		(end 288.331402 0.30734)
		(width 0.1651)
		(layer "F.Cu")
		(net "M_C_DQ<34>")
	)
	(segment
		(start 288.200338 -0.821182)
		(end 288.19983 -0.821182)
		(width 0.1651)
		(layer "F.Cu")
		(net "M_C_DQ<34>")
	)
	(segment
		(start 288.331402 0.53086)
		(end 288.19983 0.662432)
		(width 0.1651)
		(layer "F.Cu")
		(net "M_C_DQ<34>")
	)
	(segment
		(start 276.344634 -59.866784)
		(end 275.773134 -59.866784)
		(width 0.0889)
		(layer "F.Cu")
		(net "M_C_DQ<34>")
	)
	(via
		(at 287.349946 -4.357878)
		(size 0.508)
		(drill 0.254)
		(layers "F.Cu" "B.Cu")
		(net "M_C_DQ<34>")
	)
	(via
		(at 288.19983 0.9398)
		(size 0.508)
		(drill 0.254)
		(layers "F.Cu" "B.Cu")
		(net "M_C_DQ<34>")
	)
	(via
		(at 275.773134 -59.866784)
		(size 0.508)
		(drill 0.254)
		(layers "F.Cu" "B.Cu")
		(net "M_C_DQ<34>")
	)
	(segment
		(start 287.350454 -5.621782)
		(end 287.349946 -5.621782)
		(width 0.1651)
		(layer "B.Cu")
		(net "M_C_DQ<34>")
	)
	(segment
		(start 287.349946 -5.621782)
		(end 287.349946 -4.357878)
		(width 0.1651)
		(layer "B.Cu")
		(net "M_C_DQ<34>")
	)
	(segment
		(start 287.909 -30.27934)
		(end 279.498552 -38.689788)
		(width 0.14224)
		(layer "In11.Cu")
		(net "M_C_DQ<34>")
	)
	(segment
		(start 287.76168 -1.04775)
		(end 287.45688 -1.35255)
		(width 0.14224)
		(layer "In11.Cu")
		(net "M_C_DQ<34>")
	)
	(segment
		(start 287.7566 -10.185146)
		(end 287.7566 -10.508996)
		(width 0.14224)
		(layer "In11.Cu")
		(net "M_C_DQ<34>")
	)
	(segment
		(start 279.498552 -38.689788)
		(end 279.498552 -39.19093)
		(width 0.14224)
		(layer "In11.Cu")
		(net "M_C_DQ<34>")
	)
	(segment
		(start 276.12467 -54.722522)
		(end 276.119844 -54.713886)
		(width 0.0889)
		(layer "In11.Cu")
		(net "M_C_DQ<34>")
	)
	(segment
		(start 287.9852 -7.09676)
		(end 287.716214 -7.365746)
		(width 0.14224)
		(layer "In11.Cu")
		(net "M_C_DQ<34>")
	)
	(segment
		(start 279.498552 -41.87063)
		(end 279.498552 -42.63009)
		(width 0.14224)
		(layer "In11.Cu")
		(net "M_C_DQ<34>")
	)
	(segment
		(start 287.716214 -16.966946)
		(end 287.716214 -18.425414)
		(width 0.14224)
		(layer "In11.Cu")
		(net "M_C_DQ<34>")
	)
	(segment
		(start 287.801812 0.541782)
		(end 287.801812 0.236728)
		(width 0.14224)
		(layer "In11.Cu")
		(net "M_C_DQ<34>")
	)
	(segment
		(start 287.76168 -0.761746)
		(end 287.76168 -1.04775)
		(width 0.14224)
		(layer "In11.Cu")
		(net "M_C_DQ<34>")
	)
	(segment
		(start 276.12467 -53.731922)
		(end 276.119844 -53.723286)
		(width 0.0889)
		(layer "In11.Cu")
		(net "M_C_DQ<34>")
	)
	(segment
		(start 276.102826 -59.105546)
		(end 276.119844 -59.076336)
		(width 0.0889)
		(layer "In11.Cu")
		(net "M_C_DQ<34>")
	)
	(segment
		(start 287.843214 -11.745468)
		(end 287.843214 -12.195556)
		(width 0.14224)
		(layer "In11.Cu")
		(net "M_C_DQ<34>")
	)
	(segment
		(start 278.910542 -41.71569)
		(end 279.343612 -41.71569)
		(width 0.14224)
		(layer "In11.Cu")
		(net "M_C_DQ<34>")
	)
	(segment
		(start 276.119844 -57.685686)
		(end 276.113494 -57.675018)
		(width 0.0889)
		(layer "In11.Cu")
		(net "M_C_DQ<34>")
	)
	(segment
		(start 287.5788 -10.007346)
		(end 287.7566 -10.185146)
		(width 0.14224)
		(layer "In11.Cu")
		(net "M_C_DQ<34>")
	)
	(segment
		(start 288.0106 -14.732)
		(end 287.826196 -14.916404)
		(width 0.14224)
		(layer "In11.Cu")
		(net "M_C_DQ<34>")
	)
	(segment
		(start 278.755602 -41.56075)
		(end 278.910542 -41.71569)
		(width 0.14224)
		(layer "In11.Cu")
		(net "M_C_DQ<34>")
	)
	(segment
		(start 287.065212 -3.3274)
		(end 287.065212 -4.073144)
		(width 0.14224)
		(layer "In11.Cu")
		(net "M_C_DQ<34>")
	)
	(segment
		(start 287.7312 -19.1008)
		(end 287.7312 -21.234146)
		(width 0.14224)
		(layer "In11.Cu")
		(net "M_C_DQ<34>")
	)
	(segment
		(start 287.826196 -16.198596)
		(end 288.036 -16.4084)
		(width 0.14224)
		(layer "In11.Cu")
		(net "M_C_DQ<34>")
	)
	(segment
		(start 279.498552 -39.19093)
		(end 279.343612 -39.34587)
		(width 0.14224)
		(layer "In11.Cu")
		(net "M_C_DQ<34>")
	)
	(segment
		(start 287.6042 -10.661396)
		(end 287.6042 -11.506454)
		(width 0.14224)
		(layer "In11.Cu")
		(net "M_C_DQ<34>")
	)
	(segment
		(start 287.826196 -14.916404)
		(end 287.826196 -15.2654)
		(width 0.14224)
		(layer "In11.Cu")
		(net "M_C_DQ<34>")
	)
	(segment
		(start 287.782 -6.5024)
		(end 287.9852 -6.7056)
		(width 0.14224)
		(layer "In11.Cu")
		(net "M_C_DQ<34>")
	)
	(segment
		(start 277.464266 -44.664376)
		(end 277.464266 -47.898558)
		(width 0.14224)
		(layer "In11.Cu")
		(net "M_C_DQ<34>")
	)
	(segment
		(start 287.6296 -12.40917)
		(end 287.6296 -13.480542)
		(width 0.14224)
		(layer "In11.Cu")
		(net "M_C_DQ<34>")
	)
	(segment
		(start 287.91408 -2.2098)
		(end 287.91408 -2.478532)
		(width 0.14224)
		(layer "In11.Cu")
		(net "M_C_DQ<34>")
	)
	(segment
		(start 279.498552 -42.63009)
		(end 277.464266 -44.664376)
		(width 0.14224)
		(layer "In11.Cu")
		(net "M_C_DQ<34>")
	)
	(segment
		(start 287.9598 -5.639054)
		(end 287.782 -5.816854)
		(width 0.14224)
		(layer "In11.Cu")
		(net "M_C_DQ<34>")
	)
	(segment
		(start 279.343612 -41.71569)
		(end 279.498552 -41.87063)
		(width 0.14224)
		(layer "In11.Cu")
		(net "M_C_DQ<34>")
	)
	(segment
		(start 287.909 -23.368254)
		(end 287.909 -30.27934)
		(width 0.14224)
		(layer "In11.Cu")
		(net "M_C_DQ<34>")
	)
	(segment
		(start 278.910542 -40.92575)
		(end 278.755602 -41.08069)
		(width 0.14224)
		(layer "In11.Cu")
		(net "M_C_DQ<34>")
	)
	(segment
		(start 287.826196 -13.677138)
		(end 287.826196 -14.2748)
		(width 0.14224)
		(layer "In11.Cu")
		(net "M_C_DQ<34>")
	)
	(segment
		(start 287.065212 -4.073144)
		(end 287.349946 -4.357878)
		(width 0.14224)
		(layer "In11.Cu")
		(net "M_C_DQ<34>")
	)
	(segment
		(start 278.910542 -39.34587)
		(end 278.755602 -39.50081)
		(width 0.14224)
		(layer "In11.Cu")
		(net "M_C_DQ<34>")
	)
	(segment
		(start 287.924748 -21.427694)
		(end 287.924748 -21.715222)
		(width 0.14224)
		(layer "In11.Cu")
		(net "M_C_DQ<34>")
	)
	(segment
		(start 288.036 -15.475204)
		(end 288.036 -15.748)
		(width 0.14224)
		(layer "In11.Cu")
		(net "M_C_DQ<34>")
	)
	(segment
		(start 287.6296 -13.480542)
		(end 287.826196 -13.677138)
		(width 0.14224)
		(layer "In11.Cu")
		(net "M_C_DQ<34>")
	)
	(segment
		(start 276.12467 -57.694322)
		(end 276.119844 -57.685686)
		(width 0.0889)
		(layer "In11.Cu")
		(net "M_C_DQ<34>")
	)
	(segment
		(start 287.9852 -6.7056)
		(end 287.9852 -7.09676)
		(width 0.14224)
		(layer "In11.Cu")
		(net "M_C_DQ<34>")
	)
	(segment
		(start 287.91408 -2.478532)
		(end 287.065212 -3.3274)
		(width 0.14224)
		(layer "In11.Cu")
		(net "M_C_DQ<34>")
	)
	(segment
		(start 287.716214 -8.798814)
		(end 287.843214 -8.925814)
		(width 0.14224)
		(layer "In11.Cu")
		(net "M_C_DQ<34>")
	)
	(segment
		(start 287.826196 -14.2748)
		(end 288.0106 -14.459204)
		(width 0.14224)
		(layer "In11.Cu")
		(net "M_C_DQ<34>")
	)
	(segment
		(start 278.755602 -41.08069)
		(end 278.755602 -41.56075)
		(width 0.14224)
		(layer "In11.Cu")
		(net "M_C_DQ<34>")
	)
	(segment
		(start 287.349946 -4.357878)
		(end 287.9598 -4.967732)
		(width 0.14224)
		(layer "In11.Cu")
		(net "M_C_DQ<34>")
	)
	(segment
		(start 287.96107 -18.87093)
		(end 287.7312 -19.1008)
		(width 0.14224)
		(layer "In11.Cu")
		(net "M_C_DQ<34>")
	)
	(segment
		(start 275.773134 -59.866784)
		(end 276.102826 -59.105546)
		(width 0.0889)
		(layer "In11.Cu")
		(net "M_C_DQ<34>")
	)
	(segment
		(start 287.45688 -0.108204)
		(end 287.45688 -0.456946)
		(width 0.14224)
		(layer "In11.Cu")
		(net "M_C_DQ<34>")
	)
	(segment
		(start 287.45688 -1.35255)
		(end 287.45688 -1.7526)
		(width 0.14224)
		(layer "In11.Cu")
		(net "M_C_DQ<34>")
	)
	(segment
		(start 278.755602 -39.98087)
		(end 278.910542 -40.13581)
		(width 0.14224)
		(layer "In11.Cu")
		(net "M_C_DQ<34>")
	)
	(segment
		(start 287.7566 -10.508996)
		(end 287.6042 -10.661396)
		(width 0.14224)
		(layer "In11.Cu")
		(net "M_C_DQ<34>")
	)
	(segment
		(start 287.6042 -11.506454)
		(end 287.843214 -11.745468)
		(width 0.14224)
		(layer "In11.Cu")
		(net "M_C_DQ<34>")
	)
	(segment
		(start 277.464266 -47.898558)
		(end 277.656544 -48.090836)
		(width 0.0889)
		(layer "In11.Cu")
		(net "M_C_DQ<34>")
	)
	(segment
		(start 287.826196 -15.957804)
		(end 287.826196 -16.198596)
		(width 0.14224)
		(layer "In11.Cu")
		(net "M_C_DQ<34>")
	)
	(segment
		(start 277.656544 -48.090836)
		(end 277.656544 -48.356012)
		(width 0.0889)
		(layer "In11.Cu")
		(net "M_C_DQ<34>")
	)
	(segment
		(start 276.119844 -56.695086)
		(end 276.113494 -56.684418)
		(width 0.0889)
		(layer "In11.Cu")
		(net "M_C_DQ<34>")
	)
	(segment
		(start 279.498552 -40.29075)
		(end 279.498552 -40.77081)
		(width 0.14224)
		(layer "In11.Cu")
		(net "M_C_DQ<34>")
	)
	(segment
		(start 277.656544 -48.356012)
		(end 276.610064 -49.402492)
		(width 0.0889)
		(layer "In11.Cu")
		(net "M_C_DQ<34>")
	)
	(segment
		(start 287.7058 -21.93417)
		(end 287.7058 -23.165054)
		(width 0.14224)
		(layer "In11.Cu")
		(net "M_C_DQ<34>")
	)
	(segment
		(start 288.0106 -14.459204)
		(end 288.0106 -14.732)
		(width 0.14224)
		(layer "In11.Cu")
		(net "M_C_DQ<34>")
	)
	(segment
		(start 287.826196 -15.2654)
		(end 288.036 -15.475204)
		(width 0.14224)
		(layer "In11.Cu")
		(net "M_C_DQ<34>")
	)
	(segment
		(start 287.96107 -18.67027)
		(end 287.96107 -18.87093)
		(width 0.14224)
		(layer "In11.Cu")
		(net "M_C_DQ<34>")
	)
	(segment
		(start 288.19983 0.9398)
		(end 287.801812 0.541782)
		(width 0.14224)
		(layer "In11.Cu")
		(net "M_C_DQ<34>")
	)
	(segment
		(start 278.910542 -40.13581)
		(end 279.343612 -40.13581)
		(width 0.14224)
		(layer "In11.Cu")
		(net "M_C_DQ<34>")
	)
	(segment
		(start 287.45688 -1.7526)
		(end 287.91408 -2.2098)
		(width 0.14224)
		(layer "In11.Cu")
		(net "M_C_DQ<34>")
	)
	(segment
		(start 287.843214 -9.362186)
		(end 287.5788 -9.6266)
		(width 0.14224)
		(layer "In11.Cu")
		(net "M_C_DQ<34>")
	)
	(segment
		(start 287.9598 -4.967732)
		(end 287.9598 -5.639054)
		(width 0.14224)
		(layer "In11.Cu")
		(net "M_C_DQ<34>")
	)
	(segment
		(start 287.716214 -7.365746)
		(end 287.716214 -8.798814)
		(width 0.14224)
		(layer "In11.Cu")
		(net "M_C_DQ<34>")
	)
	(segment
		(start 287.716214 -18.425414)
		(end 287.96107 -18.67027)
		(width 0.14224)
		(layer "In11.Cu")
		(net "M_C_DQ<34>")
	)
	(segment
		(start 276.610064 -49.402492)
		(end 276.610064 -52.39893)
		(width 0.0889)
		(layer "In11.Cu")
		(net "M_C_DQ<34>")
	)
	(segment
		(start 279.343612 -40.13581)
		(end 279.498552 -40.29075)
		(width 0.14224)
		(layer "In11.Cu")
		(net "M_C_DQ<34>")
	)
	(segment
		(start 287.801812 0.236728)
		(end 287.45688 -0.108204)
		(width 0.14224)
		(layer "In11.Cu")
		(net "M_C_DQ<34>")
	)
	(segment
		(start 276.12467 -55.713122)
		(end 276.119844 -55.704486)
		(width 0.0889)
		(layer "In11.Cu")
		(net "M_C_DQ<34>")
	)
	(segment
		(start 276.119844 -54.713886)
		(end 276.113494 -54.703218)
		(width 0.0889)
		(layer "In11.Cu")
		(net "M_C_DQ<34>")
	)
	(segment
		(start 287.5788 -9.6266)
		(end 287.5788 -10.007346)
		(width 0.14224)
		(layer "In11.Cu")
		(net "M_C_DQ<34>")
	)
	(segment
		(start 287.7312 -21.234146)
		(end 287.924748 -21.427694)
		(width 0.14224)
		(layer "In11.Cu")
		(net "M_C_DQ<34>")
	)
	(segment
		(start 287.782 -5.816854)
		(end 287.782 -6.5024)
		(width 0.14224)
		(layer "In11.Cu")
		(net "M_C_DQ<34>")
	)
	(segment
		(start 288.036 -15.748)
		(end 287.826196 -15.957804)
		(width 0.14224)
		(layer "In11.Cu")
		(net "M_C_DQ<34>")
	)
	(segment
		(start 279.498552 -40.77081)
		(end 279.343612 -40.92575)
		(width 0.14224)
		(layer "In11.Cu")
		(net "M_C_DQ<34>")
	)
	(segment
		(start 287.843214 -12.195556)
		(end 287.6296 -12.40917)
		(width 0.14224)
		(layer "In11.Cu")
		(net "M_C_DQ<34>")
	)
	(segment
		(start 288.036 -16.64716)
		(end 287.716214 -16.966946)
		(width 0.14224)
		(layer "In11.Cu")
		(net "M_C_DQ<34>")
	)
	(segment
		(start 276.610064 -52.39893)
		(end 276.040596 -52.968398)
		(width 0.0889)
		(layer "In11.Cu")
		(net "M_C_DQ<34>")
	)
	(segment
		(start 287.924748 -21.715222)
		(end 287.7058 -21.93417)
		(width 0.14224)
		(layer "In11.Cu")
		(net "M_C_DQ<34>")
	)
	(segment
		(start 276.040596 -52.968398)
		(end 276.040596 -53.427884)
		(width 0.0889)
		(layer "In11.Cu")
		(net "M_C_DQ<34>")
	)
	(segment
		(start 287.7058 -23.165054)
		(end 287.909 -23.368254)
		(width 0.14224)
		(layer "In11.Cu")
		(net "M_C_DQ<34>")
	)
	(segment
		(start 279.343612 -40.92575)
		(end 278.910542 -40.92575)
		(width 0.14224)
		(layer "In11.Cu")
		(net "M_C_DQ<34>")
	)
	(segment
		(start 278.755602 -39.50081)
		(end 278.755602 -39.98087)
		(width 0.14224)
		(layer "In11.Cu")
		(net "M_C_DQ<34>")
	)
	(segment
		(start 276.119844 -55.704486)
		(end 276.113494 -55.693818)
		(width 0.0889)
		(layer "In11.Cu")
		(net "M_C_DQ<34>")
	)
	(segment
		(start 287.843214 -8.925814)
		(end 287.843214 -9.362186)
		(width 0.14224)
		(layer "In11.Cu")
		(net "M_C_DQ<34>")
	)
	(segment
		(start 287.45688 -0.456946)
		(end 287.76168 -0.761746)
		(width 0.14224)
		(layer "In11.Cu")
		(net "M_C_DQ<34>")
	)
	(segment
		(start 279.343612 -39.34587)
		(end 278.910542 -39.34587)
		(width 0.14224)
		(layer "In11.Cu")
		(net "M_C_DQ<34>")
	)
	(segment
		(start 288.036 -16.4084)
		(end 288.036 -16.64716)
		(width 0.14224)
		(layer "In11.Cu")
		(net "M_C_DQ<34>")
	)
	(segment
		(start 276.12467 -56.703722)
		(end 276.119844 -56.695086)
		(width 0.0889)
		(layer "In11.Cu")
		(net "M_C_DQ<34>")
	)
	(arc
		(start 276.119844 -54.123336)
		(mid 276.173314 -53.928273)
		(end 276.12467 -53.731922)
		(width 0.0889)
		(layer "In11.Cu")
		(net "M_C_DQ<34>")
	)
	(arc
		(start 276.119844 -58.085736)
		(mid 276.173314 -57.890673)
		(end 276.12467 -57.694322)
		(width 0.0889)
		(layer "In11.Cu")
		(net "M_C_DQ<34>")
	)
	(arc
		(start 276.113494 -56.684418)
		(mid 276.040696 -56.393655)
		(end 276.119844 -56.104536)
		(width 0.0889)
		(layer "In11.Cu")
		(net "M_C_DQ<34>")
	)
	(arc
		(start 276.119844 -55.113936)
		(mid 276.173314 -54.918873)
		(end 276.12467 -54.722522)
		(width 0.0889)
		(layer "In11.Cu")
		(net "M_C_DQ<34>")
	)
	(arc
		(start 276.119844 -59.076336)
		(mid 276.173343 -58.876438)
		(end 276.119844 -58.67654)
		(width 0.0889)
		(layer "In11.Cu")
		(net "M_C_DQ<34>")
	)
	(arc
		(start 276.119844 -53.723286)
		(mid 276.060777 -53.5808)
		(end 276.040596 -53.427884)
		(width 0.0889)
		(layer "In11.Cu")
		(net "M_C_DQ<34>")
	)
	(arc
		(start 276.113494 -55.693818)
		(mid 276.040696 -55.403055)
		(end 276.119844 -55.113936)
		(width 0.0889)
		(layer "In11.Cu")
		(net "M_C_DQ<34>")
	)
	(arc
		(start 276.119844 -57.095136)
		(mid 276.173314 -56.900073)
		(end 276.12467 -56.703722)
		(width 0.0889)
		(layer "In11.Cu")
		(net "M_C_DQ<34>")
	)
	(arc
		(start 276.119844 -58.67654)
		(mid 276.040713 -58.381138)
		(end 276.119844 -58.085736)
		(width 0.0889)
		(layer "In11.Cu")
		(net "M_C_DQ<34>")
	)
	(arc
		(start 276.113494 -57.675018)
		(mid 276.040696 -57.384255)
		(end 276.119844 -57.095136)
		(width 0.0889)
		(layer "In11.Cu")
		(net "M_C_DQ<34>")
	)
	(arc
		(start 276.113494 -54.703218)
		(mid 276.040696 -54.412455)
		(end 276.119844 -54.123336)
		(width 0.0889)
		(layer "In11.Cu")
		(net "M_C_DQ<34>")
	)
	(arc
		(start 276.119844 -56.104536)
		(mid 276.173314 -55.909473)
		(end 276.12467 -55.713122)
		(width 0.0889)
		(layer "In11.Cu")
		(net "M_C_DQ<34>")
	)
	(segment
		(start 281.399996 3.778758)
		(end 281.399996 2.514854)
		(width 0.1651)
		(layer "F.Cu")
		(net "M_C_DQ<33>")
	)
	(segment
		(start 273.769328 -61.352938)
		(end 273.197828 -61.352938)
		(width 0.0889)
		(layer "F.Cu")
		(net "M_C_DQ<33>")
	)
	(segment
		(start 281.400504 3.778758)
		(end 281.399996 3.778758)
		(width 0.1651)
		(layer "F.Cu")
		(net "M_C_DQ<33>")
	)
	(via
		(at 273.197828 -61.352938)
		(size 0.508)
		(drill 0.254)
		(layers "F.Cu" "B.Cu")
		(net "M_C_DQ<33>")
	)
	(via
		(at 282.07208 -3.076956)
		(size 0.508)
		(drill 0.254)
		(layers "F.Cu" "B.Cu")
		(net "M_C_DQ<33>")
	)
	(via
		(at 281.399996 2.514854)
		(size 0.508)
		(drill 0.254)
		(layers "F.Cu" "B.Cu")
		(net "M_C_DQ<33>")
	)
	(segment
		(start 282.250388 -1.021842)
		(end 282.24988 -1.021842)
		(width 0.1651)
		(layer "B.Cu")
		(net "M_C_DQ<33>")
	)
	(segment
		(start 282.07208 -2.573782)
		(end 282.07208 -3.076956)
		(width 0.1651)
		(layer "B.Cu")
		(net "M_C_DQ<33>")
	)
	(segment
		(start 282.24988 -2.395982)
		(end 282.07208 -2.573782)
		(width 0.1651)
		(layer "B.Cu")
		(net "M_C_DQ<33>")
	)
	(segment
		(start 282.24988 -1.021842)
		(end 282.24988 -2.395982)
		(width 0.1651)
		(layer "B.Cu")
		(net "M_C_DQ<33>")
	)
	(segment
		(start 272.851118 -56.599836)
		(end 272.857468 -56.610504)
		(width 0.0889)
		(layer "In11.Cu")
		(net "M_C_DQ<33>")
	)
	(segment
		(start 272.846292 -55.6006)
		(end 272.851118 -55.609236)
		(width 0.0889)
		(layer "In11.Cu")
		(net "M_C_DQ<33>")
	)
	(segment
		(start 273.463512 -51.476402)
		(end 273.463766 -51.476656)
		(width 0.0889)
		(layer "In11.Cu")
		(net "M_C_DQ<33>")
	)
	(segment
		(start 281.9527 -26.8859)
		(end 281.686 -27.1526)
		(width 0.14224)
		(layer "In11.Cu")
		(net "M_C_DQ<33>")
	)
	(segment
		(start 272.838418 -54.574694)
		(end 272.930112 -54.666388)
		(width 0.0889)
		(layer "In11.Cu")
		(net "M_C_DQ<33>")
	)
	(segment
		(start 281.925014 -5.700014)
		(end 282.560014 -6.335014)
		(width 0.14224)
		(layer "In11.Cu")
		(net "M_C_DQ<33>")
	)
	(segment
		(start 282.446222 0.630936)
		(end 282.446222 -2.702814)
		(width 0.14224)
		(layer "In11.Cu")
		(net "M_C_DQ<33>")
	)
	(segment
		(start 281.877262 1.4986)
		(end 282.232862 1.4986)
		(width 0.14224)
		(layer "In11.Cu")
		(net "M_C_DQ<33>")
	)
	(segment
		(start 282.560014 -11.748516)
		(end 282.560014 -19.05)
		(width 0.14224)
		(layer "In11.Cu")
		(net "M_C_DQ<33>")
	)
	(segment
		(start 272.779744 -52.161186)
		(end 272.779236 -52.161694)
		(width 0.0889)
		(layer "In11.Cu")
		(net "M_C_DQ<33>")
	)
	(segment
		(start 272.850864 -60.561982)
		(end 273.197828 -61.352938)
		(width 0.0889)
		(layer "In11.Cu")
		(net "M_C_DQ<33>")
	)
	(segment
		(start 282.560014 -9.433814)
		(end 282.704032 -9.577832)
		(width 0.14224)
		(layer "In11.Cu")
		(net "M_C_DQ<33>")
	)
	(segment
		(start 281.399996 1.975866)
		(end 281.877262 1.4986)
		(width 0.14224)
		(layer "In11.Cu")
		(net "M_C_DQ<33>")
	)
	(segment
		(start 282.232862 1.4986)
		(end 282.602686 1.128776)
		(width 0.14224)
		(layer "In11.Cu")
		(net "M_C_DQ<33>")
	)
	(segment
		(start 282.07208 -3.076956)
		(end 281.545538 -3.603498)
		(width 0.14224)
		(layer "In11.Cu")
		(net "M_C_DQ<33>")
	)
	(segment
		(start 282.356814 -26.8859)
		(end 281.9527 -26.8859)
		(width 0.14224)
		(layer "In11.Cu")
		(net "M_C_DQ<33>")
	)
	(segment
		(start 281.686 -29.443172)
		(end 281.8892 -29.646372)
		(width 0.14224)
		(layer "In11.Cu")
		(net "M_C_DQ<33>")
	)
	(segment
		(start 281.545538 -3.872992)
		(end 281.925014 -4.252468)
		(width 0.14224)
		(layer "In11.Cu")
		(net "M_C_DQ<33>")
	)
	(segment
		(start 273.463512 -48.90262)
		(end 273.463512 -51.476402)
		(width 0.0889)
		(layer "In11.Cu")
		(net "M_C_DQ<33>")
	)
	(segment
		(start 281.686 -30.662372)
		(end 281.686 -30.898846)
		(width 0.14224)
		(layer "In11.Cu")
		(net "M_C_DQ<33>")
	)
	(segment
		(start 273.308064 -48.165004)
		(end 273.308064 -48.747172)
		(width 0.0889)
		(layer "In11.Cu")
		(net "M_C_DQ<33>")
	)
	(segment
		(start 281.8892 -29.646372)
		(end 282.0924 -29.646372)
		(width 0.14224)
		(layer "In11.Cu")
		(net "M_C_DQ<33>")
	)
	(segment
		(start 282.2956 -29.849572)
		(end 282.2956 -30.255972)
		(width 0.14224)
		(layer "In11.Cu")
		(net "M_C_DQ<33>")
	)
	(segment
		(start 273.308064 -48.747172)
		(end 273.463512 -48.90262)
		(width 0.0889)
		(layer "In11.Cu")
		(net "M_C_DQ<33>")
	)
	(segment
		(start 281.686 -27.1526)
		(end 281.686 -29.443172)
		(width 0.14224)
		(layer "In11.Cu")
		(net "M_C_DQ<33>")
	)
	(segment
		(start 272.779236 -52.758848)
		(end 272.838418 -52.81803)
		(width 0.0889)
		(layer "In11.Cu")
		(net "M_C_DQ<33>")
	)
	(segment
		(start 273.57451 -39.010336)
		(end 273.57451 -47.898558)
		(width 0.14224)
		(layer "In11.Cu")
		(net "M_C_DQ<33>")
	)
	(segment
		(start 272.851118 -57.590436)
		(end 272.857468 -57.601104)
		(width 0.0889)
		(layer "In11.Cu")
		(net "M_C_DQ<33>")
	)
	(segment
		(start 282.446222 -2.702814)
		(end 282.07208 -3.076956)
		(width 0.14224)
		(layer "In11.Cu")
		(net "M_C_DQ<33>")
	)
	(segment
		(start 282.2956 -30.255972)
		(end 282.0924 -30.459172)
		(width 0.14224)
		(layer "In11.Cu")
		(net "M_C_DQ<33>")
	)
	(segment
		(start 282.7274 -19.217386)
		(end 282.7274 -21.1582)
		(width 0.14224)
		(layer "In11.Cu")
		(net "M_C_DQ<33>")
	)
	(segment
		(start 272.930112 -54.666388)
		(end 272.930112 -54.914292)
		(width 0.0889)
		(layer "In11.Cu")
		(net "M_C_DQ<33>")
	)
	(segment
		(start 282.602686 0.7874)
		(end 282.446222 0.630936)
		(width 0.14224)
		(layer "In11.Cu")
		(net "M_C_DQ<33>")
	)
	(segment
		(start 282.560014 -26.6827)
		(end 282.356814 -26.8859)
		(width 0.14224)
		(layer "In11.Cu")
		(net "M_C_DQ<33>")
	)
	(segment
		(start 282.602686 1.128776)
		(end 282.602686 0.7874)
		(width 0.14224)
		(layer "In11.Cu")
		(net "M_C_DQ<33>")
	)
	(segment
		(start 272.779236 -52.161694)
		(end 272.779236 -52.758848)
		(width 0.0889)
		(layer "In11.Cu")
		(net "M_C_DQ<33>")
	)
	(segment
		(start 272.846292 -56.5912)
		(end 272.851118 -56.599836)
		(width 0.0889)
		(layer "In11.Cu")
		(net "M_C_DQ<33>")
	)
	(segment
		(start 282.704032 -9.577832)
		(end 282.704032 -11.604498)
		(width 0.14224)
		(layer "In11.Cu")
		(net "M_C_DQ<33>")
	)
	(segment
		(start 281.545538 -3.603498)
		(end 281.545538 -3.872992)
		(width 0.14224)
		(layer "In11.Cu")
		(net "M_C_DQ<33>")
	)
	(segment
		(start 282.0924 -29.646372)
		(end 282.2956 -29.849572)
		(width 0.14224)
		(layer "In11.Cu")
		(net "M_C_DQ<33>")
	)
	(segment
		(start 281.686 -30.898846)
		(end 273.57451 -39.010336)
		(width 0.14224)
		(layer "In11.Cu")
		(net "M_C_DQ<33>")
	)
	(segment
		(start 282.560014 -19.05)
		(end 282.7274 -19.217386)
		(width 0.14224)
		(layer "In11.Cu")
		(net "M_C_DQ<33>")
	)
	(segment
		(start 272.851118 -55.609236)
		(end 272.857468 -55.619904)
		(width 0.0889)
		(layer "In11.Cu")
		(net "M_C_DQ<33>")
	)
	(segment
		(start 273.57451 -47.898558)
		(end 273.308064 -48.165004)
		(width 0.0889)
		(layer "In11.Cu")
		(net "M_C_DQ<33>")
	)
	(segment
		(start 273.463766 -51.476656)
		(end 272.779744 -52.160678)
		(width 0.0889)
		(layer "In11.Cu")
		(net "M_C_DQ<33>")
	)
	(segment
		(start 282.0924 -30.459172)
		(end 281.8892 -30.459172)
		(width 0.14224)
		(layer "In11.Cu")
		(net "M_C_DQ<33>")
	)
	(segment
		(start 282.560014 -21.325586)
		(end 282.560014 -26.6827)
		(width 0.14224)
		(layer "In11.Cu")
		(net "M_C_DQ<33>")
	)
	(segment
		(start 282.560014 -6.335014)
		(end 282.560014 -9.433814)
		(width 0.14224)
		(layer "In11.Cu")
		(net "M_C_DQ<33>")
	)
	(segment
		(start 281.8892 -30.459172)
		(end 281.686 -30.662372)
		(width 0.14224)
		(layer "In11.Cu")
		(net "M_C_DQ<33>")
	)
	(segment
		(start 281.925014 -4.252468)
		(end 281.925014 -5.700014)
		(width 0.14224)
		(layer "In11.Cu")
		(net "M_C_DQ<33>")
	)
	(segment
		(start 282.704032 -11.604498)
		(end 282.560014 -11.748516)
		(width 0.14224)
		(layer "In11.Cu")
		(net "M_C_DQ<33>")
	)
	(segment
		(start 272.779744 -52.160678)
		(end 272.779744 -52.161186)
		(width 0.0889)
		(layer "In11.Cu")
		(net "M_C_DQ<33>")
	)
	(segment
		(start 272.846292 -57.5818)
		(end 272.851118 -57.590436)
		(width 0.0889)
		(layer "In11.Cu")
		(net "M_C_DQ<33>")
	)
	(segment
		(start 282.7274 -21.1582)
		(end 282.560014 -21.325586)
		(width 0.14224)
		(layer "In11.Cu")
		(net "M_C_DQ<33>")
	)
	(segment
		(start 281.399996 2.514854)
		(end 281.399996 1.975866)
		(width 0.14224)
		(layer "In11.Cu")
		(net "M_C_DQ<33>")
	)
	(segment
		(start 272.838418 -52.81803)
		(end 272.838418 -54.574694)
		(width 0.0889)
		(layer "In11.Cu")
		(net "M_C_DQ<33>")
	)
	(arc
		(start 272.850864 -58.580782)
		(mid 273.060825 -58.832569)
		(end 273.34337 -58.998866)
		(width 0.0889)
		(layer "In11.Cu")
		(net "M_C_DQ<33>")
	)
	(arc
		(start 272.851118 -57.190386)
		(mid 272.797648 -57.385449)
		(end 272.846292 -57.5818)
		(width 0.0889)
		(layer "In11.Cu")
		(net "M_C_DQ<33>")
	)
	(arc
		(start 272.851118 -55.209186)
		(mid 272.797648 -55.404249)
		(end 272.846292 -55.6006)
		(width 0.0889)
		(layer "In11.Cu")
		(net "M_C_DQ<33>")
	)
	(arc
		(start 272.851118 -56.199786)
		(mid 272.797648 -56.394849)
		(end 272.846292 -56.5912)
		(width 0.0889)
		(layer "In11.Cu")
		(net "M_C_DQ<33>")
	)
	(arc
		(start 273.515074 -59.61507)
		(mid 273.306439 -59.837264)
		(end 273.044158 -59.992514)
		(width 0.0889)
		(layer "In11.Cu")
		(net "M_C_DQ<33>")
	)
	(arc
		(start 272.857468 -55.619904)
		(mid 272.930266 -55.910667)
		(end 272.851118 -56.199786)
		(width 0.0889)
		(layer "In11.Cu")
		(net "M_C_DQ<33>")
	)
	(arc
		(start 272.857468 -56.610504)
		(mid 272.930266 -56.901267)
		(end 272.851118 -57.190386)
		(width 0.0889)
		(layer "In11.Cu")
		(net "M_C_DQ<33>")
	)
	(arc
		(start 272.850864 -58.180986)
		(mid 272.797365 -58.380884)
		(end 272.850864 -58.580782)
		(width 0.0889)
		(layer "In11.Cu")
		(net "M_C_DQ<33>")
	)
	(arc
		(start 272.857468 -57.601104)
		(mid 272.929954 -57.891897)
		(end 272.850864 -58.180986)
		(width 0.0889)
		(layer "In11.Cu")
		(net "M_C_DQ<33>")
	)
	(arc
		(start 273.044158 -59.992514)
		(mid 272.81865 -60.233494)
		(end 272.850864 -60.561982)
		(width 0.0889)
		(layer "In11.Cu")
		(net "M_C_DQ<33>")
	)
	(arc
		(start 272.930112 -54.914292)
		(mid 272.910025 -55.066939)
		(end 272.851118 -55.209186)
		(width 0.0889)
		(layer "In11.Cu")
		(net "M_C_DQ<33>")
	)
	(arc
		(start 273.34337 -58.998866)
		(mid 273.583021 -59.264099)
		(end 273.515074 -59.61507)
		(width 0.0889)
		(layer "In11.Cu")
		(net "M_C_DQ<33>")
	)
	(segment
		(start 282.24988 -0.821182)
		(end 282.07208 1.0414)
		(width 0.1651)
		(layer "F.Cu")
		(net "M_C_DQ<32>")
	)
	(segment
		(start 273.769328 -59.371484)
		(end 273.197828 -59.371484)
		(width 0.0889)
		(layer "F.Cu")
		(net "M_C_DQ<32>")
	)
	(segment
		(start 282.250388 -0.821182)
		(end 282.24988 -0.821182)
		(width 0.1651)
		(layer "F.Cu")
		(net "M_C_DQ<32>")
	)
	(via
		(at 273.197828 -59.371484)
		(size 0.508)
		(drill 0.254)
		(layers "F.Cu" "B.Cu")
		(net "M_C_DQ<32>")
	)
	(via
		(at 282.07208 1.0414)
		(size 0.508)
		(drill 0.254)
		(layers "F.Cu" "B.Cu")
		(net "M_C_DQ<32>")
	)
	(via
		(at 281.399996 -4.357878)
		(size 0.508)
		(drill 0.254)
		(layers "F.Cu" "B.Cu")
		(net "M_C_DQ<32>")
	)
	(segment
		(start 281.399996 -5.621782)
		(end 281.399996 -4.357878)
		(width 0.1651)
		(layer "B.Cu")
		(net "M_C_DQ<32>")
	)
	(segment
		(start 281.400504 -5.621782)
		(end 281.399996 -5.621782)
		(width 0.1651)
		(layer "B.Cu")
		(net "M_C_DQ<32>")
	)
	(segment
		(start 280.161492 -30.605476)
		(end 279.960324 -30.605476)
		(width 0.14224)
		(layer "In11.Cu")
		(net "M_C_DQ<32>")
	)
	(segment
		(start 277.603712 -34.08299)
		(end 272.828258 -38.859968)
		(width 0.14224)
		(layer "In11.Cu")
		(net "M_C_DQ<32>")
	)
	(segment
		(start 272.679668 -56.684418)
		(end 272.686018 -56.695086)
		(width 0.0889)
		(layer "In11.Cu")
		(net "M_C_DQ<32>")
	)
	(segment
		(start 279.90292 -31.783782)
		(end 279.615138 -32.071564)
		(width 0.14224)
		(layer "In11.Cu")
		(net "M_C_DQ<32>")
	)
	(segment
		(start 281.582114 -8.684514)
		(end 281.8638 -8.9662)
		(width 0.14224)
		(layer "In11.Cu")
		(net "M_C_DQ<32>")
	)
	(segment
		(start 279.58669 -30.97911)
		(end 279.58669 -31.180278)
		(width 0.14224)
		(layer "In11.Cu")
		(net "M_C_DQ<32>")
	)
	(segment
		(start 281.603196 -21.989796)
		(end 281.603196 -23.094696)
		(width 0.14224)
		(layer "In11.Cu")
		(net "M_C_DQ<32>")
	)
	(segment
		(start 281.78125 -21.20265)
		(end 281.8384 -21.2598)
		(width 0.14224)
		(layer "In11.Cu")
		(net "M_C_DQ<32>")
	)
	(segment
		(start 273.15541 -59.326526)
		(end 273.197828 -59.371484)
		(width 0.0889)
		(layer "In11.Cu")
		(net "M_C_DQ<32>")
	)
	(segment
		(start 278.194008 -31.799784)
		(end 278.194008 -32.086804)
		(width 0.14224)
		(layer "In11.Cu")
		(net "M_C_DQ<32>")
	)
	(segment
		(start 279.960324 -30.605476)
		(end 279.58669 -30.97911)
		(width 0.14224)
		(layer "In11.Cu")
		(net "M_C_DQ<32>")
	)
	(segment
		(start 281.115262 -4.073144)
		(end 281.399996 -4.357878)
		(width 0.14224)
		(layer "In11.Cu")
		(net "M_C_DQ<32>")
	)
	(segment
		(start 281.925014 -16.778986)
		(end 281.582114 -17.121886)
		(width 0.14224)
		(layer "In11.Cu")
		(net "M_C_DQ<32>")
	)
	(segment
		(start 279.58669 -31.180278)
		(end 279.90292 -31.496508)
		(width 0.14224)
		(layer "In11.Cu")
		(net "M_C_DQ<32>")
	)
	(segment
		(start 281.7368 -11.597386)
		(end 281.8384 -11.698986)
		(width 0.14224)
		(layer "In11.Cu")
		(net "M_C_DQ<32>")
	)
	(segment
		(start 281.582114 -7.520686)
		(end 281.582114 -8.684514)
		(width 0.14224)
		(layer "In11.Cu")
		(net "M_C_DQ<32>")
	)
	(segment
		(start 278.48179 -31.512002)
		(end 278.194008 -31.799784)
		(width 0.14224)
		(layer "In11.Cu")
		(net "M_C_DQ<32>")
	)
	(segment
		(start 281.925014 -13.853668)
		(end 281.925014 -16.778986)
		(width 0.14224)
		(layer "In11.Cu")
		(net "M_C_DQ<32>")
	)
	(segment
		(start 281.7368 -9.6012)
		(end 281.7368 -11.597386)
		(width 0.14224)
		(layer "In11.Cu")
		(net "M_C_DQ<32>")
	)
	(segment
		(start 281.582114 -17.121886)
		(end 281.582114 -18.311114)
		(width 0.14224)
		(layer "In11.Cu")
		(net "M_C_DQ<32>")
	)
	(segment
		(start 277.93061 -32.973264)
		(end 277.643844 -32.973264)
		(width 0.14224)
		(layer "In11.Cu")
		(net "M_C_DQ<32>")
	)
	(segment
		(start 277.356062 -33.261046)
		(end 277.356062 -33.548066)
		(width 0.14224)
		(layer "In11.Cu")
		(net "M_C_DQ<32>")
	)
	(segment
		(start 273.273012 -48.981614)
		(end 273.273012 -51.397154)
		(width 0.0889)
		(layer "In11.Cu")
		(net "M_C_DQ<32>")
	)
	(segment
		(start 272.647918 -54.653688)
		(end 272.739612 -54.745382)
		(width 0.0889)
		(layer "In11.Cu")
		(net "M_C_DQ<32>")
	)
	(segment
		(start 281.8638 -8.9662)
		(end 281.8638 -9.4742)
		(width 0.14224)
		(layer "In11.Cu")
		(net "M_C_DQ<32>")
	)
	(segment
		(start 278.178514 -33.221168)
		(end 277.93061 -32.973264)
		(width 0.14224)
		(layer "In11.Cu")
		(net "M_C_DQ<32>")
	)
	(segment
		(start 278.194008 -32.086804)
		(end 278.753316 -32.646112)
		(width 0.14224)
		(layer "In11.Cu")
		(net "M_C_DQ<32>")
	)
	(segment
		(start 279.615138 -32.071564)
		(end 279.328118 -32.071564)
		(width 0.14224)
		(layer "In11.Cu")
		(net "M_C_DQ<32>")
	)
	(segment
		(start 281.8638 -9.4742)
		(end 281.7368 -9.6012)
		(width 0.14224)
		(layer "In11.Cu")
		(net "M_C_DQ<32>")
	)
	(segment
		(start 281.874214 -7.228586)
		(end 281.582114 -7.520686)
		(width 0.14224)
		(layer "In11.Cu")
		(net "M_C_DQ<32>")
	)
	(segment
		(start 272.686018 -56.695086)
		(end 272.690844 -56.703722)
		(width 0.0889)
		(layer "In11.Cu")
		(net "M_C_DQ<32>")
	)
	(segment
		(start 279.90292 -31.496508)
		(end 279.90292 -31.783782)
		(width 0.14224)
		(layer "In11.Cu")
		(net "M_C_DQ<32>")
	)
	(segment
		(start 272.685764 -58.676286)
		(end 272.689828 -58.683398)
		(width 0.0889)
		(layer "In11.Cu")
		(net "M_C_DQ<32>")
	)
	(segment
		(start 281.051 -26.797)
		(end 281.051 -30.635702)
		(width 0.14224)
		(layer "In11.Cu")
		(net "M_C_DQ<32>")
	)
	(segment
		(start 281.882596 -25.965404)
		(end 281.051 -26.797)
		(width 0.14224)
		(layer "In11.Cu")
		(net "M_C_DQ<32>")
	)
	(segment
		(start 272.58899 -52.837334)
		(end 272.647918 -52.896262)
		(width 0.0889)
		(layer "In11.Cu")
		(net "M_C_DQ<32>")
	)
	(segment
		(start 273.117564 -48.076612)
		(end 273.117564 -48.826166)
		(width 0.0889)
		(layer "In11.Cu")
		(net "M_C_DQ<32>")
	)
	(segment
		(start 281.78125 -19.193764)
		(end 281.78125 -21.20265)
		(width 0.14224)
		(layer "In11.Cu")
		(net "M_C_DQ<32>")
	)
	(segment
		(start 281.603196 -23.094696)
		(end 281.882596 -23.374096)
		(width 0.14224)
		(layer "In11.Cu")
		(net "M_C_DQ<32>")
	)
	(segment
		(start 281.051 -30.635702)
		(end 280.764742 -30.92196)
		(width 0.14224)
		(layer "In11.Cu")
		(net "M_C_DQ<32>")
	)
	(segment
		(start 281.8384 -21.2598)
		(end 281.8384 -21.754592)
		(width 0.14224)
		(layer "In11.Cu")
		(net "M_C_DQ<32>")
	)
	(segment
		(start 281.857196 -19.117818)
		(end 281.78125 -19.193764)
		(width 0.14224)
		(layer "In11.Cu")
		(net "M_C_DQ<32>")
	)
	(segment
		(start 272.679668 -57.675018)
		(end 272.686018 -57.685686)
		(width 0.0889)
		(layer "In11.Cu")
		(net "M_C_DQ<32>")
	)
	(segment
		(start 281.46248 -1.701546)
		(end 281.851862 -2.090928)
		(width 0.14224)
		(layer "In11.Cu")
		(net "M_C_DQ<32>")
	)
	(segment
		(start 281.77998 -1.0795)
		(end 281.46248 -1.397)
		(width 0.14224)
		(layer "In11.Cu")
		(net "M_C_DQ<32>")
	)
	(segment
		(start 277.356062 -33.548066)
		(end 277.603712 -33.795716)
		(width 0.14224)
		(layer "In11.Cu")
		(net "M_C_DQ<32>")
	)
	(segment
		(start 281.582114 -12.424156)
		(end 281.582114 -13.510768)
		(width 0.14224)
		(layer "In11.Cu")
		(net "M_C_DQ<32>")
	)
	(segment
		(start 278.465534 -33.221168)
		(end 278.178514 -33.221168)
		(width 0.14224)
		(layer "In11.Cu")
		(net "M_C_DQ<32>")
	)
	(segment
		(start 277.603712 -33.795716)
		(end 277.603712 -34.08299)
		(width 0.14224)
		(layer "In11.Cu")
		(net "M_C_DQ<32>")
	)
	(segment
		(start 281.582114 -13.510768)
		(end 281.925014 -13.853668)
		(width 0.14224)
		(layer "In11.Cu")
		(net "M_C_DQ<32>")
	)
	(segment
		(start 272.686018 -57.685686)
		(end 272.690844 -57.694322)
		(width 0.0889)
		(layer "In11.Cu")
		(net "M_C_DQ<32>")
	)
	(segment
		(start 272.679668 -55.693818)
		(end 272.686018 -55.704486)
		(width 0.0889)
		(layer "In11.Cu")
		(net "M_C_DQ<32>")
	)
	(segment
		(start 273.273012 -51.397154)
		(end 272.58899 -52.081176)
		(width 0.0889)
		(layer "In11.Cu")
		(net "M_C_DQ<32>")
	)
	(segment
		(start 281.851862 -2.090928)
		(end 281.851862 -2.5908)
		(width 0.14224)
		(layer "In11.Cu")
		(net "M_C_DQ<32>")
	)
	(segment
		(start 281.399996 -4.357878)
		(end 281.399996 -6.140196)
		(width 0.14224)
		(layer "In11.Cu")
		(net "M_C_DQ<32>")
	)
	(segment
		(start 278.753316 -32.646112)
		(end 278.753316 -32.933386)
		(width 0.14224)
		(layer "In11.Cu")
		(net "M_C_DQ<32>")
	)
	(segment
		(start 281.399996 -6.140196)
		(end 281.874214 -6.614414)
		(width 0.14224)
		(layer "In11.Cu")
		(net "M_C_DQ<32>")
	)
	(segment
		(start 280.764742 -30.92196)
		(end 280.477976 -30.92196)
		(width 0.14224)
		(layer "In11.Cu")
		(net "M_C_DQ<32>")
	)
	(segment
		(start 281.857196 -18.586196)
		(end 281.857196 -19.117818)
		(width 0.14224)
		(layer "In11.Cu")
		(net "M_C_DQ<32>")
	)
	(segment
		(start 281.851862 0.236728)
		(end 281.43708 -0.178054)
		(width 0.14224)
		(layer "In11.Cu")
		(net "M_C_DQ<32>")
	)
	(segment
		(start 282.07208 1.0414)
		(end 281.851862 0.821182)
		(width 0.14224)
		(layer "In11.Cu")
		(net "M_C_DQ<32>")
	)
	(segment
		(start 281.874214 -6.614414)
		(end 281.874214 -7.228586)
		(width 0.14224)
		(layer "In11.Cu")
		(net "M_C_DQ<32>")
	)
	(segment
		(start 272.739612 -54.745382)
		(end 272.739612 -54.913784)
		(width 0.0889)
		(layer "In11.Cu")
		(net "M_C_DQ<32>")
	)
	(segment
		(start 281.8384 -11.698986)
		(end 281.8384 -12.16787)
		(width 0.14224)
		(layer "In11.Cu")
		(net "M_C_DQ<32>")
	)
	(segment
		(start 281.43708 -0.178054)
		(end 281.43708 -0.508)
		(width 0.14224)
		(layer "In11.Cu")
		(net "M_C_DQ<32>")
	)
	(segment
		(start 281.582114 -18.311114)
		(end 281.857196 -18.586196)
		(width 0.14224)
		(layer "In11.Cu")
		(net "M_C_DQ<32>")
	)
	(segment
		(start 278.768556 -31.512002)
		(end 278.48179 -31.512002)
		(width 0.14224)
		(layer "In11.Cu")
		(net "M_C_DQ<32>")
	)
	(segment
		(start 281.77998 -0.8509)
		(end 281.77998 -1.0795)
		(width 0.14224)
		(layer "In11.Cu")
		(net "M_C_DQ<32>")
	)
	(segment
		(start 281.115262 -3.3274)
		(end 281.115262 -4.073144)
		(width 0.14224)
		(layer "In11.Cu")
		(net "M_C_DQ<32>")
	)
	(segment
		(start 280.477976 -30.92196)
		(end 280.161492 -30.605476)
		(width 0.14224)
		(layer "In11.Cu")
		(net "M_C_DQ<32>")
	)
	(segment
		(start 281.8384 -12.16787)
		(end 281.582114 -12.424156)
		(width 0.14224)
		(layer "In11.Cu")
		(net "M_C_DQ<32>")
	)
	(segment
		(start 281.8384 -21.754592)
		(end 281.603196 -21.989796)
		(width 0.14224)
		(layer "In11.Cu")
		(net "M_C_DQ<32>")
	)
	(segment
		(start 273.117564 -48.826166)
		(end 273.273012 -48.981614)
		(width 0.0889)
		(layer "In11.Cu")
		(net "M_C_DQ<32>")
	)
	(segment
		(start 272.686018 -55.704486)
		(end 272.690844 -55.713122)
		(width 0.0889)
		(layer "In11.Cu")
		(net "M_C_DQ<32>")
	)
	(segment
		(start 281.46248 -1.397)
		(end 281.46248 -1.701546)
		(width 0.14224)
		(layer "In11.Cu")
		(net "M_C_DQ<32>")
	)
	(segment
		(start 272.93951 -47.898558)
		(end 273.117564 -48.076612)
		(width 0.0889)
		(layer "In11.Cu")
		(net "M_C_DQ<32>")
	)
	(segment
		(start 272.647918 -52.896262)
		(end 272.647918 -54.653688)
		(width 0.0889)
		(layer "In11.Cu")
		(net "M_C_DQ<32>")
	)
	(segment
		(start 281.43708 -0.508)
		(end 281.77998 -0.8509)
		(width 0.14224)
		(layer "In11.Cu")
		(net "M_C_DQ<32>")
	)
	(segment
		(start 281.851862 0.821182)
		(end 281.851862 0.236728)
		(width 0.14224)
		(layer "In11.Cu")
		(net "M_C_DQ<32>")
	)
	(segment
		(start 281.851862 -2.5908)
		(end 281.115262 -3.3274)
		(width 0.14224)
		(layer "In11.Cu")
		(net "M_C_DQ<32>")
	)
	(segment
		(start 278.753316 -32.933386)
		(end 278.465534 -33.221168)
		(width 0.14224)
		(layer "In11.Cu")
		(net "M_C_DQ<32>")
	)
	(segment
		(start 272.828258 -47.787306)
		(end 272.93951 -47.898558)
		(width 0.14224)
		(layer "In11.Cu")
		(net "M_C_DQ<32>")
	)
	(segment
		(start 281.882596 -23.374096)
		(end 281.882596 -25.965404)
		(width 0.14224)
		(layer "In11.Cu")
		(net "M_C_DQ<32>")
	)
	(segment
		(start 272.58899 -52.081176)
		(end 272.58899 -52.837334)
		(width 0.0889)
		(layer "In11.Cu")
		(net "M_C_DQ<32>")
	)
	(segment
		(start 272.828258 -38.859968)
		(end 272.828258 -47.787306)
		(width 0.14224)
		(layer "In11.Cu")
		(net "M_C_DQ<32>")
	)
	(segment
		(start 279.328118 -32.071564)
		(end 278.768556 -31.512002)
		(width 0.14224)
		(layer "In11.Cu")
		(net "M_C_DQ<32>")
	)
	(segment
		(start 277.643844 -32.973264)
		(end 277.356062 -33.261046)
		(width 0.14224)
		(layer "In11.Cu")
		(net "M_C_DQ<32>")
	)
	(arc
		(start 272.686018 -56.104536)
		(mid 272.606796 -56.393654)
		(end 272.679668 -56.684418)
		(width 0.0889)
		(layer "In11.Cu")
		(net "M_C_DQ<32>")
	)
	(arc
		(start 272.686018 -55.113936)
		(mid 272.606796 -55.403054)
		(end 272.679668 -55.693818)
		(width 0.0889)
		(layer "In11.Cu")
		(net "M_C_DQ<32>")
	)
	(arc
		(start 272.689828 -58.683398)
		(mid 272.906049 -59.016957)
		(end 273.15541 -59.326526)
		(width 0.0889)
		(layer "In11.Cu")
		(net "M_C_DQ<32>")
	)
	(arc
		(start 272.690844 -57.694322)
		(mid 272.73932 -57.89056)
		(end 272.685764 -58.085482)
		(width 0.0889)
		(layer "In11.Cu")
		(net "M_C_DQ<32>")
	)
	(arc
		(start 272.685764 -58.085482)
		(mid 272.606633 -58.380884)
		(end 272.685764 -58.676286)
		(width 0.0889)
		(layer "In11.Cu")
		(net "M_C_DQ<32>")
	)
	(arc
		(start 272.690844 -56.703722)
		(mid 272.739599 -56.900074)
		(end 272.686018 -57.095136)
		(width 0.0889)
		(layer "In11.Cu")
		(net "M_C_DQ<32>")
	)
	(arc
		(start 272.690844 -55.713122)
		(mid 272.739599 -55.909474)
		(end 272.686018 -56.104536)
		(width 0.0889)
		(layer "In11.Cu")
		(net "M_C_DQ<32>")
	)
	(arc
		(start 272.686018 -57.095136)
		(mid 272.606796 -57.384254)
		(end 272.679668 -57.675018)
		(width 0.0889)
		(layer "In11.Cu")
		(net "M_C_DQ<32>")
	)
	(arc
		(start 272.739612 -54.913784)
		(mid 272.726028 -55.017402)
		(end 272.686018 -55.113936)
		(width 0.0889)
		(layer "In11.Cu")
		(net "M_C_DQ<32>")
	)
	(segment
		(start 250.778264 -66.982086)
		(end 250.206764 -66.982086)
		(width 0.0889)
		(layer "F.Cu")
		(net "M_C_DQ<31>")
	)
	(segment
		(start 230.399844 3.778758)
		(end 230.399844 2.514854)
		(width 0.1651)
		(layer "F.Cu")
		(net "M_C_DQ<31>")
	)
	(segment
		(start 230.400352 3.778758)
		(end 230.399844 3.778758)
		(width 0.1651)
		(layer "F.Cu")
		(net "M_C_DQ<31>")
	)
	(via
		(at 250.206764 -66.982086)
		(size 0.508)
		(drill 0.254)
		(layers "F.Cu" "B.Cu")
		(net "M_C_DQ<31>")
	)
	(via
		(at 230.399844 2.514854)
		(size 0.508)
		(drill 0.254)
		(layers "F.Cu" "B.Cu")
		(net "M_C_DQ<31>")
	)
	(via
		(at 231.249728 -3.076956)
		(size 0.508)
		(drill 0.254)
		(layers "F.Cu" "B.Cu")
		(net "M_C_DQ<31>")
	)
	(segment
		(start 231.25049 -3.076194)
		(end 231.249728 -3.076956)
		(width 0.1651)
		(layer "B.Cu")
		(net "M_C_DQ<31>")
	)
	(segment
		(start 231.25049 -1.021842)
		(end 231.25049 -3.076194)
		(width 0.1651)
		(layer "B.Cu")
		(net "M_C_DQ<31>")
	)
	(segment
		(start 231.831134 -7.492746)
		(end 231.831134 -8.732266)
		(width 0.14224)
		(layer "In11.Cu")
		(net "M_C_DQ<31>")
	)
	(segment
		(start 250.713748 -56.772302)
		(end 250.718574 -56.780938)
		(width 0.0889)
		(layer "In11.Cu")
		(net "M_C_DQ<31>")
	)
	(segment
		(start 250.718574 -62.724538)
		(end 250.724924 -62.735206)
		(width 0.0889)
		(layer "In11.Cu")
		(net "M_C_DQ<31>")
	)
	(segment
		(start 248.816876 -50.072036)
		(end 248.661174 -50.227738)
		(width 0.0889)
		(layer "In11.Cu")
		(net "M_C_DQ<31>")
	)
	(segment
		(start 231.590596 -28.314396)
		(end 231.590596 -28.891484)
		(width 0.14224)
		(layer "In11.Cu")
		(net "M_C_DQ<31>")
	)
	(segment
		(start 231.805734 -13.516356)
		(end 231.627934 -13.694156)
		(width 0.14224)
		(layer "In11.Cu")
		(net "M_C_DQ<31>")
	)
	(segment
		(start 231.590596 -28.891484)
		(end 238.9378 -36.238688)
		(width 0.14224)
		(layer "In11.Cu")
		(net "M_C_DQ<31>")
	)
	(segment
		(start 231.602534 0.581152)
		(end 231.602534 -2.72415)
		(width 0.14224)
		(layer "In11.Cu")
		(net "M_C_DQ<31>")
	)
	(segment
		(start 238.9378 -38.615366)
		(end 249.002804 -48.68037)
		(width 0.14224)
		(layer "In11.Cu")
		(net "M_C_DQ<31>")
	)
	(segment
		(start 249.88774 -52.543202)
		(end 249.88774 -53.937154)
		(width 0.0889)
		(layer "In11.Cu")
		(net "M_C_DQ<31>")
	)
	(segment
		(start 250.713748 -60.734702)
		(end 250.718574 -60.743338)
		(width 0.0889)
		(layer "In11.Cu")
		(net "M_C_DQ<31>")
	)
	(segment
		(start 231.300782 1.5494)
		(end 231.757982 1.0922)
		(width 0.14224)
		(layer "In11.Cu")
		(net "M_C_DQ<31>")
	)
	(segment
		(start 249.002804 -48.68037)
		(end 249.002804 -49.636934)
		(width 0.14224)
		(layer "In11.Cu")
		(net "M_C_DQ<31>")
	)
	(segment
		(start 231.805734 -23.117556)
		(end 231.627934 -23.295356)
		(width 0.14224)
		(layer "In11.Cu")
		(net "M_C_DQ<31>")
	)
	(segment
		(start 231.627934 -16.890746)
		(end 231.831134 -17.093946)
		(width 0.14224)
		(layer "In11.Cu")
		(net "M_C_DQ<31>")
	)
	(segment
		(start 231.831134 -8.732266)
		(end 231.602534 -8.960866)
		(width 0.14224)
		(layer "In11.Cu")
		(net "M_C_DQ<31>")
	)
	(segment
		(start 231.805734 -12.373356)
		(end 231.805734 -13.516356)
		(width 0.14224)
		(layer "In11.Cu")
		(net "M_C_DQ<31>")
	)
	(segment
		(start 250.713748 -62.715902)
		(end 250.718574 -62.724538)
		(width 0.0889)
		(layer "In11.Cu")
		(net "M_C_DQ<31>")
	)
	(segment
		(start 231.7496 -21.138134)
		(end 231.602534 -21.2852)
		(width 0.14224)
		(layer "In11.Cu")
		(net "M_C_DQ<31>")
	)
	(segment
		(start 238.9378 -36.238688)
		(end 238.9378 -38.615366)
		(width 0.14224)
		(layer "In11.Cu")
		(net "M_C_DQ<31>")
	)
	(segment
		(start 231.602534 -21.771356)
		(end 231.805734 -21.974556)
		(width 0.14224)
		(layer "In11.Cu")
		(net "M_C_DQ<31>")
	)
	(segment
		(start 231.602534 -18.587466)
		(end 231.602534 -19.080734)
		(width 0.14224)
		(layer "In11.Cu")
		(net "M_C_DQ<31>")
	)
	(segment
		(start 231.805734 -21.974556)
		(end 231.805734 -23.117556)
		(width 0.14224)
		(layer "In11.Cu")
		(net "M_C_DQ<31>")
	)
	(segment
		(start 248.816876 -49.822862)
		(end 248.816876 -50.072036)
		(width 0.0889)
		(layer "In11.Cu")
		(net "M_C_DQ<31>")
	)
	(segment
		(start 231.158034 -4.782312)
		(end 231.627934 -5.252212)
		(width 0.14224)
		(layer "In11.Cu")
		(net "M_C_DQ<31>")
	)
	(segment
		(start 250.553474 -66.191638)
		(end 250.206764 -66.982086)
		(width 0.0889)
		(layer "In11.Cu")
		(net "M_C_DQ<31>")
	)
	(segment
		(start 248.661174 -51.316636)
		(end 249.88774 -52.543202)
		(width 0.0889)
		(layer "In11.Cu")
		(net "M_C_DQ<31>")
	)
	(segment
		(start 231.757982 0.7366)
		(end 231.602534 0.581152)
		(width 0.14224)
		(layer "In11.Cu")
		(net "M_C_DQ<31>")
	)
	(segment
		(start 231.627934 -6.44017)
		(end 231.551734 -6.51637)
		(width 0.14224)
		(layer "In11.Cu")
		(net "M_C_DQ<31>")
	)
	(segment
		(start 231.602534 -12.170156)
		(end 231.805734 -12.373356)
		(width 0.14224)
		(layer "In11.Cu")
		(net "M_C_DQ<31>")
	)
	(segment
		(start 250.713748 -59.744102)
		(end 250.718574 -59.752738)
		(width 0.0889)
		(layer "In11.Cu")
		(net "M_C_DQ<31>")
	)
	(segment
		(start 250.713748 -61.725302)
		(end 250.718574 -61.733938)
		(width 0.0889)
		(layer "In11.Cu")
		(net "M_C_DQ<31>")
	)
	(segment
		(start 250.713748 -57.762902)
		(end 250.718574 -57.771538)
		(width 0.0889)
		(layer "In11.Cu")
		(net "M_C_DQ<31>")
	)
	(segment
		(start 231.757982 1.0922)
		(end 231.757982 0.7366)
		(width 0.14224)
		(layer "In11.Cu")
		(net "M_C_DQ<31>")
	)
	(segment
		(start 231.158034 -4.435856)
		(end 231.158034 -4.782312)
		(width 0.14224)
		(layer "In11.Cu")
		(net "M_C_DQ<31>")
	)
	(segment
		(start 231.602534 -8.960866)
		(end 231.602534 -9.428734)
		(width 0.14224)
		(layer "In11.Cu")
		(net "M_C_DQ<31>")
	)
	(segment
		(start 231.627934 -5.252212)
		(end 231.627934 -6.44017)
		(width 0.14224)
		(layer "In11.Cu")
		(net "M_C_DQ<31>")
	)
	(segment
		(start 250.718574 -60.743338)
		(end 250.724924 -60.754006)
		(width 0.0889)
		(layer "In11.Cu")
		(net "M_C_DQ<31>")
	)
	(segment
		(start 230.716582 2.198116)
		(end 230.716582 1.8796)
		(width 0.14224)
		(layer "In11.Cu")
		(net "M_C_DQ<31>")
	)
	(segment
		(start 231.627934 -13.694156)
		(end 231.627934 -16.890746)
		(width 0.14224)
		(layer "In11.Cu")
		(net "M_C_DQ<31>")
	)
	(segment
		(start 231.627934 -23.295356)
		(end 231.627934 -26.700734)
		(width 0.14224)
		(layer "In11.Cu")
		(net "M_C_DQ<31>")
	)
	(segment
		(start 231.602534 -9.428734)
		(end 231.7496 -9.5758)
		(width 0.14224)
		(layer "In11.Cu")
		(net "M_C_DQ<31>")
	)
	(segment
		(start 249.88774 -53.937154)
		(end 250.675394 -54.724808)
		(width 0.0889)
		(layer "In11.Cu")
		(net "M_C_DQ<31>")
	)
	(segment
		(start 231.551734 -7.213346)
		(end 231.831134 -7.492746)
		(width 0.14224)
		(layer "In11.Cu")
		(net "M_C_DQ<31>")
	)
	(segment
		(start 230.716582 1.8796)
		(end 231.046782 1.5494)
		(width 0.14224)
		(layer "In11.Cu")
		(net "M_C_DQ<31>")
	)
	(segment
		(start 231.551734 -6.51637)
		(end 231.551734 -7.213346)
		(width 0.14224)
		(layer "In11.Cu")
		(net "M_C_DQ<31>")
	)
	(segment
		(start 231.7496 -11.587734)
		(end 231.602534 -11.7348)
		(width 0.14224)
		(layer "In11.Cu")
		(net "M_C_DQ<31>")
	)
	(segment
		(start 230.789734 -4.067556)
		(end 231.158034 -4.435856)
		(width 0.14224)
		(layer "In11.Cu")
		(net "M_C_DQ<31>")
	)
	(segment
		(start 250.718574 -55.790338)
		(end 250.724924 -55.801006)
		(width 0.0889)
		(layer "In11.Cu")
		(net "M_C_DQ<31>")
	)
	(segment
		(start 231.7496 -9.5758)
		(end 231.7496 -11.587734)
		(width 0.14224)
		(layer "In11.Cu")
		(net "M_C_DQ<31>")
	)
	(segment
		(start 231.7496 -19.2278)
		(end 231.7496 -21.138134)
		(width 0.14224)
		(layer "In11.Cu")
		(net "M_C_DQ<31>")
	)
	(segment
		(start 250.718574 -55.390288)
		(end 250.713748 -55.398924)
		(width 0.0889)
		(layer "In11.Cu")
		(net "M_C_DQ<31>")
	)
	(segment
		(start 231.602534 -2.72415)
		(end 231.249728 -3.076956)
		(width 0.14224)
		(layer "In11.Cu")
		(net "M_C_DQ<31>")
	)
	(segment
		(start 231.627934 -26.700734)
		(end 231.793796 -26.866596)
		(width 0.14224)
		(layer "In11.Cu")
		(net "M_C_DQ<31>")
	)
	(segment
		(start 250.718574 -59.752738)
		(end 250.724924 -59.763406)
		(width 0.0889)
		(layer "In11.Cu")
		(net "M_C_DQ<31>")
	)
	(segment
		(start 250.724924 -58.35142)
		(end 250.718574 -58.362088)
		(width 0.0889)
		(layer "In11.Cu")
		(net "M_C_DQ<31>")
	)
	(segment
		(start 250.675394 -54.724808)
		(end 250.718574 -54.799738)
		(width 0.0889)
		(layer "In11.Cu")
		(net "M_C_DQ<31>")
	)
	(segment
		(start 231.793796 -28.111196)
		(end 231.590596 -28.314396)
		(width 0.14224)
		(layer "In11.Cu")
		(net "M_C_DQ<31>")
	)
	(segment
		(start 231.831134 -17.093946)
		(end 231.831134 -18.358866)
		(width 0.14224)
		(layer "In11.Cu")
		(net "M_C_DQ<31>")
	)
	(segment
		(start 250.718574 -56.780938)
		(end 250.724924 -56.791606)
		(width 0.0889)
		(layer "In11.Cu")
		(net "M_C_DQ<31>")
	)
	(segment
		(start 231.249728 -3.076956)
		(end 230.789734 -3.53695)
		(width 0.14224)
		(layer "In11.Cu")
		(net "M_C_DQ<31>")
	)
	(segment
		(start 249.002804 -49.636934)
		(end 248.816876 -49.822862)
		(width 0.0889)
		(layer "In11.Cu")
		(net "M_C_DQ<31>")
	)
	(segment
		(start 231.793796 -26.866596)
		(end 231.793796 -28.111196)
		(width 0.14224)
		(layer "In11.Cu")
		(net "M_C_DQ<31>")
	)
	(segment
		(start 230.789734 -3.53695)
		(end 230.789734 -4.067556)
		(width 0.14224)
		(layer "In11.Cu")
		(net "M_C_DQ<31>")
	)
	(segment
		(start 231.046782 1.5494)
		(end 231.300782 1.5494)
		(width 0.14224)
		(layer "In11.Cu")
		(net "M_C_DQ<31>")
	)
	(segment
		(start 231.602534 -21.2852)
		(end 231.602534 -21.771356)
		(width 0.14224)
		(layer "In11.Cu")
		(net "M_C_DQ<31>")
	)
	(segment
		(start 231.602534 -11.7348)
		(end 231.602534 -12.170156)
		(width 0.14224)
		(layer "In11.Cu")
		(net "M_C_DQ<31>")
	)
	(segment
		(start 231.831134 -18.358866)
		(end 231.602534 -18.587466)
		(width 0.14224)
		(layer "In11.Cu")
		(net "M_C_DQ<31>")
	)
	(segment
		(start 250.724924 -55.37962)
		(end 250.718574 -55.390288)
		(width 0.0889)
		(layer "In11.Cu")
		(net "M_C_DQ<31>")
	)
	(segment
		(start 248.661174 -50.227738)
		(end 248.661174 -51.316636)
		(width 0.0889)
		(layer "In11.Cu")
		(net "M_C_DQ<31>")
	)
	(segment
		(start 230.399844 2.514854)
		(end 230.716582 2.198116)
		(width 0.14224)
		(layer "In11.Cu")
		(net "M_C_DQ<31>")
	)
	(segment
		(start 250.718574 -61.733938)
		(end 250.724924 -61.744606)
		(width 0.0889)
		(layer "In11.Cu")
		(net "M_C_DQ<31>")
	)
	(segment
		(start 231.602534 -19.080734)
		(end 231.7496 -19.2278)
		(width 0.14224)
		(layer "In11.Cu")
		(net "M_C_DQ<31>")
	)
	(arc
		(start 250.724924 -61.744606)
		(mid 250.797722 -62.035369)
		(end 250.718574 -62.324488)
		(width 0.0889)
		(layer "In11.Cu")
		(net "M_C_DQ<31>")
	)
	(arc
		(start 250.718574 -58.761884)
		(mid 250.797705 -59.057286)
		(end 250.718574 -59.352688)
		(width 0.0889)
		(layer "In11.Cu")
		(net "M_C_DQ<31>")
	)
	(arc
		(start 250.718574 -57.771538)
		(mid 250.797796 -58.060656)
		(end 250.724924 -58.35142)
		(width 0.0889)
		(layer "In11.Cu")
		(net "M_C_DQ<31>")
	)
	(arc
		(start 250.724924 -62.735206)
		(mid 250.797722 -63.025969)
		(end 250.718574 -63.315088)
		(width 0.0889)
		(layer "In11.Cu")
		(net "M_C_DQ<31>")
	)
	(arc
		(start 250.718574 -58.362088)
		(mid 250.665075 -58.561986)
		(end 250.718574 -58.761884)
		(width 0.0889)
		(layer "In11.Cu")
		(net "M_C_DQ<31>")
	)
	(arc
		(start 250.713748 -55.398924)
		(mid 250.664993 -55.595276)
		(end 250.718574 -55.790338)
		(width 0.0889)
		(layer "In11.Cu")
		(net "M_C_DQ<31>")
	)
	(arc
		(start 250.718574 -57.371488)
		(mid 250.665104 -57.566551)
		(end 250.713748 -57.762902)
		(width 0.0889)
		(layer "In11.Cu")
		(net "M_C_DQ<31>")
	)
	(arc
		(start 250.718574 -63.715138)
		(mid 250.797705 -64.01054)
		(end 250.718574 -64.305942)
		(width 0.0889)
		(layer "In11.Cu")
		(net "M_C_DQ<31>")
	)
	(arc
		(start 250.718574 -64.305942)
		(mid 250.665075 -64.50584)
		(end 250.718574 -64.705738)
		(width 0.0889)
		(layer "In11.Cu")
		(net "M_C_DQ<31>")
	)
	(arc
		(start 250.718574 -56.380888)
		(mid 250.665104 -56.575951)
		(end 250.713748 -56.772302)
		(width 0.0889)
		(layer "In11.Cu")
		(net "M_C_DQ<31>")
	)
	(arc
		(start 250.718574 -63.315088)
		(mid 250.664914 -63.51513)
		(end 250.718574 -63.715138)
		(width 0.0889)
		(layer "In11.Cu")
		(net "M_C_DQ<31>")
	)
	(arc
		(start 250.724924 -56.791606)
		(mid 250.797722 -57.082369)
		(end 250.718574 -57.371488)
		(width 0.0889)
		(layer "In11.Cu")
		(net "M_C_DQ<31>")
	)
	(arc
		(start 250.718574 -60.343288)
		(mid 250.665104 -60.538351)
		(end 250.713748 -60.734702)
		(width 0.0889)
		(layer "In11.Cu")
		(net "M_C_DQ<31>")
	)
	(arc
		(start 250.724924 -59.763406)
		(mid 250.797722 -60.054169)
		(end 250.718574 -60.343288)
		(width 0.0889)
		(layer "In11.Cu")
		(net "M_C_DQ<31>")
	)
	(arc
		(start 250.718574 -65.296542)
		(mid 250.606328 -65.599818)
		(end 250.600972 -65.92316)
		(width 0.0889)
		(layer "In11.Cu")
		(net "M_C_DQ<31>")
	)
	(arc
		(start 250.718574 -62.324488)
		(mid 250.665104 -62.519551)
		(end 250.713748 -62.715902)
		(width 0.0889)
		(layer "In11.Cu")
		(net "M_C_DQ<31>")
	)
	(arc
		(start 250.600972 -65.92316)
		(mid 250.600755 -66.061555)
		(end 250.553474 -66.191638)
		(width 0.0889)
		(layer "In11.Cu")
		(net "M_C_DQ<31>")
	)
	(arc
		(start 250.718574 -61.333888)
		(mid 250.665104 -61.528951)
		(end 250.713748 -61.725302)
		(width 0.0889)
		(layer "In11.Cu")
		(net "M_C_DQ<31>")
	)
	(arc
		(start 250.718574 -59.352688)
		(mid 250.665104 -59.547751)
		(end 250.713748 -59.744102)
		(width 0.0889)
		(layer "In11.Cu")
		(net "M_C_DQ<31>")
	)
	(arc
		(start 250.718574 -54.799738)
		(mid 250.797796 -55.088856)
		(end 250.724924 -55.37962)
		(width 0.0889)
		(layer "In11.Cu")
		(net "M_C_DQ<31>")
	)
	(arc
		(start 250.724924 -60.754006)
		(mid 250.797722 -61.044769)
		(end 250.718574 -61.333888)
		(width 0.0889)
		(layer "In11.Cu")
		(net "M_C_DQ<31>")
	)
	(arc
		(start 250.718574 -64.705738)
		(mid 250.797705 -65.00114)
		(end 250.718574 -65.296542)
		(width 0.0889)
		(layer "In11.Cu")
		(net "M_C_DQ<31>")
	)
	(arc
		(start 250.724924 -55.801006)
		(mid 250.797722 -56.091769)
		(end 250.718574 -56.380888)
		(width 0.0889)
		(layer "In11.Cu")
		(net "M_C_DQ<31>")
	)
	(segment
		(start 231.382062 0.28448)
		(end 231.382062 0.50292)
		(width 0.1651)
		(layer "F.Cu")
		(net "M_C_DQ<30>")
	)
	(segment
		(start 231.249982 0.939546)
		(end 231.249728 0.9398)
		(width 0.1651)
		(layer "F.Cu")
		(net "M_C_DQ<30>")
	)
	(segment
		(start 231.249982 0.635)
		(end 231.249982 0.939546)
		(width 0.1651)
		(layer "F.Cu")
		(net "M_C_DQ<30>")
	)
	(segment
		(start 231.25049 -0.821182)
		(end 231.249982 -0.821182)
		(width 0.1651)
		(layer "F.Cu")
		(net "M_C_DQ<30>")
	)
	(segment
		(start 231.249982 0.1524)
		(end 231.382062 0.28448)
		(width 0.1651)
		(layer "F.Cu")
		(net "M_C_DQ<30>")
	)
	(segment
		(start 250.778264 -65.000886)
		(end 250.206764 -65.000886)
		(width 0.0889)
		(layer "F.Cu")
		(net "M_C_DQ<30>")
	)
	(segment
		(start 231.382062 0.50292)
		(end 231.249982 0.635)
		(width 0.1651)
		(layer "F.Cu")
		(net "M_C_DQ<30>")
	)
	(segment
		(start 231.249982 -0.821182)
		(end 231.249982 0.1524)
		(width 0.1651)
		(layer "F.Cu")
		(net "M_C_DQ<30>")
	)
	(via
		(at 250.206764 -65.000886)
		(size 0.508)
		(drill 0.254)
		(layers "F.Cu" "B.Cu")
		(net "M_C_DQ<30>")
	)
	(via
		(at 231.249728 0.9398)
		(size 0.508)
		(drill 0.254)
		(layers "F.Cu" "B.Cu")
		(net "M_C_DQ<30>")
	)
	(via
		(at 230.399844 -4.357878)
		(size 0.508)
		(drill 0.254)
		(layers "F.Cu" "B.Cu")
		(net "M_C_DQ<30>")
	)
	(segment
		(start 230.400352 -5.621782)
		(end 230.399844 -5.621782)
		(width 0.1651)
		(layer "B.Cu")
		(net "M_C_DQ<30>")
	)
	(segment
		(start 230.399844 -5.621782)
		(end 230.399844 -4.357878)
		(width 0.1651)
		(layer "B.Cu")
		(net "M_C_DQ<30>")
	)
	(segment
		(start 230.930196 -29.129228)
		(end 237.271052 -35.470084)
		(width 0.14224)
		(layer "In11.Cu")
		(net "M_C_DQ<30>")
	)
	(segment
		(start 236.451648 -36.508436)
		(end 236.451648 -36.727384)
		(width 0.14224)
		(layer "In11.Cu")
		(net "M_C_DQ<30>")
	)
	(segment
		(start 230.676196 -27.018996)
		(end 230.676196 -28.060396)
		(width 0.14224)
		(layer "In11.Cu")
		(net "M_C_DQ<30>")
	)
	(segment
		(start 249.69724 -52.62245)
		(end 249.69724 -54.016402)
		(width 0.0889)
		(layer "In11.Cu")
		(net "M_C_DQ<30>")
	)
	(segment
		(start 237.92053 -36.11753)
		(end 238.157766 -36.354766)
		(width 0.14224)
		(layer "In11.Cu")
		(net "M_C_DQ<30>")
	)
	(segment
		(start 230.967534 -21.36648)
		(end 230.967534 -21.771356)
		(width 0.14224)
		(layer "In11.Cu")
		(net "M_C_DQ<30>")
	)
	(segment
		(start 250.547124 -59.83732)
		(end 250.553474 -59.847988)
		(width 0.0889)
		(layer "In11.Cu")
		(net "M_C_DQ<30>")
	)
	(segment
		(start 230.399844 -4.357878)
		(end 230.399844 -4.922266)
		(width 0.14224)
		(layer "In11.Cu")
		(net "M_C_DQ<30>")
	)
	(segment
		(start 230.916734 -5.439156)
		(end 230.916734 -7.238746)
		(width 0.14224)
		(layer "In11.Cu")
		(net "M_C_DQ<30>")
	)
	(segment
		(start 230.764334 -23.168356)
		(end 230.865934 -23.269956)
		(width 0.14224)
		(layer "In11.Cu")
		(net "M_C_DQ<30>")
	)
	(segment
		(start 250.5583 -55.286402)
		(end 250.553474 -55.295038)
		(width 0.0889)
		(layer "In11.Cu")
		(net "M_C_DQ<30>")
	)
	(segment
		(start 230.51135 -0.076454)
		(end 230.51135 -0.387096)
		(width 0.14224)
		(layer "In11.Cu")
		(net "M_C_DQ<30>")
	)
	(segment
		(start 231.249728 0.9398)
		(end 230.875332 0.565404)
		(width 0.14224)
		(layer "In11.Cu")
		(net "M_C_DQ<30>")
	)
	(segment
		(start 230.764334 -12.373356)
		(end 230.764334 -13.567156)
		(width 0.14224)
		(layer "In11.Cu")
		(net "M_C_DQ<30>")
	)
	(segment
		(start 230.764334 -21.974556)
		(end 230.764334 -23.168356)
		(width 0.14224)
		(layer "In11.Cu")
		(net "M_C_DQ<30>")
	)
	(segment
		(start 230.967534 -9.022334)
		(end 230.967534 -9.392666)
		(width 0.14224)
		(layer "In11.Cu")
		(net "M_C_DQ<30>")
	)
	(segment
		(start 230.916734 -7.238746)
		(end 230.764334 -7.391146)
		(width 0.14224)
		(layer "In11.Cu")
		(net "M_C_DQ<30>")
	)
	(segment
		(start 237.719362 -36.11753)
		(end 237.92053 -36.11753)
		(width 0.14224)
		(layer "In11.Cu")
		(net "M_C_DQ<30>")
	)
	(segment
		(start 248.470674 -50.148744)
		(end 248.470674 -51.395884)
		(width 0.0889)
		(layer "In11.Cu")
		(net "M_C_DQ<30>")
	)
	(segment
		(start 230.9368 -2.554986)
		(end 230.164132 -3.327654)
		(width 0.14224)
		(layer "In11.Cu")
		(net "M_C_DQ<30>")
	)
	(segment
		(start 230.8098 -21.208746)
		(end 230.967534 -21.36648)
		(width 0.14224)
		(layer "In11.Cu")
		(net "M_C_DQ<30>")
	)
	(segment
		(start 238.157766 -36.354766)
		(end 238.157766 -36.555934)
		(width 0.14224)
		(layer "In11.Cu")
		(net "M_C_DQ<30>")
	)
	(segment
		(start 230.89235 -0.768096)
		(end 230.89235 -1.111504)
		(width 0.14224)
		(layer "In11.Cu")
		(net "M_C_DQ<30>")
	)
	(segment
		(start 236.671104 -36.94684)
		(end 236.890052 -36.94684)
		(width 0.14224)
		(layer "In11.Cu")
		(net "M_C_DQ<30>")
	)
	(segment
		(start 230.51135 -1.492504)
		(end 230.51135 -1.777746)
		(width 0.14224)
		(layer "In11.Cu")
		(net "M_C_DQ<30>")
	)
	(segment
		(start 250.547124 -62.80912)
		(end 250.553474 -62.819788)
		(width 0.0889)
		(layer "In11.Cu")
		(net "M_C_DQ<30>")
	)
	(segment
		(start 236.451648 -36.727384)
		(end 236.671104 -36.94684)
		(width 0.14224)
		(layer "In11.Cu")
		(net "M_C_DQ<30>")
	)
	(segment
		(start 238.157766 -36.555934)
		(end 237.3122 -37.4015)
		(width 0.14224)
		(layer "In11.Cu")
		(net "M_C_DQ<30>")
	)
	(segment
		(start 250.553474 -58.266838)
		(end 250.547124 -58.277506)
		(width 0.0889)
		(layer "In11.Cu")
		(net "M_C_DQ<30>")
	)
	(segment
		(start 250.553474 -59.847988)
		(end 250.5583 -59.856624)
		(width 0.0889)
		(layer "In11.Cu")
		(net "M_C_DQ<30>")
	)
	(segment
		(start 230.7844 -11.602466)
		(end 230.967534 -11.7856)
		(width 0.14224)
		(layer "In11.Cu")
		(net "M_C_DQ<30>")
	)
	(segment
		(start 230.764334 -13.567156)
		(end 230.865934 -13.668756)
		(width 0.14224)
		(layer "In11.Cu")
		(net "M_C_DQ<30>")
	)
	(segment
		(start 248.412 -49.633378)
		(end 248.405904 -49.639474)
		(width 0.14224)
		(layer "In11.Cu")
		(net "M_C_DQ<30>")
	)
	(segment
		(start 230.51135 -1.777746)
		(end 230.9368 -2.203196)
		(width 0.14224)
		(layer "In11.Cu")
		(net "M_C_DQ<30>")
	)
	(segment
		(start 230.865934 -23.269956)
		(end 230.865934 -26.829258)
		(width 0.14224)
		(layer "In11.Cu")
		(net "M_C_DQ<30>")
	)
	(segment
		(start 250.553474 -56.876188)
		(end 250.5583 -56.884824)
		(width 0.0889)
		(layer "In11.Cu")
		(net "M_C_DQ<30>")
	)
	(segment
		(start 250.553474 -55.885588)
		(end 250.5583 -55.894224)
		(width 0.0889)
		(layer "In11.Cu")
		(net "M_C_DQ<30>")
	)
	(segment
		(start 230.865934 -26.829258)
		(end 230.676196 -27.018996)
		(width 0.14224)
		(layer "In11.Cu")
		(net "M_C_DQ<30>")
	)
	(segment
		(start 230.875332 0.287528)
		(end 230.51135 -0.076454)
		(width 0.14224)
		(layer "In11.Cu")
		(net "M_C_DQ<30>")
	)
	(segment
		(start 230.967534 -19.044666)
		(end 230.8098 -19.2024)
		(width 0.14224)
		(layer "In11.Cu")
		(net "M_C_DQ<30>")
	)
	(segment
		(start 249.69724 -54.016402)
		(end 250.522994 -54.842156)
		(width 0.0889)
		(layer "In11.Cu")
		(net "M_C_DQ<30>")
	)
	(segment
		(start 230.967534 -21.771356)
		(end 230.764334 -21.974556)
		(width 0.14224)
		(layer "In11.Cu")
		(net "M_C_DQ<30>")
	)
	(segment
		(start 250.522994 -54.842156)
		(end 250.553474 -54.894988)
		(width 0.0889)
		(layer "In11.Cu")
		(net "M_C_DQ<30>")
	)
	(segment
		(start 230.89235 -1.111504)
		(end 230.51135 -1.492504)
		(width 0.14224)
		(layer "In11.Cu")
		(net "M_C_DQ<30>")
	)
	(segment
		(start 230.764334 -7.391146)
		(end 230.764334 -8.819134)
		(width 0.14224)
		(layer "In11.Cu")
		(net "M_C_DQ<30>")
	)
	(segment
		(start 248.626884 -49.860454)
		(end 248.626884 -49.992534)
		(width 0.0889)
		(layer "In11.Cu")
		(net "M_C_DQ<30>")
	)
	(segment
		(start 250.553474 -62.819788)
		(end 250.5583 -62.828424)
		(width 0.0889)
		(layer "In11.Cu")
		(net "M_C_DQ<30>")
	)
	(segment
		(start 230.164132 -3.327654)
		(end 230.164132 -4.122166)
		(width 0.14224)
		(layer "In11.Cu")
		(net "M_C_DQ<30>")
	)
	(segment
		(start 230.51135 -0.387096)
		(end 230.89235 -0.768096)
		(width 0.14224)
		(layer "In11.Cu")
		(net "M_C_DQ<30>")
	)
	(segment
		(start 248.405904 -49.639474)
		(end 248.626884 -49.860454)
		(width 0.0889)
		(layer "In11.Cu")
		(net "M_C_DQ<30>")
	)
	(segment
		(start 230.676196 -28.060396)
		(end 230.930196 -28.314396)
		(width 0.14224)
		(layer "In11.Cu")
		(net "M_C_DQ<30>")
	)
	(segment
		(start 230.865934 -13.668756)
		(end 230.865934 -16.890746)
		(width 0.14224)
		(layer "In11.Cu")
		(net "M_C_DQ<30>")
	)
	(segment
		(start 230.865934 -16.890746)
		(end 230.764334 -16.992346)
		(width 0.14224)
		(layer "In11.Cu")
		(net "M_C_DQ<30>")
	)
	(segment
		(start 230.967534 -12.170156)
		(end 230.764334 -12.373356)
		(width 0.14224)
		(layer "In11.Cu")
		(net "M_C_DQ<30>")
	)
	(segment
		(start 230.930196 -28.314396)
		(end 230.930196 -29.129228)
		(width 0.14224)
		(layer "In11.Cu")
		(net "M_C_DQ<30>")
	)
	(segment
		(start 237.271052 -35.689032)
		(end 236.451648 -36.508436)
		(width 0.14224)
		(layer "In11.Cu")
		(net "M_C_DQ<30>")
	)
	(segment
		(start 230.7844 -9.5758)
		(end 230.7844 -11.602466)
		(width 0.14224)
		(layer "In11.Cu")
		(net "M_C_DQ<30>")
	)
	(segment
		(start 230.967534 -11.7856)
		(end 230.967534 -12.170156)
		(width 0.14224)
		(layer "In11.Cu")
		(net "M_C_DQ<30>")
	)
	(segment
		(start 230.764334 -18.420334)
		(end 230.967534 -18.623534)
		(width 0.14224)
		(layer "In11.Cu")
		(net "M_C_DQ<30>")
	)
	(segment
		(start 237.3122 -37.4015)
		(end 237.3122 -37.88791)
		(width 0.14224)
		(layer "In11.Cu")
		(net "M_C_DQ<30>")
	)
	(segment
		(start 250.553474 -60.838588)
		(end 250.5583 -60.847224)
		(width 0.0889)
		(layer "In11.Cu")
		(net "M_C_DQ<30>")
	)
	(segment
		(start 237.3122 -37.88791)
		(end 248.412 -48.98771)
		(width 0.14224)
		(layer "In11.Cu")
		(net "M_C_DQ<30>")
	)
	(segment
		(start 230.875332 0.565404)
		(end 230.875332 0.287528)
		(width 0.14224)
		(layer "In11.Cu")
		(net "M_C_DQ<30>")
	)
	(segment
		(start 250.553474 -55.295038)
		(end 250.547124 -55.305706)
		(width 0.0889)
		(layer "In11.Cu")
		(net "M_C_DQ<30>")
	)
	(segment
		(start 230.8098 -19.2024)
		(end 230.8098 -21.208746)
		(width 0.14224)
		(layer "In11.Cu")
		(net "M_C_DQ<30>")
	)
	(segment
		(start 230.764334 -16.992346)
		(end 230.764334 -18.420334)
		(width 0.14224)
		(layer "In11.Cu")
		(net "M_C_DQ<30>")
	)
	(segment
		(start 250.553474 -58.857388)
		(end 250.5583 -58.866024)
		(width 0.0889)
		(layer "In11.Cu")
		(net "M_C_DQ<30>")
	)
	(segment
		(start 230.764334 -8.819134)
		(end 230.967534 -9.022334)
		(width 0.14224)
		(layer "In11.Cu")
		(net "M_C_DQ<30>")
	)
	(segment
		(start 248.412 -48.98771)
		(end 248.412 -49.633378)
		(width 0.14224)
		(layer "In11.Cu")
		(net "M_C_DQ<30>")
	)
	(segment
		(start 250.547124 -61.81852)
		(end 250.553474 -61.829188)
		(width 0.0889)
		(layer "In11.Cu")
		(net "M_C_DQ<30>")
	)
	(segment
		(start 230.399844 -4.922266)
		(end 230.916734 -5.439156)
		(width 0.14224)
		(layer "In11.Cu")
		(net "M_C_DQ<30>")
	)
	(segment
		(start 250.553474 -61.829188)
		(end 250.5583 -61.837824)
		(width 0.0889)
		(layer "In11.Cu")
		(net "M_C_DQ<30>")
	)
	(segment
		(start 248.626884 -49.992534)
		(end 248.470674 -50.148744)
		(width 0.0889)
		(layer "In11.Cu")
		(net "M_C_DQ<30>")
	)
	(segment
		(start 236.890052 -36.94684)
		(end 237.719362 -36.11753)
		(width 0.14224)
		(layer "In11.Cu")
		(net "M_C_DQ<30>")
	)
	(segment
		(start 230.967534 -9.392666)
		(end 230.7844 -9.5758)
		(width 0.14224)
		(layer "In11.Cu")
		(net "M_C_DQ<30>")
	)
	(segment
		(start 248.470674 -51.395884)
		(end 249.69724 -52.62245)
		(width 0.0889)
		(layer "In11.Cu")
		(net "M_C_DQ<30>")
	)
	(segment
		(start 237.271052 -35.470084)
		(end 237.271052 -35.689032)
		(width 0.14224)
		(layer "In11.Cu")
		(net "M_C_DQ<30>")
	)
	(segment
		(start 230.164132 -4.122166)
		(end 230.399844 -4.357878)
		(width 0.14224)
		(layer "In11.Cu")
		(net "M_C_DQ<30>")
	)
	(segment
		(start 250.5202 -64.277494)
		(end 250.206764 -65.000886)
		(width 0.0889)
		(layer "In11.Cu")
		(net "M_C_DQ<30>")
	)
	(segment
		(start 250.547124 -60.82792)
		(end 250.553474 -60.838588)
		(width 0.0889)
		(layer "In11.Cu")
		(net "M_C_DQ<30>")
	)
	(segment
		(start 250.547124 -56.86552)
		(end 250.553474 -56.876188)
		(width 0.0889)
		(layer "In11.Cu")
		(net "M_C_DQ<30>")
	)
	(segment
		(start 230.9368 -2.203196)
		(end 230.9368 -2.554986)
		(width 0.14224)
		(layer "In11.Cu")
		(net "M_C_DQ<30>")
	)
	(segment
		(start 230.967534 -18.623534)
		(end 230.967534 -19.044666)
		(width 0.14224)
		(layer "In11.Cu")
		(net "M_C_DQ<30>")
	)
	(arc
		(start 250.547124 -58.277506)
		(mid 250.474326 -58.568269)
		(end 250.553474 -58.857388)
		(width 0.0889)
		(layer "In11.Cu")
		(net "M_C_DQ<30>")
	)
	(arc
		(start 250.553474 -56.285638)
		(mid 250.474252 -56.574756)
		(end 250.547124 -56.86552)
		(width 0.0889)
		(layer "In11.Cu")
		(net "M_C_DQ<30>")
	)
	(arc
		(start 250.553474 -59.257438)
		(mid 250.474252 -59.546556)
		(end 250.547124 -59.83732)
		(width 0.0889)
		(layer "In11.Cu")
		(net "M_C_DQ<30>")
	)
	(arc
		(start 250.553474 -57.867042)
		(mid 250.606973 -58.06694)
		(end 250.553474 -58.266838)
		(width 0.0889)
		(layer "In11.Cu")
		(net "M_C_DQ<30>")
	)
	(arc
		(start 250.5583 -55.894224)
		(mid 250.607055 -56.090576)
		(end 250.553474 -56.285638)
		(width 0.0889)
		(layer "In11.Cu")
		(net "M_C_DQ<30>")
	)
	(arc
		(start 250.553474 -62.229238)
		(mid 250.474252 -62.518356)
		(end 250.547124 -62.80912)
		(width 0.0889)
		(layer "In11.Cu")
		(net "M_C_DQ<30>")
	)
	(arc
		(start 250.553474 -57.276238)
		(mid 250.474343 -57.57164)
		(end 250.553474 -57.867042)
		(width 0.0889)
		(layer "In11.Cu")
		(net "M_C_DQ<30>")
	)
	(arc
		(start 250.5583 -60.847224)
		(mid 250.607055 -61.043576)
		(end 250.553474 -61.238638)
		(width 0.0889)
		(layer "In11.Cu")
		(net "M_C_DQ<30>")
	)
	(arc
		(start 250.553474 -64.210438)
		(mid 250.535772 -64.243438)
		(end 250.5202 -64.277494)
		(width 0.0889)
		(layer "In11.Cu")
		(net "M_C_DQ<30>")
	)
	(arc
		(start 250.553474 -54.894988)
		(mid 250.606944 -55.090051)
		(end 250.5583 -55.286402)
		(width 0.0889)
		(layer "In11.Cu")
		(net "M_C_DQ<30>")
	)
	(arc
		(start 250.5583 -62.828424)
		(mid 250.607055 -63.024776)
		(end 250.553474 -63.219838)
		(width 0.0889)
		(layer "In11.Cu")
		(net "M_C_DQ<30>")
	)
	(arc
		(start 250.5583 -59.856624)
		(mid 250.607055 -60.052976)
		(end 250.553474 -60.248038)
		(width 0.0889)
		(layer "In11.Cu")
		(net "M_C_DQ<30>")
	)
	(arc
		(start 250.553474 -63.810642)
		(mid 250.606973 -64.01054)
		(end 250.553474 -64.210438)
		(width 0.0889)
		(layer "In11.Cu")
		(net "M_C_DQ<30>")
	)
	(arc
		(start 250.547124 -55.305706)
		(mid 250.474326 -55.596469)
		(end 250.553474 -55.885588)
		(width 0.0889)
		(layer "In11.Cu")
		(net "M_C_DQ<30>")
	)
	(arc
		(start 250.553474 -61.238638)
		(mid 250.474252 -61.527756)
		(end 250.547124 -61.81852)
		(width 0.0889)
		(layer "In11.Cu")
		(net "M_C_DQ<30>")
	)
	(arc
		(start 250.5583 -58.866024)
		(mid 250.607055 -59.062376)
		(end 250.553474 -59.257438)
		(width 0.0889)
		(layer "In11.Cu")
		(net "M_C_DQ<30>")
	)
	(arc
		(start 250.5583 -56.884824)
		(mid 250.607055 -57.081176)
		(end 250.553474 -57.276238)
		(width 0.0889)
		(layer "In11.Cu")
		(net "M_C_DQ<30>")
	)
	(arc
		(start 250.553474 -60.248038)
		(mid 250.474252 -60.537156)
		(end 250.547124 -60.82792)
		(width 0.0889)
		(layer "In11.Cu")
		(net "M_C_DQ<30>")
	)
	(arc
		(start 250.5583 -61.837824)
		(mid 250.607055 -62.034176)
		(end 250.553474 -62.229238)
		(width 0.0889)
		(layer "In11.Cu")
		(net "M_C_DQ<30>")
	)
	(arc
		(start 250.553474 -63.219838)
		(mid 250.474411 -63.51524)
		(end 250.553474 -63.810642)
		(width 0.0889)
		(layer "In11.Cu")
		(net "M_C_DQ<30>")
	)
	(segment
		(start 240.476278 -64.010286)
		(end 239.904778 -64.010286)
		(width 0.0889)
		(layer "F.Cu")
		(net "M_C_DQ<2>")
	)
	(segment
		(start 204.899768 -0.821182)
		(end 204.899768 0.175768)
		(width 0.1651)
		(layer "F.Cu")
		(net "M_C_DQ<2>")
	)
	(segment
		(start 205.03134 0.53086)
		(end 204.899768 0.662432)
		(width 0.1651)
		(layer "F.Cu")
		(net "M_C_DQ<2>")
	)
	(segment
		(start 204.899768 0.662432)
		(end 204.899768 0.9398)
		(width 0.1651)
		(layer "F.Cu")
		(net "M_C_DQ<2>")
	)
	(segment
		(start 204.900276 -0.821182)
		(end 204.899768 -0.821182)
		(width 0.1651)
		(layer "F.Cu")
		(net "M_C_DQ<2>")
	)
	(segment
		(start 204.899768 0.175768)
		(end 205.03134 0.30734)
		(width 0.1651)
		(layer "F.Cu")
		(net "M_C_DQ<2>")
	)
	(segment
		(start 205.03134 0.30734)
		(end 205.03134 0.53086)
		(width 0.1651)
		(layer "F.Cu")
		(net "M_C_DQ<2>")
	)
	(via
		(at 204.899768 0.9398)
		(size 0.508)
		(drill 0.254)
		(layers "F.Cu" "B.Cu")
		(net "M_C_DQ<2>")
	)
	(via
		(at 204.049884 -4.357878)
		(size 0.508)
		(drill 0.254)
		(layers "F.Cu" "B.Cu")
		(net "M_C_DQ<2>")
	)
	(via
		(at 239.904778 -64.010286)
		(size 0.508)
		(drill 0.254)
		(layers "F.Cu" "B.Cu")
		(net "M_C_DQ<2>")
	)
	(segment
		(start 204.050392 -5.621782)
		(end 204.049884 -5.621782)
		(width 0.1651)
		(layer "B.Cu")
		(net "M_C_DQ<2>")
	)
	(segment
		(start 204.049884 -5.621782)
		(end 204.049884 -4.357878)
		(width 0.1651)
		(layer "B.Cu")
		(net "M_C_DQ<2>")
	)
	(segment
		(start 204.416152 -8.810498)
		(end 204.543152 -8.937498)
		(width 0.14224)
		(layer "In11.Cu")
		(net "M_C_DQ<2>")
	)
	(segment
		(start 204.28204 -32.679386)
		(end 204.1398 -32.821626)
		(width 0.14224)
		(layer "In11.Cu")
		(net "M_C_DQ<2>")
	)
	(segment
		(start 235.594398 -62.12459)
		(end 235.627164 -62.12459)
		(width 0.0889)
		(layer "In11.Cu")
		(net "M_C_DQ<2>")
	)
	(segment
		(start 212.090508 -46.580806)
		(end 212.309456 -46.580806)
		(width 0.14224)
		(layer "In11.Cu")
		(net "M_C_DQ<2>")
	)
	(segment
		(start 224.123504 -58.692288)
		(end 225.015552 -58.692288)
		(width 0.14224)
		(layer "In11.Cu")
		(net "M_C_DQ<2>")
	)
	(segment
		(start 216.756234 -49.806352)
		(end 216.756234 -50.0253)
		(width 0.14224)
		(layer "In11.Cu")
		(net "M_C_DQ<2>")
	)
	(segment
		(start 215.59774 -50.088038)
		(end 215.816688 -50.088038)
		(width 0.14224)
		(layer "In11.Cu")
		(net "M_C_DQ<2>")
	)
	(segment
		(start 211.871052 -46.36135)
		(end 212.090508 -46.580806)
		(width 0.14224)
		(layer "In11.Cu")
		(net "M_C_DQ<2>")
	)
	(segment
		(start 204.3938 -11.6078)
		(end 204.543152 -11.757152)
		(width 0.14224)
		(layer "In11.Cu")
		(net "M_C_DQ<2>")
	)
	(segment
		(start 204.5462 -23.298404)
		(end 204.5462 -25.603454)
		(width 0.14224)
		(layer "In11.Cu")
		(net "M_C_DQ<2>")
	)
	(segment
		(start 204.614018 -2.478532)
		(end 203.76515 -3.3274)
		(width 0.14224)
		(layer "In11.Cu")
		(net "M_C_DQ<2>")
	)
	(segment
		(start 213.624668 -48.114966)
		(end 213.844124 -48.334422)
		(width 0.14224)
		(layer "In11.Cu")
		(net "M_C_DQ<2>")
	)
	(segment
		(start 215.378284 -49.868582)
		(end 215.59774 -50.088038)
		(width 0.14224)
		(layer "In11.Cu")
		(net "M_C_DQ<2>")
	)
	(segment
		(start 217.413586 -50.463704)
		(end 217.633042 -50.68316)
		(width 0.14224)
		(layer "In11.Cu")
		(net "M_C_DQ<2>")
	)
	(segment
		(start 204.1398 -32.821626)
		(end 204.1398 -33.187386)
		(width 0.14224)
		(layer "In11.Cu")
		(net "M_C_DQ<2>")
	)
	(segment
		(start 204.543152 -18.564098)
		(end 204.543152 -19.027648)
		(width 0.14224)
		(layer "In11.Cu")
		(net "M_C_DQ<2>")
	)
	(segment
		(start 204.2922 -6.530848)
		(end 204.619352 -6.858)
		(width 0.14224)
		(layer "In11.Cu")
		(net "M_C_DQ<2>")
	)
	(segment
		(start 204.692504 -32.679386)
		(end 204.28204 -32.679386)
		(width 0.14224)
		(layer "In11.Cu")
		(net "M_C_DQ<2>")
	)
	(segment
		(start 216.255092 -50.526442)
		(end 216.255092 -50.74539)
		(width 0.14224)
		(layer "In11.Cu")
		(net "M_C_DQ<2>")
	)
	(segment
		(start 215.816688 -50.088038)
		(end 216.31783 -49.586896)
		(width 0.14224)
		(layer "In11.Cu")
		(net "M_C_DQ<2>")
	)
	(segment
		(start 215.002618 -48.271684)
		(end 214.501476 -48.772826)
		(width 0.14224)
		(layer "In11.Cu")
		(net "M_C_DQ<2>")
	)
	(segment
		(start 204.3938 -9.496552)
		(end 204.3938 -11.6078)
		(width 0.14224)
		(layer "In11.Cu")
		(net "M_C_DQ<2>")
	)
	(segment
		(start 204.156818 -0.108204)
		(end 204.156818 -0.456946)
		(width 0.14224)
		(layer "In11.Cu")
		(net "M_C_DQ<2>")
	)
	(segment
		(start 204.390752 -13.541756)
		(end 204.632052 -13.783056)
		(width 0.14224)
		(layer "In11.Cu")
		(net "M_C_DQ<2>")
	)
	(segment
		(start 204.461618 -0.761746)
		(end 204.461618 -1.04775)
		(width 0.14224)
		(layer "In11.Cu")
		(net "M_C_DQ<2>")
	)
	(segment
		(start 231.77627 -62.068964)
		(end 231.831896 -62.12459)
		(width 0.0889)
		(layer "In11.Cu")
		(net "M_C_DQ<2>")
	)
	(segment
		(start 204.619352 -6.858)
		(end 204.619352 -7.162546)
		(width 0.14224)
		(layer "In11.Cu")
		(net "M_C_DQ<2>")
	)
	(segment
		(start 218.290394 -51.340512)
		(end 218.720416 -51.770534)
		(width 0.14224)
		(layer "In11.Cu")
		(net "M_C_DQ<2>")
	)
	(segment
		(start 214.564214 -47.83328)
		(end 214.783162 -47.83328)
		(width 0.14224)
		(layer "In11.Cu")
		(net "M_C_DQ<2>")
	)
	(segment
		(start 239.18418 -64.10579)
		(end 239.894364 -64.02324)
		(width 0.0889)
		(layer "In11.Cu")
		(net "M_C_DQ<2>")
	)
	(segment
		(start 204.416152 -16.966946)
		(end 204.416152 -18.437098)
		(width 0.14224)
		(layer "In11.Cu")
		(net "M_C_DQ<2>")
	)
	(segment
		(start 217.194638 -50.463704)
		(end 217.413586 -50.463704)
		(width 0.14224)
		(layer "In11.Cu")
		(net "M_C_DQ<2>")
	)
	(segment
		(start 204.1398 -33.187386)
		(end 204.28204 -33.329626)
		(width 0.14224)
		(layer "In11.Cu")
		(net "M_C_DQ<2>")
	)
	(segment
		(start 204.4192 -21.237448)
		(end 204.543152 -21.3614)
		(width 0.14224)
		(layer "In11.Cu")
		(net "M_C_DQ<2>")
	)
	(segment
		(start 213.687406 -46.956472)
		(end 213.906354 -46.956472)
		(width 0.14224)
		(layer "In11.Cu")
		(net "M_C_DQ<2>")
	)
	(segment
		(start 214.501476 -48.991774)
		(end 214.720932 -49.21123)
		(width 0.14224)
		(layer "In11.Cu")
		(net "M_C_DQ<2>")
	)
	(segment
		(start 216.474548 -50.964846)
		(end 216.693496 -50.964846)
		(width 0.14224)
		(layer "In11.Cu")
		(net "M_C_DQ<2>")
	)
	(segment
		(start 215.879426 -48.929544)
		(end 215.879426 -49.148492)
		(width 0.14224)
		(layer "In11.Cu")
		(net "M_C_DQ<2>")
	)
	(segment
		(start 215.879426 -49.148492)
		(end 215.378284 -49.649634)
		(width 0.14224)
		(layer "In11.Cu")
		(net "M_C_DQ<2>")
	)
	(segment
		(start 212.967316 -47.457614)
		(end 213.186264 -47.457614)
		(width 0.14224)
		(layer "In11.Cu")
		(net "M_C_DQ<2>")
	)
	(segment
		(start 238.166148 -63.610236)
		(end 238.198914 -63.610236)
		(width 0.0889)
		(layer "In11.Cu")
		(net "M_C_DQ<2>")
	)
	(segment
		(start 204.156818 -0.456946)
		(end 204.461618 -0.761746)
		(width 0.14224)
		(layer "In11.Cu")
		(net "M_C_DQ<2>")
	)
	(segment
		(start 216.756234 -50.0253)
		(end 216.255092 -50.526442)
		(width 0.14224)
		(layer "In11.Cu")
		(net "M_C_DQ<2>")
	)
	(segment
		(start 216.693496 -50.964846)
		(end 217.194638 -50.463704)
		(width 0.14224)
		(layer "In11.Cu")
		(net "M_C_DQ<2>")
	)
	(segment
		(start 204.543152 -12.195556)
		(end 204.390752 -12.347956)
		(width 0.14224)
		(layer "In11.Cu")
		(net "M_C_DQ<2>")
	)
	(segment
		(start 217.570304 -51.841654)
		(end 218.071446 -51.340512)
		(width 0.14224)
		(layer "In11.Cu")
		(net "M_C_DQ<2>")
	)
	(segment
		(start 231.776524 -62.068456)
		(end 231.77627 -62.068456)
		(width 0.0889)
		(layer "In11.Cu")
		(net "M_C_DQ<2>")
	)
	(segment
		(start 204.614018 -2.2098)
		(end 204.614018 -2.478532)
		(width 0.14224)
		(layer "In11.Cu")
		(net "M_C_DQ<2>")
	)
	(segment
		(start 225.015552 -58.692288)
		(end 228.167184 -61.84392)
		(width 0.14224)
		(layer "In11.Cu")
		(net "M_C_DQ<2>")
	)
	(segment
		(start 212.309456 -46.580806)
		(end 212.810598 -46.079664)
		(width 0.14224)
		(layer "In11.Cu")
		(net "M_C_DQ<2>")
	)
	(segment
		(start 228.167184 -61.84392)
		(end 230.788718 -61.84392)
		(width 0.14224)
		(layer "In11.Cu")
		(net "M_C_DQ<2>")
	)
	(segment
		(start 239.894364 -64.02324)
		(end 239.904778 -64.010286)
		(width 0.0889)
		(layer "In11.Cu")
		(net "M_C_DQ<2>")
	)
	(segment
		(start 204.50175 0.541782)
		(end 204.50175 0.236728)
		(width 0.14224)
		(layer "In11.Cu")
		(net "M_C_DQ<2>")
	)
	(segment
		(start 214.93988 -49.21123)
		(end 215.441022 -48.710088)
		(width 0.14224)
		(layer "In11.Cu")
		(net "M_C_DQ<2>")
	)
	(segment
		(start 213.249002 -46.29912)
		(end 213.249002 -46.518068)
		(width 0.14224)
		(layer "In11.Cu")
		(net "M_C_DQ<2>")
	)
	(segment
		(start 203.76515 -4.073144)
		(end 204.049884 -4.357878)
		(width 0.14224)
		(layer "In11.Cu")
		(net "M_C_DQ<2>")
	)
	(segment
		(start 204.543152 -11.757152)
		(end 204.543152 -12.195556)
		(width 0.14224)
		(layer "In11.Cu")
		(net "M_C_DQ<2>")
	)
	(segment
		(start 231.831896 -62.12459)
		(end 232.30459 -62.12459)
		(width 0.0889)
		(layer "In11.Cu")
		(net "M_C_DQ<2>")
	)
	(segment
		(start 216.255092 -50.74539)
		(end 216.474548 -50.964846)
		(width 0.14224)
		(layer "In11.Cu")
		(net "M_C_DQ<2>")
	)
	(segment
		(start 204.619352 -7.162546)
		(end 204.416152 -7.365746)
		(width 0.14224)
		(layer "In11.Cu")
		(net "M_C_DQ<2>")
	)
	(segment
		(start 231.244394 -61.628528)
		(end 231.336596 -61.628528)
		(width 0.0889)
		(layer "In11.Cu")
		(net "M_C_DQ<2>")
	)
	(segment
		(start 213.906354 -46.956472)
		(end 214.12581 -47.175928)
		(width 0.14224)
		(layer "In11.Cu")
		(net "M_C_DQ<2>")
	)
	(segment
		(start 212.74786 -47.01921)
		(end 212.74786 -47.238158)
		(width 0.14224)
		(layer "In11.Cu")
		(net "M_C_DQ<2>")
	)
	(segment
		(start 217.1319 -51.40325)
		(end 217.1319 -51.622198)
		(width 0.14224)
		(layer "In11.Cu")
		(net "M_C_DQ<2>")
	)
	(segment
		(start 213.624668 -47.896018)
		(end 213.624668 -48.114966)
		(width 0.14224)
		(layer "In11.Cu")
		(net "M_C_DQ<2>")
	)
	(segment
		(start 217.1319 -51.622198)
		(end 217.351356 -51.841654)
		(width 0.14224)
		(layer "In11.Cu")
		(net "M_C_DQ<2>")
	)
	(segment
		(start 214.063072 -48.334422)
		(end 214.564214 -47.83328)
		(width 0.14224)
		(layer "In11.Cu")
		(net "M_C_DQ<2>")
	)
	(segment
		(start 204.390752 -23.142956)
		(end 204.5462 -23.298404)
		(width 0.14224)
		(layer "In11.Cu")
		(net "M_C_DQ<2>")
	)
	(segment
		(start 214.783162 -47.83328)
		(end 215.002618 -48.052736)
		(width 0.14224)
		(layer "In11.Cu")
		(net "M_C_DQ<2>")
	)
	(segment
		(start 214.12581 -47.394876)
		(end 213.624668 -47.896018)
		(width 0.14224)
		(layer "In11.Cu")
		(net "M_C_DQ<2>")
	)
	(segment
		(start 204.156818 -1.7526)
		(end 204.614018 -2.2098)
		(width 0.14224)
		(layer "In11.Cu")
		(net "M_C_DQ<2>")
	)
	(segment
		(start 204.156818 -1.35255)
		(end 204.156818 -1.7526)
		(width 0.14224)
		(layer "In11.Cu")
		(net "M_C_DQ<2>")
	)
	(segment
		(start 233.877358 -62.12459)
		(end 233.912918 -62.12459)
		(width 0.0889)
		(layer "In11.Cu")
		(net "M_C_DQ<2>")
	)
	(segment
		(start 204.049884 -4.357878)
		(end 204.2922 -4.600194)
		(width 0.14224)
		(layer "In11.Cu")
		(net "M_C_DQ<2>")
	)
	(segment
		(start 218.071446 -51.340512)
		(end 218.290394 -51.340512)
		(width 0.14224)
		(layer "In11.Cu")
		(net "M_C_DQ<2>")
	)
	(segment
		(start 204.834744 -37.884862)
		(end 212.372194 -45.422312)
		(width 0.14224)
		(layer "In11.Cu")
		(net "M_C_DQ<2>")
	)
	(segment
		(start 230.788718 -61.84392)
		(end 231.003348 -61.62929)
		(width 0.0889)
		(layer "In11.Cu")
		(net "M_C_DQ<2>")
	)
	(segment
		(start 204.4192 -19.1516)
		(end 204.4192 -21.237448)
		(width 0.14224)
		(layer "In11.Cu")
		(net "M_C_DQ<2>")
	)
	(segment
		(start 204.28204 -33.329626)
		(end 204.692504 -33.329626)
		(width 0.14224)
		(layer "In11.Cu")
		(net "M_C_DQ<2>")
	)
	(segment
		(start 204.461618 -1.04775)
		(end 204.156818 -1.35255)
		(width 0.14224)
		(layer "In11.Cu")
		(net "M_C_DQ<2>")
	)
	(segment
		(start 204.834744 -33.471866)
		(end 204.834744 -37.884862)
		(width 0.14224)
		(layer "In11.Cu")
		(net "M_C_DQ<2>")
	)
	(segment
		(start 213.029546 -46.079664)
		(end 213.249002 -46.29912)
		(width 0.14224)
		(layer "In11.Cu")
		(net "M_C_DQ<2>")
	)
	(segment
		(start 211.871052 -46.142402)
		(end 211.871052 -46.36135)
		(width 0.14224)
		(layer "In11.Cu")
		(net "M_C_DQ<2>")
	)
	(segment
		(start 212.372194 -45.64126)
		(end 211.871052 -46.142402)
		(width 0.14224)
		(layer "In11.Cu")
		(net "M_C_DQ<2>")
	)
	(segment
		(start 212.372194 -45.422312)
		(end 212.372194 -45.64126)
		(width 0.14224)
		(layer "In11.Cu")
		(net "M_C_DQ<2>")
	)
	(segment
		(start 217.633042 -50.68316)
		(end 217.633042 -50.902108)
		(width 0.14224)
		(layer "In11.Cu")
		(net "M_C_DQ<2>")
	)
	(segment
		(start 213.186264 -47.457614)
		(end 213.687406 -46.956472)
		(width 0.14224)
		(layer "In11.Cu")
		(net "M_C_DQ<2>")
	)
	(segment
		(start 232.870248 -61.629036)
		(end 233.047794 -61.629036)
		(width 0.0889)
		(layer "In11.Cu")
		(net "M_C_DQ<2>")
	)
	(segment
		(start 231.336596 -61.628528)
		(end 231.776524 -62.068456)
		(width 0.0889)
		(layer "In11.Cu")
		(net "M_C_DQ<2>")
	)
	(segment
		(start 215.441022 -48.710088)
		(end 215.65997 -48.710088)
		(width 0.14224)
		(layer "In11.Cu")
		(net "M_C_DQ<2>")
	)
	(segment
		(start 218.720416 -53.2892)
		(end 224.123504 -58.692288)
		(width 0.14224)
		(layer "In11.Cu")
		(net "M_C_DQ<2>")
	)
	(segment
		(start 204.416152 -7.365746)
		(end 204.416152 -8.810498)
		(width 0.14224)
		(layer "In11.Cu")
		(net "M_C_DQ<2>")
	)
	(segment
		(start 204.390752 -21.949156)
		(end 204.390752 -23.142956)
		(width 0.14224)
		(layer "In11.Cu")
		(net "M_C_DQ<2>")
	)
	(segment
		(start 212.74786 -47.238158)
		(end 212.967316 -47.457614)
		(width 0.14224)
		(layer "In11.Cu")
		(net "M_C_DQ<2>")
	)
	(segment
		(start 214.12581 -47.175928)
		(end 214.12581 -47.394876)
		(width 0.14224)
		(layer "In11.Cu")
		(net "M_C_DQ<2>")
	)
	(segment
		(start 217.633042 -50.902108)
		(end 217.1319 -51.40325)
		(width 0.14224)
		(layer "In11.Cu")
		(net "M_C_DQ<2>")
	)
	(segment
		(start 204.5462 -25.603454)
		(end 204.834744 -25.891998)
		(width 0.14224)
		(layer "In11.Cu")
		(net "M_C_DQ<2>")
	)
	(segment
		(start 204.692504 -33.329626)
		(end 204.834744 -33.471866)
		(width 0.14224)
		(layer "In11.Cu")
		(net "M_C_DQ<2>")
	)
	(segment
		(start 204.632052 -13.783056)
		(end 204.632052 -16.751046)
		(width 0.14224)
		(layer "In11.Cu")
		(net "M_C_DQ<2>")
	)
	(segment
		(start 231.003348 -61.62929)
		(end 231.243632 -61.62929)
		(width 0.0889)
		(layer "In11.Cu")
		(net "M_C_DQ<2>")
	)
	(segment
		(start 237.311438 -63.11519)
		(end 237.344204 -63.11519)
		(width 0.0889)
		(layer "In11.Cu")
		(net "M_C_DQ<2>")
	)
	(segment
		(start 204.834744 -32.537146)
		(end 204.692504 -32.679386)
		(width 0.14224)
		(layer "In11.Cu")
		(net "M_C_DQ<2>")
	)
	(segment
		(start 214.720932 -49.21123)
		(end 214.93988 -49.21123)
		(width 0.14224)
		(layer "In11.Cu")
		(net "M_C_DQ<2>")
	)
	(segment
		(start 204.899768 0.9398)
		(end 204.50175 0.541782)
		(width 0.14224)
		(layer "In11.Cu")
		(net "M_C_DQ<2>")
	)
	(segment
		(start 236.449108 -62.619636)
		(end 236.481874 -62.619636)
		(width 0.0889)
		(layer "In11.Cu")
		(net "M_C_DQ<2>")
	)
	(segment
		(start 214.501476 -48.772826)
		(end 214.501476 -48.991774)
		(width 0.14224)
		(layer "In11.Cu")
		(net "M_C_DQ<2>")
	)
	(segment
		(start 218.720416 -51.770534)
		(end 218.720416 -53.2892)
		(width 0.14224)
		(layer "In11.Cu")
		(net "M_C_DQ<2>")
	)
	(segment
		(start 204.50175 0.236728)
		(end 204.156818 -0.108204)
		(width 0.14224)
		(layer "In11.Cu")
		(net "M_C_DQ<2>")
	)
	(segment
		(start 204.416152 -18.437098)
		(end 204.543152 -18.564098)
		(width 0.14224)
		(layer "In11.Cu")
		(net "M_C_DQ<2>")
	)
	(segment
		(start 204.543152 -8.937498)
		(end 204.543152 -9.3472)
		(width 0.14224)
		(layer "In11.Cu")
		(net "M_C_DQ<2>")
	)
	(segment
		(start 213.844124 -48.334422)
		(end 214.063072 -48.334422)
		(width 0.14224)
		(layer "In11.Cu")
		(net "M_C_DQ<2>")
	)
	(segment
		(start 216.536778 -49.586896)
		(end 216.756234 -49.806352)
		(width 0.14224)
		(layer "In11.Cu")
		(net "M_C_DQ<2>")
	)
	(segment
		(start 204.543152 -19.027648)
		(end 204.4192 -19.1516)
		(width 0.14224)
		(layer "In11.Cu")
		(net "M_C_DQ<2>")
	)
	(segment
		(start 203.76515 -3.3274)
		(end 203.76515 -4.073144)
		(width 0.14224)
		(layer "In11.Cu")
		(net "M_C_DQ<2>")
	)
	(segment
		(start 215.002618 -48.052736)
		(end 215.002618 -48.271684)
		(width 0.14224)
		(layer "In11.Cu")
		(net "M_C_DQ<2>")
	)
	(segment
		(start 231.77627 -62.068456)
		(end 231.77627 -62.068964)
		(width 0.0889)
		(layer "In11.Cu")
		(net "M_C_DQ<2>")
	)
	(segment
		(start 204.543152 -9.3472)
		(end 204.3938 -9.496552)
		(width 0.14224)
		(layer "In11.Cu")
		(net "M_C_DQ<2>")
	)
	(segment
		(start 239.028478 -64.10579)
		(end 239.18418 -64.10579)
		(width 0.0889)
		(layer "In11.Cu")
		(net "M_C_DQ<2>")
	)
	(segment
		(start 204.834744 -25.891998)
		(end 204.834744 -32.537146)
		(width 0.14224)
		(layer "In11.Cu")
		(net "M_C_DQ<2>")
	)
	(segment
		(start 213.249002 -46.518068)
		(end 212.74786 -47.01921)
		(width 0.14224)
		(layer "In11.Cu")
		(net "M_C_DQ<2>")
	)
	(segment
		(start 215.65997 -48.710088)
		(end 215.879426 -48.929544)
		(width 0.14224)
		(layer "In11.Cu")
		(net "M_C_DQ<2>")
	)
	(segment
		(start 231.243632 -61.62929)
		(end 231.244394 -61.628528)
		(width 0.0889)
		(layer "In11.Cu")
		(net "M_C_DQ<2>")
	)
	(segment
		(start 215.378284 -49.649634)
		(end 215.378284 -49.868582)
		(width 0.14224)
		(layer "In11.Cu")
		(net "M_C_DQ<2>")
	)
	(segment
		(start 204.543152 -21.3614)
		(end 204.543152 -21.796756)
		(width 0.14224)
		(layer "In11.Cu")
		(net "M_C_DQ<2>")
	)
	(segment
		(start 204.2922 -4.600194)
		(end 204.2922 -6.530848)
		(width 0.14224)
		(layer "In11.Cu")
		(net "M_C_DQ<2>")
	)
	(segment
		(start 204.632052 -16.751046)
		(end 204.416152 -16.966946)
		(width 0.14224)
		(layer "In11.Cu")
		(net "M_C_DQ<2>")
	)
	(segment
		(start 217.351356 -51.841654)
		(end 217.570304 -51.841654)
		(width 0.14224)
		(layer "In11.Cu")
		(net "M_C_DQ<2>")
	)
	(segment
		(start 204.543152 -21.796756)
		(end 204.390752 -21.949156)
		(width 0.14224)
		(layer "In11.Cu")
		(net "M_C_DQ<2>")
	)
	(segment
		(start 204.390752 -12.347956)
		(end 204.390752 -13.541756)
		(width 0.14224)
		(layer "In11.Cu")
		(net "M_C_DQ<2>")
	)
	(segment
		(start 212.810598 -46.079664)
		(end 213.029546 -46.079664)
		(width 0.14224)
		(layer "In11.Cu")
		(net "M_C_DQ<2>")
	)
	(segment
		(start 216.31783 -49.586896)
		(end 216.536778 -49.586896)
		(width 0.14224)
		(layer "In11.Cu")
		(net "M_C_DQ<2>")
	)
	(arc
		(start 235.100368 -61.829188)
		(mid 235.308976 -62.04112)
		(end 235.594398 -62.12459)
		(width 0.0889)
		(layer "In11.Cu")
		(net "M_C_DQ<2>")
	)
	(arc
		(start 236.817408 -62.819788)
		(mid 237.026016 -63.03172)
		(end 237.311438 -63.11519)
		(width 0.0889)
		(layer "In11.Cu")
		(net "M_C_DQ<2>")
	)
	(arc
		(start 233.047794 -61.629036)
		(mid 233.241644 -61.685386)
		(end 233.383328 -61.829188)
		(width 0.0889)
		(layer "In11.Cu")
		(net "M_C_DQ<2>")
	)
	(arc
		(start 232.653586 -61.826394)
		(mid 232.7447 -61.708802)
		(end 232.870248 -61.629036)
		(width 0.0889)
		(layer "In11.Cu")
		(net "M_C_DQ<2>")
	)
	(arc
		(start 235.627164 -62.12459)
		(mid 235.818806 -62.181756)
		(end 235.958888 -62.324488)
		(width 0.0889)
		(layer "In11.Cu")
		(net "M_C_DQ<2>")
	)
	(arc
		(start 236.481874 -62.619636)
		(mid 236.675724 -62.675986)
		(end 236.817408 -62.819788)
		(width 0.0889)
		(layer "In11.Cu")
		(net "M_C_DQ<2>")
	)
	(arc
		(start 238.198914 -63.610236)
		(mid 238.392764 -63.666586)
		(end 238.534448 -63.810388)
		(width 0.0889)
		(layer "In11.Cu")
		(net "M_C_DQ<2>")
	)
	(arc
		(start 235.958888 -62.324488)
		(mid 236.165892 -62.535352)
		(end 236.449108 -62.619636)
		(width 0.0889)
		(layer "In11.Cu")
		(net "M_C_DQ<2>")
	)
	(arc
		(start 233.912918 -62.12459)
		(mid 234.198342 -62.041123)
		(end 234.406948 -61.829188)
		(width 0.0889)
		(layer "In11.Cu")
		(net "M_C_DQ<2>")
	)
	(arc
		(start 237.344204 -63.11519)
		(mid 237.535846 -63.172356)
		(end 237.675928 -63.315088)
		(width 0.0889)
		(layer "In11.Cu")
		(net "M_C_DQ<2>")
	)
	(arc
		(start 232.30459 -62.12459)
		(mid 232.507488 -62.00873)
		(end 232.653586 -61.826394)
		(width 0.0889)
		(layer "In11.Cu")
		(net "M_C_DQ<2>")
	)
	(arc
		(start 233.383328 -61.829188)
		(mid 233.591936 -62.04112)
		(end 233.877358 -62.12459)
		(width 0.0889)
		(layer "In11.Cu")
		(net "M_C_DQ<2>")
	)
	(arc
		(start 237.675928 -63.315088)
		(mid 237.882932 -63.525952)
		(end 238.166148 -63.610236)
		(width 0.0889)
		(layer "In11.Cu")
		(net "M_C_DQ<2>")
	)
	(arc
		(start 234.406948 -61.829188)
		(mid 234.753658 -61.628877)
		(end 235.100368 -61.829188)
		(width 0.0889)
		(layer "In11.Cu")
		(net "M_C_DQ<2>")
	)
	(arc
		(start 238.534448 -63.810388)
		(mid 238.743056 -64.02232)
		(end 239.028478 -64.10579)
		(width 0.0889)
		(layer "In11.Cu")
		(net "M_C_DQ<2>")
	)
	(segment
		(start 224.450402 3.778758)
		(end 224.449894 3.778758)
		(width 0.1651)
		(layer "F.Cu")
		(net "M_C_DQ<29>")
	)
	(segment
		(start 224.449894 3.778758)
		(end 224.449894 2.514854)
		(width 0.1651)
		(layer "F.Cu")
		(net "M_C_DQ<29>")
	)
	(segment
		(start 248.202704 -66.48704)
		(end 247.631204 -66.48704)
		(width 0.0889)
		(layer "F.Cu")
		(net "M_C_DQ<29>")
	)
	(via
		(at 247.631204 -66.48704)
		(size 0.508)
		(drill 0.254)
		(layers "F.Cu" "B.Cu")
		(net "M_C_DQ<29>")
	)
	(via
		(at 224.449894 2.514854)
		(size 0.508)
		(drill 0.254)
		(layers "F.Cu" "B.Cu")
		(net "M_C_DQ<29>")
	)
	(via
		(at 225.223578 -3.076956)
		(size 0.508)
		(drill 0.254)
		(layers "F.Cu" "B.Cu")
		(net "M_C_DQ<29>")
	)
	(segment
		(start 225.299778 -3.000756)
		(end 225.223578 -3.076956)
		(width 0.1651)
		(layer "B.Cu")
		(net "M_C_DQ<29>")
	)
	(segment
		(start 225.299778 -1.021842)
		(end 225.299778 -3.000756)
		(width 0.1651)
		(layer "B.Cu")
		(net "M_C_DQ<29>")
	)
	(segment
		(start 225.300286 -1.021842)
		(end 225.299778 -1.021842)
		(width 0.1651)
		(layer "B.Cu")
		(net "M_C_DQ<29>")
	)
	(segment
		(start 247.279668 -61.725302)
		(end 247.284494 -61.733938)
		(width 0.0889)
		(layer "In11.Cu")
		(net "M_C_DQ<29>")
	)
	(segment
		(start 247.279668 -63.706502)
		(end 247.284494 -63.715138)
		(width 0.0889)
		(layer "In11.Cu")
		(net "M_C_DQ<29>")
	)
	(segment
		(start 247.284494 -60.743338)
		(end 247.290844 -60.754006)
		(width 0.0889)
		(layer "In11.Cu")
		(net "M_C_DQ<29>")
	)
	(segment
		(start 225.545396 -28.390596)
		(end 225.545396 -31.558484)
		(width 0.14224)
		(layer "In11.Cu")
		(net "M_C_DQ<29>")
	)
	(segment
		(start 242.4938 -48.506888)
		(end 242.4938 -51.215544)
		(width 0.14224)
		(layer "In11.Cu")
		(net "M_C_DQ<29>")
	)
	(segment
		(start 225.806 -21.1582)
		(end 225.6536 -21.3106)
		(width 0.14224)
		(layer "In11.Cu")
		(net "M_C_DQ<29>")
	)
	(segment
		(start 225.697034 -12.360656)
		(end 225.697034 -13.617956)
		(width 0.14224)
		(layer "In11.Cu")
		(net "M_C_DQ<29>")
	)
	(segment
		(start 247.279668 -59.744102)
		(end 247.284494 -59.752738)
		(width 0.0889)
		(layer "In11.Cu")
		(net "M_C_DQ<29>")
	)
	(segment
		(start 225.679 -19.024346)
		(end 225.806 -19.151346)
		(width 0.14224)
		(layer "In11.Cu")
		(net "M_C_DQ<29>")
	)
	(segment
		(start 225.608134 -11.7348)
		(end 225.608134 -12.271756)
		(width 0.14224)
		(layer "In11.Cu")
		(net "M_C_DQ<29>")
	)
	(segment
		(start 225.331528 1.5494)
		(end 225.020632 1.5494)
		(width 0.14224)
		(layer "In11.Cu")
		(net "M_C_DQ<29>")
	)
	(segment
		(start 225.679 -16.4338)
		(end 225.679 -19.024346)
		(width 0.14224)
		(layer "In11.Cu")
		(net "M_C_DQ<29>")
	)
	(segment
		(start 225.697796 -28.238196)
		(end 225.545396 -28.390596)
		(width 0.14224)
		(layer "In11.Cu")
		(net "M_C_DQ<29>")
	)
	(segment
		(start 247.48744 -64.879474)
		(end 247.912636 -65.183004)
		(width 0.0889)
		(layer "In11.Cu")
		(net "M_C_DQ<29>")
	)
	(segment
		(start 247.284494 -59.752738)
		(end 247.290844 -59.763406)
		(width 0.0889)
		(layer "In11.Cu")
		(net "M_C_DQ<29>")
	)
	(segment
		(start 225.020632 1.5494)
		(end 224.449894 2.120138)
		(width 0.14224)
		(layer "In11.Cu")
		(net "M_C_DQ<29>")
	)
	(segment
		(start 247.284494 -56.780938)
		(end 247.290844 -56.791606)
		(width 0.0889)
		(layer "In11.Cu")
		(net "M_C_DQ<29>")
	)
	(segment
		(start 242.4938 -51.215544)
		(end 242.824 -51.545744)
		(width 0.14224)
		(layer "In11.Cu")
		(net "M_C_DQ<29>")
	)
	(segment
		(start 245.922038 -54.000908)
		(end 245.922038 -54.350666)
		(width 0.0889)
		(layer "In11.Cu")
		(net "M_C_DQ<29>")
	)
	(segment
		(start 247.284494 -61.733938)
		(end 247.290844 -61.744606)
		(width 0.0889)
		(layer "In11.Cu")
		(net "M_C_DQ<29>")
	)
	(segment
		(start 225.534982 0.53975)
		(end 225.731832 0.7366)
		(width 0.14224)
		(layer "In11.Cu")
		(net "M_C_DQ<29>")
	)
	(segment
		(start 247.284494 -63.715138)
		(end 247.290844 -63.725806)
		(width 0.0889)
		(layer "In11.Cu")
		(net "M_C_DQ<29>")
	)
	(segment
		(start 245.040658 -53.513736)
		(end 245.434866 -53.513736)
		(width 0.0889)
		(layer "In11.Cu")
		(net "M_C_DQ<29>")
	)
	(segment
		(start 225.692716 -9.346184)
		(end 225.9838 -9.637268)
		(width 0.14224)
		(layer "In11.Cu")
		(net "M_C_DQ<29>")
	)
	(segment
		(start 247.290844 -58.35142)
		(end 247.284494 -58.362088)
		(width 0.0889)
		(layer "In11.Cu")
		(net "M_C_DQ<29>")
	)
	(segment
		(start 225.633534 -26.309066)
		(end 225.633534 -26.827734)
		(width 0.14224)
		(layer "In11.Cu")
		(net "M_C_DQ<29>")
	)
	(segment
		(start 242.824 -51.81981)
		(end 244.02288 -53.01869)
		(width 0.0889)
		(layer "In11.Cu")
		(net "M_C_DQ<29>")
	)
	(segment
		(start 225.223578 -3.076956)
		(end 225.534982 -2.765552)
		(width 0.14224)
		(layer "In11.Cu")
		(net "M_C_DQ<29>")
	)
	(segment
		(start 225.223578 -3.076956)
		(end 224.719134 -3.5814)
		(width 0.14224)
		(layer "In11.Cu")
		(net "M_C_DQ<29>")
	)
	(segment
		(start 225.806 -19.151346)
		(end 225.806 -21.1582)
		(width 0.14224)
		(layer "In11.Cu")
		(net "M_C_DQ<29>")
	)
	(segment
		(start 247.284494 -62.724538)
		(end 247.290844 -62.735206)
		(width 0.0889)
		(layer "In11.Cu")
		(net "M_C_DQ<29>")
	)
	(segment
		(start 225.697796 -26.891996)
		(end 225.697796 -28.238196)
		(width 0.14224)
		(layer "In11.Cu")
		(net "M_C_DQ<29>")
	)
	(segment
		(start 225.633534 -13.681456)
		(end 225.633534 -16.388334)
		(width 0.14224)
		(layer "In11.Cu")
		(net "M_C_DQ<29>")
	)
	(segment
		(start 242.824 -51.545744)
		(end 242.824 -51.81981)
		(width 0.0889)
		(layer "In11.Cu")
		(net "M_C_DQ<29>")
	)
	(segment
		(start 225.6536 -21.3106)
		(end 225.6536 -21.918422)
		(width 0.14224)
		(layer "In11.Cu")
		(net "M_C_DQ<29>")
	)
	(segment
		(start 247.279668 -60.734702)
		(end 247.284494 -60.743338)
		(width 0.0889)
		(layer "In11.Cu")
		(net "M_C_DQ<29>")
	)
	(segment
		(start 225.731832 0.7366)
		(end 225.731832 1.149096)
		(width 0.14224)
		(layer "In11.Cu")
		(net "M_C_DQ<29>")
	)
	(segment
		(start 225.692716 -7.323328)
		(end 225.692716 -9.346184)
		(width 0.14224)
		(layer "In11.Cu")
		(net "M_C_DQ<29>")
	)
	(segment
		(start 224.719134 -3.5814)
		(end 224.719134 -3.940556)
		(width 0.14224)
		(layer "In11.Cu")
		(net "M_C_DQ<29>")
	)
	(segment
		(start 225.552 -7.182612)
		(end 225.692716 -7.323328)
		(width 0.14224)
		(layer "In11.Cu")
		(net "M_C_DQ<29>")
	)
	(segment
		(start 225.6917 -26.2509)
		(end 225.633534 -26.309066)
		(width 0.14224)
		(layer "In11.Cu")
		(net "M_C_DQ<29>")
	)
	(segment
		(start 225.633534 -16.388334)
		(end 225.679 -16.4338)
		(width 0.14224)
		(layer "In11.Cu")
		(net "M_C_DQ<29>")
	)
	(segment
		(start 247.279668 -57.762902)
		(end 247.284494 -57.771538)
		(width 0.0889)
		(layer "In11.Cu")
		(net "M_C_DQ<29>")
	)
	(segment
		(start 225.9838 -11.359134)
		(end 225.608134 -11.7348)
		(width 0.14224)
		(layer "In11.Cu")
		(net "M_C_DQ<29>")
	)
	(segment
		(start 224.719134 -3.940556)
		(end 225.552 -4.773422)
		(width 0.14224)
		(layer "In11.Cu")
		(net "M_C_DQ<29>")
	)
	(segment
		(start 225.552 -4.773422)
		(end 225.552 -7.182612)
		(width 0.14224)
		(layer "In11.Cu")
		(net "M_C_DQ<29>")
	)
	(segment
		(start 225.608134 -12.271756)
		(end 225.697034 -12.360656)
		(width 0.14224)
		(layer "In11.Cu")
		(net "M_C_DQ<29>")
	)
	(segment
		(start 247.98274 -65.687702)
		(end 247.960642 -65.726056)
		(width 0.0889)
		(layer "In11.Cu")
		(net "M_C_DQ<29>")
	)
	(segment
		(start 247.179338 -55.607966)
		(end 247.284494 -55.790084)
		(width 0.0889)
		(layer "In11.Cu")
		(net "M_C_DQ<29>")
	)
	(segment
		(start 247.912636 -65.183004)
		(end 247.977914 -65.296288)
		(width 0.0889)
		(layer "In11.Cu")
		(net "M_C_DQ<29>")
	)
	(segment
		(start 244.02288 -53.01869)
		(end 244.197124 -53.01869)
		(width 0.0889)
		(layer "In11.Cu")
		(net "M_C_DQ<29>")
	)
	(segment
		(start 225.731832 1.149096)
		(end 225.331528 1.5494)
		(width 0.14224)
		(layer "In11.Cu")
		(net "M_C_DQ<29>")
	)
	(segment
		(start 225.534982 -2.765552)
		(end 225.534982 0.53975)
		(width 0.14224)
		(layer "In11.Cu")
		(net "M_C_DQ<29>")
	)
	(segment
		(start 225.697034 -13.617956)
		(end 225.633534 -13.681456)
		(width 0.14224)
		(layer "In11.Cu")
		(net "M_C_DQ<29>")
	)
	(segment
		(start 247.279668 -56.772302)
		(end 247.284494 -56.780938)
		(width 0.0889)
		(layer "In11.Cu")
		(net "M_C_DQ<29>")
	)
	(segment
		(start 245.434866 -53.513736)
		(end 245.922038 -54.000908)
		(width 0.0889)
		(layer "In11.Cu")
		(net "M_C_DQ<29>")
	)
	(segment
		(start 225.633534 -26.827734)
		(end 225.697796 -26.891996)
		(width 0.14224)
		(layer "In11.Cu")
		(net "M_C_DQ<29>")
	)
	(segment
		(start 247.279668 -62.715902)
		(end 247.284494 -62.724538)
		(width 0.0889)
		(layer "In11.Cu")
		(net "M_C_DQ<29>")
	)
	(segment
		(start 225.545396 -31.558484)
		(end 242.4938 -48.506888)
		(width 0.14224)
		(layer "In11.Cu")
		(net "M_C_DQ<29>")
	)
	(segment
		(start 225.6536 -21.918422)
		(end 225.6917 -21.956522)
		(width 0.14224)
		(layer "In11.Cu")
		(net "M_C_DQ<29>")
	)
	(segment
		(start 225.6917 -21.956522)
		(end 225.6917 -26.2509)
		(width 0.14224)
		(layer "In11.Cu")
		(net "M_C_DQ<29>")
	)
	(segment
		(start 247.960642 -65.726056)
		(end 247.631204 -66.48704)
		(width 0.0889)
		(layer "In11.Cu")
		(net "M_C_DQ<29>")
	)
	(segment
		(start 225.9838 -9.637268)
		(end 225.9838 -11.359134)
		(width 0.14224)
		(layer "In11.Cu")
		(net "M_C_DQ<29>")
	)
	(segment
		(start 224.449894 2.120138)
		(end 224.449894 2.514854)
		(width 0.14224)
		(layer "In11.Cu")
		(net "M_C_DQ<29>")
	)
	(segment
		(start 245.922038 -54.350666)
		(end 247.179338 -55.607966)
		(width 0.0889)
		(layer "In11.Cu")
		(net "M_C_DQ<29>")
	)
	(arc
		(start 244.708934 -53.313838)
		(mid 244.849013 -53.456574)
		(end 245.040658 -53.513736)
		(width 0.0889)
		(layer "In11.Cu")
		(net "M_C_DQ<29>")
	)
	(arc
		(start 247.290844 -56.791606)
		(mid 247.363642 -57.082369)
		(end 247.284494 -57.371488)
		(width 0.0889)
		(layer "In11.Cu")
		(net "M_C_DQ<29>")
	)
	(arc
		(start 247.290844 -59.763406)
		(mid 247.363642 -60.054169)
		(end 247.284494 -60.343288)
		(width 0.0889)
		(layer "In11.Cu")
		(net "M_C_DQ<29>")
	)
	(arc
		(start 247.284494 -64.305688)
		(mid 247.253781 -64.639334)
		(end 247.48744 -64.879474)
		(width 0.0889)
		(layer "In11.Cu")
		(net "M_C_DQ<29>")
	)
	(arc
		(start 247.284494 -57.371488)
		(mid 247.231024 -57.566551)
		(end 247.279668 -57.762902)
		(width 0.0889)
		(layer "In11.Cu")
		(net "M_C_DQ<29>")
	)
	(arc
		(start 247.284494 -58.761884)
		(mid 247.363625 -59.057286)
		(end 247.284494 -59.352688)
		(width 0.0889)
		(layer "In11.Cu")
		(net "M_C_DQ<29>")
	)
	(arc
		(start 247.290844 -62.735206)
		(mid 247.363642 -63.025969)
		(end 247.284494 -63.315088)
		(width 0.0889)
		(layer "In11.Cu")
		(net "M_C_DQ<29>")
	)
	(arc
		(start 247.290844 -63.725806)
		(mid 247.363642 -64.016569)
		(end 247.284494 -64.305688)
		(width 0.0889)
		(layer "In11.Cu")
		(net "M_C_DQ<29>")
	)
	(arc
		(start 247.284494 -63.315088)
		(mid 247.231024 -63.510151)
		(end 247.279668 -63.706502)
		(width 0.0889)
		(layer "In11.Cu")
		(net "M_C_DQ<29>")
	)
	(arc
		(start 247.290844 -60.754006)
		(mid 247.363642 -61.044769)
		(end 247.284494 -61.333888)
		(width 0.0889)
		(layer "In11.Cu")
		(net "M_C_DQ<29>")
	)
	(arc
		(start 247.284494 -55.790084)
		(mid 247.363625 -56.085486)
		(end 247.284494 -56.380888)
		(width 0.0889)
		(layer "In11.Cu")
		(net "M_C_DQ<29>")
	)
	(arc
		(start 247.284494 -60.343288)
		(mid 247.231024 -60.538351)
		(end 247.279668 -60.734702)
		(width 0.0889)
		(layer "In11.Cu")
		(net "M_C_DQ<29>")
	)
	(arc
		(start 247.284494 -61.333888)
		(mid 247.231024 -61.528951)
		(end 247.279668 -61.725302)
		(width 0.0889)
		(layer "In11.Cu")
		(net "M_C_DQ<29>")
	)
	(arc
		(start 247.284494 -56.380888)
		(mid 247.231024 -56.575951)
		(end 247.279668 -56.772302)
		(width 0.0889)
		(layer "In11.Cu")
		(net "M_C_DQ<29>")
	)
	(arc
		(start 247.284494 -57.771538)
		(mid 247.363716 -58.060656)
		(end 247.290844 -58.35142)
		(width 0.0889)
		(layer "In11.Cu")
		(net "M_C_DQ<29>")
	)
	(arc
		(start 247.290844 -61.744606)
		(mid 247.363642 -62.035369)
		(end 247.284494 -62.324488)
		(width 0.0889)
		(layer "In11.Cu")
		(net "M_C_DQ<29>")
	)
	(arc
		(start 247.284494 -62.324488)
		(mid 247.231024 -62.519551)
		(end 247.279668 -62.715902)
		(width 0.0889)
		(layer "In11.Cu")
		(net "M_C_DQ<29>")
	)
	(arc
		(start 247.284494 -59.352688)
		(mid 247.231024 -59.547751)
		(end 247.279668 -59.744102)
		(width 0.0889)
		(layer "In11.Cu")
		(net "M_C_DQ<29>")
	)
	(arc
		(start 247.284494 -58.362088)
		(mid 247.230995 -58.561986)
		(end 247.284494 -58.761884)
		(width 0.0889)
		(layer "In11.Cu")
		(net "M_C_DQ<29>")
	)
	(arc
		(start 247.977914 -65.296288)
		(mid 248.031384 -65.491351)
		(end 247.98274 -65.687702)
		(width 0.0889)
		(layer "In11.Cu")
		(net "M_C_DQ<29>")
	)
	(arc
		(start 244.197124 -53.01869)
		(mid 244.49258 -53.097659)
		(end 244.708934 -53.313838)
		(width 0.0889)
		(layer "In11.Cu")
		(net "M_C_DQ<29>")
	)
	(segment
		(start 225.299778 -0.821182)
		(end 225.299778 0.510032)
		(width 0.1651)
		(layer "F.Cu")
		(net "M_C_DQ<28>")
	)
	(segment
		(start 225.299778 0.510032)
		(end 225.201734 1.0414)
		(width 0.1651)
		(layer "F.Cu")
		(net "M_C_DQ<28>")
	)
	(segment
		(start 225.300286 -0.821182)
		(end 225.299778 -0.821182)
		(width 0.1651)
		(layer "F.Cu")
		(net "M_C_DQ<28>")
	)
	(segment
		(start 248.202704 -65.49644)
		(end 247.631204 -65.49644)
		(width 0.1016)
		(layer "F.Cu")
		(net "M_C_DQ<28>")
	)
	(via
		(at 224.449894 -4.357878)
		(size 0.508)
		(drill 0.254)
		(layers "F.Cu" "B.Cu")
		(net "M_C_DQ<28>")
	)
	(via
		(at 247.631204 -65.49644)
		(size 0.508)
		(drill 0.254)
		(layers "F.Cu" "B.Cu")
		(net "M_C_DQ<28>")
	)
	(via
		(at 225.201734 1.0414)
		(size 0.508)
		(drill 0.254)
		(layers "F.Cu" "B.Cu")
		(net "M_C_DQ<28>")
	)
	(segment
		(start 224.450402 -5.621782)
		(end 224.449894 -5.621782)
		(width 0.1651)
		(layer "B.Cu")
		(net "M_C_DQ<28>")
	)
	(segment
		(start 224.449894 -5.621782)
		(end 224.449894 -4.357878)
		(width 0.1651)
		(layer "B.Cu")
		(net "M_C_DQ<28>")
	)
	(segment
		(start 224.8408 -19.1008)
		(end 224.8408 -21.208746)
		(width 0.14224)
		(layer "In11.Cu")
		(net "M_C_DQ<28>")
	)
	(segment
		(start 224.719134 -17.038066)
		(end 224.719134 -18.313146)
		(width 0.14224)
		(layer "In11.Cu")
		(net "M_C_DQ<28>")
	)
	(segment
		(start 224.947734 -26.676858)
		(end 224.732596 -26.891996)
		(width 0.14224)
		(layer "In11.Cu")
		(net "M_C_DQ<28>")
	)
	(segment
		(start 224.214182 -4.122166)
		(end 224.449894 -4.357878)
		(width 0.14224)
		(layer "In11.Cu")
		(net "M_C_DQ<28>")
	)
	(segment
		(start 224.9424 -1.0668)
		(end 224.5741 -1.4351)
		(width 0.14224)
		(layer "In11.Cu")
		(net "M_C_DQ<28>")
	)
	(segment
		(start 234.113832 -41.685464)
		(end 234.113832 -41.886632)
		(width 0.14224)
		(layer "In11.Cu")
		(net "M_C_DQ<28>")
	)
	(segment
		(start 224.925382 0.287528)
		(end 224.5614 -0.076454)
		(width 0.14224)
		(layer "In11.Cu")
		(net "M_C_DQ<28>")
	)
	(segment
		(start 224.5741 -1.4351)
		(end 224.5741 -1.790446)
		(width 0.14224)
		(layer "In11.Cu")
		(net "M_C_DQ<28>")
	)
	(segment
		(start 247.119394 -63.810388)
		(end 247.12422 -63.819024)
		(width 0.0889)
		(layer "In11.Cu")
		(net "M_C_DQ<28>")
	)
	(segment
		(start 245.731538 -54.080664)
		(end 245.731538 -54.430422)
		(width 0.0889)
		(layer "In11.Cu")
		(net "M_C_DQ<28>")
	)
	(segment
		(start 224.973134 -18.968466)
		(end 224.8408 -19.1008)
		(width 0.14224)
		(layer "In11.Cu")
		(net "M_C_DQ<28>")
	)
	(segment
		(start 224.9424 -0.762)
		(end 224.9424 -1.0668)
		(width 0.14224)
		(layer "In11.Cu")
		(net "M_C_DQ<28>")
	)
	(segment
		(start 247.119394 -56.876188)
		(end 247.12422 -56.884824)
		(width 0.0889)
		(layer "In11.Cu")
		(net "M_C_DQ<28>")
	)
	(segment
		(start 224.8408 -11.602466)
		(end 224.973134 -11.7348)
		(width 0.14224)
		(layer "In11.Cu")
		(net "M_C_DQ<28>")
	)
	(segment
		(start 224.947734 -13.795756)
		(end 224.947734 -16.809466)
		(width 0.14224)
		(layer "In11.Cu")
		(net "M_C_DQ<28>")
	)
	(segment
		(start 240.9698 -49.0474)
		(end 240.9698 -50.0126)
		(width 0.14224)
		(layer "In11.Cu")
		(net "M_C_DQ<28>")
	)
	(segment
		(start 245.731538 -54.430422)
		(end 247.0277 -55.726584)
		(width 0.0889)
		(layer "In11.Cu")
		(net "M_C_DQ<28>")
	)
	(segment
		(start 243.940584 -53.20919)
		(end 244.197124 -53.20919)
		(width 0.0889)
		(layer "In11.Cu")
		(net "M_C_DQ<28>")
	)
	(segment
		(start 247.119394 -61.829188)
		(end 247.12422 -61.837824)
		(width 0.0889)
		(layer "In11.Cu")
		(net "M_C_DQ<28>")
	)
	(segment
		(start 224.214182 -3.327654)
		(end 224.214182 -4.122166)
		(width 0.14224)
		(layer "In11.Cu")
		(net "M_C_DQ<28>")
	)
	(segment
		(start 224.5741 -1.790446)
		(end 224.925382 -2.141728)
		(width 0.14224)
		(layer "In11.Cu")
		(net "M_C_DQ<28>")
	)
	(segment
		(start 224.719134 -21.949156)
		(end 224.719134 -23.168356)
		(width 0.14224)
		(layer "In11.Cu")
		(net "M_C_DQ<28>")
	)
	(segment
		(start 240.9698 -50.0126)
		(end 241.681 -50.7238)
		(width 0.14224)
		(layer "In11.Cu")
		(net "M_C_DQ<28>")
	)
	(segment
		(start 224.719134 -18.313146)
		(end 224.973134 -18.567146)
		(width 0.14224)
		(layer "In11.Cu")
		(net "M_C_DQ<28>")
	)
	(segment
		(start 224.449894 -4.357878)
		(end 224.947734 -4.855718)
		(width 0.14224)
		(layer "In11.Cu")
		(net "M_C_DQ<28>")
	)
	(segment
		(start 224.925382 -2.141728)
		(end 224.925382 -2.616454)
		(width 0.14224)
		(layer "In11.Cu")
		(net "M_C_DQ<28>")
	)
	(segment
		(start 224.5614 -0.381)
		(end 224.9424 -0.762)
		(width 0.14224)
		(layer "In11.Cu")
		(net "M_C_DQ<28>")
	)
	(segment
		(start 224.973134 -9.341866)
		(end 224.8408 -9.4742)
		(width 0.14224)
		(layer "In11.Cu")
		(net "M_C_DQ<28>")
	)
	(segment
		(start 247.113044 -62.80912)
		(end 247.119394 -62.819788)
		(width 0.0889)
		(layer "In11.Cu")
		(net "M_C_DQ<28>")
	)
	(segment
		(start 247.119394 -58.266838)
		(end 247.113044 -58.277506)
		(width 0.0889)
		(layer "In11.Cu")
		(net "M_C_DQ<28>")
	)
	(segment
		(start 242.699794 -51.9684)
		(end 243.940584 -53.20919)
		(width 0.0889)
		(layer "In11.Cu")
		(net "M_C_DQ<28>")
	)
	(segment
		(start 224.907094 -28.285694)
		(end 224.907094 -31.818326)
		(width 0.14224)
		(layer "In11.Cu")
		(net "M_C_DQ<28>")
	)
	(segment
		(start 241.2238 -48.135032)
		(end 241.2238 -48.7934)
		(width 0.14224)
		(layer "In11.Cu")
		(net "M_C_DQ<28>")
	)
	(segment
		(start 245.034054 -53.704236)
		(end 245.35511 -53.704236)
		(width 0.0889)
		(layer "In11.Cu")
		(net "M_C_DQ<28>")
	)
	(segment
		(start 224.925382 -2.616454)
		(end 224.214182 -3.327654)
		(width 0.14224)
		(layer "In11.Cu")
		(net "M_C_DQ<28>")
	)
	(segment
		(start 242.34648 -51.9684)
		(end 242.699794 -51.9684)
		(width 0.0889)
		(layer "In11.Cu")
		(net "M_C_DQ<28>")
	)
	(segment
		(start 224.719134 -8.711946)
		(end 224.973134 -8.965946)
		(width 0.14224)
		(layer "In11.Cu")
		(net "M_C_DQ<28>")
	)
	(segment
		(start 234.300268 -41.499028)
		(end 234.113832 -41.685464)
		(width 0.14224)
		(layer "In11.Cu")
		(net "M_C_DQ<28>")
	)
	(segment
		(start 241.681 -51.30292)
		(end 242.34648 -51.9684)
		(width 0.14224)
		(layer "In11.Cu")
		(net "M_C_DQ<28>")
	)
	(segment
		(start 247.0277 -55.726584)
		(end 247.119394 -55.885334)
		(width 0.0889)
		(layer "In11.Cu")
		(net "M_C_DQ<28>")
	)
	(segment
		(start 224.719134 -7.462266)
		(end 224.719134 -8.711946)
		(width 0.14224)
		(layer "In11.Cu")
		(net "M_C_DQ<28>")
	)
	(segment
		(start 224.947734 -23.396956)
		(end 224.947734 -26.676858)
		(width 0.14224)
		(layer "In11.Cu")
		(net "M_C_DQ<28>")
	)
	(segment
		(start 234.688634 -42.260266)
		(end 234.87507 -42.07383)
		(width 0.14224)
		(layer "In11.Cu")
		(net "M_C_DQ<28>")
	)
	(segment
		(start 224.947734 -16.809466)
		(end 224.719134 -17.038066)
		(width 0.14224)
		(layer "In11.Cu")
		(net "M_C_DQ<28>")
	)
	(segment
		(start 224.5614 -0.076454)
		(end 224.5614 -0.381)
		(width 0.14224)
		(layer "In11.Cu")
		(net "M_C_DQ<28>")
	)
	(segment
		(start 225.201734 1.0414)
		(end 224.925382 0.765048)
		(width 0.14224)
		(layer "In11.Cu")
		(net "M_C_DQ<28>")
	)
	(segment
		(start 247.113044 -59.83732)
		(end 247.119394 -59.847988)
		(width 0.0889)
		(layer "In11.Cu")
		(net "M_C_DQ<28>")
	)
	(segment
		(start 247.136158 -64.830452)
		(end 247.631204 -65.49644)
		(width 0.0889)
		(layer "In11.Cu")
		(net "M_C_DQ<28>")
	)
	(segment
		(start 234.87507 -42.07383)
		(end 235.162598 -42.07383)
		(width 0.14224)
		(layer "In11.Cu")
		(net "M_C_DQ<28>")
	)
	(segment
		(start 234.113832 -41.886632)
		(end 234.487466 -42.260266)
		(width 0.14224)
		(layer "In11.Cu")
		(net "M_C_DQ<28>")
	)
	(segment
		(start 247.113044 -60.82792)
		(end 247.119394 -60.838588)
		(width 0.0889)
		(layer "In11.Cu")
		(net "M_C_DQ<28>")
	)
	(segment
		(start 245.35511 -53.704236)
		(end 245.731538 -54.080664)
		(width 0.0889)
		(layer "In11.Cu")
		(net "M_C_DQ<28>")
	)
	(segment
		(start 224.719134 -13.567156)
		(end 224.947734 -13.795756)
		(width 0.14224)
		(layer "In11.Cu")
		(net "M_C_DQ<28>")
	)
	(segment
		(start 247.119394 -59.847988)
		(end 247.12422 -59.856624)
		(width 0.0889)
		(layer "In11.Cu")
		(net "M_C_DQ<28>")
	)
	(segment
		(start 247.113044 -56.86552)
		(end 247.119394 -56.876188)
		(width 0.0889)
		(layer "In11.Cu")
		(net "M_C_DQ<28>")
	)
	(segment
		(start 247.113044 -61.81852)
		(end 247.119394 -61.829188)
		(width 0.0889)
		(layer "In11.Cu")
		(net "M_C_DQ<28>")
	)
	(segment
		(start 247.113044 -64.79032)
		(end 247.119394 -64.800988)
		(width 0.0889)
		(layer "In11.Cu")
		(net "M_C_DQ<28>")
	)
	(segment
		(start 247.119394 -62.819788)
		(end 247.12422 -62.828424)
		(width 0.0889)
		(layer "In11.Cu")
		(net "M_C_DQ<28>")
	)
	(segment
		(start 224.925382 0.765048)
		(end 224.925382 0.287528)
		(width 0.14224)
		(layer "In11.Cu")
		(net "M_C_DQ<28>")
	)
	(segment
		(start 224.732596 -28.111196)
		(end 224.907094 -28.285694)
		(width 0.14224)
		(layer "In11.Cu")
		(net "M_C_DQ<28>")
	)
	(segment
		(start 241.681 -50.7238)
		(end 241.681 -51.30292)
		(width 0.14224)
		(layer "In11.Cu")
		(net "M_C_DQ<28>")
	)
	(segment
		(start 224.973134 -11.7348)
		(end 224.973134 -12.093956)
		(width 0.14224)
		(layer "In11.Cu")
		(net "M_C_DQ<28>")
	)
	(segment
		(start 224.973134 -18.567146)
		(end 224.973134 -18.968466)
		(width 0.14224)
		(layer "In11.Cu")
		(net "M_C_DQ<28>")
	)
	(segment
		(start 247.119394 -60.838588)
		(end 247.12422 -60.847224)
		(width 0.0889)
		(layer "In11.Cu")
		(net "M_C_DQ<28>")
	)
	(segment
		(start 224.973134 -21.695156)
		(end 224.719134 -21.949156)
		(width 0.14224)
		(layer "In11.Cu")
		(net "M_C_DQ<28>")
	)
	(segment
		(start 224.973134 -12.093956)
		(end 224.719134 -12.347956)
		(width 0.14224)
		(layer "In11.Cu")
		(net "M_C_DQ<28>")
	)
	(segment
		(start 235.162598 -42.07383)
		(end 241.2238 -48.135032)
		(width 0.14224)
		(layer "In11.Cu")
		(net "M_C_DQ<28>")
	)
	(segment
		(start 224.973134 -21.34108)
		(end 224.973134 -21.695156)
		(width 0.14224)
		(layer "In11.Cu")
		(net "M_C_DQ<28>")
	)
	(segment
		(start 234.487466 -42.260266)
		(end 234.688634 -42.260266)
		(width 0.14224)
		(layer "In11.Cu")
		(net "M_C_DQ<28>")
	)
	(segment
		(start 224.719134 -12.347956)
		(end 224.719134 -13.567156)
		(width 0.14224)
		(layer "In11.Cu")
		(net "M_C_DQ<28>")
	)
	(segment
		(start 234.300268 -41.2115)
		(end 234.300268 -41.499028)
		(width 0.14224)
		(layer "In11.Cu")
		(net "M_C_DQ<28>")
	)
	(segment
		(start 247.119394 -58.857388)
		(end 247.12422 -58.866024)
		(width 0.0889)
		(layer "In11.Cu")
		(net "M_C_DQ<28>")
	)
	(segment
		(start 224.907094 -31.818326)
		(end 234.300268 -41.2115)
		(width 0.14224)
		(layer "In11.Cu")
		(net "M_C_DQ<28>")
	)
	(segment
		(start 247.119394 -64.800988)
		(end 247.136158 -64.830452)
		(width 0.0889)
		(layer "In11.Cu")
		(net "M_C_DQ<28>")
	)
	(segment
		(start 224.973134 -8.965946)
		(end 224.973134 -9.341866)
		(width 0.14224)
		(layer "In11.Cu")
		(net "M_C_DQ<28>")
	)
	(segment
		(start 224.8408 -21.208746)
		(end 224.973134 -21.34108)
		(width 0.14224)
		(layer "In11.Cu")
		(net "M_C_DQ<28>")
	)
	(segment
		(start 247.113044 -63.79972)
		(end 247.119394 -63.810388)
		(width 0.0889)
		(layer "In11.Cu")
		(net "M_C_DQ<28>")
	)
	(segment
		(start 224.732596 -26.891996)
		(end 224.732596 -28.111196)
		(width 0.14224)
		(layer "In11.Cu")
		(net "M_C_DQ<28>")
	)
	(segment
		(start 224.947734 -7.233666)
		(end 224.719134 -7.462266)
		(width 0.14224)
		(layer "In11.Cu")
		(net "M_C_DQ<28>")
	)
	(segment
		(start 224.719134 -23.168356)
		(end 224.947734 -23.396956)
		(width 0.14224)
		(layer "In11.Cu")
		(net "M_C_DQ<28>")
	)
	(segment
		(start 224.947734 -4.855718)
		(end 224.947734 -7.233666)
		(width 0.14224)
		(layer "In11.Cu")
		(net "M_C_DQ<28>")
	)
	(segment
		(start 241.2238 -48.7934)
		(end 240.9698 -49.0474)
		(width 0.14224)
		(layer "In11.Cu")
		(net "M_C_DQ<28>")
	)
	(segment
		(start 224.8408 -9.4742)
		(end 224.8408 -11.602466)
		(width 0.14224)
		(layer "In11.Cu")
		(net "M_C_DQ<28>")
	)
	(arc
		(start 247.119394 -57.276238)
		(mid 247.040263 -57.57164)
		(end 247.119394 -57.867042)
		(width 0.0889)
		(layer "In11.Cu")
		(net "M_C_DQ<28>")
	)
	(arc
		(start 247.119394 -57.867042)
		(mid 247.172893 -58.06694)
		(end 247.119394 -58.266838)
		(width 0.0889)
		(layer "In11.Cu")
		(net "M_C_DQ<28>")
	)
	(arc
		(start 247.12422 -63.819024)
		(mid 247.172975 -64.015376)
		(end 247.119394 -64.210438)
		(width 0.0889)
		(layer "In11.Cu")
		(net "M_C_DQ<28>")
	)
	(arc
		(start 247.113044 -58.277506)
		(mid 247.040246 -58.568269)
		(end 247.119394 -58.857388)
		(width 0.0889)
		(layer "In11.Cu")
		(net "M_C_DQ<28>")
	)
	(arc
		(start 247.119394 -64.210438)
		(mid 247.040172 -64.499556)
		(end 247.113044 -64.79032)
		(width 0.0889)
		(layer "In11.Cu")
		(net "M_C_DQ<28>")
	)
	(arc
		(start 247.12422 -62.828424)
		(mid 247.172975 -63.024776)
		(end 247.119394 -63.219838)
		(width 0.0889)
		(layer "In11.Cu")
		(net "M_C_DQ<28>")
	)
	(arc
		(start 247.12422 -59.856624)
		(mid 247.172975 -60.052976)
		(end 247.119394 -60.248038)
		(width 0.0889)
		(layer "In11.Cu")
		(net "M_C_DQ<28>")
	)
	(arc
		(start 247.119394 -55.885334)
		(mid 247.17302 -56.085486)
		(end 247.119394 -56.285638)
		(width 0.0889)
		(layer "In11.Cu")
		(net "M_C_DQ<28>")
	)
	(arc
		(start 244.543834 -53.409088)
		(mid 244.750838 -53.619952)
		(end 245.034054 -53.704236)
		(width 0.0889)
		(layer "In11.Cu")
		(net "M_C_DQ<28>")
	)
	(arc
		(start 247.119394 -56.285638)
		(mid 247.040172 -56.574756)
		(end 247.113044 -56.86552)
		(width 0.0889)
		(layer "In11.Cu")
		(net "M_C_DQ<28>")
	)
	(arc
		(start 247.12422 -56.884824)
		(mid 247.172975 -57.081176)
		(end 247.119394 -57.276238)
		(width 0.0889)
		(layer "In11.Cu")
		(net "M_C_DQ<28>")
	)
	(arc
		(start 247.12422 -58.866024)
		(mid 247.172975 -59.062376)
		(end 247.119394 -59.257438)
		(width 0.0889)
		(layer "In11.Cu")
		(net "M_C_DQ<28>")
	)
	(arc
		(start 247.12422 -61.837824)
		(mid 247.172975 -62.034176)
		(end 247.119394 -62.229238)
		(width 0.0889)
		(layer "In11.Cu")
		(net "M_C_DQ<28>")
	)
	(arc
		(start 247.119394 -59.257438)
		(mid 247.040172 -59.546556)
		(end 247.113044 -59.83732)
		(width 0.0889)
		(layer "In11.Cu")
		(net "M_C_DQ<28>")
	)
	(arc
		(start 247.12422 -60.847224)
		(mid 247.172975 -61.043576)
		(end 247.119394 -61.238638)
		(width 0.0889)
		(layer "In11.Cu")
		(net "M_C_DQ<28>")
	)
	(arc
		(start 247.119394 -60.248038)
		(mid 247.040172 -60.537156)
		(end 247.113044 -60.82792)
		(width 0.0889)
		(layer "In11.Cu")
		(net "M_C_DQ<28>")
	)
	(arc
		(start 247.119394 -61.238638)
		(mid 247.040172 -61.527756)
		(end 247.113044 -61.81852)
		(width 0.0889)
		(layer "In11.Cu")
		(net "M_C_DQ<28>")
	)
	(arc
		(start 247.119394 -62.229238)
		(mid 247.040172 -62.518356)
		(end 247.113044 -62.80912)
		(width 0.0889)
		(layer "In11.Cu")
		(net "M_C_DQ<28>")
	)
	(arc
		(start 247.119394 -63.219838)
		(mid 247.040172 -63.508956)
		(end 247.113044 -63.79972)
		(width 0.0889)
		(layer "In11.Cu")
		(net "M_C_DQ<28>")
	)
	(arc
		(start 244.197124 -53.20919)
		(mid 244.397303 -53.262621)
		(end 244.543834 -53.409088)
		(width 0.0889)
		(layer "In11.Cu")
		(net "M_C_DQ<28>")
	)
	(segment
		(start 232.100374 3.778758)
		(end 232.099866 3.778758)
		(width 0.1651)
		(layer "F.Cu")
		(net "M_C_DQ<27>")
	)
	(segment
		(start 232.099866 3.778758)
		(end 232.099866 2.514854)
		(width 0.1651)
		(layer "F.Cu")
		(net "M_C_DQ<27>")
	)
	(segment
		(start 251.636784 -66.48704)
		(end 251.065284 -66.48704)
		(width 0.0889)
		(layer "F.Cu")
		(net "M_C_DQ<27>")
	)
	(via
		(at 232.099866 2.514854)
		(size 0.508)
		(drill 0.254)
		(layers "F.Cu" "B.Cu")
		(net "M_C_DQ<27>")
	)
	(via
		(at 232.94975 -3.076956)
		(size 0.508)
		(drill 0.254)
		(layers "F.Cu" "B.Cu")
		(net "M_C_DQ<27>")
	)
	(via
		(at 251.065284 -66.48704)
		(size 0.508)
		(drill 0.254)
		(layers "F.Cu" "B.Cu")
		(net "M_C_DQ<27>")
	)
	(segment
		(start 232.950512 -1.021842)
		(end 232.950512 -3.076194)
		(width 0.1651)
		(layer "B.Cu")
		(net "M_C_DQ<27>")
	)
	(segment
		(start 232.950512 -3.076194)
		(end 232.94975 -3.076956)
		(width 0.1651)
		(layer "B.Cu")
		(net "M_C_DQ<27>")
	)
	(segment
		(start 251.583444 -59.83732)
		(end 251.577094 -59.847988)
		(width 0.0889)
		(layer "In11.Cu")
		(net "M_C_DQ<27>")
	)
	(segment
		(start 232.099866 2.514854)
		(end 232.416604 2.198116)
		(width 0.14224)
		(layer "In11.Cu")
		(net "M_C_DQ<27>")
	)
	(segment
		(start 251.577094 -62.819788)
		(end 251.572268 -62.828424)
		(width 0.0889)
		(layer "In11.Cu")
		(net "M_C_DQ<27>")
	)
	(segment
		(start 250.039124 -49.873154)
		(end 249.503184 -50.409094)
		(width 0.0889)
		(layer "In11.Cu")
		(net "M_C_DQ<27>")
	)
	(segment
		(start 251.583444 -63.79972)
		(end 251.577094 -63.810388)
		(width 0.0889)
		(layer "In11.Cu")
		(net "M_C_DQ<27>")
	)
	(segment
		(start 251.583444 -60.82792)
		(end 251.577094 -60.838588)
		(width 0.0889)
		(layer "In11.Cu")
		(net "M_C_DQ<27>")
	)
	(segment
		(start 233.482134 -21.999956)
		(end 233.482134 -23.183596)
		(width 0.14224)
		(layer "In11.Cu")
		(net "M_C_DQ<27>")
	)
	(segment
		(start 233.4768 -11.557)
		(end 233.304334 -11.729466)
		(width 0.14224)
		(layer "In11.Cu")
		(net "M_C_DQ<27>")
	)
	(segment
		(start 233.304334 -18.587466)
		(end 233.304334 -18.953734)
		(width 0.14224)
		(layer "In11.Cu")
		(net "M_C_DQ<27>")
	)
	(segment
		(start 233.456734 -17.030446)
		(end 233.456734 -18.435066)
		(width 0.14224)
		(layer "In11.Cu")
		(net "M_C_DQ<27>")
	)
	(segment
		(start 233.304334 -9.3726)
		(end 233.4768 -9.545066)
		(width 0.14224)
		(layer "In11.Cu")
		(net "M_C_DQ<27>")
	)
	(segment
		(start 250.039124 -49.659794)
		(end 250.039124 -49.873154)
		(width 0.0889)
		(layer "In11.Cu")
		(net "M_C_DQ<27>")
	)
	(segment
		(start 233.456734 -8.833866)
		(end 233.304334 -8.986266)
		(width 0.14224)
		(layer "In11.Cu")
		(net "M_C_DQ<27>")
	)
	(segment
		(start 233.317034 -13.681456)
		(end 233.317034 -16.890746)
		(width 0.14224)
		(layer "In11.Cu")
		(net "M_C_DQ<27>")
	)
	(segment
		(start 233.292396 -28.263596)
		(end 233.292396 -28.796996)
		(width 0.14224)
		(layer "In11.Cu")
		(net "M_C_DQ<27>")
	)
	(segment
		(start 251.577094 -55.885588)
		(end 251.572268 -55.894224)
		(width 0.0889)
		(layer "In11.Cu")
		(net "M_C_DQ<27>")
	)
	(segment
		(start 233.304334 -8.986266)
		(end 233.304334 -9.3726)
		(width 0.14224)
		(layer "In11.Cu")
		(net "M_C_DQ<27>")
	)
	(segment
		(start 251.577094 -58.857388)
		(end 251.572268 -58.866024)
		(width 0.0889)
		(layer "In11.Cu")
		(net "M_C_DQ<27>")
	)
	(segment
		(start 250.272804 -49.426114)
		(end 250.039124 -49.659794)
		(width 0.0889)
		(layer "In11.Cu")
		(net "M_C_DQ<27>")
	)
	(segment
		(start 251.583444 -61.81852)
		(end 251.577094 -61.829188)
		(width 0.0889)
		(layer "In11.Cu")
		(net "M_C_DQ<27>")
	)
	(segment
		(start 250.656344 -53.767736)
		(end 250.897898 -54.00929)
		(width 0.0889)
		(layer "In11.Cu")
		(net "M_C_DQ<27>")
	)
	(segment
		(start 250.897898 -54.00929)
		(end 251.086874 -54.00929)
		(width 0.0889)
		(layer "In11.Cu")
		(net "M_C_DQ<27>")
	)
	(segment
		(start 233.462068 -28.093924)
		(end 233.292396 -28.263596)
		(width 0.14224)
		(layer "In11.Cu")
		(net "M_C_DQ<27>")
	)
	(segment
		(start 251.583444 -64.79032)
		(end 251.577094 -64.800988)
		(width 0.0889)
		(layer "In11.Cu")
		(net "M_C_DQ<27>")
	)
	(segment
		(start 233.456734 -7.429246)
		(end 233.456734 -8.833866)
		(width 0.14224)
		(layer "In11.Cu")
		(net "M_C_DQ<27>")
	)
	(segment
		(start 251.583444 -56.86552)
		(end 251.577094 -56.876188)
		(width 0.0889)
		(layer "In11.Cu")
		(net "M_C_DQ<27>")
	)
	(segment
		(start 251.583444 -54.88432)
		(end 251.577094 -54.894988)
		(width 0.0889)
		(layer "In11.Cu")
		(net "M_C_DQ<27>")
	)
	(segment
		(start 232.746804 1.5494)
		(end 233.000804 1.5494)
		(width 0.14224)
		(layer "In11.Cu")
		(net "M_C_DQ<27>")
	)
	(segment
		(start 233.329734 -23.335996)
		(end 233.329734 -26.77668)
		(width 0.14224)
		(layer "In11.Cu")
		(net "M_C_DQ<27>")
	)
	(segment
		(start 233.304334 -18.953734)
		(end 233.4768 -19.1262)
		(width 0.14224)
		(layer "In11.Cu")
		(net "M_C_DQ<27>")
	)
	(segment
		(start 251.577094 -64.800988)
		(end 251.572268 -64.809624)
		(width 0.0889)
		(layer "In11.Cu")
		(net "M_C_DQ<27>")
	)
	(segment
		(start 233.4768 -9.545066)
		(end 233.4768 -11.557)
		(width 0.14224)
		(layer "In11.Cu")
		(net "M_C_DQ<27>")
	)
	(segment
		(start 251.577094 -56.876188)
		(end 251.572268 -56.884824)
		(width 0.0889)
		(layer "In11.Cu")
		(net "M_C_DQ<27>")
	)
	(segment
		(start 251.577094 -61.829188)
		(end 251.572268 -61.837824)
		(width 0.0889)
		(layer "In11.Cu")
		(net "M_C_DQ<27>")
	)
	(segment
		(start 251.577094 -59.847988)
		(end 251.572268 -59.856624)
		(width 0.0889)
		(layer "In11.Cu")
		(net "M_C_DQ<27>")
	)
	(segment
		(start 233.4006 -13.59789)
		(end 233.317034 -13.681456)
		(width 0.14224)
		(layer "In11.Cu")
		(net "M_C_DQ<27>")
	)
	(segment
		(start 242.2398 -37.7444)
		(end 242.2398 -40.121078)
		(width 0.14224)
		(layer "In11.Cu")
		(net "M_C_DQ<27>")
	)
	(segment
		(start 251.56033 -65.821052)
		(end 251.065284 -66.48704)
		(width 0.0889)
		(layer "In11.Cu")
		(net "M_C_DQ<27>")
	)
	(segment
		(start 251.577094 -65.791588)
		(end 251.56033 -65.821052)
		(width 0.0889)
		(layer "In11.Cu")
		(net "M_C_DQ<27>")
	)
	(segment
		(start 232.466134 -3.560572)
		(end 232.466134 -3.965956)
		(width 0.14224)
		(layer "In11.Cu")
		(net "M_C_DQ<27>")
	)
	(segment
		(start 233.304334 -12.220956)
		(end 233.4006 -12.317222)
		(width 0.14224)
		(layer "In11.Cu")
		(net "M_C_DQ<27>")
	)
	(segment
		(start 233.317034 -7.289546)
		(end 233.456734 -7.429246)
		(width 0.14224)
		(layer "In11.Cu")
		(net "M_C_DQ<27>")
	)
	(segment
		(start 233.458004 0.7366)
		(end 233.302556 0.581152)
		(width 0.14224)
		(layer "In11.Cu")
		(net "M_C_DQ<27>")
	)
	(segment
		(start 233.4768 -21.138134)
		(end 233.304334 -21.3106)
		(width 0.14224)
		(layer "In11.Cu")
		(net "M_C_DQ<27>")
	)
	(segment
		(start 250.272804 -48.154082)
		(end 250.272804 -49.426114)
		(width 0.14224)
		(layer "In11.Cu")
		(net "M_C_DQ<27>")
	)
	(segment
		(start 233.302556 0.581152)
		(end 233.302556 -2.72415)
		(width 0.14224)
		(layer "In11.Cu")
		(net "M_C_DQ<27>")
	)
	(segment
		(start 249.503184 -50.724054)
		(end 250.656344 -51.877214)
		(width 0.0889)
		(layer "In11.Cu")
		(net "M_C_DQ<27>")
	)
	(segment
		(start 251.577094 -58.266838)
		(end 251.583444 -58.277506)
		(width 0.0889)
		(layer "In11.Cu")
		(net "M_C_DQ<27>")
	)
	(segment
		(start 233.482134 -23.183596)
		(end 233.329734 -23.335996)
		(width 0.14224)
		(layer "In11.Cu")
		(net "M_C_DQ<27>")
	)
	(segment
		(start 233.456734 -18.435066)
		(end 233.304334 -18.587466)
		(width 0.14224)
		(layer "In11.Cu")
		(net "M_C_DQ<27>")
	)
	(segment
		(start 233.317034 -16.890746)
		(end 233.456734 -17.030446)
		(width 0.14224)
		(layer "In11.Cu")
		(net "M_C_DQ<27>")
	)
	(segment
		(start 251.577094 -54.894988)
		(end 251.572268 -54.903624)
		(width 0.0889)
		(layer "In11.Cu")
		(net "M_C_DQ<27>")
	)
	(segment
		(start 232.416604 1.8796)
		(end 232.746804 1.5494)
		(width 0.14224)
		(layer "In11.Cu")
		(net "M_C_DQ<27>")
	)
	(segment
		(start 233.462068 -26.909014)
		(end 233.462068 -28.093924)
		(width 0.14224)
		(layer "In11.Cu")
		(net "M_C_DQ<27>")
	)
	(segment
		(start 249.503184 -50.409094)
		(end 249.503184 -50.724054)
		(width 0.0889)
		(layer "In11.Cu")
		(net "M_C_DQ<27>")
	)
	(segment
		(start 251.577094 -60.838588)
		(end 251.572268 -60.847224)
		(width 0.0889)
		(layer "In11.Cu")
		(net "M_C_DQ<27>")
	)
	(segment
		(start 233.304334 -21.822156)
		(end 233.482134 -21.999956)
		(width 0.14224)
		(layer "In11.Cu")
		(net "M_C_DQ<27>")
	)
	(segment
		(start 233.302556 -2.72415)
		(end 232.94975 -3.076956)
		(width 0.14224)
		(layer "In11.Cu")
		(net "M_C_DQ<27>")
	)
	(segment
		(start 233.4768 -19.1262)
		(end 233.4768 -21.138134)
		(width 0.14224)
		(layer "In11.Cu")
		(net "M_C_DQ<27>")
	)
	(segment
		(start 233.458004 1.0922)
		(end 233.458004 0.7366)
		(width 0.14224)
		(layer "In11.Cu")
		(net "M_C_DQ<27>")
	)
	(segment
		(start 233.292396 -28.796996)
		(end 242.2398 -37.7444)
		(width 0.14224)
		(layer "In11.Cu")
		(net "M_C_DQ<27>")
	)
	(segment
		(start 232.466134 -3.965956)
		(end 233.317034 -4.816856)
		(width 0.14224)
		(layer "In11.Cu")
		(net "M_C_DQ<27>")
	)
	(segment
		(start 251.583444 -62.80912)
		(end 251.577094 -62.819788)
		(width 0.0889)
		(layer "In11.Cu")
		(net "M_C_DQ<27>")
	)
	(segment
		(start 233.304334 -11.729466)
		(end 233.304334 -12.220956)
		(width 0.14224)
		(layer "In11.Cu")
		(net "M_C_DQ<27>")
	)
	(segment
		(start 233.317034 -4.816856)
		(end 233.317034 -7.289546)
		(width 0.14224)
		(layer "In11.Cu")
		(net "M_C_DQ<27>")
	)
	(segment
		(start 232.94975 -3.076956)
		(end 232.466134 -3.560572)
		(width 0.14224)
		(layer "In11.Cu")
		(net "M_C_DQ<27>")
	)
	(segment
		(start 232.416604 2.198116)
		(end 232.416604 1.8796)
		(width 0.14224)
		(layer "In11.Cu")
		(net "M_C_DQ<27>")
	)
	(segment
		(start 233.4006 -12.317222)
		(end 233.4006 -13.59789)
		(width 0.14224)
		(layer "In11.Cu")
		(net "M_C_DQ<27>")
	)
	(segment
		(start 251.577094 -63.810388)
		(end 251.572268 -63.819024)
		(width 0.0889)
		(layer "In11.Cu")
		(net "M_C_DQ<27>")
	)
	(segment
		(start 242.2398 -40.121078)
		(end 250.272804 -48.154082)
		(width 0.14224)
		(layer "In11.Cu")
		(net "M_C_DQ<27>")
	)
	(segment
		(start 233.329734 -26.77668)
		(end 233.462068 -26.909014)
		(width 0.14224)
		(layer "In11.Cu")
		(net "M_C_DQ<27>")
	)
	(segment
		(start 251.583444 -65.78092)
		(end 251.577094 -65.791588)
		(width 0.0889)
		(layer "In11.Cu")
		(net "M_C_DQ<27>")
	)
	(segment
		(start 233.304334 -21.3106)
		(end 233.304334 -21.822156)
		(width 0.14224)
		(layer "In11.Cu")
		(net "M_C_DQ<27>")
	)
	(segment
		(start 250.656344 -51.877214)
		(end 250.656344 -53.767736)
		(width 0.0889)
		(layer "In11.Cu")
		(net "M_C_DQ<27>")
	)
	(segment
		(start 233.000804 1.5494)
		(end 233.458004 1.0922)
		(width 0.14224)
		(layer "In11.Cu")
		(net "M_C_DQ<27>")
	)
	(segment
		(start 251.583444 -55.87492)
		(end 251.577094 -55.885588)
		(width 0.0889)
		(layer "In11.Cu")
		(net "M_C_DQ<27>")
	)
	(arc
		(start 251.577094 -57.276238)
		(mid 251.656225 -57.57164)
		(end 251.577094 -57.867042)
		(width 0.0889)
		(layer "In11.Cu")
		(net "M_C_DQ<27>")
	)
	(arc
		(start 251.572268 -54.903624)
		(mid 251.523513 -55.099976)
		(end 251.577094 -55.295038)
		(width 0.0889)
		(layer "In11.Cu")
		(net "M_C_DQ<27>")
	)
	(arc
		(start 251.572268 -60.847224)
		(mid 251.523513 -61.043576)
		(end 251.577094 -61.238638)
		(width 0.0889)
		(layer "In11.Cu")
		(net "M_C_DQ<27>")
	)
	(arc
		(start 251.577094 -56.285638)
		(mid 251.656316 -56.574756)
		(end 251.583444 -56.86552)
		(width 0.0889)
		(layer "In11.Cu")
		(net "M_C_DQ<27>")
	)
	(arc
		(start 251.572268 -58.866024)
		(mid 251.523513 -59.062376)
		(end 251.577094 -59.257438)
		(width 0.0889)
		(layer "In11.Cu")
		(net "M_C_DQ<27>")
	)
	(arc
		(start 251.577094 -57.867042)
		(mid 251.523595 -58.06694)
		(end 251.577094 -58.266838)
		(width 0.0889)
		(layer "In11.Cu")
		(net "M_C_DQ<27>")
	)
	(arc
		(start 251.577094 -60.248038)
		(mid 251.656316 -60.537156)
		(end 251.583444 -60.82792)
		(width 0.0889)
		(layer "In11.Cu")
		(net "M_C_DQ<27>")
	)
	(arc
		(start 251.583444 -58.277506)
		(mid 251.656242 -58.568269)
		(end 251.577094 -58.857388)
		(width 0.0889)
		(layer "In11.Cu")
		(net "M_C_DQ<27>")
	)
	(arc
		(start 251.086874 -54.00929)
		(mid 251.579264 -54.308223)
		(end 251.583444 -54.88432)
		(width 0.0889)
		(layer "In11.Cu")
		(net "M_C_DQ<27>")
	)
	(arc
		(start 251.577094 -59.257438)
		(mid 251.656316 -59.546556)
		(end 251.583444 -59.83732)
		(width 0.0889)
		(layer "In11.Cu")
		(net "M_C_DQ<27>")
	)
	(arc
		(start 251.577094 -61.238638)
		(mid 251.656316 -61.527756)
		(end 251.583444 -61.81852)
		(width 0.0889)
		(layer "In11.Cu")
		(net "M_C_DQ<27>")
	)
	(arc
		(start 251.572268 -59.856624)
		(mid 251.523513 -60.052976)
		(end 251.577094 -60.248038)
		(width 0.0889)
		(layer "In11.Cu")
		(net "M_C_DQ<27>")
	)
	(arc
		(start 251.572268 -61.837824)
		(mid 251.523513 -62.034176)
		(end 251.577094 -62.229238)
		(width 0.0889)
		(layer "In11.Cu")
		(net "M_C_DQ<27>")
	)
	(arc
		(start 251.577094 -55.295038)
		(mid 251.656316 -55.584156)
		(end 251.583444 -55.87492)
		(width 0.0889)
		(layer "In11.Cu")
		(net "M_C_DQ<27>")
	)
	(arc
		(start 251.577094 -65.201038)
		(mid 251.656316 -65.490156)
		(end 251.583444 -65.78092)
		(width 0.0889)
		(layer "In11.Cu")
		(net "M_C_DQ<27>")
	)
	(arc
		(start 251.572268 -63.819024)
		(mid 251.523513 -64.015376)
		(end 251.577094 -64.210438)
		(width 0.0889)
		(layer "In11.Cu")
		(net "M_C_DQ<27>")
	)
	(arc
		(start 251.577094 -64.210438)
		(mid 251.656316 -64.499556)
		(end 251.583444 -64.79032)
		(width 0.0889)
		(layer "In11.Cu")
		(net "M_C_DQ<27>")
	)
	(arc
		(start 251.572268 -56.884824)
		(mid 251.523513 -57.081176)
		(end 251.577094 -57.276238)
		(width 0.0889)
		(layer "In11.Cu")
		(net "M_C_DQ<27>")
	)
	(arc
		(start 251.572268 -62.828424)
		(mid 251.523513 -63.024776)
		(end 251.577094 -63.219838)
		(width 0.0889)
		(layer "In11.Cu")
		(net "M_C_DQ<27>")
	)
	(arc
		(start 251.572268 -55.894224)
		(mid 251.523513 -56.090576)
		(end 251.577094 -56.285638)
		(width 0.0889)
		(layer "In11.Cu")
		(net "M_C_DQ<27>")
	)
	(arc
		(start 251.577094 -63.219838)
		(mid 251.656316 -63.508956)
		(end 251.583444 -63.79972)
		(width 0.0889)
		(layer "In11.Cu")
		(net "M_C_DQ<27>")
	)
	(arc
		(start 251.572268 -64.809624)
		(mid 251.523513 -65.005976)
		(end 251.577094 -65.201038)
		(width 0.0889)
		(layer "In11.Cu")
		(net "M_C_DQ<27>")
	)
	(arc
		(start 251.577094 -62.229238)
		(mid 251.656316 -62.518356)
		(end 251.583444 -62.80912)
		(width 0.0889)
		(layer "In11.Cu")
		(net "M_C_DQ<27>")
	)
	(segment
		(start 232.950512 -0.821182)
		(end 232.94975 -0.82042)
		(width 0.1651)
		(layer "F.Cu")
		(net "M_C_DQ<26>")
	)
	(segment
		(start 233.081322 0.53086)
		(end 232.94975 0.662432)
		(width 0.1651)
		(layer "F.Cu")
		(net "M_C_DQ<26>")
	)
	(segment
		(start 251.636784 -65.49644)
		(end 251.065284 -65.49644)
		(width 0.0889)
		(layer "F.Cu")
		(net "M_C_DQ<26>")
	)
	(segment
		(start 233.081322 0.30734)
		(end 233.081322 0.53086)
		(width 0.1651)
		(layer "F.Cu")
		(net "M_C_DQ<26>")
	)
	(segment
		(start 232.94975 -0.82042)
		(end 232.94975 0.175768)
		(width 0.1651)
		(layer "F.Cu")
		(net "M_C_DQ<26>")
	)
	(segment
		(start 232.94975 0.662432)
		(end 232.94975 0.9398)
		(width 0.1651)
		(layer "F.Cu")
		(net "M_C_DQ<26>")
	)
	(segment
		(start 232.94975 0.175768)
		(end 233.081322 0.30734)
		(width 0.1651)
		(layer "F.Cu")
		(net "M_C_DQ<26>")
	)
	(via
		(at 232.94975 0.9398)
		(size 0.508)
		(drill 0.254)
		(layers "F.Cu" "B.Cu")
		(net "M_C_DQ<26>")
	)
	(via
		(at 251.065284 -65.49644)
		(size 0.508)
		(drill 0.254)
		(layers "F.Cu" "B.Cu")
		(net "M_C_DQ<26>")
	)
	(via
		(at 232.099866 -4.357878)
		(size 0.508)
		(drill 0.254)
		(layers "F.Cu" "B.Cu")
		(net "M_C_DQ<26>")
	)
	(segment
		(start 232.100374 -5.621782)
		(end 232.099866 -5.621782)
		(width 0.1651)
		(layer "B.Cu")
		(net "M_C_DQ<26>")
	)
	(segment
		(start 232.099866 -5.621782)
		(end 232.099866 -4.357878)
		(width 0.1651)
		(layer "B.Cu")
		(net "M_C_DQ<26>")
	)
	(segment
		(start 232.664 -2.478532)
		(end 231.815132 -3.3274)
		(width 0.14224)
		(layer "In11.Cu")
		(net "M_C_DQ<26>")
	)
	(segment
		(start 232.466134 -7.365746)
		(end 232.466134 -8.844534)
		(width 0.14224)
		(layer "In11.Cu")
		(net "M_C_DQ<26>")
	)
	(segment
		(start 232.099866 -4.514342)
		(end 232.669334 -5.08381)
		(width 0.14224)
		(layer "In11.Cu")
		(net "M_C_DQ<26>")
	)
	(segment
		(start 251.411994 -55.790338)
		(end 251.405644 -55.801006)
		(width 0.0889)
		(layer "In11.Cu")
		(net "M_C_DQ<26>")
	)
	(segment
		(start 232.94975 0.9398)
		(end 232.551732 0.541782)
		(width 0.14224)
		(layer "In11.Cu")
		(net "M_C_DQ<26>")
	)
	(segment
		(start 251.41682 -62.715902)
		(end 251.411994 -62.724538)
		(width 0.0889)
		(layer "In11.Cu")
		(net "M_C_DQ<26>")
	)
	(segment
		(start 250.465844 -53.849524)
		(end 250.81611 -54.19979)
		(width 0.0889)
		(layer "In11.Cu")
		(net "M_C_DQ<26>")
	)
	(segment
		(start 232.2068 -0.108204)
		(end 232.2068 -0.456946)
		(width 0.14224)
		(layer "In11.Cu")
		(net "M_C_DQ<26>")
	)
	(segment
		(start 232.2068 -0.456946)
		(end 232.5116 -0.761746)
		(width 0.14224)
		(layer "In11.Cu")
		(net "M_C_DQ<26>")
	)
	(segment
		(start 232.449116 -11.590782)
		(end 232.593134 -11.7348)
		(width 0.14224)
		(layer "In11.Cu")
		(net "M_C_DQ<26>")
	)
	(segment
		(start 239.5728 -38.352476)
		(end 240.04524 -38.824916)
		(width 0.14224)
		(layer "In11.Cu")
		(net "M_C_DQ<26>")
	)
	(segment
		(start 232.2068 -1.7526)
		(end 232.664 -2.2098)
		(width 0.14224)
		(layer "In11.Cu")
		(net "M_C_DQ<26>")
	)
	(segment
		(start 251.411994 -60.743338)
		(end 251.405644 -60.754006)
		(width 0.0889)
		(layer "In11.Cu")
		(net "M_C_DQ<26>")
	)
	(segment
		(start 251.411994 -63.715138)
		(end 251.405644 -63.725806)
		(width 0.0889)
		(layer "In11.Cu")
		(net "M_C_DQ<26>")
	)
	(segment
		(start 232.593134 -9.443466)
		(end 232.449116 -9.587484)
		(width 0.14224)
		(layer "In11.Cu")
		(net "M_C_DQ<26>")
	)
	(segment
		(start 232.466134 -16.966946)
		(end 232.466134 -18.445734)
		(width 0.14224)
		(layer "In11.Cu")
		(net "M_C_DQ<26>")
	)
	(segment
		(start 249.848624 -49.794414)
		(end 249.312684 -50.330354)
		(width 0.0889)
		(layer "In11.Cu")
		(net "M_C_DQ<26>")
	)
	(segment
		(start 241.035078 -38.036246)
		(end 241.236246 -38.036246)
		(width 0.14224)
		(layer "In11.Cu")
		(net "M_C_DQ<26>")
	)
	(segment
		(start 251.41682 -57.762902)
		(end 251.411994 -57.771538)
		(width 0.0889)
		(layer "In11.Cu")
		(net "M_C_DQ<26>")
	)
	(segment
		(start 232.581196 -28.98394)
		(end 239.5728 -35.975544)
		(width 0.14224)
		(layer "In11.Cu")
		(net "M_C_DQ<26>")
	)
	(segment
		(start 232.428796 -26.815796)
		(end 232.428796 -28.085796)
		(width 0.14224)
		(layer "In11.Cu")
		(net "M_C_DQ<26>")
	)
	(segment
		(start 251.41682 -56.772302)
		(end 251.411994 -56.780938)
		(width 0.0889)
		(layer "In11.Cu")
		(net "M_C_DQ<26>")
	)
	(segment
		(start 232.593134 -18.572734)
		(end 232.593134 -18.968466)
		(width 0.14224)
		(layer "In11.Cu")
		(net "M_C_DQ<26>")
	)
	(segment
		(start 251.41682 -59.744102)
		(end 251.411994 -59.752738)
		(width 0.0889)
		(layer "In11.Cu")
		(net "M_C_DQ<26>")
	)
	(segment
		(start 240.706402 -39.28491)
		(end 240.706402 -39.486078)
		(width 0.14224)
		(layer "In11.Cu")
		(net "M_C_DQ<26>")
	)
	(segment
		(start 251.411994 -56.780938)
		(end 251.405644 -56.791606)
		(width 0.0889)
		(layer "In11.Cu")
		(net "M_C_DQ<26>")
	)
	(segment
		(start 232.5116 -1.04775)
		(end 232.2068 -1.35255)
		(width 0.14224)
		(layer "In11.Cu")
		(net "M_C_DQ<26>")
	)
	(segment
		(start 232.41 -19.1516)
		(end 232.41 -21.152866)
		(width 0.14224)
		(layer "In11.Cu")
		(net "M_C_DQ<26>")
	)
	(segment
		(start 249.848624 -49.636934)
		(end 249.848624 -49.794414)
		(width 0.0889)
		(layer "In11.Cu")
		(net "M_C_DQ<26>")
	)
	(segment
		(start 249.312684 -50.802794)
		(end 250.465844 -51.955954)
		(width 0.0889)
		(layer "In11.Cu")
		(net "M_C_DQ<26>")
	)
	(segment
		(start 251.41682 -63.706502)
		(end 251.411994 -63.715138)
		(width 0.0889)
		(layer "In11.Cu")
		(net "M_C_DQ<26>")
	)
	(segment
		(start 239.5728 -35.975544)
		(end 239.5728 -38.352476)
		(width 0.14224)
		(layer "In11.Cu")
		(net "M_C_DQ<26>")
	)
	(segment
		(start 251.405644 -58.35142)
		(end 251.411994 -58.362088)
		(width 0.0889)
		(layer "In11.Cu")
		(net "M_C_DQ<26>")
	)
	(segment
		(start 232.682034 -16.751046)
		(end 232.466134 -16.966946)
		(width 0.14224)
		(layer "In11.Cu")
		(net "M_C_DQ<26>")
	)
	(segment
		(start 251.41682 -60.734702)
		(end 251.411994 -60.743338)
		(width 0.0889)
		(layer "In11.Cu")
		(net "M_C_DQ<26>")
	)
	(segment
		(start 231.815132 -4.073144)
		(end 232.099866 -4.357878)
		(width 0.14224)
		(layer "In11.Cu")
		(net "M_C_DQ<26>")
	)
	(segment
		(start 232.669334 -7.162546)
		(end 232.466134 -7.365746)
		(width 0.14224)
		(layer "In11.Cu")
		(net "M_C_DQ<26>")
	)
	(segment
		(start 240.246408 -38.824916)
		(end 241.035078 -38.036246)
		(width 0.14224)
		(layer "In11.Cu")
		(net "M_C_DQ<26>")
	)
	(segment
		(start 232.593134 -21.336)
		(end 232.593134 -21.796756)
		(width 0.14224)
		(layer "In11.Cu")
		(net "M_C_DQ<26>")
	)
	(segment
		(start 232.593134 -18.968466)
		(end 232.41 -19.1516)
		(width 0.14224)
		(layer "In11.Cu")
		(net "M_C_DQ<26>")
	)
	(segment
		(start 241.495072 -38.295072)
		(end 241.495072 -38.49624)
		(width 0.14224)
		(layer "In11.Cu")
		(net "M_C_DQ<26>")
	)
	(segment
		(start 251.41682 -55.781702)
		(end 251.411994 -55.790338)
		(width 0.0889)
		(layer "In11.Cu")
		(net "M_C_DQ<26>")
	)
	(segment
		(start 241.236246 -38.036246)
		(end 241.495072 -38.295072)
		(width 0.14224)
		(layer "In11.Cu")
		(net "M_C_DQ<26>")
	)
	(segment
		(start 251.411994 -61.733938)
		(end 251.405644 -61.744606)
		(width 0.0889)
		(layer "In11.Cu")
		(net "M_C_DQ<26>")
	)
	(segment
		(start 232.581196 -28.238196)
		(end 232.581196 -28.98394)
		(width 0.14224)
		(layer "In11.Cu")
		(net "M_C_DQ<26>")
	)
	(segment
		(start 251.411994 -59.752738)
		(end 251.405644 -59.763406)
		(width 0.0889)
		(layer "In11.Cu")
		(net "M_C_DQ<26>")
	)
	(segment
		(start 232.428796 -28.085796)
		(end 232.581196 -28.238196)
		(width 0.14224)
		(layer "In11.Cu")
		(net "M_C_DQ<26>")
	)
	(segment
		(start 232.551732 0.541782)
		(end 232.551732 0.236728)
		(width 0.14224)
		(layer "In11.Cu")
		(net "M_C_DQ<26>")
	)
	(segment
		(start 240.04524 -38.824916)
		(end 240.246408 -38.824916)
		(width 0.14224)
		(layer "In11.Cu")
		(net "M_C_DQ<26>")
	)
	(segment
		(start 251.394722 -64.735456)
		(end 251.065284 -65.49644)
		(width 0.0889)
		(layer "In11.Cu")
		(net "M_C_DQ<26>")
	)
	(segment
		(start 232.581196 -23.283418)
		(end 232.581196 -26.663396)
		(width 0.14224)
		(layer "In11.Cu")
		(net "M_C_DQ<26>")
	)
	(segment
		(start 251.41682 -64.697102)
		(end 251.394722 -64.735456)
		(width 0.0889)
		(layer "In11.Cu")
		(net "M_C_DQ<26>")
	)
	(segment
		(start 232.593134 -21.796756)
		(end 232.440734 -21.949156)
		(width 0.14224)
		(layer "In11.Cu")
		(net "M_C_DQ<26>")
	)
	(segment
		(start 232.669334 -5.08381)
		(end 232.669334 -7.162546)
		(width 0.14224)
		(layer "In11.Cu")
		(net "M_C_DQ<26>")
	)
	(segment
		(start 251.411994 -62.724538)
		(end 251.405644 -62.735206)
		(width 0.0889)
		(layer "In11.Cu")
		(net "M_C_DQ<26>")
	)
	(segment
		(start 232.099866 -4.357878)
		(end 232.099866 -4.514342)
		(width 0.14224)
		(layer "In11.Cu")
		(net "M_C_DQ<26>")
	)
	(segment
		(start 232.5116 -0.761746)
		(end 232.5116 -1.04775)
		(width 0.14224)
		(layer "In11.Cu")
		(net "M_C_DQ<26>")
	)
	(segment
		(start 240.706402 -39.486078)
		(end 249.637804 -48.41748)
		(width 0.14224)
		(layer "In11.Cu")
		(net "M_C_DQ<26>")
	)
	(segment
		(start 241.495072 -38.49624)
		(end 240.706402 -39.28491)
		(width 0.14224)
		(layer "In11.Cu")
		(net "M_C_DQ<26>")
	)
	(segment
		(start 249.637804 -49.426114)
		(end 249.848624 -49.636934)
		(width 0.0889)
		(layer "In11.Cu")
		(net "M_C_DQ<26>")
	)
	(segment
		(start 251.411994 -54.799738)
		(end 251.405644 -54.810406)
		(width 0.0889)
		(layer "In11.Cu")
		(net "M_C_DQ<26>")
	)
	(segment
		(start 232.2068 -1.35255)
		(end 232.2068 -1.7526)
		(width 0.14224)
		(layer "In11.Cu")
		(net "M_C_DQ<26>")
	)
	(segment
		(start 249.312684 -50.330354)
		(end 249.312684 -50.802794)
		(width 0.0889)
		(layer "In11.Cu")
		(net "M_C_DQ<26>")
	)
	(segment
		(start 232.466134 -18.445734)
		(end 232.593134 -18.572734)
		(width 0.14224)
		(layer "In11.Cu")
		(net "M_C_DQ<26>")
	)
	(segment
		(start 250.81611 -54.19979)
		(end 251.08027 -54.19979)
		(width 0.0889)
		(layer "In11.Cu")
		(net "M_C_DQ<26>")
	)
	(segment
		(start 249.637804 -48.41748)
		(end 249.637804 -49.426114)
		(width 0.14224)
		(layer "In11.Cu")
		(net "M_C_DQ<26>")
	)
	(segment
		(start 232.41 -21.152866)
		(end 232.593134 -21.336)
		(width 0.14224)
		(layer "In11.Cu")
		(net "M_C_DQ<26>")
	)
	(segment
		(start 232.593134 -8.971534)
		(end 232.593134 -9.443466)
		(width 0.14224)
		(layer "In11.Cu")
		(net "M_C_DQ<26>")
	)
	(segment
		(start 232.440734 -21.949156)
		(end 232.440734 -23.142956)
		(width 0.14224)
		(layer "In11.Cu")
		(net "M_C_DQ<26>")
	)
	(segment
		(start 232.449116 -9.587484)
		(end 232.449116 -11.590782)
		(width 0.14224)
		(layer "In11.Cu")
		(net "M_C_DQ<26>")
	)
	(segment
		(start 232.593134 -12.195556)
		(end 232.440734 -12.347956)
		(width 0.14224)
		(layer "In11.Cu")
		(net "M_C_DQ<26>")
	)
	(segment
		(start 232.664 -2.2098)
		(end 232.664 -2.478532)
		(width 0.14224)
		(layer "In11.Cu")
		(net "M_C_DQ<26>")
	)
	(segment
		(start 232.440734 -12.347956)
		(end 232.440734 -13.541756)
		(width 0.14224)
		(layer "In11.Cu")
		(net "M_C_DQ<26>")
	)
	(segment
		(start 232.581196 -26.663396)
		(end 232.428796 -26.815796)
		(width 0.14224)
		(layer "In11.Cu")
		(net "M_C_DQ<26>")
	)
	(segment
		(start 251.41682 -54.791102)
		(end 251.411994 -54.799738)
		(width 0.0889)
		(layer "In11.Cu")
		(net "M_C_DQ<26>")
	)
	(segment
		(start 232.551732 0.236728)
		(end 232.2068 -0.108204)
		(width 0.14224)
		(layer "In11.Cu")
		(net "M_C_DQ<26>")
	)
	(segment
		(start 232.682034 -13.783056)
		(end 232.682034 -16.751046)
		(width 0.14224)
		(layer "In11.Cu")
		(net "M_C_DQ<26>")
	)
	(segment
		(start 232.440734 -23.142956)
		(end 232.581196 -23.283418)
		(width 0.14224)
		(layer "In11.Cu")
		(net "M_C_DQ<26>")
	)
	(segment
		(start 232.440734 -13.541756)
		(end 232.682034 -13.783056)
		(width 0.14224)
		(layer "In11.Cu")
		(net "M_C_DQ<26>")
	)
	(segment
		(start 232.593134 -11.7348)
		(end 232.593134 -12.195556)
		(width 0.14224)
		(layer "In11.Cu")
		(net "M_C_DQ<26>")
	)
	(segment
		(start 232.466134 -8.844534)
		(end 232.593134 -8.971534)
		(width 0.14224)
		(layer "In11.Cu")
		(net "M_C_DQ<26>")
	)
	(segment
		(start 250.465844 -51.955954)
		(end 250.465844 -53.849524)
		(width 0.0889)
		(layer "In11.Cu")
		(net "M_C_DQ<26>")
	)
	(segment
		(start 231.815132 -3.3274)
		(end 231.815132 -4.073144)
		(width 0.14224)
		(layer "In11.Cu")
		(net "M_C_DQ<26>")
	)
	(segment
		(start 251.41682 -61.725302)
		(end 251.411994 -61.733938)
		(width 0.0889)
		(layer "In11.Cu")
		(net "M_C_DQ<26>")
	)
	(arc
		(start 251.411994 -58.761884)
		(mid 251.332863 -59.057286)
		(end 251.411994 -59.352688)
		(width 0.0889)
		(layer "In11.Cu")
		(net "M_C_DQ<26>")
	)
	(arc
		(start 251.08027 -54.19979)
		(mid 251.413188 -54.401781)
		(end 251.41682 -54.791102)
		(width 0.0889)
		(layer "In11.Cu")
		(net "M_C_DQ<26>")
	)
	(arc
		(start 251.405644 -56.791606)
		(mid 251.332846 -57.082369)
		(end 251.411994 -57.371488)
		(width 0.0889)
		(layer "In11.Cu")
		(net "M_C_DQ<26>")
	)
	(arc
		(start 251.405644 -60.754006)
		(mid 251.332846 -61.044769)
		(end 251.411994 -61.333888)
		(width 0.0889)
		(layer "In11.Cu")
		(net "M_C_DQ<26>")
	)
	(arc
		(start 251.411994 -56.380888)
		(mid 251.465464 -56.575951)
		(end 251.41682 -56.772302)
		(width 0.0889)
		(layer "In11.Cu")
		(net "M_C_DQ<26>")
	)
	(arc
		(start 251.405644 -62.735206)
		(mid 251.332846 -63.025969)
		(end 251.411994 -63.315088)
		(width 0.0889)
		(layer "In11.Cu")
		(net "M_C_DQ<26>")
	)
	(arc
		(start 251.411994 -63.315088)
		(mid 251.465464 -63.510151)
		(end 251.41682 -63.706502)
		(width 0.0889)
		(layer "In11.Cu")
		(net "M_C_DQ<26>")
	)
	(arc
		(start 251.405644 -59.763406)
		(mid 251.332846 -60.054169)
		(end 251.411994 -60.343288)
		(width 0.0889)
		(layer "In11.Cu")
		(net "M_C_DQ<26>")
	)
	(arc
		(start 251.411994 -62.324488)
		(mid 251.465464 -62.519551)
		(end 251.41682 -62.715902)
		(width 0.0889)
		(layer "In11.Cu")
		(net "M_C_DQ<26>")
	)
	(arc
		(start 251.411994 -57.371488)
		(mid 251.465464 -57.566551)
		(end 251.41682 -57.762902)
		(width 0.0889)
		(layer "In11.Cu")
		(net "M_C_DQ<26>")
	)
	(arc
		(start 251.411994 -61.333888)
		(mid 251.465464 -61.528951)
		(end 251.41682 -61.725302)
		(width 0.0889)
		(layer "In11.Cu")
		(net "M_C_DQ<26>")
	)
	(arc
		(start 251.405644 -63.725806)
		(mid 251.332846 -64.016569)
		(end 251.411994 -64.305688)
		(width 0.0889)
		(layer "In11.Cu")
		(net "M_C_DQ<26>")
	)
	(arc
		(start 251.411994 -59.352688)
		(mid 251.465464 -59.547751)
		(end 251.41682 -59.744102)
		(width 0.0889)
		(layer "In11.Cu")
		(net "M_C_DQ<26>")
	)
	(arc
		(start 251.411994 -57.771538)
		(mid 251.332772 -58.060656)
		(end 251.405644 -58.35142)
		(width 0.0889)
		(layer "In11.Cu")
		(net "M_C_DQ<26>")
	)
	(arc
		(start 251.405644 -55.801006)
		(mid 251.332846 -56.091769)
		(end 251.411994 -56.380888)
		(width 0.0889)
		(layer "In11.Cu")
		(net "M_C_DQ<26>")
	)
	(arc
		(start 251.405644 -54.810406)
		(mid 251.332846 -55.101169)
		(end 251.411994 -55.390288)
		(width 0.0889)
		(layer "In11.Cu")
		(net "M_C_DQ<26>")
	)
	(arc
		(start 251.411994 -55.390288)
		(mid 251.465464 -55.585351)
		(end 251.41682 -55.781702)
		(width 0.0889)
		(layer "In11.Cu")
		(net "M_C_DQ<26>")
	)
	(arc
		(start 251.405644 -61.744606)
		(mid 251.332846 -62.035369)
		(end 251.411994 -62.324488)
		(width 0.0889)
		(layer "In11.Cu")
		(net "M_C_DQ<26>")
	)
	(arc
		(start 251.411994 -58.362088)
		(mid 251.465493 -58.561986)
		(end 251.411994 -58.761884)
		(width 0.0889)
		(layer "In11.Cu")
		(net "M_C_DQ<26>")
	)
	(arc
		(start 251.411994 -60.343288)
		(mid 251.465464 -60.538351)
		(end 251.41682 -60.734702)
		(width 0.0889)
		(layer "In11.Cu")
		(net "M_C_DQ<26>")
	)
	(arc
		(start 251.411994 -64.305688)
		(mid 251.465464 -64.500751)
		(end 251.41682 -64.697102)
		(width 0.0889)
		(layer "In11.Cu")
		(net "M_C_DQ<26>")
	)
	(segment
		(start 249.061224 -66.982086)
		(end 248.489724 -66.982086)
		(width 0.1016)
		(layer "F.Cu")
		(net "M_C_DQ<25>")
	)
	(segment
		(start 226.149916 3.778758)
		(end 226.149916 2.514854)
		(width 0.1651)
		(layer "F.Cu")
		(net "M_C_DQ<25>")
	)
	(segment
		(start 226.150424 3.778758)
		(end 226.149916 3.778758)
		(width 0.1651)
		(layer "F.Cu")
		(net "M_C_DQ<25>")
	)
	(via
		(at 248.489724 -66.982086)
		(size 0.508)
		(drill 0.254)
		(layers "F.Cu" "B.Cu")
		(net "M_C_DQ<25>")
	)
	(via
		(at 226.822 -3.076956)
		(size 0.508)
		(drill 0.254)
		(layers "F.Cu" "B.Cu")
		(net "M_C_DQ<25>")
	)
	(via
		(at 226.149916 2.514854)
		(size 0.508)
		(drill 0.254)
		(layers "F.Cu" "B.Cu")
		(net "M_C_DQ<25>")
	)
	(segment
		(start 226.822 -2.573782)
		(end 226.822 -3.076956)
		(width 0.1651)
		(layer "B.Cu")
		(net "M_C_DQ<25>")
	)
	(segment
		(start 226.9998 -1.021842)
		(end 226.9998 -2.395982)
		(width 0.1651)
		(layer "B.Cu")
		(net "M_C_DQ<25>")
	)
	(segment
		(start 226.9998 -2.395982)
		(end 226.822 -2.573782)
		(width 0.1651)
		(layer "B.Cu")
		(net "M_C_DQ<25>")
	)
	(segment
		(start 227.000308 -1.021842)
		(end 226.9998 -1.021842)
		(width 0.1651)
		(layer "B.Cu")
		(net "M_C_DQ<25>")
	)
	(segment
		(start 227.309934 -29.158184)
		(end 228.8032 -30.65145)
		(width 0.14224)
		(layer "In11.Cu")
		(net "M_C_DQ<25>")
	)
	(segment
		(start 245.295928 -51.576986)
		(end 247.158764 -53.439822)
		(width 0.0889)
		(layer "In11.Cu")
		(net "M_C_DQ<25>")
	)
	(segment
		(start 233.299508 -37.516308)
		(end 243.967 -48.1838)
		(width 0.14224)
		(layer "In11.Cu")
		(net "M_C_DQ<25>")
	)
	(segment
		(start 248.143014 -58.266838)
		(end 248.149364 -58.277506)
		(width 0.0889)
		(layer "In11.Cu")
		(net "M_C_DQ<25>")
	)
	(segment
		(start 227.457 -19.1516)
		(end 227.457 -21.183854)
		(width 0.14224)
		(layer "In11.Cu")
		(net "M_C_DQ<25>")
	)
	(segment
		(start 248.149364 -60.82792)
		(end 248.143014 -60.838588)
		(width 0.0889)
		(layer "In11.Cu")
		(net "M_C_DQ<25>")
	)
	(segment
		(start 226.982782 1.4986)
		(end 227.352606 1.128776)
		(width 0.14224)
		(layer "In11.Cu")
		(net "M_C_DQ<25>")
	)
	(segment
		(start 247.158764 -53.439822)
		(end 247.158764 -53.851302)
		(width 0.0889)
		(layer "In11.Cu")
		(net "M_C_DQ<25>")
	)
	(segment
		(start 228.8032 -30.65145)
		(end 228.8032 -32.424116)
		(width 0.14224)
		(layer "In11.Cu")
		(net "M_C_DQ<25>")
	)
	(segment
		(start 226.295458 -3.867912)
		(end 226.674934 -4.247388)
		(width 0.14224)
		(layer "In11.Cu")
		(net "M_C_DQ<25>")
	)
	(segment
		(start 227.457 -11.562334)
		(end 227.309934 -11.7094)
		(width 0.14224)
		(layer "In11.Cu")
		(net "M_C_DQ<25>")
	)
	(segment
		(start 248.143014 -62.819788)
		(end 248.138188 -62.828424)
		(width 0.0889)
		(layer "In11.Cu")
		(net "M_C_DQ<25>")
	)
	(segment
		(start 248.149364 -56.86552)
		(end 248.143014 -56.876188)
		(width 0.0889)
		(layer "In11.Cu")
		(net "M_C_DQ<25>")
	)
	(segment
		(start 227.352606 0.7874)
		(end 227.196142 0.630936)
		(width 0.14224)
		(layer "In11.Cu")
		(net "M_C_DQ<25>")
	)
	(segment
		(start 243.967 -48.1838)
		(end 243.967 -49.919382)
		(width 0.14224)
		(layer "In11.Cu")
		(net "M_C_DQ<25>")
	)
	(segment
		(start 248.149364 -61.81852)
		(end 248.143014 -61.829188)
		(width 0.0889)
		(layer "In11.Cu")
		(net "M_C_DQ<25>")
	)
	(segment
		(start 226.149916 1.975866)
		(end 226.627182 1.4986)
		(width 0.14224)
		(layer "In11.Cu")
		(net "M_C_DQ<25>")
	)
	(segment
		(start 227.309934 -9.454134)
		(end 227.457 -9.6012)
		(width 0.14224)
		(layer "In11.Cu")
		(net "M_C_DQ<25>")
	)
	(segment
		(start 227.309934 -6.583934)
		(end 227.309934 -9.454134)
		(width 0.14224)
		(layer "In11.Cu")
		(net "M_C_DQ<25>")
	)
	(segment
		(start 226.674934 -5.948934)
		(end 227.309934 -6.583934)
		(width 0.14224)
		(layer "In11.Cu")
		(net "M_C_DQ<25>")
	)
	(segment
		(start 248.143014 -56.876188)
		(end 248.138188 -56.884824)
		(width 0.0889)
		(layer "In11.Cu")
		(net "M_C_DQ<25>")
	)
	(segment
		(start 227.196142 -2.702814)
		(end 226.822 -3.076956)
		(width 0.14224)
		(layer "In11.Cu")
		(net "M_C_DQ<25>")
	)
	(segment
		(start 233.299508 -36.920424)
		(end 233.299508 -37.516308)
		(width 0.14224)
		(layer "In11.Cu")
		(net "M_C_DQ<25>")
	)
	(segment
		(start 226.627182 1.4986)
		(end 226.982782 1.4986)
		(width 0.14224)
		(layer "In11.Cu")
		(net "M_C_DQ<25>")
	)
	(segment
		(start 247.452896 -54.145434)
		(end 247.452896 -54.896512)
		(width 0.0889)
		(layer "In11.Cu")
		(net "M_C_DQ<25>")
	)
	(segment
		(start 226.822 -3.076956)
		(end 226.295458 -3.603498)
		(width 0.14224)
		(layer "In11.Cu")
		(net "M_C_DQ<25>")
	)
	(segment
		(start 247.158764 -53.851302)
		(end 247.452896 -54.145434)
		(width 0.0889)
		(layer "In11.Cu")
		(net "M_C_DQ<25>")
	)
	(segment
		(start 247.452896 -54.896512)
		(end 248.084594 -55.52821)
		(width 0.0889)
		(layer "In11.Cu")
		(net "M_C_DQ<25>")
	)
	(segment
		(start 227.309934 -21.33092)
		(end 227.309934 -29.158184)
		(width 0.14224)
		(layer "In11.Cu")
		(net "M_C_DQ<25>")
	)
	(segment
		(start 248.084594 -56.184546)
		(end 248.143014 -56.285638)
		(width 0.0889)
		(layer "In11.Cu")
		(net "M_C_DQ<25>")
	)
	(segment
		(start 227.309934 -11.7094)
		(end 227.309934 -19.004534)
		(width 0.14224)
		(layer "In11.Cu")
		(net "M_C_DQ<25>")
	)
	(segment
		(start 243.967 -49.919382)
		(end 245.295928 -51.24831)
		(width 0.14224)
		(layer "In11.Cu")
		(net "M_C_DQ<25>")
	)
	(segment
		(start 226.674934 -4.247388)
		(end 226.674934 -5.948934)
		(width 0.14224)
		(layer "In11.Cu")
		(net "M_C_DQ<25>")
	)
	(segment
		(start 248.143014 -58.857388)
		(end 248.138188 -58.866024)
		(width 0.0889)
		(layer "In11.Cu")
		(net "M_C_DQ<25>")
	)
	(segment
		(start 227.457 -9.6012)
		(end 227.457 -11.562334)
		(width 0.14224)
		(layer "In11.Cu")
		(net "M_C_DQ<25>")
	)
	(segment
		(start 227.457 -21.183854)
		(end 227.309934 -21.33092)
		(width 0.14224)
		(layer "In11.Cu")
		(net "M_C_DQ<25>")
	)
	(segment
		(start 228.8032 -32.424116)
		(end 233.299508 -36.920424)
		(width 0.14224)
		(layer "In11.Cu")
		(net "M_C_DQ<25>")
	)
	(segment
		(start 245.295928 -51.24831)
		(end 245.295928 -51.576986)
		(width 0.0889)
		(layer "In11.Cu")
		(net "M_C_DQ<25>")
	)
	(segment
		(start 248.084594 -55.52821)
		(end 248.084594 -56.184546)
		(width 0.0889)
		(layer "In11.Cu")
		(net "M_C_DQ<25>")
	)
	(segment
		(start 227.309934 -19.004534)
		(end 227.457 -19.1516)
		(width 0.14224)
		(layer "In11.Cu")
		(net "M_C_DQ<25>")
	)
	(segment
		(start 248.486422 -66.980816)
		(end 248.489724 -66.982086)
		(width 0.0889)
		(layer "In11.Cu")
		(net "M_C_DQ<25>")
	)
	(segment
		(start 226.149916 2.514854)
		(end 226.149916 1.975866)
		(width 0.14224)
		(layer "In11.Cu")
		(net "M_C_DQ<25>")
	)
	(segment
		(start 248.148856 -66.203322)
		(end 248.486422 -66.980816)
		(width 0.0889)
		(layer "In11.Cu")
		(net "M_C_DQ<25>")
	)
	(segment
		(start 248.143014 -59.847988)
		(end 248.138188 -59.856624)
		(width 0.0889)
		(layer "In11.Cu")
		(net "M_C_DQ<25>")
	)
	(segment
		(start 248.143014 -61.829188)
		(end 248.138188 -61.837824)
		(width 0.0889)
		(layer "In11.Cu")
		(net "M_C_DQ<25>")
	)
	(segment
		(start 227.196142 0.630936)
		(end 227.196142 -2.702814)
		(width 0.14224)
		(layer "In11.Cu")
		(net "M_C_DQ<25>")
	)
	(segment
		(start 248.143014 -60.838588)
		(end 248.138188 -60.847224)
		(width 0.0889)
		(layer "In11.Cu")
		(net "M_C_DQ<25>")
	)
	(segment
		(start 227.352606 1.128776)
		(end 227.352606 0.7874)
		(width 0.14224)
		(layer "In11.Cu")
		(net "M_C_DQ<25>")
	)
	(segment
		(start 248.149364 -59.83732)
		(end 248.143014 -59.847988)
		(width 0.0889)
		(layer "In11.Cu")
		(net "M_C_DQ<25>")
	)
	(segment
		(start 248.149364 -62.80912)
		(end 248.143014 -62.819788)
		(width 0.0889)
		(layer "In11.Cu")
		(net "M_C_DQ<25>")
	)
	(segment
		(start 226.295458 -3.603498)
		(end 226.295458 -3.867912)
		(width 0.14224)
		(layer "In11.Cu")
		(net "M_C_DQ<25>")
	)
	(arc
		(start 248.143014 -57.276238)
		(mid 248.222145 -57.57164)
		(end 248.143014 -57.867042)
		(width 0.0889)
		(layer "In11.Cu")
		(net "M_C_DQ<25>")
	)
	(arc
		(start 248.143014 -56.285638)
		(mid 248.222236 -56.574756)
		(end 248.149364 -56.86552)
		(width 0.0889)
		(layer "In11.Cu")
		(net "M_C_DQ<25>")
	)
	(arc
		(start 248.138188 -58.866024)
		(mid 248.089433 -59.062376)
		(end 248.143014 -59.257438)
		(width 0.0889)
		(layer "In11.Cu")
		(net "M_C_DQ<25>")
	)
	(arc
		(start 248.149364 -58.277506)
		(mid 248.222162 -58.568269)
		(end 248.143014 -58.857388)
		(width 0.0889)
		(layer "In11.Cu")
		(net "M_C_DQ<25>")
	)
	(arc
		(start 248.143014 -64.210438)
		(mid 248.352975 -64.462225)
		(end 248.63552 -64.628522)
		(width 0.0889)
		(layer "In11.Cu")
		(net "M_C_DQ<25>")
	)
	(arc
		(start 248.143014 -63.810642)
		(mid 248.089515 -64.01054)
		(end 248.143014 -64.210438)
		(width 0.0889)
		(layer "In11.Cu")
		(net "M_C_DQ<25>")
	)
	(arc
		(start 248.143014 -61.238638)
		(mid 248.222236 -61.527756)
		(end 248.149364 -61.81852)
		(width 0.0889)
		(layer "In11.Cu")
		(net "M_C_DQ<25>")
	)
	(arc
		(start 248.336308 -65.62217)
		(mid 248.1108 -65.86315)
		(end 248.143014 -66.191638)
		(width 0.0889)
		(layer "In11.Cu")
		(net "M_C_DQ<25>")
	)
	(arc
		(start 248.143014 -63.219838)
		(mid 248.222077 -63.51524)
		(end 248.143014 -63.810642)
		(width 0.0889)
		(layer "In11.Cu")
		(net "M_C_DQ<25>")
	)
	(arc
		(start 248.138188 -56.884824)
		(mid 248.089433 -57.081176)
		(end 248.143014 -57.276238)
		(width 0.0889)
		(layer "In11.Cu")
		(net "M_C_DQ<25>")
	)
	(arc
		(start 248.143014 -59.257438)
		(mid 248.222236 -59.546556)
		(end 248.149364 -59.83732)
		(width 0.0889)
		(layer "In11.Cu")
		(net "M_C_DQ<25>")
	)
	(arc
		(start 248.143014 -57.867042)
		(mid 248.089515 -58.06694)
		(end 248.143014 -58.266838)
		(width 0.0889)
		(layer "In11.Cu")
		(net "M_C_DQ<25>")
	)
	(arc
		(start 248.138188 -59.856624)
		(mid 248.089433 -60.052976)
		(end 248.143014 -60.248038)
		(width 0.0889)
		(layer "In11.Cu")
		(net "M_C_DQ<25>")
	)
	(arc
		(start 248.143014 -60.248038)
		(mid 248.222236 -60.537156)
		(end 248.149364 -60.82792)
		(width 0.0889)
		(layer "In11.Cu")
		(net "M_C_DQ<25>")
	)
	(arc
		(start 248.143014 -66.191638)
		(mid 248.146097 -66.197399)
		(end 248.148856 -66.203322)
		(width 0.0889)
		(layer "In11.Cu")
		(net "M_C_DQ<25>")
	)
	(arc
		(start 248.138188 -61.837824)
		(mid 248.089433 -62.034176)
		(end 248.143014 -62.229238)
		(width 0.0889)
		(layer "In11.Cu")
		(net "M_C_DQ<25>")
	)
	(arc
		(start 248.143014 -62.229238)
		(mid 248.222236 -62.518356)
		(end 248.149364 -62.80912)
		(width 0.0889)
		(layer "In11.Cu")
		(net "M_C_DQ<25>")
	)
	(arc
		(start 248.63552 -64.628522)
		(mid 248.875171 -64.893755)
		(end 248.807224 -65.244726)
		(width 0.0889)
		(layer "In11.Cu")
		(net "M_C_DQ<25>")
	)
	(arc
		(start 248.138188 -62.828424)
		(mid 248.089433 -63.024776)
		(end 248.143014 -63.219838)
		(width 0.0889)
		(layer "In11.Cu")
		(net "M_C_DQ<25>")
	)
	(arc
		(start 248.138188 -60.847224)
		(mid 248.089433 -61.043576)
		(end 248.143014 -61.238638)
		(width 0.0889)
		(layer "In11.Cu")
		(net "M_C_DQ<25>")
	)
	(arc
		(start 248.807224 -65.244726)
		(mid 248.598589 -65.46692)
		(end 248.336308 -65.62217)
		(width 0.0889)
		(layer "In11.Cu")
		(net "M_C_DQ<25>")
	)
	(segment
		(start 226.9998 -0.821182)
		(end 226.822 1.0414)
		(width 0.1651)
		(layer "F.Cu")
		(net "M_C_DQ<24>")
	)
	(segment
		(start 249.061224 -65.000886)
		(end 248.489724 -65.000886)
		(width 0.0889)
		(layer "F.Cu")
		(net "M_C_DQ<24>")
	)
	(segment
		(start 227.000308 -0.821182)
		(end 226.9998 -0.821182)
		(width 0.1651)
		(layer "F.Cu")
		(net "M_C_DQ<24>")
	)
	(via
		(at 226.149916 -4.357878)
		(size 0.508)
		(drill 0.254)
		(layers "F.Cu" "B.Cu")
		(net "M_C_DQ<24>")
	)
	(via
		(at 248.489724 -65.000886)
		(size 0.508)
		(drill 0.254)
		(layers "F.Cu" "B.Cu")
		(net "M_C_DQ<24>")
	)
	(via
		(at 226.822 1.0414)
		(size 0.508)
		(drill 0.254)
		(layers "F.Cu" "B.Cu")
		(net "M_C_DQ<24>")
	)
	(segment
		(start 226.149916 -5.621782)
		(end 226.149916 -4.357878)
		(width 0.1651)
		(layer "B.Cu")
		(net "M_C_DQ<24>")
	)
	(segment
		(start 226.150424 -5.621782)
		(end 226.149916 -5.621782)
		(width 0.1651)
		(layer "B.Cu")
		(net "M_C_DQ<24>")
	)
	(segment
		(start 247.894094 -55.607204)
		(end 247.894094 -56.235346)
		(width 0.0889)
		(layer "In11.Cu")
		(net "M_C_DQ<24>")
	)
	(segment
		(start 247.98274 -61.725302)
		(end 247.977914 -61.733938)
		(width 0.0889)
		(layer "In11.Cu")
		(net "M_C_DQ<24>")
	)
	(segment
		(start 226.601782 0.821182)
		(end 226.822 1.0414)
		(width 0.14224)
		(layer "In11.Cu")
		(net "M_C_DQ<24>")
	)
	(segment
		(start 226.624134 -7.224776)
		(end 226.3648 -7.48411)
		(width 0.14224)
		(layer "In11.Cu")
		(net "M_C_DQ<24>")
	)
	(segment
		(start 226.601782 0.236728)
		(end 226.601782 0.821182)
		(width 0.14224)
		(layer "In11.Cu")
		(net "M_C_DQ<24>")
	)
	(segment
		(start 247.98274 -57.762902)
		(end 247.977914 -57.771538)
		(width 0.0889)
		(layer "In11.Cu")
		(net "M_C_DQ<24>")
	)
	(segment
		(start 226.674934 -18.943066)
		(end 226.5426 -19.0754)
		(width 0.14224)
		(layer "In11.Cu")
		(net "M_C_DQ<24>")
	)
	(segment
		(start 232.687876 -37.144452)
		(end 232.687876 -37.80282)
		(width 0.14224)
		(layer "In11.Cu")
		(net "M_C_DQ<24>")
	)
	(segment
		(start 226.6188 -8.9916)
		(end 226.6188 -9.4488)
		(width 0.14224)
		(layer "In11.Cu")
		(net "M_C_DQ<24>")
	)
	(segment
		(start 226.3394 -18.291048)
		(end 226.674934 -18.626582)
		(width 0.14224)
		(layer "In11.Cu")
		(net "M_C_DQ<24>")
	)
	(segment
		(start 226.624134 -6.837934)
		(end 226.624134 -7.224776)
		(width 0.14224)
		(layer "In11.Cu")
		(net "M_C_DQ<24>")
	)
	(segment
		(start 243.2304 -48.345344)
		(end 243.2304 -50.165762)
		(width 0.14224)
		(layer "In11.Cu")
		(net "M_C_DQ<24>")
	)
	(segment
		(start 247.977914 -56.780938)
		(end 247.971564 -56.791606)
		(width 0.0889)
		(layer "In11.Cu")
		(net "M_C_DQ<24>")
	)
	(segment
		(start 227.14204 -30.175708)
		(end 226.65309 -30.664658)
		(width 0.14224)
		(layer "In11.Cu")
		(net "M_C_DQ<24>")
	)
	(segment
		(start 247.262396 -54.224682)
		(end 247.262396 -54.975506)
		(width 0.0889)
		(layer "In11.Cu")
		(net "M_C_DQ<24>")
	)
	(segment
		(start 247.98274 -56.772302)
		(end 247.977914 -56.780938)
		(width 0.0889)
		(layer "In11.Cu")
		(net "M_C_DQ<24>")
	)
	(segment
		(start 226.612196 -29.35859)
		(end 227.14204 -29.888434)
		(width 0.14224)
		(layer "In11.Cu")
		(net "M_C_DQ<24>")
	)
	(segment
		(start 228.003862 -30.750256)
		(end 228.317806 -31.0642)
		(width 0.14224)
		(layer "In11.Cu")
		(net "M_C_DQ<24>")
	)
	(segment
		(start 226.332796 -26.968196)
		(end 226.332796 -28.034996)
		(width 0.14224)
		(layer "In11.Cu")
		(net "M_C_DQ<24>")
	)
	(segment
		(start 247.262396 -54.975506)
		(end 247.894094 -55.607204)
		(width 0.0889)
		(layer "In11.Cu")
		(net "M_C_DQ<24>")
	)
	(segment
		(start 232.687876 -37.80282)
		(end 243.2304 -48.345344)
		(width 0.14224)
		(layer "In11.Cu")
		(net "M_C_DQ<24>")
	)
	(segment
		(start 228.317806 -31.351982)
		(end 227.696522 -31.973266)
		(width 0.14224)
		(layer "In11.Cu")
		(net "M_C_DQ<24>")
	)
	(segment
		(start 227.227892 -31.23946)
		(end 227.717096 -30.750256)
		(width 0.14224)
		(layer "In11.Cu")
		(net "M_C_DQ<24>")
	)
	(segment
		(start 226.5426 -21.229066)
		(end 226.674934 -21.3614)
		(width 0.14224)
		(layer "In11.Cu")
		(net "M_C_DQ<24>")
	)
	(segment
		(start 226.332034 -23.106888)
		(end 226.674934 -23.449788)
		(width 0.14224)
		(layer "In11.Cu")
		(net "M_C_DQ<24>")
	)
	(segment
		(start 243.2304 -50.165762)
		(end 244.728238 -51.6636)
		(width 0.14224)
		(layer "In11.Cu")
		(net "M_C_DQ<24>")
	)
	(segment
		(start 226.65309 -30.84449)
		(end 227.04806 -31.23946)
		(width 0.14224)
		(layer "In11.Cu")
		(net "M_C_DQ<24>")
	)
	(segment
		(start 248.44756 -64.956182)
		(end 248.489724 -65.000886)
		(width 0.0889)
		(layer "In11.Cu")
		(net "M_C_DQ<24>")
	)
	(segment
		(start 226.65309 -30.664658)
		(end 226.65309 -30.84449)
		(width 0.14224)
		(layer "In11.Cu")
		(net "M_C_DQ<24>")
	)
	(segment
		(start 227.717096 -30.750256)
		(end 228.003862 -30.750256)
		(width 0.14224)
		(layer "In11.Cu")
		(net "M_C_DQ<24>")
	)
	(segment
		(start 226.6188 -11.7602)
		(end 226.6188 -12.13739)
		(width 0.14224)
		(layer "In11.Cu")
		(net "M_C_DQ<24>")
	)
	(segment
		(start 226.5299 -1.0795)
		(end 226.5299 -0.8509)
		(width 0.14224)
		(layer "In11.Cu")
		(net "M_C_DQ<24>")
	)
	(segment
		(start 226.3648 -8.7376)
		(end 226.6188 -8.9916)
		(width 0.14224)
		(layer "In11.Cu")
		(net "M_C_DQ<24>")
	)
	(segment
		(start 226.149916 -6.363716)
		(end 226.624134 -6.837934)
		(width 0.14224)
		(layer "In11.Cu")
		(net "M_C_DQ<24>")
	)
	(segment
		(start 247.977914 -59.752738)
		(end 247.971564 -59.763406)
		(width 0.0889)
		(layer "In11.Cu")
		(net "M_C_DQ<24>")
	)
	(segment
		(start 245.11381 -51.6636)
		(end 246.968264 -53.518054)
		(width 0.0889)
		(layer "In11.Cu")
		(net "M_C_DQ<24>")
	)
	(segment
		(start 247.98274 -59.744102)
		(end 247.977914 -59.752738)
		(width 0.0889)
		(layer "In11.Cu")
		(net "M_C_DQ<24>")
	)
	(segment
		(start 247.977914 -60.743338)
		(end 247.971564 -60.754006)
		(width 0.0889)
		(layer "In11.Cu")
		(net "M_C_DQ<24>")
	)
	(segment
		(start 247.977914 -64.305942)
		(end 247.981978 -64.313054)
		(width 0.0889)
		(layer "In11.Cu")
		(net "M_C_DQ<24>")
	)
	(segment
		(start 244.728238 -51.6636)
		(end 245.11381 -51.6636)
		(width 0.0889)
		(layer "In11.Cu")
		(net "M_C_DQ<24>")
	)
	(segment
		(start 226.332796 -28.034996)
		(end 226.612196 -28.314396)
		(width 0.14224)
		(layer "In11.Cu")
		(net "M_C_DQ<24>")
	)
	(segment
		(start 226.332034 -12.424156)
		(end 226.332034 -13.505688)
		(width 0.14224)
		(layer "In11.Cu")
		(net "M_C_DQ<24>")
	)
	(segment
		(start 226.2124 -1.701546)
		(end 226.2124 -1.397)
		(width 0.14224)
		(layer "In11.Cu")
		(net "M_C_DQ<24>")
	)
	(segment
		(start 226.149916 -4.357878)
		(end 226.149916 -6.363716)
		(width 0.14224)
		(layer "In11.Cu")
		(net "M_C_DQ<24>")
	)
	(segment
		(start 226.3394 -17.116552)
		(end 226.3394 -18.291048)
		(width 0.14224)
		(layer "In11.Cu")
		(net "M_C_DQ<24>")
	)
	(segment
		(start 247.894094 -56.235346)
		(end 247.977914 -56.380888)
		(width 0.0889)
		(layer "In11.Cu")
		(net "M_C_DQ<24>")
	)
	(segment
		(start 226.187 -0.508)
		(end 226.187 -0.178054)
		(width 0.14224)
		(layer "In11.Cu")
		(net "M_C_DQ<24>")
	)
	(segment
		(start 226.612196 -28.314396)
		(end 226.612196 -29.35859)
		(width 0.14224)
		(layer "In11.Cu")
		(net "M_C_DQ<24>")
	)
	(segment
		(start 246.968264 -53.93055)
		(end 247.262396 -54.224682)
		(width 0.0889)
		(layer "In11.Cu")
		(net "M_C_DQ<24>")
	)
	(segment
		(start 226.6442 -13.817854)
		(end 226.6442 -16.811752)
		(width 0.14224)
		(layer "In11.Cu")
		(net "M_C_DQ<24>")
	)
	(segment
		(start 226.601782 -2.090928)
		(end 226.2124 -1.701546)
		(width 0.14224)
		(layer "In11.Cu")
		(net "M_C_DQ<24>")
	)
	(segment
		(start 247.977914 -62.724538)
		(end 247.971564 -62.735206)
		(width 0.0889)
		(layer "In11.Cu")
		(net "M_C_DQ<24>")
	)
	(segment
		(start 247.98274 -60.734702)
		(end 247.977914 -60.743338)
		(width 0.0889)
		(layer "In11.Cu")
		(net "M_C_DQ<24>")
	)
	(segment
		(start 226.332034 -13.505688)
		(end 226.6442 -13.817854)
		(width 0.14224)
		(layer "In11.Cu")
		(net "M_C_DQ<24>")
	)
	(segment
		(start 226.332034 -22.025356)
		(end 226.332034 -23.106888)
		(width 0.14224)
		(layer "In11.Cu")
		(net "M_C_DQ<24>")
	)
	(segment
		(start 228.317806 -31.0642)
		(end 228.317806 -31.351982)
		(width 0.14224)
		(layer "In11.Cu")
		(net "M_C_DQ<24>")
	)
	(segment
		(start 227.14204 -29.888434)
		(end 227.14204 -30.175708)
		(width 0.14224)
		(layer "In11.Cu")
		(net "M_C_DQ<24>")
	)
	(segment
		(start 247.977914 -61.733938)
		(end 247.971564 -61.744606)
		(width 0.0889)
		(layer "In11.Cu")
		(net "M_C_DQ<24>")
	)
	(segment
		(start 226.5172 -9.5504)
		(end 226.5172 -11.6586)
		(width 0.14224)
		(layer "In11.Cu")
		(net "M_C_DQ<24>")
	)
	(segment
		(start 226.674934 -21.3614)
		(end 226.674934 -21.682456)
		(width 0.14224)
		(layer "In11.Cu")
		(net "M_C_DQ<24>")
	)
	(segment
		(start 226.149916 -4.357878)
		(end 225.865182 -4.073144)
		(width 0.14224)
		(layer "In11.Cu")
		(net "M_C_DQ<24>")
	)
	(segment
		(start 246.968264 -53.518054)
		(end 246.968264 -53.93055)
		(width 0.0889)
		(layer "In11.Cu")
		(net "M_C_DQ<24>")
	)
	(segment
		(start 226.5426 -19.0754)
		(end 226.5426 -21.229066)
		(width 0.14224)
		(layer "In11.Cu")
		(net "M_C_DQ<24>")
	)
	(segment
		(start 226.6442 -16.811752)
		(end 226.3394 -17.116552)
		(width 0.14224)
		(layer "In11.Cu")
		(net "M_C_DQ<24>")
	)
	(segment
		(start 226.6188 -12.13739)
		(end 226.332034 -12.424156)
		(width 0.14224)
		(layer "In11.Cu")
		(net "M_C_DQ<24>")
	)
	(segment
		(start 226.601782 -2.5908)
		(end 226.601782 -2.090928)
		(width 0.14224)
		(layer "In11.Cu")
		(net "M_C_DQ<24>")
	)
	(segment
		(start 227.04806 -31.23946)
		(end 227.227892 -31.23946)
		(width 0.14224)
		(layer "In11.Cu")
		(net "M_C_DQ<24>")
	)
	(segment
		(start 226.674934 -23.449788)
		(end 226.674934 -26.626058)
		(width 0.14224)
		(layer "In11.Cu")
		(net "M_C_DQ<24>")
	)
	(segment
		(start 226.5172 -11.6586)
		(end 226.6188 -11.7602)
		(width 0.14224)
		(layer "In11.Cu")
		(net "M_C_DQ<24>")
	)
	(segment
		(start 226.2124 -1.397)
		(end 226.5299 -1.0795)
		(width 0.14224)
		(layer "In11.Cu")
		(net "M_C_DQ<24>")
	)
	(segment
		(start 225.865182 -3.3274)
		(end 226.601782 -2.5908)
		(width 0.14224)
		(layer "In11.Cu")
		(net "M_C_DQ<24>")
	)
	(segment
		(start 226.674934 -21.682456)
		(end 226.332034 -22.025356)
		(width 0.14224)
		(layer "In11.Cu")
		(net "M_C_DQ<24>")
	)
	(segment
		(start 226.3648 -7.48411)
		(end 226.3648 -8.7376)
		(width 0.14224)
		(layer "In11.Cu")
		(net "M_C_DQ<24>")
	)
	(segment
		(start 226.674934 -18.626582)
		(end 226.674934 -18.943066)
		(width 0.14224)
		(layer "In11.Cu")
		(net "M_C_DQ<24>")
	)
	(segment
		(start 227.696522 -31.973266)
		(end 227.696522 -32.153098)
		(width 0.14224)
		(layer "In11.Cu")
		(net "M_C_DQ<24>")
	)
	(segment
		(start 226.187 -0.178054)
		(end 226.601782 0.236728)
		(width 0.14224)
		(layer "In11.Cu")
		(net "M_C_DQ<24>")
	)
	(segment
		(start 247.971564 -58.35142)
		(end 247.977914 -58.362088)
		(width 0.0889)
		(layer "In11.Cu")
		(net "M_C_DQ<24>")
	)
	(segment
		(start 226.6188 -9.4488)
		(end 226.5172 -9.5504)
		(width 0.14224)
		(layer "In11.Cu")
		(net "M_C_DQ<24>")
	)
	(segment
		(start 226.5299 -0.8509)
		(end 226.187 -0.508)
		(width 0.14224)
		(layer "In11.Cu")
		(net "M_C_DQ<24>")
	)
	(segment
		(start 226.674934 -26.626058)
		(end 226.332796 -26.968196)
		(width 0.14224)
		(layer "In11.Cu")
		(net "M_C_DQ<24>")
	)
	(segment
		(start 225.865182 -4.073144)
		(end 225.865182 -3.3274)
		(width 0.14224)
		(layer "In11.Cu")
		(net "M_C_DQ<24>")
	)
	(segment
		(start 227.696522 -32.153098)
		(end 232.687876 -37.144452)
		(width 0.14224)
		(layer "In11.Cu")
		(net "M_C_DQ<24>")
	)
	(segment
		(start 247.98274 -62.715902)
		(end 247.977914 -62.724538)
		(width 0.0889)
		(layer "In11.Cu")
		(net "M_C_DQ<24>")
	)
	(arc
		(start 247.971564 -62.735206)
		(mid 247.898766 -63.025969)
		(end 247.977914 -63.315088)
		(width 0.0889)
		(layer "In11.Cu")
		(net "M_C_DQ<24>")
	)
	(arc
		(start 247.981978 -64.313054)
		(mid 248.198199 -64.646613)
		(end 248.44756 -64.956182)
		(width 0.0889)
		(layer "In11.Cu")
		(net "M_C_DQ<24>")
	)
	(arc
		(start 247.971564 -56.791606)
		(mid 247.898766 -57.082369)
		(end 247.977914 -57.371488)
		(width 0.0889)
		(layer "In11.Cu")
		(net "M_C_DQ<24>")
	)
	(arc
		(start 247.971564 -59.763406)
		(mid 247.898766 -60.054169)
		(end 247.977914 -60.343288)
		(width 0.0889)
		(layer "In11.Cu")
		(net "M_C_DQ<24>")
	)
	(arc
		(start 247.977914 -63.315088)
		(mid 248.031574 -63.51513)
		(end 247.977914 -63.715138)
		(width 0.0889)
		(layer "In11.Cu")
		(net "M_C_DQ<24>")
	)
	(arc
		(start 247.971564 -60.754006)
		(mid 247.898766 -61.044769)
		(end 247.977914 -61.333888)
		(width 0.0889)
		(layer "In11.Cu")
		(net "M_C_DQ<24>")
	)
	(arc
		(start 247.977914 -57.771538)
		(mid 247.898692 -58.060656)
		(end 247.971564 -58.35142)
		(width 0.0889)
		(layer "In11.Cu")
		(net "M_C_DQ<24>")
	)
	(arc
		(start 247.977914 -58.761884)
		(mid 247.898783 -59.057286)
		(end 247.977914 -59.352688)
		(width 0.0889)
		(layer "In11.Cu")
		(net "M_C_DQ<24>")
	)
	(arc
		(start 247.977914 -63.715138)
		(mid 247.898783 -64.01054)
		(end 247.977914 -64.305942)
		(width 0.0889)
		(layer "In11.Cu")
		(net "M_C_DQ<24>")
	)
	(arc
		(start 247.977914 -57.371488)
		(mid 248.031384 -57.566551)
		(end 247.98274 -57.762902)
		(width 0.0889)
		(layer "In11.Cu")
		(net "M_C_DQ<24>")
	)
	(arc
		(start 247.977914 -60.343288)
		(mid 248.031384 -60.538351)
		(end 247.98274 -60.734702)
		(width 0.0889)
		(layer "In11.Cu")
		(net "M_C_DQ<24>")
	)
	(arc
		(start 247.977914 -59.352688)
		(mid 248.031384 -59.547751)
		(end 247.98274 -59.744102)
		(width 0.0889)
		(layer "In11.Cu")
		(net "M_C_DQ<24>")
	)
	(arc
		(start 247.977914 -58.362088)
		(mid 248.031413 -58.561986)
		(end 247.977914 -58.761884)
		(width 0.0889)
		(layer "In11.Cu")
		(net "M_C_DQ<24>")
	)
	(arc
		(start 247.977914 -62.324488)
		(mid 248.031384 -62.519551)
		(end 247.98274 -62.715902)
		(width 0.0889)
		(layer "In11.Cu")
		(net "M_C_DQ<24>")
	)
	(arc
		(start 247.971564 -61.744606)
		(mid 247.898766 -62.035369)
		(end 247.977914 -62.324488)
		(width 0.0889)
		(layer "In11.Cu")
		(net "M_C_DQ<24>")
	)
	(arc
		(start 247.977914 -61.333888)
		(mid 248.031384 -61.528951)
		(end 247.98274 -61.725302)
		(width 0.0889)
		(layer "In11.Cu")
		(net "M_C_DQ<24>")
	)
	(arc
		(start 247.977914 -56.380888)
		(mid 248.031384 -56.575951)
		(end 247.98274 -56.772302)
		(width 0.0889)
		(layer "In11.Cu")
		(net "M_C_DQ<24>")
	)
	(segment
		(start 221.050358 3.778758)
		(end 221.04985 3.778758)
		(width 0.1651)
		(layer "F.Cu")
		(net "M_C_DQ<23>")
	)
	(segment
		(start 247.344184 -58.06694)
		(end 246.772684 -58.06694)
		(width 0.0889)
		(layer "F.Cu")
		(net "M_C_DQ<23>")
	)
	(segment
		(start 221.04985 3.778758)
		(end 221.04985 2.514854)
		(width 0.1651)
		(layer "F.Cu")
		(net "M_C_DQ<23>")
	)
	(via
		(at 221.04985 2.514854)
		(size 0.508)
		(drill 0.254)
		(layers "F.Cu" "B.Cu")
		(net "M_C_DQ<23>")
	)
	(via
		(at 221.899734 -3.076956)
		(size 0.508)
		(drill 0.254)
		(layers "F.Cu" "B.Cu")
		(net "M_C_DQ<23>")
	)
	(via
		(at 246.772684 -58.06694)
		(size 0.508)
		(drill 0.254)
		(layers "F.Cu" "B.Cu")
		(net "M_C_DQ<23>")
	)
	(segment
		(start 221.900496 -1.021842)
		(end 221.900496 -3.076194)
		(width 0.1651)
		(layer "B.Cu")
		(net "M_C_DQ<23>")
	)
	(segment
		(start 221.900496 -3.076194)
		(end 221.899734 -3.076956)
		(width 0.1651)
		(layer "B.Cu")
		(net "M_C_DQ<23>")
	)
	(segment
		(start 228.01707 -38.680898)
		(end 227.882958 -38.81501)
		(width 0.14224)
		(layer "In11.Cu")
		(net "M_C_DQ<23>")
	)
	(segment
		(start 221.97568 -26.391108)
		(end 221.82074 -26.546048)
		(width 0.14224)
		(layer "In11.Cu")
		(net "M_C_DQ<23>")
	)
	(segment
		(start 222.25254 -18.565114)
		(end 222.25254 -19.00174)
		(width 0.14224)
		(layer "In11.Cu")
		(net "M_C_DQ<23>")
	)
	(segment
		(start 222.45574 -23.117556)
		(end 222.2754 -23.297896)
		(width 0.14224)
		(layer "In11.Cu")
		(net "M_C_DQ<23>")
	)
	(segment
		(start 222.25254 -2.72415)
		(end 221.899734 -3.076956)
		(width 0.14224)
		(layer "In11.Cu")
		(net "M_C_DQ<23>")
	)
	(segment
		(start 222.2754 -9.4742)
		(end 222.3516 -9.5504)
		(width 0.14224)
		(layer "In11.Cu")
		(net "M_C_DQ<23>")
	)
	(segment
		(start 245.040658 -56.485536)
		(end 245.073424 -56.485536)
		(width 0.0889)
		(layer "In11.Cu")
		(net "M_C_DQ<23>")
	)
	(segment
		(start 222.246952 -27.630628)
		(end 221.97568 -27.630628)
		(width 0.14224)
		(layer "In11.Cu")
		(net "M_C_DQ<23>")
	)
	(segment
		(start 222.401892 -27.475688)
		(end 222.246952 -27.630628)
		(width 0.14224)
		(layer "In11.Cu")
		(net "M_C_DQ<23>")
	)
	(segment
		(start 222.45574 -13.516356)
		(end 222.27794 -13.694156)
		(width 0.14224)
		(layer "In11.Cu")
		(net "M_C_DQ<23>")
	)
	(segment
		(start 239.035082 -53.018436)
		(end 239.059212 -53.018436)
		(width 0.0889)
		(layer "In11.Cu")
		(net "M_C_DQ<23>")
	)
	(segment
		(start 222.377 -7.388606)
		(end 222.377 -8.864854)
		(width 0.14224)
		(layer "In11.Cu")
		(net "M_C_DQ<23>")
	)
	(segment
		(start 237.841028 -50.932588)
		(end 237.836202 -50.941224)
		(width 0.0889)
		(layer "In11.Cu")
		(net "M_C_DQ<23>")
	)
	(segment
		(start 222.2754 -4.903216)
		(end 222.2754 -7.287006)
		(width 0.14224)
		(layer "In11.Cu")
		(net "M_C_DQ<23>")
	)
	(segment
		(start 222.2754 -24.657558)
		(end 221.82074 -25.112218)
		(width 0.14224)
		(layer "In11.Cu")
		(net "M_C_DQ<23>")
	)
	(segment
		(start 222.377 -8.864854)
		(end 222.2754 -8.966454)
		(width 0.14224)
		(layer "In11.Cu")
		(net "M_C_DQ<23>")
	)
	(segment
		(start 222.45574 -21.974556)
		(end 222.45574 -23.117556)
		(width 0.14224)
		(layer "In11.Cu")
		(net "M_C_DQ<23>")
	)
	(segment
		(start 222.246952 -25.771348)
		(end 222.401892 -25.926288)
		(width 0.14224)
		(layer "In11.Cu")
		(net "M_C_DQ<23>")
	)
	(segment
		(start 222.25254 0.581152)
		(end 222.25254 -2.72415)
		(width 0.14224)
		(layer "In11.Cu")
		(net "M_C_DQ<23>")
	)
	(segment
		(start 237.38078 -48.399954)
		(end 237.920022 -48.939196)
		(width 0.0889)
		(layer "In11.Cu")
		(net "M_C_DQ<23>")
	)
	(segment
		(start 225.804984 -35.990784)
		(end 225.804984 -36.95573)
		(width 0.14224)
		(layer "In11.Cu")
		(net "M_C_DQ<23>")
	)
	(segment
		(start 227.882958 -38.81501)
		(end 227.882958 -39.033704)
		(width 0.14224)
		(layer "In11.Cu")
		(net "M_C_DQ<23>")
	)
	(segment
		(start 221.82074 -27.785568)
		(end 221.82074 -32.00654)
		(width 0.14224)
		(layer "In11.Cu")
		(net "M_C_DQ<23>")
	)
	(segment
		(start 242.469162 -54.99989)
		(end 242.50523 -54.99989)
		(width 0.0889)
		(layer "In11.Cu")
		(net "M_C_DQ<23>")
	)
	(segment
		(start 238.169704 -52.523136)
		(end 238.209328 -52.523136)
		(width 0.0889)
		(layer "In11.Cu")
		(net "M_C_DQ<23>")
	)
	(segment
		(start 221.899734 -3.076956)
		(end 221.43974 -3.53695)
		(width 0.14224)
		(layer "In11.Cu")
		(net "M_C_DQ<23>")
	)
	(segment
		(start 222.4024 -19.1516)
		(end 222.4024 -21.16074)
		(width 0.14224)
		(layer "In11.Cu")
		(net "M_C_DQ<23>")
	)
	(segment
		(start 239.889792 -53.513736)
		(end 239.922558 -53.513736)
		(width 0.0889)
		(layer "In11.Cu")
		(net "M_C_DQ<23>")
	)
	(segment
		(start 228.01707 -38.501066)
		(end 228.01707 -38.680898)
		(width 0.14224)
		(layer "In11.Cu")
		(net "M_C_DQ<23>")
	)
	(segment
		(start 236.406182 -47.1424)
		(end 237.38078 -48.116998)
		(width 0.14224)
		(layer "In11.Cu")
		(net "M_C_DQ<23>")
	)
	(segment
		(start 222.4024 -21.16074)
		(end 222.25254 -21.3106)
		(width 0.14224)
		(layer "In11.Cu")
		(net "M_C_DQ<23>")
	)
	(segment
		(start 222.45574 -12.373356)
		(end 222.45574 -13.516356)
		(width 0.14224)
		(layer "In11.Cu")
		(net "M_C_DQ<23>")
	)
	(segment
		(start 221.82074 -32.00654)
		(end 225.804984 -35.990784)
		(width 0.14224)
		(layer "In11.Cu")
		(net "M_C_DQ<23>")
	)
	(segment
		(start 222.25254 -21.3106)
		(end 222.25254 -21.771356)
		(width 0.14224)
		(layer "In11.Cu")
		(net "M_C_DQ<23>")
	)
	(segment
		(start 221.82074 -25.112218)
		(end 221.82074 -25.616408)
		(width 0.14224)
		(layer "In11.Cu")
		(net "M_C_DQ<23>")
	)
	(segment
		(start 222.2754 -7.287006)
		(end 222.377 -7.388606)
		(width 0.14224)
		(layer "In11.Cu")
		(net "M_C_DQ<23>")
	)
	(segment
		(start 241.606832 -54.504336)
		(end 241.639598 -54.504336)
		(width 0.0889)
		(layer "In11.Cu")
		(net "M_C_DQ<23>")
	)
	(segment
		(start 222.401892 -27.165808)
		(end 222.401892 -27.475688)
		(width 0.14224)
		(layer "In11.Cu")
		(net "M_C_DQ<23>")
	)
	(segment
		(start 227.882958 -39.033704)
		(end 235.991654 -47.1424)
		(width 0.14224)
		(layer "In11.Cu")
		(net "M_C_DQ<23>")
	)
	(segment
		(start 222.3516 -9.5504)
		(end 222.3516 -11.6586)
		(width 0.14224)
		(layer "In11.Cu")
		(net "M_C_DQ<23>")
	)
	(segment
		(start 222.401892 -25.926288)
		(end 222.401892 -26.236168)
		(width 0.14224)
		(layer "In11.Cu")
		(net "M_C_DQ<23>")
	)
	(segment
		(start 222.246952 -26.391108)
		(end 221.97568 -26.391108)
		(width 0.14224)
		(layer "In11.Cu")
		(net "M_C_DQ<23>")
	)
	(segment
		(start 222.27794 -16.890746)
		(end 222.48114 -17.093946)
		(width 0.14224)
		(layer "In11.Cu")
		(net "M_C_DQ<23>")
	)
	(segment
		(start 222.401892 -26.236168)
		(end 222.246952 -26.391108)
		(width 0.14224)
		(layer "In11.Cu")
		(net "M_C_DQ<23>")
	)
	(segment
		(start 222.25254 -19.00174)
		(end 222.4024 -19.1516)
		(width 0.14224)
		(layer "In11.Cu")
		(net "M_C_DQ<23>")
	)
	(segment
		(start 222.48114 -17.093946)
		(end 222.48114 -18.336514)
		(width 0.14224)
		(layer "In11.Cu")
		(net "M_C_DQ<23>")
	)
	(segment
		(start 243.338604 -55.494936)
		(end 243.356384 -55.494936)
		(width 0.0889)
		(layer "In11.Cu")
		(net "M_C_DQ<23>")
	)
	(segment
		(start 237.38078 -48.116998)
		(end 237.38078 -48.399954)
		(width 0.0889)
		(layer "In11.Cu")
		(net "M_C_DQ<23>")
	)
	(segment
		(start 221.366588 1.8796)
		(end 221.696788 1.5494)
		(width 0.14224)
		(layer "In11.Cu")
		(net "M_C_DQ<23>")
	)
	(segment
		(start 237.920022 -48.939196)
		(end 237.920022 -50.63744)
		(width 0.0889)
		(layer "In11.Cu")
		(net "M_C_DQ<23>")
	)
	(segment
		(start 221.97568 -25.771348)
		(end 222.246952 -25.771348)
		(width 0.14224)
		(layer "In11.Cu")
		(net "M_C_DQ<23>")
	)
	(segment
		(start 222.246952 -27.010868)
		(end 222.401892 -27.165808)
		(width 0.14224)
		(layer "In11.Cu")
		(net "M_C_DQ<23>")
	)
	(segment
		(start 221.82074 -26.855928)
		(end 221.97568 -27.010868)
		(width 0.14224)
		(layer "In11.Cu")
		(net "M_C_DQ<23>")
	)
	(segment
		(start 222.407988 0.7366)
		(end 222.25254 0.581152)
		(width 0.14224)
		(layer "In11.Cu")
		(net "M_C_DQ<23>")
	)
	(segment
		(start 222.2754 -8.966454)
		(end 222.2754 -9.4742)
		(width 0.14224)
		(layer "In11.Cu")
		(net "M_C_DQ<23>")
	)
	(segment
		(start 246.425974 -57.276238)
		(end 246.442738 -57.305194)
		(width 0.0889)
		(layer "In11.Cu")
		(net "M_C_DQ<23>")
	)
	(segment
		(start 244.185948 -55.99049)
		(end 244.218714 -55.99049)
		(width 0.0889)
		(layer "In11.Cu")
		(net "M_C_DQ<23>")
	)
	(segment
		(start 222.48114 -18.336514)
		(end 222.25254 -18.565114)
		(width 0.14224)
		(layer "In11.Cu")
		(net "M_C_DQ<23>")
	)
	(segment
		(start 221.43974 -3.53695)
		(end 221.43974 -4.067556)
		(width 0.14224)
		(layer "In11.Cu")
		(net "M_C_DQ<23>")
	)
	(segment
		(start 221.97568 -27.630628)
		(end 221.82074 -27.785568)
		(width 0.14224)
		(layer "In11.Cu")
		(net "M_C_DQ<23>")
	)
	(segment
		(start 222.3516 -11.6586)
		(end 222.2754 -11.7348)
		(width 0.14224)
		(layer "In11.Cu")
		(net "M_C_DQ<23>")
	)
	(segment
		(start 221.950788 1.5494)
		(end 222.407988 1.0922)
		(width 0.14224)
		(layer "In11.Cu")
		(net "M_C_DQ<23>")
	)
	(segment
		(start 221.04985 2.514854)
		(end 221.366588 2.198116)
		(width 0.14224)
		(layer "In11.Cu")
		(net "M_C_DQ<23>")
	)
	(segment
		(start 222.407988 1.0922)
		(end 222.407988 0.7366)
		(width 0.14224)
		(layer "In11.Cu")
		(net "M_C_DQ<23>")
	)
	(segment
		(start 235.991654 -47.1424)
		(end 236.406182 -47.1424)
		(width 0.14224)
		(layer "In11.Cu")
		(net "M_C_DQ<23>")
	)
	(segment
		(start 227.758498 -38.242494)
		(end 228.01707 -38.501066)
		(width 0.14224)
		(layer "In11.Cu")
		(net "M_C_DQ<23>")
	)
	(segment
		(start 240.752122 -54.00929)
		(end 240.784888 -54.00929)
		(width 0.0889)
		(layer "In11.Cu")
		(net "M_C_DQ<23>")
	)
	(segment
		(start 222.25254 -21.771356)
		(end 222.45574 -21.974556)
		(width 0.14224)
		(layer "In11.Cu")
		(net "M_C_DQ<23>")
	)
	(segment
		(start 221.82074 -26.546048)
		(end 221.82074 -26.855928)
		(width 0.14224)
		(layer "In11.Cu")
		(net "M_C_DQ<23>")
	)
	(segment
		(start 227.225606 -38.376352)
		(end 227.444808 -38.376352)
		(width 0.14224)
		(layer "In11.Cu")
		(net "M_C_DQ<23>")
	)
	(segment
		(start 246.442738 -57.305194)
		(end 246.772684 -58.06694)
		(width 0.0889)
		(layer "In11.Cu")
		(net "M_C_DQ<23>")
	)
	(segment
		(start 225.804984 -36.95573)
		(end 227.225606 -38.376352)
		(width 0.14224)
		(layer "In11.Cu")
		(net "M_C_DQ<23>")
	)
	(segment
		(start 222.27794 -13.694156)
		(end 222.27794 -16.890746)
		(width 0.14224)
		(layer "In11.Cu")
		(net "M_C_DQ<23>")
	)
	(segment
		(start 221.366588 2.198116)
		(end 221.366588 1.8796)
		(width 0.14224)
		(layer "In11.Cu")
		(net "M_C_DQ<23>")
	)
	(segment
		(start 242.992148 -55.294784)
		(end 242.99545 -55.300626)
		(width 0.0889)
		(layer "In11.Cu")
		(net "M_C_DQ<23>")
	)
	(segment
		(start 221.696788 1.5494)
		(end 221.950788 1.5494)
		(width 0.14224)
		(layer "In11.Cu")
		(net "M_C_DQ<23>")
	)
	(segment
		(start 221.97568 -27.010868)
		(end 222.246952 -27.010868)
		(width 0.14224)
		(layer "In11.Cu")
		(net "M_C_DQ<23>")
	)
	(segment
		(start 221.43974 -4.067556)
		(end 222.2754 -4.903216)
		(width 0.14224)
		(layer "In11.Cu")
		(net "M_C_DQ<23>")
	)
	(segment
		(start 222.2754 -23.297896)
		(end 222.2754 -24.657558)
		(width 0.14224)
		(layer "In11.Cu")
		(net "M_C_DQ<23>")
	)
	(segment
		(start 222.2754 -11.7348)
		(end 222.2754 -12.193016)
		(width 0.14224)
		(layer "In11.Cu")
		(net "M_C_DQ<23>")
	)
	(segment
		(start 221.82074 -25.616408)
		(end 221.97568 -25.771348)
		(width 0.14224)
		(layer "In11.Cu")
		(net "M_C_DQ<23>")
	)
	(segment
		(start 227.444808 -38.376352)
		(end 227.578666 -38.242494)
		(width 0.14224)
		(layer "In11.Cu")
		(net "M_C_DQ<23>")
	)
	(segment
		(start 222.2754 -12.193016)
		(end 222.45574 -12.373356)
		(width 0.14224)
		(layer "In11.Cu")
		(net "M_C_DQ<23>")
	)
	(segment
		(start 245.902988 -56.98109)
		(end 245.935754 -56.98109)
		(width 0.0889)
		(layer "In11.Cu")
		(net "M_C_DQ<23>")
	)
	(segment
		(start 227.578666 -38.242494)
		(end 227.758498 -38.242494)
		(width 0.14224)
		(layer "In11.Cu")
		(net "M_C_DQ<23>")
	)
	(arc
		(start 238.209328 -52.523136)
		(mid 238.492545 -52.607417)
		(end 238.699548 -52.818284)
		(width 0.0889)
		(layer "In11.Cu")
		(net "M_C_DQ<23>")
	)
	(arc
		(start 241.639598 -54.504336)
		(mid 241.925022 -54.587803)
		(end 242.133628 -54.799738)
		(width 0.0889)
		(layer "In11.Cu")
		(net "M_C_DQ<23>")
	)
	(arc
		(start 241.275108 -54.304438)
		(mid 241.415187 -54.447174)
		(end 241.606832 -54.504336)
		(width 0.0889)
		(layer "In11.Cu")
		(net "M_C_DQ<23>")
	)
	(arc
		(start 239.059212 -53.018436)
		(mid 239.347357 -53.100755)
		(end 239.558068 -53.313838)
		(width 0.0889)
		(layer "In11.Cu")
		(net "M_C_DQ<23>")
	)
	(arc
		(start 237.841028 -51.923442)
		(mid 237.836783 -52.315687)
		(end 238.169704 -52.523136)
		(width 0.0889)
		(layer "In11.Cu")
		(net "M_C_DQ<23>")
	)
	(arc
		(start 238.699548 -52.818284)
		(mid 238.841231 -52.962088)
		(end 239.035082 -53.018436)
		(width 0.0889)
		(layer "In11.Cu")
		(net "M_C_DQ<23>")
	)
	(arc
		(start 240.784888 -54.00929)
		(mid 241.068105 -54.093571)
		(end 241.275108 -54.304438)
		(width 0.0889)
		(layer "In11.Cu")
		(net "M_C_DQ<23>")
	)
	(arc
		(start 242.50523 -54.99989)
		(mid 242.78653 -55.084856)
		(end 242.992148 -55.294784)
		(width 0.0889)
		(layer "In11.Cu")
		(net "M_C_DQ<23>")
	)
	(arc
		(start 244.218714 -55.99049)
		(mid 244.501931 -56.074771)
		(end 244.708934 -56.285638)
		(width 0.0889)
		(layer "In11.Cu")
		(net "M_C_DQ<23>")
	)
	(arc
		(start 245.567454 -56.780938)
		(mid 245.709137 -56.924742)
		(end 245.902988 -56.98109)
		(width 0.0889)
		(layer "In11.Cu")
		(net "M_C_DQ<23>")
	)
	(arc
		(start 239.558068 -53.313838)
		(mid 239.698147 -53.456574)
		(end 239.889792 -53.513736)
		(width 0.0889)
		(layer "In11.Cu")
		(net "M_C_DQ<23>")
	)
	(arc
		(start 245.073424 -56.485536)
		(mid 245.358848 -56.569003)
		(end 245.567454 -56.780938)
		(width 0.0889)
		(layer "In11.Cu")
		(net "M_C_DQ<23>")
	)
	(arc
		(start 244.708934 -56.285638)
		(mid 244.849013 -56.428374)
		(end 245.040658 -56.485536)
		(width 0.0889)
		(layer "In11.Cu")
		(net "M_C_DQ<23>")
	)
	(arc
		(start 243.356384 -55.494936)
		(mid 243.641808 -55.578403)
		(end 243.850414 -55.790338)
		(width 0.0889)
		(layer "In11.Cu")
		(net "M_C_DQ<23>")
	)
	(arc
		(start 237.836202 -50.941224)
		(mid 237.787447 -51.137576)
		(end 237.841028 -51.332638)
		(width 0.0889)
		(layer "In11.Cu")
		(net "M_C_DQ<23>")
	)
	(arc
		(start 237.920022 -50.63744)
		(mid 237.89993 -50.790207)
		(end 237.841028 -50.932588)
		(width 0.0889)
		(layer "In11.Cu")
		(net "M_C_DQ<23>")
	)
	(arc
		(start 245.935754 -56.98109)
		(mid 246.218971 -57.065371)
		(end 246.425974 -57.276238)
		(width 0.0889)
		(layer "In11.Cu")
		(net "M_C_DQ<23>")
	)
	(arc
		(start 243.850414 -55.790338)
		(mid 243.992097 -55.934142)
		(end 244.185948 -55.99049)
		(width 0.0889)
		(layer "In11.Cu")
		(net "M_C_DQ<23>")
	)
	(arc
		(start 242.99545 -55.300626)
		(mid 243.141416 -55.443025)
		(end 243.338604 -55.494936)
		(width 0.0889)
		(layer "In11.Cu")
		(net "M_C_DQ<23>")
	)
	(arc
		(start 237.841028 -51.332638)
		(mid 237.920159 -51.62804)
		(end 237.841028 -51.923442)
		(width 0.0889)
		(layer "In11.Cu")
		(net "M_C_DQ<23>")
	)
	(arc
		(start 240.416588 -53.809138)
		(mid 240.558271 -53.952942)
		(end 240.752122 -54.00929)
		(width 0.0889)
		(layer "In11.Cu")
		(net "M_C_DQ<23>")
	)
	(arc
		(start 239.922558 -53.513736)
		(mid 240.207982 -53.597203)
		(end 240.416588 -53.809138)
		(width 0.0889)
		(layer "In11.Cu")
		(net "M_C_DQ<23>")
	)
	(arc
		(start 242.133628 -54.799738)
		(mid 242.275311 -54.943542)
		(end 242.469162 -54.99989)
		(width 0.0889)
		(layer "In11.Cu")
		(net "M_C_DQ<23>")
	)
	(segment
		(start 221.899988 -0.821182)
		(end 221.899988 0.1524)
		(width 0.1651)
		(layer "F.Cu")
		(net "M_C_DQ<22>")
	)
	(segment
		(start 222.032068 0.50292)
		(end 221.899988 0.635)
		(width 0.1651)
		(layer "F.Cu")
		(net "M_C_DQ<22>")
	)
	(segment
		(start 222.032068 0.28448)
		(end 222.032068 0.50292)
		(width 0.1651)
		(layer "F.Cu")
		(net "M_C_DQ<22>")
	)
	(segment
		(start 221.899988 0.635)
		(end 221.899988 0.939546)
		(width 0.1651)
		(layer "F.Cu")
		(net "M_C_DQ<22>")
	)
	(segment
		(start 221.899988 0.1524)
		(end 222.032068 0.28448)
		(width 0.1651)
		(layer "F.Cu")
		(net "M_C_DQ<22>")
	)
	(segment
		(start 221.899988 0.939546)
		(end 221.899734 0.9398)
		(width 0.1651)
		(layer "F.Cu")
		(net "M_C_DQ<22>")
	)
	(segment
		(start 245.627144 -57.076086)
		(end 245.055644 -57.076086)
		(width 0.0889)
		(layer "F.Cu")
		(net "M_C_DQ<22>")
	)
	(segment
		(start 221.900496 -0.821182)
		(end 221.899988 -0.821182)
		(width 0.1651)
		(layer "F.Cu")
		(net "M_C_DQ<22>")
	)
	(via
		(at 221.899734 0.9398)
		(size 0.508)
		(drill 0.254)
		(layers "F.Cu" "B.Cu")
		(net "M_C_DQ<22>")
	)
	(via
		(at 221.04985 -4.357878)
		(size 0.508)
		(drill 0.254)
		(layers "F.Cu" "B.Cu")
		(net "M_C_DQ<22>")
	)
	(via
		(at 245.055644 -57.076086)
		(size 0.508)
		(drill 0.254)
		(layers "F.Cu" "B.Cu")
		(net "M_C_DQ<22>")
	)
	(segment
		(start 221.050358 -5.621782)
		(end 221.04985 -5.621782)
		(width 0.1651)
		(layer "B.Cu")
		(net "M_C_DQ<22>")
	)
	(segment
		(start 221.04985 -5.621782)
		(end 221.04985 -4.357878)
		(width 0.1651)
		(layer "B.Cu")
		(net "M_C_DQ<22>")
	)
	(segment
		(start 238.169958 -52.71389)
		(end 238.205772 -52.71389)
		(width 0.0889)
		(layer "In11.Cu")
		(net "M_C_DQ<22>")
	)
	(segment
		(start 221.161356 -0.076454)
		(end 221.161356 -0.387096)
		(width 0.14224)
		(layer "In11.Cu")
		(net "M_C_DQ<22>")
	)
	(segment
		(start 221.41434 -16.992346)
		(end 221.41434 -18.443194)
		(width 0.14224)
		(layer "In11.Cu")
		(net "M_C_DQ<22>")
	)
	(segment
		(start 223.842326 -34.975292)
		(end 224.061274 -34.975292)
		(width 0.14224)
		(layer "In11.Cu")
		(net "M_C_DQ<22>")
	)
	(segment
		(start 234.053126 -46.016672)
		(end 234.053126 -46.23562)
		(width 0.14224)
		(layer "In11.Cu")
		(net "M_C_DQ<22>")
	)
	(segment
		(start 223.098106 -35.061652)
		(end 223.317562 -35.281108)
		(width 0.14224)
		(layer "In11.Cu")
		(net "M_C_DQ<22>")
	)
	(segment
		(start 237.006638 -48.62576)
		(end 237.30077 -48.62576)
		(width 0.0889)
		(layer "In11.Cu")
		(net "M_C_DQ<22>")
	)
	(segment
		(start 221.525338 0.287528)
		(end 221.161356 -0.076454)
		(width 0.14224)
		(layer "In11.Cu")
		(net "M_C_DQ<22>")
	)
	(segment
		(start 222.08871 -33.221676)
		(end 222.307658 -33.221676)
		(width 0.14224)
		(layer "In11.Cu")
		(net "M_C_DQ<22>")
	)
	(segment
		(start 224.28073 -35.413696)
		(end 223.974914 -35.719512)
		(width 0.14224)
		(layer "In11.Cu")
		(net "M_C_DQ<22>")
	)
	(segment
		(start 221.542356 -1.111504)
		(end 221.161356 -1.492504)
		(width 0.14224)
		(layer "In11.Cu")
		(net "M_C_DQ<22>")
	)
	(segment
		(start 221.41434 -12.373356)
		(end 221.41434 -13.567156)
		(width 0.14224)
		(layer "In11.Cu")
		(net "M_C_DQ<22>")
	)
	(segment
		(start 222.440754 -34.4043)
		(end 222.659702 -34.4043)
		(width 0.14224)
		(layer "In11.Cu")
		(net "M_C_DQ<22>")
	)
	(segment
		(start 222.307658 -33.221676)
		(end 222.527114 -33.441132)
		(width 0.14224)
		(layer "In11.Cu")
		(net "M_C_DQ<22>")
	)
	(segment
		(start 237.675928 -50.837338)
		(end 237.669578 -50.848006)
		(width 0.0889)
		(layer "In11.Cu")
		(net "M_C_DQ<22>")
	)
	(segment
		(start 234.929934 -47.112428)
		(end 234.587542 -47.45482)
		(width 0.14224)
		(layer "In11.Cu")
		(net "M_C_DQ<22>")
	)
	(segment
		(start 221.41434 -21.974556)
		(end 221.41434 -23.168356)
		(width 0.14224)
		(layer "In11.Cu")
		(net "M_C_DQ<22>")
	)
	(segment
		(start 235.368338 -47.550832)
		(end 235.587286 -47.550832)
		(width 0.14224)
		(layer "In11.Cu")
		(net "M_C_DQ<22>")
	)
	(segment
		(start 221.41434 -23.168356)
		(end 221.5134 -23.267416)
		(width 0.14224)
		(layer "In11.Cu")
		(net "M_C_DQ<22>")
	)
	(segment
		(start 224.28073 -35.194748)
		(end 224.28073 -35.413696)
		(width 0.14224)
		(layer "In11.Cu")
		(net "M_C_DQ<22>")
	)
	(segment
		(start 221.41434 -13.567156)
		(end 221.51594 -13.668756)
		(width 0.14224)
		(layer "In11.Cu")
		(net "M_C_DQ<22>")
	)
	(segment
		(start 221.41434 -18.443194)
		(end 221.61754 -18.646394)
		(width 0.14224)
		(layer "In11.Cu")
		(net "M_C_DQ<22>")
	)
	(segment
		(start 237.680754 -51.819302)
		(end 237.675928 -51.827938)
		(width 0.0889)
		(layer "In11.Cu")
		(net "M_C_DQ<22>")
	)
	(segment
		(start 221.51594 -16.890746)
		(end 221.41434 -16.992346)
		(width 0.14224)
		(layer "In11.Cu")
		(net "M_C_DQ<22>")
	)
	(segment
		(start 221.161356 -1.777746)
		(end 221.586806 -2.203196)
		(width 0.14224)
		(layer "In11.Cu")
		(net "M_C_DQ<22>")
	)
	(segment
		(start 223.184466 -34.098484)
		(end 223.403922 -34.31794)
		(width 0.14224)
		(layer "In11.Cu")
		(net "M_C_DQ<22>")
	)
	(segment
		(start 237.729776 -49.054766)
		(end 237.729776 -50.636932)
		(width 0.0889)
		(layer "In11.Cu")
		(net "M_C_DQ<22>")
	)
	(segment
		(start 221.61754 -18.99666)
		(end 221.4372 -19.177)
		(width 0.14224)
		(layer "In11.Cu")
		(net "M_C_DQ<22>")
	)
	(segment
		(start 221.5134 -4.821428)
		(end 221.5134 -7.292086)
		(width 0.14224)
		(layer "In11.Cu")
		(net "M_C_DQ<22>")
	)
	(segment
		(start 239.883188 -53.704236)
		(end 239.915954 -53.704236)
		(width 0.0889)
		(layer "In11.Cu")
		(net "M_C_DQ<22>")
	)
	(segment
		(start 233.710734 -46.79696)
		(end 233.93019 -47.016416)
		(width 0.14224)
		(layer "In11.Cu")
		(net "M_C_DQ<22>")
	)
	(segment
		(start 237.729776 -50.636932)
		(end 237.729268 -50.63744)
		(width 0.0889)
		(layer "In11.Cu")
		(net "M_C_DQ<22>")
	)
	(segment
		(start 240.745518 -54.19979)
		(end 240.778284 -54.19979)
		(width 0.0889)
		(layer "In11.Cu")
		(net "M_C_DQ<22>")
	)
	(segment
		(start 221.61754 -18.646394)
		(end 221.61754 -18.99666)
		(width 0.14224)
		(layer "In11.Cu")
		(net "M_C_DQ<22>")
	)
	(segment
		(start 222.965518 -34.098484)
		(end 223.184466 -34.098484)
		(width 0.14224)
		(layer "In11.Cu")
		(net "M_C_DQ<22>")
	)
	(segment
		(start 221.5134 -12.274296)
		(end 221.41434 -12.373356)
		(width 0.14224)
		(layer "In11.Cu")
		(net "M_C_DQ<22>")
	)
	(segment
		(start 234.929934 -46.89348)
		(end 234.929934 -47.112428)
		(width 0.14224)
		(layer "In11.Cu")
		(net "M_C_DQ<22>")
	)
	(segment
		(start 234.710478 -46.674024)
		(end 234.929934 -46.89348)
		(width 0.14224)
		(layer "In11.Cu")
		(net "M_C_DQ<22>")
	)
	(segment
		(start 223.974914 -35.719512)
		(end 223.974914 -35.93846)
		(width 0.14224)
		(layer "In11.Cu")
		(net "M_C_DQ<22>")
	)
	(segment
		(start 223.317562 -35.281108)
		(end 223.53651 -35.281108)
		(width 0.14224)
		(layer "In11.Cu")
		(net "M_C_DQ<22>")
	)
	(segment
		(start 221.04985 -4.357878)
		(end 221.5134 -4.821428)
		(width 0.14224)
		(layer "In11.Cu")
		(net "M_C_DQ<22>")
	)
	(segment
		(start 223.098106 -34.842704)
		(end 223.098106 -35.061652)
		(width 0.14224)
		(layer "In11.Cu")
		(net "M_C_DQ<22>")
	)
	(segment
		(start 237.30077 -48.62576)
		(end 237.729776 -49.054766)
		(width 0.0889)
		(layer "In11.Cu")
		(net "M_C_DQ<22>")
	)
	(segment
		(start 222.527114 -33.441132)
		(end 222.527114 -33.66008)
		(width 0.14224)
		(layer "In11.Cu")
		(net "M_C_DQ<22>")
	)
	(segment
		(start 234.053126 -46.23562)
		(end 233.710734 -46.578012)
		(width 0.14224)
		(layer "In11.Cu")
		(net "M_C_DQ<22>")
	)
	(segment
		(start 220.814138 -3.327654)
		(end 220.814138 -4.122166)
		(width 0.14224)
		(layer "In11.Cu")
		(net "M_C_DQ<22>")
	)
	(segment
		(start 221.4372 -21.20646)
		(end 221.61754 -21.3868)
		(width 0.14224)
		(layer "In11.Cu")
		(net "M_C_DQ<22>")
	)
	(segment
		(start 222.221298 -34.184844)
		(end 222.440754 -34.4043)
		(width 0.14224)
		(layer "In11.Cu")
		(net "M_C_DQ<22>")
	)
	(segment
		(start 234.149138 -47.016416)
		(end 234.49153 -46.674024)
		(width 0.14224)
		(layer "In11.Cu")
		(net "M_C_DQ<22>")
	)
	(segment
		(start 224.061274 -34.975292)
		(end 224.28073 -35.194748)
		(width 0.14224)
		(layer "In11.Cu")
		(net "M_C_DQ<22>")
	)
	(segment
		(start 243.313712 -55.685436)
		(end 243.34978 -55.685436)
		(width 0.0889)
		(layer "In11.Cu")
		(net "M_C_DQ<22>")
	)
	(segment
		(start 221.61754 -21.3868)
		(end 221.61754 -21.771356)
		(width 0.14224)
		(layer "In11.Cu")
		(net "M_C_DQ<22>")
	)
	(segment
		(start 221.18574 -33.149286)
		(end 221.563946 -33.527492)
		(width 0.14224)
		(layer "In11.Cu")
		(net "M_C_DQ<22>")
	)
	(segment
		(start 221.586806 -2.203196)
		(end 221.586806 -2.554986)
		(width 0.14224)
		(layer "In11.Cu")
		(net "M_C_DQ<22>")
	)
	(segment
		(start 221.5134 -9.4742)
		(end 221.4118 -9.5758)
		(width 0.14224)
		(layer "In11.Cu")
		(net "M_C_DQ<22>")
	)
	(segment
		(start 221.5134 -24.525224)
		(end 221.18574 -24.852884)
		(width 0.14224)
		(layer "In11.Cu")
		(net "M_C_DQ<22>")
	)
	(segment
		(start 236.662214 -48.62576)
		(end 237.006638 -48.62576)
		(width 0.14224)
		(layer "In11.Cu")
		(net "M_C_DQ<22>")
	)
	(segment
		(start 222.527114 -33.66008)
		(end 222.221298 -33.965896)
		(width 0.14224)
		(layer "In11.Cu")
		(net "M_C_DQ<22>")
	)
	(segment
		(start 233.93019 -47.016416)
		(end 234.149138 -47.016416)
		(width 0.14224)
		(layer "In11.Cu")
		(net "M_C_DQ<22>")
	)
	(segment
		(start 221.4118 -11.5824)
		(end 221.5134 -11.684)
		(width 0.14224)
		(layer "In11.Cu")
		(net "M_C_DQ<22>")
	)
	(segment
		(start 221.4372 -19.177)
		(end 221.4372 -21.20646)
		(width 0.14224)
		(layer "In11.Cu")
		(net "M_C_DQ<22>")
	)
	(segment
		(start 220.814138 -4.122166)
		(end 221.04985 -4.357878)
		(width 0.14224)
		(layer "In11.Cu")
		(net "M_C_DQ<22>")
	)
	(segment
		(start 234.49153 -46.674024)
		(end 234.710478 -46.674024)
		(width 0.14224)
		(layer "In11.Cu")
		(net "M_C_DQ<22>")
	)
	(segment
		(start 244.543834 -56.380888)
		(end 244.560598 -56.410352)
		(width 0.0889)
		(layer "In11.Cu")
		(net "M_C_DQ<22>")
	)
	(segment
		(start 221.563946 -33.527492)
		(end 221.782894 -33.527492)
		(width 0.14224)
		(layer "In11.Cu")
		(net "M_C_DQ<22>")
	)
	(segment
		(start 223.974914 -35.93846)
		(end 234.053126 -46.016672)
		(width 0.14224)
		(layer "In11.Cu")
		(net "M_C_DQ<22>")
	)
	(segment
		(start 234.587542 -47.45482)
		(end 234.587542 -47.673768)
		(width 0.14224)
		(layer "In11.Cu")
		(net "M_C_DQ<22>")
	)
	(segment
		(start 221.51594 -13.668756)
		(end 221.51594 -16.890746)
		(width 0.14224)
		(layer "In11.Cu")
		(net "M_C_DQ<22>")
	)
	(segment
		(start 221.542356 -0.768096)
		(end 221.542356 -1.111504)
		(width 0.14224)
		(layer "In11.Cu")
		(net "M_C_DQ<22>")
	)
	(segment
		(start 222.221298 -33.965896)
		(end 222.221298 -34.184844)
		(width 0.14224)
		(layer "In11.Cu")
		(net "M_C_DQ<22>")
	)
	(segment
		(start 239.033304 -53.20919)
		(end 239.061244 -53.20919)
		(width 0.0889)
		(layer "In11.Cu")
		(net "M_C_DQ<22>")
	)
	(segment
		(start 223.403922 -34.536888)
		(end 223.098106 -34.842704)
		(width 0.14224)
		(layer "In11.Cu")
		(net "M_C_DQ<22>")
	)
	(segment
		(start 221.161356 -1.492504)
		(end 221.161356 -1.777746)
		(width 0.14224)
		(layer "In11.Cu")
		(net "M_C_DQ<22>")
	)
	(segment
		(start 221.5134 -7.292086)
		(end 221.41434 -7.391146)
		(width 0.14224)
		(layer "In11.Cu")
		(net "M_C_DQ<22>")
	)
	(segment
		(start 221.5134 -23.267416)
		(end 221.5134 -24.525224)
		(width 0.14224)
		(layer "In11.Cu")
		(net "M_C_DQ<22>")
	)
	(segment
		(start 244.560598 -56.410352)
		(end 245.055644 -57.076086)
		(width 0.0889)
		(layer "In11.Cu")
		(net "M_C_DQ<22>")
	)
	(segment
		(start 221.899734 0.9398)
		(end 221.525338 0.565404)
		(width 0.14224)
		(layer "In11.Cu")
		(net "M_C_DQ<22>")
	)
	(segment
		(start 233.710734 -46.578012)
		(end 233.710734 -46.79696)
		(width 0.14224)
		(layer "In11.Cu")
		(net "M_C_DQ<22>")
	)
	(segment
		(start 221.5134 -11.684)
		(end 221.5134 -12.274296)
		(width 0.14224)
		(layer "In11.Cu")
		(net "M_C_DQ<22>")
	)
	(segment
		(start 221.41434 -8.841994)
		(end 221.5134 -8.941054)
		(width 0.14224)
		(layer "In11.Cu")
		(net "M_C_DQ<22>")
	)
	(segment
		(start 221.4118 -9.5758)
		(end 221.4118 -11.5824)
		(width 0.14224)
		(layer "In11.Cu")
		(net "M_C_DQ<22>")
	)
	(segment
		(start 221.586806 -2.554986)
		(end 220.814138 -3.327654)
		(width 0.14224)
		(layer "In11.Cu")
		(net "M_C_DQ<22>")
	)
	(segment
		(start 221.525338 0.565404)
		(end 221.525338 0.287528)
		(width 0.14224)
		(layer "In11.Cu")
		(net "M_C_DQ<22>")
	)
	(segment
		(start 221.782894 -33.527492)
		(end 222.08871 -33.221676)
		(width 0.14224)
		(layer "In11.Cu")
		(net "M_C_DQ<22>")
	)
	(segment
		(start 235.587286 -47.550832)
		(end 236.662214 -48.62576)
		(width 0.14224)
		(layer "In11.Cu")
		(net "M_C_DQ<22>")
	)
	(segment
		(start 235.025946 -47.893224)
		(end 235.368338 -47.550832)
		(width 0.14224)
		(layer "In11.Cu")
		(net "M_C_DQ<22>")
	)
	(segment
		(start 221.41434 -7.391146)
		(end 221.41434 -8.841994)
		(width 0.14224)
		(layer "In11.Cu")
		(net "M_C_DQ<22>")
	)
	(segment
		(start 222.659702 -34.4043)
		(end 222.965518 -34.098484)
		(width 0.14224)
		(layer "In11.Cu")
		(net "M_C_DQ<22>")
	)
	(segment
		(start 244.179344 -56.18099)
		(end 244.21211 -56.18099)
		(width 0.0889)
		(layer "In11.Cu")
		(net "M_C_DQ<22>")
	)
	(segment
		(start 234.587542 -47.673768)
		(end 234.806998 -47.893224)
		(width 0.14224)
		(layer "In11.Cu")
		(net "M_C_DQ<22>")
	)
	(segment
		(start 223.403922 -34.31794)
		(end 223.403922 -34.536888)
		(width 0.14224)
		(layer "In11.Cu")
		(net "M_C_DQ<22>")
	)
	(segment
		(start 241.600228 -54.694836)
		(end 241.632994 -54.694836)
		(width 0.0889)
		(layer "In11.Cu")
		(net "M_C_DQ<22>")
	)
	(segment
		(start 221.61754 -21.771356)
		(end 221.41434 -21.974556)
		(width 0.14224)
		(layer "In11.Cu")
		(net "M_C_DQ<22>")
	)
	(segment
		(start 242.823492 -55.3847)
		(end 242.826794 -55.390542)
		(width 0.0889)
		(layer "In11.Cu")
		(net "M_C_DQ<22>")
	)
	(segment
		(start 234.806998 -47.893224)
		(end 235.025946 -47.893224)
		(width 0.14224)
		(layer "In11.Cu")
		(net "M_C_DQ<22>")
	)
	(segment
		(start 221.161356 -0.387096)
		(end 221.542356 -0.768096)
		(width 0.14224)
		(layer "In11.Cu")
		(net "M_C_DQ<22>")
	)
	(segment
		(start 221.18574 -24.852884)
		(end 221.18574 -33.149286)
		(width 0.14224)
		(layer "In11.Cu")
		(net "M_C_DQ<22>")
	)
	(segment
		(start 242.462558 -55.19039)
		(end 242.480338 -55.19039)
		(width 0.0889)
		(layer "In11.Cu")
		(net "M_C_DQ<22>")
	)
	(segment
		(start 221.5134 -8.941054)
		(end 221.5134 -9.4742)
		(width 0.14224)
		(layer "In11.Cu")
		(net "M_C_DQ<22>")
	)
	(segment
		(start 223.53651 -35.281108)
		(end 223.842326 -34.975292)
		(width 0.14224)
		(layer "In11.Cu")
		(net "M_C_DQ<22>")
	)
	(arc
		(start 244.21211 -56.18099)
		(mid 244.403752 -56.238156)
		(end 244.543834 -56.380888)
		(width 0.0889)
		(layer "In11.Cu")
		(net "M_C_DQ<22>")
	)
	(arc
		(start 239.915954 -53.704236)
		(mid 240.109804 -53.760586)
		(end 240.251488 -53.904388)
		(width 0.0889)
		(layer "In11.Cu")
		(net "M_C_DQ<22>")
	)
	(arc
		(start 239.392968 -53.409088)
		(mid 239.599972 -53.619952)
		(end 239.883188 -53.704236)
		(width 0.0889)
		(layer "In11.Cu")
		(net "M_C_DQ<22>")
	)
	(arc
		(start 243.685314 -55.885588)
		(mid 243.893922 -56.09752)
		(end 244.179344 -56.18099)
		(width 0.0889)
		(layer "In11.Cu")
		(net "M_C_DQ<22>")
	)
	(arc
		(start 237.669578 -50.848006)
		(mid 237.59678 -51.138769)
		(end 237.675928 -51.427888)
		(width 0.0889)
		(layer "In11.Cu")
		(net "M_C_DQ<22>")
	)
	(arc
		(start 241.968528 -54.894988)
		(mid 242.177136 -55.10692)
		(end 242.462558 -55.19039)
		(width 0.0889)
		(layer "In11.Cu")
		(net "M_C_DQ<22>")
	)
	(arc
		(start 242.826794 -55.390542)
		(mid 243.032415 -55.600465)
		(end 243.313712 -55.685436)
		(width 0.0889)
		(layer "In11.Cu")
		(net "M_C_DQ<22>")
	)
	(arc
		(start 239.061244 -53.20919)
		(mid 239.252886 -53.266356)
		(end 239.392968 -53.409088)
		(width 0.0889)
		(layer "In11.Cu")
		(net "M_C_DQ<22>")
	)
	(arc
		(start 238.205772 -52.71389)
		(mid 238.395701 -52.77176)
		(end 238.534448 -52.913788)
		(width 0.0889)
		(layer "In11.Cu")
		(net "M_C_DQ<22>")
	)
	(arc
		(start 241.632994 -54.694836)
		(mid 241.826844 -54.751186)
		(end 241.968528 -54.894988)
		(width 0.0889)
		(layer "In11.Cu")
		(net "M_C_DQ<22>")
	)
	(arc
		(start 240.251488 -53.904388)
		(mid 240.460096 -54.11632)
		(end 240.745518 -54.19979)
		(width 0.0889)
		(layer "In11.Cu")
		(net "M_C_DQ<22>")
	)
	(arc
		(start 242.480338 -55.19039)
		(mid 242.677499 -55.242349)
		(end 242.823492 -55.3847)
		(width 0.0889)
		(layer "In11.Cu")
		(net "M_C_DQ<22>")
	)
	(arc
		(start 243.34978 -55.685436)
		(mid 243.54363 -55.741786)
		(end 243.685314 -55.885588)
		(width 0.0889)
		(layer "In11.Cu")
		(net "M_C_DQ<22>")
	)
	(arc
		(start 237.729268 -50.63744)
		(mid 237.715729 -50.740891)
		(end 237.675928 -50.837338)
		(width 0.0889)
		(layer "In11.Cu")
		(net "M_C_DQ<22>")
	)
	(arc
		(start 237.675928 -51.827938)
		(mid 237.671599 -52.41111)
		(end 238.169958 -52.71389)
		(width 0.0889)
		(layer "In11.Cu")
		(net "M_C_DQ<22>")
	)
	(arc
		(start 237.675928 -51.427888)
		(mid 237.729398 -51.622951)
		(end 237.680754 -51.819302)
		(width 0.0889)
		(layer "In11.Cu")
		(net "M_C_DQ<22>")
	)
	(arc
		(start 238.534448 -52.913788)
		(mid 238.745161 -53.126867)
		(end 239.033304 -53.20919)
		(width 0.0889)
		(layer "In11.Cu")
		(net "M_C_DQ<22>")
	)
	(arc
		(start 241.110008 -54.399688)
		(mid 241.317012 -54.610552)
		(end 241.600228 -54.694836)
		(width 0.0889)
		(layer "In11.Cu")
		(net "M_C_DQ<22>")
	)
	(arc
		(start 240.778284 -54.19979)
		(mid 240.969926 -54.256956)
		(end 241.110008 -54.399688)
		(width 0.0889)
		(layer "In11.Cu")
		(net "M_C_DQ<22>")
	)
	(segment
		(start 245.627144 -60.047886)
		(end 245.055644 -60.047886)
		(width 0.0889)
		(layer "F.Cu")
		(net "M_C_DQ<21>")
	)
	(segment
		(start 215.100408 3.778758)
		(end 215.0999 3.778758)
		(width 0.1651)
		(layer "F.Cu")
		(net "M_C_DQ<21>")
	)
	(segment
		(start 215.0999 3.778758)
		(end 215.0999 2.514854)
		(width 0.1651)
		(layer "F.Cu")
		(net "M_C_DQ<21>")
	)
	(via
		(at 245.055644 -60.047886)
		(size 0.508)
		(drill 0.254)
		(layers "F.Cu" "B.Cu")
		(net "M_C_DQ<21>")
	)
	(via
		(at 215.873584 -3.076956)
		(size 0.508)
		(drill 0.254)
		(layers "F.Cu" "B.Cu")
		(net "M_C_DQ<21>")
	)
	(via
		(at 215.0999 2.514854)
		(size 0.508)
		(drill 0.254)
		(layers "F.Cu" "B.Cu")
		(net "M_C_DQ<21>")
	)
	(segment
		(start 215.950292 -1.021842)
		(end 215.949784 -1.021842)
		(width 0.1651)
		(layer "B.Cu")
		(net "M_C_DQ<21>")
	)
	(segment
		(start 215.949784 -3.000756)
		(end 215.873584 -3.076956)
		(width 0.1651)
		(layer "B.Cu")
		(net "M_C_DQ<21>")
	)
	(segment
		(start 215.949784 -1.021842)
		(end 215.949784 -3.000756)
		(width 0.1651)
		(layer "B.Cu")
		(net "M_C_DQ<21>")
	)
	(segment
		(start 233.313224 -52.055014)
		(end 233.364024 -52.105814)
		(width 0.0889)
		(layer "In11.Cu")
		(net "M_C_DQ<21>")
	)
	(segment
		(start 241.603784 -58.466736)
		(end 241.643408 -58.466736)
		(width 0.0889)
		(layer "In11.Cu")
		(net "M_C_DQ<21>")
	)
	(segment
		(start 216.1794 -4.750816)
		(end 216.1794 -7.160006)
		(width 0.14224)
		(layer "In11.Cu")
		(net "M_C_DQ<21>")
	)
	(segment
		(start 215.873584 -3.076956)
		(end 215.36914 -3.5814)
		(width 0.14224)
		(layer "In11.Cu")
		(net "M_C_DQ<21>")
	)
	(segment
		(start 215.36914 -3.5814)
		(end 215.36914 -3.940556)
		(width 0.14224)
		(layer "In11.Cu")
		(net "M_C_DQ<21>")
	)
	(segment
		(start 216.408 -21.16074)
		(end 216.25814 -21.3106)
		(width 0.14224)
		(layer "In11.Cu")
		(net "M_C_DQ<21>")
	)
	(segment
		(start 216.34704 -12.360656)
		(end 216.34704 -13.617956)
		(width 0.14224)
		(layer "In11.Cu")
		(net "M_C_DQ<21>")
	)
	(segment
		(start 216.34704 -18.503646)
		(end 216.25814 -18.592546)
		(width 0.14224)
		(layer "In11.Cu")
		(net "M_C_DQ<21>")
	)
	(segment
		(start 239.889792 -57.476136)
		(end 239.917732 -57.476136)
		(width 0.0889)
		(layer "In11.Cu")
		(net "M_C_DQ<21>")
	)
	(segment
		(start 216.25814 -18.592546)
		(end 216.25814 -19.10334)
		(width 0.14224)
		(layer "In11.Cu")
		(net "M_C_DQ<21>")
	)
	(segment
		(start 216.184988 0.53975)
		(end 216.381838 0.7366)
		(width 0.14224)
		(layer "In11.Cu")
		(net "M_C_DQ<21>")
	)
	(segment
		(start 215.670638 1.5494)
		(end 215.0999 2.120138)
		(width 0.14224)
		(layer "In11.Cu")
		(net "M_C_DQ<21>")
	)
	(segment
		(start 239.035082 -56.98109)
		(end 239.067848 -56.98109)
		(width 0.0889)
		(layer "In11.Cu")
		(net "M_C_DQ<21>")
	)
	(segment
		(start 216.408 -19.2532)
		(end 216.408 -21.16074)
		(width 0.14224)
		(layer "In11.Cu")
		(net "M_C_DQ<21>")
	)
	(segment
		(start 237.318042 -55.99049)
		(end 237.350808 -55.99049)
		(width 0.0889)
		(layer "In11.Cu")
		(net "M_C_DQ<21>")
	)
	(segment
		(start 243.613178 -59.348624)
		(end 243.904262 -59.218068)
		(width 0.0889)
		(layer "In11.Cu")
		(net "M_C_DQ<21>")
	)
	(segment
		(start 236.455712 -55.494936)
		(end 236.488478 -55.494936)
		(width 0.0889)
		(layer "In11.Cu")
		(net "M_C_DQ<21>")
	)
	(segment
		(start 242.469162 -58.962036)
		(end 242.498118 -58.962036)
		(width 0.0889)
		(layer "In11.Cu")
		(net "M_C_DQ<21>")
	)
	(segment
		(start 216.34704 -7.327646)
		(end 216.34704 -8.902446)
		(width 0.14224)
		(layer "In11.Cu")
		(net "M_C_DQ<21>")
	)
	(segment
		(start 216.28354 -16.865346)
		(end 216.34704 -16.928846)
		(width 0.14224)
		(layer "In11.Cu")
		(net "M_C_DQ<21>")
	)
	(segment
		(start 216.25814 -11.684)
		(end 216.25814 -12.271756)
		(width 0.14224)
		(layer "In11.Cu")
		(net "M_C_DQ<21>")
	)
	(segment
		(start 234.742482 -54.504336)
		(end 234.771438 -54.504336)
		(width 0.0889)
		(layer "In11.Cu")
		(net "M_C_DQ<21>")
	)
	(segment
		(start 233.5022 -52.736242)
		(end 233.548428 -52.818284)
		(width 0.0889)
		(layer "In11.Cu")
		(net "M_C_DQ<21>")
	)
	(segment
		(start 216.34704 -23.219156)
		(end 216.342722 -23.223474)
		(width 0.14224)
		(layer "In11.Cu")
		(net "M_C_DQ<21>")
	)
	(segment
		(start 216.25814 -21.872956)
		(end 216.34704 -21.961856)
		(width 0.14224)
		(layer "In11.Cu")
		(net "M_C_DQ<21>")
	)
	(segment
		(start 244.138704 -59.15279)
		(end 244.21211 -59.15279)
		(width 0.0889)
		(layer "In11.Cu")
		(net "M_C_DQ<21>")
	)
	(segment
		(start 216.342722 -27.675078)
		(end 217.3478 -28.680156)
		(width 0.14224)
		(layer "In11.Cu")
		(net "M_C_DQ<21>")
	)
	(segment
		(start 243.904262 -59.218068)
		(end 244.138704 -59.15279)
		(width 0.0889)
		(layer "In11.Cu")
		(net "M_C_DQ<21>")
	)
	(segment
		(start 233.883962 -53.018436)
		(end 233.916728 -53.018436)
		(width 0.0889)
		(layer "In11.Cu")
		(net "M_C_DQ<21>")
	)
	(segment
		(start 244.560598 -59.382152)
		(end 245.055644 -60.047886)
		(width 0.0889)
		(layer "In11.Cu")
		(net "M_C_DQ<21>")
	)
	(segment
		(start 216.34704 -8.902446)
		(end 216.25814 -8.991346)
		(width 0.14224)
		(layer "In11.Cu")
		(net "M_C_DQ<21>")
	)
	(segment
		(start 235.601002 -54.99989)
		(end 235.633768 -54.99989)
		(width 0.0889)
		(layer "In11.Cu")
		(net "M_C_DQ<21>")
	)
	(segment
		(start 216.408 -9.6266)
		(end 216.408 -11.53414)
		(width 0.14224)
		(layer "In11.Cu")
		(net "M_C_DQ<21>")
	)
	(segment
		(start 216.25814 -12.271756)
		(end 216.34704 -12.360656)
		(width 0.14224)
		(layer "In11.Cu")
		(net "M_C_DQ<21>")
	)
	(segment
		(start 233.493564 -52.514754)
		(end 233.493564 -52.721002)
		(width 0.0889)
		(layer "In11.Cu")
		(net "M_C_DQ<21>")
	)
	(segment
		(start 215.873584 -3.076956)
		(end 216.184988 -2.765552)
		(width 0.14224)
		(layer "In11.Cu")
		(net "M_C_DQ<21>")
	)
	(segment
		(start 216.34704 -13.617956)
		(end 216.28354 -13.681456)
		(width 0.14224)
		(layer "In11.Cu")
		(net "M_C_DQ<21>")
	)
	(segment
		(start 233.313224 -51.982624)
		(end 233.313224 -52.055014)
		(width 0.14224)
		(layer "In11.Cu")
		(net "M_C_DQ<21>")
	)
	(segment
		(start 215.0999 2.120138)
		(end 215.0999 2.514854)
		(width 0.14224)
		(layer "In11.Cu")
		(net "M_C_DQ<21>")
	)
	(segment
		(start 240.745264 -57.971436)
		(end 240.781078 -57.971436)
		(width 0.0889)
		(layer "In11.Cu")
		(net "M_C_DQ<21>")
	)
	(segment
		(start 227.999798 -46.669198)
		(end 233.313224 -51.982624)
		(width 0.14224)
		(layer "In11.Cu")
		(net "M_C_DQ<21>")
	)
	(segment
		(start 244.543834 -59.352688)
		(end 244.560598 -59.382152)
		(width 0.0889)
		(layer "In11.Cu")
		(net "M_C_DQ<21>")
	)
	(segment
		(start 233.364024 -52.385214)
		(end 233.493564 -52.514754)
		(width 0.0889)
		(layer "In11.Cu")
		(net "M_C_DQ<21>")
	)
	(segment
		(start 216.25814 -8.991346)
		(end 216.25814 -9.47674)
		(width 0.14224)
		(layer "In11.Cu")
		(net "M_C_DQ<21>")
	)
	(segment
		(start 216.381838 0.7366)
		(end 216.381838 1.149096)
		(width 0.14224)
		(layer "In11.Cu")
		(net "M_C_DQ<21>")
	)
	(segment
		(start 216.28354 -13.681456)
		(end 216.28354 -16.865346)
		(width 0.14224)
		(layer "In11.Cu")
		(net "M_C_DQ<21>")
	)
	(segment
		(start 216.381838 1.149096)
		(end 215.981534 1.5494)
		(width 0.14224)
		(layer "In11.Cu")
		(net "M_C_DQ<21>")
	)
	(segment
		(start 217.3478 -28.680156)
		(end 217.3478 -34.71926)
		(width 0.14224)
		(layer "In11.Cu")
		(net "M_C_DQ<21>")
	)
	(segment
		(start 227.999798 -45.371258)
		(end 227.999798 -46.669198)
		(width 0.14224)
		(layer "In11.Cu")
		(net "M_C_DQ<21>")
	)
	(segment
		(start 215.36914 -3.940556)
		(end 216.1794 -4.750816)
		(width 0.14224)
		(layer "In11.Cu")
		(net "M_C_DQ<21>")
	)
	(segment
		(start 216.34704 -16.928846)
		(end 216.34704 -18.503646)
		(width 0.14224)
		(layer "In11.Cu")
		(net "M_C_DQ<21>")
	)
	(segment
		(start 233.364024 -52.105814)
		(end 233.364024 -52.385214)
		(width 0.0889)
		(layer "In11.Cu")
		(net "M_C_DQ<21>")
	)
	(segment
		(start 238.172752 -56.485536)
		(end 238.205518 -56.485536)
		(width 0.0889)
		(layer "In11.Cu")
		(net "M_C_DQ<21>")
	)
	(segment
		(start 216.25814 -21.3106)
		(end 216.25814 -21.872956)
		(width 0.14224)
		(layer "In11.Cu")
		(net "M_C_DQ<21>")
	)
	(segment
		(start 216.1794 -7.160006)
		(end 216.34704 -7.327646)
		(width 0.14224)
		(layer "In11.Cu")
		(net "M_C_DQ<21>")
	)
	(segment
		(start 233.493564 -52.721002)
		(end 233.5022 -52.736242)
		(width 0.0889)
		(layer "In11.Cu")
		(net "M_C_DQ<21>")
	)
	(segment
		(start 242.992148 -59.257184)
		(end 242.99545 -59.263026)
		(width 0.0889)
		(layer "In11.Cu")
		(net "M_C_DQ<21>")
	)
	(segment
		(start 216.25814 -19.10334)
		(end 216.408 -19.2532)
		(width 0.14224)
		(layer "In11.Cu")
		(net "M_C_DQ<21>")
	)
	(segment
		(start 216.25814 -9.47674)
		(end 216.408 -9.6266)
		(width 0.14224)
		(layer "In11.Cu")
		(net "M_C_DQ<21>")
	)
	(segment
		(start 216.408 -11.53414)
		(end 216.25814 -11.684)
		(width 0.14224)
		(layer "In11.Cu")
		(net "M_C_DQ<21>")
	)
	(segment
		(start 215.981534 1.5494)
		(end 215.670638 1.5494)
		(width 0.14224)
		(layer "In11.Cu")
		(net "M_C_DQ<21>")
	)
	(segment
		(start 216.34704 -21.961856)
		(end 216.34704 -23.219156)
		(width 0.14224)
		(layer "In11.Cu")
		(net "M_C_DQ<21>")
	)
	(segment
		(start 217.3478 -34.71926)
		(end 227.999798 -45.371258)
		(width 0.14224)
		(layer "In11.Cu")
		(net "M_C_DQ<21>")
	)
	(segment
		(start 216.184988 -2.765552)
		(end 216.184988 0.53975)
		(width 0.14224)
		(layer "In11.Cu")
		(net "M_C_DQ<21>")
	)
	(segment
		(start 216.342722 -23.223474)
		(end 216.342722 -27.675078)
		(width 0.14224)
		(layer "In11.Cu")
		(net "M_C_DQ<21>")
	)
	(arc
		(start 242.99545 -59.263026)
		(mid 243.283847 -59.453811)
		(end 243.613178 -59.348624)
		(width 0.0889)
		(layer "In11.Cu")
		(net "M_C_DQ<21>")
	)
	(arc
		(start 237.350808 -55.99049)
		(mid 237.634025 -56.074771)
		(end 237.841028 -56.285638)
		(width 0.0889)
		(layer "In11.Cu")
		(net "M_C_DQ<21>")
	)
	(arc
		(start 240.416588 -57.771538)
		(mid 240.555332 -57.913571)
		(end 240.745264 -57.971436)
		(width 0.0889)
		(layer "In11.Cu")
		(net "M_C_DQ<21>")
	)
	(arc
		(start 239.067848 -56.98109)
		(mid 239.351065 -57.065371)
		(end 239.558068 -57.276238)
		(width 0.0889)
		(layer "In11.Cu")
		(net "M_C_DQ<21>")
	)
	(arc
		(start 238.699548 -56.780938)
		(mid 238.841231 -56.924742)
		(end 239.035082 -56.98109)
		(width 0.0889)
		(layer "In11.Cu")
		(net "M_C_DQ<21>")
	)
	(arc
		(start 239.917732 -57.476136)
		(mid 240.205877 -57.558455)
		(end 240.416588 -57.771538)
		(width 0.0889)
		(layer "In11.Cu")
		(net "M_C_DQ<21>")
	)
	(arc
		(start 236.982508 -55.790338)
		(mid 237.124191 -55.934142)
		(end 237.318042 -55.99049)
		(width 0.0889)
		(layer "In11.Cu")
		(net "M_C_DQ<21>")
	)
	(arc
		(start 235.265468 -54.799738)
		(mid 235.407151 -54.943542)
		(end 235.601002 -54.99989)
		(width 0.0889)
		(layer "In11.Cu")
		(net "M_C_DQ<21>")
	)
	(arc
		(start 240.781078 -57.971436)
		(mid 241.066502 -58.054903)
		(end 241.275108 -58.266838)
		(width 0.0889)
		(layer "In11.Cu")
		(net "M_C_DQ<21>")
	)
	(arc
		(start 233.548428 -52.818284)
		(mid 233.690111 -52.962088)
		(end 233.883962 -53.018436)
		(width 0.0889)
		(layer "In11.Cu")
		(net "M_C_DQ<21>")
	)
	(arc
		(start 237.841028 -56.285638)
		(mid 237.981107 -56.428374)
		(end 238.172752 -56.485536)
		(width 0.0889)
		(layer "In11.Cu")
		(net "M_C_DQ<21>")
	)
	(arc
		(start 241.643408 -58.466736)
		(mid 241.926625 -58.551017)
		(end 242.133628 -58.761884)
		(width 0.0889)
		(layer "In11.Cu")
		(net "M_C_DQ<21>")
	)
	(arc
		(start 234.771438 -54.504336)
		(mid 235.056862 -54.587803)
		(end 235.265468 -54.799738)
		(width 0.0889)
		(layer "In11.Cu")
		(net "M_C_DQ<21>")
	)
	(arc
		(start 244.21211 -59.15279)
		(mid 244.403752 -59.209956)
		(end 244.543834 -59.352688)
		(width 0.0889)
		(layer "In11.Cu")
		(net "M_C_DQ<21>")
	)
	(arc
		(start 236.123988 -55.295038)
		(mid 236.264067 -55.437774)
		(end 236.455712 -55.494936)
		(width 0.0889)
		(layer "In11.Cu")
		(net "M_C_DQ<21>")
	)
	(arc
		(start 234.406948 -53.904388)
		(mid 234.404365 -54.299635)
		(end 234.742482 -54.504336)
		(width 0.0889)
		(layer "In11.Cu")
		(net "M_C_DQ<21>")
	)
	(arc
		(start 236.488478 -55.494936)
		(mid 236.773902 -55.578403)
		(end 236.982508 -55.790338)
		(width 0.0889)
		(layer "In11.Cu")
		(net "M_C_DQ<21>")
	)
	(arc
		(start 238.205518 -56.485536)
		(mid 238.490942 -56.569003)
		(end 238.699548 -56.780938)
		(width 0.0889)
		(layer "In11.Cu")
		(net "M_C_DQ<21>")
	)
	(arc
		(start 235.633768 -54.99989)
		(mid 235.916985 -55.084171)
		(end 236.123988 -55.295038)
		(width 0.0889)
		(layer "In11.Cu")
		(net "M_C_DQ<21>")
	)
	(arc
		(start 241.275108 -58.266838)
		(mid 241.413852 -58.408871)
		(end 241.603784 -58.466736)
		(width 0.0889)
		(layer "In11.Cu")
		(net "M_C_DQ<21>")
	)
	(arc
		(start 233.916728 -53.018436)
		(mid 234.412205 -53.322879)
		(end 234.406948 -53.904388)
		(width 0.0889)
		(layer "In11.Cu")
		(net "M_C_DQ<21>")
	)
	(arc
		(start 242.498118 -58.962036)
		(mid 242.78348 -59.045424)
		(end 242.992148 -59.257184)
		(width 0.0889)
		(layer "In11.Cu")
		(net "M_C_DQ<21>")
	)
	(arc
		(start 239.558068 -57.276238)
		(mid 239.698147 -57.418974)
		(end 239.889792 -57.476136)
		(width 0.0889)
		(layer "In11.Cu")
		(net "M_C_DQ<21>")
	)
	(arc
		(start 242.133628 -58.761884)
		(mid 242.275311 -58.905688)
		(end 242.469162 -58.962036)
		(width 0.0889)
		(layer "In11.Cu")
		(net "M_C_DQ<21>")
	)
	(segment
		(start 244.768624 -59.55284)
		(end 244.197124 -59.55284)
		(width 0.0889)
		(layer "F.Cu")
		(net "M_C_DQ<20>")
	)
	(segment
		(start 215.950292 -0.821182)
		(end 215.949784 -0.821182)
		(width 0.1651)
		(layer "F.Cu")
		(net "M_C_DQ<20>")
	)
	(segment
		(start 215.949784 -0.821182)
		(end 215.949784 0.510032)
		(width 0.1651)
		(layer "F.Cu")
		(net "M_C_DQ<20>")
	)
	(segment
		(start 215.949784 0.510032)
		(end 215.85174 1.0414)
		(width 0.1651)
		(layer "F.Cu")
		(net "M_C_DQ<20>")
	)
	(via
		(at 215.85174 1.0414)
		(size 0.508)
		(drill 0.254)
		(layers "F.Cu" "B.Cu")
		(net "M_C_DQ<20>")
	)
	(via
		(at 215.0999 -4.357878)
		(size 0.508)
		(drill 0.254)
		(layers "F.Cu" "B.Cu")
		(net "M_C_DQ<20>")
	)
	(via
		(at 244.197124 -59.55284)
		(size 0.508)
		(drill 0.254)
		(layers "F.Cu" "B.Cu")
		(net "M_C_DQ<20>")
	)
	(segment
		(start 215.0999 -5.621782)
		(end 215.0999 -4.357878)
		(width 0.1651)
		(layer "B.Cu")
		(net "M_C_DQ<20>")
	)
	(segment
		(start 215.100408 -5.621782)
		(end 215.0999 -5.621782)
		(width 0.1651)
		(layer "B.Cu")
		(net "M_C_DQ<20>")
	)
	(segment
		(start 215.36914 -13.567156)
		(end 215.59774 -13.795756)
		(width 0.14224)
		(layer "In11.Cu")
		(net "M_C_DQ<20>")
	)
	(segment
		(start 232.838752 -52.498752)
		(end 232.838752 -52.52974)
		(width 0.14224)
		(layer "In11.Cu")
		(net "M_C_DQ<20>")
	)
	(segment
		(start 235.594398 -55.19039)
		(end 235.627164 -55.19039)
		(width 0.0889)
		(layer "In11.Cu")
		(net "M_C_DQ<20>")
	)
	(segment
		(start 215.575388 -2.616454)
		(end 215.575388 -2.141728)
		(width 0.14224)
		(layer "In11.Cu")
		(net "M_C_DQ<20>")
	)
	(segment
		(start 215.62314 -18.99666)
		(end 215.4428 -19.177)
		(width 0.14224)
		(layer "In11.Cu")
		(net "M_C_DQ<20>")
	)
	(segment
		(start 215.0999 -4.357878)
		(end 214.864188 -4.122166)
		(width 0.14224)
		(layer "In11.Cu")
		(net "M_C_DQ<20>")
	)
	(segment
		(start 215.0999 -4.357878)
		(end 215.0999 -4.609846)
		(width 0.14224)
		(layer "In11.Cu")
		(net "M_C_DQ<20>")
	)
	(segment
		(start 227.384356 -47.044356)
		(end 232.838752 -52.498752)
		(width 0.14224)
		(layer "In11.Cu")
		(net "M_C_DQ<20>")
	)
	(segment
		(start 239.028478 -57.17159)
		(end 239.061244 -57.17159)
		(width 0.0889)
		(layer "In11.Cu")
		(net "M_C_DQ<20>")
	)
	(segment
		(start 215.211406 -0.076454)
		(end 215.575388 0.287528)
		(width 0.14224)
		(layer "In11.Cu")
		(net "M_C_DQ<20>")
	)
	(segment
		(start 227.384356 -45.800772)
		(end 227.384356 -47.044356)
		(width 0.14224)
		(layer "In11.Cu")
		(net "M_C_DQ<20>")
	)
	(segment
		(start 215.36914 -18.313146)
		(end 215.62314 -18.567146)
		(width 0.14224)
		(layer "In11.Cu")
		(net "M_C_DQ<20>")
	)
	(segment
		(start 215.36914 -17.066514)
		(end 215.36914 -18.313146)
		(width 0.14224)
		(layer "In11.Cu")
		(net "M_C_DQ<20>")
	)
	(segment
		(start 238.166148 -56.676036)
		(end 238.198914 -56.676036)
		(width 0.0889)
		(layer "In11.Cu")
		(net "M_C_DQ<20>")
	)
	(segment
		(start 215.4428 -19.177)
		(end 215.4428 -21.20646)
		(width 0.14224)
		(layer "In11.Cu")
		(net "M_C_DQ<20>")
	)
	(segment
		(start 236.449108 -55.685436)
		(end 236.481874 -55.685436)
		(width 0.0889)
		(layer "In11.Cu")
		(net "M_C_DQ<20>")
	)
	(segment
		(start 215.0999 -4.609846)
		(end 215.59774 -5.107686)
		(width 0.14224)
		(layer "In11.Cu")
		(net "M_C_DQ<20>")
	)
	(segment
		(start 216.7128 -35.129216)
		(end 227.384356 -45.800772)
		(width 0.14224)
		(layer "In11.Cu")
		(net "M_C_DQ<20>")
	)
	(segment
		(start 242.467384 -59.15279)
		(end 242.480338 -59.15279)
		(width 0.0889)
		(layer "In11.Cu")
		(net "M_C_DQ<20>")
	)
	(segment
		(start 215.59774 -7.236714)
		(end 215.36914 -7.465314)
		(width 0.14224)
		(layer "In11.Cu")
		(net "M_C_DQ<20>")
	)
	(segment
		(start 215.62314 -8.965946)
		(end 215.62314 -9.4488)
		(width 0.14224)
		(layer "In11.Cu")
		(net "M_C_DQ<20>")
	)
	(segment
		(start 241.604038 -58.65749)
		(end 241.639852 -58.65749)
		(width 0.0889)
		(layer "In11.Cu")
		(net "M_C_DQ<20>")
	)
	(segment
		(start 233.092498 -52.52974)
		(end 233.256328 -52.69357)
		(width 0.0889)
		(layer "In11.Cu")
		(net "M_C_DQ<20>")
	)
	(segment
		(start 215.592406 -0.762)
		(end 215.211406 -0.381)
		(width 0.14224)
		(layer "In11.Cu")
		(net "M_C_DQ<20>")
	)
	(segment
		(start 215.575388 -2.141728)
		(end 215.224106 -1.790446)
		(width 0.14224)
		(layer "In11.Cu")
		(net "M_C_DQ<20>")
	)
	(segment
		(start 215.224106 -1.4351)
		(end 215.592406 -1.0668)
		(width 0.14224)
		(layer "In11.Cu")
		(net "M_C_DQ<20>")
	)
	(segment
		(start 243.42979 -59.641232)
		(end 244.197124 -59.55284)
		(width 0.0889)
		(layer "In11.Cu")
		(net "M_C_DQ<20>")
	)
	(segment
		(start 215.6968 -28.074112)
		(end 216.7128 -29.090112)
		(width 0.14224)
		(layer "In11.Cu")
		(net "M_C_DQ<20>")
	)
	(segment
		(start 215.224106 -1.790446)
		(end 215.224106 -1.4351)
		(width 0.14224)
		(layer "In11.Cu")
		(net "M_C_DQ<20>")
	)
	(segment
		(start 240.741708 -58.16219)
		(end 240.781332 -58.16219)
		(width 0.0889)
		(layer "In11.Cu")
		(net "M_C_DQ<20>")
	)
	(segment
		(start 215.211406 -0.381)
		(end 215.211406 -0.076454)
		(width 0.14224)
		(layer "In11.Cu")
		(net "M_C_DQ<20>")
	)
	(segment
		(start 215.6968 -23.496016)
		(end 215.6968 -28.074112)
		(width 0.14224)
		(layer "In11.Cu")
		(net "M_C_DQ<20>")
	)
	(segment
		(start 215.592406 -1.0668)
		(end 215.592406 -0.762)
		(width 0.14224)
		(layer "In11.Cu")
		(net "M_C_DQ<20>")
	)
	(segment
		(start 215.62314 -18.567146)
		(end 215.62314 -18.99666)
		(width 0.14224)
		(layer "In11.Cu")
		(net "M_C_DQ<20>")
	)
	(segment
		(start 233.873548 -53.208936)
		(end 233.906314 -53.208936)
		(width 0.0889)
		(layer "In11.Cu")
		(net "M_C_DQ<20>")
	)
	(segment
		(start 215.4428 -11.5824)
		(end 215.62314 -11.76274)
		(width 0.14224)
		(layer "In11.Cu")
		(net "M_C_DQ<20>")
	)
	(segment
		(start 237.311438 -56.18099)
		(end 237.344204 -56.18099)
		(width 0.0889)
		(layer "In11.Cu")
		(net "M_C_DQ<20>")
	)
	(segment
		(start 214.864188 -4.122166)
		(end 214.864188 -3.327654)
		(width 0.14224)
		(layer "In11.Cu")
		(net "M_C_DQ<20>")
	)
	(segment
		(start 234.732068 -54.694836)
		(end 234.764834 -54.694836)
		(width 0.0889)
		(layer "In11.Cu")
		(net "M_C_DQ<20>")
	)
	(segment
		(start 215.575388 0.287528)
		(end 215.575388 0.765048)
		(width 0.14224)
		(layer "In11.Cu")
		(net "M_C_DQ<20>")
	)
	(segment
		(start 215.36914 -8.711946)
		(end 215.62314 -8.965946)
		(width 0.14224)
		(layer "In11.Cu")
		(net "M_C_DQ<20>")
	)
	(segment
		(start 215.36914 -12.347956)
		(end 215.36914 -13.567156)
		(width 0.14224)
		(layer "In11.Cu")
		(net "M_C_DQ<20>")
	)
	(segment
		(start 215.4428 -9.62914)
		(end 215.4428 -11.5824)
		(width 0.14224)
		(layer "In11.Cu")
		(net "M_C_DQ<20>")
	)
	(segment
		(start 215.575388 0.765048)
		(end 215.85174 1.0414)
		(width 0.14224)
		(layer "In11.Cu")
		(net "M_C_DQ<20>")
	)
	(segment
		(start 215.36914 -21.949156)
		(end 215.36914 -23.168356)
		(width 0.14224)
		(layer "In11.Cu")
		(net "M_C_DQ<20>")
	)
	(segment
		(start 215.59774 -5.107686)
		(end 215.59774 -7.236714)
		(width 0.14224)
		(layer "In11.Cu")
		(net "M_C_DQ<20>")
	)
	(segment
		(start 215.36914 -23.168356)
		(end 215.6968 -23.496016)
		(width 0.14224)
		(layer "In11.Cu")
		(net "M_C_DQ<20>")
	)
	(segment
		(start 232.838752 -52.52974)
		(end 233.092498 -52.52974)
		(width 0.0889)
		(layer "In11.Cu")
		(net "M_C_DQ<20>")
	)
	(segment
		(start 243.313712 -59.647836)
		(end 243.360194 -59.647836)
		(width 0.0889)
		(layer "In11.Cu")
		(net "M_C_DQ<20>")
	)
	(segment
		(start 216.7128 -29.090112)
		(end 216.7128 -35.129216)
		(width 0.14224)
		(layer "In11.Cu")
		(net "M_C_DQ<20>")
	)
	(segment
		(start 215.62314 -21.695156)
		(end 215.36914 -21.949156)
		(width 0.14224)
		(layer "In11.Cu")
		(net "M_C_DQ<20>")
	)
	(segment
		(start 215.62314 -21.3868)
		(end 215.62314 -21.695156)
		(width 0.14224)
		(layer "In11.Cu")
		(net "M_C_DQ<20>")
	)
	(segment
		(start 233.3498 -52.855622)
		(end 233.383328 -52.913788)
		(width 0.0889)
		(layer "In11.Cu")
		(net "M_C_DQ<20>")
	)
	(segment
		(start 215.59774 -13.795756)
		(end 215.59774 -16.837914)
		(width 0.14224)
		(layer "In11.Cu")
		(net "M_C_DQ<20>")
	)
	(segment
		(start 242.823492 -59.3471)
		(end 242.826794 -59.352942)
		(width 0.0889)
		(layer "In11.Cu")
		(net "M_C_DQ<20>")
	)
	(segment
		(start 215.62314 -11.76274)
		(end 215.62314 -12.093956)
		(width 0.14224)
		(layer "In11.Cu")
		(net "M_C_DQ<20>")
	)
	(segment
		(start 215.36914 -7.465314)
		(end 215.36914 -8.711946)
		(width 0.14224)
		(layer "In11.Cu")
		(net "M_C_DQ<20>")
	)
	(segment
		(start 239.891824 -57.66689)
		(end 239.915954 -57.66689)
		(width 0.0889)
		(layer "In11.Cu")
		(net "M_C_DQ<20>")
	)
	(segment
		(start 215.62314 -9.4488)
		(end 215.4428 -9.62914)
		(width 0.14224)
		(layer "In11.Cu")
		(net "M_C_DQ<20>")
	)
	(segment
		(start 215.59774 -16.837914)
		(end 215.36914 -17.066514)
		(width 0.14224)
		(layer "In11.Cu")
		(net "M_C_DQ<20>")
	)
	(segment
		(start 215.62314 -12.093956)
		(end 215.36914 -12.347956)
		(width 0.14224)
		(layer "In11.Cu")
		(net "M_C_DQ<20>")
	)
	(segment
		(start 233.256328 -52.69357)
		(end 233.3498 -52.855622)
		(width 0.0889)
		(layer "In11.Cu")
		(net "M_C_DQ<20>")
	)
	(segment
		(start 215.4428 -21.20646)
		(end 215.62314 -21.3868)
		(width 0.14224)
		(layer "In11.Cu")
		(net "M_C_DQ<20>")
	)
	(segment
		(start 214.864188 -3.327654)
		(end 215.575388 -2.616454)
		(width 0.14224)
		(layer "In11.Cu")
		(net "M_C_DQ<20>")
	)
	(arc
		(start 233.906314 -53.208936)
		(mid 234.244429 -53.413638)
		(end 234.241848 -53.808884)
		(width 0.0889)
		(layer "In11.Cu")
		(net "M_C_DQ<20>")
	)
	(arc
		(start 239.392968 -57.371488)
		(mid 239.603681 -57.584567)
		(end 239.891824 -57.66689)
		(width 0.0889)
		(layer "In11.Cu")
		(net "M_C_DQ<20>")
	)
	(arc
		(start 236.481874 -55.685436)
		(mid 236.675724 -55.741786)
		(end 236.817408 -55.885588)
		(width 0.0889)
		(layer "In11.Cu")
		(net "M_C_DQ<20>")
	)
	(arc
		(start 241.110008 -58.362088)
		(mid 241.318616 -58.57402)
		(end 241.604038 -58.65749)
		(width 0.0889)
		(layer "In11.Cu")
		(net "M_C_DQ<20>")
	)
	(arc
		(start 238.534448 -56.876188)
		(mid 238.743056 -57.08812)
		(end 239.028478 -57.17159)
		(width 0.0889)
		(layer "In11.Cu")
		(net "M_C_DQ<20>")
	)
	(arc
		(start 243.360194 -59.647836)
		(mid 243.39509 -59.64557)
		(end 243.42979 -59.641232)
		(width 0.0889)
		(layer "In11.Cu")
		(net "M_C_DQ<20>")
	)
	(arc
		(start 235.100368 -54.894988)
		(mid 235.308976 -55.10692)
		(end 235.594398 -55.19039)
		(width 0.0889)
		(layer "In11.Cu")
		(net "M_C_DQ<20>")
	)
	(arc
		(start 239.061244 -57.17159)
		(mid 239.252886 -57.228756)
		(end 239.392968 -57.371488)
		(width 0.0889)
		(layer "In11.Cu")
		(net "M_C_DQ<20>")
	)
	(arc
		(start 235.958888 -55.390288)
		(mid 236.165892 -55.601152)
		(end 236.449108 -55.685436)
		(width 0.0889)
		(layer "In11.Cu")
		(net "M_C_DQ<20>")
	)
	(arc
		(start 234.764834 -54.694836)
		(mid 234.958684 -54.751186)
		(end 235.100368 -54.894988)
		(width 0.0889)
		(layer "In11.Cu")
		(net "M_C_DQ<20>")
	)
	(arc
		(start 237.675928 -56.380888)
		(mid 237.882932 -56.591752)
		(end 238.166148 -56.676036)
		(width 0.0889)
		(layer "In11.Cu")
		(net "M_C_DQ<20>")
	)
	(arc
		(start 234.241848 -53.808884)
		(mid 234.236594 -54.390392)
		(end 234.732068 -54.694836)
		(width 0.0889)
		(layer "In11.Cu")
		(net "M_C_DQ<20>")
	)
	(arc
		(start 242.480338 -59.15279)
		(mid 242.677499 -59.204749)
		(end 242.823492 -59.3471)
		(width 0.0889)
		(layer "In11.Cu")
		(net "M_C_DQ<20>")
	)
	(arc
		(start 240.251488 -57.867042)
		(mid 240.458492 -58.077906)
		(end 240.741708 -58.16219)
		(width 0.0889)
		(layer "In11.Cu")
		(net "M_C_DQ<20>")
	)
	(arc
		(start 242.826794 -59.352942)
		(mid 243.032415 -59.562865)
		(end 243.313712 -59.647836)
		(width 0.0889)
		(layer "In11.Cu")
		(net "M_C_DQ<20>")
	)
	(arc
		(start 235.627164 -55.19039)
		(mid 235.818806 -55.247556)
		(end 235.958888 -55.390288)
		(width 0.0889)
		(layer "In11.Cu")
		(net "M_C_DQ<20>")
	)
	(arc
		(start 241.639852 -58.65749)
		(mid 241.829781 -58.71536)
		(end 241.968528 -58.857388)
		(width 0.0889)
		(layer "In11.Cu")
		(net "M_C_DQ<20>")
	)
	(arc
		(start 238.198914 -56.676036)
		(mid 238.392764 -56.732386)
		(end 238.534448 -56.876188)
		(width 0.0889)
		(layer "In11.Cu")
		(net "M_C_DQ<20>")
	)
	(arc
		(start 236.817408 -55.885588)
		(mid 237.026016 -56.09752)
		(end 237.311438 -56.18099)
		(width 0.0889)
		(layer "In11.Cu")
		(net "M_C_DQ<20>")
	)
	(arc
		(start 240.781332 -58.16219)
		(mid 240.971261 -58.22006)
		(end 241.110008 -58.362088)
		(width 0.0889)
		(layer "In11.Cu")
		(net "M_C_DQ<20>")
	)
	(arc
		(start 239.915954 -57.66689)
		(mid 240.109804 -57.72324)
		(end 240.251488 -57.867042)
		(width 0.0889)
		(layer "In11.Cu")
		(net "M_C_DQ<20>")
	)
	(arc
		(start 237.344204 -56.18099)
		(mid 237.535846 -56.238156)
		(end 237.675928 -56.380888)
		(width 0.0889)
		(layer "In11.Cu")
		(net "M_C_DQ<20>")
	)
	(arc
		(start 241.968528 -58.857388)
		(mid 242.179241 -59.070467)
		(end 242.467384 -59.15279)
		(width 0.0889)
		(layer "In11.Cu")
		(net "M_C_DQ<20>")
	)
	(arc
		(start 233.383328 -52.913788)
		(mid 233.590332 -53.124652)
		(end 233.873548 -53.208936)
		(width 0.0889)
		(layer "In11.Cu")
		(net "M_C_DQ<20>")
	)
	(segment
		(start 198.100442 3.778758)
		(end 198.099934 3.778758)
		(width 0.1651)
		(layer "F.Cu")
		(net "M_C_DQ<1>")
	)
	(segment
		(start 243.051838 -65.49644)
		(end 242.480338 -65.49644)
		(width 0.0889)
		(layer "F.Cu")
		(net "M_C_DQ<1>")
	)
	(segment
		(start 198.099934 3.778758)
		(end 198.099934 2.514854)
		(width 0.1651)
		(layer "F.Cu")
		(net "M_C_DQ<1>")
	)
	(via
		(at 198.099934 2.514854)
		(size 0.508)
		(drill 0.254)
		(layers "F.Cu" "B.Cu")
		(net "M_C_DQ<1>")
	)
	(via
		(at 198.772018 -3.076956)
		(size 0.508)
		(drill 0.254)
		(layers "F.Cu" "B.Cu")
		(net "M_C_DQ<1>")
	)
	(via
		(at 242.480338 -65.49644)
		(size 0.508)
		(drill 0.254)
		(layers "F.Cu" "B.Cu")
		(net "M_C_DQ<1>")
	)
	(segment
		(start 198.949818 -1.021842)
		(end 198.949818 -2.395982)
		(width 0.1651)
		(layer "B.Cu")
		(net "M_C_DQ<1>")
	)
	(segment
		(start 198.772018 -2.573782)
		(end 198.772018 -3.076956)
		(width 0.1651)
		(layer "B.Cu")
		(net "M_C_DQ<1>")
	)
	(segment
		(start 198.949818 -2.395982)
		(end 198.772018 -2.573782)
		(width 0.1651)
		(layer "B.Cu")
		(net "M_C_DQ<1>")
	)
	(segment
		(start 198.950326 -1.021842)
		(end 198.949818 -1.021842)
		(width 0.1651)
		(layer "B.Cu")
		(net "M_C_DQ<1>")
	)
	(segment
		(start 199.4154 -19.2024)
		(end 199.4154 -21.180552)
		(width 0.14224)
		(layer "In11.Cu")
		(net "M_C_DQ<1>")
	)
	(segment
		(start 198.9328 1.4986)
		(end 198.5772 1.4986)
		(width 0.14224)
		(layer "In11.Cu")
		(net "M_C_DQ<1>")
	)
	(segment
		(start 198.624952 -5.763006)
		(end 199.259952 -6.398006)
		(width 0.14224)
		(layer "In11.Cu")
		(net "M_C_DQ<1>")
	)
	(segment
		(start 231.553004 -65.81902)
		(end 231.630474 -65.89649)
		(width 0.0889)
		(layer "In11.Cu")
		(net "M_C_DQ<1>")
	)
	(segment
		(start 233.018838 -65.400936)
		(end 233.054398 -65.400936)
		(width 0.0889)
		(layer "In11.Cu")
		(net "M_C_DQ<1>")
	)
	(segment
		(start 198.5772 1.4986)
		(end 198.099934 1.975866)
		(width 0.14224)
		(layer "In11.Cu")
		(net "M_C_DQ<1>")
	)
	(segment
		(start 199.259952 -19.046952)
		(end 199.4154 -19.2024)
		(width 0.14224)
		(layer "In11.Cu")
		(net "M_C_DQ<1>")
	)
	(segment
		(start 199.302624 1.128776)
		(end 198.9328 1.4986)
		(width 0.14224)
		(layer "In11.Cu")
		(net "M_C_DQ<1>")
	)
	(segment
		(start 241.606832 -66.391536)
		(end 241.636804 -66.391536)
		(width 0.0889)
		(layer "In11.Cu")
		(net "M_C_DQ<1>")
	)
	(segment
		(start 240.748312 -66.08699)
		(end 240.864644 -66.08699)
		(width 0.0889)
		(layer "In11.Cu")
		(net "M_C_DQ<1>")
	)
	(segment
		(start 199.259952 -24.0284)
		(end 198.7804 -24.507952)
		(width 0.14224)
		(layer "In11.Cu")
		(net "M_C_DQ<1>")
	)
	(segment
		(start 199.14616 0.630936)
		(end 199.302624 0.7874)
		(width 0.14224)
		(layer "In11.Cu")
		(net "M_C_DQ<1>")
	)
	(segment
		(start 237.318042 -66.88709)
		(end 237.350808 -66.88709)
		(width 0.0889)
		(layer "In11.Cu")
		(net "M_C_DQ<1>")
	)
	(segment
		(start 241.968528 -66.191638)
		(end 241.985292 -66.162174)
		(width 0.0889)
		(layer "In11.Cu")
		(net "M_C_DQ<1>")
	)
	(segment
		(start 240.310416 -67.080384)
		(end 240.324894 -66.890392)
		(width 0.0889)
		(layer "In11.Cu")
		(net "M_C_DQ<1>")
	)
	(segment
		(start 238.172752 -67.382136)
		(end 238.205518 -67.382136)
		(width 0.0889)
		(layer "In11.Cu")
		(net "M_C_DQ<1>")
	)
	(segment
		(start 199.259952 -11.687048)
		(end 199.259952 -19.046952)
		(width 0.14224)
		(layer "In11.Cu")
		(net "M_C_DQ<1>")
	)
	(segment
		(start 202.93838 -41.750234)
		(end 203.69276 -42.504614)
		(width 0.14224)
		(layer "In11.Cu")
		(net "M_C_DQ<1>")
	)
	(segment
		(start 236.455712 -66.391536)
		(end 236.488478 -66.391536)
		(width 0.0889)
		(layer "In11.Cu")
		(net "M_C_DQ<1>")
	)
	(segment
		(start 234.735878 -65.400936)
		(end 234.771438 -65.400936)
		(width 0.0889)
		(layer "In11.Cu")
		(net "M_C_DQ<1>")
	)
	(segment
		(start 203.69276 -42.504614)
		(end 203.69276 -43.703494)
		(width 0.14224)
		(layer "In11.Cu")
		(net "M_C_DQ<1>")
	)
	(segment
		(start 198.772018 -3.076956)
		(end 198.245476 -3.603498)
		(width 0.14224)
		(layer "In11.Cu")
		(net "M_C_DQ<1>")
	)
	(segment
		(start 240.864644 -66.08699)
		(end 241.414554 -66.334132)
		(width 0.0889)
		(layer "In11.Cu")
		(net "M_C_DQ<1>")
	)
	(segment
		(start 198.7804 -24.507952)
		(end 198.7804 -38.506654)
		(width 0.14224)
		(layer "In11.Cu")
		(net "M_C_DQ<1>")
	)
	(segment
		(start 199.259952 -21.336)
		(end 199.259952 -24.0284)
		(width 0.14224)
		(layer "In11.Cu")
		(net "M_C_DQ<1>")
	)
	(segment
		(start 199.403716 -9.617964)
		(end 199.403716 -11.543284)
		(width 0.14224)
		(layer "In11.Cu")
		(net "M_C_DQ<1>")
	)
	(segment
		(start 198.772018 -3.076956)
		(end 199.14616 -2.702814)
		(width 0.14224)
		(layer "In11.Cu")
		(net "M_C_DQ<1>")
	)
	(segment
		(start 240.324894 -66.890392)
		(end 240.311178 -66.667126)
		(width 0.0889)
		(layer "In11.Cu")
		(net "M_C_DQ<1>")
	)
	(segment
		(start 198.099934 1.975866)
		(end 198.099934 2.514854)
		(width 0.14224)
		(layer "In11.Cu")
		(net "M_C_DQ<1>")
	)
	(segment
		(start 240.251488 -67.182238)
		(end 240.310416 -67.080384)
		(width 0.0889)
		(layer "In11.Cu")
		(net "M_C_DQ<1>")
	)
	(segment
		(start 203.69276 -43.703494)
		(end 225.808286 -65.81902)
		(width 0.14224)
		(layer "In11.Cu")
		(net "M_C_DQ<1>")
	)
	(segment
		(start 199.259952 -6.398006)
		(end 199.259952 -9.4742)
		(width 0.14224)
		(layer "In11.Cu")
		(net "M_C_DQ<1>")
	)
	(segment
		(start 199.302624 0.7874)
		(end 199.302624 1.128776)
		(width 0.14224)
		(layer "In11.Cu")
		(net "M_C_DQ<1>")
	)
	(segment
		(start 231.630474 -65.89649)
		(end 232.189274 -65.89649)
		(width 0.0889)
		(layer "In11.Cu")
		(net "M_C_DQ<1>")
	)
	(segment
		(start 202.552808 -41.750234)
		(end 202.93838 -41.750234)
		(width 0.14224)
		(layer "In11.Cu")
		(net "M_C_DQ<1>")
	)
	(segment
		(start 198.245476 -3.859276)
		(end 198.624952 -4.238752)
		(width 0.14224)
		(layer "In11.Cu")
		(net "M_C_DQ<1>")
	)
	(segment
		(start 231.062276 -65.81902)
		(end 231.553004 -65.81902)
		(width 0.0889)
		(layer "In11.Cu")
		(net "M_C_DQ<1>")
	)
	(segment
		(start 198.624952 -4.238752)
		(end 198.624952 -5.763006)
		(width 0.14224)
		(layer "In11.Cu")
		(net "M_C_DQ<1>")
	)
	(segment
		(start 199.403716 -11.543284)
		(end 199.259952 -11.687048)
		(width 0.14224)
		(layer "In11.Cu")
		(net "M_C_DQ<1>")
	)
	(segment
		(start 239.886998 -67.382136)
		(end 239.919764 -67.382136)
		(width 0.0889)
		(layer "In11.Cu")
		(net "M_C_DQ<1>")
	)
	(segment
		(start 199.259952 -9.4742)
		(end 199.403716 -9.617964)
		(width 0.14224)
		(layer "In11.Cu")
		(net "M_C_DQ<1>")
	)
	(segment
		(start 199.999346 -39.7256)
		(end 200.528174 -39.7256)
		(width 0.14224)
		(layer "In11.Cu")
		(net "M_C_DQ<1>")
	)
	(segment
		(start 240.311178 -66.667126)
		(end 240.375948 -66.385948)
		(width 0.0889)
		(layer "In11.Cu")
		(net "M_C_DQ<1>")
	)
	(segment
		(start 235.601002 -65.89649)
		(end 235.633768 -65.89649)
		(width 0.0889)
		(layer "In11.Cu")
		(net "M_C_DQ<1>")
	)
	(segment
		(start 198.245476 -3.603498)
		(end 198.245476 -3.859276)
		(width 0.14224)
		(layer "In11.Cu")
		(net "M_C_DQ<1>")
	)
	(segment
		(start 241.985292 -66.162174)
		(end 242.480338 -65.49644)
		(width 0.0889)
		(layer "In11.Cu")
		(net "M_C_DQ<1>")
	)
	(segment
		(start 198.7804 -38.506654)
		(end 199.999346 -39.7256)
		(width 0.14224)
		(layer "In11.Cu")
		(net "M_C_DQ<1>")
	)
	(segment
		(start 199.14616 -2.702814)
		(end 199.14616 0.630936)
		(width 0.14224)
		(layer "In11.Cu")
		(net "M_C_DQ<1>")
	)
	(segment
		(start 225.808286 -65.81902)
		(end 231.062276 -65.81902)
		(width 0.14224)
		(layer "In11.Cu")
		(net "M_C_DQ<1>")
	)
	(segment
		(start 199.4154 -21.180552)
		(end 199.259952 -21.336)
		(width 0.14224)
		(layer "In11.Cu")
		(net "M_C_DQ<1>")
	)
	(segment
		(start 200.528174 -39.7256)
		(end 202.552808 -41.750234)
		(width 0.14224)
		(layer "In11.Cu")
		(net "M_C_DQ<1>")
	)
	(arc
		(start 241.636804 -66.391536)
		(mid 241.828446 -66.33437)
		(end 241.968528 -66.191638)
		(width 0.0889)
		(layer "In11.Cu")
		(net "M_C_DQ<1>")
	)
	(arc
		(start 236.982508 -66.686938)
		(mid 237.124191 -66.830742)
		(end 237.318042 -66.88709)
		(width 0.0889)
		(layer "In11.Cu")
		(net "M_C_DQ<1>")
	)
	(arc
		(start 239.392968 -67.677538)
		(mid 239.601576 -67.465606)
		(end 239.886998 -67.382136)
		(width 0.0889)
		(layer "In11.Cu")
		(net "M_C_DQ<1>")
	)
	(arc
		(start 233.548428 -65.696338)
		(mid 233.895138 -65.896649)
		(end 234.241848 -65.696338)
		(width 0.0889)
		(layer "In11.Cu")
		(net "M_C_DQ<1>")
	)
	(arc
		(start 232.189274 -65.89649)
		(mid 232.383124 -65.84014)
		(end 232.524808 -65.696338)
		(width 0.0889)
		(layer "In11.Cu")
		(net "M_C_DQ<1>")
	)
	(arc
		(start 235.633768 -65.89649)
		(mid 235.916985 -65.980771)
		(end 236.123988 -66.191638)
		(width 0.0889)
		(layer "In11.Cu")
		(net "M_C_DQ<1>")
	)
	(arc
		(start 234.241848 -65.696338)
		(mid 234.450456 -65.484406)
		(end 234.735878 -65.400936)
		(width 0.0889)
		(layer "In11.Cu")
		(net "M_C_DQ<1>")
	)
	(arc
		(start 232.524808 -65.696338)
		(mid 232.733416 -65.484406)
		(end 233.018838 -65.400936)
		(width 0.0889)
		(layer "In11.Cu")
		(net "M_C_DQ<1>")
	)
	(arc
		(start 238.205518 -67.382136)
		(mid 238.490942 -67.465603)
		(end 238.699548 -67.677538)
		(width 0.0889)
		(layer "In11.Cu")
		(net "M_C_DQ<1>")
	)
	(arc
		(start 240.375948 -66.385948)
		(mid 240.512676 -66.174873)
		(end 240.748312 -66.08699)
		(width 0.0889)
		(layer "In11.Cu")
		(net "M_C_DQ<1>")
	)
	(arc
		(start 237.350808 -66.88709)
		(mid 237.634025 -66.971371)
		(end 237.841028 -67.182238)
		(width 0.0889)
		(layer "In11.Cu")
		(net "M_C_DQ<1>")
	)
	(arc
		(start 236.123988 -66.191638)
		(mid 236.264067 -66.334374)
		(end 236.455712 -66.391536)
		(width 0.0889)
		(layer "In11.Cu")
		(net "M_C_DQ<1>")
	)
	(arc
		(start 241.414554 -66.334132)
		(mid 241.507038 -66.375078)
		(end 241.606832 -66.391536)
		(width 0.0889)
		(layer "In11.Cu")
		(net "M_C_DQ<1>")
	)
	(arc
		(start 234.771438 -65.400936)
		(mid 235.056862 -65.484403)
		(end 235.265468 -65.696338)
		(width 0.0889)
		(layer "In11.Cu")
		(net "M_C_DQ<1>")
	)
	(arc
		(start 235.265468 -65.696338)
		(mid 235.407151 -65.840142)
		(end 235.601002 -65.89649)
		(width 0.0889)
		(layer "In11.Cu")
		(net "M_C_DQ<1>")
	)
	(arc
		(start 239.919764 -67.382136)
		(mid 240.111406 -67.32497)
		(end 240.251488 -67.182238)
		(width 0.0889)
		(layer "In11.Cu")
		(net "M_C_DQ<1>")
	)
	(arc
		(start 237.841028 -67.182238)
		(mid 237.981107 -67.324974)
		(end 238.172752 -67.382136)
		(width 0.0889)
		(layer "In11.Cu")
		(net "M_C_DQ<1>")
	)
	(arc
		(start 238.699548 -67.677538)
		(mid 239.046258 -67.877849)
		(end 239.392968 -67.677538)
		(width 0.0889)
		(layer "In11.Cu")
		(net "M_C_DQ<1>")
	)
	(arc
		(start 233.054398 -65.400936)
		(mid 233.339822 -65.484403)
		(end 233.548428 -65.696338)
		(width 0.0889)
		(layer "In11.Cu")
		(net "M_C_DQ<1>")
	)
	(arc
		(start 236.488478 -66.391536)
		(mid 236.773902 -66.475003)
		(end 236.982508 -66.686938)
		(width 0.0889)
		(layer "In11.Cu")
		(net "M_C_DQ<1>")
	)
	(segment
		(start 222.749872 3.778758)
		(end 222.749872 2.514854)
		(width 0.1651)
		(layer "F.Cu")
		(net "M_C_DQ<19>")
	)
	(segment
		(start 222.75038 3.778758)
		(end 222.749872 3.778758)
		(width 0.1651)
		(layer "F.Cu")
		(net "M_C_DQ<19>")
	)
	(segment
		(start 247.344184 -57.076086)
		(end 246.772684 -57.076086)
		(width 0.0889)
		(layer "F.Cu")
		(net "M_C_DQ<19>")
	)
	(via
		(at 246.772684 -57.076086)
		(size 0.508)
		(drill 0.254)
		(layers "F.Cu" "B.Cu")
		(net "M_C_DQ<19>")
	)
	(via
		(at 223.599756 -3.076956)
		(size 0.508)
		(drill 0.254)
		(layers "F.Cu" "B.Cu")
		(net "M_C_DQ<19>")
	)
	(via
		(at 222.749872 2.514854)
		(size 0.508)
		(drill 0.254)
		(layers "F.Cu" "B.Cu")
		(net "M_C_DQ<19>")
	)
	(segment
		(start 223.600518 -3.076194)
		(end 223.599756 -3.076956)
		(width 0.1651)
		(layer "B.Cu")
		(net "M_C_DQ<19>")
	)
	(segment
		(start 223.600518 -1.021842)
		(end 223.600518 -3.076194)
		(width 0.1651)
		(layer "B.Cu")
		(net "M_C_DQ<19>")
	)
	(segment
		(start 223.95434 -18.95094)
		(end 224.0534 -19.05)
		(width 0.14224)
		(layer "In11.Cu")
		(net "M_C_DQ<19>")
	)
	(segment
		(start 238.694722 -50.828702)
		(end 238.699548 -50.837338)
		(width 0.0889)
		(layer "In11.Cu")
		(net "M_C_DQ<19>")
	)
	(segment
		(start 245.040658 -55.494936)
		(end 245.073424 -55.494936)
		(width 0.0889)
		(layer "In11.Cu")
		(net "M_C_DQ<19>")
	)
	(segment
		(start 224.09404 -18.425414)
		(end 223.95434 -18.565114)
		(width 0.14224)
		(layer "In11.Cu")
		(net "M_C_DQ<19>")
	)
	(segment
		(start 223.891094 -30.911546)
		(end 223.736154 -31.066486)
		(width 0.14224)
		(layer "In11.Cu")
		(net "M_C_DQ<19>")
	)
	(segment
		(start 223.65081 1.5494)
		(end 224.10801 1.0922)
		(width 0.14224)
		(layer "In11.Cu")
		(net "M_C_DQ<19>")
	)
	(segment
		(start 224.0534 -21.23694)
		(end 223.95434 -21.336)
		(width 0.14224)
		(layer "In11.Cu")
		(net "M_C_DQ<19>")
	)
	(segment
		(start 223.96704 -16.890746)
		(end 224.09404 -17.017746)
		(width 0.14224)
		(layer "In11.Cu")
		(net "M_C_DQ<19>")
	)
	(segment
		(start 223.11614 -3.560572)
		(end 223.11614 -3.965956)
		(width 0.14224)
		(layer "In11.Cu")
		(net "M_C_DQ<19>")
	)
	(segment
		(start 237.923832 -46.370748)
		(end 238.050832 -46.497748)
		(width 0.14224)
		(layer "In11.Cu")
		(net "M_C_DQ<19>")
	)
	(segment
		(start 238.73968 -48.015398)
		(end 238.996982 -48.2727)
		(width 0.0889)
		(layer "In11.Cu")
		(net "M_C_DQ<19>")
	)
	(segment
		(start 223.736154 -31.686246)
		(end 223.891094 -31.841186)
		(width 0.14224)
		(layer "In11.Cu")
		(net "M_C_DQ<19>")
	)
	(segment
		(start 224.09404 -17.017746)
		(end 224.09404 -18.425414)
		(width 0.14224)
		(layer "In11.Cu")
		(net "M_C_DQ<19>")
	)
	(segment
		(start 223.891094 -31.841186)
		(end 223.891094 -32.239204)
		(width 0.14224)
		(layer "In11.Cu")
		(net "M_C_DQ<19>")
	)
	(segment
		(start 237.581186 -45.626782)
		(end 237.923832 -45.969428)
		(width 0.14224)
		(layer "In11.Cu")
		(net "M_C_DQ<19>")
	)
	(segment
		(start 239.028224 -52.027836)
		(end 239.064038 -52.027836)
		(width 0.0889)
		(layer "In11.Cu")
		(net "M_C_DQ<19>")
	)
	(segment
		(start 238.699548 -50.837338)
		(end 238.705898 -50.848006)
		(width 0.0889)
		(layer "In11.Cu")
		(net "M_C_DQ<19>")
	)
	(segment
		(start 224.10674 -7.429246)
		(end 224.10674 -8.811514)
		(width 0.14224)
		(layer "In11.Cu")
		(net "M_C_DQ<19>")
	)
	(segment
		(start 242.992148 -54.304184)
		(end 242.99545 -54.310026)
		(width 0.0889)
		(layer "In11.Cu")
		(net "M_C_DQ<19>")
	)
	(segment
		(start 224.10801 1.0922)
		(end 224.10801 0.7366)
		(width 0.14224)
		(layer "In11.Cu")
		(net "M_C_DQ<19>")
	)
	(segment
		(start 233.823764 -43.298364)
		(end 234.358688 -43.298364)
		(width 0.14224)
		(layer "In11.Cu")
		(net "M_C_DQ<19>")
	)
	(segment
		(start 238.996982 -48.2727)
		(end 238.996982 -49.922938)
		(width 0.0889)
		(layer "In11.Cu")
		(net "M_C_DQ<19>")
	)
	(segment
		(start 223.95434 -9.37514)
		(end 224.1296 -9.5504)
		(width 0.14224)
		(layer "In11.Cu")
		(net "M_C_DQ<19>")
	)
	(segment
		(start 242.465352 -54.00929)
		(end 242.50523 -54.00929)
		(width 0.0889)
		(layer "In11.Cu")
		(net "M_C_DQ<19>")
	)
	(segment
		(start 241.606832 -53.513736)
		(end 241.639598 -53.513736)
		(width 0.0889)
		(layer "In11.Cu")
		(net "M_C_DQ<19>")
	)
	(segment
		(start 223.96704 -7.289546)
		(end 224.10674 -7.429246)
		(width 0.14224)
		(layer "In11.Cu")
		(net "M_C_DQ<19>")
	)
	(segment
		(start 223.96704 -4.816856)
		(end 223.96704 -7.289546)
		(width 0.14224)
		(layer "In11.Cu")
		(net "M_C_DQ<19>")
	)
	(segment
		(start 237.012226 -45.8978)
		(end 237.283244 -45.626782)
		(width 0.14224)
		(layer "In11.Cu")
		(net "M_C_DQ<19>")
	)
	(segment
		(start 238.452152 -46.497748)
		(end 238.73968 -46.785276)
		(width 0.14224)
		(layer "In11.Cu")
		(net "M_C_DQ<19>")
	)
	(segment
		(start 236.163866 -45.638466)
		(end 236.4232 -45.8978)
		(width 0.14224)
		(layer "In11.Cu")
		(net "M_C_DQ<19>")
	)
	(segment
		(start 223.95434 -21.822156)
		(end 224.13214 -21.999956)
		(width 0.14224)
		(layer "In11.Cu")
		(net "M_C_DQ<19>")
	)
	(segment
		(start 223.891094 -32.239204)
		(end 233.167936 -41.516046)
		(width 0.14224)
		(layer "In11.Cu")
		(net "M_C_DQ<19>")
	)
	(segment
		(start 245.902988 -55.99049)
		(end 245.935754 -55.99049)
		(width 0.0889)
		(layer "In11.Cu")
		(net "M_C_DQ<19>")
	)
	(segment
		(start 224.084134 -12.33805)
		(end 224.084134 -13.577062)
		(width 0.14224)
		(layer "In11.Cu")
		(net "M_C_DQ<19>")
	)
	(segment
		(start 223.207326 -31.066486)
		(end 223.052386 -31.221426)
		(width 0.14224)
		(layer "In11.Cu")
		(net "M_C_DQ<19>")
	)
	(segment
		(start 233.167936 -41.516046)
		(end 233.167936 -42.642536)
		(width 0.14224)
		(layer "In11.Cu")
		(net "M_C_DQ<19>")
	)
	(segment
		(start 238.996982 -49.922938)
		(end 238.699548 -50.437288)
		(width 0.0889)
		(layer "In11.Cu")
		(net "M_C_DQ<19>")
	)
	(segment
		(start 224.13214 -23.183596)
		(end 223.891094 -23.424642)
		(width 0.14224)
		(layer "In11.Cu")
		(net "M_C_DQ<19>")
	)
	(segment
		(start 223.599756 -3.076956)
		(end 223.11614 -3.560572)
		(width 0.14224)
		(layer "In11.Cu")
		(net "M_C_DQ<19>")
	)
	(segment
		(start 223.952562 0.581152)
		(end 223.952562 -2.72415)
		(width 0.14224)
		(layer "In11.Cu")
		(net "M_C_DQ<19>")
	)
	(segment
		(start 223.95434 -11.7602)
		(end 223.95434 -12.208256)
		(width 0.14224)
		(layer "In11.Cu")
		(net "M_C_DQ<19>")
	)
	(segment
		(start 223.11614 -3.965956)
		(end 223.96704 -4.816856)
		(width 0.14224)
		(layer "In11.Cu")
		(net "M_C_DQ<19>")
	)
	(segment
		(start 223.39681 1.5494)
		(end 223.65081 1.5494)
		(width 0.14224)
		(layer "In11.Cu")
		(net "M_C_DQ<19>")
	)
	(segment
		(start 223.736154 -31.066486)
		(end 223.207326 -31.066486)
		(width 0.14224)
		(layer "In11.Cu")
		(net "M_C_DQ<19>")
	)
	(segment
		(start 223.96704 -13.694156)
		(end 223.96704 -16.890746)
		(width 0.14224)
		(layer "In11.Cu")
		(net "M_C_DQ<19>")
	)
	(segment
		(start 239.886744 -52.523136)
		(end 239.926368 -52.523136)
		(width 0.0889)
		(layer "In11.Cu")
		(net "M_C_DQ<19>")
	)
	(segment
		(start 224.1296 -9.5504)
		(end 224.1296 -11.58494)
		(width 0.14224)
		(layer "In11.Cu")
		(net "M_C_DQ<19>")
	)
	(segment
		(start 235.782866 -44.722542)
		(end 235.984034 -44.722542)
		(width 0.14224)
		(layer "In11.Cu")
		(net "M_C_DQ<19>")
	)
	(segment
		(start 236.665262 -44.918122)
		(end 236.163866 -45.419518)
		(width 0.14224)
		(layer "In11.Cu")
		(net "M_C_DQ<19>")
	)
	(segment
		(start 243.338604 -54.504336)
		(end 243.356384 -54.504336)
		(width 0.0889)
		(layer "In11.Cu")
		(net "M_C_DQ<19>")
	)
	(segment
		(start 240.752122 -53.018436)
		(end 240.776252 -53.018436)
		(width 0.0889)
		(layer "In11.Cu")
		(net "M_C_DQ<19>")
	)
	(segment
		(start 224.0534 -19.05)
		(end 224.0534 -21.23694)
		(width 0.14224)
		(layer "In11.Cu")
		(net "M_C_DQ<19>")
	)
	(segment
		(start 223.95434 -8.963914)
		(end 223.95434 -9.37514)
		(width 0.14224)
		(layer "In11.Cu")
		(net "M_C_DQ<19>")
	)
	(segment
		(start 223.95434 -21.336)
		(end 223.95434 -21.822156)
		(width 0.14224)
		(layer "In11.Cu")
		(net "M_C_DQ<19>")
	)
	(segment
		(start 224.10674 -8.811514)
		(end 223.95434 -8.963914)
		(width 0.14224)
		(layer "In11.Cu")
		(net "M_C_DQ<19>")
	)
	(segment
		(start 244.185948 -54.99989)
		(end 244.218714 -54.99989)
		(width 0.0889)
		(layer "In11.Cu")
		(net "M_C_DQ<19>")
	)
	(segment
		(start 224.10801 0.7366)
		(end 223.952562 0.581152)
		(width 0.14224)
		(layer "In11.Cu")
		(net "M_C_DQ<19>")
	)
	(segment
		(start 223.952562 -2.72415)
		(end 223.599756 -3.076956)
		(width 0.14224)
		(layer "In11.Cu")
		(net "M_C_DQ<19>")
	)
	(segment
		(start 236.163866 -45.419518)
		(end 236.163866 -45.638466)
		(width 0.14224)
		(layer "In11.Cu")
		(net "M_C_DQ<19>")
	)
	(segment
		(start 223.052386 -31.531306)
		(end 223.207326 -31.686246)
		(width 0.14224)
		(layer "In11.Cu")
		(net "M_C_DQ<19>")
	)
	(segment
		(start 224.13214 -21.999956)
		(end 224.13214 -23.183596)
		(width 0.14224)
		(layer "In11.Cu")
		(net "M_C_DQ<19>")
	)
	(segment
		(start 237.923832 -45.969428)
		(end 237.923832 -46.370748)
		(width 0.14224)
		(layer "In11.Cu")
		(net "M_C_DQ<19>")
	)
	(segment
		(start 223.207326 -31.686246)
		(end 223.736154 -31.686246)
		(width 0.14224)
		(layer "In11.Cu")
		(net "M_C_DQ<19>")
	)
	(segment
		(start 223.95434 -18.565114)
		(end 223.95434 -18.95094)
		(width 0.14224)
		(layer "In11.Cu")
		(net "M_C_DQ<19>")
	)
	(segment
		(start 222.749872 2.514854)
		(end 223.06661 2.198116)
		(width 0.14224)
		(layer "In11.Cu")
		(net "M_C_DQ<19>")
	)
	(segment
		(start 236.226858 -44.479718)
		(end 236.445806 -44.479718)
		(width 0.14224)
		(layer "In11.Cu")
		(net "M_C_DQ<19>")
	)
	(segment
		(start 223.06661 2.198116)
		(end 223.06661 1.8796)
		(width 0.14224)
		(layer "In11.Cu")
		(net "M_C_DQ<19>")
	)
	(segment
		(start 224.1296 -11.58494)
		(end 223.95434 -11.7602)
		(width 0.14224)
		(layer "In11.Cu")
		(net "M_C_DQ<19>")
	)
	(segment
		(start 236.665262 -44.699174)
		(end 236.665262 -44.918122)
		(width 0.14224)
		(layer "In11.Cu")
		(net "M_C_DQ<19>")
	)
	(segment
		(start 236.4232 -45.8978)
		(end 237.012226 -45.8978)
		(width 0.14224)
		(layer "In11.Cu")
		(net "M_C_DQ<19>")
	)
	(segment
		(start 238.050832 -46.497748)
		(end 238.452152 -46.497748)
		(width 0.14224)
		(layer "In11.Cu")
		(net "M_C_DQ<19>")
	)
	(segment
		(start 223.052386 -31.221426)
		(end 223.052386 -31.531306)
		(width 0.14224)
		(layer "In11.Cu")
		(net "M_C_DQ<19>")
	)
	(segment
		(start 234.358688 -43.298364)
		(end 235.782866 -44.722542)
		(width 0.14224)
		(layer "In11.Cu")
		(net "M_C_DQ<19>")
	)
	(segment
		(start 236.445806 -44.479718)
		(end 236.665262 -44.699174)
		(width 0.14224)
		(layer "In11.Cu")
		(net "M_C_DQ<19>")
	)
	(segment
		(start 223.891094 -23.424642)
		(end 223.891094 -30.911546)
		(width 0.14224)
		(layer "In11.Cu")
		(net "M_C_DQ<19>")
	)
	(segment
		(start 235.984034 -44.722542)
		(end 236.226858 -44.479718)
		(width 0.14224)
		(layer "In11.Cu")
		(net "M_C_DQ<19>")
	)
	(segment
		(start 223.95434 -12.208256)
		(end 224.084134 -12.33805)
		(width 0.14224)
		(layer "In11.Cu")
		(net "M_C_DQ<19>")
	)
	(segment
		(start 246.45493 -56.342788)
		(end 246.772684 -57.076086)
		(width 0.0889)
		(layer "In11.Cu")
		(net "M_C_DQ<19>")
	)
	(segment
		(start 223.06661 1.8796)
		(end 223.39681 1.5494)
		(width 0.14224)
		(layer "In11.Cu")
		(net "M_C_DQ<19>")
	)
	(segment
		(start 224.084134 -13.577062)
		(end 223.96704 -13.694156)
		(width 0.14224)
		(layer "In11.Cu")
		(net "M_C_DQ<19>")
	)
	(segment
		(start 237.283244 -45.626782)
		(end 237.581186 -45.626782)
		(width 0.14224)
		(layer "In11.Cu")
		(net "M_C_DQ<19>")
	)
	(segment
		(start 233.167936 -42.642536)
		(end 233.823764 -43.298364)
		(width 0.14224)
		(layer "In11.Cu")
		(net "M_C_DQ<19>")
	)
	(segment
		(start 238.73968 -46.785276)
		(end 238.73968 -47.47768)
		(width 0.14224)
		(layer "In11.Cu")
		(net "M_C_DQ<19>")
	)
	(segment
		(start 238.73968 -47.47768)
		(end 238.73968 -48.015398)
		(width 0.0889)
		(layer "In11.Cu")
		(net "M_C_DQ<19>")
	)
	(arc
		(start 242.133628 -53.809138)
		(mid 242.273646 -53.952049)
		(end 242.465352 -54.00929)
		(width 0.0889)
		(layer "In11.Cu")
		(net "M_C_DQ<19>")
	)
	(arc
		(start 240.776252 -53.018436)
		(mid 241.064397 -53.100755)
		(end 241.275108 -53.313838)
		(width 0.0889)
		(layer "In11.Cu")
		(net "M_C_DQ<19>")
	)
	(arc
		(start 244.218714 -54.99989)
		(mid 244.501931 -55.084171)
		(end 244.708934 -55.295038)
		(width 0.0889)
		(layer "In11.Cu")
		(net "M_C_DQ<19>")
	)
	(arc
		(start 238.699548 -51.427888)
		(mid 238.695138 -51.820351)
		(end 239.028224 -52.027836)
		(width 0.0889)
		(layer "In11.Cu")
		(net "M_C_DQ<19>")
	)
	(arc
		(start 245.935754 -55.99049)
		(mid 246.245967 -56.092039)
		(end 246.45493 -56.342788)
		(width 0.0889)
		(layer "In11.Cu")
		(net "M_C_DQ<19>")
	)
	(arc
		(start 239.558068 -52.323238)
		(mid 239.696812 -52.465271)
		(end 239.886744 -52.523136)
		(width 0.0889)
		(layer "In11.Cu")
		(net "M_C_DQ<19>")
	)
	(arc
		(start 239.064038 -52.027836)
		(mid 239.349462 -52.111303)
		(end 239.558068 -52.323238)
		(width 0.0889)
		(layer "In11.Cu")
		(net "M_C_DQ<19>")
	)
	(arc
		(start 245.073424 -55.494936)
		(mid 245.358848 -55.578403)
		(end 245.567454 -55.790338)
		(width 0.0889)
		(layer "In11.Cu")
		(net "M_C_DQ<19>")
	)
	(arc
		(start 239.926368 -52.523136)
		(mid 240.209585 -52.607417)
		(end 240.416588 -52.818284)
		(width 0.0889)
		(layer "In11.Cu")
		(net "M_C_DQ<19>")
	)
	(arc
		(start 243.356384 -54.504336)
		(mid 243.641808 -54.587803)
		(end 243.850414 -54.799738)
		(width 0.0889)
		(layer "In11.Cu")
		(net "M_C_DQ<19>")
	)
	(arc
		(start 242.99545 -54.310026)
		(mid 243.141416 -54.452425)
		(end 243.338604 -54.504336)
		(width 0.0889)
		(layer "In11.Cu")
		(net "M_C_DQ<19>")
	)
	(arc
		(start 238.705898 -50.848006)
		(mid 238.778696 -51.138769)
		(end 238.699548 -51.427888)
		(width 0.0889)
		(layer "In11.Cu")
		(net "M_C_DQ<19>")
	)
	(arc
		(start 238.699548 -50.437288)
		(mid 238.646078 -50.632351)
		(end 238.694722 -50.828702)
		(width 0.0889)
		(layer "In11.Cu")
		(net "M_C_DQ<19>")
	)
	(arc
		(start 242.50523 -54.00929)
		(mid 242.78653 -54.094256)
		(end 242.992148 -54.304184)
		(width 0.0889)
		(layer "In11.Cu")
		(net "M_C_DQ<19>")
	)
	(arc
		(start 245.567454 -55.790338)
		(mid 245.709137 -55.934142)
		(end 245.902988 -55.99049)
		(width 0.0889)
		(layer "In11.Cu")
		(net "M_C_DQ<19>")
	)
	(arc
		(start 240.416588 -52.818284)
		(mid 240.558271 -52.962088)
		(end 240.752122 -53.018436)
		(width 0.0889)
		(layer "In11.Cu")
		(net "M_C_DQ<19>")
	)
	(arc
		(start 241.639598 -53.513736)
		(mid 241.925022 -53.597203)
		(end 242.133628 -53.809138)
		(width 0.0889)
		(layer "In11.Cu")
		(net "M_C_DQ<19>")
	)
	(arc
		(start 241.275108 -53.313838)
		(mid 241.415187 -53.456574)
		(end 241.606832 -53.513736)
		(width 0.0889)
		(layer "In11.Cu")
		(net "M_C_DQ<19>")
	)
	(arc
		(start 243.850414 -54.799738)
		(mid 243.992097 -54.943542)
		(end 244.185948 -54.99989)
		(width 0.0889)
		(layer "In11.Cu")
		(net "M_C_DQ<19>")
	)
	(arc
		(start 244.708934 -55.295038)
		(mid 244.849013 -55.437774)
		(end 245.040658 -55.494936)
		(width 0.0889)
		(layer "In11.Cu")
		(net "M_C_DQ<19>")
	)
	(segment
		(start 223.731328 0.53086)
		(end 223.599756 0.662432)
		(width 0.1651)
		(layer "F.Cu")
		(net "M_C_DQ<18>")
	)
	(segment
		(start 223.599756 0.662432)
		(end 223.599756 0.9398)
		(width 0.1651)
		(layer "F.Cu")
		(net "M_C_DQ<18>")
	)
	(segment
		(start 223.600518 0.17653)
		(end 223.731328 0.30734)
		(width 0.1651)
		(layer "F.Cu")
		(net "M_C_DQ<18>")
	)
	(segment
		(start 223.731328 0.30734)
		(end 223.731328 0.53086)
		(width 0.1651)
		(layer "F.Cu")
		(net "M_C_DQ<18>")
	)
	(segment
		(start 246.485664 -56.58104)
		(end 245.914164 -56.58104)
		(width 0.0889)
		(layer "F.Cu")
		(net "M_C_DQ<18>")
	)
	(segment
		(start 223.600518 -0.821182)
		(end 223.600518 0.17653)
		(width 0.1651)
		(layer "F.Cu")
		(net "M_C_DQ<18>")
	)
	(via
		(at 223.599756 0.9398)
		(size 0.508)
		(drill 0.254)
		(layers "F.Cu" "B.Cu")
		(net "M_C_DQ<18>")
	)
	(via
		(at 245.914164 -56.58104)
		(size 0.508)
		(drill 0.254)
		(layers "F.Cu" "B.Cu")
		(net "M_C_DQ<18>")
	)
	(via
		(at 222.749872 -4.357878)
		(size 0.508)
		(drill 0.254)
		(layers "F.Cu" "B.Cu")
		(net "M_C_DQ<18>")
	)
	(segment
		(start 222.75038 -5.621782)
		(end 222.749872 -5.621782)
		(width 0.1651)
		(layer "B.Cu")
		(net "M_C_DQ<18>")
	)
	(segment
		(start 222.749872 -5.621782)
		(end 222.749872 -4.357878)
		(width 0.1651)
		(layer "B.Cu")
		(net "M_C_DQ<18>")
	)
	(segment
		(start 222.66148 -29.216604)
		(end 222.50654 -29.371544)
		(width 0.14224)
		(layer "In11.Cu")
		(net "M_C_DQ<18>")
	)
	(segment
		(start 223.24314 -12.195556)
		(end 223.09074 -12.347956)
		(width 0.14224)
		(layer "In11.Cu")
		(net "M_C_DQ<18>")
	)
	(segment
		(start 228.92639 -39.375842)
		(end 229.145338 -39.375842)
		(width 0.14224)
		(layer "In11.Cu")
		(net "M_C_DQ<18>")
	)
	(segment
		(start 226.845876 -36.980876)
		(end 227.047044 -36.980876)
		(width 0.14224)
		(layer "In11.Cu")
		(net "M_C_DQ<18>")
	)
	(segment
		(start 226.830382 -36.27755)
		(end 226.58705 -36.520882)
		(width 0.14224)
		(layer "In11.Cu")
		(net "M_C_DQ<18>")
	)
	(segment
		(start 222.779336 -27.968194)
		(end 222.50654 -28.24099)
		(width 0.14224)
		(layer "In11.Cu")
		(net "M_C_DQ<18>")
	)
	(segment
		(start 223.33204 -13.783056)
		(end 223.33204 -16.751046)
		(width 0.14224)
		(layer "In11.Cu")
		(net "M_C_DQ<18>")
	)
	(segment
		(start 223.099376 -9.539224)
		(end 223.099376 -11.565636)
		(width 0.14224)
		(layer "In11.Cu")
		(net "M_C_DQ<18>")
	)
	(segment
		(start 223.09074 -21.949156)
		(end 223.09074 -23.142956)
		(width 0.14224)
		(layer "In11.Cu")
		(net "M_C_DQ<18>")
	)
	(segment
		(start 229.96652 -39.431468)
		(end 229.583742 -39.814246)
		(width 0.14224)
		(layer "In11.Cu")
		(net "M_C_DQ<18>")
	)
	(segment
		(start 232.563924 -42.85107)
		(end 236.169454 -46.4566)
		(width 0.14224)
		(layer "In11.Cu")
		(net "M_C_DQ<18>")
	)
	(segment
		(start 223.24314 -18.570194)
		(end 223.24314 -19.04746)
		(width 0.14224)
		(layer "In11.Cu")
		(net "M_C_DQ<18>")
	)
	(segment
		(start 222.66148 -28.659074)
		(end 223.106488 -28.659074)
		(width 0.14224)
		(layer "In11.Cu")
		(net "M_C_DQ<18>")
	)
	(segment
		(start 230.843328 -40.308276)
		(end 230.46055 -40.691054)
		(width 0.14224)
		(layer "In11.Cu")
		(net "M_C_DQ<18>")
	)
	(segment
		(start 222.856806 -1.7526)
		(end 223.314006 -2.2098)
		(width 0.14224)
		(layer "In11.Cu")
		(net "M_C_DQ<18>")
	)
	(segment
		(start 228.706934 -38.937438)
		(end 228.706934 -39.156386)
		(width 0.14224)
		(layer "In11.Cu")
		(net "M_C_DQ<18>")
	)
	(segment
		(start 240.750344 -53.20919)
		(end 240.778284 -53.20919)
		(width 0.0889)
		(layer "In11.Cu")
		(net "M_C_DQ<18>")
	)
	(segment
		(start 229.145338 -39.375842)
		(end 229.528116 -38.993064)
		(width 0.14224)
		(layer "In11.Cu")
		(net "M_C_DQ<18>")
	)
	(segment
		(start 222.749872 -4.357878)
		(end 223.2152 -4.823206)
		(width 0.14224)
		(layer "In11.Cu")
		(net "M_C_DQ<18>")
	)
	(segment
		(start 223.261428 -29.91739)
		(end 223.261428 -30.234636)
		(width 0.14224)
		(layer "In11.Cu")
		(net "M_C_DQ<18>")
	)
	(segment
		(start 229.747064 -38.993064)
		(end 229.96652 -39.21252)
		(width 0.14224)
		(layer "In11.Cu")
		(net "M_C_DQ<18>")
	)
	(segment
		(start 230.46055 -40.691054)
		(end 230.46055 -40.910002)
		(width 0.14224)
		(layer "In11.Cu")
		(net "M_C_DQ<18>")
	)
	(segment
		(start 229.803198 -40.25265)
		(end 230.022146 -40.25265)
		(width 0.14224)
		(layer "In11.Cu")
		(net "M_C_DQ<18>")
	)
	(segment
		(start 223.106488 -28.659074)
		(end 223.261428 -28.814014)
		(width 0.14224)
		(layer "In11.Cu")
		(net "M_C_DQ<18>")
	)
	(segment
		(start 222.50654 -28.24099)
		(end 222.50654 -28.504134)
		(width 0.14224)
		(layer "In11.Cu")
		(net "M_C_DQ<18>")
	)
	(segment
		(start 226.830382 -36.076382)
		(end 226.830382 -36.27755)
		(width 0.14224)
		(layer "In11.Cu")
		(net "M_C_DQ<18>")
	)
	(segment
		(start 230.623872 -39.869872)
		(end 230.843328 -40.089328)
		(width 0.14224)
		(layer "In11.Cu")
		(net "M_C_DQ<18>")
	)
	(segment
		(start 223.201738 0.236728)
		(end 222.856806 -0.108204)
		(width 0.14224)
		(layer "In11.Cu")
		(net "M_C_DQ<18>")
	)
	(segment
		(start 238.287306 -48.12538)
		(end 238.57839 -48.12538)
		(width 0.0889)
		(layer "In11.Cu")
		(net "M_C_DQ<18>")
	)
	(segment
		(start 223.139 -7.342886)
		(end 223.139 -8.890254)
		(width 0.14224)
		(layer "In11.Cu")
		(net "M_C_DQ<18>")
	)
	(segment
		(start 243.313712 -54.694836)
		(end 243.34978 -54.694836)
		(width 0.0889)
		(layer "In11.Cu")
		(net "M_C_DQ<18>")
	)
	(segment
		(start 222.465138 -4.073144)
		(end 222.749872 -4.357878)
		(width 0.14224)
		(layer "In11.Cu")
		(net "M_C_DQ<18>")
	)
	(segment
		(start 238.534448 -50.932588)
		(end 238.539274 -50.941224)
		(width 0.0889)
		(layer "In11.Cu")
		(net "M_C_DQ<18>")
	)
	(segment
		(start 222.50654 -31.75254)
		(end 226.830382 -36.076382)
		(width 0.14224)
		(layer "In11.Cu")
		(net "M_C_DQ<18>")
	)
	(segment
		(start 223.24314 -21.336)
		(end 223.24314 -21.796756)
		(width 0.14224)
		(layer "In11.Cu")
		(net "M_C_DQ<18>")
	)
	(segment
		(start 239.886998 -52.71389)
		(end 239.922812 -52.71389)
		(width 0.0889)
		(layer "In11.Cu")
		(net "M_C_DQ<18>")
	)
	(segment
		(start 223.139 -8.890254)
		(end 223.24314 -8.994394)
		(width 0.14224)
		(layer "In11.Cu")
		(net "M_C_DQ<18>")
	)
	(segment
		(start 229.089712 -38.335712)
		(end 229.089712 -38.55466)
		(width 0.14224)
		(layer "In11.Cu")
		(net "M_C_DQ<18>")
	)
	(segment
		(start 239.024668 -52.21859)
		(end 239.064292 -52.21859)
		(width 0.0889)
		(layer "In11.Cu")
		(net "M_C_DQ<18>")
	)
	(segment
		(start 222.50654 -28.504134)
		(end 222.66148 -28.659074)
		(width 0.14224)
		(layer "In11.Cu")
		(net "M_C_DQ<18>")
	)
	(segment
		(start 222.50654 -29.371544)
		(end 222.50654 -29.60751)
		(width 0.14224)
		(layer "In11.Cu")
		(net "M_C_DQ<18>")
	)
	(segment
		(start 223.24314 -11.7094)
		(end 223.24314 -12.195556)
		(width 0.14224)
		(layer "In11.Cu")
		(net "M_C_DQ<18>")
	)
	(segment
		(start 227.491544 -36.737544)
		(end 229.089712 -38.335712)
		(width 0.14224)
		(layer "In11.Cu")
		(net "M_C_DQ<18>")
	)
	(segment
		(start 222.465138 -3.3274)
		(end 222.465138 -4.073144)
		(width 0.14224)
		(layer "In11.Cu")
		(net "M_C_DQ<18>")
	)
	(segment
		(start 230.404924 -39.869872)
		(end 230.623872 -39.869872)
		(width 0.14224)
		(layer "In11.Cu")
		(net "M_C_DQ<18>")
	)
	(segment
		(start 227.290376 -36.737544)
		(end 227.491544 -36.737544)
		(width 0.14224)
		(layer "In11.Cu")
		(net "M_C_DQ<18>")
	)
	(segment
		(start 223.129094 -27.968194)
		(end 222.779336 -27.968194)
		(width 0.14224)
		(layer "In11.Cu")
		(net "M_C_DQ<18>")
	)
	(segment
		(start 230.891842 -41.341294)
		(end 231.968294 -41.341294)
		(width 0.14224)
		(layer "In11.Cu")
		(net "M_C_DQ<18>")
	)
	(segment
		(start 223.256094 -23.30831)
		(end 223.256094 -27.841194)
		(width 0.14224)
		(layer "In11.Cu")
		(net "M_C_DQ<18>")
	)
	(segment
		(start 230.843328 -40.089328)
		(end 230.843328 -40.308276)
		(width 0.14224)
		(layer "In11.Cu")
		(net "M_C_DQ<18>")
	)
	(segment
		(start 238.525558 -50.917348)
		(end 238.534448 -50.932588)
		(width 0.0889)
		(layer "In11.Cu")
		(net "M_C_DQ<18>")
	)
	(segment
		(start 223.106488 -30.389576)
		(end 222.66148 -30.389576)
		(width 0.14224)
		(layer "In11.Cu")
		(net "M_C_DQ<18>")
	)
	(segment
		(start 223.24314 -9.39546)
		(end 223.099376 -9.539224)
		(width 0.14224)
		(layer "In11.Cu")
		(net "M_C_DQ<18>")
	)
	(segment
		(start 229.583742 -39.814246)
		(end 229.583742 -40.033194)
		(width 0.14224)
		(layer "In11.Cu")
		(net "M_C_DQ<18>")
	)
	(segment
		(start 222.856806 -0.456946)
		(end 223.161606 -0.761746)
		(width 0.14224)
		(layer "In11.Cu")
		(net "M_C_DQ<18>")
	)
	(segment
		(start 229.089712 -38.55466)
		(end 228.706934 -38.937438)
		(width 0.14224)
		(layer "In11.Cu")
		(net "M_C_DQ<18>")
	)
	(segment
		(start 223.33204 -16.751046)
		(end 223.11614 -16.966946)
		(width 0.14224)
		(layer "In11.Cu")
		(net "M_C_DQ<18>")
	)
	(segment
		(start 223.599756 0.9398)
		(end 223.201738 0.541782)
		(width 0.14224)
		(layer "In11.Cu")
		(net "M_C_DQ<18>")
	)
	(segment
		(start 223.24314 -19.04746)
		(end 223.139 -19.1516)
		(width 0.14224)
		(layer "In11.Cu")
		(net "M_C_DQ<18>")
	)
	(segment
		(start 242.462558 -54.200044)
		(end 242.49253 -54.200044)
		(width 0.0889)
		(layer "In11.Cu")
		(net "M_C_DQ<18>")
	)
	(segment
		(start 236.169454 -46.4566)
		(end 236.618526 -46.4566)
		(width 0.14224)
		(layer "In11.Cu")
		(net "M_C_DQ<18>")
	)
	(segment
		(start 223.261428 -29.061664)
		(end 223.106488 -29.216604)
		(width 0.14224)
		(layer "In11.Cu")
		(net "M_C_DQ<18>")
	)
	(segment
		(start 223.256094 -27.841194)
		(end 223.129094 -27.968194)
		(width 0.14224)
		(layer "In11.Cu")
		(net "M_C_DQ<18>")
	)
	(segment
		(start 222.856806 -0.108204)
		(end 222.856806 -0.456946)
		(width 0.14224)
		(layer "In11.Cu")
		(net "M_C_DQ<18>")
	)
	(segment
		(start 238.57839 -48.12538)
		(end 238.806482 -48.353472)
		(width 0.0889)
		(layer "In11.Cu")
		(net "M_C_DQ<18>")
	)
	(segment
		(start 223.09074 -12.347956)
		(end 223.09074 -13.541756)
		(width 0.14224)
		(layer "In11.Cu")
		(net "M_C_DQ<18>")
	)
	(segment
		(start 223.2152 -7.266686)
		(end 223.139 -7.342886)
		(width 0.14224)
		(layer "In11.Cu")
		(net "M_C_DQ<18>")
	)
	(segment
		(start 245.513098 -56.024272)
		(end 245.914164 -56.58104)
		(width 0.0889)
		(layer "In11.Cu")
		(net "M_C_DQ<18>")
	)
	(segment
		(start 238.806482 -48.353472)
		(end 238.806482 -49.87163)
		(width 0.0889)
		(layer "In11.Cu")
		(net "M_C_DQ<18>")
	)
	(segment
		(start 232.563924 -41.936924)
		(end 232.563924 -42.85107)
		(width 0.14224)
		(layer "In11.Cu")
		(net "M_C_DQ<18>")
	)
	(segment
		(start 223.261428 -28.814014)
		(end 223.261428 -29.061664)
		(width 0.14224)
		(layer "In11.Cu")
		(net "M_C_DQ<18>")
	)
	(segment
		(start 228.706934 -39.156386)
		(end 228.92639 -39.375842)
		(width 0.14224)
		(layer "In11.Cu")
		(net "M_C_DQ<18>")
	)
	(segment
		(start 222.856806 -1.35255)
		(end 222.856806 -1.7526)
		(width 0.14224)
		(layer "In11.Cu")
		(net "M_C_DQ<18>")
	)
	(segment
		(start 223.161606 -1.04775)
		(end 222.856806 -1.35255)
		(width 0.14224)
		(layer "In11.Cu")
		(net "M_C_DQ<18>")
	)
	(segment
		(start 241.600228 -53.704236)
		(end 241.626644 -53.704236)
		(width 0.0889)
		(layer "In11.Cu")
		(net "M_C_DQ<18>")
	)
	(segment
		(start 226.58705 -36.520882)
		(end 226.58705 -36.72205)
		(width 0.14224)
		(layer "In11.Cu")
		(net "M_C_DQ<18>")
	)
	(segment
		(start 223.24314 -8.994394)
		(end 223.24314 -9.39546)
		(width 0.14224)
		(layer "In11.Cu")
		(net "M_C_DQ<18>")
	)
	(segment
		(start 223.11614 -18.443194)
		(end 223.24314 -18.570194)
		(width 0.14224)
		(layer "In11.Cu")
		(net "M_C_DQ<18>")
	)
	(segment
		(start 223.09074 -23.142956)
		(end 223.256094 -23.30831)
		(width 0.14224)
		(layer "In11.Cu")
		(net "M_C_DQ<18>")
	)
	(segment
		(start 229.528116 -38.993064)
		(end 229.747064 -38.993064)
		(width 0.14224)
		(layer "In11.Cu")
		(net "M_C_DQ<18>")
	)
	(segment
		(start 244.179344 -55.19039)
		(end 244.21211 -55.19039)
		(width 0.0889)
		(layer "In11.Cu")
		(net "M_C_DQ<18>")
	)
	(segment
		(start 223.139 -21.23186)
		(end 223.24314 -21.336)
		(width 0.14224)
		(layer "In11.Cu")
		(net "M_C_DQ<18>")
	)
	(segment
		(start 223.201738 0.541782)
		(end 223.201738 0.236728)
		(width 0.14224)
		(layer "In11.Cu")
		(net "M_C_DQ<18>")
	)
	(segment
		(start 223.314006 -2.2098)
		(end 223.314006 -2.478532)
		(width 0.14224)
		(layer "In11.Cu")
		(net "M_C_DQ<18>")
	)
	(segment
		(start 223.106488 -29.76245)
		(end 223.261428 -29.91739)
		(width 0.14224)
		(layer "In11.Cu")
		(net "M_C_DQ<18>")
	)
	(segment
		(start 230.022146 -40.25265)
		(end 230.404924 -39.869872)
		(width 0.14224)
		(layer "In11.Cu")
		(net "M_C_DQ<18>")
	)
	(segment
		(start 229.583742 -40.033194)
		(end 229.803198 -40.25265)
		(width 0.14224)
		(layer "In11.Cu")
		(net "M_C_DQ<18>")
	)
	(segment
		(start 223.161606 -0.761746)
		(end 223.161606 -1.04775)
		(width 0.14224)
		(layer "In11.Cu")
		(net "M_C_DQ<18>")
	)
	(segment
		(start 230.46055 -40.910002)
		(end 230.891842 -41.341294)
		(width 0.14224)
		(layer "In11.Cu")
		(net "M_C_DQ<18>")
	)
	(segment
		(start 222.50654 -30.544516)
		(end 222.50654 -31.75254)
		(width 0.14224)
		(layer "In11.Cu")
		(net "M_C_DQ<18>")
	)
	(segment
		(start 238.806482 -49.87163)
		(end 238.534448 -50.341784)
		(width 0.0889)
		(layer "In11.Cu")
		(net "M_C_DQ<18>")
	)
	(segment
		(start 223.106488 -29.216604)
		(end 222.66148 -29.216604)
		(width 0.14224)
		(layer "In11.Cu")
		(net "M_C_DQ<18>")
	)
	(segment
		(start 223.314006 -2.478532)
		(end 222.465138 -3.3274)
		(width 0.14224)
		(layer "In11.Cu")
		(net "M_C_DQ<18>")
	)
	(segment
		(start 223.24314 -21.796756)
		(end 223.09074 -21.949156)
		(width 0.14224)
		(layer "In11.Cu")
		(net "M_C_DQ<18>")
	)
	(segment
		(start 222.66148 -29.76245)
		(end 223.106488 -29.76245)
		(width 0.14224)
		(layer "In11.Cu")
		(net "M_C_DQ<18>")
	)
	(segment
		(start 223.11614 -16.966946)
		(end 223.11614 -18.443194)
		(width 0.14224)
		(layer "In11.Cu")
		(net "M_C_DQ<18>")
	)
	(segment
		(start 229.96652 -39.21252)
		(end 229.96652 -39.431468)
		(width 0.14224)
		(layer "In11.Cu")
		(net "M_C_DQ<18>")
	)
	(segment
		(start 222.50654 -29.60751)
		(end 222.66148 -29.76245)
		(width 0.14224)
		(layer "In11.Cu")
		(net "M_C_DQ<18>")
	)
	(segment
		(start 245.034054 -55.685436)
		(end 245.06682 -55.685436)
		(width 0.0889)
		(layer "In11.Cu")
		(net "M_C_DQ<18>")
	)
	(segment
		(start 223.09074 -13.541756)
		(end 223.33204 -13.783056)
		(width 0.14224)
		(layer "In11.Cu")
		(net "M_C_DQ<18>")
	)
	(segment
		(start 223.139 -19.1516)
		(end 223.139 -21.23186)
		(width 0.14224)
		(layer "In11.Cu")
		(net "M_C_DQ<18>")
	)
	(segment
		(start 222.66148 -30.389576)
		(end 222.50654 -30.544516)
		(width 0.14224)
		(layer "In11.Cu")
		(net "M_C_DQ<18>")
	)
	(segment
		(start 223.261428 -30.234636)
		(end 223.106488 -30.389576)
		(width 0.14224)
		(layer "In11.Cu")
		(net "M_C_DQ<18>")
	)
	(segment
		(start 226.58705 -36.72205)
		(end 226.845876 -36.980876)
		(width 0.14224)
		(layer "In11.Cu")
		(net "M_C_DQ<18>")
	)
	(segment
		(start 223.2152 -4.823206)
		(end 223.2152 -7.266686)
		(width 0.14224)
		(layer "In11.Cu")
		(net "M_C_DQ<18>")
	)
	(segment
		(start 231.968294 -41.341294)
		(end 232.563924 -41.936924)
		(width 0.14224)
		(layer "In11.Cu")
		(net "M_C_DQ<18>")
	)
	(segment
		(start 227.047044 -36.980876)
		(end 227.290376 -36.737544)
		(width 0.14224)
		(layer "In11.Cu")
		(net "M_C_DQ<18>")
	)
	(segment
		(start 223.099376 -11.565636)
		(end 223.24314 -11.7094)
		(width 0.14224)
		(layer "In11.Cu")
		(net "M_C_DQ<18>")
	)
	(segment
		(start 236.618526 -46.4566)
		(end 238.287306 -48.12538)
		(width 0.14224)
		(layer "In11.Cu")
		(net "M_C_DQ<18>")
	)
	(arc
		(start 239.392968 -52.418488)
		(mid 239.601576 -52.63042)
		(end 239.886998 -52.71389)
		(width 0.0889)
		(layer "In11.Cu")
		(net "M_C_DQ<18>")
	)
	(arc
		(start 242.826794 -54.399942)
		(mid 243.032415 -54.609865)
		(end 243.313712 -54.694836)
		(width 0.0889)
		(layer "In11.Cu")
		(net "M_C_DQ<18>")
	)
	(arc
		(start 239.922812 -52.71389)
		(mid 240.112741 -52.77176)
		(end 240.251488 -52.913788)
		(width 0.0889)
		(layer "In11.Cu")
		(net "M_C_DQ<18>")
	)
	(arc
		(start 243.34978 -54.694836)
		(mid 243.54363 -54.751186)
		(end 243.685314 -54.894988)
		(width 0.0889)
		(layer "In11.Cu")
		(net "M_C_DQ<18>")
	)
	(arc
		(start 240.251488 -52.913788)
		(mid 240.462201 -53.126867)
		(end 240.750344 -53.20919)
		(width 0.0889)
		(layer "In11.Cu")
		(net "M_C_DQ<18>")
	)
	(arc
		(start 244.21211 -55.19039)
		(mid 244.403752 -55.247556)
		(end 244.543834 -55.390288)
		(width 0.0889)
		(layer "In11.Cu")
		(net "M_C_DQ<18>")
	)
	(arc
		(start 241.110008 -53.409088)
		(mid 241.317012 -53.619952)
		(end 241.600228 -53.704236)
		(width 0.0889)
		(layer "In11.Cu")
		(net "M_C_DQ<18>")
	)
	(arc
		(start 241.626644 -53.704236)
		(mid 241.824141 -53.759136)
		(end 241.968528 -53.904642)
		(width 0.0889)
		(layer "In11.Cu")
		(net "M_C_DQ<18>")
	)
	(arc
		(start 238.534448 -50.341784)
		(mid 238.455259 -50.628399)
		(end 238.525558 -50.917348)
		(width 0.0889)
		(layer "In11.Cu")
		(net "M_C_DQ<18>")
	)
	(arc
		(start 239.064292 -52.21859)
		(mid 239.254221 -52.27646)
		(end 239.392968 -52.418488)
		(width 0.0889)
		(layer "In11.Cu")
		(net "M_C_DQ<18>")
	)
	(arc
		(start 243.685314 -54.894988)
		(mid 243.893922 -55.10692)
		(end 244.179344 -55.19039)
		(width 0.0889)
		(layer "In11.Cu")
		(net "M_C_DQ<18>")
	)
	(arc
		(start 242.49253 -54.200044)
		(mid 242.685633 -54.256563)
		(end 242.826794 -54.399942)
		(width 0.0889)
		(layer "In11.Cu")
		(net "M_C_DQ<18>")
	)
	(arc
		(start 238.534448 -51.332638)
		(mid 238.529194 -51.914146)
		(end 239.024668 -52.21859)
		(width 0.0889)
		(layer "In11.Cu")
		(net "M_C_DQ<18>")
	)
	(arc
		(start 238.539274 -50.941224)
		(mid 238.588029 -51.137576)
		(end 238.534448 -51.332638)
		(width 0.0889)
		(layer "In11.Cu")
		(net "M_C_DQ<18>")
	)
	(arc
		(start 241.968528 -53.904642)
		(mid 242.177136 -54.116574)
		(end 242.462558 -54.200044)
		(width 0.0889)
		(layer "In11.Cu")
		(net "M_C_DQ<18>")
	)
	(arc
		(start 244.543834 -55.390288)
		(mid 244.750838 -55.601152)
		(end 245.034054 -55.685436)
		(width 0.0889)
		(layer "In11.Cu")
		(net "M_C_DQ<18>")
	)
	(arc
		(start 245.06682 -55.685436)
		(mid 245.26067 -55.741786)
		(end 245.402354 -55.885588)
		(width 0.0889)
		(layer "In11.Cu")
		(net "M_C_DQ<18>")
	)
	(arc
		(start 240.778284 -53.20919)
		(mid 240.969926 -53.266356)
		(end 241.110008 -53.409088)
		(width 0.0889)
		(layer "In11.Cu")
		(net "M_C_DQ<18>")
	)
	(arc
		(start 245.402354 -55.885588)
		(mid 245.45249 -55.959111)
		(end 245.513098 -56.024272)
		(width 0.0889)
		(layer "In11.Cu")
		(net "M_C_DQ<18>")
	)
	(segment
		(start 246.485664 -59.55284)
		(end 245.914164 -59.55284)
		(width 0.0889)
		(layer "F.Cu")
		(net "M_C_DQ<17>")
	)
	(segment
		(start 216.799922 3.778758)
		(end 216.799922 2.514854)
		(width 0.1651)
		(layer "F.Cu")
		(net "M_C_DQ<17>")
	)
	(segment
		(start 216.80043 3.778758)
		(end 216.799922 3.778758)
		(width 0.1651)
		(layer "F.Cu")
		(net "M_C_DQ<17>")
	)
	(via
		(at 245.914164 -59.55284)
		(size 0.508)
		(drill 0.254)
		(layers "F.Cu" "B.Cu")
		(net "M_C_DQ<17>")
	)
	(via
		(at 216.799922 2.514854)
		(size 0.508)
		(drill 0.254)
		(layers "F.Cu" "B.Cu")
		(net "M_C_DQ<17>")
	)
	(via
		(at 217.472006 -3.076956)
		(size 0.508)
		(drill 0.254)
		(layers "F.Cu" "B.Cu")
		(net "M_C_DQ<17>")
	)
	(segment
		(start 217.472006 -2.573782)
		(end 217.472006 -3.076956)
		(width 0.1651)
		(layer "B.Cu")
		(net "M_C_DQ<17>")
	)
	(segment
		(start 217.649806 -1.021842)
		(end 217.649806 -2.395982)
		(width 0.1651)
		(layer "B.Cu")
		(net "M_C_DQ<17>")
	)
	(segment
		(start 217.649806 -2.395982)
		(end 217.472006 -2.573782)
		(width 0.1651)
		(layer "B.Cu")
		(net "M_C_DQ<17>")
	)
	(segment
		(start 217.650314 -1.021842)
		(end 217.649806 -1.021842)
		(width 0.1651)
		(layer "B.Cu")
		(net "M_C_DQ<17>")
	)
	(segment
		(start 239.035082 -55.99049)
		(end 239.067848 -55.99049)
		(width 0.0889)
		(layer "In11.Cu")
		(net "M_C_DQ<17>")
	)
	(segment
		(start 217.95994 -6.428994)
		(end 217.95994 -9.34974)
		(width 0.14224)
		(layer "In11.Cu")
		(net "M_C_DQ<17>")
	)
	(segment
		(start 239.889792 -56.485536)
		(end 239.922558 -56.485536)
		(width 0.0889)
		(layer "In11.Cu")
		(net "M_C_DQ<17>")
	)
	(segment
		(start 216.945464 -3.864864)
		(end 217.2716 -4.191)
		(width 0.14224)
		(layer "In11.Cu")
		(net "M_C_DQ<17>")
	)
	(segment
		(start 244.413024 -58.217562)
		(end 244.520974 -58.284618)
		(width 0.0889)
		(layer "In11.Cu")
		(net "M_C_DQ<17>")
	)
	(segment
		(start 217.95994 -9.34974)
		(end 218.1352 -9.525)
		(width 0.14224)
		(layer "In11.Cu")
		(net "M_C_DQ<17>")
	)
	(segment
		(start 244.59692 -58.454036)
		(end 244.660928 -58.990992)
		(width 0.0889)
		(layer "In11.Cu")
		(net "M_C_DQ<17>")
	)
	(segment
		(start 218.1098 -21.199348)
		(end 217.95994 -21.349208)
		(width 0.14224)
		(layer "In11.Cu")
		(net "M_C_DQ<17>")
	)
	(segment
		(start 230.93807 -47.60087)
		(end 233.459274 -50.122074)
		(width 0.14224)
		(layer "In11.Cu")
		(net "M_C_DQ<17>")
	)
	(segment
		(start 217.846148 0.630936)
		(end 217.846148 -2.702814)
		(width 0.14224)
		(layer "In11.Cu")
		(net "M_C_DQ<17>")
	)
	(segment
		(start 235.601002 -54.00929)
		(end 235.633768 -54.00929)
		(width 0.0889)
		(layer "In11.Cu")
		(net "M_C_DQ<17>")
	)
	(segment
		(start 217.472006 -3.076956)
		(end 216.945464 -3.603498)
		(width 0.14224)
		(layer "In11.Cu")
		(net "M_C_DQ<17>")
	)
	(segment
		(start 234.214924 -50.670968)
		(end 234.214924 -50.999898)
		(width 0.0889)
		(layer "In11.Cu")
		(net "M_C_DQ<17>")
	)
	(segment
		(start 217.2716 -5.740654)
		(end 217.95994 -6.428994)
		(width 0.14224)
		(layer "In11.Cu")
		(net "M_C_DQ<17>")
	)
	(segment
		(start 218.1352 -9.525)
		(end 218.1352 -11.55954)
		(width 0.14224)
		(layer "In11.Cu")
		(net "M_C_DQ<17>")
	)
	(segment
		(start 217.2716 -4.191)
		(end 217.2716 -5.740654)
		(width 0.14224)
		(layer "In11.Cu")
		(net "M_C_DQ<17>")
	)
	(segment
		(start 245.040658 -59.457336)
		(end 245.091712 -59.457336)
		(width 0.0889)
		(layer "In11.Cu")
		(net "M_C_DQ<17>")
	)
	(segment
		(start 218.6178 -34.177224)
		(end 230.93807 -46.497494)
		(width 0.14224)
		(layer "In11.Cu")
		(net "M_C_DQ<17>")
	)
	(segment
		(start 217.95994 -11.7348)
		(end 217.95994 -19.00174)
		(width 0.14224)
		(layer "In11.Cu")
		(net "M_C_DQ<17>")
	)
	(segment
		(start 234.214924 -50.999898)
		(end 234.406948 -51.332638)
		(width 0.0889)
		(layer "In11.Cu")
		(net "M_C_DQ<17>")
	)
	(segment
		(start 216.945464 -3.603498)
		(end 216.945464 -3.864864)
		(width 0.14224)
		(layer "In11.Cu")
		(net "M_C_DQ<17>")
	)
	(segment
		(start 244.324124 -58.16219)
		(end 244.413024 -58.217562)
		(width 0.0889)
		(layer "In11.Cu")
		(net "M_C_DQ<17>")
	)
	(segment
		(start 230.93807 -46.497494)
		(end 230.93807 -47.60087)
		(width 0.14224)
		(layer "In11.Cu")
		(net "M_C_DQ<17>")
	)
	(segment
		(start 233.66603 -50.122074)
		(end 234.214924 -50.670968)
		(width 0.0889)
		(layer "In11.Cu")
		(net "M_C_DQ<17>")
	)
	(segment
		(start 244.520974 -58.284618)
		(end 244.59692 -58.454036)
		(width 0.0889)
		(layer "In11.Cu")
		(net "M_C_DQ<17>")
	)
	(segment
		(start 218.1098 -19.1516)
		(end 218.1098 -21.199348)
		(width 0.14224)
		(layer "In11.Cu")
		(net "M_C_DQ<17>")
	)
	(segment
		(start 236.455712 -54.504336)
		(end 236.488478 -54.504336)
		(width 0.0889)
		(layer "In11.Cu")
		(net "M_C_DQ<17>")
	)
	(segment
		(start 218.6178 -27.94)
		(end 218.6178 -34.177224)
		(width 0.14224)
		(layer "In11.Cu")
		(net "M_C_DQ<17>")
	)
	(segment
		(start 242.462304 -57.971436)
		(end 242.501928 -57.971436)
		(width 0.0889)
		(layer "In11.Cu")
		(net "M_C_DQ<17>")
	)
	(segment
		(start 218.002612 1.128776)
		(end 218.002612 0.7874)
		(width 0.14224)
		(layer "In11.Cu")
		(net "M_C_DQ<17>")
	)
	(segment
		(start 218.002612 0.7874)
		(end 217.846148 0.630936)
		(width 0.14224)
		(layer "In11.Cu")
		(net "M_C_DQ<17>")
	)
	(segment
		(start 233.459274 -50.122074)
		(end 233.66603 -50.122074)
		(width 0.14224)
		(layer "In11.Cu")
		(net "M_C_DQ<17>")
	)
	(segment
		(start 217.846148 -2.702814)
		(end 217.472006 -3.076956)
		(width 0.14224)
		(layer "In11.Cu")
		(net "M_C_DQ<17>")
	)
	(segment
		(start 216.799922 2.514854)
		(end 216.799922 1.975866)
		(width 0.14224)
		(layer "In11.Cu")
		(net "M_C_DQ<17>")
	)
	(segment
		(start 244.049804 -58.16219)
		(end 244.324124 -58.16219)
		(width 0.0889)
		(layer "In11.Cu")
		(net "M_C_DQ<17>")
	)
	(segment
		(start 217.95994 -23.94966)
		(end 217.805 -24.1046)
		(width 0.14224)
		(layer "In11.Cu")
		(net "M_C_DQ<17>")
	)
	(segment
		(start 243.338604 -58.466736)
		(end 243.356638 -58.466736)
		(width 0.0889)
		(layer "In11.Cu")
		(net "M_C_DQ<17>")
	)
	(segment
		(start 237.318042 -54.99989)
		(end 237.350808 -54.99989)
		(width 0.0889)
		(layer "In11.Cu")
		(net "M_C_DQ<17>")
	)
	(segment
		(start 243.637308 -58.333386)
		(end 244.049804 -58.16219)
		(width 0.0889)
		(layer "In11.Cu")
		(net "M_C_DQ<17>")
	)
	(segment
		(start 218.1352 -11.55954)
		(end 217.95994 -11.7348)
		(width 0.14224)
		(layer "In11.Cu")
		(net "M_C_DQ<17>")
	)
	(segment
		(start 217.95994 -21.349208)
		(end 217.95994 -23.94966)
		(width 0.14224)
		(layer "In11.Cu")
		(net "M_C_DQ<17>")
	)
	(segment
		(start 234.735624 -52.523136)
		(end 234.775248 -52.523136)
		(width 0.0889)
		(layer "In11.Cu")
		(net "M_C_DQ<17>")
	)
	(segment
		(start 217.277188 1.4986)
		(end 217.632788 1.4986)
		(width 0.14224)
		(layer "In11.Cu")
		(net "M_C_DQ<17>")
	)
	(segment
		(start 217.805 -27.1272)
		(end 218.6178 -27.94)
		(width 0.14224)
		(layer "In11.Cu")
		(net "M_C_DQ<17>")
	)
	(segment
		(start 217.805 -24.1046)
		(end 217.805 -27.1272)
		(width 0.14224)
		(layer "In11.Cu")
		(net "M_C_DQ<17>")
	)
	(segment
		(start 245.091712 -59.457336)
		(end 245.914164 -59.55284)
		(width 0.0889)
		(layer "In11.Cu")
		(net "M_C_DQ<17>")
	)
	(segment
		(start 241.606832 -57.476136)
		(end 241.634772 -57.476136)
		(width 0.0889)
		(layer "In11.Cu")
		(net "M_C_DQ<17>")
	)
	(segment
		(start 216.799922 1.975866)
		(end 217.277188 1.4986)
		(width 0.14224)
		(layer "In11.Cu")
		(net "M_C_DQ<17>")
	)
	(segment
		(start 217.632788 1.4986)
		(end 218.002612 1.128776)
		(width 0.14224)
		(layer "In11.Cu")
		(net "M_C_DQ<17>")
	)
	(segment
		(start 217.95994 -19.00174)
		(end 218.1098 -19.1516)
		(width 0.14224)
		(layer "In11.Cu")
		(net "M_C_DQ<17>")
	)
	(segment
		(start 242.992148 -58.266584)
		(end 242.99545 -58.272426)
		(width 0.0889)
		(layer "In11.Cu")
		(net "M_C_DQ<17>")
	)
	(segment
		(start 240.752122 -56.98109)
		(end 240.784888 -56.98109)
		(width 0.0889)
		(layer "In11.Cu")
		(net "M_C_DQ<17>")
	)
	(segment
		(start 238.172752 -55.494936)
		(end 238.205518 -55.494936)
		(width 0.0889)
		(layer "In11.Cu")
		(net "M_C_DQ<17>")
	)
	(arc
		(start 240.784888 -56.98109)
		(mid 241.068105 -57.065371)
		(end 241.275108 -57.276238)
		(width 0.0889)
		(layer "In11.Cu")
		(net "M_C_DQ<17>")
	)
	(arc
		(start 235.633768 -54.00929)
		(mid 235.916985 -54.093571)
		(end 236.123988 -54.304438)
		(width 0.0889)
		(layer "In11.Cu")
		(net "M_C_DQ<17>")
	)
	(arc
		(start 242.99545 -58.272426)
		(mid 243.141416 -58.414825)
		(end 243.338604 -58.466736)
		(width 0.0889)
		(layer "In11.Cu")
		(net "M_C_DQ<17>")
	)
	(arc
		(start 237.841028 -55.295038)
		(mid 237.981107 -55.437774)
		(end 238.172752 -55.494936)
		(width 0.0889)
		(layer "In11.Cu")
		(net "M_C_DQ<17>")
	)
	(arc
		(start 235.265468 -53.409088)
		(mid 235.26272 -53.804555)
		(end 235.601002 -54.00929)
		(width 0.0889)
		(layer "In11.Cu")
		(net "M_C_DQ<17>")
	)
	(arc
		(start 241.275108 -57.276238)
		(mid 241.415187 -57.418974)
		(end 241.606832 -57.476136)
		(width 0.0889)
		(layer "In11.Cu")
		(net "M_C_DQ<17>")
	)
	(arc
		(start 234.406948 -51.923442)
		(mid 234.402703 -52.315687)
		(end 234.735624 -52.523136)
		(width 0.0889)
		(layer "In11.Cu")
		(net "M_C_DQ<17>")
	)
	(arc
		(start 236.488478 -54.504336)
		(mid 236.773902 -54.587803)
		(end 236.982508 -54.799738)
		(width 0.0889)
		(layer "In11.Cu")
		(net "M_C_DQ<17>")
	)
	(arc
		(start 234.775248 -52.523136)
		(mid 235.270725 -52.827579)
		(end 235.265468 -53.409088)
		(width 0.0889)
		(layer "In11.Cu")
		(net "M_C_DQ<17>")
	)
	(arc
		(start 237.350808 -54.99989)
		(mid 237.634025 -55.084171)
		(end 237.841028 -55.295038)
		(width 0.0889)
		(layer "In11.Cu")
		(net "M_C_DQ<17>")
	)
	(arc
		(start 243.356638 -58.466736)
		(mid 243.451867 -58.450844)
		(end 243.540534 -58.412634)
		(width 0.0889)
		(layer "In11.Cu")
		(net "M_C_DQ<17>")
	)
	(arc
		(start 236.123988 -54.304438)
		(mid 236.264067 -54.447174)
		(end 236.455712 -54.504336)
		(width 0.0889)
		(layer "In11.Cu")
		(net "M_C_DQ<17>")
	)
	(arc
		(start 244.660928 -58.990992)
		(mid 244.745302 -59.310037)
		(end 245.040658 -59.457336)
		(width 0.0889)
		(layer "In11.Cu")
		(net "M_C_DQ<17>")
	)
	(arc
		(start 239.558068 -56.285638)
		(mid 239.698147 -56.428374)
		(end 239.889792 -56.485536)
		(width 0.0889)
		(layer "In11.Cu")
		(net "M_C_DQ<17>")
	)
	(arc
		(start 239.067848 -55.99049)
		(mid 239.351065 -56.074771)
		(end 239.558068 -56.285638)
		(width 0.0889)
		(layer "In11.Cu")
		(net "M_C_DQ<17>")
	)
	(arc
		(start 242.501928 -57.971436)
		(mid 242.785145 -58.055717)
		(end 242.992148 -58.266584)
		(width 0.0889)
		(layer "In11.Cu")
		(net "M_C_DQ<17>")
	)
	(arc
		(start 240.416588 -56.780938)
		(mid 240.558271 -56.924742)
		(end 240.752122 -56.98109)
		(width 0.0889)
		(layer "In11.Cu")
		(net "M_C_DQ<17>")
	)
	(arc
		(start 238.205518 -55.494936)
		(mid 238.490942 -55.578403)
		(end 238.699548 -55.790338)
		(width 0.0889)
		(layer "In11.Cu")
		(net "M_C_DQ<17>")
	)
	(arc
		(start 234.406948 -51.332638)
		(mid 234.486079 -51.62804)
		(end 234.406948 -51.923442)
		(width 0.0889)
		(layer "In11.Cu")
		(net "M_C_DQ<17>")
	)
	(arc
		(start 243.540534 -58.412634)
		(mid 243.592024 -58.376801)
		(end 243.637308 -58.333386)
		(width 0.0889)
		(layer "In11.Cu")
		(net "M_C_DQ<17>")
	)
	(arc
		(start 239.922558 -56.485536)
		(mid 240.207982 -56.569003)
		(end 240.416588 -56.780938)
		(width 0.0889)
		(layer "In11.Cu")
		(net "M_C_DQ<17>")
	)
	(arc
		(start 241.634772 -57.476136)
		(mid 241.922917 -57.558455)
		(end 242.133628 -57.771538)
		(width 0.0889)
		(layer "In11.Cu")
		(net "M_C_DQ<17>")
	)
	(arc
		(start 242.133628 -57.771538)
		(mid 242.272372 -57.913571)
		(end 242.462304 -57.971436)
		(width 0.0889)
		(layer "In11.Cu")
		(net "M_C_DQ<17>")
	)
	(arc
		(start 236.982508 -54.799738)
		(mid 237.124191 -54.943542)
		(end 237.318042 -54.99989)
		(width 0.0889)
		(layer "In11.Cu")
		(net "M_C_DQ<17>")
	)
	(arc
		(start 238.699548 -55.790338)
		(mid 238.841231 -55.934142)
		(end 239.035082 -55.99049)
		(width 0.0889)
		(layer "In11.Cu")
		(net "M_C_DQ<17>")
	)
	(segment
		(start 217.649806 -0.821182)
		(end 217.472006 1.0414)
		(width 0.1651)
		(layer "F.Cu")
		(net "M_C_DQ<16>")
	)
	(segment
		(start 244.768624 -58.561986)
		(end 244.197124 -58.561986)
		(width 0.0889)
		(layer "F.Cu")
		(net "M_C_DQ<16>")
	)
	(segment
		(start 217.650314 -0.821182)
		(end 217.649806 -0.821182)
		(width 0.1651)
		(layer "F.Cu")
		(net "M_C_DQ<16>")
	)
	(via
		(at 217.472006 1.0414)
		(size 0.508)
		(drill 0.254)
		(layers "F.Cu" "B.Cu")
		(net "M_C_DQ<16>")
	)
	(via
		(at 216.799922 -4.357878)
		(size 0.508)
		(drill 0.254)
		(layers "F.Cu" "B.Cu")
		(net "M_C_DQ<16>")
	)
	(via
		(at 244.197124 -58.561986)
		(size 0.508)
		(drill 0.254)
		(layers "F.Cu" "B.Cu")
		(net "M_C_DQ<16>")
	)
	(segment
		(start 216.80043 -5.621782)
		(end 216.799922 -5.621782)
		(width 0.1651)
		(layer "B.Cu")
		(net "M_C_DQ<16>")
	)
	(segment
		(start 216.799922 -5.621782)
		(end 216.799922 -4.357878)
		(width 0.1651)
		(layer "B.Cu")
		(net "M_C_DQ<16>")
	)
	(segment
		(start 230.310944 -46.955456)
		(end 229.953312 -47.313088)
		(width 0.14224)
		(layer "In11.Cu")
		(net "M_C_DQ<16>")
	)
	(segment
		(start 230.310944 -46.753272)
		(end 230.310944 -46.955456)
		(width 0.14224)
		(layer "In11.Cu")
		(net "M_C_DQ<16>")
	)
	(segment
		(start 217.27414 -6.682486)
		(end 217.27414 -7.224776)
		(width 0.14224)
		(layer "In11.Cu")
		(net "M_C_DQ<16>")
	)
	(segment
		(start 243.320824 -58.65749)
		(end 243.689378 -58.65749)
		(width 0.0889)
		(layer "In11.Cu")
		(net "M_C_DQ<16>")
	)
	(segment
		(start 244.16512 -58.602118)
		(end 244.197124 -58.561986)
		(width 0.0889)
		(layer "In11.Cu")
		(net "M_C_DQ<16>")
	)
	(segment
		(start 217.32494 -12.081256)
		(end 216.98204 -12.424156)
		(width 0.14224)
		(layer "In11.Cu")
		(net "M_C_DQ<16>")
	)
	(segment
		(start 229.953312 -47.514256)
		(end 233.19613 -50.757074)
		(width 0.14224)
		(layer "In11.Cu")
		(net "M_C_DQ<16>")
	)
	(segment
		(start 217.251788 0.821182)
		(end 217.472006 1.0414)
		(width 0.14224)
		(layer "In11.Cu")
		(net "M_C_DQ<16>")
	)
	(segment
		(start 241.608864 -57.66689)
		(end 241.632994 -57.66689)
		(width 0.0889)
		(layer "In11.Cu")
		(net "M_C_DQ<16>")
	)
	(segment
		(start 216.837006 -0.508)
		(end 216.837006 -0.178054)
		(width 0.14224)
		(layer "In11.Cu")
		(net "M_C_DQ<16>")
	)
	(segment
		(start 239.028478 -56.18099)
		(end 239.061244 -56.18099)
		(width 0.0889)
		(layer "In11.Cu")
		(net "M_C_DQ<16>")
	)
	(segment
		(start 233.19613 -50.757074)
		(end 233.247184 -50.757074)
		(width 0.14224)
		(layer "In11.Cu")
		(net "M_C_DQ<16>")
	)
	(segment
		(start 216.98204 -18.302986)
		(end 217.32494 -18.645886)
		(width 0.14224)
		(layer "In11.Cu")
		(net "M_C_DQ<16>")
	)
	(segment
		(start 217.32494 -21.33854)
		(end 217.32494 -21.682456)
		(width 0.14224)
		(layer "In11.Cu")
		(net "M_C_DQ<16>")
	)
	(segment
		(start 216.515188 -3.3274)
		(end 217.251788 -2.5908)
		(width 0.14224)
		(layer "In11.Cu")
		(net "M_C_DQ<16>")
	)
	(segment
		(start 217.9828 -34.425128)
		(end 229.220268 -45.662596)
		(width 0.14224)
		(layer "In11.Cu")
		(net "M_C_DQ<16>")
	)
	(segment
		(start 229.690676 -46.351952)
		(end 229.909624 -46.351952)
		(width 0.14224)
		(layer "In11.Cu")
		(net "M_C_DQ<16>")
	)
	(segment
		(start 217.251788 -2.090928)
		(end 216.862406 -1.701546)
		(width 0.14224)
		(layer "In11.Cu")
		(net "M_C_DQ<16>")
	)
	(segment
		(start 217.27414 -7.224776)
		(end 216.98204 -7.516876)
		(width 0.14224)
		(layer "In11.Cu")
		(net "M_C_DQ<16>")
	)
	(segment
		(start 242.458748 -58.16219)
		(end 242.49253 -58.16219)
		(width 0.0889)
		(layer "In11.Cu")
		(net "M_C_DQ<16>")
	)
	(segment
		(start 216.98204 -23.10384)
		(end 217.2716 -23.3934)
		(width 0.14224)
		(layer "In11.Cu")
		(net "M_C_DQ<16>")
	)
	(segment
		(start 217.251788 0.236728)
		(end 217.251788 0.821182)
		(width 0.14224)
		(layer "In11.Cu")
		(net "M_C_DQ<16>")
	)
	(segment
		(start 228.98354 -46.84014)
		(end 229.202488 -46.84014)
		(width 0.14224)
		(layer "In11.Cu")
		(net "M_C_DQ<16>")
	)
	(segment
		(start 216.98204 -8.701786)
		(end 217.32494 -9.044686)
		(width 0.14224)
		(layer "In11.Cu")
		(net "M_C_DQ<16>")
	)
	(segment
		(start 216.515188 -4.073144)
		(end 216.515188 -3.3274)
		(width 0.14224)
		(layer "In11.Cu")
		(net "M_C_DQ<16>")
	)
	(segment
		(start 217.32494 -9.044686)
		(end 217.32494 -9.34466)
		(width 0.14224)
		(layer "In11.Cu")
		(net "M_C_DQ<16>")
	)
	(segment
		(start 229.220268 -45.662596)
		(end 229.220268 -45.881544)
		(width 0.14224)
		(layer "In11.Cu")
		(net "M_C_DQ<16>")
	)
	(segment
		(start 216.799922 -4.357878)
		(end 216.515188 -4.073144)
		(width 0.14224)
		(layer "In11.Cu")
		(net "M_C_DQ<16>")
	)
	(segment
		(start 217.1192 -21.1328)
		(end 217.32494 -21.33854)
		(width 0.14224)
		(layer "In11.Cu")
		(net "M_C_DQ<16>")
	)
	(segment
		(start 217.32494 -13.84554)
		(end 217.32494 -16.781018)
		(width 0.14224)
		(layer "In11.Cu")
		(net "M_C_DQ<16>")
	)
	(segment
		(start 217.179906 -1.0795)
		(end 217.179906 -0.8509)
		(width 0.14224)
		(layer "In11.Cu")
		(net "M_C_DQ<16>")
	)
	(segment
		(start 216.837006 -0.178054)
		(end 217.251788 0.236728)
		(width 0.14224)
		(layer "In11.Cu")
		(net "M_C_DQ<16>")
	)
	(segment
		(start 228.73208 -46.58868)
		(end 228.98354 -46.84014)
		(width 0.14224)
		(layer "In11.Cu")
		(net "M_C_DQ<16>")
	)
	(segment
		(start 217.251788 -2.5908)
		(end 217.251788 -2.090928)
		(width 0.14224)
		(layer "In11.Cu")
		(net "M_C_DQ<16>")
	)
	(segment
		(start 217.2716 -23.3934)
		(end 217.2716 -27.512264)
		(width 0.14224)
		(layer "In11.Cu")
		(net "M_C_DQ<16>")
	)
	(segment
		(start 240.745518 -57.17159)
		(end 240.778284 -57.17159)
		(width 0.0889)
		(layer "In11.Cu")
		(net "M_C_DQ<16>")
	)
	(segment
		(start 217.32494 -11.7856)
		(end 217.32494 -12.081256)
		(width 0.14224)
		(layer "In11.Cu")
		(net "M_C_DQ<16>")
	)
	(segment
		(start 217.2716 -27.512264)
		(end 217.9828 -28.223464)
		(width 0.14224)
		(layer "In11.Cu")
		(net "M_C_DQ<16>")
	)
	(segment
		(start 216.862406 -1.701546)
		(end 216.862406 -1.397)
		(width 0.14224)
		(layer "In11.Cu")
		(net "M_C_DQ<16>")
	)
	(segment
		(start 235.594398 -54.19979)
		(end 235.627164 -54.19979)
		(width 0.0889)
		(layer "In11.Cu")
		(net "M_C_DQ<16>")
	)
	(segment
		(start 217.32494 -18.645886)
		(end 217.32494 -18.94586)
		(width 0.14224)
		(layer "In11.Cu")
		(net "M_C_DQ<16>")
	)
	(segment
		(start 217.9828 -28.223464)
		(end 217.9828 -34.425128)
		(width 0.14224)
		(layer "In11.Cu")
		(net "M_C_DQ<16>")
	)
	(segment
		(start 243.689378 -58.65749)
		(end 244.16512 -58.602118)
		(width 0.0889)
		(layer "In11.Cu")
		(net "M_C_DQ<16>")
	)
	(segment
		(start 217.17 -11.63066)
		(end 217.32494 -11.7856)
		(width 0.14224)
		(layer "In11.Cu")
		(net "M_C_DQ<16>")
	)
	(segment
		(start 229.953312 -47.313088)
		(end 229.953312 -47.514256)
		(width 0.14224)
		(layer "In11.Cu")
		(net "M_C_DQ<16>")
	)
	(segment
		(start 216.98204 -12.424156)
		(end 216.98204 -13.50264)
		(width 0.14224)
		(layer "In11.Cu")
		(net "M_C_DQ<16>")
	)
	(segment
		(start 236.449108 -54.694836)
		(end 236.481874 -54.694836)
		(width 0.0889)
		(layer "In11.Cu")
		(net "M_C_DQ<16>")
	)
	(segment
		(start 239.883188 -56.676036)
		(end 239.915954 -56.676036)
		(width 0.0889)
		(layer "In11.Cu")
		(net "M_C_DQ<16>")
	)
	(segment
		(start 237.311438 -55.19039)
		(end 237.344204 -55.19039)
		(width 0.0889)
		(layer "In11.Cu")
		(net "M_C_DQ<16>")
	)
	(segment
		(start 234.735878 -52.71389)
		(end 234.771692 -52.71389)
		(width 0.0889)
		(layer "In11.Cu")
		(net "M_C_DQ<16>")
	)
	(segment
		(start 217.32494 -21.682456)
		(end 216.98204 -22.025356)
		(width 0.14224)
		(layer "In11.Cu")
		(net "M_C_DQ<16>")
	)
	(segment
		(start 217.179906 -0.8509)
		(end 216.837006 -0.508)
		(width 0.14224)
		(layer "In11.Cu")
		(net "M_C_DQ<16>")
	)
	(segment
		(start 229.909624 -46.351952)
		(end 230.310944 -46.753272)
		(width 0.14224)
		(layer "In11.Cu")
		(net "M_C_DQ<16>")
	)
	(segment
		(start 216.98204 -17.123918)
		(end 216.98204 -18.302986)
		(width 0.14224)
		(layer "In11.Cu")
		(net "M_C_DQ<16>")
	)
	(segment
		(start 217.17 -9.4996)
		(end 217.17 -11.63066)
		(width 0.14224)
		(layer "In11.Cu")
		(net "M_C_DQ<16>")
	)
	(segment
		(start 216.862406 -1.397)
		(end 217.179906 -1.0795)
		(width 0.14224)
		(layer "In11.Cu")
		(net "M_C_DQ<16>")
	)
	(segment
		(start 217.32494 -18.94586)
		(end 217.1192 -19.1516)
		(width 0.14224)
		(layer "In11.Cu")
		(net "M_C_DQ<16>")
	)
	(segment
		(start 229.202488 -46.84014)
		(end 229.690676 -46.351952)
		(width 0.14224)
		(layer "In11.Cu")
		(net "M_C_DQ<16>")
	)
	(segment
		(start 216.799922 -4.357878)
		(end 216.799922 -6.208268)
		(width 0.14224)
		(layer "In11.Cu")
		(net "M_C_DQ<16>")
	)
	(segment
		(start 233.718354 -51.228244)
		(end 233.915712 -51.228244)
		(width 0.0889)
		(layer "In11.Cu")
		(net "M_C_DQ<16>")
	)
	(segment
		(start 216.98204 -22.025356)
		(end 216.98204 -23.10384)
		(width 0.14224)
		(layer "In11.Cu")
		(net "M_C_DQ<16>")
	)
	(segment
		(start 228.73208 -46.369732)
		(end 228.73208 -46.58868)
		(width 0.14224)
		(layer "In11.Cu")
		(net "M_C_DQ<16>")
	)
	(segment
		(start 229.220268 -45.881544)
		(end 228.73208 -46.369732)
		(width 0.14224)
		(layer "In11.Cu")
		(net "M_C_DQ<16>")
	)
	(segment
		(start 217.32494 -9.34466)
		(end 217.17 -9.4996)
		(width 0.14224)
		(layer "In11.Cu")
		(net "M_C_DQ<16>")
	)
	(segment
		(start 217.1192 -19.1516)
		(end 217.1192 -21.1328)
		(width 0.14224)
		(layer "In11.Cu")
		(net "M_C_DQ<16>")
	)
	(segment
		(start 217.32494 -16.781018)
		(end 216.98204 -17.123918)
		(width 0.14224)
		(layer "In11.Cu")
		(net "M_C_DQ<16>")
	)
	(segment
		(start 233.247184 -50.757074)
		(end 233.718354 -51.228244)
		(width 0.0889)
		(layer "In11.Cu")
		(net "M_C_DQ<16>")
	)
	(segment
		(start 216.799922 -6.208268)
		(end 217.27414 -6.682486)
		(width 0.14224)
		(layer "In11.Cu")
		(net "M_C_DQ<16>")
	)
	(segment
		(start 216.98204 -13.50264)
		(end 217.32494 -13.84554)
		(width 0.14224)
		(layer "In11.Cu")
		(net "M_C_DQ<16>")
	)
	(segment
		(start 216.98204 -7.516876)
		(end 216.98204 -8.701786)
		(width 0.14224)
		(layer "In11.Cu")
		(net "M_C_DQ<16>")
	)
	(segment
		(start 238.166148 -55.685436)
		(end 238.198914 -55.685436)
		(width 0.0889)
		(layer "In11.Cu")
		(net "M_C_DQ<16>")
	)
	(segment
		(start 234.246674 -51.819302)
		(end 234.241848 -51.827938)
		(width 0.0889)
		(layer "In11.Cu")
		(net "M_C_DQ<16>")
	)
	(arc
		(start 240.778284 -57.17159)
		(mid 240.969926 -57.228756)
		(end 241.110008 -57.371488)
		(width 0.0889)
		(layer "In11.Cu")
		(net "M_C_DQ<16>")
	)
	(arc
		(start 234.771692 -52.71389)
		(mid 235.104661 -52.921438)
		(end 235.100368 -53.313838)
		(width 0.0889)
		(layer "In11.Cu")
		(net "M_C_DQ<16>")
	)
	(arc
		(start 242.49253 -58.16219)
		(mid 242.685633 -58.218709)
		(end 242.826794 -58.362088)
		(width 0.0889)
		(layer "In11.Cu")
		(net "M_C_DQ<16>")
	)
	(arc
		(start 239.061244 -56.18099)
		(mid 239.252886 -56.238156)
		(end 239.392968 -56.380888)
		(width 0.0889)
		(layer "In11.Cu")
		(net "M_C_DQ<16>")
	)
	(arc
		(start 242.826794 -58.362088)
		(mid 243.035402 -58.57402)
		(end 243.320824 -58.65749)
		(width 0.0889)
		(layer "In11.Cu")
		(net "M_C_DQ<16>")
	)
	(arc
		(start 239.392968 -56.380888)
		(mid 239.599972 -56.591752)
		(end 239.883188 -56.676036)
		(width 0.0889)
		(layer "In11.Cu")
		(net "M_C_DQ<16>")
	)
	(arc
		(start 241.110008 -57.371488)
		(mid 241.320721 -57.584567)
		(end 241.608864 -57.66689)
		(width 0.0889)
		(layer "In11.Cu")
		(net "M_C_DQ<16>")
	)
	(arc
		(start 233.915712 -51.228244)
		(mid 234.244412 -51.432419)
		(end 234.246674 -51.819302)
		(width 0.0889)
		(layer "In11.Cu")
		(net "M_C_DQ<16>")
	)
	(arc
		(start 237.675928 -55.390288)
		(mid 237.882932 -55.601152)
		(end 238.166148 -55.685436)
		(width 0.0889)
		(layer "In11.Cu")
		(net "M_C_DQ<16>")
	)
	(arc
		(start 239.915954 -56.676036)
		(mid 240.109804 -56.732386)
		(end 240.251488 -56.876188)
		(width 0.0889)
		(layer "In11.Cu")
		(net "M_C_DQ<16>")
	)
	(arc
		(start 238.534448 -55.885588)
		(mid 238.743056 -56.09752)
		(end 239.028478 -56.18099)
		(width 0.0889)
		(layer "In11.Cu")
		(net "M_C_DQ<16>")
	)
	(arc
		(start 235.958888 -54.399688)
		(mid 236.165892 -54.610552)
		(end 236.449108 -54.694836)
		(width 0.0889)
		(layer "In11.Cu")
		(net "M_C_DQ<16>")
	)
	(arc
		(start 236.817408 -54.894988)
		(mid 237.026016 -55.10692)
		(end 237.311438 -55.19039)
		(width 0.0889)
		(layer "In11.Cu")
		(net "M_C_DQ<16>")
	)
	(arc
		(start 236.481874 -54.694836)
		(mid 236.675724 -54.751186)
		(end 236.817408 -54.894988)
		(width 0.0889)
		(layer "In11.Cu")
		(net "M_C_DQ<16>")
	)
	(arc
		(start 234.241848 -51.827938)
		(mid 234.237519 -52.41111)
		(end 234.735878 -52.71389)
		(width 0.0889)
		(layer "In11.Cu")
		(net "M_C_DQ<16>")
	)
	(arc
		(start 235.100368 -53.313838)
		(mid 235.096039 -53.89701)
		(end 235.594398 -54.19979)
		(width 0.0889)
		(layer "In11.Cu")
		(net "M_C_DQ<16>")
	)
	(arc
		(start 237.344204 -55.19039)
		(mid 237.535846 -55.247556)
		(end 237.675928 -55.390288)
		(width 0.0889)
		(layer "In11.Cu")
		(net "M_C_DQ<16>")
	)
	(arc
		(start 241.632994 -57.66689)
		(mid 241.826844 -57.72324)
		(end 241.968528 -57.867042)
		(width 0.0889)
		(layer "In11.Cu")
		(net "M_C_DQ<16>")
	)
	(arc
		(start 238.198914 -55.685436)
		(mid 238.392764 -55.741786)
		(end 238.534448 -55.885588)
		(width 0.0889)
		(layer "In11.Cu")
		(net "M_C_DQ<16>")
	)
	(arc
		(start 235.627164 -54.19979)
		(mid 235.818806 -54.256956)
		(end 235.958888 -54.399688)
		(width 0.0889)
		(layer "In11.Cu")
		(net "M_C_DQ<16>")
	)
	(arc
		(start 241.968528 -57.867042)
		(mid 242.175532 -58.077906)
		(end 242.458748 -58.16219)
		(width 0.0889)
		(layer "In11.Cu")
		(net "M_C_DQ<16>")
	)
	(arc
		(start 240.251488 -56.876188)
		(mid 240.460096 -57.08812)
		(end 240.745518 -57.17159)
		(width 0.0889)
		(layer "In11.Cu")
		(net "M_C_DQ<16>")
	)
	(segment
		(start 242.193318 -59.057286)
		(end 241.621818 -59.057286)
		(width 0.0889)
		(layer "F.Cu")
		(net "M_C_DQ<15>")
	)
	(segment
		(start 211.699856 3.778758)
		(end 211.699856 2.514854)
		(width 0.1651)
		(layer "F.Cu")
		(net "M_C_DQ<15>")
	)
	(segment
		(start 211.700364 3.778758)
		(end 211.699856 3.778758)
		(width 0.1651)
		(layer "F.Cu")
		(net "M_C_DQ<15>")
	)
	(via
		(at 241.621818 -59.057286)
		(size 0.508)
		(drill 0.254)
		(layers "F.Cu" "B.Cu")
		(net "M_C_DQ<15>")
	)
	(via
		(at 212.54974 -3.076956)
		(size 0.508)
		(drill 0.254)
		(layers "F.Cu" "B.Cu")
		(net "M_C_DQ<15>")
	)
	(via
		(at 211.699856 2.514854)
		(size 0.508)
		(drill 0.254)
		(layers "F.Cu" "B.Cu")
		(net "M_C_DQ<15>")
	)
	(segment
		(start 212.550502 -1.021842)
		(end 212.550502 -3.076194)
		(width 0.1651)
		(layer "B.Cu")
		(net "M_C_DQ<15>")
	)
	(segment
		(start 212.550502 -3.076194)
		(end 212.54974 -3.076956)
		(width 0.1651)
		(layer "B.Cu")
		(net "M_C_DQ<15>")
	)
	(segment
		(start 213.105746 -21.974556)
		(end 213.105746 -23.117556)
		(width 0.14224)
		(layer "In11.Cu")
		(net "M_C_DQ<15>")
	)
	(segment
		(start 213.0552 -19.177)
		(end 213.0552 -21.208746)
		(width 0.14224)
		(layer "In11.Cu")
		(net "M_C_DQ<15>")
	)
	(segment
		(start 235.633768 -56.98109)
		(end 235.601002 -56.98109)
		(width 0.0889)
		(layer "In11.Cu")
		(net "M_C_DQ<15>")
	)
	(segment
		(start 212.902546 -12.170156)
		(end 213.105746 -12.373356)
		(width 0.14224)
		(layer "In11.Cu")
		(net "M_C_DQ<15>")
	)
	(segment
		(start 212.902546 -21.771356)
		(end 213.105746 -21.974556)
		(width 0.14224)
		(layer "In11.Cu")
		(net "M_C_DQ<15>")
	)
	(segment
		(start 212.344 -28.041854)
		(end 212.344 -33.2994)
		(width 0.14224)
		(layer "In11.Cu")
		(net "M_C_DQ<15>")
	)
	(segment
		(start 212.902546 -2.72415)
		(end 212.54974 -3.076956)
		(width 0.14224)
		(layer "In11.Cu")
		(net "M_C_DQ<15>")
	)
	(segment
		(start 212.458046 -4.782312)
		(end 212.927946 -5.252212)
		(width 0.14224)
		(layer "In11.Cu")
		(net "M_C_DQ<15>")
	)
	(segment
		(start 220.777562 -44.603162)
		(end 229.108 -52.9336)
		(width 0.14224)
		(layer "In11.Cu")
		(net "M_C_DQ<15>")
	)
	(segment
		(start 229.108 -53.213)
		(end 230.462582 -54.567582)
		(width 0.14224)
		(layer "In11.Cu")
		(net "M_C_DQ<15>")
	)
	(segment
		(start 212.089746 -3.53695)
		(end 212.089746 -4.067556)
		(width 0.14224)
		(layer "In11.Cu")
		(net "M_C_DQ<15>")
	)
	(segment
		(start 213.131146 -7.492746)
		(end 213.131146 -8.737854)
		(width 0.14224)
		(layer "In11.Cu")
		(net "M_C_DQ<15>")
	)
	(segment
		(start 240.502694 -59.248802)
		(end 240.239042 -59.388248)
		(width 0.0889)
		(layer "In11.Cu")
		(net "M_C_DQ<15>")
	)
	(segment
		(start 232.46715 -54.828694)
		(end 234.123992 -56.485536)
		(width 0.0889)
		(layer "In11.Cu")
		(net "M_C_DQ<15>")
	)
	(segment
		(start 213.0044 -11.6078)
		(end 212.902546 -11.709654)
		(width 0.14224)
		(layer "In11.Cu")
		(net "M_C_DQ<15>")
	)
	(segment
		(start 212.927946 -23.295356)
		(end 212.927946 -27.457908)
		(width 0.14224)
		(layer "In11.Cu")
		(net "M_C_DQ<15>")
	)
	(segment
		(start 212.016594 2.198116)
		(end 212.016594 1.8796)
		(width 0.14224)
		(layer "In11.Cu")
		(net "M_C_DQ<15>")
	)
	(segment
		(start 213.9696 -36.521136)
		(end 220.777562 -43.329098)
		(width 0.14224)
		(layer "In11.Cu")
		(net "M_C_DQ<15>")
	)
	(segment
		(start 213.9696 -30.5562)
		(end 213.9696 -36.521136)
		(width 0.14224)
		(layer "In11.Cu")
		(net "M_C_DQ<15>")
	)
	(segment
		(start 212.927946 -16.890746)
		(end 213.131146 -17.093946)
		(width 0.14224)
		(layer "In11.Cu")
		(net "M_C_DQ<15>")
	)
	(segment
		(start 212.346794 1.5494)
		(end 212.600794 1.5494)
		(width 0.14224)
		(layer "In11.Cu")
		(net "M_C_DQ<15>")
	)
	(segment
		(start 213.131146 -17.093946)
		(end 213.131146 -18.364454)
		(width 0.14224)
		(layer "In11.Cu")
		(net "M_C_DQ<15>")
	)
	(segment
		(start 212.016594 1.8796)
		(end 212.346794 1.5494)
		(width 0.14224)
		(layer "In11.Cu")
		(net "M_C_DQ<15>")
	)
	(segment
		(start 238.209328 -58.466736)
		(end 238.169704 -58.466736)
		(width 0.0889)
		(layer "In11.Cu")
		(net "M_C_DQ<15>")
	)
	(segment
		(start 213.131146 -8.737854)
		(end 212.902546 -8.966454)
		(width 0.14224)
		(layer "In11.Cu")
		(net "M_C_DQ<15>")
	)
	(segment
		(start 239.059212 -58.962036)
		(end 239.035082 -58.962036)
		(width 0.0889)
		(layer "In11.Cu")
		(net "M_C_DQ<15>")
	)
	(segment
		(start 212.344 -33.2994)
		(end 212.5472 -33.5026)
		(width 0.14224)
		(layer "In11.Cu")
		(net "M_C_DQ<15>")
	)
	(segment
		(start 212.600794 1.5494)
		(end 213.057994 1.0922)
		(width 0.14224)
		(layer "In11.Cu")
		(net "M_C_DQ<15>")
	)
	(segment
		(start 213.057994 0.7366)
		(end 212.902546 0.581152)
		(width 0.14224)
		(layer "In11.Cu")
		(net "M_C_DQ<15>")
	)
	(segment
		(start 213.105746 -23.117556)
		(end 212.927946 -23.295356)
		(width 0.14224)
		(layer "In11.Cu")
		(net "M_C_DQ<15>")
	)
	(segment
		(start 212.902546 -11.709654)
		(end 212.902546 -12.170156)
		(width 0.14224)
		(layer "In11.Cu")
		(net "M_C_DQ<15>")
	)
	(segment
		(start 213.0552 -21.208746)
		(end 212.902546 -21.3614)
		(width 0.14224)
		(layer "In11.Cu")
		(net "M_C_DQ<15>")
	)
	(segment
		(start 213.7664 -30.353)
		(end 213.9696 -30.5562)
		(width 0.14224)
		(layer "In11.Cu")
		(net "M_C_DQ<15>")
	)
	(segment
		(start 212.927946 -13.694156)
		(end 212.927946 -16.890746)
		(width 0.14224)
		(layer "In11.Cu")
		(net "M_C_DQ<15>")
	)
	(segment
		(start 213.0044 -9.576054)
		(end 213.0044 -11.6078)
		(width 0.14224)
		(layer "In11.Cu")
		(net "M_C_DQ<15>")
	)
	(segment
		(start 232.019856 -54.828694)
		(end 232.46715 -54.828694)
		(width 0.0889)
		(layer "In11.Cu")
		(net "M_C_DQ<15>")
	)
	(segment
		(start 212.5472 -33.5026)
		(end 212.9536 -33.5026)
		(width 0.14224)
		(layer "In11.Cu")
		(net "M_C_DQ<15>")
	)
	(segment
		(start 213.057994 1.0922)
		(end 213.057994 0.7366)
		(width 0.14224)
		(layer "In11.Cu")
		(net "M_C_DQ<15>")
	)
	(segment
		(start 212.902546 -18.593054)
		(end 212.902546 -19.024346)
		(width 0.14224)
		(layer "In11.Cu")
		(net "M_C_DQ<15>")
	)
	(segment
		(start 213.105746 -13.516356)
		(end 212.927946 -13.694156)
		(width 0.14224)
		(layer "In11.Cu")
		(net "M_C_DQ<15>")
	)
	(segment
		(start 212.902546 -8.966454)
		(end 212.902546 -9.4742)
		(width 0.14224)
		(layer "In11.Cu")
		(net "M_C_DQ<15>")
	)
	(segment
		(start 212.902546 -9.4742)
		(end 213.0044 -9.576054)
		(width 0.14224)
		(layer "In11.Cu")
		(net "M_C_DQ<15>")
	)
	(segment
		(start 212.902546 -21.3614)
		(end 212.902546 -21.771356)
		(width 0.14224)
		(layer "In11.Cu")
		(net "M_C_DQ<15>")
	)
	(segment
		(start 213.1568 -33.2994)
		(end 213.1568 -30.5562)
		(width 0.14224)
		(layer "In11.Cu")
		(net "M_C_DQ<15>")
	)
	(segment
		(start 212.089746 -4.067556)
		(end 212.458046 -4.435856)
		(width 0.14224)
		(layer "In11.Cu")
		(net "M_C_DQ<15>")
	)
	(segment
		(start 212.927946 -5.252212)
		(end 212.927946 -7.289546)
		(width 0.14224)
		(layer "In11.Cu")
		(net "M_C_DQ<15>")
	)
	(segment
		(start 213.131146 -18.364454)
		(end 212.902546 -18.593054)
		(width 0.14224)
		(layer "In11.Cu")
		(net "M_C_DQ<15>")
	)
	(segment
		(start 213.36 -30.353)
		(end 213.7664 -30.353)
		(width 0.14224)
		(layer "In11.Cu")
		(net "M_C_DQ<15>")
	)
	(segment
		(start 240.797842 -59.15279)
		(end 240.748312 -59.15279)
		(width 0.0889)
		(layer "In11.Cu")
		(net "M_C_DQ<15>")
	)
	(segment
		(start 212.458046 -4.435856)
		(end 212.458046 -4.782312)
		(width 0.14224)
		(layer "In11.Cu")
		(net "M_C_DQ<15>")
	)
	(segment
		(start 213.105746 -12.373356)
		(end 213.105746 -13.516356)
		(width 0.14224)
		(layer "In11.Cu")
		(net "M_C_DQ<15>")
	)
	(segment
		(start 211.699856 2.514854)
		(end 212.016594 2.198116)
		(width 0.14224)
		(layer "In11.Cu")
		(net "M_C_DQ<15>")
	)
	(segment
		(start 229.108 -52.9336)
		(end 229.108 -53.213)
		(width 0.14224)
		(layer "In11.Cu")
		(net "M_C_DQ<15>")
	)
	(segment
		(start 213.1568 -30.5562)
		(end 213.36 -30.353)
		(width 0.14224)
		(layer "In11.Cu")
		(net "M_C_DQ<15>")
	)
	(segment
		(start 240.239042 -59.388248)
		(end 240.033302 -59.457336)
		(width 0.0889)
		(layer "In11.Cu")
		(net "M_C_DQ<15>")
	)
	(segment
		(start 234.771438 -56.485536)
		(end 234.123992 -56.485536)
		(width 0.0889)
		(layer "In11.Cu")
		(net "M_C_DQ<15>")
	)
	(segment
		(start 212.54974 -3.076956)
		(end 212.089746 -3.53695)
		(width 0.14224)
		(layer "In11.Cu")
		(net "M_C_DQ<15>")
	)
	(segment
		(start 220.777562 -43.329098)
		(end 220.777562 -44.603162)
		(width 0.14224)
		(layer "In11.Cu")
		(net "M_C_DQ<15>")
	)
	(segment
		(start 231.758744 -54.567582)
		(end 232.019856 -54.828694)
		(width 0.0889)
		(layer "In11.Cu")
		(net "M_C_DQ<15>")
	)
	(segment
		(start 212.902546 0.581152)
		(end 212.902546 -2.72415)
		(width 0.14224)
		(layer "In11.Cu")
		(net "M_C_DQ<15>")
	)
	(segment
		(start 240.033302 -59.457336)
		(end 239.889792 -59.457336)
		(width 0.0889)
		(layer "In11.Cu")
		(net "M_C_DQ<15>")
	)
	(segment
		(start 212.927946 -27.457908)
		(end 212.344 -28.041854)
		(width 0.14224)
		(layer "In11.Cu")
		(net "M_C_DQ<15>")
	)
	(segment
		(start 230.462582 -54.567582)
		(end 231.758744 -54.567582)
		(width 0.14224)
		(layer "In11.Cu")
		(net "M_C_DQ<15>")
	)
	(segment
		(start 212.902546 -19.024346)
		(end 213.0552 -19.177)
		(width 0.14224)
		(layer "In11.Cu")
		(net "M_C_DQ<15>")
	)
	(segment
		(start 212.927946 -7.289546)
		(end 213.131146 -7.492746)
		(width 0.14224)
		(layer "In11.Cu")
		(net "M_C_DQ<15>")
	)
	(segment
		(start 241.621818 -59.057286)
		(end 240.797842 -59.15279)
		(width 0.0889)
		(layer "In11.Cu")
		(net "M_C_DQ<15>")
	)
	(segment
		(start 237.346998 -57.971436)
		(end 237.311184 -57.971436)
		(width 0.0889)
		(layer "In11.Cu")
		(net "M_C_DQ<15>")
	)
	(segment
		(start 212.9536 -33.5026)
		(end 213.1568 -33.2994)
		(width 0.14224)
		(layer "In11.Cu")
		(net "M_C_DQ<15>")
	)
	(segment
		(start 236.483652 -57.476136)
		(end 236.455712 -57.476136)
		(width 0.0889)
		(layer "In11.Cu")
		(net "M_C_DQ<15>")
	)
	(arc
		(start 235.601002 -56.98109)
		(mid 235.407152 -56.92474)
		(end 235.265468 -56.780938)
		(width 0.0889)
		(layer "In11.Cu")
		(net "M_C_DQ<15>")
	)
	(arc
		(start 235.265468 -56.780938)
		(mid 235.05686 -56.569006)
		(end 234.771438 -56.485536)
		(width 0.0889)
		(layer "In11.Cu")
		(net "M_C_DQ<15>")
	)
	(arc
		(start 236.455712 -57.476136)
		(mid 236.26407 -57.41897)
		(end 236.123988 -57.276238)
		(width 0.0889)
		(layer "In11.Cu")
		(net "M_C_DQ<15>")
	)
	(arc
		(start 238.169704 -58.466736)
		(mid 237.979775 -58.408866)
		(end 237.841028 -58.266838)
		(width 0.0889)
		(layer "In11.Cu")
		(net "M_C_DQ<15>")
	)
	(arc
		(start 238.699548 -58.761884)
		(mid 238.492544 -58.55102)
		(end 238.209328 -58.466736)
		(width 0.0889)
		(layer "In11.Cu")
		(net "M_C_DQ<15>")
	)
	(arc
		(start 239.558068 -59.257438)
		(mid 239.347355 -59.044359)
		(end 239.059212 -58.962036)
		(width 0.0889)
		(layer "In11.Cu")
		(net "M_C_DQ<15>")
	)
	(arc
		(start 239.035082 -58.962036)
		(mid 238.841232 -58.905686)
		(end 238.699548 -58.761884)
		(width 0.0889)
		(layer "In11.Cu")
		(net "M_C_DQ<15>")
	)
	(arc
		(start 237.841028 -58.266838)
		(mid 237.63242 -58.054906)
		(end 237.346998 -57.971436)
		(width 0.0889)
		(layer "In11.Cu")
		(net "M_C_DQ<15>")
	)
	(arc
		(start 236.982508 -57.771538)
		(mid 236.771795 -57.558459)
		(end 236.483652 -57.476136)
		(width 0.0889)
		(layer "In11.Cu")
		(net "M_C_DQ<15>")
	)
	(arc
		(start 237.311184 -57.971436)
		(mid 237.121255 -57.913566)
		(end 236.982508 -57.771538)
		(width 0.0889)
		(layer "In11.Cu")
		(net "M_C_DQ<15>")
	)
	(arc
		(start 239.889792 -59.457336)
		(mid 239.69815 -59.40017)
		(end 239.558068 -59.257438)
		(width 0.0889)
		(layer "In11.Cu")
		(net "M_C_DQ<15>")
	)
	(arc
		(start 236.123988 -57.276238)
		(mid 235.916984 -57.065374)
		(end 235.633768 -56.98109)
		(width 0.0889)
		(layer "In11.Cu")
		(net "M_C_DQ<15>")
	)
	(arc
		(start 240.748312 -59.15279)
		(mid 240.617358 -59.179969)
		(end 240.502694 -59.248802)
		(width 0.0889)
		(layer "In11.Cu")
		(net "M_C_DQ<15>")
	)
	(segment
		(start 212.682074 0.50292)
		(end 212.549994 0.635)
		(width 0.1651)
		(layer "F.Cu")
		(net "M_C_DQ<14>")
	)
	(segment
		(start 240.476278 -60.047886)
		(end 239.904778 -60.047886)
		(width 0.0889)
		(layer "F.Cu")
		(net "M_C_DQ<14>")
	)
	(segment
		(start 212.549994 -0.821182)
		(end 212.549994 0.1524)
		(width 0.1651)
		(layer "F.Cu")
		(net "M_C_DQ<14>")
	)
	(segment
		(start 212.549994 0.1524)
		(end 212.682074 0.28448)
		(width 0.1651)
		(layer "F.Cu")
		(net "M_C_DQ<14>")
	)
	(segment
		(start 212.682074 0.28448)
		(end 212.682074 0.50292)
		(width 0.1651)
		(layer "F.Cu")
		(net "M_C_DQ<14>")
	)
	(segment
		(start 212.549994 0.635)
		(end 212.549994 0.939546)
		(width 0.1651)
		(layer "F.Cu")
		(net "M_C_DQ<14>")
	)
	(segment
		(start 212.550502 -0.821182)
		(end 212.549994 -0.821182)
		(width 0.1651)
		(layer "F.Cu")
		(net "M_C_DQ<14>")
	)
	(segment
		(start 212.549994 0.939546)
		(end 212.54974 0.9398)
		(width 0.1651)
		(layer "F.Cu")
		(net "M_C_DQ<14>")
	)
	(via
		(at 211.699856 -4.357878)
		(size 0.508)
		(drill 0.254)
		(layers "F.Cu" "B.Cu")
		(net "M_C_DQ<14>")
	)
	(via
		(at 239.904778 -60.047886)
		(size 0.508)
		(drill 0.254)
		(layers "F.Cu" "B.Cu")
		(net "M_C_DQ<14>")
	)
	(via
		(at 212.54974 0.9398)
		(size 0.508)
		(drill 0.254)
		(layers "F.Cu" "B.Cu")
		(net "M_C_DQ<14>")
	)
	(segment
		(start 211.700364 -5.621782)
		(end 211.699856 -5.621782)
		(width 0.1651)
		(layer "B.Cu")
		(net "M_C_DQ<14>")
	)
	(segment
		(start 211.699856 -5.621782)
		(end 211.699856 -4.357878)
		(width 0.1651)
		(layer "B.Cu")
		(net "M_C_DQ<14>")
	)
	(segment
		(start 211.7598 -28.958286)
		(end 211.5566 -29.161486)
		(width 0.14224)
		(layer "In11.Cu")
		(net "M_C_DQ<14>")
	)
	(segment
		(start 212.267546 -9.398)
		(end 212.0646 -9.600946)
		(width 0.14224)
		(layer "In11.Cu")
		(net "M_C_DQ<14>")
	)
	(segment
		(start 211.5312 -29.974286)
		(end 211.709 -30.152086)
		(width 0.14224)
		(layer "In11.Cu")
		(net "M_C_DQ<14>")
	)
	(segment
		(start 212.1662 -7.289292)
		(end 212.064346 -7.391146)
		(width 0.14224)
		(layer "In11.Cu")
		(net "M_C_DQ<14>")
	)
	(segment
		(start 231.942132 -55.019194)
		(end 232.388156 -55.019194)
		(width 0.0889)
		(layer "In11.Cu")
		(net "M_C_DQ<14>")
	)
	(segment
		(start 211.464144 -4.122166)
		(end 211.699856 -4.357878)
		(width 0.14224)
		(layer "In11.Cu")
		(net "M_C_DQ<14>")
	)
	(segment
		(start 214.193374 -38.605206)
		(end 214.523828 -38.274752)
		(width 0.14224)
		(layer "In11.Cu")
		(net "M_C_DQ<14>")
	)
	(segment
		(start 210.70951 -29.364686)
		(end 210.70951 -29.771086)
		(width 0.14224)
		(layer "In11.Cu")
		(net "M_C_DQ<14>")
	)
	(segment
		(start 211.811362 -0.076454)
		(end 211.811362 -0.387096)
		(width 0.14224)
		(layer "In11.Cu")
		(net "M_C_DQ<14>")
	)
	(segment
		(start 212.064346 -21.974556)
		(end 212.064346 -23.168356)
		(width 0.14224)
		(layer "In11.Cu")
		(net "M_C_DQ<14>")
	)
	(segment
		(start 213.73338 -38.34638)
		(end 213.992206 -38.605206)
		(width 0.14224)
		(layer "In11.Cu")
		(net "M_C_DQ<14>")
	)
	(segment
		(start 211.706968 -27.535886)
		(end 210.91271 -27.535886)
		(width 0.14224)
		(layer "In11.Cu")
		(net "M_C_DQ<14>")
	)
	(segment
		(start 213.992206 -38.605206)
		(end 214.193374 -38.605206)
		(width 0.14224)
		(layer "In11.Cu")
		(net "M_C_DQ<14>")
	)
	(segment
		(start 213.3346 -36.884356)
		(end 214.063834 -37.61359)
		(width 0.14224)
		(layer "In11.Cu")
		(net "M_C_DQ<14>")
	)
	(segment
		(start 211.709 -36.195)
		(end 211.9122 -36.3982)
		(width 0.14224)
		(layer "In11.Cu")
		(net "M_C_DQ<14>")
	)
	(segment
		(start 210.70951 -27.739086)
		(end 210.70951 -28.145486)
		(width 0.14224)
		(layer "In11.Cu")
		(net "M_C_DQ<14>")
	)
	(segment
		(start 211.7598 -28.551886)
		(end 211.7598 -28.958286)
		(width 0.14224)
		(layer "In11.Cu")
		(net "M_C_DQ<14>")
	)
	(segment
		(start 212.267546 -19.024854)
		(end 212.1154 -19.177)
		(width 0.14224)
		(layer "In11.Cu")
		(net "M_C_DQ<14>")
	)
	(segment
		(start 212.165946 -27.076908)
		(end 211.706968 -27.535886)
		(width 0.14224)
		(layer "In11.Cu")
		(net "M_C_DQ<14>")
	)
	(segment
		(start 239.409732 -59.382152)
		(end 239.904778 -60.047886)
		(width 0.0889)
		(layer "In11.Cu")
		(net "M_C_DQ<14>")
	)
	(segment
		(start 214.523828 -38.274752)
		(end 214.724996 -38.274752)
		(width 0.14224)
		(layer "In11.Cu")
		(net "M_C_DQ<14>")
	)
	(segment
		(start 212.165946 -16.890746)
		(end 212.064346 -16.992346)
		(width 0.14224)
		(layer "In11.Cu")
		(net "M_C_DQ<14>")
	)
	(segment
		(start 212.192362 -1.111504)
		(end 211.811362 -1.492504)
		(width 0.14224)
		(layer "In11.Cu")
		(net "M_C_DQ<14>")
	)
	(segment
		(start 234.044998 -56.676036)
		(end 234.764834 -56.676036)
		(width 0.0889)
		(layer "In11.Cu")
		(net "M_C_DQ<14>")
	)
	(segment
		(start 212.064346 -13.567156)
		(end 212.165946 -13.668756)
		(width 0.14224)
		(layer "In11.Cu")
		(net "M_C_DQ<14>")
	)
	(segment
		(start 212.064346 -7.391146)
		(end 212.064346 -8.864346)
		(width 0.14224)
		(layer "In11.Cu")
		(net "M_C_DQ<14>")
	)
	(segment
		(start 212.064346 -18.440146)
		(end 212.267546 -18.643346)
		(width 0.14224)
		(layer "In11.Cu")
		(net "M_C_DQ<14>")
	)
	(segment
		(start 211.811362 -1.777746)
		(end 212.236812 -2.203196)
		(width 0.14224)
		(layer "In11.Cu")
		(net "M_C_DQ<14>")
	)
	(segment
		(start 212.1154 -21.234654)
		(end 212.267546 -21.3868)
		(width 0.14224)
		(layer "In11.Cu")
		(net "M_C_DQ<14>")
	)
	(segment
		(start 219.463112 -44.245276)
		(end 230.420418 -55.202582)
		(width 0.14224)
		(layer "In11.Cu")
		(net "M_C_DQ<14>")
	)
	(segment
		(start 230.420418 -55.202582)
		(end 231.758744 -55.202582)
		(width 0.14224)
		(layer "In11.Cu")
		(net "M_C_DQ<14>")
	)
	(segment
		(start 212.064346 -23.168356)
		(end 212.165946 -23.269956)
		(width 0.14224)
		(layer "In11.Cu")
		(net "M_C_DQ<14>")
	)
	(segment
		(start 211.464144 -3.327654)
		(end 211.464144 -4.122166)
		(width 0.14224)
		(layer "In11.Cu")
		(net "M_C_DQ<14>")
	)
	(segment
		(start 212.236812 -2.554986)
		(end 211.464144 -3.327654)
		(width 0.14224)
		(layer "In11.Cu")
		(net "M_C_DQ<14>")
	)
	(segment
		(start 212.1662 -5.38861)
		(end 212.1662 -7.289292)
		(width 0.14224)
		(layer "In11.Cu")
		(net "M_C_DQ<14>")
	)
	(segment
		(start 214.724996 -38.274752)
		(end 219.463112 -43.012868)
		(width 0.14224)
		(layer "In11.Cu")
		(net "M_C_DQ<14>")
	)
	(segment
		(start 212.267546 -21.3868)
		(end 212.267546 -21.771356)
		(width 0.14224)
		(layer "In11.Cu")
		(net "M_C_DQ<14>")
	)
	(segment
		(start 237.307628 -58.16219)
		(end 237.347252 -58.16219)
		(width 0.0889)
		(layer "In11.Cu")
		(net "M_C_DQ<14>")
	)
	(segment
		(start 213.73338 -38.145212)
		(end 213.73338 -38.34638)
		(width 0.14224)
		(layer "In11.Cu")
		(net "M_C_DQ<14>")
	)
	(segment
		(start 212.165946 -13.668756)
		(end 212.165946 -16.890746)
		(width 0.14224)
		(layer "In11.Cu")
		(net "M_C_DQ<14>")
	)
	(segment
		(start 212.1154 -19.177)
		(end 212.1154 -21.234654)
		(width 0.14224)
		(layer "In11.Cu")
		(net "M_C_DQ<14>")
	)
	(segment
		(start 213.1314 -34.2138)
		(end 213.3346 -34.417)
		(width 0.14224)
		(layer "In11.Cu")
		(net "M_C_DQ<14>")
	)
	(segment
		(start 214.063834 -37.61359)
		(end 214.063834 -37.814758)
		(width 0.14224)
		(layer "In11.Cu")
		(net "M_C_DQ<14>")
	)
	(segment
		(start 212.54974 0.9398)
		(end 212.175344 0.565404)
		(width 0.14224)
		(layer "In11.Cu")
		(net "M_C_DQ<14>")
	)
	(segment
		(start 212.267546 -9.067546)
		(end 212.267546 -9.398)
		(width 0.14224)
		(layer "In11.Cu")
		(net "M_C_DQ<14>")
	)
	(segment
		(start 211.5566 -29.161486)
		(end 210.91271 -29.161486)
		(width 0.14224)
		(layer "In11.Cu")
		(net "M_C_DQ<14>")
	)
	(segment
		(start 212.5218 -36.195)
		(end 212.5218 -34.417)
		(width 0.14224)
		(layer "In11.Cu")
		(net "M_C_DQ<14>")
	)
	(segment
		(start 212.267546 -21.771356)
		(end 212.064346 -21.974556)
		(width 0.14224)
		(layer "In11.Cu")
		(net "M_C_DQ<14>")
	)
	(segment
		(start 211.699856 -4.357878)
		(end 211.699856 -4.922266)
		(width 0.14224)
		(layer "In11.Cu")
		(net "M_C_DQ<14>")
	)
	(segment
		(start 212.175344 0.287528)
		(end 211.811362 -0.076454)
		(width 0.14224)
		(layer "In11.Cu")
		(net "M_C_DQ<14>")
	)
	(segment
		(start 210.91271 -27.535886)
		(end 210.70951 -27.739086)
		(width 0.14224)
		(layer "In11.Cu")
		(net "M_C_DQ<14>")
	)
	(segment
		(start 231.758744 -55.202582)
		(end 231.942132 -55.019194)
		(width 0.0889)
		(layer "In11.Cu")
		(net "M_C_DQ<14>")
	)
	(segment
		(start 212.064346 -12.373356)
		(end 212.064346 -13.567156)
		(width 0.14224)
		(layer "In11.Cu")
		(net "M_C_DQ<14>")
	)
	(segment
		(start 213.3346 -34.417)
		(end 213.3346 -36.884356)
		(width 0.14224)
		(layer "In11.Cu")
		(net "M_C_DQ<14>")
	)
	(segment
		(start 235.594398 -57.17159)
		(end 235.627164 -57.17159)
		(width 0.0889)
		(layer "In11.Cu")
		(net "M_C_DQ<14>")
	)
	(segment
		(start 210.70951 -29.771086)
		(end 210.91271 -29.974286)
		(width 0.14224)
		(layer "In11.Cu")
		(net "M_C_DQ<14>")
	)
	(segment
		(start 211.709 -30.152086)
		(end 211.709 -36.195)
		(width 0.14224)
		(layer "In11.Cu")
		(net "M_C_DQ<14>")
	)
	(segment
		(start 239.392968 -59.352688)
		(end 239.409732 -59.382152)
		(width 0.0889)
		(layer "In11.Cu")
		(net "M_C_DQ<14>")
	)
	(segment
		(start 212.192362 -0.768096)
		(end 212.192362 -1.111504)
		(width 0.14224)
		(layer "In11.Cu")
		(net "M_C_DQ<14>")
	)
	(segment
		(start 210.70951 -28.145486)
		(end 210.91271 -28.348686)
		(width 0.14224)
		(layer "In11.Cu")
		(net "M_C_DQ<14>")
	)
	(segment
		(start 239.033304 -59.15279)
		(end 239.061244 -59.15279)
		(width 0.0889)
		(layer "In11.Cu")
		(net "M_C_DQ<14>")
	)
	(segment
		(start 211.5566 -28.348686)
		(end 211.7598 -28.551886)
		(width 0.14224)
		(layer "In11.Cu")
		(net "M_C_DQ<14>")
	)
	(segment
		(start 212.267546 -18.643346)
		(end 212.267546 -19.024854)
		(width 0.14224)
		(layer "In11.Cu")
		(net "M_C_DQ<14>")
	)
	(segment
		(start 214.063834 -37.814758)
		(end 213.73338 -38.145212)
		(width 0.14224)
		(layer "In11.Cu")
		(net "M_C_DQ<14>")
	)
	(segment
		(start 212.064346 -8.864346)
		(end 212.267546 -9.067546)
		(width 0.14224)
		(layer "In11.Cu")
		(net "M_C_DQ<14>")
	)
	(segment
		(start 232.388156 -55.019194)
		(end 234.044998 -56.676036)
		(width 0.0889)
		(layer "In11.Cu")
		(net "M_C_DQ<14>")
	)
	(segment
		(start 211.699856 -4.922266)
		(end 212.1662 -5.38861)
		(width 0.14224)
		(layer "In11.Cu")
		(net "M_C_DQ<14>")
	)
	(segment
		(start 212.725 -34.2138)
		(end 213.1314 -34.2138)
		(width 0.14224)
		(layer "In11.Cu")
		(net "M_C_DQ<14>")
	)
	(segment
		(start 212.0646 -11.557)
		(end 212.267546 -11.759946)
		(width 0.14224)
		(layer "In11.Cu")
		(net "M_C_DQ<14>")
	)
	(segment
		(start 238.169958 -58.65749)
		(end 238.205772 -58.65749)
		(width 0.0889)
		(layer "In11.Cu")
		(net "M_C_DQ<14>")
	)
	(segment
		(start 210.91271 -29.974286)
		(end 211.5312 -29.974286)
		(width 0.14224)
		(layer "In11.Cu")
		(net "M_C_DQ<14>")
	)
	(segment
		(start 211.811362 -0.387096)
		(end 212.192362 -0.768096)
		(width 0.14224)
		(layer "In11.Cu")
		(net "M_C_DQ<14>")
	)
	(segment
		(start 212.5218 -34.417)
		(end 212.725 -34.2138)
		(width 0.14224)
		(layer "In11.Cu")
		(net "M_C_DQ<14>")
	)
	(segment
		(start 212.267546 -12.170156)
		(end 212.064346 -12.373356)
		(width 0.14224)
		(layer "In11.Cu")
		(net "M_C_DQ<14>")
	)
	(segment
		(start 210.91271 -29.161486)
		(end 210.70951 -29.364686)
		(width 0.14224)
		(layer "In11.Cu")
		(net "M_C_DQ<14>")
	)
	(segment
		(start 210.91271 -28.348686)
		(end 211.5566 -28.348686)
		(width 0.14224)
		(layer "In11.Cu")
		(net "M_C_DQ<14>")
	)
	(segment
		(start 212.064346 -16.992346)
		(end 212.064346 -18.440146)
		(width 0.14224)
		(layer "In11.Cu")
		(net "M_C_DQ<14>")
	)
	(segment
		(start 211.811362 -1.492504)
		(end 211.811362 -1.777746)
		(width 0.14224)
		(layer "In11.Cu")
		(net "M_C_DQ<14>")
	)
	(segment
		(start 212.267546 -11.759946)
		(end 212.267546 -12.170156)
		(width 0.14224)
		(layer "In11.Cu")
		(net "M_C_DQ<14>")
	)
	(segment
		(start 212.0646 -9.600946)
		(end 212.0646 -11.557)
		(width 0.14224)
		(layer "In11.Cu")
		(net "M_C_DQ<14>")
	)
	(segment
		(start 219.463112 -43.012868)
		(end 219.463112 -44.245276)
		(width 0.14224)
		(layer "In11.Cu")
		(net "M_C_DQ<14>")
	)
	(segment
		(start 212.236812 -2.203196)
		(end 212.236812 -2.554986)
		(width 0.14224)
		(layer "In11.Cu")
		(net "M_C_DQ<14>")
	)
	(segment
		(start 212.175344 0.565404)
		(end 212.175344 0.287528)
		(width 0.14224)
		(layer "In11.Cu")
		(net "M_C_DQ<14>")
	)
	(segment
		(start 212.3186 -36.3982)
		(end 212.5218 -36.195)
		(width 0.14224)
		(layer "In11.Cu")
		(net "M_C_DQ<14>")
	)
	(segment
		(start 236.457744 -57.66689)
		(end 236.481874 -57.66689)
		(width 0.0889)
		(layer "In11.Cu")
		(net "M_C_DQ<14>")
	)
	(segment
		(start 211.9122 -36.3982)
		(end 212.3186 -36.3982)
		(width 0.14224)
		(layer "In11.Cu")
		(net "M_C_DQ<14>")
	)
	(segment
		(start 212.165946 -23.269956)
		(end 212.165946 -27.076908)
		(width 0.14224)
		(layer "In11.Cu")
		(net "M_C_DQ<14>")
	)
	(arc
		(start 236.481874 -57.66689)
		(mid 236.675724 -57.72324)
		(end 236.817408 -57.867042)
		(width 0.0889)
		(layer "In11.Cu")
		(net "M_C_DQ<14>")
	)
	(arc
		(start 238.205772 -58.65749)
		(mid 238.395701 -58.71536)
		(end 238.534448 -58.857388)
		(width 0.0889)
		(layer "In11.Cu")
		(net "M_C_DQ<14>")
	)
	(arc
		(start 238.534448 -58.857388)
		(mid 238.745161 -59.070467)
		(end 239.033304 -59.15279)
		(width 0.0889)
		(layer "In11.Cu")
		(net "M_C_DQ<14>")
	)
	(arc
		(start 237.675928 -58.362088)
		(mid 237.884536 -58.57402)
		(end 238.169958 -58.65749)
		(width 0.0889)
		(layer "In11.Cu")
		(net "M_C_DQ<14>")
	)
	(arc
		(start 235.958888 -57.371488)
		(mid 236.169601 -57.584567)
		(end 236.457744 -57.66689)
		(width 0.0889)
		(layer "In11.Cu")
		(net "M_C_DQ<14>")
	)
	(arc
		(start 235.100368 -56.876188)
		(mid 235.308976 -57.08812)
		(end 235.594398 -57.17159)
		(width 0.0889)
		(layer "In11.Cu")
		(net "M_C_DQ<14>")
	)
	(arc
		(start 234.764834 -56.676036)
		(mid 234.958684 -56.732386)
		(end 235.100368 -56.876188)
		(width 0.0889)
		(layer "In11.Cu")
		(net "M_C_DQ<14>")
	)
	(arc
		(start 236.817408 -57.867042)
		(mid 237.024412 -58.077906)
		(end 237.307628 -58.16219)
		(width 0.0889)
		(layer "In11.Cu")
		(net "M_C_DQ<14>")
	)
	(arc
		(start 235.627164 -57.17159)
		(mid 235.818806 -57.228756)
		(end 235.958888 -57.371488)
		(width 0.0889)
		(layer "In11.Cu")
		(net "M_C_DQ<14>")
	)
	(arc
		(start 237.347252 -58.16219)
		(mid 237.537181 -58.22006)
		(end 237.675928 -58.362088)
		(width 0.0889)
		(layer "In11.Cu")
		(net "M_C_DQ<14>")
	)
	(arc
		(start 239.061244 -59.15279)
		(mid 239.252886 -59.209956)
		(end 239.392968 -59.352688)
		(width 0.0889)
		(layer "In11.Cu")
		(net "M_C_DQ<14>")
	)
	(segment
		(start 243.051838 -61.53404)
		(end 242.480338 -61.53404)
		(width 0.0889)
		(layer "F.Cu")
		(net "M_C_DQ<13>")
	)
	(segment
		(start 205.749906 3.778758)
		(end 205.749906 2.514854)
		(width 0.1651)
		(layer "F.Cu")
		(net "M_C_DQ<13>")
	)
	(segment
		(start 205.750414 3.778758)
		(end 205.749906 3.778758)
		(width 0.1651)
		(layer "F.Cu")
		(net "M_C_DQ<13>")
	)
	(via
		(at 205.749906 2.514854)
		(size 0.508)
		(drill 0.254)
		(layers "F.Cu" "B.Cu")
		(net "M_C_DQ<13>")
	)
	(via
		(at 206.52359 -3.076956)
		(size 0.508)
		(drill 0.254)
		(layers "F.Cu" "B.Cu")
		(net "M_C_DQ<13>")
	)
	(via
		(at 242.480338 -61.53404)
		(size 0.508)
		(drill 0.254)
		(layers "F.Cu" "B.Cu")
		(net "M_C_DQ<13>")
	)
	(segment
		(start 206.59979 -3.000756)
		(end 206.52359 -3.076956)
		(width 0.1651)
		(layer "B.Cu")
		(net "M_C_DQ<13>")
	)
	(segment
		(start 206.600298 -1.021842)
		(end 206.59979 -1.021842)
		(width 0.1651)
		(layer "B.Cu")
		(net "M_C_DQ<13>")
	)
	(segment
		(start 206.59979 -1.021842)
		(end 206.59979 -3.000756)
		(width 0.1651)
		(layer "B.Cu")
		(net "M_C_DQ<13>")
	)
	(segment
		(start 206.9592 -9.550654)
		(end 207.0608 -9.652254)
		(width 0.14224)
		(layer "In11.Cu")
		(net "M_C_DQ<13>")
	)
	(segment
		(start 206.933546 -13.681456)
		(end 206.933546 -16.865346)
		(width 0.14224)
		(layer "In11.Cu")
		(net "M_C_DQ<13>")
	)
	(segment
		(start 239.035082 -62.92469)
		(end 239.211104 -62.92469)
		(width 0.0889)
		(layer "In11.Cu")
		(net "M_C_DQ<13>")
	)
	(segment
		(start 207.031844 0.7366)
		(end 206.834994 0.53975)
		(width 0.14224)
		(layer "In11.Cu")
		(net "M_C_DQ<13>")
	)
	(segment
		(start 206.0448 -3.936746)
		(end 206.7814 -4.673346)
		(width 0.14224)
		(layer "In11.Cu")
		(net "M_C_DQ<13>")
	)
	(segment
		(start 230.62057 -59.776614)
		(end 232.674414 -59.776614)
		(width 0.0889)
		(layer "In11.Cu")
		(net "M_C_DQ<13>")
	)
	(segment
		(start 241.658902 -61.629036)
		(end 242.480338 -61.53404)
		(width 0.0889)
		(layer "In11.Cu")
		(net "M_C_DQ<13>")
	)
	(segment
		(start 206.997046 -18.1864)
		(end 206.9338 -18.7706)
		(width 0.14224)
		(layer "In11.Cu")
		(net "M_C_DQ<13>")
	)
	(segment
		(start 207.264 -24.549354)
		(end 207.264 -24.904446)
		(width 0.14224)
		(layer "In11.Cu")
		(net "M_C_DQ<13>")
	)
	(segment
		(start 207.031844 1.149096)
		(end 207.031844 0.7366)
		(width 0.14224)
		(layer "In11.Cu")
		(net "M_C_DQ<13>")
	)
	(segment
		(start 205.749906 2.120138)
		(end 206.320644 1.5494)
		(width 0.14224)
		(layer "In11.Cu")
		(net "M_C_DQ<13>")
	)
	(segment
		(start 238.172752 -62.429136)
		(end 238.205518 -62.429136)
		(width 0.0889)
		(layer "In11.Cu")
		(net "M_C_DQ<13>")
	)
	(segment
		(start 236.455712 -61.438536)
		(end 236.488478 -61.438536)
		(width 0.0889)
		(layer "In11.Cu")
		(net "M_C_DQ<13>")
	)
	(segment
		(start 206.834994 0.53975)
		(end 206.834994 -2.765552)
		(width 0.14224)
		(layer "In11.Cu")
		(net "M_C_DQ<13>")
	)
	(segment
		(start 207.016096 -19.177)
		(end 207.0608 -19.3294)
		(width 0.14224)
		(layer "In11.Cu")
		(net "M_C_DQ<13>")
	)
	(segment
		(start 206.983838 -22.165564)
		(end 206.997046 -22.2758)
		(width 0.14224)
		(layer "In11.Cu")
		(net "M_C_DQ<13>")
	)
	(segment
		(start 206.997046 -12.6746)
		(end 206.997046 -13.617956)
		(width 0.14224)
		(layer "In11.Cu")
		(net "M_C_DQ<13>")
	)
	(segment
		(start 206.997046 -22.2758)
		(end 206.997046 -24.2824)
		(width 0.14224)
		(layer "In11.Cu")
		(net "M_C_DQ<13>")
	)
	(segment
		(start 234.735878 -60.447936)
		(end 234.771438 -60.447936)
		(width 0.0889)
		(layer "In11.Cu")
		(net "M_C_DQ<13>")
	)
	(segment
		(start 206.997046 -7.327646)
		(end 206.997046 -8.5852)
		(width 0.14224)
		(layer "In11.Cu")
		(net "M_C_DQ<13>")
	)
	(segment
		(start 239.211104 -62.92469)
		(end 239.656874 -62.705488)
		(width 0.0889)
		(layer "In11.Cu")
		(net "M_C_DQ<13>")
	)
	(segment
		(start 241.610642 -61.629036)
		(end 241.658902 -61.629036)
		(width 0.0889)
		(layer "In11.Cu")
		(net "M_C_DQ<13>")
	)
	(segment
		(start 207.0608 -19.3294)
		(end 207.0608 -21.208746)
		(width 0.14224)
		(layer "In11.Cu")
		(net "M_C_DQ<13>")
	)
	(segment
		(start 206.9338 -18.7706)
		(end 206.9338 -18.8976)
		(width 0.14224)
		(layer "In11.Cu")
		(net "M_C_DQ<13>")
	)
	(segment
		(start 206.9592 -8.844788)
		(end 206.9592 -9.550654)
		(width 0.14224)
		(layer "In11.Cu")
		(net "M_C_DQ<13>")
	)
	(segment
		(start 206.908146 -21.3614)
		(end 206.908146 -21.5392)
		(width 0.14224)
		(layer "In11.Cu")
		(net "M_C_DQ<13>")
	)
	(segment
		(start 206.997046 -13.617956)
		(end 206.933546 -13.681456)
		(width 0.14224)
		(layer "In11.Cu")
		(net "M_C_DQ<13>")
	)
	(segment
		(start 206.997046 -8.5852)
		(end 206.971138 -8.763)
		(width 0.14224)
		(layer "In11.Cu")
		(net "M_C_DQ<13>")
	)
	(segment
		(start 232.674414 -59.776614)
		(end 233.421936 -60.524136)
		(width 0.0889)
		(layer "In11.Cu")
		(net "M_C_DQ<13>")
	)
	(segment
		(start 206.7814 -4.673346)
		(end 206.7814 -7.112)
		(width 0.14224)
		(layer "In11.Cu")
		(net "M_C_DQ<13>")
	)
	(segment
		(start 206.52359 -3.076956)
		(end 206.0448 -3.555746)
		(width 0.14224)
		(layer "In11.Cu")
		(net "M_C_DQ<13>")
	)
	(segment
		(start 230.392224 -59.548268)
		(end 230.62057 -59.776614)
		(width 0.0889)
		(layer "In11.Cu")
		(net "M_C_DQ<13>")
	)
	(segment
		(start 237.318042 -61.93409)
		(end 237.350808 -61.93409)
		(width 0.0889)
		(layer "In11.Cu")
		(net "M_C_DQ<13>")
	)
	(segment
		(start 206.997046 -24.2824)
		(end 207.264 -24.549354)
		(width 0.14224)
		(layer "In11.Cu")
		(net "M_C_DQ<13>")
	)
	(segment
		(start 206.997046 -16.928846)
		(end 206.997046 -18.1864)
		(width 0.14224)
		(layer "In11.Cu")
		(net "M_C_DQ<13>")
	)
	(segment
		(start 206.908146 -11.760454)
		(end 206.908146 -12.065)
		(width 0.14224)
		(layer "In11.Cu")
		(net "M_C_DQ<13>")
	)
	(segment
		(start 206.320644 1.5494)
		(end 206.63154 1.5494)
		(width 0.14224)
		(layer "In11.Cu")
		(net "M_C_DQ<13>")
	)
	(segment
		(start 206.63154 1.5494)
		(end 207.031844 1.149096)
		(width 0.14224)
		(layer "In11.Cu")
		(net "M_C_DQ<13>")
	)
	(segment
		(start 235.601002 -60.94349)
		(end 235.633768 -60.94349)
		(width 0.0889)
		(layer "In11.Cu")
		(net "M_C_DQ<13>")
	)
	(segment
		(start 207.0608 -11.6078)
		(end 206.908146 -11.760454)
		(width 0.14224)
		(layer "In11.Cu")
		(net "M_C_DQ<13>")
	)
	(segment
		(start 206.997046 -25.1714)
		(end 206.997046 -37.184584)
		(width 0.14224)
		(layer "In11.Cu")
		(net "M_C_DQ<13>")
	)
	(segment
		(start 206.0448 -3.555746)
		(end 206.0448 -3.936746)
		(width 0.14224)
		(layer "In11.Cu")
		(net "M_C_DQ<13>")
	)
	(segment
		(start 206.7814 -7.112)
		(end 206.997046 -7.327646)
		(width 0.14224)
		(layer "In11.Cu")
		(net "M_C_DQ<13>")
	)
	(segment
		(start 206.834994 -2.765552)
		(end 206.52359 -3.076956)
		(width 0.14224)
		(layer "In11.Cu")
		(net "M_C_DQ<13>")
	)
	(segment
		(start 207.264 -24.904446)
		(end 206.997046 -25.1714)
		(width 0.14224)
		(layer "In11.Cu")
		(net "M_C_DQ<13>")
	)
	(segment
		(start 206.9338 -18.8976)
		(end 207.016096 -19.177)
		(width 0.14224)
		(layer "In11.Cu")
		(net "M_C_DQ<13>")
	)
	(segment
		(start 207.0608 -9.652254)
		(end 207.0608 -11.6078)
		(width 0.14224)
		(layer "In11.Cu")
		(net "M_C_DQ<13>")
	)
	(segment
		(start 206.933546 -16.865346)
		(end 206.997046 -16.928846)
		(width 0.14224)
		(layer "In11.Cu")
		(net "M_C_DQ<13>")
	)
	(segment
		(start 240.748312 -62.12459)
		(end 240.781078 -62.12459)
		(width 0.0889)
		(layer "In11.Cu")
		(net "M_C_DQ<13>")
	)
	(segment
		(start 233.421936 -60.524136)
		(end 233.548428 -60.743338)
		(width 0.0889)
		(layer "In11.Cu")
		(net "M_C_DQ<13>")
	)
	(segment
		(start 205.749906 2.514854)
		(end 205.749906 2.120138)
		(width 0.14224)
		(layer "In11.Cu")
		(net "M_C_DQ<13>")
	)
	(segment
		(start 229.36073 -59.548268)
		(end 230.392224 -59.548268)
		(width 0.14224)
		(layer "In11.Cu")
		(net "M_C_DQ<13>")
	)
	(segment
		(start 206.908146 -12.065)
		(end 206.997046 -12.6746)
		(width 0.14224)
		(layer "In11.Cu")
		(net "M_C_DQ<13>")
	)
	(segment
		(start 206.908146 -21.5392)
		(end 206.983838 -22.165564)
		(width 0.14224)
		(layer "In11.Cu")
		(net "M_C_DQ<13>")
	)
	(segment
		(start 207.0608 -21.208746)
		(end 206.908146 -21.3614)
		(width 0.14224)
		(layer "In11.Cu")
		(net "M_C_DQ<13>")
	)
	(segment
		(start 206.997046 -37.184584)
		(end 229.36073 -59.548268)
		(width 0.14224)
		(layer "In11.Cu")
		(net "M_C_DQ<13>")
	)
	(segment
		(start 206.971138 -8.763)
		(end 206.9592 -8.844788)
		(width 0.14224)
		(layer "In11.Cu")
		(net "M_C_DQ<13>")
	)
	(segment
		(start 239.893602 -62.619636)
		(end 239.926368 -62.619636)
		(width 0.0889)
		(layer "In11.Cu")
		(net "M_C_DQ<13>")
	)
	(arc
		(start 235.265468 -60.743338)
		(mid 235.407151 -60.887142)
		(end 235.601002 -60.94349)
		(width 0.0889)
		(layer "In11.Cu")
		(net "M_C_DQ<13>")
	)
	(arc
		(start 239.926368 -62.619636)
		(mid 240.209585 -62.535355)
		(end 240.416588 -62.324488)
		(width 0.0889)
		(layer "In11.Cu")
		(net "M_C_DQ<13>")
	)
	(arc
		(start 234.771438 -60.447936)
		(mid 235.056862 -60.531403)
		(end 235.265468 -60.743338)
		(width 0.0889)
		(layer "In11.Cu")
		(net "M_C_DQ<13>")
	)
	(arc
		(start 236.123988 -61.238638)
		(mid 236.264067 -61.381374)
		(end 236.455712 -61.438536)
		(width 0.0889)
		(layer "In11.Cu")
		(net "M_C_DQ<13>")
	)
	(arc
		(start 241.275108 -61.829188)
		(mid 241.416791 -61.685384)
		(end 241.610642 -61.629036)
		(width 0.0889)
		(layer "In11.Cu")
		(net "M_C_DQ<13>")
	)
	(arc
		(start 239.656874 -62.705488)
		(mid 239.768308 -62.643451)
		(end 239.893602 -62.619636)
		(width 0.0889)
		(layer "In11.Cu")
		(net "M_C_DQ<13>")
	)
	(arc
		(start 238.699548 -62.724538)
		(mid 238.841231 -62.868342)
		(end 239.035082 -62.92469)
		(width 0.0889)
		(layer "In11.Cu")
		(net "M_C_DQ<13>")
	)
	(arc
		(start 236.982508 -61.733938)
		(mid 237.124191 -61.877742)
		(end 237.318042 -61.93409)
		(width 0.0889)
		(layer "In11.Cu")
		(net "M_C_DQ<13>")
	)
	(arc
		(start 237.350808 -61.93409)
		(mid 237.634025 -62.018371)
		(end 237.841028 -62.229238)
		(width 0.0889)
		(layer "In11.Cu")
		(net "M_C_DQ<13>")
	)
	(arc
		(start 233.548428 -60.743338)
		(mid 233.895138 -60.943649)
		(end 234.241848 -60.743338)
		(width 0.0889)
		(layer "In11.Cu")
		(net "M_C_DQ<13>")
	)
	(arc
		(start 237.841028 -62.229238)
		(mid 237.981107 -62.371974)
		(end 238.172752 -62.429136)
		(width 0.0889)
		(layer "In11.Cu")
		(net "M_C_DQ<13>")
	)
	(arc
		(start 238.205518 -62.429136)
		(mid 238.490942 -62.512603)
		(end 238.699548 -62.724538)
		(width 0.0889)
		(layer "In11.Cu")
		(net "M_C_DQ<13>")
	)
	(arc
		(start 240.781078 -62.12459)
		(mid 241.066502 -62.041123)
		(end 241.275108 -61.829188)
		(width 0.0889)
		(layer "In11.Cu")
		(net "M_C_DQ<13>")
	)
	(arc
		(start 235.633768 -60.94349)
		(mid 235.916985 -61.027771)
		(end 236.123988 -61.238638)
		(width 0.0889)
		(layer "In11.Cu")
		(net "M_C_DQ<13>")
	)
	(arc
		(start 234.241848 -60.743338)
		(mid 234.450456 -60.531406)
		(end 234.735878 -60.447936)
		(width 0.0889)
		(layer "In11.Cu")
		(net "M_C_DQ<13>")
	)
	(arc
		(start 236.488478 -61.438536)
		(mid 236.773902 -61.522003)
		(end 236.982508 -61.733938)
		(width 0.0889)
		(layer "In11.Cu")
		(net "M_C_DQ<13>")
	)
	(arc
		(start 240.416588 -62.324488)
		(mid 240.556667 -62.181752)
		(end 240.748312 -62.12459)
		(width 0.0889)
		(layer "In11.Cu")
		(net "M_C_DQ<13>")
	)
	(segment
		(start 206.59979 -0.821182)
		(end 206.59979 0.510032)
		(width 0.1651)
		(layer "F.Cu")
		(net "M_C_DQ<12>")
	)
	(segment
		(start 206.59979 0.510032)
		(end 206.501746 1.0414)
		(width 0.1651)
		(layer "F.Cu")
		(net "M_C_DQ<12>")
	)
	(segment
		(start 242.193318 -62.029086)
		(end 241.621818 -62.029086)
		(width 0.0889)
		(layer "F.Cu")
		(net "M_C_DQ<12>")
	)
	(segment
		(start 206.600298 -0.821182)
		(end 206.59979 -0.821182)
		(width 0.1651)
		(layer "F.Cu")
		(net "M_C_DQ<12>")
	)
	(via
		(at 205.749906 -4.357878)
		(size 0.508)
		(drill 0.254)
		(layers "F.Cu" "B.Cu")
		(net "M_C_DQ<12>")
	)
	(via
		(at 206.501746 1.0414)
		(size 0.508)
		(drill 0.254)
		(layers "F.Cu" "B.Cu")
		(net "M_C_DQ<12>")
	)
	(via
		(at 241.621818 -62.029086)
		(size 0.508)
		(drill 0.254)
		(layers "F.Cu" "B.Cu")
		(net "M_C_DQ<12>")
	)
	(segment
		(start 205.749906 -5.621782)
		(end 205.749906 -4.357878)
		(width 0.1651)
		(layer "B.Cu")
		(net "M_C_DQ<12>")
	)
	(segment
		(start 205.750414 -5.621782)
		(end 205.749906 -5.621782)
		(width 0.1651)
		(layer "B.Cu")
		(net "M_C_DQ<12>")
	)
	(segment
		(start 206.2226 -13.77061)
		(end 206.2226 -16.8402)
		(width 0.14224)
		(layer "In11.Cu")
		(net "M_C_DQ<12>")
	)
	(segment
		(start 206.0194 -11.4808)
		(end 206.2226 -11.684)
		(width 0.14224)
		(layer "In11.Cu")
		(net "M_C_DQ<12>")
	)
	(segment
		(start 206.2226 -16.8402)
		(end 206.0194 -17.0434)
		(width 0.14224)
		(layer "In11.Cu")
		(net "M_C_DQ<12>")
	)
	(segment
		(start 233.877358 -61.13399)
		(end 233.912918 -61.13399)
		(width 0.0889)
		(layer "In11.Cu")
		(net "M_C_DQ<12>")
	)
	(segment
		(start 206.242412 -0.762)
		(end 206.242412 -1.0668)
		(width 0.14224)
		(layer "In11.Cu")
		(net "M_C_DQ<12>")
	)
	(segment
		(start 229.097586 -60.183268)
		(end 230.341932 -60.183268)
		(width 0.14224)
		(layer "In11.Cu")
		(net "M_C_DQ<12>")
	)
	(segment
		(start 206.0194 -18.3134)
		(end 206.2226 -18.5166)
		(width 0.14224)
		(layer "In11.Cu")
		(net "M_C_DQ<12>")
	)
	(segment
		(start 232.574338 -59.966606)
		(end 233.297476 -60.689744)
		(width 0.0889)
		(layer "In11.Cu")
		(net "M_C_DQ<12>")
	)
	(segment
		(start 230.341932 -60.183268)
		(end 230.558594 -59.966606)
		(width 0.0889)
		(layer "In11.Cu")
		(net "M_C_DQ<12>")
	)
	(segment
		(start 206.225394 -2.141728)
		(end 206.225394 -2.616454)
		(width 0.14224)
		(layer "In11.Cu")
		(net "M_C_DQ<12>")
	)
	(segment
		(start 206.270352 -37.356034)
		(end 229.097586 -60.183268)
		(width 0.14224)
		(layer "In11.Cu")
		(net "M_C_DQ<12>")
	)
	(segment
		(start 206.270352 -23.390098)
		(end 206.270352 -37.356034)
		(width 0.14224)
		(layer "In11.Cu")
		(net "M_C_DQ<12>")
	)
	(segment
		(start 206.0194 -17.0434)
		(end 206.0194 -18.3134)
		(width 0.14224)
		(layer "In11.Cu")
		(net "M_C_DQ<12>")
	)
	(segment
		(start 206.2226 -9.3726)
		(end 206.0194 -9.5758)
		(width 0.14224)
		(layer "In11.Cu")
		(net "M_C_DQ<12>")
	)
	(segment
		(start 206.2226 -8.9154)
		(end 206.2226 -9.3726)
		(width 0.14224)
		(layer "In11.Cu")
		(net "M_C_DQ<12>")
	)
	(segment
		(start 233.297476 -60.689744)
		(end 233.383328 -60.838588)
		(width 0.0889)
		(layer "In11.Cu")
		(net "M_C_DQ<12>")
	)
	(segment
		(start 206.0448 -21.923502)
		(end 206.0448 -23.164546)
		(width 0.14224)
		(layer "In11.Cu")
		(net "M_C_DQ<12>")
	)
	(segment
		(start 206.242412 -1.0668)
		(end 205.874112 -1.4351)
		(width 0.14224)
		(layer "In11.Cu")
		(net "M_C_DQ<12>")
	)
	(segment
		(start 205.874112 -1.4351)
		(end 205.874112 -1.790446)
		(width 0.14224)
		(layer "In11.Cu")
		(net "M_C_DQ<12>")
	)
	(segment
		(start 205.861412 -0.076454)
		(end 205.861412 -0.381)
		(width 0.14224)
		(layer "In11.Cu")
		(net "M_C_DQ<12>")
	)
	(segment
		(start 230.558594 -59.966606)
		(end 232.574338 -59.966606)
		(width 0.0889)
		(layer "In11.Cu")
		(net "M_C_DQ<12>")
	)
	(segment
		(start 240.741708 -62.92469)
		(end 240.774474 -62.92469)
		(width 0.0889)
		(layer "In11.Cu")
		(net "M_C_DQ<12>")
	)
	(segment
		(start 239.889792 -63.419736)
		(end 239.919764 -63.419736)
		(width 0.0889)
		(layer "In11.Cu")
		(net "M_C_DQ<12>")
	)
	(segment
		(start 206.1464 -21.2344)
		(end 206.2226 -21.3106)
		(width 0.14224)
		(layer "In11.Cu")
		(net "M_C_DQ<12>")
	)
	(segment
		(start 205.514194 -3.327654)
		(end 205.514194 -4.122166)
		(width 0.14224)
		(layer "In11.Cu")
		(net "M_C_DQ<12>")
	)
	(segment
		(start 206.2226 -18.5166)
		(end 206.2226 -19.05)
		(width 0.14224)
		(layer "In11.Cu")
		(net "M_C_DQ<12>")
	)
	(segment
		(start 206.247746 -4.855718)
		(end 206.247746 -7.239254)
		(width 0.14224)
		(layer "In11.Cu")
		(net "M_C_DQ<12>")
	)
	(segment
		(start 236.449108 -61.629036)
		(end 236.481874 -61.629036)
		(width 0.0889)
		(layer "In11.Cu")
		(net "M_C_DQ<12>")
	)
	(segment
		(start 206.501746 1.0414)
		(end 206.225394 0.765048)
		(width 0.14224)
		(layer "In11.Cu")
		(net "M_C_DQ<12>")
	)
	(segment
		(start 206.0448 -12.322302)
		(end 206.0448 -13.59281)
		(width 0.14224)
		(layer "In11.Cu")
		(net "M_C_DQ<12>")
	)
	(segment
		(start 206.0194 -9.5758)
		(end 206.0194 -11.4808)
		(width 0.14224)
		(layer "In11.Cu")
		(net "M_C_DQ<12>")
	)
	(segment
		(start 206.0448 -13.59281)
		(end 206.2226 -13.77061)
		(width 0.14224)
		(layer "In11.Cu")
		(net "M_C_DQ<12>")
	)
	(segment
		(start 241.110008 -62.724538)
		(end 241.126772 -62.695074)
		(width 0.0889)
		(layer "In11.Cu")
		(net "M_C_DQ<12>")
	)
	(segment
		(start 206.0448 -23.164546)
		(end 206.270352 -23.390098)
		(width 0.14224)
		(layer "In11.Cu")
		(net "M_C_DQ<12>")
	)
	(segment
		(start 206.2226 -19.05)
		(end 206.1464 -19.1262)
		(width 0.14224)
		(layer "In11.Cu")
		(net "M_C_DQ<12>")
	)
	(segment
		(start 206.225394 -2.616454)
		(end 205.514194 -3.327654)
		(width 0.14224)
		(layer "In11.Cu")
		(net "M_C_DQ<12>")
	)
	(segment
		(start 205.749906 -4.357878)
		(end 206.247746 -4.855718)
		(width 0.14224)
		(layer "In11.Cu")
		(net "M_C_DQ<12>")
	)
	(segment
		(start 205.861412 -0.381)
		(end 206.242412 -0.762)
		(width 0.14224)
		(layer "In11.Cu")
		(net "M_C_DQ<12>")
	)
	(segment
		(start 205.874112 -1.790446)
		(end 206.225394 -2.141728)
		(width 0.14224)
		(layer "In11.Cu")
		(net "M_C_DQ<12>")
	)
	(segment
		(start 239.211104 -63.11519)
		(end 239.666018 -63.340996)
		(width 0.0889)
		(layer "In11.Cu")
		(net "M_C_DQ<12>")
	)
	(segment
		(start 205.514194 -4.122166)
		(end 205.749906 -4.357878)
		(width 0.14224)
		(layer "In11.Cu")
		(net "M_C_DQ<12>")
	)
	(segment
		(start 206.2226 -21.3106)
		(end 206.2226 -21.745702)
		(width 0.14224)
		(layer "In11.Cu")
		(net "M_C_DQ<12>")
	)
	(segment
		(start 206.019146 -8.711946)
		(end 206.2226 -8.9154)
		(width 0.14224)
		(layer "In11.Cu")
		(net "M_C_DQ<12>")
	)
	(segment
		(start 206.1464 -19.1262)
		(end 206.1464 -21.2344)
		(width 0.14224)
		(layer "In11.Cu")
		(net "M_C_DQ<12>")
	)
	(segment
		(start 235.594398 -61.13399)
		(end 235.627164 -61.13399)
		(width 0.0889)
		(layer "In11.Cu")
		(net "M_C_DQ<12>")
	)
	(segment
		(start 206.225394 0.765048)
		(end 206.225394 0.287528)
		(width 0.14224)
		(layer "In11.Cu")
		(net "M_C_DQ<12>")
	)
	(segment
		(start 206.247746 -7.239254)
		(end 206.019146 -7.467854)
		(width 0.14224)
		(layer "In11.Cu")
		(net "M_C_DQ<12>")
	)
	(segment
		(start 206.2226 -11.684)
		(end 206.2226 -12.144502)
		(width 0.14224)
		(layer "In11.Cu")
		(net "M_C_DQ<12>")
	)
	(segment
		(start 237.311438 -62.12459)
		(end 237.344204 -62.12459)
		(width 0.0889)
		(layer "In11.Cu")
		(net "M_C_DQ<12>")
	)
	(segment
		(start 239.028478 -63.11519)
		(end 239.211104 -63.11519)
		(width 0.0889)
		(layer "In11.Cu")
		(net "M_C_DQ<12>")
	)
	(segment
		(start 206.2226 -12.144502)
		(end 206.0448 -12.322302)
		(width 0.14224)
		(layer "In11.Cu")
		(net "M_C_DQ<12>")
	)
	(segment
		(start 206.225394 0.287528)
		(end 205.861412 -0.076454)
		(width 0.14224)
		(layer "In11.Cu")
		(net "M_C_DQ<12>")
	)
	(segment
		(start 238.166148 -62.619636)
		(end 238.198914 -62.619636)
		(width 0.0889)
		(layer "In11.Cu")
		(net "M_C_DQ<12>")
	)
	(segment
		(start 206.2226 -21.745702)
		(end 206.0448 -21.923502)
		(width 0.14224)
		(layer "In11.Cu")
		(net "M_C_DQ<12>")
	)
	(segment
		(start 206.019146 -7.467854)
		(end 206.019146 -8.711946)
		(width 0.14224)
		(layer "In11.Cu")
		(net "M_C_DQ<12>")
	)
	(segment
		(start 241.126772 -62.695074)
		(end 241.621818 -62.029086)
		(width 0.0889)
		(layer "In11.Cu")
		(net "M_C_DQ<12>")
	)
	(arc
		(start 239.919764 -63.419736)
		(mid 240.111406 -63.36257)
		(end 240.251488 -63.219838)
		(width 0.0889)
		(layer "In11.Cu")
		(net "M_C_DQ<12>")
	)
	(arc
		(start 240.774474 -62.92469)
		(mid 240.968324 -62.86834)
		(end 241.110008 -62.724538)
		(width 0.0889)
		(layer "In11.Cu")
		(net "M_C_DQ<12>")
	)
	(arc
		(start 238.534448 -62.819788)
		(mid 238.743056 -63.03172)
		(end 239.028478 -63.11519)
		(width 0.0889)
		(layer "In11.Cu")
		(net "M_C_DQ<12>")
	)
	(arc
		(start 238.198914 -62.619636)
		(mid 238.392764 -62.675986)
		(end 238.534448 -62.819788)
		(width 0.0889)
		(layer "In11.Cu")
		(net "M_C_DQ<12>")
	)
	(arc
		(start 235.627164 -61.13399)
		(mid 235.818806 -61.191156)
		(end 235.958888 -61.333888)
		(width 0.0889)
		(layer "In11.Cu")
		(net "M_C_DQ<12>")
	)
	(arc
		(start 237.344204 -62.12459)
		(mid 237.535846 -62.181756)
		(end 237.675928 -62.324488)
		(width 0.0889)
		(layer "In11.Cu")
		(net "M_C_DQ<12>")
	)
	(arc
		(start 235.958888 -61.333888)
		(mid 236.165892 -61.544752)
		(end 236.449108 -61.629036)
		(width 0.0889)
		(layer "In11.Cu")
		(net "M_C_DQ<12>")
	)
	(arc
		(start 236.817408 -61.829188)
		(mid 237.026016 -62.04112)
		(end 237.311438 -62.12459)
		(width 0.0889)
		(layer "In11.Cu")
		(net "M_C_DQ<12>")
	)
	(arc
		(start 239.666018 -63.340996)
		(mid 239.771941 -63.397311)
		(end 239.889792 -63.419736)
		(width 0.0889)
		(layer "In11.Cu")
		(net "M_C_DQ<12>")
	)
	(arc
		(start 236.481874 -61.629036)
		(mid 236.675724 -61.685386)
		(end 236.817408 -61.829188)
		(width 0.0889)
		(layer "In11.Cu")
		(net "M_C_DQ<12>")
	)
	(arc
		(start 235.100368 -60.838588)
		(mid 235.308976 -61.05052)
		(end 235.594398 -61.13399)
		(width 0.0889)
		(layer "In11.Cu")
		(net "M_C_DQ<12>")
	)
	(arc
		(start 233.912918 -61.13399)
		(mid 234.198342 -61.050523)
		(end 234.406948 -60.838588)
		(width 0.0889)
		(layer "In11.Cu")
		(net "M_C_DQ<12>")
	)
	(arc
		(start 234.406948 -60.838588)
		(mid 234.753658 -60.638277)
		(end 235.100368 -60.838588)
		(width 0.0889)
		(layer "In11.Cu")
		(net "M_C_DQ<12>")
	)
	(arc
		(start 237.675928 -62.324488)
		(mid 237.882932 -62.535352)
		(end 238.166148 -62.619636)
		(width 0.0889)
		(layer "In11.Cu")
		(net "M_C_DQ<12>")
	)
	(arc
		(start 240.251488 -63.219838)
		(mid 240.458492 -63.008974)
		(end 240.741708 -62.92469)
		(width 0.0889)
		(layer "In11.Cu")
		(net "M_C_DQ<12>")
	)
	(arc
		(start 233.383328 -60.838588)
		(mid 233.591936 -61.05052)
		(end 233.877358 -61.13399)
		(width 0.0889)
		(layer "In11.Cu")
		(net "M_C_DQ<12>")
	)
	(segment
		(start 213.399878 3.778758)
		(end 213.399878 2.514854)
		(width 0.1651)
		(layer "F.Cu")
		(net "M_C_DQ<11>")
	)
	(segment
		(start 241.334798 -58.561986)
		(end 240.763298 -58.561986)
		(width 0.0889)
		(layer "F.Cu")
		(net "M_C_DQ<11>")
	)
	(segment
		(start 213.400386 3.778758)
		(end 213.399878 3.778758)
		(width 0.1651)
		(layer "F.Cu")
		(net "M_C_DQ<11>")
	)
	(via
		(at 214.249762 -3.076956)
		(size 0.508)
		(drill 0.254)
		(layers "F.Cu" "B.Cu")
		(net "M_C_DQ<11>")
	)
	(via
		(at 213.399878 2.514854)
		(size 0.508)
		(drill 0.254)
		(layers "F.Cu" "B.Cu")
		(net "M_C_DQ<11>")
	)
	(via
		(at 240.763298 -58.561986)
		(size 0.508)
		(drill 0.254)
		(layers "F.Cu" "B.Cu")
		(net "M_C_DQ<11>")
	)
	(segment
		(start 214.250524 -3.076194)
		(end 214.249762 -3.076956)
		(width 0.1651)
		(layer "B.Cu")
		(net "M_C_DQ<11>")
	)
	(segment
		(start 214.250524 -1.021842)
		(end 214.250524 -3.076194)
		(width 0.1651)
		(layer "B.Cu")
		(net "M_C_DQ<11>")
	)
	(segment
		(start 221.750128 -41.570402)
		(end 221.969076 -41.570402)
		(width 0.14224)
		(layer "In11.Cu")
		(net "M_C_DQ<11>")
	)
	(segment
		(start 214.617046 -16.890746)
		(end 214.756746 -17.030446)
		(width 0.14224)
		(layer "In11.Cu")
		(net "M_C_DQ<11>")
	)
	(segment
		(start 219.964254 -39.827962)
		(end 219.964254 -40.02913)
		(width 0.14224)
		(layer "In11.Cu")
		(net "M_C_DQ<11>")
	)
	(segment
		(start 217.8304 -38.62451)
		(end 218.118944 -38.913054)
		(width 0.14224)
		(layer "In11.Cu")
		(net "M_C_DQ<11>")
	)
	(segment
		(start 223.942148 -43.762422)
		(end 223.564704 -44.139866)
		(width 0.14224)
		(layer "In11.Cu")
		(net "M_C_DQ<11>")
	)
	(segment
		(start 219.50426 -39.568882)
		(end 219.705428 -39.569136)
		(width 0.14224)
		(layer "In11.Cu")
		(net "M_C_DQ<11>")
	)
	(segment
		(start 221.811088 -42.605198)
		(end 222.030544 -42.824654)
		(width 0.14224)
		(layer "In11.Cu")
		(net "M_C_DQ<11>")
	)
	(segment
		(start 231.994456 -53.533294)
		(end 232.256076 -53.533294)
		(width 0.0889)
		(layer "In11.Cu")
		(net "M_C_DQ<11>")
	)
	(segment
		(start 226.134168 -45.954442)
		(end 226.353116 -45.954442)
		(width 0.14224)
		(layer "In11.Cu")
		(net "M_C_DQ<11>")
	)
	(segment
		(start 238.172752 -57.476136)
		(end 238.200692 -57.476136)
		(width 0.0889)
		(layer "In11.Cu")
		(net "M_C_DQ<11>")
	)
	(segment
		(start 214.757 -19.2532)
		(end 214.757 -21.157946)
		(width 0.14224)
		(layer "In11.Cu")
		(net "M_C_DQ<11>")
	)
	(segment
		(start 214.758016 0.7366)
		(end 214.602568 0.581152)
		(width 0.14224)
		(layer "In11.Cu")
		(net "M_C_DQ<11>")
	)
	(segment
		(start 226.572572 -46.392846)
		(end 226.195128 -46.77029)
		(width 0.14224)
		(layer "In11.Cu")
		(net "M_C_DQ<11>")
	)
	(segment
		(start 222.845884 -42.44721)
		(end 223.06534 -42.666666)
		(width 0.14224)
		(layer "In11.Cu")
		(net "M_C_DQ<11>")
	)
	(segment
		(start 232.256076 -53.533294)
		(end 234.217718 -55.494936)
		(width 0.0889)
		(layer "In11.Cu")
		(net "M_C_DQ<11>")
	)
	(segment
		(start 222.687896 -43.482006)
		(end 222.907352 -43.701462)
		(width 0.14224)
		(layer "In11.Cu")
		(net "M_C_DQ<11>")
	)
	(segment
		(start 222.188532 -41.789858)
		(end 222.188532 -42.008806)
		(width 0.14224)
		(layer "In11.Cu")
		(net "M_C_DQ<11>")
	)
	(segment
		(start 219.2401 -39.833042)
		(end 219.50426 -39.568882)
		(width 0.14224)
		(layer "In11.Cu")
		(net "M_C_DQ<11>")
	)
	(segment
		(start 214.617046 -13.681456)
		(end 214.617046 -16.890746)
		(width 0.14224)
		(layer "In11.Cu")
		(net "M_C_DQ<11>")
	)
	(segment
		(start 225.695764 -45.516038)
		(end 225.31832 -45.893482)
		(width 0.14224)
		(layer "In11.Cu")
		(net "M_C_DQ<11>")
	)
	(segment
		(start 239.941354 -58.466736)
		(end 240.763298 -58.561986)
		(width 0.0889)
		(layer "In11.Cu")
		(net "M_C_DQ<11>")
	)
	(segment
		(start 236.455712 -56.485536)
		(end 236.488478 -56.485536)
		(width 0.0889)
		(layer "In11.Cu")
		(net "M_C_DQ<11>")
	)
	(segment
		(start 219.964254 -40.02913)
		(end 219.700094 -40.29329)
		(width 0.14224)
		(layer "In11.Cu")
		(net "M_C_DQ<11>")
	)
	(segment
		(start 224.003108 -44.57827)
		(end 224.380552 -44.200826)
		(width 0.14224)
		(layer "In11.Cu")
		(net "M_C_DQ<11>")
	)
	(segment
		(start 223.942148 -43.543474)
		(end 223.942148 -43.762422)
		(width 0.14224)
		(layer "In11.Cu")
		(net "M_C_DQ<11>")
	)
	(segment
		(start 224.879916 -45.455078)
		(end 225.25736 -45.077634)
		(width 0.14224)
		(layer "In11.Cu")
		(net "M_C_DQ<11>")
	)
	(segment
		(start 214.629746 -23.335996)
		(end 214.629746 -28.4734)
		(width 0.14224)
		(layer "In11.Cu")
		(net "M_C_DQ<11>")
	)
	(segment
		(start 237.318042 -56.98109)
		(end 237.350808 -56.98109)
		(width 0.0889)
		(layer "In11.Cu")
		(net "M_C_DQ<11>")
	)
	(segment
		(start 218.118944 -38.913054)
		(end 218.320112 -38.913054)
		(width 0.14224)
		(layer "In11.Cu")
		(net "M_C_DQ<11>")
	)
	(segment
		(start 221.153736 -41.947846)
		(end 221.372684 -41.947846)
		(width 0.14224)
		(layer "In11.Cu")
		(net "M_C_DQ<11>")
	)
	(segment
		(start 235.601002 -55.99049)
		(end 235.633768 -55.99049)
		(width 0.0889)
		(layer "In11.Cu")
		(net "M_C_DQ<11>")
	)
	(segment
		(start 222.030544 -42.824654)
		(end 222.249492 -42.824654)
		(width 0.14224)
		(layer "In11.Cu")
		(net "M_C_DQ<11>")
	)
	(segment
		(start 223.503744 -43.324018)
		(end 223.722692 -43.324018)
		(width 0.14224)
		(layer "In11.Cu")
		(net "M_C_DQ<11>")
	)
	(segment
		(start 219.038932 -39.833042)
		(end 219.2401 -39.833042)
		(width 0.14224)
		(layer "In11.Cu")
		(net "M_C_DQ<11>")
	)
	(segment
		(start 220.495876 -41.071038)
		(end 220.894656 -40.672258)
		(width 0.14224)
		(layer "In11.Cu")
		(net "M_C_DQ<11>")
	)
	(segment
		(start 214.782146 -13.516356)
		(end 214.617046 -13.681456)
		(width 0.14224)
		(layer "In11.Cu")
		(net "M_C_DQ<11>")
	)
	(segment
		(start 224.441512 -45.016674)
		(end 224.441512 -45.235622)
		(width 0.14224)
		(layer "In11.Cu")
		(net "M_C_DQ<11>")
	)
	(segment
		(start 223.1263 -43.701462)
		(end 223.503744 -43.324018)
		(width 0.14224)
		(layer "In11.Cu")
		(net "M_C_DQ<11>")
	)
	(segment
		(start 225.476308 -45.077634)
		(end 225.695764 -45.29709)
		(width 0.14224)
		(layer "In11.Cu")
		(net "M_C_DQ<11>")
	)
	(segment
		(start 225.695764 -45.29709)
		(end 225.695764 -45.516038)
		(width 0.14224)
		(layer "In11.Cu")
		(net "M_C_DQ<11>")
	)
	(segment
		(start 218.780106 -39.373302)
		(end 218.779852 -39.573962)
		(width 0.14224)
		(layer "In11.Cu")
		(net "M_C_DQ<11>")
	)
	(segment
		(start 221.372684 -41.947846)
		(end 221.750128 -41.570402)
		(width 0.14224)
		(layer "In11.Cu")
		(net "M_C_DQ<11>")
	)
	(segment
		(start 223.06534 -42.885614)
		(end 222.687896 -43.263058)
		(width 0.14224)
		(layer "In11.Cu")
		(net "M_C_DQ<11>")
	)
	(segment
		(start 221.333314 -41.110408)
		(end 220.93428 -41.509442)
		(width 0.14224)
		(layer "In11.Cu")
		(net "M_C_DQ<11>")
	)
	(segment
		(start 239.028224 -57.971436)
		(end 239.064038 -57.971436)
		(width 0.0889)
		(layer "In11.Cu")
		(net "M_C_DQ<11>")
	)
	(segment
		(start 214.757 -21.157946)
		(end 214.604346 -21.3106)
		(width 0.14224)
		(layer "In11.Cu")
		(net "M_C_DQ<11>")
	)
	(segment
		(start 234.217718 -55.494936)
		(end 234.771438 -55.494936)
		(width 0.0889)
		(layer "In11.Cu")
		(net "M_C_DQ<11>")
	)
	(segment
		(start 214.604346 -11.7094)
		(end 214.604346 -12.220956)
		(width 0.14224)
		(layer "In11.Cu")
		(net "M_C_DQ<11>")
	)
	(segment
		(start 219.705428 -39.569136)
		(end 219.964254 -39.827962)
		(width 0.14224)
		(layer "In11.Cu")
		(net "M_C_DQ<11>")
	)
	(segment
		(start 226.572572 -46.173898)
		(end 226.572572 -46.392846)
		(width 0.14224)
		(layer "In11.Cu")
		(net "M_C_DQ<11>")
	)
	(segment
		(start 213.766146 -3.965956)
		(end 214.132668 -4.332478)
		(width 0.14224)
		(layer "In11.Cu")
		(net "M_C_DQ<11>")
	)
	(segment
		(start 224.660968 -45.455078)
		(end 224.879916 -45.455078)
		(width 0.14224)
		(layer "In11.Cu")
		(net "M_C_DQ<11>")
	)
	(segment
		(start 226.353116 -45.954442)
		(end 226.572572 -46.173898)
		(width 0.14224)
		(layer "In11.Cu")
		(net "M_C_DQ<11>")
	)
	(segment
		(start 214.756746 -17.030446)
		(end 214.756746 -18.415254)
		(width 0.14224)
		(layer "In11.Cu")
		(net "M_C_DQ<11>")
	)
	(segment
		(start 231.758744 -53.297582)
		(end 231.994456 -53.533294)
		(width 0.0889)
		(layer "In11.Cu")
		(net "M_C_DQ<11>")
	)
	(segment
		(start 221.969076 -41.570402)
		(end 222.188532 -41.789858)
		(width 0.14224)
		(layer "In11.Cu")
		(net "M_C_DQ<11>")
	)
	(segment
		(start 230.6828 -52.221638)
		(end 231.758744 -53.297582)
		(width 0.14224)
		(layer "In11.Cu")
		(net "M_C_DQ<11>")
	)
	(segment
		(start 214.249762 -3.076956)
		(end 213.766146 -3.560572)
		(width 0.14224)
		(layer "In11.Cu")
		(net "M_C_DQ<11>")
	)
	(segment
		(start 215.675972 -35.768026)
		(end 217.8304 -37.922454)
		(width 0.14224)
		(layer "In11.Cu")
		(net "M_C_DQ<11>")
	)
	(segment
		(start 226.195128 -46.77029)
		(end 226.195128 -46.989238)
		(width 0.14224)
		(layer "In11.Cu")
		(net "M_C_DQ<11>")
	)
	(segment
		(start 213.716616 1.8796)
		(end 214.046816 1.5494)
		(width 0.14224)
		(layer "In11.Cu")
		(net "M_C_DQ<11>")
	)
	(segment
		(start 215.675972 -29.519626)
		(end 215.675972 -35.768026)
		(width 0.14224)
		(layer "In11.Cu")
		(net "M_C_DQ<11>")
	)
	(segment
		(start 214.782146 -23.183596)
		(end 214.629746 -23.335996)
		(width 0.14224)
		(layer "In11.Cu")
		(net "M_C_DQ<11>")
	)
	(segment
		(start 214.7824 -11.531346)
		(end 214.604346 -11.7094)
		(width 0.14224)
		(layer "In11.Cu")
		(net "M_C_DQ<11>")
	)
	(segment
		(start 214.604346 -21.822156)
		(end 214.782146 -21.999956)
		(width 0.14224)
		(layer "In11.Cu")
		(net "M_C_DQ<11>")
	)
	(segment
		(start 214.604346 -19.100546)
		(end 214.757 -19.2532)
		(width 0.14224)
		(layer "In11.Cu")
		(net "M_C_DQ<11>")
	)
	(segment
		(start 214.617046 -7.289546)
		(end 214.756746 -7.429246)
		(width 0.14224)
		(layer "In11.Cu")
		(net "M_C_DQ<11>")
	)
	(segment
		(start 214.604346 -9.346946)
		(end 214.7824 -9.525)
		(width 0.14224)
		(layer "In11.Cu")
		(net "M_C_DQ<11>")
	)
	(segment
		(start 219.044266 -38.907974)
		(end 219.044266 -39.109142)
		(width 0.14224)
		(layer "In11.Cu")
		(net "M_C_DQ<11>")
	)
	(segment
		(start 214.132668 -4.332478)
		(end 214.132668 -4.646422)
		(width 0.14224)
		(layer "In11.Cu")
		(net "M_C_DQ<11>")
	)
	(segment
		(start 214.782146 -21.999956)
		(end 214.782146 -23.183596)
		(width 0.14224)
		(layer "In11.Cu")
		(net "M_C_DQ<11>")
	)
	(segment
		(start 213.716616 2.198116)
		(end 213.716616 1.8796)
		(width 0.14224)
		(layer "In11.Cu")
		(net "M_C_DQ<11>")
	)
	(segment
		(start 214.604346 -8.941054)
		(end 214.604346 -9.346946)
		(width 0.14224)
		(layer "In11.Cu")
		(net "M_C_DQ<11>")
	)
	(segment
		(start 224.818956 -44.63923)
		(end 224.441512 -45.016674)
		(width 0.14224)
		(layer "In11.Cu")
		(net "M_C_DQ<11>")
	)
	(segment
		(start 223.564704 -44.358814)
		(end 223.78416 -44.57827)
		(width 0.14224)
		(layer "In11.Cu")
		(net "M_C_DQ<11>")
	)
	(segment
		(start 214.629746 -28.4734)
		(end 215.675972 -29.519626)
		(width 0.14224)
		(layer "In11.Cu")
		(net "M_C_DQ<11>")
	)
	(segment
		(start 214.617046 -5.1308)
		(end 214.617046 -7.289546)
		(width 0.14224)
		(layer "In11.Cu")
		(net "M_C_DQ<11>")
	)
	(segment
		(start 225.537776 -46.331886)
		(end 225.756724 -46.331886)
		(width 0.14224)
		(layer "In11.Cu")
		(net "M_C_DQ<11>")
	)
	(segment
		(start 224.818956 -44.420282)
		(end 224.818956 -44.63923)
		(width 0.14224)
		(layer "In11.Cu")
		(net "M_C_DQ<11>")
	)
	(segment
		(start 217.8304 -37.922454)
		(end 217.8304 -38.62451)
		(width 0.14224)
		(layer "In11.Cu")
		(net "M_C_DQ<11>")
	)
	(segment
		(start 221.811088 -42.38625)
		(end 221.811088 -42.605198)
		(width 0.14224)
		(layer "In11.Cu")
		(net "M_C_DQ<11>")
	)
	(segment
		(start 222.626936 -42.44721)
		(end 222.845884 -42.44721)
		(width 0.14224)
		(layer "In11.Cu")
		(net "M_C_DQ<11>")
	)
	(segment
		(start 214.300816 1.5494)
		(end 214.758016 1.0922)
		(width 0.14224)
		(layer "In11.Cu")
		(net "M_C_DQ<11>")
	)
	(segment
		(start 222.907352 -43.701462)
		(end 223.1263 -43.701462)
		(width 0.14224)
		(layer "In11.Cu")
		(net "M_C_DQ<11>")
	)
	(segment
		(start 220.93428 -41.72839)
		(end 221.153736 -41.947846)
		(width 0.14224)
		(layer "In11.Cu")
		(net "M_C_DQ<11>")
	)
	(segment
		(start 214.046816 1.5494)
		(end 214.300816 1.5494)
		(width 0.14224)
		(layer "In11.Cu")
		(net "M_C_DQ<11>")
	)
	(segment
		(start 214.604346 -18.567654)
		(end 214.604346 -19.100546)
		(width 0.14224)
		(layer "In11.Cu")
		(net "M_C_DQ<11>")
	)
	(segment
		(start 214.756746 -7.429246)
		(end 214.756746 -8.788654)
		(width 0.14224)
		(layer "In11.Cu")
		(net "M_C_DQ<11>")
	)
	(segment
		(start 214.756746 -8.788654)
		(end 214.604346 -8.941054)
		(width 0.14224)
		(layer "In11.Cu")
		(net "M_C_DQ<11>")
	)
	(segment
		(start 214.756746 -18.415254)
		(end 214.604346 -18.567654)
		(width 0.14224)
		(layer "In11.Cu")
		(net "M_C_DQ<11>")
	)
	(segment
		(start 220.894656 -40.672258)
		(end 221.113858 -40.672258)
		(width 0.14224)
		(layer "In11.Cu")
		(net "M_C_DQ<11>")
	)
	(segment
		(start 214.782146 -12.398756)
		(end 214.782146 -13.516356)
		(width 0.14224)
		(layer "In11.Cu")
		(net "M_C_DQ<11>")
	)
	(segment
		(start 225.25736 -45.077634)
		(end 225.476308 -45.077634)
		(width 0.14224)
		(layer "In11.Cu")
		(net "M_C_DQ<11>")
	)
	(segment
		(start 218.320112 -38.913054)
		(end 218.584272 -38.648894)
		(width 0.14224)
		(layer "In11.Cu")
		(net "M_C_DQ<11>")
	)
	(segment
		(start 213.766146 -3.560572)
		(end 213.766146 -3.965956)
		(width 0.14224)
		(layer "In11.Cu")
		(net "M_C_DQ<11>")
	)
	(segment
		(start 222.687896 -43.263058)
		(end 222.687896 -43.482006)
		(width 0.14224)
		(layer "In11.Cu")
		(net "M_C_DQ<11>")
	)
	(segment
		(start 224.5995 -44.200826)
		(end 224.818956 -44.420282)
		(width 0.14224)
		(layer "In11.Cu")
		(net "M_C_DQ<11>")
	)
	(segment
		(start 223.564704 -44.139866)
		(end 223.564704 -44.358814)
		(width 0.14224)
		(layer "In11.Cu")
		(net "M_C_DQ<11>")
	)
	(segment
		(start 218.584272 -38.648894)
		(end 218.78544 -38.649148)
		(width 0.14224)
		(layer "In11.Cu")
		(net "M_C_DQ<11>")
	)
	(segment
		(start 223.78416 -44.57827)
		(end 224.003108 -44.57827)
		(width 0.14224)
		(layer "In11.Cu")
		(net "M_C_DQ<11>")
	)
	(segment
		(start 221.333314 -40.891714)
		(end 221.333314 -41.110408)
		(width 0.14224)
		(layer "In11.Cu")
		(net "M_C_DQ<11>")
	)
	(segment
		(start 226.195128 -46.989238)
		(end 230.6828 -51.47691)
		(width 0.14224)
		(layer "In11.Cu")
		(net "M_C_DQ<11>")
	)
	(segment
		(start 218.779852 -39.573962)
		(end 219.038932 -39.833042)
		(width 0.14224)
		(layer "In11.Cu")
		(net "M_C_DQ<11>")
	)
	(segment
		(start 214.7824 -9.525)
		(end 214.7824 -11.531346)
		(width 0.14224)
		(layer "In11.Cu")
		(net "M_C_DQ<11>")
	)
	(segment
		(start 214.602568 -2.72415)
		(end 214.249762 -3.076956)
		(width 0.14224)
		(layer "In11.Cu")
		(net "M_C_DQ<11>")
	)
	(segment
		(start 214.758016 1.0922)
		(end 214.758016 0.7366)
		(width 0.14224)
		(layer "In11.Cu")
		(net "M_C_DQ<11>")
	)
	(segment
		(start 219.044266 -39.109142)
		(end 218.780106 -39.373302)
		(width 0.14224)
		(layer "In11.Cu")
		(net "M_C_DQ<11>")
	)
	(segment
		(start 214.604346 -21.3106)
		(end 214.604346 -21.822156)
		(width 0.14224)
		(layer "In11.Cu")
		(net "M_C_DQ<11>")
	)
	(segment
		(start 225.31832 -46.11243)
		(end 225.537776 -46.331886)
		(width 0.14224)
		(layer "In11.Cu")
		(net "M_C_DQ<11>")
	)
	(segment
		(start 220.276928 -41.071038)
		(end 220.495876 -41.071038)
		(width 0.14224)
		(layer "In11.Cu")
		(net "M_C_DQ<11>")
	)
	(segment
		(start 214.132668 -4.646422)
		(end 214.617046 -5.1308)
		(width 0.14224)
		(layer "In11.Cu")
		(net "M_C_DQ<11>")
	)
	(segment
		(start 222.249492 -42.824654)
		(end 222.626936 -42.44721)
		(width 0.14224)
		(layer "In11.Cu")
		(net "M_C_DQ<11>")
	)
	(segment
		(start 239.886744 -58.466736)
		(end 239.941354 -58.466736)
		(width 0.0889)
		(layer "In11.Cu")
		(net "M_C_DQ<11>")
	)
	(segment
		(start 225.756724 -46.331886)
		(end 226.134168 -45.954442)
		(width 0.14224)
		(layer "In11.Cu")
		(net "M_C_DQ<11>")
	)
	(segment
		(start 223.722692 -43.324018)
		(end 223.942148 -43.543474)
		(width 0.14224)
		(layer "In11.Cu")
		(net "M_C_DQ<11>")
	)
	(segment
		(start 223.06534 -42.666666)
		(end 223.06534 -42.885614)
		(width 0.14224)
		(layer "In11.Cu")
		(net "M_C_DQ<11>")
	)
	(segment
		(start 214.604346 -12.220956)
		(end 214.782146 -12.398756)
		(width 0.14224)
		(layer "In11.Cu")
		(net "M_C_DQ<11>")
	)
	(segment
		(start 224.441512 -45.235622)
		(end 224.660968 -45.455078)
		(width 0.14224)
		(layer "In11.Cu")
		(net "M_C_DQ<11>")
	)
	(segment
		(start 224.380552 -44.200826)
		(end 224.5995 -44.200826)
		(width 0.14224)
		(layer "In11.Cu")
		(net "M_C_DQ<11>")
	)
	(segment
		(start 218.78544 -38.649148)
		(end 219.044266 -38.907974)
		(width 0.14224)
		(layer "In11.Cu")
		(net "M_C_DQ<11>")
	)
	(segment
		(start 230.6828 -51.47691)
		(end 230.6828 -52.221638)
		(width 0.14224)
		(layer "In11.Cu")
		(net "M_C_DQ<11>")
	)
	(segment
		(start 225.31832 -45.893482)
		(end 225.31832 -46.11243)
		(width 0.14224)
		(layer "In11.Cu")
		(net "M_C_DQ<11>")
	)
	(segment
		(start 214.602568 0.581152)
		(end 214.602568 -2.72415)
		(width 0.14224)
		(layer "In11.Cu")
		(net "M_C_DQ<11>")
	)
	(segment
		(start 219.69984 -40.49395)
		(end 220.276928 -41.071038)
		(width 0.14224)
		(layer "In11.Cu")
		(net "M_C_DQ<11>")
	)
	(segment
		(start 219.700094 -40.29329)
		(end 219.69984 -40.49395)
		(width 0.14224)
		(layer "In11.Cu")
		(net "M_C_DQ<11>")
	)
	(segment
		(start 213.399878 2.514854)
		(end 213.716616 2.198116)
		(width 0.14224)
		(layer "In11.Cu")
		(net "M_C_DQ<11>")
	)
	(segment
		(start 220.93428 -41.509442)
		(end 220.93428 -41.72839)
		(width 0.14224)
		(layer "In11.Cu")
		(net "M_C_DQ<11>")
	)
	(segment
		(start 222.188532 -42.008806)
		(end 221.811088 -42.38625)
		(width 0.14224)
		(layer "In11.Cu")
		(net "M_C_DQ<11>")
	)
	(segment
		(start 221.113858 -40.672258)
		(end 221.333314 -40.891714)
		(width 0.14224)
		(layer "In11.Cu")
		(net "M_C_DQ<11>")
	)
	(arc
		(start 237.841028 -57.276238)
		(mid 237.981107 -57.418974)
		(end 238.172752 -57.476136)
		(width 0.0889)
		(layer "In11.Cu")
		(net "M_C_DQ<11>")
	)
	(arc
		(start 235.265468 -55.790338)
		(mid 235.407151 -55.934142)
		(end 235.601002 -55.99049)
		(width 0.0889)
		(layer "In11.Cu")
		(net "M_C_DQ<11>")
	)
	(arc
		(start 239.558068 -58.266838)
		(mid 239.696812 -58.408871)
		(end 239.886744 -58.466736)
		(width 0.0889)
		(layer "In11.Cu")
		(net "M_C_DQ<11>")
	)
	(arc
		(start 236.123988 -56.285638)
		(mid 236.264067 -56.428374)
		(end 236.455712 -56.485536)
		(width 0.0889)
		(layer "In11.Cu")
		(net "M_C_DQ<11>")
	)
	(arc
		(start 239.064038 -57.971436)
		(mid 239.349462 -58.054903)
		(end 239.558068 -58.266838)
		(width 0.0889)
		(layer "In11.Cu")
		(net "M_C_DQ<11>")
	)
	(arc
		(start 237.350808 -56.98109)
		(mid 237.634025 -57.065371)
		(end 237.841028 -57.276238)
		(width 0.0889)
		(layer "In11.Cu")
		(net "M_C_DQ<11>")
	)
	(arc
		(start 236.488478 -56.485536)
		(mid 236.773902 -56.569003)
		(end 236.982508 -56.780938)
		(width 0.0889)
		(layer "In11.Cu")
		(net "M_C_DQ<11>")
	)
	(arc
		(start 235.633768 -55.99049)
		(mid 235.916985 -56.074771)
		(end 236.123988 -56.285638)
		(width 0.0889)
		(layer "In11.Cu")
		(net "M_C_DQ<11>")
	)
	(arc
		(start 238.200692 -57.476136)
		(mid 238.488837 -57.558455)
		(end 238.699548 -57.771538)
		(width 0.0889)
		(layer "In11.Cu")
		(net "M_C_DQ<11>")
	)
	(arc
		(start 236.982508 -56.780938)
		(mid 237.124191 -56.924742)
		(end 237.318042 -56.98109)
		(width 0.0889)
		(layer "In11.Cu")
		(net "M_C_DQ<11>")
	)
	(arc
		(start 234.771438 -55.494936)
		(mid 235.056862 -55.578403)
		(end 235.265468 -55.790338)
		(width 0.0889)
		(layer "In11.Cu")
		(net "M_C_DQ<11>")
	)
	(arc
		(start 238.699548 -57.771538)
		(mid 238.838292 -57.913571)
		(end 239.028224 -57.971436)
		(width 0.0889)
		(layer "In11.Cu")
		(net "M_C_DQ<11>")
	)
	(segment
		(start 214.381334 0.30734)
		(end 214.381334 0.53086)
		(width 0.1651)
		(layer "F.Cu")
		(net "M_C_DQ<10>")
	)
	(segment
		(start 214.249762 0.662432)
		(end 214.249762 0.9398)
		(width 0.1651)
		(layer "F.Cu")
		(net "M_C_DQ<10>")
	)
	(segment
		(start 214.250524 0.17653)
		(end 214.381334 0.30734)
		(width 0.1651)
		(layer "F.Cu")
		(net "M_C_DQ<10>")
	)
	(segment
		(start 214.250524 -0.821182)
		(end 214.250524 0.17653)
		(width 0.1651)
		(layer "F.Cu")
		(net "M_C_DQ<10>")
	)
	(segment
		(start 240.476278 -59.057286)
		(end 239.904778 -59.057286)
		(width 0.0889)
		(layer "F.Cu")
		(net "M_C_DQ<10>")
	)
	(segment
		(start 214.381334 0.53086)
		(end 214.249762 0.662432)
		(width 0.1651)
		(layer "F.Cu")
		(net "M_C_DQ<10>")
	)
	(via
		(at 214.249762 0.9398)
		(size 0.508)
		(drill 0.254)
		(layers "F.Cu" "B.Cu")
		(net "M_C_DQ<10>")
	)
	(via
		(at 239.904778 -59.057286)
		(size 0.508)
		(drill 0.254)
		(layers "F.Cu" "B.Cu")
		(net "M_C_DQ<10>")
	)
	(via
		(at 213.399878 -4.357878)
		(size 0.508)
		(drill 0.254)
		(layers "F.Cu" "B.Cu")
		(net "M_C_DQ<10>")
	)
	(segment
		(start 213.400386 -5.621782)
		(end 213.399878 -5.621782)
		(width 0.1651)
		(layer "B.Cu")
		(net "M_C_DQ<10>")
	)
	(segment
		(start 213.399878 -5.621782)
		(end 213.399878 -4.357878)
		(width 0.1651)
		(layer "B.Cu")
		(net "M_C_DQ<10>")
	)
	(segment
		(start 213.741 -11.608054)
		(end 213.893146 -11.7602)
		(width 0.14224)
		(layer "In11.Cu")
		(net "M_C_DQ<10>")
	)
	(segment
		(start 232.177844 -53.723794)
		(end 234.139486 -55.685436)
		(width 0.0889)
		(layer "In11.Cu")
		(net "M_C_DQ<10>")
	)
	(segment
		(start 216.786714 -38.161214)
		(end 216.786714 -38.362382)
		(width 0.14224)
		(layer "In11.Cu")
		(net "M_C_DQ<10>")
	)
	(segment
		(start 213.893146 -21.796756)
		(end 213.740746 -21.949156)
		(width 0.14224)
		(layer "In11.Cu")
		(net "M_C_DQ<10>")
	)
	(segment
		(start 229.683818 -52.072794)
		(end 231.543606 -53.932582)
		(width 0.14224)
		(layer "In11.Cu")
		(net "M_C_DQ<10>")
	)
	(segment
		(start 223.681036 -46.46422)
		(end 223.899984 -46.46422)
		(width 0.14224)
		(layer "In11.Cu")
		(net "M_C_DQ<10>")
	)
	(segment
		(start 216.013792 -37.09416)
		(end 215.866726 -37.241226)
		(width 0.14224)
		(layer "In11.Cu")
		(net "M_C_DQ<10>")
	)
	(segment
		(start 225.754184 -48.560736)
		(end 225.973132 -48.560736)
		(width 0.14224)
		(layer "In11.Cu")
		(net "M_C_DQ<10>")
	)
	(segment
		(start 213.861396 -23.263606)
		(end 213.861396 -29.127196)
		(width 0.14224)
		(layer "In11.Cu")
		(net "M_C_DQ<10>")
	)
	(segment
		(start 236.449108 -56.676036)
		(end 236.481874 -56.676036)
		(width 0.0889)
		(layer "In11.Cu")
		(net "M_C_DQ<10>")
	)
	(segment
		(start 216.473786 -37.554154)
		(end 216.674954 -37.554154)
		(width 0.14224)
		(layer "In11.Cu")
		(net "M_C_DQ<10>")
	)
	(segment
		(start 225.931222 -47.50689)
		(end 225.931222 -47.725838)
		(width 0.14224)
		(layer "In11.Cu")
		(net "M_C_DQ<10>")
	)
	(segment
		(start 228.561646 -50.137314)
		(end 228.561646 -50.356262)
		(width 0.14224)
		(layer "In11.Cu")
		(net "M_C_DQ<10>")
	)
	(segment
		(start 213.893146 -8.991346)
		(end 213.893146 -9.372854)
		(width 0.14224)
		(layer "In11.Cu")
		(net "M_C_DQ<10>")
	)
	(segment
		(start 225.534728 -48.34128)
		(end 225.754184 -48.560736)
		(width 0.14224)
		(layer "In11.Cu")
		(net "M_C_DQ<10>")
	)
	(segment
		(start 235.594398 -56.18099)
		(end 235.627164 -56.18099)
		(width 0.0889)
		(layer "In11.Cu")
		(net "M_C_DQ<10>")
	)
	(segment
		(start 222.092774 -43.668442)
		(end 222.092774 -43.88739)
		(width 0.14224)
		(layer "In11.Cu")
		(net "M_C_DQ<10>")
	)
	(segment
		(start 229.683818 -51.259486)
		(end 229.683818 -52.072794)
		(width 0.14224)
		(layer "In11.Cu")
		(net "M_C_DQ<10>")
	)
	(segment
		(start 213.982046 -13.783056)
		(end 213.982046 -16.751046)
		(width 0.14224)
		(layer "In11.Cu")
		(net "M_C_DQ<10>")
	)
	(segment
		(start 213.851744 0.541782)
		(end 213.851744 0.236728)
		(width 0.14224)
		(layer "In11.Cu")
		(net "M_C_DQ<10>")
	)
	(segment
		(start 239.392968 -58.362088)
		(end 239.409732 -58.391552)
		(width 0.0889)
		(layer "In11.Cu")
		(net "M_C_DQ<10>")
	)
	(segment
		(start 227.246434 -49.04105)
		(end 227.465382 -49.04105)
		(width 0.14224)
		(layer "In11.Cu")
		(net "M_C_DQ<10>")
	)
	(segment
		(start 216.93378 -37.81298)
		(end 216.93378 -38.014148)
		(width 0.14224)
		(layer "In11.Cu")
		(net "M_C_DQ<10>")
	)
	(segment
		(start 223.84639 -45.641006)
		(end 223.46158 -46.025816)
		(width 0.14224)
		(layer "In11.Cu")
		(net "M_C_DQ<10>")
	)
	(segment
		(start 213.741 -9.525)
		(end 213.741 -11.608054)
		(width 0.14224)
		(layer "In11.Cu")
		(net "M_C_DQ<10>")
	)
	(segment
		(start 226.84994 -49.437544)
		(end 227.246434 -49.04105)
		(width 0.14224)
		(layer "In11.Cu")
		(net "M_C_DQ<10>")
	)
	(segment
		(start 213.766146 -7.365746)
		(end 213.766146 -8.864346)
		(width 0.14224)
		(layer "In11.Cu")
		(net "M_C_DQ<10>")
	)
	(segment
		(start 213.740746 -23.142956)
		(end 213.861396 -23.263606)
		(width 0.14224)
		(layer "In11.Cu")
		(net "M_C_DQ<10>")
	)
	(segment
		(start 237.311438 -57.17159)
		(end 237.344204 -57.17159)
		(width 0.0889)
		(layer "In11.Cu")
		(net "M_C_DQ<10>")
	)
	(segment
		(start 226.80803 -48.602646)
		(end 226.411536 -48.99914)
		(width 0.14224)
		(layer "In11.Cu")
		(net "M_C_DQ<10>")
	)
	(segment
		(start 224.503742 -46.07941)
		(end 225.054414 -46.630082)
		(width 0.14224)
		(layer "In11.Cu")
		(net "M_C_DQ<10>")
	)
	(segment
		(start 213.399878 -4.891278)
		(end 213.969346 -5.460746)
		(width 0.14224)
		(layer "In11.Cu")
		(net "M_C_DQ<10>")
	)
	(segment
		(start 213.893146 -18.567146)
		(end 213.893146 -19.024854)
		(width 0.14224)
		(layer "In11.Cu")
		(net "M_C_DQ<10>")
	)
	(segment
		(start 222.584772 -45.149008)
		(end 222.584772 -45.367956)
		(width 0.14224)
		(layer "In11.Cu")
		(net "M_C_DQ<10>")
	)
	(segment
		(start 231.543606 -53.932582)
		(end 231.758744 -53.932582)
		(width 0.14224)
		(layer "In11.Cu")
		(net "M_C_DQ<10>")
	)
	(segment
		(start 224.65792 -47.464472)
		(end 224.877376 -47.683928)
		(width 0.14224)
		(layer "In11.Cu")
		(net "M_C_DQ<10>")
	)
	(segment
		(start 213.506812 -0.108204)
		(end 213.506812 -0.456946)
		(width 0.14224)
		(layer "In11.Cu")
		(net "M_C_DQ<10>")
	)
	(segment
		(start 216.32672 -37.70122)
		(end 216.473786 -37.554154)
		(width 0.14224)
		(layer "In11.Cu")
		(net "M_C_DQ<10>")
	)
	(segment
		(start 227.288344 -50.094896)
		(end 227.5078 -50.314352)
		(width 0.14224)
		(layer "In11.Cu")
		(net "M_C_DQ<10>")
	)
	(segment
		(start 226.369626 -48.164242)
		(end 226.588574 -48.164242)
		(width 0.14224)
		(layer "In11.Cu")
		(net "M_C_DQ<10>")
	)
	(segment
		(start 213.399878 -4.357878)
		(end 213.399878 -4.891278)
		(width 0.14224)
		(layer "In11.Cu")
		(net "M_C_DQ<10>")
	)
	(segment
		(start 226.630992 -49.437544)
		(end 226.84994 -49.437544)
		(width 0.14224)
		(layer "In11.Cu")
		(net "M_C_DQ<10>")
	)
	(segment
		(start 222.750126 -44.325794)
		(end 222.969582 -44.54525)
		(width 0.14224)
		(layer "In11.Cu")
		(net "M_C_DQ<10>")
	)
	(segment
		(start 223.626934 -45.202602)
		(end 223.84639 -45.422058)
		(width 0.14224)
		(layer "In11.Cu")
		(net "M_C_DQ<10>")
	)
	(segment
		(start 216.786714 -38.362382)
		(end 222.092774 -43.668442)
		(width 0.14224)
		(layer "In11.Cu")
		(net "M_C_DQ<10>")
	)
	(segment
		(start 228.603556 -51.19116)
		(end 229.00005 -50.794666)
		(width 0.14224)
		(layer "In11.Cu")
		(net "M_C_DQ<10>")
	)
	(segment
		(start 224.65792 -47.245524)
		(end 224.65792 -47.464472)
		(width 0.14224)
		(layer "In11.Cu")
		(net "M_C_DQ<10>")
	)
	(segment
		(start 213.7664 -19.1516)
		(end 213.7664 -21.209254)
		(width 0.14224)
		(layer "In11.Cu")
		(net "M_C_DQ<10>")
	)
	(segment
		(start 221.707964 -44.2722)
		(end 221.707964 -44.491148)
		(width 0.14224)
		(layer "In11.Cu")
		(net "M_C_DQ<10>")
	)
	(segment
		(start 216.674954 -37.554154)
		(end 216.93378 -37.81298)
		(width 0.14224)
		(layer "In11.Cu")
		(net "M_C_DQ<10>")
	)
	(segment
		(start 223.899984 -46.46422)
		(end 224.284794 -46.07941)
		(width 0.14224)
		(layer "In11.Cu")
		(net "M_C_DQ<10>")
	)
	(segment
		(start 222.804228 -45.587412)
		(end 223.023176 -45.587412)
		(width 0.14224)
		(layer "In11.Cu")
		(net "M_C_DQ<10>")
	)
	(segment
		(start 228.123242 -49.917858)
		(end 228.34219 -49.917858)
		(width 0.14224)
		(layer "In11.Cu")
		(net "M_C_DQ<10>")
	)
	(segment
		(start 213.506812 -0.456946)
		(end 213.811612 -0.761746)
		(width 0.14224)
		(layer "In11.Cu")
		(net "M_C_DQ<10>")
	)
	(segment
		(start 222.584772 -45.367956)
		(end 222.804228 -45.587412)
		(width 0.14224)
		(layer "In11.Cu")
		(net "M_C_DQ<10>")
	)
	(segment
		(start 239.409732 -58.391552)
		(end 239.904778 -59.057286)
		(width 0.0889)
		(layer "In11.Cu")
		(net "M_C_DQ<10>")
	)
	(segment
		(start 222.146368 -44.710604)
		(end 222.531178 -44.325794)
		(width 0.14224)
		(layer "In11.Cu")
		(net "M_C_DQ<10>")
	)
	(segment
		(start 213.811612 -1.04775)
		(end 213.506812 -1.35255)
		(width 0.14224)
		(layer "In11.Cu")
		(net "M_C_DQ<10>")
	)
	(segment
		(start 226.80803 -48.383698)
		(end 226.80803 -48.602646)
		(width 0.14224)
		(layer "In11.Cu")
		(net "M_C_DQ<10>")
	)
	(segment
		(start 225.534728 -48.122332)
		(end 225.534728 -48.34128)
		(width 0.14224)
		(layer "In11.Cu")
		(net "M_C_DQ<10>")
	)
	(segment
		(start 213.115144 -3.3274)
		(end 213.115144 -4.073144)
		(width 0.14224)
		(layer "In11.Cu")
		(net "M_C_DQ<10>")
	)
	(segment
		(start 215.553798 -36.634166)
		(end 215.754966 -36.634166)
		(width 0.14224)
		(layer "In11.Cu")
		(net "M_C_DQ<10>")
	)
	(segment
		(start 222.969582 -44.54525)
		(end 222.969582 -44.764198)
		(width 0.14224)
		(layer "In11.Cu")
		(net "M_C_DQ<10>")
	)
	(segment
		(start 234.139486 -55.685436)
		(end 234.764834 -55.685436)
		(width 0.0889)
		(layer "In11.Cu")
		(net "M_C_DQ<10>")
	)
	(segment
		(start 226.411536 -48.99914)
		(end 226.411536 -49.218088)
		(width 0.14224)
		(layer "In11.Cu")
		(net "M_C_DQ<10>")
	)
	(segment
		(start 225.973132 -48.560736)
		(end 226.369626 -48.164242)
		(width 0.14224)
		(layer "In11.Cu")
		(net "M_C_DQ<10>")
	)
	(segment
		(start 213.893146 -11.7602)
		(end 213.893146 -12.195556)
		(width 0.14224)
		(layer "In11.Cu")
		(net "M_C_DQ<10>")
	)
	(segment
		(start 225.931222 -47.725838)
		(end 225.534728 -48.122332)
		(width 0.14224)
		(layer "In11.Cu")
		(net "M_C_DQ<10>")
	)
	(segment
		(start 221.92742 -44.710604)
		(end 222.146368 -44.710604)
		(width 0.14224)
		(layer "In11.Cu")
		(net "M_C_DQ<10>")
	)
	(segment
		(start 213.740746 -13.541756)
		(end 213.982046 -13.783056)
		(width 0.14224)
		(layer "In11.Cu")
		(net "M_C_DQ<10>")
	)
	(segment
		(start 213.766146 -8.864346)
		(end 213.893146 -8.991346)
		(width 0.14224)
		(layer "In11.Cu")
		(net "M_C_DQ<10>")
	)
	(segment
		(start 213.861396 -29.127196)
		(end 214.5538 -29.8196)
		(width 0.14224)
		(layer "In11.Cu")
		(net "M_C_DQ<10>")
	)
	(segment
		(start 223.46158 -46.025816)
		(end 223.46158 -46.244764)
		(width 0.14224)
		(layer "In11.Cu")
		(net "M_C_DQ<10>")
	)
	(segment
		(start 226.588574 -48.164242)
		(end 226.80803 -48.383698)
		(width 0.14224)
		(layer "In11.Cu")
		(net "M_C_DQ<10>")
	)
	(segment
		(start 215.406732 -36.781232)
		(end 215.553798 -36.634166)
		(width 0.14224)
		(layer "In11.Cu")
		(net "M_C_DQ<10>")
	)
	(segment
		(start 213.740746 -12.347956)
		(end 213.740746 -13.541756)
		(width 0.14224)
		(layer "In11.Cu")
		(net "M_C_DQ<10>")
	)
	(segment
		(start 214.5538 -36.129468)
		(end 215.205564 -36.781232)
		(width 0.14224)
		(layer "In11.Cu")
		(net "M_C_DQ<10>")
	)
	(segment
		(start 225.054414 -46.630082)
		(end 225.054414 -46.84903)
		(width 0.14224)
		(layer "In11.Cu")
		(net "M_C_DQ<10>")
	)
	(segment
		(start 214.5538 -29.8196)
		(end 214.5538 -36.129468)
		(width 0.14224)
		(layer "In11.Cu")
		(net "M_C_DQ<10>")
	)
	(segment
		(start 231.758744 -53.932582)
		(end 231.967532 -53.723794)
		(width 0.0889)
		(layer "In11.Cu")
		(net "M_C_DQ<10>")
	)
	(segment
		(start 213.893146 -21.336)
		(end 213.893146 -21.796756)
		(width 0.14224)
		(layer "In11.Cu")
		(net "M_C_DQ<10>")
	)
	(segment
		(start 226.411536 -49.218088)
		(end 226.630992 -49.437544)
		(width 0.14224)
		(layer "In11.Cu")
		(net "M_C_DQ<10>")
	)
	(segment
		(start 215.205564 -36.781232)
		(end 215.406732 -36.781232)
		(width 0.14224)
		(layer "In11.Cu")
		(net "M_C_DQ<10>")
	)
	(segment
		(start 227.726748 -50.314352)
		(end 228.123242 -49.917858)
		(width 0.14224)
		(layer "In11.Cu")
		(net "M_C_DQ<10>")
	)
	(segment
		(start 213.851744 0.236728)
		(end 213.506812 -0.108204)
		(width 0.14224)
		(layer "In11.Cu")
		(net "M_C_DQ<10>")
	)
	(segment
		(start 215.866726 -37.442394)
		(end 216.125552 -37.70122)
		(width 0.14224)
		(layer "In11.Cu")
		(net "M_C_DQ<10>")
	)
	(segment
		(start 213.811612 -0.761746)
		(end 213.811612 -1.04775)
		(width 0.14224)
		(layer "In11.Cu")
		(net "M_C_DQ<10>")
	)
	(segment
		(start 213.964012 -2.2098)
		(end 213.964012 -2.478532)
		(width 0.14224)
		(layer "In11.Cu")
		(net "M_C_DQ<10>")
	)
	(segment
		(start 213.740746 -21.949156)
		(end 213.740746 -23.142956)
		(width 0.14224)
		(layer "In11.Cu")
		(net "M_C_DQ<10>")
	)
	(segment
		(start 213.893146 -9.372854)
		(end 213.741 -9.525)
		(width 0.14224)
		(layer "In11.Cu")
		(net "M_C_DQ<10>")
	)
	(segment
		(start 222.969582 -44.764198)
		(end 222.584772 -45.149008)
		(width 0.14224)
		(layer "In11.Cu")
		(net "M_C_DQ<10>")
	)
	(segment
		(start 213.506812 -1.35255)
		(end 213.506812 -1.7526)
		(width 0.14224)
		(layer "In11.Cu")
		(net "M_C_DQ<10>")
	)
	(segment
		(start 213.7664 -21.209254)
		(end 213.893146 -21.336)
		(width 0.14224)
		(layer "In11.Cu")
		(net "M_C_DQ<10>")
	)
	(segment
		(start 239.024668 -58.16219)
		(end 239.064292 -58.16219)
		(width 0.0889)
		(layer "In11.Cu")
		(net "M_C_DQ<10>")
	)
	(segment
		(start 227.465382 -49.04105)
		(end 227.684838 -49.260506)
		(width 0.14224)
		(layer "In11.Cu")
		(net "M_C_DQ<10>")
	)
	(segment
		(start 222.092774 -43.88739)
		(end 221.707964 -44.2722)
		(width 0.14224)
		(layer "In11.Cu")
		(net "M_C_DQ<10>")
	)
	(segment
		(start 216.125552 -37.70122)
		(end 216.32672 -37.70122)
		(width 0.14224)
		(layer "In11.Cu")
		(net "M_C_DQ<10>")
	)
	(segment
		(start 223.407986 -45.202602)
		(end 223.626934 -45.202602)
		(width 0.14224)
		(layer "In11.Cu")
		(net "M_C_DQ<10>")
	)
	(segment
		(start 228.165152 -50.971704)
		(end 228.384608 -51.19116)
		(width 0.14224)
		(layer "In11.Cu")
		(net "M_C_DQ<10>")
	)
	(segment
		(start 213.893146 -12.195556)
		(end 213.740746 -12.347956)
		(width 0.14224)
		(layer "In11.Cu")
		(net "M_C_DQ<10>")
	)
	(segment
		(start 227.684838 -49.260506)
		(end 227.684838 -49.479454)
		(width 0.14224)
		(layer "In11.Cu")
		(net "M_C_DQ<10>")
	)
	(segment
		(start 227.288344 -49.875948)
		(end 227.288344 -50.094896)
		(width 0.14224)
		(layer "In11.Cu")
		(net "M_C_DQ<10>")
	)
	(segment
		(start 213.893146 -19.024854)
		(end 213.7664 -19.1516)
		(width 0.14224)
		(layer "In11.Cu")
		(net "M_C_DQ<10>")
	)
	(segment
		(start 227.5078 -50.314352)
		(end 227.726748 -50.314352)
		(width 0.14224)
		(layer "In11.Cu")
		(net "M_C_DQ<10>")
	)
	(segment
		(start 215.866726 -37.241226)
		(end 215.866726 -37.442394)
		(width 0.14224)
		(layer "In11.Cu")
		(net "M_C_DQ<10>")
	)
	(segment
		(start 215.754966 -36.634166)
		(end 216.013792 -36.892992)
		(width 0.14224)
		(layer "In11.Cu")
		(net "M_C_DQ<10>")
	)
	(segment
		(start 213.766146 -18.440146)
		(end 213.893146 -18.567146)
		(width 0.14224)
		(layer "In11.Cu")
		(net "M_C_DQ<10>")
	)
	(segment
		(start 223.023176 -45.587412)
		(end 223.407986 -45.202602)
		(width 0.14224)
		(layer "In11.Cu")
		(net "M_C_DQ<10>")
	)
	(segment
		(start 224.284794 -46.07941)
		(end 224.503742 -46.07941)
		(width 0.14224)
		(layer "In11.Cu")
		(net "M_C_DQ<10>")
	)
	(segment
		(start 213.982046 -16.751046)
		(end 213.766146 -16.966946)
		(width 0.14224)
		(layer "In11.Cu")
		(net "M_C_DQ<10>")
	)
	(segment
		(start 225.054414 -46.84903)
		(end 224.65792 -47.245524)
		(width 0.14224)
		(layer "In11.Cu")
		(net "M_C_DQ<10>")
	)
	(segment
		(start 229.00005 -50.794666)
		(end 229.218998 -50.794666)
		(width 0.14224)
		(layer "In11.Cu")
		(net "M_C_DQ<10>")
	)
	(segment
		(start 213.506812 -1.7526)
		(end 213.964012 -2.2098)
		(width 0.14224)
		(layer "In11.Cu")
		(net "M_C_DQ<10>")
	)
	(segment
		(start 228.34219 -49.917858)
		(end 228.561646 -50.137314)
		(width 0.14224)
		(layer "In11.Cu")
		(net "M_C_DQ<10>")
	)
	(segment
		(start 216.93378 -38.014148)
		(end 216.786714 -38.161214)
		(width 0.14224)
		(layer "In11.Cu")
		(net "M_C_DQ<10>")
	)
	(segment
		(start 227.684838 -49.479454)
		(end 227.288344 -49.875948)
		(width 0.14224)
		(layer "In11.Cu")
		(net "M_C_DQ<10>")
	)
	(segment
		(start 228.384608 -51.19116)
		(end 228.603556 -51.19116)
		(width 0.14224)
		(layer "In11.Cu")
		(net "M_C_DQ<10>")
	)
	(segment
		(start 229.218998 -50.794666)
		(end 229.683818 -51.259486)
		(width 0.14224)
		(layer "In11.Cu")
		(net "M_C_DQ<10>")
	)
	(segment
		(start 216.013792 -36.892992)
		(end 216.013792 -37.09416)
		(width 0.14224)
		(layer "In11.Cu")
		(net "M_C_DQ<10>")
	)
	(segment
		(start 213.969346 -7.162546)
		(end 213.766146 -7.365746)
		(width 0.14224)
		(layer "In11.Cu")
		(net "M_C_DQ<10>")
	)
	(segment
		(start 225.711766 -47.287434)
		(end 225.931222 -47.50689)
		(width 0.14224)
		(layer "In11.Cu")
		(net "M_C_DQ<10>")
	)
	(segment
		(start 238.174784 -57.66689)
		(end 238.198914 -57.66689)
		(width 0.0889)
		(layer "In11.Cu")
		(net "M_C_DQ<10>")
	)
	(segment
		(start 213.969346 -5.460746)
		(end 213.969346 -7.162546)
		(width 0.14224)
		(layer "In11.Cu")
		(net "M_C_DQ<10>")
	)
	(segment
		(start 225.096324 -47.683928)
		(end 225.492818 -47.287434)
		(width 0.14224)
		(layer "In11.Cu")
		(net "M_C_DQ<10>")
	)
	(segment
		(start 224.877376 -47.683928)
		(end 225.096324 -47.683928)
		(width 0.14224)
		(layer "In11.Cu")
		(net "M_C_DQ<10>")
	)
	(segment
		(start 213.115144 -4.073144)
		(end 213.399878 -4.357878)
		(width 0.14224)
		(layer "In11.Cu")
		(net "M_C_DQ<10>")
	)
	(segment
		(start 228.165152 -50.752756)
		(end 228.165152 -50.971704)
		(width 0.14224)
		(layer "In11.Cu")
		(net "M_C_DQ<10>")
	)
	(segment
		(start 223.84639 -45.422058)
		(end 223.84639 -45.641006)
		(width 0.14224)
		(layer "In11.Cu")
		(net "M_C_DQ<10>")
	)
	(segment
		(start 225.492818 -47.287434)
		(end 225.711766 -47.287434)
		(width 0.14224)
		(layer "In11.Cu")
		(net "M_C_DQ<10>")
	)
	(segment
		(start 214.249762 0.9398)
		(end 213.851744 0.541782)
		(width 0.14224)
		(layer "In11.Cu")
		(net "M_C_DQ<10>")
	)
	(segment
		(start 222.531178 -44.325794)
		(end 222.750126 -44.325794)
		(width 0.14224)
		(layer "In11.Cu")
		(net "M_C_DQ<10>")
	)
	(segment
		(start 223.46158 -46.244764)
		(end 223.681036 -46.46422)
		(width 0.14224)
		(layer "In11.Cu")
		(net "M_C_DQ<10>")
	)
	(segment
		(start 221.707964 -44.491148)
		(end 221.92742 -44.710604)
		(width 0.14224)
		(layer "In11.Cu")
		(net "M_C_DQ<10>")
	)
	(segment
		(start 231.967532 -53.723794)
		(end 232.177844 -53.723794)
		(width 0.0889)
		(layer "In11.Cu")
		(net "M_C_DQ<10>")
	)
	(segment
		(start 213.964012 -2.478532)
		(end 213.115144 -3.3274)
		(width 0.14224)
		(layer "In11.Cu")
		(net "M_C_DQ<10>")
	)
	(segment
		(start 228.561646 -50.356262)
		(end 228.165152 -50.752756)
		(width 0.14224)
		(layer "In11.Cu")
		(net "M_C_DQ<10>")
	)
	(segment
		(start 213.766146 -16.966946)
		(end 213.766146 -18.440146)
		(width 0.14224)
		(layer "In11.Cu")
		(net "M_C_DQ<10>")
	)
	(arc
		(start 234.764834 -55.685436)
		(mid 234.958684 -55.741786)
		(end 235.100368 -55.885588)
		(width 0.0889)
		(layer "In11.Cu")
		(net "M_C_DQ<10>")
	)
	(arc
		(start 237.675928 -57.371488)
		(mid 237.886641 -57.584567)
		(end 238.174784 -57.66689)
		(width 0.0889)
		(layer "In11.Cu")
		(net "M_C_DQ<10>")
	)
	(arc
		(start 236.481874 -56.676036)
		(mid 236.675724 -56.732386)
		(end 236.817408 -56.876188)
		(width 0.0889)
		(layer "In11.Cu")
		(net "M_C_DQ<10>")
	)
	(arc
		(start 235.958888 -56.380888)
		(mid 236.165892 -56.591752)
		(end 236.449108 -56.676036)
		(width 0.0889)
		(layer "In11.Cu")
		(net "M_C_DQ<10>")
	)
	(arc
		(start 238.198914 -57.66689)
		(mid 238.392764 -57.72324)
		(end 238.534448 -57.867042)
		(width 0.0889)
		(layer "In11.Cu")
		(net "M_C_DQ<10>")
	)
	(arc
		(start 235.627164 -56.18099)
		(mid 235.818806 -56.238156)
		(end 235.958888 -56.380888)
		(width 0.0889)
		(layer "In11.Cu")
		(net "M_C_DQ<10>")
	)
	(arc
		(start 237.344204 -57.17159)
		(mid 237.535846 -57.228756)
		(end 237.675928 -57.371488)
		(width 0.0889)
		(layer "In11.Cu")
		(net "M_C_DQ<10>")
	)
	(arc
		(start 236.817408 -56.876188)
		(mid 237.026016 -57.08812)
		(end 237.311438 -57.17159)
		(width 0.0889)
		(layer "In11.Cu")
		(net "M_C_DQ<10>")
	)
	(arc
		(start 238.534448 -57.867042)
		(mid 238.741452 -58.077906)
		(end 239.024668 -58.16219)
		(width 0.0889)
		(layer "In11.Cu")
		(net "M_C_DQ<10>")
	)
	(arc
		(start 235.100368 -55.885588)
		(mid 235.308976 -56.09752)
		(end 235.594398 -56.18099)
		(width 0.0889)
		(layer "In11.Cu")
		(net "M_C_DQ<10>")
	)
	(arc
		(start 239.064292 -58.16219)
		(mid 239.254221 -58.22006)
		(end 239.392968 -58.362088)
		(width 0.0889)
		(layer "In11.Cu")
		(net "M_C_DQ<10>")
	)
	(segment
		(start 241.334798 -66.48704)
		(end 240.763298 -66.48704)
		(width 0.0889)
		(layer "F.Cu")
		(net "M_C_DQ<0>")
	)
	(segment
		(start 198.949818 -0.821182)
		(end 198.772018 1.0414)
		(width 0.1651)
		(layer "F.Cu")
		(net "M_C_DQ<0>")
	)
	(segment
		(start 198.950326 -0.821182)
		(end 198.949818 -0.821182)
		(width 0.1651)
		(layer "F.Cu")
		(net "M_C_DQ<0>")
	)
	(via
		(at 198.772018 1.0414)
		(size 0.508)
		(drill 0.254)
		(layers "F.Cu" "B.Cu")
		(net "M_C_DQ<0>")
	)
	(via
		(at 240.763298 -66.48704)
		(size 0.508)
		(drill 0.254)
		(layers "F.Cu" "B.Cu")
		(net "M_C_DQ<0>")
	)
	(via
		(at 198.099934 -4.357878)
		(size 0.508)
		(drill 0.254)
		(layers "F.Cu" "B.Cu")
		(net "M_C_DQ<0>")
	)
	(segment
		(start 198.100442 -5.621782)
		(end 198.099934 -5.621782)
		(width 0.1651)
		(layer "B.Cu")
		(net "M_C_DQ<0>")
	)
	(segment
		(start 198.099934 -5.621782)
		(end 198.099934 -4.357878)
		(width 0.1651)
		(layer "B.Cu")
		(net "M_C_DQ<0>")
	)
	(segment
		(start 236.449108 -66.582036)
		(end 236.481874 -66.582036)
		(width 0.0889)
		(layer "In11.Cu")
		(net "M_C_DQ<0>")
	)
	(segment
		(start 198.479918 -0.8509)
		(end 198.137018 -0.508)
		(width 0.14224)
		(layer "In11.Cu")
		(net "M_C_DQ<0>")
	)
	(segment
		(start 198.099934 -4.357878)
		(end 197.8152 -4.073144)
		(width 0.14224)
		(layer "In11.Cu")
		(net "M_C_DQ<0>")
	)
	(segment
		(start 198.624952 -21.3614)
		(end 198.624952 -21.682456)
		(width 0.14224)
		(layer "In11.Cu")
		(net "M_C_DQ<0>")
	)
	(segment
		(start 201.803 -41.783)
		(end 201.803 -42.28973)
		(width 0.14224)
		(layer "In11.Cu")
		(net "M_C_DQ<0>")
	)
	(segment
		(start 237.311438 -67.07759)
		(end 237.344204 -67.07759)
		(width 0.0889)
		(layer "In11.Cu")
		(net "M_C_DQ<0>")
	)
	(segment
		(start 198.282052 -23.098252)
		(end 198.5772 -23.3934)
		(width 0.14224)
		(layer "In11.Cu")
		(net "M_C_DQ<0>")
	)
	(segment
		(start 198.624952 -9.375648)
		(end 198.4756 -9.525)
		(width 0.14224)
		(layer "In11.Cu")
		(net "M_C_DQ<0>")
	)
	(segment
		(start 197.989952 -5.966206)
		(end 198.574152 -6.550406)
		(width 0.14224)
		(layer "In11.Cu")
		(net "M_C_DQ<0>")
	)
	(segment
		(start 198.137018 -0.508)
		(end 198.137018 -0.178054)
		(width 0.14224)
		(layer "In11.Cu")
		(net "M_C_DQ<0>")
	)
	(segment
		(start 198.282052 -12.424156)
		(end 198.282052 -13.497052)
		(width 0.14224)
		(layer "In11.Cu")
		(net "M_C_DQ<0>")
	)
	(segment
		(start 199.477122 -40.386)
		(end 200.177654 -40.386)
		(width 0.14224)
		(layer "In11.Cu")
		(net "M_C_DQ<0>")
	)
	(segment
		(start 233.877358 -66.08699)
		(end 233.912918 -66.08699)
		(width 0.0889)
		(layer "In11.Cu")
		(net "M_C_DQ<0>")
	)
	(segment
		(start 201.6252 -41.6052)
		(end 201.803 -41.783)
		(width 0.14224)
		(layer "In11.Cu")
		(net "M_C_DQ<0>")
	)
	(segment
		(start 231.692704 -66.08699)
		(end 232.195878 -66.08699)
		(width 0.0889)
		(layer "In11.Cu")
		(net "M_C_DQ<0>")
	)
	(segment
		(start 198.624952 -13.839952)
		(end 198.624952 -16.779494)
		(width 0.14224)
		(layer "In11.Cu")
		(net "M_C_DQ<0>")
	)
	(segment
		(start 198.624952 -16.779494)
		(end 198.282052 -17.122394)
		(width 0.14224)
		(layer "In11.Cu")
		(net "M_C_DQ<0>")
	)
	(segment
		(start 199.2122 -39.615618)
		(end 199.2122 -40.121078)
		(width 0.14224)
		(layer "In11.Cu")
		(net "M_C_DQ<0>")
	)
	(segment
		(start 238.166148 -67.572636)
		(end 238.198914 -67.572636)
		(width 0.0889)
		(layer "In11.Cu")
		(net "M_C_DQ<0>")
	)
	(segment
		(start 198.624952 -11.7348)
		(end 198.624952 -12.081256)
		(width 0.14224)
		(layer "In11.Cu")
		(net "M_C_DQ<0>")
	)
	(segment
		(start 198.4756 -11.585448)
		(end 198.624952 -11.7348)
		(width 0.14224)
		(layer "In11.Cu")
		(net "M_C_DQ<0>")
	)
	(segment
		(start 199.2122 -40.121078)
		(end 199.477122 -40.386)
		(width 0.14224)
		(layer "In11.Cu")
		(net "M_C_DQ<0>")
	)
	(segment
		(start 198.5518 0.821182)
		(end 198.772018 1.0414)
		(width 0.14224)
		(layer "In11.Cu")
		(net "M_C_DQ<0>")
	)
	(segment
		(start 203.116688 -42.605706)
		(end 203.116688 -44.025566)
		(width 0.14224)
		(layer "In11.Cu")
		(net "M_C_DQ<0>")
	)
	(segment
		(start 200.406 -41.314878)
		(end 200.696322 -41.6052)
		(width 0.14224)
		(layer "In11.Cu")
		(net "M_C_DQ<0>")
	)
	(segment
		(start 197.8152 -3.3274)
		(end 198.5518 -2.5908)
		(width 0.14224)
		(layer "In11.Cu")
		(net "M_C_DQ<0>")
	)
	(segment
		(start 200.177654 -40.386)
		(end 200.406 -40.614346)
		(width 0.14224)
		(layer "In11.Cu")
		(net "M_C_DQ<0>")
	)
	(segment
		(start 198.282052 -8.696706)
		(end 198.624952 -9.039606)
		(width 0.14224)
		(layer "In11.Cu")
		(net "M_C_DQ<0>")
	)
	(segment
		(start 235.594398 -66.08699)
		(end 235.627164 -66.08699)
		(width 0.0889)
		(layer "In11.Cu")
		(net "M_C_DQ<0>")
	)
	(segment
		(start 198.099934 -4.693666)
		(end 197.989952 -4.803648)
		(width 0.14224)
		(layer "In11.Cu")
		(net "M_C_DQ<0>")
	)
	(segment
		(start 198.4756 -9.525)
		(end 198.4756 -11.585448)
		(width 0.14224)
		(layer "In11.Cu")
		(net "M_C_DQ<0>")
	)
	(segment
		(start 198.099934 -4.357878)
		(end 198.099934 -4.693666)
		(width 0.14224)
		(layer "In11.Cu")
		(net "M_C_DQ<0>")
	)
	(segment
		(start 198.574152 -7.229094)
		(end 198.282052 -7.521194)
		(width 0.14224)
		(layer "In11.Cu")
		(net "M_C_DQ<0>")
	)
	(segment
		(start 198.5772 -23.771352)
		(end 198.1454 -24.203152)
		(width 0.14224)
		(layer "In11.Cu")
		(net "M_C_DQ<0>")
	)
	(segment
		(start 202.989434 -42.478452)
		(end 203.116688 -42.605706)
		(width 0.14224)
		(layer "In11.Cu")
		(net "M_C_DQ<0>")
	)
	(segment
		(start 200.696322 -41.6052)
		(end 201.6252 -41.6052)
		(width 0.14224)
		(layer "In11.Cu")
		(net "M_C_DQ<0>")
	)
	(segment
		(start 198.282052 -17.122394)
		(end 198.282052 -18.297906)
		(width 0.14224)
		(layer "In11.Cu")
		(net "M_C_DQ<0>")
	)
	(segment
		(start 198.4248 -19.2024)
		(end 198.4248 -21.161248)
		(width 0.14224)
		(layer "In11.Cu")
		(net "M_C_DQ<0>")
	)
	(segment
		(start 198.624952 -12.081256)
		(end 198.282052 -12.424156)
		(width 0.14224)
		(layer "In11.Cu")
		(net "M_C_DQ<0>")
	)
	(segment
		(start 197.8152 -4.073144)
		(end 197.8152 -3.3274)
		(width 0.14224)
		(layer "In11.Cu")
		(net "M_C_DQ<0>")
	)
	(segment
		(start 198.574152 -6.550406)
		(end 198.574152 -7.229094)
		(width 0.14224)
		(layer "In11.Cu")
		(net "M_C_DQ<0>")
	)
	(segment
		(start 198.5518 0.236728)
		(end 198.5518 0.821182)
		(width 0.14224)
		(layer "In11.Cu")
		(net "M_C_DQ<0>")
	)
	(segment
		(start 203.116688 -44.025566)
		(end 225.545142 -66.45402)
		(width 0.14224)
		(layer "In11.Cu")
		(net "M_C_DQ<0>")
	)
	(segment
		(start 198.624952 -9.039606)
		(end 198.624952 -9.375648)
		(width 0.14224)
		(layer "In11.Cu")
		(net "M_C_DQ<0>")
	)
	(segment
		(start 198.410322 -39.3192)
		(end 198.915782 -39.3192)
		(width 0.14224)
		(layer "In11.Cu")
		(net "M_C_DQ<0>")
	)
	(segment
		(start 197.989952 -4.803648)
		(end 197.989952 -5.966206)
		(width 0.14224)
		(layer "In11.Cu")
		(net "M_C_DQ<0>")
	)
	(segment
		(start 198.282052 -13.497052)
		(end 198.624952 -13.839952)
		(width 0.14224)
		(layer "In11.Cu")
		(net "M_C_DQ<0>")
	)
	(segment
		(start 198.282052 -7.521194)
		(end 198.282052 -8.696706)
		(width 0.14224)
		(layer "In11.Cu")
		(net "M_C_DQ<0>")
	)
	(segment
		(start 198.162418 -1.701546)
		(end 198.162418 -1.397)
		(width 0.14224)
		(layer "In11.Cu")
		(net "M_C_DQ<0>")
	)
	(segment
		(start 240.416588 -67.277488)
		(end 240.479834 -67.16903)
		(width 0.0889)
		(layer "In11.Cu")
		(net "M_C_DQ<0>")
	)
	(segment
		(start 198.915782 -39.3192)
		(end 199.2122 -39.615618)
		(width 0.14224)
		(layer "In11.Cu")
		(net "M_C_DQ<0>")
	)
	(segment
		(start 198.624952 -19.002248)
		(end 198.4248 -19.2024)
		(width 0.14224)
		(layer "In11.Cu")
		(net "M_C_DQ<0>")
	)
	(segment
		(start 198.282052 -18.297906)
		(end 198.624952 -18.640806)
		(width 0.14224)
		(layer "In11.Cu")
		(net "M_C_DQ<0>")
	)
	(segment
		(start 231.325674 -66.45402)
		(end 231.692704 -66.08699)
		(width 0.0889)
		(layer "In11.Cu")
		(net "M_C_DQ<0>")
	)
	(segment
		(start 198.1454 -24.203152)
		(end 198.1454 -39.054278)
		(width 0.14224)
		(layer "In11.Cu")
		(net "M_C_DQ<0>")
	)
	(segment
		(start 201.991722 -42.478452)
		(end 202.989434 -42.478452)
		(width 0.14224)
		(layer "In11.Cu")
		(net "M_C_DQ<0>")
	)
	(segment
		(start 198.162418 -1.397)
		(end 198.479918 -1.0795)
		(width 0.14224)
		(layer "In11.Cu")
		(net "M_C_DQ<0>")
	)
	(segment
		(start 198.282052 -22.025356)
		(end 198.282052 -23.098252)
		(width 0.14224)
		(layer "In11.Cu")
		(net "M_C_DQ<0>")
	)
	(segment
		(start 198.5518 -2.5908)
		(end 198.5518 -2.090928)
		(width 0.14224)
		(layer "In11.Cu")
		(net "M_C_DQ<0>")
	)
	(segment
		(start 239.893602 -67.572636)
		(end 239.926368 -67.572636)
		(width 0.0889)
		(layer "In11.Cu")
		(net "M_C_DQ<0>")
	)
	(segment
		(start 198.137018 -0.178054)
		(end 198.5518 0.236728)
		(width 0.14224)
		(layer "In11.Cu")
		(net "M_C_DQ<0>")
	)
	(segment
		(start 231.134158 -66.45402)
		(end 231.325674 -66.45402)
		(width 0.0889)
		(layer "In11.Cu")
		(net "M_C_DQ<0>")
	)
	(segment
		(start 198.624952 -21.682456)
		(end 198.282052 -22.025356)
		(width 0.14224)
		(layer "In11.Cu")
		(net "M_C_DQ<0>")
	)
	(segment
		(start 201.803 -42.28973)
		(end 201.991722 -42.478452)
		(width 0.14224)
		(layer "In11.Cu")
		(net "M_C_DQ<0>")
	)
	(segment
		(start 198.4248 -21.161248)
		(end 198.624952 -21.3614)
		(width 0.14224)
		(layer "In11.Cu")
		(net "M_C_DQ<0>")
	)
	(segment
		(start 198.1454 -39.054278)
		(end 198.410322 -39.3192)
		(width 0.14224)
		(layer "In11.Cu")
		(net "M_C_DQ<0>")
	)
	(segment
		(start 198.5518 -2.090928)
		(end 198.162418 -1.701546)
		(width 0.14224)
		(layer "In11.Cu")
		(net "M_C_DQ<0>")
	)
	(segment
		(start 198.5772 -23.3934)
		(end 198.5772 -23.771352)
		(width 0.14224)
		(layer "In11.Cu")
		(net "M_C_DQ<0>")
	)
	(segment
		(start 239.028478 -68.06819)
		(end 239.064038 -68.06819)
		(width 0.0889)
		(layer "In11.Cu")
		(net "M_C_DQ<0>")
	)
	(segment
		(start 240.768886 -66.501518)
		(end 240.763298 -66.48704)
		(width 0.0889)
		(layer "In11.Cu")
		(net "M_C_DQ<0>")
	)
	(segment
		(start 198.624952 -18.640806)
		(end 198.624952 -19.002248)
		(width 0.14224)
		(layer "In11.Cu")
		(net "M_C_DQ<0>")
	)
	(segment
		(start 198.479918 -1.0795)
		(end 198.479918 -0.8509)
		(width 0.14224)
		(layer "In11.Cu")
		(net "M_C_DQ<0>")
	)
	(segment
		(start 225.545142 -66.45402)
		(end 231.134158 -66.45402)
		(width 0.14224)
		(layer "In11.Cu")
		(net "M_C_DQ<0>")
	)
	(segment
		(start 200.406 -40.614346)
		(end 200.406 -41.314878)
		(width 0.14224)
		(layer "In11.Cu")
		(net "M_C_DQ<0>")
	)
	(segment
		(start 240.479834 -67.16903)
		(end 240.768886 -66.501518)
		(width 0.0889)
		(layer "In11.Cu")
		(net "M_C_DQ<0>")
	)
	(arc
		(start 233.383328 -65.791588)
		(mid 233.591936 -66.00352)
		(end 233.877358 -66.08699)
		(width 0.0889)
		(layer "In11.Cu")
		(net "M_C_DQ<0>")
	)
	(arc
		(start 235.100368 -65.791588)
		(mid 235.308976 -66.00352)
		(end 235.594398 -66.08699)
		(width 0.0889)
		(layer "In11.Cu")
		(net "M_C_DQ<0>")
	)
	(arc
		(start 239.064038 -68.06819)
		(mid 239.349462 -67.984723)
		(end 239.558068 -67.772788)
		(width 0.0889)
		(layer "In11.Cu")
		(net "M_C_DQ<0>")
	)
	(arc
		(start 234.406948 -65.791588)
		(mid 234.753658 -65.591277)
		(end 235.100368 -65.791588)
		(width 0.0889)
		(layer "In11.Cu")
		(net "M_C_DQ<0>")
	)
	(arc
		(start 239.558068 -67.772788)
		(mid 239.699751 -67.628984)
		(end 239.893602 -67.572636)
		(width 0.0889)
		(layer "In11.Cu")
		(net "M_C_DQ<0>")
	)
	(arc
		(start 235.627164 -66.08699)
		(mid 235.818806 -66.144156)
		(end 235.958888 -66.286888)
		(width 0.0889)
		(layer "In11.Cu")
		(net "M_C_DQ<0>")
	)
	(arc
		(start 233.912918 -66.08699)
		(mid 234.198342 -66.003523)
		(end 234.406948 -65.791588)
		(width 0.0889)
		(layer "In11.Cu")
		(net "M_C_DQ<0>")
	)
	(arc
		(start 238.198914 -67.572636)
		(mid 238.392764 -67.628986)
		(end 238.534448 -67.772788)
		(width 0.0889)
		(layer "In11.Cu")
		(net "M_C_DQ<0>")
	)
	(arc
		(start 237.675928 -67.277488)
		(mid 237.882932 -67.488352)
		(end 238.166148 -67.572636)
		(width 0.0889)
		(layer "In11.Cu")
		(net "M_C_DQ<0>")
	)
	(arc
		(start 232.195878 -66.08699)
		(mid 232.481302 -66.003523)
		(end 232.689908 -65.791588)
		(width 0.0889)
		(layer "In11.Cu")
		(net "M_C_DQ<0>")
	)
	(arc
		(start 235.958888 -66.286888)
		(mid 236.165892 -66.497752)
		(end 236.449108 -66.582036)
		(width 0.0889)
		(layer "In11.Cu")
		(net "M_C_DQ<0>")
	)
	(arc
		(start 239.926368 -67.572636)
		(mid 240.209585 -67.488355)
		(end 240.416588 -67.277488)
		(width 0.0889)
		(layer "In11.Cu")
		(net "M_C_DQ<0>")
	)
	(arc
		(start 238.534448 -67.772788)
		(mid 238.743056 -67.98472)
		(end 239.028478 -68.06819)
		(width 0.0889)
		(layer "In11.Cu")
		(net "M_C_DQ<0>")
	)
	(arc
		(start 236.481874 -66.582036)
		(mid 236.675724 -66.638386)
		(end 236.817408 -66.782188)
		(width 0.0889)
		(layer "In11.Cu")
		(net "M_C_DQ<0>")
	)
	(arc
		(start 237.344204 -67.07759)
		(mid 237.535846 -67.134756)
		(end 237.675928 -67.277488)
		(width 0.0889)
		(layer "In11.Cu")
		(net "M_C_DQ<0>")
	)
	(arc
		(start 236.817408 -66.782188)
		(mid 237.026016 -66.99412)
		(end 237.311438 -67.07759)
		(width 0.0889)
		(layer "In11.Cu")
		(net "M_C_DQ<0>")
	)
	(arc
		(start 232.689908 -65.791588)
		(mid 233.036618 -65.591277)
		(end 233.383328 -65.791588)
		(width 0.0889)
		(layer "In11.Cu")
		(net "M_C_DQ<0>")
	)
	(segment
		(start 267.948156 -58.06694)
		(end 268.557756 -58.06694)
		(width 0.1016)
		(layer "F.Cu")
		(net "M_C_CS_N<7>")
	)
	(via
		(at 277.999952 -2.316988)
		(size 0.4572)
		(drill 0.2032)
		(layers "F.Cu" "B.Cu")
		(net "M_C_CS_N<7>")
	)
	(via
		(at 268.557756 -58.06694)
		(size 0.508)
		(drill 0.254)
		(layers "F.Cu" "B.Cu")
		(net "M_C_CS_N<7>")
	)
	(segment
		(start 278.00046 -1.021842)
		(end 277.999952 -1.021842)
		(width 0.1651)
		(layer "B.Cu")
		(net "M_C_CS_N<7>")
	)
	(segment
		(start 277.999952 -1.021842)
		(end 277.999952 -2.316988)
		(width 0.1651)
		(layer "B.Cu")
		(net "M_C_CS_N<7>")
	)
	(segment
		(start 268.1478 -56.261)
		(end 268.1478 -51.867054)
		(width 0.0889)
		(layer "In2.Cu")
		(net "M_C_CS_N<7>")
	)
	(segment
		(start 268.1478 -51.867054)
		(end 268.3256 -51.689254)
		(width 0.0889)
		(layer "In2.Cu")
		(net "M_C_CS_N<7>")
	)
	(segment
		(start 269.836392 -48.222408)
		(end 269.836392 -47.932848)
		(width 0.0889)
		(layer "In2.Cu")
		(net "M_C_CS_N<7>")
	)
	(segment
		(start 268.9606 -56.896)
		(end 268.6558 -56.5912)
		(width 0.0889)
		(layer "In2.Cu")
		(net "M_C_CS_N<7>")
	)
	(segment
		(start 278.408638 -13.181076)
		(end 278.408638 -6.797294)
		(width 0.14224)
		(layer "In2.Cu")
		(net "M_C_CS_N<7>")
	)
	(segment
		(start 268.6558 -56.5912)
		(end 268.478 -56.5912)
		(width 0.0889)
		(layer "In2.Cu")
		(net "M_C_CS_N<7>")
	)
	(segment
		(start 278.496522 -13.26896)
		(end 278.408638 -13.181076)
		(width 0.14224)
		(layer "In2.Cu")
		(net "M_C_CS_N<7>")
	)
	(segment
		(start 268.3256 -49.7332)
		(end 269.836392 -48.222408)
		(width 0.0889)
		(layer "In2.Cu")
		(net "M_C_CS_N<7>")
	)
	(segment
		(start 278.5364 -4.085336)
		(end 278.238458 -3.787394)
		(width 0.14224)
		(layer "In2.Cu")
		(net "M_C_CS_N<7>")
	)
	(segment
		(start 268.557756 -58.06694)
		(end 268.9606 -57.664096)
		(width 0.0889)
		(layer "In2.Cu")
		(net "M_C_CS_N<7>")
	)
	(segment
		(start 269.836392 -33.48736)
		(end 278.496522 -24.82723)
		(width 0.14224)
		(layer "In2.Cu")
		(net "M_C_CS_N<7>")
	)
	(segment
		(start 268.9606 -57.664096)
		(end 268.9606 -56.896)
		(width 0.0889)
		(layer "In2.Cu")
		(net "M_C_CS_N<7>")
	)
	(segment
		(start 278.408638 -6.797294)
		(end 278.5364 -6.669532)
		(width 0.14224)
		(layer "In2.Cu")
		(net "M_C_CS_N<7>")
	)
	(segment
		(start 268.3256 -51.689254)
		(end 268.3256 -49.7332)
		(width 0.0889)
		(layer "In2.Cu")
		(net "M_C_CS_N<7>")
	)
	(segment
		(start 278.238458 -2.555494)
		(end 277.999952 -2.316988)
		(width 0.14224)
		(layer "In2.Cu")
		(net "M_C_CS_N<7>")
	)
	(segment
		(start 269.836392 -47.932848)
		(end 269.836392 -33.48736)
		(width 0.14224)
		(layer "In2.Cu")
		(net "M_C_CS_N<7>")
	)
	(segment
		(start 268.478 -56.5912)
		(end 268.1478 -56.261)
		(width 0.0889)
		(layer "In2.Cu")
		(net "M_C_CS_N<7>")
	)
	(segment
		(start 278.238458 -3.787394)
		(end 278.238458 -2.555494)
		(width 0.14224)
		(layer "In2.Cu")
		(net "M_C_CS_N<7>")
	)
	(segment
		(start 278.5364 -6.669532)
		(end 278.5364 -4.085336)
		(width 0.14224)
		(layer "In2.Cu")
		(net "M_C_CS_N<7>")
	)
	(segment
		(start 278.496522 -24.82723)
		(end 278.496522 -13.26896)
		(width 0.14224)
		(layer "In2.Cu")
		(net "M_C_CS_N<7>")
	)
	(segment
		(start 267.948156 -57.076086)
		(end 268.557756 -57.076086)
		(width 0.1016)
		(layer "F.Cu")
		(net "M_C_CS_N<6>")
	)
	(via
		(at 268.557756 -57.076086)
		(size 0.508)
		(drill 0.254)
		(layers "F.Cu" "B.Cu")
		(net "M_C_CS_N<6>")
	)
	(via
		(at 277.999952 -4.332986)
		(size 0.4572)
		(drill 0.2032)
		(layers "F.Cu" "B.Cu")
		(net "M_C_CS_N<6>")
	)
	(segment
		(start 278.00046 -5.621782)
		(end 277.999952 -5.621782)
		(width 0.1651)
		(layer "B.Cu")
		(net "M_C_CS_N<6>")
	)
	(segment
		(start 277.999952 -5.621782)
		(end 277.999952 -4.332986)
		(width 0.1651)
		(layer "B.Cu")
		(net "M_C_CS_N<6>")
	)
	(segment
		(start 268.1224 -49.478946)
		(end 269.30096 -48.300386)
		(width 0.0889)
		(layer "In2.Cu")
		(net "M_C_CS_N<6>")
	)
	(segment
		(start 277.297388 -14.84249)
		(end 277.297388 -14.467078)
		(width 0.14224)
		(layer "In2.Cu")
		(net "M_C_CS_N<6>")
	)
	(segment
		(start 277.055072 -24.697436)
		(end 277.342346 -24.697436)
		(width 0.14224)
		(layer "In2.Cu")
		(net "M_C_CS_N<6>")
	)
	(segment
		(start 277.326598 -16.229584)
		(end 277.326598 -15.86484)
		(width 0.14224)
		(layer "In2.Cu")
		(net "M_C_CS_N<6>")
	)
	(segment
		(start 277.35911 -17.463008)
		(end 277.585678 -17.23644)
		(width 0.14224)
		(layer "In2.Cu")
		(net "M_C_CS_N<6>")
	)
	(segment
		(start 277.455122 -13.396468)
		(end 277.455122 -12.937744)
		(width 0.14224)
		(layer "In2.Cu")
		(net "M_C_CS_N<6>")
	)
	(segment
		(start 277.582884 -12.809982)
		(end 277.582884 -11.070844)
		(width 0.14224)
		(layer "In2.Cu")
		(net "M_C_CS_N<6>")
	)
	(segment
		(start 267.781024 -51.80203)
		(end 268.1224 -51.460654)
		(width 0.0889)
		(layer "In2.Cu")
		(net "M_C_CS_N<6>")
	)
	(segment
		(start 269.30096 -33.304226)
		(end 275.757132 -26.848054)
		(width 0.14224)
		(layer "In2.Cu")
		(net "M_C_CS_N<6>")
	)
	(segment
		(start 277.881842 -15.024354)
		(end 277.479252 -15.024354)
		(width 0.14224)
		(layer "In2.Cu")
		(net "M_C_CS_N<6>")
	)
	(segment
		(start 277.881842 -15.687294)
		(end 278.036782 -15.532354)
		(width 0.14224)
		(layer "In2.Cu")
		(net "M_C_CS_N<6>")
	)
	(segment
		(start 277.455122 -22.599396)
		(end 277.632922 -22.421596)
		(width 0.14224)
		(layer "In2.Cu")
		(net "M_C_CS_N<6>")
	)
	(segment
		(start 276.906736 -25.41143)
		(end 276.76729 -25.272238)
		(width 0.14224)
		(layer "In2.Cu")
		(net "M_C_CS_N<6>")
	)
	(segment
		(start 277.504144 -15.687294)
		(end 277.881842 -15.687294)
		(width 0.14224)
		(layer "In2.Cu")
		(net "M_C_CS_N<6>")
	)
	(segment
		(start 277.584408 -5.752592)
		(end 277.999952 -5.337048)
		(width 0.14224)
		(layer "In2.Cu")
		(net "M_C_CS_N<6>")
	)
	(segment
		(start 275.757132 -26.561034)
		(end 275.617686 -26.421842)
		(width 0.14224)
		(layer "In2.Cu")
		(net "M_C_CS_N<6>")
	)
	(segment
		(start 268.1224 -51.460654)
		(end 268.1224 -49.478946)
		(width 0.0889)
		(layer "In2.Cu")
		(net "M_C_CS_N<6>")
	)
	(segment
		(start 277.585678 -18.318226)
		(end 277.35911 -18.091658)
		(width 0.14224)
		(layer "In2.Cu")
		(net "M_C_CS_N<6>")
	)
	(segment
		(start 275.617686 -26.134822)
		(end 275.905468 -25.84704)
		(width 0.14224)
		(layer "In2.Cu")
		(net "M_C_CS_N<6>")
	)
	(segment
		(start 278.036782 -15.179294)
		(end 277.881842 -15.024354)
		(width 0.14224)
		(layer "In2.Cu")
		(net "M_C_CS_N<6>")
	)
	(segment
		(start 277.297388 -14.467078)
		(end 277.585678 -14.178788)
		(width 0.14224)
		(layer "In2.Cu")
		(net "M_C_CS_N<6>")
	)
	(segment
		(start 277.584408 -8.083296)
		(end 277.584408 -5.752592)
		(width 0.14224)
		(layer "In2.Cu")
		(net "M_C_CS_N<6>")
	)
	(segment
		(start 277.342346 -24.697436)
		(end 277.481538 -24.836628)
		(width 0.14224)
		(layer "In2.Cu")
		(net "M_C_CS_N<6>")
	)
	(segment
		(start 277.58771 -8.086598)
		(end 277.584408 -8.083296)
		(width 0.14224)
		(layer "In2.Cu")
		(net "M_C_CS_N<6>")
	)
	(segment
		(start 276.192742 -25.84704)
		(end 276.331934 -25.986232)
		(width 0.14224)
		(layer "In2.Cu")
		(net "M_C_CS_N<6>")
	)
	(segment
		(start 268.557756 -57.076086)
		(end 267.781024 -56.299354)
		(width 0.0889)
		(layer "In2.Cu")
		(net "M_C_CS_N<6>")
	)
	(segment
		(start 278.036782 -15.532354)
		(end 278.036782 -15.179294)
		(width 0.14224)
		(layer "In2.Cu")
		(net "M_C_CS_N<6>")
	)
	(segment
		(start 277.649686 -9.83869)
		(end 277.58771 -9.776714)
		(width 0.14224)
		(layer "In2.Cu")
		(net "M_C_CS_N<6>")
	)
	(segment
		(start 275.905468 -25.84704)
		(end 276.192742 -25.84704)
		(width 0.14224)
		(layer "In2.Cu")
		(net "M_C_CS_N<6>")
	)
	(segment
		(start 269.30096 -47.991522)
		(end 269.30096 -33.304226)
		(width 0.14224)
		(layer "In2.Cu")
		(net "M_C_CS_N<6>")
	)
	(segment
		(start 277.582884 -11.070844)
		(end 277.649686 -11.004042)
		(width 0.14224)
		(layer "In2.Cu")
		(net "M_C_CS_N<6>")
	)
	(segment
		(start 276.76729 -25.272238)
		(end 276.76729 -24.985218)
		(width 0.14224)
		(layer "In2.Cu")
		(net "M_C_CS_N<6>")
	)
	(segment
		(start 276.76729 -24.985218)
		(end 277.055072 -24.697436)
		(width 0.14224)
		(layer "In2.Cu")
		(net "M_C_CS_N<6>")
	)
	(segment
		(start 277.35911 -18.091658)
		(end 277.35911 -17.463008)
		(width 0.14224)
		(layer "In2.Cu")
		(net "M_C_CS_N<6>")
	)
	(segment
		(start 277.455122 -23.132796)
		(end 277.455122 -22.599396)
		(width 0.14224)
		(layer "In2.Cu")
		(net "M_C_CS_N<6>")
	)
	(segment
		(start 275.617686 -26.421842)
		(end 275.617686 -26.134822)
		(width 0.14224)
		(layer "In2.Cu")
		(net "M_C_CS_N<6>")
	)
	(segment
		(start 277.585678 -13.527024)
		(end 277.455122 -13.396468)
		(width 0.14224)
		(layer "In2.Cu")
		(net "M_C_CS_N<6>")
	)
	(segment
		(start 277.479252 -15.024354)
		(end 277.297388 -14.84249)
		(width 0.14224)
		(layer "In2.Cu")
		(net "M_C_CS_N<6>")
	)
	(segment
		(start 276.331934 -25.986232)
		(end 276.618954 -25.986232)
		(width 0.14224)
		(layer "In2.Cu")
		(net "M_C_CS_N<6>")
	)
	(segment
		(start 275.757132 -26.848054)
		(end 275.757132 -26.561034)
		(width 0.14224)
		(layer "In2.Cu")
		(net "M_C_CS_N<6>")
	)
	(segment
		(start 277.999952 -5.337048)
		(end 277.999952 -4.332986)
		(width 0.14224)
		(layer "In2.Cu")
		(net "M_C_CS_N<6>")
	)
	(segment
		(start 278.010874 -24.594312)
		(end 278.010874 -23.688548)
		(width 0.14224)
		(layer "In2.Cu")
		(net "M_C_CS_N<6>")
	)
	(segment
		(start 277.632922 -21.938996)
		(end 277.505922 -21.811996)
		(width 0.14224)
		(layer "In2.Cu")
		(net "M_C_CS_N<6>")
	)
	(segment
		(start 278.010874 -23.688548)
		(end 277.455122 -23.132796)
		(width 0.14224)
		(layer "In2.Cu")
		(net "M_C_CS_N<6>")
	)
	(segment
		(start 277.505922 -21.811996)
		(end 277.505922 -19.242278)
		(width 0.14224)
		(layer "In2.Cu")
		(net "M_C_CS_N<6>")
	)
	(segment
		(start 277.455122 -12.937744)
		(end 277.582884 -12.809982)
		(width 0.14224)
		(layer "In2.Cu")
		(net "M_C_CS_N<6>")
	)
	(segment
		(start 277.632922 -22.421596)
		(end 277.632922 -21.938996)
		(width 0.14224)
		(layer "In2.Cu")
		(net "M_C_CS_N<6>")
	)
	(segment
		(start 277.585678 -14.178788)
		(end 277.585678 -13.527024)
		(width 0.14224)
		(layer "In2.Cu")
		(net "M_C_CS_N<6>")
	)
	(segment
		(start 276.618954 -25.986232)
		(end 276.906736 -25.69845)
		(width 0.14224)
		(layer "In2.Cu")
		(net "M_C_CS_N<6>")
	)
	(segment
		(start 277.585678 -17.23644)
		(end 277.585678 -16.488664)
		(width 0.14224)
		(layer "In2.Cu")
		(net "M_C_CS_N<6>")
	)
	(segment
		(start 277.585678 -16.488664)
		(end 277.326598 -16.229584)
		(width 0.14224)
		(layer "In2.Cu")
		(net "M_C_CS_N<6>")
	)
	(segment
		(start 276.906736 -25.69845)
		(end 276.906736 -25.41143)
		(width 0.14224)
		(layer "In2.Cu")
		(net "M_C_CS_N<6>")
	)
	(segment
		(start 277.649686 -11.004042)
		(end 277.649686 -9.83869)
		(width 0.14224)
		(layer "In2.Cu")
		(net "M_C_CS_N<6>")
	)
	(segment
		(start 277.481538 -24.836628)
		(end 277.768558 -24.836628)
		(width 0.14224)
		(layer "In2.Cu")
		(net "M_C_CS_N<6>")
	)
	(segment
		(start 277.326598 -15.86484)
		(end 277.504144 -15.687294)
		(width 0.14224)
		(layer "In2.Cu")
		(net "M_C_CS_N<6>")
	)
	(segment
		(start 267.781024 -56.299354)
		(end 267.781024 -51.80203)
		(width 0.0889)
		(layer "In2.Cu")
		(net "M_C_CS_N<6>")
	)
	(segment
		(start 277.768558 -24.836628)
		(end 278.010874 -24.594312)
		(width 0.14224)
		(layer "In2.Cu")
		(net "M_C_CS_N<6>")
	)
	(segment
		(start 277.58771 -9.776714)
		(end 277.58771 -8.086598)
		(width 0.14224)
		(layer "In2.Cu")
		(net "M_C_CS_N<6>")
	)
	(segment
		(start 277.505922 -19.242278)
		(end 277.585678 -19.162522)
		(width 0.14224)
		(layer "In2.Cu")
		(net "M_C_CS_N<6>")
	)
	(segment
		(start 269.30096 -48.300386)
		(end 269.30096 -47.991522)
		(width 0.0889)
		(layer "In2.Cu")
		(net "M_C_CS_N<6>")
	)
	(segment
		(start 277.585678 -19.162522)
		(end 277.585678 -18.318226)
		(width 0.14224)
		(layer "In2.Cu")
		(net "M_C_CS_N<6>")
	)
	(segment
		(start 265.372596 -58.561986)
		(end 264.801096 -58.561986)
		(width 0.1016)
		(layer "F.Cu")
		(net "M_C_CS_N<5>")
	)
	(via
		(at 274.599908 -4.328668)
		(size 0.4572)
		(drill 0.2032)
		(layers "F.Cu" "B.Cu")
		(net "M_C_CS_N<5>")
	)
	(via
		(at 264.801096 -58.561986)
		(size 0.508)
		(drill 0.254)
		(layers "F.Cu" "B.Cu")
		(net "M_C_CS_N<5>")
	)
	(segment
		(start 274.599908 -5.621782)
		(end 274.599908 -4.328668)
		(width 0.1651)
		(layer "B.Cu")
		(net "M_C_CS_N<5>")
	)
	(segment
		(start 274.600416 -5.621782)
		(end 274.599908 -5.621782)
		(width 0.1651)
		(layer "B.Cu")
		(net "M_C_CS_N<5>")
	)
	(segment
		(start 273.334226 -18.95475)
		(end 273.334226 -18.439638)
		(width 0.14224)
		(layer "In2.Cu")
		(net "M_C_CS_N<5>")
	)
	(segment
		(start 273.11223 -10.206228)
		(end 273.421856 -10.206228)
		(width 0.14224)
		(layer "In2.Cu")
		(net "M_C_CS_N<5>")
	)
	(segment
		(start 264.801096 -58.561986)
		(end 265.105896 -57.860692)
		(width 0.0889)
		(layer "In2.Cu")
		(net "M_C_CS_N<5>")
	)
	(segment
		(start 272.95729 -10.714228)
		(end 272.95729 -10.361168)
		(width 0.14224)
		(layer "In2.Cu")
		(net "M_C_CS_N<5>")
	)
	(segment
		(start 273.384772 -20.774152)
		(end 273.078702 -20.774152)
		(width 0.14224)
		(layer "In2.Cu")
		(net "M_C_CS_N<5>")
	)
	(segment
		(start 273.539712 -19.160236)
		(end 273.334226 -18.95475)
		(width 0.14224)
		(layer "In2.Cu")
		(net "M_C_CS_N<5>")
	)
	(segment
		(start 273.539712 -20.929092)
		(end 273.384772 -20.774152)
		(width 0.14224)
		(layer "In2.Cu")
		(net "M_C_CS_N<5>")
	)
	(segment
		(start 266.76096 -48.462946)
		(end 266.76096 -32.250634)
		(width 0.14224)
		(layer "In2.Cu")
		(net "M_C_CS_N<5>")
	)
	(segment
		(start 273.242278 -17.134586)
		(end 273.336766 -17.040098)
		(width 0.14224)
		(layer "In2.Cu")
		(net "M_C_CS_N<5>")
	)
	(segment
		(start 273.576796 -9.600184)
		(end 273.335496 -9.358884)
		(width 0.14224)
		(layer "In2.Cu")
		(net "M_C_CS_N<5>")
	)
	(segment
		(start 273.336766 -14.592046)
		(end 273.313398 -14.568678)
		(width 0.14224)
		(layer "In2.Cu")
		(net "M_C_CS_N<5>")
	)
	(segment
		(start 273.313398 -13.612876)
		(end 273.420078 -13.506196)
		(width 0.14224)
		(layer "In2.Cu")
		(net "M_C_CS_N<5>")
	)
	(segment
		(start 273.420078 -23.107396)
		(end 273.420078 -22.573996)
		(width 0.14224)
		(layer "In2.Cu")
		(net "M_C_CS_N<5>")
	)
	(segment
		(start 271.578324 -25.56002)
		(end 272.116296 -25.022048)
		(width 0.14224)
		(layer "In2.Cu")
		(net "M_C_CS_N<5>")
	)
	(segment
		(start 273.420078 -22.573996)
		(end 273.242278 -22.396196)
		(width 0.14224)
		(layer "In2.Cu")
		(net "M_C_CS_N<5>")
	)
	(segment
		(start 273.242278 -22.396196)
		(end 273.242278 -21.913596)
		(width 0.14224)
		(layer "In2.Cu")
		(net "M_C_CS_N<5>")
	)
	(segment
		(start 273.313398 -14.568678)
		(end 273.313398 -13.612876)
		(width 0.14224)
		(layer "In2.Cu")
		(net "M_C_CS_N<5>")
	)
	(segment
		(start 273.341846 -11.684254)
		(end 273.576796 -11.449304)
		(width 0.14224)
		(layer "In2.Cu")
		(net "M_C_CS_N<5>")
	)
	(segment
		(start 273.059906 -20.111212)
		(end 273.384772 -20.111212)
		(width 0.14224)
		(layer "In2.Cu")
		(net "M_C_CS_N<5>")
	)
	(segment
		(start 273.421856 -10.206228)
		(end 273.576796 -10.051288)
		(width 0.14224)
		(layer "In2.Cu")
		(net "M_C_CS_N<5>")
	)
	(segment
		(start 266.76096 -32.250634)
		(end 271.578324 -27.43327)
		(width 0.14224)
		(layer "In2.Cu")
		(net "M_C_CS_N<5>")
	)
	(segment
		(start 272.914364 -20.609814)
		(end 272.914364 -20.256754)
		(width 0.14224)
		(layer "In2.Cu")
		(net "M_C_CS_N<5>")
	)
	(segment
		(start 273.334226 -18.439638)
		(end 273.394678 -18.379186)
		(width 0.14224)
		(layer "In2.Cu")
		(net "M_C_CS_N<5>")
	)
	(segment
		(start 273.394678 -18.379186)
		(end 273.394678 -17.794986)
		(width 0.14224)
		(layer "In2.Cu")
		(net "M_C_CS_N<5>")
	)
	(segment
		(start 273.11223 -10.869168)
		(end 272.95729 -10.714228)
		(width 0.14224)
		(layer "In2.Cu")
		(net "M_C_CS_N<5>")
	)
	(segment
		(start 273.335496 -9.358884)
		(end 273.335496 -5.599684)
		(width 0.14224)
		(layer "In2.Cu")
		(net "M_C_CS_N<5>")
	)
	(segment
		(start 273.336766 -17.040098)
		(end 273.336766 -14.592046)
		(width 0.14224)
		(layer "In2.Cu")
		(net "M_C_CS_N<5>")
	)
	(segment
		(start 273.421856 -10.869168)
		(end 273.11223 -10.869168)
		(width 0.14224)
		(layer "In2.Cu")
		(net "M_C_CS_N<5>")
	)
	(segment
		(start 272.95729 -10.361168)
		(end 273.11223 -10.206228)
		(width 0.14224)
		(layer "In2.Cu")
		(net "M_C_CS_N<5>")
	)
	(segment
		(start 273.242278 -21.913596)
		(end 273.539712 -21.616162)
		(width 0.14224)
		(layer "In2.Cu")
		(net "M_C_CS_N<5>")
	)
	(segment
		(start 273.420078 -12.972796)
		(end 273.242278 -12.794996)
		(width 0.14224)
		(layer "In2.Cu")
		(net "M_C_CS_N<5>")
	)
	(segment
		(start 273.420078 -13.506196)
		(end 273.420078 -12.972796)
		(width 0.14224)
		(layer "In2.Cu")
		(net "M_C_CS_N<5>")
	)
	(segment
		(start 265.4554 -52.286408)
		(end 265.4554 -50.91176)
		(width 0.0889)
		(layer "In2.Cu")
		(net "M_C_CS_N<5>")
	)
	(segment
		(start 273.539712 -21.616162)
		(end 273.539712 -20.929092)
		(width 0.14224)
		(layer "In2.Cu")
		(net "M_C_CS_N<5>")
	)
	(segment
		(start 273.242278 -12.794996)
		(end 273.242278 -12.312396)
		(width 0.14224)
		(layer "In2.Cu")
		(net "M_C_CS_N<5>")
	)
	(segment
		(start 274.32 -4.608576)
		(end 274.599908 -4.328668)
		(width 0.14224)
		(layer "In2.Cu")
		(net "M_C_CS_N<5>")
	)
	(segment
		(start 273.2786 -23.248874)
		(end 273.420078 -23.107396)
		(width 0.14224)
		(layer "In2.Cu")
		(net "M_C_CS_N<5>")
	)
	(segment
		(start 273.384772 -20.111212)
		(end 273.539712 -19.956272)
		(width 0.14224)
		(layer "In2.Cu")
		(net "M_C_CS_N<5>")
	)
	(segment
		(start 273.335496 -5.599684)
		(end 274.32 -4.61518)
		(width 0.14224)
		(layer "In2.Cu")
		(net "M_C_CS_N<5>")
	)
	(segment
		(start 273.576796 -11.449304)
		(end 273.576796 -11.024108)
		(width 0.14224)
		(layer "In2.Cu")
		(net "M_C_CS_N<5>")
	)
	(segment
		(start 265.4554 -50.91176)
		(end 266.13358 -50.23358)
		(width 0.0889)
		(layer "In2.Cu")
		(net "M_C_CS_N<5>")
	)
	(segment
		(start 273.539712 -19.956272)
		(end 273.539712 -19.160236)
		(width 0.14224)
		(layer "In2.Cu")
		(net "M_C_CS_N<5>")
	)
	(segment
		(start 273.242278 -12.312396)
		(end 273.341846 -12.212828)
		(width 0.14224)
		(layer "In2.Cu")
		(net "M_C_CS_N<5>")
	)
	(segment
		(start 273.576796 -11.024108)
		(end 273.421856 -10.869168)
		(width 0.14224)
		(layer "In2.Cu")
		(net "M_C_CS_N<5>")
	)
	(segment
		(start 266.13358 -49.41062)
		(end 266.76096 -48.78324)
		(width 0.0889)
		(layer "In2.Cu")
		(net "M_C_CS_N<5>")
	)
	(segment
		(start 273.242278 -17.642586)
		(end 273.242278 -17.134586)
		(width 0.14224)
		(layer "In2.Cu")
		(net "M_C_CS_N<5>")
	)
	(segment
		(start 274.32 -4.61518)
		(end 274.32 -4.608576)
		(width 0.14224)
		(layer "In2.Cu")
		(net "M_C_CS_N<5>")
	)
	(segment
		(start 273.341846 -12.212828)
		(end 273.341846 -11.684254)
		(width 0.14224)
		(layer "In2.Cu")
		(net "M_C_CS_N<5>")
	)
	(segment
		(start 272.914364 -20.256754)
		(end 273.059906 -20.111212)
		(width 0.14224)
		(layer "In2.Cu")
		(net "M_C_CS_N<5>")
	)
	(segment
		(start 272.116296 -25.022048)
		(end 272.564352 -25.022048)
		(width 0.14224)
		(layer "In2.Cu")
		(net "M_C_CS_N<5>")
	)
	(segment
		(start 272.564352 -25.022048)
		(end 273.2786 -24.3078)
		(width 0.14224)
		(layer "In2.Cu")
		(net "M_C_CS_N<5>")
	)
	(segment
		(start 273.2786 -24.3078)
		(end 273.2786 -23.248874)
		(width 0.14224)
		(layer "In2.Cu")
		(net "M_C_CS_N<5>")
	)
	(segment
		(start 266.13358 -50.23358)
		(end 266.13358 -49.41062)
		(width 0.0889)
		(layer "In2.Cu")
		(net "M_C_CS_N<5>")
	)
	(segment
		(start 273.394678 -17.794986)
		(end 273.242278 -17.642586)
		(width 0.14224)
		(layer "In2.Cu")
		(net "M_C_CS_N<5>")
	)
	(segment
		(start 271.578324 -27.43327)
		(end 271.578324 -25.56002)
		(width 0.14224)
		(layer "In2.Cu")
		(net "M_C_CS_N<5>")
	)
	(segment
		(start 273.576796 -10.051288)
		(end 273.576796 -9.600184)
		(width 0.14224)
		(layer "In2.Cu")
		(net "M_C_CS_N<5>")
	)
	(segment
		(start 265.147806 -52.818792)
		(end 265.4554 -52.286408)
		(width 0.0889)
		(layer "In2.Cu")
		(net "M_C_CS_N<5>")
	)
	(segment
		(start 273.078702 -20.774152)
		(end 272.914364 -20.609814)
		(width 0.14224)
		(layer "In2.Cu")
		(net "M_C_CS_N<5>")
	)
	(segment
		(start 266.76096 -48.78324)
		(end 266.76096 -48.462946)
		(width 0.0889)
		(layer "In2.Cu")
		(net "M_C_CS_N<5>")
	)
	(arc
		(start 265.147806 -54.799992)
		(mid 265.201305 -54.600094)
		(end 265.147806 -54.400196)
		(width 0.0889)
		(layer "In2.Cu")
		(net "M_C_CS_N<5>")
	)
	(arc
		(start 265.147806 -55.390796)
		(mid 265.068675 -55.095394)
		(end 265.147806 -54.799992)
		(width 0.0889)
		(layer "In2.Cu")
		(net "M_C_CS_N<5>")
	)
	(arc
		(start 265.147806 -53.409596)
		(mid 265.068675 -53.114194)
		(end 265.147806 -52.818792)
		(width 0.0889)
		(layer "In2.Cu")
		(net "M_C_CS_N<5>")
	)
	(arc
		(start 265.147806 -55.790592)
		(mid 265.201305 -55.590694)
		(end 265.147806 -55.390796)
		(width 0.0889)
		(layer "In2.Cu")
		(net "M_C_CS_N<5>")
	)
	(arc
		(start 265.147806 -53.809392)
		(mid 265.201305 -53.609494)
		(end 265.147806 -53.409596)
		(width 0.0889)
		(layer "In2.Cu")
		(net "M_C_CS_N<5>")
	)
	(arc
		(start 265.147806 -57.371996)
		(mid 265.068675 -57.076594)
		(end 265.147806 -56.781192)
		(width 0.0889)
		(layer "In2.Cu")
		(net "M_C_CS_N<5>")
	)
	(arc
		(start 265.147806 -54.400196)
		(mid 265.068743 -54.104794)
		(end 265.147806 -53.809392)
		(width 0.0889)
		(layer "In2.Cu")
		(net "M_C_CS_N<5>")
	)
	(arc
		(start 265.147806 -56.381396)
		(mid 265.068675 -56.085994)
		(end 265.147806 -55.790592)
		(width 0.0889)
		(layer "In2.Cu")
		(net "M_C_CS_N<5>")
	)
	(arc
		(start 265.147806 -56.781192)
		(mid 265.201305 -56.581294)
		(end 265.147806 -56.381396)
		(width 0.0889)
		(layer "In2.Cu")
		(net "M_C_CS_N<5>")
	)
	(arc
		(start 265.105896 -57.860692)
		(mid 265.125003 -57.815371)
		(end 265.147806 -57.771792)
		(width 0.0889)
		(layer "In2.Cu")
		(net "M_C_CS_N<5>")
	)
	(arc
		(start 265.147806 -57.771792)
		(mid 265.201305 -57.571894)
		(end 265.147806 -57.371996)
		(width 0.0889)
		(layer "In2.Cu")
		(net "M_C_CS_N<5>")
	)
	(segment
		(start 262.79729 -60.047886)
		(end 262.22579 -60.047886)
		(width 0.1016)
		(layer "F.Cu")
		(net "M_C_CS_N<4>")
	)
	(via
		(at 270.350234 -4.332478)
		(size 0.4572)
		(drill 0.2032)
		(layers "F.Cu" "B.Cu")
		(net "M_C_CS_N<4>")
	)
	(via
		(at 262.22579 -60.047886)
		(size 0.508)
		(drill 0.254)
		(layers "F.Cu" "B.Cu")
		(net "M_C_CS_N<4>")
	)
	(segment
		(start 270.34998 -4.332732)
		(end 270.350234 -4.332478)
		(width 0.1651)
		(layer "B.Cu")
		(net "M_C_CS_N<4>")
	)
	(segment
		(start 270.34998 -5.621782)
		(end 270.34998 -4.332732)
		(width 0.1651)
		(layer "B.Cu")
		(net "M_C_CS_N<4>")
	)
	(segment
		(start 270.350488 -5.621782)
		(end 270.34998 -5.621782)
		(width 0.1651)
		(layer "B.Cu")
		(net "M_C_CS_N<4>")
	)
	(segment
		(start 269.083536 -8.5598)
		(end 269.207234 -8.436102)
		(width 0.14224)
		(layer "In2.Cu")
		(net "M_C_CS_N<4>")
	)
	(segment
		(start 262.22579 -60.047886)
		(end 262.720836 -59.382152)
		(width 0.0889)
		(layer "In2.Cu")
		(net "M_C_CS_N<4>")
	)
	(segment
		(start 262.7376 -57.771538)
		(end 262.732774 -57.762902)
		(width 0.0889)
		(layer "In2.Cu")
		(net "M_C_CS_N<4>")
	)
	(segment
		(start 263.3726 -51.1048)
		(end 263.678924 -50.798476)
		(width 0.0889)
		(layer "In2.Cu")
		(net "M_C_CS_N<4>")
	)
	(segment
		(start 269.089124 -7.491476)
		(end 269.089124 -5.593588)
		(width 0.14224)
		(layer "In2.Cu")
		(net "M_C_CS_N<4>")
	)
	(segment
		(start 269.207234 -8.436102)
		(end 269.207234 -7.609586)
		(width 0.14224)
		(layer "In2.Cu")
		(net "M_C_CS_N<4>")
	)
	(segment
		(start 262.7376 -58.362088)
		(end 262.74395 -58.35142)
		(width 0.0889)
		(layer "In2.Cu")
		(net "M_C_CS_N<4>")
	)
	(segment
		(start 269.004034 -23.107396)
		(end 269.004034 -22.599396)
		(width 0.14224)
		(layer "In2.Cu")
		(net "M_C_CS_N<4>")
	)
	(segment
		(start 269.004034 -21.735796)
		(end 269.004034 -21.278596)
		(width 0.14224)
		(layer "In2.Cu")
		(net "M_C_CS_N<4>")
	)
	(segment
		(start 269.083536 -12.214098)
		(end 269.083536 -8.5598)
		(width 0.14224)
		(layer "In2.Cu")
		(net "M_C_CS_N<4>")
	)
	(segment
		(start 267.6906 -27.727148)
		(end 267.6906 -25.664668)
		(width 0.14224)
		(layer "In2.Cu")
		(net "M_C_CS_N<4>")
	)
	(segment
		(start 269.083282 -17.086834)
		(end 269.083282 -15.85468)
		(width 0.14224)
		(layer "In2.Cu")
		(net "M_C_CS_N<4>")
	)
	(segment
		(start 264.22096 -48.529494)
		(end 264.22096 -48.32096)
		(width 0.0889)
		(layer "In2.Cu")
		(net "M_C_CS_N<4>")
	)
	(segment
		(start 269.004034 -21.278596)
		(end 269.087346 -21.195284)
		(width 0.14224)
		(layer "In2.Cu")
		(net "M_C_CS_N<4>")
	)
	(segment
		(start 269.156434 -22.446996)
		(end 269.156434 -21.888196)
		(width 0.14224)
		(layer "In2.Cu")
		(net "M_C_CS_N<4>")
	)
	(segment
		(start 262.74395 -56.791606)
		(end 262.7376 -56.780938)
		(width 0.0889)
		(layer "In2.Cu")
		(net "M_C_CS_N<4>")
	)
	(segment
		(start 262.7376 -54.799738)
		(end 262.732774 -54.791102)
		(width 0.0889)
		(layer "In2.Cu")
		(net "M_C_CS_N<4>")
	)
	(segment
		(start 269.207234 -18.233898)
		(end 269.207234 -17.210786)
		(width 0.14224)
		(layer "In2.Cu")
		(net "M_C_CS_N<4>")
	)
	(segment
		(start 262.7376 -55.790338)
		(end 262.732774 -55.781702)
		(width 0.0889)
		(layer "In2.Cu")
		(net "M_C_CS_N<4>")
	)
	(segment
		(start 262.7376 -53.809138)
		(end 262.732774 -53.800502)
		(width 0.0889)
		(layer "In2.Cu")
		(net "M_C_CS_N<4>")
	)
	(segment
		(start 269.182596 -24.172672)
		(end 269.182596 -23.285958)
		(width 0.14224)
		(layer "In2.Cu")
		(net "M_C_CS_N<4>")
	)
	(segment
		(start 269.004034 -22.599396)
		(end 269.156434 -22.446996)
		(width 0.14224)
		(layer "In2.Cu")
		(net "M_C_CS_N<4>")
	)
	(segment
		(start 262.720836 -59.382152)
		(end 262.7376 -59.352688)
		(width 0.0889)
		(layer "In2.Cu")
		(net "M_C_CS_N<4>")
	)
	(segment
		(start 269.06601 -13.487908)
		(end 269.156434 -13.397484)
		(width 0.14224)
		(layer "In2.Cu")
		(net "M_C_CS_N<4>")
	)
	(segment
		(start 262.655304 -52.673758)
		(end 262.655304 -52.458366)
		(width 0.0889)
		(layer "In2.Cu")
		(net "M_C_CS_N<4>")
	)
	(segment
		(start 264.22096 -48.32096)
		(end 264.22096 -31.196788)
		(width 0.14224)
		(layer "In2.Cu")
		(net "M_C_CS_N<4>")
	)
	(segment
		(start 263.678924 -49.07153)
		(end 264.22096 -48.529494)
		(width 0.0889)
		(layer "In2.Cu")
		(net "M_C_CS_N<4>")
	)
	(segment
		(start 263.678924 -50.798476)
		(end 263.678924 -49.07153)
		(width 0.0889)
		(layer "In2.Cu")
		(net "M_C_CS_N<4>")
	)
	(segment
		(start 262.655304 -52.458366)
		(end 263.3726 -51.74107)
		(width 0.0889)
		(layer "In2.Cu")
		(net "M_C_CS_N<4>")
	)
	(segment
		(start 269.083282 -15.85468)
		(end 269.06601 -15.837408)
		(width 0.14224)
		(layer "In2.Cu")
		(net "M_C_CS_N<4>")
	)
	(segment
		(start 262.74395 -53.819806)
		(end 262.7376 -53.809138)
		(width 0.0889)
		(layer "In2.Cu")
		(net "M_C_CS_N<4>")
	)
	(segment
		(start 267.6906 -25.664668)
		(end 269.182596 -24.172672)
		(width 0.14224)
		(layer "In2.Cu")
		(net "M_C_CS_N<4>")
	)
	(segment
		(start 269.156434 -12.286996)
		(end 269.083536 -12.214098)
		(width 0.14224)
		(layer "In2.Cu")
		(net "M_C_CS_N<4>")
	)
	(segment
		(start 269.156434 -13.397484)
		(end 269.156434 -12.286996)
		(width 0.14224)
		(layer "In2.Cu")
		(net "M_C_CS_N<4>")
	)
	(segment
		(start 269.089124 -5.593588)
		(end 270.350234 -4.332478)
		(width 0.14224)
		(layer "In2.Cu")
		(net "M_C_CS_N<4>")
	)
	(segment
		(start 269.156434 -21.888196)
		(end 269.004034 -21.735796)
		(width 0.14224)
		(layer "In2.Cu")
		(net "M_C_CS_N<4>")
	)
	(segment
		(start 262.7376 -56.780938)
		(end 262.732774 -56.772302)
		(width 0.0889)
		(layer "In2.Cu")
		(net "M_C_CS_N<4>")
	)
	(segment
		(start 269.182596 -23.285958)
		(end 269.004034 -23.107396)
		(width 0.14224)
		(layer "In2.Cu")
		(net "M_C_CS_N<4>")
	)
	(segment
		(start 263.3726 -51.74107)
		(end 263.3726 -51.1048)
		(width 0.0889)
		(layer "In2.Cu")
		(net "M_C_CS_N<4>")
	)
	(segment
		(start 269.06601 -15.837408)
		(end 269.06601 -13.487908)
		(width 0.14224)
		(layer "In2.Cu")
		(net "M_C_CS_N<4>")
	)
	(segment
		(start 262.74395 -54.810406)
		(end 262.7376 -54.799738)
		(width 0.0889)
		(layer "In2.Cu")
		(net "M_C_CS_N<4>")
	)
	(segment
		(start 264.22096 -31.196788)
		(end 267.6906 -27.727148)
		(width 0.14224)
		(layer "In2.Cu")
		(net "M_C_CS_N<4>")
	)
	(segment
		(start 269.207234 -17.210786)
		(end 269.083282 -17.086834)
		(width 0.14224)
		(layer "In2.Cu")
		(net "M_C_CS_N<4>")
	)
	(segment
		(start 269.087346 -21.195284)
		(end 269.087346 -18.353786)
		(width 0.14224)
		(layer "In2.Cu")
		(net "M_C_CS_N<4>")
	)
	(segment
		(start 262.74395 -55.801006)
		(end 262.7376 -55.790338)
		(width 0.0889)
		(layer "In2.Cu")
		(net "M_C_CS_N<4>")
	)
	(segment
		(start 269.207234 -7.609586)
		(end 269.089124 -7.491476)
		(width 0.14224)
		(layer "In2.Cu")
		(net "M_C_CS_N<4>")
	)
	(segment
		(start 262.7376 -52.818284)
		(end 262.655304 -52.673758)
		(width 0.0889)
		(layer "In2.Cu")
		(net "M_C_CS_N<4>")
	)
	(segment
		(start 269.087346 -18.353786)
		(end 269.207234 -18.233898)
		(width 0.14224)
		(layer "In2.Cu")
		(net "M_C_CS_N<4>")
	)
	(arc
		(start 262.7376 -59.352688)
		(mid 262.816731 -59.057286)
		(end 262.7376 -58.761884)
		(width 0.0889)
		(layer "In2.Cu")
		(net "M_C_CS_N<4>")
	)
	(arc
		(start 262.732774 -54.791102)
		(mid 262.684019 -54.59475)
		(end 262.7376 -54.399688)
		(width 0.0889)
		(layer "In2.Cu")
		(net "M_C_CS_N<4>")
	)
	(arc
		(start 262.732774 -53.800502)
		(mid 262.684019 -53.60415)
		(end 262.7376 -53.409088)
		(width 0.0889)
		(layer "In2.Cu")
		(net "M_C_CS_N<4>")
	)
	(arc
		(start 262.732774 -57.762902)
		(mid 262.684019 -57.56655)
		(end 262.7376 -57.371488)
		(width 0.0889)
		(layer "In2.Cu")
		(net "M_C_CS_N<4>")
	)
	(arc
		(start 262.732774 -56.772302)
		(mid 262.684019 -56.57595)
		(end 262.7376 -56.380888)
		(width 0.0889)
		(layer "In2.Cu")
		(net "M_C_CS_N<4>")
	)
	(arc
		(start 262.7376 -55.390288)
		(mid 262.816822 -55.10117)
		(end 262.74395 -54.810406)
		(width 0.0889)
		(layer "In2.Cu")
		(net "M_C_CS_N<4>")
	)
	(arc
		(start 262.7376 -57.371488)
		(mid 262.816822 -57.08237)
		(end 262.74395 -56.791606)
		(width 0.0889)
		(layer "In2.Cu")
		(net "M_C_CS_N<4>")
	)
	(arc
		(start 262.74395 -58.35142)
		(mid 262.816748 -58.060657)
		(end 262.7376 -57.771538)
		(width 0.0889)
		(layer "In2.Cu")
		(net "M_C_CS_N<4>")
	)
	(arc
		(start 262.7376 -56.380888)
		(mid 262.816822 -56.09177)
		(end 262.74395 -55.801006)
		(width 0.0889)
		(layer "In2.Cu")
		(net "M_C_CS_N<4>")
	)
	(arc
		(start 262.7376 -53.409088)
		(mid 262.816731 -53.113686)
		(end 262.7376 -52.818284)
		(width 0.0889)
		(layer "In2.Cu")
		(net "M_C_CS_N<4>")
	)
	(arc
		(start 262.7376 -58.761884)
		(mid 262.684101 -58.561986)
		(end 262.7376 -58.362088)
		(width 0.0889)
		(layer "In2.Cu")
		(net "M_C_CS_N<4>")
	)
	(arc
		(start 262.732774 -55.781702)
		(mid 262.684019 -55.58535)
		(end 262.7376 -55.390288)
		(width 0.0889)
		(layer "In2.Cu")
		(net "M_C_CS_N<4>")
	)
	(arc
		(start 262.7376 -54.399688)
		(mid 262.816822 -54.11057)
		(end 262.74395 -53.819806)
		(width 0.0889)
		(layer "In2.Cu")
		(net "M_C_CS_N<4>")
	)
	(segment
		(start 266.518136 -59.55284)
		(end 267.089636 -59.55284)
		(width 0.1016)
		(layer "F.Cu")
		(net "M_C_CS_N<3>")
	)
	(segment
		(start 277.999952 -0.821182)
		(end 277.999952 1.152144)
		(width 0.1651)
		(layer "F.Cu")
		(net "M_C_CS_N<3>")
	)
	(segment
		(start 278.00046 -0.821182)
		(end 277.999952 -0.821182)
		(width 0.1651)
		(layer "F.Cu")
		(net "M_C_CS_N<3>")
	)
	(via
		(at 277.999952 1.152144)
		(size 0.508)
		(drill 0.254)
		(layers "F.Cu" "B.Cu")
		(net "M_C_CS_N<3>")
	)
	(via
		(at 266.518136 -59.55284)
		(size 0.508)
		(drill 0.254)
		(layers "F.Cu" "B.Cu")
		(net "M_C_CS_N<3>")
	)
	(segment
		(start 276.820122 -23.107396)
		(end 276.820122 -22.573996)
		(width 0.14224)
		(layer "In2.Cu")
		(net "M_C_CS_N<3>")
	)
	(segment
		(start 274.8026 -26.212546)
		(end 276.642322 -24.372824)
		(width 0.14224)
		(layer "In2.Cu")
		(net "M_C_CS_N<3>")
	)
	(segment
		(start 276.642322 -21.913596)
		(end 276.794722 -21.761196)
		(width 0.14224)
		(layer "In2.Cu")
		(net "M_C_CS_N<3>")
	)
	(segment
		(start 276.710394 -18.463514)
		(end 276.794722 -18.379186)
		(width 0.14224)
		(layer "In2.Cu")
		(net "M_C_CS_N<3>")
	)
	(segment
		(start 267.208 -49.9364)
		(end 268.79296 -48.35144)
		(width 0.0889)
		(layer "In2.Cu")
		(net "M_C_CS_N<3>")
	)
	(segment
		(start 274.8026 -27.08402)
		(end 274.8026 -26.212546)
		(width 0.14224)
		(layer "In2.Cu")
		(net "M_C_CS_N<3>")
	)
	(segment
		(start 276.794722 -8.777986)
		(end 276.794722 -8.193786)
		(width 0.14224)
		(layer "In2.Cu")
		(net "M_C_CS_N<3>")
	)
	(segment
		(start 277.999952 -1.425448)
		(end 277.999952 1.152144)
		(width 0.14224)
		(layer "In2.Cu")
		(net "M_C_CS_N<3>")
	)
	(segment
		(start 276.794722 -19.141186)
		(end 276.710394 -19.056858)
		(width 0.14224)
		(layer "In2.Cu")
		(net "M_C_CS_N<3>")
	)
	(segment
		(start 276.642322 -8.041386)
		(end 276.642322 -7.533386)
		(width 0.14224)
		(layer "In2.Cu")
		(net "M_C_CS_N<3>")
	)
	(segment
		(start 276.642322 -24.372824)
		(end 276.642322 -23.285196)
		(width 0.14224)
		(layer "In2.Cu")
		(net "M_C_CS_N<3>")
	)
	(segment
		(start 276.712934 -11.167364)
		(end 276.794722 -11.085576)
		(width 0.14224)
		(layer "In2.Cu")
		(net "M_C_CS_N<3>")
	)
	(segment
		(start 276.713188 -17.06372)
		(end 276.713188 -13.61313)
		(width 0.14224)
		(layer "In2.Cu")
		(net "M_C_CS_N<3>")
	)
	(segment
		(start 276.820122 -12.91336)
		(end 276.712934 -12.806172)
		(width 0.14224)
		(layer "In2.Cu")
		(net "M_C_CS_N<3>")
	)
	(segment
		(start 276.820122 -13.506196)
		(end 276.820122 -12.91336)
		(width 0.14224)
		(layer "In2.Cu")
		(net "M_C_CS_N<3>")
	)
	(segment
		(start 266.518136 -59.55284)
		(end 267.4112 -58.659776)
		(width 0.0889)
		(layer "In2.Cu")
		(net "M_C_CS_N<3>")
	)
	(segment
		(start 276.714458 -5.606542)
		(end 277.587456 -4.733544)
		(width 0.14224)
		(layer "In2.Cu")
		(net "M_C_CS_N<3>")
	)
	(segment
		(start 267.208 -51.5366)
		(end 267.208 -49.9364)
		(width 0.0889)
		(layer "In2.Cu")
		(net "M_C_CS_N<3>")
	)
	(segment
		(start 276.713188 -13.61313)
		(end 276.820122 -13.506196)
		(width 0.14224)
		(layer "In2.Cu")
		(net "M_C_CS_N<3>")
	)
	(segment
		(start 276.714458 -7.46125)
		(end 276.714458 -5.606542)
		(width 0.14224)
		(layer "In2.Cu")
		(net "M_C_CS_N<3>")
	)
	(segment
		(start 276.710394 -19.056858)
		(end 276.710394 -18.463514)
		(width 0.14224)
		(layer "In2.Cu")
		(net "M_C_CS_N<3>")
	)
	(segment
		(start 276.794722 -17.794986)
		(end 276.642322 -17.642586)
		(width 0.14224)
		(layer "In2.Cu")
		(net "M_C_CS_N<3>")
	)
	(segment
		(start 276.642322 -23.285196)
		(end 276.820122 -23.107396)
		(width 0.14224)
		(layer "In2.Cu")
		(net "M_C_CS_N<3>")
	)
	(segment
		(start 276.715982 -9.461246)
		(end 276.715982 -8.856726)
		(width 0.14224)
		(layer "In2.Cu")
		(net "M_C_CS_N<3>")
	)
	(segment
		(start 276.820122 -22.573996)
		(end 276.642322 -22.396196)
		(width 0.14224)
		(layer "In2.Cu")
		(net "M_C_CS_N<3>")
	)
	(segment
		(start 276.715982 -8.856726)
		(end 276.794722 -8.777986)
		(width 0.14224)
		(layer "In2.Cu")
		(net "M_C_CS_N<3>")
	)
	(segment
		(start 276.642322 -22.396196)
		(end 276.642322 -21.913596)
		(width 0.14224)
		(layer "In2.Cu")
		(net "M_C_CS_N<3>")
	)
	(segment
		(start 276.794722 -11.085576)
		(end 276.794722 -9.539986)
		(width 0.14224)
		(layer "In2.Cu")
		(net "M_C_CS_N<3>")
	)
	(segment
		(start 267.4112 -58.659776)
		(end 267.4112 -51.7398)
		(width 0.0889)
		(layer "In2.Cu")
		(net "M_C_CS_N<3>")
	)
	(segment
		(start 276.642322 -17.134586)
		(end 276.713188 -17.06372)
		(width 0.14224)
		(layer "In2.Cu")
		(net "M_C_CS_N<3>")
	)
	(segment
		(start 276.794722 -18.379186)
		(end 276.794722 -17.794986)
		(width 0.14224)
		(layer "In2.Cu")
		(net "M_C_CS_N<3>")
	)
	(segment
		(start 267.4112 -51.7398)
		(end 267.208 -51.5366)
		(width 0.0889)
		(layer "In2.Cu")
		(net "M_C_CS_N<3>")
	)
	(segment
		(start 276.642322 -7.533386)
		(end 276.714458 -7.46125)
		(width 0.14224)
		(layer "In2.Cu")
		(net "M_C_CS_N<3>")
	)
	(segment
		(start 268.79296 -33.09366)
		(end 274.8026 -27.08402)
		(width 0.14224)
		(layer "In2.Cu")
		(net "M_C_CS_N<3>")
	)
	(segment
		(start 276.712934 -12.806172)
		(end 276.712934 -11.167364)
		(width 0.14224)
		(layer "In2.Cu")
		(net "M_C_CS_N<3>")
	)
	(segment
		(start 268.79296 -48.093122)
		(end 268.79296 -33.09366)
		(width 0.14224)
		(layer "In2.Cu")
		(net "M_C_CS_N<3>")
	)
	(segment
		(start 277.587456 -4.733544)
		(end 277.587456 -1.837944)
		(width 0.14224)
		(layer "In2.Cu")
		(net "M_C_CS_N<3>")
	)
	(segment
		(start 276.642322 -17.642586)
		(end 276.642322 -17.134586)
		(width 0.14224)
		(layer "In2.Cu")
		(net "M_C_CS_N<3>")
	)
	(segment
		(start 276.794722 -8.193786)
		(end 276.642322 -8.041386)
		(width 0.14224)
		(layer "In2.Cu")
		(net "M_C_CS_N<3>")
	)
	(segment
		(start 277.587456 -1.837944)
		(end 277.999952 -1.425448)
		(width 0.14224)
		(layer "In2.Cu")
		(net "M_C_CS_N<3>")
	)
	(segment
		(start 276.794722 -9.539986)
		(end 276.715982 -9.461246)
		(width 0.14224)
		(layer "In2.Cu")
		(net "M_C_CS_N<3>")
	)
	(segment
		(start 276.794722 -21.761196)
		(end 276.794722 -19.141186)
		(width 0.14224)
		(layer "In2.Cu")
		(net "M_C_CS_N<3>")
	)
	(segment
		(start 268.79296 -48.35144)
		(end 268.79296 -48.093122)
		(width 0.0889)
		(layer "In2.Cu")
		(net "M_C_CS_N<3>")
	)
	(segment
		(start 277.999952 3.778758)
		(end 277.999952 2.485644)
		(width 0.1651)
		(layer "F.Cu")
		(net "M_C_CS_N<2>")
	)
	(segment
		(start 267.089636 -58.561986)
		(end 266.518136 -58.561986)
		(width 0.1016)
		(layer "F.Cu")
		(net "M_C_CS_N<2>")
	)
	(segment
		(start 278.00046 3.778758)
		(end 277.999952 3.778758)
		(width 0.1651)
		(layer "F.Cu")
		(net "M_C_CS_N<2>")
	)
	(via
		(at 277.999952 2.485644)
		(size 0.508)
		(drill 0.254)
		(layers "F.Cu" "B.Cu")
		(net "M_C_CS_N<2>")
	)
	(via
		(at 266.518136 -58.561986)
		(size 0.508)
		(drill 0.254)
		(layers "F.Cu" "B.Cu")
		(net "M_C_CS_N<2>")
	)
	(segment
		(start 276.714458 0.094742)
		(end 276.714458 -4.742688)
		(width 0.14224)
		(layer "In2.Cu")
		(net "M_C_CS_N<2>")
	)
	(segment
		(start 275.892768 -5.564378)
		(end 275.892768 -7.495032)
		(width 0.14224)
		(layer "In2.Cu")
		(net "M_C_CS_N<2>")
	)
	(segment
		(start 275.89226 -17.095724)
		(end 276.007322 -17.210786)
		(width 0.14224)
		(layer "In2.Cu")
		(net "M_C_CS_N<2>")
	)
	(segment
		(start 275.892768 -7.495032)
		(end 276.007322 -7.609586)
		(width 0.14224)
		(layer "In2.Cu")
		(net "M_C_CS_N<2>")
	)
	(segment
		(start 274.2692 -25.983946)
		(end 274.2692 -26.898854)
		(width 0.14224)
		(layer "In2.Cu")
		(net "M_C_CS_N<2>")
	)
	(segment
		(start 276.007322 -7.965186)
		(end 275.871686 -8.100822)
		(width 0.14224)
		(layer "In2.Cu")
		(net "M_C_CS_N<2>")
	)
	(segment
		(start 275.956522 -9.901682)
		(end 275.956522 -11.524996)
		(width 0.14224)
		(layer "In2.Cu")
		(net "M_C_CS_N<2>")
	)
	(segment
		(start 275.956522 -21.888196)
		(end 275.956522 -22.446996)
		(width 0.14224)
		(layer "In2.Cu")
		(net "M_C_CS_N<2>")
	)
	(segment
		(start 275.871686 -8.100822)
		(end 275.871686 -9.696704)
		(width 0.14224)
		(layer "In2.Cu")
		(net "M_C_CS_N<2>")
	)
	(segment
		(start 275.804122 -21.735796)
		(end 275.956522 -21.888196)
		(width 0.14224)
		(layer "In2.Cu")
		(net "M_C_CS_N<2>")
	)
	(segment
		(start 275.804122 -18.328386)
		(end 275.883878 -18.408142)
		(width 0.14224)
		(layer "In2.Cu")
		(net "M_C_CS_N<2>")
	)
	(segment
		(start 275.871686 -9.696704)
		(end 275.956522 -9.901682)
		(width 0.14224)
		(layer "In2.Cu")
		(net "M_C_CS_N<2>")
	)
	(segment
		(start 275.956522 -23.259796)
		(end 275.956522 -24.296624)
		(width 0.14224)
		(layer "In2.Cu")
		(net "M_C_CS_N<2>")
	)
	(segment
		(start 276.007322 -17.566386)
		(end 275.804122 -17.769586)
		(width 0.14224)
		(layer "In2.Cu")
		(net "M_C_CS_N<2>")
	)
	(segment
		(start 276.6568 0.1524)
		(end 276.714458 0.094742)
		(width 0.14224)
		(layer "In2.Cu")
		(net "M_C_CS_N<2>")
	)
	(segment
		(start 275.883878 -18.408142)
		(end 275.883878 -21.19884)
		(width 0.14224)
		(layer "In2.Cu")
		(net "M_C_CS_N<2>")
	)
	(segment
		(start 266.973304 -58.106818)
		(end 266.518136 -58.561986)
		(width 0.0889)
		(layer "In2.Cu")
		(net "M_C_CS_N<2>")
	)
	(segment
		(start 275.956522 -11.524996)
		(end 275.887942 -11.593576)
		(width 0.14224)
		(layer "In2.Cu")
		(net "M_C_CS_N<2>")
	)
	(segment
		(start 275.956522 -24.296624)
		(end 274.2692 -25.983946)
		(width 0.14224)
		(layer "In2.Cu")
		(net "M_C_CS_N<2>")
	)
	(segment
		(start 275.804122 -23.107396)
		(end 275.956522 -23.259796)
		(width 0.14224)
		(layer "In2.Cu")
		(net "M_C_CS_N<2>")
	)
	(segment
		(start 268.28496 -32.883094)
		(end 268.28496 -48.194722)
		(width 0.14224)
		(layer "In2.Cu")
		(net "M_C_CS_N<2>")
	)
	(segment
		(start 268.28496 -48.194722)
		(end 268.28496 -48.47844)
		(width 0.0889)
		(layer "In2.Cu")
		(net "M_C_CS_N<2>")
	)
	(segment
		(start 276.714458 -4.742688)
		(end 275.892768 -5.564378)
		(width 0.14224)
		(layer "In2.Cu")
		(net "M_C_CS_N<2>")
	)
	(segment
		(start 275.804122 -17.769586)
		(end 275.804122 -18.328386)
		(width 0.14224)
		(layer "In2.Cu")
		(net "M_C_CS_N<2>")
	)
	(segment
		(start 276.007322 -7.609586)
		(end 276.007322 -7.965186)
		(width 0.14224)
		(layer "In2.Cu")
		(net "M_C_CS_N<2>")
	)
	(segment
		(start 275.956522 -22.446996)
		(end 275.804122 -22.599396)
		(width 0.14224)
		(layer "In2.Cu")
		(net "M_C_CS_N<2>")
	)
	(segment
		(start 276.007322 -17.210786)
		(end 276.007322 -17.566386)
		(width 0.14224)
		(layer "In2.Cu")
		(net "M_C_CS_N<2>")
	)
	(segment
		(start 275.804122 -22.599396)
		(end 275.804122 -23.107396)
		(width 0.14224)
		(layer "In2.Cu")
		(net "M_C_CS_N<2>")
	)
	(segment
		(start 275.804122 -21.278596)
		(end 275.804122 -21.735796)
		(width 0.14224)
		(layer "In2.Cu")
		(net "M_C_CS_N<2>")
	)
	(segment
		(start 275.804122 -12.998196)
		(end 275.804122 -13.506196)
		(width 0.14224)
		(layer "In2.Cu")
		(net "M_C_CS_N<2>")
	)
	(segment
		(start 275.956522 -12.286996)
		(end 275.956522 -12.845796)
		(width 0.14224)
		(layer "In2.Cu")
		(net "M_C_CS_N<2>")
	)
	(segment
		(start 275.804122 -13.506196)
		(end 275.89226 -13.594334)
		(width 0.14224)
		(layer "In2.Cu")
		(net "M_C_CS_N<2>")
	)
	(segment
		(start 266.973304 -49.790096)
		(end 266.973304 -58.106818)
		(width 0.0889)
		(layer "In2.Cu")
		(net "M_C_CS_N<2>")
	)
	(segment
		(start 277.999952 2.040128)
		(end 276.6568 0.696976)
		(width 0.14224)
		(layer "In2.Cu")
		(net "M_C_CS_N<2>")
	)
	(segment
		(start 274.2692 -26.898854)
		(end 268.28496 -32.883094)
		(width 0.14224)
		(layer "In2.Cu")
		(net "M_C_CS_N<2>")
	)
	(segment
		(start 275.887942 -12.218416)
		(end 275.956522 -12.286996)
		(width 0.14224)
		(layer "In2.Cu")
		(net "M_C_CS_N<2>")
	)
	(segment
		(start 268.28496 -48.47844)
		(end 266.973304 -49.790096)
		(width 0.0889)
		(layer "In2.Cu")
		(net "M_C_CS_N<2>")
	)
	(segment
		(start 275.956522 -12.845796)
		(end 275.804122 -12.998196)
		(width 0.14224)
		(layer "In2.Cu")
		(net "M_C_CS_N<2>")
	)
	(segment
		(start 275.883878 -21.19884)
		(end 275.804122 -21.278596)
		(width 0.14224)
		(layer "In2.Cu")
		(net "M_C_CS_N<2>")
	)
	(segment
		(start 275.89226 -13.594334)
		(end 275.89226 -17.095724)
		(width 0.14224)
		(layer "In2.Cu")
		(net "M_C_CS_N<2>")
	)
	(segment
		(start 275.887942 -11.593576)
		(end 275.887942 -12.218416)
		(width 0.14224)
		(layer "In2.Cu")
		(net "M_C_CS_N<2>")
	)
	(segment
		(start 276.6568 0.696976)
		(end 276.6568 0.1524)
		(width 0.14224)
		(layer "In2.Cu")
		(net "M_C_CS_N<2>")
	)
	(segment
		(start 277.999952 2.485644)
		(end 277.999952 2.040128)
		(width 0.14224)
		(layer "In2.Cu")
		(net "M_C_CS_N<2>")
	)
	(segment
		(start 274.599908 3.778758)
		(end 274.599908 2.514854)
		(width 0.1651)
		(layer "F.Cu")
		(net "M_C_CS_N<1>")
	)
	(segment
		(start 264.51433 -60.047886)
		(end 263.94283 -60.047886)
		(width 0.1016)
		(layer "F.Cu")
		(net "M_C_CS_N<1>")
	)
	(segment
		(start 274.600416 3.778758)
		(end 274.599908 3.778758)
		(width 0.1651)
		(layer "F.Cu")
		(net "M_C_CS_N<1>")
	)
	(via
		(at 263.94283 -60.047886)
		(size 0.508)
		(drill 0.254)
		(layers "F.Cu" "B.Cu")
		(net "M_C_CS_N<1>")
	)
	(via
		(at 274.599908 2.514854)
		(size 0.508)
		(drill 0.254)
		(layers "F.Cu" "B.Cu")
		(net "M_C_CS_N<1>")
	)
	(segment
		(start 272.458942 -8.682482)
		(end 272.643346 -8.498078)
		(width 0.14224)
		(layer "In2.Cu")
		(net "M_C_CS_N<1>")
	)
	(segment
		(start 273.308064 -4.90855)
		(end 273.308064 -4.009136)
		(width 0.14224)
		(layer "In2.Cu")
		(net "M_C_CS_N<1>")
	)
	(segment
		(start 272.485104 -12.215622)
		(end 272.458942 -12.18946)
		(width 0.14224)
		(layer "In2.Cu")
		(net "M_C_CS_N<1>")
	)
	(segment
		(start 264.46353 -55.805578)
		(end 264.45464 -55.790338)
		(width 0.0889)
		(layer "In2.Cu")
		(net "M_C_CS_N<1>")
	)
	(segment
		(start 274.15871 -3.15849)
		(end 274.15871 -0.05969)
		(width 0.14224)
		(layer "In2.Cu")
		(net "M_C_CS_N<1>")
	)
	(segment
		(start 272.404078 -23.107396)
		(end 272.404078 -22.599396)
		(width 0.14224)
		(layer "In2.Cu")
		(net "M_C_CS_N<1>")
	)
	(segment
		(start 272.460212 -5.756402)
		(end 273.308064 -4.90855)
		(width 0.14224)
		(layer "In2.Cu")
		(net "M_C_CS_N<1>")
	)
	(segment
		(start 264.439146 -59.380374)
		(end 264.45464 -59.352942)
		(width 0.0889)
		(layer "In2.Cu")
		(net "M_C_CS_N<1>")
	)
	(segment
		(start 265.200892 -52.115974)
		(end 265.200892 -50.022252)
		(width 0.0889)
		(layer "In2.Cu")
		(net "M_C_CS_N<1>")
	)
	(segment
		(start 271.018 -27.274774)
		(end 271.018 -25.247346)
		(width 0.14224)
		(layer "In2.Cu")
		(net "M_C_CS_N<1>")
	)
	(segment
		(start 265.200892 -50.022252)
		(end 266.25296 -48.970184)
		(width 0.0889)
		(layer "In2.Cu")
		(net "M_C_CS_N<1>")
	)
	(segment
		(start 274.2438 0.762)
		(end 274.1422 0.8636)
		(width 0.14224)
		(layer "In2.Cu")
		(net "M_C_CS_N<1>")
	)
	(segment
		(start 272.556478 -23.259796)
		(end 272.404078 -23.107396)
		(width 0.14224)
		(layer "In2.Cu")
		(net "M_C_CS_N<1>")
	)
	(segment
		(start 272.556478 -22.446996)
		(end 272.556478 -21.888196)
		(width 0.14224)
		(layer "In2.Cu")
		(net "M_C_CS_N<1>")
	)
	(segment
		(start 272.460212 -7.46252)
		(end 272.460212 -5.756402)
		(width 0.14224)
		(layer "In2.Cu")
		(net "M_C_CS_N<1>")
	)
	(segment
		(start 264.46353 -53.824378)
		(end 264.45464 -53.809138)
		(width 0.0889)
		(layer "In2.Cu")
		(net "M_C_CS_N<1>")
	)
	(segment
		(start 272.404078 -19.111468)
		(end 272.461736 -19.05381)
		(width 0.14224)
		(layer "In2.Cu")
		(net "M_C_CS_N<1>")
	)
	(segment
		(start 264.45464 -53.409342)
		(end 265.200892 -52.115974)
		(width 0.0889)
		(layer "In2.Cu")
		(net "M_C_CS_N<1>")
	)
	(segment
		(start 263.94283 -60.047886)
		(end 264.439146 -59.380374)
		(width 0.0889)
		(layer "In2.Cu")
		(net "M_C_CS_N<1>")
	)
	(segment
		(start 264.46353 -54.814978)
		(end 264.45464 -54.799738)
		(width 0.0889)
		(layer "In2.Cu")
		(net "M_C_CS_N<1>")
	)
	(segment
		(start 272.607278 -18.04289)
		(end 272.607278 -17.210786)
		(width 0.14224)
		(layer "In2.Cu")
		(net "M_C_CS_N<1>")
	)
	(segment
		(start 272.643346 -7.645654)
		(end 272.460212 -7.46252)
		(width 0.14224)
		(layer "In2.Cu")
		(net "M_C_CS_N<1>")
	)
	(segment
		(start 264.46353 -56.796178)
		(end 264.45464 -56.780938)
		(width 0.0889)
		(layer "In2.Cu")
		(net "M_C_CS_N<1>")
	)
	(segment
		(start 272.461736 -18.188432)
		(end 272.607278 -18.04289)
		(width 0.14224)
		(layer "In2.Cu")
		(net "M_C_CS_N<1>")
	)
	(segment
		(start 274.2438 0.0254)
		(end 274.2438 0.762)
		(width 0.14224)
		(layer "In2.Cu")
		(net "M_C_CS_N<1>")
	)
	(segment
		(start 274.1422 1.3716)
		(end 274.599908 1.829308)
		(width 0.14224)
		(layer "In2.Cu")
		(net "M_C_CS_N<1>")
	)
	(segment
		(start 264.45464 -58.362088)
		(end 264.46099 -58.35142)
		(width 0.0889)
		(layer "In2.Cu")
		(net "M_C_CS_N<1>")
	)
	(segment
		(start 272.607278 -17.210786)
		(end 272.461482 -17.06499)
		(width 0.14224)
		(layer "In2.Cu")
		(net "M_C_CS_N<1>")
	)
	(segment
		(start 272.556478 -21.888196)
		(end 272.404078 -21.735796)
		(width 0.14224)
		(layer "In2.Cu")
		(net "M_C_CS_N<1>")
	)
	(segment
		(start 272.458942 -12.18946)
		(end 272.458942 -8.682482)
		(width 0.14224)
		(layer "In2.Cu")
		(net "M_C_CS_N<1>")
	)
	(segment
		(start 273.308064 -4.009136)
		(end 274.15871 -3.15849)
		(width 0.14224)
		(layer "In2.Cu")
		(net "M_C_CS_N<1>")
	)
	(segment
		(start 272.404078 -22.599396)
		(end 272.556478 -22.446996)
		(width 0.14224)
		(layer "In2.Cu")
		(net "M_C_CS_N<1>")
	)
	(segment
		(start 272.461482 -17.06499)
		(end 272.461482 -14.592554)
		(width 0.14224)
		(layer "In2.Cu")
		(net "M_C_CS_N<1>")
	)
	(segment
		(start 271.018 -25.247346)
		(end 272.556478 -23.708868)
		(width 0.14224)
		(layer "In2.Cu")
		(net "M_C_CS_N<1>")
	)
	(segment
		(start 274.15871 -0.05969)
		(end 274.2438 0.0254)
		(width 0.14224)
		(layer "In2.Cu")
		(net "M_C_CS_N<1>")
	)
	(segment
		(start 272.485104 -14.568932)
		(end 272.485104 -12.215622)
		(width 0.14224)
		(layer "In2.Cu")
		(net "M_C_CS_N<1>")
	)
	(segment
		(start 272.461736 -19.05381)
		(end 272.461736 -18.188432)
		(width 0.14224)
		(layer "In2.Cu")
		(net "M_C_CS_N<1>")
	)
	(segment
		(start 274.1422 0.8636)
		(end 274.1422 1.3716)
		(width 0.14224)
		(layer "In2.Cu")
		(net "M_C_CS_N<1>")
	)
	(segment
		(start 266.25296 -32.039814)
		(end 271.018 -27.274774)
		(width 0.14224)
		(layer "In2.Cu")
		(net "M_C_CS_N<1>")
	)
	(segment
		(start 264.46099 -58.772552)
		(end 264.45464 -58.761884)
		(width 0.0889)
		(layer "In2.Cu")
		(net "M_C_CS_N<1>")
	)
	(segment
		(start 266.25296 -48.970184)
		(end 266.25296 -48.589184)
		(width 0.0889)
		(layer "In2.Cu")
		(net "M_C_CS_N<1>")
	)
	(segment
		(start 274.599908 1.829308)
		(end 274.599908 2.514854)
		(width 0.14224)
		(layer "In2.Cu")
		(net "M_C_CS_N<1>")
	)
	(segment
		(start 272.556478 -23.708868)
		(end 272.556478 -23.259796)
		(width 0.14224)
		(layer "In2.Cu")
		(net "M_C_CS_N<1>")
	)
	(segment
		(start 272.643346 -8.498078)
		(end 272.643346 -7.645654)
		(width 0.14224)
		(layer "In2.Cu")
		(net "M_C_CS_N<1>")
	)
	(segment
		(start 272.461482 -14.592554)
		(end 272.485104 -14.568932)
		(width 0.14224)
		(layer "In2.Cu")
		(net "M_C_CS_N<1>")
	)
	(segment
		(start 266.25296 -48.589184)
		(end 266.25296 -32.039814)
		(width 0.14224)
		(layer "In2.Cu")
		(net "M_C_CS_N<1>")
	)
	(segment
		(start 272.404078 -21.735796)
		(end 272.404078 -19.111468)
		(width 0.14224)
		(layer "In2.Cu")
		(net "M_C_CS_N<1>")
	)
	(arc
		(start 264.45464 -57.371742)
		(mid 264.533829 -57.085127)
		(end 264.46353 -56.796178)
		(width 0.0889)
		(layer "In2.Cu")
		(net "M_C_CS_N<1>")
	)
	(arc
		(start 264.45464 -55.790338)
		(mid 264.401107 -55.59044)
		(end 264.45464 -55.390542)
		(width 0.0889)
		(layer "In2.Cu")
		(net "M_C_CS_N<1>")
	)
	(arc
		(start 264.46099 -58.35142)
		(mid 264.533788 -58.060657)
		(end 264.45464 -57.771538)
		(width 0.0889)
		(layer "In2.Cu")
		(net "M_C_CS_N<1>")
	)
	(arc
		(start 264.45464 -56.780938)
		(mid 264.401107 -56.58104)
		(end 264.45464 -56.381142)
		(width 0.0889)
		(layer "In2.Cu")
		(net "M_C_CS_N<1>")
	)
	(arc
		(start 264.45464 -53.809138)
		(mid 264.401107 -53.60924)
		(end 264.45464 -53.409342)
		(width 0.0889)
		(layer "In2.Cu")
		(net "M_C_CS_N<1>")
	)
	(arc
		(start 264.45464 -55.390542)
		(mid 264.533829 -55.103927)
		(end 264.46353 -54.814978)
		(width 0.0889)
		(layer "In2.Cu")
		(net "M_C_CS_N<1>")
	)
	(arc
		(start 264.45464 -54.399942)
		(mid 264.533829 -54.113327)
		(end 264.46353 -53.824378)
		(width 0.0889)
		(layer "In2.Cu")
		(net "M_C_CS_N<1>")
	)
	(arc
		(start 264.45464 -59.352942)
		(mid 264.533989 -59.06357)
		(end 264.46099 -58.772552)
		(width 0.0889)
		(layer "In2.Cu")
		(net "M_C_CS_N<1>")
	)
	(arc
		(start 264.45464 -57.771538)
		(mid 264.401107 -57.57164)
		(end 264.45464 -57.371742)
		(width 0.0889)
		(layer "In2.Cu")
		(net "M_C_CS_N<1>")
	)
	(arc
		(start 264.45464 -56.381142)
		(mid 264.533829 -56.094527)
		(end 264.46353 -55.805578)
		(width 0.0889)
		(layer "In2.Cu")
		(net "M_C_CS_N<1>")
	)
	(arc
		(start 264.45464 -54.799738)
		(mid 264.401107 -54.59984)
		(end 264.45464 -54.399942)
		(width 0.0889)
		(layer "In2.Cu")
		(net "M_C_CS_N<1>")
	)
	(arc
		(start 264.45464 -58.761884)
		(mid 264.401107 -58.561986)
		(end 264.45464 -58.362088)
		(width 0.0889)
		(layer "In2.Cu")
		(net "M_C_CS_N<1>")
	)
	(segment
		(start 270.350488 3.778758)
		(end 270.34998 3.778758)
		(width 0.1651)
		(layer "F.Cu")
		(net "M_C_CS_N<0>")
	)
	(segment
		(start 270.34998 3.778758)
		(end 270.34998 1.805686)
		(width 0.1651)
		(layer "F.Cu")
		(net "M_C_CS_N<0>")
	)
	(segment
		(start 262.79729 -58.06694)
		(end 262.22579 -58.06694)
		(width 0.1016)
		(layer "F.Cu")
		(net "M_C_CS_N<0>")
	)
	(segment
		(start 270.34998 1.805686)
		(end 270.349726 1.805432)
		(width 0.1651)
		(layer "F.Cu")
		(net "M_C_CS_N<0>")
	)
	(via
		(at 270.349726 1.805432)
		(size 0.508)
		(drill 0.254)
		(layers "F.Cu" "B.Cu")
		(net "M_C_CS_N<0>")
	)
	(via
		(at 262.22579 -58.06694)
		(size 0.508)
		(drill 0.254)
		(layers "F.Cu" "B.Cu")
		(net "M_C_CS_N<0>")
	)
	(segment
		(start 262.441436 -52.188618)
		(end 263.0424 -51.587654)
		(width 0.0889)
		(layer "In2.Cu")
		(net "M_C_CS_N<0>")
	)
	(segment
		(start 269.59306 -0.664718)
		(end 269.310104 -0.664718)
		(width 0.14224)
		(layer "In2.Cu")
		(net "M_C_CS_N<0>")
	)
	(segment
		(start 268.04239 -12.363196)
		(end 268.211808 -12.193778)
		(width 0.14224)
		(layer "In2.Cu")
		(net "M_C_CS_N<0>")
	)
	(segment
		(start 263.0424 -50.952654)
		(end 263.285224 -50.70983)
		(width 0.0889)
		(layer "In2.Cu")
		(net "M_C_CS_N<0>")
	)
	(segment
		(start 268.21384 -9.584436)
		(end 268.21384 -8.162036)
		(width 0.14224)
		(layer "In2.Cu")
		(net "M_C_CS_N<0>")
	)
	(segment
		(start 268.04239 -13.503148)
		(end 268.04239 -12.363196)
		(width 0.14224)
		(layer "In2.Cu")
		(net "M_C_CS_N<0>")
	)
	(segment
		(start 268.21384 -8.162036)
		(end 268.04239 -7.990586)
		(width 0.14224)
		(layer "In2.Cu")
		(net "M_C_CS_N<0>")
	)
	(segment
		(start 269.06093 -4.72567)
		(end 269.06093 -3.847084)
		(width 0.14224)
		(layer "In2.Cu")
		(net "M_C_CS_N<0>")
	)
	(segment
		(start 269.585948 -1.477518)
		(end 269.792704 -1.270762)
		(width 0.14224)
		(layer "In2.Cu")
		(net "M_C_CS_N<0>")
	)
	(segment
		(start 268.29639 -19.268186)
		(end 268.20876 -19.180556)
		(width 0.14224)
		(layer "In2.Cu")
		(net "M_C_CS_N<0>")
	)
	(segment
		(start 268.209014 -16.993362)
		(end 268.209014 -13.669772)
		(width 0.14224)
		(layer "In2.Cu")
		(net "M_C_CS_N<0>")
	)
	(segment
		(start 268.209014 -13.669772)
		(end 268.04239 -13.503148)
		(width 0.14224)
		(layer "In2.Cu")
		(net "M_C_CS_N<0>")
	)
	(segment
		(start 262.577326 -55.894224)
		(end 262.5725 -55.885588)
		(width 0.0889)
		(layer "In2.Cu")
		(net "M_C_CS_N<0>")
	)
	(segment
		(start 268.20876 -19.180556)
		(end 268.20876 -17.758156)
		(width 0.14224)
		(layer "In2.Cu")
		(net "M_C_CS_N<0>")
	)
	(segment
		(start 268.04239 -17.591786)
		(end 268.04239 -17.159986)
		(width 0.14224)
		(layer "In2.Cu")
		(net "M_C_CS_N<0>")
	)
	(segment
		(start 262.5725 -55.885588)
		(end 262.56615 -55.87492)
		(width 0.0889)
		(layer "In2.Cu")
		(net "M_C_CS_N<0>")
	)
	(segment
		(start 262.441436 -52.704492)
		(end 262.441436 -52.188618)
		(width 0.0889)
		(layer "In2.Cu")
		(net "M_C_CS_N<0>")
	)
	(segment
		(start 263.71296 -48.281336)
		(end 263.71296 -30.985968)
		(width 0.14224)
		(layer "In2.Cu")
		(net "M_C_CS_N<0>")
	)
	(segment
		(start 269.106904 0.768096)
		(end 269.0114 0.8636)
		(width 0.14224)
		(layer "In2.Cu")
		(net "M_C_CS_N<0>")
	)
	(segment
		(start 262.5725 -56.876188)
		(end 262.56615 -56.86552)
		(width 0.0889)
		(layer "In2.Cu")
		(net "M_C_CS_N<0>")
	)
	(segment
		(start 262.5725 -52.913788)
		(end 262.441436 -52.704492)
		(width 0.0889)
		(layer "In2.Cu")
		(net "M_C_CS_N<0>")
	)
	(segment
		(start 268.29639 -21.710396)
		(end 268.29639 -19.268186)
		(width 0.14224)
		(layer "In2.Cu")
		(net "M_C_CS_N<0>")
	)
	(segment
		(start 268.37386 -23.106126)
		(end 268.37386 -22.740366)
		(width 0.14224)
		(layer "In2.Cu")
		(net "M_C_CS_N<0>")
	)
	(segment
		(start 269.244826 -1.477518)
		(end 269.585948 -1.477518)
		(width 0.14224)
		(layer "In2.Cu")
		(net "M_C_CS_N<0>")
	)
	(segment
		(start 268.04239 -21.964396)
		(end 268.29639 -21.710396)
		(width 0.14224)
		(layer "In2.Cu")
		(net "M_C_CS_N<0>")
	)
	(segment
		(start 262.577326 -54.903624)
		(end 262.5725 -54.894988)
		(width 0.0889)
		(layer "In2.Cu")
		(net "M_C_CS_N<0>")
	)
	(segment
		(start 263.285224 -50.70983)
		(end 263.285224 -48.956976)
		(width 0.0889)
		(layer "In2.Cu")
		(net "M_C_CS_N<0>")
	)
	(segment
		(start 262.5725 -53.904388)
		(end 262.56615 -53.89372)
		(width 0.0889)
		(layer "In2.Cu")
		(net "M_C_CS_N<0>")
	)
	(segment
		(start 268.211808 -12.193778)
		(end 268.211808 -11.045444)
		(width 0.14224)
		(layer "In2.Cu")
		(net "M_C_CS_N<0>")
	)
	(segment
		(start 268.37386 -22.740366)
		(end 268.04239 -22.408896)
		(width 0.14224)
		(layer "In2.Cu")
		(net "M_C_CS_N<0>")
	)
	(segment
		(start 268.208506 -7.39267)
		(end 268.208506 -5.578094)
		(width 0.14224)
		(layer "In2.Cu")
		(net "M_C_CS_N<0>")
	)
	(segment
		(start 269.792704 -1.270762)
		(end 269.792704 -0.864362)
		(width 0.14224)
		(layer "In2.Cu")
		(net "M_C_CS_N<0>")
	)
	(segment
		(start 262.577326 -56.884824)
		(end 262.5725 -56.876188)
		(width 0.0889)
		(layer "In2.Cu")
		(net "M_C_CS_N<0>")
	)
	(segment
		(start 268.20876 -17.758156)
		(end 268.04239 -17.591786)
		(width 0.14224)
		(layer "In2.Cu")
		(net "M_C_CS_N<0>")
	)
	(segment
		(start 262.218678 -58.04916)
		(end 262.497062 -57.406286)
		(width 0.0889)
		(layer "In2.Cu")
		(net "M_C_CS_N<0>")
	)
	(segment
		(start 269.310104 -0.664718)
		(end 269.106904 -0.461518)
		(width 0.14224)
		(layer "In2.Cu")
		(net "M_C_CS_N<0>")
	)
	(segment
		(start 262.497062 -57.406286)
		(end 262.5725 -57.276238)
		(width 0.0889)
		(layer "In2.Cu")
		(net "M_C_CS_N<0>")
	)
	(segment
		(start 266.3444 -26.149808)
		(end 268.04239 -24.451818)
		(width 0.14224)
		(layer "In2.Cu")
		(net "M_C_CS_N<0>")
	)
	(segment
		(start 262.22579 -58.06694)
		(end 262.218678 -58.04916)
		(width 0.0889)
		(layer "In2.Cu")
		(net "M_C_CS_N<0>")
	)
	(segment
		(start 269.33525 -3.572764)
		(end 269.33525 -2.81686)
		(width 0.14224)
		(layer "In2.Cu")
		(net "M_C_CS_N<0>")
	)
	(segment
		(start 268.208506 -5.578094)
		(end 269.06093 -4.72567)
		(width 0.14224)
		(layer "In2.Cu")
		(net "M_C_CS_N<0>")
	)
	(segment
		(start 263.0424 -51.587654)
		(end 263.0424 -50.952654)
		(width 0.0889)
		(layer "In2.Cu")
		(net "M_C_CS_N<0>")
	)
	(segment
		(start 269.0114 0.8636)
		(end 269.0114 1.448308)
		(width 0.14224)
		(layer "In2.Cu")
		(net "M_C_CS_N<0>")
	)
	(segment
		(start 269.06093 -3.847084)
		(end 269.33525 -3.572764)
		(width 0.14224)
		(layer "In2.Cu")
		(net "M_C_CS_N<0>")
	)
	(segment
		(start 268.211808 -11.045444)
		(end 268.399006 -10.858246)
		(width 0.14224)
		(layer "In2.Cu")
		(net "M_C_CS_N<0>")
	)
	(segment
		(start 268.04239 -22.408896)
		(end 268.04239 -21.964396)
		(width 0.14224)
		(layer "In2.Cu")
		(net "M_C_CS_N<0>")
	)
	(segment
		(start 266.3444 -28.354528)
		(end 266.3444 -26.149808)
		(width 0.14224)
		(layer "In2.Cu")
		(net "M_C_CS_N<0>")
	)
	(segment
		(start 263.71296 -30.985968)
		(end 266.3444 -28.354528)
		(width 0.14224)
		(layer "In2.Cu")
		(net "M_C_CS_N<0>")
	)
	(segment
		(start 268.04239 -7.558786)
		(end 268.208506 -7.39267)
		(width 0.14224)
		(layer "In2.Cu")
		(net "M_C_CS_N<0>")
	)
	(segment
		(start 262.5725 -54.894988)
		(end 262.56615 -54.88432)
		(width 0.0889)
		(layer "In2.Cu")
		(net "M_C_CS_N<0>")
	)
	(segment
		(start 269.368524 1.805432)
		(end 270.349726 1.805432)
		(width 0.14224)
		(layer "In2.Cu")
		(net "M_C_CS_N<0>")
	)
	(segment
		(start 268.399006 -9.769602)
		(end 268.21384 -9.584436)
		(width 0.14224)
		(layer "In2.Cu")
		(net "M_C_CS_N<0>")
	)
	(segment
		(start 268.04239 -7.990586)
		(end 268.04239 -7.558786)
		(width 0.14224)
		(layer "In2.Cu")
		(net "M_C_CS_N<0>")
	)
	(segment
		(start 269.089886 -2.571496)
		(end 269.089886 -1.632458)
		(width 0.14224)
		(layer "In2.Cu")
		(net "M_C_CS_N<0>")
	)
	(segment
		(start 263.71296 -48.52924)
		(end 263.71296 -48.281336)
		(width 0.0889)
		(layer "In2.Cu")
		(net "M_C_CS_N<0>")
	)
	(segment
		(start 268.399006 -10.858246)
		(end 268.399006 -9.769602)
		(width 0.14224)
		(layer "In2.Cu")
		(net "M_C_CS_N<0>")
	)
	(segment
		(start 269.089886 -1.632458)
		(end 269.244826 -1.477518)
		(width 0.14224)
		(layer "In2.Cu")
		(net "M_C_CS_N<0>")
	)
	(segment
		(start 268.04239 -24.451818)
		(end 268.04239 -23.437596)
		(width 0.14224)
		(layer "In2.Cu")
		(net "M_C_CS_N<0>")
	)
	(segment
		(start 263.285224 -48.956976)
		(end 263.71296 -48.52924)
		(width 0.0889)
		(layer "In2.Cu")
		(net "M_C_CS_N<0>")
	)
	(segment
		(start 269.792704 -0.864362)
		(end 269.59306 -0.664718)
		(width 0.14224)
		(layer "In2.Cu")
		(net "M_C_CS_N<0>")
	)
	(segment
		(start 268.04239 -17.159986)
		(end 268.209014 -16.993362)
		(width 0.14224)
		(layer "In2.Cu")
		(net "M_C_CS_N<0>")
	)
	(segment
		(start 269.33525 -2.81686)
		(end 269.089886 -2.571496)
		(width 0.14224)
		(layer "In2.Cu")
		(net "M_C_CS_N<0>")
	)
	(segment
		(start 262.577326 -52.922424)
		(end 262.5725 -52.913788)
		(width 0.0889)
		(layer "In2.Cu")
		(net "M_C_CS_N<0>")
	)
	(segment
		(start 262.577326 -53.913024)
		(end 262.5725 -53.904388)
		(width 0.0889)
		(layer "In2.Cu")
		(net "M_C_CS_N<0>")
	)
	(segment
		(start 269.0114 1.448308)
		(end 269.368524 1.805432)
		(width 0.14224)
		(layer "In2.Cu")
		(net "M_C_CS_N<0>")
	)
	(segment
		(start 269.106904 -0.461518)
		(end 269.106904 0.768096)
		(width 0.14224)
		(layer "In2.Cu")
		(net "M_C_CS_N<0>")
	)
	(segment
		(start 268.04239 -23.437596)
		(end 268.37386 -23.106126)
		(width 0.14224)
		(layer "In2.Cu")
		(net "M_C_CS_N<0>")
	)
	(arc
		(start 262.5725 -54.304438)
		(mid 262.62597 -54.109375)
		(end 262.577326 -53.913024)
		(width 0.0889)
		(layer "In2.Cu")
		(net "M_C_CS_N<0>")
	)
	(arc
		(start 262.56615 -54.88432)
		(mid 262.493352 -54.593557)
		(end 262.5725 -54.304438)
		(width 0.0889)
		(layer "In2.Cu")
		(net "M_C_CS_N<0>")
	)
	(arc
		(start 262.5725 -57.276238)
		(mid 262.62597 -57.081175)
		(end 262.577326 -56.884824)
		(width 0.0889)
		(layer "In2.Cu")
		(net "M_C_CS_N<0>")
	)
	(arc
		(start 262.5725 -56.285638)
		(mid 262.62597 -56.090575)
		(end 262.577326 -55.894224)
		(width 0.0889)
		(layer "In2.Cu")
		(net "M_C_CS_N<0>")
	)
	(arc
		(start 262.56615 -53.89372)
		(mid 262.493352 -53.602957)
		(end 262.5725 -53.313838)
		(width 0.0889)
		(layer "In2.Cu")
		(net "M_C_CS_N<0>")
	)
	(arc
		(start 262.56615 -56.86552)
		(mid 262.493352 -56.574757)
		(end 262.5725 -56.285638)
		(width 0.0889)
		(layer "In2.Cu")
		(net "M_C_CS_N<0>")
	)
	(arc
		(start 262.5725 -53.313838)
		(mid 262.62597 -53.118775)
		(end 262.577326 -52.922424)
		(width 0.0889)
		(layer "In2.Cu")
		(net "M_C_CS_N<0>")
	)
	(arc
		(start 262.56615 -55.87492)
		(mid 262.493352 -55.584157)
		(end 262.5725 -55.295038)
		(width 0.0889)
		(layer "In2.Cu")
		(net "M_C_CS_N<0>")
	)
	(arc
		(start 262.5725 -55.295038)
		(mid 262.62597 -55.099975)
		(end 262.577326 -54.903624)
		(width 0.0889)
		(layer "In2.Cu")
		(net "M_C_CS_N<0>")
	)
	(segment
		(start 257.64617 -58.06694)
		(end 257.07467 -58.06694)
		(width 0.1016)
		(layer "F.Cu")
		(net "M_C_CLK_DP<3>")
	)
	(via
		(at 257.07467 -58.06694)
		(size 0.508)
		(drill 0.254)
		(layers "F.Cu" "B.Cu")
		(net "M_C_CLK_DP<3>")
	)
	(via
		(at 256.749804 -2.314956)
		(size 0.508)
		(drill 0.254)
		(layers "F.Cu" "B.Cu")
		(net "M_C_CLK_DP<3>")
	)
	(segment
		(start 256.749804 -1.021842)
		(end 256.749804 -2.314956)
		(width 0.1651)
		(layer "B.Cu")
		(net "M_C_CLK_DP<3>")
	)
	(segment
		(start 256.750312 -1.021842)
		(end 256.749804 -1.021842)
		(width 0.1651)
		(layer "B.Cu")
		(net "M_C_CLK_DP<3>")
	)
	(segment
		(start 257.527298 -52.105814)
		(end 257.331464 -51.76774)
		(width 0.0889)
		(layer "In2.Cu")
		(net "M_C_CLK_DP<3>")
	)
	(segment
		(start 259.72516 -11.66876)
		(end 259.05968 -11.00328)
		(width 0.14224)
		(layer "In2.Cu")
		(net "M_C_CLK_DP<3>")
	)
	(segment
		(start 256.77876 -21.343874)
		(end 256.77876 -18.20164)
		(width 0.14224)
		(layer "In2.Cu")
		(net "M_C_CLK_DP<3>")
	)
	(segment
		(start 258.697222 -6.44652)
		(end 257.388868 -6.44652)
		(width 0.14224)
		(layer "In2.Cu")
		(net "M_C_CLK_DP<3>")
	)
	(segment
		(start 258.363974 -50.295556)
		(end 258.363974 -49.901094)
		(width 0.0889)
		(layer "In2.Cu")
		(net "M_C_CLK_DP<3>")
	)
	(segment
		(start 259.05968 -11.00328)
		(end 259.05968 -6.808978)
		(width 0.14224)
		(layer "In2.Cu")
		(net "M_C_CLK_DP<3>")
	)
	(segment
		(start 257.331464 -51.328066)
		(end 258.363974 -50.295556)
		(width 0.0889)
		(layer "In2.Cu")
		(net "M_C_CLK_DP<3>")
	)
	(segment
		(start 258.324604 -49.839626)
		(end 258.324604 -26.17597)
		(width 0.14224)
		(layer "In2.Cu")
		(net "M_C_CLK_DP<3>")
	)
	(segment
		(start 256.356612 -24.207978)
		(end 256.356612 -21.766022)
		(width 0.14224)
		(layer "In2.Cu")
		(net "M_C_CLK_DP<3>")
	)
	(segment
		(start 258.324604 -49.861724)
		(end 258.324604 -49.839626)
		(width 0.0889)
		(layer "In2.Cu")
		(net "M_C_CLK_DP<3>")
	)
	(segment
		(start 256.77876 -18.20164)
		(end 257.4544 -17.526)
		(width 0.14224)
		(layer "In2.Cu")
		(net "M_C_CLK_DP<3>")
	)
	(segment
		(start 257.4544 -15.8496)
		(end 259.05968 -14.24432)
		(width 0.14224)
		(layer "In2.Cu")
		(net "M_C_CLK_DP<3>")
	)
	(segment
		(start 256.41427 -3.831082)
		(end 257.021076 -3.224276)
		(width 0.14224)
		(layer "In2.Cu")
		(net "M_C_CLK_DP<3>")
	)
	(segment
		(start 258.324604 -26.17597)
		(end 256.356612 -24.207978)
		(width 0.14224)
		(layer "In2.Cu")
		(net "M_C_CLK_DP<3>")
	)
	(segment
		(start 259.05968 -13.54582)
		(end 259.72516 -12.88034)
		(width 0.14224)
		(layer "In2.Cu")
		(net "M_C_CLK_DP<3>")
	)
	(segment
		(start 256.356612 -21.766022)
		(end 256.77876 -21.343874)
		(width 0.14224)
		(layer "In2.Cu")
		(net "M_C_CLK_DP<3>")
	)
	(segment
		(start 257.021076 -2.586228)
		(end 256.749804 -2.314956)
		(width 0.14224)
		(layer "In2.Cu")
		(net "M_C_CLK_DP<3>")
	)
	(segment
		(start 259.05968 -6.808978)
		(end 258.697222 -6.44652)
		(width 0.14224)
		(layer "In2.Cu")
		(net "M_C_CLK_DP<3>")
	)
	(segment
		(start 257.367786 -58.236104)
		(end 257.446526 -58.214768)
		(width 0.0889)
		(layer "In2.Cu")
		(net "M_C_CLK_DP<3>")
	)
	(segment
		(start 259.72516 -12.88034)
		(end 259.72516 -11.66876)
		(width 0.14224)
		(layer "In2.Cu")
		(net "M_C_CLK_DP<3>")
	)
	(segment
		(start 257.388868 -6.44652)
		(end 256.41427 -5.471922)
		(width 0.14224)
		(layer "In2.Cu")
		(net "M_C_CLK_DP<3>")
	)
	(segment
		(start 259.05968 -14.24432)
		(end 259.05968 -13.54582)
		(width 0.14224)
		(layer "In2.Cu")
		(net "M_C_CLK_DP<3>")
	)
	(segment
		(start 257.4544 -17.526)
		(end 257.4544 -15.8496)
		(width 0.14224)
		(layer "In2.Cu")
		(net "M_C_CLK_DP<3>")
	)
	(segment
		(start 258.363974 -49.901094)
		(end 258.324604 -49.861724)
		(width 0.0889)
		(layer "In2.Cu")
		(net "M_C_CLK_DP<3>")
	)
	(segment
		(start 257.021076 -3.224276)
		(end 257.021076 -2.586228)
		(width 0.14224)
		(layer "In2.Cu")
		(net "M_C_CLK_DP<3>")
	)
	(segment
		(start 257.527298 -54.122066)
		(end 257.527298 -52.105814)
		(width 0.0889)
		(layer "In2.Cu")
		(net "M_C_CLK_DP<3>")
	)
	(segment
		(start 257.42138 -54.304692)
		(end 257.527298 -54.122066)
		(width 0.0889)
		(layer "In2.Cu")
		(net "M_C_CLK_DP<3>")
	)
	(segment
		(start 256.41427 -5.471922)
		(end 256.41427 -3.831082)
		(width 0.14224)
		(layer "In2.Cu")
		(net "M_C_CLK_DP<3>")
	)
	(segment
		(start 257.07467 -58.06694)
		(end 257.367786 -58.236104)
		(width 0.0889)
		(layer "In2.Cu")
		(net "M_C_CLK_DP<3>")
	)
	(segment
		(start 257.331464 -51.76774)
		(end 257.331464 -51.328066)
		(width 0.0889)
		(layer "In2.Cu")
		(net "M_C_CLK_DP<3>")
	)
	(arc
		(start 257.42138 -55.886096)
		(mid 257.342249 -55.590694)
		(end 257.42138 -55.295292)
		(width 0.0889)
		(layer "In2.Cu")
		(net "M_C_CLK_DP<3>")
	)
	(arc
		(start 257.47472 -58.065416)
		(mid 257.460961 -57.96288)
		(end 257.42138 -57.867296)
		(width 0.0889)
		(layer "In2.Cu")
		(net "M_C_CLK_DP<3>")
	)
	(arc
		(start 257.42138 -55.295292)
		(mid 257.474879 -55.095394)
		(end 257.42138 -54.895496)
		(width 0.0889)
		(layer "In2.Cu")
		(net "M_C_CLK_DP<3>")
	)
	(arc
		(start 257.42138 -57.867296)
		(mid 257.342249 -57.571894)
		(end 257.42138 -57.276492)
		(width 0.0889)
		(layer "In2.Cu")
		(net "M_C_CLK_DP<3>")
	)
	(arc
		(start 257.42138 -54.895496)
		(mid 257.342249 -54.600094)
		(end 257.42138 -54.304692)
		(width 0.0889)
		(layer "In2.Cu")
		(net "M_C_CLK_DP<3>")
	)
	(arc
		(start 257.42138 -56.876696)
		(mid 257.342249 -56.581294)
		(end 257.42138 -56.285892)
		(width 0.0889)
		(layer "In2.Cu")
		(net "M_C_CLK_DP<3>")
	)
	(arc
		(start 257.42138 -56.285892)
		(mid 257.474879 -56.085994)
		(end 257.42138 -55.886096)
		(width 0.0889)
		(layer "In2.Cu")
		(net "M_C_CLK_DP<3>")
	)
	(arc
		(start 257.446526 -58.214768)
		(mid 257.467775 -58.141442)
		(end 257.47472 -58.065416)
		(width 0.0889)
		(layer "In2.Cu")
		(net "M_C_CLK_DP<3>")
	)
	(arc
		(start 257.42138 -57.276492)
		(mid 257.474879 -57.076594)
		(end 257.42138 -56.876696)
		(width 0.0889)
		(layer "In2.Cu")
		(net "M_C_CLK_DP<3>")
	)
	(segment
		(start 256.749804 -0.821182)
		(end 256.749804 0.471932)
		(width 0.1651)
		(layer "F.Cu")
		(net "M_C_CLK_DP<1>")
	)
	(segment
		(start 259.36321 -58.06694)
		(end 258.79171 -58.06694)
		(width 0.1016)
		(layer "F.Cu")
		(net "M_C_CLK_DP<1>")
	)
	(segment
		(start 256.750312 -0.821182)
		(end 256.749804 -0.821182)
		(width 0.1651)
		(layer "F.Cu")
		(net "M_C_CLK_DP<1>")
	)
	(via
		(at 256.749804 0.471932)
		(size 0.508)
		(drill 0.254)
		(layers "F.Cu" "B.Cu")
		(net "M_C_CLK_DP<1>")
	)
	(via
		(at 258.79171 -58.06694)
		(size 0.508)
		(drill 0.254)
		(layers "F.Cu" "B.Cu")
		(net "M_C_CLK_DP<1>")
	)
	(segment
		(start 258.522724 -0.267208)
		(end 258.8895 -0.267208)
		(width 0.14224)
		(layer "In2.Cu")
		(net "M_C_CLK_DP<1>")
	)
	(segment
		(start 260.958076 -14.022324)
		(end 260.958076 -25.954482)
		(width 0.14224)
		(layer "In2.Cu")
		(net "M_C_CLK_DP<1>")
	)
	(segment
		(start 260.958076 -10.514076)
		(end 261.22376 -10.77976)
		(width 0.14224)
		(layer "In2.Cu")
		(net "M_C_CLK_DP<1>")
	)
	(segment
		(start 260.958076 -25.954482)
		(end 260.013704 -26.898854)
		(width 0.14224)
		(layer "In2.Cu")
		(net "M_C_CLK_DP<1>")
	)
	(segment
		(start 261.22376 -10.77976)
		(end 261.22376 -13.75664)
		(width 0.14224)
		(layer "In2.Cu")
		(net "M_C_CLK_DP<1>")
	)
	(segment
		(start 258.367022 -1.471422)
		(end 258.367022 -0.42291)
		(width 0.14224)
		(layer "In2.Cu")
		(net "M_C_CLK_DP<1>")
	)
	(segment
		(start 260.958076 -2.880614)
		(end 260.958076 -10.514076)
		(width 0.14224)
		(layer "In2.Cu")
		(net "M_C_CLK_DP<1>")
	)
	(segment
		(start 258.367022 -0.42291)
		(end 258.522724 -0.267208)
		(width 0.14224)
		(layer "In2.Cu")
		(net "M_C_CLK_DP<1>")
	)
	(segment
		(start 259.044948 -0.422656)
		(end 259.044948 -1.340358)
		(width 0.14224)
		(layer "In2.Cu")
		(net "M_C_CLK_DP<1>")
	)
	(segment
		(start 260.046724 -48.132238)
		(end 260.046724 -48.496474)
		(width 0.0889)
		(layer "In2.Cu")
		(net "M_C_CLK_DP<1>")
	)
	(segment
		(start 260.594348 -2.516886)
		(end 260.958076 -2.880614)
		(width 0.14224)
		(layer "In2.Cu")
		(net "M_C_CLK_DP<1>")
	)
	(segment
		(start 259.13842 -51.678586)
		(end 259.13842 -52.323492)
		(width 0.0889)
		(layer "In2.Cu")
		(net "M_C_CLK_DP<1>")
	)
	(segment
		(start 256.749804 0.471932)
		(end 257.021076 0.20066)
		(width 0.14224)
		(layer "In2.Cu")
		(net "M_C_CLK_DP<1>")
	)
	(segment
		(start 260.221476 -2.516886)
		(end 260.594348 -2.516886)
		(width 0.14224)
		(layer "In2.Cu")
		(net "M_C_CLK_DP<1>")
	)
	(segment
		(start 257.021076 0.20066)
		(end 257.021076 -0.312674)
		(width 0.14224)
		(layer "In2.Cu")
		(net "M_C_CLK_DP<1>")
	)
	(segment
		(start 259.881624 -48.661574)
		(end 259.881624 -50.935382)
		(width 0.0889)
		(layer "In2.Cu")
		(net "M_C_CLK_DP<1>")
	)
	(segment
		(start 259.163566 -58.214768)
		(end 259.084826 -58.236104)
		(width 0.0889)
		(layer "In2.Cu")
		(net "M_C_CLK_DP<1>")
	)
	(segment
		(start 256.844292 -0.489458)
		(end 255.982216 -0.489458)
		(width 0.14224)
		(layer "In2.Cu")
		(net "M_C_CLK_DP<1>")
	)
	(segment
		(start 260.013704 -26.898854)
		(end 260.013704 -48.099218)
		(width 0.14224)
		(layer "In2.Cu")
		(net "M_C_CLK_DP<1>")
	)
	(segment
		(start 255.982216 -0.489458)
		(end 255.674876 -0.796798)
		(width 0.14224)
		(layer "In2.Cu")
		(net "M_C_CLK_DP<1>")
	)
	(segment
		(start 255.674876 -0.796798)
		(end 255.674876 -1.502664)
		(width 0.14224)
		(layer "In2.Cu")
		(net "M_C_CLK_DP<1>")
	)
	(segment
		(start 258.012438 -1.826006)
		(end 258.367022 -1.471422)
		(width 0.14224)
		(layer "In2.Cu")
		(net "M_C_CLK_DP<1>")
	)
	(segment
		(start 259.044948 -1.340358)
		(end 260.221476 -2.516886)
		(width 0.14224)
		(layer "In2.Cu")
		(net "M_C_CLK_DP<1>")
	)
	(segment
		(start 260.046724 -48.496474)
		(end 259.881624 -48.661574)
		(width 0.0889)
		(layer "In2.Cu")
		(net "M_C_CLK_DP<1>")
	)
	(segment
		(start 260.013704 -48.099218)
		(end 260.046724 -48.132238)
		(width 0.0889)
		(layer "In2.Cu")
		(net "M_C_CLK_DP<1>")
	)
	(segment
		(start 259.881624 -50.935382)
		(end 259.13842 -51.678586)
		(width 0.0889)
		(layer "In2.Cu")
		(net "M_C_CLK_DP<1>")
	)
	(segment
		(start 258.8895 -0.267208)
		(end 259.044948 -0.422656)
		(width 0.14224)
		(layer "In2.Cu")
		(net "M_C_CLK_DP<1>")
	)
	(segment
		(start 255.998218 -1.826006)
		(end 258.012438 -1.826006)
		(width 0.14224)
		(layer "In2.Cu")
		(net "M_C_CLK_DP<1>")
	)
	(segment
		(start 257.021076 -0.312674)
		(end 256.844292 -0.489458)
		(width 0.14224)
		(layer "In2.Cu")
		(net "M_C_CLK_DP<1>")
	)
	(segment
		(start 255.674876 -1.502664)
		(end 255.998218 -1.826006)
		(width 0.14224)
		(layer "In2.Cu")
		(net "M_C_CLK_DP<1>")
	)
	(segment
		(start 261.22376 -13.75664)
		(end 260.958076 -14.022324)
		(width 0.14224)
		(layer "In2.Cu")
		(net "M_C_CLK_DP<1>")
	)
	(segment
		(start 259.084826 -58.236104)
		(end 258.79171 -58.06694)
		(width 0.0889)
		(layer "In2.Cu")
		(net "M_C_CLK_DP<1>")
	)
	(arc
		(start 259.13842 -52.323492)
		(mid 259.059289 -52.618894)
		(end 259.13842 -52.914296)
		(width 0.0889)
		(layer "In2.Cu")
		(net "M_C_CLK_DP<1>")
	)
	(arc
		(start 259.13842 -55.886096)
		(mid 259.191919 -56.085994)
		(end 259.13842 -56.285892)
		(width 0.0889)
		(layer "In2.Cu")
		(net "M_C_CLK_DP<1>")
	)
	(arc
		(start 259.13842 -55.295292)
		(mid 259.059289 -55.590694)
		(end 259.13842 -55.886096)
		(width 0.0889)
		(layer "In2.Cu")
		(net "M_C_CLK_DP<1>")
	)
	(arc
		(start 259.13842 -56.285892)
		(mid 259.059289 -56.581294)
		(end 259.13842 -56.876696)
		(width 0.0889)
		(layer "In2.Cu")
		(net "M_C_CLK_DP<1>")
	)
	(arc
		(start 259.13842 -54.895496)
		(mid 259.191919 -55.095394)
		(end 259.13842 -55.295292)
		(width 0.0889)
		(layer "In2.Cu")
		(net "M_C_CLK_DP<1>")
	)
	(arc
		(start 259.19176 -58.065416)
		(mid 259.184818 -58.141443)
		(end 259.163566 -58.214768)
		(width 0.0889)
		(layer "In2.Cu")
		(net "M_C_CLK_DP<1>")
	)
	(arc
		(start 259.13842 -53.314092)
		(mid 259.059289 -53.609494)
		(end 259.13842 -53.904896)
		(width 0.0889)
		(layer "In2.Cu")
		(net "M_C_CLK_DP<1>")
	)
	(arc
		(start 259.13842 -57.276492)
		(mid 259.059289 -57.571894)
		(end 259.13842 -57.867296)
		(width 0.0889)
		(layer "In2.Cu")
		(net "M_C_CLK_DP<1>")
	)
	(arc
		(start 259.13842 -57.867296)
		(mid 259.177996 -57.962881)
		(end 259.19176 -58.065416)
		(width 0.0889)
		(layer "In2.Cu")
		(net "M_C_CLK_DP<1>")
	)
	(arc
		(start 259.13842 -56.876696)
		(mid 259.191919 -57.076594)
		(end 259.13842 -57.276492)
		(width 0.0889)
		(layer "In2.Cu")
		(net "M_C_CLK_DP<1>")
	)
	(arc
		(start 259.13842 -53.904896)
		(mid 259.191919 -54.104794)
		(end 259.13842 -54.304692)
		(width 0.0889)
		(layer "In2.Cu")
		(net "M_C_CLK_DP<1>")
	)
	(arc
		(start 259.13842 -52.914296)
		(mid 259.191919 -53.114194)
		(end 259.13842 -53.314092)
		(width 0.0889)
		(layer "In2.Cu")
		(net "M_C_CLK_DP<1>")
	)
	(arc
		(start 259.13842 -54.304692)
		(mid 259.059289 -54.600094)
		(end 259.13842 -54.895496)
		(width 0.0889)
		(layer "In2.Cu")
		(net "M_C_CLK_DP<1>")
	)
	(segment
		(start 257.64617 -60.047886)
		(end 257.07467 -60.047886)
		(width 0.1016)
		(layer "F.Cu")
		(net "M_C_CLK_DP<2>")
	)
	(via
		(at 257.11658 -4.321556)
		(size 0.508)
		(drill 0.254)
		(layers "F.Cu" "B.Cu")
		(net "M_C_CLK_DP<2>")
	)
	(via
		(at 257.07467 -60.047886)
		(size 0.508)
		(drill 0.254)
		(layers "F.Cu" "B.Cu")
		(net "M_C_CLK_DP<2>")
	)
	(segment
		(start 256.750312 -5.621782)
		(end 256.749804 -5.621782)
		(width 0.1651)
		(layer "B.Cu")
		(net "M_C_CLK_DP<2>")
	)
	(segment
		(start 256.749804 -5.207508)
		(end 257.11658 -4.321556)
		(width 0.1651)
		(layer "B.Cu")
		(net "M_C_CLK_DP<2>")
	)
	(segment
		(start 256.749804 -5.621782)
		(end 256.749804 -5.207508)
		(width 0.1651)
		(layer "B.Cu")
		(net "M_C_CLK_DP<2>")
	)
	(segment
		(start 260.51256 -13.18514)
		(end 260.51256 -11.10996)
		(width 0.14224)
		(layer "In2.Cu")
		(net "M_C_CLK_DP<2>")
	)
	(segment
		(start 259.007864 -21.337778)
		(end 258.20878 -21.337778)
		(width 0.14224)
		(layer "In2.Cu")
		(net "M_C_CLK_DP<2>")
	)
	(segment
		(start 258.200652 -52.18684)
		(end 258.3561 -52.031392)
		(width 0.0889)
		(layer "In2.Cu")
		(net "M_C_CLK_DP<2>")
	)
	(segment
		(start 257.326892 -4.531868)
		(end 257.11658 -4.321556)
		(width 0.14224)
		(layer "In2.Cu")
		(net "M_C_CLK_DP<2>")
	)
	(segment
		(start 257.326892 -5.01904)
		(end 257.326892 -4.531868)
		(width 0.14224)
		(layer "In2.Cu")
		(net "M_C_CLK_DP<2>")
	)
	(segment
		(start 259.94868 -10.54608)
		(end 259.94868 -6.181344)
		(width 0.14224)
		(layer "In2.Cu")
		(net "M_C_CLK_DP<2>")
	)
	(segment
		(start 259.162804 -47.926752)
		(end 259.162804 -21.492718)
		(width 0.14224)
		(layer "In2.Cu")
		(net "M_C_CLK_DP<2>")
	)
	(segment
		(start 259.162804 -47.937928)
		(end 259.162804 -47.926752)
		(width 0.0889)
		(layer "In2.Cu")
		(net "M_C_CLK_DP<2>")
	)
	(segment
		(start 257.903726 -21.032724)
		(end 257.903726 -20.456144)
		(width 0.14224)
		(layer "In2.Cu")
		(net "M_C_CLK_DP<2>")
	)
	(segment
		(start 259.94868 -13.74902)
		(end 260.51256 -13.18514)
		(width 0.14224)
		(layer "In2.Cu")
		(net "M_C_CLK_DP<2>")
	)
	(segment
		(start 258.20878 -21.337778)
		(end 257.903726 -21.032724)
		(width 0.14224)
		(layer "In2.Cu")
		(net "M_C_CLK_DP<2>")
	)
	(segment
		(start 259.94868 -14.90472)
		(end 259.94868 -13.74902)
		(width 0.14224)
		(layer "In2.Cu")
		(net "M_C_CLK_DP<2>")
	)
	(segment
		(start 258.3561 -52.031392)
		(end 258.3561 -51.533044)
		(width 0.0889)
		(layer "In2.Cu")
		(net "M_C_CLK_DP<2>")
	)
	(segment
		(start 257.07467 -60.047886)
		(end 257.188462 -59.93384)
		(width 0.0889)
		(layer "In2.Cu")
		(net "M_C_CLK_DP<2>")
	)
	(segment
		(start 259.202174 -50.68697)
		(end 259.202174 -47.977298)
		(width 0.0889)
		(layer "In2.Cu")
		(net "M_C_CLK_DP<2>")
	)
	(segment
		(start 257.611372 -5.30352)
		(end 257.326892 -5.01904)
		(width 0.14224)
		(layer "In2.Cu")
		(net "M_C_CLK_DP<2>")
	)
	(segment
		(start 258.223512 -20.136358)
		(end 259.007864 -20.136358)
		(width 0.14224)
		(layer "In2.Cu")
		(net "M_C_CLK_DP<2>")
	)
	(segment
		(start 259.202174 -47.977298)
		(end 259.162804 -47.937928)
		(width 0.0889)
		(layer "In2.Cu")
		(net "M_C_CLK_DP<2>")
	)
	(segment
		(start 257.903726 -20.456144)
		(end 258.223512 -20.136358)
		(width 0.14224)
		(layer "In2.Cu")
		(net "M_C_CLK_DP<2>")
	)
	(segment
		(start 258.200652 -54.097682)
		(end 258.200652 -52.18684)
		(width 0.0889)
		(layer "In2.Cu")
		(net "M_C_CLK_DP<2>")
	)
	(segment
		(start 259.162804 -15.690596)
		(end 259.94868 -14.90472)
		(width 0.14224)
		(layer "In2.Cu")
		(net "M_C_CLK_DP<2>")
	)
	(segment
		(start 258.3561 -51.533044)
		(end 259.202174 -50.68697)
		(width 0.0889)
		(layer "In2.Cu")
		(net "M_C_CLK_DP<2>")
	)
	(segment
		(start 259.94868 -6.181344)
		(end 259.070856 -5.30352)
		(width 0.14224)
		(layer "In2.Cu")
		(net "M_C_CLK_DP<2>")
	)
	(segment
		(start 259.162804 -19.981418)
		(end 259.162804 -15.690596)
		(width 0.14224)
		(layer "In2.Cu")
		(net "M_C_CLK_DP<2>")
	)
	(segment
		(start 260.51256 -11.10996)
		(end 259.94868 -10.54608)
		(width 0.14224)
		(layer "In2.Cu")
		(net "M_C_CLK_DP<2>")
	)
	(segment
		(start 257.9116 -58.962544)
		(end 257.944366 -58.962544)
		(width 0.0889)
		(layer "In2.Cu")
		(net "M_C_CLK_DP<2>")
	)
	(segment
		(start 259.162804 -21.492718)
		(end 259.007864 -21.337778)
		(width 0.14224)
		(layer "In2.Cu")
		(net "M_C_CLK_DP<2>")
	)
	(segment
		(start 259.070856 -5.30352)
		(end 257.611372 -5.30352)
		(width 0.14224)
		(layer "In2.Cu")
		(net "M_C_CLK_DP<2>")
	)
	(segment
		(start 259.007864 -20.136358)
		(end 259.162804 -19.981418)
		(width 0.14224)
		(layer "In2.Cu")
		(net "M_C_CLK_DP<2>")
	)
	(arc
		(start 258.2799 -56.381396)
		(mid 258.200769 -56.085994)
		(end 258.2799 -55.790592)
		(width 0.0889)
		(layer "In2.Cu")
		(net "M_C_CLK_DP<2>")
	)
	(arc
		(start 258.2799 -55.790592)
		(mid 258.333399 -55.590694)
		(end 258.2799 -55.390796)
		(width 0.0889)
		(layer "In2.Cu")
		(net "M_C_CLK_DP<2>")
	)
	(arc
		(start 258.2799 -57.371996)
		(mid 258.200769 -57.076594)
		(end 258.2799 -56.781192)
		(width 0.0889)
		(layer "In2.Cu")
		(net "M_C_CLK_DP<2>")
	)
	(arc
		(start 258.2799 -54.799992)
		(mid 258.333399 -54.600094)
		(end 258.2799 -54.400196)
		(width 0.0889)
		(layer "In2.Cu")
		(net "M_C_CLK_DP<2>")
	)
	(arc
		(start 258.2799 -56.781192)
		(mid 258.333399 -56.581294)
		(end 258.2799 -56.381396)
		(width 0.0889)
		(layer "In2.Cu")
		(net "M_C_CLK_DP<2>")
	)
	(arc
		(start 258.2799 -58.362596)
		(mid 258.200769 -58.067194)
		(end 258.2799 -57.771792)
		(width 0.0889)
		(layer "In2.Cu")
		(net "M_C_CLK_DP<2>")
	)
	(arc
		(start 257.188462 -59.93384)
		(mid 257.302153 -59.763829)
		(end 257.342132 -59.563254)
		(width 0.0889)
		(layer "In2.Cu")
		(net "M_C_CLK_DP<2>")
	)
	(arc
		(start 258.2799 -55.390796)
		(mid 258.200769 -55.095394)
		(end 258.2799 -54.799992)
		(width 0.0889)
		(layer "In2.Cu")
		(net "M_C_CLK_DP<2>")
	)
	(arc
		(start 257.944366 -58.962544)
		(mid 258.282481 -58.757842)
		(end 258.2799 -58.362596)
		(width 0.0889)
		(layer "In2.Cu")
		(net "M_C_CLK_DP<2>")
	)
	(arc
		(start 258.2799 -57.771792)
		(mid 258.333399 -57.571894)
		(end 258.2799 -57.371996)
		(width 0.0889)
		(layer "In2.Cu")
		(net "M_C_CLK_DP<2>")
	)
	(arc
		(start 257.342132 -59.563254)
		(mid 257.50411 -59.14647)
		(end 257.9116 -58.962544)
		(width 0.0889)
		(layer "In2.Cu")
		(net "M_C_CLK_DP<2>")
	)
	(arc
		(start 258.2799 -54.400196)
		(mid 258.219922 -54.254273)
		(end 258.200652 -54.097682)
		(width 0.0889)
		(layer "In2.Cu")
		(net "M_C_CLK_DP<2>")
	)
	(segment
		(start 256.750312 3.778758)
		(end 256.749804 3.778758)
		(width 0.1651)
		(layer "F.Cu")
		(net "M_C_CLK_DP<0>")
	)
	(segment
		(start 259.36321 -60.047886)
		(end 258.79171 -60.047886)
		(width 0.1016)
		(layer "F.Cu")
		(net "M_C_CLK_DP<0>")
	)
	(segment
		(start 256.749804 3.778758)
		(end 256.749804 2.485644)
		(width 0.1651)
		(layer "F.Cu")
		(net "M_C_CLK_DP<0>")
	)
	(via
		(at 256.749804 2.485644)
		(size 0.508)
		(drill 0.254)
		(layers "F.Cu" "B.Cu")
		(net "M_C_CLK_DP<0>")
	)
	(via
		(at 258.79171 -60.047886)
		(size 0.508)
		(drill 0.254)
		(layers "F.Cu" "B.Cu")
		(net "M_C_CLK_DP<0>")
	)
	(segment
		(start 260.4516 -1.143)
		(end 259.8166 -0.508)
		(width 0.14224)
		(layer "In2.Cu")
		(net "M_C_CLK_DP<0>")
	)
	(segment
		(start 259.8166 -0.508)
		(end 259.8166 0.611378)
		(width 0.14224)
		(layer "In2.Cu")
		(net "M_C_CLK_DP<0>")
	)
	(segment
		(start 259.62864 -58.962544)
		(end 259.661406 -58.962544)
		(width 0.0889)
		(layer "In2.Cu")
		(net "M_C_CLK_DP<0>")
	)
	(segment
		(start 258.79171 -60.047886)
		(end 258.905502 -59.93384)
		(width 0.0889)
		(layer "In2.Cu")
		(net "M_C_CLK_DP<0>")
	)
	(segment
		(start 259.004308 1.42367)
		(end 257.406902 1.42367)
		(width 0.14224)
		(layer "In2.Cu")
		(net "M_C_CLK_DP<0>")
	)
	(segment
		(start 257.406902 1.42367)
		(end 257.021076 1.809496)
		(width 0.14224)
		(layer "In2.Cu")
		(net "M_C_CLK_DP<0>")
	)
	(segment
		(start 260.851904 -48.082708)
		(end 260.851904 -27.509216)
		(width 0.14224)
		(layer "In2.Cu")
		(net "M_C_CLK_DP<0>")
	)
	(segment
		(start 261.90448 -26.45664)
		(end 261.90448 -20.39112)
		(width 0.14224)
		(layer "In2.Cu")
		(net "M_C_CLK_DP<0>")
	)
	(segment
		(start 262.2296 -1.915414)
		(end 261.457186 -1.143)
		(width 0.14224)
		(layer "In2.Cu")
		(net "M_C_CLK_DP<0>")
	)
	(segment
		(start 262.5344 -11.3792)
		(end 262.5344 -10.27684)
		(width 0.14224)
		(layer "In2.Cu")
		(net "M_C_CLK_DP<0>")
	)
	(segment
		(start 260.4897 -51.254406)
		(end 260.4897 -48.891444)
		(width 0.0889)
		(layer "In2.Cu")
		(net "M_C_CLK_DP<0>")
	)
	(segment
		(start 259.907024 -51.837082)
		(end 260.4897 -51.254406)
		(width 0.0889)
		(layer "In2.Cu")
		(net "M_C_CLK_DP<0>")
	)
	(segment
		(start 259.99694 -52.418996)
		(end 259.907024 -52.269898)
		(width 0.0889)
		(layer "In2.Cu")
		(net "M_C_CLK_DP<0>")
	)
	(segment
		(start 262.21436 -11.69924)
		(end 262.5344 -11.3792)
		(width 0.14224)
		(layer "In2.Cu")
		(net "M_C_CLK_DP<0>")
	)
	(segment
		(start 257.021076 1.809496)
		(end 257.021076 2.214372)
		(width 0.14224)
		(layer "In2.Cu")
		(net "M_C_CLK_DP<0>")
	)
	(segment
		(start 260.4897 -48.891444)
		(end 260.891274 -48.48987)
		(width 0.0889)
		(layer "In2.Cu")
		(net "M_C_CLK_DP<0>")
	)
	(segment
		(start 262.5344 -10.27684)
		(end 262.2296 -9.97204)
		(width 0.14224)
		(layer "In2.Cu")
		(net "M_C_CLK_DP<0>")
	)
	(segment
		(start 259.907024 -52.269898)
		(end 259.907024 -51.837082)
		(width 0.0889)
		(layer "In2.Cu")
		(net "M_C_CLK_DP<0>")
	)
	(segment
		(start 260.891274 -48.48987)
		(end 260.891274 -48.144176)
		(width 0.0889)
		(layer "In2.Cu")
		(net "M_C_CLK_DP<0>")
	)
	(segment
		(start 262.21436 -20.08124)
		(end 262.21436 -11.69924)
		(width 0.14224)
		(layer "In2.Cu")
		(net "M_C_CLK_DP<0>")
	)
	(segment
		(start 261.90448 -20.39112)
		(end 262.21436 -20.08124)
		(width 0.14224)
		(layer "In2.Cu")
		(net "M_C_CLK_DP<0>")
	)
	(segment
		(start 261.457186 -1.143)
		(end 260.4516 -1.143)
		(width 0.14224)
		(layer "In2.Cu")
		(net "M_C_CLK_DP<0>")
	)
	(segment
		(start 259.8166 0.611378)
		(end 259.004308 1.42367)
		(width 0.14224)
		(layer "In2.Cu")
		(net "M_C_CLK_DP<0>")
	)
	(segment
		(start 260.851904 -48.104806)
		(end 260.851904 -48.082708)
		(width 0.0889)
		(layer "In2.Cu")
		(net "M_C_CLK_DP<0>")
	)
	(segment
		(start 262.2296 -9.97204)
		(end 262.2296 -1.915414)
		(width 0.14224)
		(layer "In2.Cu")
		(net "M_C_CLK_DP<0>")
	)
	(segment
		(start 260.851904 -27.509216)
		(end 261.90448 -26.45664)
		(width 0.14224)
		(layer "In2.Cu")
		(net "M_C_CLK_DP<0>")
	)
	(segment
		(start 257.021076 2.214372)
		(end 256.749804 2.485644)
		(width 0.14224)
		(layer "In2.Cu")
		(net "M_C_CLK_DP<0>")
	)
	(segment
		(start 260.891274 -48.144176)
		(end 260.851904 -48.104806)
		(width 0.0889)
		(layer "In2.Cu")
		(net "M_C_CLK_DP<0>")
	)
	(arc
		(start 259.99694 -56.381396)
		(mid 259.917809 -56.085994)
		(end 259.99694 -55.790592)
		(width 0.0889)
		(layer "In2.Cu")
		(net "M_C_CLK_DP<0>")
	)
	(arc
		(start 259.99694 -56.781192)
		(mid 260.050439 -56.581294)
		(end 259.99694 -56.381396)
		(width 0.0889)
		(layer "In2.Cu")
		(net "M_C_CLK_DP<0>")
	)
	(arc
		(start 259.99694 -54.400196)
		(mid 259.917809 -54.104794)
		(end 259.99694 -53.809392)
		(width 0.0889)
		(layer "In2.Cu")
		(net "M_C_CLK_DP<0>")
	)
	(arc
		(start 259.99694 -57.771792)
		(mid 260.050439 -57.571894)
		(end 259.99694 -57.371996)
		(width 0.0889)
		(layer "In2.Cu")
		(net "M_C_CLK_DP<0>")
	)
	(arc
		(start 259.99694 -57.371996)
		(mid 259.917809 -57.076594)
		(end 259.99694 -56.781192)
		(width 0.0889)
		(layer "In2.Cu")
		(net "M_C_CLK_DP<0>")
	)
	(arc
		(start 259.99694 -58.362596)
		(mid 259.917809 -58.067194)
		(end 259.99694 -57.771792)
		(width 0.0889)
		(layer "In2.Cu")
		(net "M_C_CLK_DP<0>")
	)
	(arc
		(start 259.99694 -53.409596)
		(mid 259.917809 -53.114194)
		(end 259.99694 -52.818792)
		(width 0.0889)
		(layer "In2.Cu")
		(net "M_C_CLK_DP<0>")
	)
	(arc
		(start 258.905502 -59.93384)
		(mid 259.019193 -59.763829)
		(end 259.059172 -59.563254)
		(width 0.0889)
		(layer "In2.Cu")
		(net "M_C_CLK_DP<0>")
	)
	(arc
		(start 259.99694 -53.809392)
		(mid 260.050439 -53.609494)
		(end 259.99694 -53.409596)
		(width 0.0889)
		(layer "In2.Cu")
		(net "M_C_CLK_DP<0>")
	)
	(arc
		(start 259.99694 -52.818792)
		(mid 260.050439 -52.618894)
		(end 259.99694 -52.418996)
		(width 0.0889)
		(layer "In2.Cu")
		(net "M_C_CLK_DP<0>")
	)
	(arc
		(start 259.99694 -55.790592)
		(mid 260.050439 -55.590694)
		(end 259.99694 -55.390796)
		(width 0.0889)
		(layer "In2.Cu")
		(net "M_C_CLK_DP<0>")
	)
	(arc
		(start 259.661406 -58.962544)
		(mid 259.999521 -58.757842)
		(end 259.99694 -58.362596)
		(width 0.0889)
		(layer "In2.Cu")
		(net "M_C_CLK_DP<0>")
	)
	(arc
		(start 259.99694 -54.799992)
		(mid 260.050439 -54.600094)
		(end 259.99694 -54.400196)
		(width 0.0889)
		(layer "In2.Cu")
		(net "M_C_CLK_DP<0>")
	)
	(arc
		(start 259.99694 -55.390796)
		(mid 259.917809 -55.095394)
		(end 259.99694 -54.799992)
		(width 0.0889)
		(layer "In2.Cu")
		(net "M_C_CLK_DP<0>")
	)
	(arc
		(start 259.059172 -59.563254)
		(mid 259.22115 -59.14647)
		(end 259.62864 -58.962544)
		(width 0.0889)
		(layer "In2.Cu")
		(net "M_C_CLK_DP<0>")
	)
	(segment
		(start 258.50469 -58.561986)
		(end 257.93319 -58.561986)
		(width 0.1016)
		(layer "F.Cu")
		(net "M_C_CLK_DN<3>")
	)
	(via
		(at 257.93319 -58.561986)
		(size 0.508)
		(drill 0.254)
		(layers "F.Cu" "B.Cu")
		(net "M_C_CLK_DN<3>")
	)
	(via
		(at 257.599942 -2.314956)
		(size 0.508)
		(drill 0.254)
		(layers "F.Cu" "B.Cu")
		(net "M_C_CLK_DN<3>")
	)
	(segment
		(start 257.60045 -1.021842)
		(end 257.599942 -1.021842)
		(width 0.1651)
		(layer "B.Cu")
		(net "M_C_CLK_DN<3>")
	)
	(segment
		(start 257.599942 -1.021842)
		(end 257.599942 -2.314956)
		(width 0.1651)
		(layer "B.Cu")
		(net "M_C_CLK_DN<3>")
	)
	(segment
		(start 258.593844 -49.861724)
		(end 258.593844 -49.839626)
		(width 0.0889)
		(layer "In2.Cu")
		(net "M_C_CLK_DN<3>")
	)
	(segment
		(start 258.593844 -49.839626)
		(end 258.593844 -26.06421)
		(width 0.14224)
		(layer "In2.Cu")
		(net "M_C_CLK_DN<3>")
	)
	(segment
		(start 259.9944 -11.557)
		(end 259.32892 -10.89152)
		(width 0.14224)
		(layer "In2.Cu")
		(net "M_C_CLK_DN<3>")
	)
	(segment
		(start 258.808982 -6.17728)
		(end 257.500628 -6.17728)
		(width 0.14224)
		(layer "In2.Cu")
		(net "M_C_CLK_DN<3>")
	)
	(segment
		(start 258.593844 -26.06421)
		(end 256.625852 -24.096218)
		(width 0.14224)
		(layer "In2.Cu")
		(net "M_C_CLK_DN<3>")
	)
	(segment
		(start 257.048 -21.455634)
		(end 257.048 -18.3134)
		(width 0.14224)
		(layer "In2.Cu")
		(net "M_C_CLK_DN<3>")
	)
	(segment
		(start 259.32892 -13.65758)
		(end 259.9944 -12.9921)
		(width 0.14224)
		(layer "In2.Cu")
		(net "M_C_CLK_DN<3>")
	)
	(segment
		(start 257.72364 -15.96136)
		(end 259.32892 -14.35608)
		(width 0.14224)
		(layer "In2.Cu")
		(net "M_C_CLK_DN<3>")
	)
	(segment
		(start 257.58648 -54.400196)
		(end 257.717798 -54.173374)
		(width 0.0889)
		(layer "In2.Cu")
		(net "M_C_CLK_DN<3>")
	)
	(segment
		(start 256.625852 -21.877782)
		(end 257.048 -21.455634)
		(width 0.14224)
		(layer "In2.Cu")
		(net "M_C_CLK_DN<3>")
	)
	(segment
		(start 257.717798 -54.173374)
		(end 257.717798 -52.054506)
		(width 0.0889)
		(layer "In2.Cu")
		(net "M_C_CLK_DN<3>")
	)
	(segment
		(start 256.68351 -5.360162)
		(end 256.68351 -3.942842)
		(width 0.14224)
		(layer "In2.Cu")
		(net "M_C_CLK_DN<3>")
	)
	(segment
		(start 259.32892 -14.35608)
		(end 259.32892 -13.65758)
		(width 0.14224)
		(layer "In2.Cu")
		(net "M_C_CLK_DN<3>")
	)
	(segment
		(start 258.554474 -49.901094)
		(end 258.593844 -49.861724)
		(width 0.0889)
		(layer "In2.Cu")
		(net "M_C_CLK_DN<3>")
	)
	(segment
		(start 257.72364 -17.63776)
		(end 257.72364 -15.96136)
		(width 0.14224)
		(layer "In2.Cu")
		(net "M_C_CLK_DN<3>")
	)
	(segment
		(start 259.32892 -6.697218)
		(end 258.808982 -6.17728)
		(width 0.14224)
		(layer "In2.Cu")
		(net "M_C_CLK_DN<3>")
	)
	(segment
		(start 256.68351 -3.942842)
		(end 257.290316 -3.336036)
		(width 0.14224)
		(layer "In2.Cu")
		(net "M_C_CLK_DN<3>")
	)
	(segment
		(start 257.521964 -51.40706)
		(end 258.554474 -50.37455)
		(width 0.0889)
		(layer "In2.Cu")
		(net "M_C_CLK_DN<3>")
	)
	(segment
		(start 257.93319 -58.561986)
		(end 257.828288 -58.457084)
		(width 0.0889)
		(layer "In2.Cu")
		(net "M_C_CLK_DN<3>")
	)
	(segment
		(start 257.717798 -52.054506)
		(end 257.521964 -51.716432)
		(width 0.0889)
		(layer "In2.Cu")
		(net "M_C_CLK_DN<3>")
	)
	(segment
		(start 257.521964 -51.716432)
		(end 257.521964 -51.40706)
		(width 0.0889)
		(layer "In2.Cu")
		(net "M_C_CLK_DN<3>")
	)
	(segment
		(start 256.625852 -24.096218)
		(end 256.625852 -21.877782)
		(width 0.14224)
		(layer "In2.Cu")
		(net "M_C_CLK_DN<3>")
	)
	(segment
		(start 257.290316 -3.336036)
		(end 257.290316 -2.624582)
		(width 0.14224)
		(layer "In2.Cu")
		(net "M_C_CLK_DN<3>")
	)
	(segment
		(start 259.9944 -12.9921)
		(end 259.9944 -11.557)
		(width 0.14224)
		(layer "In2.Cu")
		(net "M_C_CLK_DN<3>")
	)
	(segment
		(start 257.500628 -6.17728)
		(end 256.68351 -5.360162)
		(width 0.14224)
		(layer "In2.Cu")
		(net "M_C_CLK_DN<3>")
	)
	(segment
		(start 259.32892 -10.89152)
		(end 259.32892 -6.697218)
		(width 0.14224)
		(layer "In2.Cu")
		(net "M_C_CLK_DN<3>")
	)
	(segment
		(start 258.554474 -50.37455)
		(end 258.554474 -49.901094)
		(width 0.0889)
		(layer "In2.Cu")
		(net "M_C_CLK_DN<3>")
	)
	(segment
		(start 257.048 -18.3134)
		(end 257.72364 -17.63776)
		(width 0.14224)
		(layer "In2.Cu")
		(net "M_C_CLK_DN<3>")
	)
	(segment
		(start 257.290316 -2.624582)
		(end 257.599942 -2.314956)
		(width 0.14224)
		(layer "In2.Cu")
		(net "M_C_CLK_DN<3>")
	)
	(arc
		(start 257.58648 -56.781192)
		(mid 257.532981 -56.581294)
		(end 257.58648 -56.381396)
		(width 0.0889)
		(layer "In2.Cu")
		(net "M_C_CLK_DN<3>")
	)
	(arc
		(start 257.58648 -54.799992)
		(mid 257.532981 -54.600094)
		(end 257.58648 -54.400196)
		(width 0.0889)
		(layer "In2.Cu")
		(net "M_C_CLK_DN<3>")
	)
	(arc
		(start 257.58648 -56.381396)
		(mid 257.665611 -56.085994)
		(end 257.58648 -55.790592)
		(width 0.0889)
		(layer "In2.Cu")
		(net "M_C_CLK_DN<3>")
	)
	(arc
		(start 257.58648 -55.390796)
		(mid 257.665611 -55.095394)
		(end 257.58648 -54.799992)
		(width 0.0889)
		(layer "In2.Cu")
		(net "M_C_CLK_DN<3>")
	)
	(arc
		(start 257.58648 -57.771792)
		(mid 257.532981 -57.571894)
		(end 257.58648 -57.371996)
		(width 0.0889)
		(layer "In2.Cu")
		(net "M_C_CLK_DN<3>")
	)
	(arc
		(start 257.828288 -58.457084)
		(mid 257.707983 -58.277036)
		(end 257.665728 -58.064654)
		(width 0.0889)
		(layer "In2.Cu")
		(net "M_C_CLK_DN<3>")
	)
	(arc
		(start 257.58648 -55.790592)
		(mid 257.532981 -55.590694)
		(end 257.58648 -55.390796)
		(width 0.0889)
		(layer "In2.Cu")
		(net "M_C_CLK_DN<3>")
	)
	(arc
		(start 257.58648 -57.371996)
		(mid 257.665611 -57.076594)
		(end 257.58648 -56.781192)
		(width 0.0889)
		(layer "In2.Cu")
		(net "M_C_CLK_DN<3>")
	)
	(arc
		(start 257.665728 -58.064654)
		(mid 257.645213 -57.913052)
		(end 257.58648 -57.771792)
		(width 0.0889)
		(layer "In2.Cu")
		(net "M_C_CLK_DN<3>")
	)
	(segment
		(start 257.599942 -0.821182)
		(end 257.599942 0.471932)
		(width 0.1651)
		(layer "F.Cu")
		(net "M_C_CLK_DN<1>")
	)
	(segment
		(start 257.60045 -0.821182)
		(end 257.599942 -0.821182)
		(width 0.1651)
		(layer "F.Cu")
		(net "M_C_CLK_DN<1>")
	)
	(segment
		(start 260.22173 -58.561986)
		(end 259.65023 -58.561986)
		(width 0.1016)
		(layer "F.Cu")
		(net "M_C_CLK_DN<1>")
	)
	(via
		(at 259.65023 -58.561986)
		(size 0.508)
		(drill 0.254)
		(layers "F.Cu" "B.Cu")
		(net "M_C_CLK_DN<1>")
	)
	(via
		(at 257.599942 0.471932)
		(size 0.508)
		(drill 0.254)
		(layers "F.Cu" "B.Cu")
		(net "M_C_CLK_DN<1>")
	)
	(segment
		(start 258.097782 -1.359662)
		(end 258.097782 -0.31115)
		(width 0.14224)
		(layer "In2.Cu")
		(net "M_C_CLK_DN<1>")
	)
	(segment
		(start 260.282944 -48.059086)
		(end 260.282944 -48.081184)
		(width 0.0889)
		(layer "In2.Cu")
		(net "M_C_CLK_DN<1>")
	)
	(segment
		(start 257.290316 -0.424434)
		(end 256.956052 -0.758698)
		(width 0.14224)
		(layer "In2.Cu")
		(net "M_C_CLK_DN<1>")
	)
	(segment
		(start 260.072124 -51.014376)
		(end 259.32892 -51.75758)
		(width 0.0889)
		(layer "In2.Cu")
		(net "M_C_CLK_DN<1>")
	)
	(segment
		(start 257.900678 -1.556766)
		(end 258.097782 -1.359662)
		(width 0.14224)
		(layer "In2.Cu")
		(net "M_C_CLK_DN<1>")
	)
	(segment
		(start 259.32892 -52.374546)
		(end 259.30352 -52.418742)
		(width 0.0889)
		(layer "In2.Cu")
		(net "M_C_CLK_DN<1>")
	)
	(segment
		(start 260.282944 -48.081184)
		(end 260.237224 -48.126904)
		(width 0.0889)
		(layer "In2.Cu")
		(net "M_C_CLK_DN<1>")
	)
	(segment
		(start 259.00126 0.002032)
		(end 259.314188 -0.310896)
		(width 0.14224)
		(layer "In2.Cu")
		(net "M_C_CLK_DN<1>")
	)
	(segment
		(start 255.944116 -0.908558)
		(end 255.944116 -1.390904)
		(width 0.14224)
		(layer "In2.Cu")
		(net "M_C_CLK_DN<1>")
	)
	(segment
		(start 260.706108 -2.247646)
		(end 261.227316 -2.768854)
		(width 0.14224)
		(layer "In2.Cu")
		(net "M_C_CLK_DN<1>")
	)
	(segment
		(start 259.30352 -52.819046)
		(end 259.30352 -52.818792)
		(width 0.0889)
		(layer "In2.Cu")
		(net "M_C_CLK_DN<1>")
	)
	(segment
		(start 260.237224 -48.575468)
		(end 260.072124 -48.740568)
		(width 0.0889)
		(layer "In2.Cu")
		(net "M_C_CLK_DN<1>")
	)
	(segment
		(start 261.227316 -10.402316)
		(end 261.493 -10.668)
		(width 0.14224)
		(layer "In2.Cu")
		(net "M_C_CLK_DN<1>")
	)
	(segment
		(start 259.32892 -51.75758)
		(end 259.32892 -52.374546)
		(width 0.0889)
		(layer "In2.Cu")
		(net "M_C_CLK_DN<1>")
	)
	(segment
		(start 257.290316 0.162306)
		(end 257.290316 -0.424434)
		(width 0.14224)
		(layer "In2.Cu")
		(net "M_C_CLK_DN<1>")
	)
	(segment
		(start 260.333236 -2.247646)
		(end 260.706108 -2.247646)
		(width 0.14224)
		(layer "In2.Cu")
		(net "M_C_CLK_DN<1>")
	)
	(segment
		(start 261.227316 -26.066242)
		(end 260.282944 -27.010614)
		(width 0.14224)
		(layer "In2.Cu")
		(net "M_C_CLK_DN<1>")
	)
	(segment
		(start 259.314188 -1.228598)
		(end 260.333236 -2.247646)
		(width 0.14224)
		(layer "In2.Cu")
		(net "M_C_CLK_DN<1>")
	)
	(segment
		(start 261.227316 -2.768854)
		(end 261.227316 -10.402316)
		(width 0.14224)
		(layer "In2.Cu")
		(net "M_C_CLK_DN<1>")
	)
	(segment
		(start 260.237224 -48.126904)
		(end 260.237224 -48.575468)
		(width 0.0889)
		(layer "In2.Cu")
		(net "M_C_CLK_DN<1>")
	)
	(segment
		(start 256.956052 -0.758698)
		(end 256.093976 -0.758698)
		(width 0.14224)
		(layer "In2.Cu")
		(net "M_C_CLK_DN<1>")
	)
	(segment
		(start 261.493 -13.8684)
		(end 261.227316 -14.134084)
		(width 0.14224)
		(layer "In2.Cu")
		(net "M_C_CLK_DN<1>")
	)
	(segment
		(start 260.282944 -27.010614)
		(end 260.282944 -48.059086)
		(width 0.14224)
		(layer "In2.Cu")
		(net "M_C_CLK_DN<1>")
	)
	(segment
		(start 260.072124 -48.740568)
		(end 260.072124 -51.014376)
		(width 0.0889)
		(layer "In2.Cu")
		(net "M_C_CLK_DN<1>")
	)
	(segment
		(start 257.599942 0.471932)
		(end 257.290316 0.162306)
		(width 0.14224)
		(layer "In2.Cu")
		(net "M_C_CLK_DN<1>")
	)
	(segment
		(start 261.493 -10.668)
		(end 261.493 -13.8684)
		(width 0.14224)
		(layer "In2.Cu")
		(net "M_C_CLK_DN<1>")
	)
	(segment
		(start 256.109978 -1.556766)
		(end 257.900678 -1.556766)
		(width 0.14224)
		(layer "In2.Cu")
		(net "M_C_CLK_DN<1>")
	)
	(segment
		(start 258.097782 -0.31115)
		(end 258.410964 0.002032)
		(width 0.14224)
		(layer "In2.Cu")
		(net "M_C_CLK_DN<1>")
	)
	(segment
		(start 259.545328 -58.457084)
		(end 259.65023 -58.561986)
		(width 0.0889)
		(layer "In2.Cu")
		(net "M_C_CLK_DN<1>")
	)
	(segment
		(start 259.314188 -0.310896)
		(end 259.314188 -1.228598)
		(width 0.14224)
		(layer "In2.Cu")
		(net "M_C_CLK_DN<1>")
	)
	(segment
		(start 261.227316 -14.134084)
		(end 261.227316 -26.066242)
		(width 0.14224)
		(layer "In2.Cu")
		(net "M_C_CLK_DN<1>")
	)
	(segment
		(start 256.093976 -0.758698)
		(end 255.944116 -0.908558)
		(width 0.14224)
		(layer "In2.Cu")
		(net "M_C_CLK_DN<1>")
	)
	(segment
		(start 255.944116 -1.390904)
		(end 256.109978 -1.556766)
		(width 0.14224)
		(layer "In2.Cu")
		(net "M_C_CLK_DN<1>")
	)
	(segment
		(start 258.410964 0.002032)
		(end 259.00126 0.002032)
		(width 0.14224)
		(layer "In2.Cu")
		(net "M_C_CLK_DN<1>")
	)
	(arc
		(start 259.30352 -53.809392)
		(mid 259.382651 -54.104794)
		(end 259.30352 -54.400196)
		(width 0.0889)
		(layer "In2.Cu")
		(net "M_C_CLK_DN<1>")
	)
	(arc
		(start 259.30352 -57.371996)
		(mid 259.250021 -57.571894)
		(end 259.30352 -57.771792)
		(width 0.0889)
		(layer "In2.Cu")
		(net "M_C_CLK_DN<1>")
	)
	(arc
		(start 259.382768 -58.064654)
		(mid 259.425014 -58.277039)
		(end 259.545328 -58.457084)
		(width 0.0889)
		(layer "In2.Cu")
		(net "M_C_CLK_DN<1>")
	)
	(arc
		(start 259.30352 -52.418742)
		(mid 259.249894 -52.618894)
		(end 259.30352 -52.819046)
		(width 0.0889)
		(layer "In2.Cu")
		(net "M_C_CLK_DN<1>")
	)
	(arc
		(start 259.30352 -53.409596)
		(mid 259.250021 -53.609494)
		(end 259.30352 -53.809392)
		(width 0.0889)
		(layer "In2.Cu")
		(net "M_C_CLK_DN<1>")
	)
	(arc
		(start 259.30352 -56.381396)
		(mid 259.250021 -56.581294)
		(end 259.30352 -56.781192)
		(width 0.0889)
		(layer "In2.Cu")
		(net "M_C_CLK_DN<1>")
	)
	(arc
		(start 259.30352 -55.390796)
		(mid 259.250021 -55.590694)
		(end 259.30352 -55.790592)
		(width 0.0889)
		(layer "In2.Cu")
		(net "M_C_CLK_DN<1>")
	)
	(arc
		(start 259.30352 -52.818792)
		(mid 259.382651 -53.114194)
		(end 259.30352 -53.409596)
		(width 0.0889)
		(layer "In2.Cu")
		(net "M_C_CLK_DN<1>")
	)
	(arc
		(start 259.30352 -57.771792)
		(mid 259.362257 -57.913051)
		(end 259.382768 -58.064654)
		(width 0.0889)
		(layer "In2.Cu")
		(net "M_C_CLK_DN<1>")
	)
	(arc
		(start 259.30352 -55.790592)
		(mid 259.382651 -56.085994)
		(end 259.30352 -56.381396)
		(width 0.0889)
		(layer "In2.Cu")
		(net "M_C_CLK_DN<1>")
	)
	(arc
		(start 259.30352 -54.799992)
		(mid 259.382651 -55.095394)
		(end 259.30352 -55.390796)
		(width 0.0889)
		(layer "In2.Cu")
		(net "M_C_CLK_DN<1>")
	)
	(arc
		(start 259.30352 -54.400196)
		(mid 259.250021 -54.600094)
		(end 259.30352 -54.799992)
		(width 0.0889)
		(layer "In2.Cu")
		(net "M_C_CLK_DN<1>")
	)
	(arc
		(start 259.30352 -56.781192)
		(mid 259.382651 -57.076594)
		(end 259.30352 -57.371996)
		(width 0.0889)
		(layer "In2.Cu")
		(net "M_C_CLK_DN<1>")
	)
	(segment
		(start 258.50469 -59.55284)
		(end 257.93319 -59.55284)
		(width 0.1016)
		(layer "F.Cu")
		(net "M_C_CLK_DN<2>")
	)
	(via
		(at 257.93319 -59.55284)
		(size 0.508)
		(drill 0.254)
		(layers "F.Cu" "B.Cu")
		(net "M_C_CLK_DN<2>")
	)
	(via
		(at 257.789426 -4.328668)
		(size 0.508)
		(drill 0.254)
		(layers "F.Cu" "B.Cu")
		(net "M_C_CLK_DN<2>")
	)
	(segment
		(start 257.599942 -5.621782)
		(end 257.599942 -4.518152)
		(width 0.1651)
		(layer "B.Cu")
		(net "M_C_CLK_DN<2>")
	)
	(segment
		(start 257.60045 -5.621782)
		(end 257.599942 -5.621782)
		(width 0.1651)
		(layer "B.Cu")
		(net "M_C_CLK_DN<2>")
	)
	(segment
		(start 257.599942 -4.518152)
		(end 257.789426 -4.328668)
		(width 0.1651)
		(layer "B.Cu")
		(net "M_C_CLK_DN<2>")
	)
	(segment
		(start 257.596132 -4.90728)
		(end 257.596132 -4.521962)
		(width 0.14224)
		(layer "In2.Cu")
		(net "M_C_CLK_DN<2>")
	)
	(segment
		(start 259.119624 -20.405598)
		(end 259.432044 -20.093178)
		(width 0.14224)
		(layer "In2.Cu")
		(net "M_C_CLK_DN<2>")
	)
	(segment
		(start 259.392674 -47.98822)
		(end 259.432044 -47.94885)
		(width 0.0889)
		(layer "In2.Cu")
		(net "M_C_CLK_DN<2>")
	)
	(segment
		(start 257.596132 -4.521962)
		(end 257.789426 -4.328668)
		(width 0.14224)
		(layer "In2.Cu")
		(net "M_C_CLK_DN<2>")
	)
	(segment
		(start 259.392674 -50.765964)
		(end 259.392674 -47.98822)
		(width 0.0889)
		(layer "In2.Cu")
		(net "M_C_CLK_DN<2>")
	)
	(segment
		(start 258.172966 -20.567904)
		(end 258.335272 -20.405598)
		(width 0.14224)
		(layer "In2.Cu")
		(net "M_C_CLK_DN<2>")
	)
	(segment
		(start 259.432044 -21.380958)
		(end 259.119624 -21.068538)
		(width 0.14224)
		(layer "In2.Cu")
		(net "M_C_CLK_DN<2>")
	)
	(segment
		(start 259.432044 -15.802356)
		(end 260.21792 -15.01648)
		(width 0.14224)
		(layer "In2.Cu")
		(net "M_C_CLK_DN<2>")
	)
	(segment
		(start 258.32054 -21.068538)
		(end 258.172966 -20.920964)
		(width 0.14224)
		(layer "In2.Cu")
		(net "M_C_CLK_DN<2>")
	)
	(segment
		(start 258.5466 -51.612038)
		(end 259.392674 -50.765964)
		(width 0.0889)
		(layer "In2.Cu")
		(net "M_C_CLK_DN<2>")
	)
	(segment
		(start 260.7818 -10.9982)
		(end 260.21792 -10.43432)
		(width 0.14224)
		(layer "In2.Cu")
		(net "M_C_CLK_DN<2>")
	)
	(segment
		(start 258.391406 -54.099968)
		(end 258.391152 -54.097682)
		(width 0.0889)
		(layer "In2.Cu")
		(net "M_C_CLK_DN<2>")
	)
	(segment
		(start 260.21792 -15.01648)
		(end 260.21792 -13.86078)
		(width 0.14224)
		(layer "In2.Cu")
		(net "M_C_CLK_DN<2>")
	)
	(segment
		(start 257.922014 -59.153044)
		(end 257.95478 -59.153044)
		(width 0.0889)
		(layer "In2.Cu")
		(net "M_C_CLK_DN<2>")
	)
	(segment
		(start 260.21792 -10.43432)
		(end 260.21792 -6.069584)
		(width 0.14224)
		(layer "In2.Cu")
		(net "M_C_CLK_DN<2>")
	)
	(segment
		(start 258.335272 -20.405598)
		(end 259.119624 -20.405598)
		(width 0.14224)
		(layer "In2.Cu")
		(net "M_C_CLK_DN<2>")
	)
	(segment
		(start 257.640074 -59.722004)
		(end 257.561334 -59.700668)
		(width 0.0889)
		(layer "In2.Cu")
		(net "M_C_CLK_DN<2>")
	)
	(segment
		(start 258.5466 -52.110386)
		(end 258.5466 -51.612038)
		(width 0.0889)
		(layer "In2.Cu")
		(net "M_C_CLK_DN<2>")
	)
	(segment
		(start 259.432044 -47.94885)
		(end 259.432044 -47.926752)
		(width 0.0889)
		(layer "In2.Cu")
		(net "M_C_CLK_DN<2>")
	)
	(segment
		(start 259.432044 -47.926752)
		(end 259.432044 -21.380958)
		(width 0.14224)
		(layer "In2.Cu")
		(net "M_C_CLK_DN<2>")
	)
	(segment
		(start 258.391152 -52.265834)
		(end 258.5466 -52.110386)
		(width 0.0889)
		(layer "In2.Cu")
		(net "M_C_CLK_DN<2>")
	)
	(segment
		(start 260.21792 -6.069584)
		(end 259.182616 -5.03428)
		(width 0.14224)
		(layer "In2.Cu")
		(net "M_C_CLK_DN<2>")
	)
	(segment
		(start 259.432044 -20.093178)
		(end 259.432044 -15.802356)
		(width 0.14224)
		(layer "In2.Cu")
		(net "M_C_CLK_DN<2>")
	)
	(segment
		(start 260.7818 -13.2969)
		(end 260.7818 -10.9982)
		(width 0.14224)
		(layer "In2.Cu")
		(net "M_C_CLK_DN<2>")
	)
	(segment
		(start 257.723132 -5.03428)
		(end 257.596132 -4.90728)
		(width 0.14224)
		(layer "In2.Cu")
		(net "M_C_CLK_DN<2>")
	)
	(segment
		(start 257.93319 -59.55284)
		(end 257.640074 -59.722004)
		(width 0.0889)
		(layer "In2.Cu")
		(net "M_C_CLK_DN<2>")
	)
	(segment
		(start 259.119624 -21.068538)
		(end 258.32054 -21.068538)
		(width 0.14224)
		(layer "In2.Cu")
		(net "M_C_CLK_DN<2>")
	)
	(segment
		(start 259.182616 -5.03428)
		(end 257.723132 -5.03428)
		(width 0.14224)
		(layer "In2.Cu")
		(net "M_C_CLK_DN<2>")
	)
	(segment
		(start 260.21792 -13.86078)
		(end 260.7818 -13.2969)
		(width 0.14224)
		(layer "In2.Cu")
		(net "M_C_CLK_DN<2>")
	)
	(segment
		(start 258.172966 -20.920964)
		(end 258.172966 -20.567904)
		(width 0.14224)
		(layer "In2.Cu")
		(net "M_C_CLK_DN<2>")
	)
	(segment
		(start 258.391152 -54.097682)
		(end 258.391152 -52.265834)
		(width 0.0889)
		(layer "In2.Cu")
		(net "M_C_CLK_DN<2>")
	)
	(arc
		(start 257.561334 -59.700668)
		(mid 257.540896 -59.631582)
		(end 257.53314 -59.559952)
		(width 0.0889)
		(layer "In2.Cu")
		(net "M_C_CLK_DN<2>")
	)
	(arc
		(start 258.445 -57.276492)
		(mid 258.391501 -57.076594)
		(end 258.445 -56.876696)
		(width 0.0889)
		(layer "In2.Cu")
		(net "M_C_CLK_DN<2>")
	)
	(arc
		(start 257.95478 -59.153044)
		(mid 258.450257 -58.848601)
		(end 258.445 -58.267092)
		(width 0.0889)
		(layer "In2.Cu")
		(net "M_C_CLK_DN<2>")
	)
	(arc
		(start 257.53314 -59.559952)
		(mid 257.643967 -59.276621)
		(end 257.922014 -59.153044)
		(width 0.0889)
		(layer "In2.Cu")
		(net "M_C_CLK_DN<2>")
	)
	(arc
		(start 258.445 -55.295292)
		(mid 258.391501 -55.095394)
		(end 258.445 -54.895496)
		(width 0.0889)
		(layer "In2.Cu")
		(net "M_C_CLK_DN<2>")
	)
	(arc
		(start 258.445 -54.895496)
		(mid 258.524131 -54.600094)
		(end 258.445 -54.304692)
		(width 0.0889)
		(layer "In2.Cu")
		(net "M_C_CLK_DN<2>")
	)
	(arc
		(start 258.445 -57.867296)
		(mid 258.524131 -57.571894)
		(end 258.445 -57.276492)
		(width 0.0889)
		(layer "In2.Cu")
		(net "M_C_CLK_DN<2>")
	)
	(arc
		(start 258.445 -56.876696)
		(mid 258.524131 -56.581294)
		(end 258.445 -56.285892)
		(width 0.0889)
		(layer "In2.Cu")
		(net "M_C_CLK_DN<2>")
	)
	(arc
		(start 258.445 -54.304692)
		(mid 258.404428 -54.205936)
		(end 258.391406 -54.099968)
		(width 0.0889)
		(layer "In2.Cu")
		(net "M_C_CLK_DN<2>")
	)
	(arc
		(start 258.445 -55.886096)
		(mid 258.524131 -55.590694)
		(end 258.445 -55.295292)
		(width 0.0889)
		(layer "In2.Cu")
		(net "M_C_CLK_DN<2>")
	)
	(arc
		(start 258.445 -58.267092)
		(mid 258.391501 -58.067194)
		(end 258.445 -57.867296)
		(width 0.0889)
		(layer "In2.Cu")
		(net "M_C_CLK_DN<2>")
	)
	(arc
		(start 258.445 -56.285892)
		(mid 258.391501 -56.085994)
		(end 258.445 -55.886096)
		(width 0.0889)
		(layer "In2.Cu")
		(net "M_C_CLK_DN<2>")
	)
	(segment
		(start 257.599942 3.778758)
		(end 257.599942 2.485644)
		(width 0.1651)
		(layer "F.Cu")
		(net "M_C_CLK_DN<0>")
	)
	(segment
		(start 257.60045 3.778758)
		(end 257.599942 3.778758)
		(width 0.1651)
		(layer "F.Cu")
		(net "M_C_CLK_DN<0>")
	)
	(segment
		(start 260.22173 -59.55284)
		(end 259.65023 -59.55284)
		(width 0.1016)
		(layer "F.Cu")
		(net "M_C_CLK_DN<0>")
	)
	(via
		(at 257.599942 2.485644)
		(size 0.508)
		(drill 0.254)
		(layers "F.Cu" "B.Cu")
		(net "M_C_CLK_DN<0>")
	)
	(via
		(at 259.65023 -59.55284)
		(size 0.508)
		(drill 0.254)
		(layers "F.Cu" "B.Cu")
		(net "M_C_CLK_DN<0>")
	)
	(segment
		(start 260.6802 -48.970438)
		(end 261.081774 -48.568864)
		(width 0.0889)
		(layer "In2.Cu")
		(net "M_C_CLK_DN<0>")
	)
	(segment
		(start 261.081774 -48.568864)
		(end 261.081774 -48.144176)
		(width 0.0889)
		(layer "In2.Cu")
		(net "M_C_CLK_DN<0>")
	)
	(segment
		(start 259.116068 1.69291)
		(end 257.518662 1.69291)
		(width 0.14224)
		(layer "In2.Cu")
		(net "M_C_CLK_DN<0>")
	)
	(segment
		(start 257.290316 1.921256)
		(end 257.290316 2.176018)
		(width 0.14224)
		(layer "In2.Cu")
		(net "M_C_CLK_DN<0>")
	)
	(segment
		(start 262.49884 -1.803654)
		(end 261.568946 -0.87376)
		(width 0.14224)
		(layer "In2.Cu")
		(net "M_C_CLK_DN<0>")
	)
	(segment
		(start 262.49884 -9.86028)
		(end 262.49884 -1.803654)
		(width 0.14224)
		(layer "In2.Cu")
		(net "M_C_CLK_DN<0>")
	)
	(segment
		(start 260.6802 -51.3334)
		(end 260.6802 -48.970438)
		(width 0.0889)
		(layer "In2.Cu")
		(net "M_C_CLK_DN<0>")
	)
	(segment
		(start 260.08584 -0.39624)
		(end 260.08584 0.723138)
		(width 0.14224)
		(layer "In2.Cu")
		(net "M_C_CLK_DN<0>")
	)
	(segment
		(start 262.17372 -20.50288)
		(end 262.4836 -20.193)
		(width 0.14224)
		(layer "In2.Cu")
		(net "M_C_CLK_DN<0>")
	)
	(segment
		(start 259.357114 -59.722004)
		(end 259.278374 -59.700668)
		(width 0.0889)
		(layer "In2.Cu")
		(net "M_C_CLK_DN<0>")
	)
	(segment
		(start 259.65023 -59.55284)
		(end 259.357114 -59.722004)
		(width 0.0889)
		(layer "In2.Cu")
		(net "M_C_CLK_DN<0>")
	)
	(segment
		(start 260.16077 -52.321714)
		(end 260.097524 -52.216812)
		(width 0.0889)
		(layer "In2.Cu")
		(net "M_C_CLK_DN<0>")
	)
	(segment
		(start 260.097524 -52.216812)
		(end 260.097524 -51.916076)
		(width 0.0889)
		(layer "In2.Cu")
		(net "M_C_CLK_DN<0>")
	)
	(segment
		(start 261.081774 -48.144176)
		(end 261.121144 -48.104806)
		(width 0.0889)
		(layer "In2.Cu")
		(net "M_C_CLK_DN<0>")
	)
	(segment
		(start 259.639054 -59.153044)
		(end 259.67182 -59.153044)
		(width 0.0889)
		(layer "In2.Cu")
		(net "M_C_CLK_DN<0>")
	)
	(segment
		(start 260.08584 0.723138)
		(end 259.116068 1.69291)
		(width 0.14224)
		(layer "In2.Cu")
		(net "M_C_CLK_DN<0>")
	)
	(segment
		(start 261.121144 -48.082708)
		(end 261.121144 -27.620976)
		(width 0.14224)
		(layer "In2.Cu")
		(net "M_C_CLK_DN<0>")
	)
	(segment
		(start 262.4836 -20.193)
		(end 262.4836 -11.811)
		(width 0.14224)
		(layer "In2.Cu")
		(net "M_C_CLK_DN<0>")
	)
	(segment
		(start 257.290316 2.176018)
		(end 257.599942 2.485644)
		(width 0.14224)
		(layer "In2.Cu")
		(net "M_C_CLK_DN<0>")
	)
	(segment
		(start 262.17372 -26.5684)
		(end 262.17372 -20.50288)
		(width 0.14224)
		(layer "In2.Cu")
		(net "M_C_CLK_DN<0>")
	)
	(segment
		(start 260.097524 -51.916076)
		(end 260.6802 -51.3334)
		(width 0.0889)
		(layer "In2.Cu")
		(net "M_C_CLK_DN<0>")
	)
	(segment
		(start 260.56336 -0.87376)
		(end 260.08584 -0.39624)
		(width 0.14224)
		(layer "In2.Cu")
		(net "M_C_CLK_DN<0>")
	)
	(segment
		(start 262.4836 -11.811)
		(end 262.80364 -11.49096)
		(width 0.14224)
		(layer "In2.Cu")
		(net "M_C_CLK_DN<0>")
	)
	(segment
		(start 261.568946 -0.87376)
		(end 260.56336 -0.87376)
		(width 0.14224)
		(layer "In2.Cu")
		(net "M_C_CLK_DN<0>")
	)
	(segment
		(start 262.80364 -11.49096)
		(end 262.80364 -10.16508)
		(width 0.14224)
		(layer "In2.Cu")
		(net "M_C_CLK_DN<0>")
	)
	(segment
		(start 257.518662 1.69291)
		(end 257.290316 1.921256)
		(width 0.14224)
		(layer "In2.Cu")
		(net "M_C_CLK_DN<0>")
	)
	(segment
		(start 262.80364 -10.16508)
		(end 262.49884 -9.86028)
		(width 0.14224)
		(layer "In2.Cu")
		(net "M_C_CLK_DN<0>")
	)
	(segment
		(start 261.121144 -48.104806)
		(end 261.121144 -48.082708)
		(width 0.0889)
		(layer "In2.Cu")
		(net "M_C_CLK_DN<0>")
	)
	(segment
		(start 261.121144 -27.620976)
		(end 262.17372 -26.5684)
		(width 0.14224)
		(layer "In2.Cu")
		(net "M_C_CLK_DN<0>")
	)
	(segment
		(start 260.16204 -52.914296)
		(end 260.16204 -52.914042)
		(width 0.0889)
		(layer "In2.Cu")
		(net "M_C_CLK_DN<0>")
	)
	(arc
		(start 260.16204 -57.867296)
		(mid 260.241171 -57.571894)
		(end 260.16204 -57.276492)
		(width 0.0889)
		(layer "In2.Cu")
		(net "M_C_CLK_DN<0>")
	)
	(arc
		(start 260.16204 -53.904896)
		(mid 260.241171 -53.609494)
		(end 260.16204 -53.314092)
		(width 0.0889)
		(layer "In2.Cu")
		(net "M_C_CLK_DN<0>")
	)
	(arc
		(start 260.16204 -52.914042)
		(mid 260.241043 -52.617696)
		(end 260.16077 -52.321714)
		(width 0.0889)
		(layer "In2.Cu")
		(net "M_C_CLK_DN<0>")
	)
	(arc
		(start 260.16204 -53.314092)
		(mid 260.108541 -53.114194)
		(end 260.16204 -52.914296)
		(width 0.0889)
		(layer "In2.Cu")
		(net "M_C_CLK_DN<0>")
	)
	(arc
		(start 259.278374 -59.700668)
		(mid 259.257936 -59.631582)
		(end 259.25018 -59.559952)
		(width 0.0889)
		(layer "In2.Cu")
		(net "M_C_CLK_DN<0>")
	)
	(arc
		(start 259.25018 -59.559952)
		(mid 259.361007 -59.276621)
		(end 259.639054 -59.153044)
		(width 0.0889)
		(layer "In2.Cu")
		(net "M_C_CLK_DN<0>")
	)
	(arc
		(start 259.67182 -59.153044)
		(mid 260.167297 -58.848601)
		(end 260.16204 -58.267092)
		(width 0.0889)
		(layer "In2.Cu")
		(net "M_C_CLK_DN<0>")
	)
	(arc
		(start 260.16204 -55.886096)
		(mid 260.241171 -55.590694)
		(end 260.16204 -55.295292)
		(width 0.0889)
		(layer "In2.Cu")
		(net "M_C_CLK_DN<0>")
	)
	(arc
		(start 260.16204 -56.876696)
		(mid 260.241171 -56.581294)
		(end 260.16204 -56.285892)
		(width 0.0889)
		(layer "In2.Cu")
		(net "M_C_CLK_DN<0>")
	)
	(arc
		(start 260.16204 -55.295292)
		(mid 260.108541 -55.095394)
		(end 260.16204 -54.895496)
		(width 0.0889)
		(layer "In2.Cu")
		(net "M_C_CLK_DN<0>")
	)
	(arc
		(start 260.16204 -54.895496)
		(mid 260.241171 -54.600094)
		(end 260.16204 -54.304692)
		(width 0.0889)
		(layer "In2.Cu")
		(net "M_C_CLK_DN<0>")
	)
	(arc
		(start 260.16204 -54.304692)
		(mid 260.108541 -54.104794)
		(end 260.16204 -53.904896)
		(width 0.0889)
		(layer "In2.Cu")
		(net "M_C_CLK_DN<0>")
	)
	(arc
		(start 260.16204 -57.276492)
		(mid 260.108541 -57.076594)
		(end 260.16204 -56.876696)
		(width 0.0889)
		(layer "In2.Cu")
		(net "M_C_CLK_DN<0>")
	)
	(arc
		(start 260.16204 -58.267092)
		(mid 260.108541 -58.067194)
		(end 260.16204 -57.867296)
		(width 0.0889)
		(layer "In2.Cu")
		(net "M_C_CLK_DN<0>")
	)
	(arc
		(start 260.16204 -56.285892)
		(mid 260.108541 -56.085994)
		(end 260.16204 -55.886096)
		(width 0.0889)
		(layer "In2.Cu")
		(net "M_C_CLK_DN<0>")
	)
	(segment
		(start 252.495304 -60.047886)
		(end 251.923804 -60.047886)
		(width 0.1016)
		(layer "F.Cu")
		(net "M_C_CKE<3>")
	)
	(via
		(at 251.923804 -60.047886)
		(size 0.508)
		(drill 0.254)
		(layers "F.Cu" "B.Cu")
		(net "M_C_CKE<3>")
	)
	(via
		(at 243.999766 -2.314956)
		(size 0.4572)
		(drill 0.2032)
		(layers "F.Cu" "B.Cu")
		(net "M_C_CKE<3>")
	)
	(segment
		(start 243.999766 -1.021842)
		(end 243.999766 -2.314956)
		(width 0.1651)
		(layer "B.Cu")
		(net "M_C_CKE<3>")
	)
	(segment
		(start 244.000274 -1.021842)
		(end 243.999766 -1.021842)
		(width 0.1651)
		(layer "B.Cu")
		(net "M_C_CKE<3>")
	)
	(segment
		(start 251.405644 -56.791606)
		(end 251.411994 -56.780938)
		(width 0.0889)
		(layer "In2.Cu")
		(net "M_C_CKE<3>")
	)
	(segment
		(start 251.175774 -32.659066)
		(end 245.999 -27.482292)
		(width 0.14224)
		(layer "In2.Cu")
		(net "M_C_CKE<3>")
	)
	(segment
		(start 244.366796 -21.938996)
		(end 244.493796 -21.811996)
		(width 0.14224)
		(layer "In2.Cu")
		(net "M_C_CKE<3>")
	)
	(segment
		(start 244.341396 -17.617186)
		(end 244.341396 -17.109186)
		(width 0.14224)
		(layer "In2.Cu")
		(net "M_C_CKE<3>")
	)
	(segment
		(start 244.423184 -18.475198)
		(end 244.493796 -18.404586)
		(width 0.14224)
		(layer "In2.Cu")
		(net "M_C_CKE<3>")
	)
	(segment
		(start 244.366796 -22.421596)
		(end 244.366796 -21.938996)
		(width 0.14224)
		(layer "In2.Cu")
		(net "M_C_CKE<3>")
	)
	(segment
		(start 251.314204 -51.249834)
		(end 251.314204 -48.900588)
		(width 0.0889)
		(layer "In2.Cu")
		(net "M_C_CKE<3>")
	)
	(segment
		(start 245.999 -27.482292)
		(end 245.999 -26.289)
		(width 0.14224)
		(layer "In2.Cu")
		(net "M_C_CKE<3>")
	)
	(segment
		(start 244.493796 -21.811996)
		(end 244.493796 -19.40433)
		(width 0.14224)
		(layer "In2.Cu")
		(net "M_C_CKE<3>")
	)
	(segment
		(start 244.423184 -19.333718)
		(end 244.423184 -18.475198)
		(width 0.14224)
		(layer "In2.Cu")
		(net "M_C_CKE<3>")
	)
	(segment
		(start 244.4115 -7.62)
		(end 244.432836 -7.598664)
		(width 0.14224)
		(layer "In2.Cu")
		(net "M_C_CKE<3>")
	)
	(segment
		(start 244.493796 -17.769586)
		(end 244.341396 -17.617186)
		(width 0.14224)
		(layer "In2.Cu")
		(net "M_C_CKE<3>")
	)
	(segment
		(start 244.358922 -23.31847)
		(end 244.544596 -23.132796)
		(width 0.14224)
		(layer "In2.Cu")
		(net "M_C_CKE<3>")
	)
	(segment
		(start 251.411994 -54.799738)
		(end 251.41682 -54.791102)
		(width 0.0889)
		(layer "In2.Cu")
		(net "M_C_CKE<3>")
	)
	(segment
		(start 244.341396 -17.109186)
		(end 244.442234 -17.008348)
		(width 0.14224)
		(layer "In2.Cu")
		(net "M_C_CKE<3>")
	)
	(segment
		(start 251.59081 -58.289952)
		(end 251.475494 -58.090562)
		(width 0.0889)
		(layer "In2.Cu")
		(net "M_C_CKE<3>")
	)
	(segment
		(start 251.405644 -54.810406)
		(end 251.411994 -54.799738)
		(width 0.0889)
		(layer "In2.Cu")
		(net "M_C_CKE<3>")
	)
	(segment
		(start 244.432836 -7.598664)
		(end 244.432836 -2.748026)
		(width 0.14224)
		(layer "In2.Cu")
		(net "M_C_CKE<3>")
	)
	(segment
		(start 251.405644 -55.801006)
		(end 251.411994 -55.790338)
		(width 0.0889)
		(layer "In2.Cu")
		(net "M_C_CKE<3>")
	)
	(segment
		(start 251.175774 -48.762158)
		(end 251.175774 -48.567848)
		(width 0.0889)
		(layer "In2.Cu")
		(net "M_C_CKE<3>")
	)
	(segment
		(start 244.358922 -24.648922)
		(end 244.358922 -23.31847)
		(width 0.14224)
		(layer "In2.Cu")
		(net "M_C_CKE<3>")
	)
	(segment
		(start 251.332746 -57.378346)
		(end 251.332746 -57.08142)
		(width 0.0889)
		(layer "In2.Cu")
		(net "M_C_CKE<3>")
	)
	(segment
		(start 251.405644 -53.819806)
		(end 251.411994 -53.809138)
		(width 0.0889)
		(layer "In2.Cu")
		(net "M_C_CKE<3>")
	)
	(segment
		(start 244.4115 -12.341606)
		(end 244.4115 -7.62)
		(width 0.14224)
		(layer "In2.Cu")
		(net "M_C_CKE<3>")
	)
	(segment
		(start 251.923804 -60.047886)
		(end 251.593858 -59.28614)
		(width 0.0889)
		(layer "In2.Cu")
		(net "M_C_CKE<3>")
	)
	(segment
		(start 251.467874 -51.731164)
		(end 251.467874 -51.403504)
		(width 0.0889)
		(layer "In2.Cu")
		(net "M_C_CKE<3>")
	)
	(segment
		(start 244.493796 -19.40433)
		(end 244.423184 -19.333718)
		(width 0.14224)
		(layer "In2.Cu")
		(net "M_C_CKE<3>")
	)
	(segment
		(start 244.544596 -22.599396)
		(end 244.366796 -22.421596)
		(width 0.14224)
		(layer "In2.Cu")
		(net "M_C_CKE<3>")
	)
	(segment
		(start 251.572268 -58.866024)
		(end 251.59462 -58.826146)
		(width 0.0889)
		(layer "In2.Cu")
		(net "M_C_CKE<3>")
	)
	(segment
		(start 251.475494 -58.090562)
		(end 251.475494 -57.521094)
		(width 0.0889)
		(layer "In2.Cu")
		(net "M_C_CKE<3>")
	)
	(segment
		(start 251.314204 -48.900588)
		(end 251.175774 -48.762158)
		(width 0.0889)
		(layer "In2.Cu")
		(net "M_C_CKE<3>")
	)
	(segment
		(start 244.432836 -2.748026)
		(end 243.999766 -2.314956)
		(width 0.14224)
		(layer "In2.Cu")
		(net "M_C_CKE<3>")
	)
	(segment
		(start 251.411994 -53.809138)
		(end 251.41682 -53.800502)
		(width 0.0889)
		(layer "In2.Cu")
		(net "M_C_CKE<3>")
	)
	(segment
		(start 251.411994 -55.790338)
		(end 251.41682 -55.781702)
		(width 0.0889)
		(layer "In2.Cu")
		(net "M_C_CKE<3>")
	)
	(segment
		(start 244.544596 -23.132796)
		(end 244.544596 -22.599396)
		(width 0.14224)
		(layer "In2.Cu")
		(net "M_C_CKE<3>")
	)
	(segment
		(start 251.475494 -57.521094)
		(end 251.332746 -57.378346)
		(width 0.0889)
		(layer "In2.Cu")
		(net "M_C_CKE<3>")
	)
	(segment
		(start 251.593858 -59.28614)
		(end 251.577094 -59.257438)
		(width 0.0889)
		(layer "In2.Cu")
		(net "M_C_CKE<3>")
	)
	(segment
		(start 245.999 -26.289)
		(end 244.358922 -24.648922)
		(width 0.14224)
		(layer "In2.Cu")
		(net "M_C_CKE<3>")
	)
	(segment
		(start 244.442234 -17.008348)
		(end 244.442234 -12.37234)
		(width 0.14224)
		(layer "In2.Cu")
		(net "M_C_CKE<3>")
	)
	(segment
		(start 244.493796 -18.404586)
		(end 244.493796 -17.769586)
		(width 0.14224)
		(layer "In2.Cu")
		(net "M_C_CKE<3>")
	)
	(segment
		(start 251.411994 -56.780938)
		(end 251.41682 -56.772302)
		(width 0.0889)
		(layer "In2.Cu")
		(net "M_C_CKE<3>")
	)
	(segment
		(start 244.442234 -12.37234)
		(end 244.4115 -12.341606)
		(width 0.14224)
		(layer "In2.Cu")
		(net "M_C_CKE<3>")
	)
	(segment
		(start 251.175774 -48.567848)
		(end 251.175774 -32.659066)
		(width 0.14224)
		(layer "In2.Cu")
		(net "M_C_CKE<3>")
	)
	(segment
		(start 251.411994 -51.828192)
		(end 251.467874 -51.731164)
		(width 0.0889)
		(layer "In2.Cu")
		(net "M_C_CKE<3>")
	)
	(segment
		(start 251.467874 -51.403504)
		(end 251.314204 -51.249834)
		(width 0.0889)
		(layer "In2.Cu")
		(net "M_C_CKE<3>")
	)
	(arc
		(start 251.59462 -58.826146)
		(mid 251.663529 -58.557556)
		(end 251.59081 -58.289952)
		(width 0.0889)
		(layer "In2.Cu")
		(net "M_C_CKE<3>")
	)
	(arc
		(start 251.411994 -54.399688)
		(mid 251.332772 -54.11057)
		(end 251.405644 -53.819806)
		(width 0.0889)
		(layer "In2.Cu")
		(net "M_C_CKE<3>")
	)
	(arc
		(start 251.41682 -54.791102)
		(mid 251.465575 -54.59475)
		(end 251.411994 -54.399688)
		(width 0.0889)
		(layer "In2.Cu")
		(net "M_C_CKE<3>")
	)
	(arc
		(start 251.332746 -57.08142)
		(mid 251.350594 -56.931836)
		(end 251.405644 -56.791606)
		(width 0.0889)
		(layer "In2.Cu")
		(net "M_C_CKE<3>")
	)
	(arc
		(start 251.411994 -53.409088)
		(mid 251.332863 -53.113686)
		(end 251.411994 -52.818284)
		(width 0.0889)
		(layer "In2.Cu")
		(net "M_C_CKE<3>")
	)
	(arc
		(start 251.41682 -55.781702)
		(mid 251.465575 -55.58535)
		(end 251.411994 -55.390288)
		(width 0.0889)
		(layer "In2.Cu")
		(net "M_C_CKE<3>")
	)
	(arc
		(start 251.41682 -53.800502)
		(mid 251.465575 -53.60415)
		(end 251.411994 -53.409088)
		(width 0.0889)
		(layer "In2.Cu")
		(net "M_C_CKE<3>")
	)
	(arc
		(start 251.41682 -56.772302)
		(mid 251.465575 -56.57595)
		(end 251.411994 -56.380888)
		(width 0.0889)
		(layer "In2.Cu")
		(net "M_C_CKE<3>")
	)
	(arc
		(start 251.411994 -56.380888)
		(mid 251.332772 -56.09177)
		(end 251.405644 -55.801006)
		(width 0.0889)
		(layer "In2.Cu")
		(net "M_C_CKE<3>")
	)
	(arc
		(start 251.411994 -52.818284)
		(mid 251.465493 -52.618386)
		(end 251.411994 -52.418488)
		(width 0.0889)
		(layer "In2.Cu")
		(net "M_C_CKE<3>")
	)
	(arc
		(start 251.577094 -59.257438)
		(mid 251.523624 -59.062375)
		(end 251.572268 -58.866024)
		(width 0.0889)
		(layer "In2.Cu")
		(net "M_C_CKE<3>")
	)
	(arc
		(start 251.411994 -55.390288)
		(mid 251.332772 -55.10117)
		(end 251.405644 -54.810406)
		(width 0.0889)
		(layer "In2.Cu")
		(net "M_C_CKE<3>")
	)
	(arc
		(start 251.411994 -52.418488)
		(mid 251.332989 -52.12334)
		(end 251.411994 -51.828192)
		(width 0.0889)
		(layer "In2.Cu")
		(net "M_C_CKE<3>")
	)
	(segment
		(start 252.495304 -58.06694)
		(end 251.923804 -58.06694)
		(width 0.1016)
		(layer "F.Cu")
		(net "M_C_CKE<2>")
	)
	(via
		(at 244.849904 -4.332478)
		(size 0.4572)
		(drill 0.2032)
		(layers "F.Cu" "B.Cu")
		(net "M_C_CKE<2>")
	)
	(via
		(at 251.923804 -58.06694)
		(size 0.508)
		(drill 0.254)
		(layers "F.Cu" "B.Cu")
		(net "M_C_CKE<2>")
	)
	(segment
		(start 244.850412 -5.621782)
		(end 244.849904 -5.621782)
		(width 0.1651)
		(layer "B.Cu")
		(net "M_C_CKE<2>")
	)
	(segment
		(start 244.849904 -5.621782)
		(end 244.849904 -4.332478)
		(width 0.1651)
		(layer "B.Cu")
		(net "M_C_CKE<2>")
	)
	(segment
		(start 245.287546 -18.461736)
		(end 245.204996 -18.379186)
		(width 0.14224)
		(layer "In2.Cu")
		(net "M_C_CKE<2>")
	)
	(segment
		(start 245.2624 -17.03959)
		(end 245.2624 -12.43584)
		(width 0.14224)
		(layer "In2.Cu")
		(net "M_C_CKE<2>")
	)
	(segment
		(start 245.357396 -22.396196)
		(end 245.357396 -21.913596)
		(width 0.14224)
		(layer "In2.Cu")
		(net "M_C_CKE<2>")
	)
	(segment
		(start 245.2878 -12.41044)
		(end 245.2878 -8.86079)
		(width 0.14224)
		(layer "In2.Cu")
		(net "M_C_CKE<2>")
	)
	(segment
		(start 245.204996 -21.761196)
		(end 245.204996 -19.141186)
		(width 0.14224)
		(layer "In2.Cu")
		(net "M_C_CKE<2>")
	)
	(segment
		(start 251.577094 -53.904388)
		(end 251.583444 -53.89372)
		(width 0.0889)
		(layer "In2.Cu")
		(net "M_C_CKE<2>")
	)
	(segment
		(start 245.204996 -8.777986)
		(end 245.204996 -8.193786)
		(width 0.14224)
		(layer "In2.Cu")
		(net "M_C_CKE<2>")
	)
	(segment
		(start 245.357396 -23.285196)
		(end 245.179596 -23.107396)
		(width 0.14224)
		(layer "In2.Cu")
		(net "M_C_CKE<2>")
	)
	(segment
		(start 245.357396 -17.642586)
		(end 245.357396 -17.134586)
		(width 0.14224)
		(layer "In2.Cu")
		(net "M_C_CKE<2>")
	)
	(segment
		(start 251.683774 -50.922174)
		(end 251.683774 -32.4993)
		(width 0.14224)
		(layer "In2.Cu")
		(net "M_C_CKE<2>")
	)
	(segment
		(start 251.577094 -51.923442)
		(end 251.683774 -51.738276)
		(width 0.0889)
		(layer "In2.Cu")
		(net "M_C_CKE<2>")
	)
	(segment
		(start 245.2624 -12.43584)
		(end 245.2878 -12.41044)
		(width 0.14224)
		(layer "In2.Cu")
		(net "M_C_CKE<2>")
	)
	(segment
		(start 246.507 -26.035)
		(end 245.357396 -24.885396)
		(width 0.14224)
		(layer "In2.Cu")
		(net "M_C_CKE<2>")
	)
	(segment
		(start 245.179596 -22.573996)
		(end 245.357396 -22.396196)
		(width 0.14224)
		(layer "In2.Cu")
		(net "M_C_CKE<2>")
	)
	(segment
		(start 245.204996 -8.193786)
		(end 245.357396 -8.041386)
		(width 0.14224)
		(layer "In2.Cu")
		(net "M_C_CKE<2>")
	)
	(segment
		(start 245.179596 -23.107396)
		(end 245.179596 -22.573996)
		(width 0.14224)
		(layer "In2.Cu")
		(net "M_C_CKE<2>")
	)
	(segment
		(start 245.357396 -17.134586)
		(end 245.2624 -17.03959)
		(width 0.14224)
		(layer "In2.Cu")
		(net "M_C_CKE<2>")
	)
	(segment
		(start 251.593858 -57.305194)
		(end 251.577094 -57.276238)
		(width 0.0889)
		(layer "In2.Cu")
		(net "M_C_CKE<2>")
	)
	(segment
		(start 251.572268 -56.884824)
		(end 251.577094 -56.876188)
		(width 0.0889)
		(layer "In2.Cu")
		(net "M_C_CKE<2>")
	)
	(segment
		(start 251.572268 -53.913024)
		(end 251.577094 -53.904388)
		(width 0.0889)
		(layer "In2.Cu")
		(net "M_C_CKE<2>")
	)
	(segment
		(start 245.266718 -5.109718)
		(end 244.851174 -4.694174)
		(width 0.14224)
		(layer "In2.Cu")
		(net "M_C_CKE<2>")
	)
	(segment
		(start 245.357396 -24.885396)
		(end 245.357396 -23.285196)
		(width 0.14224)
		(layer "In2.Cu")
		(net "M_C_CKE<2>")
	)
	(segment
		(start 251.923804 -58.06694)
		(end 251.593858 -57.305194)
		(width 0.0889)
		(layer "In2.Cu")
		(net "M_C_CKE<2>")
	)
	(segment
		(start 245.204996 -19.141186)
		(end 245.287546 -19.058636)
		(width 0.14224)
		(layer "In2.Cu")
		(net "M_C_CKE<2>")
	)
	(segment
		(start 251.577094 -56.876188)
		(end 251.583444 -56.86552)
		(width 0.0889)
		(layer "In2.Cu")
		(net "M_C_CKE<2>")
	)
	(segment
		(start 244.851174 -4.694174)
		(end 244.851174 -4.333748)
		(width 0.14224)
		(layer "In2.Cu")
		(net "M_C_CKE<2>")
	)
	(segment
		(start 244.851174 -4.333748)
		(end 244.849904 -4.332478)
		(width 0.14224)
		(layer "In2.Cu")
		(net "M_C_CKE<2>")
	)
	(segment
		(start 245.266718 -7.442708)
		(end 245.266718 -5.109718)
		(width 0.14224)
		(layer "In2.Cu")
		(net "M_C_CKE<2>")
	)
	(segment
		(start 251.572268 -52.922424)
		(end 251.577094 -52.913788)
		(width 0.0889)
		(layer "In2.Cu")
		(net "M_C_CKE<2>")
	)
	(segment
		(start 251.683774 -32.4993)
		(end 246.507 -27.322526)
		(width 0.14224)
		(layer "In2.Cu")
		(net "M_C_CKE<2>")
	)
	(segment
		(start 251.583444 -52.333906)
		(end 251.577094 -52.323238)
		(width 0.0889)
		(layer "In2.Cu")
		(net "M_C_CKE<2>")
	)
	(segment
		(start 245.357396 -21.913596)
		(end 245.204996 -21.761196)
		(width 0.14224)
		(layer "In2.Cu")
		(net "M_C_CKE<2>")
	)
	(segment
		(start 251.683774 -51.738276)
		(end 251.683774 -50.922174)
		(width 0.0889)
		(layer "In2.Cu")
		(net "M_C_CKE<2>")
	)
	(segment
		(start 251.572268 -55.894224)
		(end 251.577094 -55.885588)
		(width 0.0889)
		(layer "In2.Cu")
		(net "M_C_CKE<2>")
	)
	(segment
		(start 251.572268 -54.903624)
		(end 251.577094 -54.894988)
		(width 0.0889)
		(layer "In2.Cu")
		(net "M_C_CKE<2>")
	)
	(segment
		(start 245.204996 -17.794986)
		(end 245.357396 -17.642586)
		(width 0.14224)
		(layer "In2.Cu")
		(net "M_C_CKE<2>")
	)
	(segment
		(start 246.507 -27.322526)
		(end 246.507 -26.035)
		(width 0.14224)
		(layer "In2.Cu")
		(net "M_C_CKE<2>")
	)
	(segment
		(start 245.357396 -7.533386)
		(end 245.266718 -7.442708)
		(width 0.14224)
		(layer "In2.Cu")
		(net "M_C_CKE<2>")
	)
	(segment
		(start 245.287546 -19.058636)
		(end 245.287546 -18.461736)
		(width 0.14224)
		(layer "In2.Cu")
		(net "M_C_CKE<2>")
	)
	(segment
		(start 245.204996 -18.379186)
		(end 245.204996 -17.794986)
		(width 0.14224)
		(layer "In2.Cu")
		(net "M_C_CKE<2>")
	)
	(segment
		(start 251.577094 -54.894988)
		(end 251.583444 -54.88432)
		(width 0.0889)
		(layer "In2.Cu")
		(net "M_C_CKE<2>")
	)
	(segment
		(start 251.577094 -55.885588)
		(end 251.583444 -55.87492)
		(width 0.0889)
		(layer "In2.Cu")
		(net "M_C_CKE<2>")
	)
	(segment
		(start 245.357396 -8.041386)
		(end 245.357396 -7.533386)
		(width 0.14224)
		(layer "In2.Cu")
		(net "M_C_CKE<2>")
	)
	(segment
		(start 245.2878 -8.86079)
		(end 245.204996 -8.777986)
		(width 0.14224)
		(layer "In2.Cu")
		(net "M_C_CKE<2>")
	)
	(arc
		(start 251.577094 -55.295038)
		(mid 251.523624 -55.099975)
		(end 251.572268 -54.903624)
		(width 0.0889)
		(layer "In2.Cu")
		(net "M_C_CKE<2>")
	)
	(arc
		(start 251.583444 -53.89372)
		(mid 251.656242 -53.602957)
		(end 251.577094 -53.313838)
		(width 0.0889)
		(layer "In2.Cu")
		(net "M_C_CKE<2>")
	)
	(arc
		(start 251.583444 -55.87492)
		(mid 251.656242 -55.584157)
		(end 251.577094 -55.295038)
		(width 0.0889)
		(layer "In2.Cu")
		(net "M_C_CKE<2>")
	)
	(arc
		(start 251.577094 -53.313838)
		(mid 251.523624 -53.118775)
		(end 251.572268 -52.922424)
		(width 0.0889)
		(layer "In2.Cu")
		(net "M_C_CKE<2>")
	)
	(arc
		(start 251.583444 -54.88432)
		(mid 251.656242 -54.593557)
		(end 251.577094 -54.304438)
		(width 0.0889)
		(layer "In2.Cu")
		(net "M_C_CKE<2>")
	)
	(arc
		(start 251.577094 -52.323238)
		(mid 251.523595 -52.12334)
		(end 251.577094 -51.923442)
		(width 0.0889)
		(layer "In2.Cu")
		(net "M_C_CKE<2>")
	)
	(arc
		(start 251.577094 -52.913788)
		(mid 251.656316 -52.62467)
		(end 251.583444 -52.333906)
		(width 0.0889)
		(layer "In2.Cu")
		(net "M_C_CKE<2>")
	)
	(arc
		(start 251.577094 -57.276238)
		(mid 251.523624 -57.081175)
		(end 251.572268 -56.884824)
		(width 0.0889)
		(layer "In2.Cu")
		(net "M_C_CKE<2>")
	)
	(arc
		(start 251.583444 -56.86552)
		(mid 251.656242 -56.574757)
		(end 251.577094 -56.285638)
		(width 0.0889)
		(layer "In2.Cu")
		(net "M_C_CKE<2>")
	)
	(arc
		(start 251.577094 -56.285638)
		(mid 251.523624 -56.090575)
		(end 251.572268 -55.894224)
		(width 0.0889)
		(layer "In2.Cu")
		(net "M_C_CKE<2>")
	)
	(arc
		(start 251.577094 -54.304438)
		(mid 251.523624 -54.109375)
		(end 251.572268 -53.913024)
		(width 0.0889)
		(layer "In2.Cu")
		(net "M_C_CKE<2>")
	)
	(segment
		(start 244.000274 -0.821182)
		(end 243.999766 -0.821182)
		(width 0.1651)
		(layer "F.Cu")
		(net "M_C_CKE<1>")
	)
	(segment
		(start 243.999766 -0.821182)
		(end 243.999766 1.152144)
		(width 0.1651)
		(layer "F.Cu")
		(net "M_C_CKE<1>")
	)
	(segment
		(start 252.495304 -61.038486)
		(end 251.923804 -61.038486)
		(width 0.1016)
		(layer "F.Cu")
		(net "M_C_CKE<1>")
	)
	(via
		(at 243.999766 1.152144)
		(size 0.508)
		(drill 0.254)
		(layers "F.Cu" "B.Cu")
		(net "M_C_CKE<1>")
	)
	(via
		(at 251.923804 -61.038486)
		(size 0.508)
		(drill 0.254)
		(layers "F.Cu" "B.Cu")
		(net "M_C_CKE<1>")
	)
	(segment
		(start 251.465334 -58.592974)
		(end 251.465334 -58.55208)
		(width 0.0889)
		(layer "In2.Cu")
		(net "M_C_CKE<1>")
	)
	(segment
		(start 243.757196 -23.437596)
		(end 243.503196 -23.183596)
		(width 0.14224)
		(layer "In2.Cu")
		(net "M_C_CKE<1>")
	)
	(segment
		(start 243.5606 -7.36219)
		(end 243.5606 -3.81)
		(width 0.14224)
		(layer "In2.Cu")
		(net "M_C_CKE<1>")
	)
	(segment
		(start 243.586 -18.502122)
		(end 243.757196 -18.330926)
		(width 0.14224)
		(layer "In2.Cu")
		(net "M_C_CKE<1>")
	)
	(segment
		(start 251.464318 -58.59399)
		(end 251.465334 -58.592974)
		(width 0.0889)
		(layer "In2.Cu")
		(net "M_C_CKE<1>")
	)
	(segment
		(start 243.586 -0.9398)
		(end 243.999766 -0.526034)
		(width 0.14224)
		(layer "In2.Cu")
		(net "M_C_CKE<1>")
	)
	(segment
		(start 245.4148 -27.752294)
		(end 245.4148 -26.4668)
		(width 0.14224)
		(layer "In2.Cu")
		(net "M_C_CKE<1>")
	)
	(segment
		(start 243.7384 -12.591288)
		(end 243.582952 -12.43584)
		(width 0.14224)
		(layer "In2.Cu")
		(net "M_C_CKE<1>")
	)
	(segment
		(start 243.586 -2.660396)
		(end 243.586 -0.9398)
		(width 0.14224)
		(layer "In2.Cu")
		(net "M_C_CKE<1>")
	)
	(segment
		(start 243.757196 -21.964396)
		(end 243.503196 -21.710396)
		(width 0.14224)
		(layer "In2.Cu")
		(net "M_C_CKE<1>")
	)
	(segment
		(start 251.2568 -58.092848)
		(end 251.2568 -57.6326)
		(width 0.0889)
		(layer "In2.Cu")
		(net "M_C_CKE<1>")
	)
	(segment
		(start 243.582952 -8.486902)
		(end 243.757196 -8.312658)
		(width 0.14224)
		(layer "In2.Cu")
		(net "M_C_CKE<1>")
	)
	(segment
		(start 251.2568 -57.6326)
		(end 250.797822 -57.173622)
		(width 0.0889)
		(layer "In2.Cu")
		(net "M_C_CKE<1>")
	)
	(segment
		(start 251.417074 -58.370978)
		(end 251.2568 -58.092848)
		(width 0.0889)
		(layer "In2.Cu")
		(net "M_C_CKE<1>")
	)
	(segment
		(start 243.757196 -18.330926)
		(end 243.757196 -17.159986)
		(width 0.14224)
		(layer "In2.Cu")
		(net "M_C_CKE<1>")
	)
	(segment
		(start 243.5606 -3.81)
		(end 243.7384 -3.6322)
		(width 0.14224)
		(layer "In2.Cu")
		(net "M_C_CKE<1>")
	)
	(segment
		(start 243.7384 -2.812796)
		(end 243.586 -2.660396)
		(width 0.14224)
		(layer "In2.Cu")
		(net "M_C_CKE<1>")
	)
	(segment
		(start 243.586 -19.380454)
		(end 243.586 -18.502122)
		(width 0.14224)
		(layer "In2.Cu")
		(net "M_C_CKE<1>")
	)
	(segment
		(start 251.411994 -59.752738)
		(end 251.41682 -59.744102)
		(width 0.0889)
		(layer "In2.Cu")
		(net "M_C_CKE<1>")
	)
	(segment
		(start 243.503196 -22.662896)
		(end 243.757196 -22.408896)
		(width 0.14224)
		(layer "In2.Cu")
		(net "M_C_CKE<1>")
	)
	(segment
		(start 250.797822 -57.173622)
		(end 250.797822 -57.0738)
		(width 0.0889)
		(layer "In2.Cu")
		(net "M_C_CKE<1>")
	)
	(segment
		(start 243.582952 -12.43584)
		(end 243.582952 -8.486902)
		(width 0.14224)
		(layer "In2.Cu")
		(net "M_C_CKE<1>")
	)
	(segment
		(start 243.566696 -13.260578)
		(end 243.7384 -13.088874)
		(width 0.14224)
		(layer "In2.Cu")
		(net "M_C_CKE<1>")
	)
	(segment
		(start 243.503196 -19.463258)
		(end 243.586 -19.380454)
		(width 0.14224)
		(layer "In2.Cu")
		(net "M_C_CKE<1>")
	)
	(segment
		(start 250.667774 -33.005268)
		(end 245.4148 -27.752294)
		(width 0.14224)
		(layer "In2.Cu")
		(net "M_C_CKE<1>")
	)
	(segment
		(start 243.503196 -21.710396)
		(end 243.503196 -19.463258)
		(width 0.14224)
		(layer "In2.Cu")
		(net "M_C_CKE<1>")
	)
	(segment
		(start 251.923804 -61.038486)
		(end 251.593858 -60.27674)
		(width 0.0889)
		(layer "In2.Cu")
		(net "M_C_CKE<1>")
	)
	(segment
		(start 245.4148 -26.4668)
		(end 243.757196 -24.809196)
		(width 0.14224)
		(layer "In2.Cu")
		(net "M_C_CKE<1>")
	)
	(segment
		(start 243.757196 -24.809196)
		(end 243.757196 -23.437596)
		(width 0.14224)
		(layer "In2.Cu")
		(net "M_C_CKE<1>")
	)
	(segment
		(start 250.667774 -48.720756)
		(end 250.667774 -48.432212)
		(width 0.0889)
		(layer "In2.Cu")
		(net "M_C_CKE<1>")
	)
	(segment
		(start 251.593858 -60.27674)
		(end 251.411994 -59.962034)
		(width 0.0889)
		(layer "In2.Cu")
		(net "M_C_CKE<1>")
	)
	(segment
		(start 250.66498 -51.39182)
		(end 250.990862 -51.065938)
		(width 0.0889)
		(layer "In2.Cu")
		(net "M_C_CKE<1>")
	)
	(segment
		(start 243.999766 -0.526034)
		(end 243.999766 1.152144)
		(width 0.14224)
		(layer "In2.Cu")
		(net "M_C_CKE<1>")
	)
	(segment
		(start 243.757196 -7.558786)
		(end 243.5606 -7.36219)
		(width 0.14224)
		(layer "In2.Cu")
		(net "M_C_CKE<1>")
	)
	(segment
		(start 250.990862 -49.043844)
		(end 250.667774 -48.720756)
		(width 0.0889)
		(layer "In2.Cu")
		(net "M_C_CKE<1>")
	)
	(segment
		(start 243.757196 -17.159986)
		(end 243.566696 -16.969486)
		(width 0.14224)
		(layer "In2.Cu")
		(net "M_C_CKE<1>")
	)
	(segment
		(start 250.667774 -48.432212)
		(end 250.667774 -33.005268)
		(width 0.14224)
		(layer "In2.Cu")
		(net "M_C_CKE<1>")
	)
	(segment
		(start 250.990862 -51.065938)
		(end 250.990862 -49.043844)
		(width 0.0889)
		(layer "In2.Cu")
		(net "M_C_CKE<1>")
	)
	(segment
		(start 243.503196 -23.183596)
		(end 243.503196 -22.662896)
		(width 0.14224)
		(layer "In2.Cu")
		(net "M_C_CKE<1>")
	)
	(segment
		(start 250.66498 -53.605938)
		(end 250.66498 -51.39182)
		(width 0.0889)
		(layer "In2.Cu")
		(net "M_C_CKE<1>")
	)
	(segment
		(start 243.7384 -3.6322)
		(end 243.7384 -2.812796)
		(width 0.14224)
		(layer "In2.Cu")
		(net "M_C_CKE<1>")
	)
	(segment
		(start 243.757196 -22.408896)
		(end 243.757196 -21.964396)
		(width 0.14224)
		(layer "In2.Cu")
		(net "M_C_CKE<1>")
	)
	(segment
		(start 243.566696 -16.969486)
		(end 243.566696 -13.260578)
		(width 0.14224)
		(layer "In2.Cu")
		(net "M_C_CKE<1>")
	)
	(segment
		(start 243.757196 -8.312658)
		(end 243.757196 -7.558786)
		(width 0.14224)
		(layer "In2.Cu")
		(net "M_C_CKE<1>")
	)
	(segment
		(start 243.7384 -13.088874)
		(end 243.7384 -12.591288)
		(width 0.14224)
		(layer "In2.Cu")
		(net "M_C_CKE<1>")
	)
	(arc
		(start 250.718574 -53.809392)
		(mid 250.678163 -53.71125)
		(end 250.66498 -53.605938)
		(width 0.0889)
		(layer "In2.Cu")
		(net "M_C_CKE<1>")
	)
	(arc
		(start 251.411994 -59.352688)
		(mid 251.332863 -59.057286)
		(end 251.411994 -58.761884)
		(width 0.0889)
		(layer "In2.Cu")
		(net "M_C_CKE<1>")
	)
	(arc
		(start 251.41682 -59.744102)
		(mid 251.465575 -59.54775)
		(end 251.411994 -59.352688)
		(width 0.0889)
		(layer "In2.Cu")
		(net "M_C_CKE<1>")
	)
	(arc
		(start 250.718574 -55.390796)
		(mid 250.797705 -55.095394)
		(end 250.718574 -54.799992)
		(width 0.0889)
		(layer "In2.Cu")
		(net "M_C_CKE<1>")
	)
	(arc
		(start 250.718574 -56.381396)
		(mid 250.797705 -56.085994)
		(end 250.718574 -55.790592)
		(width 0.0889)
		(layer "In2.Cu")
		(net "M_C_CKE<1>")
	)
	(arc
		(start 251.411994 -59.962034)
		(mid 251.383967 -59.857386)
		(end 251.411994 -59.752738)
		(width 0.0889)
		(layer "In2.Cu")
		(net "M_C_CKE<1>")
	)
	(arc
		(start 251.411994 -58.761884)
		(mid 251.447489 -58.680846)
		(end 251.464318 -58.59399)
		(width 0.0889)
		(layer "In2.Cu")
		(net "M_C_CKE<1>")
	)
	(arc
		(start 250.718574 -55.790592)
		(mid 250.665075 -55.590694)
		(end 250.718574 -55.390796)
		(width 0.0889)
		(layer "In2.Cu")
		(net "M_C_CKE<1>")
	)
	(arc
		(start 250.718574 -54.400196)
		(mid 250.797705 -54.104794)
		(end 250.718574 -53.809392)
		(width 0.0889)
		(layer "In2.Cu")
		(net "M_C_CKE<1>")
	)
	(arc
		(start 250.718574 -54.799992)
		(mid 250.665075 -54.600094)
		(end 250.718574 -54.400196)
		(width 0.0889)
		(layer "In2.Cu")
		(net "M_C_CKE<1>")
	)
	(arc
		(start 250.797822 -57.0738)
		(mid 250.777275 -56.922329)
		(end 250.718574 -56.781192)
		(width 0.0889)
		(layer "In2.Cu")
		(net "M_C_CKE<1>")
	)
	(arc
		(start 250.718574 -56.781192)
		(mid 250.665075 -56.581294)
		(end 250.718574 -56.381396)
		(width 0.0889)
		(layer "In2.Cu")
		(net "M_C_CKE<1>")
	)
	(arc
		(start 251.465334 -58.55208)
		(mid 251.451958 -58.458662)
		(end 251.417074 -58.370978)
		(width 0.0889)
		(layer "In2.Cu")
		(net "M_C_CKE<1>")
	)
	(segment
		(start 244.850412 3.778758)
		(end 244.849904 3.778758)
		(width 0.1651)
		(layer "F.Cu")
		(net "M_C_CKE<0>")
	)
	(segment
		(start 253.353824 -59.55284)
		(end 252.782324 -59.55284)
		(width 0.1016)
		(layer "F.Cu")
		(net "M_C_CKE<0>")
	)
	(segment
		(start 244.849904 3.778758)
		(end 244.849904 1.805432)
		(width 0.1651)
		(layer "F.Cu")
		(net "M_C_CKE<0>")
	)
	(via
		(at 244.849904 1.805432)
		(size 0.508)
		(drill 0.254)
		(layers "F.Cu" "B.Cu")
		(net "M_C_CKE<0>")
	)
	(via
		(at 252.782324 -59.55284)
		(size 0.508)
		(drill 0.254)
		(layers "F.Cu" "B.Cu")
		(net "M_C_CKE<0>")
	)
	(segment
		(start 245.291102 0.758698)
		(end 245.291102 -2.77876)
		(width 0.14224)
		(layer "In2.Cu")
		(net "M_C_CKE<0>")
	)
	(segment
		(start 246.0498 -17.62379)
		(end 246.110506 -17.684496)
		(width 0.14224)
		(layer "In2.Cu")
		(net "M_C_CKE<0>")
	)
	(segment
		(start 252.270514 -52.323238)
		(end 252.264164 -52.333906)
		(width 0.0889)
		(layer "In2.Cu")
		(net "M_C_CKE<0>")
	)
	(segment
		(start 246.110506 -17.684496)
		(end 246.110506 -21.193506)
		(width 0.14224)
		(layer "In2.Cu")
		(net "M_C_CKE<0>")
	)
	(segment
		(start 246.195596 -21.278596)
		(end 246.195596 -21.735796)
		(width 0.14224)
		(layer "In2.Cu")
		(net "M_C_CKE<0>")
	)
	(segment
		(start 252.264164 -56.86552)
		(end 252.270514 -56.876188)
		(width 0.0889)
		(layer "In2.Cu")
		(net "M_C_CKE<0>")
	)
	(segment
		(start 246.142256 -17.060926)
		(end 246.0498 -17.153382)
		(width 0.14224)
		(layer "In2.Cu")
		(net "M_C_CKE<0>")
	)
	(segment
		(start 252.270514 -58.266838)
		(end 252.264164 -58.277506)
		(width 0.0889)
		(layer "In2.Cu")
		(net "M_C_CKE<0>")
	)
	(segment
		(start 244.849904 1.199896)
		(end 245.291102 0.758698)
		(width 0.14224)
		(layer "In2.Cu")
		(net "M_C_CKE<0>")
	)
	(segment
		(start 252.772164 -59.551316)
		(end 252.782324 -59.55284)
		(width 0.0889)
		(layer "In2.Cu")
		(net "M_C_CKE<0>")
	)
	(segment
		(start 245.992396 -7.609586)
		(end 245.992396 -8.688578)
		(width 0.14224)
		(layer "In2.Cu")
		(net "M_C_CKE<0>")
	)
	(segment
		(start 252.270514 -58.857388)
		(end 252.318012 -58.940192)
		(width 0.0889)
		(layer "In2.Cu")
		(net "M_C_CKE<0>")
	)
	(segment
		(start 246.139716 -7.462266)
		(end 245.992396 -7.609586)
		(width 0.14224)
		(layer "In2.Cu")
		(net "M_C_CKE<0>")
	)
	(segment
		(start 252.191774 -50.972974)
		(end 252.191774 -51.782472)
		(width 0.0889)
		(layer "In2.Cu")
		(net "M_C_CKE<0>")
	)
	(segment
		(start 245.291102 -2.77876)
		(end 245.2624 -2.807462)
		(width 0.14224)
		(layer "In2.Cu")
		(net "M_C_CKE<0>")
	)
	(segment
		(start 252.264164 -54.88432)
		(end 252.270514 -54.894988)
		(width 0.0889)
		(layer "In2.Cu")
		(net "M_C_CKE<0>")
	)
	(segment
		(start 246.9388 -25.7048)
		(end 246.9388 -27.008074)
		(width 0.14224)
		(layer "In2.Cu")
		(net "M_C_CKE<0>")
	)
	(segment
		(start 252.270514 -55.885588)
		(end 252.27534 -55.894224)
		(width 0.0889)
		(layer "In2.Cu")
		(net "M_C_CKE<0>")
	)
	(segment
		(start 246.043196 -21.888196)
		(end 246.043196 -22.446996)
		(width 0.14224)
		(layer "In2.Cu")
		(net "M_C_CKE<0>")
	)
	(segment
		(start 252.270514 -53.904388)
		(end 252.27534 -53.913024)
		(width 0.0889)
		(layer "In2.Cu")
		(net "M_C_CKE<0>")
	)
	(segment
		(start 246.139716 -6.715506)
		(end 246.139716 -7.462266)
		(width 0.14224)
		(layer "In2.Cu")
		(net "M_C_CKE<0>")
	)
	(segment
		(start 245.874032 -6.449822)
		(end 246.139716 -6.715506)
		(width 0.14224)
		(layer "In2.Cu")
		(net "M_C_CKE<0>")
	)
	(segment
		(start 245.2624 -2.807462)
		(end 245.2624 -4.520946)
		(width 0.14224)
		(layer "In2.Cu")
		(net "M_C_CKE<0>")
	)
	(segment
		(start 246.142256 -13.468096)
		(end 246.142256 -17.060926)
		(width 0.14224)
		(layer "In2.Cu")
		(net "M_C_CKE<0>")
	)
	(segment
		(start 245.8974 -23.405592)
		(end 245.8974 -24.6634)
		(width 0.14224)
		(layer "In2.Cu")
		(net "M_C_CKE<0>")
	)
	(segment
		(start 246.1133 -13.43914)
		(end 246.142256 -13.468096)
		(width 0.14224)
		(layer "In2.Cu")
		(net "M_C_CKE<0>")
	)
	(segment
		(start 246.195596 -21.735796)
		(end 246.043196 -21.888196)
		(width 0.14224)
		(layer "In2.Cu")
		(net "M_C_CKE<0>")
	)
	(segment
		(start 252.318012 -58.940192)
		(end 252.772164 -59.551316)
		(width 0.0889)
		(layer "In2.Cu")
		(net "M_C_CKE<0>")
	)
	(segment
		(start 252.270514 -54.894988)
		(end 252.27534 -54.903624)
		(width 0.0889)
		(layer "In2.Cu")
		(net "M_C_CKE<0>")
	)
	(segment
		(start 252.191774 -32.261048)
		(end 252.191774 -50.972974)
		(width 0.14224)
		(layer "In2.Cu")
		(net "M_C_CKE<0>")
	)
	(segment
		(start 246.9388 -27.008074)
		(end 252.191774 -32.261048)
		(width 0.14224)
		(layer "In2.Cu")
		(net "M_C_CKE<0>")
	)
	(segment
		(start 246.1133 -8.809482)
		(end 246.1133 -13.43914)
		(width 0.14224)
		(layer "In2.Cu")
		(net "M_C_CKE<0>")
	)
	(segment
		(start 246.195596 -22.599396)
		(end 246.195596 -23.107396)
		(width 0.14224)
		(layer "In2.Cu")
		(net "M_C_CKE<0>")
	)
	(segment
		(start 252.264164 -55.87492)
		(end 252.270514 -55.885588)
		(width 0.0889)
		(layer "In2.Cu")
		(net "M_C_CKE<0>")
	)
	(segment
		(start 245.2624 -4.520946)
		(end 245.874032 -5.132578)
		(width 0.14224)
		(layer "In2.Cu")
		(net "M_C_CKE<0>")
	)
	(segment
		(start 246.110506 -21.193506)
		(end 246.195596 -21.278596)
		(width 0.14224)
		(layer "In2.Cu")
		(net "M_C_CKE<0>")
	)
	(segment
		(start 245.992396 -8.688578)
		(end 246.1133 -8.809482)
		(width 0.14224)
		(layer "In2.Cu")
		(net "M_C_CKE<0>")
	)
	(segment
		(start 252.264164 -53.89372)
		(end 252.270514 -53.904388)
		(width 0.0889)
		(layer "In2.Cu")
		(net "M_C_CKE<0>")
	)
	(segment
		(start 245.874032 -5.132578)
		(end 245.874032 -6.449822)
		(width 0.14224)
		(layer "In2.Cu")
		(net "M_C_CKE<0>")
	)
	(segment
		(start 252.270514 -56.876188)
		(end 252.27534 -56.884824)
		(width 0.0889)
		(layer "In2.Cu")
		(net "M_C_CKE<0>")
	)
	(segment
		(start 246.0498 -17.153382)
		(end 246.0498 -17.62379)
		(width 0.14224)
		(layer "In2.Cu")
		(net "M_C_CKE<0>")
	)
	(segment
		(start 252.270514 -52.913788)
		(end 252.27534 -52.922424)
		(width 0.0889)
		(layer "In2.Cu")
		(net "M_C_CKE<0>")
	)
	(segment
		(start 246.043196 -22.446996)
		(end 246.195596 -22.599396)
		(width 0.14224)
		(layer "In2.Cu")
		(net "M_C_CKE<0>")
	)
	(segment
		(start 244.849904 1.805432)
		(end 244.849904 1.199896)
		(width 0.14224)
		(layer "In2.Cu")
		(net "M_C_CKE<0>")
	)
	(segment
		(start 246.195596 -23.107396)
		(end 245.8974 -23.405592)
		(width 0.14224)
		(layer "In2.Cu")
		(net "M_C_CKE<0>")
	)
	(segment
		(start 245.8974 -24.6634)
		(end 246.9388 -25.7048)
		(width 0.14224)
		(layer "In2.Cu")
		(net "M_C_CKE<0>")
	)
	(segment
		(start 252.191774 -51.782472)
		(end 252.270514 -51.923188)
		(width 0.0889)
		(layer "In2.Cu")
		(net "M_C_CKE<0>")
	)
	(arc
		(start 252.270514 -51.923188)
		(mid 252.32414 -52.12323)
		(end 252.270514 -52.323238)
		(width 0.0889)
		(layer "In2.Cu")
		(net "M_C_CKE<0>")
	)
	(arc
		(start 252.27534 -56.884824)
		(mid 252.324095 -57.081176)
		(end 252.270514 -57.276238)
		(width 0.0889)
		(layer "In2.Cu")
		(net "M_C_CKE<0>")
	)
	(arc
		(start 252.270514 -55.295038)
		(mid 252.191292 -55.584156)
		(end 252.264164 -55.87492)
		(width 0.0889)
		(layer "In2.Cu")
		(net "M_C_CKE<0>")
	)
	(arc
		(start 252.270514 -56.285638)
		(mid 252.191292 -56.574756)
		(end 252.264164 -56.86552)
		(width 0.0889)
		(layer "In2.Cu")
		(net "M_C_CKE<0>")
	)
	(arc
		(start 252.27534 -54.903624)
		(mid 252.324095 -55.099976)
		(end 252.270514 -55.295038)
		(width 0.0889)
		(layer "In2.Cu")
		(net "M_C_CKE<0>")
	)
	(arc
		(start 252.27534 -53.913024)
		(mid 252.324095 -54.109376)
		(end 252.270514 -54.304438)
		(width 0.0889)
		(layer "In2.Cu")
		(net "M_C_CKE<0>")
	)
	(arc
		(start 252.270514 -57.276238)
		(mid 252.191383 -57.57164)
		(end 252.270514 -57.867042)
		(width 0.0889)
		(layer "In2.Cu")
		(net "M_C_CKE<0>")
	)
	(arc
		(start 252.270514 -54.304438)
		(mid 252.191292 -54.593556)
		(end 252.264164 -54.88432)
		(width 0.0889)
		(layer "In2.Cu")
		(net "M_C_CKE<0>")
	)
	(arc
		(start 252.270514 -53.313838)
		(mid 252.191292 -53.602956)
		(end 252.264164 -53.89372)
		(width 0.0889)
		(layer "In2.Cu")
		(net "M_C_CKE<0>")
	)
	(arc
		(start 252.270514 -57.867042)
		(mid 252.324013 -58.06694)
		(end 252.270514 -58.266838)
		(width 0.0889)
		(layer "In2.Cu")
		(net "M_C_CKE<0>")
	)
	(arc
		(start 252.264164 -52.333906)
		(mid 252.191366 -52.624669)
		(end 252.270514 -52.913788)
		(width 0.0889)
		(layer "In2.Cu")
		(net "M_C_CKE<0>")
	)
	(arc
		(start 252.264164 -58.277506)
		(mid 252.191366 -58.568269)
		(end 252.270514 -58.857388)
		(width 0.0889)
		(layer "In2.Cu")
		(net "M_C_CKE<0>")
	)
	(arc
		(start 252.27534 -55.894224)
		(mid 252.324095 -56.090576)
		(end 252.270514 -56.285638)
		(width 0.0889)
		(layer "In2.Cu")
		(net "M_C_CKE<0>")
	)
	(arc
		(start 252.27534 -52.922424)
		(mid 252.324095 -53.118776)
		(end 252.270514 -53.313838)
		(width 0.0889)
		(layer "In2.Cu")
		(net "M_C_CKE<0>")
	)
	(segment
		(start 276.29993 -0.821182)
		(end 276.29993 1.152144)
		(width 0.1651)
		(layer "F.Cu")
		(net "M_C_C<2>")
	)
	(segment
		(start 276.300438 -0.821182)
		(end 276.29993 -0.821182)
		(width 0.1651)
		(layer "F.Cu")
		(net "M_C_C<2>")
	)
	(segment
		(start 267.948156 -60.047886)
		(end 268.557756 -60.047886)
		(width 0.1016)
		(layer "F.Cu")
		(net "M_C_C<2>")
	)
	(via
		(at 276.29993 1.152144)
		(size 0.508)
		(drill 0.254)
		(layers "F.Cu" "B.Cu")
		(net "M_C_C<2>")
	)
	(via
		(at 276.300438 -2.316988)
		(size 0.4572)
		(drill 0.2032)
		(layers "F.Cu" "B.Cu")
		(net "M_C_C<2>")
	)
	(via
		(at 268.557756 -60.047886)
		(size 0.508)
		(drill 0.254)
		(layers "F.Cu" "B.Cu")
		(net "M_C_C<2>")
	)
	(segment
		(start 276.300438 -1.021842)
		(end 276.29993 -1.021842)
		(width 0.1651)
		(layer "B.Cu")
		(net "M_C_C<2>")
	)
	(segment
		(start 276.29993 -2.31648)
		(end 276.300438 -2.316988)
		(width 0.1651)
		(layer "B.Cu")
		(net "M_C_C<2>")
	)
	(segment
		(start 276.29993 -1.021842)
		(end 276.29993 -2.31648)
		(width 0.1651)
		(layer "B.Cu")
		(net "M_C_C<2>")
	)
	(segment
		(start 270.017748 -49.590452)
		(end 268.9606 -50.6476)
		(width 0.14224)
		(layer "In11.Cu")
		(net "M_C_C<2>")
	)
	(segment
		(start 278.457152 -21.745448)
		(end 278.457152 -25.961848)
		(width 0.14224)
		(layer "In11.Cu")
		(net "M_C_C<2>")
	)
	(segment
		(start 278.4602 -21.7424)
		(end 278.457152 -21.745448)
		(width 0.14224)
		(layer "In11.Cu")
		(net "M_C_C<2>")
	)
	(segment
		(start 278.411432 -9.425432)
		(end 278.4602 -9.4742)
		(width 0.14224)
		(layer "In11.Cu")
		(net "M_C_C<2>")
	)
	(segment
		(start 277.800816 -5.472176)
		(end 277.343362 -5.92963)
		(width 0.14224)
		(layer "In11.Cu")
		(net "M_C_C<2>")
	)
	(segment
		(start 276.7076 -3.24358)
		(end 276.7076 -4.53771)
		(width 0.14224)
		(layer "In11.Cu")
		(net "M_C_C<2>")
	)
	(segment
		(start 276.300438 -2.316988)
		(end 276.29993 -2.317496)
		(width 0.14224)
		(layer "In11.Cu")
		(net "M_C_C<2>")
	)
	(segment
		(start 277.007828 -4.837938)
		(end 277.649178 -4.837938)
		(width 0.14224)
		(layer "In11.Cu")
		(net "M_C_C<2>")
	)
	(segment
		(start 277.343362 -6.67258)
		(end 277.590504 -6.919722)
		(width 0.14224)
		(layer "In11.Cu")
		(net "M_C_C<2>")
	)
	(segment
		(start 278.0792 -26.3398)
		(end 278.0792 -26.8986)
		(width 0.14224)
		(layer "In11.Cu")
		(net "M_C_C<2>")
	)
	(segment
		(start 278.0792 -26.8986)
		(end 278.252682 -27.072082)
		(width 0.14224)
		(layer "In11.Cu")
		(net "M_C_C<2>")
	)
	(segment
		(start 270.017748 -35.976052)
		(end 270.017748 -49.590452)
		(width 0.14224)
		(layer "In11.Cu")
		(net "M_C_C<2>")
	)
	(segment
		(start 277.590504 -6.919722)
		(end 277.590504 -7.893304)
		(width 0.14224)
		(layer "In11.Cu")
		(net "M_C_C<2>")
	)
	(segment
		(start 276.29993 1.152144)
		(end 276.29993 0.610616)
		(width 0.15494)
		(layer "In11.Cu")
		(net "M_C_C<2>")
	)
	(segment
		(start 277.800816 -4.989576)
		(end 277.800816 -5.472176)
		(width 0.14224)
		(layer "In11.Cu")
		(net "M_C_C<2>")
	)
	(segment
		(start 276.300438 0.610108)
		(end 276.300438 -2.316988)
		(width 0.14224)
		(layer "In11.Cu")
		(net "M_C_C<2>")
	)
	(segment
		(start 267.908024 -53.07203)
		(end 267.908024 -59.398154)
		(width 0.14224)
		(layer "In11.Cu")
		(net "M_C_C<2>")
	)
	(segment
		(start 278.411432 -8.714232)
		(end 278.411432 -9.425432)
		(width 0.14224)
		(layer "In11.Cu")
		(net "M_C_C<2>")
	)
	(segment
		(start 276.29993 -2.83591)
		(end 276.7076 -3.24358)
		(width 0.14224)
		(layer "In11.Cu")
		(net "M_C_C<2>")
	)
	(segment
		(start 278.252682 -27.072082)
		(end 278.252682 -27.741118)
		(width 0.15494)
		(layer "In11.Cu")
		(net "M_C_C<2>")
	)
	(segment
		(start 268.9606 -50.6476)
		(end 268.9606 -52.019454)
		(width 0.14224)
		(layer "In11.Cu")
		(net "M_C_C<2>")
	)
	(segment
		(start 268.9606 -52.019454)
		(end 267.908024 -53.07203)
		(width 0.14224)
		(layer "In11.Cu")
		(net "M_C_C<2>")
	)
	(segment
		(start 278.457152 -25.961848)
		(end 278.0792 -26.3398)
		(width 0.14224)
		(layer "In11.Cu")
		(net "M_C_C<2>")
	)
	(segment
		(start 277.590504 -7.893304)
		(end 278.411432 -8.714232)
		(width 0.14224)
		(layer "In11.Cu")
		(net "M_C_C<2>")
	)
	(segment
		(start 278.4602 -9.4742)
		(end 278.4602 -21.7424)
		(width 0.14224)
		(layer "In11.Cu")
		(net "M_C_C<2>")
	)
	(segment
		(start 276.7076 -4.53771)
		(end 277.007828 -4.837938)
		(width 0.14224)
		(layer "In11.Cu")
		(net "M_C_C<2>")
	)
	(segment
		(start 267.908024 -59.398154)
		(end 268.557756 -60.047886)
		(width 0.14224)
		(layer "In11.Cu")
		(net "M_C_C<2>")
	)
	(segment
		(start 277.343362 -5.92963)
		(end 277.343362 -6.67258)
		(width 0.14224)
		(layer "In11.Cu")
		(net "M_C_C<2>")
	)
	(segment
		(start 277.649178 -4.837938)
		(end 277.800816 -4.989576)
		(width 0.14224)
		(layer "In11.Cu")
		(net "M_C_C<2>")
	)
	(segment
		(start 278.252682 -27.741118)
		(end 270.017748 -35.976052)
		(width 0.14224)
		(layer "In11.Cu")
		(net "M_C_C<2>")
	)
	(segment
		(start 276.29993 -2.317496)
		(end 276.29993 -2.83591)
		(width 0.14224)
		(layer "In11.Cu")
		(net "M_C_C<2>")
	)
	(segment
		(start 276.29993 0.610616)
		(end 276.300438 0.610108)
		(width 0.15494)
		(layer "In11.Cu")
		(net "M_C_C<2>")
	)
	(segment
		(start 247.400318 -0.821182)
		(end 247.39981 -0.821182)
		(width 0.1651)
		(layer "F.Cu")
		(net "M_C_BG<1>")
	)
	(segment
		(start 253.353824 -61.53404)
		(end 252.782324 -61.53404)
		(width 0.1016)
		(layer "F.Cu")
		(net "M_C_BG<1>")
	)
	(segment
		(start 247.39981 -0.821182)
		(end 247.39981 1.152144)
		(width 0.1651)
		(layer "F.Cu")
		(net "M_C_BG<1>")
	)
	(via
		(at 247.39981 -2.314956)
		(size 0.4572)
		(drill 0.2032)
		(layers "F.Cu" "B.Cu")
		(net "M_C_BG<1>")
	)
	(via
		(at 247.39981 1.152144)
		(size 0.508)
		(drill 0.254)
		(layers "F.Cu" "B.Cu")
		(net "M_C_BG<1>")
	)
	(via
		(at 252.782324 -61.53404)
		(size 0.508)
		(drill 0.254)
		(layers "F.Cu" "B.Cu")
		(net "M_C_BG<1>")
	)
	(segment
		(start 247.39981 -1.021842)
		(end 247.39981 -2.314956)
		(width 0.1651)
		(layer "B.Cu")
		(net "M_C_BG<1>")
	)
	(segment
		(start 247.400318 -1.021842)
		(end 247.39981 -1.021842)
		(width 0.1651)
		(layer "B.Cu")
		(net "M_C_BG<1>")
	)
	(segment
		(start 255.6002 -20.310602)
		(end 255.6002 -18.695416)
		(width 0.14224)
		(layer "In11.Cu")
		(net "M_C_BG<1>")
	)
	(segment
		(start 252.782324 -61.53404)
		(end 253.27737 -60.868052)
		(width 0.0889)
		(layer "In11.Cu")
		(net "M_C_BG<1>")
	)
	(segment
		(start 252.091698 -8.658098)
		(end 251.24029 -7.80669)
		(width 0.14224)
		(layer "In11.Cu")
		(net "M_C_BG<1>")
	)
	(segment
		(start 255.6002 -18.695416)
		(end 254.635 -17.730216)
		(width 0.14224)
		(layer "In11.Cu")
		(net "M_C_BG<1>")
	)
	(segment
		(start 251.6251 -10.96772)
		(end 251.6251 -10.53084)
		(width 0.14224)
		(layer "In11.Cu")
		(net "M_C_BG<1>")
	)
	(segment
		(start 252.091698 -10.064242)
		(end 252.091698 -8.658098)
		(width 0.14224)
		(layer "In11.Cu")
		(net "M_C_BG<1>")
	)
	(segment
		(start 255.87579 -53.819806)
		(end 255.86944 -53.809138)
		(width 0.0889)
		(layer "In11.Cu")
		(net "M_C_BG<1>")
	)
	(segment
		(start 255.581404 -26.526236)
		(end 255.581404 -27.913076)
		(width 0.14224)
		(layer "In11.Cu")
		(net "M_C_BG<1>")
	)
	(segment
		(start 248.5644 -6.4516)
		(end 248.5644 -5.756148)
		(width 0.14224)
		(layer "In11.Cu")
		(net "M_C_BG<1>")
	)
	(segment
		(start 255.38811 -28.10637)
		(end 254.928878 -28.10637)
		(width 0.14224)
		(layer "In11.Cu")
		(net "M_C_BG<1>")
	)
	(segment
		(start 251.24029 -7.80669)
		(end 251.24029 -6.91769)
		(width 0.14224)
		(layer "In11.Cu")
		(net "M_C_BG<1>")
	)
	(segment
		(start 254.516382 -25.510236)
		(end 254.516382 -23.156672)
		(width 0.14224)
		(layer "In11.Cu")
		(net "M_C_BG<1>")
	)
	(segment
		(start 254.645922 -23.027132)
		(end 254.645922 -22.449282)
		(width 0.14224)
		(layer "In11.Cu")
		(net "M_C_BG<1>")
	)
	(segment
		(start 254.699008 -21.777706)
		(end 254.699008 -21.211794)
		(width 0.14224)
		(layer "In11.Cu")
		(net "M_C_BG<1>")
	)
	(segment
		(start 253.1618 -13.2334)
		(end 252.08738 -12.15898)
		(width 0.14224)
		(layer "In11.Cu")
		(net "M_C_BG<1>")
	)
	(segment
		(start 247.816878 -5.008626)
		(end 247.816878 -2.732024)
		(width 0.14224)
		(layer "In11.Cu")
		(net "M_C_BG<1>")
	)
	(segment
		(start 254.699008 -21.211794)
		(end 255.6002 -20.310602)
		(width 0.14224)
		(layer "In11.Cu")
		(net "M_C_BG<1>")
	)
	(segment
		(start 256.203704 -52.02682)
		(end 256.394204 -51.201574)
		(width 0.0889)
		(layer "In11.Cu")
		(net "M_C_BG<1>")
	)
	(segment
		(start 253.79172 -14.39418)
		(end 253.79172 -13.42644)
		(width 0.14224)
		(layer "In11.Cu")
		(net "M_C_BG<1>")
	)
	(segment
		(start 256.394204 -50.562256)
		(end 256.394204 -26.526236)
		(width 0.14224)
		(layer "In11.Cu")
		(net "M_C_BG<1>")
	)
	(segment
		(start 253.79172 -13.42644)
		(end 253.59868 -13.2334)
		(width 0.14224)
		(layer "In11.Cu")
		(net "M_C_BG<1>")
	)
	(segment
		(start 252.08738 -12.15898)
		(end 252.08738 -11.43)
		(width 0.14224)
		(layer "In11.Cu")
		(net "M_C_BG<1>")
	)
	(segment
		(start 254.635 -17.730216)
		(end 254.635 -15.23746)
		(width 0.14224)
		(layer "In11.Cu")
		(net "M_C_BG<1>")
	)
	(segment
		(start 255.581404 -27.913076)
		(end 255.38811 -28.10637)
		(width 0.14224)
		(layer "In11.Cu")
		(net "M_C_BG<1>")
	)
	(segment
		(start 255.750314 -59.23661)
		(end 255.815846 -58.88482)
		(width 0.0889)
		(layer "In11.Cu")
		(net "M_C_BG<1>")
	)
	(segment
		(start 252.08738 -11.43)
		(end 251.6251 -10.96772)
		(width 0.14224)
		(layer "In11.Cu")
		(net "M_C_BG<1>")
	)
	(segment
		(start 255.784604 -26.323036)
		(end 255.581404 -26.526236)
		(width 0.14224)
		(layer "In11.Cu")
		(net "M_C_BG<1>")
	)
	(segment
		(start 255.86944 -53.409088)
		(end 256.203704 -52.864512)
		(width 0.0889)
		(layer "In11.Cu")
		(net "M_C_BG<1>")
	)
	(segment
		(start 254.928878 -28.10637)
		(end 254.768604 -27.946096)
		(width 0.14224)
		(layer "In11.Cu")
		(net "M_C_BG<1>")
	)
	(segment
		(start 254.569468 -21.907246)
		(end 254.699008 -21.777706)
		(width 0.14224)
		(layer "In11.Cu")
		(net "M_C_BG<1>")
	)
	(segment
		(start 255.86944 -53.809138)
		(end 255.864614 -53.800502)
		(width 0.0889)
		(layer "In11.Cu")
		(net "M_C_BG<1>")
	)
	(segment
		(start 253.439676 -60.692538)
		(end 255.407414 -59.535822)
		(width 0.0889)
		(layer "In11.Cu")
		(net "M_C_BG<1>")
	)
	(segment
		(start 247.816878 -2.732024)
		(end 247.39981 -2.314956)
		(width 0.14224)
		(layer "In11.Cu")
		(net "M_C_BG<1>")
	)
	(segment
		(start 256.394204 -26.526236)
		(end 256.191004 -26.323036)
		(width 0.14224)
		(layer "In11.Cu")
		(net "M_C_BG<1>")
	)
	(segment
		(start 254.516382 -23.156672)
		(end 254.645922 -23.027132)
		(width 0.14224)
		(layer "In11.Cu")
		(net "M_C_BG<1>")
	)
	(segment
		(start 253.27737 -60.868052)
		(end 253.294134 -60.838588)
		(width 0.0889)
		(layer "In11.Cu")
		(net "M_C_BG<1>")
	)
	(segment
		(start 247.39981 -2.314956)
		(end 247.39981 1.152144)
		(width 0.14224)
		(layer "In11.Cu")
		(net "M_C_BG<1>")
	)
	(segment
		(start 254.768604 -25.762458)
		(end 254.516382 -25.510236)
		(width 0.14224)
		(layer "In11.Cu")
		(net "M_C_BG<1>")
	)
	(segment
		(start 251.24029 -6.91769)
		(end 250.9774 -6.6548)
		(width 0.14224)
		(layer "In11.Cu")
		(net "M_C_BG<1>")
	)
	(segment
		(start 255.407414 -59.535822)
		(end 255.528318 -59.458606)
		(width 0.0889)
		(layer "In11.Cu")
		(net "M_C_BG<1>")
	)
	(segment
		(start 254.645922 -22.449282)
		(end 254.569468 -22.372828)
		(width 0.14224)
		(layer "In11.Cu")
		(net "M_C_BG<1>")
	)
	(segment
		(start 248.5644 -5.756148)
		(end 247.816878 -5.008626)
		(width 0.14224)
		(layer "In11.Cu")
		(net "M_C_BG<1>")
	)
	(segment
		(start 251.6251 -10.53084)
		(end 252.091698 -10.064242)
		(width 0.14224)
		(layer "In11.Cu")
		(net "M_C_BG<1>")
	)
	(segment
		(start 250.9774 -6.6548)
		(end 248.7676 -6.6548)
		(width 0.14224)
		(layer "In11.Cu")
		(net "M_C_BG<1>")
	)
	(segment
		(start 254.635 -15.23746)
		(end 253.79172 -14.39418)
		(width 0.14224)
		(layer "In11.Cu")
		(net "M_C_BG<1>")
	)
	(segment
		(start 253.59868 -13.2334)
		(end 253.1618 -13.2334)
		(width 0.14224)
		(layer "In11.Cu")
		(net "M_C_BG<1>")
	)
	(segment
		(start 256.191004 -26.323036)
		(end 255.784604 -26.323036)
		(width 0.14224)
		(layer "In11.Cu")
		(net "M_C_BG<1>")
	)
	(segment
		(start 255.528318 -59.458606)
		(end 255.750314 -59.23661)
		(width 0.0889)
		(layer "In11.Cu")
		(net "M_C_BG<1>")
	)
	(segment
		(start 254.768604 -27.946096)
		(end 254.768604 -25.762458)
		(width 0.14224)
		(layer "In11.Cu")
		(net "M_C_BG<1>")
	)
	(segment
		(start 248.7676 -6.6548)
		(end 248.5644 -6.4516)
		(width 0.14224)
		(layer "In11.Cu")
		(net "M_C_BG<1>")
	)
	(segment
		(start 254.569468 -22.372828)
		(end 254.569468 -21.907246)
		(width 0.14224)
		(layer "In11.Cu")
		(net "M_C_BG<1>")
	)
	(segment
		(start 256.394204 -51.201574)
		(end 256.394204 -50.562256)
		(width 0.0889)
		(layer "In11.Cu")
		(net "M_C_BG<1>")
	)
	(segment
		(start 255.815846 -58.88482)
		(end 255.815846 -54.604666)
		(width 0.0889)
		(layer "In11.Cu")
		(net "M_C_BG<1>")
	)
	(segment
		(start 256.203704 -52.864512)
		(end 256.203704 -52.02682)
		(width 0.0889)
		(layer "In11.Cu")
		(net "M_C_BG<1>")
	)
	(arc
		(start 255.815846 -54.604666)
		(mid 255.828838 -54.498568)
		(end 255.86944 -54.399688)
		(width 0.0889)
		(layer "In11.Cu")
		(net "M_C_BG<1>")
	)
	(arc
		(start 253.294134 -60.838588)
		(mid 253.357331 -60.75602)
		(end 253.439676 -60.692538)
		(width 0.0889)
		(layer "In11.Cu")
		(net "M_C_BG<1>")
	)
	(arc
		(start 255.864614 -53.800502)
		(mid 255.815859 -53.60415)
		(end 255.86944 -53.409088)
		(width 0.0889)
		(layer "In11.Cu")
		(net "M_C_BG<1>")
	)
	(arc
		(start 255.86944 -54.399688)
		(mid 255.948662 -54.11057)
		(end 255.87579 -53.819806)
		(width 0.0889)
		(layer "In11.Cu")
		(net "M_C_BG<1>")
	)
	(segment
		(start 247.400318 3.778758)
		(end 247.39981 3.778758)
		(width 0.1651)
		(layer "F.Cu")
		(net "M_C_BG<0>")
	)
	(segment
		(start 255.07061 -59.55284)
		(end 254.49911 -59.55284)
		(width 0.1016)
		(layer "F.Cu")
		(net "M_C_BG<0>")
	)
	(segment
		(start 247.39981 3.778758)
		(end 247.39981 2.514854)
		(width 0.1651)
		(layer "F.Cu")
		(net "M_C_BG<0>")
	)
	(via
		(at 247.39981 2.514854)
		(size 0.508)
		(drill 0.254)
		(layers "F.Cu" "B.Cu")
		(net "M_C_BG<0>")
	)
	(via
		(at 254.49911 -59.55284)
		(size 0.508)
		(drill 0.254)
		(layers "F.Cu" "B.Cu")
		(net "M_C_BG<0>")
	)
	(via
		(at 247.39981 -4.332478)
		(size 0.4572)
		(drill 0.2032)
		(layers "F.Cu" "B.Cu")
		(net "M_C_BG<0>")
	)
	(segment
		(start 247.39981 -5.621782)
		(end 247.39981 -4.332478)
		(width 0.1651)
		(layer "B.Cu")
		(net "M_C_BG<0>")
	)
	(segment
		(start 247.400318 -5.621782)
		(end 247.39981 -5.621782)
		(width 0.1651)
		(layer "B.Cu")
		(net "M_C_BG<0>")
	)
	(segment
		(start 253.294134 -56.876188)
		(end 253.289308 -56.884824)
		(width 0.0889)
		(layer "In2.Cu")
		(net "M_C_BG<0>")
	)
	(segment
		(start 248.509028 -13.043408)
		(end 248.509028 -13.435584)
		(width 0.14224)
		(layer "In2.Cu")
		(net "M_C_BG<0>")
	)
	(segment
		(start 253.9873 -58.857388)
		(end 254.003302 -58.885328)
		(width 0.0889)
		(layer "In2.Cu")
		(net "M_C_BG<0>")
	)
	(segment
		(start 249.7328 -26.92781)
		(end 253.722124 -30.917134)
		(width 0.14224)
		(layer "In2.Cu")
		(net "M_C_BG<0>")
	)
	(segment
		(start 253.335282 -58.338212)
		(end 253.598934 -58.551064)
		(width 0.0889)
		(layer "In2.Cu")
		(net "M_C_BG<0>")
	)
	(segment
		(start 248.666 -3.066288)
		(end 247.39981 -4.332478)
		(width 0.14224)
		(layer "In2.Cu")
		(net "M_C_BG<0>")
	)
	(segment
		(start 248.66092 -8.833866)
		(end 248.66092 -12.215876)
		(width 0.14224)
		(layer "In2.Cu")
		(net "M_C_BG<0>")
	)
	(segment
		(start 248.6914 -13.617956)
		(end 248.6914 -16.920718)
		(width 0.14224)
		(layer "In2.Cu")
		(net "M_C_BG<0>")
	)
	(segment
		(start 248.520966 -18.386552)
		(end 248.66346 -18.529046)
		(width 0.14224)
		(layer "In2.Cu")
		(net "M_C_BG<0>")
	)
	(segment
		(start 248.829322 -22.414738)
		(end 248.57964 -22.66442)
		(width 0.14224)
		(layer "In2.Cu")
		(net "M_C_BG<0>")
	)
	(segment
		(start 248.75744 -23.285196)
		(end 248.75744 -24.78024)
		(width 0.14224)
		(layer "In2.Cu")
		(net "M_C_BG<0>")
	)
	(segment
		(start 253.722124 -51.246786)
		(end 253.294134 -51.923442)
		(width 0.0889)
		(layer "In2.Cu")
		(net "M_C_BG<0>")
	)
	(segment
		(start 248.75744 -6.669786)
		(end 248.6914 -6.735826)
		(width 0.14224)
		(layer "In2.Cu")
		(net "M_C_BG<0>")
	)
	(segment
		(start 253.722124 -30.917134)
		(end 253.722124 -51.052476)
		(width 0.14224)
		(layer "In2.Cu")
		(net "M_C_BG<0>")
	)
	(segment
		(start 247.39981 1.97739)
		(end 248.816876 0.560324)
		(width 0.14224)
		(layer "In2.Cu")
		(net "M_C_BG<0>")
	)
	(segment
		(start 253.300484 -53.89372)
		(end 253.294134 -53.904388)
		(width 0.0889)
		(layer "In2.Cu")
		(net "M_C_BG<0>")
	)
	(segment
		(start 253.294134 -52.323238)
		(end 253.300484 -52.333906)
		(width 0.0889)
		(layer "In2.Cu")
		(net "M_C_BG<0>")
	)
	(segment
		(start 248.520966 -17.87906)
		(end 248.520966 -18.386552)
		(width 0.14224)
		(layer "In2.Cu")
		(net "M_C_BG<0>")
	)
	(segment
		(start 254.003302 -58.885328)
		(end 254.49911 -59.55284)
		(width 0.0889)
		(layer "In2.Cu")
		(net "M_C_BG<0>")
	)
	(segment
		(start 248.60504 -21.761196)
		(end 248.829322 -21.985478)
		(width 0.14224)
		(layer "In2.Cu")
		(net "M_C_BG<0>")
	)
	(segment
		(start 253.294134 -58.266838)
		(end 253.335282 -58.338212)
		(width 0.0889)
		(layer "In2.Cu")
		(net "M_C_BG<0>")
	)
	(segment
		(start 253.722124 -51.052476)
		(end 253.722124 -51.246786)
		(width 0.0889)
		(layer "In2.Cu")
		(net "M_C_BG<0>")
	)
	(segment
		(start 253.300484 -54.88432)
		(end 253.294134 -54.894988)
		(width 0.0889)
		(layer "In2.Cu")
		(net "M_C_BG<0>")
	)
	(segment
		(start 253.300484 -55.87492)
		(end 253.294134 -55.885588)
		(width 0.0889)
		(layer "In2.Cu")
		(net "M_C_BG<0>")
	)
	(segment
		(start 248.81713 -12.735306)
		(end 248.509028 -13.043408)
		(width 0.14224)
		(layer "In2.Cu")
		(net "M_C_BG<0>")
	)
	(segment
		(start 248.88444 -7.48919)
		(end 248.88444 -7.914386)
		(width 0.14224)
		(layer "In2.Cu")
		(net "M_C_BG<0>")
	)
	(segment
		(start 248.66346 -19.082766)
		(end 248.60504 -19.141186)
		(width 0.14224)
		(layer "In2.Cu")
		(net "M_C_BG<0>")
	)
	(segment
		(start 248.509028 -13.435584)
		(end 248.6914 -13.617956)
		(width 0.14224)
		(layer "In2.Cu")
		(net "M_C_BG<0>")
	)
	(segment
		(start 248.524014 -8.274812)
		(end 248.524014 -8.69696)
		(width 0.14224)
		(layer "In2.Cu")
		(net "M_C_BG<0>")
	)
	(segment
		(start 248.66092 -12.215876)
		(end 248.81713 -12.372086)
		(width 0.14224)
		(layer "In2.Cu")
		(net "M_C_BG<0>")
	)
	(segment
		(start 248.75744 -5.690108)
		(end 248.75744 -6.669786)
		(width 0.14224)
		(layer "In2.Cu")
		(net "M_C_BG<0>")
	)
	(segment
		(start 253.294134 -55.885588)
		(end 253.289308 -55.894224)
		(width 0.0889)
		(layer "In2.Cu")
		(net "M_C_BG<0>")
	)
	(segment
		(start 248.816876 0.560324)
		(end 248.816876 -1.044956)
		(width 0.14224)
		(layer "In2.Cu")
		(net "M_C_BG<0>")
	)
	(segment
		(start 248.81713 -12.372086)
		(end 248.81713 -12.735306)
		(width 0.14224)
		(layer "In2.Cu")
		(net "M_C_BG<0>")
	)
	(segment
		(start 248.816876 -1.044956)
		(end 248.666 -1.195832)
		(width 0.14224)
		(layer "In2.Cu")
		(net "M_C_BG<0>")
	)
	(segment
		(start 253.294134 -53.904388)
		(end 253.289308 -53.913024)
		(width 0.0889)
		(layer "In2.Cu")
		(net "M_C_BG<0>")
	)
	(segment
		(start 248.88444 -7.914386)
		(end 248.524014 -8.274812)
		(width 0.14224)
		(layer "In2.Cu")
		(net "M_C_BG<0>")
	)
	(segment
		(start 247.39981 2.514854)
		(end 247.39981 1.97739)
		(width 0.14224)
		(layer "In2.Cu")
		(net "M_C_BG<0>")
	)
	(segment
		(start 248.6914 -16.920718)
		(end 248.844562 -17.07388)
		(width 0.14224)
		(layer "In2.Cu")
		(net "M_C_BG<0>")
	)
	(segment
		(start 248.66346 -18.529046)
		(end 248.66346 -19.082766)
		(width 0.14224)
		(layer "In2.Cu")
		(net "M_C_BG<0>")
	)
	(segment
		(start 253.598934 -58.551064)
		(end 253.849632 -58.716164)
		(width 0.0889)
		(layer "In2.Cu")
		(net "M_C_BG<0>")
	)
	(segment
		(start 253.294134 -54.894988)
		(end 253.289308 -54.903624)
		(width 0.0889)
		(layer "In2.Cu")
		(net "M_C_BG<0>")
	)
	(segment
		(start 253.300484 -56.86552)
		(end 253.294134 -56.876188)
		(width 0.0889)
		(layer "In2.Cu")
		(net "M_C_BG<0>")
	)
	(segment
		(start 248.60504 -19.141186)
		(end 248.60504 -21.761196)
		(width 0.14224)
		(layer "In2.Cu")
		(net "M_C_BG<0>")
	)
	(segment
		(start 248.844562 -17.555464)
		(end 248.520966 -17.87906)
		(width 0.14224)
		(layer "In2.Cu")
		(net "M_C_BG<0>")
	)
	(segment
		(start 253.294134 -52.913788)
		(end 253.289308 -52.922424)
		(width 0.0889)
		(layer "In2.Cu")
		(net "M_C_BG<0>")
	)
	(segment
		(start 248.57964 -22.66442)
		(end 248.57964 -23.107396)
		(width 0.14224)
		(layer "In2.Cu")
		(net "M_C_BG<0>")
	)
	(segment
		(start 248.844562 -17.07388)
		(end 248.844562 -17.555464)
		(width 0.14224)
		(layer "In2.Cu")
		(net "M_C_BG<0>")
	)
	(segment
		(start 248.6914 -7.29615)
		(end 248.88444 -7.48919)
		(width 0.14224)
		(layer "In2.Cu")
		(net "M_C_BG<0>")
	)
	(segment
		(start 248.6914 -6.735826)
		(end 248.6914 -7.29615)
		(width 0.14224)
		(layer "In2.Cu")
		(net "M_C_BG<0>")
	)
	(segment
		(start 248.524014 -8.69696)
		(end 248.66092 -8.833866)
		(width 0.14224)
		(layer "In2.Cu")
		(net "M_C_BG<0>")
	)
	(segment
		(start 248.75744 -24.78024)
		(end 249.7328 -25.7556)
		(width 0.14224)
		(layer "In2.Cu")
		(net "M_C_BG<0>")
	)
	(segment
		(start 247.39981 -4.332478)
		(end 248.75744 -5.690108)
		(width 0.14224)
		(layer "In2.Cu")
		(net "M_C_BG<0>")
	)
	(segment
		(start 249.7328 -25.7556)
		(end 249.7328 -26.92781)
		(width 0.14224)
		(layer "In2.Cu")
		(net "M_C_BG<0>")
	)
	(segment
		(start 248.829322 -21.985478)
		(end 248.829322 -22.414738)
		(width 0.14224)
		(layer "In2.Cu")
		(net "M_C_BG<0>")
	)
	(segment
		(start 248.57964 -23.107396)
		(end 248.75744 -23.285196)
		(width 0.14224)
		(layer "In2.Cu")
		(net "M_C_BG<0>")
	)
	(segment
		(start 248.666 -1.195832)
		(end 248.666 -3.066288)
		(width 0.14224)
		(layer "In2.Cu")
		(net "M_C_BG<0>")
	)
	(arc
		(start 253.289308 -53.913024)
		(mid 253.240553 -54.109376)
		(end 253.294134 -54.304438)
		(width 0.0889)
		(layer "In2.Cu")
		(net "M_C_BG<0>")
	)
	(arc
		(start 253.294134 -51.923442)
		(mid 253.240635 -52.12334)
		(end 253.294134 -52.323238)
		(width 0.0889)
		(layer "In2.Cu")
		(net "M_C_BG<0>")
	)
	(arc
		(start 253.294134 -57.276238)
		(mid 253.373265 -57.57164)
		(end 253.294134 -57.867042)
		(width 0.0889)
		(layer "In2.Cu")
		(net "M_C_BG<0>")
	)
	(arc
		(start 253.289308 -55.894224)
		(mid 253.240553 -56.090576)
		(end 253.294134 -56.285638)
		(width 0.0889)
		(layer "In2.Cu")
		(net "M_C_BG<0>")
	)
	(arc
		(start 253.289308 -54.903624)
		(mid 253.240553 -55.099976)
		(end 253.294134 -55.295038)
		(width 0.0889)
		(layer "In2.Cu")
		(net "M_C_BG<0>")
	)
	(arc
		(start 253.849632 -58.716164)
		(mid 253.92729 -58.778171)
		(end 253.9873 -58.857388)
		(width 0.0889)
		(layer "In2.Cu")
		(net "M_C_BG<0>")
	)
	(arc
		(start 253.294134 -56.285638)
		(mid 253.373356 -56.574756)
		(end 253.300484 -56.86552)
		(width 0.0889)
		(layer "In2.Cu")
		(net "M_C_BG<0>")
	)
	(arc
		(start 253.294134 -57.867042)
		(mid 253.240635 -58.06694)
		(end 253.294134 -58.266838)
		(width 0.0889)
		(layer "In2.Cu")
		(net "M_C_BG<0>")
	)
	(arc
		(start 253.294134 -54.304438)
		(mid 253.373356 -54.593556)
		(end 253.300484 -54.88432)
		(width 0.0889)
		(layer "In2.Cu")
		(net "M_C_BG<0>")
	)
	(arc
		(start 253.294134 -53.313838)
		(mid 253.373356 -53.602956)
		(end 253.300484 -53.89372)
		(width 0.0889)
		(layer "In2.Cu")
		(net "M_C_BG<0>")
	)
	(arc
		(start 253.300484 -52.333906)
		(mid 253.373282 -52.624669)
		(end 253.294134 -52.913788)
		(width 0.0889)
		(layer "In2.Cu")
		(net "M_C_BG<0>")
	)
	(arc
		(start 253.289308 -56.884824)
		(mid 253.240553 -57.081176)
		(end 253.294134 -57.276238)
		(width 0.0889)
		(layer "In2.Cu")
		(net "M_C_BG<0>")
	)
	(arc
		(start 253.294134 -55.295038)
		(mid 253.373356 -55.584156)
		(end 253.300484 -55.87492)
		(width 0.0889)
		(layer "In2.Cu")
		(net "M_C_BG<0>")
	)
	(arc
		(start 253.289308 -52.922424)
		(mid 253.240553 -53.118776)
		(end 253.294134 -53.313838)
		(width 0.0889)
		(layer "In2.Cu")
		(net "M_C_BG<0>")
	)
	(segment
		(start 258.50469 -61.53404)
		(end 257.93319 -61.53404)
		(width 0.1016)
		(layer "F.Cu")
		(net "M_C_BA<1>")
	)
	(segment
		(start 266.949936 -0.821182)
		(end 266.949936 0.442468)
		(width 0.1651)
		(layer "F.Cu")
		(net "M_C_BA<1>")
	)
	(segment
		(start 266.949936 0.442468)
		(end 266.949682 0.442722)
		(width 0.1651)
		(layer "F.Cu")
		(net "M_C_BA<1>")
	)
	(segment
		(start 266.950444 -0.821182)
		(end 266.949936 -0.821182)
		(width 0.1651)
		(layer "F.Cu")
		(net "M_C_BA<1>")
	)
	(via
		(at 257.93319 -61.53404)
		(size 0.508)
		(drill 0.254)
		(layers "F.Cu" "B.Cu")
		(net "M_C_BA<1>")
	)
	(via
		(at 266.949682 0.442722)
		(size 0.508)
		(drill 0.254)
		(layers "F.Cu" "B.Cu")
		(net "M_C_BA<1>")
	)
	(via
		(at 266.95019 -2.316988)
		(size 0.4572)
		(drill 0.2032)
		(layers "F.Cu" "B.Cu")
		(net "M_C_BA<1>")
	)
	(segment
		(start 266.950444 -1.021842)
		(end 266.949936 -1.021842)
		(width 0.1651)
		(layer "B.Cu")
		(net "M_C_BA<1>")
	)
	(segment
		(start 266.949936 -1.021842)
		(end 266.949936 -2.316734)
		(width 0.1651)
		(layer "B.Cu")
		(net "M_C_BA<1>")
	)
	(segment
		(start 266.949936 -2.316734)
		(end 266.95019 -2.316988)
		(width 0.1651)
		(layer "B.Cu")
		(net "M_C_BA<1>")
	)
	(segment
		(start 258.200652 -53.762148)
		(end 258.3434 -53.6194)
		(width 0.0889)
		(layer "In11.Cu")
		(net "M_C_BA<1>")
	)
	(segment
		(start 265.202162 -6.392418)
		(end 266.50823 -5.08635)
		(width 0.14224)
		(layer "In11.Cu")
		(net "M_C_BA<1>")
	)
	(segment
		(start 266.95019 -2.316988)
		(end 266.95019 -1.298702)
		(width 0.14224)
		(layer "In11.Cu")
		(net "M_C_BA<1>")
	)
	(segment
		(start 266.79525 -0.351282)
		(end 266.95019 -0.196342)
		(width 0.14224)
		(layer "In11.Cu")
		(net "M_C_BA<1>")
	)
	(segment
		(start 266.79525 -1.143762)
		(end 266.230862 -1.143762)
		(width 0.14224)
		(layer "In11.Cu")
		(net "M_C_BA<1>")
	)
	(segment
		(start 266.08278 -0.99568)
		(end 266.08278 -0.51308)
		(width 0.14224)
		(layer "In11.Cu")
		(net "M_C_BA<1>")
	)
	(segment
		(start 260.131814 -24.572976)
		(end 260.131814 -22.500082)
		(width 0.14224)
		(layer "In11.Cu")
		(net "M_C_BA<1>")
	)
	(segment
		(start 266.76985 -3.58775)
		(end 266.76985 -3.175)
		(width 0.14224)
		(layer "In11.Cu")
		(net "M_C_BA<1>")
	)
	(segment
		(start 266.949682 -2.995168)
		(end 266.949682 -2.317496)
		(width 0.14224)
		(layer "In11.Cu")
		(net "M_C_BA<1>")
	)
	(segment
		(start 258.3434 -50.977546)
		(end 258.502404 -50.818542)
		(width 0.0889)
		(layer "In11.Cu")
		(net "M_C_BA<1>")
	)
	(segment
		(start 266.50823 -3.84937)
		(end 266.76985 -3.58775)
		(width 0.14224)
		(layer "In11.Cu")
		(net "M_C_BA<1>")
	)
	(segment
		(start 258.502404 -50.818542)
		(end 258.502404 -50.475896)
		(width 0.0889)
		(layer "In11.Cu")
		(net "M_C_BA<1>")
	)
	(segment
		(start 258.502404 -26.202386)
		(end 260.131814 -24.572976)
		(width 0.14224)
		(layer "In11.Cu")
		(net "M_C_BA<1>")
	)
	(segment
		(start 262.12165 -9.75995)
		(end 262.12165 -7.397496)
		(width 0.14224)
		(layer "In11.Cu")
		(net "M_C_BA<1>")
	)
	(segment
		(start 258.26339 -60.77204)
		(end 258.2799 -60.743592)
		(width 0.0889)
		(layer "In11.Cu")
		(net "M_C_BA<1>")
	)
	(segment
		(start 259.90296 -21.000212)
		(end 260.5278 -20.375372)
		(width 0.14224)
		(layer "In11.Cu")
		(net "M_C_BA<1>")
	)
	(segment
		(start 258.3434 -53.6194)
		(end 258.3434 -50.977546)
		(width 0.0889)
		(layer "In11.Cu")
		(net "M_C_BA<1>")
	)
	(segment
		(start 260.5278 -11.3538)
		(end 262.12165 -9.75995)
		(width 0.14224)
		(layer "In11.Cu")
		(net "M_C_BA<1>")
	)
	(segment
		(start 266.95019 -0.196342)
		(end 266.95019 0.442214)
		(width 0.14224)
		(layer "In11.Cu")
		(net "M_C_BA<1>")
	)
	(segment
		(start 266.949682 -2.317496)
		(end 266.95019 -2.316988)
		(width 0.14224)
		(layer "In11.Cu")
		(net "M_C_BA<1>")
	)
	(segment
		(start 260.5278 -20.375372)
		(end 260.5278 -11.3538)
		(width 0.14224)
		(layer "In11.Cu")
		(net "M_C_BA<1>")
	)
	(segment
		(start 258.502404 -50.475896)
		(end 258.502404 -26.202386)
		(width 0.14224)
		(layer "In11.Cu")
		(net "M_C_BA<1>")
	)
	(segment
		(start 259.90296 -22.271228)
		(end 259.90296 -21.000212)
		(width 0.14224)
		(layer "In11.Cu")
		(net "M_C_BA<1>")
	)
	(segment
		(start 262.12165 -7.397496)
		(end 263.126728 -6.392418)
		(width 0.14224)
		(layer "In11.Cu")
		(net "M_C_BA<1>")
	)
	(segment
		(start 266.244578 -0.351282)
		(end 266.79525 -0.351282)
		(width 0.14224)
		(layer "In11.Cu")
		(net "M_C_BA<1>")
	)
	(segment
		(start 266.76985 -3.175)
		(end 266.949682 -2.995168)
		(width 0.14224)
		(layer "In11.Cu")
		(net "M_C_BA<1>")
	)
	(segment
		(start 257.93319 -61.53404)
		(end 258.26339 -60.77204)
		(width 0.0889)
		(layer "In11.Cu")
		(net "M_C_BA<1>")
	)
	(segment
		(start 266.95019 0.442214)
		(end 266.949682 0.442722)
		(width 0.14224)
		(layer "In11.Cu")
		(net "M_C_BA<1>")
	)
	(segment
		(start 266.95019 -1.298702)
		(end 266.79525 -1.143762)
		(width 0.14224)
		(layer "In11.Cu")
		(net "M_C_BA<1>")
	)
	(segment
		(start 260.131814 -22.500082)
		(end 259.90296 -22.271228)
		(width 0.14224)
		(layer "In11.Cu")
		(net "M_C_BA<1>")
	)
	(segment
		(start 263.126728 -6.392418)
		(end 265.202162 -6.392418)
		(width 0.14224)
		(layer "In11.Cu")
		(net "M_C_BA<1>")
	)
	(segment
		(start 258.200652 -54.102)
		(end 258.200652 -53.762148)
		(width 0.0889)
		(layer "In11.Cu")
		(net "M_C_BA<1>")
	)
	(segment
		(start 266.50823 -5.08635)
		(end 266.50823 -3.84937)
		(width 0.14224)
		(layer "In11.Cu")
		(net "M_C_BA<1>")
	)
	(segment
		(start 266.230862 -1.143762)
		(end 266.08278 -0.99568)
		(width 0.14224)
		(layer "In11.Cu")
		(net "M_C_BA<1>")
	)
	(segment
		(start 266.08278 -0.51308)
		(end 266.244578 -0.351282)
		(width 0.14224)
		(layer "In11.Cu")
		(net "M_C_BA<1>")
	)
	(arc
		(start 258.2799 -60.743592)
		(mid 258.333399 -60.543694)
		(end 258.2799 -60.343796)
		(width 0.0889)
		(layer "In11.Cu")
		(net "M_C_BA<1>")
	)
	(arc
		(start 258.2799 -60.343796)
		(mid 258.200769 -60.048394)
		(end 258.2799 -59.752992)
		(width 0.0889)
		(layer "In11.Cu")
		(net "M_C_BA<1>")
	)
	(arc
		(start 258.2799 -57.371996)
		(mid 258.200769 -57.076594)
		(end 258.2799 -56.781192)
		(width 0.0889)
		(layer "In11.Cu")
		(net "M_C_BA<1>")
	)
	(arc
		(start 258.2799 -55.390796)
		(mid 258.200769 -55.095394)
		(end 258.2799 -54.799992)
		(width 0.0889)
		(layer "In11.Cu")
		(net "M_C_BA<1>")
	)
	(arc
		(start 258.2799 -57.771792)
		(mid 258.333399 -57.571894)
		(end 258.2799 -57.371996)
		(width 0.0889)
		(layer "In11.Cu")
		(net "M_C_BA<1>")
	)
	(arc
		(start 258.2799 -56.781192)
		(mid 258.333399 -56.581294)
		(end 258.2799 -56.381396)
		(width 0.0889)
		(layer "In11.Cu")
		(net "M_C_BA<1>")
	)
	(arc
		(start 258.2799 -54.400196)
		(mid 258.220472 -54.256361)
		(end 258.200652 -54.102)
		(width 0.0889)
		(layer "In11.Cu")
		(net "M_C_BA<1>")
	)
	(arc
		(start 258.2799 -58.362596)
		(mid 258.200769 -58.067194)
		(end 258.2799 -57.771792)
		(width 0.0889)
		(layer "In11.Cu")
		(net "M_C_BA<1>")
	)
	(arc
		(start 258.2799 -58.762392)
		(mid 258.333399 -58.562494)
		(end 258.2799 -58.362596)
		(width 0.0889)
		(layer "In11.Cu")
		(net "M_C_BA<1>")
	)
	(arc
		(start 258.2799 -55.790592)
		(mid 258.333399 -55.590694)
		(end 258.2799 -55.390796)
		(width 0.0889)
		(layer "In11.Cu")
		(net "M_C_BA<1>")
	)
	(arc
		(start 258.2799 -56.381396)
		(mid 258.200769 -56.085994)
		(end 258.2799 -55.790592)
		(width 0.0889)
		(layer "In11.Cu")
		(net "M_C_BA<1>")
	)
	(arc
		(start 258.2799 -54.799992)
		(mid 258.333399 -54.600094)
		(end 258.2799 -54.400196)
		(width 0.0889)
		(layer "In11.Cu")
		(net "M_C_BA<1>")
	)
	(arc
		(start 258.2799 -59.752992)
		(mid 258.333399 -59.553094)
		(end 258.2799 -59.353196)
		(width 0.0889)
		(layer "In11.Cu")
		(net "M_C_BA<1>")
	)
	(arc
		(start 258.2799 -59.353196)
		(mid 258.200769 -59.057794)
		(end 258.2799 -58.762392)
		(width 0.0889)
		(layer "In11.Cu")
		(net "M_C_BA<1>")
	)
	(segment
		(start 267.79982 3.778758)
		(end 267.79982 2.514854)
		(width 0.1651)
		(layer "F.Cu")
		(net "M_C_BA<0>")
	)
	(segment
		(start 267.800328 3.778758)
		(end 267.79982 3.778758)
		(width 0.1651)
		(layer "F.Cu")
		(net "M_C_BA<0>")
	)
	(segment
		(start 261.93877 -58.561986)
		(end 261.36727 -58.561986)
		(width 0.1016)
		(layer "F.Cu")
		(net "M_C_BA<0>")
	)
	(via
		(at 267.800074 -4.332478)
		(size 0.4572)
		(drill 0.2032)
		(layers "F.Cu" "B.Cu")
		(net "M_C_BA<0>")
	)
	(via
		(at 261.36727 -58.561986)
		(size 0.508)
		(drill 0.254)
		(layers "F.Cu" "B.Cu")
		(net "M_C_BA<0>")
	)
	(via
		(at 267.79982 2.514854)
		(size 0.508)
		(drill 0.254)
		(layers "F.Cu" "B.Cu")
		(net "M_C_BA<0>")
	)
	(segment
		(start 267.79982 -4.332732)
		(end 267.800074 -4.332478)
		(width 0.1651)
		(layer "B.Cu")
		(net "M_C_BA<0>")
	)
	(segment
		(start 267.800328 -5.621782)
		(end 267.79982 -5.621782)
		(width 0.1651)
		(layer "B.Cu")
		(net "M_C_BA<0>")
	)
	(segment
		(start 267.79982 -5.621782)
		(end 267.79982 -4.332732)
		(width 0.1651)
		(layer "B.Cu")
		(net "M_C_BA<0>")
	)
	(segment
		(start 263.968738 -28.961334)
		(end 263.795256 -28.787852)
		(width 0.14224)
		(layer "In2.Cu")
		(net "M_C_BA<0>")
	)
	(segment
		(start 266.59459 -18.379186)
		(end 266.59459 -17.794986)
		(width 0.14224)
		(layer "In2.Cu")
		(net "M_C_BA<0>")
	)
	(segment
		(start 266.562586 -23.1648)
		(end 266.562586 -22.516592)
		(width 0.14224)
		(layer "In2.Cu")
		(net "M_C_BA<0>")
	)
	(segment
		(start 262.932926 -29.362654)
		(end 263.220454 -29.362654)
		(width 0.14224)
		(layer "In2.Cu")
		(net "M_C_BA<0>")
	)
	(segment
		(start 261.71398 -56.780938)
		(end 261.718806 -56.772302)
		(width 0.0889)
		(layer "In2.Cu")
		(net "M_C_BA<0>")
	)
	(segment
		(start 266.53998 -14.595348)
		(end 266.513564 -14.568932)
		(width 0.14224)
		(layer "In2.Cu")
		(net "M_C_BA<0>")
	)
	(segment
		(start 267.462 0.7112)
		(end 267.3096 0.8636)
		(width 0.14224)
		(layer "In2.Cu")
		(net "M_C_BA<0>")
	)
	(segment
		(start 261.70763 -55.801006)
		(end 261.71398 -55.790338)
		(width 0.0889)
		(layer "In2.Cu")
		(net "M_C_BA<0>")
	)
	(segment
		(start 266.44219 -24.614378)
		(end 266.44219 -23.285196)
		(width 0.14224)
		(layer "In2.Cu")
		(net "M_C_BA<0>")
	)
	(segment
		(start 267.5128 -2.7686)
		(end 267.378942 -2.634742)
		(width 0.14224)
		(layer "In2.Cu")
		(net "M_C_BA<0>")
	)
	(segment
		(start 266.513564 -13.612622)
		(end 266.533884 -13.592302)
		(width 0.14224)
		(layer "In2.Cu")
		(net "M_C_BA<0>")
	)
	(segment
		(start 266.534138 -19.080734)
		(end 266.534138 -18.439638)
		(width 0.14224)
		(layer "In2.Cu")
		(net "M_C_BA<0>")
	)
	(segment
		(start 263.795256 -28.500324)
		(end 265.3284 -26.96718)
		(width 0.14224)
		(layer "In2.Cu")
		(net "M_C_BA<0>")
	)
	(segment
		(start 262.509 -48.679608)
		(end 262.69696 -48.491648)
		(width 0.0889)
		(layer "In2.Cu")
		(net "M_C_BA<0>")
	)
	(segment
		(start 261.71398 -55.790338)
		(end 261.718806 -55.781702)
		(width 0.0889)
		(layer "In2.Cu")
		(net "M_C_BA<0>")
	)
	(segment
		(start 266.562586 -22.516592)
		(end 266.47013 -22.424136)
		(width 0.14224)
		(layer "In2.Cu")
		(net "M_C_BA<0>")
	)
	(segment
		(start 266.509246 -19.84375)
		(end 266.636246 -19.71675)
		(width 0.14224)
		(layer "In2.Cu")
		(net "M_C_BA<0>")
	)
	(segment
		(start 266.710414 -20.840446)
		(end 266.506198 -20.63623)
		(width 0.14224)
		(layer "In2.Cu")
		(net "M_C_BA<0>")
	)
	(segment
		(start 266.53998 -17.036796)
		(end 266.53998 -14.595348)
		(width 0.14224)
		(layer "In2.Cu")
		(net "M_C_BA<0>")
	)
	(segment
		(start 267.3096 1.397)
		(end 267.79982 1.88722)
		(width 0.14224)
		(layer "In2.Cu")
		(net "M_C_BA<0>")
	)
	(segment
		(start 263.681464 -29.536136)
		(end 263.968738 -29.248862)
		(width 0.14224)
		(layer "In2.Cu")
		(net "M_C_BA<0>")
	)
	(segment
		(start 266.636246 -19.71675)
		(end 266.636246 -19.182842)
		(width 0.14224)
		(layer "In2.Cu")
		(net "M_C_BA<0>")
	)
	(segment
		(start 266.44219 -17.642586)
		(end 266.44219 -17.134586)
		(width 0.14224)
		(layer "In2.Cu")
		(net "M_C_BA<0>")
	)
	(segment
		(start 266.47013 -21.885656)
		(end 266.710414 -21.645372)
		(width 0.14224)
		(layer "In2.Cu")
		(net "M_C_BA<0>")
	)
	(segment
		(start 262.69696 -48.278034)
		(end 262.69696 -29.59862)
		(width 0.14224)
		(layer "In2.Cu")
		(net "M_C_BA<0>")
	)
	(segment
		(start 266.636246 -19.182842)
		(end 266.534138 -19.080734)
		(width 0.14224)
		(layer "In2.Cu")
		(net "M_C_BA<0>")
	)
	(segment
		(start 261.69747 -57.799986)
		(end 261.718806 -57.762902)
		(width 0.0889)
		(layer "In2.Cu")
		(net "M_C_BA<0>")
	)
	(segment
		(start 266.295378 -20.63623)
		(end 266.146534 -20.487386)
		(width 0.14224)
		(layer "In2.Cu")
		(net "M_C_BA<0>")
	)
	(segment
		(start 266.146534 -20.487386)
		(end 266.146534 -20.004786)
		(width 0.14224)
		(layer "In2.Cu")
		(net "M_C_BA<0>")
	)
	(segment
		(start 266.534138 -18.439638)
		(end 266.59459 -18.379186)
		(width 0.14224)
		(layer "In2.Cu")
		(net "M_C_BA<0>")
	)
	(segment
		(start 266.506198 -20.63623)
		(end 266.295378 -20.63623)
		(width 0.14224)
		(layer "In2.Cu")
		(net "M_C_BA<0>")
	)
	(segment
		(start 263.393936 -29.536136)
		(end 263.681464 -29.536136)
		(width 0.14224)
		(layer "In2.Cu")
		(net "M_C_BA<0>")
	)
	(segment
		(start 261.7724 -50.993294)
		(end 262.509 -50.256694)
		(width 0.0889)
		(layer "In2.Cu")
		(net "M_C_BA<0>")
	)
	(segment
		(start 267.800074 -4.332478)
		(end 267.5128 -4.045204)
		(width 0.14224)
		(layer "In2.Cu")
		(net "M_C_BA<0>")
	)
	(segment
		(start 267.79982 1.88722)
		(end 267.79982 2.514854)
		(width 0.14224)
		(layer "In2.Cu")
		(net "M_C_BA<0>")
	)
	(segment
		(start 267.5128 -4.045204)
		(end 267.5128 -2.7686)
		(width 0.14224)
		(layer "In2.Cu")
		(net "M_C_BA<0>")
	)
	(segment
		(start 263.795256 -28.787852)
		(end 263.795256 -28.500324)
		(width 0.14224)
		(layer "In2.Cu")
		(net "M_C_BA<0>")
	)
	(segment
		(start 266.513564 -14.568932)
		(end 266.513564 -13.612622)
		(width 0.14224)
		(layer "In2.Cu")
		(net "M_C_BA<0>")
	)
	(segment
		(start 261.36727 -58.561986)
		(end 261.69747 -57.799986)
		(width 0.0889)
		(layer "In2.Cu")
		(net "M_C_BA<0>")
	)
	(segment
		(start 266.533884 -13.592302)
		(end 266.533884 -5.598668)
		(width 0.14224)
		(layer "In2.Cu")
		(net "M_C_BA<0>")
	)
	(segment
		(start 262.509 -50.256694)
		(end 262.509 -48.679608)
		(width 0.0889)
		(layer "In2.Cu")
		(net "M_C_BA<0>")
	)
	(segment
		(start 261.71398 -53.809138)
		(end 261.718806 -53.800502)
		(width 0.0889)
		(layer "In2.Cu")
		(net "M_C_BA<0>")
	)
	(segment
		(start 261.7724 -52.600098)
		(end 261.7724 -50.993294)
		(width 0.0889)
		(layer "In2.Cu")
		(net "M_C_BA<0>")
	)
	(segment
		(start 266.59459 -17.794986)
		(end 266.44219 -17.642586)
		(width 0.14224)
		(layer "In2.Cu")
		(net "M_C_BA<0>")
	)
	(segment
		(start 261.71398 -54.799738)
		(end 261.718806 -54.791102)
		(width 0.0889)
		(layer "In2.Cu")
		(net "M_C_BA<0>")
	)
	(segment
		(start 265.3284 -26.96718)
		(end 265.3284 -25.728168)
		(width 0.14224)
		(layer "In2.Cu")
		(net "M_C_BA<0>")
	)
	(segment
		(start 261.70763 -53.819806)
		(end 261.71398 -53.809138)
		(width 0.0889)
		(layer "In2.Cu")
		(net "M_C_BA<0>")
	)
	(segment
		(start 263.220454 -29.362654)
		(end 263.393936 -29.536136)
		(width 0.14224)
		(layer "In2.Cu")
		(net "M_C_BA<0>")
	)
	(segment
		(start 266.533884 -5.598668)
		(end 267.800074 -4.332478)
		(width 0.14224)
		(layer "In2.Cu")
		(net "M_C_BA<0>")
	)
	(segment
		(start 266.44219 -23.285196)
		(end 266.562586 -23.1648)
		(width 0.14224)
		(layer "In2.Cu")
		(net "M_C_BA<0>")
	)
	(segment
		(start 266.44219 -17.134586)
		(end 266.53998 -17.036796)
		(width 0.14224)
		(layer "In2.Cu")
		(net "M_C_BA<0>")
	)
	(segment
		(start 262.69696 -29.59862)
		(end 262.932926 -29.362654)
		(width 0.14224)
		(layer "In2.Cu")
		(net "M_C_BA<0>")
	)
	(segment
		(start 267.378942 -0.235458)
		(end 267.462 -0.1524)
		(width 0.14224)
		(layer "In2.Cu")
		(net "M_C_BA<0>")
	)
	(segment
		(start 266.146534 -20.004786)
		(end 266.30757 -19.84375)
		(width 0.14224)
		(layer "In2.Cu")
		(net "M_C_BA<0>")
	)
	(segment
		(start 267.378942 -2.634742)
		(end 267.378942 -0.235458)
		(width 0.14224)
		(layer "In2.Cu")
		(net "M_C_BA<0>")
	)
	(segment
		(start 266.47013 -22.424136)
		(end 266.47013 -21.885656)
		(width 0.14224)
		(layer "In2.Cu")
		(net "M_C_BA<0>")
	)
	(segment
		(start 267.462 -0.1524)
		(end 267.462 0.7112)
		(width 0.14224)
		(layer "In2.Cu")
		(net "M_C_BA<0>")
	)
	(segment
		(start 267.3096 0.8636)
		(end 267.3096 1.397)
		(width 0.14224)
		(layer "In2.Cu")
		(net "M_C_BA<0>")
	)
	(segment
		(start 261.70763 -56.791606)
		(end 261.71398 -56.780938)
		(width 0.0889)
		(layer "In2.Cu")
		(net "M_C_BA<0>")
	)
	(segment
		(start 266.30757 -19.84375)
		(end 266.509246 -19.84375)
		(width 0.14224)
		(layer "In2.Cu")
		(net "M_C_BA<0>")
	)
	(segment
		(start 265.3284 -25.728168)
		(end 266.44219 -24.614378)
		(width 0.14224)
		(layer "In2.Cu")
		(net "M_C_BA<0>")
	)
	(segment
		(start 263.968738 -29.248862)
		(end 263.968738 -28.961334)
		(width 0.14224)
		(layer "In2.Cu")
		(net "M_C_BA<0>")
	)
	(segment
		(start 266.710414 -21.645372)
		(end 266.710414 -20.840446)
		(width 0.14224)
		(layer "In2.Cu")
		(net "M_C_BA<0>")
	)
	(segment
		(start 262.69696 -48.491648)
		(end 262.69696 -48.278034)
		(width 0.0889)
		(layer "In2.Cu")
		(net "M_C_BA<0>")
	)
	(segment
		(start 261.70763 -54.810406)
		(end 261.71398 -54.799738)
		(width 0.0889)
		(layer "In2.Cu")
		(net "M_C_BA<0>")
	)
	(arc
		(start 261.71398 -55.390288)
		(mid 261.634758 -55.10117)
		(end 261.70763 -54.810406)
		(width 0.0889)
		(layer "In2.Cu")
		(net "M_C_BA<0>")
	)
	(arc
		(start 261.718806 -56.772302)
		(mid 261.767561 -56.57595)
		(end 261.71398 -56.380888)
		(width 0.0889)
		(layer "In2.Cu")
		(net "M_C_BA<0>")
	)
	(arc
		(start 261.718806 -54.791102)
		(mid 261.767561 -54.59475)
		(end 261.71398 -54.399688)
		(width 0.0889)
		(layer "In2.Cu")
		(net "M_C_BA<0>")
	)
	(arc
		(start 261.71398 -54.399688)
		(mid 261.634758 -54.11057)
		(end 261.70763 -53.819806)
		(width 0.0889)
		(layer "In2.Cu")
		(net "M_C_BA<0>")
	)
	(arc
		(start 261.71398 -57.371488)
		(mid 261.634758 -57.08237)
		(end 261.70763 -56.791606)
		(width 0.0889)
		(layer "In2.Cu")
		(net "M_C_BA<0>")
	)
	(arc
		(start 261.718806 -57.762902)
		(mid 261.767561 -57.56655)
		(end 261.71398 -57.371488)
		(width 0.0889)
		(layer "In2.Cu")
		(net "M_C_BA<0>")
	)
	(arc
		(start 261.718806 -55.781702)
		(mid 261.767561 -55.58535)
		(end 261.71398 -55.390288)
		(width 0.0889)
		(layer "In2.Cu")
		(net "M_C_BA<0>")
	)
	(arc
		(start 261.71398 -53.409088)
		(mid 261.634849 -53.113686)
		(end 261.71398 -52.818284)
		(width 0.0889)
		(layer "In2.Cu")
		(net "M_C_BA<0>")
	)
	(arc
		(start 261.718806 -53.800502)
		(mid 261.767561 -53.60415)
		(end 261.71398 -53.409088)
		(width 0.0889)
		(layer "In2.Cu")
		(net "M_C_BA<0>")
	)
	(arc
		(start 261.71398 -56.380888)
		(mid 261.634758 -56.09177)
		(end 261.70763 -55.801006)
		(width 0.0889)
		(layer "In2.Cu")
		(net "M_C_BA<0>")
	)
	(arc
		(start 261.71398 -52.818284)
		(mid 261.75757 -52.713039)
		(end 261.7724 -52.600098)
		(width 0.0889)
		(layer "In2.Cu")
		(net "M_C_BA<0>")
	)
	(segment
		(start 254.212344 -61.038486)
		(end 253.640844 -61.038486)
		(width 0.1016)
		(layer "F.Cu")
		(net "M_C_ALERT_N")
	)
	(segment
		(start 248.250456 -0.821182)
		(end 248.249948 -0.821182)
		(width 0.1651)
		(layer "F.Cu")
		(net "M_C_ALERT_N")
	)
	(segment
		(start 248.249948 -0.821182)
		(end 248.249948 0.442722)
		(width 0.1651)
		(layer "F.Cu")
		(net "M_C_ALERT_N")
	)
	(via
		(at 253.640844 -61.038486)
		(size 0.508)
		(drill 0.254)
		(layers "F.Cu" "B.Cu")
		(net "M_C_ALERT_N")
	)
	(via
		(at 248.249948 0.442722)
		(size 0.508)
		(drill 0.254)
		(layers "F.Cu" "B.Cu")
		(net "M_C_ALERT_N")
	)
	(via
		(at 248.249948 -2.314956)
		(size 0.4572)
		(drill 0.2032)
		(layers "F.Cu" "B.Cu")
		(net "M_C_ALERT_N")
	)
	(segment
		(start 248.249948 -1.021842)
		(end 248.249948 -2.314956)
		(width 0.1651)
		(layer "B.Cu")
		(net "M_C_ALERT_N")
	)
	(segment
		(start 248.250456 -1.021842)
		(end 248.249948 -1.021842)
		(width 0.1651)
		(layer "B.Cu")
		(net "M_C_ALERT_N")
	)
	(segment
		(start 253.640844 -61.038486)
		(end 253.640844 -60.810902)
		(width 0.0889)
		(layer "In2.Cu")
		(net "M_C_ALERT_N")
	)
	(segment
		(start 248.249948 -2.314956)
		(end 248.1072 -2.172208)
		(width 0.14224)
		(layer "In2.Cu")
		(net "M_C_ALERT_N")
	)
	(segment
		(start 247.89384 -20.73402)
		(end 247.831356 -20.671536)
		(width 0.14224)
		(layer "In2.Cu")
		(net "M_C_ALERT_N")
	)
	(segment
		(start 253.240794 -59.045602)
		(end 253.22657 -58.824114)
		(width 0.0889)
		(layer "In2.Cu")
		(net "M_C_ALERT_N")
	)
	(segment
		(start 248.1072 -2.172208)
		(end 248.1072 -0.2032)
		(width 0.14224)
		(layer "In2.Cu")
		(net "M_C_ALERT_N")
	)
	(segment
		(start 249.2756 -27.189176)
		(end 249.2756 -25.9334)
		(width 0.14224)
		(layer "In2.Cu")
		(net "M_C_ALERT_N")
	)
	(segment
		(start 254.127 -59.817)
		(end 253.873 -59.563)
		(width 0.0889)
		(layer "In2.Cu")
		(net "M_C_ALERT_N")
	)
	(segment
		(start 253.640844 -60.810902)
		(end 254.127 -60.324746)
		(width 0.0889)
		(layer "In2.Cu")
		(net "M_C_ALERT_N")
	)
	(segment
		(start 247.89384 -17.769586)
		(end 247.74144 -17.617186)
		(width 0.14224)
		(layer "In2.Cu")
		(net "M_C_ALERT_N")
	)
	(segment
		(start 247.7008 -8.178546)
		(end 247.7008 -7.548626)
		(width 0.14224)
		(layer "In2.Cu")
		(net "M_C_ALERT_N")
	)
	(segment
		(start 253.129034 -54.799738)
		(end 253.13386 -54.791102)
		(width 0.0889)
		(layer "In2.Cu")
		(net "M_C_ALERT_N")
	)
	(segment
		(start 253.122684 -54.810406)
		(end 253.129034 -54.799738)
		(width 0.0889)
		(layer "In2.Cu")
		(net "M_C_ALERT_N")
	)
	(segment
		(start 248.249948 -0.060452)
		(end 248.249948 0.442722)
		(width 0.14224)
		(layer "In2.Cu")
		(net "M_C_ALERT_N")
	)
	(segment
		(start 253.653544 -59.563)
		(end 253.533402 -59.442858)
		(width 0.0889)
		(layer "In2.Cu")
		(net "M_C_ALERT_N")
	)
	(segment
		(start 247.76684 -21.938996)
		(end 247.89384 -21.811996)
		(width 0.14224)
		(layer "In2.Cu")
		(net "M_C_ALERT_N")
	)
	(segment
		(start 253.17196 -58.436764)
		(end 253.122684 -58.35142)
		(width 0.0889)
		(layer "In2.Cu")
		(net "M_C_ALERT_N")
	)
	(segment
		(start 253.122684 -56.791606)
		(end 253.129034 -56.780938)
		(width 0.0889)
		(layer "In2.Cu")
		(net "M_C_ALERT_N")
	)
	(segment
		(start 247.89384 -21.811996)
		(end 247.89384 -20.73402)
		(width 0.14224)
		(layer "In2.Cu")
		(net "M_C_ALERT_N")
	)
	(segment
		(start 247.74144 -17.109186)
		(end 247.81002 -17.040606)
		(width 0.14224)
		(layer "In2.Cu")
		(net "M_C_ALERT_N")
	)
	(segment
		(start 253.129034 -53.809138)
		(end 253.13386 -53.800502)
		(width 0.0889)
		(layer "In2.Cu")
		(net "M_C_ALERT_N")
	)
	(segment
		(start 248.1072 -0.2032)
		(end 248.249948 -0.060452)
		(width 0.14224)
		(layer "In2.Cu")
		(net "M_C_ALERT_N")
	)
	(segment
		(start 246.9642 -3.600704)
		(end 248.249948 -2.314956)
		(width 0.14224)
		(layer "In2.Cu")
		(net "M_C_ALERT_N")
	)
	(segment
		(start 247.76684 -22.421596)
		(end 247.76684 -21.938996)
		(width 0.14224)
		(layer "In2.Cu")
		(net "M_C_ALERT_N")
	)
	(segment
		(start 247.83034 -8.308086)
		(end 247.7008 -8.178546)
		(width 0.14224)
		(layer "In2.Cu")
		(net "M_C_ALERT_N")
	)
	(segment
		(start 247.831356 -18.46707)
		(end 247.89384 -18.404586)
		(width 0.14224)
		(layer "In2.Cu")
		(net "M_C_ALERT_N")
	)
	(segment
		(start 246.9642 -4.782566)
		(end 246.9642 -3.600704)
		(width 0.14224)
		(layer "In2.Cu")
		(net "M_C_ALERT_N")
	)
	(segment
		(start 253.873 -59.563)
		(end 253.653544 -59.563)
		(width 0.0889)
		(layer "In2.Cu")
		(net "M_C_ALERT_N")
	)
	(segment
		(start 253.122684 -55.801006)
		(end 253.129034 -55.790338)
		(width 0.0889)
		(layer "In2.Cu")
		(net "M_C_ALERT_N")
	)
	(segment
		(start 249.2756 -25.9334)
		(end 247.758966 -24.416766)
		(width 0.14224)
		(layer "In2.Cu")
		(net "M_C_ALERT_N")
	)
	(segment
		(start 253.214124 -31.1277)
		(end 249.2756 -27.189176)
		(width 0.14224)
		(layer "In2.Cu")
		(net "M_C_ALERT_N")
	)
	(segment
		(start 247.758966 -24.416766)
		(end 247.758966 -23.31847)
		(width 0.14224)
		(layer "In2.Cu")
		(net "M_C_ALERT_N")
	)
	(segment
		(start 247.83034 -13.645896)
		(end 247.83034 -8.308086)
		(width 0.14224)
		(layer "In2.Cu")
		(net "M_C_ALERT_N")
	)
	(segment
		(start 247.7008 -7.548626)
		(end 247.816878 -7.432548)
		(width 0.14224)
		(layer "In2.Cu")
		(net "M_C_ALERT_N")
	)
	(segment
		(start 254.127 -60.324746)
		(end 254.127 -59.817)
		(width 0.0889)
		(layer "In2.Cu")
		(net "M_C_ALERT_N")
	)
	(segment
		(start 247.816878 -7.432548)
		(end 247.816878 -5.635244)
		(width 0.14224)
		(layer "In2.Cu")
		(net "M_C_ALERT_N")
	)
	(segment
		(start 253.129034 -52.418488)
		(end 253.122684 -52.40782)
		(width 0.0889)
		(layer "In2.Cu")
		(net "M_C_ALERT_N")
	)
	(segment
		(start 247.74144 -17.617186)
		(end 247.74144 -17.109186)
		(width 0.14224)
		(layer "In2.Cu")
		(net "M_C_ALERT_N")
	)
	(segment
		(start 253.129034 -55.790338)
		(end 253.13386 -55.781702)
		(width 0.0889)
		(layer "In2.Cu")
		(net "M_C_ALERT_N")
	)
	(segment
		(start 247.816878 -5.635244)
		(end 246.9642 -4.782566)
		(width 0.14224)
		(layer "In2.Cu")
		(net "M_C_ALERT_N")
	)
	(segment
		(start 247.89384 -18.404586)
		(end 247.89384 -17.769586)
		(width 0.14224)
		(layer "In2.Cu")
		(net "M_C_ALERT_N")
	)
	(segment
		(start 253.129034 -56.780938)
		(end 253.13386 -56.772302)
		(width 0.0889)
		(layer "In2.Cu")
		(net "M_C_ALERT_N")
	)
	(segment
		(start 247.94464 -23.132796)
		(end 247.94464 -22.599396)
		(width 0.14224)
		(layer "In2.Cu")
		(net "M_C_ALERT_N")
	)
	(segment
		(start 247.94464 -22.599396)
		(end 247.76684 -22.421596)
		(width 0.14224)
		(layer "In2.Cu")
		(net "M_C_ALERT_N")
	)
	(segment
		(start 247.81002 -17.040606)
		(end 247.81002 -13.666216)
		(width 0.14224)
		(layer "In2.Cu")
		(net "M_C_ALERT_N")
	)
	(segment
		(start 247.758966 -23.31847)
		(end 247.94464 -23.132796)
		(width 0.14224)
		(layer "In2.Cu")
		(net "M_C_ALERT_N")
	)
	(segment
		(start 253.214124 -51.680872)
		(end 253.214124 -51.08067)
		(width 0.0889)
		(layer "In2.Cu")
		(net "M_C_ALERT_N")
	)
	(segment
		(start 253.122684 -53.819806)
		(end 253.129034 -53.809138)
		(width 0.0889)
		(layer "In2.Cu")
		(net "M_C_ALERT_N")
	)
	(segment
		(start 253.22657 -58.824114)
		(end 253.17196 -58.436764)
		(width 0.0889)
		(layer "In2.Cu")
		(net "M_C_ALERT_N")
	)
	(segment
		(start 247.81002 -13.666216)
		(end 247.83034 -13.645896)
		(width 0.14224)
		(layer "In2.Cu")
		(net "M_C_ALERT_N")
	)
	(segment
		(start 253.129034 -57.771538)
		(end 253.13386 -57.762902)
		(width 0.0889)
		(layer "In2.Cu")
		(net "M_C_ALERT_N")
	)
	(segment
		(start 253.129034 -51.827938)
		(end 253.214124 -51.680872)
		(width 0.0889)
		(layer "In2.Cu")
		(net "M_C_ALERT_N")
	)
	(segment
		(start 247.831356 -20.671536)
		(end 247.831356 -18.46707)
		(width 0.14224)
		(layer "In2.Cu")
		(net "M_C_ALERT_N")
	)
	(segment
		(start 253.214124 -51.08067)
		(end 253.214124 -31.1277)
		(width 0.14224)
		(layer "In2.Cu")
		(net "M_C_ALERT_N")
	)
	(arc
		(start 253.13386 -56.772302)
		(mid 253.182615 -56.57595)
		(end 253.129034 -56.380888)
		(width 0.0889)
		(layer "In2.Cu")
		(net "M_C_ALERT_N")
	)
	(arc
		(start 253.13386 -55.781702)
		(mid 253.182615 -55.58535)
		(end 253.129034 -55.390288)
		(width 0.0889)
		(layer "In2.Cu")
		(net "M_C_ALERT_N")
	)
	(arc
		(start 253.129034 -53.409088)
		(mid 253.049903 -53.113686)
		(end 253.129034 -52.818284)
		(width 0.0889)
		(layer "In2.Cu")
		(net "M_C_ALERT_N")
	)
	(arc
		(start 253.129034 -56.380888)
		(mid 253.049812 -56.09177)
		(end 253.122684 -55.801006)
		(width 0.0889)
		(layer "In2.Cu")
		(net "M_C_ALERT_N")
	)
	(arc
		(start 253.13386 -53.800502)
		(mid 253.182615 -53.60415)
		(end 253.129034 -53.409088)
		(width 0.0889)
		(layer "In2.Cu")
		(net "M_C_ALERT_N")
	)
	(arc
		(start 253.129034 -52.818284)
		(mid 253.182533 -52.618386)
		(end 253.129034 -52.418488)
		(width 0.0889)
		(layer "In2.Cu")
		(net "M_C_ALERT_N")
	)
	(arc
		(start 253.13386 -54.791102)
		(mid 253.182615 -54.59475)
		(end 253.129034 -54.399688)
		(width 0.0889)
		(layer "In2.Cu")
		(net "M_C_ALERT_N")
	)
	(arc
		(start 253.129034 -57.371488)
		(mid 253.049812 -57.08237)
		(end 253.122684 -56.791606)
		(width 0.0889)
		(layer "In2.Cu")
		(net "M_C_ALERT_N")
	)
	(arc
		(start 253.122684 -58.35142)
		(mid 253.049886 -58.060657)
		(end 253.129034 -57.771538)
		(width 0.0889)
		(layer "In2.Cu")
		(net "M_C_ALERT_N")
	)
	(arc
		(start 253.129034 -55.390288)
		(mid 253.049812 -55.10117)
		(end 253.122684 -54.810406)
		(width 0.0889)
		(layer "In2.Cu")
		(net "M_C_ALERT_N")
	)
	(arc
		(start 253.129034 -54.399688)
		(mid 253.049812 -54.11057)
		(end 253.122684 -53.819806)
		(width 0.0889)
		(layer "In2.Cu")
		(net "M_C_ALERT_N")
	)
	(arc
		(start 253.122684 -52.40782)
		(mid 253.049886 -52.117057)
		(end 253.129034 -51.827938)
		(width 0.0889)
		(layer "In2.Cu")
		(net "M_C_ALERT_N")
	)
	(arc
		(start 253.13386 -57.762902)
		(mid 253.182615 -57.56655)
		(end 253.129034 -57.371488)
		(width 0.0889)
		(layer "In2.Cu")
		(net "M_C_ALERT_N")
	)
	(arc
		(start 253.533402 -59.442858)
		(mid 253.318585 -59.294686)
		(end 253.240794 -59.045602)
		(width 0.0889)
		(layer "In2.Cu")
		(net "M_C_ALERT_N")
	)
	(segment
		(start 246.549926 3.778758)
		(end 246.549926 1.805432)
		(width 0.1651)
		(layer "F.Cu")
		(net "M_C_ACT_N")
	)
	(segment
		(start 246.550434 3.778758)
		(end 246.549926 3.778758)
		(width 0.1651)
		(layer "F.Cu")
		(net "M_C_ACT_N")
	)
	(segment
		(start 254.212344 -60.047886)
		(end 253.640844 -60.047886)
		(width 0.1016)
		(layer "F.Cu")
		(net "M_C_ACT_N")
	)
	(via
		(at 253.640844 -60.047886)
		(size 0.508)
		(drill 0.254)
		(layers "F.Cu" "B.Cu")
		(net "M_C_ACT_N")
	)
	(via
		(at 246.549926 -4.332478)
		(size 0.4572)
		(drill 0.2032)
		(layers "F.Cu" "B.Cu")
		(net "M_C_ACT_N")
	)
	(via
		(at 246.549926 1.805432)
		(size 0.508)
		(drill 0.254)
		(layers "F.Cu" "B.Cu")
		(net "M_C_ACT_N")
	)
	(segment
		(start 246.550434 -5.621782)
		(end 246.549926 -5.621782)
		(width 0.1651)
		(layer "B.Cu")
		(net "M_C_ACT_N")
	)
	(segment
		(start 246.549926 -5.621782)
		(end 246.549926 -4.332478)
		(width 0.1651)
		(layer "B.Cu")
		(net "M_C_ACT_N")
	)
	(segment
		(start 246.116856 -3.673856)
		(end 246.549926 -4.106926)
		(width 0.14224)
		(layer "In2.Cu")
		(net "M_C_ACT_N")
	)
	(segment
		(start 252.435614 -56.780938)
		(end 252.430788 -56.772302)
		(width 0.0889)
		(layer "In2.Cu")
		(net "M_C_ACT_N")
	)
	(segment
		(start 252.435614 -58.362088)
		(end 252.441964 -58.35142)
		(width 0.0889)
		(layer "In2.Cu")
		(net "M_C_ACT_N")
	)
	(segment
		(start 253.640844 -60.047886)
		(end 253.341632 -60.047886)
		(width 0.0889)
		(layer "In2.Cu")
		(net "M_C_ACT_N")
	)
	(segment
		(start 247.15724 -8.696706)
		(end 247.15724 -7.558786)
		(width 0.14224)
		(layer "In2.Cu")
		(net "M_C_ACT_N")
	)
	(segment
		(start 252.435614 -55.790338)
		(end 252.430788 -55.781702)
		(width 0.0889)
		(layer "In2.Cu")
		(net "M_C_ACT_N")
	)
	(segment
		(start 252.435614 -54.799738)
		(end 252.430788 -54.791102)
		(width 0.0889)
		(layer "In2.Cu")
		(net "M_C_ACT_N")
	)
	(segment
		(start 246.988584 -19.182842)
		(end 246.988584 -18.46453)
		(width 0.14224)
		(layer "In2.Cu")
		(net "M_C_ACT_N")
	)
	(segment
		(start 247.15724 -12.363196)
		(end 246.9896 -12.195556)
		(width 0.14224)
		(layer "In2.Cu")
		(net "M_C_ACT_N")
	)
	(segment
		(start 246.9896 -12.195556)
		(end 246.9896 -8.864346)
		(width 0.14224)
		(layer "In2.Cu")
		(net "M_C_ACT_N")
	)
	(segment
		(start 246.549926 -4.106926)
		(end 246.549926 -4.332478)
		(width 0.14224)
		(layer "In2.Cu")
		(net "M_C_ACT_N")
	)
	(segment
		(start 246.271796 -0.522732)
		(end 246.53875 -0.522732)
		(width 0.14224)
		(layer "In2.Cu")
		(net "M_C_ACT_N")
	)
	(segment
		(start 246.98452 -16.987266)
		(end 246.98452 -13.16228)
		(width 0.14224)
		(layer "In2.Cu")
		(net "M_C_ACT_N")
	)
	(segment
		(start 252.441964 -54.810406)
		(end 252.435614 -54.799738)
		(width 0.0889)
		(layer "In2.Cu")
		(net "M_C_ACT_N")
	)
	(segment
		(start 246.94261 -23.222966)
		(end 246.94261 -22.623526)
		(width 0.14224)
		(layer "In2.Cu")
		(net "M_C_ACT_N")
	)
	(segment
		(start 247.15724 -12.98956)
		(end 247.15724 -12.363196)
		(width 0.14224)
		(layer "In2.Cu")
		(net "M_C_ACT_N")
	)
	(segment
		(start 246.98452 -13.16228)
		(end 247.15724 -12.98956)
		(width 0.14224)
		(layer "In2.Cu")
		(net "M_C_ACT_N")
	)
	(segment
		(start 248.7168 -26.035)
		(end 247.015 -24.3332)
		(width 0.14224)
		(layer "In2.Cu")
		(net "M_C_ACT_N")
	)
	(segment
		(start 253.145798 -59.382152)
		(end 253.129034 -59.352688)
		(width 0.0889)
		(layer "In2.Cu")
		(net "M_C_ACT_N")
	)
	(segment
		(start 246.53875 -1.315212)
		(end 246.271796 -1.315212)
		(width 0.14224)
		(layer "In2.Cu")
		(net "M_C_ACT_N")
	)
	(segment
		(start 246.116856 -0.367792)
		(end 246.271796 -0.522732)
		(width 0.14224)
		(layer "In2.Cu")
		(net "M_C_ACT_N")
	)
	(segment
		(start 246.9896 -8.864346)
		(end 247.15724 -8.696706)
		(width 0.14224)
		(layer "In2.Cu")
		(net "M_C_ACT_N")
	)
	(segment
		(start 247.0658 -17.068546)
		(end 246.98452 -16.987266)
		(width 0.14224)
		(layer "In2.Cu")
		(net "M_C_ACT_N")
	)
	(segment
		(start 252.435614 -53.809138)
		(end 252.430788 -53.800502)
		(width 0.0889)
		(layer "In2.Cu")
		(net "M_C_ACT_N")
	)
	(segment
		(start 252.441964 -53.819806)
		(end 252.435614 -53.809138)
		(width 0.0889)
		(layer "In2.Cu")
		(net "M_C_ACT_N")
	)
	(segment
		(start 248.7168 -27.837638)
		(end 248.7168 -26.035)
		(width 0.14224)
		(layer "In2.Cu")
		(net "M_C_ACT_N")
	)
	(segment
		(start 252.855984 -59.131962)
		(end 252.477524 -58.834528)
		(width 0.0889)
		(layer "In2.Cu")
		(net "M_C_ACT_N")
	)
	(segment
		(start 246.90324 -19.268186)
		(end 246.988584 -19.182842)
		(width 0.14224)
		(layer "In2.Cu")
		(net "M_C_ACT_N")
	)
	(segment
		(start 246.9642 -6.6294)
		(end 246.549926 -6.215126)
		(width 0.14224)
		(layer "In2.Cu")
		(net "M_C_ACT_N")
	)
	(segment
		(start 252.435614 -51.827938)
		(end 252.382274 -51.732688)
		(width 0.0889)
		(layer "In2.Cu")
		(net "M_C_ACT_N")
	)
	(segment
		(start 246.116856 -1.470152)
		(end 246.116856 -3.673856)
		(width 0.14224)
		(layer "In2.Cu")
		(net "M_C_ACT_N")
	)
	(segment
		(start 246.988584 -18.46453)
		(end 247.0658 -18.387314)
		(width 0.14224)
		(layer "In2.Cu")
		(net "M_C_ACT_N")
	)
	(segment
		(start 252.435614 -52.418488)
		(end 252.441964 -52.40782)
		(width 0.0889)
		(layer "In2.Cu")
		(net "M_C_ACT_N")
	)
	(segment
		(start 252.382274 -51.732688)
		(end 252.382274 -51.458876)
		(width 0.0889)
		(layer "In2.Cu")
		(net "M_C_ACT_N")
	)
	(segment
		(start 252.706124 -50.885344)
		(end 252.706124 -31.826962)
		(width 0.14224)
		(layer "In2.Cu")
		(net "M_C_ACT_N")
	)
	(segment
		(start 252.441964 -56.791606)
		(end 252.435614 -56.780938)
		(width 0.0889)
		(layer "In2.Cu")
		(net "M_C_ACT_N")
	)
	(segment
		(start 252.477524 -58.834528)
		(end 252.435614 -58.761884)
		(width 0.0889)
		(layer "In2.Cu")
		(net "M_C_ACT_N")
	)
	(segment
		(start 247.015 -24.3332)
		(end 247.015 -23.295356)
		(width 0.14224)
		(layer "In2.Cu")
		(net "M_C_ACT_N")
	)
	(segment
		(start 246.69369 -1.160272)
		(end 246.53875 -1.315212)
		(width 0.14224)
		(layer "In2.Cu")
		(net "M_C_ACT_N")
	)
	(segment
		(start 246.549926 1.805432)
		(end 246.549926 1.185926)
		(width 0.14224)
		(layer "In2.Cu")
		(net "M_C_ACT_N")
	)
	(segment
		(start 252.435614 -57.771538)
		(end 252.430788 -57.762902)
		(width 0.0889)
		(layer "In2.Cu")
		(net "M_C_ACT_N")
	)
	(segment
		(start 247.007126 -21.814282)
		(end 246.90324 -21.710396)
		(width 0.14224)
		(layer "In2.Cu")
		(net "M_C_ACT_N")
	)
	(segment
		(start 246.69369 -0.677672)
		(end 246.69369 -1.160272)
		(width 0.14224)
		(layer "In2.Cu")
		(net "M_C_ACT_N")
	)
	(segment
		(start 252.441964 -55.801006)
		(end 252.435614 -55.790338)
		(width 0.0889)
		(layer "In2.Cu")
		(net "M_C_ACT_N")
	)
	(segment
		(start 246.53875 -0.522732)
		(end 246.69369 -0.677672)
		(width 0.14224)
		(layer "In2.Cu")
		(net "M_C_ACT_N")
	)
	(segment
		(start 252.99289 -59.21248)
		(end 252.855984 -59.131962)
		(width 0.0889)
		(layer "In2.Cu")
		(net "M_C_ACT_N")
	)
	(segment
		(start 247.015 -23.295356)
		(end 246.94261 -23.222966)
		(width 0.14224)
		(layer "In2.Cu")
		(net "M_C_ACT_N")
	)
	(segment
		(start 253.341632 -60.047886)
		(end 253.1872 -59.893454)
		(width 0.0889)
		(layer "In2.Cu")
		(net "M_C_ACT_N")
	)
	(segment
		(start 252.382274 -51.458876)
		(end 252.706124 -51.135026)
		(width 0.0889)
		(layer "In2.Cu")
		(net "M_C_ACT_N")
	)
	(segment
		(start 247.0658 -18.387314)
		(end 247.0658 -17.068546)
		(width 0.14224)
		(layer "In2.Cu")
		(net "M_C_ACT_N")
	)
	(segment
		(start 253.1872 -59.893454)
		(end 253.1872 -59.538616)
		(width 0.0889)
		(layer "In2.Cu")
		(net "M_C_ACT_N")
	)
	(segment
		(start 246.9642 -7.365746)
		(end 246.9642 -6.6294)
		(width 0.14224)
		(layer "In2.Cu")
		(net "M_C_ACT_N")
	)
	(segment
		(start 247.15724 -7.558786)
		(end 246.9642 -7.365746)
		(width 0.14224)
		(layer "In2.Cu")
		(net "M_C_ACT_N")
	)
	(segment
		(start 252.706124 -31.826962)
		(end 248.7168 -27.837638)
		(width 0.14224)
		(layer "In2.Cu")
		(net "M_C_ACT_N")
	)
	(segment
		(start 246.116856 0.752856)
		(end 246.116856 -0.367792)
		(width 0.14224)
		(layer "In2.Cu")
		(net "M_C_ACT_N")
	)
	(segment
		(start 246.90324 -21.710396)
		(end 246.90324 -19.268186)
		(width 0.14224)
		(layer "In2.Cu")
		(net "M_C_ACT_N")
	)
	(segment
		(start 247.007126 -22.55901)
		(end 247.007126 -21.814282)
		(width 0.14224)
		(layer "In2.Cu")
		(net "M_C_ACT_N")
	)
	(segment
		(start 246.549926 -6.215126)
		(end 246.549926 -4.332478)
		(width 0.14224)
		(layer "In2.Cu")
		(net "M_C_ACT_N")
	)
	(segment
		(start 246.94261 -22.623526)
		(end 247.007126 -22.55901)
		(width 0.14224)
		(layer "In2.Cu")
		(net "M_C_ACT_N")
	)
	(segment
		(start 252.706124 -51.135026)
		(end 252.706124 -50.885344)
		(width 0.0889)
		(layer "In2.Cu")
		(net "M_C_ACT_N")
	)
	(segment
		(start 246.271796 -1.315212)
		(end 246.116856 -1.470152)
		(width 0.14224)
		(layer "In2.Cu")
		(net "M_C_ACT_N")
	)
	(segment
		(start 246.549926 1.185926)
		(end 246.116856 0.752856)
		(width 0.14224)
		(layer "In2.Cu")
		(net "M_C_ACT_N")
	)
	(arc
		(start 252.435614 -52.818284)
		(mid 252.382115 -52.618386)
		(end 252.435614 -52.418488)
		(width 0.0889)
		(layer "In2.Cu")
		(net "M_C_ACT_N")
	)
	(arc
		(start 252.430788 -56.772302)
		(mid 252.382033 -56.57595)
		(end 252.435614 -56.380888)
		(width 0.0889)
		(layer "In2.Cu")
		(net "M_C_ACT_N")
	)
	(arc
		(start 252.441964 -52.40782)
		(mid 252.514762 -52.117057)
		(end 252.435614 -51.827938)
		(width 0.0889)
		(layer "In2.Cu")
		(net "M_C_ACT_N")
	)
	(arc
		(start 252.430788 -54.791102)
		(mid 252.382033 -54.59475)
		(end 252.435614 -54.399688)
		(width 0.0889)
		(layer "In2.Cu")
		(net "M_C_ACT_N")
	)
	(arc
		(start 252.435614 -54.399688)
		(mid 252.514836 -54.11057)
		(end 252.441964 -53.819806)
		(width 0.0889)
		(layer "In2.Cu")
		(net "M_C_ACT_N")
	)
	(arc
		(start 252.441964 -58.35142)
		(mid 252.514762 -58.060657)
		(end 252.435614 -57.771538)
		(width 0.0889)
		(layer "In2.Cu")
		(net "M_C_ACT_N")
	)
	(arc
		(start 253.1872 -59.538616)
		(mid 253.176678 -59.457689)
		(end 253.145798 -59.382152)
		(width 0.0889)
		(layer "In2.Cu")
		(net "M_C_ACT_N")
	)
	(arc
		(start 252.430788 -53.800502)
		(mid 252.382033 -53.60415)
		(end 252.435614 -53.409088)
		(width 0.0889)
		(layer "In2.Cu")
		(net "M_C_ACT_N")
	)
	(arc
		(start 252.435614 -55.390288)
		(mid 252.514836 -55.10117)
		(end 252.441964 -54.810406)
		(width 0.0889)
		(layer "In2.Cu")
		(net "M_C_ACT_N")
	)
	(arc
		(start 252.435614 -58.761884)
		(mid 252.382115 -58.561986)
		(end 252.435614 -58.362088)
		(width 0.0889)
		(layer "In2.Cu")
		(net "M_C_ACT_N")
	)
	(arc
		(start 252.430788 -57.762902)
		(mid 252.382033 -57.56655)
		(end 252.435614 -57.371488)
		(width 0.0889)
		(layer "In2.Cu")
		(net "M_C_ACT_N")
	)
	(arc
		(start 252.435614 -56.380888)
		(mid 252.514836 -56.09177)
		(end 252.441964 -55.801006)
		(width 0.0889)
		(layer "In2.Cu")
		(net "M_C_ACT_N")
	)
	(arc
		(start 252.435614 -57.371488)
		(mid 252.514836 -57.08237)
		(end 252.441964 -56.791606)
		(width 0.0889)
		(layer "In2.Cu")
		(net "M_C_ACT_N")
	)
	(arc
		(start 252.430788 -55.781702)
		(mid 252.382033 -55.58535)
		(end 252.435614 -55.390288)
		(width 0.0889)
		(layer "In2.Cu")
		(net "M_C_ACT_N")
	)
	(arc
		(start 253.129034 -59.352688)
		(mid 253.069629 -59.274174)
		(end 252.99289 -59.21248)
		(width 0.0889)
		(layer "In2.Cu")
		(net "M_C_ACT_N")
	)
	(arc
		(start 252.435614 -53.409088)
		(mid 252.514745 -53.113686)
		(end 252.435614 -52.818284)
		(width 0.0889)
		(layer "In2.Cu")
		(net "M_C_ACT_N")
	)
	(segment
		(start 260.50875 -54.104286)
		(end 261.08025 -54.104286)
		(width 0.1651)
		(layer "F.Cu")
		(net "M_B_PAR")
	)
	(segment
		(start 265.250422 -10.422382)
		(end 265.249914 -10.422382)
		(width 0.1651)
		(layer "F.Cu")
		(net "M_B_PAR")
	)
	(segment
		(start 265.249914 -10.422382)
		(end 265.249914 -9.158732)
		(width 0.1651)
		(layer "F.Cu")
		(net "M_B_PAR")
	)
	(segment
		(start 265.249914 -9.158732)
		(end 265.250168 -9.158478)
		(width 0.1651)
		(layer "F.Cu")
		(net "M_B_PAR")
	)
	(segment
		(start 265.250168 -9.158478)
		(end 265.250168 -9.133078)
		(width 0.1651)
		(layer "F.Cu")
		(net "M_B_PAR")
	)
	(via
		(at 260.50875 -54.104286)
		(size 0.508)
		(drill 0.254)
		(layers "F.Cu" "B.Cu")
		(net "M_B_PAR")
	)
	(via
		(at 265.250168 -9.133078)
		(size 0.4572)
		(drill 0.2032)
		(layers "F.Cu" "B.Cu")
		(net "M_B_PAR")
	)
	(via
		(at 265.24966 -12.596368)
		(size 0.508)
		(drill 0.254)
		(layers "F.Cu" "B.Cu")
		(net "M_B_PAR")
	)
	(segment
		(start 265.24966 -12.596368)
		(end 265.24966 -10.623804)
		(width 0.1651)
		(layer "B.Cu")
		(net "M_B_PAR")
	)
	(segment
		(start 265.24966 -10.623804)
		(end 265.250422 -10.623042)
		(width 0.1651)
		(layer "B.Cu")
		(net "M_B_PAR")
	)
	(segment
		(start 262.607044 -24.997156)
		(end 263.10209 -24.50211)
		(width 0.14224)
		(layer "In4.Cu")
		(net "M_B_PAR")
	)
	(segment
		(start 264.7442 -14.1732)
		(end 264.7442 -13.101828)
		(width 0.14224)
		(layer "In4.Cu")
		(net "M_B_PAR")
	)
	(segment
		(start 263.10209 -24.50211)
		(end 263.835134 -24.50211)
		(width 0.14224)
		(layer "In4.Cu")
		(net "M_B_PAR")
	)
	(segment
		(start 260.50875 -54.104286)
		(end 260.512052 -54.104286)
		(width 0.0889)
		(layer "In4.Cu")
		(net "M_B_PAR")
	)
	(segment
		(start 265.557 -12.289028)
		(end 265.557 -11.7348)
		(width 0.14224)
		(layer "In4.Cu")
		(net "M_B_PAR")
	)
	(segment
		(start 265.557 -11.7348)
		(end 265.7094 -11.5824)
		(width 0.14224)
		(layer "In4.Cu")
		(net "M_B_PAR")
	)
	(segment
		(start 264.7442 -13.101828)
		(end 265.24966 -12.596368)
		(width 0.14224)
		(layer "In4.Cu")
		(net "M_B_PAR")
	)
	(segment
		(start 265.7094 -9.59231)
		(end 265.250168 -9.133078)
		(width 0.14224)
		(layer "In4.Cu")
		(net "M_B_PAR")
	)
	(segment
		(start 265.24966 -12.596368)
		(end 265.557 -12.289028)
		(width 0.14224)
		(layer "In4.Cu")
		(net "M_B_PAR")
	)
	(segment
		(start 265.7094 -11.5824)
		(end 265.7094 -9.59231)
		(width 0.14224)
		(layer "In4.Cu")
		(net "M_B_PAR")
	)
	(segment
		(start 263.9822 -15.7988)
		(end 263.9822 -14.9352)
		(width 0.14224)
		(layer "In4.Cu")
		(net "M_B_PAR")
	)
	(segment
		(start 262.607044 -26.66238)
		(end 262.607044 -24.997156)
		(width 0.14224)
		(layer "In4.Cu")
		(net "M_B_PAR")
	)
	(segment
		(start 260.910324 -53.706014)
		(end 260.910324 -51.273456)
		(width 0.0889)
		(layer "In4.Cu")
		(net "M_B_PAR")
	)
	(segment
		(start 264.7696 -23.567644)
		(end 264.7696 -16.5862)
		(width 0.14224)
		(layer "In4.Cu")
		(net "M_B_PAR")
	)
	(segment
		(start 263.9822 -14.9352)
		(end 264.7442 -14.1732)
		(width 0.14224)
		(layer "In4.Cu")
		(net "M_B_PAR")
	)
	(segment
		(start 262.158988 -27.110436)
		(end 262.607044 -26.66238)
		(width 0.14224)
		(layer "In4.Cu")
		(net "M_B_PAR")
	)
	(segment
		(start 260.512052 -54.104286)
		(end 260.910324 -53.706014)
		(width 0.0889)
		(layer "In4.Cu")
		(net "M_B_PAR")
	)
	(segment
		(start 260.910324 -51.273456)
		(end 262.158988 -50.024792)
		(width 0.0889)
		(layer "In4.Cu")
		(net "M_B_PAR")
	)
	(segment
		(start 262.158988 -50.024792)
		(end 262.158988 -49.603406)
		(width 0.0889)
		(layer "In4.Cu")
		(net "M_B_PAR")
	)
	(segment
		(start 263.835134 -24.50211)
		(end 264.7696 -23.567644)
		(width 0.14224)
		(layer "In4.Cu")
		(net "M_B_PAR")
	)
	(segment
		(start 264.7696 -16.5862)
		(end 263.9822 -15.7988)
		(width 0.14224)
		(layer "In4.Cu")
		(net "M_B_PAR")
	)
	(segment
		(start 262.158988 -49.603406)
		(end 262.158988 -27.110436)
		(width 0.14224)
		(layer "In4.Cu")
		(net "M_B_PAR")
	)
	(segment
		(start 265.659616 -57.076086)
		(end 266.231116 -57.076086)
		(width 0.1016)
		(layer "F.Cu")
		(net "M_B_ODT<3>")
	)
	(via
		(at 265.659616 -57.076086)
		(size 0.508)
		(drill 0.254)
		(layers "F.Cu" "B.Cu")
		(net "M_B_ODT<3>")
	)
	(via
		(at 276.29993 -13.934186)
		(size 0.4572)
		(drill 0.2032)
		(layers "F.Cu" "B.Cu")
		(net "M_B_ODT<3>")
	)
	(segment
		(start 276.29993 -15.222982)
		(end 276.29993 -13.934186)
		(width 0.1651)
		(layer "B.Cu")
		(net "M_B_ODT<3>")
	)
	(segment
		(start 276.300438 -15.222982)
		(end 276.29993 -15.222982)
		(width 0.1651)
		(layer "B.Cu")
		(net "M_B_ODT<3>")
	)
	(segment
		(start 275.038058 -15.196058)
		(end 276.29993 -13.934186)
		(width 0.14224)
		(layer "In4.Cu")
		(net "M_B_ODT<3>")
	)
	(segment
		(start 265.989562 -56.31434)
		(end 266.006326 -56.285638)
		(width 0.0889)
		(layer "In4.Cu")
		(net "M_B_ODT<3>")
	)
	(segment
		(start 267.313156 -49.67097)
		(end 267.313156 -33.341564)
		(width 0.14224)
		(layer "In4.Cu")
		(net "M_B_ODT<3>")
	)
	(segment
		(start 273.1262 -25.9334)
		(end 274.894294 -24.165306)
		(width 0.14224)
		(layer "In4.Cu")
		(net "M_B_ODT<3>")
	)
	(segment
		(start 275.068538 -23.139654)
		(end 275.068538 -22.567138)
		(width 0.14224)
		(layer "In4.Cu")
		(net "M_B_ODT<3>")
	)
	(segment
		(start 274.894294 -23.313898)
		(end 275.068538 -23.139654)
		(width 0.14224)
		(layer "In4.Cu")
		(net "M_B_ODT<3>")
	)
	(segment
		(start 266.78001 -54.19979)
		(end 267.108432 -53.871368)
		(width 0.0889)
		(layer "In4.Cu")
		(net "M_B_ODT<3>")
	)
	(segment
		(start 273.1262 -27.52852)
		(end 273.1262 -25.9334)
		(width 0.14224)
		(layer "In4.Cu")
		(net "M_B_ODT<3>")
	)
	(segment
		(start 267.313156 -49.955958)
		(end 267.313156 -49.67097)
		(width 0.0889)
		(layer "In4.Cu")
		(net "M_B_ODT<3>")
	)
	(segment
		(start 274.661376 -17.310862)
		(end 275.038058 -16.93418)
		(width 0.14224)
		(layer "In4.Cu")
		(net "M_B_ODT<3>")
	)
	(segment
		(start 266.171426 -54.799738)
		(end 266.1666 -54.791102)
		(width 0.0889)
		(layer "In4.Cu")
		(net "M_B_ODT<3>")
	)
	(segment
		(start 266.006326 -55.676292)
		(end 266.171426 -55.390288)
		(width 0.0889)
		(layer "In4.Cu")
		(net "M_B_ODT<3>")
	)
	(segment
		(start 275.033232 -21.77796)
		(end 275.033232 -18.447258)
		(width 0.14224)
		(layer "In4.Cu")
		(net "M_B_ODT<3>")
	)
	(segment
		(start 267.313156 -33.341564)
		(end 273.1262 -27.52852)
		(width 0.14224)
		(layer "In4.Cu")
		(net "M_B_ODT<3>")
	)
	(segment
		(start 275.033232 -18.447258)
		(end 274.661376 -18.075402)
		(width 0.14224)
		(layer "In4.Cu")
		(net "M_B_ODT<3>")
	)
	(segment
		(start 275.038058 -16.93418)
		(end 275.038058 -15.196058)
		(width 0.14224)
		(layer "In4.Cu")
		(net "M_B_ODT<3>")
	)
	(segment
		(start 265.659616 -57.076086)
		(end 265.989562 -56.31434)
		(width 0.0889)
		(layer "In4.Cu")
		(net "M_B_ODT<3>")
	)
	(segment
		(start 267.108432 -53.871368)
		(end 267.108432 -50.160682)
		(width 0.0889)
		(layer "In4.Cu")
		(net "M_B_ODT<3>")
	)
	(segment
		(start 266.177776 -54.810406)
		(end 266.171426 -54.799738)
		(width 0.0889)
		(layer "In4.Cu")
		(net "M_B_ODT<3>")
	)
	(segment
		(start 274.975066 -21.836126)
		(end 275.033232 -21.77796)
		(width 0.14224)
		(layer "In4.Cu")
		(net "M_B_ODT<3>")
	)
	(segment
		(start 274.975066 -22.473666)
		(end 274.975066 -21.836126)
		(width 0.14224)
		(layer "In4.Cu")
		(net "M_B_ODT<3>")
	)
	(segment
		(start 275.068538 -22.567138)
		(end 274.975066 -22.473666)
		(width 0.14224)
		(layer "In4.Cu")
		(net "M_B_ODT<3>")
	)
	(segment
		(start 274.894294 -24.165306)
		(end 274.894294 -23.313898)
		(width 0.14224)
		(layer "In4.Cu")
		(net "M_B_ODT<3>")
	)
	(segment
		(start 274.661376 -18.075402)
		(end 274.661376 -17.310862)
		(width 0.14224)
		(layer "In4.Cu")
		(net "M_B_ODT<3>")
	)
	(segment
		(start 266.011152 -55.894224)
		(end 266.006326 -55.885588)
		(width 0.0889)
		(layer "In4.Cu")
		(net "M_B_ODT<3>")
	)
	(segment
		(start 267.108432 -50.160682)
		(end 267.313156 -49.955958)
		(width 0.0889)
		(layer "In4.Cu")
		(net "M_B_ODT<3>")
	)
	(segment
		(start 266.50315 -54.19979)
		(end 266.78001 -54.19979)
		(width 0.0889)
		(layer "In4.Cu")
		(net "M_B_ODT<3>")
	)
	(arc
		(start 266.006326 -55.885588)
		(mid 265.978299 -55.78094)
		(end 266.006326 -55.676292)
		(width 0.0889)
		(layer "In4.Cu")
		(net "M_B_ODT<3>")
	)
	(arc
		(start 266.171426 -55.390288)
		(mid 266.250648 -55.10117)
		(end 266.177776 -54.810406)
		(width 0.0889)
		(layer "In4.Cu")
		(net "M_B_ODT<3>")
	)
	(arc
		(start 266.006326 -56.285638)
		(mid 266.059796 -56.090575)
		(end 266.011152 -55.894224)
		(width 0.0889)
		(layer "In4.Cu")
		(net "M_B_ODT<3>")
	)
	(arc
		(start 266.1666 -54.791102)
		(mid 266.170347 -54.401846)
		(end 266.50315 -54.19979)
		(width 0.0889)
		(layer "In4.Cu")
		(net "M_B_ODT<3>")
	)
	(segment
		(start 263.94283 -55.094886)
		(end 264.51433 -55.094886)
		(width 0.1016)
		(layer "F.Cu")
		(net "M_B_ODT<2>")
	)
	(via
		(at 263.94283 -55.094886)
		(size 0.508)
		(drill 0.254)
		(layers "F.Cu" "B.Cu")
		(net "M_B_ODT<2>")
	)
	(via
		(at 272.899886 -13.929868)
		(size 0.4572)
		(drill 0.2032)
		(layers "F.Cu" "B.Cu")
		(net "M_B_ODT<2>")
	)
	(segment
		(start 272.900394 -15.222982)
		(end 272.899886 -15.222982)
		(width 0.1651)
		(layer "B.Cu")
		(net "M_B_ODT<2>")
	)
	(segment
		(start 272.899886 -15.222982)
		(end 272.899886 -13.929868)
		(width 0.1651)
		(layer "B.Cu")
		(net "M_B_ODT<2>")
	)
	(segment
		(start 271.718278 -19.141186)
		(end 271.640808 -19.063716)
		(width 0.14224)
		(layer "In4.Cu")
		(net "M_B_ODT<2>")
	)
	(segment
		(start 265.520678 -49.014888)
		(end 265.520678 -32.259016)
		(width 0.14224)
		(layer "In4.Cu")
		(net "M_B_ODT<2>")
	)
	(segment
		(start 264.37463 -54.54142)
		(end 264.45464 -54.399942)
		(width 0.0889)
		(layer "In4.Cu")
		(net "M_B_ODT<2>")
	)
	(segment
		(start 271.5768 -23.274274)
		(end 271.718278 -23.132796)
		(width 0.14224)
		(layer "In4.Cu")
		(net "M_B_ODT<2>")
	)
	(segment
		(start 264.45464 -53.409342)
		(end 264.5918 -53.158136)
		(width 0.0889)
		(layer "In4.Cu")
		(net "M_B_ODT<2>")
	)
	(segment
		(start 271.6403 -16.4211)
		(end 271.41932 -16.20012)
		(width 0.14224)
		(layer "In4.Cu")
		(net "M_B_ODT<2>")
	)
	(segment
		(start 271.645126 -18.452338)
		(end 271.645126 -18.232882)
		(width 0.14224)
		(layer "In4.Cu")
		(net "M_B_ODT<2>")
	)
	(segment
		(start 265.5062 -50.753772)
		(end 265.252708 -50.50028)
		(width 0.0889)
		(layer "In4.Cu")
		(net "M_B_ODT<2>")
	)
	(segment
		(start 265.252708 -49.957482)
		(end 265.520678 -49.689512)
		(width 0.0889)
		(layer "In4.Cu")
		(net "M_B_ODT<2>")
	)
	(segment
		(start 271.6403 -17.060164)
		(end 271.6403 -16.4211)
		(width 0.14224)
		(layer "In4.Cu")
		(net "M_B_ODT<2>")
	)
	(segment
		(start 271.565878 -18.153634)
		(end 271.565878 -17.134586)
		(width 0.14224)
		(layer "In4.Cu")
		(net "M_B_ODT<2>")
	)
	(segment
		(start 265.5062 -51.917854)
		(end 265.5062 -50.753772)
		(width 0.0889)
		(layer "In4.Cu")
		(net "M_B_ODT<2>")
	)
	(segment
		(start 271.645126 -18.232882)
		(end 271.565878 -18.153634)
		(width 0.14224)
		(layer "In4.Cu")
		(net "M_B_ODT<2>")
	)
	(segment
		(start 265.252708 -50.50028)
		(end 265.252708 -49.957482)
		(width 0.0889)
		(layer "In4.Cu")
		(net "M_B_ODT<2>")
	)
	(segment
		(start 271.640808 -18.456656)
		(end 271.645126 -18.452338)
		(width 0.14224)
		(layer "In4.Cu")
		(net "M_B_ODT<2>")
	)
	(segment
		(start 269.7988 -27.980894)
		(end 269.7988 -25.9842)
		(width 0.14224)
		(layer "In4.Cu")
		(net "M_B_ODT<2>")
	)
	(segment
		(start 264.5918 -53.158136)
		(end 264.5918 -52.832)
		(width 0.0889)
		(layer "In4.Cu")
		(net "M_B_ODT<2>")
	)
	(segment
		(start 271.640808 -19.063716)
		(end 271.640808 -18.456656)
		(width 0.14224)
		(layer "In4.Cu")
		(net "M_B_ODT<2>")
	)
	(segment
		(start 264.46353 -53.824378)
		(end 264.45464 -53.809138)
		(width 0.0889)
		(layer "In4.Cu")
		(net "M_B_ODT<2>")
	)
	(segment
		(start 271.565878 -17.134586)
		(end 271.6403 -17.060164)
		(width 0.14224)
		(layer "In4.Cu")
		(net "M_B_ODT<2>")
	)
	(segment
		(start 271.41932 -15.27048)
		(end 272.759932 -13.929868)
		(width 0.14224)
		(layer "In4.Cu")
		(net "M_B_ODT<2>")
	)
	(segment
		(start 269.7988 -25.9842)
		(end 271.5768 -24.2062)
		(width 0.14224)
		(layer "In4.Cu")
		(net "M_B_ODT<2>")
	)
	(segment
		(start 271.718278 -23.132796)
		(end 271.718278 -19.141186)
		(width 0.14224)
		(layer "In4.Cu")
		(net "M_B_ODT<2>")
	)
	(segment
		(start 263.94283 -55.094886)
		(end 264.17016 -54.816502)
		(width 0.0889)
		(layer "In4.Cu")
		(net "M_B_ODT<2>")
	)
	(segment
		(start 272.759932 -13.929868)
		(end 272.899886 -13.929868)
		(width 0.14224)
		(layer "In4.Cu")
		(net "M_B_ODT<2>")
	)
	(segment
		(start 265.061446 -52.362354)
		(end 265.0617 -52.362354)
		(width 0.0889)
		(layer "In4.Cu")
		(net "M_B_ODT<2>")
	)
	(segment
		(start 264.17016 -54.816502)
		(end 264.37463 -54.54142)
		(width 0.0889)
		(layer "In4.Cu")
		(net "M_B_ODT<2>")
	)
	(segment
		(start 264.5918 -52.832)
		(end 265.061446 -52.362354)
		(width 0.0889)
		(layer "In4.Cu")
		(net "M_B_ODT<2>")
	)
	(segment
		(start 271.5768 -24.2062)
		(end 271.5768 -23.274274)
		(width 0.14224)
		(layer "In4.Cu")
		(net "M_B_ODT<2>")
	)
	(segment
		(start 265.520678 -49.689512)
		(end 265.520678 -49.014888)
		(width 0.0889)
		(layer "In4.Cu")
		(net "M_B_ODT<2>")
	)
	(segment
		(start 271.41932 -16.20012)
		(end 271.41932 -15.27048)
		(width 0.14224)
		(layer "In4.Cu")
		(net "M_B_ODT<2>")
	)
	(segment
		(start 265.0617 -52.362354)
		(end 265.5062 -51.917854)
		(width 0.0889)
		(layer "In4.Cu")
		(net "M_B_ODT<2>")
	)
	(segment
		(start 265.520678 -32.259016)
		(end 269.7988 -27.980894)
		(width 0.14224)
		(layer "In4.Cu")
		(net "M_B_ODT<2>")
	)
	(arc
		(start 264.45464 -54.399942)
		(mid 264.533829 -54.113327)
		(end 264.46353 -53.824378)
		(width 0.0889)
		(layer "In4.Cu")
		(net "M_B_ODT<2>")
	)
	(arc
		(start 264.45464 -53.809138)
		(mid 264.401107 -53.60924)
		(end 264.45464 -53.409342)
		(width 0.0889)
		(layer "In4.Cu")
		(net "M_B_ODT<2>")
	)
	(segment
		(start 276.29993 -5.822442)
		(end 276.29993 -7.11708)
		(width 0.1651)
		(layer "F.Cu")
		(net "M_B_ODT<1>")
	)
	(segment
		(start 276.29993 -7.11708)
		(end 276.300438 -7.117588)
		(width 0.1651)
		(layer "F.Cu")
		(net "M_B_ODT<1>")
	)
	(segment
		(start 265.372596 -56.58104)
		(end 264.801096 -56.58104)
		(width 0.1016)
		(layer "F.Cu")
		(net "M_B_ODT<1>")
	)
	(segment
		(start 276.300438 -5.822442)
		(end 276.29993 -5.822442)
		(width 0.1651)
		(layer "F.Cu")
		(net "M_B_ODT<1>")
	)
	(via
		(at 276.300438 -7.117588)
		(size 0.4572)
		(drill 0.2032)
		(layers "F.Cu" "B.Cu")
		(net "M_B_ODT<1>")
	)
	(via
		(at 264.801096 -56.58104)
		(size 0.508)
		(drill 0.254)
		(layers "F.Cu" "B.Cu")
		(net "M_B_ODT<1>")
	)
	(segment
		(start 276.300438 -7.646162)
		(end 276.300438 -7.117588)
		(width 0.14224)
		(layer "In4.Cu")
		(net "M_B_ODT<1>")
	)
	(segment
		(start 274.21967 -22.489922)
		(end 274.21967 -21.87067)
		(width 0.14224)
		(layer "In4.Cu")
		(net "M_B_ODT<1>")
	)
	(segment
		(start 275.04136 -8.90524)
		(end 276.300438 -7.646162)
		(width 0.14224)
		(layer "In4.Cu")
		(net "M_B_ODT<1>")
	)
	(segment
		(start 274.157948 -21.129244)
		(end 274.157948 -18.376138)
		(width 0.14224)
		(layer "In4.Cu")
		(net "M_B_ODT<1>")
	)
	(segment
		(start 266.011152 -54.903624)
		(end 266.006326 -54.894988)
		(width 0.0889)
		(layer "In4.Cu")
		(net "M_B_ODT<1>")
	)
	(segment
		(start 274.110196 -23.132796)
		(end 274.110196 -22.599396)
		(width 0.14224)
		(layer "In4.Cu")
		(net "M_B_ODT<1>")
	)
	(segment
		(start 265.64844 -55.685436)
		(end 265.659616 -55.685436)
		(width 0.0889)
		(layer "In4.Cu")
		(net "M_B_ODT<1>")
	)
	(segment
		(start 275.015706 -14.471142)
		(end 275.015706 -13.604494)
		(width 0.14224)
		(layer "In4.Cu")
		(net "M_B_ODT<1>")
	)
	(segment
		(start 272.6182 -27.3177)
		(end 272.6182 -25.6794)
		(width 0.14224)
		(layer "In4.Cu")
		(net "M_B_ODT<1>")
	)
	(segment
		(start 266.006326 -54.894988)
		(end 265.999976 -54.88432)
		(width 0.0889)
		(layer "In4.Cu")
		(net "M_B_ODT<1>")
	)
	(segment
		(start 272.6182 -25.6794)
		(end 274.215098 -24.082502)
		(width 0.14224)
		(layer "In4.Cu")
		(net "M_B_ODT<1>")
	)
	(segment
		(start 274.157948 -18.376138)
		(end 274.084796 -18.302986)
		(width 0.14224)
		(layer "In4.Cu")
		(net "M_B_ODT<1>")
	)
	(segment
		(start 266.917932 -49.695608)
		(end 266.917932 -33.017968)
		(width 0.14224)
		(layer "In4.Cu")
		(net "M_B_ODT<1>")
	)
	(segment
		(start 264.801096 -56.58104)
		(end 265.296142 -55.915052)
		(width 0.0889)
		(layer "In4.Cu")
		(net "M_B_ODT<1>")
	)
	(segment
		(start 275.015706 -13.604494)
		(end 274.655534 -13.244322)
		(width 0.14224)
		(layer "In4.Cu")
		(net "M_B_ODT<1>")
	)
	(segment
		(start 274.084796 -17.820386)
		(end 274.162774 -17.742408)
		(width 0.14224)
		(layer "In4.Cu")
		(net "M_B_ODT<1>")
	)
	(segment
		(start 274.21967 -21.87067)
		(end 274.10664 -21.75764)
		(width 0.14224)
		(layer "In4.Cu")
		(net "M_B_ODT<1>")
	)
	(segment
		(start 274.162774 -17.742408)
		(end 274.162774 -15.324074)
		(width 0.14224)
		(layer "In4.Cu")
		(net "M_B_ODT<1>")
	)
	(segment
		(start 274.215098 -23.237698)
		(end 274.110196 -23.132796)
		(width 0.14224)
		(layer "In4.Cu")
		(net "M_B_ODT<1>")
	)
	(segment
		(start 266.917932 -53.779674)
		(end 266.917932 -49.695608)
		(width 0.0889)
		(layer "In4.Cu")
		(net "M_B_ODT<1>")
	)
	(segment
		(start 274.10664 -21.180552)
		(end 274.157948 -21.129244)
		(width 0.14224)
		(layer "In4.Cu")
		(net "M_B_ODT<1>")
	)
	(segment
		(start 274.084796 -18.302986)
		(end 274.084796 -17.820386)
		(width 0.14224)
		(layer "In4.Cu")
		(net "M_B_ODT<1>")
	)
	(segment
		(start 265.296142 -55.915052)
		(end 265.312906 -55.885588)
		(width 0.0889)
		(layer "In4.Cu")
		(net "M_B_ODT<1>")
	)
	(segment
		(start 274.655534 -12.643866)
		(end 275.04136 -12.25804)
		(width 0.14224)
		(layer "In4.Cu")
		(net "M_B_ODT<1>")
	)
	(segment
		(start 266.917932 -33.017968)
		(end 272.6182 -27.3177)
		(width 0.14224)
		(layer "In4.Cu")
		(net "M_B_ODT<1>")
	)
	(segment
		(start 275.04136 -12.25804)
		(end 275.04136 -8.90524)
		(width 0.14224)
		(layer "In4.Cu")
		(net "M_B_ODT<1>")
	)
	(segment
		(start 266.496546 -54.00929)
		(end 266.688316 -54.00929)
		(width 0.0889)
		(layer "In4.Cu")
		(net "M_B_ODT<1>")
	)
	(segment
		(start 274.215098 -24.082502)
		(end 274.215098 -23.237698)
		(width 0.14224)
		(layer "In4.Cu")
		(net "M_B_ODT<1>")
	)
	(segment
		(start 266.688316 -54.00929)
		(end 266.917932 -53.779674)
		(width 0.0889)
		(layer "In4.Cu")
		(net "M_B_ODT<1>")
	)
	(segment
		(start 274.655534 -13.244322)
		(end 274.655534 -12.643866)
		(width 0.14224)
		(layer "In4.Cu")
		(net "M_B_ODT<1>")
	)
	(segment
		(start 274.110196 -22.599396)
		(end 274.21967 -22.489922)
		(width 0.14224)
		(layer "In4.Cu")
		(net "M_B_ODT<1>")
	)
	(segment
		(start 274.162774 -15.324074)
		(end 275.015706 -14.471142)
		(width 0.14224)
		(layer "In4.Cu")
		(net "M_B_ODT<1>")
	)
	(segment
		(start 265.841734 -55.58028)
		(end 266.006326 -55.295038)
		(width 0.0889)
		(layer "In4.Cu")
		(net "M_B_ODT<1>")
	)
	(segment
		(start 274.10664 -21.75764)
		(end 274.10664 -21.180552)
		(width 0.14224)
		(layer "In4.Cu")
		(net "M_B_ODT<1>")
	)
	(arc
		(start 265.659616 -55.685436)
		(mid 265.764768 -55.657262)
		(end 265.841734 -55.58028)
		(width 0.0889)
		(layer "In4.Cu")
		(net "M_B_ODT<1>")
	)
	(arc
		(start 265.312906 -55.885588)
		(mid 265.454589 -55.741784)
		(end 265.64844 -55.685436)
		(width 0.0889)
		(layer "In4.Cu")
		(net "M_B_ODT<1>")
	)
	(arc
		(start 266.006326 -55.295038)
		(mid 266.059796 -55.099975)
		(end 266.011152 -54.903624)
		(width 0.0889)
		(layer "In4.Cu")
		(net "M_B_ODT<1>")
	)
	(arc
		(start 265.999976 -54.88432)
		(mid 266.004007 -54.308138)
		(end 266.496546 -54.00929)
		(width 0.0889)
		(layer "In4.Cu")
		(net "M_B_ODT<1>")
	)
	(segment
		(start 263.65581 -55.59044)
		(end 263.08431 -55.59044)
		(width 0.1016)
		(layer "F.Cu")
		(net "M_B_ODT<0>")
	)
	(segment
		(start 272.899886 -5.822442)
		(end 272.899886 -7.113778)
		(width 0.1651)
		(layer "F.Cu")
		(net "M_B_ODT<0>")
	)
	(segment
		(start 272.900394 -5.822442)
		(end 272.899886 -5.822442)
		(width 0.1651)
		(layer "F.Cu")
		(net "M_B_ODT<0>")
	)
	(via
		(at 263.08431 -55.59044)
		(size 0.508)
		(drill 0.254)
		(layers "F.Cu" "B.Cu")
		(net "M_B_ODT<0>")
	)
	(via
		(at 272.899886 -7.113778)
		(size 0.508)
		(drill 0.254)
		(layers "F.Cu" "B.Cu")
		(net "M_B_ODT<0>")
	)
	(segment
		(start 265.063224 -49.017936)
		(end 265.063224 -31.99765)
		(width 0.14224)
		(layer "In4.Cu")
		(net "M_B_ODT<0>")
	)
	(segment
		(start 270.655034 -23.136098)
		(end 270.655034 -22.625558)
		(width 0.14224)
		(layer "In4.Cu")
		(net "M_B_ODT<0>")
	)
	(segment
		(start 265.063224 -49.225708)
		(end 265.063224 -49.017936)
		(width 0.0889)
		(layer "In4.Cu")
		(net "M_B_ODT<0>")
	)
	(segment
		(start 270.833596 -21.938996)
		(end 270.710406 -21.815806)
		(width 0.14224)
		(layer "In4.Cu")
		(net "M_B_ODT<0>")
	)
	(segment
		(start 265.063224 -31.99765)
		(end 269.2908 -27.770074)
		(width 0.14224)
		(layer "In4.Cu")
		(net "M_B_ODT<0>")
	)
	(segment
		(start 272.46326 -8.78586)
		(end 272.899886 -8.349234)
		(width 0.14224)
		(layer "In4.Cu")
		(net "M_B_ODT<0>")
	)
	(segment
		(start 264.289286 -53.313584)
		(end 264.297414 -53.29936)
		(width 0.0889)
		(layer "In4.Cu")
		(net "M_B_ODT<0>")
	)
	(segment
		(start 271.888712 -13.404088)
		(end 272.219928 -13.404088)
		(width 0.14224)
		(layer "In4.Cu")
		(net "M_B_ODT<0>")
	)
	(segment
		(start 263.413748 -54.829456)
		(end 263.43102 -54.799738)
		(width 0.0889)
		(layer "In4.Cu")
		(net "M_B_ODT<0>")
	)
	(segment
		(start 265.230864 -50.80508)
		(end 265.058398 -50.632614)
		(width 0.0889)
		(layer "In4.Cu")
		(net "M_B_ODT<0>")
	)
	(segment
		(start 271.640808 -14.141958)
		(end 271.640808 -13.651992)
		(width 0.14224)
		(layer "In4.Cu")
		(net "M_B_ODT<0>")
	)
	(segment
		(start 265.230864 -49.689766)
		(end 265.230864 -49.393348)
		(width 0.0889)
		(layer "In4.Cu")
		(net "M_B_ODT<0>")
	)
	(segment
		(start 270.765524 -16.406876)
		(end 270.8529 -16.3195)
		(width 0.14224)
		(layer "In4.Cu")
		(net "M_B_ODT<0>")
	)
	(segment
		(start 265.230864 -51.811936)
		(end 265.230864 -50.80508)
		(width 0.0889)
		(layer "In4.Cu")
		(net "M_B_ODT<0>")
	)
	(segment
		(start 264.289286 -53.904388)
		(end 264.280396 -53.889148)
		(width 0.0889)
		(layer "In4.Cu")
		(net "M_B_ODT<0>")
	)
	(segment
		(start 264.342626 -53.134514)
		(end 264.342626 -52.700174)
		(width 0.0889)
		(layer "In4.Cu")
		(net "M_B_ODT<0>")
	)
	(segment
		(start 270.765524 -21.207476)
		(end 270.765524 -16.406876)
		(width 0.14224)
		(layer "In4.Cu")
		(net "M_B_ODT<0>")
	)
	(segment
		(start 270.8529 -14.929866)
		(end 271.640808 -14.141958)
		(width 0.14224)
		(layer "In4.Cu")
		(net "M_B_ODT<0>")
	)
	(segment
		(start 265.058398 -49.862232)
		(end 265.230864 -49.689766)
		(width 0.0889)
		(layer "In4.Cu")
		(net "M_B_ODT<0>")
	)
	(segment
		(start 272.899886 -8.349234)
		(end 272.899886 -7.113778)
		(width 0.14224)
		(layer "In4.Cu")
		(net "M_B_ODT<0>")
	)
	(segment
		(start 270.710406 -21.262594)
		(end 270.765524 -21.207476)
		(width 0.14224)
		(layer "In4.Cu")
		(net "M_B_ODT<0>")
	)
	(segment
		(start 271.640808 -13.651992)
		(end 271.888712 -13.404088)
		(width 0.14224)
		(layer "In4.Cu")
		(net "M_B_ODT<0>")
	)
	(segment
		(start 265.230864 -49.393348)
		(end 265.063224 -49.225708)
		(width 0.0889)
		(layer "In4.Cu")
		(net "M_B_ODT<0>")
	)
	(segment
		(start 270.8529 -16.3195)
		(end 270.8529 -14.929866)
		(width 0.14224)
		(layer "In4.Cu")
		(net "M_B_ODT<0>")
	)
	(segment
		(start 272.219928 -13.404088)
		(end 272.46326 -13.160756)
		(width 0.14224)
		(layer "In4.Cu")
		(net "M_B_ODT<0>")
	)
	(segment
		(start 270.710406 -21.815806)
		(end 270.710406 -21.262594)
		(width 0.14224)
		(layer "In4.Cu")
		(net "M_B_ODT<0>")
	)
	(segment
		(start 270.655034 -22.625558)
		(end 270.833596 -22.446996)
		(width 0.14224)
		(layer "In4.Cu")
		(net "M_B_ODT<0>")
	)
	(segment
		(start 272.46326 -13.160756)
		(end 272.46326 -8.78586)
		(width 0.14224)
		(layer "In4.Cu")
		(net "M_B_ODT<0>")
	)
	(segment
		(start 269.2908 -27.770074)
		(end 269.2908 -25.7556)
		(width 0.14224)
		(layer "In4.Cu")
		(net "M_B_ODT<0>")
	)
	(segment
		(start 263.08431 -55.59044)
		(end 263.413748 -54.829456)
		(width 0.0889)
		(layer "In4.Cu")
		(net "M_B_ODT<0>")
	)
	(segment
		(start 263.92505 -54.504336)
		(end 263.94283 -54.504336)
		(width 0.0889)
		(layer "In4.Cu")
		(net "M_B_ODT<0>")
	)
	(segment
		(start 270.864584 -23.345648)
		(end 270.655034 -23.136098)
		(width 0.14224)
		(layer "In4.Cu")
		(net "M_B_ODT<0>")
	)
	(segment
		(start 265.058398 -50.632614)
		(end 265.058398 -49.862232)
		(width 0.0889)
		(layer "In4.Cu")
		(net "M_B_ODT<0>")
	)
	(segment
		(start 269.2908 -25.7556)
		(end 270.864584 -24.181816)
		(width 0.14224)
		(layer "In4.Cu")
		(net "M_B_ODT<0>")
	)
	(segment
		(start 270.864584 -24.181816)
		(end 270.864584 -23.345648)
		(width 0.14224)
		(layer "In4.Cu")
		(net "M_B_ODT<0>")
	)
	(segment
		(start 264.342626 -52.700174)
		(end 265.230864 -51.811936)
		(width 0.0889)
		(layer "In4.Cu")
		(net "M_B_ODT<0>")
	)
	(segment
		(start 270.833596 -22.446996)
		(end 270.833596 -21.938996)
		(width 0.14224)
		(layer "In4.Cu")
		(net "M_B_ODT<0>")
	)
	(arc
		(start 263.94283 -54.504336)
		(mid 264.289256 -54.304359)
		(end 264.289286 -53.904388)
		(width 0.0889)
		(layer "In4.Cu")
		(net "M_B_ODT<0>")
	)
	(arc
		(start 264.280396 -53.889148)
		(mid 264.209999 -53.600197)
		(end 264.289286 -53.313584)
		(width 0.0889)
		(layer "In4.Cu")
		(net "M_B_ODT<0>")
	)
	(arc
		(start 264.297414 -53.29936)
		(mid 264.328931 -53.21938)
		(end 264.342626 -53.134514)
		(width 0.0889)
		(layer "In4.Cu")
		(net "M_B_ODT<0>")
	)
	(arc
		(start 263.43102 -54.799738)
		(mid 263.639628 -54.587806)
		(end 263.92505 -54.504336)
		(width 0.0889)
		(layer "In4.Cu")
		(net "M_B_ODT<0>")
	)
	(segment
		(start 249.94997 -5.822442)
		(end 249.94997 -7.115302)
		(width 0.1651)
		(layer "F.Cu")
		(net "M_B_MA<9>")
	)
	(segment
		(start 249.950478 -5.822442)
		(end 249.94997 -5.822442)
		(width 0.1651)
		(layer "F.Cu")
		(net "M_B_MA<9>")
	)
	(segment
		(start 255.92913 -54.104286)
		(end 255.35763 -54.104286)
		(width 0.1016)
		(layer "F.Cu")
		(net "M_B_MA<9>")
	)
	(segment
		(start 249.94997 -7.115302)
		(end 249.949716 -7.115556)
		(width 0.1651)
		(layer "F.Cu")
		(net "M_B_MA<9>")
	)
	(via
		(at 255.35763 -54.104286)
		(size 0.508)
		(drill 0.254)
		(layers "F.Cu" "B.Cu")
		(net "M_B_MA<9>")
	)
	(via
		(at 249.949716 -7.115556)
		(size 0.4572)
		(drill 0.2032)
		(layers "F.Cu" "B.Cu")
		(net "M_B_MA<9>")
	)
	(via
		(at 249.94997 -13.933678)
		(size 0.4572)
		(drill 0.2032)
		(layers "F.Cu" "B.Cu")
		(net "M_B_MA<9>")
	)
	(segment
		(start 249.950478 -15.222982)
		(end 249.94997 -15.222982)
		(width 0.1651)
		(layer "B.Cu")
		(net "M_B_MA<9>")
	)
	(segment
		(start 249.94997 -15.222982)
		(end 249.94997 -13.933678)
		(width 0.1651)
		(layer "B.Cu")
		(net "M_B_MA<9>")
	)
	(segment
		(start 253.786894 -16.225774)
		(end 253.786894 -17.662906)
		(width 0.14224)
		(layer "In11.Cu")
		(net "M_B_MA<9>")
	)
	(segment
		(start 250.486672 -14.49578)
		(end 252.993144 -14.49578)
		(width 0.14224)
		(layer "In11.Cu")
		(net "M_B_MA<9>")
	)
	(segment
		(start 253.8222 -23.241)
		(end 253.8222 -23.7744)
		(width 0.14224)
		(layer "In11.Cu")
		(net "M_B_MA<9>")
	)
	(segment
		(start 255.01092 -53.313838)
		(end 255.027684 -53.34254)
		(width 0.0889)
		(layer "In11.Cu")
		(net "M_B_MA<9>")
	)
	(segment
		(start 255.581404 -30.018736)
		(end 254.829564 -30.770576)
		(width 0.14224)
		(layer "In11.Cu")
		(net "M_B_MA<9>")
	)
	(segment
		(start 249.949716 -7.115556)
		(end 250.3678 -7.53364)
		(width 0.14224)
		(layer "In11.Cu")
		(net "M_B_MA<9>")
	)
	(segment
		(start 253.6952 -17.7546)
		(end 253.6952 -18.3896)
		(width 0.14224)
		(layer "In11.Cu")
		(net "M_B_MA<9>")
	)
	(segment
		(start 254.1905 -28.6893)
		(end 254.1905 -28.9687)
		(width 0.14224)
		(layer "In11.Cu")
		(net "M_B_MA<9>")
	)
	(segment
		(start 254.829564 -30.770576)
		(end 254.829564 -31.058104)
		(width 0.14224)
		(layer "In11.Cu")
		(net "M_B_MA<9>")
	)
	(segment
		(start 254.1905 -28.9687)
		(end 253.566676 -29.592524)
		(width 0.14224)
		(layer "In11.Cu")
		(net "M_B_MA<9>")
	)
	(segment
		(start 253.8222 -23.7744)
		(end 253.640082 -23.956518)
		(width 0.14224)
		(layer "In11.Cu")
		(net "M_B_MA<9>")
	)
	(segment
		(start 252.993144 -14.49578)
		(end 253.5682 -15.070836)
		(width 0.14224)
		(layer "In11.Cu")
		(net "M_B_MA<9>")
	)
	(segment
		(start 253.7206 -21.6916)
		(end 253.8222 -21.7932)
		(width 0.14224)
		(layer "In11.Cu")
		(net "M_B_MA<9>")
	)
	(segment
		(start 253.955804 -26.067004)
		(end 253.955804 -28.454604)
		(width 0.14224)
		(layer "In11.Cu")
		(net "M_B_MA<9>")
	)
	(segment
		(start 253.759716 -21.246084)
		(end 253.7206 -21.2852)
		(width 0.14224)
		(layer "In11.Cu")
		(net "M_B_MA<9>")
	)
	(segment
		(start 255.472184 -50.820574)
		(end 255.472184 -51.156616)
		(width 0.0889)
		(layer "In11.Cu")
		(net "M_B_MA<9>")
	)
	(segment
		(start 254.829564 -31.058104)
		(end 255.472184 -31.700724)
		(width 0.14224)
		(layer "In11.Cu")
		(net "M_B_MA<9>")
	)
	(segment
		(start 255.581404 -29.731208)
		(end 255.581404 -30.018736)
		(width 0.14224)
		(layer "In11.Cu")
		(net "M_B_MA<9>")
	)
	(segment
		(start 253.566676 -29.868876)
		(end 253.930404 -30.232604)
		(width 0.14224)
		(layer "In11.Cu")
		(net "M_B_MA<9>")
	)
	(segment
		(start 253.640082 -23.956518)
		(end 253.640082 -25.751282)
		(width 0.14224)
		(layer "In11.Cu")
		(net "M_B_MA<9>")
	)
	(segment
		(start 255.027684 -53.34254)
		(end 255.35763 -54.104286)
		(width 0.0889)
		(layer "In11.Cu")
		(net "M_B_MA<9>")
	)
	(segment
		(start 249.94997 -13.933678)
		(end 249.94997 -13.959078)
		(width 0.14224)
		(layer "In11.Cu")
		(net "M_B_MA<9>")
	)
	(segment
		(start 253.955804 -28.454604)
		(end 254.1905 -28.6893)
		(width 0.14224)
		(layer "In11.Cu")
		(net "M_B_MA<9>")
	)
	(segment
		(start 250.3678 -13.515848)
		(end 249.94997 -13.933678)
		(width 0.14224)
		(layer "In11.Cu")
		(net "M_B_MA<9>")
	)
	(segment
		(start 255.472184 -51.156616)
		(end 254.9398 -51.689)
		(width 0.0889)
		(layer "In11.Cu")
		(net "M_B_MA<9>")
	)
	(segment
		(start 253.930404 -30.232604)
		(end 254.217932 -30.232604)
		(width 0.14224)
		(layer "In11.Cu")
		(net "M_B_MA<9>")
	)
	(segment
		(start 254.9398 -51.689)
		(end 254.9398 -53.051202)
		(width 0.0889)
		(layer "In11.Cu")
		(net "M_B_MA<9>")
	)
	(segment
		(start 255.006602 -29.443934)
		(end 255.29413 -29.443934)
		(width 0.14224)
		(layer "In11.Cu")
		(net "M_B_MA<9>")
	)
	(segment
		(start 249.94997 -13.959078)
		(end 250.486672 -14.49578)
		(width 0.14224)
		(layer "In11.Cu")
		(net "M_B_MA<9>")
	)
	(segment
		(start 253.8222 -22.5044)
		(end 253.7206 -22.606)
		(width 0.14224)
		(layer "In11.Cu")
		(net "M_B_MA<9>")
	)
	(segment
		(start 253.786894 -17.662906)
		(end 253.6952 -17.7546)
		(width 0.14224)
		(layer "In11.Cu")
		(net "M_B_MA<9>")
	)
	(segment
		(start 250.3678 -7.53364)
		(end 250.3678 -13.515848)
		(width 0.14224)
		(layer "In11.Cu")
		(net "M_B_MA<9>")
	)
	(segment
		(start 253.7206 -21.2852)
		(end 253.7206 -21.6916)
		(width 0.14224)
		(layer "In11.Cu")
		(net "M_B_MA<9>")
	)
	(segment
		(start 254.217932 -30.232604)
		(end 255.006602 -29.443934)
		(width 0.14224)
		(layer "In11.Cu")
		(net "M_B_MA<9>")
	)
	(segment
		(start 253.759716 -18.454116)
		(end 253.759716 -21.246084)
		(width 0.14224)
		(layer "In11.Cu")
		(net "M_B_MA<9>")
	)
	(segment
		(start 253.7206 -22.606)
		(end 253.7206 -23.1394)
		(width 0.14224)
		(layer "In11.Cu")
		(net "M_B_MA<9>")
	)
	(segment
		(start 255.472184 -31.700724)
		(end 255.472184 -50.820574)
		(width 0.14224)
		(layer "In11.Cu")
		(net "M_B_MA<9>")
	)
	(segment
		(start 253.7206 -23.1394)
		(end 253.8222 -23.241)
		(width 0.14224)
		(layer "In11.Cu")
		(net "M_B_MA<9>")
	)
	(segment
		(start 253.5682 -15.070836)
		(end 253.5682 -16.00708)
		(width 0.14224)
		(layer "In11.Cu")
		(net "M_B_MA<9>")
	)
	(segment
		(start 255.29413 -29.443934)
		(end 255.581404 -29.731208)
		(width 0.14224)
		(layer "In11.Cu")
		(net "M_B_MA<9>")
	)
	(segment
		(start 253.640082 -25.751282)
		(end 253.955804 -26.067004)
		(width 0.14224)
		(layer "In11.Cu")
		(net "M_B_MA<9>")
	)
	(segment
		(start 253.566676 -29.592524)
		(end 253.566676 -29.868876)
		(width 0.14224)
		(layer "In11.Cu")
		(net "M_B_MA<9>")
	)
	(segment
		(start 253.8222 -21.7932)
		(end 253.8222 -22.5044)
		(width 0.14224)
		(layer "In11.Cu")
		(net "M_B_MA<9>")
	)
	(segment
		(start 253.5682 -16.00708)
		(end 253.786894 -16.225774)
		(width 0.14224)
		(layer "In11.Cu")
		(net "M_B_MA<9>")
	)
	(segment
		(start 253.6952 -18.3896)
		(end 253.759716 -18.454116)
		(width 0.14224)
		(layer "In11.Cu")
		(net "M_B_MA<9>")
	)
	(arc
		(start 254.9398 -53.051202)
		(mid 254.95788 -53.187258)
		(end 255.01092 -53.313838)
		(width 0.0889)
		(layer "In11.Cu")
		(net "M_B_MA<9>")
	)
	(segment
		(start 255.07061 -58.561986)
		(end 254.49911 -58.561986)
		(width 0.1016)
		(layer "F.Cu")
		(net "M_B_MA<8>")
	)
	(segment
		(start 251.6505 -5.822442)
		(end 251.649992 -5.822442)
		(width 0.1651)
		(layer "F.Cu")
		(net "M_B_MA<8>")
	)
	(segment
		(start 251.649992 -5.822442)
		(end 251.649992 -7.117588)
		(width 0.1651)
		(layer "F.Cu")
		(net "M_B_MA<8>")
	)
	(via
		(at 254.49911 -58.561986)
		(size 0.508)
		(drill 0.254)
		(layers "F.Cu" "B.Cu")
		(net "M_B_MA<8>")
	)
	(via
		(at 251.649992 -13.933678)
		(size 0.4572)
		(drill 0.2032)
		(layers "F.Cu" "B.Cu")
		(net "M_B_MA<8>")
	)
	(via
		(at 251.649992 -7.117588)
		(size 0.4572)
		(drill 0.2032)
		(layers "F.Cu" "B.Cu")
		(net "M_B_MA<8>")
	)
	(segment
		(start 251.6505 -15.222982)
		(end 251.649992 -15.222982)
		(width 0.1651)
		(layer "B.Cu")
		(net "M_B_MA<8>")
	)
	(segment
		(start 251.649992 -15.222982)
		(end 251.649992 -13.933678)
		(width 0.1651)
		(layer "B.Cu")
		(net "M_B_MA<8>")
	)
	(segment
		(start 254.2794 -51.5112)
		(end 254.2794 -52.93614)
		(width 0.0889)
		(layer "In4.Cu")
		(net "M_B_MA<8>")
	)
	(segment
		(start 250.557284 -22.408896)
		(end 250.303284 -22.662896)
		(width 0.14224)
		(layer "In4.Cu")
		(net "M_B_MA<8>")
	)
	(segment
		(start 250.633992 -18.17751)
		(end 250.3678 -18.443702)
		(width 0.14224)
		(layer "In4.Cu")
		(net "M_B_MA<8>")
	)
	(segment
		(start 251.649992 -7.795768)
		(end 251.3584 -8.08736)
		(width 0.14224)
		(layer "In4.Cu")
		(net "M_B_MA<8>")
	)
	(segment
		(start 254.152654 -56.780938)
		(end 254.161544 -56.796178)
		(width 0.0889)
		(layer "In4.Cu")
		(net "M_B_MA<8>")
	)
	(segment
		(start 250.3678 -18.443702)
		(end 250.3678 -21.093684)
		(width 0.14224)
		(layer "In4.Cu")
		(net "M_B_MA<8>")
	)
	(segment
		(start 250.219464 -24.227536)
		(end 250.219464 -24.515064)
		(width 0.14224)
		(layer "In4.Cu")
		(net "M_B_MA<8>")
	)
	(segment
		(start 251.649992 -14.228318)
		(end 251.45619 -14.42212)
		(width 0.14224)
		(layer "In4.Cu")
		(net "M_B_MA<8>")
	)
	(segment
		(start 250.100338 -16.011652)
		(end 250.36145 -16.272764)
		(width 0.14224)
		(layer "In4.Cu")
		(net "M_B_MA<8>")
	)
	(segment
		(start 251.45619 -14.42212)
		(end 250.296172 -14.42212)
		(width 0.14224)
		(layer "In4.Cu")
		(net "M_B_MA<8>")
	)
	(segment
		(start 251.3584 -8.08736)
		(end 251.3584 -8.737854)
		(width 0.14224)
		(layer "In4.Cu")
		(net "M_B_MA<8>")
	)
	(segment
		(start 250.3678 -21.093684)
		(end 250.303284 -21.1582)
		(width 0.14224)
		(layer "In4.Cu")
		(net "M_B_MA<8>")
	)
	(segment
		(start 250.303284 -21.710396)
		(end 250.557284 -21.964396)
		(width 0.14224)
		(layer "In4.Cu")
		(net "M_B_MA<8>")
	)
	(segment
		(start 255.4478 -29.7434)
		(end 255.4478 -48.23587)
		(width 0.14224)
		(layer "In4.Cu")
		(net "M_B_MA<8>")
	)
	(segment
		(start 254.152654 -54.799738)
		(end 254.161544 -54.814978)
		(width 0.0889)
		(layer "In4.Cu")
		(net "M_B_MA<8>")
	)
	(segment
		(start 254.152654 -55.790338)
		(end 254.161544 -55.805578)
		(width 0.0889)
		(layer "In4.Cu")
		(net "M_B_MA<8>")
	)
	(segment
		(start 250.100338 -14.617954)
		(end 250.100338 -16.011652)
		(width 0.14224)
		(layer "In4.Cu")
		(net "M_B_MA<8>")
	)
	(segment
		(start 250.6726 -23.7744)
		(end 250.219464 -24.227536)
		(width 0.14224)
		(layer "In4.Cu")
		(net "M_B_MA<8>")
	)
	(segment
		(start 251.649992 -13.933678)
		(end 251.649992 -14.228318)
		(width 0.14224)
		(layer "In4.Cu")
		(net "M_B_MA<8>")
	)
	(segment
		(start 251.3584 -8.737854)
		(end 251.210318 -8.885936)
		(width 0.14224)
		(layer "In4.Cu")
		(net "M_B_MA<8>")
	)
	(segment
		(start 255.4478 -48.23587)
		(end 254.964184 -48.719486)
		(width 0.14224)
		(layer "In4.Cu")
		(net "M_B_MA<8>")
	)
	(segment
		(start 250.36145 -16.964152)
		(end 250.633992 -17.236694)
		(width 0.14224)
		(layer "In4.Cu")
		(net "M_B_MA<8>")
	)
	(segment
		(start 254.964184 -50.826416)
		(end 254.2794 -51.5112)
		(width 0.0889)
		(layer "In4.Cu")
		(net "M_B_MA<8>")
	)
	(segment
		(start 250.296172 -14.42212)
		(end 250.100338 -14.617954)
		(width 0.14224)
		(layer "In4.Cu")
		(net "M_B_MA<8>")
	)
	(segment
		(start 250.557284 -21.964396)
		(end 250.557284 -22.408896)
		(width 0.14224)
		(layer "In4.Cu")
		(net "M_B_MA<8>")
	)
	(segment
		(start 250.303284 -23.183596)
		(end 250.6726 -23.552912)
		(width 0.14224)
		(layer "In4.Cu")
		(net "M_B_MA<8>")
	)
	(segment
		(start 250.633992 -17.236694)
		(end 250.633992 -18.17751)
		(width 0.14224)
		(layer "In4.Cu")
		(net "M_B_MA<8>")
	)
	(segment
		(start 250.6726 -23.552912)
		(end 250.6726 -23.7744)
		(width 0.14224)
		(layer "In4.Cu")
		(net "M_B_MA<8>")
	)
	(segment
		(start 251.210318 -13.494004)
		(end 251.649992 -13.933678)
		(width 0.14224)
		(layer "In4.Cu")
		(net "M_B_MA<8>")
	)
	(segment
		(start 250.219464 -24.515064)
		(end 255.4478 -29.7434)
		(width 0.14224)
		(layer "In4.Cu")
		(net "M_B_MA<8>")
	)
	(segment
		(start 251.210318 -8.885936)
		(end 251.210318 -13.494004)
		(width 0.14224)
		(layer "In4.Cu")
		(net "M_B_MA<8>")
	)
	(segment
		(start 254.964184 -50.478436)
		(end 254.964184 -50.826416)
		(width 0.0889)
		(layer "In4.Cu")
		(net "M_B_MA<8>")
	)
	(segment
		(start 250.303284 -22.662896)
		(end 250.303284 -23.183596)
		(width 0.14224)
		(layer "In4.Cu")
		(net "M_B_MA<8>")
	)
	(segment
		(start 254.152654 -53.809138)
		(end 254.161544 -53.824378)
		(width 0.0889)
		(layer "In4.Cu")
		(net "M_B_MA<8>")
	)
	(segment
		(start 251.649992 -7.117588)
		(end 251.649992 -7.795768)
		(width 0.14224)
		(layer "In4.Cu")
		(net "M_B_MA<8>")
	)
	(segment
		(start 254.152654 -57.771538)
		(end 254.404114 -58.207402)
		(width 0.0889)
		(layer "In4.Cu")
		(net "M_B_MA<8>")
	)
	(segment
		(start 250.36145 -16.272764)
		(end 250.36145 -16.964152)
		(width 0.14224)
		(layer "In4.Cu")
		(net "M_B_MA<8>")
	)
	(segment
		(start 250.303284 -21.1582)
		(end 250.303284 -21.710396)
		(width 0.14224)
		(layer "In4.Cu")
		(net "M_B_MA<8>")
	)
	(segment
		(start 254.964184 -48.719486)
		(end 254.964184 -50.478436)
		(width 0.14224)
		(layer "In4.Cu")
		(net "M_B_MA<8>")
	)
	(arc
		(start 254.152654 -54.399942)
		(mid 254.099121 -54.59984)
		(end 254.152654 -54.799738)
		(width 0.0889)
		(layer "In4.Cu")
		(net "M_B_MA<8>")
	)
	(arc
		(start 254.152654 -57.371742)
		(mid 254.099121 -57.57164)
		(end 254.152654 -57.771538)
		(width 0.0889)
		(layer "In4.Cu")
		(net "M_B_MA<8>")
	)
	(arc
		(start 254.161544 -53.824378)
		(mid 254.231941 -54.113329)
		(end 254.152654 -54.399942)
		(width 0.0889)
		(layer "In4.Cu")
		(net "M_B_MA<8>")
	)
	(arc
		(start 254.152654 -56.381142)
		(mid 254.099121 -56.58104)
		(end 254.152654 -56.780938)
		(width 0.0889)
		(layer "In4.Cu")
		(net "M_B_MA<8>")
	)
	(arc
		(start 254.161544 -54.814978)
		(mid 254.231941 -55.103929)
		(end 254.152654 -55.390542)
		(width 0.0889)
		(layer "In4.Cu")
		(net "M_B_MA<8>")
	)
	(arc
		(start 254.152654 -53.409342)
		(mid 254.099121 -53.60924)
		(end 254.152654 -53.809138)
		(width 0.0889)
		(layer "In4.Cu")
		(net "M_B_MA<8>")
	)
	(arc
		(start 254.2794 -52.93614)
		(mid 254.247171 -53.181085)
		(end 254.152654 -53.409342)
		(width 0.0889)
		(layer "In4.Cu")
		(net "M_B_MA<8>")
	)
	(arc
		(start 254.161544 -55.805578)
		(mid 254.231941 -56.094529)
		(end 254.152654 -56.381142)
		(width 0.0889)
		(layer "In4.Cu")
		(net "M_B_MA<8>")
	)
	(arc
		(start 254.161544 -56.796178)
		(mid 254.231941 -57.085129)
		(end 254.152654 -57.371742)
		(width 0.0889)
		(layer "In4.Cu")
		(net "M_B_MA<8>")
	)
	(arc
		(start 254.152654 -55.390542)
		(mid 254.099121 -55.59044)
		(end 254.152654 -55.790338)
		(width 0.0889)
		(layer "In4.Cu")
		(net "M_B_MA<8>")
	)
	(arc
		(start 254.404114 -58.207402)
		(mid 254.474934 -58.378444)
		(end 254.49911 -58.561986)
		(width 0.0889)
		(layer "In4.Cu")
		(net "M_B_MA<8>")
	)
	(segment
		(start 250.800362 -10.422382)
		(end 250.799854 -10.422382)
		(width 0.1651)
		(layer "F.Cu")
		(net "M_B_MA<7>")
	)
	(segment
		(start 254.212344 -58.06694)
		(end 253.640844 -58.06694)
		(width 0.1016)
		(layer "F.Cu")
		(net "M_B_MA<7>")
	)
	(segment
		(start 250.799854 -10.422382)
		(end 250.799854 -9.133078)
		(width 0.1651)
		(layer "F.Cu")
		(net "M_B_MA<7>")
	)
	(via
		(at 250.799854 -9.133078)
		(size 0.4572)
		(drill 0.2032)
		(layers "F.Cu" "B.Cu")
		(net "M_B_MA<7>")
	)
	(via
		(at 250.799854 -11.916156)
		(size 0.4572)
		(drill 0.2032)
		(layers "F.Cu" "B.Cu")
		(net "M_B_MA<7>")
	)
	(via
		(at 253.640844 -58.06694)
		(size 0.508)
		(drill 0.254)
		(layers "F.Cu" "B.Cu")
		(net "M_B_MA<7>")
	)
	(segment
		(start 250.799854 -10.623042)
		(end 250.799854 -11.916156)
		(width 0.1651)
		(layer "B.Cu")
		(net "M_B_MA<7>")
	)
	(segment
		(start 250.800362 -10.623042)
		(end 250.799854 -10.623042)
		(width 0.1651)
		(layer "B.Cu")
		(net "M_B_MA<7>")
	)
	(segment
		(start 249.44324 -23.259796)
		(end 249.44324 -24.501094)
		(width 0.14224)
		(layer "In4.Cu")
		(net "M_B_MA<7>")
	)
	(segment
		(start 249.44324 -21.888196)
		(end 249.44324 -22.446996)
		(width 0.14224)
		(layer "In4.Cu")
		(net "M_B_MA<7>")
	)
	(segment
		(start 249.44324 -24.501094)
		(end 254.456184 -29.514038)
		(width 0.14224)
		(layer "In4.Cu")
		(net "M_B_MA<7>")
	)
	(segment
		(start 249.463052 -12.667488)
		(end 249.463052 -13.268452)
		(width 0.14224)
		(layer "In4.Cu")
		(net "M_B_MA<7>")
	)
	(segment
		(start 253.97841 -55.870348)
		(end 253.9873 -55.885588)
		(width 0.0889)
		(layer "In4.Cu")
		(net "M_B_MA<7>")
	)
	(segment
		(start 249.53595 -18.388076)
		(end 249.53595 -21.795486)
		(width 0.14224)
		(layer "In4.Cu")
		(net "M_B_MA<7>")
	)
	(segment
		(start 254.456184 -29.514038)
		(end 254.456184 -50.558446)
		(width 0.14224)
		(layer "In4.Cu")
		(net "M_B_MA<7>")
	)
	(segment
		(start 249.463052 -13.268452)
		(end 249.5296 -13.335)
		(width 0.14224)
		(layer "In4.Cu")
		(net "M_B_MA<7>")
	)
	(segment
		(start 254.052324 -51.255676)
		(end 254.052324 -52.855876)
		(width 0.0889)
		(layer "In4.Cu")
		(net "M_B_MA<7>")
	)
	(segment
		(start 253.97841 -54.879748)
		(end 253.9873 -54.894988)
		(width 0.0889)
		(layer "In4.Cu")
		(net "M_B_MA<7>")
	)
	(segment
		(start 250.644914 -10.083292)
		(end 250.799854 -10.238232)
		(width 0.14224)
		(layer "In4.Cu")
		(net "M_B_MA<7>")
	)
	(segment
		(start 249.44324 -22.446996)
		(end 249.556016 -22.559772)
		(width 0.14224)
		(layer "In4.Cu")
		(net "M_B_MA<7>")
	)
	(segment
		(start 253.97841 -56.860948)
		(end 253.9873 -56.876188)
		(width 0.0889)
		(layer "In4.Cu")
		(net "M_B_MA<7>")
	)
	(segment
		(start 249.556016 -22.559772)
		(end 249.556016 -23.14702)
		(width 0.14224)
		(layer "In4.Cu")
		(net "M_B_MA<7>")
	)
	(segment
		(start 254.456184 -50.558446)
		(end 254.456184 -50.851816)
		(width 0.0889)
		(layer "In4.Cu")
		(net "M_B_MA<7>")
	)
	(segment
		(start 254.456184 -50.851816)
		(end 254.052324 -51.255676)
		(width 0.0889)
		(layer "In4.Cu")
		(net "M_B_MA<7>")
	)
	(segment
		(start 249.68454 -12.446)
		(end 249.463052 -12.667488)
		(width 0.14224)
		(layer "In4.Cu")
		(net "M_B_MA<7>")
	)
	(segment
		(start 250.238514 -11.27125)
		(end 250.238514 -10.238232)
		(width 0.14224)
		(layer "In4.Cu")
		(net "M_B_MA<7>")
	)
	(segment
		(start 249.82678 -11.431524)
		(end 250.07824 -11.431524)
		(width 0.14224)
		(layer "In4.Cu")
		(net "M_B_MA<7>")
	)
	(segment
		(start 253.971298 -57.303162)
		(end 253.640844 -58.06694)
		(width 0.0889)
		(layer "In4.Cu")
		(net "M_B_MA<7>")
	)
	(segment
		(start 249.5296 -17.073626)
		(end 249.39244 -17.210786)
		(width 0.14224)
		(layer "In4.Cu")
		(net "M_B_MA<7>")
	)
	(segment
		(start 249.39244 -18.244566)
		(end 249.53595 -18.388076)
		(width 0.14224)
		(layer "In4.Cu")
		(net "M_B_MA<7>")
	)
	(segment
		(start 250.799854 -9.133078)
		(end 250.799854 -9.398254)
		(width 0.14224)
		(layer "In4.Cu")
		(net "M_B_MA<7>")
	)
	(segment
		(start 249.677174 -11.281918)
		(end 249.82678 -11.431524)
		(width 0.14224)
		(layer "In4.Cu")
		(net "M_B_MA<7>")
	)
	(segment
		(start 249.5296 -13.335)
		(end 249.5296 -17.073626)
		(width 0.14224)
		(layer "In4.Cu")
		(net "M_B_MA<7>")
	)
	(segment
		(start 250.653804 -9.544304)
		(end 249.90171 -9.544304)
		(width 0.14224)
		(layer "In4.Cu")
		(net "M_B_MA<7>")
	)
	(segment
		(start 250.07824 -11.431524)
		(end 250.238514 -11.27125)
		(width 0.14224)
		(layer "In4.Cu")
		(net "M_B_MA<7>")
	)
	(segment
		(start 249.677174 -9.76884)
		(end 249.677174 -11.281918)
		(width 0.14224)
		(layer "In4.Cu")
		(net "M_B_MA<7>")
	)
	(segment
		(start 250.799854 -10.238232)
		(end 250.799854 -11.916156)
		(width 0.14224)
		(layer "In4.Cu")
		(net "M_B_MA<7>")
	)
	(segment
		(start 249.39244 -17.210786)
		(end 249.39244 -18.244566)
		(width 0.14224)
		(layer "In4.Cu")
		(net "M_B_MA<7>")
	)
	(segment
		(start 249.53595 -21.795486)
		(end 249.44324 -21.888196)
		(width 0.14224)
		(layer "In4.Cu")
		(net "M_B_MA<7>")
	)
	(segment
		(start 254.0508 -52.8574)
		(end 254.0508 -53.076856)
		(width 0.0889)
		(layer "In4.Cu")
		(net "M_B_MA<7>")
	)
	(segment
		(start 254.052324 -52.855876)
		(end 254.0508 -52.8574)
		(width 0.0889)
		(layer "In4.Cu")
		(net "M_B_MA<7>")
	)
	(segment
		(start 250.799854 -11.916156)
		(end 250.27001 -12.446)
		(width 0.14224)
		(layer "In4.Cu")
		(net "M_B_MA<7>")
	)
	(segment
		(start 253.9873 -57.275984)
		(end 253.971298 -57.303162)
		(width 0.0889)
		(layer "In4.Cu")
		(net "M_B_MA<7>")
	)
	(segment
		(start 250.238514 -10.238232)
		(end 250.393454 -10.083292)
		(width 0.14224)
		(layer "In4.Cu")
		(net "M_B_MA<7>")
	)
	(segment
		(start 250.799854 -9.398254)
		(end 250.653804 -9.544304)
		(width 0.14224)
		(layer "In4.Cu")
		(net "M_B_MA<7>")
	)
	(segment
		(start 249.556016 -23.14702)
		(end 249.44324 -23.259796)
		(width 0.14224)
		(layer "In4.Cu")
		(net "M_B_MA<7>")
	)
	(segment
		(start 249.90171 -9.544304)
		(end 249.677174 -9.76884)
		(width 0.14224)
		(layer "In4.Cu")
		(net "M_B_MA<7>")
	)
	(segment
		(start 253.97841 -53.889148)
		(end 253.9873 -53.904388)
		(width 0.0889)
		(layer "In4.Cu")
		(net "M_B_MA<7>")
	)
	(segment
		(start 250.27001 -12.446)
		(end 249.68454 -12.446)
		(width 0.14224)
		(layer "In4.Cu")
		(net "M_B_MA<7>")
	)
	(segment
		(start 250.393454 -10.083292)
		(end 250.644914 -10.083292)
		(width 0.14224)
		(layer "In4.Cu")
		(net "M_B_MA<7>")
	)
	(arc
		(start 253.9873 -55.294784)
		(mid 253.908111 -55.581399)
		(end 253.97841 -55.870348)
		(width 0.0889)
		(layer "In4.Cu")
		(net "M_B_MA<7>")
	)
	(arc
		(start 253.9873 -56.876188)
		(mid 254.040833 -57.076086)
		(end 253.9873 -57.275984)
		(width 0.0889)
		(layer "In4.Cu")
		(net "M_B_MA<7>")
	)
	(arc
		(start 253.9873 -53.313584)
		(mid 253.908111 -53.600199)
		(end 253.97841 -53.889148)
		(width 0.0889)
		(layer "In4.Cu")
		(net "M_B_MA<7>")
	)
	(arc
		(start 253.9873 -53.904388)
		(mid 254.040833 -54.104286)
		(end 253.9873 -54.304184)
		(width 0.0889)
		(layer "In4.Cu")
		(net "M_B_MA<7>")
	)
	(arc
		(start 253.9873 -54.894988)
		(mid 254.040833 -55.094886)
		(end 253.9873 -55.294784)
		(width 0.0889)
		(layer "In4.Cu")
		(net "M_B_MA<7>")
	)
	(arc
		(start 253.9873 -54.304184)
		(mid 253.908111 -54.590799)
		(end 253.97841 -54.879748)
		(width 0.0889)
		(layer "In4.Cu")
		(net "M_B_MA<7>")
	)
	(arc
		(start 253.9873 -55.885588)
		(mid 254.040833 -56.085486)
		(end 253.9873 -56.285384)
		(width 0.0889)
		(layer "In4.Cu")
		(net "M_B_MA<7>")
	)
	(arc
		(start 253.9873 -56.285384)
		(mid 253.908111 -56.571999)
		(end 253.97841 -56.860948)
		(width 0.0889)
		(layer "In4.Cu")
		(net "M_B_MA<7>")
	)
	(arc
		(start 254.0508 -53.076856)
		(mid 254.034663 -53.199412)
		(end 253.9873 -53.313584)
		(width 0.0889)
		(layer "In4.Cu")
		(net "M_B_MA<7>")
	)
	(segment
		(start 252.499876 -5.822442)
		(end 252.499876 -7.117588)
		(width 0.1651)
		(layer "F.Cu")
		(net "M_B_MA<6>")
	)
	(segment
		(start 255.92913 -57.076086)
		(end 255.35763 -57.076086)
		(width 0.1016)
		(layer "F.Cu")
		(net "M_B_MA<6>")
	)
	(segment
		(start 252.500384 -5.822442)
		(end 252.499876 -5.822442)
		(width 0.1651)
		(layer "F.Cu")
		(net "M_B_MA<6>")
	)
	(via
		(at 255.35763 -57.076086)
		(size 0.508)
		(drill 0.254)
		(layers "F.Cu" "B.Cu")
		(net "M_B_MA<6>")
	)
	(via
		(at 252.499876 -7.117588)
		(size 0.4572)
		(drill 0.2032)
		(layers "F.Cu" "B.Cu")
		(net "M_B_MA<6>")
	)
	(via
		(at 252.499876 -13.933678)
		(size 0.4572)
		(drill 0.2032)
		(layers "F.Cu" "B.Cu")
		(net "M_B_MA<6>")
	)
	(segment
		(start 252.500384 -15.222982)
		(end 252.499876 -15.222982)
		(width 0.1651)
		(layer "B.Cu")
		(net "M_B_MA<6>")
	)
	(segment
		(start 252.499876 -15.222982)
		(end 252.499876 -13.933678)
		(width 0.1651)
		(layer "B.Cu")
		(net "M_B_MA<6>")
	)
	(segment
		(start 252.499876 -13.933678)
		(end 252.08738 -12.937744)
		(width 0.14224)
		(layer "In4.Cu")
		(net "M_B_MA<6>")
	)
	(segment
		(start 251.192792 -23.284688)
		(end 251.46 -23.01748)
		(width 0.14224)
		(layer "In4.Cu")
		(net "M_B_MA<6>")
	)
	(segment
		(start 254.7366 -53.00091)
		(end 254.7366 -51.5874)
		(width 0.0889)
		(layer "In4.Cu")
		(net "M_B_MA<6>")
	)
	(segment
		(start 251.293884 -21.16582)
		(end 251.212096 -21.084032)
		(width 0.14224)
		(layer "In4.Cu")
		(net "M_B_MA<6>")
	)
	(segment
		(start 251.212096 -18.486374)
		(end 251.462286 -18.236184)
		(width 0.14224)
		(layer "In4.Cu")
		(net "M_B_MA<6>")
	)
	(segment
		(start 250.886214 -15.291562)
		(end 251.041154 -15.136622)
		(width 0.14224)
		(layer "In4.Cu")
		(net "M_B_MA<6>")
	)
	(segment
		(start 252.499876 -14.213078)
		(end 252.499876 -13.933678)
		(width 0.14224)
		(layer "In4.Cu")
		(net "M_B_MA<6>")
	)
	(segment
		(start 254.83947 -54.810406)
		(end 254.84582 -54.799738)
		(width 0.0889)
		(layer "In4.Cu")
		(net "M_B_MA<6>")
	)
	(segment
		(start 250.886214 -15.543022)
		(end 250.886214 -15.291562)
		(width 0.14224)
		(layer "In4.Cu")
		(net "M_B_MA<6>")
	)
	(segment
		(start 251.192792 -24.756364)
		(end 251.192792 -23.284688)
		(width 0.14224)
		(layer "In4.Cu")
		(net "M_B_MA<6>")
	)
	(segment
		(start 251.462286 -18.236184)
		(end 251.462286 -17.643348)
		(width 0.14224)
		(layer "In4.Cu")
		(net "M_B_MA<6>")
	)
	(segment
		(start 251.72416 -9.676384)
		(end 252.091698 -9.308846)
		(width 0.14224)
		(layer "In4.Cu")
		(net "M_B_MA<6>")
	)
	(segment
		(start 252.08738 -12.937744)
		(end 252.08738 -11.742928)
		(width 0.14224)
		(layer "In4.Cu")
		(net "M_B_MA<6>")
	)
	(segment
		(start 251.72416 -11.379708)
		(end 251.72416 -9.676384)
		(width 0.14224)
		(layer "In4.Cu")
		(net "M_B_MA<6>")
	)
	(segment
		(start 251.293884 -21.811996)
		(end 251.293884 -21.16582)
		(width 0.14224)
		(layer "In4.Cu")
		(net "M_B_MA<6>")
	)
	(segment
		(start 251.242068 -17.42313)
		(end 251.242068 -16.53159)
		(width 0.14224)
		(layer "In4.Cu")
		(net "M_B_MA<6>")
	)
	(segment
		(start 251.212096 -21.084032)
		(end 251.212096 -18.486374)
		(width 0.14224)
		(layer "In4.Cu")
		(net "M_B_MA<6>")
	)
	(segment
		(start 251.430536 -15.697962)
		(end 251.041154 -15.697962)
		(width 0.14224)
		(layer "In4.Cu")
		(net "M_B_MA<6>")
	)
	(segment
		(start 254.83947 -55.801006)
		(end 254.84582 -55.790338)
		(width 0.0889)
		(layer "In4.Cu")
		(net "M_B_MA<6>")
	)
	(segment
		(start 255.9558 -29.519372)
		(end 251.192792 -24.756364)
		(width 0.14224)
		(layer "In4.Cu")
		(net "M_B_MA<6>")
	)
	(segment
		(start 251.46 -23.01748)
		(end 251.46 -22.714712)
		(width 0.14224)
		(layer "In4.Cu")
		(net "M_B_MA<6>")
	)
	(segment
		(start 251.576332 -15.136622)
		(end 252.499876 -14.213078)
		(width 0.14224)
		(layer "In4.Cu")
		(net "M_B_MA<6>")
	)
	(segment
		(start 252.30836 -8.079994)
		(end 252.349254 -7.874)
		(width 0.14224)
		(layer "In4.Cu")
		(net "M_B_MA<6>")
	)
	(segment
		(start 251.462286 -17.643348)
		(end 251.242068 -17.42313)
		(width 0.14224)
		(layer "In4.Cu")
		(net "M_B_MA<6>")
	)
	(segment
		(start 251.041154 -15.697962)
		(end 250.886214 -15.543022)
		(width 0.14224)
		(layer "In4.Cu")
		(net "M_B_MA<6>")
	)
	(segment
		(start 252.091698 -8.60298)
		(end 252.30836 -8.079994)
		(width 0.14224)
		(layer "In4.Cu")
		(net "M_B_MA<6>")
	)
	(segment
		(start 255.472184 -48.930052)
		(end 255.9558 -48.446436)
		(width 0.14224)
		(layer "In4.Cu")
		(net "M_B_MA<6>")
	)
	(segment
		(start 251.62002 -15.887446)
		(end 251.430536 -15.697962)
		(width 0.14224)
		(layer "In4.Cu")
		(net "M_B_MA<6>")
	)
	(segment
		(start 251.242068 -16.53159)
		(end 251.62002 -16.153638)
		(width 0.14224)
		(layer "In4.Cu")
		(net "M_B_MA<6>")
	)
	(segment
		(start 255.9558 -48.446436)
		(end 255.9558 -29.519372)
		(width 0.14224)
		(layer "In4.Cu")
		(net "M_B_MA<6>")
	)
	(segment
		(start 254.912114 -56.495442)
		(end 254.84582 -56.380888)
		(width 0.0889)
		(layer "In4.Cu")
		(net "M_B_MA<6>")
	)
	(segment
		(start 251.041154 -15.136622)
		(end 251.576332 -15.136622)
		(width 0.14224)
		(layer "In4.Cu")
		(net "M_B_MA<6>")
	)
	(segment
		(start 254.83947 -53.819806)
		(end 254.84582 -53.809138)
		(width 0.0889)
		(layer "In4.Cu")
		(net "M_B_MA<6>")
	)
	(segment
		(start 254.7366 -51.5874)
		(end 255.472184 -50.851816)
		(width 0.0889)
		(layer "In4.Cu")
		(net "M_B_MA<6>")
	)
	(segment
		(start 251.166884 -21.938996)
		(end 251.293884 -21.811996)
		(width 0.14224)
		(layer "In4.Cu")
		(net "M_B_MA<6>")
	)
	(segment
		(start 252.349254 -7.874)
		(end 252.499876 -7.117588)
		(width 0.14224)
		(layer "In4.Cu")
		(net "M_B_MA<6>")
	)
	(segment
		(start 254.84582 -55.790338)
		(end 254.850646 -55.781702)
		(width 0.0889)
		(layer "In4.Cu")
		(net "M_B_MA<6>")
	)
	(segment
		(start 255.472184 -50.851816)
		(end 255.472184 -50.496978)
		(width 0.0889)
		(layer "In4.Cu")
		(net "M_B_MA<6>")
	)
	(segment
		(start 254.84582 -54.799738)
		(end 254.850646 -54.791102)
		(width 0.0889)
		(layer "In4.Cu")
		(net "M_B_MA<6>")
	)
	(segment
		(start 251.166884 -22.421596)
		(end 251.166884 -21.938996)
		(width 0.14224)
		(layer "In4.Cu")
		(net "M_B_MA<6>")
	)
	(segment
		(start 254.84582 -53.809138)
		(end 254.850646 -53.800502)
		(width 0.0889)
		(layer "In4.Cu")
		(net "M_B_MA<6>")
	)
	(segment
		(start 252.091698 -9.308846)
		(end 252.091698 -8.60298)
		(width 0.14224)
		(layer "In4.Cu")
		(net "M_B_MA<6>")
	)
	(segment
		(start 251.62002 -16.153638)
		(end 251.62002 -15.887446)
		(width 0.14224)
		(layer "In4.Cu")
		(net "M_B_MA<6>")
	)
	(segment
		(start 255.472184 -50.496978)
		(end 255.472184 -48.930052)
		(width 0.14224)
		(layer "In4.Cu")
		(net "M_B_MA<6>")
	)
	(segment
		(start 251.46 -22.714712)
		(end 251.166884 -22.421596)
		(width 0.14224)
		(layer "In4.Cu")
		(net "M_B_MA<6>")
	)
	(segment
		(start 252.08738 -11.742928)
		(end 251.72416 -11.379708)
		(width 0.14224)
		(layer "In4.Cu")
		(net "M_B_MA<6>")
	)
	(arc
		(start 254.84582 -56.380888)
		(mid 254.766598 -56.09177)
		(end 254.83947 -55.801006)
		(width 0.0889)
		(layer "In4.Cu")
		(net "M_B_MA<6>")
	)
	(arc
		(start 254.850646 -55.781702)
		(mid 254.899401 -55.58535)
		(end 254.84582 -55.390288)
		(width 0.0889)
		(layer "In4.Cu")
		(net "M_B_MA<6>")
	)
	(arc
		(start 254.850646 -54.791102)
		(mid 254.899401 -54.59475)
		(end 254.84582 -54.399688)
		(width 0.0889)
		(layer "In4.Cu")
		(net "M_B_MA<6>")
	)
	(arc
		(start 254.84582 -55.390288)
		(mid 254.766598 -55.10117)
		(end 254.83947 -54.810406)
		(width 0.0889)
		(layer "In4.Cu")
		(net "M_B_MA<6>")
	)
	(arc
		(start 254.84582 -53.409088)
		(mid 254.764356 -53.212183)
		(end 254.7366 -53.00091)
		(width 0.0889)
		(layer "In4.Cu")
		(net "M_B_MA<6>")
	)
	(arc
		(start 255.35763 -57.076086)
		(mid 255.115856 -56.800354)
		(end 254.912114 -56.495442)
		(width 0.0889)
		(layer "In4.Cu")
		(net "M_B_MA<6>")
	)
	(arc
		(start 254.850646 -53.800502)
		(mid 254.899401 -53.60415)
		(end 254.84582 -53.409088)
		(width 0.0889)
		(layer "In4.Cu")
		(net "M_B_MA<6>")
	)
	(arc
		(start 254.84582 -54.399688)
		(mid 254.766598 -54.11057)
		(end 254.83947 -53.819806)
		(width 0.0889)
		(layer "In4.Cu")
		(net "M_B_MA<6>")
	)
	(segment
		(start 252.500384 -10.422382)
		(end 252.499876 -10.422382)
		(width 0.1651)
		(layer "F.Cu")
		(net "M_B_MA<5>")
	)
	(segment
		(start 252.499876 -10.422382)
		(end 252.499876 -9.133078)
		(width 0.1651)
		(layer "F.Cu")
		(net "M_B_MA<5>")
	)
	(segment
		(start 256.78765 -56.58104)
		(end 256.21615 -56.58104)
		(width 0.1016)
		(layer "F.Cu")
		(net "M_B_MA<5>")
	)
	(via
		(at 256.21615 -56.58104)
		(size 0.508)
		(drill 0.254)
		(layers "F.Cu" "B.Cu")
		(net "M_B_MA<5>")
	)
	(via
		(at 252.499876 -11.918188)
		(size 0.4572)
		(drill 0.2032)
		(layers "F.Cu" "B.Cu")
		(net "M_B_MA<5>")
	)
	(via
		(at 252.499876 -9.133078)
		(size 0.4572)
		(drill 0.2032)
		(layers "F.Cu" "B.Cu")
		(net "M_B_MA<5>")
	)
	(segment
		(start 252.500384 -10.623042)
		(end 252.499876 -10.623042)
		(width 0.1651)
		(layer "B.Cu")
		(net "M_B_MA<5>")
	)
	(segment
		(start 252.499876 -10.623042)
		(end 252.499876 -11.918188)
		(width 0.1651)
		(layer "B.Cu")
		(net "M_B_MA<5>")
	)
	(segment
		(start 253.080266 -10.248392)
		(end 253.235206 -10.403332)
		(width 0.14224)
		(layer "In4.Cu")
		(net "M_B_MA<5>")
	)
	(segment
		(start 252.499876 -12.7)
		(end 252.913896 -13.11402)
		(width 0.14224)
		(layer "In4.Cu")
		(net "M_B_MA<5>")
	)
	(segment
		(start 255.342644 -55.494936)
		(end 255.37541 -55.494936)
		(width 0.0889)
		(layer "In4.Cu")
		(net "M_B_MA<5>")
	)
	(segment
		(start 252.499876 -9.133078)
		(end 252.780038 -9.133078)
		(width 0.14224)
		(layer "In4.Cu")
		(net "M_B_MA<5>")
	)
	(segment
		(start 252.107192 -23.234904)
		(end 252.107192 -24.952198)
		(width 0.14224)
		(layer "In4.Cu")
		(net "M_B_MA<5>")
	)
	(segment
		(start 255.01727 -54.88432)
		(end 255.01092 -54.894988)
		(width 0.0889)
		(layer "In4.Cu")
		(net "M_B_MA<5>")
	)
	(segment
		(start 252.279912 -10.809732)
		(end 252.13818 -10.951464)
		(width 0.14224)
		(layer "In4.Cu")
		(net "M_B_MA<5>")
	)
	(segment
		(start 252.005084 -21.761196)
		(end 252.157484 -21.913596)
		(width 0.14224)
		(layer "In4.Cu")
		(net "M_B_MA<5>")
	)
	(segment
		(start 252.005084 -19.08937)
		(end 252.005084 -21.761196)
		(width 0.14224)
		(layer "In4.Cu")
		(net "M_B_MA<5>")
	)
	(segment
		(start 252.13818 -10.951464)
		(end 252.13818 -11.202924)
		(width 0.14224)
		(layer "In4.Cu")
		(net "M_B_MA<5>")
	)
	(segment
		(start 252.053598 -22.500082)
		(end 252.053598 -23.18131)
		(width 0.14224)
		(layer "In4.Cu")
		(net "M_B_MA<5>")
	)
	(segment
		(start 252.81001 -11.918188)
		(end 252.499876 -11.918188)
		(width 0.14224)
		(layer "In4.Cu")
		(net "M_B_MA<5>")
	)
	(segment
		(start 252.923802 -9.276842)
		(end 252.923802 -9.534906)
		(width 0.14224)
		(layer "In4.Cu")
		(net "M_B_MA<5>")
	)
	(segment
		(start 256.4638 -48.984662)
		(end 256.4638 -49.276)
		(width 0.0889)
		(layer "In4.Cu")
		(net "M_B_MA<5>")
	)
	(segment
		(start 253.080266 -10.809732)
		(end 252.279912 -10.809732)
		(width 0.14224)
		(layer "In4.Cu")
		(net "M_B_MA<5>")
	)
	(segment
		(start 252.293374 -10.248392)
		(end 253.080266 -10.248392)
		(width 0.14224)
		(layer "In4.Cu")
		(net "M_B_MA<5>")
	)
	(segment
		(start 252.076712 -18.450814)
		(end 252.090174 -18.464276)
		(width 0.14224)
		(layer "In4.Cu")
		(net "M_B_MA<5>")
	)
	(segment
		(start 252.076712 -15.232634)
		(end 252.076712 -18.450814)
		(width 0.14224)
		(layer "In4.Cu")
		(net "M_B_MA<5>")
	)
	(segment
		(start 255.01727 -53.89372)
		(end 255.01092 -53.904388)
		(width 0.0889)
		(layer "In4.Cu")
		(net "M_B_MA<5>")
	)
	(segment
		(start 253.235206 -10.403332)
		(end 253.235206 -10.654792)
		(width 0.14224)
		(layer "In4.Cu")
		(net "M_B_MA<5>")
	)
	(segment
		(start 252.499876 -11.918188)
		(end 252.499876 -12.7)
		(width 0.14224)
		(layer "In4.Cu")
		(net "M_B_MA<5>")
	)
	(segment
		(start 255.01092 -53.904388)
		(end 255.006094 -53.913024)
		(width 0.0889)
		(layer "In4.Cu")
		(net "M_B_MA<5>")
	)
	(segment
		(start 252.053598 -23.18131)
		(end 252.107192 -23.234904)
		(width 0.14224)
		(layer "In4.Cu")
		(net "M_B_MA<5>")
	)
	(segment
		(start 252.138434 -9.841992)
		(end 252.138434 -10.093452)
		(width 0.14224)
		(layer "In4.Cu")
		(net "M_B_MA<5>")
	)
	(segment
		(start 252.090174 -18.464276)
		(end 252.090174 -19.00428)
		(width 0.14224)
		(layer "In4.Cu")
		(net "M_B_MA<5>")
	)
	(segment
		(start 252.107192 -24.952198)
		(end 256.4638 -29.308806)
		(width 0.14224)
		(layer "In4.Cu")
		(net "M_B_MA<5>")
	)
	(segment
		(start 252.13818 -11.202924)
		(end 252.306328 -11.371072)
		(width 0.14224)
		(layer "In4.Cu")
		(net "M_B_MA<5>")
	)
	(segment
		(start 254.9398 -51.892454)
		(end 254.9398 -53.048662)
		(width 0.0889)
		(layer "In4.Cu")
		(net "M_B_MA<5>")
	)
	(segment
		(start 252.77699 -11.371072)
		(end 252.93701 -11.531092)
		(width 0.14224)
		(layer "In4.Cu")
		(net "M_B_MA<5>")
	)
	(segment
		(start 252.93701 -11.791188)
		(end 252.81001 -11.918188)
		(width 0.14224)
		(layer "In4.Cu")
		(net "M_B_MA<5>")
	)
	(segment
		(start 252.93701 -11.531092)
		(end 252.93701 -11.791188)
		(width 0.14224)
		(layer "In4.Cu")
		(net "M_B_MA<5>")
	)
	(segment
		(start 252.923802 -9.534906)
		(end 252.771656 -9.687052)
		(width 0.14224)
		(layer "In4.Cu")
		(net "M_B_MA<5>")
	)
	(segment
		(start 252.913896 -13.11402)
		(end 252.913896 -14.39545)
		(width 0.14224)
		(layer "In4.Cu")
		(net "M_B_MA<5>")
	)
	(segment
		(start 253.235206 -10.654792)
		(end 253.080266 -10.809732)
		(width 0.14224)
		(layer "In4.Cu")
		(net "M_B_MA<5>")
	)
	(segment
		(start 256.4638 -29.308806)
		(end 256.4638 -48.984662)
		(width 0.14224)
		(layer "In4.Cu")
		(net "M_B_MA<5>")
	)
	(segment
		(start 252.306328 -11.371072)
		(end 252.77699 -11.371072)
		(width 0.14224)
		(layer "In4.Cu")
		(net "M_B_MA<5>")
	)
	(segment
		(start 252.157484 -22.396196)
		(end 252.053598 -22.500082)
		(width 0.14224)
		(layer "In4.Cu")
		(net "M_B_MA<5>")
	)
	(segment
		(start 252.090174 -19.00428)
		(end 252.005084 -19.08937)
		(width 0.14224)
		(layer "In4.Cu")
		(net "M_B_MA<5>")
	)
	(segment
		(start 252.293374 -9.687052)
		(end 252.138434 -9.841992)
		(width 0.14224)
		(layer "In4.Cu")
		(net "M_B_MA<5>")
	)
	(segment
		(start 252.138434 -10.093452)
		(end 252.293374 -10.248392)
		(width 0.14224)
		(layer "In4.Cu")
		(net "M_B_MA<5>")
	)
	(segment
		(start 252.913896 -14.39545)
		(end 252.076712 -15.232634)
		(width 0.14224)
		(layer "In4.Cu")
		(net "M_B_MA<5>")
	)
	(segment
		(start 255.886712 -55.820056)
		(end 256.21615 -56.58104)
		(width 0.0889)
		(layer "In4.Cu")
		(net "M_B_MA<5>")
	)
	(segment
		(start 255.905 -50.927254)
		(end 254.9398 -51.892454)
		(width 0.0889)
		(layer "In4.Cu")
		(net "M_B_MA<5>")
	)
	(segment
		(start 252.771656 -9.687052)
		(end 252.293374 -9.687052)
		(width 0.14224)
		(layer "In4.Cu")
		(net "M_B_MA<5>")
	)
	(segment
		(start 255.905 -49.8348)
		(end 255.905 -50.927254)
		(width 0.0889)
		(layer "In4.Cu")
		(net "M_B_MA<5>")
	)
	(segment
		(start 256.4638 -49.276)
		(end 255.905 -49.8348)
		(width 0.0889)
		(layer "In4.Cu")
		(net "M_B_MA<5>")
	)
	(segment
		(start 252.157484 -21.913596)
		(end 252.157484 -22.396196)
		(width 0.14224)
		(layer "In4.Cu")
		(net "M_B_MA<5>")
	)
	(segment
		(start 252.780038 -9.133078)
		(end 252.923802 -9.276842)
		(width 0.14224)
		(layer "In4.Cu")
		(net "M_B_MA<5>")
	)
	(segment
		(start 255.01092 -54.894988)
		(end 255.006094 -54.903624)
		(width 0.0889)
		(layer "In4.Cu")
		(net "M_B_MA<5>")
	)
	(segment
		(start 255.86944 -55.790338)
		(end 255.886712 -55.820056)
		(width 0.0889)
		(layer "In4.Cu")
		(net "M_B_MA<5>")
	)
	(arc
		(start 255.006094 -53.913024)
		(mid 254.957339 -54.109376)
		(end 255.01092 -54.304438)
		(width 0.0889)
		(layer "In4.Cu")
		(net "M_B_MA<5>")
	)
	(arc
		(start 255.006094 -54.903624)
		(mid 255.009841 -55.29288)
		(end 255.342644 -55.494936)
		(width 0.0889)
		(layer "In4.Cu")
		(net "M_B_MA<5>")
	)
	(arc
		(start 255.37541 -55.494936)
		(mid 255.660834 -55.578403)
		(end 255.86944 -55.790338)
		(width 0.0889)
		(layer "In4.Cu")
		(net "M_B_MA<5>")
	)
	(arc
		(start 255.01092 -53.313838)
		(mid 255.090142 -53.602956)
		(end 255.01727 -53.89372)
		(width 0.0889)
		(layer "In4.Cu")
		(net "M_B_MA<5>")
	)
	(arc
		(start 255.01092 -54.304438)
		(mid 255.090142 -54.593556)
		(end 255.01727 -54.88432)
		(width 0.0889)
		(layer "In4.Cu")
		(net "M_B_MA<5>")
	)
	(arc
		(start 254.9398 -53.048662)
		(mid 254.957876 -53.185943)
		(end 255.01092 -53.313838)
		(width 0.0889)
		(layer "In4.Cu")
		(net "M_B_MA<5>")
	)
	(segment
		(start 253.350522 -10.422382)
		(end 253.350014 -10.422382)
		(width 0.1651)
		(layer "F.Cu")
		(net "M_B_MA<4>")
	)
	(segment
		(start 255.92913 -55.094886)
		(end 255.35763 -55.094886)
		(width 0.1016)
		(layer "F.Cu")
		(net "M_B_MA<4>")
	)
	(segment
		(start 253.350014 -10.422382)
		(end 253.350014 -9.133078)
		(width 0.1651)
		(layer "F.Cu")
		(net "M_B_MA<4>")
	)
	(via
		(at 253.350014 -11.918188)
		(size 0.4572)
		(drill 0.2032)
		(layers "F.Cu" "B.Cu")
		(net "M_B_MA<4>")
	)
	(via
		(at 255.35763 -55.094886)
		(size 0.508)
		(drill 0.254)
		(layers "F.Cu" "B.Cu")
		(net "M_B_MA<4>")
	)
	(via
		(at 253.350014 -9.133078)
		(size 0.4572)
		(drill 0.2032)
		(layers "F.Cu" "B.Cu")
		(net "M_B_MA<4>")
	)
	(segment
		(start 253.350522 -10.623042)
		(end 253.350014 -10.623042)
		(width 0.1651)
		(layer "B.Cu")
		(net "M_B_MA<4>")
	)
	(segment
		(start 253.350014 -10.623042)
		(end 253.350014 -11.918188)
		(width 0.1651)
		(layer "B.Cu")
		(net "M_B_MA<4>")
	)
	(segment
		(start 253.350014 -12.448794)
		(end 253.350014 -11.918188)
		(width 0.14224)
		(layer "In4.Cu")
		(net "M_B_MA<4>")
	)
	(segment
		(start 255.709166 -53.913024)
		(end 255.70434 -53.904388)
		(width 0.0889)
		(layer "In4.Cu")
		(net "M_B_MA<4>")
	)
	(segment
		(start 255.70434 -53.904388)
		(end 255.69799 -53.89372)
		(width 0.0889)
		(layer "In4.Cu")
		(net "M_B_MA<4>")
	)
	(segment
		(start 255.687576 -54.33314)
		(end 255.70434 -54.304438)
		(width 0.0889)
		(layer "In4.Cu")
		(net "M_B_MA<4>")
	)
	(segment
		(start 253.350014 -11.918188)
		(end 253.350014 -11.499088)
		(width 0.14224)
		(layer "In4.Cu")
		(net "M_B_MA<4>")
	)
	(segment
		(start 252.995684 -22.599396)
		(end 252.843284 -22.446996)
		(width 0.14224)
		(layer "In4.Cu")
		(net "M_B_MA<4>")
	)
	(segment
		(start 256.159 -50.0634)
		(end 256.9718 -49.2506)
		(width 0.0889)
		(layer "In4.Cu")
		(net "M_B_MA<4>")
	)
	(segment
		(start 255.821434 -52.876958)
		(end 255.821434 -51.636676)
		(width 0.0889)
		(layer "In4.Cu")
		(net "M_B_MA<4>")
	)
	(segment
		(start 253.350014 -9.584944)
		(end 253.350014 -9.133078)
		(width 0.14224)
		(layer "In4.Cu")
		(net "M_B_MA<4>")
	)
	(segment
		(start 252.995684 -17.769586)
		(end 252.792484 -17.566386)
		(width 0.14224)
		(layer "In4.Cu")
		(net "M_B_MA<4>")
	)
	(segment
		(start 253.350014 -11.499088)
		(end 253.652274 -11.196828)
		(width 0.14224)
		(layer "In4.Cu")
		(net "M_B_MA<4>")
	)
	(segment
		(start 253.7841 -13.74648)
		(end 253.5428 -13.50518)
		(width 0.14224)
		(layer "In4.Cu")
		(net "M_B_MA<4>")
	)
	(segment
		(start 252.921008 -18.403062)
		(end 252.995684 -18.328386)
		(width 0.14224)
		(layer "In4.Cu")
		(net "M_B_MA<4>")
	)
	(segment
		(start 253.652274 -9.887204)
		(end 253.350014 -9.584944)
		(width 0.14224)
		(layer "In4.Cu")
		(net "M_B_MA<4>")
	)
	(segment
		(start 252.792484 -17.566386)
		(end 252.792484 -17.210786)
		(width 0.14224)
		(layer "In4.Cu")
		(net "M_B_MA<4>")
	)
	(segment
		(start 252.843284 -22.446996)
		(end 252.843284 -21.888196)
		(width 0.14224)
		(layer "In4.Cu")
		(net "M_B_MA<4>")
	)
	(segment
		(start 256.9718 -49.2506)
		(end 256.9718 -48.984662)
		(width 0.0889)
		(layer "In4.Cu")
		(net "M_B_MA<4>")
	)
	(segment
		(start 255.821434 -51.636676)
		(end 256.159 -51.29911)
		(width 0.0889)
		(layer "In4.Cu")
		(net "M_B_MA<4>")
	)
	(segment
		(start 256.159 -51.29911)
		(end 256.159 -50.0634)
		(width 0.0889)
		(layer "In4.Cu")
		(net "M_B_MA<4>")
	)
	(segment
		(start 252.995684 -18.328386)
		(end 252.995684 -17.769586)
		(width 0.14224)
		(layer "In4.Cu")
		(net "M_B_MA<4>")
	)
	(segment
		(start 256.9718 -29.097986)
		(end 253.512828 -25.639014)
		(width 0.14224)
		(layer "In4.Cu")
		(net "M_B_MA<4>")
	)
	(segment
		(start 253.5428 -12.64158)
		(end 253.350014 -12.448794)
		(width 0.14224)
		(layer "In4.Cu")
		(net "M_B_MA<4>")
	)
	(segment
		(start 255.35763 -55.094886)
		(end 255.687576 -54.33314)
		(width 0.0889)
		(layer "In4.Cu")
		(net "M_B_MA<4>")
	)
	(segment
		(start 253.7841 -14.2113)
		(end 253.7841 -13.74648)
		(width 0.14224)
		(layer "In4.Cu")
		(net "M_B_MA<4>")
	)
	(segment
		(start 252.995684 -23.107396)
		(end 252.995684 -22.599396)
		(width 0.14224)
		(layer "In4.Cu")
		(net "M_B_MA<4>")
	)
	(segment
		(start 252.792484 -17.210786)
		(end 252.913388 -17.089882)
		(width 0.14224)
		(layer "In4.Cu")
		(net "M_B_MA<4>")
	)
	(segment
		(start 252.843284 -21.888196)
		(end 252.995684 -21.735796)
		(width 0.14224)
		(layer "In4.Cu")
		(net "M_B_MA<4>")
	)
	(segment
		(start 253.5428 -13.50518)
		(end 253.5428 -12.64158)
		(width 0.14224)
		(layer "In4.Cu")
		(net "M_B_MA<4>")
	)
	(segment
		(start 252.913388 -15.082012)
		(end 253.7841 -14.2113)
		(width 0.14224)
		(layer "In4.Cu")
		(net "M_B_MA<4>")
	)
	(segment
		(start 252.995684 -21.735796)
		(end 252.995684 -21.2598)
		(width 0.14224)
		(layer "In4.Cu")
		(net "M_B_MA<4>")
	)
	(segment
		(start 252.995684 -21.2598)
		(end 252.921008 -21.185124)
		(width 0.14224)
		(layer "In4.Cu")
		(net "M_B_MA<4>")
	)
	(segment
		(start 253.512828 -24.369776)
		(end 252.843284 -23.700232)
		(width 0.14224)
		(layer "In4.Cu")
		(net "M_B_MA<4>")
	)
	(segment
		(start 252.843284 -23.259796)
		(end 252.995684 -23.107396)
		(width 0.14224)
		(layer "In4.Cu")
		(net "M_B_MA<4>")
	)
	(segment
		(start 253.652274 -11.196828)
		(end 253.652274 -9.887204)
		(width 0.14224)
		(layer "In4.Cu")
		(net "M_B_MA<4>")
	)
	(segment
		(start 252.913388 -17.089882)
		(end 252.913388 -15.082012)
		(width 0.14224)
		(layer "In4.Cu")
		(net "M_B_MA<4>")
	)
	(segment
		(start 253.512828 -25.639014)
		(end 253.512828 -24.369776)
		(width 0.14224)
		(layer "In4.Cu")
		(net "M_B_MA<4>")
	)
	(segment
		(start 252.843284 -23.700232)
		(end 252.843284 -23.259796)
		(width 0.14224)
		(layer "In4.Cu")
		(net "M_B_MA<4>")
	)
	(segment
		(start 252.921008 -21.185124)
		(end 252.921008 -18.403062)
		(width 0.14224)
		(layer "In4.Cu")
		(net "M_B_MA<4>")
	)
	(segment
		(start 256.9718 -48.984662)
		(end 256.9718 -29.097986)
		(width 0.14224)
		(layer "In4.Cu")
		(net "M_B_MA<4>")
	)
	(arc
		(start 255.70434 -53.313838)
		(mid 255.791682 -53.103113)
		(end 255.821434 -52.876958)
		(width 0.0889)
		(layer "In4.Cu")
		(net "M_B_MA<4>")
	)
	(arc
		(start 255.70434 -54.304438)
		(mid 255.75781 -54.109375)
		(end 255.709166 -53.913024)
		(width 0.0889)
		(layer "In4.Cu")
		(net "M_B_MA<4>")
	)
	(arc
		(start 255.69799 -53.89372)
		(mid 255.625192 -53.602957)
		(end 255.70434 -53.313838)
		(width 0.0889)
		(layer "In4.Cu")
		(net "M_B_MA<4>")
	)
	(segment
		(start 256.78765 -55.59044)
		(end 256.21615 -55.59044)
		(width 0.1016)
		(layer "F.Cu")
		(net "M_B_MA<3>")
	)
	(segment
		(start 254.200406 -5.822442)
		(end 254.199898 -5.822442)
		(width 0.1651)
		(layer "F.Cu")
		(net "M_B_MA<3>")
	)
	(segment
		(start 254.199898 -5.822442)
		(end 254.199898 -7.117588)
		(width 0.1651)
		(layer "F.Cu")
		(net "M_B_MA<3>")
	)
	(via
		(at 256.21615 -55.59044)
		(size 0.508)
		(drill 0.254)
		(layers "F.Cu" "B.Cu")
		(net "M_B_MA<3>")
	)
	(via
		(at 254.199898 -13.933678)
		(size 0.4572)
		(drill 0.2032)
		(layers "F.Cu" "B.Cu")
		(net "M_B_MA<3>")
	)
	(via
		(at 254.199898 -7.117588)
		(size 0.4572)
		(drill 0.2032)
		(layers "F.Cu" "B.Cu")
		(net "M_B_MA<3>")
	)
	(segment
		(start 254.200406 -15.222982)
		(end 254.199898 -15.222982)
		(width 0.1651)
		(layer "B.Cu")
		(net "M_B_MA<3>")
	)
	(segment
		(start 254.199898 -15.222982)
		(end 254.199898 -13.933678)
		(width 0.1651)
		(layer "B.Cu")
		(net "M_B_MA<3>")
	)
	(segment
		(start 253.742698 -21.212048)
		(end 253.764288 -21.190458)
		(width 0.14224)
		(layer "In4.Cu")
		(net "M_B_MA<3>")
	)
	(segment
		(start 254.020828 -23.501096)
		(end 253.742698 -23.222966)
		(width 0.14224)
		(layer "In4.Cu")
		(net "M_B_MA<3>")
	)
	(segment
		(start 253.742698 -18.418556)
		(end 253.742698 -17.806416)
		(width 0.14224)
		(layer "In4.Cu")
		(net "M_B_MA<3>")
	)
	(segment
		(start 255.87579 -53.819806)
		(end 255.86944 -53.809138)
		(width 0.0889)
		(layer "In4.Cu")
		(net "M_B_MA<3>")
	)
	(segment
		(start 257.4798 -48.910494)
		(end 257.4798 -28.887166)
		(width 0.14224)
		(layer "In4.Cu")
		(net "M_B_MA<3>")
	)
	(segment
		(start 254.0762 -9.700514)
		(end 253.763018 -9.387332)
		(width 0.14224)
		(layer "In4.Cu")
		(net "M_B_MA<3>")
	)
	(segment
		(start 253.76124 -12.167108)
		(end 253.76124 -11.678666)
		(width 0.14224)
		(layer "In4.Cu")
		(net "M_B_MA<3>")
	)
	(segment
		(start 254.3556 -14.376654)
		(end 254.3556 -14.08938)
		(width 0.14224)
		(layer "In4.Cu")
		(net "M_B_MA<3>")
	)
	(segment
		(start 253.763018 -8.029448)
		(end 254.199898 -7.592568)
		(width 0.14224)
		(layer "In4.Cu")
		(net "M_B_MA<3>")
	)
	(segment
		(start 253.807214 -22.55901)
		(end 253.807214 -21.814282)
		(width 0.14224)
		(layer "In4.Cu")
		(net "M_B_MA<3>")
	)
	(segment
		(start 256.413 -51.409092)
		(end 256.413 -50.292)
		(width 0.0889)
		(layer "In4.Cu")
		(net "M_B_MA<3>")
	)
	(segment
		(start 253.788672 -17.760442)
		(end 253.788672 -14.943582)
		(width 0.14224)
		(layer "In4.Cu")
		(net "M_B_MA<3>")
	)
	(segment
		(start 255.86944 -53.409088)
		(end 255.997202 -53.1876)
		(width 0.0889)
		(layer "In4.Cu")
		(net "M_B_MA<3>")
	)
	(segment
		(start 253.742698 -17.806416)
		(end 253.788672 -17.760442)
		(width 0.14224)
		(layer "In4.Cu")
		(net "M_B_MA<3>")
	)
	(segment
		(start 256.413 -50.292)
		(end 257.4798 -49.2252)
		(width 0.0889)
		(layer "In4.Cu")
		(net "M_B_MA<3>")
	)
	(segment
		(start 254.020828 -25.428194)
		(end 254.020828 -23.501096)
		(width 0.14224)
		(layer "In4.Cu")
		(net "M_B_MA<3>")
	)
	(segment
		(start 254.0762 -11.363706)
		(end 254.0762 -9.700514)
		(width 0.14224)
		(layer "In4.Cu")
		(net "M_B_MA<3>")
	)
	(segment
		(start 255.886712 -54.829456)
		(end 255.864614 -54.791102)
		(width 0.0889)
		(layer "In4.Cu")
		(net "M_B_MA<3>")
	)
	(segment
		(start 256.21615 -55.59044)
		(end 255.886712 -54.829456)
		(width 0.0889)
		(layer "In4.Cu")
		(net "M_B_MA<3>")
	)
	(segment
		(start 257.4798 -49.2252)
		(end 257.4798 -48.910494)
		(width 0.0889)
		(layer "In4.Cu")
		(net "M_B_MA<3>")
	)
	(segment
		(start 254.199898 -13.249656)
		(end 254.0762 -13.125958)
		(width 0.14224)
		(layer "In4.Cu")
		(net "M_B_MA<3>")
	)
	(segment
		(start 253.742698 -22.623526)
		(end 253.807214 -22.55901)
		(width 0.14224)
		(layer "In4.Cu")
		(net "M_B_MA<3>")
	)
	(segment
		(start 253.742698 -23.222966)
		(end 253.742698 -22.623526)
		(width 0.14224)
		(layer "In4.Cu")
		(net "M_B_MA<3>")
	)
	(segment
		(start 255.86944 -53.809138)
		(end 255.864614 -53.800502)
		(width 0.0889)
		(layer "In4.Cu")
		(net "M_B_MA<3>")
	)
	(segment
		(start 256.133092 -51.689)
		(end 256.413 -51.409092)
		(width 0.0889)
		(layer "In4.Cu")
		(net "M_B_MA<3>")
	)
	(segment
		(start 253.788672 -14.943582)
		(end 254.3556 -14.376654)
		(width 0.14224)
		(layer "In4.Cu")
		(net "M_B_MA<3>")
	)
	(segment
		(start 253.807214 -21.814282)
		(end 253.742698 -21.749766)
		(width 0.14224)
		(layer "In4.Cu")
		(net "M_B_MA<3>")
	)
	(segment
		(start 254.3556 -14.08938)
		(end 254.199898 -13.933678)
		(width 0.14224)
		(layer "In4.Cu")
		(net "M_B_MA<3>")
	)
	(segment
		(start 253.764288 -18.440146)
		(end 253.742698 -18.418556)
		(width 0.14224)
		(layer "In4.Cu")
		(net "M_B_MA<3>")
	)
	(segment
		(start 253.763018 -9.387332)
		(end 253.763018 -8.029448)
		(width 0.14224)
		(layer "In4.Cu")
		(net "M_B_MA<3>")
	)
	(segment
		(start 254.199898 -7.592568)
		(end 254.199898 -7.117588)
		(width 0.14224)
		(layer "In4.Cu")
		(net "M_B_MA<3>")
	)
	(segment
		(start 254.199898 -13.933678)
		(end 254.199898 -13.249656)
		(width 0.14224)
		(layer "In4.Cu")
		(net "M_B_MA<3>")
	)
	(segment
		(start 253.76124 -11.678666)
		(end 254.0762 -11.363706)
		(width 0.14224)
		(layer "In4.Cu")
		(net "M_B_MA<3>")
	)
	(segment
		(start 254.0762 -12.482068)
		(end 253.76124 -12.167108)
		(width 0.14224)
		(layer "In4.Cu")
		(net "M_B_MA<3>")
	)
	(segment
		(start 254.0762 -13.125958)
		(end 254.0762 -12.482068)
		(width 0.14224)
		(layer "In4.Cu")
		(net "M_B_MA<3>")
	)
	(segment
		(start 253.764288 -21.190458)
		(end 253.764288 -18.440146)
		(width 0.14224)
		(layer "In4.Cu")
		(net "M_B_MA<3>")
	)
	(segment
		(start 257.4798 -28.887166)
		(end 254.020828 -25.428194)
		(width 0.14224)
		(layer "In4.Cu")
		(net "M_B_MA<3>")
	)
	(segment
		(start 256.133092 -52.6796)
		(end 256.133092 -51.689)
		(width 0.0889)
		(layer "In4.Cu")
		(net "M_B_MA<3>")
	)
	(segment
		(start 253.742698 -21.749766)
		(end 253.742698 -21.212048)
		(width 0.14224)
		(layer "In4.Cu")
		(net "M_B_MA<3>")
	)
	(arc
		(start 255.864614 -54.791102)
		(mid 255.815859 -54.59475)
		(end 255.86944 -54.399688)
		(width 0.0889)
		(layer "In4.Cu")
		(net "M_B_MA<3>")
	)
	(arc
		(start 255.86944 -54.399688)
		(mid 255.948662 -54.11057)
		(end 255.87579 -53.819806)
		(width 0.0889)
		(layer "In4.Cu")
		(net "M_B_MA<3>")
	)
	(arc
		(start 255.997202 -53.1876)
		(mid 256.098578 -52.942539)
		(end 256.133092 -52.6796)
		(width 0.0889)
		(layer "In4.Cu")
		(net "M_B_MA<3>")
	)
	(arc
		(start 255.864614 -53.800502)
		(mid 255.815859 -53.60415)
		(end 255.86944 -53.409088)
		(width 0.0889)
		(layer "In4.Cu")
		(net "M_B_MA<3>")
	)
	(segment
		(start 255.050036 -9.158478)
		(end 255.050036 -9.133078)
		(width 0.1651)
		(layer "F.Cu")
		(net "M_B_MA<2>")
	)
	(segment
		(start 255.049782 -10.422382)
		(end 255.049782 -9.158732)
		(width 0.1651)
		(layer "F.Cu")
		(net "M_B_MA<2>")
	)
	(segment
		(start 255.05029 -10.422382)
		(end 255.049782 -10.422382)
		(width 0.1651)
		(layer "F.Cu")
		(net "M_B_MA<2>")
	)
	(segment
		(start 255.049782 -9.158732)
		(end 255.050036 -9.158478)
		(width 0.1651)
		(layer "F.Cu")
		(net "M_B_MA<2>")
	)
	(segment
		(start 257.64617 -54.104286)
		(end 257.07467 -54.104286)
		(width 0.1016)
		(layer "F.Cu")
		(net "M_B_MA<2>")
	)
	(via
		(at 257.07467 -54.104286)
		(size 0.508)
		(drill 0.254)
		(layers "F.Cu" "B.Cu")
		(net "M_B_MA<2>")
	)
	(via
		(at 255.049782 -11.918188)
		(size 0.4572)
		(drill 0.2032)
		(layers "F.Cu" "B.Cu")
		(net "M_B_MA<2>")
	)
	(via
		(at 255.050036 -9.133078)
		(size 0.4572)
		(drill 0.2032)
		(layers "F.Cu" "B.Cu")
		(net "M_B_MA<2>")
	)
	(segment
		(start 255.049782 -10.623042)
		(end 255.049782 -11.918188)
		(width 0.1651)
		(layer "B.Cu")
		(net "M_B_MA<2>")
	)
	(segment
		(start 255.05029 -10.623042)
		(end 255.049782 -10.623042)
		(width 0.1651)
		(layer "B.Cu")
		(net "M_B_MA<2>")
	)
	(segment
		(start 255.463294 -16.418814)
		(end 255.463294 -16.92402)
		(width 0.14224)
		(layer "In4.Cu")
		(net "M_B_MA<2>")
	)
	(segment
		(start 255.417828 -14.970252)
		(end 255.417828 -15.344394)
		(width 0.14224)
		(layer "In4.Cu")
		(net "M_B_MA<2>")
	)
	(segment
		(start 255.474978 -10.259568)
		(end 255.049782 -10.684764)
		(width 0.14224)
		(layer "In4.Cu")
		(net "M_B_MA<2>")
	)
	(segment
		(start 255.049782 -10.684764)
		(end 255.049782 -11.918188)
		(width 0.14224)
		(layer "In4.Cu")
		(net "M_B_MA<2>")
	)
	(segment
		(start 258.4958 -49.2252)
		(end 256.921 -50.8)
		(width 0.0889)
		(layer "In4.Cu")
		(net "M_B_MA<2>")
	)
	(segment
		(start 255.329944 -18.429986)
		(end 255.557528 -18.65757)
		(width 0.14224)
		(layer "In4.Cu")
		(net "M_B_MA<2>")
	)
	(segment
		(start 255.474978 -9.55802)
		(end 255.474978 -10.259568)
		(width 0.14224)
		(layer "In4.Cu")
		(net "M_B_MA<2>")
	)
	(segment
		(start 255.557528 -18.65757)
		(end 255.557528 -21.06422)
		(width 0.14224)
		(layer "In4.Cu")
		(net "M_B_MA<2>")
	)
	(segment
		(start 255.405128 -21.761196)
		(end 255.46685 -21.822918)
		(width 0.14224)
		(layer "In4.Cu")
		(net "M_B_MA<2>")
	)
	(segment
		(start 255.417828 -15.344394)
		(end 255.544828 -15.471394)
		(width 0.14224)
		(layer "In4.Cu")
		(net "M_B_MA<2>")
	)
	(segment
		(start 256.921 -51.696366)
		(end 256.674366 -51.943)
		(width 0.0889)
		(layer "In4.Cu")
		(net "M_B_MA<2>")
	)
	(segment
		(start 255.463294 -16.92402)
		(end 255.329944 -17.05737)
		(width 0.14224)
		(layer "In4.Cu")
		(net "M_B_MA<2>")
	)
	(segment
		(start 255.049782 -11.918188)
		(end 255.049782 -13.267182)
		(width 0.14224)
		(layer "In4.Cu")
		(net "M_B_MA<2>")
	)
	(segment
		(start 255.618234 -16.263874)
		(end 255.463294 -16.418814)
		(width 0.14224)
		(layer "In4.Cu")
		(net "M_B_MA<2>")
	)
	(segment
		(start 255.049782 -13.267182)
		(end 255.636014 -13.853414)
		(width 0.14224)
		(layer "In4.Cu")
		(net "M_B_MA<2>")
	)
	(segment
		(start 255.544828 -15.471394)
		(end 256.124456 -15.471394)
		(width 0.14224)
		(layer "In4.Cu")
		(net "M_B_MA<2>")
	)
	(segment
		(start 256.674366 -51.943)
		(end 256.674366 -53.111146)
		(width 0.0889)
		(layer "In4.Cu")
		(net "M_B_MA<2>")
	)
	(segment
		(start 257.61569 -26.467816)
		(end 258.4958 -27.347926)
		(width 0.14224)
		(layer "In4.Cu")
		(net "M_B_MA<2>")
	)
	(segment
		(start 256.124456 -15.471394)
		(end 256.279396 -15.626334)
		(width 0.14224)
		(layer "In4.Cu")
		(net "M_B_MA<2>")
	)
	(segment
		(start 255.379728 -23.107396)
		(end 255.47066 -23.198328)
		(width 0.14224)
		(layer "In4.Cu")
		(net "M_B_MA<2>")
	)
	(segment
		(start 256.72796 -53.314092)
		(end 257.07467 -54.104286)
		(width 0.0889)
		(layer "In4.Cu")
		(net "M_B_MA<2>")
	)
	(segment
		(start 255.557528 -21.06422)
		(end 255.405128 -21.21662)
		(width 0.14224)
		(layer "In4.Cu")
		(net "M_B_MA<2>")
	)
	(segment
		(start 255.47066 -23.198328)
		(end 255.47066 -23.975568)
		(width 0.14224)
		(layer "In4.Cu")
		(net "M_B_MA<2>")
	)
	(segment
		(start 255.379728 -22.573996)
		(end 255.379728 -23.107396)
		(width 0.14224)
		(layer "In4.Cu")
		(net "M_B_MA<2>")
	)
	(segment
		(start 255.46685 -22.486874)
		(end 255.379728 -22.573996)
		(width 0.14224)
		(layer "In4.Cu")
		(net "M_B_MA<2>")
	)
	(segment
		(start 256.279396 -15.626334)
		(end 256.279396 -16.108934)
		(width 0.14224)
		(layer "In4.Cu")
		(net "M_B_MA<2>")
	)
	(segment
		(start 256.279396 -16.108934)
		(end 256.124456 -16.263874)
		(width 0.14224)
		(layer "In4.Cu")
		(net "M_B_MA<2>")
	)
	(segment
		(start 255.636014 -13.853414)
		(end 255.636014 -14.752066)
		(width 0.14224)
		(layer "In4.Cu")
		(net "M_B_MA<2>")
	)
	(segment
		(start 255.405128 -21.21662)
		(end 255.405128 -21.761196)
		(width 0.14224)
		(layer "In4.Cu")
		(net "M_B_MA<2>")
	)
	(segment
		(start 256.124456 -16.263874)
		(end 255.618234 -16.263874)
		(width 0.14224)
		(layer "In4.Cu")
		(net "M_B_MA<2>")
	)
	(segment
		(start 255.329944 -17.05737)
		(end 255.329944 -18.429986)
		(width 0.14224)
		(layer "In4.Cu")
		(net "M_B_MA<2>")
	)
	(segment
		(start 257.61569 -26.120598)
		(end 257.61569 -26.467816)
		(width 0.14224)
		(layer "In4.Cu")
		(net "M_B_MA<2>")
	)
	(segment
		(start 255.46685 -21.822918)
		(end 255.46685 -22.486874)
		(width 0.14224)
		(layer "In4.Cu")
		(net "M_B_MA<2>")
	)
	(segment
		(start 258.4958 -27.347926)
		(end 258.4958 -49.015396)
		(width 0.14224)
		(layer "In4.Cu")
		(net "M_B_MA<2>")
	)
	(segment
		(start 255.050036 -9.133078)
		(end 255.474978 -9.55802)
		(width 0.14224)
		(layer "In4.Cu")
		(net "M_B_MA<2>")
	)
	(segment
		(start 256.921 -50.8)
		(end 256.921 -51.696366)
		(width 0.0889)
		(layer "In4.Cu")
		(net "M_B_MA<2>")
	)
	(segment
		(start 258.4958 -49.015396)
		(end 258.4958 -49.2252)
		(width 0.0889)
		(layer "In4.Cu")
		(net "M_B_MA<2>")
	)
	(segment
		(start 255.47066 -23.975568)
		(end 257.61569 -26.120598)
		(width 0.14224)
		(layer "In4.Cu")
		(net "M_B_MA<2>")
	)
	(segment
		(start 255.636014 -14.752066)
		(end 255.417828 -14.970252)
		(width 0.14224)
		(layer "In4.Cu")
		(net "M_B_MA<2>")
	)
	(arc
		(start 256.674366 -53.111146)
		(mid 256.687635 -53.21619)
		(end 256.72796 -53.314092)
		(width 0.0889)
		(layer "In4.Cu")
		(net "M_B_MA<2>")
	)
	(segment
		(start 255.05029 -5.822442)
		(end 255.049782 -5.822442)
		(width 0.1651)
		(layer "F.Cu")
		(net "M_B_MA<1>")
	)
	(segment
		(start 255.049782 -5.822442)
		(end 255.049782 -7.117588)
		(width 0.1651)
		(layer "F.Cu")
		(net "M_B_MA<1>")
	)
	(segment
		(start 256.78765 -53.60924)
		(end 256.21615 -53.60924)
		(width 0.1016)
		(layer "F.Cu")
		(net "M_B_MA<1>")
	)
	(via
		(at 255.050036 -13.933678)
		(size 0.4572)
		(drill 0.2032)
		(layers "F.Cu" "B.Cu")
		(net "M_B_MA<1>")
	)
	(via
		(at 256.21615 -53.60924)
		(size 0.508)
		(drill 0.254)
		(layers "F.Cu" "B.Cu")
		(net "M_B_MA<1>")
	)
	(via
		(at 255.049782 -7.117588)
		(size 0.4572)
		(drill 0.2032)
		(layers "F.Cu" "B.Cu")
		(net "M_B_MA<1>")
	)
	(segment
		(start 255.049782 -13.959332)
		(end 255.050036 -13.959078)
		(width 0.1651)
		(layer "B.Cu")
		(net "M_B_MA<1>")
	)
	(segment
		(start 255.05029 -15.222982)
		(end 255.049782 -15.222982)
		(width 0.1651)
		(layer "B.Cu")
		(net "M_B_MA<1>")
	)
	(segment
		(start 255.049782 -15.222982)
		(end 255.049782 -13.959332)
		(width 0.1651)
		(layer "B.Cu")
		(net "M_B_MA<1>")
	)
	(segment
		(start 255.050036 -13.959078)
		(end 255.050036 -13.933678)
		(width 0.1651)
		(layer "B.Cu")
		(net "M_B_MA<1>")
	)
	(segment
		(start 256.21615 -53.60924)
		(end 256.413 -53.101748)
		(width 0.0889)
		(layer "In4.Cu")
		(net "M_B_MA<1>")
	)
	(segment
		(start 254.635 -14.8336)
		(end 255.050036 -14.418564)
		(width 0.14224)
		(layer "In4.Cu")
		(net "M_B_MA<1>")
	)
	(segment
		(start 256.789936 -27.478736)
		(end 256.789936 -27.191208)
		(width 0.14224)
		(layer "In4.Cu")
		(net "M_B_MA<1>")
	)
	(segment
		(start 256.663444 -51.565556)
		(end 256.663444 -50.549556)
		(width 0.0889)
		(layer "In4.Cu")
		(net "M_B_MA<1>")
	)
	(segment
		(start 254.635 -12.196572)
		(end 254.635 -8.762746)
		(width 0.14224)
		(layer "In4.Cu")
		(net "M_B_MA<1>")
	)
	(segment
		(start 257.9878 -49.2252)
		(end 257.9878 -48.941482)
		(width 0.0889)
		(layer "In4.Cu")
		(net "M_B_MA<1>")
	)
	(segment
		(start 255.911858 -25.770078)
		(end 255.911858 -25.48255)
		(width 0.14224)
		(layer "In4.Cu")
		(net "M_B_MA<1>")
	)
	(segment
		(start 254.635 -17.015714)
		(end 254.635 -14.8336)
		(width 0.14224)
		(layer "In4.Cu")
		(net "M_B_MA<1>")
	)
	(segment
		(start 255.050036 -13.933678)
		(end 254.635 -13.518642)
		(width 0.14224)
		(layer "In4.Cu")
		(net "M_B_MA<1>")
	)
	(segment
		(start 257.061462 -26.632154)
		(end 256.774188 -26.34488)
		(width 0.14224)
		(layer "In4.Cu")
		(net "M_B_MA<1>")
	)
	(segment
		(start 254.5842 -13.1064)
		(end 254.5842 -12.247372)
		(width 0.14224)
		(layer "In4.Cu")
		(net "M_B_MA<1>")
	)
	(segment
		(start 254.638302 -17.71396)
		(end 254.541528 -17.617186)
		(width 0.14224)
		(layer "In4.Cu")
		(net "M_B_MA<1>")
	)
	(segment
		(start 254.541528 -17.109186)
		(end 254.635 -17.015714)
		(width 0.14224)
		(layer "In4.Cu")
		(net "M_B_MA<1>")
	)
	(segment
		(start 255.927606 -26.616406)
		(end 255.640332 -26.329132)
		(width 0.14224)
		(layer "In4.Cu")
		(net "M_B_MA<1>")
	)
	(segment
		(start 255.050036 -14.418564)
		(end 255.050036 -13.933678)
		(width 0.14224)
		(layer "In4.Cu")
		(net "M_B_MA<1>")
	)
	(segment
		(start 255.050036 -7.117842)
		(end 255.049782 -7.117588)
		(width 0.14224)
		(layer "In4.Cu")
		(net "M_B_MA<1>")
	)
	(segment
		(start 254.744728 -22.599396)
		(end 254.381 -22.235668)
		(width 0.14224)
		(layer "In4.Cu")
		(net "M_B_MA<1>")
	)
	(segment
		(start 255.640332 -26.329132)
		(end 255.640332 -26.041604)
		(width 0.14224)
		(layer "In4.Cu")
		(net "M_B_MA<1>")
	)
	(segment
		(start 257.9878 -27.939492)
		(end 257.814318 -27.76601)
		(width 0.14224)
		(layer "In4.Cu")
		(net "M_B_MA<1>")
	)
	(segment
		(start 256.774188 -26.34488)
		(end 256.48666 -26.34488)
		(width 0.14224)
		(layer "In4.Cu")
		(net "M_B_MA<1>")
	)
	(segment
		(start 256.215134 -26.616406)
		(end 255.927606 -26.616406)
		(width 0.14224)
		(layer "In4.Cu")
		(net "M_B_MA<1>")
	)
	(segment
		(start 256.789936 -27.191208)
		(end 257.061462 -26.919682)
		(width 0.14224)
		(layer "In4.Cu")
		(net "M_B_MA<1>")
	)
	(segment
		(start 254.744728 -23.132796)
		(end 254.744728 -22.599396)
		(width 0.14224)
		(layer "In4.Cu")
		(net "M_B_MA<1>")
	)
	(segment
		(start 257.9878 -48.941482)
		(end 257.9878 -27.939492)
		(width 0.14224)
		(layer "In4.Cu")
		(net "M_B_MA<1>")
	)
	(segment
		(start 254.693928 -21.267928)
		(end 254.638302 -21.212302)
		(width 0.14224)
		(layer "In4.Cu")
		(net "M_B_MA<1>")
	)
	(segment
		(start 255.640332 -26.041604)
		(end 255.911858 -25.770078)
		(width 0.14224)
		(layer "In4.Cu")
		(net "M_B_MA<1>")
	)
	(segment
		(start 256.663444 -50.549556)
		(end 257.9878 -49.2252)
		(width 0.0889)
		(layer "In4.Cu")
		(net "M_B_MA<1>")
	)
	(segment
		(start 254.559054 -23.31847)
		(end 254.744728 -23.132796)
		(width 0.14224)
		(layer "In4.Cu")
		(net "M_B_MA<1>")
	)
	(segment
		(start 257.061462 -26.919682)
		(end 257.061462 -26.632154)
		(width 0.14224)
		(layer "In4.Cu")
		(net "M_B_MA<1>")
	)
	(segment
		(start 255.911858 -25.48255)
		(end 255.624584 -25.195276)
		(width 0.14224)
		(layer "In4.Cu")
		(net "M_B_MA<1>")
	)
	(segment
		(start 256.48666 -26.34488)
		(end 256.215134 -26.616406)
		(width 0.14224)
		(layer "In4.Cu")
		(net "M_B_MA<1>")
	)
	(segment
		(start 254.635 -13.518642)
		(end 254.635 -13.1572)
		(width 0.14224)
		(layer "In4.Cu")
		(net "M_B_MA<1>")
	)
	(segment
		(start 255.148334 -25.195276)
		(end 254.559054 -24.605996)
		(width 0.14224)
		(layer "In4.Cu")
		(net "M_B_MA<1>")
	)
	(segment
		(start 254.381 -22.235668)
		(end 254.381 -21.971)
		(width 0.14224)
		(layer "In4.Cu")
		(net "M_B_MA<1>")
	)
	(segment
		(start 254.635 -13.1572)
		(end 254.5842 -13.1064)
		(width 0.14224)
		(layer "In4.Cu")
		(net "M_B_MA<1>")
	)
	(segment
		(start 257.07721 -27.76601)
		(end 256.789936 -27.478736)
		(width 0.14224)
		(layer "In4.Cu")
		(net "M_B_MA<1>")
	)
	(segment
		(start 254.693928 -21.658072)
		(end 254.693928 -21.267928)
		(width 0.14224)
		(layer "In4.Cu")
		(net "M_B_MA<1>")
	)
	(segment
		(start 257.814318 -27.76601)
		(end 257.07721 -27.76601)
		(width 0.14224)
		(layer "In4.Cu")
		(net "M_B_MA<1>")
	)
	(segment
		(start 255.624584 -25.195276)
		(end 255.148334 -25.195276)
		(width 0.14224)
		(layer "In4.Cu")
		(net "M_B_MA<1>")
	)
	(segment
		(start 254.638302 -21.212302)
		(end 254.638302 -17.71396)
		(width 0.14224)
		(layer "In4.Cu")
		(net "M_B_MA<1>")
	)
	(segment
		(start 254.5842 -12.247372)
		(end 254.635 -12.196572)
		(width 0.14224)
		(layer "In4.Cu")
		(net "M_B_MA<1>")
	)
	(segment
		(start 255.050036 -8.34771)
		(end 255.050036 -7.117842)
		(width 0.14224)
		(layer "In4.Cu")
		(net "M_B_MA<1>")
	)
	(segment
		(start 254.541528 -17.617186)
		(end 254.541528 -17.109186)
		(width 0.14224)
		(layer "In4.Cu")
		(net "M_B_MA<1>")
	)
	(segment
		(start 254.635 -8.762746)
		(end 255.050036 -8.34771)
		(width 0.14224)
		(layer "In4.Cu")
		(net "M_B_MA<1>")
	)
	(segment
		(start 256.413 -51.816)
		(end 256.663444 -51.565556)
		(width 0.0889)
		(layer "In4.Cu")
		(net "M_B_MA<1>")
	)
	(segment
		(start 254.381 -21.971)
		(end 254.693928 -21.658072)
		(width 0.14224)
		(layer "In4.Cu")
		(net "M_B_MA<1>")
	)
	(segment
		(start 256.413 -53.101748)
		(end 256.413 -51.816)
		(width 0.0889)
		(layer "In4.Cu")
		(net "M_B_MA<1>")
	)
	(segment
		(start 254.559054 -24.605996)
		(end 254.559054 -23.31847)
		(width 0.14224)
		(layer "In4.Cu")
		(net "M_B_MA<1>")
	)
	(segment
		(start 275.4503 -10.422382)
		(end 275.449792 -10.422382)
		(width 0.1651)
		(layer "F.Cu")
		(net "M_B_MA<17>")
	)
	(segment
		(start 265.372596 -55.59044)
		(end 264.801096 -55.59044)
		(width 0.1016)
		(layer "F.Cu")
		(net "M_B_MA<17>")
	)
	(segment
		(start 275.449792 -9.133586)
		(end 275.4503 -9.133078)
		(width 0.1651)
		(layer "F.Cu")
		(net "M_B_MA<17>")
	)
	(segment
		(start 275.449792 -10.422382)
		(end 275.449792 -9.133586)
		(width 0.1651)
		(layer "F.Cu")
		(net "M_B_MA<17>")
	)
	(via
		(at 264.801096 -55.59044)
		(size 0.508)
		(drill 0.254)
		(layers "F.Cu" "B.Cu")
		(net "M_B_MA<17>")
	)
	(via
		(at 275.4503 -9.133078)
		(size 0.4572)
		(drill 0.2032)
		(layers "F.Cu" "B.Cu")
		(net "M_B_MA<17>")
	)
	(via
		(at 275.4503 -11.918188)
		(size 0.4572)
		(drill 0.2032)
		(layers "F.Cu" "B.Cu")
		(net "M_B_MA<17>")
	)
	(segment
		(start 275.449792 -10.623042)
		(end 275.449792 -11.91768)
		(width 0.1651)
		(layer "B.Cu")
		(net "M_B_MA<17>")
	)
	(segment
		(start 275.4503 -10.623042)
		(end 275.449792 -10.623042)
		(width 0.1651)
		(layer "B.Cu")
		(net "M_B_MA<17>")
	)
	(segment
		(start 275.449792 -11.91768)
		(end 275.4503 -11.918188)
		(width 0.1651)
		(layer "B.Cu")
		(net "M_B_MA<17>")
	)
	(segment
		(start 265.147806 -54.799992)
		(end 265.131296 -54.82844)
		(width 0.0889)
		(layer "In11.Cu")
		(net "M_B_MA<17>")
	)
	(segment
		(start 265.131296 -54.82844)
		(end 264.801096 -55.59044)
		(width 0.0889)
		(layer "In11.Cu")
		(net "M_B_MA<17>")
	)
	(segment
		(start 274.1422 -21.2598)
		(end 274.1422 -21.7932)
		(width 0.14224)
		(layer "In11.Cu")
		(net "M_B_MA<17>")
	)
	(segment
		(start 266.396724 -49.435766)
		(end 265.8872 -51.424078)
		(width 0.0889)
		(layer "In11.Cu")
		(net "M_B_MA<17>")
	)
	(segment
		(start 274.161758 -16.221456)
		(end 274.161758 -19.17065)
		(width 0.14224)
		(layer "In11.Cu")
		(net "M_B_MA<17>")
	)
	(segment
		(start 275.086826 -11.554714)
		(end 275.086826 -9.496552)
		(width 0.14224)
		(layer "In11.Cu")
		(net "M_B_MA<17>")
	)
	(segment
		(start 274.1422 -27.733752)
		(end 266.828524 -35.047428)
		(width 0.14224)
		(layer "In11.Cu")
		(net "M_B_MA<17>")
	)
	(segment
		(start 274.2311 -23.749)
		(end 274.1422 -23.8379)
		(width 0.14224)
		(layer "In11.Cu")
		(net "M_B_MA<17>")
	)
	(segment
		(start 275.4503 -11.918188)
		(end 274.638516 -12.729972)
		(width 0.14224)
		(layer "In11.Cu")
		(net "M_B_MA<17>")
	)
	(segment
		(start 265.068812 -52.77612)
		(end 265.068812 -53.13172)
		(width 0.0889)
		(layer "In11.Cu")
		(net "M_B_MA<17>")
	)
	(segment
		(start 274.137882 -23.185882)
		(end 274.2311 -23.2791)
		(width 0.14224)
		(layer "In11.Cu")
		(net "M_B_MA<17>")
	)
	(segment
		(start 274.2692 -22.5298)
		(end 274.137882 -22.661118)
		(width 0.14224)
		(layer "In11.Cu")
		(net "M_B_MA<17>")
	)
	(segment
		(start 274.2438 -19.252692)
		(end 274.2438 -21.1582)
		(width 0.14224)
		(layer "In11.Cu")
		(net "M_B_MA<17>")
	)
	(segment
		(start 274.161758 -19.17065)
		(end 274.2438 -19.252692)
		(width 0.14224)
		(layer "In11.Cu")
		(net "M_B_MA<17>")
	)
	(segment
		(start 274.638516 -12.729972)
		(end 274.638516 -13.21181)
		(width 0.14224)
		(layer "In11.Cu")
		(net "M_B_MA<17>")
	)
	(segment
		(start 274.1422 -21.7932)
		(end 274.2692 -21.9202)
		(width 0.14224)
		(layer "In11.Cu")
		(net "M_B_MA<17>")
	)
	(segment
		(start 275.009356 -15.373858)
		(end 274.161758 -16.221456)
		(width 0.14224)
		(layer "In11.Cu")
		(net "M_B_MA<17>")
	)
	(segment
		(start 274.2692 -21.9202)
		(end 274.2692 -22.5298)
		(width 0.14224)
		(layer "In11.Cu")
		(net "M_B_MA<17>")
	)
	(segment
		(start 274.137882 -22.661118)
		(end 274.137882 -23.185882)
		(width 0.14224)
		(layer "In11.Cu")
		(net "M_B_MA<17>")
	)
	(segment
		(start 266.828524 -35.047428)
		(end 266.828524 -48.690276)
		(width 0.14224)
		(layer "In11.Cu")
		(net "M_B_MA<17>")
	)
	(segment
		(start 274.2311 -23.2791)
		(end 274.2311 -23.749)
		(width 0.14224)
		(layer "In11.Cu")
		(net "M_B_MA<17>")
	)
	(segment
		(start 275.4503 -11.918188)
		(end 275.086826 -11.554714)
		(width 0.14224)
		(layer "In11.Cu")
		(net "M_B_MA<17>")
	)
	(segment
		(start 274.1422 -23.8379)
		(end 274.1422 -27.733752)
		(width 0.14224)
		(layer "In11.Cu")
		(net "M_B_MA<17>")
	)
	(segment
		(start 274.638516 -13.21181)
		(end 275.009356 -13.58265)
		(width 0.14224)
		(layer "In11.Cu")
		(net "M_B_MA<17>")
	)
	(segment
		(start 266.828524 -48.690276)
		(end 266.828524 -49.003966)
		(width 0.0889)
		(layer "In11.Cu")
		(net "M_B_MA<17>")
	)
	(segment
		(start 274.2438 -21.1582)
		(end 274.1422 -21.2598)
		(width 0.14224)
		(layer "In11.Cu")
		(net "M_B_MA<17>")
	)
	(segment
		(start 266.828524 -49.003966)
		(end 266.396724 -49.435766)
		(width 0.0889)
		(layer "In11.Cu")
		(net "M_B_MA<17>")
	)
	(segment
		(start 275.086826 -9.496552)
		(end 275.4503 -9.133078)
		(width 0.14224)
		(layer "In11.Cu")
		(net "M_B_MA<17>")
	)
	(segment
		(start 275.009356 -13.58265)
		(end 275.009356 -15.373858)
		(width 0.14224)
		(layer "In11.Cu")
		(net "M_B_MA<17>")
	)
	(segment
		(start 265.8872 -51.424078)
		(end 265.068812 -52.77612)
		(width 0.0889)
		(layer "In11.Cu")
		(net "M_B_MA<17>")
	)
	(arc
		(start 265.147806 -53.809392)
		(mid 265.068675 -54.104794)
		(end 265.147806 -54.400196)
		(width 0.0889)
		(layer "In11.Cu")
		(net "M_B_MA<17>")
	)
	(arc
		(start 265.147806 -54.400196)
		(mid 265.201305 -54.600094)
		(end 265.147806 -54.799992)
		(width 0.0889)
		(layer "In11.Cu")
		(net "M_B_MA<17>")
	)
	(arc
		(start 265.068812 -53.13172)
		(mid 265.09107 -53.275559)
		(end 265.147806 -53.409596)
		(width 0.0889)
		(layer "In11.Cu")
		(net "M_B_MA<17>")
	)
	(arc
		(start 265.147806 -53.409596)
		(mid 265.201305 -53.609494)
		(end 265.147806 -53.809392)
		(width 0.0889)
		(layer "In11.Cu")
		(net "M_B_MA<17>")
	)
	(segment
		(start 261.93877 -56.58104)
		(end 261.36727 -56.58104)
		(width 0.1016)
		(layer "F.Cu")
		(net "M_B_MA<16>")
	)
	(segment
		(start 268.649958 -5.822442)
		(end 268.649958 -7.113778)
		(width 0.1651)
		(layer "F.Cu")
		(net "M_B_MA<16>")
	)
	(segment
		(start 268.650466 -5.822442)
		(end 268.649958 -5.822442)
		(width 0.1651)
		(layer "F.Cu")
		(net "M_B_MA<16>")
	)
	(via
		(at 268.649958 -13.929868)
		(size 0.4572)
		(drill 0.2032)
		(layers "F.Cu" "B.Cu")
		(net "M_B_MA<16>")
	)
	(via
		(at 268.649958 -7.113778)
		(size 0.508)
		(drill 0.254)
		(layers "F.Cu" "B.Cu")
		(net "M_B_MA<16>")
	)
	(via
		(at 261.36727 -56.58104)
		(size 0.508)
		(drill 0.254)
		(layers "F.Cu" "B.Cu")
		(net "M_B_MA<16>")
	)
	(segment
		(start 268.649958 -15.222982)
		(end 268.649958 -13.929868)
		(width 0.1651)
		(layer "B.Cu")
		(net "M_B_MA<16>")
	)
	(segment
		(start 268.650466 -15.222982)
		(end 268.649958 -15.222982)
		(width 0.1651)
		(layer "B.Cu")
		(net "M_B_MA<16>")
	)
	(segment
		(start 267.110972 -17.400778)
		(end 267.372592 -17.139158)
		(width 0.14224)
		(layer "In4.Cu")
		(net "M_B_MA<16>")
	)
	(segment
		(start 261.02056 -54.799738)
		(end 261.015734 -54.791102)
		(width 0.0889)
		(layer "In4.Cu")
		(net "M_B_MA<16>")
	)
	(segment
		(start 265.803888 -26.591768)
		(end 265.575034 -26.362914)
		(width 0.14224)
		(layer "In4.Cu")
		(net "M_B_MA<16>")
	)
	(segment
		(start 268.649958 -13.929868)
		(end 268.213332 -13.493242)
		(width 0.14224)
		(layer "In4.Cu")
		(net "M_B_MA<16>")
	)
	(segment
		(start 263.674352 -28.044648)
		(end 263.8933 -28.044648)
		(width 0.14224)
		(layer "In4.Cu")
		(net "M_B_MA<16>")
	)
	(segment
		(start 263.8933 -28.044648)
		(end 264.34288 -28.494228)
		(width 0.14224)
		(layer "In4.Cu")
		(net "M_B_MA<16>")
	)
	(segment
		(start 264.897362 -28.119832)
		(end 264.897362 -27.927554)
		(width 0.14224)
		(layer "In4.Cu")
		(net "M_B_MA<16>")
	)
	(segment
		(start 267.3858 -21.0566)
		(end 267.3858 -20.414996)
		(width 0.14224)
		(layer "In4.Cu")
		(net "M_B_MA<16>")
	)
	(segment
		(start 262.4074 -52.197)
		(end 263.424416 -51.179984)
		(width 0.0889)
		(layer "In4.Cu")
		(net "M_B_MA<16>")
	)
	(segment
		(start 267.2842 -22.509734)
		(end 267.406882 -22.387052)
		(width 0.14224)
		(layer "In4.Cu")
		(net "M_B_MA<16>")
	)
	(segment
		(start 261.02056 -55.790338)
		(end 261.015734 -55.781702)
		(width 0.0889)
		(layer "In4.Cu")
		(net "M_B_MA<16>")
	)
	(segment
		(start 269.153386 -7.617206)
		(end 268.649958 -7.113778)
		(width 0.14224)
		(layer "In4.Cu")
		(net "M_B_MA<16>")
	)
	(segment
		(start 268.213332 -10.197846)
		(end 269.086838 -9.32434)
		(width 0.14224)
		(layer "In4.Cu")
		(net "M_B_MA<16>")
	)
	(segment
		(start 263.424416 -51.179984)
		(end 263.424416 -50.798984)
		(width 0.0889)
		(layer "In4.Cu")
		(net "M_B_MA<16>")
	)
	(segment
		(start 267.2842 -21.1582)
		(end 267.3858 -21.0566)
		(width 0.14224)
		(layer "In4.Cu")
		(net "M_B_MA<16>")
	)
	(segment
		(start 265.803888 -26.7716)
		(end 265.803888 -26.591768)
		(width 0.14224)
		(layer "In4.Cu")
		(net "M_B_MA<16>")
	)
	(segment
		(start 261.02691 -55.801006)
		(end 261.02056 -55.790338)
		(width 0.0889)
		(layer "In4.Cu")
		(net "M_B_MA<16>")
	)
	(segment
		(start 267.372592 -17.139158)
		(end 267.372592 -14.974062)
		(width 0.14224)
		(layer "In4.Cu")
		(net "M_B_MA<16>")
	)
	(segment
		(start 267.3858 -20.414996)
		(end 267.09878 -20.127976)
		(width 0.14224)
		(layer "In4.Cu")
		(net "M_B_MA<16>")
	)
	(segment
		(start 267.110972 -18.274284)
		(end 267.110972 -17.400778)
		(width 0.14224)
		(layer "In4.Cu")
		(net "M_B_MA<16>")
	)
	(segment
		(start 267.386054 -18.549366)
		(end 267.110972 -18.274284)
		(width 0.14224)
		(layer "In4.Cu")
		(net "M_B_MA<16>")
	)
	(segment
		(start 264.795508 -26.923492)
		(end 265.014456 -26.923492)
		(width 0.14224)
		(layer "In4.Cu")
		(net "M_B_MA<16>")
	)
	(segment
		(start 267.2842 -21.885402)
		(end 267.2842 -21.1582)
		(width 0.14224)
		(layer "In4.Cu")
		(net "M_B_MA<16>")
	)
	(segment
		(start 264.897362 -27.927554)
		(end 264.453878 -27.48407)
		(width 0.14224)
		(layer "In4.Cu")
		(net "M_B_MA<16>")
	)
	(segment
		(start 266.869672 -24.257)
		(end 267.159994 -24.257)
		(width 0.14224)
		(layer "In4.Cu")
		(net "M_B_MA<16>")
	)
	(segment
		(start 265.575034 -26.362914)
		(end 265.575034 -26.143966)
		(width 0.14224)
		(layer "In4.Cu")
		(net "M_B_MA<16>")
	)
	(segment
		(start 264.453878 -27.48407)
		(end 264.453878 -27.265122)
		(width 0.14224)
		(layer "In4.Cu")
		(net "M_B_MA<16>")
	)
	(segment
		(start 268.387576 -13.959078)
		(end 268.620748 -13.959078)
		(width 0.14224)
		(layer "In4.Cu")
		(net "M_B_MA<16>")
	)
	(segment
		(start 267.406882 -22.008084)
		(end 267.2842 -21.885402)
		(width 0.14224)
		(layer "In4.Cu")
		(net "M_B_MA<16>")
	)
	(segment
		(start 263.424416 -50.798984)
		(end 263.424416 -28.294584)
		(width 0.14224)
		(layer "In4.Cu")
		(net "M_B_MA<16>")
	)
	(segment
		(start 269.153386 -8.819896)
		(end 269.153386 -7.617206)
		(width 0.14224)
		(layer "In4.Cu")
		(net "M_B_MA<16>")
	)
	(segment
		(start 267.3858 -18.550128)
		(end 267.386054 -18.549366)
		(width 0.14224)
		(layer "In4.Cu")
		(net "M_B_MA<16>")
	)
	(segment
		(start 261.02691 -54.810406)
		(end 261.02056 -54.799738)
		(width 0.0889)
		(layer "In4.Cu")
		(net "M_B_MA<16>")
	)
	(segment
		(start 266.568682 -24.55799)
		(end 266.869672 -24.257)
		(width 0.14224)
		(layer "In4.Cu")
		(net "M_B_MA<16>")
	)
	(segment
		(start 265.575034 -26.143966)
		(end 266.568682 -25.150318)
		(width 0.14224)
		(layer "In4.Cu")
		(net "M_B_MA<16>")
	)
	(segment
		(start 267.372592 -14.974062)
		(end 268.387576 -13.959078)
		(width 0.14224)
		(layer "In4.Cu")
		(net "M_B_MA<16>")
	)
	(segment
		(start 264.453878 -27.265122)
		(end 264.795508 -26.923492)
		(width 0.14224)
		(layer "In4.Cu")
		(net "M_B_MA<16>")
	)
	(segment
		(start 265.24331 -27.152346)
		(end 265.423142 -27.152346)
		(width 0.14224)
		(layer "In4.Cu")
		(net "M_B_MA<16>")
	)
	(segment
		(start 263.424416 -28.294584)
		(end 263.674352 -28.044648)
		(width 0.14224)
		(layer "In4.Cu")
		(net "M_B_MA<16>")
	)
	(segment
		(start 266.568682 -25.150318)
		(end 266.568682 -24.55799)
		(width 0.14224)
		(layer "In4.Cu")
		(net "M_B_MA<16>")
	)
	(segment
		(start 265.423142 -27.152346)
		(end 265.803888 -26.7716)
		(width 0.14224)
		(layer "In4.Cu")
		(net "M_B_MA<16>")
	)
	(segment
		(start 264.34288 -28.494228)
		(end 264.522966 -28.494228)
		(width 0.14224)
		(layer "In4.Cu")
		(net "M_B_MA<16>")
	)
	(segment
		(start 269.086838 -8.886444)
		(end 269.153386 -8.819896)
		(width 0.14224)
		(layer "In4.Cu")
		(net "M_B_MA<16>")
	)
	(segment
		(start 261.1374 -56.35117)
		(end 261.1374 -56.23179)
		(width 0.0889)
		(layer "In4.Cu")
		(net "M_B_MA<16>")
	)
	(segment
		(start 261.506462 -53.556662)
		(end 261.735316 -53.1622)
		(width 0.0889)
		(layer "In4.Cu")
		(net "M_B_MA<16>")
	)
	(segment
		(start 267.09878 -20.127976)
		(end 267.09878 -19.431508)
		(width 0.14224)
		(layer "In4.Cu")
		(net "M_B_MA<16>")
	)
	(segment
		(start 268.620748 -13.959078)
		(end 268.649958 -13.929868)
		(width 0.14224)
		(layer "In4.Cu")
		(net "M_B_MA<16>")
	)
	(segment
		(start 269.086838 -9.32434)
		(end 269.086838 -8.886444)
		(width 0.14224)
		(layer "In4.Cu")
		(net "M_B_MA<16>")
	)
	(segment
		(start 261.851394 -52.961794)
		(end 261.94639 -52.797456)
		(width 0.0889)
		(layer "In4.Cu")
		(net "M_B_MA<16>")
	)
	(segment
		(start 264.522966 -28.494228)
		(end 264.897362 -28.119832)
		(width 0.14224)
		(layer "In4.Cu")
		(net "M_B_MA<16>")
	)
	(segment
		(start 268.213332 -13.493242)
		(end 268.213332 -10.197846)
		(width 0.14224)
		(layer "In4.Cu")
		(net "M_B_MA<16>")
	)
	(segment
		(start 267.504926 -23.468838)
		(end 267.2842 -23.248112)
		(width 0.14224)
		(layer "In4.Cu")
		(net "M_B_MA<16>")
	)
	(segment
		(start 267.159994 -24.257)
		(end 267.504926 -23.912068)
		(width 0.14224)
		(layer "In4.Cu")
		(net "M_B_MA<16>")
	)
	(segment
		(start 267.406882 -22.387052)
		(end 267.406882 -22.008084)
		(width 0.14224)
		(layer "In4.Cu")
		(net "M_B_MA<16>")
	)
	(segment
		(start 267.504926 -23.912068)
		(end 267.504926 -23.468838)
		(width 0.14224)
		(layer "In4.Cu")
		(net "M_B_MA<16>")
	)
	(segment
		(start 267.3858 -19.144488)
		(end 267.3858 -18.550128)
		(width 0.14224)
		(layer "In4.Cu")
		(net "M_B_MA<16>")
	)
	(segment
		(start 261.36727 -56.58104)
		(end 261.1374 -56.35117)
		(width 0.0889)
		(layer "In4.Cu")
		(net "M_B_MA<16>")
	)
	(segment
		(start 261.02056 -54.399688)
		(end 261.506462 -53.556662)
		(width 0.0889)
		(layer "In4.Cu")
		(net "M_B_MA<16>")
	)
	(segment
		(start 265.014456 -26.923492)
		(end 265.24331 -27.152346)
		(width 0.14224)
		(layer "In4.Cu")
		(net "M_B_MA<16>")
	)
	(segment
		(start 267.09878 -19.431508)
		(end 267.3858 -19.144488)
		(width 0.14224)
		(layer "In4.Cu")
		(net "M_B_MA<16>")
	)
	(segment
		(start 261.735316 -53.1622)
		(end 261.851394 -52.961794)
		(width 0.0889)
		(layer "In4.Cu")
		(net "M_B_MA<16>")
	)
	(segment
		(start 267.2842 -23.248112)
		(end 267.2842 -22.509734)
		(width 0.14224)
		(layer "In4.Cu")
		(net "M_B_MA<16>")
	)
	(arc
		(start 261.94639 -52.797456)
		(mid 262.157267 -52.482158)
		(end 262.4074 -52.197)
		(width 0.0889)
		(layer "In4.Cu")
		(net "M_B_MA<16>")
	)
	(arc
		(start 261.1374 -56.23179)
		(mid 261.10934 -56.009425)
		(end 261.02691 -55.801006)
		(width 0.0889)
		(layer "In4.Cu")
		(net "M_B_MA<16>")
	)
	(arc
		(start 261.015734 -54.791102)
		(mid 260.966979 -54.59475)
		(end 261.02056 -54.399688)
		(width 0.0889)
		(layer "In4.Cu")
		(net "M_B_MA<16>")
	)
	(arc
		(start 261.015734 -55.781702)
		(mid 260.966979 -55.58535)
		(end 261.02056 -55.390288)
		(width 0.0889)
		(layer "In4.Cu")
		(net "M_B_MA<16>")
	)
	(arc
		(start 261.02056 -55.390288)
		(mid 261.099782 -55.10117)
		(end 261.02691 -54.810406)
		(width 0.0889)
		(layer "In4.Cu")
		(net "M_B_MA<16>")
	)
	(segment
		(start 272.050002 -5.822442)
		(end 272.050002 -7.117334)
		(width 0.1651)
		(layer "F.Cu")
		(net "M_B_MA<15>")
	)
	(segment
		(start 272.05051 -5.822442)
		(end 272.050002 -5.822442)
		(width 0.1651)
		(layer "F.Cu")
		(net "M_B_MA<15>")
	)
	(segment
		(start 261.93877 -55.59044)
		(end 261.36727 -55.59044)
		(width 0.1016)
		(layer "F.Cu")
		(net "M_B_MA<15>")
	)
	(segment
		(start 272.050002 -7.117334)
		(end 272.050256 -7.117588)
		(width 0.1651)
		(layer "F.Cu")
		(net "M_B_MA<15>")
	)
	(via
		(at 272.050256 -7.117588)
		(size 0.4572)
		(drill 0.2032)
		(layers "F.Cu" "B.Cu")
		(net "M_B_MA<15>")
	)
	(via
		(at 261.36727 -55.59044)
		(size 0.508)
		(drill 0.254)
		(layers "F.Cu" "B.Cu")
		(net "M_B_MA<15>")
	)
	(via
		(at 272.050256 -13.933678)
		(size 0.4572)
		(drill 0.2032)
		(layers "F.Cu" "B.Cu")
		(net "M_B_MA<15>")
	)
	(segment
		(start 272.050002 -13.933932)
		(end 272.050256 -13.933678)
		(width 0.10795)
		(layer "B.Cu")
		(net "M_B_MA<15>")
	)
	(segment
		(start 272.050002 -15.222982)
		(end 272.050002 -13.933932)
		(width 0.10795)
		(layer "B.Cu")
		(net "M_B_MA<15>")
	)
	(segment
		(start 272.05051 -15.222982)
		(end 272.050002 -15.222982)
		(width 0.10795)
		(layer "B.Cu")
		(net "M_B_MA<15>")
	)
	(segment
		(start 263.1948 -50.8762)
		(end 263.1948 -51.942492)
		(width 0.0889)
		(layer "In11.Cu")
		(net "M_B_MA<15>")
	)
	(segment
		(start 267.15085 -29.751528)
		(end 267.321284 -29.921962)
		(width 0.14224)
		(layer "In11.Cu")
		(net "M_B_MA<15>")
	)
	(segment
		(start 264.854182 -32.053276)
		(end 265.022076 -32.22117)
		(width 0.14224)
		(layer "In11.Cu")
		(net "M_B_MA<15>")
	)
	(segment
		(start 270.0274 -18.288)
		(end 269.916656 -18.398744)
		(width 0.14224)
		(layer "In11.Cu")
		(net "M_B_MA<15>")
	)
	(segment
		(start 270.8656 -23.4188)
		(end 270.8656 -27.111706)
		(width 0.14224)
		(layer "In11.Cu")
		(net "M_B_MA<15>")
	)
	(segment
		(start 266.270994 -30.313884)
		(end 265.98372 -30.601158)
		(width 0.14224)
		(layer "In11.Cu")
		(net "M_B_MA<15>")
	)
	(segment
		(start 264.174224 -49.896776)
		(end 263.1948 -50.8762)
		(width 0.0889)
		(layer "In11.Cu")
		(net "M_B_MA<15>")
	)
	(segment
		(start 271.636236 -12.495022)
		(end 271.636236 -8.627364)
		(width 0.14224)
		(layer "In11.Cu")
		(net "M_B_MA<15>")
	)
	(segment
		(start 270.0274 -17.787874)
		(end 270.0274 -18.288)
		(width 0.14224)
		(layer "In11.Cu")
		(net "M_B_MA<15>")
	)
	(segment
		(start 265.449558 -31.499048)
		(end 265.141456 -31.499048)
		(width 0.14224)
		(layer "In11.Cu")
		(net "M_B_MA<15>")
	)
	(segment
		(start 263.1948 -51.942492)
		(end 262.6614 -52.475892)
		(width 0.0889)
		(layer "In11.Cu")
		(net "M_B_MA<15>")
	)
	(segment
		(start 271.529302 -7.638542)
		(end 272.050256 -7.117588)
		(width 0.14224)
		(layer "In11.Cu")
		(net "M_B_MA<15>")
	)
	(segment
		(start 262.382 -54.5338)
		(end 262.188198 -54.5338)
		(width 0.0889)
		(layer "In11.Cu")
		(net "M_B_MA<15>")
	)
	(segment
		(start 266.563602 -30.313884)
		(end 266.270994 -30.313884)
		(width 0.14224)
		(layer "In11.Cu")
		(net "M_B_MA<15>")
	)
	(segment
		(start 268.77645 -29.200856)
		(end 267.40231 -29.200856)
		(width 0.14224)
		(layer "In11.Cu")
		(net "M_B_MA<15>")
	)
	(segment
		(start 270.8402 -22.4536)
		(end 270.7386 -22.5552)
		(width 0.14224)
		(layer "In11.Cu")
		(net "M_B_MA<15>")
	)
	(segment
		(start 270.759428 -16.317722)
		(end 270.759428 -17.055846)
		(width 0.14224)
		(layer "In11.Cu")
		(net "M_B_MA<15>")
	)
	(segment
		(start 265.98372 -30.601158)
		(end 265.98372 -30.883606)
		(width 0.14224)
		(layer "In11.Cu")
		(net "M_B_MA<15>")
	)
	(segment
		(start 265.884406 -31.646368)
		(end 265.596878 -31.646368)
		(width 0.14224)
		(layer "In11.Cu")
		(net "M_B_MA<15>")
	)
	(segment
		(start 270.8656 -27.111706)
		(end 268.77645 -29.200856)
		(width 0.14224)
		(layer "In11.Cu")
		(net "M_B_MA<15>")
	)
	(segment
		(start 272.050256 -13.933678)
		(end 272.050256 -15.026894)
		(width 0.14224)
		(layer "In11.Cu")
		(net "M_B_MA<15>")
	)
	(segment
		(start 267.15085 -29.452316)
		(end 267.15085 -29.751528)
		(width 0.14224)
		(layer "In11.Cu")
		(net "M_B_MA<15>")
	)
	(segment
		(start 262.6614 -54.2544)
		(end 262.382 -54.5338)
		(width 0.0889)
		(layer "In11.Cu")
		(net "M_B_MA<15>")
	)
	(segment
		(start 266.17168 -31.071566)
		(end 266.17168 -31.359094)
		(width 0.14224)
		(layer "In11.Cu")
		(net "M_B_MA<15>")
	)
	(segment
		(start 271.636236 -8.627364)
		(end 271.529302 -8.52043)
		(width 0.14224)
		(layer "In11.Cu")
		(net "M_B_MA<15>")
	)
	(segment
		(start 270.8402 -21.8948)
		(end 270.8402 -22.4536)
		(width 0.14224)
		(layer "In11.Cu")
		(net "M_B_MA<15>")
	)
	(segment
		(start 267.321284 -29.921962)
		(end 267.321284 -30.20949)
		(width 0.14224)
		(layer "In11.Cu")
		(net "M_B_MA<15>")
	)
	(segment
		(start 270.7386 -23.2918)
		(end 270.8656 -23.4188)
		(width 0.14224)
		(layer "In11.Cu")
		(net "M_B_MA<15>")
	)
	(segment
		(start 262.6614 -52.475892)
		(end 262.6614 -54.2544)
		(width 0.0889)
		(layer "In11.Cu")
		(net "M_B_MA<15>")
	)
	(segment
		(start 265.141456 -31.499048)
		(end 264.854182 -31.786322)
		(width 0.14224)
		(layer "In11.Cu")
		(net "M_B_MA<15>")
	)
	(segment
		(start 272.050256 -13.933678)
		(end 271.519904 -13.403326)
		(width 0.14224)
		(layer "In11.Cu")
		(net "M_B_MA<15>")
	)
	(segment
		(start 261.575296 -55.146702)
		(end 261.36727 -55.59044)
		(width 0.0889)
		(layer "In11.Cu")
		(net "M_B_MA<15>")
	)
	(segment
		(start 271.529302 -8.52043)
		(end 271.529302 -7.638542)
		(width 0.14224)
		(layer "In11.Cu")
		(net "M_B_MA<15>")
	)
	(segment
		(start 267.03401 -30.496764)
		(end 266.746482 -30.496764)
		(width 0.14224)
		(layer "In11.Cu")
		(net "M_B_MA<15>")
	)
	(segment
		(start 264.174224 -33.35655)
		(end 264.174224 -48.66005)
		(width 0.14224)
		(layer "In11.Cu")
		(net "M_B_MA<15>")
	)
	(segment
		(start 265.022076 -32.22117)
		(end 265.022076 -32.508698)
		(width 0.14224)
		(layer "In11.Cu")
		(net "M_B_MA<15>")
	)
	(segment
		(start 271.519904 -13.403326)
		(end 271.519904 -12.611354)
		(width 0.14224)
		(layer "In11.Cu")
		(net "M_B_MA<15>")
	)
	(segment
		(start 262.188198 -54.5338)
		(end 261.575296 -55.146702)
		(width 0.0889)
		(layer "In11.Cu")
		(net "M_B_MA<15>")
	)
	(segment
		(start 270.759428 -17.055846)
		(end 270.0274 -17.787874)
		(width 0.14224)
		(layer "In11.Cu")
		(net "M_B_MA<15>")
	)
	(segment
		(start 266.746482 -30.496764)
		(end 266.563602 -30.313884)
		(width 0.14224)
		(layer "In11.Cu")
		(net "M_B_MA<15>")
	)
	(segment
		(start 270.7386 -22.5552)
		(end 270.7386 -23.2918)
		(width 0.14224)
		(layer "In11.Cu")
		(net "M_B_MA<15>")
	)
	(segment
		(start 267.321284 -30.20949)
		(end 267.03401 -30.496764)
		(width 0.14224)
		(layer "In11.Cu")
		(net "M_B_MA<15>")
	)
	(segment
		(start 265.596878 -31.646368)
		(end 265.449558 -31.499048)
		(width 0.14224)
		(layer "In11.Cu")
		(net "M_B_MA<15>")
	)
	(segment
		(start 267.40231 -29.200856)
		(end 267.15085 -29.452316)
		(width 0.14224)
		(layer "In11.Cu")
		(net "M_B_MA<15>")
	)
	(segment
		(start 265.022076 -32.508698)
		(end 264.174224 -33.35655)
		(width 0.14224)
		(layer "In11.Cu")
		(net "M_B_MA<15>")
	)
	(segment
		(start 271.519904 -12.611354)
		(end 271.636236 -12.495022)
		(width 0.14224)
		(layer "In11.Cu")
		(net "M_B_MA<15>")
	)
	(segment
		(start 266.17168 -31.359094)
		(end 265.884406 -31.646368)
		(width 0.14224)
		(layer "In11.Cu")
		(net "M_B_MA<15>")
	)
	(segment
		(start 269.916656 -18.398744)
		(end 269.916656 -20.971256)
		(width 0.14224)
		(layer "In11.Cu")
		(net "M_B_MA<15>")
	)
	(segment
		(start 265.98372 -30.883606)
		(end 266.17168 -31.071566)
		(width 0.14224)
		(layer "In11.Cu")
		(net "M_B_MA<15>")
	)
	(segment
		(start 269.916656 -20.971256)
		(end 270.8402 -21.8948)
		(width 0.14224)
		(layer "In11.Cu")
		(net "M_B_MA<15>")
	)
	(segment
		(start 264.854182 -31.786322)
		(end 264.854182 -32.053276)
		(width 0.14224)
		(layer "In11.Cu")
		(net "M_B_MA<15>")
	)
	(segment
		(start 264.174224 -48.66005)
		(end 264.174224 -49.896776)
		(width 0.0889)
		(layer "In11.Cu")
		(net "M_B_MA<15>")
	)
	(segment
		(start 272.050256 -15.026894)
		(end 270.759428 -16.317722)
		(width 0.14224)
		(layer "In11.Cu")
		(net "M_B_MA<15>")
	)
	(segment
		(start 270.34998 -10.422382)
		(end 270.34998 -9.133332)
		(width 0.1651)
		(layer "F.Cu")
		(net "M_B_MA<14>")
	)
	(segment
		(start 270.350488 -10.422382)
		(end 270.34998 -10.422382)
		(width 0.1651)
		(layer "F.Cu")
		(net "M_B_MA<14>")
	)
	(segment
		(start 262.79729 -57.076086)
		(end 262.22579 -57.076086)
		(width 0.1016)
		(layer "F.Cu")
		(net "M_B_MA<14>")
	)
	(segment
		(start 270.34998 -9.133332)
		(end 270.350234 -9.133078)
		(width 0.1651)
		(layer "F.Cu")
		(net "M_B_MA<14>")
	)
	(via
		(at 270.350234 -11.918188)
		(size 0.4572)
		(drill 0.2032)
		(layers "F.Cu" "B.Cu")
		(net "M_B_MA<14>")
	)
	(via
		(at 270.350234 -9.133078)
		(size 0.4572)
		(drill 0.2032)
		(layers "F.Cu" "B.Cu")
		(net "M_B_MA<14>")
	)
	(via
		(at 262.22579 -57.076086)
		(size 0.508)
		(drill 0.254)
		(layers "F.Cu" "B.Cu")
		(net "M_B_MA<14>")
	)
	(segment
		(start 270.34998 -10.623042)
		(end 270.34998 -11.917934)
		(width 0.1651)
		(layer "B.Cu")
		(net "M_B_MA<14>")
	)
	(segment
		(start 270.34998 -11.917934)
		(end 270.350234 -11.918188)
		(width 0.1651)
		(layer "B.Cu")
		(net "M_B_MA<14>")
	)
	(segment
		(start 270.350488 -10.623042)
		(end 270.34998 -10.623042)
		(width 0.1651)
		(layer "B.Cu")
		(net "M_B_MA<14>")
	)
	(segment
		(start 270.350234 -12.417298)
		(end 270.350234 -11.918188)
		(width 0.14224)
		(layer "In4.Cu")
		(net "M_B_MA<14>")
	)
	(segment
		(start 268.25702 -23.04034)
		(end 268.25702 -22.661372)
		(width 0.14224)
		(layer "In4.Cu")
		(net "M_B_MA<14>")
	)
	(segment
		(start 268.90853 -14.467078)
		(end 269.06347 -14.312138)
		(width 0.14224)
		(layer "In4.Cu")
		(net "M_B_MA<14>")
	)
	(segment
		(start 269.684754 -10.700512)
		(end 270.947134 -10.700512)
		(width 0.14224)
		(layer "In4.Cu")
		(net "M_B_MA<14>")
	)
	(segment
		(start 262.0518 -53.6956)
		(end 262.4709 -53.4797)
		(width 0.0889)
		(layer "In4.Cu")
		(net "M_B_MA<14>")
	)
	(segment
		(start 268.25702 -18.23974)
		(end 268.25702 -17.860772)
		(width 0.14224)
		(layer "In4.Cu")
		(net "M_B_MA<14>")
	)
	(segment
		(start 263.807956 -51.304444)
		(end 263.807956 -48.740314)
		(width 0.0889)
		(layer "In4.Cu")
		(net "M_B_MA<14>")
	)
	(segment
		(start 271.0688 -10.578846)
		(end 271.0688 -9.961372)
		(width 0.14224)
		(layer "In4.Cu")
		(net "M_B_MA<14>")
	)
	(segment
		(start 268.765274 -10.373106)
		(end 268.934438 -10.203942)
		(width 0.14224)
		(layer "In4.Cu")
		(net "M_B_MA<14>")
	)
	(segment
		(start 269.557754 -10.330942)
		(end 269.557754 -10.573512)
		(width 0.14224)
		(layer "In4.Cu")
		(net "M_B_MA<14>")
	)
	(segment
		(start 262.662924 -53.287676)
		(end 262.662924 -52.449476)
		(width 0.0889)
		(layer "In4.Cu")
		(net "M_B_MA<14>")
	)
	(segment
		(start 270.947134 -10.700512)
		(end 271.0688 -10.578846)
		(width 0.14224)
		(layer "In4.Cu")
		(net "M_B_MA<14>")
	)
	(segment
		(start 270.839184 -9.731756)
		(end 270.506698 -9.731756)
		(width 0.14224)
		(layer "In4.Cu")
		(net "M_B_MA<14>")
	)
	(segment
		(start 270.350234 -11.918188)
		(end 270.350234 -11.739626)
		(width 0.14224)
		(layer "In4.Cu")
		(net "M_B_MA<14>")
	)
	(segment
		(start 268.209776 -16.924274)
		(end 268.209776 -14.797024)
		(width 0.14224)
		(layer "In4.Cu")
		(net "M_B_MA<14>")
	)
	(segment
		(start 268.3002 -19.075654)
		(end 268.215364 -18.990818)
		(width 0.14224)
		(layer "In4.Cu")
		(net "M_B_MA<14>")
	)
	(segment
		(start 268.1732 -24.27986)
		(end 268.1732 -23.12416)
		(width 0.14224)
		(layer "In4.Cu")
		(net "M_B_MA<14>")
	)
	(segment
		(start 269.06347 -14.312138)
		(end 269.06347 -13.704062)
		(width 0.14224)
		(layer "In4.Cu")
		(net "M_B_MA<14>")
	)
	(segment
		(start 270.506698 -9.731756)
		(end 270.350234 -9.575292)
		(width 0.14224)
		(layer "In4.Cu")
		(net "M_B_MA<14>")
	)
	(segment
		(start 271.0688 -9.961372)
		(end 270.839184 -9.731756)
		(width 0.14224)
		(layer "In4.Cu")
		(net "M_B_MA<14>")
	)
	(segment
		(start 262.4709 -53.4797)
		(end 262.662924 -53.287676)
		(width 0.0889)
		(layer "In4.Cu")
		(net "M_B_MA<14>")
	)
	(segment
		(start 270.103854 -11.493246)
		(end 269.022322 -11.493246)
		(width 0.14224)
		(layer "In4.Cu")
		(net "M_B_MA<14>")
	)
	(segment
		(start 269.430754 -10.203942)
		(end 269.557754 -10.330942)
		(width 0.14224)
		(layer "In4.Cu")
		(net "M_B_MA<14>")
	)
	(segment
		(start 263.807956 -29.993844)
		(end 266.446 -27.3558)
		(width 0.14224)
		(layer "In4.Cu")
		(net "M_B_MA<14>")
	)
	(segment
		(start 269.022322 -11.493246)
		(end 268.765274 -11.236198)
		(width 0.14224)
		(layer "In4.Cu")
		(net "M_B_MA<14>")
	)
	(segment
		(start 268.209776 -14.797024)
		(end 268.539722 -14.467078)
		(width 0.14224)
		(layer "In4.Cu")
		(net "M_B_MA<14>")
	)
	(segment
		(start 268.1732 -21.76145)
		(end 268.3002 -21.63445)
		(width 0.14224)
		(layer "In4.Cu")
		(net "M_B_MA<14>")
	)
	(segment
		(start 268.1732 -23.12416)
		(end 268.25702 -23.04034)
		(width 0.14224)
		(layer "In4.Cu")
		(net "M_B_MA<14>")
	)
	(segment
		(start 270.350234 -11.739626)
		(end 270.103854 -11.493246)
		(width 0.14224)
		(layer "In4.Cu")
		(net "M_B_MA<14>")
	)
	(segment
		(start 262.662924 -52.449476)
		(end 263.807956 -51.304444)
		(width 0.0889)
		(layer "In4.Cu")
		(net "M_B_MA<14>")
	)
	(segment
		(start 261.7978 -53.9496)
		(end 262.0518 -53.6956)
		(width 0.0889)
		(layer "In4.Cu")
		(net "M_B_MA<14>")
	)
	(segment
		(start 269.557754 -10.573512)
		(end 269.684754 -10.700512)
		(width 0.14224)
		(layer "In4.Cu")
		(net "M_B_MA<14>")
	)
	(segment
		(start 268.25702 -22.661372)
		(end 268.1732 -22.577552)
		(width 0.14224)
		(layer "In4.Cu")
		(net "M_B_MA<14>")
	)
	(segment
		(start 269.06347 -13.704062)
		(end 270.350234 -12.417298)
		(width 0.14224)
		(layer "In4.Cu")
		(net "M_B_MA<14>")
	)
	(segment
		(start 268.1732 -17.776952)
		(end 268.1732 -16.96085)
		(width 0.14224)
		(layer "In4.Cu")
		(net "M_B_MA<14>")
	)
	(segment
		(start 266.446 -27.3558)
		(end 266.446 -26.00706)
		(width 0.14224)
		(layer "In4.Cu")
		(net "M_B_MA<14>")
	)
	(segment
		(start 263.807956 -48.740314)
		(end 263.807956 -29.993844)
		(width 0.14224)
		(layer "In4.Cu")
		(net "M_B_MA<14>")
	)
	(segment
		(start 268.215364 -18.281396)
		(end 268.25702 -18.23974)
		(width 0.14224)
		(layer "In4.Cu")
		(net "M_B_MA<14>")
	)
	(segment
		(start 268.539722 -14.467078)
		(end 268.90853 -14.467078)
		(width 0.14224)
		(layer "In4.Cu")
		(net "M_B_MA<14>")
	)
	(segment
		(start 268.1732 -16.96085)
		(end 268.209776 -16.924274)
		(width 0.14224)
		(layer "In4.Cu")
		(net "M_B_MA<14>")
	)
	(segment
		(start 268.934438 -10.203942)
		(end 269.430754 -10.203942)
		(width 0.14224)
		(layer "In4.Cu")
		(net "M_B_MA<14>")
	)
	(segment
		(start 270.350234 -9.575292)
		(end 270.350234 -9.133078)
		(width 0.14224)
		(layer "In4.Cu")
		(net "M_B_MA<14>")
	)
	(segment
		(start 268.1732 -22.577552)
		(end 268.1732 -21.76145)
		(width 0.14224)
		(layer "In4.Cu")
		(net "M_B_MA<14>")
	)
	(segment
		(start 266.446 -26.00706)
		(end 268.1732 -24.27986)
		(width 0.14224)
		(layer "In4.Cu")
		(net "M_B_MA<14>")
	)
	(segment
		(start 261.7978 -56.1086)
		(end 261.7978 -53.9496)
		(width 0.0889)
		(layer "In4.Cu")
		(net "M_B_MA<14>")
	)
	(segment
		(start 268.215364 -18.990818)
		(end 268.215364 -18.281396)
		(width 0.14224)
		(layer "In4.Cu")
		(net "M_B_MA<14>")
	)
	(segment
		(start 268.3002 -21.63445)
		(end 268.3002 -19.075654)
		(width 0.14224)
		(layer "In4.Cu")
		(net "M_B_MA<14>")
	)
	(segment
		(start 268.25702 -17.860772)
		(end 268.1732 -17.776952)
		(width 0.14224)
		(layer "In4.Cu")
		(net "M_B_MA<14>")
	)
	(segment
		(start 262.22579 -57.076086)
		(end 261.7978 -56.1086)
		(width 0.0889)
		(layer "In4.Cu")
		(net "M_B_MA<14>")
	)
	(segment
		(start 268.765274 -11.236198)
		(end 268.765274 -10.373106)
		(width 0.14224)
		(layer "In4.Cu")
		(net "M_B_MA<14>")
	)
	(segment
		(start 273.750278 -10.422382)
		(end 273.74977 -10.422382)
		(width 0.1651)
		(layer "F.Cu")
		(net "M_B_MA<13>")
	)
	(segment
		(start 273.74977 -9.133586)
		(end 273.750278 -9.133078)
		(width 0.1651)
		(layer "F.Cu")
		(net "M_B_MA<13>")
	)
	(segment
		(start 262.79729 -55.094886)
		(end 262.22579 -55.094886)
		(width 0.1016)
		(layer "F.Cu")
		(net "M_B_MA<13>")
	)
	(segment
		(start 273.74977 -10.422382)
		(end 273.74977 -9.133586)
		(width 0.1651)
		(layer "F.Cu")
		(net "M_B_MA<13>")
	)
	(via
		(at 273.750278 -11.918188)
		(size 0.4572)
		(drill 0.2032)
		(layers "F.Cu" "B.Cu")
		(net "M_B_MA<13>")
	)
	(via
		(at 273.750278 -9.133078)
		(size 0.4572)
		(drill 0.2032)
		(layers "F.Cu" "B.Cu")
		(net "M_B_MA<13>")
	)
	(via
		(at 262.22579 -55.094886)
		(size 0.508)
		(drill 0.254)
		(layers "F.Cu" "B.Cu")
		(net "M_B_MA<13>")
	)
	(segment
		(start 273.74977 -10.623042)
		(end 273.74977 -11.91768)
		(width 0.1651)
		(layer "B.Cu")
		(net "M_B_MA<13>")
	)
	(segment
		(start 273.750278 -10.623042)
		(end 273.74977 -10.623042)
		(width 0.1651)
		(layer "B.Cu")
		(net "M_B_MA<13>")
	)
	(segment
		(start 273.74977 -11.91768)
		(end 273.750278 -11.918188)
		(width 0.1651)
		(layer "B.Cu")
		(net "M_B_MA<13>")
	)
	(segment
		(start 273.595338 -11.431778)
		(end 272.588482 -11.431778)
		(width 0.14224)
		(layer "In11.Cu")
		(net "M_B_MA<13>")
	)
	(segment
		(start 270.759428 -17.784572)
		(end 270.759428 -19.290792)
		(width 0.14224)
		(layer "In11.Cu")
		(net "M_B_MA<13>")
	)
	(segment
		(start 271.6784 -21.6916)
		(end 271.5768 -21.7932)
		(width 0.14224)
		(layer "In11.Cu")
		(net "M_B_MA<13>")
	)
	(segment
		(start 271.5006 -23.241)
		(end 271.5006 -27.195272)
		(width 0.14224)
		(layer "In11.Cu")
		(net "M_B_MA<13>")
	)
	(segment
		(start 271.634712 -16.305784)
		(end 271.634712 -16.909288)
		(width 0.14224)
		(layer "In11.Cu")
		(net "M_B_MA<13>")
	)
	(segment
		(start 271.634712 -16.909288)
		(end 270.759428 -17.784572)
		(width 0.14224)
		(layer "In11.Cu")
		(net "M_B_MA<13>")
	)
	(segment
		(start 272.588482 -10.860024)
		(end 273.595338 -10.860024)
		(width 0.14224)
		(layer "In11.Cu")
		(net "M_B_MA<13>")
	)
	(segment
		(start 273.595338 -10.245598)
		(end 272.588482 -10.245598)
		(width 0.14224)
		(layer "In11.Cu")
		(net "M_B_MA<13>")
	)
	(segment
		(start 264.682224 -49.005744)
		(end 264.3886 -49.299368)
		(width 0.0889)
		(layer "In11.Cu")
		(net "M_B_MA<13>")
	)
	(segment
		(start 272.588482 -10.245598)
		(end 272.433542 -10.090658)
		(width 0.14224)
		(layer "In11.Cu")
		(net "M_B_MA<13>")
	)
	(segment
		(start 264.3886 -50.038)
		(end 263.4996 -50.927)
		(width 0.0889)
		(layer "In11.Cu")
		(net "M_B_MA<13>")
	)
	(segment
		(start 264.3886 -49.299368)
		(end 264.3886 -50.038)
		(width 0.0889)
		(layer "In11.Cu")
		(net "M_B_MA<13>")
	)
	(segment
		(start 268.540484 -29.708856)
		(end 264.682224 -33.567116)
		(width 0.14224)
		(layer "In11.Cu")
		(net "M_B_MA<13>")
	)
	(segment
		(start 271.6784 -22.6568)
		(end 271.6784 -23.0632)
		(width 0.14224)
		(layer "In11.Cu")
		(net "M_B_MA<13>")
	)
	(segment
		(start 272.433542 -9.741154)
		(end 272.601436 -9.57326)
		(width 0.14224)
		(layer "In11.Cu")
		(net "M_B_MA<13>")
	)
	(segment
		(start 270.9545 -20.21967)
		(end 271.6784 -20.94357)
		(width 0.14224)
		(layer "In11.Cu")
		(net "M_B_MA<13>")
	)
	(segment
		(start 273.314414 -14.626082)
		(end 271.634712 -16.305784)
		(width 0.14224)
		(layer "In11.Cu")
		(net "M_B_MA<13>")
	)
	(segment
		(start 263.192514 -55.094886)
		(end 262.22579 -55.094886)
		(width 0.0889)
		(layer "In11.Cu")
		(net "M_B_MA<13>")
	)
	(segment
		(start 264.682224 -48.672496)
		(end 264.682224 -49.005744)
		(width 0.0889)
		(layer "In11.Cu")
		(net "M_B_MA<13>")
	)
	(segment
		(start 271.6784 -20.94357)
		(end 271.6784 -21.6916)
		(width 0.14224)
		(layer "In11.Cu")
		(net "M_B_MA<13>")
	)
	(segment
		(start 271.5006 -27.195272)
		(end 268.987016 -29.708856)
		(width 0.14224)
		(layer "In11.Cu")
		(net "M_B_MA<13>")
	)
	(segment
		(start 263.4996 -54.7878)
		(end 263.192514 -55.094886)
		(width 0.0889)
		(layer "In11.Cu")
		(net "M_B_MA<13>")
	)
	(segment
		(start 263.4996 -50.927)
		(end 263.4996 -54.7878)
		(width 0.0889)
		(layer "In11.Cu")
		(net "M_B_MA<13>")
	)
	(segment
		(start 273.595338 -10.860024)
		(end 273.750278 -10.705084)
		(width 0.14224)
		(layer "In11.Cu")
		(net "M_B_MA<13>")
	)
	(segment
		(start 272.433542 -11.276838)
		(end 272.433542 -11.014964)
		(width 0.14224)
		(layer "In11.Cu")
		(net "M_B_MA<13>")
	)
	(segment
		(start 268.987016 -29.708856)
		(end 268.540484 -29.708856)
		(width 0.14224)
		(layer "In11.Cu")
		(net "M_B_MA<13>")
	)
	(segment
		(start 273.750278 -11.586718)
		(end 273.595338 -11.431778)
		(width 0.14224)
		(layer "In11.Cu")
		(net "M_B_MA<13>")
	)
	(segment
		(start 270.759428 -19.290792)
		(end 270.9545 -19.485864)
		(width 0.14224)
		(layer "In11.Cu")
		(net "M_B_MA<13>")
	)
	(segment
		(start 270.9545 -19.485864)
		(end 270.9545 -20.21967)
		(width 0.14224)
		(layer "In11.Cu")
		(net "M_B_MA<13>")
	)
	(segment
		(start 273.750278 -10.400538)
		(end 273.595338 -10.245598)
		(width 0.14224)
		(layer "In11.Cu")
		(net "M_B_MA<13>")
	)
	(segment
		(start 273.750278 -11.918188)
		(end 273.750278 -11.586718)
		(width 0.14224)
		(layer "In11.Cu")
		(net "M_B_MA<13>")
	)
	(segment
		(start 273.74977 -13.06703)
		(end 273.314414 -13.502386)
		(width 0.14224)
		(layer "In11.Cu")
		(net "M_B_MA<13>")
	)
	(segment
		(start 273.74977 -11.918696)
		(end 273.74977 -13.06703)
		(width 0.14224)
		(layer "In11.Cu")
		(net "M_B_MA<13>")
	)
	(segment
		(start 264.682224 -33.567116)
		(end 264.682224 -48.672496)
		(width 0.14224)
		(layer "In11.Cu")
		(net "M_B_MA<13>")
	)
	(segment
		(start 273.750278 -11.918188)
		(end 273.74977 -11.918696)
		(width 0.14224)
		(layer "In11.Cu")
		(net "M_B_MA<13>")
	)
	(segment
		(start 273.314414 -13.502386)
		(end 273.314414 -14.626082)
		(width 0.14224)
		(layer "In11.Cu")
		(net "M_B_MA<13>")
	)
	(segment
		(start 272.601436 -9.57326)
		(end 273.623278 -9.57326)
		(width 0.14224)
		(layer "In11.Cu")
		(net "M_B_MA<13>")
	)
	(segment
		(start 272.433542 -10.090658)
		(end 272.433542 -9.741154)
		(width 0.14224)
		(layer "In11.Cu")
		(net "M_B_MA<13>")
	)
	(segment
		(start 271.5768 -21.7932)
		(end 271.5768 -22.5552)
		(width 0.14224)
		(layer "In11.Cu")
		(net "M_B_MA<13>")
	)
	(segment
		(start 273.750278 -10.705084)
		(end 273.750278 -10.400538)
		(width 0.14224)
		(layer "In11.Cu")
		(net "M_B_MA<13>")
	)
	(segment
		(start 273.750278 -9.44626)
		(end 273.750278 -9.133078)
		(width 0.14224)
		(layer "In11.Cu")
		(net "M_B_MA<13>")
	)
	(segment
		(start 272.433542 -11.014964)
		(end 272.588482 -10.860024)
		(width 0.14224)
		(layer "In11.Cu")
		(net "M_B_MA<13>")
	)
	(segment
		(start 272.588482 -11.431778)
		(end 272.433542 -11.276838)
		(width 0.14224)
		(layer "In11.Cu")
		(net "M_B_MA<13>")
	)
	(segment
		(start 271.5768 -22.5552)
		(end 271.6784 -22.6568)
		(width 0.14224)
		(layer "In11.Cu")
		(net "M_B_MA<13>")
	)
	(segment
		(start 271.6784 -23.0632)
		(end 271.5006 -23.241)
		(width 0.14224)
		(layer "In11.Cu")
		(net "M_B_MA<13>")
	)
	(segment
		(start 273.623278 -9.57326)
		(end 273.750278 -9.44626)
		(width 0.14224)
		(layer "In11.Cu")
		(net "M_B_MA<13>")
	)
	(segment
		(start 254.212344 -57.076086)
		(end 253.640844 -57.076086)
		(width 0.1016)
		(layer "F.Cu")
		(net "M_B_MA<12>")
	)
	(segment
		(start 249.099832 -5.822442)
		(end 249.099832 -7.115556)
		(width 0.1651)
		(layer "F.Cu")
		(net "M_B_MA<12>")
	)
	(segment
		(start 249.10034 -5.822442)
		(end 249.099832 -5.822442)
		(width 0.1651)
		(layer "F.Cu")
		(net "M_B_MA<12>")
	)
	(via
		(at 253.640844 -57.076086)
		(size 0.508)
		(drill 0.254)
		(layers "F.Cu" "B.Cu")
		(net "M_B_MA<12>")
	)
	(via
		(at 249.099832 -7.115556)
		(size 0.4572)
		(drill 0.2032)
		(layers "F.Cu" "B.Cu")
		(net "M_B_MA<12>")
	)
	(via
		(at 249.099832 -13.933678)
		(size 0.4572)
		(drill 0.2032)
		(layers "F.Cu" "B.Cu")
		(net "M_B_MA<12>")
	)
	(segment
		(start 249.099832 -15.222982)
		(end 249.099832 -13.933678)
		(width 0.1651)
		(layer "B.Cu")
		(net "M_B_MA<12>")
	)
	(segment
		(start 249.10034 -15.222982)
		(end 249.099832 -15.222982)
		(width 0.1651)
		(layer "B.Cu")
		(net "M_B_MA<12>")
	)
	(segment
		(start 248.409968 -7.80542)
		(end 249.099832 -7.115556)
		(width 0.14224)
		(layer "In11.Cu")
		(net "M_B_MA<12>")
	)
	(segment
		(start 249.099832 -14.962632)
		(end 249.693176 -15.555976)
		(width 0.14224)
		(layer "In11.Cu")
		(net "M_B_MA<12>")
	)
	(segment
		(start 249.693176 -15.555976)
		(end 251.25299 -15.555976)
		(width 0.14224)
		(layer "In11.Cu")
		(net "M_B_MA<12>")
	)
	(segment
		(start 254.456184 -50.749708)
		(end 254.456184 -51.04892)
		(width 0.0889)
		(layer "In11.Cu")
		(net "M_B_MA<12>")
	)
	(segment
		(start 252.107192 -25.869392)
		(end 252.511306 -26.273506)
		(width 0.14224)
		(layer "In11.Cu")
		(net "M_B_MA<12>")
	)
	(segment
		(start 248.65838 -8.919972)
		(end 248.409968 -8.67156)
		(width 0.14224)
		(layer "In11.Cu")
		(net "M_B_MA<12>")
	)
	(segment
		(start 254.644398 -55.963566)
		(end 254.185928 -56.234838)
		(width 0.0889)
		(layer "In11.Cu")
		(net "M_B_MA<12>")
	)
	(segment
		(start 254.456184 -51.04892)
		(end 254.3556 -51.149504)
		(width 0.0889)
		(layer "In11.Cu")
		(net "M_B_MA<12>")
	)
	(segment
		(start 248.409968 -8.67156)
		(end 248.409968 -7.80542)
		(width 0.14224)
		(layer "In11.Cu")
		(net "M_B_MA<12>")
	)
	(segment
		(start 252.085094 -17.688306)
		(end 252.042676 -17.730724)
		(width 0.14224)
		(layer "In11.Cu")
		(net "M_B_MA<12>")
	)
	(segment
		(start 252.041152 -23.136352)
		(end 252.107192 -23.202392)
		(width 0.14224)
		(layer "In11.Cu")
		(net "M_B_MA<12>")
	)
	(segment
		(start 252.107192 -23.202392)
		(end 252.107192 -25.869392)
		(width 0.14224)
		(layer "In11.Cu")
		(net "M_B_MA<12>")
	)
	(segment
		(start 254.361442 -54.975506)
		(end 254.446024 -55.006494)
		(width 0.0889)
		(layer "In11.Cu")
		(net "M_B_MA<12>")
	)
	(segment
		(start 251.9172 -19.1516)
		(end 251.9172 -21.7424)
		(width 0.14224)
		(layer "In11.Cu")
		(net "M_B_MA<12>")
	)
	(segment
		(start 249.099832 -13.933678)
		(end 249.099832 -14.962632)
		(width 0.14224)
		(layer "In11.Cu")
		(net "M_B_MA<12>")
	)
	(segment
		(start 254.152654 -53.809138)
		(end 254.161544 -53.824378)
		(width 0.0889)
		(layer "In11.Cu")
		(net "M_B_MA<12>")
	)
	(segment
		(start 252.511306 -30.507686)
		(end 254.456184 -32.452564)
		(width 0.14224)
		(layer "In11.Cu")
		(net "M_B_MA<12>")
	)
	(segment
		(start 252.107192 -22.517608)
		(end 252.041152 -22.583648)
		(width 0.14224)
		(layer "In11.Cu")
		(net "M_B_MA<12>")
	)
	(segment
		(start 252.042676 -17.730724)
		(end 252.042676 -18.438876)
		(width 0.14224)
		(layer "In11.Cu")
		(net "M_B_MA<12>")
	)
	(segment
		(start 248.65838 -13.32738)
		(end 248.65838 -8.919972)
		(width 0.14224)
		(layer "In11.Cu")
		(net "M_B_MA<12>")
	)
	(segment
		(start 254.3556 -51.149504)
		(end 254.3556 -52.651406)
		(width 0.0889)
		(layer "In11.Cu")
		(net "M_B_MA<12>")
	)
	(segment
		(start 252.085094 -18.983706)
		(end 251.9172 -19.1516)
		(width 0.14224)
		(layer "In11.Cu")
		(net "M_B_MA<12>")
	)
	(segment
		(start 249.099832 -13.768832)
		(end 248.65838 -13.32738)
		(width 0.14224)
		(layer "In11.Cu")
		(net "M_B_MA<12>")
	)
	(segment
		(start 251.25299 -15.555976)
		(end 252.085094 -16.38808)
		(width 0.14224)
		(layer "In11.Cu")
		(net "M_B_MA<12>")
	)
	(segment
		(start 254.456184 -32.452564)
		(end 254.456184 -50.749708)
		(width 0.14224)
		(layer "In11.Cu")
		(net "M_B_MA<12>")
	)
	(segment
		(start 249.099832 -13.933678)
		(end 249.099832 -13.768832)
		(width 0.14224)
		(layer "In11.Cu")
		(net "M_B_MA<12>")
	)
	(segment
		(start 252.107192 -21.932392)
		(end 252.107192 -22.517608)
		(width 0.14224)
		(layer "In11.Cu")
		(net "M_B_MA<12>")
	)
	(segment
		(start 252.511306 -26.273506)
		(end 252.511306 -30.507686)
		(width 0.14224)
		(layer "In11.Cu")
		(net "M_B_MA<12>")
	)
	(segment
		(start 254.832866 -55.36819)
		(end 254.84582 -55.390796)
		(width 0.0889)
		(layer "In11.Cu")
		(net "M_B_MA<12>")
	)
	(segment
		(start 251.9172 -21.7424)
		(end 252.107192 -21.932392)
		(width 0.14224)
		(layer "In11.Cu")
		(net "M_B_MA<12>")
	)
	(segment
		(start 252.085094 -18.481294)
		(end 252.085094 -18.983706)
		(width 0.14224)
		(layer "In11.Cu")
		(net "M_B_MA<12>")
	)
	(segment
		(start 254.185928 -56.234838)
		(end 253.640844 -57.076086)
		(width 0.0889)
		(layer "In11.Cu")
		(net "M_B_MA<12>")
	)
	(segment
		(start 252.042676 -18.438876)
		(end 252.085094 -18.481294)
		(width 0.14224)
		(layer "In11.Cu")
		(net "M_B_MA<12>")
	)
	(segment
		(start 252.041152 -22.583648)
		(end 252.041152 -23.136352)
		(width 0.14224)
		(layer "In11.Cu")
		(net "M_B_MA<12>")
	)
	(segment
		(start 252.085094 -16.38808)
		(end 252.085094 -17.688306)
		(width 0.14224)
		(layer "In11.Cu")
		(net "M_B_MA<12>")
	)
	(arc
		(start 254.161544 -53.824378)
		(mid 254.231941 -54.113329)
		(end 254.152654 -54.399942)
		(width 0.0889)
		(layer "In11.Cu")
		(net "M_B_MA<12>")
	)
	(arc
		(start 254.152654 -53.409342)
		(mid 254.099121 -53.60924)
		(end 254.152654 -53.809138)
		(width 0.0889)
		(layer "In11.Cu")
		(net "M_B_MA<12>")
	)
	(arc
		(start 254.3556 -52.651406)
		(mid 254.303973 -53.043717)
		(end 254.152654 -53.409342)
		(width 0.0889)
		(layer "In11.Cu")
		(net "M_B_MA<12>")
	)
	(arc
		(start 254.152654 -54.399942)
		(mid 254.123112 -54.736283)
		(end 254.361442 -54.975506)
		(width 0.0889)
		(layer "In11.Cu")
		(net "M_B_MA<12>")
	)
	(arc
		(start 254.446024 -55.006494)
		(mid 254.560671 -55.063267)
		(end 254.6604 -55.1434)
		(width 0.0889)
		(layer "In11.Cu")
		(net "M_B_MA<12>")
	)
	(arc
		(start 254.84582 -55.390796)
		(mid 254.876659 -55.72345)
		(end 254.644398 -55.963566)
		(width 0.0889)
		(layer "In11.Cu")
		(net "M_B_MA<12>")
	)
	(arc
		(start 254.6604 -55.1434)
		(mid 254.754008 -55.250136)
		(end 254.832866 -55.36819)
		(width 0.0889)
		(layer "In11.Cu")
		(net "M_B_MA<12>")
	)
	(segment
		(start 255.07061 -56.58104)
		(end 254.49911 -56.58104)
		(width 0.1016)
		(layer "F.Cu")
		(net "M_B_MA<11>")
	)
	(segment
		(start 249.94997 -10.422382)
		(end 249.94997 -9.133078)
		(width 0.1651)
		(layer "F.Cu")
		(net "M_B_MA<11>")
	)
	(segment
		(start 249.950478 -10.422382)
		(end 249.94997 -10.422382)
		(width 0.1651)
		(layer "F.Cu")
		(net "M_B_MA<11>")
	)
	(via
		(at 249.94997 -9.133078)
		(size 0.4572)
		(drill 0.2032)
		(layers "F.Cu" "B.Cu")
		(net "M_B_MA<11>")
	)
	(via
		(at 249.949716 -11.916156)
		(size 0.4572)
		(drill 0.2032)
		(layers "F.Cu" "B.Cu")
		(net "M_B_MA<11>")
	)
	(via
		(at 254.49911 -56.58104)
		(size 0.508)
		(drill 0.254)
		(layers "F.Cu" "B.Cu")
		(net "M_B_MA<11>")
	)
	(segment
		(start 249.94997 -11.915902)
		(end 249.949716 -11.916156)
		(width 0.1651)
		(layer "B.Cu")
		(net "M_B_MA<11>")
	)
	(segment
		(start 249.94997 -10.623042)
		(end 249.94997 -11.915902)
		(width 0.1651)
		(layer "B.Cu")
		(net "M_B_MA<11>")
	)
	(segment
		(start 249.950478 -10.623042)
		(end 249.94997 -10.623042)
		(width 0.1651)
		(layer "B.Cu")
		(net "M_B_MA<11>")
	)
	(segment
		(start 252.8824 -23.2156)
		(end 252.9586 -23.1394)
		(width 0.14224)
		(layer "In11.Cu")
		(net "M_B_MA<11>")
	)
	(segment
		(start 253.019306 -30.296866)
		(end 253.019306 -23.876)
		(width 0.14224)
		(layer "In11.Cu")
		(net "M_B_MA<11>")
	)
	(segment
		(start 254.6858 -52.8574)
		(end 254.6858 -51.405028)
		(width 0.0889)
		(layer "In11.Cu")
		(net "M_B_MA<11>")
	)
	(segment
		(start 254.964184 -51.126644)
		(end 254.964184 -50.842164)
		(width 0.0889)
		(layer "In11.Cu")
		(net "M_B_MA<11>")
	)
	(segment
		(start 252.911356 -17.707356)
		(end 252.911356 -16.284956)
		(width 0.14224)
		(layer "In11.Cu")
		(net "M_B_MA<11>")
	)
	(segment
		(start 249.652028 -10.088372)
		(end 249.652028 -11.618468)
		(width 0.14224)
		(layer "In11.Cu")
		(net "M_B_MA<11>")
	)
	(segment
		(start 252.892814 -22.514814)
		(end 252.892814 -21.782786)
		(width 0.14224)
		(layer "In11.Cu")
		(net "M_B_MA<11>")
	)
	(segment
		(start 249.652028 -11.618468)
		(end 249.949716 -11.916156)
		(width 0.14224)
		(layer "In11.Cu")
		(net "M_B_MA<11>")
	)
	(segment
		(start 252.9586 -23.1394)
		(end 252.9586 -22.5806)
		(width 0.14224)
		(layer "In11.Cu")
		(net "M_B_MA<11>")
	)
	(segment
		(start 249.263662 -12.60221)
		(end 249.949716 -11.916156)
		(width 0.14224)
		(layer "In11.Cu")
		(net "M_B_MA<11>")
	)
	(segment
		(start 252.8824 -23.739094)
		(end 252.8824 -23.2156)
		(width 0.14224)
		(layer "In11.Cu")
		(net "M_B_MA<11>")
	)
	(segment
		(start 254.84582 -53.409088)
		(end 254.822706 -53.368956)
		(width 0.0889)
		(layer "In11.Cu")
		(net "M_B_MA<11>")
	)
	(segment
		(start 249.5169 -13.2842)
		(end 249.263662 -13.030962)
		(width 0.14224)
		(layer "In11.Cu")
		(net "M_B_MA<11>")
	)
	(segment
		(start 254.964184 -32.241744)
		(end 253.019306 -30.296866)
		(width 0.14224)
		(layer "In11.Cu")
		(net "M_B_MA<11>")
	)
	(segment
		(start 254.99441 -55.914798)
		(end 255.01092 -55.886096)
		(width 0.0889)
		(layer "In11.Cu")
		(net "M_B_MA<11>")
	)
	(segment
		(start 254.83947 -53.819806)
		(end 254.84582 -53.809138)
		(width 0.0889)
		(layer "In11.Cu")
		(net "M_B_MA<11>")
	)
	(segment
		(start 249.263662 -13.030962)
		(end 249.263662 -12.60221)
		(width 0.14224)
		(layer "In11.Cu")
		(net "M_B_MA<11>")
	)
	(segment
		(start 252.9332 -21.3106)
		(end 252.9332 -18.3896)
		(width 0.14224)
		(layer "In11.Cu")
		(net "M_B_MA<11>")
	)
	(segment
		(start 253.019306 -23.876)
		(end 252.8824 -23.739094)
		(width 0.14224)
		(layer "In11.Cu")
		(net "M_B_MA<11>")
	)
	(segment
		(start 252.9586 -21.717)
		(end 252.9586 -21.336)
		(width 0.14224)
		(layer "In11.Cu")
		(net "M_B_MA<11>")
	)
	(segment
		(start 254.964184 -50.842164)
		(end 254.964184 -32.241744)
		(width 0.14224)
		(layer "In11.Cu")
		(net "M_B_MA<11>")
	)
	(segment
		(start 251.6886 -15.0622)
		(end 249.9868 -15.0622)
		(width 0.14224)
		(layer "In11.Cu")
		(net "M_B_MA<11>")
	)
	(segment
		(start 249.94997 -9.79043)
		(end 249.652028 -10.088372)
		(width 0.14224)
		(layer "In11.Cu")
		(net "M_B_MA<11>")
	)
	(segment
		(start 249.94997 -9.133078)
		(end 249.94997 -9.79043)
		(width 0.14224)
		(layer "In11.Cu")
		(net "M_B_MA<11>")
	)
	(segment
		(start 252.892814 -21.782786)
		(end 252.9586 -21.717)
		(width 0.14224)
		(layer "In11.Cu")
		(net "M_B_MA<11>")
	)
	(segment
		(start 254.6858 -51.405028)
		(end 254.964184 -51.126644)
		(width 0.0889)
		(layer "In11.Cu")
		(net "M_B_MA<11>")
	)
	(segment
		(start 253.0094 -17.8054)
		(end 252.911356 -17.707356)
		(width 0.14224)
		(layer "In11.Cu")
		(net "M_B_MA<11>")
	)
	(segment
		(start 249.9868 -15.0622)
		(end 249.5169 -14.5923)
		(width 0.14224)
		(layer "In11.Cu")
		(net "M_B_MA<11>")
	)
	(segment
		(start 254.84582 -53.809138)
		(end 254.850646 -53.800502)
		(width 0.0889)
		(layer "In11.Cu")
		(net "M_B_MA<11>")
	)
	(segment
		(start 254.9398 -54.493668)
		(end 254.84582 -54.399688)
		(width 0.0889)
		(layer "In11.Cu")
		(net "M_B_MA<11>")
	)
	(segment
		(start 254.49911 -56.58104)
		(end 254.99441 -55.914798)
		(width 0.0889)
		(layer "In11.Cu")
		(net "M_B_MA<11>")
	)
	(segment
		(start 252.9586 -22.5806)
		(end 252.892814 -22.514814)
		(width 0.14224)
		(layer "In11.Cu")
		(net "M_B_MA<11>")
	)
	(segment
		(start 252.911356 -16.284956)
		(end 251.6886 -15.0622)
		(width 0.14224)
		(layer "In11.Cu")
		(net "M_B_MA<11>")
	)
	(segment
		(start 249.5169 -14.5923)
		(end 249.5169 -13.2842)
		(width 0.14224)
		(layer "In11.Cu")
		(net "M_B_MA<11>")
	)
	(segment
		(start 254.9398 -55.029862)
		(end 254.9398 -54.493668)
		(width 0.0889)
		(layer "In11.Cu")
		(net "M_B_MA<11>")
	)
	(segment
		(start 252.9586 -21.336)
		(end 252.9332 -21.3106)
		(width 0.14224)
		(layer "In11.Cu")
		(net "M_B_MA<11>")
	)
	(segment
		(start 252.9332 -18.3896)
		(end 253.0094 -18.3134)
		(width 0.14224)
		(layer "In11.Cu")
		(net "M_B_MA<11>")
	)
	(segment
		(start 253.0094 -18.3134)
		(end 253.0094 -17.8054)
		(width 0.14224)
		(layer "In11.Cu")
		(net "M_B_MA<11>")
	)
	(arc
		(start 254.850646 -53.800502)
		(mid 254.899401 -53.60415)
		(end 254.84582 -53.409088)
		(width 0.0889)
		(layer "In11.Cu")
		(net "M_B_MA<11>")
	)
	(arc
		(start 255.01092 -55.886096)
		(mid 255.090051 -55.590694)
		(end 255.01092 -55.295292)
		(width 0.0889)
		(layer "In11.Cu")
		(net "M_B_MA<11>")
	)
	(arc
		(start 255.01092 -55.295292)
		(mid 254.957912 -55.167254)
		(end 254.9398 -55.029862)
		(width 0.0889)
		(layer "In11.Cu")
		(net "M_B_MA<11>")
	)
	(arc
		(start 254.84582 -54.399688)
		(mid 254.766598 -54.11057)
		(end 254.83947 -53.819806)
		(width 0.0889)
		(layer "In11.Cu")
		(net "M_B_MA<11>")
	)
	(arc
		(start 254.822706 -53.368956)
		(mid 254.720638 -53.122176)
		(end 254.6858 -52.8574)
		(width 0.0889)
		(layer "In11.Cu")
		(net "M_B_MA<11>")
	)
	(segment
		(start 267.79982 -10.422382)
		(end 267.79982 -9.158732)
		(width 0.1651)
		(layer "F.Cu")
		(net "M_B_MA<10>")
	)
	(segment
		(start 259.36321 -55.094886)
		(end 258.79171 -55.094886)
		(width 0.1016)
		(layer "F.Cu")
		(net "M_B_MA<10>")
	)
	(segment
		(start 267.800328 -10.422382)
		(end 267.79982 -10.422382)
		(width 0.1651)
		(layer "F.Cu")
		(net "M_B_MA<10>")
	)
	(segment
		(start 267.79982 -9.158732)
		(end 267.800074 -9.158478)
		(width 0.1651)
		(layer "F.Cu")
		(net "M_B_MA<10>")
	)
	(segment
		(start 267.800074 -9.158478)
		(end 267.800074 -9.133078)
		(width 0.1651)
		(layer "F.Cu")
		(net "M_B_MA<10>")
	)
	(via
		(at 267.800074 -9.133078)
		(size 0.4572)
		(drill 0.2032)
		(layers "F.Cu" "B.Cu")
		(net "M_B_MA<10>")
	)
	(via
		(at 267.800074 -11.918188)
		(size 0.4572)
		(drill 0.2032)
		(layers "F.Cu" "B.Cu")
		(net "M_B_MA<10>")
	)
	(via
		(at 258.79171 -55.094886)
		(size 0.508)
		(drill 0.254)
		(layers "F.Cu" "B.Cu")
		(net "M_B_MA<10>")
	)
	(segment
		(start 267.800328 -10.623042)
		(end 267.79982 -10.623042)
		(width 0.1651)
		(layer "B.Cu")
		(net "M_B_MA<10>")
	)
	(segment
		(start 267.79982 -10.623042)
		(end 267.79982 -11.917934)
		(width 0.1651)
		(layer "B.Cu")
		(net "M_B_MA<10>")
	)
	(segment
		(start 267.79982 -11.917934)
		(end 267.800074 -11.918188)
		(width 0.1651)
		(layer "B.Cu")
		(net "M_B_MA<10>")
	)
	(segment
		(start 267.800074 -11.52779)
		(end 268.3764 -10.951464)
		(width 0.14224)
		(layer "In11.Cu")
		(net "M_B_MA<10>")
	)
	(segment
		(start 267.081 -13.2588)
		(end 266.954 -13.2588)
		(width 0.14224)
		(layer "In11.Cu")
		(net "M_B_MA<10>")
	)
	(segment
		(start 260.534404 -30.720792)
		(end 260.534404 -50.02022)
		(width 0.14224)
		(layer "In11.Cu")
		(net "M_B_MA<10>")
	)
	(segment
		(start 262.654288 -20.0914)
		(end 262.2042 -20.541488)
		(width 0.14224)
		(layer "In11.Cu")
		(net "M_B_MA<10>")
	)
	(segment
		(start 264.472928 -19.967448)
		(end 264.25398 -19.967448)
		(width 0.14224)
		(layer "In11.Cu")
		(net "M_B_MA<10>")
	)
	(segment
		(start 267.800074 -11.918188)
		(end 267.79982 -11.918442)
		(width 0.14224)
		(layer "In11.Cu")
		(net "M_B_MA<10>")
	)
	(segment
		(start 267.800074 -11.918188)
		(end 267.800074 -11.52779)
		(width 0.14224)
		(layer "In11.Cu")
		(net "M_B_MA<10>")
	)
	(segment
		(start 264.722864 -19.717512)
		(end 264.472928 -19.967448)
		(width 0.14224)
		(layer "In11.Cu")
		(net "M_B_MA<10>")
	)
	(segment
		(start 259.23875 -51.582574)
		(end 259.23875 -54.17312)
		(width 0.0889)
		(layer "In11.Cu")
		(net "M_B_MA<10>")
	)
	(segment
		(start 264.7696 -18.950432)
		(end 264.58164 -19.138392)
		(width 0.14224)
		(layer "In11.Cu")
		(net "M_B_MA<10>")
	)
	(segment
		(start 268.3764 -10.951464)
		(end 268.3764 -9.709404)
		(width 0.14224)
		(layer "In11.Cu")
		(net "M_B_MA<10>")
	)
	(segment
		(start 263.893808 -19.826224)
		(end 263.628632 -20.0914)
		(width 0.14224)
		(layer "In11.Cu")
		(net "M_B_MA<10>")
	)
	(segment
		(start 264.25398 -19.967448)
		(end 264.112756 -19.826224)
		(width 0.14224)
		(layer "In11.Cu")
		(net "M_B_MA<10>")
	)
	(segment
		(start 264.58164 -19.35734)
		(end 264.722864 -19.498564)
		(width 0.14224)
		(layer "In11.Cu")
		(net "M_B_MA<10>")
	)
	(segment
		(start 263.628632 -20.0914)
		(end 262.654288 -20.0914)
		(width 0.14224)
		(layer "In11.Cu")
		(net "M_B_MA<10>")
	)
	(segment
		(start 267.79982 -12.53998)
		(end 267.081 -13.2588)
		(width 0.14224)
		(layer "In11.Cu")
		(net "M_B_MA<10>")
	)
	(segment
		(start 259.23875 -54.17312)
		(end 258.79171 -55.094886)
		(width 0.0889)
		(layer "In11.Cu")
		(net "M_B_MA<10>")
	)
	(segment
		(start 260.534404 -50.02022)
		(end 260.534404 -50.28692)
		(width 0.0889)
		(layer "In11.Cu")
		(net "M_B_MA<10>")
	)
	(segment
		(start 262.2042 -20.541488)
		(end 262.2042 -29.050996)
		(width 0.14224)
		(layer "In11.Cu")
		(net "M_B_MA<10>")
	)
	(segment
		(start 267.79982 -11.918442)
		(end 267.79982 -12.53998)
		(width 0.14224)
		(layer "In11.Cu")
		(net "M_B_MA<10>")
	)
	(segment
		(start 266.514326 -14.884908)
		(end 264.7696 -16.629634)
		(width 0.14224)
		(layer "In11.Cu")
		(net "M_B_MA<10>")
	)
	(segment
		(start 266.954 -13.2588)
		(end 266.514326 -13.698474)
		(width 0.14224)
		(layer "In11.Cu")
		(net "M_B_MA<10>")
	)
	(segment
		(start 266.514326 -13.698474)
		(end 266.514326 -14.884908)
		(width 0.14224)
		(layer "In11.Cu")
		(net "M_B_MA<10>")
	)
	(segment
		(start 264.112756 -19.826224)
		(end 263.893808 -19.826224)
		(width 0.14224)
		(layer "In11.Cu")
		(net "M_B_MA<10>")
	)
	(segment
		(start 268.3764 -9.709404)
		(end 267.800074 -9.133078)
		(width 0.14224)
		(layer "In11.Cu")
		(net "M_B_MA<10>")
	)
	(segment
		(start 260.534404 -50.28692)
		(end 259.23875 -51.582574)
		(width 0.0889)
		(layer "In11.Cu")
		(net "M_B_MA<10>")
	)
	(segment
		(start 264.58164 -19.138392)
		(end 264.58164 -19.35734)
		(width 0.14224)
		(layer "In11.Cu")
		(net "M_B_MA<10>")
	)
	(segment
		(start 262.2042 -29.050996)
		(end 260.534404 -30.720792)
		(width 0.14224)
		(layer "In11.Cu")
		(net "M_B_MA<10>")
	)
	(segment
		(start 264.7696 -16.629634)
		(end 264.7696 -18.950432)
		(width 0.14224)
		(layer "In11.Cu")
		(net "M_B_MA<10>")
	)
	(segment
		(start 264.722864 -19.498564)
		(end 264.722864 -19.717512)
		(width 0.14224)
		(layer "In11.Cu")
		(net "M_B_MA<10>")
	)
	(segment
		(start 261.62 -53.29047)
		(end 261.62 -52.871116)
		(width 0.0889)
		(layer "F.Cu")
		(net "M_B_MA<0>")
	)
	(segment
		(start 261.93877 -53.60924)
		(end 261.62 -53.29047)
		(width 0.0889)
		(layer "F.Cu")
		(net "M_B_MA<0>")
	)
	(segment
		(start 266.099798 -5.822442)
		(end 266.099798 -7.113778)
		(width 0.1651)
		(layer "F.Cu")
		(net "M_B_MA<0>")
	)
	(segment
		(start 266.100306 -5.822442)
		(end 266.099798 -5.822442)
		(width 0.1651)
		(layer "F.Cu")
		(net "M_B_MA<0>")
	)
	(segment
		(start 261.62 -52.871116)
		(end 261.36727 -52.618386)
		(width 0.0889)
		(layer "F.Cu")
		(net "M_B_MA<0>")
	)
	(via
		(at 261.36727 -52.618386)
		(size 0.508)
		(drill 0.254)
		(layers "F.Cu" "B.Cu")
		(net "M_B_MA<0>")
	)
	(via
		(at 266.099798 -7.113778)
		(size 0.508)
		(drill 0.254)
		(layers "F.Cu" "B.Cu")
		(net "M_B_MA<0>")
	)
	(via
		(at 266.099798 -13.929868)
		(size 0.4572)
		(drill 0.2032)
		(layers "F.Cu" "B.Cu")
		(net "M_B_MA<0>")
	)
	(segment
		(start 266.099798 -15.222982)
		(end 266.099798 -13.929868)
		(width 0.1651)
		(layer "B.Cu")
		(net "M_B_MA<0>")
	)
	(segment
		(start 266.100306 -15.222982)
		(end 266.099798 -15.222982)
		(width 0.1651)
		(layer "B.Cu")
		(net "M_B_MA<0>")
	)
	(segment
		(start 266.099798 -13.929868)
		(end 266.099798 -14.672564)
		(width 0.14224)
		(layer "In4.Cu")
		(net "M_B_MA<0>")
	)
	(segment
		(start 265.742674 -22.394672)
		(end 265.4554 -22.681946)
		(width 0.14224)
		(layer "In4.Cu")
		(net "M_B_MA<0>")
	)
	(segment
		(start 266.53744 -12.148312)
		(end 266.099798 -12.585954)
		(width 0.14224)
		(layer "In4.Cu")
		(net "M_B_MA<0>")
	)
	(segment
		(start 265.96213 -17.277842)
		(end 265.96213 -18.016728)
		(width 0.14224)
		(layer "In4.Cu")
		(net "M_B_MA<0>")
	)
	(segment
		(start 262.570976 -49.732692)
		(end 262.570976 -50.174144)
		(width 0.0889)
		(layer "In4.Cu")
		(net "M_B_MA<0>")
	)
	(segment
		(start 264.7188 -14.942058)
		(end 264.5156 -15.145258)
		(width 0.14224)
		(layer "In4.Cu")
		(net "M_B_MA<0>")
	)
	(segment
		(start 265.427968 -18.55089)
		(end 265.427968 -19.355308)
		(width 0.14224)
		(layer "In4.Cu")
		(net "M_B_MA<0>")
	)
	(segment
		(start 264.213594 -24.78913)
		(end 264.213594 -25.089358)
		(width 0.14224)
		(layer "In4.Cu")
		(net "M_B_MA<0>")
	)
	(segment
		(start 265.051286 -24.777446)
		(end 264.788396 -24.514556)
		(width 0.14224)
		(layer "In4.Cu")
		(net "M_B_MA<0>")
	)
	(segment
		(start 263.030208 -26.20518)
		(end 263.458452 -26.633424)
		(width 0.14224)
		(layer "In4.Cu")
		(net "M_B_MA<0>")
	)
	(segment
		(start 263.951974 -25.977342)
		(end 263.681464 -25.706832)
		(width 0.14224)
		(layer "In4.Cu")
		(net "M_B_MA<0>")
	)
	(segment
		(start 263.458452 -26.867612)
		(end 262.570976 -27.755088)
		(width 0.14224)
		(layer "In4.Cu")
		(net "M_B_MA<0>")
	)
	(segment
		(start 265.6078 -16.923512)
		(end 265.96213 -17.277842)
		(width 0.14224)
		(layer "In4.Cu")
		(net "M_B_MA<0>")
	)
	(segment
		(start 264.7188 -15.754858)
		(end 265.437112 -15.754858)
		(width 0.14224)
		(layer "In4.Cu")
		(net "M_B_MA<0>")
	)
	(segment
		(start 264.239502 -25.977342)
		(end 263.951974 -25.977342)
		(width 0.14224)
		(layer "In4.Cu")
		(net "M_B_MA<0>")
	)
	(segment
		(start 265.6078 -15.925546)
		(end 265.6078 -16.923512)
		(width 0.14224)
		(layer "In4.Cu")
		(net "M_B_MA<0>")
	)
	(segment
		(start 264.526776 -25.690068)
		(end 264.239502 -25.977342)
		(width 0.14224)
		(layer "In4.Cu")
		(net "M_B_MA<0>")
	)
	(segment
		(start 264.5156 -15.145258)
		(end 264.5156 -15.551658)
		(width 0.14224)
		(layer "In4.Cu")
		(net "M_B_MA<0>")
	)
	(segment
		(start 264.213594 -25.089358)
		(end 264.526776 -25.40254)
		(width 0.14224)
		(layer "In4.Cu")
		(net "M_B_MA<0>")
	)
	(segment
		(start 263.317482 -25.706832)
		(end 263.030208 -25.994106)
		(width 0.14224)
		(layer "In4.Cu")
		(net "M_B_MA<0>")
	)
	(segment
		(start 266.099798 -14.672564)
		(end 265.830304 -14.942058)
		(width 0.14224)
		(layer "In4.Cu")
		(net "M_B_MA<0>")
	)
	(segment
		(start 265.4554 -22.681946)
		(end 265.4554 -24.611838)
		(width 0.14224)
		(layer "In4.Cu")
		(net "M_B_MA<0>")
	)
	(segment
		(start 265.830304 -14.942058)
		(end 264.7188 -14.942058)
		(width 0.14224)
		(layer "In4.Cu")
		(net "M_B_MA<0>")
	)
	(segment
		(start 263.030208 -25.994106)
		(end 263.030208 -26.20518)
		(width 0.14224)
		(layer "In4.Cu")
		(net "M_B_MA<0>")
	)
	(segment
		(start 265.289792 -24.777446)
		(end 265.051286 -24.777446)
		(width 0.14224)
		(layer "In4.Cu")
		(net "M_B_MA<0>")
	)
	(segment
		(start 266.099798 -7.113778)
		(end 266.099798 -7.679944)
		(width 0.14224)
		(layer "In4.Cu")
		(net "M_B_MA<0>")
	)
	(segment
		(start 266.300458 -13.729208)
		(end 266.099798 -13.929868)
		(width 0.14224)
		(layer "In4.Cu")
		(net "M_B_MA<0>")
	)
	(segment
		(start 265.57097 -21.85797)
		(end 265.742674 -22.029674)
		(width 0.14224)
		(layer "In4.Cu")
		(net "M_B_MA<0>")
	)
	(segment
		(start 266.300458 -13.450316)
		(end 266.300458 -13.729208)
		(width 0.14224)
		(layer "In4.Cu")
		(net "M_B_MA<0>")
	)
	(segment
		(start 264.5156 -15.551658)
		(end 264.7188 -15.754858)
		(width 0.14224)
		(layer "In4.Cu")
		(net "M_B_MA<0>")
	)
	(segment
		(start 266.099798 -13.249656)
		(end 266.300458 -13.450316)
		(width 0.14224)
		(layer "In4.Cu")
		(net "M_B_MA<0>")
	)
	(segment
		(start 265.822684 -19.750024)
		(end 265.822684 -21.118576)
		(width 0.14224)
		(layer "In4.Cu")
		(net "M_B_MA<0>")
	)
	(segment
		(start 265.822684 -21.118576)
		(end 265.57097 -21.37029)
		(width 0.14224)
		(layer "In4.Cu")
		(net "M_B_MA<0>")
	)
	(segment
		(start 262.570976 -50.174144)
		(end 261.36727 -51.37785)
		(width 0.0889)
		(layer "In4.Cu")
		(net "M_B_MA<0>")
	)
	(segment
		(start 265.96213 -18.016728)
		(end 265.427968 -18.55089)
		(width 0.14224)
		(layer "In4.Cu")
		(net "M_B_MA<0>")
	)
	(segment
		(start 262.570976 -27.755088)
		(end 262.570976 -49.732692)
		(width 0.14224)
		(layer "In4.Cu")
		(net "M_B_MA<0>")
	)
	(segment
		(start 264.526776 -25.40254)
		(end 264.526776 -25.690068)
		(width 0.14224)
		(layer "In4.Cu")
		(net "M_B_MA<0>")
	)
	(segment
		(start 263.681464 -25.706832)
		(end 263.317482 -25.706832)
		(width 0.14224)
		(layer "In4.Cu")
		(net "M_B_MA<0>")
	)
	(segment
		(start 261.36727 -51.37785)
		(end 261.36727 -52.618386)
		(width 0.0889)
		(layer "In4.Cu")
		(net "M_B_MA<0>")
	)
	(segment
		(start 265.4554 -24.611838)
		(end 265.289792 -24.777446)
		(width 0.14224)
		(layer "In4.Cu")
		(net "M_B_MA<0>")
	)
	(segment
		(start 264.488168 -24.514556)
		(end 264.213594 -24.78913)
		(width 0.14224)
		(layer "In4.Cu")
		(net "M_B_MA<0>")
	)
	(segment
		(start 266.099798 -12.585954)
		(end 266.099798 -13.249656)
		(width 0.14224)
		(layer "In4.Cu")
		(net "M_B_MA<0>")
	)
	(segment
		(start 266.53744 -8.117586)
		(end 266.53744 -12.148312)
		(width 0.14224)
		(layer "In4.Cu")
		(net "M_B_MA<0>")
	)
	(segment
		(start 265.742674 -22.029674)
		(end 265.742674 -22.394672)
		(width 0.14224)
		(layer "In4.Cu")
		(net "M_B_MA<0>")
	)
	(segment
		(start 263.458452 -26.633424)
		(end 263.458452 -26.867612)
		(width 0.14224)
		(layer "In4.Cu")
		(net "M_B_MA<0>")
	)
	(segment
		(start 265.437112 -15.754858)
		(end 265.6078 -15.925546)
		(width 0.14224)
		(layer "In4.Cu")
		(net "M_B_MA<0>")
	)
	(segment
		(start 264.788396 -24.514556)
		(end 264.488168 -24.514556)
		(width 0.14224)
		(layer "In4.Cu")
		(net "M_B_MA<0>")
	)
	(segment
		(start 266.099798 -7.679944)
		(end 266.53744 -8.117586)
		(width 0.14224)
		(layer "In4.Cu")
		(net "M_B_MA<0>")
	)
	(segment
		(start 265.57097 -21.37029)
		(end 265.57097 -21.85797)
		(width 0.14224)
		(layer "In4.Cu")
		(net "M_B_MA<0>")
	)
	(segment
		(start 265.427968 -19.355308)
		(end 265.822684 -19.750024)
		(width 0.14224)
		(layer "In4.Cu")
		(net "M_B_MA<0>")
	)
	(segment
		(start 244.4369 -34.3281)
		(end 244.4369 -36.8681)
		(width 0.1651)
		(layer "F.Cu")
		(net "M_B_ECC<7>")
	)
	(segment
		(start 249.655076 -50.99812)
		(end 249.655076 -51.260502)
		(width 0.0889)
		(layer "F.Cu")
		(net "M_B_ECC<7>")
	)
	(segment
		(start 249.51944 -52.554378)
		(end 249.51944 -52.618132)
		(width 0.0889)
		(layer "F.Cu")
		(net "M_B_ECC<7>")
	)
	(segment
		(start 249.462798 -50.073814)
		(end 249.462798 -50.5333)
		(width 0.0889)
		(layer "F.Cu")
		(net "M_B_ECC<7>")
	)
	(segment
		(start 242.979448 -30.894528)
		(end 242.736878 -31.137098)
		(width 0.1651)
		(layer "F.Cu")
		(net "M_B_ECC<7>")
	)
	(segment
		(start 249.54103 -51.458114)
		(end 249.54103 -51.745134)
		(width 0.0889)
		(layer "F.Cu")
		(net "M_B_ECC<7>")
	)
	(segment
		(start 242.979448 -30.660848)
		(end 242.979448 -30.894528)
		(width 0.1651)
		(layer "F.Cu")
		(net "M_B_ECC<7>")
	)
	(segment
		(start 239.750346 -5.822442)
		(end 239.749838 -5.822442)
		(width 0.1651)
		(layer "F.Cu")
		(net "M_B_ECC<7>")
	)
	(segment
		(start 243.286026 -41.653968)
		(end 244.454172 -42.822114)
		(width 0.1016)
		(layer "F.Cu")
		(net "M_B_ECC<7>")
	)
	(segment
		(start 249.462798 -50.5333)
		(end 249.655076 -50.99812)
		(width 0.0889)
		(layer "F.Cu")
		(net "M_B_ECC<7>")
	)
	(segment
		(start 239.916716 -26.691336)
		(end 239.79632 -26.811732)
		(width 0.1651)
		(layer "F.Cu")
		(net "M_B_ECC<7>")
	)
	(segment
		(start 239.749838 -5.822442)
		(end 239.749838 -7.086346)
		(width 0.1651)
		(layer "F.Cu")
		(net "M_B_ECC<7>")
	)
	(segment
		(start 242.736878 -31.137098)
		(end 242.736878 -31.370778)
		(width 0.1651)
		(layer "F.Cu")
		(net "M_B_ECC<7>")
	)
	(segment
		(start 242.736878 -31.370778)
		(end 243.1669 -31.8008)
		(width 0.1651)
		(layer "F.Cu")
		(net "M_B_ECC<7>")
	)
	(segment
		(start 242.3668 -38.0238)
		(end 242.3668 -41.364916)
		(width 0.1651)
		(layer "F.Cu")
		(net "M_B_ECC<7>")
	)
	(segment
		(start 242.503452 -30.418532)
		(end 242.737132 -30.418532)
		(width 0.1651)
		(layer "F.Cu")
		(net "M_B_ECC<7>")
	)
	(segment
		(start 243.1669 -33.0581)
		(end 244.4369 -34.3281)
		(width 0.1651)
		(layer "F.Cu")
		(net "M_B_ECC<7>")
	)
	(segment
		(start 240.599722 -26.691336)
		(end 239.916716 -26.691336)
		(width 0.1651)
		(layer "F.Cu")
		(net "M_B_ECC<7>")
	)
	(segment
		(start 244.454172 -42.822114)
		(end 244.667532 -42.822114)
		(width 0.1016)
		(layer "F.Cu")
		(net "M_B_ECC<7>")
	)
	(segment
		(start 249.407934 -54.304438)
		(end 249.39117 -54.33314)
		(width 0.0889)
		(layer "F.Cu")
		(net "M_B_ECC<7>")
	)
	(segment
		(start 249.631962 -51.902614)
		(end 249.631962 -52.360576)
		(width 0.0889)
		(layer "F.Cu")
		(net "M_B_ECC<7>")
	)
	(segment
		(start 241.784886 -29.974286)
		(end 241.784886 -30.418786)
		(width 0.1651)
		(layer "F.Cu")
		(net "M_B_ECC<7>")
	)
	(segment
		(start 240.5888 -29.2227)
		(end 241.07521 -29.70911)
		(width 0.1651)
		(layer "F.Cu")
		(net "M_B_ECC<7>")
	)
	(segment
		(start 249.54103 -51.745134)
		(end 249.631962 -51.902614)
		(width 0.0889)
		(layer "F.Cu")
		(net "M_B_ECC<7>")
	)
	(segment
		(start 242.9764 -37.4142)
		(end 242.3668 -38.0238)
		(width 0.1651)
		(layer "F.Cu")
		(net "M_B_ECC<7>")
	)
	(segment
		(start 242.737132 -30.418532)
		(end 242.979448 -30.660848)
		(width 0.1651)
		(layer "F.Cu")
		(net "M_B_ECC<7>")
	)
	(segment
		(start 242.561364 -41.55948)
		(end 242.655852 -41.653968)
		(width 0.1016)
		(layer "F.Cu")
		(net "M_B_ECC<7>")
	)
	(segment
		(start 244.667532 -42.822114)
		(end 249.462798 -47.61738)
		(width 0.1016)
		(layer "F.Cu")
		(net "M_B_ECC<7>")
	)
	(segment
		(start 242.3668 -41.364916)
		(end 242.561364 -41.55948)
		(width 0.1651)
		(layer "F.Cu")
		(net "M_B_ECC<7>")
	)
	(segment
		(start 249.407934 -53.904388)
		(end 249.41276 -53.913024)
		(width 0.0889)
		(layer "F.Cu")
		(net "M_B_ECC<7>")
	)
	(segment
		(start 243.1669 -31.8008)
		(end 243.1669 -33.0581)
		(width 0.1651)
		(layer "F.Cu")
		(net "M_B_ECC<7>")
	)
	(segment
		(start 242.655852 -41.653968)
		(end 243.286026 -41.653968)
		(width 0.1016)
		(layer "F.Cu")
		(net "M_B_ECC<7>")
	)
	(segment
		(start 249.655076 -51.260502)
		(end 249.54103 -51.458114)
		(width 0.0889)
		(layer "F.Cu")
		(net "M_B_ECC<7>")
	)
	(segment
		(start 241.07521 -29.70911)
		(end 241.51971 -29.70911)
		(width 0.1651)
		(layer "F.Cu")
		(net "M_B_ECC<7>")
	)
	(segment
		(start 241.784886 -30.418786)
		(end 242.027202 -30.661102)
		(width 0.1651)
		(layer "F.Cu")
		(net "M_B_ECC<7>")
	)
	(segment
		(start 239.79632 -27.29992)
		(end 240.5888 -28.0924)
		(width 0.1651)
		(layer "F.Cu")
		(net "M_B_ECC<7>")
	)
	(segment
		(start 249.631962 -52.360576)
		(end 249.51944 -52.554378)
		(width 0.0889)
		(layer "F.Cu")
		(net "M_B_ECC<7>")
	)
	(segment
		(start 239.79632 -26.811732)
		(end 239.79632 -27.29992)
		(width 0.1651)
		(layer "F.Cu")
		(net "M_B_ECC<7>")
	)
	(segment
		(start 242.027202 -30.661102)
		(end 242.260882 -30.661102)
		(width 0.1651)
		(layer "F.Cu")
		(net "M_B_ECC<7>")
	)
	(segment
		(start 242.260882 -30.661102)
		(end 242.503452 -30.418532)
		(width 0.1651)
		(layer "F.Cu")
		(net "M_B_ECC<7>")
	)
	(segment
		(start 249.39117 -54.33314)
		(end 249.061224 -55.094886)
		(width 0.0889)
		(layer "F.Cu")
		(net "M_B_ECC<7>")
	)
	(segment
		(start 249.462798 -47.61738)
		(end 249.462798 -50.073814)
		(width 0.1016)
		(layer "F.Cu")
		(net "M_B_ECC<7>")
	)
	(segment
		(start 243.8908 -37.4142)
		(end 242.9764 -37.4142)
		(width 0.1651)
		(layer "F.Cu")
		(net "M_B_ECC<7>")
	)
	(segment
		(start 249.573034 -53.409088)
		(end 249.407934 -53.701696)
		(width 0.0889)
		(layer "F.Cu")
		(net "M_B_ECC<7>")
	)
	(segment
		(start 241.51971 -29.70911)
		(end 241.784886 -29.974286)
		(width 0.1651)
		(layer "F.Cu")
		(net "M_B_ECC<7>")
	)
	(segment
		(start 244.4369 -36.8681)
		(end 243.8908 -37.4142)
		(width 0.1651)
		(layer "F.Cu")
		(net "M_B_ECC<7>")
	)
	(segment
		(start 240.5888 -28.0924)
		(end 240.5888 -29.2227)
		(width 0.1651)
		(layer "F.Cu")
		(net "M_B_ECC<7>")
	)
	(segment
		(start 249.407934 -53.701696)
		(end 249.407934 -53.904388)
		(width 0.0889)
		(layer "F.Cu")
		(net "M_B_ECC<7>")
	)
	(via
		(at 240.599722 -26.691336)
		(size 0.508)
		(drill 0.254)
		(layers "F.Cu" "B.Cu")
		(net "M_B_ECC<7>")
	)
	(via
		(at 240.599722 -12.678156)
		(size 0.508)
		(drill 0.254)
		(layers "F.Cu" "B.Cu")
		(net "M_B_ECC<7>")
	)
	(via
		(at 239.749838 -7.086346)
		(size 0.508)
		(drill 0.254)
		(layers "F.Cu" "B.Cu")
		(net "M_B_ECC<7>")
	)
	(arc
		(start 249.41276 -53.913024)
		(mid 249.461515 -54.109376)
		(end 249.407934 -54.304438)
		(width 0.0889)
		(layer "F.Cu")
		(net "M_B_ECC<7>")
	)
	(arc
		(start 249.51944 -52.618132)
		(mid 249.533078 -52.721729)
		(end 249.573034 -52.818284)
		(width 0.0889)
		(layer "F.Cu")
		(net "M_B_ECC<7>")
	)
	(arc
		(start 249.573034 -52.818284)
		(mid 249.652165 -53.113686)
		(end 249.573034 -53.409088)
		(width 0.0889)
		(layer "F.Cu")
		(net "M_B_ECC<7>")
	)
	(segment
		(start 240.599976 -10.623042)
		(end 240.599976 -11.110722)
		(width 0.1651)
		(layer "B.Cu")
		(net "M_B_ECC<7>")
	)
	(segment
		(start 240.600484 -10.623042)
		(end 240.599976 -10.623042)
		(width 0.1651)
		(layer "B.Cu")
		(net "M_B_ECC<7>")
	)
	(segment
		(start 240.599976 -11.110722)
		(end 240.599722 -11.110976)
		(width 0.1651)
		(layer "B.Cu")
		(net "M_B_ECC<7>")
	)
	(segment
		(start 240.599722 -11.110976)
		(end 240.599722 -12.678156)
		(width 0.1651)
		(layer "B.Cu")
		(net "M_B_ECC<7>")
	)
	(segment
		(start 240.988596 -21.317204)
		(end 240.988596 -21.862796)
		(width 0.14224)
		(layer "In11.Cu")
		(net "M_B_ECC<7>")
	)
	(segment
		(start 240.952528 -9.020048)
		(end 240.952528 -12.32535)
		(width 0.14224)
		(layer "In11.Cu")
		(net "M_B_ECC<7>")
	)
	(segment
		(start 240.963196 -26.327862)
		(end 240.599722 -26.691336)
		(width 0.14224)
		(layer "In11.Cu")
		(net "M_B_ECC<7>")
	)
	(segment
		(start 240.963196 -23.294848)
		(end 240.963196 -26.327862)
		(width 0.14224)
		(layer "In11.Cu")
		(net "M_B_ECC<7>")
	)
	(segment
		(start 240.952528 -12.32535)
		(end 240.599722 -12.678156)
		(width 0.14224)
		(layer "In11.Cu")
		(net "M_B_ECC<7>")
	)
	(segment
		(start 240.396776 -8.0518)
		(end 240.650776 -8.0518)
		(width 0.14224)
		(layer "In11.Cu")
		(net "M_B_ECC<7>")
	)
	(segment
		(start 241.115596 -17.032986)
		(end 241.115596 -18.328386)
		(width 0.14224)
		(layer "In11.Cu")
		(net "M_B_ECC<7>")
	)
	(segment
		(start 240.599722 -12.678156)
		(end 240.166652 -13.111226)
		(width 0.14224)
		(layer "In11.Cu")
		(net "M_B_ECC<7>")
	)
	(segment
		(start 241.0714 -19.2024)
		(end 241.0714 -21.2344)
		(width 0.14224)
		(layer "In11.Cu")
		(net "M_B_ECC<7>")
	)
	(segment
		(start 240.166652 -13.111226)
		(end 240.166652 -13.543534)
		(width 0.14224)
		(layer "In11.Cu")
		(net "M_B_ECC<7>")
	)
	(segment
		(start 241.0714 -21.2344)
		(end 240.988596 -21.317204)
		(width 0.14224)
		(layer "In11.Cu")
		(net "M_B_ECC<7>")
	)
	(segment
		(start 240.810796 -14.187678)
		(end 240.810796 -16.728186)
		(width 0.14224)
		(layer "In11.Cu")
		(net "M_B_ECC<7>")
	)
	(segment
		(start 241.140996 -22.015196)
		(end 241.140996 -23.117048)
		(width 0.14224)
		(layer "In11.Cu")
		(net "M_B_ECC<7>")
	)
	(segment
		(start 241.107976 -8.8646)
		(end 240.952528 -9.020048)
		(width 0.14224)
		(layer "In11.Cu")
		(net "M_B_ECC<7>")
	)
	(segment
		(start 240.810796 -16.728186)
		(end 241.115596 -17.032986)
		(width 0.14224)
		(layer "In11.Cu")
		(net "M_B_ECC<7>")
	)
	(segment
		(start 241.115596 -18.328386)
		(end 240.988596 -18.455386)
		(width 0.14224)
		(layer "In11.Cu")
		(net "M_B_ECC<7>")
	)
	(segment
		(start 241.107976 -8.509)
		(end 241.107976 -8.8646)
		(width 0.14224)
		(layer "In11.Cu")
		(net "M_B_ECC<7>")
	)
	(segment
		(start 240.988596 -21.862796)
		(end 241.140996 -22.015196)
		(width 0.14224)
		(layer "In11.Cu")
		(net "M_B_ECC<7>")
	)
	(segment
		(start 240.988596 -18.455386)
		(end 240.988596 -19.119596)
		(width 0.14224)
		(layer "In11.Cu")
		(net "M_B_ECC<7>")
	)
	(segment
		(start 239.749838 -7.086346)
		(end 240.066576 -7.403084)
		(width 0.14224)
		(layer "In11.Cu")
		(net "M_B_ECC<7>")
	)
	(segment
		(start 240.650776 -8.0518)
		(end 241.107976 -8.509)
		(width 0.14224)
		(layer "In11.Cu")
		(net "M_B_ECC<7>")
	)
	(segment
		(start 241.140996 -23.117048)
		(end 240.963196 -23.294848)
		(width 0.14224)
		(layer "In11.Cu")
		(net "M_B_ECC<7>")
	)
	(segment
		(start 240.066576 -7.403084)
		(end 240.066576 -7.7216)
		(width 0.14224)
		(layer "In11.Cu")
		(net "M_B_ECC<7>")
	)
	(segment
		(start 240.066576 -7.7216)
		(end 240.396776 -8.0518)
		(width 0.14224)
		(layer "In11.Cu")
		(net "M_B_ECC<7>")
	)
	(segment
		(start 240.988596 -19.119596)
		(end 241.0714 -19.2024)
		(width 0.14224)
		(layer "In11.Cu")
		(net "M_B_ECC<7>")
	)
	(segment
		(start 240.166652 -13.543534)
		(end 240.810796 -14.187678)
		(width 0.14224)
		(layer "In11.Cu")
		(net "M_B_ECC<7>")
	)
	(segment
		(start 249.157998 -50.073814)
		(end 249.157998 -47.743872)
		(width 0.1016)
		(layer "F.Cu")
		(net "M_B_ECC<6>")
	)
	(segment
		(start 243.586 -34.4678)
		(end 243.2431 -34.4678)
		(width 0.1651)
		(layer "F.Cu")
		(net "M_B_ECC<6>")
	)
	(segment
		(start 249.328686 -52.617624)
		(end 249.328686 -52.497482)
		(width 0.0889)
		(layer "F.Cu")
		(net "M_B_ECC<6>")
	)
	(segment
		(start 242.4049 -32.004)
		(end 241.59845 -31.19755)
		(width 0.1651)
		(layer "F.Cu")
		(net "M_B_ECC<6>")
	)
	(segment
		(start 242.4049 -35.7632)
		(end 242.4049 -32.004)
		(width 0.1651)
		(layer "F.Cu")
		(net "M_B_ECC<6>")
	)
	(segment
		(start 243.078 -34.6329)
		(end 243.078 -35.7632)
		(width 0.1651)
		(layer "F.Cu")
		(net "M_B_ECC<6>")
	)
	(segment
		(start 249.1486 -53.381656)
		(end 249.257058 -53.412644)
		(width 0.0889)
		(layer "F.Cu")
		(net "M_B_ECC<6>")
	)
	(segment
		(start 242.5319 -35.8902)
		(end 242.4049 -35.7632)
		(width 0.1651)
		(layer "F.Cu")
		(net "M_B_ECC<6>")
	)
	(segment
		(start 243.6241 -36.703)
		(end 243.7511 -36.576)
		(width 0.1651)
		(layer "F.Cu")
		(net "M_B_ECC<6>")
	)
	(segment
		(start 249.441462 -51.953922)
		(end 249.35053 -51.796442)
		(width 0.0889)
		(layer "F.Cu")
		(net "M_B_ECC<6>")
	)
	(segment
		(start 243.122958 -42.047668)
		(end 242.137438 -42.047668)
		(width 0.1016)
		(layer "F.Cu")
		(net "M_B_ECC<6>")
	)
	(segment
		(start 242.951 -35.8902)
		(end 242.5319 -35.8902)
		(width 0.1651)
		(layer "F.Cu")
		(net "M_B_ECC<6>")
	)
	(segment
		(start 240.599976 -10.422382)
		(end 240.599976 -9.4488)
		(width 0.1651)
		(layer "F.Cu")
		(net "M_B_ECC<6>")
	)
	(segment
		(start 240.600484 -10.422382)
		(end 240.599976 -10.422382)
		(width 0.1651)
		(layer "F.Cu")
		(net "M_B_ECC<6>")
	)
	(segment
		(start 249.35053 -51.796442)
		(end 249.35053 -51.40706)
		(width 0.0889)
		(layer "F.Cu")
		(net "M_B_ECC<6>")
	)
	(segment
		(start 244.202204 -43.126914)
		(end 243.122958 -42.047668)
		(width 0.1016)
		(layer "F.Cu")
		(net "M_B_ECC<6>")
	)
	(segment
		(start 249.257058 -53.412644)
		(end 249.330464 -53.40096)
		(width 0.0889)
		(layer "F.Cu")
		(net "M_B_ECC<6>")
	)
	(segment
		(start 249.157998 -47.743872)
		(end 244.54104 -43.126914)
		(width 0.1016)
		(layer "F.Cu")
		(net "M_B_ECC<6>")
	)
	(segment
		(start 243.7511 -34.6329)
		(end 243.586 -34.4678)
		(width 0.1651)
		(layer "F.Cu")
		(net "M_B_ECC<6>")
	)
	(segment
		(start 241.6937 -37.655754)
		(end 242.646454 -36.703)
		(width 0.1651)
		(layer "F.Cu")
		(net "M_B_ECC<6>")
	)
	(segment
		(start 249.35053 -51.40706)
		(end 249.464576 -51.209194)
		(width 0.0889)
		(layer "F.Cu")
		(net "M_B_ECC<6>")
	)
	(segment
		(start 240.599976 -8.661654)
		(end 240.599722 -8.6614)
		(width 0.1651)
		(layer "F.Cu")
		(net "M_B_ECC<6>")
	)
	(segment
		(start 240.599976 -9.4488)
		(end 240.732056 -9.31672)
		(width 0.1651)
		(layer "F.Cu")
		(net "M_B_ECC<6>")
	)
	(segment
		(start 249.328686 -52.497482)
		(end 249.441462 -52.302156)
		(width 0.0889)
		(layer "F.Cu")
		(net "M_B_ECC<6>")
	)
	(segment
		(start 249.441462 -52.302156)
		(end 249.441462 -51.953922)
		(width 0.0889)
		(layer "F.Cu")
		(net "M_B_ECC<6>")
	)
	(segment
		(start 239.902238 -29.501338)
		(end 239.902238 -28.175458)
		(width 0.1651)
		(layer "F.Cu")
		(net "M_B_ECC<6>")
	)
	(segment
		(start 241.6937 -41.60393)
		(end 241.6937 -37.655754)
		(width 0.1651)
		(layer "F.Cu")
		(net "M_B_ECC<6>")
	)
	(segment
		(start 242.137438 -42.047668)
		(end 242.027964 -41.938194)
		(width 0.1016)
		(layer "F.Cu")
		(net "M_B_ECC<6>")
	)
	(segment
		(start 243.7511 -36.576)
		(end 243.7511 -34.6329)
		(width 0.1651)
		(layer "F.Cu")
		(net "M_B_ECC<6>")
	)
	(segment
		(start 240.599976 -8.9662)
		(end 240.599976 -8.661654)
		(width 0.1651)
		(layer "F.Cu")
		(net "M_B_ECC<6>")
	)
	(segment
		(start 242.646454 -36.703)
		(end 243.6241 -36.703)
		(width 0.1651)
		(layer "F.Cu")
		(net "M_B_ECC<6>")
	)
	(segment
		(start 243.078 -35.7632)
		(end 242.951 -35.8902)
		(width 0.1651)
		(layer "F.Cu")
		(net "M_B_ECC<6>")
	)
	(segment
		(start 249.157998 -50.34661)
		(end 249.157998 -50.073814)
		(width 0.0889)
		(layer "F.Cu")
		(net "M_B_ECC<6>")
	)
	(segment
		(start 244.54104 -43.126914)
		(end 244.202204 -43.126914)
		(width 0.1016)
		(layer "F.Cu")
		(net "M_B_ECC<6>")
	)
	(segment
		(start 249.464576 -51.038506)
		(end 249.157998 -50.34661)
		(width 0.0889)
		(layer "F.Cu")
		(net "M_B_ECC<6>")
	)
	(segment
		(start 240.732056 -9.31672)
		(end 240.732056 -9.09828)
		(width 0.1651)
		(layer "F.Cu")
		(net "M_B_ECC<6>")
	)
	(segment
		(start 249.464576 -51.209194)
		(end 249.464576 -51.038506)
		(width 0.0889)
		(layer "F.Cu")
		(net "M_B_ECC<6>")
	)
	(segment
		(start 243.2431 -34.4678)
		(end 243.078 -34.6329)
		(width 0.1651)
		(layer "F.Cu")
		(net "M_B_ECC<6>")
	)
	(segment
		(start 240.732056 -9.09828)
		(end 240.599976 -8.9662)
		(width 0.1651)
		(layer "F.Cu")
		(net "M_B_ECC<6>")
	)
	(segment
		(start 241.59845 -31.19755)
		(end 239.902238 -29.501338)
		(width 0.1651)
		(layer "F.Cu")
		(net "M_B_ECC<6>")
	)
	(segment
		(start 242.027964 -41.938194)
		(end 241.6937 -41.60393)
		(width 0.1651)
		(layer "F.Cu")
		(net "M_B_ECC<6>")
	)
	(via
		(at 239.902238 -28.175458)
		(size 0.508)
		(drill 0.254)
		(layers "F.Cu" "B.Cu")
		(net "M_B_ECC<6>")
	)
	(via
		(at 240.599722 -8.6614)
		(size 0.508)
		(drill 0.254)
		(layers "F.Cu" "B.Cu")
		(net "M_B_ECC<6>")
	)
	(via
		(at 239.749838 -13.959078)
		(size 0.508)
		(drill 0.254)
		(layers "F.Cu" "B.Cu")
		(net "M_B_ECC<6>")
	)
	(via
		(at 241.59845 -31.19755)
		(size 0.508)
		(drill 0.254)
		(layers "F.Cu" "B.Cu")
		(net "M_B_ECC<6>")
	)
	(arc
		(start 249.407934 -52.914042)
		(mid 249.348735 -52.771066)
		(end 249.328686 -52.617624)
		(width 0.0889)
		(layer "F.Cu")
		(net "M_B_ECC<6>")
	)
	(arc
		(start 249.407934 -53.313838)
		(mid 249.461433 -53.11394)
		(end 249.407934 -52.914042)
		(width 0.0889)
		(layer "F.Cu")
		(net "M_B_ECC<6>")
	)
	(arc
		(start 249.061224 -53.113686)
		(mid 249.083667 -53.254595)
		(end 249.1486 -53.381656)
		(width 0.0889)
		(layer "F.Cu")
		(net "M_B_ECC<6>")
	)
	(arc
		(start 249.330464 -53.40096)
		(mid 249.373652 -53.361359)
		(end 249.407934 -53.313838)
		(width 0.0889)
		(layer "F.Cu")
		(net "M_B_ECC<6>")
	)
	(segment
		(start 239.749838 -15.222982)
		(end 239.749838 -13.959078)
		(width 0.1651)
		(layer "B.Cu")
		(net "M_B_ECC<6>")
	)
	(segment
		(start 239.750346 -15.222982)
		(end 239.749838 -15.222982)
		(width 0.1651)
		(layer "B.Cu")
		(net "M_B_ECC<6>")
	)
	(segment
		(start 240.599722 -8.6614)
		(end 240.193576 -9.067546)
		(width 0.14224)
		(layer "In11.Cu")
		(net "M_B_ECC<6>")
	)
	(segment
		(start 240.226596 -18.9992)
		(end 240.0808 -19.144996)
		(width 0.14224)
		(layer "In11.Cu")
		(net "M_B_ECC<6>")
	)
	(segment
		(start 240.193576 -9.067546)
		(end 240.193576 -12.4333)
		(width 0.14224)
		(layer "In11.Cu")
		(net "M_B_ECC<6>")
	)
	(segment
		(start 240.226596 -21.862796)
		(end 240.048796 -22.040596)
		(width 0.14224)
		(layer "In11.Cu")
		(net "M_B_ECC<6>")
	)
	(segment
		(start 240.328196 -26.194258)
		(end 240.099596 -26.422858)
		(width 0.14224)
		(layer "In11.Cu")
		(net "M_B_ECC<6>")
	)
	(segment
		(start 239.749838 -13.959078)
		(end 240.251996 -14.461236)
		(width 0.14224)
		(layer "In11.Cu")
		(net "M_B_ECC<6>")
	)
	(segment
		(start 240.0808 -19.144996)
		(end 240.0808 -21.1836)
		(width 0.14224)
		(layer "In11.Cu")
		(net "M_B_ECC<6>")
	)
	(segment
		(start 240.328196 -23.412196)
		(end 240.328196 -26.194258)
		(width 0.14224)
		(layer "In11.Cu")
		(net "M_B_ECC<6>")
	)
	(segment
		(start 240.251996 -16.842486)
		(end 240.048796 -17.045686)
		(width 0.14224)
		(layer "In11.Cu")
		(net "M_B_ECC<6>")
	)
	(segment
		(start 240.226596 -21.329396)
		(end 240.226596 -21.862796)
		(width 0.14224)
		(layer "In11.Cu")
		(net "M_B_ECC<6>")
	)
	(segment
		(start 240.251996 -14.461236)
		(end 240.251996 -16.842486)
		(width 0.14224)
		(layer "In11.Cu")
		(net "M_B_ECC<6>")
	)
	(segment
		(start 240.0808 -21.1836)
		(end 240.226596 -21.329396)
		(width 0.14224)
		(layer "In11.Cu")
		(net "M_B_ECC<6>")
	)
	(segment
		(start 240.048796 -17.045686)
		(end 240.048796 -18.33245)
		(width 0.14224)
		(layer "In11.Cu")
		(net "M_B_ECC<6>")
	)
	(segment
		(start 240.048796 -22.040596)
		(end 240.048796 -23.132796)
		(width 0.14224)
		(layer "In11.Cu")
		(net "M_B_ECC<6>")
	)
	(segment
		(start 240.048796 -23.132796)
		(end 240.328196 -23.412196)
		(width 0.14224)
		(layer "In11.Cu")
		(net "M_B_ECC<6>")
	)
	(segment
		(start 240.193576 -12.4333)
		(end 239.431576 -13.1953)
		(width 0.14224)
		(layer "In11.Cu")
		(net "M_B_ECC<6>")
	)
	(segment
		(start 240.099596 -27.9781)
		(end 239.902238 -28.175458)
		(width 0.14224)
		(layer "In11.Cu")
		(net "M_B_ECC<6>")
	)
	(segment
		(start 240.226596 -18.51025)
		(end 240.226596 -18.9992)
		(width 0.14224)
		(layer "In11.Cu")
		(net "M_B_ECC<6>")
	)
	(segment
		(start 240.048796 -18.33245)
		(end 240.226596 -18.51025)
		(width 0.14224)
		(layer "In11.Cu")
		(net "M_B_ECC<6>")
	)
	(segment
		(start 239.431576 -13.1953)
		(end 239.431576 -13.640816)
		(width 0.14224)
		(layer "In11.Cu")
		(net "M_B_ECC<6>")
	)
	(segment
		(start 240.099596 -26.422858)
		(end 240.099596 -27.9781)
		(width 0.14224)
		(layer "In11.Cu")
		(net "M_B_ECC<6>")
	)
	(segment
		(start 239.431576 -13.640816)
		(end 239.749838 -13.959078)
		(width 0.14224)
		(layer "In11.Cu")
		(net "M_B_ECC<6>")
	)
	(segment
		(start 235.9914 -34.925)
		(end 235.9914 -41.377108)
		(width 0.1651)
		(layer "F.Cu")
		(net "M_B_ECC<5>")
	)
	(segment
		(start 235.9914 -41.377108)
		(end 239.377474 -44.763182)
		(width 0.1651)
		(layer "F.Cu")
		(net "M_B_ECC<5>")
	)
	(segment
		(start 234.6198 -30.721554)
		(end 235.9914 -32.093154)
		(width 0.1651)
		(layer "F.Cu")
		(net "M_B_ECC<5>")
	)
	(segment
		(start 246.507254 -54.00929)
		(end 246.474488 -54.00929)
		(width 0.0889)
		(layer "F.Cu")
		(net "M_B_ECC<5>")
	)
	(segment
		(start 234.6198 -28.6258)
		(end 234.6198 -30.721554)
		(width 0.1651)
		(layer "F.Cu")
		(net "M_B_ECC<5>")
	)
	(segment
		(start 239.377474 -44.763182)
		(end 239.41786 -44.803568)
		(width 0.1016)
		(layer "F.Cu")
		(net "M_B_ECC<5>")
	)
	(segment
		(start 235.9914 -32.093154)
		(end 235.9914 -34.925)
		(width 0.1651)
		(layer "F.Cu")
		(net "M_B_ECC<5>")
	)
	(segment
		(start 234.573572 -27.250136)
		(end 234.004358 -27.250136)
		(width 0.1651)
		(layer "F.Cu")
		(net "M_B_ECC<5>")
	)
	(segment
		(start 241.979704 -44.803568)
		(end 242.43665 -45.260514)
		(width 0.1016)
		(layer "F.Cu")
		(net "M_B_ECC<5>")
	)
	(segment
		(start 233.800396 -5.822442)
		(end 233.799888 -5.822442)
		(width 0.1651)
		(layer "F.Cu")
		(net "M_B_ECC<5>")
	)
	(segment
		(start 246.881142 -51.510946)
		(end 246.881142 -51.695858)
		(width 0.0889)
		(layer "F.Cu")
		(net "M_B_ECC<5>")
	)
	(segment
		(start 233.799888 -5.822442)
		(end 233.799888 -7.086346)
		(width 0.1651)
		(layer "F.Cu")
		(net "M_B_ECC<5>")
	)
	(segment
		(start 233.839258 -27.845258)
		(end 234.6198 -28.6258)
		(width 0.1651)
		(layer "F.Cu")
		(net "M_B_ECC<5>")
	)
	(segment
		(start 247.344184 -55.094886)
		(end 247.014238 -54.33314)
		(width 0.0889)
		(layer "F.Cu")
		(net "M_B_ECC<5>")
	)
	(segment
		(start 247.024398 -48.629316)
		(end 247.024398 -50.073814)
		(width 0.1016)
		(layer "F.Cu")
		(net "M_B_ECC<5>")
	)
	(segment
		(start 246.881142 -51.695858)
		(end 246.752872 -51.917854)
		(width 0.0889)
		(layer "F.Cu")
		(net "M_B_ECC<5>")
	)
	(segment
		(start 246.712994 -53.140102)
		(end 246.59717 -53.20919)
		(width 0.0889)
		(layer "F.Cu")
		(net "M_B_ECC<5>")
	)
	(segment
		(start 246.8245 -52.412392)
		(end 246.868442 -52.495958)
		(width 0.0889)
		(layer "F.Cu")
		(net "M_B_ECC<5>")
	)
	(segment
		(start 239.41786 -44.803568)
		(end 241.979704 -44.803568)
		(width 0.1016)
		(layer "F.Cu")
		(net "M_B_ECC<5>")
	)
	(segment
		(start 247.024398 -50.073814)
		(end 247.024398 -50.498248)
		(width 0.0889)
		(layer "F.Cu")
		(net "M_B_ECC<5>")
	)
	(segment
		(start 246.75592 -51.29403)
		(end 246.881142 -51.510946)
		(width 0.0889)
		(layer "F.Cu")
		(net "M_B_ECC<5>")
	)
	(segment
		(start 242.43665 -45.260514)
		(end 243.655596 -45.260514)
		(width 0.1016)
		(layer "F.Cu")
		(net "M_B_ECC<5>")
	)
	(segment
		(start 233.839258 -27.415236)
		(end 233.839258 -27.845258)
		(width 0.1651)
		(layer "F.Cu")
		(net "M_B_ECC<5>")
	)
	(segment
		(start 246.75592 -50.963322)
		(end 246.75592 -51.29403)
		(width 0.0889)
		(layer "F.Cu")
		(net "M_B_ECC<5>")
	)
	(segment
		(start 246.752872 -51.917854)
		(end 246.752872 -52.124356)
		(width 0.0889)
		(layer "F.Cu")
		(net "M_B_ECC<5>")
	)
	(segment
		(start 246.59717 -53.20919)
		(end 246.470678 -53.20919)
		(width 0.0889)
		(layer "F.Cu")
		(net "M_B_ECC<5>")
	)
	(segment
		(start 247.024398 -50.498248)
		(end 246.75592 -50.963322)
		(width 0.0889)
		(layer "F.Cu")
		(net "M_B_ECC<5>")
	)
	(segment
		(start 243.655596 -45.260514)
		(end 247.024398 -48.629316)
		(width 0.1016)
		(layer "F.Cu")
		(net "M_B_ECC<5>")
	)
	(segment
		(start 246.7864 -52.926488)
		(end 246.712994 -53.140102)
		(width 0.0889)
		(layer "F.Cu")
		(net "M_B_ECC<5>")
	)
	(segment
		(start 234.004358 -27.250136)
		(end 233.839258 -27.415236)
		(width 0.1651)
		(layer "F.Cu")
		(net "M_B_ECC<5>")
	)
	(segment
		(start 247.014238 -54.33314)
		(end 246.997474 -54.304438)
		(width 0.0889)
		(layer "F.Cu")
		(net "M_B_ECC<5>")
	)
	(via
		(at 234.573572 -12.678156)
		(size 0.508)
		(drill 0.254)
		(layers "F.Cu" "B.Cu")
		(net "M_B_ECC<5>")
	)
	(via
		(at 234.573572 -27.250136)
		(size 0.508)
		(drill 0.254)
		(layers "F.Cu" "B.Cu")
		(net "M_B_ECC<5>")
	)
	(via
		(at 233.799888 -7.086346)
		(size 0.508)
		(drill 0.254)
		(layers "F.Cu" "B.Cu")
		(net "M_B_ECC<5>")
	)
	(via
		(at 235.9914 -34.925)
		(size 0.508)
		(drill 0.254)
		(layers "F.Cu" "B.Cu")
		(net "M_B_ECC<5>")
	)
	(arc
		(start 246.752872 -52.124356)
		(mid 246.771228 -52.272715)
		(end 246.8245 -52.412392)
		(width 0.0889)
		(layer "F.Cu")
		(net "M_B_ECC<5>")
	)
	(arc
		(start 246.474488 -54.00929)
		(mid 246.085462 -53.611144)
		(end 246.470678 -53.20919)
		(width 0.0889)
		(layer "F.Cu")
		(net "M_B_ECC<5>")
	)
	(arc
		(start 246.870474 -52.733194)
		(mid 246.823593 -52.827734)
		(end 246.7864 -52.926488)
		(width 0.0889)
		(layer "F.Cu")
		(net "M_B_ECC<5>")
	)
	(arc
		(start 246.997474 -54.304438)
		(mid 246.79047 -54.093574)
		(end 246.507254 -54.00929)
		(width 0.0889)
		(layer "F.Cu")
		(net "M_B_ECC<5>")
	)
	(arc
		(start 246.868442 -52.495958)
		(mid 246.891694 -52.556793)
		(end 246.899684 -52.621434)
		(width 0.0889)
		(layer "F.Cu")
		(net "M_B_ECC<5>")
	)
	(arc
		(start 246.899684 -52.621434)
		(mid 246.892274 -52.679198)
		(end 246.870474 -52.733194)
		(width 0.0889)
		(layer "F.Cu")
		(net "M_B_ECC<5>")
	)
	(segment
		(start 234.649772 -12.601956)
		(end 234.573572 -12.678156)
		(width 0.1651)
		(layer "B.Cu")
		(net "M_B_ECC<5>")
	)
	(segment
		(start 234.649772 -10.623042)
		(end 234.649772 -12.601956)
		(width 0.1651)
		(layer "B.Cu")
		(net "M_B_ECC<5>")
	)
	(segment
		(start 234.65028 -10.623042)
		(end 234.649772 -10.623042)
		(width 0.1651)
		(layer "B.Cu")
		(net "M_B_ECC<5>")
	)
	(segment
		(start 234.994196 -26.829512)
		(end 234.994196 -23.234396)
		(width 0.14224)
		(layer "In11.Cu")
		(net "M_B_ECC<5>")
	)
	(segment
		(start 235.081826 -8.452104)
		(end 234.681522 -8.0518)
		(width 0.14224)
		(layer "In11.Cu")
		(net "M_B_ECC<5>")
	)
	(segment
		(start 234.95 -14.097)
		(end 234.7468 -13.8938)
		(width 0.14224)
		(layer "In11.Cu")
		(net "M_B_ECC<5>")
	)
	(segment
		(start 234.681522 -8.0518)
		(end 234.370626 -8.0518)
		(width 0.14224)
		(layer "In11.Cu")
		(net "M_B_ECC<5>")
	)
	(segment
		(start 234.884976 -9.06145)
		(end 235.081826 -8.8646)
		(width 0.14224)
		(layer "In11.Cu")
		(net "M_B_ECC<5>")
	)
	(segment
		(start 234.968796 -21.862796)
		(end 234.968796 -21.3614)
		(width 0.14224)
		(layer "In11.Cu")
		(net "M_B_ECC<5>")
	)
	(segment
		(start 234.370626 -8.0518)
		(end 234.0864 -7.767574)
		(width 0.14224)
		(layer "In11.Cu")
		(net "M_B_ECC<5>")
	)
	(segment
		(start 234.573572 -27.250136)
		(end 234.994196 -26.829512)
		(width 0.14224)
		(layer "In11.Cu")
		(net "M_B_ECC<5>")
	)
	(segment
		(start 235.044996 -17.109186)
		(end 234.95 -17.01419)
		(width 0.14224)
		(layer "In11.Cu")
		(net "M_B_ECC<5>")
	)
	(segment
		(start 235.081826 -8.8646)
		(end 235.081826 -8.452104)
		(width 0.14224)
		(layer "In11.Cu")
		(net "M_B_ECC<5>")
	)
	(segment
		(start 235.044996 -18.455386)
		(end 235.044996 -17.109186)
		(width 0.14224)
		(layer "In11.Cu")
		(net "M_B_ECC<5>")
	)
	(segment
		(start 235.070396 -21.964396)
		(end 234.968796 -21.862796)
		(width 0.14224)
		(layer "In11.Cu")
		(net "M_B_ECC<5>")
	)
	(segment
		(start 234.994196 -23.234396)
		(end 235.070396 -23.158196)
		(width 0.14224)
		(layer "In11.Cu")
		(net "M_B_ECC<5>")
	)
	(segment
		(start 234.968796 -18.531586)
		(end 235.044996 -18.455386)
		(width 0.14224)
		(layer "In11.Cu")
		(net "M_B_ECC<5>")
	)
	(segment
		(start 235.1532 -19.2786)
		(end 234.968796 -19.094196)
		(width 0.14224)
		(layer "In11.Cu")
		(net "M_B_ECC<5>")
	)
	(segment
		(start 234.0864 -7.372858)
		(end 233.799888 -7.086346)
		(width 0.14224)
		(layer "In11.Cu")
		(net "M_B_ECC<5>")
	)
	(segment
		(start 234.573572 -12.678156)
		(end 234.884976 -12.366752)
		(width 0.14224)
		(layer "In11.Cu")
		(net "M_B_ECC<5>")
	)
	(segment
		(start 234.7468 -13.8938)
		(end 234.7468 -12.851384)
		(width 0.14224)
		(layer "In11.Cu")
		(net "M_B_ECC<5>")
	)
	(segment
		(start 234.968796 -19.094196)
		(end 234.968796 -18.531586)
		(width 0.14224)
		(layer "In11.Cu")
		(net "M_B_ECC<5>")
	)
	(segment
		(start 235.070396 -23.158196)
		(end 235.070396 -21.964396)
		(width 0.14224)
		(layer "In11.Cu")
		(net "M_B_ECC<5>")
	)
	(segment
		(start 234.968796 -21.3614)
		(end 235.1532 -21.176996)
		(width 0.14224)
		(layer "In11.Cu")
		(net "M_B_ECC<5>")
	)
	(segment
		(start 234.0864 -7.767574)
		(end 234.0864 -7.372858)
		(width 0.14224)
		(layer "In11.Cu")
		(net "M_B_ECC<5>")
	)
	(segment
		(start 234.95 -17.01419)
		(end 234.95 -14.097)
		(width 0.14224)
		(layer "In11.Cu")
		(net "M_B_ECC<5>")
	)
	(segment
		(start 234.7468 -12.851384)
		(end 234.573572 -12.678156)
		(width 0.14224)
		(layer "In11.Cu")
		(net "M_B_ECC<5>")
	)
	(segment
		(start 234.884976 -12.366752)
		(end 234.884976 -9.06145)
		(width 0.14224)
		(layer "In11.Cu")
		(net "M_B_ECC<5>")
	)
	(segment
		(start 235.1532 -21.176996)
		(end 235.1532 -19.2786)
		(width 0.14224)
		(layer "In11.Cu")
		(net "M_B_ECC<5>")
	)
	(segment
		(start 235.2802 -41.582086)
		(end 235.843826 -42.145712)
		(width 0.1651)
		(layer "F.Cu")
		(net "M_B_ECC<4>")
	)
	(segment
		(start 234.804204 -34.807906)
		(end 234.6071 -35.00501)
		(width 0.1651)
		(layer "F.Cu")
		(net "M_B_ECC<4>")
	)
	(segment
		(start 241.811048 -45.209968)
		(end 242.179094 -45.578014)
		(width 0.127)
		(layer "F.Cu")
		(net "M_B_ECC<4>")
	)
	(segment
		(start 246.078502 -52.978558)
		(end 245.973854 -53.313838)
		(width 0.0889)
		(layer "F.Cu")
		(net "M_B_ECC<4>")
	)
	(segment
		(start 235.083096 -34.807906)
		(end 234.804204 -34.807906)
		(width 0.1651)
		(layer "F.Cu")
		(net "M_B_ECC<4>")
	)
	(segment
		(start 245.967504 -53.89372)
		(end 245.973854 -53.904388)
		(width 0.0889)
		(layer "F.Cu")
		(net "M_B_ECC<4>")
	)
	(segment
		(start 235.083096 -35.481006)
		(end 235.2802 -35.67811)
		(width 0.1651)
		(layer "F.Cu")
		(net "M_B_ECC<4>")
	)
	(segment
		(start 234.6071 -33.937702)
		(end 234.804204 -34.134806)
		(width 0.1651)
		(layer "F.Cu")
		(net "M_B_ECC<4>")
	)
	(segment
		(start 235.083096 -33.461706)
		(end 234.804204 -33.461706)
		(width 0.1651)
		(layer "F.Cu")
		(net "M_B_ECC<4>")
	)
	(segment
		(start 242.179094 -45.578014)
		(end 243.524024 -45.578014)
		(width 0.127)
		(layer "F.Cu")
		(net "M_B_ECC<4>")
	)
	(segment
		(start 243.524024 -45.578014)
		(end 246.706898 -48.760888)
		(width 0.127)
		(layer "F.Cu")
		(net "M_B_ECC<4>")
	)
	(segment
		(start 235.2802 -34.33191)
		(end 235.2802 -34.610802)
		(width 0.1651)
		(layer "F.Cu")
		(net "M_B_ECC<4>")
	)
	(segment
		(start 234.649772 -10.422382)
		(end 234.649772 -9.091168)
		(width 0.1651)
		(layer "F.Cu")
		(net "M_B_ECC<4>")
	)
	(segment
		(start 234.804204 -35.481006)
		(end 235.083096 -35.481006)
		(width 0.1651)
		(layer "F.Cu")
		(net "M_B_ECC<4>")
	)
	(segment
		(start 235.083096 -34.134806)
		(end 235.2802 -34.33191)
		(width 0.1651)
		(layer "F.Cu")
		(net "M_B_ECC<4>")
	)
	(segment
		(start 233.799888 -30.891734)
		(end 235.2802 -32.372046)
		(width 0.1651)
		(layer "F.Cu")
		(net "M_B_ECC<4>")
	)
	(segment
		(start 246.706898 -50.39741)
		(end 246.343424 -51.086512)
		(width 0.0889)
		(layer "F.Cu")
		(net "M_B_ECC<4>")
	)
	(segment
		(start 235.843826 -42.145712)
		(end 235.843826 -42.424604)
		(width 0.1651)
		(layer "F.Cu")
		(net "M_B_ECC<4>")
	)
	(segment
		(start 234.804204 -33.461706)
		(end 234.6071 -33.65881)
		(width 0.1651)
		(layer "F.Cu")
		(net "M_B_ECC<4>")
	)
	(segment
		(start 235.2802 -32.372046)
		(end 235.2802 -33.264602)
		(width 0.1651)
		(layer "F.Cu")
		(net "M_B_ECC<4>")
	)
	(segment
		(start 235.520738 -42.747692)
		(end 235.520738 -43.026584)
		(width 0.1651)
		(layer "F.Cu")
		(net "M_B_ECC<4>")
	)
	(segment
		(start 235.2802 -35.67811)
		(end 235.2802 -36.195)
		(width 0.1651)
		(layer "F.Cu")
		(net "M_B_ECC<4>")
	)
	(segment
		(start 246.343424 -51.086512)
		(end 246.13362 -51.393344)
		(width 0.0889)
		(layer "F.Cu")
		(net "M_B_ECC<4>")
	)
	(segment
		(start 234.6071 -35.00501)
		(end 234.6071 -35.283902)
		(width 0.1651)
		(layer "F.Cu")
		(net "M_B_ECC<4>")
	)
	(segment
		(start 246.706898 -50.073814)
		(end 246.706898 -50.39741)
		(width 0.0889)
		(layer "F.Cu")
		(net "M_B_ECC<4>")
	)
	(segment
		(start 246.078502 -51.622452)
		(end 246.078502 -52.978558)
		(width 0.0889)
		(layer "F.Cu")
		(net "M_B_ECC<4>")
	)
	(segment
		(start 245.973854 -53.904388)
		(end 245.990618 -53.933852)
		(width 0.0889)
		(layer "F.Cu")
		(net "M_B_ECC<4>")
	)
	(segment
		(start 234.58932 -8.763)
		(end 234.551728 -8.5598)
		(width 0.1651)
		(layer "F.Cu")
		(net "M_B_ECC<4>")
	)
	(segment
		(start 235.996734 -43.223688)
		(end 236.319822 -42.9006)
		(width 0.1651)
		(layer "F.Cu")
		(net "M_B_ECC<4>")
	)
	(segment
		(start 235.2802 -34.610802)
		(end 235.083096 -34.807906)
		(width 0.1651)
		(layer "F.Cu")
		(net "M_B_ECC<4>")
	)
	(segment
		(start 235.843826 -42.424604)
		(end 235.520738 -42.747692)
		(width 0.1651)
		(layer "F.Cu")
		(net "M_B_ECC<4>")
	)
	(segment
		(start 234.804204 -34.134806)
		(end 235.083096 -34.134806)
		(width 0.1651)
		(layer "F.Cu")
		(net "M_B_ECC<4>")
	)
	(segment
		(start 234.65028 -10.422382)
		(end 234.649772 -10.422382)
		(width 0.1651)
		(layer "F.Cu")
		(net "M_B_ECC<4>")
	)
	(segment
		(start 234.649772 -9.091168)
		(end 234.58932 -8.763)
		(width 0.1651)
		(layer "F.Cu")
		(net "M_B_ECC<4>")
	)
	(segment
		(start 235.520738 -43.026584)
		(end 235.717842 -43.223688)
		(width 0.1651)
		(layer "F.Cu")
		(net "M_B_ECC<4>")
	)
	(segment
		(start 235.2802 -33.264602)
		(end 235.083096 -33.461706)
		(width 0.1651)
		(layer "F.Cu")
		(net "M_B_ECC<4>")
	)
	(segment
		(start 238.908082 -45.209968)
		(end 241.811048 -45.209968)
		(width 0.127)
		(layer "F.Cu")
		(net "M_B_ECC<4>")
	)
	(segment
		(start 235.2802 -36.195)
		(end 235.2802 -41.582086)
		(width 0.1651)
		(layer "F.Cu")
		(net "M_B_ECC<4>")
	)
	(segment
		(start 234.6071 -33.65881)
		(end 234.6071 -33.937702)
		(width 0.1651)
		(layer "F.Cu")
		(net "M_B_ECC<4>")
	)
	(segment
		(start 236.319822 -42.9006)
		(end 236.598714 -42.9006)
		(width 0.1651)
		(layer "F.Cu")
		(net "M_B_ECC<4>")
	)
	(segment
		(start 234.6071 -35.283902)
		(end 234.804204 -35.481006)
		(width 0.1651)
		(layer "F.Cu")
		(net "M_B_ECC<4>")
	)
	(segment
		(start 246.706898 -48.760888)
		(end 246.706898 -50.073814)
		(width 0.127)
		(layer "F.Cu")
		(net "M_B_ECC<4>")
	)
	(segment
		(start 233.799888 -28.531058)
		(end 233.799888 -30.891734)
		(width 0.1651)
		(layer "F.Cu")
		(net "M_B_ECC<4>")
	)
	(segment
		(start 246.079772 -51.56073)
		(end 246.078502 -51.622452)
		(width 0.0889)
		(layer "F.Cu")
		(net "M_B_ECC<4>")
	)
	(segment
		(start 245.990618 -53.933852)
		(end 246.485664 -54.59984)
		(width 0.0889)
		(layer "F.Cu")
		(net "M_B_ECC<4>")
	)
	(segment
		(start 236.598714 -42.9006)
		(end 238.908082 -45.209968)
		(width 0.1651)
		(layer "F.Cu")
		(net "M_B_ECC<4>")
	)
	(segment
		(start 235.717842 -43.223688)
		(end 235.996734 -43.223688)
		(width 0.1651)
		(layer "F.Cu")
		(net "M_B_ECC<4>")
	)
	(via
		(at 235.2802 -36.195)
		(size 0.508)
		(drill 0.254)
		(layers "F.Cu" "B.Cu")
		(net "M_B_ECC<4>")
	)
	(via
		(at 234.551728 -8.5598)
		(size 0.508)
		(drill 0.254)
		(layers "F.Cu" "B.Cu")
		(net "M_B_ECC<4>")
	)
	(via
		(at 233.799888 -13.959078)
		(size 0.508)
		(drill 0.254)
		(layers "F.Cu" "B.Cu")
		(net "M_B_ECC<4>")
	)
	(via
		(at 233.799888 -28.531058)
		(size 0.508)
		(drill 0.254)
		(layers "F.Cu" "B.Cu")
		(net "M_B_ECC<4>")
	)
	(arc
		(start 246.13362 -51.393344)
		(mid 246.094541 -51.473128)
		(end 246.079772 -51.56073)
		(width 0.0889)
		(layer "F.Cu")
		(net "M_B_ECC<4>")
	)
	(arc
		(start 245.973854 -53.313838)
		(mid 245.894632 -53.602956)
		(end 245.967504 -53.89372)
		(width 0.0889)
		(layer "F.Cu")
		(net "M_B_ECC<4>")
	)
	(segment
		(start 233.800396 -15.222982)
		(end 233.799888 -15.222982)
		(width 0.1651)
		(layer "B.Cu")
		(net "M_B_ECC<4>")
	)
	(segment
		(start 233.799888 -15.222982)
		(end 233.799888 -13.959078)
		(width 0.1651)
		(layer "B.Cu")
		(net "M_B_ECC<4>")
	)
	(segment
		(start 234.275376 -12.217654)
		(end 234.275376 -8.836152)
		(width 0.14224)
		(layer "In11.Cu")
		(net "M_B_ECC<4>")
	)
	(segment
		(start 234.282996 -21.336)
		(end 234.1372 -21.190204)
		(width 0.14224)
		(layer "In11.Cu")
		(net "M_B_ECC<4>")
	)
	(segment
		(start 234.1118 -13.647166)
		(end 234.1118 -12.38123)
		(width 0.14224)
		(layer "In11.Cu")
		(net "M_B_ECC<4>")
	)
	(segment
		(start 234.079796 -26.891996)
		(end 234.282996 -26.688796)
		(width 0.14224)
		(layer "In11.Cu")
		(net "M_B_ECC<4>")
	)
	(segment
		(start 234.079796 -18.328386)
		(end 234.079796 -17.024858)
		(width 0.14224)
		(layer "In11.Cu")
		(net "M_B_ECC<4>")
	)
	(segment
		(start 234.282996 -18.531586)
		(end 234.079796 -18.328386)
		(width 0.14224)
		(layer "In11.Cu")
		(net "M_B_ECC<4>")
	)
	(segment
		(start 234.079796 -21.938996)
		(end 234.282996 -21.735796)
		(width 0.14224)
		(layer "In11.Cu")
		(net "M_B_ECC<4>")
	)
	(segment
		(start 234.282996 -18.980404)
		(end 234.282996 -18.531586)
		(width 0.14224)
		(layer "In11.Cu")
		(net "M_B_ECC<4>")
	)
	(segment
		(start 234.282996 -21.735796)
		(end 234.282996 -21.336)
		(width 0.14224)
		(layer "In11.Cu")
		(net "M_B_ECC<4>")
	)
	(segment
		(start 234.282996 -23.310596)
		(end 234.079796 -23.107396)
		(width 0.14224)
		(layer "In11.Cu")
		(net "M_B_ECC<4>")
	)
	(segment
		(start 234.282996 -14.442186)
		(end 233.799888 -13.959078)
		(width 0.14224)
		(layer "In11.Cu")
		(net "M_B_ECC<4>")
	)
	(segment
		(start 234.275376 -8.836152)
		(end 234.551728 -8.5598)
		(width 0.14224)
		(layer "In11.Cu")
		(net "M_B_ECC<4>")
	)
	(segment
		(start 234.079796 -23.107396)
		(end 234.079796 -21.938996)
		(width 0.14224)
		(layer "In11.Cu")
		(net "M_B_ECC<4>")
	)
	(segment
		(start 234.079796 -28.25115)
		(end 234.079796 -26.891996)
		(width 0.14224)
		(layer "In11.Cu")
		(net "M_B_ECC<4>")
	)
	(segment
		(start 234.079796 -17.024858)
		(end 234.282996 -16.821658)
		(width 0.14224)
		(layer "In11.Cu")
		(net "M_B_ECC<4>")
	)
	(segment
		(start 234.1372 -21.190204)
		(end 234.1372 -19.1262)
		(width 0.14224)
		(layer "In11.Cu")
		(net "M_B_ECC<4>")
	)
	(segment
		(start 234.1372 -19.1262)
		(end 234.282996 -18.980404)
		(width 0.14224)
		(layer "In11.Cu")
		(net "M_B_ECC<4>")
	)
	(segment
		(start 233.799888 -28.531058)
		(end 234.079796 -28.25115)
		(width 0.14224)
		(layer "In11.Cu")
		(net "M_B_ECC<4>")
	)
	(segment
		(start 234.282996 -16.821658)
		(end 234.282996 -14.442186)
		(width 0.14224)
		(layer "In11.Cu")
		(net "M_B_ECC<4>")
	)
	(segment
		(start 234.1118 -12.38123)
		(end 234.275376 -12.217654)
		(width 0.14224)
		(layer "In11.Cu")
		(net "M_B_ECC<4>")
	)
	(segment
		(start 233.799888 -13.959078)
		(end 234.1118 -13.647166)
		(width 0.14224)
		(layer "In11.Cu")
		(net "M_B_ECC<4>")
	)
	(segment
		(start 234.282996 -26.688796)
		(end 234.282996 -23.310596)
		(width 0.14224)
		(layer "In11.Cu")
		(net "M_B_ECC<4>")
	)
	(segment
		(start 244.57025 -29.24175)
		(end 244.8814 -29.5529)
		(width 0.1651)
		(layer "F.Cu")
		(net "M_B_ECC<3>")
	)
	(segment
		(start 250.426728 -52.922424)
		(end 250.431554 -52.913788)
		(width 0.0889)
		(layer "F.Cu")
		(net "M_B_ECC<3>")
	)
	(segment
		(start 249.919744 -54.268116)
		(end 249.992134 -54.195726)
		(width 0.0889)
		(layer "F.Cu")
		(net "M_B_ECC<3>")
	)
	(segment
		(start 245.3132 -40.6527)
		(end 245.1862 -40.7797)
		(width 0.1651)
		(layer "F.Cu")
		(net "M_B_ECC<3>")
	)
	(segment
		(start 244.0178 -39.5478)
		(end 243.838984 -39.726616)
		(width 0.1651)
		(layer "F.Cu")
		(net "M_B_ECC<3>")
	)
	(segment
		(start 250.522994 -51.787044)
		(end 250.522994 -51.463448)
		(width 0.0889)
		(layer "F.Cu")
		(net "M_B_ECC<3>")
	)
	(segment
		(start 243.838984 -39.726616)
		(end 243.838984 -40.842184)
		(width 0.1651)
		(layer "F.Cu")
		(net "M_B_ECC<3>")
	)
	(segment
		(start 250.085098 -49.492916)
		(end 250.085098 -47.359316)
		(width 0.127)
		(layer "F.Cu")
		(net "M_B_ECC<3>")
	)
	(segment
		(start 241.450368 -7.085838)
		(end 241.44986 -7.086346)
		(width 0.1651)
		(layer "F.Cu")
		(net "M_B_ECC<3>")
	)
	(segment
		(start 250.522994 -51.463448)
		(end 250.401074 -51.25212)
		(width 0.0889)
		(layer "F.Cu")
		(net "M_B_ECC<3>")
	)
	(segment
		(start 250.401074 -50.955956)
		(end 250.512326 -50.76317)
		(width 0.0889)
		(layer "F.Cu")
		(net "M_B_ECC<3>")
	)
	(segment
		(start 250.39193 -52.013104)
		(end 250.522994 -51.787044)
		(width 0.0889)
		(layer "F.Cu")
		(net "M_B_ECC<3>")
	)
	(segment
		(start 250.085098 -47.359316)
		(end 245.867682 -43.1419)
		(width 0.127)
		(layer "F.Cu")
		(net "M_B_ECC<3>")
	)
	(segment
		(start 250.401074 -51.25212)
		(end 250.401074 -50.955956)
		(width 0.0889)
		(layer "F.Cu")
		(net "M_B_ECC<3>")
	)
	(segment
		(start 241.450368 -5.822442)
		(end 241.450368 -7.085838)
		(width 0.1651)
		(layer "F.Cu")
		(net "M_B_ECC<3>")
	)
	(segment
		(start 250.39193 -52.215288)
		(end 250.39193 -52.013104)
		(width 0.0889)
		(layer "F.Cu")
		(net "M_B_ECC<3>")
	)
	(segment
		(start 247.0912 -37.592)
		(end 245.3132 -39.37)
		(width 0.1651)
		(layer "F.Cu")
		(net "M_B_ECC<3>")
	)
	(segment
		(start 250.437904 -52.333906)
		(end 250.431554 -52.323238)
		(width 0.0889)
		(layer "F.Cu")
		(net "M_B_ECC<3>")
	)
	(segment
		(start 245.0846 -42.320718)
		(end 245.0846 -42.358818)
		(width 0.127)
		(layer "F.Cu")
		(net "M_B_ECC<3>")
	)
	(segment
		(start 250.512326 -50.13198)
		(end 250.085098 -49.492916)
		(width 0.0889)
		(layer "F.Cu")
		(net "M_B_ECC<3>")
	)
	(segment
		(start 250.512326 -50.76317)
		(end 250.512326 -50.13198)
		(width 0.0889)
		(layer "F.Cu")
		(net "M_B_ECC<3>")
	)
	(segment
		(start 244.6782 -40.7797)
		(end 244.5512 -40.6527)
		(width 0.1651)
		(layer "F.Cu")
		(net "M_B_ECC<3>")
	)
	(segment
		(start 249.919744 -54.59984)
		(end 249.919744 -54.268116)
		(width 0.0889)
		(layer "F.Cu")
		(net "M_B_ECC<3>")
	)
	(segment
		(start 243.838984 -41.075102)
		(end 245.0846 -42.320718)
		(width 0.127)
		(layer "F.Cu")
		(net "M_B_ECC<3>")
	)
	(segment
		(start 245.0846 -42.358818)
		(end 245.867682 -43.1419)
		(width 0.127)
		(layer "F.Cu")
		(net "M_B_ECC<3>")
	)
	(segment
		(start 244.8814 -31.5087)
		(end 247.0912 -33.7185)
		(width 0.1651)
		(layer "F.Cu")
		(net "M_B_ECC<3>")
	)
	(segment
		(start 245.1862 -40.7797)
		(end 244.6782 -40.7797)
		(width 0.1651)
		(layer "F.Cu")
		(net "M_B_ECC<3>")
	)
	(segment
		(start 243.838984 -40.842184)
		(end 243.838984 -41.075102)
		(width 0.127)
		(layer "F.Cu")
		(net "M_B_ECC<3>")
	)
	(segment
		(start 242.680236 -27.351736)
		(end 244.57025 -29.24175)
		(width 0.1651)
		(layer "F.Cu")
		(net "M_B_ECC<3>")
	)
	(segment
		(start 244.2972 -39.5478)
		(end 244.0178 -39.5478)
		(width 0.1651)
		(layer "F.Cu")
		(net "M_B_ECC<3>")
	)
	(segment
		(start 244.5512 -40.6527)
		(end 244.5512 -39.8018)
		(width 0.1651)
		(layer "F.Cu")
		(net "M_B_ECC<3>")
	)
	(segment
		(start 242.261644 -27.351736)
		(end 242.680236 -27.351736)
		(width 0.1651)
		(layer "F.Cu")
		(net "M_B_ECC<3>")
	)
	(segment
		(start 245.3132 -39.37)
		(end 245.3132 -40.6527)
		(width 0.1651)
		(layer "F.Cu")
		(net "M_B_ECC<3>")
	)
	(segment
		(start 244.8814 -29.5529)
		(end 244.8814 -31.5087)
		(width 0.1651)
		(layer "F.Cu")
		(net "M_B_ECC<3>")
	)
	(segment
		(start 244.5512 -39.8018)
		(end 244.2972 -39.5478)
		(width 0.1651)
		(layer "F.Cu")
		(net "M_B_ECC<3>")
	)
	(segment
		(start 247.0912 -33.7185)
		(end 247.0912 -37.592)
		(width 0.1651)
		(layer "F.Cu")
		(net "M_B_ECC<3>")
	)
	(via
		(at 241.44986 -7.086346)
		(size 0.508)
		(drill 0.254)
		(layers "F.Cu" "B.Cu")
		(net "M_B_ECC<3>")
	)
	(via
		(at 242.299744 -12.678156)
		(size 0.508)
		(drill 0.254)
		(layers "F.Cu" "B.Cu")
		(net "M_B_ECC<3>")
	)
	(via
		(at 244.57025 -29.24175)
		(size 0.508)
		(drill 0.254)
		(layers "F.Cu" "B.Cu")
		(net "M_B_ECC<3>")
	)
	(via
		(at 242.261644 -27.351736)
		(size 0.508)
		(drill 0.254)
		(layers "F.Cu" "B.Cu")
		(net "M_B_ECC<3>")
	)
	(arc
		(start 250.431554 -53.313838)
		(mid 250.378084 -53.118775)
		(end 250.426728 -52.922424)
		(width 0.0889)
		(layer "F.Cu")
		(net "M_B_ECC<3>")
	)
	(arc
		(start 249.992134 -54.195726)
		(mid 250.44866 -53.872782)
		(end 250.431554 -53.313838)
		(width 0.0889)
		(layer "F.Cu")
		(net "M_B_ECC<3>")
	)
	(arc
		(start 250.395994 -52.241958)
		(mid 250.392973 -52.228775)
		(end 250.39193 -52.215288)
		(width 0.0889)
		(layer "F.Cu")
		(net "M_B_ECC<3>")
	)
	(arc
		(start 250.431554 -52.323238)
		(mid 250.411511 -52.283588)
		(end 250.395994 -52.241958)
		(width 0.0889)
		(layer "F.Cu")
		(net "M_B_ECC<3>")
	)
	(arc
		(start 250.431554 -52.913788)
		(mid 250.510776 -52.62467)
		(end 250.437904 -52.333906)
		(width 0.0889)
		(layer "F.Cu")
		(net "M_B_ECC<3>")
	)
	(segment
		(start 242.300506 -12.677394)
		(end 242.299744 -12.678156)
		(width 0.1651)
		(layer "B.Cu")
		(net "M_B_ECC<3>")
	)
	(segment
		(start 242.300506 -10.623042)
		(end 242.300506 -12.677394)
		(width 0.1651)
		(layer "B.Cu")
		(net "M_B_ECC<3>")
	)
	(segment
		(start 242.614196 -19.090386)
		(end 242.791996 -19.268186)
		(width 0.14224)
		(layer "In11.Cu")
		(net "M_B_ECC<3>")
	)
	(segment
		(start 241.766598 -7.7216)
		(end 242.096798 -8.0518)
		(width 0.14224)
		(layer "In11.Cu")
		(net "M_B_ECC<3>")
	)
	(segment
		(start 242.350798 -8.0518)
		(end 242.807998 -8.509)
		(width 0.14224)
		(layer "In11.Cu")
		(net "M_B_ECC<3>")
	)
	(segment
		(start 242.692682 -16.531082)
		(end 242.766596 -16.604996)
		(width 0.14224)
		(layer "In11.Cu")
		(net "M_B_ECC<3>")
	)
	(segment
		(start 241.8334 -13.5636)
		(end 242.692682 -14.422882)
		(width 0.14224)
		(layer "In11.Cu")
		(net "M_B_ECC<3>")
	)
	(segment
		(start 242.614196 -26.180796)
		(end 242.791996 -26.358596)
		(width 0.14224)
		(layer "In11.Cu")
		(net "M_B_ECC<3>")
	)
	(segment
		(start 242.65255 -9.020048)
		(end 242.65255 -12.32535)
		(width 0.14224)
		(layer "In11.Cu")
		(net "M_B_ECC<3>")
	)
	(segment
		(start 242.096798 -8.0518)
		(end 242.350798 -8.0518)
		(width 0.14224)
		(layer "In11.Cu")
		(net "M_B_ECC<3>")
	)
	(segment
		(start 242.614196 -23.285196)
		(end 242.614196 -26.180796)
		(width 0.14224)
		(layer "In11.Cu")
		(net "M_B_ECC<3>")
	)
	(segment
		(start 241.8334 -13.1445)
		(end 241.8334 -13.5636)
		(width 0.14224)
		(layer "In11.Cu")
		(net "M_B_ECC<3>")
	)
	(segment
		(start 242.807998 -8.509)
		(end 242.807998 -8.8646)
		(width 0.14224)
		(layer "In11.Cu")
		(net "M_B_ECC<3>")
	)
	(segment
		(start 242.791996 -23.107396)
		(end 242.614196 -23.285196)
		(width 0.14224)
		(layer "In11.Cu")
		(net "M_B_ECC<3>")
	)
	(segment
		(start 242.65255 -12.32535)
		(end 242.299744 -12.678156)
		(width 0.14224)
		(layer "In11.Cu")
		(net "M_B_ECC<3>")
	)
	(segment
		(start 242.791996 -26.358596)
		(end 242.791996 -26.821384)
		(width 0.14224)
		(layer "In11.Cu")
		(net "M_B_ECC<3>")
	)
	(segment
		(start 242.807998 -8.8646)
		(end 242.65255 -9.020048)
		(width 0.14224)
		(layer "In11.Cu")
		(net "M_B_ECC<3>")
	)
	(segment
		(start 242.766596 -18.447258)
		(end 242.614196 -18.599658)
		(width 0.14224)
		(layer "In11.Cu")
		(net "M_B_ECC<3>")
	)
	(segment
		(start 242.299744 -12.678156)
		(end 241.8334 -13.1445)
		(width 0.14224)
		(layer "In11.Cu")
		(net "M_B_ECC<3>")
	)
	(segment
		(start 242.614196 -18.599658)
		(end 242.614196 -19.090386)
		(width 0.14224)
		(layer "In11.Cu")
		(net "M_B_ECC<3>")
	)
	(segment
		(start 242.766596 -16.604996)
		(end 242.766596 -18.447258)
		(width 0.14224)
		(layer "In11.Cu")
		(net "M_B_ECC<3>")
	)
	(segment
		(start 242.692682 -14.422882)
		(end 242.692682 -16.531082)
		(width 0.14224)
		(layer "In11.Cu")
		(net "M_B_ECC<3>")
	)
	(segment
		(start 241.44986 -7.086346)
		(end 241.766598 -7.403084)
		(width 0.14224)
		(layer "In11.Cu")
		(net "M_B_ECC<3>")
	)
	(segment
		(start 241.766598 -7.403084)
		(end 241.766598 -7.7216)
		(width 0.14224)
		(layer "In11.Cu")
		(net "M_B_ECC<3>")
	)
	(segment
		(start 242.791996 -26.821384)
		(end 242.261644 -27.351736)
		(width 0.14224)
		(layer "In11.Cu")
		(net "M_B_ECC<3>")
	)
	(segment
		(start 242.791996 -19.268186)
		(end 242.791996 -23.107396)
		(width 0.14224)
		(layer "In11.Cu")
		(net "M_B_ECC<3>")
	)
	(segment
		(start 245.7704 -35.9664)
		(end 245.7704 -34.9885)
		(width 0.1651)
		(layer "F.Cu")
		(net "M_B_ECC<2>")
	)
	(segment
		(start 243.1542 -38.7223)
		(end 243.1542 -40.766238)
		(width 0.1651)
		(layer "F.Cu")
		(net "M_B_ECC<2>")
	)
	(segment
		(start 244.706394 -42.517314)
		(end 244.794024 -42.517314)
		(width 0.1016)
		(layer "F.Cu")
		(net "M_B_ECC<2>")
	)
	(segment
		(start 250.210574 -50.904648)
		(end 250.321826 -50.711862)
		(width 0.0889)
		(layer "F.Cu")
		(net "M_B_ECC<2>")
	)
	(segment
		(start 250.19762 -51.925982)
		(end 250.332494 -51.692556)
		(width 0.0889)
		(layer "F.Cu")
		(net "M_B_ECC<2>")
	)
	(segment
		(start 245.2624 -37.179758)
		(end 244.215158 -38.227)
		(width 0.1651)
		(layer "F.Cu")
		(net "M_B_ECC<2>")
	)
	(segment
		(start 245.9355 -34.8234)
		(end 246.2784 -34.8234)
		(width 0.1651)
		(layer "F.Cu")
		(net "M_B_ECC<2>")
	)
	(segment
		(start 250.19762 -52.212494)
		(end 250.19762 -51.925982)
		(width 0.0889)
		(layer "F.Cu")
		(net "M_B_ECC<2>")
	)
	(segment
		(start 244.794024 -42.517314)
		(end 245.41861 -43.1419)
		(width 0.1016)
		(layer "F.Cu")
		(net "M_B_ECC<2>")
	)
	(segment
		(start 244.215158 -38.227)
		(end 243.6495 -38.227)
		(width 0.1651)
		(layer "F.Cu")
		(net "M_B_ECC<2>")
	)
	(segment
		(start 249.767598 -49.565814)
		(end 249.767598 -47.490888)
		(width 0.1016)
		(layer "F.Cu")
		(net "M_B_ECC<2>")
	)
	(segment
		(start 246.2784 -34.8234)
		(end 246.4435 -34.9885)
		(width 0.1651)
		(layer "F.Cu")
		(net "M_B_ECC<2>")
	)
	(segment
		(start 243.224304 -40.836342)
		(end 243.224304 -41.035224)
		(width 0.1016)
		(layer "F.Cu")
		(net "M_B_ECC<2>")
	)
	(segment
		(start 242.0747 -27.8638)
		(end 242.67795 -28.46705)
		(width 0.1651)
		(layer "F.Cu")
		(net "M_B_ECC<2>")
	)
	(segment
		(start 242.431316 -9.29386)
		(end 242.431316 -9.07034)
		(width 0.1651)
		(layer "F.Cu")
		(net "M_B_ECC<2>")
	)
	(segment
		(start 249.919744 -53.60924)
		(end 249.919744 -53.940964)
		(width 0.0889)
		(layer "F.Cu")
		(net "M_B_ECC<2>")
	)
	(segment
		(start 250.223274 -52.327048)
		(end 250.213114 -52.299362)
		(width 0.0889)
		(layer "F.Cu")
		(net "M_B_ECC<2>")
	)
	(segment
		(start 242.431316 -9.07034)
		(end 242.299744 -8.938768)
		(width 0.1651)
		(layer "F.Cu")
		(net "M_B_ECC<2>")
	)
	(segment
		(start 245.2624 -36.1315)
		(end 245.6053 -36.1315)
		(width 0.1651)
		(layer "F.Cu")
		(net "M_B_ECC<2>")
	)
	(segment
		(start 245.0973 -34.036)
		(end 245.0973 -35.9664)
		(width 0.1651)
		(layer "F.Cu")
		(net "M_B_ECC<2>")
	)
	(segment
		(start 243.1542 -40.766238)
		(end 243.224304 -40.836342)
		(width 0.1651)
		(layer "F.Cu")
		(net "M_B_ECC<2>")
	)
	(segment
		(start 250.210574 -51.303428)
		(end 250.210574 -50.904648)
		(width 0.0889)
		(layer "F.Cu")
		(net "M_B_ECC<2>")
	)
	(segment
		(start 243.6495 -38.227)
		(end 243.1542 -38.7223)
		(width 0.1651)
		(layer "F.Cu")
		(net "M_B_ECC<2>")
	)
	(segment
		(start 250.332494 -51.514756)
		(end 250.210574 -51.303428)
		(width 0.0889)
		(layer "F.Cu")
		(net "M_B_ECC<2>")
	)
	(segment
		(start 250.321826 -50.372772)
		(end 249.767598 -49.818544)
		(width 0.0889)
		(layer "F.Cu")
		(net "M_B_ECC<2>")
	)
	(segment
		(start 249.767598 -49.818544)
		(end 249.767598 -49.565814)
		(width 0.0889)
		(layer "F.Cu")
		(net "M_B_ECC<2>")
	)
	(segment
		(start 243.9924 -32.9311)
		(end 245.0973 -34.036)
		(width 0.1651)
		(layer "F.Cu")
		(net "M_B_ECC<2>")
	)
	(segment
		(start 241.44986 -27.8638)
		(end 242.0747 -27.8638)
		(width 0.1651)
		(layer "F.Cu")
		(net "M_B_ECC<2>")
	)
	(segment
		(start 246.4435 -37.014658)
		(end 246.2784 -37.179758)
		(width 0.1651)
		(layer "F.Cu")
		(net "M_B_ECC<2>")
	)
	(segment
		(start 250.332494 -51.692556)
		(end 250.332494 -51.514756)
		(width 0.0889)
		(layer "F.Cu")
		(net "M_B_ECC<2>")
	)
	(segment
		(start 250.266454 -52.418488)
		(end 250.260104 -52.40782)
		(width 0.0889)
		(layer "F.Cu")
		(net "M_B_ECC<2>")
	)
	(segment
		(start 242.300506 -10.422382)
		(end 242.300506 -9.42467)
		(width 0.1651)
		(layer "F.Cu")
		(net "M_B_ECC<2>")
	)
	(segment
		(start 245.6053 -36.1315)
		(end 245.7704 -35.9664)
		(width 0.1651)
		(layer "F.Cu")
		(net "M_B_ECC<2>")
	)
	(segment
		(start 249.919744 -53.940964)
		(end 249.98299 -54.00421)
		(width 0.0889)
		(layer "F.Cu")
		(net "M_B_ECC<2>")
	)
	(segment
		(start 246.4435 -34.9885)
		(end 246.4435 -37.014658)
		(width 0.1651)
		(layer "F.Cu")
		(net "M_B_ECC<2>")
	)
	(segment
		(start 242.300506 -9.42467)
		(end 242.431316 -9.29386)
		(width 0.1651)
		(layer "F.Cu")
		(net "M_B_ECC<2>")
	)
	(segment
		(start 243.224304 -41.035224)
		(end 244.706394 -42.517314)
		(width 0.1016)
		(layer "F.Cu")
		(net "M_B_ECC<2>")
	)
	(segment
		(start 245.7704 -34.9885)
		(end 245.9355 -34.8234)
		(width 0.1651)
		(layer "F.Cu")
		(net "M_B_ECC<2>")
	)
	(segment
		(start 245.41861 -43.1419)
		(end 249.767598 -47.490888)
		(width 0.1016)
		(layer "F.Cu")
		(net "M_B_ECC<2>")
	)
	(segment
		(start 242.299744 -8.938768)
		(end 242.299744 -8.6614)
		(width 0.1651)
		(layer "F.Cu")
		(net "M_B_ECC<2>")
	)
	(segment
		(start 246.2784 -37.179758)
		(end 245.2624 -37.179758)
		(width 0.1651)
		(layer "F.Cu")
		(net "M_B_ECC<2>")
	)
	(segment
		(start 243.9924 -29.7815)
		(end 243.9924 -32.9311)
		(width 0.1651)
		(layer "F.Cu")
		(net "M_B_ECC<2>")
	)
	(segment
		(start 245.0973 -35.9664)
		(end 245.2624 -36.1315)
		(width 0.1651)
		(layer "F.Cu")
		(net "M_B_ECC<2>")
	)
	(segment
		(start 250.321826 -50.711862)
		(end 250.321826 -50.372772)
		(width 0.0889)
		(layer "F.Cu")
		(net "M_B_ECC<2>")
	)
	(segment
		(start 242.67795 -28.46705)
		(end 243.9924 -29.7815)
		(width 0.1651)
		(layer "F.Cu")
		(net "M_B_ECC<2>")
	)
	(via
		(at 241.44986 -27.8638)
		(size 0.508)
		(drill 0.254)
		(layers "F.Cu" "B.Cu")
		(net "M_B_ECC<2>")
	)
	(via
		(at 242.299744 -8.6614)
		(size 0.508)
		(drill 0.254)
		(layers "F.Cu" "B.Cu")
		(net "M_B_ECC<2>")
	)
	(via
		(at 242.67795 -28.46705)
		(size 0.508)
		(drill 0.254)
		(layers "F.Cu" "B.Cu")
		(net "M_B_ECC<2>")
	)
	(via
		(at 241.44986 -13.959078)
		(size 0.508)
		(drill 0.254)
		(layers "F.Cu" "B.Cu")
		(net "M_B_ECC<2>")
	)
	(arc
		(start 250.266454 -53.409088)
		(mid 250.187323 -53.113686)
		(end 250.266454 -52.818284)
		(width 0.0889)
		(layer "F.Cu")
		(net "M_B_ECC<2>")
	)
	(arc
		(start 250.266454 -52.818284)
		(mid 250.319953 -52.618386)
		(end 250.266454 -52.418488)
		(width 0.0889)
		(layer "F.Cu")
		(net "M_B_ECC<2>")
	)
	(arc
		(start 250.260104 -52.40782)
		(mid 250.240167 -52.368128)
		(end 250.223274 -52.327048)
		(width 0.0889)
		(layer "F.Cu")
		(net "M_B_ECC<2>")
	)
	(arc
		(start 250.213114 -52.299362)
		(mid 250.201545 -52.256611)
		(end 250.19762 -52.212494)
		(width 0.0889)
		(layer "F.Cu")
		(net "M_B_ECC<2>")
	)
	(arc
		(start 249.98299 -54.00421)
		(mid 250.281093 -53.781118)
		(end 250.266454 -53.409088)
		(width 0.0889)
		(layer "F.Cu")
		(net "M_B_ECC<2>")
	)
	(segment
		(start 241.450368 -15.222982)
		(end 241.450368 -13.959586)
		(width 0.1651)
		(layer "B.Cu")
		(net "M_B_ECC<2>")
	)
	(segment
		(start 241.450368 -13.959586)
		(end 241.44986 -13.959078)
		(width 0.1651)
		(layer "B.Cu")
		(net "M_B_ECC<2>")
	)
	(segment
		(start 241.979196 -18.61185)
		(end 241.979196 -18.955004)
		(width 0.14224)
		(layer "In11.Cu")
		(net "M_B_ECC<2>")
	)
	(segment
		(start 241.826796 -23.208996)
		(end 241.953796 -23.335996)
		(width 0.14224)
		(layer "In11.Cu")
		(net "M_B_ECC<2>")
	)
	(segment
		(start 241.133376 -13.080746)
		(end 241.133376 -13.642594)
		(width 0.14224)
		(layer "In11.Cu")
		(net "M_B_ECC<2>")
	)
	(segment
		(start 241.808 -21.164804)
		(end 241.979196 -21.336)
		(width 0.14224)
		(layer "In11.Cu")
		(net "M_B_ECC<2>")
	)
	(segment
		(start 241.979196 -21.786596)
		(end 241.826796 -21.938996)
		(width 0.14224)
		(layer "In11.Cu")
		(net "M_B_ECC<2>")
	)
	(segment
		(start 241.44986 -13.959078)
		(end 242.080796 -14.590014)
		(width 0.14224)
		(layer "In11.Cu")
		(net "M_B_ECC<2>")
	)
	(segment
		(start 242.080796 -14.590014)
		(end 242.080796 -16.778986)
		(width 0.14224)
		(layer "In11.Cu")
		(net "M_B_ECC<2>")
	)
	(segment
		(start 241.953796 -26.270204)
		(end 241.44986 -26.77414)
		(width 0.14224)
		(layer "In11.Cu")
		(net "M_B_ECC<2>")
	)
	(segment
		(start 242.080796 -16.778986)
		(end 241.775996 -17.083786)
		(width 0.14224)
		(layer "In11.Cu")
		(net "M_B_ECC<2>")
	)
	(segment
		(start 241.808 -19.1262)
		(end 241.808 -21.164804)
		(width 0.14224)
		(layer "In11.Cu")
		(net "M_B_ECC<2>")
	)
	(segment
		(start 241.953796 -23.335996)
		(end 241.953796 -26.270204)
		(width 0.14224)
		(layer "In11.Cu")
		(net "M_B_ECC<2>")
	)
	(segment
		(start 241.893598 -12.320524)
		(end 241.133376 -13.080746)
		(width 0.14224)
		(layer "In11.Cu")
		(net "M_B_ECC<2>")
	)
	(segment
		(start 241.893598 -9.067546)
		(end 241.893598 -12.320524)
		(width 0.14224)
		(layer "In11.Cu")
		(net "M_B_ECC<2>")
	)
	(segment
		(start 241.979196 -21.336)
		(end 241.979196 -21.786596)
		(width 0.14224)
		(layer "In11.Cu")
		(net "M_B_ECC<2>")
	)
	(segment
		(start 242.299744 -8.6614)
		(end 241.893598 -9.067546)
		(width 0.14224)
		(layer "In11.Cu")
		(net "M_B_ECC<2>")
	)
	(segment
		(start 241.775996 -18.40865)
		(end 241.979196 -18.61185)
		(width 0.14224)
		(layer "In11.Cu")
		(net "M_B_ECC<2>")
	)
	(segment
		(start 241.979196 -18.955004)
		(end 241.808 -19.1262)
		(width 0.14224)
		(layer "In11.Cu")
		(net "M_B_ECC<2>")
	)
	(segment
		(start 241.826796 -21.938996)
		(end 241.826796 -23.208996)
		(width 0.14224)
		(layer "In11.Cu")
		(net "M_B_ECC<2>")
	)
	(segment
		(start 241.44986 -26.77414)
		(end 241.44986 -27.8638)
		(width 0.14224)
		(layer "In11.Cu")
		(net "M_B_ECC<2>")
	)
	(segment
		(start 241.133376 -13.642594)
		(end 241.44986 -13.959078)
		(width 0.14224)
		(layer "In11.Cu")
		(net "M_B_ECC<2>")
	)
	(segment
		(start 241.775996 -17.083786)
		(end 241.775996 -18.40865)
		(width 0.14224)
		(layer "In11.Cu")
		(net "M_B_ECC<2>")
	)
	(segment
		(start 235.1024 -25.9842)
		(end 234.9246 -26.162)
		(width 0.1651)
		(layer "F.Cu")
		(net "M_B_ECC<1>")
	)
	(segment
		(start 237.9726 -33.2613)
		(end 237.9726 -34.29)
		(width 0.1651)
		(layer "F.Cu")
		(net "M_B_ECC<1>")
	)
	(segment
		(start 235.4072 -28.0162)
		(end 235.6866 -28.0162)
		(width 0.1651)
		(layer "F.Cu")
		(net "M_B_ECC<1>")
	)
	(segment
		(start 236.00664 -25.9842)
		(end 235.1024 -25.9842)
		(width 0.1651)
		(layer "F.Cu")
		(net "M_B_ECC<1>")
	)
	(segment
		(start 235.9914 -28.321)
		(end 235.9914 -30.111954)
		(width 0.1651)
		(layer "F.Cu")
		(net "M_B_ECC<1>")
	)
	(segment
		(start 237.9726 -34.29)
		(end 237.9726 -35.1028)
		(width 0.1651)
		(layer "F.Cu")
		(net "M_B_ECC<1>")
	)
	(segment
		(start 242.941348 -44.650914)
		(end 243.90858 -44.650914)
		(width 0.1016)
		(layer "F.Cu")
		(net "M_B_ECC<1>")
	)
	(segment
		(start 234.9246 -26.162)
		(end 234.9246 -26.8732)
		(width 0.1651)
		(layer "F.Cu")
		(net "M_B_ECC<1>")
	)
	(segment
		(start 247.344184 -53.113686)
		(end 247.673876 -52.352448)
		(width 0.0889)
		(layer "F.Cu")
		(net "M_B_ECC<1>")
	)
	(segment
		(start 238.2139 -35.8902)
		(end 237.9726 -36.1315)
		(width 0.1651)
		(layer "F.Cu")
		(net "M_B_ECC<1>")
	)
	(segment
		(start 238.3663 -32.486854)
		(end 238.3663 -32.8676)
		(width 0.1651)
		(layer "F.Cu")
		(net "M_B_ECC<1>")
	)
	(segment
		(start 240.267236 -43.770042)
		(end 240.513362 -44.016168)
		(width 0.1016)
		(layer "F.Cu")
		(net "M_B_ECC<1>")
	)
	(segment
		(start 235.077 -27.686)
		(end 235.4072 -28.0162)
		(width 0.1651)
		(layer "F.Cu")
		(net "M_B_ECC<1>")
	)
	(segment
		(start 242.306602 -44.016168)
		(end 242.941348 -44.650914)
		(width 0.1016)
		(layer "F.Cu")
		(net "M_B_ECC<1>")
	)
	(segment
		(start 238.3663 -32.8676)
		(end 237.9726 -33.2613)
		(width 0.1651)
		(layer "F.Cu")
		(net "M_B_ECC<1>")
	)
	(segment
		(start 238.2139 -35.3441)
		(end 238.2139 -35.8902)
		(width 0.1651)
		(layer "F.Cu")
		(net "M_B_ECC<1>")
	)
	(segment
		(start 235.49991 -5.822442)
		(end 235.49991 -7.086346)
		(width 0.1651)
		(layer "F.Cu")
		(net "M_B_ECC<1>")
	)
	(segment
		(start 237.9726 -35.1028)
		(end 238.2139 -35.3441)
		(width 0.1651)
		(layer "F.Cu")
		(net "M_B_ECC<1>")
	)
	(segment
		(start 235.500418 -5.822442)
		(end 235.49991 -5.822442)
		(width 0.1651)
		(layer "F.Cu")
		(net "M_B_ECC<1>")
	)
	(segment
		(start 237.9726 -36.1315)
		(end 237.9726 -41.475406)
		(width 0.1651)
		(layer "F.Cu")
		(net "M_B_ECC<1>")
	)
	(segment
		(start 236.171994 -27.161236)
		(end 236.171994 -26.149554)
		(width 0.1651)
		(layer "F.Cu")
		(net "M_B_ECC<1>")
	)
	(segment
		(start 247.633998 -50.073814)
		(end 247.633998 -48.376332)
		(width 0.1016)
		(layer "F.Cu")
		(net "M_B_ECC<1>")
	)
	(segment
		(start 236.171994 -26.149554)
		(end 236.00664 -25.9842)
		(width 0.1651)
		(layer "F.Cu")
		(net "M_B_ECC<1>")
	)
	(segment
		(start 247.633998 -50.557938)
		(end 247.633998 -50.073814)
		(width 0.0889)
		(layer "F.Cu")
		(net "M_B_ECC<1>")
	)
	(segment
		(start 247.753124 -50.677064)
		(end 247.633998 -50.557938)
		(width 0.0889)
		(layer "F.Cu")
		(net "M_B_ECC<1>")
	)
	(segment
		(start 237.9726 -41.475406)
		(end 240.267236 -43.770042)
		(width 0.1651)
		(layer "F.Cu")
		(net "M_B_ECC<1>")
	)
	(segment
		(start 235.6866 -28.0162)
		(end 235.9914 -28.321)
		(width 0.1651)
		(layer "F.Cu")
		(net "M_B_ECC<1>")
	)
	(segment
		(start 247.753124 -52.084224)
		(end 247.753124 -50.677064)
		(width 0.0889)
		(layer "F.Cu")
		(net "M_B_ECC<1>")
	)
	(segment
		(start 235.077 -27.0256)
		(end 235.077 -27.686)
		(width 0.1651)
		(layer "F.Cu")
		(net "M_B_ECC<1>")
	)
	(segment
		(start 247.673876 -52.352448)
		(end 247.690894 -52.323238)
		(width 0.0889)
		(layer "F.Cu")
		(net "M_B_ECC<1>")
	)
	(segment
		(start 234.9246 -26.8732)
		(end 235.077 -27.0256)
		(width 0.1651)
		(layer "F.Cu")
		(net "M_B_ECC<1>")
	)
	(segment
		(start 240.513362 -44.016168)
		(end 242.306602 -44.016168)
		(width 0.1016)
		(layer "F.Cu")
		(net "M_B_ECC<1>")
	)
	(segment
		(start 247.633998 -48.376332)
		(end 243.90858 -44.650914)
		(width 0.1016)
		(layer "F.Cu")
		(net "M_B_ECC<1>")
	)
	(segment
		(start 235.9914 -30.111954)
		(end 238.3663 -32.486854)
		(width 0.1651)
		(layer "F.Cu")
		(net "M_B_ECC<1>")
	)
	(via
		(at 236.171994 -12.678156)
		(size 0.508)
		(drill 0.254)
		(layers "F.Cu" "B.Cu")
		(net "M_B_ECC<1>")
	)
	(via
		(at 235.49991 -7.086346)
		(size 0.508)
		(drill 0.254)
		(layers "F.Cu" "B.Cu")
		(net "M_B_ECC<1>")
	)
	(via
		(at 237.9726 -34.29)
		(size 0.508)
		(drill 0.254)
		(layers "F.Cu" "B.Cu")
		(net "M_B_ECC<1>")
	)
	(via
		(at 236.171994 -27.161236)
		(size 0.508)
		(drill 0.254)
		(layers "F.Cu" "B.Cu")
		(net "M_B_ECC<1>")
	)
	(arc
		(start 247.690894 -52.323238)
		(mid 247.73735 -52.207722)
		(end 247.753124 -52.084224)
		(width 0.0889)
		(layer "F.Cu")
		(net "M_B_ECC<1>")
	)
	(segment
		(start 236.349794 -11.997182)
		(end 236.171994 -12.174982)
		(width 0.1651)
		(layer "B.Cu")
		(net "M_B_ECC<1>")
	)
	(segment
		(start 236.350302 -10.623042)
		(end 236.349794 -10.623042)
		(width 0.1651)
		(layer "B.Cu")
		(net "M_B_ECC<1>")
	)
	(segment
		(start 236.171994 -12.174982)
		(end 236.171994 -12.678156)
		(width 0.1651)
		(layer "B.Cu")
		(net "M_B_ECC<1>")
	)
	(segment
		(start 236.349794 -10.623042)
		(end 236.349794 -11.997182)
		(width 0.1651)
		(layer "B.Cu")
		(net "M_B_ECC<1>")
	)
	(segment
		(start 235.49991 -7.625334)
		(end 235.977176 -8.1026)
		(width 0.14224)
		(layer "In11.Cu")
		(net "M_B_ECC<1>")
	)
	(segment
		(start 236.645196 -19.017996)
		(end 236.8296 -19.2024)
		(width 0.14224)
		(layer "In11.Cu")
		(net "M_B_ECC<1>")
	)
	(segment
		(start 236.171994 -12.678156)
		(end 235.7374 -13.11275)
		(width 0.14224)
		(layer "In11.Cu")
		(net "M_B_ECC<1>")
	)
	(segment
		(start 235.7374 -13.11275)
		(end 235.7374 -13.5509)
		(width 0.14224)
		(layer "In11.Cu")
		(net "M_B_ECC<1>")
	)
	(segment
		(start 235.7374 -13.5509)
		(end 236.022896 -13.836396)
		(width 0.14224)
		(layer "In11.Cu")
		(net "M_B_ECC<1>")
	)
	(segment
		(start 236.022896 -13.836396)
		(end 236.022896 -15.699486)
		(width 0.14224)
		(layer "In11.Cu")
		(net "M_B_ECC<1>")
	)
	(segment
		(start 235.49991 -7.086346)
		(end 235.49991 -7.625334)
		(width 0.14224)
		(layer "In11.Cu")
		(net "M_B_ECC<1>")
	)
	(segment
		(start 236.546136 -12.304014)
		(end 236.171994 -12.678156)
		(width 0.14224)
		(layer "In11.Cu")
		(net "M_B_ECC<1>")
	)
	(segment
		(start 236.645196 -26.688034)
		(end 236.171994 -27.161236)
		(width 0.14224)
		(layer "In11.Cu")
		(net "M_B_ECC<1>")
	)
	(segment
		(start 236.546136 -8.970264)
		(end 236.546136 -12.304014)
		(width 0.14224)
		(layer "In11.Cu")
		(net "M_B_ECC<1>")
	)
	(segment
		(start 236.8296 -21.151596)
		(end 236.645196 -21.336)
		(width 0.14224)
		(layer "In11.Cu")
		(net "M_B_ECC<1>")
	)
	(segment
		(start 235.977176 -8.1026)
		(end 236.332776 -8.1026)
		(width 0.14224)
		(layer "In11.Cu")
		(net "M_B_ECC<1>")
	)
	(segment
		(start 236.022896 -15.699486)
		(end 236.645196 -16.321786)
		(width 0.14224)
		(layer "In11.Cu")
		(net "M_B_ECC<1>")
	)
	(segment
		(start 236.7026 -8.472424)
		(end 236.7026 -8.8138)
		(width 0.14224)
		(layer "In11.Cu")
		(net "M_B_ECC<1>")
	)
	(segment
		(start 236.7026 -8.8138)
		(end 236.546136 -8.970264)
		(width 0.14224)
		(layer "In11.Cu")
		(net "M_B_ECC<1>")
	)
	(segment
		(start 236.8296 -19.2024)
		(end 236.8296 -21.151596)
		(width 0.14224)
		(layer "In11.Cu")
		(net "M_B_ECC<1>")
	)
	(segment
		(start 236.645196 -16.321786)
		(end 236.645196 -19.017996)
		(width 0.14224)
		(layer "In11.Cu")
		(net "M_B_ECC<1>")
	)
	(segment
		(start 236.332776 -8.1026)
		(end 236.7026 -8.472424)
		(width 0.14224)
		(layer "In11.Cu")
		(net "M_B_ECC<1>")
	)
	(segment
		(start 236.645196 -21.336)
		(end 236.645196 -26.688034)
		(width 0.14224)
		(layer "In11.Cu")
		(net "M_B_ECC<1>")
	)
	(segment
		(start 236.6518 -34.720022)
		(end 236.6518 -34.377122)
		(width 0.1651)
		(layer "F.Cu")
		(net "M_B_ECC<0>")
	)
	(segment
		(start 247.071642 -51.769264)
		(end 247.071642 -51.459638)
		(width 0.0889)
		(layer "F.Cu")
		(net "M_B_ECC<0>")
	)
	(segment
		(start 236.6518 -38.758622)
		(end 236.6518 -38.415722)
		(width 0.1651)
		(layer "F.Cu")
		(net "M_B_ECC<0>")
	)
	(segment
		(start 239.990884 -44.409868)
		(end 239.833404 -44.252388)
		(width 0.1016)
		(layer "F.Cu")
		(net "M_B_ECC<0>")
	)
	(segment
		(start 236.6518 -33.373822)
		(end 236.6518 -33.030922)
		(width 0.1651)
		(layer "F.Cu")
		(net "M_B_ECC<0>")
	)
	(segment
		(start 243.782088 -44.955714)
		(end 242.689126 -44.955714)
		(width 0.1016)
		(layer "F.Cu")
		(net "M_B_ECC<0>")
	)
	(segment
		(start 242.14328 -44.409868)
		(end 239.990884 -44.409868)
		(width 0.1016)
		(layer "F.Cu")
		(net "M_B_ECC<0>")
	)
	(segment
		(start 237.1217 -36.231322)
		(end 236.8169 -36.231322)
		(width 0.1651)
		(layer "F.Cu")
		(net "M_B_ECC<0>")
	)
	(segment
		(start 237.1217 -36.904422)
		(end 237.2868 -36.739322)
		(width 0.1651)
		(layer "F.Cu")
		(net "M_B_ECC<0>")
	)
	(segment
		(start 236.6518 -33.030922)
		(end 236.8169 -32.865822)
		(width 0.1651)
		(layer "F.Cu")
		(net "M_B_ECC<0>")
	)
	(segment
		(start 237.2868 -38.085522)
		(end 237.2868 -37.742622)
		(width 0.1651)
		(layer "F.Cu")
		(net "M_B_ECC<0>")
	)
	(segment
		(start 237.1217 -33.538922)
		(end 236.8169 -33.538922)
		(width 0.1651)
		(layer "F.Cu")
		(net "M_B_ECC<0>")
	)
	(segment
		(start 236.8169 -33.538922)
		(end 236.6518 -33.373822)
		(width 0.1651)
		(layer "F.Cu")
		(net "M_B_ECC<0>")
	)
	(segment
		(start 237.1217 -37.577522)
		(end 236.8169 -37.577522)
		(width 0.1651)
		(layer "F.Cu")
		(net "M_B_ECC<0>")
	)
	(segment
		(start 236.8169 -38.250622)
		(end 237.1217 -38.250622)
		(width 0.1651)
		(layer "F.Cu")
		(net "M_B_ECC<0>")
	)
	(segment
		(start 236.6518 -37.412422)
		(end 236.6518 -37.069522)
		(width 0.1651)
		(layer "F.Cu")
		(net "M_B_ECC<0>")
	)
	(segment
		(start 236.6518 -38.415722)
		(end 236.8169 -38.250622)
		(width 0.1651)
		(layer "F.Cu")
		(net "M_B_ECC<0>")
	)
	(segment
		(start 236.6518 -37.069522)
		(end 236.8169 -36.904422)
		(width 0.1651)
		(layer "F.Cu")
		(net "M_B_ECC<0>")
	)
	(segment
		(start 236.6518 -36.066222)
		(end 236.6518 -35.723322)
		(width 0.1651)
		(layer "F.Cu")
		(net "M_B_ECC<0>")
	)
	(segment
		(start 236.8169 -36.904422)
		(end 237.1217 -36.904422)
		(width 0.1651)
		(layer "F.Cu")
		(net "M_B_ECC<0>")
	)
	(segment
		(start 237.2868 -32.397446)
		(end 235.3056 -30.416246)
		(width 0.1651)
		(layer "F.Cu")
		(net "M_B_ECC<0>")
	)
	(segment
		(start 242.689126 -44.955714)
		(end 242.14328 -44.409868)
		(width 0.1016)
		(layer "F.Cu")
		(net "M_B_ECC<0>")
	)
	(segment
		(start 246.94388 -52.123594)
		(end 246.94388 -51.989482)
		(width 0.0889)
		(layer "F.Cu")
		(net "M_B_ECC<0>")
	)
	(segment
		(start 237.2868 -41.705784)
		(end 237.2868 -39.088822)
		(width 0.1651)
		(layer "F.Cu")
		(net "M_B_ECC<0>")
	)
	(segment
		(start 247.329198 -48.502824)
		(end 243.782088 -44.955714)
		(width 0.1016)
		(layer "F.Cu")
		(net "M_B_ECC<0>")
	)
	(segment
		(start 246.485664 -53.60924)
		(end 246.761 -53.60924)
		(width 0.0889)
		(layer "F.Cu")
		(net "M_B_ECC<0>")
	)
	(segment
		(start 236.8169 -34.212022)
		(end 237.1217 -34.212022)
		(width 0.1651)
		(layer "F.Cu")
		(net "M_B_ECC<0>")
	)
	(segment
		(start 247.071642 -51.459638)
		(end 246.94642 -51.242722)
		(width 0.0889)
		(layer "F.Cu")
		(net "M_B_ECC<0>")
	)
	(segment
		(start 246.761 -53.60924)
		(end 246.888 -53.48224)
		(width 0.0889)
		(layer "F.Cu")
		(net "M_B_ECC<0>")
	)
	(segment
		(start 237.2868 -32.700722)
		(end 237.2868 -32.397446)
		(width 0.1651)
		(layer "F.Cu")
		(net "M_B_ECC<0>")
	)
	(segment
		(start 236.8169 -32.865822)
		(end 237.1217 -32.865822)
		(width 0.1651)
		(layer "F.Cu")
		(net "M_B_ECC<0>")
	)
	(segment
		(start 247.329198 -50.351182)
		(end 247.329198 -50.073814)
		(width 0.0889)
		(layer "F.Cu")
		(net "M_B_ECC<0>")
	)
	(segment
		(start 239.833404 -44.252388)
		(end 237.2868 -41.705784)
		(width 0.1651)
		(layer "F.Cu")
		(net "M_B_ECC<0>")
	)
	(segment
		(start 237.1217 -32.865822)
		(end 237.2868 -32.700722)
		(width 0.1651)
		(layer "F.Cu")
		(net "M_B_ECC<0>")
	)
	(segment
		(start 236.8169 -36.231322)
		(end 236.6518 -36.066222)
		(width 0.1651)
		(layer "F.Cu")
		(net "M_B_ECC<0>")
	)
	(segment
		(start 237.2868 -36.396422)
		(end 237.1217 -36.231322)
		(width 0.1651)
		(layer "F.Cu")
		(net "M_B_ECC<0>")
	)
	(segment
		(start 236.191298 -8.763)
		(end 236.171994 -8.5598)
		(width 0.1651)
		(layer "F.Cu")
		(net "M_B_ECC<0>")
	)
	(segment
		(start 236.349794 -10.422382)
		(end 236.191298 -8.763)
		(width 0.1651)
		(layer "F.Cu")
		(net "M_B_ECC<0>")
	)
	(segment
		(start 237.2868 -35.393122)
		(end 237.2868 -35.050222)
		(width 0.1651)
		(layer "F.Cu")
		(net "M_B_ECC<0>")
	)
	(segment
		(start 236.350302 -10.422382)
		(end 236.349794 -10.422382)
		(width 0.1651)
		(layer "F.Cu")
		(net "M_B_ECC<0>")
	)
	(segment
		(start 237.2868 -34.046922)
		(end 237.2868 -33.704022)
		(width 0.1651)
		(layer "F.Cu")
		(net "M_B_ECC<0>")
	)
	(segment
		(start 236.6518 -35.723322)
		(end 236.8169 -35.558222)
		(width 0.1651)
		(layer "F.Cu")
		(net "M_B_ECC<0>")
	)
	(segment
		(start 237.1217 -38.923722)
		(end 236.8169 -38.923722)
		(width 0.1651)
		(layer "F.Cu")
		(net "M_B_ECC<0>")
	)
	(segment
		(start 237.1217 -34.212022)
		(end 237.2868 -34.046922)
		(width 0.1651)
		(layer "F.Cu")
		(net "M_B_ECC<0>")
	)
	(segment
		(start 235.3056 -28.725368)
		(end 235.49991 -28.531058)
		(width 0.1651)
		(layer "F.Cu")
		(net "M_B_ECC<0>")
	)
	(segment
		(start 237.2868 -37.742622)
		(end 237.1217 -37.577522)
		(width 0.1651)
		(layer "F.Cu")
		(net "M_B_ECC<0>")
	)
	(segment
		(start 246.888 -53.48224)
		(end 246.888 -53.369972)
		(width 0.0889)
		(layer "F.Cu")
		(net "M_B_ECC<0>")
	)
	(segment
		(start 246.94642 -51.01463)
		(end 247.329198 -50.351182)
		(width 0.0889)
		(layer "F.Cu")
		(net "M_B_ECC<0>")
	)
	(segment
		(start 236.8169 -37.577522)
		(end 236.6518 -37.412422)
		(width 0.1651)
		(layer "F.Cu")
		(net "M_B_ECC<0>")
	)
	(segment
		(start 237.2868 -36.739322)
		(end 237.2868 -36.396422)
		(width 0.1651)
		(layer "F.Cu")
		(net "M_B_ECC<0>")
	)
	(segment
		(start 236.8169 -34.885122)
		(end 236.6518 -34.720022)
		(width 0.1651)
		(layer "F.Cu")
		(net "M_B_ECC<0>")
	)
	(segment
		(start 237.1217 -38.250622)
		(end 237.2868 -38.085522)
		(width 0.1651)
		(layer "F.Cu")
		(net "M_B_ECC<0>")
	)
	(segment
		(start 237.2868 -35.050222)
		(end 237.1217 -34.885122)
		(width 0.1651)
		(layer "F.Cu")
		(net "M_B_ECC<0>")
	)
	(segment
		(start 236.8169 -35.558222)
		(end 237.1217 -35.558222)
		(width 0.1651)
		(layer "F.Cu")
		(net "M_B_ECC<0>")
	)
	(segment
		(start 246.94388 -51.989482)
		(end 247.071642 -51.769264)
		(width 0.0889)
		(layer "F.Cu")
		(net "M_B_ECC<0>")
	)
	(segment
		(start 235.3056 -30.416246)
		(end 235.3056 -28.725368)
		(width 0.1651)
		(layer "F.Cu")
		(net "M_B_ECC<0>")
	)
	(segment
		(start 247.329198 -50.073814)
		(end 247.329198 -48.502824)
		(width 0.1016)
		(layer "F.Cu")
		(net "M_B_ECC<0>")
	)
	(segment
		(start 237.2868 -33.704022)
		(end 237.1217 -33.538922)
		(width 0.1651)
		(layer "F.Cu")
		(net "M_B_ECC<0>")
	)
	(segment
		(start 237.1217 -35.558222)
		(end 237.2868 -35.393122)
		(width 0.1651)
		(layer "F.Cu")
		(net "M_B_ECC<0>")
	)
	(segment
		(start 236.8169 -38.923722)
		(end 236.6518 -38.758622)
		(width 0.1651)
		(layer "F.Cu")
		(net "M_B_ECC<0>")
	)
	(segment
		(start 237.1217 -34.885122)
		(end 236.8169 -34.885122)
		(width 0.1651)
		(layer "F.Cu")
		(net "M_B_ECC<0>")
	)
	(segment
		(start 236.6518 -34.377122)
		(end 236.8169 -34.212022)
		(width 0.1651)
		(layer "F.Cu")
		(net "M_B_ECC<0>")
	)
	(segment
		(start 237.2868 -39.088822)
		(end 237.1217 -38.923722)
		(width 0.1651)
		(layer "F.Cu")
		(net "M_B_ECC<0>")
	)
	(segment
		(start 246.94642 -51.242722)
		(end 246.94642 -51.01463)
		(width 0.0889)
		(layer "F.Cu")
		(net "M_B_ECC<0>")
	)
	(via
		(at 235.49991 -13.959078)
		(size 0.508)
		(drill 0.254)
		(layers "F.Cu" "B.Cu")
		(net "M_B_ECC<0>")
	)
	(via
		(at 236.171994 -8.5598)
		(size 0.508)
		(drill 0.254)
		(layers "F.Cu" "B.Cu")
		(net "M_B_ECC<0>")
	)
	(via
		(at 235.49991 -28.531058)
		(size 0.508)
		(drill 0.254)
		(layers "F.Cu" "B.Cu")
		(net "M_B_ECC<0>")
	)
	(arc
		(start 247.004332 -52.929282)
		(mid 247.06634 -52.786045)
		(end 247.09628 -52.632864)
		(width 0.0889)
		(layer "F.Cu")
		(net "M_B_ECC<0>")
	)
	(arc
		(start 246.888 -53.369972)
		(mid 246.917567 -53.142076)
		(end 247.004332 -52.929282)
		(width 0.0889)
		(layer "F.Cu")
		(net "M_B_ECC<0>")
	)
	(arc
		(start 247.09628 -52.632864)
		(mid 247.081475 -52.484797)
		(end 247.013984 -52.352194)
		(width 0.0889)
		(layer "F.Cu")
		(net "M_B_ECC<0>")
	)
	(arc
		(start 247.013984 -52.352194)
		(mid 247.002023 -52.334133)
		(end 246.992648 -52.314602)
		(width 0.0889)
		(layer "F.Cu")
		(net "M_B_ECC<0>")
	)
	(arc
		(start 246.992648 -52.314602)
		(mid 246.956315 -52.222148)
		(end 246.94388 -52.123594)
		(width 0.0889)
		(layer "F.Cu")
		(net "M_B_ECC<0>")
	)
	(segment
		(start 235.500418 -15.222982)
		(end 235.49991 -15.222982)
		(width 0.1651)
		(layer "B.Cu")
		(net "M_B_ECC<0>")
	)
	(segment
		(start 235.49991 -15.222982)
		(end 235.49991 -13.959078)
		(width 0.1651)
		(layer "B.Cu")
		(net "M_B_ECC<0>")
	)
	(segment
		(start 235.839 -21.215604)
		(end 235.839 -19.2024)
		(width 0.14224)
		(layer "In11.Cu")
		(net "M_B_ECC<0>")
	)
	(segment
		(start 235.738924 -17.06753)
		(end 235.738924 -17.067022)
		(width 0.14224)
		(layer "In11.Cu")
		(net "M_B_ECC<0>")
	)
	(segment
		(start 235.984796 -16.82115)
		(end 235.984796 -16.448786)
		(width 0.14224)
		(layer "In11.Cu")
		(net "M_B_ECC<0>")
	)
	(segment
		(start 235.49991 -13.959078)
		(end 235.2548 -13.713968)
		(width 0.14224)
		(layer "In11.Cu")
		(net "M_B_ECC<0>")
	)
	(segment
		(start 235.951776 -8.780018)
		(end 236.171994 -8.5598)
		(width 0.14224)
		(layer "In11.Cu")
		(net "M_B_ECC<0>")
	)
	(segment
		(start 235.679996 -28.350972)
		(end 235.679996 -26.917396)
		(width 0.14224)
		(layer "In11.Cu")
		(net "M_B_ECC<0>")
	)
	(segment
		(start 235.959396 -26.637996)
		(end 235.959396 -23.386796)
		(width 0.14224)
		(layer "In11.Cu")
		(net "M_B_ECC<0>")
	)
	(segment
		(start 235.984796 -16.448786)
		(end 235.49991 -15.9639)
		(width 0.14224)
		(layer "In11.Cu")
		(net "M_B_ECC<0>")
	)
	(segment
		(start 235.679996 -26.917396)
		(end 235.959396 -26.637996)
		(width 0.14224)
		(layer "In11.Cu")
		(net "M_B_ECC<0>")
	)
	(segment
		(start 235.959396 -21.336)
		(end 235.839 -21.215604)
		(width 0.14224)
		(layer "In11.Cu")
		(net "M_B_ECC<0>")
	)
	(segment
		(start 235.2548 -13.713968)
		(end 235.2548 -12.888976)
		(width 0.14224)
		(layer "In11.Cu")
		(net "M_B_ECC<0>")
	)
	(segment
		(start 235.2548 -12.888976)
		(end 235.951776 -12.192)
		(width 0.14224)
		(layer "In11.Cu")
		(net "M_B_ECC<0>")
	)
	(segment
		(start 235.738924 -17.067022)
		(end 235.984796 -16.82115)
		(width 0.14224)
		(layer "In11.Cu")
		(net "M_B_ECC<0>")
	)
	(segment
		(start 235.959396 -23.386796)
		(end 235.603796 -23.031196)
		(width 0.14224)
		(layer "In11.Cu")
		(net "M_B_ECC<0>")
	)
	(segment
		(start 235.951776 -12.192)
		(end 235.951776 -8.780018)
		(width 0.14224)
		(layer "In11.Cu")
		(net "M_B_ECC<0>")
	)
	(segment
		(start 235.705396 -17.101058)
		(end 235.738924 -17.06753)
		(width 0.14224)
		(layer "In11.Cu")
		(net "M_B_ECC<0>")
	)
	(segment
		(start 235.49991 -28.531058)
		(end 235.679996 -28.350972)
		(width 0.14224)
		(layer "In11.Cu")
		(net "M_B_ECC<0>")
	)
	(segment
		(start 235.49991 -15.9639)
		(end 235.49991 -13.959078)
		(width 0.14224)
		(layer "In11.Cu")
		(net "M_B_ECC<0>")
	)
	(segment
		(start 235.603796 -23.031196)
		(end 235.603796 -22.065996)
		(width 0.14224)
		(layer "In11.Cu")
		(net "M_B_ECC<0>")
	)
	(segment
		(start 235.959396 -19.082004)
		(end 235.959396 -18.61185)
		(width 0.14224)
		(layer "In11.Cu")
		(net "M_B_ECC<0>")
	)
	(segment
		(start 235.839 -19.2024)
		(end 235.959396 -19.082004)
		(width 0.14224)
		(layer "In11.Cu")
		(net "M_B_ECC<0>")
	)
	(segment
		(start 235.705396 -18.35785)
		(end 235.705396 -17.101058)
		(width 0.14224)
		(layer "In11.Cu")
		(net "M_B_ECC<0>")
	)
	(segment
		(start 235.959396 -18.61185)
		(end 235.705396 -18.35785)
		(width 0.14224)
		(layer "In11.Cu")
		(net "M_B_ECC<0>")
	)
	(segment
		(start 235.959396 -21.710396)
		(end 235.959396 -21.336)
		(width 0.14224)
		(layer "In11.Cu")
		(net "M_B_ECC<0>")
	)
	(segment
		(start 235.603796 -22.065996)
		(end 235.959396 -21.710396)
		(width 0.14224)
		(layer "In11.Cu")
		(net "M_B_ECC<0>")
	)
	(segment
		(start 199.279256 -7.877302)
		(end 199.36079 -8.101584)
		(width 0.1651)
		(layer "F.Cu")
		(net "M_B_DQS_DP<9>")
	)
	(segment
		(start 199.799956 -6.439154)
		(end 199.363838 -6.875272)
		(width 0.1651)
		(layer "F.Cu")
		(net "M_B_DQS_DP<9>")
	)
	(segment
		(start 199.36079 -8.101584)
		(end 199.742552 -8.483346)
		(width 0.1651)
		(layer "F.Cu")
		(net "M_B_DQS_DP<9>")
	)
	(segment
		(start 199.363838 -6.875272)
		(end 199.279256 -7.059168)
		(width 0.1651)
		(layer "F.Cu")
		(net "M_B_DQS_DP<9>")
	)
	(segment
		(start 237.042198 -66.982086)
		(end 236.470698 -66.982086)
		(width 0.0889)
		(layer "F.Cu")
		(net "M_B_DQS_DP<9>")
	)
	(segment
		(start 199.800464 -5.822442)
		(end 199.799956 -5.822442)
		(width 0.1651)
		(layer "F.Cu")
		(net "M_B_DQS_DP<9>")
	)
	(segment
		(start 199.279256 -7.059168)
		(end 199.279256 -7.877302)
		(width 0.1651)
		(layer "F.Cu")
		(net "M_B_DQS_DP<9>")
	)
	(segment
		(start 199.799956 -5.822442)
		(end 199.799956 -6.439154)
		(width 0.1651)
		(layer "F.Cu")
		(net "M_B_DQS_DP<9>")
	)
	(via
		(at 199.742552 -12.573)
		(size 0.508)
		(drill 0.254)
		(layers "F.Cu" "B.Cu")
		(net "M_B_DQS_DP<9>")
	)
	(via
		(at 236.470698 -66.982086)
		(size 0.508)
		(drill 0.254)
		(layers "F.Cu" "B.Cu")
		(net "M_B_DQS_DP<9>")
	)
	(via
		(at 199.742552 -8.483346)
		(size 0.508)
		(drill 0.254)
		(layers "F.Cu" "B.Cu")
		(net "M_B_DQS_DP<9>")
	)
	(segment
		(start 199.799956 -14.605254)
		(end 199.343772 -14.14907)
		(width 0.1651)
		(layer "B.Cu")
		(net "M_B_DQS_DP<9>")
	)
	(segment
		(start 199.353932 -12.96162)
		(end 199.742552 -12.573)
		(width 0.1651)
		(layer "B.Cu")
		(net "M_B_DQS_DP<9>")
	)
	(segment
		(start 199.799956 -15.222982)
		(end 199.799956 -14.605254)
		(width 0.1651)
		(layer "B.Cu")
		(net "M_B_DQS_DP<9>")
	)
	(segment
		(start 199.343772 -14.14907)
		(end 199.266556 -14.016736)
		(width 0.1651)
		(layer "B.Cu")
		(net "M_B_DQS_DP<9>")
	)
	(segment
		(start 199.266556 -14.016736)
		(end 199.266556 -13.121132)
		(width 0.1651)
		(layer "B.Cu")
		(net "M_B_DQS_DP<9>")
	)
	(segment
		(start 199.800464 -15.222982)
		(end 199.799956 -15.222982)
		(width 0.1651)
		(layer "B.Cu")
		(net "M_B_DQS_DP<9>")
	)
	(segment
		(start 199.266556 -13.121132)
		(end 199.353932 -12.96162)
		(width 0.1651)
		(layer "B.Cu")
		(net "M_B_DQS_DP<9>")
	)
	(segment
		(start 199.976486 -30.604968)
		(end 199.59828 -30.983174)
		(width 0.14224)
		(layer "In4.Cu")
		(net "M_B_DQS_DP<9>")
	)
	(segment
		(start 232.484422 -67.273678)
		(end 232.48493 -67.274694)
		(width 0.0889)
		(layer "In4.Cu")
		(net "M_B_DQS_DP<9>")
	)
	(segment
		(start 204.435964 -41.86301)
		(end 219.293694 -56.72074)
		(width 0.14224)
		(layer "In4.Cu")
		(net "M_B_DQS_DP<9>")
	)
	(segment
		(start 200.053956 -10.1854)
		(end 200.262236 -10.39368)
		(width 0.14224)
		(layer "In4.Cu")
		(net "M_B_DQS_DP<9>")
	)
	(segment
		(start 200.015856 -11.4427)
		(end 200.262236 -11.68908)
		(width 0.14224)
		(layer "In4.Cu")
		(net "M_B_DQS_DP<9>")
	)
	(segment
		(start 199.950578 -8.27532)
		(end 200.081642 -8.27532)
		(width 0.14224)
		(layer "In4.Cu")
		(net "M_B_DQS_DP<9>")
	)
	(segment
		(start 219.737686 -56.72074)
		(end 230.133906 -67.11696)
		(width 0.14224)
		(layer "In4.Cu")
		(net "M_B_DQS_DP<9>")
	)
	(segment
		(start 200.262236 -8.455914)
		(end 200.262236 -9.29132)
		(width 0.14224)
		(layer "In4.Cu")
		(net "M_B_DQS_DP<9>")
	)
	(segment
		(start 201.818494 -39.24554)
		(end 203.774294 -39.24554)
		(width 0.14224)
		(layer "In4.Cu")
		(net "M_B_DQS_DP<9>")
	)
	(segment
		(start 232.485184 -67.27444)
		(end 232.484422 -67.273678)
		(width 0.0889)
		(layer "In4.Cu")
		(net "M_B_DQS_DP<9>")
	)
	(segment
		(start 199.69988 -28.936696)
		(end 200.56348 -29.800296)
		(width 0.14224)
		(layer "In4.Cu")
		(net "M_B_DQS_DP<9>")
	)
	(segment
		(start 199.271636 -15.221712)
		(end 200.255632 -16.205708)
		(width 0.14224)
		(layer "In4.Cu")
		(net "M_B_DQS_DP<9>")
	)
	(segment
		(start 199.976486 -32.220408)
		(end 200.265792 -32.220408)
		(width 0.14224)
		(layer "In4.Cu")
		(net "M_B_DQS_DP<9>")
	)
	(segment
		(start 200.262236 -10.39368)
		(end 200.262236 -10.63752)
		(width 0.14224)
		(layer "In4.Cu")
		(net "M_B_DQS_DP<9>")
	)
	(segment
		(start 199.927464 -11.4427)
		(end 200.015856 -11.4427)
		(width 0.14224)
		(layer "In4.Cu")
		(net "M_B_DQS_DP<9>")
	)
	(segment
		(start 200.021698 -12.573)
		(end 199.742552 -12.573)
		(width 0.14224)
		(layer "In4.Cu")
		(net "M_B_DQS_DP<9>")
	)
	(segment
		(start 199.59828 -30.983174)
		(end 199.59828 -31.842202)
		(width 0.14224)
		(layer "In4.Cu")
		(net "M_B_DQS_DP<9>")
	)
	(segment
		(start 200.262236 -11.68908)
		(end 200.262236 -12.332462)
		(width 0.14224)
		(layer "In4.Cu")
		(net "M_B_DQS_DP<9>")
	)
	(segment
		(start 200.262236 -9.29132)
		(end 199.774556 -9.779)
		(width 0.14224)
		(layer "In4.Cu")
		(net "M_B_DQS_DP<9>")
	)
	(segment
		(start 200.265792 -32.220408)
		(end 200.48728 -32.441896)
		(width 0.14224)
		(layer "In4.Cu")
		(net "M_B_DQS_DP<9>")
	)
	(segment
		(start 200.255632 -16.205708)
		(end 200.255632 -27.69108)
		(width 0.14224)
		(layer "In4.Cu")
		(net "M_B_DQS_DP<9>")
	)
	(segment
		(start 230.133906 -67.11696)
		(end 230.632 -67.11696)
		(width 0.14224)
		(layer "In4.Cu")
		(net "M_B_DQS_DP<9>")
	)
	(segment
		(start 204.435964 -39.90721)
		(end 204.435964 -41.86301)
		(width 0.14224)
		(layer "In4.Cu")
		(net "M_B_DQS_DP<9>")
	)
	(segment
		(start 234.771946 -68.563236)
		(end 234.73537 -68.563236)
		(width 0.0889)
		(layer "In4.Cu")
		(net "M_B_DQS_DP<9>")
	)
	(segment
		(start 200.262236 -10.63752)
		(end 200.079356 -10.8204)
		(width 0.14224)
		(layer "In4.Cu")
		(net "M_B_DQS_DP<9>")
	)
	(segment
		(start 203.774294 -39.24554)
		(end 204.435964 -39.90721)
		(width 0.14224)
		(layer "In4.Cu")
		(net "M_B_DQS_DP<9>")
	)
	(segment
		(start 232.15854 -67.07759)
		(end 232.158286 -67.077844)
		(width 0.0889)
		(layer "In4.Cu")
		(net "M_B_DQS_DP<9>")
	)
	(segment
		(start 219.293694 -56.72074)
		(end 219.737686 -56.72074)
		(width 0.14224)
		(layer "In4.Cu")
		(net "M_B_DQS_DP<9>")
	)
	(segment
		(start 199.771 -10.947908)
		(end 199.771 -11.286236)
		(width 0.14224)
		(layer "In4.Cu")
		(net "M_B_DQS_DP<9>")
	)
	(segment
		(start 199.742552 -8.483346)
		(end 199.950578 -8.27532)
		(width 0.14224)
		(layer "In4.Cu")
		(net "M_B_DQS_DP<9>")
	)
	(segment
		(start 199.898508 -10.8204)
		(end 199.771 -10.947908)
		(width 0.14224)
		(layer "In4.Cu")
		(net "M_B_DQS_DP<9>")
	)
	(segment
		(start 235.598716 -67.877436)
		(end 235.325412 -68.189094)
		(width 0.0889)
		(layer "In4.Cu")
		(net "M_B_DQS_DP<9>")
	)
	(segment
		(start 233.047794 -67.572636)
		(end 232.833418 -67.572636)
		(width 0.0889)
		(layer "In4.Cu")
		(net "M_B_DQS_DP<9>")
	)
	(segment
		(start 199.774556 -9.779)
		(end 199.774556 -10.033)
		(width 0.14224)
		(layer "In4.Cu")
		(net "M_B_DQS_DP<9>")
	)
	(segment
		(start 233.910124 -68.06819)
		(end 233.877358 -68.06819)
		(width 0.0889)
		(layer "In4.Cu")
		(net "M_B_DQS_DP<9>")
	)
	(segment
		(start 200.48728 -32.441896)
		(end 200.48728 -33.076642)
		(width 0.14224)
		(layer "In4.Cu")
		(net "M_B_DQS_DP<9>")
	)
	(segment
		(start 199.774556 -10.033)
		(end 199.926956 -10.1854)
		(width 0.14224)
		(layer "In4.Cu")
		(net "M_B_DQS_DP<9>")
	)
	(segment
		(start 199.59828 -37.025326)
		(end 201.818494 -39.24554)
		(width 0.14224)
		(layer "In4.Cu")
		(net "M_B_DQS_DP<9>")
	)
	(segment
		(start 230.654098 -67.11696)
		(end 230.693468 -67.07759)
		(width 0.0889)
		(layer "In4.Cu")
		(net "M_B_DQS_DP<9>")
	)
	(segment
		(start 200.262236 -12.332462)
		(end 200.021698 -12.573)
		(width 0.14224)
		(layer "In4.Cu")
		(net "M_B_DQS_DP<9>")
	)
	(segment
		(start 199.926956 -10.1854)
		(end 200.053956 -10.1854)
		(width 0.14224)
		(layer "In4.Cu")
		(net "M_B_DQS_DP<9>")
	)
	(segment
		(start 200.255632 -27.69108)
		(end 199.69988 -28.246832)
		(width 0.14224)
		(layer "In4.Cu")
		(net "M_B_DQS_DP<9>")
	)
	(segment
		(start 200.56348 -29.800296)
		(end 200.56348 -30.30728)
		(width 0.14224)
		(layer "In4.Cu")
		(net "M_B_DQS_DP<9>")
	)
	(segment
		(start 199.59828 -31.842202)
		(end 199.976486 -32.220408)
		(width 0.14224)
		(layer "In4.Cu")
		(net "M_B_DQS_DP<9>")
	)
	(segment
		(start 200.079356 -10.8204)
		(end 199.898508 -10.8204)
		(width 0.14224)
		(layer "In4.Cu")
		(net "M_B_DQS_DP<9>")
	)
	(segment
		(start 200.265792 -30.604968)
		(end 199.976486 -30.604968)
		(width 0.14224)
		(layer "In4.Cu")
		(net "M_B_DQS_DP<9>")
	)
	(segment
		(start 200.48728 -33.076642)
		(end 199.59828 -33.965642)
		(width 0.14224)
		(layer "In4.Cu")
		(net "M_B_DQS_DP<9>")
	)
	(segment
		(start 199.69988 -28.246832)
		(end 199.69988 -28.936696)
		(width 0.14224)
		(layer "In4.Cu")
		(net "M_B_DQS_DP<9>")
	)
	(segment
		(start 230.693468 -67.07759)
		(end 232.15854 -67.07759)
		(width 0.0889)
		(layer "In4.Cu")
		(net "M_B_DQS_DP<9>")
	)
	(segment
		(start 199.742552 -12.573)
		(end 199.271636 -13.043916)
		(width 0.14224)
		(layer "In4.Cu")
		(net "M_B_DQS_DP<9>")
	)
	(segment
		(start 200.56348 -30.30728)
		(end 200.265792 -30.604968)
		(width 0.14224)
		(layer "In4.Cu")
		(net "M_B_DQS_DP<9>")
	)
	(segment
		(start 199.271636 -13.043916)
		(end 199.271636 -15.221712)
		(width 0.14224)
		(layer "In4.Cu")
		(net "M_B_DQS_DP<9>")
	)
	(segment
		(start 230.632 -67.11696)
		(end 230.654098 -67.11696)
		(width 0.0889)
		(layer "In4.Cu")
		(net "M_B_DQS_DP<9>")
	)
	(segment
		(start 199.59828 -33.965642)
		(end 199.59828 -37.025326)
		(width 0.14224)
		(layer "In4.Cu")
		(net "M_B_DQS_DP<9>")
	)
	(segment
		(start 200.081642 -8.27532)
		(end 200.262236 -8.455914)
		(width 0.14224)
		(layer "In4.Cu")
		(net "M_B_DQS_DP<9>")
	)
	(segment
		(start 199.771 -11.286236)
		(end 199.927464 -11.4427)
		(width 0.14224)
		(layer "In4.Cu")
		(net "M_B_DQS_DP<9>")
	)
	(arc
		(start 233.877358 -68.06819)
		(mid 233.591934 -67.984723)
		(end 233.383328 -67.772788)
		(width 0.0889)
		(layer "In4.Cu")
		(net "M_B_DQS_DP<9>")
	)
	(arc
		(start 236.470698 -66.982086)
		(mid 236.195374 -67.315389)
		(end 235.958888 -67.677284)
		(width 0.0889)
		(layer "In4.Cu")
		(net "M_B_DQS_DP<9>")
	)
	(arc
		(start 235.325412 -68.189094)
		(mid 235.302562 -68.214579)
		(end 235.281978 -68.241926)
		(width 0.0889)
		(layer "In4.Cu")
		(net "M_B_DQS_DP<9>")
	)
	(arc
		(start 234.73537 -68.563236)
		(mid 234.450323 -68.479708)
		(end 234.241848 -68.268088)
		(width 0.0889)
		(layer "In4.Cu")
		(net "M_B_DQS_DP<9>")
	)
	(arc
		(start 235.281978 -68.241926)
		(mid 235.273468 -68.254846)
		(end 235.265468 -68.268088)
		(width 0.0889)
		(layer "In4.Cu")
		(net "M_B_DQS_DP<9>")
	)
	(arc
		(start 235.265468 -68.268088)
		(mid 235.057049 -68.479801)
		(end 234.771946 -68.563236)
		(width 0.0889)
		(layer "In4.Cu")
		(net "M_B_DQS_DP<9>")
	)
	(arc
		(start 235.958888 -67.677284)
		(mid 235.806529 -67.827235)
		(end 235.598716 -67.877436)
		(width 0.0889)
		(layer "In4.Cu")
		(net "M_B_DQS_DP<9>")
	)
	(arc
		(start 232.158286 -67.077844)
		(mid 232.348981 -67.1308)
		(end 232.485184 -67.27444)
		(width 0.0889)
		(layer "In4.Cu")
		(net "M_B_DQS_DP<9>")
	)
	(arc
		(start 234.241848 -68.268088)
		(mid 234.101769 -68.125352)
		(end 233.910124 -68.06819)
		(width 0.0889)
		(layer "In4.Cu")
		(net "M_B_DQS_DP<9>")
	)
	(arc
		(start 233.383328 -67.772788)
		(mid 233.241645 -67.628984)
		(end 233.047794 -67.572636)
		(width 0.0889)
		(layer "In4.Cu")
		(net "M_B_DQS_DP<9>")
	)
	(arc
		(start 232.48493 -67.274694)
		(mid 232.630855 -67.456781)
		(end 232.833418 -67.572636)
		(width 0.0889)
		(layer "In4.Cu")
		(net "M_B_DQS_DP<9>")
	)
	(segment
		(start 248.202704 -54.59984)
		(end 248.022618 -54.813708)
		(width 0.0889)
		(layer "F.Cu")
		(net "M_B_DQS_DP<8>")
	)
	(segment
		(start 241.2111 -34.563558)
		(end 241.0841 -34.690558)
		(width 0.1651)
		(layer "F.Cu")
		(net "M_B_DQS_DP<8>")
	)
	(segment
		(start 239.004856 -28.007056)
		(end 239.1664 -28.1686)
		(width 0.1651)
		(layer "F.Cu")
		(net "M_B_DQS_DP<8>")
	)
	(segment
		(start 240.5761 -39.425118)
		(end 240.4491 -39.552118)
		(width 0.1651)
		(layer "F.Cu")
		(net "M_B_DQS_DP<8>")
	)
	(segment
		(start 243.949728 -43.431714)
		(end 243.28501 -42.766996)
		(width 0.1016)
		(layer "F.Cu")
		(net "M_B_DQS_DP<8>")
	)
	(segment
		(start 241.185446 -33.817052)
		(end 241.0841 -33.918398)
		(width 0.1651)
		(layer "F.Cu")
		(net "M_B_DQS_DP<8>")
	)
	(segment
		(start 240.5761 -39.933118)
		(end 240.5761 -40.187118)
		(width 0.1651)
		(layer "F.Cu")
		(net "M_B_DQS_DP<8>")
	)
	(segment
		(start 241.553492 -42.38371)
		(end 241.61115 -42.441368)
		(width 0.1016)
		(layer "F.Cu")
		(net "M_B_DQS_DP<8>")
	)
	(segment
		(start 240.31702 -31.310834)
		(end 240.31702 -31.496762)
		(width 0.1651)
		(layer "F.Cu")
		(net "M_B_DQS_DP<8>")
	)
	(segment
		(start 241.0841 -34.944558)
		(end 241.2111 -35.071558)
		(width 0.1651)
		(layer "F.Cu")
		(net "M_B_DQS_DP<8>")
	)
	(segment
		(start 248.716546 -50.929032)
		(end 248.853198 -50.684176)
		(width 0.0889)
		(layer "F.Cu")
		(net "M_B_DQS_DP<8>")
	)
	(segment
		(start 240.4491 -40.568118)
		(end 240.9317 -41.050718)
		(width 0.1651)
		(layer "F.Cu")
		(net "M_B_DQS_DP<8>")
	)
	(segment
		(start 248.66092 -52.124864)
		(end 248.66092 -51.138328)
		(width 0.0889)
		(layer "F.Cu")
		(net "M_B_DQS_DP<8>")
	)
	(segment
		(start 240.4491 -39.806118)
		(end 240.5761 -39.933118)
		(width 0.1651)
		(layer "F.Cu")
		(net "M_B_DQS_DP<8>")
	)
	(segment
		(start 239.1664 -28.1686)
		(end 239.1664 -28.6258)
		(width 0.1651)
		(layer "F.Cu")
		(net "M_B_DQS_DP<8>")
	)
	(segment
		(start 248.714514 -50.932842)
		(end 248.716546 -50.929032)
		(width 0.0889)
		(layer "F.Cu")
		(net "M_B_DQS_DP<8>")
	)
	(segment
		(start 239.565688 -30.559502)
		(end 240.31702 -31.310834)
		(width 0.1651)
		(layer "F.Cu")
		(net "M_B_DQS_DP<8>")
	)
	(segment
		(start 240.9317 -41.761918)
		(end 241.553492 -42.38371)
		(width 0.1651)
		(layer "F.Cu")
		(net "M_B_DQS_DP<8>")
	)
	(segment
		(start 248.853198 -50.073814)
		(end 248.853198 -47.870364)
		(width 0.1016)
		(layer "F.Cu")
		(net "M_B_DQS_DP<8>")
	)
	(segment
		(start 238.444532 -28.007056)
		(end 239.004856 -28.007056)
		(width 0.1651)
		(layer "F.Cu")
		(net "M_B_DQS_DP<8>")
	)
	(segment
		(start 240.5761 -40.187118)
		(end 240.4491 -40.314118)
		(width 0.1651)
		(layer "F.Cu")
		(net "M_B_DQS_DP<8>")
	)
	(segment
		(start 241.0841 -35.452558)
		(end 241.0841 -35.706558)
		(width 0.1651)
		(layer "F.Cu")
		(net "M_B_DQS_DP<8>")
	)
	(segment
		(start 238.633 -29.1592)
		(end 238.633 -29.812742)
		(width 0.1651)
		(layer "F.Cu")
		(net "M_B_DQS_DP<8>")
	)
	(segment
		(start 238.9378 -8.001)
		(end 238.69396 -7.75716)
		(width 0.1651)
		(layer "F.Cu")
		(net "M_B_DQS_DP<8>")
	)
	(segment
		(start 242.959382 -42.441368)
		(end 243.28501 -42.766996)
		(width 0.1016)
		(layer "F.Cu")
		(net "M_B_DQS_DP<8>")
	)
	(segment
		(start 248.187718 -54.19979)
		(end 248.220484 -54.19979)
		(width 0.0889)
		(layer "F.Cu")
		(net "M_B_DQS_DP<8>")
	)
	(segment
		(start 241.2111 -35.833558)
		(end 241.2111 -36.087558)
		(width 0.1651)
		(layer "F.Cu")
		(net "M_B_DQS_DP<8>")
	)
	(segment
		(start 238.900462 -10.422382)
		(end 238.899954 -10.422382)
		(width 0.1651)
		(layer "F.Cu")
		(net "M_B_DQS_DP<8>")
	)
	(segment
		(start 240.4491 -39.044118)
		(end 240.5761 -39.171118)
		(width 0.1651)
		(layer "F.Cu")
		(net "M_B_DQS_DP<8>")
	)
	(segment
		(start 241.2111 -34.309558)
		(end 241.2111 -34.563558)
		(width 0.1651)
		(layer "F.Cu")
		(net "M_B_DQS_DP<8>")
	)
	(segment
		(start 240.4491 -40.314118)
		(end 240.4491 -40.568118)
		(width 0.1651)
		(layer "F.Cu")
		(net "M_B_DQS_DP<8>")
	)
	(segment
		(start 244.414548 -43.431714)
		(end 243.949728 -43.431714)
		(width 0.1016)
		(layer "F.Cu")
		(net "M_B_DQS_DP<8>")
	)
	(segment
		(start 241.0841 -33.918398)
		(end 241.0841 -34.182558)
		(width 0.1651)
		(layer "F.Cu")
		(net "M_B_DQS_DP<8>")
	)
	(segment
		(start 241.2111 -35.071558)
		(end 241.2111 -35.325558)
		(width 0.1651)
		(layer "F.Cu")
		(net "M_B_DQS_DP<8>")
	)
	(segment
		(start 241.0841 -34.182558)
		(end 241.2111 -34.309558)
		(width 0.1651)
		(layer "F.Cu")
		(net "M_B_DQS_DP<8>")
	)
	(segment
		(start 240.31702 -31.496762)
		(end 241.0841 -32.263842)
		(width 0.1651)
		(layer "F.Cu")
		(net "M_B_DQS_DP<8>")
	)
	(segment
		(start 240.4491 -38.282118)
		(end 240.5761 -38.409118)
		(width 0.1651)
		(layer "F.Cu")
		(net "M_B_DQS_DP<8>")
	)
	(segment
		(start 241.185446 -33.563052)
		(end 241.185446 -33.817052)
		(width 0.1651)
		(layer "F.Cu")
		(net "M_B_DQS_DP<8>")
	)
	(segment
		(start 248.709688 -52.922424)
		(end 248.714514 -52.913788)
		(width 0.0889)
		(layer "F.Cu")
		(net "M_B_DQS_DP<8>")
	)
	(segment
		(start 241.2111 -36.087558)
		(end 241.0841 -36.214558)
		(width 0.1651)
		(layer "F.Cu")
		(net "M_B_DQS_DP<8>")
	)
	(segment
		(start 241.0841 -36.468558)
		(end 240.9317 -36.620958)
		(width 0.1651)
		(layer "F.Cu")
		(net "M_B_DQS_DP<8>")
	)
	(segment
		(start 238.899954 -9.410446)
		(end 238.9378 -9.3726)
		(width 0.1651)
		(layer "F.Cu")
		(net "M_B_DQS_DP<8>")
	)
	(segment
		(start 248.853198 -50.684176)
		(end 248.853198 -50.073814)
		(width 0.0889)
		(layer "F.Cu")
		(net "M_B_DQS_DP<8>")
	)
	(segment
		(start 240.4491 -39.552118)
		(end 240.4491 -39.806118)
		(width 0.1651)
		(layer "F.Cu")
		(net "M_B_DQS_DP<8>")
	)
	(segment
		(start 248.853198 -47.870364)
		(end 244.414548 -43.431714)
		(width 0.1016)
		(layer "F.Cu")
		(net "M_B_DQS_DP<8>")
	)
	(segment
		(start 241.0841 -32.263842)
		(end 241.0841 -33.461706)
		(width 0.1651)
		(layer "F.Cu")
		(net "M_B_DQS_DP<8>")
	)
	(segment
		(start 241.0841 -35.706558)
		(end 241.2111 -35.833558)
		(width 0.1651)
		(layer "F.Cu")
		(net "M_B_DQS_DP<8>")
	)
	(segment
		(start 241.0841 -34.690558)
		(end 241.0841 -34.944558)
		(width 0.1651)
		(layer "F.Cu")
		(net "M_B_DQS_DP<8>")
	)
	(segment
		(start 238.69396 -7.75716)
		(end 238.437928 -7.75716)
		(width 0.1651)
		(layer "F.Cu")
		(net "M_B_DQS_DP<8>")
	)
	(segment
		(start 240.5761 -38.409118)
		(end 240.5761 -38.663118)
		(width 0.1651)
		(layer "F.Cu")
		(net "M_B_DQS_DP<8>")
	)
	(segment
		(start 239.37976 -30.559502)
		(end 239.565688 -30.559502)
		(width 0.1651)
		(layer "F.Cu")
		(net "M_B_DQS_DP<8>")
	)
	(segment
		(start 241.61115 -42.441368)
		(end 242.959382 -42.441368)
		(width 0.1016)
		(layer "F.Cu")
		(net "M_B_DQS_DP<8>")
	)
	(segment
		(start 240.5761 -38.663118)
		(end 240.4491 -38.790118)
		(width 0.1651)
		(layer "F.Cu")
		(net "M_B_DQS_DP<8>")
	)
	(segment
		(start 241.0841 -33.461706)
		(end 241.185446 -33.563052)
		(width 0.1651)
		(layer "F.Cu")
		(net "M_B_DQS_DP<8>")
	)
	(segment
		(start 240.4491 -37.963602)
		(end 240.4491 -38.282118)
		(width 0.1651)
		(layer "F.Cu")
		(net "M_B_DQS_DP<8>")
	)
	(segment
		(start 248.720864 -52.333906)
		(end 248.714514 -52.323238)
		(width 0.0889)
		(layer "F.Cu")
		(net "M_B_DQS_DP<8>")
	)
	(segment
		(start 240.9317 -37.481002)
		(end 240.4491 -37.963602)
		(width 0.1651)
		(layer "F.Cu")
		(net "M_B_DQS_DP<8>")
	)
	(segment
		(start 240.5761 -39.171118)
		(end 240.5761 -39.425118)
		(width 0.1651)
		(layer "F.Cu")
		(net "M_B_DQS_DP<8>")
	)
	(segment
		(start 238.899954 -10.422382)
		(end 238.899954 -9.410446)
		(width 0.1651)
		(layer "F.Cu")
		(net "M_B_DQS_DP<8>")
	)
	(segment
		(start 238.633 -29.812742)
		(end 239.37976 -30.559502)
		(width 0.1651)
		(layer "F.Cu")
		(net "M_B_DQS_DP<8>")
	)
	(segment
		(start 239.1664 -28.6258)
		(end 238.633 -29.1592)
		(width 0.1651)
		(layer "F.Cu")
		(net "M_B_DQS_DP<8>")
	)
	(segment
		(start 248.022618 -54.813708)
		(end 247.891554 -54.813708)
		(width 0.0889)
		(layer "F.Cu")
		(net "M_B_DQS_DP<8>")
	)
	(segment
		(start 240.9317 -41.050718)
		(end 240.9317 -41.761918)
		(width 0.1651)
		(layer "F.Cu")
		(net "M_B_DQS_DP<8>")
	)
	(segment
		(start 241.2111 -35.325558)
		(end 241.0841 -35.452558)
		(width 0.1651)
		(layer "F.Cu")
		(net "M_B_DQS_DP<8>")
	)
	(segment
		(start 238.9378 -9.3726)
		(end 238.9378 -8.001)
		(width 0.1651)
		(layer "F.Cu")
		(net "M_B_DQS_DP<8>")
	)
	(segment
		(start 240.4491 -38.790118)
		(end 240.4491 -39.044118)
		(width 0.1651)
		(layer "F.Cu")
		(net "M_B_DQS_DP<8>")
	)
	(segment
		(start 241.0841 -36.214558)
		(end 241.0841 -36.468558)
		(width 0.1651)
		(layer "F.Cu")
		(net "M_B_DQS_DP<8>")
	)
	(segment
		(start 240.9317 -36.620958)
		(end 240.9317 -37.481002)
		(width 0.1651)
		(layer "F.Cu")
		(net "M_B_DQS_DP<8>")
	)
	(via
		(at 238.437928 -7.75716)
		(size 0.508)
		(drill 0.254)
		(layers "F.Cu" "B.Cu")
		(net "M_B_DQS_DP<8>")
	)
	(via
		(at 238.444532 -28.007056)
		(size 0.508)
		(drill 0.254)
		(layers "F.Cu" "B.Cu")
		(net "M_B_DQS_DP<8>")
	)
	(via
		(at 238.437928 -13.287756)
		(size 0.508)
		(drill 0.254)
		(layers "F.Cu" "B.Cu")
		(net "M_B_DQS_DP<8>")
	)
	(arc
		(start 248.66092 -51.138328)
		(mid 248.673842 -51.031966)
		(end 248.714514 -50.932842)
		(width 0.0889)
		(layer "F.Cu")
		(net "M_B_DQS_DP<8>")
	)
	(arc
		(start 247.891554 -54.813708)
		(mid 247.854805 -54.41755)
		(end 248.187718 -54.19979)
		(width 0.0889)
		(layer "F.Cu")
		(net "M_B_DQS_DP<8>")
	)
	(arc
		(start 248.714514 -53.313838)
		(mid 248.661044 -53.118775)
		(end 248.709688 -52.922424)
		(width 0.0889)
		(layer "F.Cu")
		(net "M_B_DQS_DP<8>")
	)
	(arc
		(start 248.714514 -52.913788)
		(mid 248.793736 -52.62467)
		(end 248.720864 -52.333906)
		(width 0.0889)
		(layer "F.Cu")
		(net "M_B_DQS_DP<8>")
	)
	(arc
		(start 248.220484 -54.19979)
		(mid 248.718735 -53.89695)
		(end 248.714514 -53.313838)
		(width 0.0889)
		(layer "F.Cu")
		(net "M_B_DQS_DP<8>")
	)
	(arc
		(start 248.714514 -52.323238)
		(mid 248.674758 -52.22755)
		(end 248.66092 -52.124864)
		(width 0.0889)
		(layer "F.Cu")
		(net "M_B_DQS_DP<8>")
	)
	(segment
		(start 238.9378 -11.811)
		(end 238.9378 -13.0302)
		(width 0.1651)
		(layer "B.Cu")
		(net "M_B_DQS_DP<8>")
	)
	(segment
		(start 238.9378 -13.0302)
		(end 238.680244 -13.287756)
		(width 0.1651)
		(layer "B.Cu")
		(net "M_B_DQS_DP<8>")
	)
	(segment
		(start 238.680244 -13.287756)
		(end 238.437928 -13.287756)
		(width 0.1651)
		(layer "B.Cu")
		(net "M_B_DQS_DP<8>")
	)
	(segment
		(start 238.899954 -10.623042)
		(end 238.899954 -11.773154)
		(width 0.1651)
		(layer "B.Cu")
		(net "M_B_DQS_DP<8>")
	)
	(segment
		(start 238.900462 -10.623042)
		(end 238.899954 -10.623042)
		(width 0.1651)
		(layer "B.Cu")
		(net "M_B_DQS_DP<8>")
	)
	(segment
		(start 238.899954 -11.773154)
		(end 238.9378 -11.811)
		(width 0.1651)
		(layer "B.Cu")
		(net "M_B_DQS_DP<8>")
	)
	(segment
		(start 239.204246 -15.150846)
		(end 238.721646 -14.668246)
		(width 0.14224)
		(layer "In11.Cu")
		(net "M_B_DQS_DP<8>")
	)
	(segment
		(start 239.248696 -8.567928)
		(end 238.437928 -7.75716)
		(width 0.14224)
		(layer "In11.Cu")
		(net "M_B_DQS_DP<8>")
	)
	(segment
		(start 238.901732 -14.201394)
		(end 238.901732 -13.75156)
		(width 0.14224)
		(layer "In11.Cu")
		(net "M_B_DQS_DP<8>")
	)
	(segment
		(start 239.204246 -27.240738)
		(end 239.204246 -15.150846)
		(width 0.14224)
		(layer "In11.Cu")
		(net "M_B_DQS_DP<8>")
	)
	(segment
		(start 238.901732 -13.75156)
		(end 238.437928 -13.287756)
		(width 0.14224)
		(layer "In11.Cu")
		(net "M_B_DQS_DP<8>")
	)
	(segment
		(start 238.721646 -14.38148)
		(end 238.901732 -14.201394)
		(width 0.14224)
		(layer "In11.Cu")
		(net "M_B_DQS_DP<8>")
	)
	(segment
		(start 239.248696 -12.476988)
		(end 239.248696 -8.567928)
		(width 0.14224)
		(layer "In11.Cu")
		(net "M_B_DQS_DP<8>")
	)
	(segment
		(start 238.444532 -28.000452)
		(end 239.204246 -27.240738)
		(width 0.14224)
		(layer "In11.Cu")
		(net "M_B_DQS_DP<8>")
	)
	(segment
		(start 238.721646 -14.668246)
		(end 238.721646 -14.38148)
		(width 0.14224)
		(layer "In11.Cu")
		(net "M_B_DQS_DP<8>")
	)
	(segment
		(start 238.437928 -13.287756)
		(end 239.248696 -12.476988)
		(width 0.14224)
		(layer "In11.Cu")
		(net "M_B_DQS_DP<8>")
	)
	(segment
		(start 238.444532 -28.007056)
		(end 238.444532 -28.000452)
		(width 0.14224)
		(layer "In11.Cu")
		(net "M_B_DQS_DP<8>")
	)
	(segment
		(start 312.661808 -8.146034)
		(end 312.857642 -8.146034)
		(width 0.1651)
		(layer "F.Cu")
		(net "M_B_DQS_DP<7>")
	)
	(segment
		(start 284.929834 -60.857384)
		(end 284.358334 -60.857384)
		(width 0.1016)
		(layer "F.Cu")
		(net "M_B_DQS_DP<7>")
	)
	(segment
		(start 312.857642 -8.146034)
		(end 313.07151 -8.359902)
		(width 0.1651)
		(layer "F.Cu")
		(net "M_B_DQS_DP<7>")
	)
	(segment
		(start 313.07151 -9.10209)
		(end 312.849768 -9.323832)
		(width 0.1651)
		(layer "F.Cu")
		(net "M_B_DQS_DP<7>")
	)
	(segment
		(start 313.07151 -8.359902)
		(end 313.07151 -9.10209)
		(width 0.1651)
		(layer "F.Cu")
		(net "M_B_DQS_DP<7>")
	)
	(segment
		(start 312.849768 -10.422382)
		(end 312.850276 -10.422382)
		(width 0.1651)
		(layer "F.Cu")
		(net "M_B_DQS_DP<7>")
	)
	(segment
		(start 312.849768 -9.323832)
		(end 312.849768 -10.422382)
		(width 0.1651)
		(layer "F.Cu")
		(net "M_B_DQS_DP<7>")
	)
	(segment
		(start 312.387996 -8.419846)
		(end 312.661808 -8.146034)
		(width 0.1651)
		(layer "F.Cu")
		(net "M_B_DQS_DP<7>")
	)
	(via
		(at 284.358334 -60.857384)
		(size 0.508)
		(drill 0.254)
		(layers "F.Cu" "B.Cu")
		(net "M_B_DQS_DP<7>")
	)
	(via
		(at 312.387996 -12.627356)
		(size 0.508)
		(drill 0.254)
		(layers "F.Cu" "B.Cu")
		(net "M_B_DQS_DP<7>")
	)
	(via
		(at 312.387996 -8.419846)
		(size 0.508)
		(drill 0.254)
		(layers "F.Cu" "B.Cu")
		(net "M_B_DQS_DP<7>")
	)
	(segment
		(start 312.66892 -12.90828)
		(end 312.387996 -12.627356)
		(width 0.1651)
		(layer "B.Cu")
		(net "M_B_DQS_DP<7>")
	)
	(segment
		(start 312.8899 -12.90828)
		(end 312.66892 -12.90828)
		(width 0.1651)
		(layer "B.Cu")
		(net "M_B_DQS_DP<7>")
	)
	(segment
		(start 312.849768 -12.139168)
		(end 313.0296 -12.319)
		(width 0.1651)
		(layer "B.Cu")
		(net "M_B_DQS_DP<7>")
	)
	(segment
		(start 312.850276 -10.623042)
		(end 312.849768 -10.623042)
		(width 0.1651)
		(layer "B.Cu")
		(net "M_B_DQS_DP<7>")
	)
	(segment
		(start 312.849768 -10.623042)
		(end 312.849768 -12.139168)
		(width 0.1651)
		(layer "B.Cu")
		(net "M_B_DQS_DP<7>")
	)
	(segment
		(start 313.0296 -12.76858)
		(end 312.8899 -12.90828)
		(width 0.1651)
		(layer "B.Cu")
		(net "M_B_DQS_DP<7>")
	)
	(segment
		(start 313.0296 -12.319)
		(end 313.0296 -12.76858)
		(width 0.1651)
		(layer "B.Cu")
		(net "M_B_DQS_DP<7>")
	)
	(segment
		(start 284.358334 -61.195458)
		(end 284.415992 -61.253116)
		(width 0.0889)
		(layer "In4.Cu")
		(net "M_B_DQS_DP<7>")
	)
	(segment
		(start 286.42183 -56.695086)
		(end 286.41548 -56.684418)
		(width 0.0889)
		(layer "In4.Cu")
		(net "M_B_DQS_DP<7>")
	)
	(segment
		(start 312.387996 -12.62761)
		(end 312.666888 -12.62761)
		(width 0.14224)
		(layer "In4.Cu")
		(net "M_B_DQS_DP<7>")
	)
	(segment
		(start 284.70479 -60.657486)
		(end 284.6959 -60.642246)
		(width 0.0889)
		(layer "In4.Cu")
		(net "M_B_DQS_DP<7>")
	)
	(segment
		(start 286.426656 -53.731922)
		(end 286.42183 -53.723286)
		(width 0.0889)
		(layer "In4.Cu")
		(net "M_B_DQS_DP<7>")
	)
	(segment
		(start 310.117744 -30.641544)
		(end 311.032144 -29.727144)
		(width 0.14224)
		(layer "In4.Cu")
		(net "M_B_DQS_DP<7>")
	)
	(segment
		(start 312.749946 -9.525)
		(end 312.929524 -9.345422)
		(width 0.14224)
		(layer "In4.Cu")
		(net "M_B_DQS_DP<7>")
	)
	(segment
		(start 286.426656 -55.713122)
		(end 286.42183 -55.704486)
		(width 0.0889)
		(layer "In4.Cu")
		(net "M_B_DQS_DP<7>")
	)
	(segment
		(start 309.7022 -31.056834)
		(end 310.117744 -30.641544)
		(width 0.14224)
		(layer "In4.Cu")
		(net "M_B_DQS_DP<7>")
	)
	(segment
		(start 312.929524 -10.339578)
		(end 312.724546 -10.1346)
		(width 0.14224)
		(layer "In4.Cu")
		(net "M_B_DQS_DP<7>")
	)
	(segment
		(start 312.901076 -15.95755)
		(end 311.94248 -14.998954)
		(width 0.14224)
		(layer "In4.Cu")
		(net "M_B_DQS_DP<7>")
	)
	(segment
		(start 312.547254 -10.1346)
		(end 312.3946 -9.981946)
		(width 0.14224)
		(layer "In4.Cu")
		(net "M_B_DQS_DP<7>")
	)
	(segment
		(start 312.7502 -11.4808)
		(end 312.619644 -11.4808)
		(width 0.14224)
		(layer "In4.Cu")
		(net "M_B_DQS_DP<7>")
	)
	(segment
		(start 312.746644 -10.8712)
		(end 312.929524 -10.68832)
		(width 0.14224)
		(layer "In4.Cu")
		(net "M_B_DQS_DP<7>")
	)
	(segment
		(start 287.28035 -52.637436)
		(end 287.763966 -52.15382)
		(width 0.0889)
		(layer "In4.Cu")
		(net "M_B_DQS_DP<7>")
	)
	(segment
		(start 309.55488 -33.146238)
		(end 309.55488 -31.204154)
		(width 0.14224)
		(layer "In4.Cu")
		(net "M_B_DQS_DP<7>")
	)
	(segment
		(start 311.94248 -14.998954)
		(end 311.94248 -13.072872)
		(width 0.14224)
		(layer "In4.Cu")
		(net "M_B_DQS_DP<7>")
	)
	(segment
		(start 312.387996 -12.627356)
		(end 312.387996 -12.62761)
		(width 0.14224)
		(layer "In4.Cu")
		(net "M_B_DQS_DP<7>")
	)
	(segment
		(start 312.3946 -9.981946)
		(end 312.3946 -9.677654)
		(width 0.14224)
		(layer "In4.Cu")
		(net "M_B_DQS_DP<7>")
	)
	(segment
		(start 309.55488 -31.204154)
		(end 309.7022 -31.056834)
		(width 0.14224)
		(layer "In4.Cu")
		(net "M_B_DQS_DP<7>")
	)
	(segment
		(start 290.570158 -50.196242)
		(end 290.570158 -50.034698)
		(width 0.14224)
		(layer "In4.Cu")
		(net "M_B_DQS_DP<7>")
	)
	(segment
		(start 290.74999 -49.854866)
		(end 290.911534 -49.854866)
		(width 0.14224)
		(layer "In4.Cu")
		(net "M_B_DQS_DP<7>")
	)
	(segment
		(start 289.706558 -51.059842)
		(end 290.008818 -50.757582)
		(width 0.14224)
		(layer "In4.Cu")
		(net "M_B_DQS_DP<7>")
	)
	(segment
		(start 295.775888 -46.92523)
		(end 309.55488 -33.146238)
		(width 0.14224)
		(layer "In4.Cu")
		(net "M_B_DQS_DP<7>")
	)
	(segment
		(start 289.364928 -51.401472)
		(end 289.364928 -51.239674)
		(width 0.14224)
		(layer "In4.Cu")
		(net "M_B_DQS_DP<7>")
	)
	(segment
		(start 312.441844 -11.049)
		(end 312.619644 -10.8712)
		(width 0.14224)
		(layer "In4.Cu")
		(net "M_B_DQS_DP<7>")
	)
	(segment
		(start 312.929524 -10.68832)
		(end 312.929524 -10.339578)
		(width 0.14224)
		(layer "In4.Cu")
		(net "M_B_DQS_DP<7>")
	)
	(segment
		(start 312.724546 -10.1346)
		(end 312.547254 -10.1346)
		(width 0.14224)
		(layer "In4.Cu")
		(net "M_B_DQS_DP<7>")
	)
	(segment
		(start 289.364928 -51.239674)
		(end 289.54476 -51.059842)
		(width 0.14224)
		(layer "In4.Cu")
		(net "M_B_DQS_DP<7>")
	)
	(segment
		(start 286.062166 -58.285634)
		(end 286.090106 -58.285634)
		(width 0.0889)
		(layer "In4.Cu")
		(net "M_B_DQS_DP<7>")
	)
	(segment
		(start 288.66846 -52.15382)
		(end 289.166046 -51.656234)
		(width 0.0889)
		(layer "In4.Cu")
		(net "M_B_DQS_DP<7>")
	)
	(segment
		(start 311.306718 -29.452062)
		(end 312.901076 -27.857704)
		(width 0.14224)
		(layer "In4.Cu")
		(net "M_B_DQS_DP<7>")
	)
	(segment
		(start 311.94248 -13.072872)
		(end 312.387996 -12.627356)
		(width 0.14224)
		(layer "In4.Cu")
		(net "M_B_DQS_DP<7>")
	)
	(segment
		(start 311.306718 -29.452316)
		(end 311.306718 -29.452062)
		(width 0.14224)
		(layer "In4.Cu")
		(net "M_B_DQS_DP<7>")
	)
	(segment
		(start 312.929524 -12.364974)
		(end 312.929524 -11.660124)
		(width 0.14224)
		(layer "In4.Cu")
		(net "M_B_DQS_DP<7>")
	)
	(segment
		(start 286.42183 -55.704486)
		(end 286.41548 -55.693818)
		(width 0.0889)
		(layer "In4.Cu")
		(net "M_B_DQS_DP<7>")
	)
	(segment
		(start 289.166046 -51.600354)
		(end 289.181794 -51.584606)
		(width 0.0889)
		(layer "In4.Cu")
		(net "M_B_DQS_DP<7>")
	)
	(segment
		(start 312.901076 -27.857704)
		(end 312.901076 -15.95755)
		(width 0.14224)
		(layer "In4.Cu")
		(net "M_B_DQS_DP<7>")
	)
	(segment
		(start 289.166046 -51.656234)
		(end 289.166046 -51.600354)
		(width 0.0889)
		(layer "In4.Cu")
		(net "M_B_DQS_DP<7>")
	)
	(segment
		(start 312.619644 -10.8712)
		(end 312.746644 -10.8712)
		(width 0.14224)
		(layer "In4.Cu")
		(net "M_B_DQS_DP<7>")
	)
	(segment
		(start 290.18865 -50.415952)
		(end 290.350448 -50.415952)
		(width 0.14224)
		(layer "In4.Cu")
		(net "M_B_DQS_DP<7>")
	)
	(segment
		(start 290.570158 -50.034698)
		(end 290.74999 -49.854866)
		(width 0.14224)
		(layer "In4.Cu")
		(net "M_B_DQS_DP<7>")
	)
	(segment
		(start 290.008818 -50.757582)
		(end 290.008818 -50.595784)
		(width 0.14224)
		(layer "In4.Cu")
		(net "M_B_DQS_DP<7>")
	)
	(segment
		(start 312.669682 -8.419846)
		(end 312.387996 -8.419846)
		(width 0.14224)
		(layer "In4.Cu")
		(net "M_B_DQS_DP<7>")
	)
	(segment
		(start 286.426656 -56.703722)
		(end 286.42183 -56.695086)
		(width 0.0889)
		(layer "In4.Cu")
		(net "M_B_DQS_DP<7>")
	)
	(segment
		(start 290.008818 -50.595784)
		(end 290.18865 -50.415952)
		(width 0.14224)
		(layer "In4.Cu")
		(net "M_B_DQS_DP<7>")
	)
	(segment
		(start 290.911534 -49.854866)
		(end 293.84117 -46.92523)
		(width 0.14224)
		(layer "In4.Cu")
		(net "M_B_DQS_DP<7>")
	)
	(segment
		(start 286.426656 -57.694322)
		(end 286.42183 -57.685686)
		(width 0.0889)
		(layer "In4.Cu")
		(net "M_B_DQS_DP<7>")
	)
	(segment
		(start 312.929524 -8.679688)
		(end 312.669682 -8.419846)
		(width 0.14224)
		(layer "In4.Cu")
		(net "M_B_DQS_DP<7>")
	)
	(segment
		(start 312.929524 -11.660124)
		(end 312.7502 -11.4808)
		(width 0.14224)
		(layer "In4.Cu")
		(net "M_B_DQS_DP<7>")
	)
	(segment
		(start 293.84117 -46.92523)
		(end 295.775888 -46.92523)
		(width 0.14224)
		(layer "In4.Cu")
		(net "M_B_DQS_DP<7>")
	)
	(segment
		(start 312.3946 -9.677654)
		(end 312.547254 -9.525)
		(width 0.14224)
		(layer "In4.Cu")
		(net "M_B_DQS_DP<7>")
	)
	(segment
		(start 312.666888 -12.62761)
		(end 312.929524 -12.364974)
		(width 0.14224)
		(layer "In4.Cu")
		(net "M_B_DQS_DP<7>")
	)
	(segment
		(start 312.547254 -9.525)
		(end 312.749946 -9.525)
		(width 0.14224)
		(layer "In4.Cu")
		(net "M_B_DQS_DP<7>")
	)
	(segment
		(start 286.42183 -54.713886)
		(end 286.41548 -54.703218)
		(width 0.0889)
		(layer "In4.Cu")
		(net "M_B_DQS_DP<7>")
	)
	(segment
		(start 286.91205 -52.837334)
		(end 286.951674 -52.837334)
		(width 0.0889)
		(layer "In4.Cu")
		(net "M_B_DQS_DP<7>")
	)
	(segment
		(start 290.350448 -50.415952)
		(end 290.570158 -50.196242)
		(width 0.14224)
		(layer "In4.Cu")
		(net "M_B_DQS_DP<7>")
	)
	(segment
		(start 284.358334 -60.857384)
		(end 284.358334 -61.195458)
		(width 0.0889)
		(layer "In4.Cu")
		(net "M_B_DQS_DP<7>")
	)
	(segment
		(start 287.763966 -52.15382)
		(end 288.66846 -52.15382)
		(width 0.0889)
		(layer "In4.Cu")
		(net "M_B_DQS_DP<7>")
	)
	(segment
		(start 312.619644 -11.4808)
		(end 312.441844 -11.303)
		(width 0.14224)
		(layer "In4.Cu")
		(net "M_B_DQS_DP<7>")
	)
	(segment
		(start 312.441844 -11.303)
		(end 312.441844 -11.049)
		(width 0.14224)
		(layer "In4.Cu")
		(net "M_B_DQS_DP<7>")
	)
	(segment
		(start 289.54476 -51.059842)
		(end 289.706558 -51.059842)
		(width 0.14224)
		(layer "In4.Cu")
		(net "M_B_DQS_DP<7>")
	)
	(segment
		(start 285.19882 -58.780934)
		(end 285.234634 -58.780934)
		(width 0.0889)
		(layer "In4.Cu")
		(net "M_B_DQS_DP<7>")
	)
	(segment
		(start 311.032144 -29.727144)
		(end 311.306718 -29.452316)
		(width 0.14224)
		(layer "In4.Cu")
		(net "M_B_DQS_DP<7>")
	)
	(segment
		(start 286.42183 -57.685686)
		(end 286.41548 -57.675018)
		(width 0.0889)
		(layer "In4.Cu")
		(net "M_B_DQS_DP<7>")
	)
	(segment
		(start 286.426656 -54.722522)
		(end 286.42183 -54.713886)
		(width 0.0889)
		(layer "In4.Cu")
		(net "M_B_DQS_DP<7>")
	)
	(segment
		(start 312.929524 -9.345422)
		(end 312.929524 -8.679688)
		(width 0.14224)
		(layer "In4.Cu")
		(net "M_B_DQS_DP<7>")
	)
	(segment
		(start 289.181794 -51.584606)
		(end 289.364928 -51.401472)
		(width 0.14224)
		(layer "In4.Cu")
		(net "M_B_DQS_DP<7>")
	)
	(arc
		(start 286.41548 -55.693818)
		(mid 286.342682 -55.403055)
		(end 286.42183 -55.113936)
		(width 0.0889)
		(layer "In4.Cu")
		(net "M_B_DQS_DP<7>")
	)
	(arc
		(start 286.42183 -56.104536)
		(mid 286.4753 -55.909473)
		(end 286.426656 -55.713122)
		(width 0.0889)
		(layer "In4.Cu")
		(net "M_B_DQS_DP<7>")
	)
	(arc
		(start 284.6959 -60.642246)
		(mid 284.625503 -60.353295)
		(end 284.70479 -60.066682)
		(width 0.0889)
		(layer "In4.Cu")
		(net "M_B_DQS_DP<7>")
	)
	(arc
		(start 286.951674 -52.837334)
		(mid 287.141603 -52.779464)
		(end 287.28035 -52.637436)
		(width 0.0889)
		(layer "In4.Cu")
		(net "M_B_DQS_DP<7>")
	)
	(arc
		(start 284.70479 -60.066682)
		(mid 284.758323 -59.866784)
		(end 284.70479 -59.666886)
		(width 0.0889)
		(layer "In4.Cu")
		(net "M_B_DQS_DP<7>")
	)
	(arc
		(start 286.090106 -58.285634)
		(mid 286.423024 -58.083643)
		(end 286.426656 -57.694322)
		(width 0.0889)
		(layer "In4.Cu")
		(net "M_B_DQS_DP<7>")
	)
	(arc
		(start 286.41548 -57.675018)
		(mid 286.342682 -57.384255)
		(end 286.42183 -57.095136)
		(width 0.0889)
		(layer "In4.Cu")
		(net "M_B_DQS_DP<7>")
	)
	(arc
		(start 284.704536 -61.057282)
		(mid 284.75823 -60.857413)
		(end 284.70479 -60.657486)
		(width 0.0889)
		(layer "In4.Cu")
		(net "M_B_DQS_DP<7>")
	)
	(arc
		(start 286.41548 -54.703218)
		(mid 286.342682 -54.412455)
		(end 286.42183 -54.123336)
		(width 0.0889)
		(layer "In4.Cu")
		(net "M_B_DQS_DP<7>")
	)
	(arc
		(start 284.415992 -61.253116)
		(mid 284.582715 -61.188287)
		(end 284.704536 -61.057282)
		(width 0.0889)
		(layer "In4.Cu")
		(net "M_B_DQS_DP<7>")
	)
	(arc
		(start 286.41548 -56.684418)
		(mid 286.342682 -56.393655)
		(end 286.42183 -56.104536)
		(width 0.0889)
		(layer "In4.Cu")
		(net "M_B_DQS_DP<7>")
	)
	(arc
		(start 285.56331 -58.581036)
		(mid 285.774023 -58.367957)
		(end 286.062166 -58.285634)
		(width 0.0889)
		(layer "In4.Cu")
		(net "M_B_DQS_DP<7>")
	)
	(arc
		(start 286.42183 -54.123336)
		(mid 286.4753 -53.928273)
		(end 286.426656 -53.731922)
		(width 0.0889)
		(layer "In4.Cu")
		(net "M_B_DQS_DP<7>")
	)
	(arc
		(start 286.42183 -55.113936)
		(mid 286.4753 -54.918873)
		(end 286.426656 -54.722522)
		(width 0.0889)
		(layer "In4.Cu")
		(net "M_B_DQS_DP<7>")
	)
	(arc
		(start 285.234634 -58.780934)
		(mid 285.424563 -58.723064)
		(end 285.56331 -58.581036)
		(width 0.0889)
		(layer "In4.Cu")
		(net "M_B_DQS_DP<7>")
	)
	(arc
		(start 286.42183 -57.095136)
		(mid 286.4753 -56.900073)
		(end 286.426656 -56.703722)
		(width 0.0889)
		(layer "In4.Cu")
		(net "M_B_DQS_DP<7>")
	)
	(arc
		(start 284.70479 -59.666886)
		(mid 284.700461 -59.083714)
		(end 285.19882 -58.780934)
		(width 0.0889)
		(layer "In4.Cu")
		(net "M_B_DQS_DP<7>")
	)
	(arc
		(start 286.42183 -53.723286)
		(mid 286.416576 -53.141778)
		(end 286.91205 -52.837334)
		(width 0.0889)
		(layer "In4.Cu")
		(net "M_B_DQS_DP<7>")
	)
	(segment
		(start 301.077122 -39.520368)
		(end 301.077122 -39.340536)
		(width 0.1651)
		(layer "F.Cu")
		(net "M_B_DQS_DP<6>")
	)
	(segment
		(start 302.885856 -29.842968)
		(end 302.885856 -29.473144)
		(width 0.1651)
		(layer "F.Cu")
		(net "M_B_DQS_DP<6>")
	)
	(segment
		(start 301.077122 -39.340536)
		(end 301.2567 -39.160958)
		(width 0.1651)
		(layer "F.Cu")
		(net "M_B_DQS_DP<6>")
	)
	(segment
		(start 299.420788 -40.99687)
		(end 299.619924 -40.797734)
		(width 0.1651)
		(layer "F.Cu")
		(net "M_B_DQS_DP<6>")
	)
	(segment
		(start 299.979334 -40.438324)
		(end 300.178724 -40.238934)
		(width 0.1651)
		(layer "F.Cu")
		(net "M_B_DQS_DP<6>")
	)
	(segment
		(start 303.5046 -28.209494)
		(end 303.302162 -28.007056)
		(width 0.1651)
		(layer "F.Cu")
		(net "M_B_DQS_DP<6>")
	)
	(segment
		(start 300.89729 -39.699946)
		(end 301.077122 -39.520368)
		(width 0.1651)
		(layer "F.Cu")
		(net "M_B_DQS_DP<6>")
	)
	(segment
		(start 284.521402 -50.239422)
		(end 285.078424 -49.6824)
		(width 0.0889)
		(layer "F.Cu")
		(net "M_B_DQS_DP<6>")
	)
	(segment
		(start 285.44393 -49.6824)
		(end 287.969706 -47.156624)
		(width 0.1016)
		(layer "F.Cu")
		(net "M_B_DQS_DP<6>")
	)
	(segment
		(start 299.799756 -40.797734)
		(end 299.979334 -40.618156)
		(width 0.1651)
		(layer "F.Cu")
		(net "M_B_DQS_DP<6>")
	)
	(segment
		(start 284.071314 -53.427884)
		(end 283.920438 -53.69052)
		(width 0.0889)
		(layer "F.Cu")
		(net "M_B_DQS_DP<6>")
	)
	(segment
		(start 303.294034 -7.75716)
		(end 303.537874 -8.001)
		(width 0.1651)
		(layer "F.Cu")
		(net "M_B_DQS_DP<6>")
	)
	(segment
		(start 299.979334 -40.618156)
		(end 299.979334 -40.438324)
		(width 0.1651)
		(layer "F.Cu")
		(net "M_B_DQS_DP<6>")
	)
	(segment
		(start 299.061378 -41.35628)
		(end 299.240956 -41.35628)
		(width 0.1651)
		(layer "F.Cu")
		(net "M_B_DQS_DP<6>")
	)
	(segment
		(start 285.078424 -49.6824)
		(end 285.44393 -49.6824)
		(width 0.0889)
		(layer "F.Cu")
		(net "M_B_DQS_DP<6>")
	)
	(segment
		(start 284.521402 -51.014884)
		(end 284.521402 -50.239422)
		(width 0.0889)
		(layer "F.Cu")
		(net "M_B_DQS_DP<6>")
	)
	(segment
		(start 300.717712 -39.699946)
		(end 300.89729 -39.699946)
		(width 0.1651)
		(layer "F.Cu")
		(net "M_B_DQS_DP<6>")
	)
	(segment
		(start 288.244026 -47.156624)
		(end 294.804846 -47.156624)
		(width 0.1016)
		(layer "F.Cu")
		(net "M_B_DQS_DP<6>")
	)
	(segment
		(start 301.61611 -38.801548)
		(end 303.381918 -37.03574)
		(width 0.1651)
		(layer "F.Cu")
		(net "M_B_DQS_DP<6>")
	)
	(segment
		(start 303.500028 -10.422128)
		(end 303.500282 -10.422382)
		(width 0.1651)
		(layer "F.Cu")
		(net "M_B_DQS_DP<6>")
	)
	(segment
		(start 303.537874 -8.001)
		(end 303.537874 -9.3726)
		(width 0.1651)
		(layer "F.Cu")
		(net "M_B_DQS_DP<6>")
	)
	(segment
		(start 301.2567 -39.160958)
		(end 301.436278 -39.160958)
		(width 0.1651)
		(layer "F.Cu")
		(net "M_B_DQS_DP<6>")
	)
	(segment
		(start 300.178724 -40.238934)
		(end 300.358556 -40.238934)
		(width 0.1651)
		(layer "F.Cu")
		(net "M_B_DQS_DP<6>")
	)
	(segment
		(start 299.240956 -41.35628)
		(end 299.420788 -41.176702)
		(width 0.1651)
		(layer "F.Cu")
		(net "M_B_DQS_DP<6>")
	)
	(segment
		(start 303.038002 -7.75716)
		(end 303.294034 -7.75716)
		(width 0.1651)
		(layer "F.Cu")
		(net "M_B_DQS_DP<6>")
	)
	(segment
		(start 302.885856 -29.473144)
		(end 303.5046 -28.8544)
		(width 0.1651)
		(layer "F.Cu")
		(net "M_B_DQS_DP<6>")
	)
	(segment
		(start 303.5046 -28.8544)
		(end 303.5046 -28.209494)
		(width 0.1651)
		(layer "F.Cu")
		(net "M_B_DQS_DP<6>")
	)
	(segment
		(start 298.8818 -41.535858)
		(end 299.061378 -41.35628)
		(width 0.1651)
		(layer "F.Cu")
		(net "M_B_DQS_DP<6>")
	)
	(segment
		(start 300.358556 -40.238934)
		(end 300.538134 -40.059356)
		(width 0.1651)
		(layer "F.Cu")
		(net "M_B_DQS_DP<6>")
	)
	(segment
		(start 303.381918 -37.03574)
		(end 303.381918 -34.29)
		(width 0.1651)
		(layer "F.Cu")
		(net "M_B_DQS_DP<6>")
	)
	(segment
		(start 284.583124 -51.742086)
		(end 284.588966 -51.731926)
		(width 0.0889)
		(layer "F.Cu")
		(net "M_B_DQS_DP<6>")
	)
	(segment
		(start 301.436278 -39.160958)
		(end 301.61611 -38.98138)
		(width 0.1651)
		(layer "F.Cu")
		(net "M_B_DQS_DP<6>")
	)
	(segment
		(start 283.775404 -53.69052)
		(end 283.746194 -53.66131)
		(width 0.0889)
		(layer "F.Cu")
		(net "M_B_DQS_DP<6>")
	)
	(segment
		(start 299.420788 -41.176702)
		(end 299.420788 -40.99687)
		(width 0.1651)
		(layer "F.Cu")
		(net "M_B_DQS_DP<6>")
	)
	(segment
		(start 303.381918 -34.29)
		(end 303.381918 -30.33903)
		(width 0.1651)
		(layer "F.Cu")
		(net "M_B_DQS_DP<6>")
	)
	(segment
		(start 300.538134 -40.059356)
		(end 300.538134 -39.879524)
		(width 0.1651)
		(layer "F.Cu")
		(net "M_B_DQS_DP<6>")
	)
	(segment
		(start 303.537874 -9.3726)
		(end 303.500028 -9.410446)
		(width 0.1651)
		(layer "F.Cu")
		(net "M_B_DQS_DP<6>")
	)
	(segment
		(start 303.381918 -30.33903)
		(end 302.885856 -29.842968)
		(width 0.1651)
		(layer "F.Cu")
		(net "M_B_DQS_DP<6>")
	)
	(segment
		(start 300.538134 -39.879524)
		(end 300.717712 -39.699946)
		(width 0.1651)
		(layer "F.Cu")
		(net "M_B_DQS_DP<6>")
	)
	(segment
		(start 287.969706 -47.156624)
		(end 288.244026 -47.156624)
		(width 0.1016)
		(layer "F.Cu")
		(net "M_B_DQS_DP<6>")
	)
	(segment
		(start 294.804846 -47.156624)
		(end 298.873672 -43.087798)
		(width 0.1016)
		(layer "F.Cu")
		(net "M_B_DQS_DP<6>")
	)
	(segment
		(start 284.588966 -51.131978)
		(end 284.521402 -51.014884)
		(width 0.0889)
		(layer "F.Cu")
		(net "M_B_DQS_DP<6>")
	)
	(segment
		(start 283.746194 -53.66131)
		(end 283.746194 -53.660548)
		(width 0.0889)
		(layer "F.Cu")
		(net "M_B_DQS_DP<6>")
	)
	(segment
		(start 298.8818 -41.8592)
		(end 298.8818 -41.535858)
		(width 0.1651)
		(layer "F.Cu")
		(net "M_B_DQS_DP<6>")
	)
	(segment
		(start 299.619924 -40.797734)
		(end 299.799756 -40.797734)
		(width 0.1651)
		(layer "F.Cu")
		(net "M_B_DQS_DP<6>")
	)
	(segment
		(start 301.61611 -38.98138)
		(end 301.61611 -38.801548)
		(width 0.1651)
		(layer "F.Cu")
		(net "M_B_DQS_DP<6>")
	)
	(segment
		(start 298.873672 -43.087798)
		(end 298.873672 -41.867328)
		(width 0.1016)
		(layer "F.Cu")
		(net "M_B_DQS_DP<6>")
	)
	(segment
		(start 283.920438 -53.69052)
		(end 283.775404 -53.69052)
		(width 0.0889)
		(layer "F.Cu")
		(net "M_B_DQS_DP<6>")
	)
	(segment
		(start 303.302162 -28.007056)
		(end 303.044606 -28.007056)
		(width 0.1651)
		(layer "F.Cu")
		(net "M_B_DQS_DP<6>")
	)
	(segment
		(start 298.873672 -41.867328)
		(end 298.8818 -41.8592)
		(width 0.1016)
		(layer "F.Cu")
		(net "M_B_DQS_DP<6>")
	)
	(segment
		(start 284.060138 -53.027834)
		(end 284.092904 -53.027834)
		(width 0.0889)
		(layer "F.Cu")
		(net "M_B_DQS_DP<6>")
	)
	(segment
		(start 303.500028 -9.410446)
		(end 303.500028 -10.422128)
		(width 0.1651)
		(layer "F.Cu")
		(net "M_B_DQS_DP<6>")
	)
	(via
		(at 303.381918 -34.29)
		(size 0.508)
		(drill 0.254)
		(layers "F.Cu" "B.Cu")
		(net "M_B_DQS_DP<6>")
	)
	(via
		(at 303.044606 -28.007056)
		(size 0.508)
		(drill 0.254)
		(layers "F.Cu" "B.Cu")
		(net "M_B_DQS_DP<6>")
	)
	(via
		(at 303.038002 -7.75716)
		(size 0.508)
		(drill 0.254)
		(layers "F.Cu" "B.Cu")
		(net "M_B_DQS_DP<6>")
	)
	(via
		(at 303.038002 -13.287756)
		(size 0.508)
		(drill 0.254)
		(layers "F.Cu" "B.Cu")
		(net "M_B_DQS_DP<6>")
	)
	(arc
		(start 284.092904 -53.027834)
		(mid 284.588381 -52.723391)
		(end 284.583124 -52.141882)
		(width 0.0889)
		(layer "F.Cu")
		(net "M_B_DQS_DP<6>")
	)
	(arc
		(start 284.588966 -51.731926)
		(mid 284.669329 -51.431952)
		(end 284.588966 -51.131978)
		(width 0.0889)
		(layer "F.Cu")
		(net "M_B_DQS_DP<6>")
	)
	(arc
		(start 284.583124 -52.141882)
		(mid 284.529591 -51.941984)
		(end 284.583124 -51.742086)
		(width 0.0889)
		(layer "F.Cu")
		(net "M_B_DQS_DP<6>")
	)
	(arc
		(start 283.746194 -53.660548)
		(mid 283.713097 -53.249818)
		(end 284.060138 -53.027834)
		(width 0.0889)
		(layer "F.Cu")
		(net "M_B_DQS_DP<6>")
	)
	(segment
		(start 303.537874 -13.0302)
		(end 303.537874 -11.811)
		(width 0.1651)
		(layer "B.Cu")
		(net "M_B_DQS_DP<6>")
	)
	(segment
		(start 303.500028 -10.623296)
		(end 303.500282 -10.623042)
		(width 0.1651)
		(layer "B.Cu")
		(net "M_B_DQS_DP<6>")
	)
	(segment
		(start 303.280318 -13.287756)
		(end 303.537874 -13.0302)
		(width 0.1651)
		(layer "B.Cu")
		(net "M_B_DQS_DP<6>")
	)
	(segment
		(start 303.537874 -11.811)
		(end 303.500028 -11.773154)
		(width 0.1651)
		(layer "B.Cu")
		(net "M_B_DQS_DP<6>")
	)
	(segment
		(start 303.500028 -11.773154)
		(end 303.500028 -10.623296)
		(width 0.1651)
		(layer "B.Cu")
		(net "M_B_DQS_DP<6>")
	)
	(segment
		(start 303.038002 -13.287756)
		(end 303.280318 -13.287756)
		(width 0.1651)
		(layer "B.Cu")
		(net "M_B_DQS_DP<6>")
	)
	(segment
		(start 303.32172 -14.38148)
		(end 303.32172 -14.668246)
		(width 0.14224)
		(layer "In4.Cu")
		(net "M_B_DQS_DP<6>")
	)
	(segment
		(start 303.84877 -12.476988)
		(end 303.038002 -13.287756)
		(width 0.14224)
		(layer "In4.Cu")
		(net "M_B_DQS_DP<6>")
	)
	(segment
		(start 303.80432 -27.240738)
		(end 303.044606 -28.000452)
		(width 0.14224)
		(layer "In4.Cu")
		(net "M_B_DQS_DP<6>")
	)
	(segment
		(start 303.501806 -14.201394)
		(end 303.32172 -14.38148)
		(width 0.14224)
		(layer "In4.Cu")
		(net "M_B_DQS_DP<6>")
	)
	(segment
		(start 303.038002 -7.75716)
		(end 303.84877 -8.567928)
		(width 0.14224)
		(layer "In4.Cu")
		(net "M_B_DQS_DP<6>")
	)
	(segment
		(start 303.84877 -8.567928)
		(end 303.84877 -12.476988)
		(width 0.14224)
		(layer "In4.Cu")
		(net "M_B_DQS_DP<6>")
	)
	(segment
		(start 303.501806 -13.75156)
		(end 303.501806 -14.201394)
		(width 0.14224)
		(layer "In4.Cu")
		(net "M_B_DQS_DP<6>")
	)
	(segment
		(start 303.038002 -13.287756)
		(end 303.501806 -13.75156)
		(width 0.14224)
		(layer "In4.Cu")
		(net "M_B_DQS_DP<6>")
	)
	(segment
		(start 303.044606 -28.000452)
		(end 303.044606 -28.007056)
		(width 0.14224)
		(layer "In4.Cu")
		(net "M_B_DQS_DP<6>")
	)
	(segment
		(start 303.80432 -15.150846)
		(end 303.80432 -27.240738)
		(width 0.14224)
		(layer "In4.Cu")
		(net "M_B_DQS_DP<6>")
	)
	(segment
		(start 303.32172 -14.668246)
		(end 303.80432 -15.150846)
		(width 0.14224)
		(layer "In4.Cu")
		(net "M_B_DQS_DP<6>")
	)
	(segment
		(start 278.82088 -53.732176)
		(end 278.920194 -53.427884)
		(width 0.0889)
		(layer "F.Cu")
		(net "M_B_DQS_DP<5>")
	)
	(segment
		(start 278.73833 -53.784246)
		(end 278.82088 -53.732176)
		(width 0.0889)
		(layer "F.Cu")
		(net "M_B_DQS_DP<5>")
	)
	(segment
		(start 286.13989 -39.063168)
		(end 285.960312 -39.242746)
		(width 0.1651)
		(layer "F.Cu")
		(net "M_B_DQS_DP<5>")
	)
	(segment
		(start 286.319468 -39.063168)
		(end 286.13989 -39.063168)
		(width 0.1651)
		(layer "F.Cu")
		(net "M_B_DQS_DP<5>")
	)
	(segment
		(start 284.702504 -40.680132)
		(end 284.522926 -40.680132)
		(width 0.1651)
		(layer "F.Cu")
		(net "M_B_DQS_DP<5>")
	)
	(segment
		(start 284.343348 -40.85971)
		(end 284.343348 -41.0718)
		(width 0.1651)
		(layer "F.Cu")
		(net "M_B_DQS_DP<5>")
	)
	(segment
		(start 294.187626 -9.3726)
		(end 294.187626 -8.001)
		(width 0.1651)
		(layer "F.Cu")
		(net "M_B_DQS_DP<5>")
	)
	(segment
		(start 284.343348 -41.0718)
		(end 284.343348 -41.239948)
		(width 0.1016)
		(layer "F.Cu")
		(net "M_B_DQS_DP<5>")
	)
	(segment
		(start 286.4993 -38.703758)
		(end 286.4993 -38.88359)
		(width 0.1651)
		(layer "F.Cu")
		(net "M_B_DQS_DP<5>")
	)
	(segment
		(start 284.882336 -40.500554)
		(end 284.702504 -40.680132)
		(width 0.1651)
		(layer "F.Cu")
		(net "M_B_DQS_DP<5>")
	)
	(segment
		(start 294.187626 -8.001)
		(end 293.943786 -7.75716)
		(width 0.1651)
		(layer "F.Cu")
		(net "M_B_DQS_DP<5>")
	)
	(segment
		(start 284.343348 -41.239948)
		(end 284.394148 -41.290748)
		(width 0.1016)
		(layer "F.Cu")
		(net "M_B_DQS_DP<5>")
	)
	(segment
		(start 284.394148 -41.290748)
		(end 284.394148 -43.044364)
		(width 0.1016)
		(layer "F.Cu")
		(net "M_B_DQS_DP<5>")
	)
	(segment
		(start 294.259 -28.803346)
		(end 293.525448 -29.536898)
		(width 0.1651)
		(layer "F.Cu")
		(net "M_B_DQS_DP<5>")
	)
	(segment
		(start 293.970456 -28.007056)
		(end 294.259 -28.2956)
		(width 0.1651)
		(layer "F.Cu")
		(net "M_B_DQS_DP<5>")
	)
	(segment
		(start 279.487884 -49.696116)
		(end 279.487884 -51.53279)
		(width 0.0889)
		(layer "F.Cu")
		(net "M_B_DQS_DP<5>")
	)
	(segment
		(start 286.4993 -38.88359)
		(end 286.319468 -39.063168)
		(width 0.1651)
		(layer "F.Cu")
		(net "M_B_DQS_DP<5>")
	)
	(segment
		(start 284.882336 -40.320722)
		(end 284.882336 -40.500554)
		(width 0.1651)
		(layer "F.Cu")
		(net "M_B_DQS_DP<5>")
	)
	(segment
		(start 285.600902 -39.602156)
		(end 285.421324 -39.781734)
		(width 0.1651)
		(layer "F.Cu")
		(net "M_B_DQS_DP<5>")
	)
	(segment
		(start 293.943786 -7.75716)
		(end 293.687754 -7.75716)
		(width 0.1651)
		(layer "F.Cu")
		(net "M_B_DQS_DP<5>")
	)
	(segment
		(start 294.150288 -10.422382)
		(end 294.14978 -10.422382)
		(width 0.1651)
		(layer "F.Cu")
		(net "M_B_DQS_DP<5>")
	)
	(segment
		(start 285.421324 -39.781734)
		(end 285.421324 -39.961566)
		(width 0.1651)
		(layer "F.Cu")
		(net "M_B_DQS_DP<5>")
	)
	(segment
		(start 284.394148 -43.044364)
		(end 279.592024 -47.846488)
		(width 0.1016)
		(layer "F.Cu")
		(net "M_B_DQS_DP<5>")
	)
	(segment
		(start 279.592024 -47.846488)
		(end 279.592024 -49.591976)
		(width 0.1016)
		(layer "F.Cu")
		(net "M_B_DQS_DP<5>")
	)
	(segment
		(start 285.061914 -40.141144)
		(end 284.882336 -40.320722)
		(width 0.1651)
		(layer "F.Cu")
		(net "M_B_DQS_DP<5>")
	)
	(segment
		(start 294.14978 -9.410446)
		(end 294.187626 -9.3726)
		(width 0.1651)
		(layer "F.Cu")
		(net "M_B_DQS_DP<5>")
	)
	(segment
		(start 293.694612 -28.007056)
		(end 293.970456 -28.007056)
		(width 0.1651)
		(layer "F.Cu")
		(net "M_B_DQS_DP<5>")
	)
	(segment
		(start 278.941784 -53.027834)
		(end 278.909018 -53.027834)
		(width 0.0889)
		(layer "F.Cu")
		(net "M_B_DQS_DP<5>")
	)
	(segment
		(start 294.259 -28.2956)
		(end 294.259 -28.803346)
		(width 0.1651)
		(layer "F.Cu")
		(net "M_B_DQS_DP<5>")
	)
	(segment
		(start 285.421324 -39.961566)
		(end 285.241492 -40.141144)
		(width 0.1651)
		(layer "F.Cu")
		(net "M_B_DQS_DP<5>")
	)
	(segment
		(start 285.241492 -40.141144)
		(end 285.061914 -40.141144)
		(width 0.1651)
		(layer "F.Cu")
		(net "M_B_DQS_DP<5>")
	)
	(segment
		(start 279.43175 -52.141882)
		(end 279.432004 -52.141882)
		(width 0.0889)
		(layer "F.Cu")
		(net "M_B_DQS_DP<5>")
	)
	(segment
		(start 286.937958 -38.2651)
		(end 286.4993 -38.703758)
		(width 0.1651)
		(layer "F.Cu")
		(net "M_B_DQS_DP<5>")
	)
	(segment
		(start 285.960312 -39.422578)
		(end 285.78048 -39.602156)
		(width 0.1651)
		(layer "F.Cu")
		(net "M_B_DQS_DP<5>")
	)
	(segment
		(start 279.592024 -49.591976)
		(end 279.487884 -49.696116)
		(width 0.0889)
		(layer "F.Cu")
		(net "M_B_DQS_DP<5>")
	)
	(segment
		(start 294.14978 -10.422382)
		(end 294.14978 -9.410446)
		(width 0.1651)
		(layer "F.Cu")
		(net "M_B_DQS_DP<5>")
	)
	(segment
		(start 284.522926 -40.680132)
		(end 284.343348 -40.85971)
		(width 0.1651)
		(layer "F.Cu")
		(net "M_B_DQS_DP<5>")
	)
	(segment
		(start 285.78048 -39.602156)
		(end 285.600902 -39.602156)
		(width 0.1651)
		(layer "F.Cu")
		(net "M_B_DQS_DP<5>")
	)
	(segment
		(start 287.540446 -38.2651)
		(end 286.937958 -38.2651)
		(width 0.1651)
		(layer "F.Cu")
		(net "M_B_DQS_DP<5>")
	)
	(segment
		(start 293.525448 -29.536898)
		(end 293.525448 -32.280098)
		(width 0.1651)
		(layer "F.Cu")
		(net "M_B_DQS_DP<5>")
	)
	(segment
		(start 285.960312 -39.242746)
		(end 285.960312 -39.422578)
		(width 0.1651)
		(layer "F.Cu")
		(net "M_B_DQS_DP<5>")
	)
	(segment
		(start 293.525448 -32.280098)
		(end 287.540446 -38.2651)
		(width 0.1651)
		(layer "F.Cu")
		(net "M_B_DQS_DP<5>")
	)
	(via
		(at 293.687754 -13.287756)
		(size 0.508)
		(drill 0.254)
		(layers "F.Cu" "B.Cu")
		(net "M_B_DQS_DP<5>")
	)
	(via
		(at 293.687754 -7.75716)
		(size 0.508)
		(drill 0.254)
		(layers "F.Cu" "B.Cu")
		(net "M_B_DQS_DP<5>")
	)
	(via
		(at 293.694612 -28.007056)
		(size 0.508)
		(drill 0.254)
		(layers "F.Cu" "B.Cu")
		(net "M_B_DQS_DP<5>")
	)
	(arc
		(start 278.909018 -53.027834)
		(mid 278.558604 -53.255851)
		(end 278.602694 -53.67147)
		(width 0.0889)
		(layer "F.Cu")
		(net "M_B_DQS_DP<5>")
	)
	(arc
		(start 279.487884 -51.53279)
		(mid 279.473741 -51.641123)
		(end 279.432004 -51.742086)
		(width 0.0889)
		(layer "F.Cu")
		(net "M_B_DQS_DP<5>")
	)
	(arc
		(start 279.432004 -52.141882)
		(mid 279.437258 -52.72339)
		(end 278.941784 -53.027834)
		(width 0.0889)
		(layer "F.Cu")
		(net "M_B_DQS_DP<5>")
	)
	(arc
		(start 279.432004 -51.742086)
		(mid 279.378378 -51.941955)
		(end 279.43175 -52.141882)
		(width 0.0889)
		(layer "F.Cu")
		(net "M_B_DQS_DP<5>")
	)
	(arc
		(start 278.602694 -53.67147)
		(mid 278.664216 -53.73543)
		(end 278.73833 -53.784246)
		(width 0.0889)
		(layer "F.Cu")
		(net "M_B_DQS_DP<5>")
	)
	(segment
		(start 294.187626 -11.811)
		(end 294.187626 -13.0302)
		(width 0.1651)
		(layer "B.Cu")
		(net "M_B_DQS_DP<5>")
	)
	(segment
		(start 294.14978 -11.773154)
		(end 294.187626 -11.811)
		(width 0.1651)
		(layer "B.Cu")
		(net "M_B_DQS_DP<5>")
	)
	(segment
		(start 294.150288 -10.623042)
		(end 294.14978 -10.623042)
		(width 0.1651)
		(layer "B.Cu")
		(net "M_B_DQS_DP<5>")
	)
	(segment
		(start 294.187626 -13.0302)
		(end 293.93007 -13.287756)
		(width 0.1651)
		(layer "B.Cu")
		(net "M_B_DQS_DP<5>")
	)
	(segment
		(start 294.14978 -10.623042)
		(end 294.14978 -11.773154)
		(width 0.1651)
		(layer "B.Cu")
		(net "M_B_DQS_DP<5>")
	)
	(segment
		(start 293.93007 -13.287756)
		(end 293.687754 -13.287756)
		(width 0.1651)
		(layer "B.Cu")
		(net "M_B_DQS_DP<5>")
	)
	(segment
		(start 293.687754 -7.75716)
		(end 293.688008 -7.75716)
		(width 0.14224)
		(layer "In11.Cu")
		(net "M_B_DQS_DP<5>")
	)
	(segment
		(start 294.498776 -8.567928)
		(end 294.498776 -12.476734)
		(width 0.14224)
		(layer "In11.Cu")
		(net "M_B_DQS_DP<5>")
	)
	(segment
		(start 293.687754 -13.287756)
		(end 294.1574 -13.757402)
		(width 0.14224)
		(layer "In11.Cu")
		(net "M_B_DQS_DP<5>")
	)
	(segment
		(start 294.1574 -14.195806)
		(end 293.971726 -14.38148)
		(width 0.14224)
		(layer "In11.Cu")
		(net "M_B_DQS_DP<5>")
	)
	(segment
		(start 293.971726 -14.38148)
		(end 293.971726 -14.668246)
		(width 0.14224)
		(layer "In11.Cu")
		(net "M_B_DQS_DP<5>")
	)
	(segment
		(start 293.688008 -7.75716)
		(end 294.498776 -8.567928)
		(width 0.14224)
		(layer "In11.Cu")
		(net "M_B_DQS_DP<5>")
	)
	(segment
		(start 294.454326 -27.240738)
		(end 293.694612 -28.000452)
		(width 0.14224)
		(layer "In11.Cu")
		(net "M_B_DQS_DP<5>")
	)
	(segment
		(start 293.971726 -14.668246)
		(end 294.454326 -15.150846)
		(width 0.14224)
		(layer "In11.Cu")
		(net "M_B_DQS_DP<5>")
	)
	(segment
		(start 294.498776 -12.476734)
		(end 293.687754 -13.287756)
		(width 0.14224)
		(layer "In11.Cu")
		(net "M_B_DQS_DP<5>")
	)
	(segment
		(start 293.694612 -28.000452)
		(end 293.694612 -28.007056)
		(width 0.14224)
		(layer "In11.Cu")
		(net "M_B_DQS_DP<5>")
	)
	(segment
		(start 294.1574 -13.757402)
		(end 294.1574 -14.195806)
		(width 0.14224)
		(layer "In11.Cu")
		(net "M_B_DQS_DP<5>")
	)
	(segment
		(start 294.454326 -15.150846)
		(end 294.454326 -27.240738)
		(width 0.14224)
		(layer "In11.Cu")
		(net "M_B_DQS_DP<5>")
	)
	(segment
		(start 284.593792 -7.75716)
		(end 284.33776 -7.75716)
		(width 0.1651)
		(layer "F.Cu")
		(net "M_B_DQS_DP<4>")
	)
	(segment
		(start 284.837632 -9.3726)
		(end 284.837632 -8.001)
		(width 0.1651)
		(layer "F.Cu")
		(net "M_B_DQS_DP<4>")
	)
	(segment
		(start 284.837632 -8.001)
		(end 284.593792 -7.75716)
		(width 0.1651)
		(layer "F.Cu")
		(net "M_B_DQS_DP<4>")
	)
	(segment
		(start 284.799786 -10.422382)
		(end 284.799786 -9.410446)
		(width 0.1651)
		(layer "F.Cu")
		(net "M_B_DQS_DP<4>")
	)
	(segment
		(start 284.799786 -9.410446)
		(end 284.837632 -9.3726)
		(width 0.1651)
		(layer "F.Cu")
		(net "M_B_DQS_DP<4>")
	)
	(segment
		(start 284.800294 -10.422382)
		(end 284.799786 -10.422382)
		(width 0.1651)
		(layer "F.Cu")
		(net "M_B_DQS_DP<4>")
	)
	(segment
		(start 272.052288 -58.381138)
		(end 271.480788 -58.381138)
		(width 0.1016)
		(layer "F.Cu")
		(net "M_B_DQS_DP<4>")
	)
	(via
		(at 284.33776 -7.75716)
		(size 0.508)
		(drill 0.254)
		(layers "F.Cu" "B.Cu")
		(net "M_B_DQS_DP<4>")
	)
	(via
		(at 284.33776 -13.287756)
		(size 0.508)
		(drill 0.254)
		(layers "F.Cu" "B.Cu")
		(net "M_B_DQS_DP<4>")
	)
	(via
		(at 271.480788 -58.381138)
		(size 0.508)
		(drill 0.254)
		(layers "F.Cu" "B.Cu")
		(net "M_B_DQS_DP<4>")
	)
	(segment
		(start 284.837632 -13.0302)
		(end 284.580076 -13.287756)
		(width 0.1651)
		(layer "B.Cu")
		(net "M_B_DQS_DP<4>")
	)
	(segment
		(start 284.800294 -10.623042)
		(end 284.799786 -10.623042)
		(width 0.1651)
		(layer "B.Cu")
		(net "M_B_DQS_DP<4>")
	)
	(segment
		(start 284.580076 -13.287756)
		(end 284.33776 -13.287756)
		(width 0.1651)
		(layer "B.Cu")
		(net "M_B_DQS_DP<4>")
	)
	(segment
		(start 284.799786 -11.773154)
		(end 284.837632 -11.811)
		(width 0.1651)
		(layer "B.Cu")
		(net "M_B_DQS_DP<4>")
	)
	(segment
		(start 284.799786 -10.623042)
		(end 284.799786 -11.773154)
		(width 0.1651)
		(layer "B.Cu")
		(net "M_B_DQS_DP<4>")
	)
	(segment
		(start 284.837632 -11.811)
		(end 284.837632 -13.0302)
		(width 0.1651)
		(layer "B.Cu")
		(net "M_B_DQS_DP<4>")
	)
	(segment
		(start 284.801564 -13.75156)
		(end 284.33776 -13.287756)
		(width 0.14224)
		(layer "In4.Cu")
		(net "M_B_DQS_DP<4>")
	)
	(segment
		(start 280.56332 -31.398718)
		(end 285.120334 -26.841704)
		(width 0.14224)
		(layer "In4.Cu")
		(net "M_B_DQS_DP<4>")
	)
	(segment
		(start 273.75104 -47.808642)
		(end 274.973288 -46.586394)
		(width 0.0889)
		(layer "In4.Cu")
		(net "M_B_DQS_DP<4>")
	)
	(segment
		(start 284.353 -14.4272)
		(end 284.6578 -14.4272)
		(width 0.14224)
		(layer "In4.Cu")
		(net "M_B_DQS_DP<4>")
	)
	(segment
		(start 275.012658 -37.82187)
		(end 280.56332 -32.271208)
		(width 0.14224)
		(layer "In4.Cu")
		(net "M_B_DQS_DP<4>")
	)
	(segment
		(start 272.328132 -55.504588)
		(end 272.360898 -55.504588)
		(width 0.0889)
		(layer "In4.Cu")
		(net "M_B_DQS_DP<4>")
	)
	(segment
		(start 285.120334 -19.58848)
		(end 285.277814 -19.431)
		(width 0.14224)
		(layer "In4.Cu")
		(net "M_B_DQS_DP<4>")
	)
	(segment
		(start 272.753836 -52.778152)
		(end 272.753836 -52.184808)
		(width 0.0889)
		(layer "In4.Cu")
		(net "M_B_DQS_DP<4>")
	)
	(segment
		(start 284.893258 -15.489174)
		(end 284.713426 -15.309342)
		(width 0.14224)
		(layer "In4.Cu")
		(net "M_B_DQS_DP<4>")
	)
	(segment
		(start 285.277814 -19.431)
		(end 285.277814 -19.177)
		(width 0.14224)
		(layer "In4.Cu")
		(net "M_B_DQS_DP<4>")
	)
	(segment
		(start 275.012658 -45.613828)
		(end 275.012658 -45.59173)
		(width 0.0889)
		(layer "In4.Cu")
		(net "M_B_DQS_DP<4>")
	)
	(segment
		(start 273.468084 -51.47056)
		(end 273.468084 -49.452784)
		(width 0.0889)
		(layer "In4.Cu")
		(net "M_B_DQS_DP<4>")
	)
	(segment
		(start 285.148528 -12.476988)
		(end 285.148528 -8.567928)
		(width 0.14224)
		(layer "In4.Cu")
		(net "M_B_DQS_DP<4>")
	)
	(segment
		(start 275.012658 -45.59173)
		(end 275.012658 -37.82187)
		(width 0.14224)
		(layer "In4.Cu")
		(net "M_B_DQS_DP<4>")
	)
	(segment
		(start 274.973288 -45.653198)
		(end 275.012658 -45.613828)
		(width 0.0889)
		(layer "In4.Cu")
		(net "M_B_DQS_DP<4>")
	)
	(segment
		(start 284.6578 -14.4272)
		(end 284.801564 -14.283436)
		(width 0.14224)
		(layer "In4.Cu")
		(net "M_B_DQS_DP<4>")
	)
	(segment
		(start 285.120334 -26.841704)
		(end 285.120334 -19.58848)
		(width 0.14224)
		(layer "In4.Cu")
		(net "M_B_DQS_DP<4>")
	)
	(segment
		(start 271.480788 -58.381138)
		(end 271.742662 -57.920382)
		(width 0.0889)
		(layer "In4.Cu")
		(net "M_B_DQS_DP<4>")
	)
	(segment
		(start 273.468084 -49.452784)
		(end 273.75104 -49.169828)
		(width 0.0889)
		(layer "In4.Cu")
		(net "M_B_DQS_DP<4>")
	)
	(segment
		(start 272.929858 -52.954174)
		(end 272.753836 -52.778152)
		(width 0.0889)
		(layer "In4.Cu")
		(net "M_B_DQS_DP<4>")
	)
	(segment
		(start 273.75104 -49.169828)
		(end 273.75104 -47.808642)
		(width 0.0889)
		(layer "In4.Cu")
		(net "M_B_DQS_DP<4>")
	)
	(segment
		(start 285.277814 -19.177)
		(end 285.120334 -19.01952)
		(width 0.14224)
		(layer "In4.Cu")
		(net "M_B_DQS_DP<4>")
	)
	(segment
		(start 284.893258 -15.711678)
		(end 284.893258 -15.489174)
		(width 0.14224)
		(layer "In4.Cu")
		(net "M_B_DQS_DP<4>")
	)
	(segment
		(start 285.120334 -15.938754)
		(end 284.893258 -15.711678)
		(width 0.14224)
		(layer "In4.Cu")
		(net "M_B_DQS_DP<4>")
	)
	(segment
		(start 272.929858 -54.896004)
		(end 272.929858 -52.954174)
		(width 0.0889)
		(layer "In4.Cu")
		(net "M_B_DQS_DP<4>")
	)
	(segment
		(start 284.33776 -13.287756)
		(end 285.148528 -12.476988)
		(width 0.14224)
		(layer "In4.Cu")
		(net "M_B_DQS_DP<4>")
	)
	(segment
		(start 280.56332 -32.271208)
		(end 280.56332 -31.398718)
		(width 0.14224)
		(layer "In4.Cu")
		(net "M_B_DQS_DP<4>")
	)
	(segment
		(start 284.490922 -15.309342)
		(end 284.161484 -14.979904)
		(width 0.14224)
		(layer "In4.Cu")
		(net "M_B_DQS_DP<4>")
	)
	(segment
		(start 272.753836 -52.184808)
		(end 273.468084 -51.47056)
		(width 0.0889)
		(layer "In4.Cu")
		(net "M_B_DQS_DP<4>")
	)
	(segment
		(start 285.120334 -19.01952)
		(end 285.120334 -15.938754)
		(width 0.14224)
		(layer "In4.Cu")
		(net "M_B_DQS_DP<4>")
	)
	(segment
		(start 285.148528 -8.567928)
		(end 284.33776 -7.75716)
		(width 0.14224)
		(layer "In4.Cu")
		(net "M_B_DQS_DP<4>")
	)
	(segment
		(start 284.161484 -14.618716)
		(end 284.353 -14.4272)
		(width 0.14224)
		(layer "In4.Cu")
		(net "M_B_DQS_DP<4>")
	)
	(segment
		(start 284.713426 -15.309342)
		(end 284.490922 -15.309342)
		(width 0.14224)
		(layer "In4.Cu")
		(net "M_B_DQS_DP<4>")
	)
	(segment
		(start 284.801564 -14.283436)
		(end 284.801564 -13.75156)
		(width 0.14224)
		(layer "In4.Cu")
		(net "M_B_DQS_DP<4>")
	)
	(segment
		(start 274.973288 -46.586394)
		(end 274.973288 -45.653198)
		(width 0.0889)
		(layer "In4.Cu")
		(net "M_B_DQS_DP<4>")
	)
	(segment
		(start 284.161484 -14.979904)
		(end 284.161484 -14.618716)
		(width 0.14224)
		(layer "In4.Cu")
		(net "M_B_DQS_DP<4>")
	)
	(arc
		(start 271.992598 -56.69534)
		(mid 272.071729 -56.399938)
		(end 271.992598 -56.104536)
		(width 0.0889)
		(layer "In4.Cu")
		(net "M_B_DQS_DP<4>")
	)
	(arc
		(start 272.360898 -55.504588)
		(mid 272.770944 -55.317653)
		(end 272.929858 -54.896004)
		(width 0.0889)
		(layer "In4.Cu")
		(net "M_B_DQS_DP<4>")
	)
	(arc
		(start 271.992598 -56.104536)
		(mid 271.990015 -55.709289)
		(end 272.328132 -55.504588)
		(width 0.0889)
		(layer "In4.Cu")
		(net "M_B_DQS_DP<4>")
	)
	(arc
		(start 271.742662 -57.920382)
		(mid 272.04643 -57.561891)
		(end 271.992598 -57.095136)
		(width 0.0889)
		(layer "In4.Cu")
		(net "M_B_DQS_DP<4>")
	)
	(arc
		(start 271.992598 -57.095136)
		(mid 271.939099 -56.895238)
		(end 271.992598 -56.69534)
		(width 0.0889)
		(layer "In4.Cu")
		(net "M_B_DQS_DP<4>")
	)
	(segment
		(start 244.428264 -50.436526)
		(end 244.424708 -50.442622)
		(width 0.0889)
		(layer "F.Cu")
		(net "M_B_DQS_DP<3>")
	)
	(segment
		(start 229.5652 -28.9306)
		(end 229.3366 -29.1592)
		(width 0.1651)
		(layer "F.Cu")
		(net "M_B_DQS_DP<3>")
	)
	(segment
		(start 228.9175 -29.2989)
		(end 228.9175 -29.54274)
		(width 0.1651)
		(layer "F.Cu")
		(net "M_B_DQS_DP<3>")
	)
	(segment
		(start 237.677452 -46.75759)
		(end 238.299752 -47.37989)
		(width 0.1016)
		(layer "F.Cu")
		(net "M_B_DQS_DP<3>")
	)
	(segment
		(start 229.0572 -29.1592)
		(end 228.9175 -29.2989)
		(width 0.1651)
		(layer "F.Cu")
		(net "M_B_DQS_DP<3>")
	)
	(segment
		(start 228.9175 -31.369)
		(end 228.9175 -32.227266)
		(width 0.1651)
		(layer "F.Cu")
		(net "M_B_DQS_DP<3>")
	)
	(segment
		(start 229.04958 -30.69082)
		(end 228.9175 -30.8229)
		(width 0.1651)
		(layer "F.Cu")
		(net "M_B_DQS_DP<3>")
	)
	(segment
		(start 229.343966 -7.75716)
		(end 229.087934 -7.75716)
		(width 0.1651)
		(layer "F.Cu")
		(net "M_B_DQS_DP<3>")
	)
	(segment
		(start 243.856764 -48.949102)
		(end 243.856764 -49.05248)
		(width 0.0889)
		(layer "F.Cu")
		(net "M_B_DQS_DP<3>")
	)
	(segment
		(start 228.9175 -30.8229)
		(end 228.9175 -31.369)
		(width 0.1651)
		(layer "F.Cu")
		(net "M_B_DQS_DP<3>")
	)
	(segment
		(start 229.5652 -28.203398)
		(end 229.5652 -28.9306)
		(width 0.1651)
		(layer "F.Cu")
		(net "M_B_DQS_DP<3>")
	)
	(segment
		(start 229.45598 -32.765746)
		(end 229.45598 -42.492422)
		(width 0.1651)
		(layer "F.Cu")
		(net "M_B_DQS_DP<3>")
	)
	(segment
		(start 229.04958 -29.92882)
		(end 228.9175 -30.0609)
		(width 0.1651)
		(layer "F.Cu")
		(net "M_B_DQS_DP<3>")
	)
	(segment
		(start 232.784396 -45.578014)
		(end 233.963972 -46.75759)
		(width 0.1016)
		(layer "F.Cu")
		(net "M_B_DQS_DP<3>")
	)
	(segment
		(start 244.089682 -52.431442)
		(end 244.089682 -52.302918)
		(width 0.0889)
		(layer "F.Cu")
		(net "M_B_DQS_DP<3>")
	)
	(segment
		(start 229.587806 -9.3726)
		(end 229.587806 -8.001)
		(width 0.1651)
		(layer "F.Cu")
		(net "M_B_DQS_DP<3>")
	)
	(segment
		(start 229.45598 -42.492422)
		(end 232.480358 -45.5168)
		(width 0.1651)
		(layer "F.Cu")
		(net "M_B_DQS_DP<3>")
	)
	(segment
		(start 229.587806 -8.001)
		(end 229.343966 -7.75716)
		(width 0.1651)
		(layer "F.Cu")
		(net "M_B_DQS_DP<3>")
	)
	(segment
		(start 229.04958 -29.67482)
		(end 229.04958 -29.92882)
		(width 0.1651)
		(layer "F.Cu")
		(net "M_B_DQS_DP<3>")
	)
	(segment
		(start 244.44452 -50.404522)
		(end 244.428264 -50.436526)
		(width 0.0889)
		(layer "F.Cu")
		(net "M_B_DQS_DP<3>")
	)
	(segment
		(start 233.963972 -46.75759)
		(end 237.677452 -46.75759)
		(width 0.1016)
		(layer "F.Cu")
		(net "M_B_DQS_DP<3>")
	)
	(segment
		(start 243.846604 -52.51831)
		(end 244.002814 -52.51831)
		(width 0.0889)
		(layer "F.Cu")
		(net "M_B_DQS_DP<3>")
	)
	(segment
		(start 244.002814 -52.51831)
		(end 244.089682 -52.431442)
		(width 0.0889)
		(layer "F.Cu")
		(net "M_B_DQS_DP<3>")
	)
	(segment
		(start 228.9175 -30.30474)
		(end 229.04958 -30.43682)
		(width 0.1651)
		(layer "F.Cu")
		(net "M_B_DQS_DP<3>")
	)
	(segment
		(start 229.54996 -10.422382)
		(end 229.54996 -9.410446)
		(width 0.1651)
		(layer "F.Cu")
		(net "M_B_DQS_DP<3>")
	)
	(segment
		(start 232.541572 -45.578014)
		(end 232.784396 -45.578014)
		(width 0.1016)
		(layer "F.Cu")
		(net "M_B_DQS_DP<3>")
	)
	(segment
		(start 229.368858 -28.007056)
		(end 229.5652 -28.203398)
		(width 0.1651)
		(layer "F.Cu")
		(net "M_B_DQS_DP<3>")
	)
	(segment
		(start 228.9175 -29.54274)
		(end 229.04958 -29.67482)
		(width 0.1651)
		(layer "F.Cu")
		(net "M_B_DQS_DP<3>")
	)
	(segment
		(start 229.54996 -9.410446)
		(end 229.587806 -9.3726)
		(width 0.1651)
		(layer "F.Cu")
		(net "M_B_DQS_DP<3>")
	)
	(segment
		(start 243.910358 -51.723798)
		(end 243.910358 -51.724052)
		(width 0.0889)
		(layer "F.Cu")
		(net "M_B_DQS_DP<3>")
	)
	(segment
		(start 232.480358 -45.5168)
		(end 232.541572 -45.578014)
		(width 0.1016)
		(layer "F.Cu")
		(net "M_B_DQS_DP<3>")
	)
	(segment
		(start 229.550468 -10.422382)
		(end 229.54996 -10.422382)
		(width 0.1651)
		(layer "F.Cu")
		(net "M_B_DQS_DP<3>")
	)
	(segment
		(start 243.856764 -49.05248)
		(end 244.098064 -49.29378)
		(width 0.0889)
		(layer "F.Cu")
		(net "M_B_DQS_DP<3>")
	)
	(segment
		(start 229.3366 -29.1592)
		(end 229.0572 -29.1592)
		(width 0.1651)
		(layer "F.Cu")
		(net "M_B_DQS_DP<3>")
	)
	(segment
		(start 228.9175 -30.0609)
		(end 228.9175 -30.30474)
		(width 0.1651)
		(layer "F.Cu")
		(net "M_B_DQS_DP<3>")
	)
	(segment
		(start 228.9175 -32.227266)
		(end 229.45598 -32.765746)
		(width 0.1651)
		(layer "F.Cu")
		(net "M_B_DQS_DP<3>")
	)
	(segment
		(start 244.089682 -52.302918)
		(end 243.910104 -52.12334)
		(width 0.0889)
		(layer "F.Cu")
		(net "M_B_DQS_DP<3>")
	)
	(segment
		(start 244.098064 -49.29378)
		(end 244.32006 -49.619154)
		(width 0.0889)
		(layer "F.Cu")
		(net "M_B_DQS_DP<3>")
	)
	(segment
		(start 238.299752 -47.37989)
		(end 242.287552 -47.37989)
		(width 0.1016)
		(layer "F.Cu")
		(net "M_B_DQS_DP<3>")
	)
	(segment
		(start 244.32006 -49.619154)
		(end 244.43436 -49.828958)
		(width 0.0889)
		(layer "F.Cu")
		(net "M_B_DQS_DP<3>")
	)
	(segment
		(start 242.287552 -47.37989)
		(end 243.856764 -48.949102)
		(width 0.1016)
		(layer "F.Cu")
		(net "M_B_DQS_DP<3>")
	)
	(segment
		(start 229.094538 -28.007056)
		(end 229.368858 -28.007056)
		(width 0.1651)
		(layer "F.Cu")
		(net "M_B_DQS_DP<3>")
	)
	(segment
		(start 229.04958 -30.43682)
		(end 229.04958 -30.69082)
		(width 0.1651)
		(layer "F.Cu")
		(net "M_B_DQS_DP<3>")
	)
	(via
		(at 229.087934 -7.75716)
		(size 0.508)
		(drill 0.254)
		(layers "F.Cu" "B.Cu")
		(net "M_B_DQS_DP<3>")
	)
	(via
		(at 229.087934 -13.287756)
		(size 0.508)
		(drill 0.254)
		(layers "F.Cu" "B.Cu")
		(net "M_B_DQS_DP<3>")
	)
	(via
		(at 229.094538 -28.007056)
		(size 0.508)
		(drill 0.254)
		(layers "F.Cu" "B.Cu")
		(net "M_B_DQS_DP<3>")
	)
	(via
		(at 228.9175 -31.369)
		(size 0.508)
		(drill 0.254)
		(layers "F.Cu" "B.Cu")
		(net "M_B_DQS_DP<3>")
	)
	(arc
		(start 244.424708 -50.442622)
		(mid 244.369778 -50.639651)
		(end 244.422168 -50.837338)
		(width 0.0889)
		(layer "F.Cu")
		(net "M_B_DQS_DP<3>")
	)
	(arc
		(start 243.910358 -51.724052)
		(mid 243.51159 -52.09185)
		(end 243.846604 -52.51831)
		(width 0.0889)
		(layer "F.Cu")
		(net "M_B_DQS_DP<3>")
	)
	(arc
		(start 244.422168 -50.837338)
		(mid 244.422077 -51.4283)
		(end 243.910358 -51.723798)
		(width 0.0889)
		(layer "F.Cu")
		(net "M_B_DQS_DP<3>")
	)
	(arc
		(start 244.43436 -49.828958)
		(mid 244.51001 -50.115485)
		(end 244.44452 -50.404522)
		(width 0.0889)
		(layer "F.Cu")
		(net "M_B_DQS_DP<3>")
	)
	(segment
		(start 229.54996 -10.623042)
		(end 229.54996 -11.773154)
		(width 0.1651)
		(layer "B.Cu")
		(net "M_B_DQS_DP<3>")
	)
	(segment
		(start 229.54996 -11.773154)
		(end 229.587806 -11.811)
		(width 0.1651)
		(layer "B.Cu")
		(net "M_B_DQS_DP<3>")
	)
	(segment
		(start 229.33025 -13.287756)
		(end 229.087934 -13.287756)
		(width 0.1651)
		(layer "B.Cu")
		(net "M_B_DQS_DP<3>")
	)
	(segment
		(start 229.587806 -11.811)
		(end 229.587806 -13.0302)
		(width 0.1651)
		(layer "B.Cu")
		(net "M_B_DQS_DP<3>")
	)
	(segment
		(start 229.550468 -10.623042)
		(end 229.54996 -10.623042)
		(width 0.1651)
		(layer "B.Cu")
		(net "M_B_DQS_DP<3>")
	)
	(segment
		(start 229.587806 -13.0302)
		(end 229.33025 -13.287756)
		(width 0.1651)
		(layer "B.Cu")
		(net "M_B_DQS_DP<3>")
	)
	(segment
		(start 229.854252 -15.150846)
		(end 229.854252 -27.498802)
		(width 0.14224)
		(layer "In4.Cu")
		(net "M_B_DQS_DP<3>")
	)
	(segment
		(start 229.898702 -12.476988)
		(end 229.087934 -13.287756)
		(width 0.14224)
		(layer "In4.Cu")
		(net "M_B_DQS_DP<3>")
	)
	(segment
		(start 229.551738 -14.201394)
		(end 229.371652 -14.38148)
		(width 0.14224)
		(layer "In4.Cu")
		(net "M_B_DQS_DP<3>")
	)
	(segment
		(start 229.371652 -14.38148)
		(end 229.371652 -14.668246)
		(width 0.14224)
		(layer "In4.Cu")
		(net "M_B_DQS_DP<3>")
	)
	(segment
		(start 229.371652 -14.668246)
		(end 229.854252 -15.150846)
		(width 0.14224)
		(layer "In4.Cu")
		(net "M_B_DQS_DP<3>")
	)
	(segment
		(start 229.087934 -13.287756)
		(end 229.551738 -13.75156)
		(width 0.14224)
		(layer "In4.Cu")
		(net "M_B_DQS_DP<3>")
	)
	(segment
		(start 229.345998 -28.007056)
		(end 229.094538 -28.007056)
		(width 0.14224)
		(layer "In4.Cu")
		(net "M_B_DQS_DP<3>")
	)
	(segment
		(start 229.898702 -8.567928)
		(end 229.898702 -12.476988)
		(width 0.14224)
		(layer "In4.Cu")
		(net "M_B_DQS_DP<3>")
	)
	(segment
		(start 229.551738 -13.75156)
		(end 229.551738 -14.201394)
		(width 0.14224)
		(layer "In4.Cu")
		(net "M_B_DQS_DP<3>")
	)
	(segment
		(start 229.087934 -7.75716)
		(end 229.898702 -8.567928)
		(width 0.14224)
		(layer "In4.Cu")
		(net "M_B_DQS_DP<3>")
	)
	(segment
		(start 229.854252 -27.498802)
		(end 229.345998 -28.007056)
		(width 0.14224)
		(layer "In4.Cu")
		(net "M_B_DQS_DP<3>")
	)
	(segment
		(start 220.199712 -9.323832)
		(end 220.421454 -9.10209)
		(width 0.1651)
		(layer "F.Cu")
		(net "M_B_DQS_DP<2>")
	)
	(segment
		(start 220.200474 -9.324594)
		(end 220.199712 -9.323832)
		(width 0.1651)
		(layer "F.Cu")
		(net "M_B_DQS_DP<2>")
	)
	(segment
		(start 238.759238 -53.113686)
		(end 238.187738 -53.113686)
		(width 0.1016)
		(layer "F.Cu")
		(net "M_B_DQS_DP<2>")
	)
	(segment
		(start 220.421454 -8.359902)
		(end 220.207586 -8.146034)
		(width 0.1651)
		(layer "F.Cu")
		(net "M_B_DQS_DP<2>")
	)
	(segment
		(start 220.011752 -8.146034)
		(end 219.73794 -8.419846)
		(width 0.1651)
		(layer "F.Cu")
		(net "M_B_DQS_DP<2>")
	)
	(segment
		(start 220.200474 -10.422382)
		(end 220.200474 -9.324594)
		(width 0.1651)
		(layer "F.Cu")
		(net "M_B_DQS_DP<2>")
	)
	(segment
		(start 220.207586 -8.146034)
		(end 220.011752 -8.146034)
		(width 0.1651)
		(layer "F.Cu")
		(net "M_B_DQS_DP<2>")
	)
	(segment
		(start 220.421454 -9.10209)
		(end 220.421454 -8.359902)
		(width 0.1651)
		(layer "F.Cu")
		(net "M_B_DQS_DP<2>")
	)
	(via
		(at 219.73794 -12.627356)
		(size 0.508)
		(drill 0.254)
		(layers "F.Cu" "B.Cu")
		(net "M_B_DQS_DP<2>")
	)
	(via
		(at 238.187738 -53.113686)
		(size 0.508)
		(drill 0.254)
		(layers "F.Cu" "B.Cu")
		(net "M_B_DQS_DP<2>")
	)
	(via
		(at 219.73794 -8.419846)
		(size 0.508)
		(drill 0.254)
		(layers "F.Cu" "B.Cu")
		(net "M_B_DQS_DP<2>")
	)
	(segment
		(start 220.200474 -10.623042)
		(end 220.199966 -10.623042)
		(width 0.1651)
		(layer "B.Cu")
		(net "M_B_DQS_DP<2>")
	)
	(segment
		(start 220.379544 -12.76858)
		(end 220.239844 -12.90828)
		(width 0.1651)
		(layer "B.Cu")
		(net "M_B_DQS_DP<2>")
	)
	(segment
		(start 220.199712 -10.9728)
		(end 220.199712 -12.139168)
		(width 0.1651)
		(layer "B.Cu")
		(net "M_B_DQS_DP<2>")
	)
	(segment
		(start 220.199966 -10.623042)
		(end 220.199966 -10.972546)
		(width 0.1651)
		(layer "B.Cu")
		(net "M_B_DQS_DP<2>")
	)
	(segment
		(start 220.199966 -10.972546)
		(end 220.199712 -10.9728)
		(width 0.1651)
		(layer "B.Cu")
		(net "M_B_DQS_DP<2>")
	)
	(segment
		(start 220.379544 -12.319)
		(end 220.379544 -12.76858)
		(width 0.1651)
		(layer "B.Cu")
		(net "M_B_DQS_DP<2>")
	)
	(segment
		(start 220.239844 -12.90828)
		(end 220.018864 -12.90828)
		(width 0.1651)
		(layer "B.Cu")
		(net "M_B_DQS_DP<2>")
	)
	(segment
		(start 220.018864 -12.90828)
		(end 219.73794 -12.627356)
		(width 0.1651)
		(layer "B.Cu")
		(net "M_B_DQS_DP<2>")
	)
	(segment
		(start 220.199712 -12.139168)
		(end 220.379544 -12.319)
		(width 0.1651)
		(layer "B.Cu")
		(net "M_B_DQS_DP<2>")
	)
	(segment
		(start 220.016832 -12.62761)
		(end 220.279468 -12.364974)
		(width 0.14224)
		(layer "In4.Cu")
		(net "M_B_DQS_DP<2>")
	)
	(segment
		(start 234.283758 -47.233586)
		(end 233.4641 -46.413928)
		(width 0.14224)
		(layer "In4.Cu")
		(net "M_B_DQS_DP<2>")
	)
	(segment
		(start 219.744544 -9.981946)
		(end 219.744544 -9.677654)
		(width 0.14224)
		(layer "In4.Cu")
		(net "M_B_DQS_DP<2>")
	)
	(segment
		(start 238.413798 -50.723546)
		(end 238.413798 -49.992026)
		(width 0.0889)
		(layer "In4.Cu")
		(net "M_B_DQS_DP<2>")
	)
	(segment
		(start 220.279468 -12.364974)
		(end 220.279468 -11.660124)
		(width 0.14224)
		(layer "In4.Cu")
		(net "M_B_DQS_DP<2>")
	)
	(segment
		(start 219.897198 -9.525)
		(end 220.09989 -9.525)
		(width 0.14224)
		(layer "In4.Cu")
		(net "M_B_DQS_DP<2>")
	)
	(segment
		(start 236.130338 -49.02454)
		(end 234.355132 -47.249334)
		(width 0.0889)
		(layer "In4.Cu")
		(net "M_B_DQS_DP<2>")
	)
	(segment
		(start 238.528098 -52.333906)
		(end 238.534448 -52.323238)
		(width 0.0889)
		(layer "In4.Cu")
		(net "M_B_DQS_DP<2>")
	)
	(segment
		(start 219.300044 -14.663166)
		(end 219.300044 -13.065252)
		(width 0.14224)
		(layer "In4.Cu")
		(net "M_B_DQS_DP<2>")
	)
	(segment
		(start 220.279468 -11.660124)
		(end 220.100144 -11.4808)
		(width 0.14224)
		(layer "In4.Cu")
		(net "M_B_DQS_DP<2>")
	)
	(segment
		(start 230.129588 -42.64406)
		(end 230.12908 -42.644314)
		(width 0.14224)
		(layer "In4.Cu")
		(net "M_B_DQS_DP<2>")
	)
	(segment
		(start 220.279468 -10.339578)
		(end 220.07449 -10.1346)
		(width 0.14224)
		(layer "In4.Cu")
		(net "M_B_DQS_DP<2>")
	)
	(segment
		(start 220.096588 -10.8712)
		(end 220.279468 -10.68832)
		(width 0.14224)
		(layer "In4.Cu")
		(net "M_B_DQS_DP<2>")
	)
	(segment
		(start 230.12908 -39.266114)
		(end 220.25102 -29.388054)
		(width 0.14224)
		(layer "In4.Cu")
		(net "M_B_DQS_DP<2>")
	)
	(segment
		(start 234.299506 -47.249334)
		(end 234.283758 -47.233586)
		(width 0.0889)
		(layer "In4.Cu")
		(net "M_B_DQS_DP<2>")
	)
	(segment
		(start 238.539274 -52.922424)
		(end 238.534448 -52.913788)
		(width 0.0889)
		(layer "In4.Cu")
		(net "M_B_DQS_DP<2>")
	)
	(segment
		(start 238.539274 -50.941224)
		(end 238.413798 -50.723546)
		(width 0.0889)
		(layer "In4.Cu")
		(net "M_B_DQS_DP<2>")
	)
	(segment
		(start 230.12908 -42.644314)
		(end 230.12908 -39.266114)
		(width 0.14224)
		(layer "In4.Cu")
		(net "M_B_DQS_DP<2>")
	)
	(segment
		(start 219.73794 -12.62761)
		(end 220.016832 -12.62761)
		(width 0.14224)
		(layer "In4.Cu")
		(net "M_B_DQS_DP<2>")
	)
	(segment
		(start 237.446312 -49.02454)
		(end 236.130338 -49.02454)
		(width 0.0889)
		(layer "In4.Cu")
		(net "M_B_DQS_DP<2>")
	)
	(segment
		(start 238.413798 -49.992026)
		(end 237.446312 -49.02454)
		(width 0.0889)
		(layer "In4.Cu")
		(net "M_B_DQS_DP<2>")
	)
	(segment
		(start 220.279468 -10.68832)
		(end 220.279468 -10.339578)
		(width 0.14224)
		(layer "In4.Cu")
		(net "M_B_DQS_DP<2>")
	)
	(segment
		(start 220.100144 -11.4808)
		(end 219.969588 -11.4808)
		(width 0.14224)
		(layer "In4.Cu")
		(net "M_B_DQS_DP<2>")
	)
	(segment
		(start 219.744544 -9.677654)
		(end 219.897198 -9.525)
		(width 0.14224)
		(layer "In4.Cu")
		(net "M_B_DQS_DP<2>")
	)
	(segment
		(start 220.09989 -9.525)
		(end 220.279468 -9.345422)
		(width 0.14224)
		(layer "In4.Cu")
		(net "M_B_DQS_DP<2>")
	)
	(segment
		(start 220.279468 -9.345422)
		(end 220.279468 -8.679688)
		(width 0.14224)
		(layer "In4.Cu")
		(net "M_B_DQS_DP<2>")
	)
	(segment
		(start 238.187738 -53.113686)
		(end 238.187738 -53.45176)
		(width 0.0889)
		(layer "In4.Cu")
		(net "M_B_DQS_DP<2>")
	)
	(segment
		(start 233.4641 -45.978572)
		(end 230.129588 -42.64406)
		(width 0.14224)
		(layer "In4.Cu")
		(net "M_B_DQS_DP<2>")
	)
	(segment
		(start 219.419424 -14.993874)
		(end 219.419424 -14.782546)
		(width 0.14224)
		(layer "In4.Cu")
		(net "M_B_DQS_DP<2>")
	)
	(segment
		(start 219.300044 -13.065252)
		(end 219.73794 -12.627356)
		(width 0.14224)
		(layer "In4.Cu")
		(net "M_B_DQS_DP<2>")
	)
	(segment
		(start 238.187738 -53.45176)
		(end 238.24565 -53.509672)
		(width 0.0889)
		(layer "In4.Cu")
		(net "M_B_DQS_DP<2>")
	)
	(segment
		(start 219.419424 -14.782546)
		(end 219.300044 -14.663166)
		(width 0.14224)
		(layer "In4.Cu")
		(net "M_B_DQS_DP<2>")
	)
	(segment
		(start 220.279468 -8.679688)
		(end 220.019626 -8.419846)
		(width 0.14224)
		(layer "In4.Cu")
		(net "M_B_DQS_DP<2>")
	)
	(segment
		(start 234.355132 -47.249334)
		(end 234.299506 -47.249334)
		(width 0.0889)
		(layer "In4.Cu")
		(net "M_B_DQS_DP<2>")
	)
	(segment
		(start 219.791788 -11.303)
		(end 219.791788 -11.049)
		(width 0.14224)
		(layer "In4.Cu")
		(net "M_B_DQS_DP<2>")
	)
	(segment
		(start 233.4641 -46.413928)
		(end 233.4641 -45.978572)
		(width 0.14224)
		(layer "In4.Cu")
		(net "M_B_DQS_DP<2>")
	)
	(segment
		(start 219.969588 -10.8712)
		(end 220.096588 -10.8712)
		(width 0.14224)
		(layer "In4.Cu")
		(net "M_B_DQS_DP<2>")
	)
	(segment
		(start 220.019626 -8.419846)
		(end 219.73794 -8.419846)
		(width 0.14224)
		(layer "In4.Cu")
		(net "M_B_DQS_DP<2>")
	)
	(segment
		(start 220.25102 -29.388054)
		(end 220.25102 -15.82547)
		(width 0.14224)
		(layer "In4.Cu")
		(net "M_B_DQS_DP<2>")
	)
	(segment
		(start 219.73794 -12.627356)
		(end 219.73794 -12.62761)
		(width 0.14224)
		(layer "In4.Cu")
		(net "M_B_DQS_DP<2>")
	)
	(segment
		(start 220.25102 -15.82547)
		(end 219.419424 -14.993874)
		(width 0.14224)
		(layer "In4.Cu")
		(net "M_B_DQS_DP<2>")
	)
	(segment
		(start 219.897198 -10.1346)
		(end 219.744544 -9.981946)
		(width 0.14224)
		(layer "In4.Cu")
		(net "M_B_DQS_DP<2>")
	)
	(segment
		(start 219.969588 -11.4808)
		(end 219.791788 -11.303)
		(width 0.14224)
		(layer "In4.Cu")
		(net "M_B_DQS_DP<2>")
	)
	(segment
		(start 220.07449 -10.1346)
		(end 219.897198 -10.1346)
		(width 0.14224)
		(layer "In4.Cu")
		(net "M_B_DQS_DP<2>")
	)
	(segment
		(start 219.791788 -11.049)
		(end 219.969588 -10.8712)
		(width 0.14224)
		(layer "In4.Cu")
		(net "M_B_DQS_DP<2>")
	)
	(arc
		(start 238.534448 -52.323238)
		(mid 238.587947 -52.12334)
		(end 238.534448 -51.923442)
		(width 0.0889)
		(layer "In4.Cu")
		(net "M_B_DQS_DP<2>")
	)
	(arc
		(start 238.534448 -52.913788)
		(mid 238.455226 -52.62467)
		(end 238.528098 -52.333906)
		(width 0.0889)
		(layer "In4.Cu")
		(net "M_B_DQS_DP<2>")
	)
	(arc
		(start 238.534448 -51.923442)
		(mid 238.455317 -51.62804)
		(end 238.534448 -51.332638)
		(width 0.0889)
		(layer "In4.Cu")
		(net "M_B_DQS_DP<2>")
	)
	(arc
		(start 238.534448 -51.332638)
		(mid 238.587918 -51.137575)
		(end 238.539274 -50.941224)
		(width 0.0889)
		(layer "In4.Cu")
		(net "M_B_DQS_DP<2>")
	)
	(arc
		(start 238.24565 -53.509672)
		(mid 238.545686 -53.29266)
		(end 238.539274 -52.922424)
		(width 0.0889)
		(layer "In4.Cu")
		(net "M_B_DQS_DP<2>")
	)
	(segment
		(start 237.900718 -61.53404)
		(end 237.329218 -61.53404)
		(width 0.1016)
		(layer "F.Cu")
		(net "M_B_DQS_DP<1>")
	)
	(segment
		(start 210.661758 -8.146034)
		(end 210.387946 -8.419846)
		(width 0.1651)
		(layer "F.Cu")
		(net "M_B_DQS_DP<1>")
	)
	(segment
		(start 210.85048 -9.32307)
		(end 211.07146 -9.10209)
		(width 0.1651)
		(layer "F.Cu")
		(net "M_B_DQS_DP<1>")
	)
	(segment
		(start 211.07146 -9.10209)
		(end 211.07146 -8.359902)
		(width 0.1651)
		(layer "F.Cu")
		(net "M_B_DQS_DP<1>")
	)
	(segment
		(start 210.857592 -8.146034)
		(end 210.661758 -8.146034)
		(width 0.1651)
		(layer "F.Cu")
		(net "M_B_DQS_DP<1>")
	)
	(segment
		(start 211.07146 -8.359902)
		(end 210.857592 -8.146034)
		(width 0.1651)
		(layer "F.Cu")
		(net "M_B_DQS_DP<1>")
	)
	(segment
		(start 210.85048 -10.422382)
		(end 210.85048 -9.32307)
		(width 0.1651)
		(layer "F.Cu")
		(net "M_B_DQS_DP<1>")
	)
	(via
		(at 237.329218 -61.53404)
		(size 0.508)
		(drill 0.254)
		(layers "F.Cu" "B.Cu")
		(net "M_B_DQS_DP<1>")
	)
	(via
		(at 210.387946 -8.419846)
		(size 0.508)
		(drill 0.254)
		(layers "F.Cu" "B.Cu")
		(net "M_B_DQS_DP<1>")
	)
	(via
		(at 210.387946 -12.627356)
		(size 0.508)
		(drill 0.254)
		(layers "F.Cu" "B.Cu")
		(net "M_B_DQS_DP<1>")
	)
	(segment
		(start 210.85048 -10.623042)
		(end 210.849972 -10.623042)
		(width 0.1651)
		(layer "B.Cu")
		(net "M_B_DQS_DP<1>")
	)
	(segment
		(start 211.02955 -12.76858)
		(end 210.88985 -12.90828)
		(width 0.1651)
		(layer "B.Cu")
		(net "M_B_DQS_DP<1>")
	)
	(segment
		(start 210.849972 -10.623042)
		(end 210.849972 -10.972546)
		(width 0.1651)
		(layer "B.Cu")
		(net "M_B_DQS_DP<1>")
	)
	(segment
		(start 210.66887 -12.90828)
		(end 210.387946 -12.627356)
		(width 0.1651)
		(layer "B.Cu")
		(net "M_B_DQS_DP<1>")
	)
	(segment
		(start 210.849718 -10.9728)
		(end 210.849718 -11.942064)
		(width 0.1651)
		(layer "B.Cu")
		(net "M_B_DQS_DP<1>")
	)
	(segment
		(start 210.88985 -12.90828)
		(end 210.66887 -12.90828)
		(width 0.1651)
		(layer "B.Cu")
		(net "M_B_DQS_DP<1>")
	)
	(segment
		(start 211.02955 -12.121896)
		(end 211.02955 -12.76858)
		(width 0.1651)
		(layer "B.Cu")
		(net "M_B_DQS_DP<1>")
	)
	(segment
		(start 210.849718 -11.942064)
		(end 211.02955 -12.121896)
		(width 0.1651)
		(layer "B.Cu")
		(net "M_B_DQS_DP<1>")
	)
	(segment
		(start 210.849972 -10.972546)
		(end 210.849718 -10.9728)
		(width 0.1651)
		(layer "B.Cu")
		(net "M_B_DQS_DP<1>")
	)
	(segment
		(start 210.39455 -9.677654)
		(end 210.547204 -9.525)
		(width 0.14224)
		(layer "In4.Cu")
		(net "M_B_DQS_DP<1>")
	)
	(segment
		(start 214.756492 -35.127946)
		(end 214.537544 -35.127946)
		(width 0.14224)
		(layer "In4.Cu")
		(net "M_B_DQS_DP<1>")
	)
	(segment
		(start 213.819994 -35.845496)
		(end 213.378796 -35.845496)
		(width 0.14224)
		(layer "In4.Cu")
		(net "M_B_DQS_DP<1>")
	)
	(segment
		(start 210.441794 -11.303)
		(end 210.441794 -11.049)
		(width 0.14224)
		(layer "In4.Cu")
		(net "M_B_DQS_DP<1>")
	)
	(segment
		(start 212.969856 -35.436556)
		(end 212.969856 -34.99485)
		(width 0.14224)
		(layer "In4.Cu")
		(net "M_B_DQS_DP<1>")
	)
	(segment
		(start 210.547204 -10.1346)
		(end 210.39455 -9.981946)
		(width 0.14224)
		(layer "In4.Cu")
		(net "M_B_DQS_DP<1>")
	)
	(segment
		(start 216.20988 -36.581334)
		(end 214.756492 -35.127946)
		(width 0.14224)
		(layer "In4.Cu")
		(net "M_B_DQS_DP<1>")
	)
	(segment
		(start 213.687152 -34.277554)
		(end 213.687152 -34.058606)
		(width 0.14224)
		(layer "In4.Cu")
		(net "M_B_DQS_DP<1>")
	)
	(segment
		(start 210.441794 -11.049)
		(end 210.619594 -10.8712)
		(width 0.14224)
		(layer "In4.Cu")
		(net "M_B_DQS_DP<1>")
	)
	(segment
		(start 211.18068 -24.152352)
		(end 210.901026 -23.872698)
		(width 0.14224)
		(layer "In4.Cu")
		(net "M_B_DQS_DP<1>")
	)
	(segment
		(start 209.95005 -13.065252)
		(end 210.387946 -12.627356)
		(width 0.14224)
		(layer "In4.Cu")
		(net "M_B_DQS_DP<1>")
	)
	(segment
		(start 215.75268 -38.966648)
		(end 216.20988 -38.509448)
		(width 0.14224)
		(layer "In4.Cu")
		(net "M_B_DQS_DP<1>")
	)
	(segment
		(start 210.619594 -10.8712)
		(end 210.746594 -10.8712)
		(width 0.14224)
		(layer "In4.Cu")
		(net "M_B_DQS_DP<1>")
	)
	(segment
		(start 210.06943 -14.782546)
		(end 209.95005 -14.663166)
		(width 0.14224)
		(layer "In4.Cu")
		(net "M_B_DQS_DP<1>")
	)
	(segment
		(start 210.749896 -9.525)
		(end 210.929474 -9.345422)
		(width 0.14224)
		(layer "In4.Cu")
		(net "M_B_DQS_DP<1>")
	)
	(segment
		(start 211.18068 -31.552134)
		(end 211.18068 -24.152352)
		(width 0.14224)
		(layer "In4.Cu")
		(net "M_B_DQS_DP<1>")
	)
	(segment
		(start 237.622334 -61.364876)
		(end 237.643416 -61.286136)
		(width 0.0889)
		(layer "In4.Cu")
		(net "M_B_DQS_DP<1>")
	)
	(segment
		(start 213.687152 -34.058606)
		(end 211.18068 -31.552134)
		(width 0.14224)
		(layer "In4.Cu")
		(net "M_B_DQS_DP<1>")
	)
	(segment
		(start 209.95005 -14.663166)
		(end 209.95005 -13.065252)
		(width 0.14224)
		(layer "In4.Cu")
		(net "M_B_DQS_DP<1>")
	)
	(segment
		(start 235.612686 -62.124336)
		(end 235.611162 -62.124336)
		(width 0.0889)
		(layer "In4.Cu")
		(net "M_B_DQS_DP<1>")
	)
	(segment
		(start 210.746594 -10.8712)
		(end 210.929474 -10.68832)
		(width 0.14224)
		(layer "In4.Cu")
		(net "M_B_DQS_DP<1>")
	)
	(segment
		(start 215.753188 -39.526464)
		(end 215.75268 -39.526718)
		(width 0.14224)
		(layer "In4.Cu")
		(net "M_B_DQS_DP<1>")
	)
	(segment
		(start 210.669632 -8.419846)
		(end 210.387946 -8.419846)
		(width 0.14224)
		(layer "In4.Cu")
		(net "M_B_DQS_DP<1>")
	)
	(segment
		(start 213.378796 -35.845496)
		(end 212.969856 -35.436556)
		(width 0.14224)
		(layer "In4.Cu")
		(net "M_B_DQS_DP<1>")
	)
	(segment
		(start 215.75268 -39.526718)
		(end 215.75268 -38.966648)
		(width 0.14224)
		(layer "In4.Cu")
		(net "M_B_DQS_DP<1>")
	)
	(segment
		(start 234.037124 -59.062112)
		(end 234.037124 -58.645044)
		(width 0.0889)
		(layer "In4.Cu")
		(net "M_B_DQS_DP<1>")
	)
	(segment
		(start 210.666838 -12.62761)
		(end 210.929474 -12.364974)
		(width 0.14224)
		(layer "In4.Cu")
		(net "M_B_DQS_DP<1>")
	)
	(segment
		(start 233.997754 -58.605674)
		(end 233.997754 -58.583576)
		(width 0.0889)
		(layer "In4.Cu")
		(net "M_B_DQS_DP<1>")
	)
	(segment
		(start 210.724496 -10.1346)
		(end 210.547204 -10.1346)
		(width 0.14224)
		(layer "In4.Cu")
		(net "M_B_DQS_DP<1>")
	)
	(segment
		(start 210.929474 -10.68832)
		(end 210.929474 -10.339578)
		(width 0.14224)
		(layer "In4.Cu")
		(net "M_B_DQS_DP<1>")
	)
	(segment
		(start 210.901026 -15.82547)
		(end 210.06943 -14.993874)
		(width 0.14224)
		(layer "In4.Cu")
		(net "M_B_DQS_DP<1>")
	)
	(segment
		(start 210.547204 -9.525)
		(end 210.749896 -9.525)
		(width 0.14224)
		(layer "In4.Cu")
		(net "M_B_DQS_DP<1>")
	)
	(segment
		(start 234.241848 -60.343288)
		(end 234.163108 -60.207144)
		(width 0.0889)
		(layer "In4.Cu")
		(net "M_B_DQS_DP<1>")
	)
	(segment
		(start 236.492288 -61.629036)
		(end 236.459522 -61.629036)
		(width 0.0889)
		(layer "In4.Cu")
		(net "M_B_DQS_DP<1>")
	)
	(segment
		(start 214.537544 -35.127946)
		(end 213.819994 -35.845496)
		(width 0.14224)
		(layer "In4.Cu")
		(net "M_B_DQS_DP<1>")
	)
	(segment
		(start 210.929474 -10.339578)
		(end 210.724496 -10.1346)
		(width 0.14224)
		(layer "In4.Cu")
		(net "M_B_DQS_DP<1>")
	)
	(segment
		(start 210.929474 -9.345422)
		(end 210.929474 -8.679688)
		(width 0.14224)
		(layer "In4.Cu")
		(net "M_B_DQS_DP<1>")
	)
	(segment
		(start 234.163108 -60.207144)
		(end 234.163108 -59.188096)
		(width 0.0889)
		(layer "In4.Cu")
		(net "M_B_DQS_DP<1>")
	)
	(segment
		(start 210.387946 -12.62761)
		(end 210.666838 -12.62761)
		(width 0.14224)
		(layer "In4.Cu")
		(net "M_B_DQS_DP<1>")
	)
	(segment
		(start 233.997754 -57.77103)
		(end 215.753188 -39.526464)
		(width 0.14224)
		(layer "In4.Cu")
		(net "M_B_DQS_DP<1>")
	)
	(segment
		(start 234.163108 -59.188096)
		(end 234.037124 -59.062112)
		(width 0.0889)
		(layer "In4.Cu")
		(net "M_B_DQS_DP<1>")
	)
	(segment
		(start 210.75015 -11.4808)
		(end 210.619594 -11.4808)
		(width 0.14224)
		(layer "In4.Cu")
		(net "M_B_DQS_DP<1>")
	)
	(segment
		(start 237.344204 -61.13399)
		(end 237.314232 -61.13399)
		(width 0.0889)
		(layer "In4.Cu")
		(net "M_B_DQS_DP<1>")
	)
	(segment
		(start 210.387946 -12.627356)
		(end 210.387946 -12.62761)
		(width 0.14224)
		(layer "In4.Cu")
		(net "M_B_DQS_DP<1>")
	)
	(segment
		(start 233.997754 -58.583576)
		(end 233.997754 -57.77103)
		(width 0.14224)
		(layer "In4.Cu")
		(net "M_B_DQS_DP<1>")
	)
	(segment
		(start 210.929474 -8.679688)
		(end 210.669632 -8.419846)
		(width 0.14224)
		(layer "In4.Cu")
		(net "M_B_DQS_DP<1>")
	)
	(segment
		(start 237.329218 -61.53404)
		(end 237.622334 -61.364876)
		(width 0.0889)
		(layer "In4.Cu")
		(net "M_B_DQS_DP<1>")
	)
	(segment
		(start 210.901026 -23.872698)
		(end 210.901026 -15.82547)
		(width 0.14224)
		(layer "In4.Cu")
		(net "M_B_DQS_DP<1>")
	)
	(segment
		(start 234.764834 -61.629036)
		(end 234.732068 -61.629036)
		(width 0.0889)
		(layer "In4.Cu")
		(net "M_B_DQS_DP<1>")
	)
	(segment
		(start 210.619594 -11.4808)
		(end 210.441794 -11.303)
		(width 0.14224)
		(layer "In4.Cu")
		(net "M_B_DQS_DP<1>")
	)
	(segment
		(start 210.929474 -11.660124)
		(end 210.75015 -11.4808)
		(width 0.14224)
		(layer "In4.Cu")
		(net "M_B_DQS_DP<1>")
	)
	(segment
		(start 210.39455 -9.981946)
		(end 210.39455 -9.677654)
		(width 0.14224)
		(layer "In4.Cu")
		(net "M_B_DQS_DP<1>")
	)
	(segment
		(start 212.969856 -34.99485)
		(end 213.687152 -34.277554)
		(width 0.14224)
		(layer "In4.Cu")
		(net "M_B_DQS_DP<1>")
	)
	(segment
		(start 210.929474 -12.364974)
		(end 210.929474 -11.660124)
		(width 0.14224)
		(layer "In4.Cu")
		(net "M_B_DQS_DP<1>")
	)
	(segment
		(start 210.06943 -14.993874)
		(end 210.06943 -14.782546)
		(width 0.14224)
		(layer "In4.Cu")
		(net "M_B_DQS_DP<1>")
	)
	(segment
		(start 234.037124 -58.645044)
		(end 233.997754 -58.605674)
		(width 0.0889)
		(layer "In4.Cu")
		(net "M_B_DQS_DP<1>")
	)
	(segment
		(start 216.20988 -38.509448)
		(end 216.20988 -36.581334)
		(width 0.14224)
		(layer "In4.Cu")
		(net "M_B_DQS_DP<1>")
	)
	(arc
		(start 237.314232 -61.13399)
		(mid 237.12259 -61.191156)
		(end 236.982508 -61.333888)
		(width 0.0889)
		(layer "In4.Cu")
		(net "M_B_DQS_DP<1>")
	)
	(arc
		(start 235.100368 -61.829188)
		(mid 234.958685 -61.685384)
		(end 234.764834 -61.629036)
		(width 0.0889)
		(layer "In4.Cu")
		(net "M_B_DQS_DP<1>")
	)
	(arc
		(start 237.643416 -61.286136)
		(mid 237.510535 -61.177153)
		(end 237.344204 -61.13399)
		(width 0.0889)
		(layer "In4.Cu")
		(net "M_B_DQS_DP<1>")
	)
	(arc
		(start 235.611162 -62.124336)
		(mid 235.316168 -62.045262)
		(end 235.100368 -61.829188)
		(width 0.0889)
		(layer "In4.Cu")
		(net "M_B_DQS_DP<1>")
	)
	(arc
		(start 236.459522 -61.629036)
		(mid 236.265672 -61.685386)
		(end 236.123988 -61.829188)
		(width 0.0889)
		(layer "In4.Cu")
		(net "M_B_DQS_DP<1>")
	)
	(arc
		(start 234.732068 -61.629036)
		(mid 234.236591 -61.324593)
		(end 234.241848 -60.743084)
		(width 0.0889)
		(layer "In4.Cu")
		(net "M_B_DQS_DP<1>")
	)
	(arc
		(start 236.123988 -61.829188)
		(mid 235.907915 -62.045296)
		(end 235.612686 -62.124336)
		(width 0.0889)
		(layer "In4.Cu")
		(net "M_B_DQS_DP<1>")
	)
	(arc
		(start 236.982508 -61.333888)
		(mid 236.775504 -61.544752)
		(end 236.492288 -61.629036)
		(width 0.0889)
		(layer "In4.Cu")
		(net "M_B_DQS_DP<1>")
	)
	(arc
		(start 234.241848 -60.743084)
		(mid 234.295347 -60.543186)
		(end 234.241848 -60.343288)
		(width 0.0889)
		(layer "In4.Cu")
		(net "M_B_DQS_DP<1>")
	)
	(segment
		(start 239.159542 -33.74136)
		(end 238.8616 -34.039302)
		(width 0.1651)
		(layer "F.Cu")
		(net "M_B_DQS_DP<17>")
	)
	(segment
		(start 239.8141 -32.968946)
		(end 239.8141 -33.57626)
		(width 0.1651)
		(layer "F.Cu")
		(net "M_B_DQS_DP<17>")
	)
	(segment
		(start 239.37595 -32.530796)
		(end 239.8141 -32.968946)
		(width 0.1651)
		(layer "F.Cu")
		(net "M_B_DQS_DP<17>")
	)
	(segment
		(start 236.6772 -27.869642)
		(end 236.6772 -28.930854)
		(width 0.1651)
		(layer "F.Cu")
		(net "M_B_DQS_DP<17>")
	)
	(segment
		(start 238.8616 -34.700718)
		(end 239.159542 -34.99866)
		(width 0.1651)
		(layer "F.Cu")
		(net "M_B_DQS_DP<17>")
	)
	(segment
		(start 239.632236 -36.1061)
		(end 239.062006 -36.1061)
		(width 0.1651)
		(layer "F.Cu")
		(net "M_B_DQS_DP<17>")
	)
	(segment
		(start 236.776514 -29.263848)
		(end 236.748066 -29.292296)
		(width 0.1651)
		(layer "F.Cu")
		(net "M_B_DQS_DP<17>")
	)
	(segment
		(start 247.850914 -52.427124)
		(end 247.85574 -52.418488)
		(width 0.0889)
		(layer "F.Cu")
		(net "M_B_DQS_DP<17>")
	)
	(segment
		(start 236.6772 -28.930854)
		(end 236.776514 -29.030168)
		(width 0.1651)
		(layer "F.Cu")
		(net "M_B_DQS_DP<17>")
	)
	(segment
		(start 236.748066 -29.292296)
		(end 236.748066 -29.902912)
		(width 0.1651)
		(layer "F.Cu")
		(net "M_B_DQS_DP<17>")
	)
	(segment
		(start 248.013474 -51.812952)
		(end 248.013474 -50.277014)
		(width 0.0889)
		(layer "F.Cu")
		(net "M_B_DQS_DP<17>")
	)
	(segment
		(start 237.149132 -27.39771)
		(end 236.6772 -27.869642)
		(width 0.1651)
		(layer "F.Cu")
		(net "M_B_DQS_DP<17>")
	)
	(segment
		(start 237.199932 -5.822442)
		(end 237.199932 -6.439154)
		(width 0.1651)
		(layer "F.Cu")
		(net "M_B_DQS_DP<17>")
	)
	(segment
		(start 236.679232 -7.877302)
		(end 236.760766 -8.101584)
		(width 0.1651)
		(layer "F.Cu")
		(net "M_B_DQS_DP<17>")
	)
	(segment
		(start 242.46967 -43.622468)
		(end 243.193316 -44.346114)
		(width 0.1016)
		(layer "F.Cu")
		(net "M_B_DQS_DP<17>")
	)
	(segment
		(start 239.8141 -35.924236)
		(end 239.632236 -36.1061)
		(width 0.1651)
		(layer "F.Cu")
		(net "M_B_DQS_DP<17>")
	)
	(segment
		(start 238.6203 -36.547806)
		(end 238.6203 -41.206928)
		(width 0.1651)
		(layer "F.Cu")
		(net "M_B_DQS_DP<17>")
	)
	(segment
		(start 239.8141 -35.16376)
		(end 239.8141 -35.924236)
		(width 0.1651)
		(layer "F.Cu")
		(net "M_B_DQS_DP<17>")
	)
	(segment
		(start 244.035072 -44.346114)
		(end 243.193316 -44.346114)
		(width 0.1016)
		(layer "F.Cu")
		(net "M_B_DQS_DP<17>")
	)
	(segment
		(start 241.03584 -43.622468)
		(end 242.46967 -43.622468)
		(width 0.1016)
		(layer "F.Cu")
		(net "M_B_DQS_DP<17>")
	)
	(segment
		(start 238.8616 -34.039302)
		(end 238.8616 -34.700718)
		(width 0.1651)
		(layer "F.Cu")
		(net "M_B_DQS_DP<17>")
	)
	(segment
		(start 237.199932 -6.439154)
		(end 236.763814 -6.875272)
		(width 0.1651)
		(layer "F.Cu")
		(net "M_B_DQS_DP<17>")
	)
	(segment
		(start 236.763814 -6.875272)
		(end 236.679232 -7.059168)
		(width 0.1651)
		(layer "F.Cu")
		(net "M_B_DQS_DP<17>")
	)
	(segment
		(start 239.062006 -36.1061)
		(end 238.6203 -36.547806)
		(width 0.1651)
		(layer "F.Cu")
		(net "M_B_DQS_DP<17>")
	)
	(segment
		(start 236.748066 -29.902912)
		(end 239.37595 -32.530796)
		(width 0.1651)
		(layer "F.Cu")
		(net "M_B_DQS_DP<17>")
	)
	(segment
		(start 239.159542 -34.99866)
		(end 239.649 -34.99866)
		(width 0.1651)
		(layer "F.Cu")
		(net "M_B_DQS_DP<17>")
	)
	(segment
		(start 236.776514 -29.030168)
		(end 236.776514 -29.263848)
		(width 0.1651)
		(layer "F.Cu")
		(net "M_B_DQS_DP<17>")
	)
	(segment
		(start 236.679232 -7.059168)
		(end 236.679232 -7.877302)
		(width 0.1651)
		(layer "F.Cu")
		(net "M_B_DQS_DP<17>")
	)
	(segment
		(start 247.938798 -50.202338)
		(end 247.938798 -50.073814)
		(width 0.0889)
		(layer "F.Cu")
		(net "M_B_DQS_DP<17>")
	)
	(segment
		(start 239.649 -34.99866)
		(end 239.8141 -35.16376)
		(width 0.1651)
		(layer "F.Cu")
		(net "M_B_DQS_DP<17>")
	)
	(segment
		(start 238.6203 -41.206928)
		(end 240.701576 -43.288204)
		(width 0.1651)
		(layer "F.Cu")
		(net "M_B_DQS_DP<17>")
	)
	(segment
		(start 239.8141 -33.57626)
		(end 239.649 -33.74136)
		(width 0.1651)
		(layer "F.Cu")
		(net "M_B_DQS_DP<17>")
	)
	(segment
		(start 248.202704 -53.60924)
		(end 247.85574 -52.818538)
		(width 0.0889)
		(layer "F.Cu")
		(net "M_B_DQS_DP<17>")
	)
	(segment
		(start 247.938798 -50.073814)
		(end 247.938798 -48.24984)
		(width 0.1016)
		(layer "F.Cu")
		(net "M_B_DQS_DP<17>")
	)
	(segment
		(start 237.20044 -5.822442)
		(end 237.199932 -5.822442)
		(width 0.1651)
		(layer "F.Cu")
		(net "M_B_DQS_DP<17>")
	)
	(segment
		(start 247.938798 -48.24984)
		(end 244.035072 -44.346114)
		(width 0.1016)
		(layer "F.Cu")
		(net "M_B_DQS_DP<17>")
	)
	(segment
		(start 240.701576 -43.288204)
		(end 241.03584 -43.622468)
		(width 0.1016)
		(layer "F.Cu")
		(net "M_B_DQS_DP<17>")
	)
	(segment
		(start 248.013474 -50.277014)
		(end 247.938798 -50.202338)
		(width 0.0889)
		(layer "F.Cu")
		(net "M_B_DQS_DP<17>")
	)
	(segment
		(start 239.649 -33.74136)
		(end 239.159542 -33.74136)
		(width 0.1651)
		(layer "F.Cu")
		(net "M_B_DQS_DP<17>")
	)
	(segment
		(start 236.760766 -8.101584)
		(end 237.142528 -8.483346)
		(width 0.1651)
		(layer "F.Cu")
		(net "M_B_DQS_DP<17>")
	)
	(via
		(at 237.142528 -8.483346)
		(size 0.508)
		(drill 0.254)
		(layers "F.Cu" "B.Cu")
		(net "M_B_DQS_DP<17>")
	)
	(via
		(at 237.142528 -12.573)
		(size 0.508)
		(drill 0.254)
		(layers "F.Cu" "B.Cu")
		(net "M_B_DQS_DP<17>")
	)
	(via
		(at 239.37595 -32.530796)
		(size 0.508)
		(drill 0.254)
		(layers "F.Cu" "B.Cu")
		(net "M_B_DQS_DP<17>")
	)
	(via
		(at 237.149132 -27.39771)
		(size 0.508)
		(drill 0.254)
		(layers "F.Cu" "B.Cu")
		(net "M_B_DQS_DP<17>")
	)
	(arc
		(start 247.85574 -52.418488)
		(mid 247.890869 -52.350923)
		(end 247.92178 -52.281328)
		(width 0.0889)
		(layer "F.Cu")
		(net "M_B_DQS_DP<17>")
	)
	(arc
		(start 247.92178 -52.281328)
		(mid 247.990364 -52.051589)
		(end 248.013474 -51.812952)
		(width 0.0889)
		(layer "F.Cu")
		(net "M_B_DQS_DP<17>")
	)
	(arc
		(start 247.85574 -52.818538)
		(mid 247.802304 -52.623475)
		(end 247.850914 -52.427124)
		(width 0.0889)
		(layer "F.Cu")
		(net "M_B_DQS_DP<17>")
	)
	(segment
		(start 236.753908 -12.96162)
		(end 237.142528 -12.573)
		(width 0.1651)
		(layer "B.Cu")
		(net "M_B_DQS_DP<17>")
	)
	(segment
		(start 237.20044 -15.222982)
		(end 237.199932 -15.222982)
		(width 0.1651)
		(layer "B.Cu")
		(net "M_B_DQS_DP<17>")
	)
	(segment
		(start 236.666532 -13.121132)
		(end 236.753908 -12.96162)
		(width 0.1651)
		(layer "B.Cu")
		(net "M_B_DQS_DP<17>")
	)
	(segment
		(start 237.199932 -15.222982)
		(end 237.199932 -14.605254)
		(width 0.1651)
		(layer "B.Cu")
		(net "M_B_DQS_DP<17>")
	)
	(segment
		(start 236.743748 -14.14907)
		(end 236.666532 -14.016736)
		(width 0.1651)
		(layer "B.Cu")
		(net "M_B_DQS_DP<17>")
	)
	(segment
		(start 236.666532 -14.016736)
		(end 236.666532 -13.121132)
		(width 0.1651)
		(layer "B.Cu")
		(net "M_B_DQS_DP<17>")
	)
	(segment
		(start 237.199932 -14.605254)
		(end 236.743748 -14.14907)
		(width 0.1651)
		(layer "B.Cu")
		(net "M_B_DQS_DP<17>")
	)
	(segment
		(start 237.298484 -10.8204)
		(end 237.479332 -10.8204)
		(width 0.14224)
		(layer "In11.Cu")
		(net "M_B_DQS_DP<17>")
	)
	(segment
		(start 237.662212 -12.332462)
		(end 237.662212 -11.68908)
		(width 0.14224)
		(layer "In11.Cu")
		(net "M_B_DQS_DP<17>")
	)
	(segment
		(start 237.639606 -26.907236)
		(end 237.639606 -15.79626)
		(width 0.14224)
		(layer "In11.Cu")
		(net "M_B_DQS_DP<17>")
	)
	(segment
		(start 237.453932 -10.1854)
		(end 237.326932 -10.1854)
		(width 0.14224)
		(layer "In11.Cu")
		(net "M_B_DQS_DP<17>")
	)
	(segment
		(start 237.131606 -14.55928)
		(end 236.641132 -14.068806)
		(width 0.14224)
		(layer "In11.Cu")
		(net "M_B_DQS_DP<17>")
	)
	(segment
		(start 237.170976 -11.286236)
		(end 237.170976 -10.947908)
		(width 0.14224)
		(layer "In11.Cu")
		(net "M_B_DQS_DP<17>")
	)
	(segment
		(start 237.174532 -9.779)
		(end 237.662212 -9.29132)
		(width 0.14224)
		(layer "In11.Cu")
		(net "M_B_DQS_DP<17>")
	)
	(segment
		(start 237.662212 -10.39368)
		(end 237.453932 -10.1854)
		(width 0.14224)
		(layer "In11.Cu")
		(net "M_B_DQS_DP<17>")
	)
	(segment
		(start 237.415832 -11.4427)
		(end 237.32744 -11.4427)
		(width 0.14224)
		(layer "In11.Cu")
		(net "M_B_DQS_DP<17>")
	)
	(segment
		(start 237.421674 -12.573)
		(end 237.662212 -12.332462)
		(width 0.14224)
		(layer "In11.Cu")
		(net "M_B_DQS_DP<17>")
	)
	(segment
		(start 237.662212 -11.68908)
		(end 237.415832 -11.4427)
		(width 0.14224)
		(layer "In11.Cu")
		(net "M_B_DQS_DP<17>")
	)
	(segment
		(start 237.662212 -8.455914)
		(end 237.481618 -8.27532)
		(width 0.14224)
		(layer "In11.Cu")
		(net "M_B_DQS_DP<17>")
	)
	(segment
		(start 237.662212 -9.29132)
		(end 237.662212 -8.455914)
		(width 0.14224)
		(layer "In11.Cu")
		(net "M_B_DQS_DP<17>")
	)
	(segment
		(start 237.149132 -27.39771)
		(end 237.639606 -26.907236)
		(width 0.14224)
		(layer "In11.Cu")
		(net "M_B_DQS_DP<17>")
	)
	(segment
		(start 237.32744 -11.4427)
		(end 237.170976 -11.286236)
		(width 0.14224)
		(layer "In11.Cu")
		(net "M_B_DQS_DP<17>")
	)
	(segment
		(start 237.131606 -15.28826)
		(end 237.131606 -14.55928)
		(width 0.14224)
		(layer "In11.Cu")
		(net "M_B_DQS_DP<17>")
	)
	(segment
		(start 237.174532 -10.033)
		(end 237.174532 -9.779)
		(width 0.14224)
		(layer "In11.Cu")
		(net "M_B_DQS_DP<17>")
	)
	(segment
		(start 237.481618 -8.27532)
		(end 237.350554 -8.27532)
		(width 0.14224)
		(layer "In11.Cu")
		(net "M_B_DQS_DP<17>")
	)
	(segment
		(start 237.170976 -10.947908)
		(end 237.298484 -10.8204)
		(width 0.14224)
		(layer "In11.Cu")
		(net "M_B_DQS_DP<17>")
	)
	(segment
		(start 237.479332 -10.8204)
		(end 237.662212 -10.63752)
		(width 0.14224)
		(layer "In11.Cu")
		(net "M_B_DQS_DP<17>")
	)
	(segment
		(start 237.350554 -8.27532)
		(end 237.142528 -8.483346)
		(width 0.14224)
		(layer "In11.Cu")
		(net "M_B_DQS_DP<17>")
	)
	(segment
		(start 236.641132 -14.068806)
		(end 236.641132 -13.074396)
		(width 0.14224)
		(layer "In11.Cu")
		(net "M_B_DQS_DP<17>")
	)
	(segment
		(start 237.326932 -10.1854)
		(end 237.174532 -10.033)
		(width 0.14224)
		(layer "In11.Cu")
		(net "M_B_DQS_DP<17>")
	)
	(segment
		(start 237.142528 -12.573)
		(end 237.421674 -12.573)
		(width 0.14224)
		(layer "In11.Cu")
		(net "M_B_DQS_DP<17>")
	)
	(segment
		(start 237.639606 -15.79626)
		(end 237.131606 -15.28826)
		(width 0.14224)
		(layer "In11.Cu")
		(net "M_B_DQS_DP<17>")
	)
	(segment
		(start 236.641132 -13.074396)
		(end 237.142528 -12.573)
		(width 0.14224)
		(layer "In11.Cu")
		(net "M_B_DQS_DP<17>")
	)
	(segment
		(start 237.662212 -10.63752)
		(end 237.662212 -10.39368)
		(width 0.14224)
		(layer "In11.Cu")
		(net "M_B_DQS_DP<17>")
	)
	(segment
		(start 311.15 -6.439154)
		(end 310.713882 -6.875272)
		(width 0.1651)
		(layer "F.Cu")
		(net "M_B_DQS_DP<16>")
	)
	(segment
		(start 310.6293 -7.877302)
		(end 310.710834 -8.101584)
		(width 0.1651)
		(layer "F.Cu")
		(net "M_B_DQS_DP<16>")
	)
	(segment
		(start 284.929834 -59.866784)
		(end 284.358334 -59.866784)
		(width 0.1016)
		(layer "F.Cu")
		(net "M_B_DQS_DP<16>")
	)
	(segment
		(start 311.150508 -5.822442)
		(end 311.15 -5.822442)
		(width 0.1651)
		(layer "F.Cu")
		(net "M_B_DQS_DP<16>")
	)
	(segment
		(start 310.6293 -7.059168)
		(end 310.6293 -7.877302)
		(width 0.1651)
		(layer "F.Cu")
		(net "M_B_DQS_DP<16>")
	)
	(segment
		(start 311.15 -5.822442)
		(end 311.15 -6.439154)
		(width 0.1651)
		(layer "F.Cu")
		(net "M_B_DQS_DP<16>")
	)
	(segment
		(start 310.710834 -8.101584)
		(end 311.092596 -8.483346)
		(width 0.1651)
		(layer "F.Cu")
		(net "M_B_DQS_DP<16>")
	)
	(segment
		(start 310.713882 -6.875272)
		(end 310.6293 -7.059168)
		(width 0.1651)
		(layer "F.Cu")
		(net "M_B_DQS_DP<16>")
	)
	(via
		(at 311.092596 -8.483346)
		(size 0.508)
		(drill 0.254)
		(layers "F.Cu" "B.Cu")
		(net "M_B_DQS_DP<16>")
	)
	(via
		(at 284.358334 -59.866784)
		(size 0.508)
		(drill 0.254)
		(layers "F.Cu" "B.Cu")
		(net "M_B_DQS_DP<16>")
	)
	(via
		(at 311.092596 -12.573)
		(size 0.508)
		(drill 0.254)
		(layers "F.Cu" "B.Cu")
		(net "M_B_DQS_DP<16>")
	)
	(segment
		(start 310.693816 -14.14907)
		(end 310.6166 -14.016736)
		(width 0.1651)
		(layer "B.Cu")
		(net "M_B_DQS_DP<16>")
	)
	(segment
		(start 311.15 -15.222982)
		(end 311.15 -14.605254)
		(width 0.1651)
		(layer "B.Cu")
		(net "M_B_DQS_DP<16>")
	)
	(segment
		(start 311.15 -14.605254)
		(end 310.693816 -14.14907)
		(width 0.1651)
		(layer "B.Cu")
		(net "M_B_DQS_DP<16>")
	)
	(segment
		(start 310.703976 -12.96162)
		(end 311.092596 -12.573)
		(width 0.1651)
		(layer "B.Cu")
		(net "M_B_DQS_DP<16>")
	)
	(segment
		(start 310.6166 -14.016736)
		(end 310.6166 -13.121132)
		(width 0.1651)
		(layer "B.Cu")
		(net "M_B_DQS_DP<16>")
	)
	(segment
		(start 310.6166 -13.121132)
		(end 310.703976 -12.96162)
		(width 0.1651)
		(layer "B.Cu")
		(net "M_B_DQS_DP<16>")
	)
	(segment
		(start 311.150508 -15.222982)
		(end 311.15 -15.222982)
		(width 0.1651)
		(layer "B.Cu")
		(net "M_B_DQS_DP<16>")
	)
	(segment
		(start 311.092596 -12.573)
		(end 311.371742 -12.573)
		(width 0.14224)
		(layer "In4.Cu")
		(net "M_B_DQS_DP<16>")
	)
	(segment
		(start 311.1246 -10.033)
		(end 311.1246 -9.779)
		(width 0.14224)
		(layer "In4.Cu")
		(net "M_B_DQS_DP<16>")
	)
	(segment
		(start 311.371742 -12.573)
		(end 311.61228 -12.332462)
		(width 0.14224)
		(layer "In4.Cu")
		(net "M_B_DQS_DP<16>")
	)
	(segment
		(start 311.3659 -11.4427)
		(end 311.277508 -11.4427)
		(width 0.14224)
		(layer "In4.Cu")
		(net "M_B_DQS_DP<16>")
	)
	(segment
		(start 307.221636 -32.616902)
		(end 307.74132 -33.136586)
		(width 0.14224)
		(layer "In4.Cu")
		(net "M_B_DQS_DP<16>")
	)
	(segment
		(start 311.277508 -11.4427)
		(end 311.121044 -11.286236)
		(width 0.14224)
		(layer "In4.Cu")
		(net "M_B_DQS_DP<16>")
	)
	(segment
		(start 288.380932 -50.566828)
		(end 288.39668 -50.55108)
		(width 0.0889)
		(layer "In4.Cu")
		(net "M_B_DQS_DP<16>")
	)
	(segment
		(start 287.2105 -51.79314)
		(end 288.380932 -50.622708)
		(width 0.0889)
		(layer "In4.Cu")
		(net "M_B_DQS_DP<16>")
	)
	(segment
		(start 311.248552 -10.8204)
		(end 311.4294 -10.8204)
		(width 0.14224)
		(layer "In4.Cu")
		(net "M_B_DQS_DP<16>")
	)
	(segment
		(start 285.55696 -54.629304)
		(end 285.56331 -54.618636)
		(width 0.0889)
		(layer "In4.Cu")
		(net "M_B_DQS_DP<16>")
	)
	(segment
		(start 311.4294 -10.8204)
		(end 311.61228 -10.63752)
		(width 0.14224)
		(layer "In4.Cu")
		(net "M_B_DQS_DP<16>")
	)
	(segment
		(start 306.055014 -33.227264)
		(end 306.665376 -32.616902)
		(width 0.14224)
		(layer "In4.Cu")
		(net "M_B_DQS_DP<16>")
	)
	(segment
		(start 311.121044 -10.947908)
		(end 311.248552 -10.8204)
		(width 0.14224)
		(layer "In4.Cu")
		(net "M_B_DQS_DP<16>")
	)
	(segment
		(start 308.053486 -33.136586)
		(end 308.502558 -32.687514)
		(width 0.14224)
		(layer "In4.Cu")
		(net "M_B_DQS_DP<16>")
	)
	(segment
		(start 306.665376 -32.616902)
		(end 307.221636 -32.616902)
		(width 0.14224)
		(layer "In4.Cu")
		(net "M_B_DQS_DP<16>")
	)
	(segment
		(start 311.1246 -9.779)
		(end 311.61228 -9.29132)
		(width 0.14224)
		(layer "In4.Cu")
		(net "M_B_DQS_DP<16>")
	)
	(segment
		(start 310.62168 -13.043916)
		(end 311.092596 -12.573)
		(width 0.14224)
		(layer "In4.Cu")
		(net "M_B_DQS_DP<16>")
	)
	(segment
		(start 284.017974 -59.087004)
		(end 284.011624 -59.076336)
		(width 0.0889)
		(layer "In4.Cu")
		(net "M_B_DQS_DP<16>")
	)
	(segment
		(start 286.42183 -52.142136)
		(end 286.539686 -51.93792)
		(width 0.0889)
		(layer "In4.Cu")
		(net "M_B_DQS_DP<16>")
	)
	(segment
		(start 286.539686 -51.93792)
		(end 286.684466 -51.79314)
		(width 0.0889)
		(layer "In4.Cu")
		(net "M_B_DQS_DP<16>")
	)
	(segment
		(start 285.191708 -57.790588)
		(end 285.227776 -57.790588)
		(width 0.0889)
		(layer "In4.Cu")
		(net "M_B_DQS_DP<16>")
	)
	(segment
		(start 311.61228 -11.68908)
		(end 311.3659 -11.4427)
		(width 0.14224)
		(layer "In4.Cu")
		(net "M_B_DQS_DP<16>")
	)
	(segment
		(start 286.684466 -51.79314)
		(end 287.2105 -51.79314)
		(width 0.0889)
		(layer "In4.Cu")
		(net "M_B_DQS_DP<16>")
	)
	(segment
		(start 311.61228 -12.332462)
		(end 311.61228 -11.68908)
		(width 0.14224)
		(layer "In4.Cu")
		(net "M_B_DQS_DP<16>")
	)
	(segment
		(start 311.277 -10.1854)
		(end 311.1246 -10.033)
		(width 0.14224)
		(layer "In4.Cu")
		(net "M_B_DQS_DP<16>")
	)
	(segment
		(start 284.358334 -59.866784)
		(end 284.22473 -59.467496)
		(width 0.0889)
		(layer "In4.Cu")
		(net "M_B_DQS_DP<16>")
	)
	(segment
		(start 307.74132 -33.136586)
		(end 308.053486 -33.136586)
		(width 0.14224)
		(layer "In4.Cu")
		(net "M_B_DQS_DP<16>")
	)
	(segment
		(start 311.431686 -8.27532)
		(end 311.300622 -8.27532)
		(width 0.14224)
		(layer "In4.Cu")
		(net "M_B_DQS_DP<16>")
	)
	(segment
		(start 311.404 -10.1854)
		(end 311.277 -10.1854)
		(width 0.14224)
		(layer "In4.Cu")
		(net "M_B_DQS_DP<16>")
	)
	(segment
		(start 285.56331 -56.599836)
		(end 285.568136 -56.5912)
		(width 0.0889)
		(layer "In4.Cu")
		(net "M_B_DQS_DP<16>")
	)
	(segment
		(start 288.39668 -50.55108)
		(end 292.77056 -46.1772)
		(width 0.14224)
		(layer "In4.Cu")
		(net "M_B_DQS_DP<16>")
	)
	(segment
		(start 285.56331 -54.618636)
		(end 285.568136 -54.61)
		(width 0.0889)
		(layer "In4.Cu")
		(net "M_B_DQS_DP<16>")
	)
	(segment
		(start 288.380932 -50.622708)
		(end 288.380932 -50.566828)
		(width 0.0889)
		(layer "In4.Cu")
		(net "M_B_DQS_DP<16>")
	)
	(segment
		(start 308.025038 -31.36138)
		(end 311.605676 -27.780742)
		(width 0.14224)
		(layer "In4.Cu")
		(net "M_B_DQS_DP<16>")
	)
	(segment
		(start 285.55696 -53.638704)
		(end 285.56331 -53.628036)
		(width 0.0889)
		(layer "In4.Cu")
		(net "M_B_DQS_DP<16>")
	)
	(segment
		(start 311.61228 -10.39368)
		(end 311.404 -10.1854)
		(width 0.14224)
		(layer "In4.Cu")
		(net "M_B_DQS_DP<16>")
	)
	(segment
		(start 306.667408 -34.66211)
		(end 306.667408 -34.349436)
		(width 0.14224)
		(layer "In4.Cu")
		(net "M_B_DQS_DP<16>")
	)
	(segment
		(start 308.025038 -31.897828)
		(end 308.025038 -31.36138)
		(width 0.14224)
		(layer "In4.Cu")
		(net "M_B_DQS_DP<16>")
	)
	(segment
		(start 308.502558 -32.375348)
		(end 308.025038 -31.897828)
		(width 0.14224)
		(layer "In4.Cu")
		(net "M_B_DQS_DP<16>")
	)
	(segment
		(start 311.300622 -8.27532)
		(end 311.092596 -8.483346)
		(width 0.14224)
		(layer "In4.Cu")
		(net "M_B_DQS_DP<16>")
	)
	(segment
		(start 311.121044 -11.286236)
		(end 311.121044 -10.947908)
		(width 0.14224)
		(layer "In4.Cu")
		(net "M_B_DQS_DP<16>")
	)
	(segment
		(start 311.605676 -16.14551)
		(end 310.62168 -15.161514)
		(width 0.14224)
		(layer "In4.Cu")
		(net "M_B_DQS_DP<16>")
	)
	(segment
		(start 286.05734 -52.342034)
		(end 286.090106 -52.342034)
		(width 0.0889)
		(layer "In4.Cu")
		(net "M_B_DQS_DP<16>")
	)
	(segment
		(start 292.77056 -46.1772)
		(end 295.152318 -46.1772)
		(width 0.14224)
		(layer "In4.Cu")
		(net "M_B_DQS_DP<16>")
	)
	(segment
		(start 284.011624 -59.076336)
		(end 283.99486 -59.046872)
		(width 0.0889)
		(layer "In4.Cu")
		(net "M_B_DQS_DP<16>")
	)
	(segment
		(start 311.61228 -10.63752)
		(end 311.61228 -10.39368)
		(width 0.14224)
		(layer "In4.Cu")
		(net "M_B_DQS_DP<16>")
	)
	(segment
		(start 311.61228 -8.455914)
		(end 311.431686 -8.27532)
		(width 0.14224)
		(layer "In4.Cu")
		(net "M_B_DQS_DP<16>")
	)
	(segment
		(start 284.22473 -59.467496)
		(end 284.017974 -59.087004)
		(width 0.0889)
		(layer "In4.Cu")
		(net "M_B_DQS_DP<16>")
	)
	(segment
		(start 285.56331 -53.628036)
		(end 285.568136 -53.6194)
		(width 0.0889)
		(layer "In4.Cu")
		(net "M_B_DQS_DP<16>")
	)
	(segment
		(start 310.62168 -15.161514)
		(end 310.62168 -13.043916)
		(width 0.14224)
		(layer "In4.Cu")
		(net "M_B_DQS_DP<16>")
	)
	(segment
		(start 311.605676 -27.780742)
		(end 311.605676 -16.14551)
		(width 0.14224)
		(layer "In4.Cu")
		(net "M_B_DQS_DP<16>")
	)
	(segment
		(start 308.502558 -32.687514)
		(end 308.502558 -32.375348)
		(width 0.14224)
		(layer "In4.Cu")
		(net "M_B_DQS_DP<16>")
	)
	(segment
		(start 306.055014 -33.737042)
		(end 306.055014 -33.227264)
		(width 0.14224)
		(layer "In4.Cu")
		(net "M_B_DQS_DP<16>")
	)
	(segment
		(start 285.56331 -55.609236)
		(end 285.568136 -55.6006)
		(width 0.0889)
		(layer "In4.Cu")
		(net "M_B_DQS_DP<16>")
	)
	(segment
		(start 285.55696 -55.619904)
		(end 285.56331 -55.609236)
		(width 0.0889)
		(layer "In4.Cu")
		(net "M_B_DQS_DP<16>")
	)
	(segment
		(start 295.152318 -46.1772)
		(end 306.667408 -34.66211)
		(width 0.14224)
		(layer "In4.Cu")
		(net "M_B_DQS_DP<16>")
	)
	(segment
		(start 284.701488 -58.091324)
		(end 284.70479 -58.085482)
		(width 0.0889)
		(layer "In4.Cu")
		(net "M_B_DQS_DP<16>")
	)
	(segment
		(start 285.55696 -56.610504)
		(end 285.56331 -56.599836)
		(width 0.0889)
		(layer "In4.Cu")
		(net "M_B_DQS_DP<16>")
	)
	(segment
		(start 311.61228 -9.29132)
		(end 311.61228 -8.455914)
		(width 0.14224)
		(layer "In4.Cu")
		(net "M_B_DQS_DP<16>")
	)
	(segment
		(start 306.667408 -34.349436)
		(end 306.055014 -33.737042)
		(width 0.14224)
		(layer "In4.Cu")
		(net "M_B_DQS_DP<16>")
	)
	(arc
		(start 284.358334 -58.285634)
		(mid 284.555495 -58.233675)
		(end 284.701488 -58.091324)
		(width 0.0889)
		(layer "In4.Cu")
		(net "M_B_DQS_DP<16>")
	)
	(arc
		(start 285.56331 -55.209186)
		(mid 285.484088 -54.920068)
		(end 285.55696 -54.629304)
		(width 0.0889)
		(layer "In4.Cu")
		(net "M_B_DQS_DP<16>")
	)
	(arc
		(start 285.56331 -56.199786)
		(mid 285.484088 -55.910668)
		(end 285.55696 -55.619904)
		(width 0.0889)
		(layer "In4.Cu")
		(net "M_B_DQS_DP<16>")
	)
	(arc
		(start 286.090106 -52.342034)
		(mid 286.281748 -52.284868)
		(end 286.42183 -52.142136)
		(width 0.0889)
		(layer "In4.Cu")
		(net "M_B_DQS_DP<16>")
	)
	(arc
		(start 285.568136 -54.61)
		(mid 285.616891 -54.413648)
		(end 285.56331 -54.218586)
		(width 0.0889)
		(layer "In4.Cu")
		(net "M_B_DQS_DP<16>")
	)
	(arc
		(start 284.70479 -58.085482)
		(mid 284.910411 -57.875559)
		(end 285.191708 -57.790588)
		(width 0.0889)
		(layer "In4.Cu")
		(net "M_B_DQS_DP<16>")
	)
	(arc
		(start 285.56331 -53.227986)
		(mid 285.558981 -52.644814)
		(end 286.05734 -52.342034)
		(width 0.0889)
		(layer "In4.Cu")
		(net "M_B_DQS_DP<16>")
	)
	(arc
		(start 283.924756 -58.8899)
		(mid 283.987076 -58.476908)
		(end 284.358334 -58.285634)
		(width 0.0889)
		(layer "In4.Cu")
		(net "M_B_DQS_DP<16>")
	)
	(arc
		(start 283.99486 -59.046872)
		(mid 283.955986 -58.970093)
		(end 283.924756 -58.8899)
		(width 0.0889)
		(layer "In4.Cu")
		(net "M_B_DQS_DP<16>")
	)
	(arc
		(start 285.56331 -57.190386)
		(mid 285.484088 -56.901268)
		(end 285.55696 -56.610504)
		(width 0.0889)
		(layer "In4.Cu")
		(net "M_B_DQS_DP<16>")
	)
	(arc
		(start 285.227776 -57.790588)
		(mid 285.565945 -57.58579)
		(end 285.56331 -57.190386)
		(width 0.0889)
		(layer "In4.Cu")
		(net "M_B_DQS_DP<16>")
	)
	(arc
		(start 285.56331 -54.218586)
		(mid 285.484088 -53.929468)
		(end 285.55696 -53.638704)
		(width 0.0889)
		(layer "In4.Cu")
		(net "M_B_DQS_DP<16>")
	)
	(arc
		(start 285.568136 -53.6194)
		(mid 285.616891 -53.423048)
		(end 285.56331 -53.227986)
		(width 0.0889)
		(layer "In4.Cu")
		(net "M_B_DQS_DP<16>")
	)
	(arc
		(start 285.568136 -55.6006)
		(mid 285.616891 -55.404248)
		(end 285.56331 -55.209186)
		(width 0.0889)
		(layer "In4.Cu")
		(net "M_B_DQS_DP<16>")
	)
	(arc
		(start 285.568136 -56.5912)
		(mid 285.616891 -56.394848)
		(end 285.56331 -56.199786)
		(width 0.0889)
		(layer "In4.Cu")
		(net "M_B_DQS_DP<16>")
	)
	(segment
		(start 301.528226 -34.417)
		(end 301.528226 -33.777174)
		(width 0.1651)
		(layer "F.Cu")
		(net "M_B_DQS_DP<15>")
	)
	(segment
		(start 301.800514 -5.822442)
		(end 301.800006 -5.822442)
		(width 0.1651)
		(layer "F.Cu")
		(net "M_B_DQS_DP<15>")
	)
	(segment
		(start 294.31488 -45.975524)
		(end 297.387772 -42.902632)
		(width 0.1016)
		(layer "F.Cu")
		(net "M_B_DQS_DP<15>")
	)
	(segment
		(start 288.244026 -45.975524)
		(end 294.31488 -45.975524)
		(width 0.1016)
		(layer "F.Cu")
		(net "M_B_DQS_DP<15>")
	)
	(segment
		(start 301.07382 -31.74365)
		(end 301.42307 -31.3944)
		(width 0.1651)
		(layer "F.Cu")
		(net "M_B_DQS_DP<15>")
	)
	(segment
		(start 283.625544 -49.963578)
		(end 284.5562 -49.032922)
		(width 0.0889)
		(layer "F.Cu")
		(net "M_B_DQS_DP<15>")
	)
	(segment
		(start 301.07382 -32.42945)
		(end 301.07382 -31.74365)
		(width 0.1651)
		(layer "F.Cu")
		(net "M_B_DQS_DP<15>")
	)
	(segment
		(start 301.42307 -32.7787)
		(end 301.07382 -32.42945)
		(width 0.1651)
		(layer "F.Cu")
		(net "M_B_DQS_DP<15>")
	)
	(segment
		(start 301.244 -29.126942)
		(end 301.244 -27.902916)
		(width 0.1651)
		(layer "F.Cu")
		(net "M_B_DQS_DP<15>")
	)
	(segment
		(start 302.1203 -32.957008)
		(end 301.941992 -32.7787)
		(width 0.1651)
		(layer "F.Cu")
		(net "M_B_DQS_DP<15>")
	)
	(segment
		(start 283.5402 -51.116484)
		(end 283.625544 -50.969418)
		(width 0.0889)
		(layer "F.Cu")
		(net "M_B_DQS_DP<15>")
	)
	(segment
		(start 302.1457 -30.83433)
		(end 301.967392 -30.656022)
		(width 0.1651)
		(layer "F.Cu")
		(net "M_B_DQS_DP<15>")
	)
	(segment
		(start 302.1203 -35.433)
		(end 301.528226 -34.840926)
		(width 0.1651)
		(layer "F.Cu")
		(net "M_B_DQS_DP<15>")
	)
	(segment
		(start 284.5562 -48.899318)
		(end 287.479994 -45.975524)
		(width 0.1016)
		(layer "F.Cu")
		(net "M_B_DQS_DP<15>")
	)
	(segment
		(start 301.528226 -33.777174)
		(end 302.1203 -33.1851)
		(width 0.1651)
		(layer "F.Cu")
		(net "M_B_DQS_DP<15>")
	)
	(segment
		(start 301.528226 -34.840926)
		(end 301.528226 -34.417)
		(width 0.1651)
		(layer "F.Cu")
		(net "M_B_DQS_DP<15>")
	)
	(segment
		(start 301.363888 -6.875272)
		(end 301.279306 -7.059168)
		(width 0.1651)
		(layer "F.Cu")
		(net "M_B_DQS_DP<15>")
	)
	(segment
		(start 297.387772 -41.892728)
		(end 297.3959 -41.8846)
		(width 0.1016)
		(layer "F.Cu")
		(net "M_B_DQS_DP<15>")
	)
	(segment
		(start 301.279306 -7.877302)
		(end 301.36084 -8.101584)
		(width 0.1651)
		(layer "F.Cu")
		(net "M_B_DQS_DP<15>")
	)
	(segment
		(start 297.3959 -41.0083)
		(end 302.1203 -36.2839)
		(width 0.1651)
		(layer "F.Cu")
		(net "M_B_DQS_DP<15>")
	)
	(segment
		(start 297.3959 -41.8846)
		(end 297.3959 -41.0083)
		(width 0.1651)
		(layer "F.Cu")
		(net "M_B_DQS_DP<15>")
	)
	(segment
		(start 301.941992 -32.7787)
		(end 301.42307 -32.7787)
		(width 0.1651)
		(layer "F.Cu")
		(net "M_B_DQS_DP<15>")
	)
	(segment
		(start 302.1203 -36.2839)
		(end 302.1203 -35.433)
		(width 0.1651)
		(layer "F.Cu")
		(net "M_B_DQS_DP<15>")
	)
	(segment
		(start 302.1203 -33.1851)
		(end 302.1203 -32.957008)
		(width 0.1651)
		(layer "F.Cu")
		(net "M_B_DQS_DP<15>")
	)
	(segment
		(start 301.42307 -31.3944)
		(end 301.967392 -31.3944)
		(width 0.1651)
		(layer "F.Cu")
		(net "M_B_DQS_DP<15>")
	)
	(segment
		(start 301.07382 -29.297122)
		(end 301.244 -29.126942)
		(width 0.1651)
		(layer "F.Cu")
		(net "M_B_DQS_DP<15>")
	)
	(segment
		(start 284.5562 -49.032922)
		(end 284.5562 -48.899318)
		(width 0.0889)
		(layer "F.Cu")
		(net "M_B_DQS_DP<15>")
	)
	(segment
		(start 287.479994 -45.975524)
		(end 288.244026 -45.975524)
		(width 0.1016)
		(layer "F.Cu")
		(net "M_B_DQS_DP<15>")
	)
	(segment
		(start 297.387772 -42.902632)
		(end 297.387772 -41.892728)
		(width 0.1016)
		(layer "F.Cu")
		(net "M_B_DQS_DP<15>")
	)
	(segment
		(start 301.244 -27.902916)
		(end 301.749206 -27.39771)
		(width 0.1651)
		(layer "F.Cu")
		(net "M_B_DQS_DP<15>")
	)
	(segment
		(start 301.967392 -30.656022)
		(end 301.371762 -30.656022)
		(width 0.1651)
		(layer "F.Cu")
		(net "M_B_DQS_DP<15>")
	)
	(segment
		(start 301.800006 -6.439154)
		(end 301.363888 -6.875272)
		(width 0.1651)
		(layer "F.Cu")
		(net "M_B_DQS_DP<15>")
	)
	(segment
		(start 283.660088 -51.871372)
		(end 283.643324 -51.855116)
		(width 0.0889)
		(layer "F.Cu")
		(net "M_B_DQS_DP<15>")
	)
	(segment
		(start 301.07382 -30.35808)
		(end 301.07382 -29.297122)
		(width 0.1651)
		(layer "F.Cu")
		(net "M_B_DQS_DP<15>")
	)
	(segment
		(start 301.36084 -8.101584)
		(end 301.742602 -8.483346)
		(width 0.1651)
		(layer "F.Cu")
		(net "M_B_DQS_DP<15>")
	)
	(segment
		(start 283.625544 -50.969418)
		(end 283.625544 -49.963578)
		(width 0.0889)
		(layer "F.Cu")
		(net "M_B_DQS_DP<15>")
	)
	(segment
		(start 302.1457 -31.216092)
		(end 302.1457 -30.83433)
		(width 0.1651)
		(layer "F.Cu")
		(net "M_B_DQS_DP<15>")
	)
	(segment
		(start 301.279306 -7.059168)
		(end 301.279306 -7.877302)
		(width 0.1651)
		(layer "F.Cu")
		(net "M_B_DQS_DP<15>")
	)
	(segment
		(start 301.967392 -31.3944)
		(end 302.1457 -31.216092)
		(width 0.1651)
		(layer "F.Cu")
		(net "M_B_DQS_DP<15>")
	)
	(segment
		(start 301.800006 -5.822442)
		(end 301.800006 -6.439154)
		(width 0.1651)
		(layer "F.Cu")
		(net "M_B_DQS_DP<15>")
	)
	(segment
		(start 301.371762 -30.656022)
		(end 301.07382 -30.35808)
		(width 0.1651)
		(layer "F.Cu")
		(net "M_B_DQS_DP<15>")
	)
	(via
		(at 301.742602 -8.483346)
		(size 0.508)
		(drill 0.254)
		(layers "F.Cu" "B.Cu")
		(net "M_B_DQS_DP<15>")
	)
	(via
		(at 301.528226 -34.417)
		(size 0.508)
		(drill 0.254)
		(layers "F.Cu" "B.Cu")
		(net "M_B_DQS_DP<15>")
	)
	(via
		(at 301.749206 -27.39771)
		(size 0.508)
		(drill 0.254)
		(layers "F.Cu" "B.Cu")
		(net "M_B_DQS_DP<15>")
	)
	(via
		(at 301.742602 -12.573)
		(size 0.508)
		(drill 0.254)
		(layers "F.Cu" "B.Cu")
		(net "M_B_DQS_DP<15>")
	)
	(arc
		(start 284.071314 -52.437538)
		(mid 283.887999 -52.138259)
		(end 283.660088 -51.871372)
		(width 0.0889)
		(layer "F.Cu")
		(net "M_B_DQS_DP<15>")
	)
	(arc
		(start 283.643324 -51.855116)
		(mid 283.464793 -51.50354)
		(end 283.5402 -51.116484)
		(width 0.0889)
		(layer "F.Cu")
		(net "M_B_DQS_DP<15>")
	)
	(segment
		(start 301.800006 -14.605254)
		(end 301.343822 -14.14907)
		(width 0.1651)
		(layer "B.Cu")
		(net "M_B_DQS_DP<15>")
	)
	(segment
		(start 301.266606 -14.016736)
		(end 301.266606 -13.121132)
		(width 0.1651)
		(layer "B.Cu")
		(net "M_B_DQS_DP<15>")
	)
	(segment
		(start 301.353982 -12.96162)
		(end 301.742602 -12.573)
		(width 0.1651)
		(layer "B.Cu")
		(net "M_B_DQS_DP<15>")
	)
	(segment
		(start 301.800006 -15.222982)
		(end 301.800006 -14.605254)
		(width 0.1651)
		(layer "B.Cu")
		(net "M_B_DQS_DP<15>")
	)
	(segment
		(start 301.266606 -13.121132)
		(end 301.353982 -12.96162)
		(width 0.1651)
		(layer "B.Cu")
		(net "M_B_DQS_DP<15>")
	)
	(segment
		(start 301.343822 -14.14907)
		(end 301.266606 -14.016736)
		(width 0.1651)
		(layer "B.Cu")
		(net "M_B_DQS_DP<15>")
	)
	(segment
		(start 301.800514 -15.222982)
		(end 301.800006 -15.222982)
		(width 0.1651)
		(layer "B.Cu")
		(net "M_B_DQS_DP<15>")
	)
	(segment
		(start 302.23968 -26.907236)
		(end 301.749206 -27.39771)
		(width 0.14224)
		(layer "In4.Cu")
		(net "M_B_DQS_DP<15>")
	)
	(segment
		(start 301.241206 -14.068806)
		(end 301.73168 -14.55928)
		(width 0.14224)
		(layer "In4.Cu")
		(net "M_B_DQS_DP<15>")
	)
	(segment
		(start 301.77105 -10.947908)
		(end 301.77105 -11.286236)
		(width 0.14224)
		(layer "In4.Cu")
		(net "M_B_DQS_DP<15>")
	)
	(segment
		(start 302.262286 -10.63752)
		(end 302.079406 -10.8204)
		(width 0.14224)
		(layer "In4.Cu")
		(net "M_B_DQS_DP<15>")
	)
	(segment
		(start 302.079406 -10.8204)
		(end 301.898558 -10.8204)
		(width 0.14224)
		(layer "In4.Cu")
		(net "M_B_DQS_DP<15>")
	)
	(segment
		(start 302.081692 -8.27532)
		(end 302.262286 -8.455914)
		(width 0.14224)
		(layer "In4.Cu")
		(net "M_B_DQS_DP<15>")
	)
	(segment
		(start 301.73168 -14.55928)
		(end 301.73168 -15.28826)
		(width 0.14224)
		(layer "In4.Cu")
		(net "M_B_DQS_DP<15>")
	)
	(segment
		(start 301.774606 -10.033)
		(end 301.927006 -10.1854)
		(width 0.14224)
		(layer "In4.Cu")
		(net "M_B_DQS_DP<15>")
	)
	(segment
		(start 302.015906 -11.4427)
		(end 302.262286 -11.68908)
		(width 0.14224)
		(layer "In4.Cu")
		(net "M_B_DQS_DP<15>")
	)
	(segment
		(start 301.774606 -9.779)
		(end 301.774606 -10.033)
		(width 0.14224)
		(layer "In4.Cu")
		(net "M_B_DQS_DP<15>")
	)
	(segment
		(start 302.262286 -12.332462)
		(end 302.021748 -12.573)
		(width 0.14224)
		(layer "In4.Cu")
		(net "M_B_DQS_DP<15>")
	)
	(segment
		(start 302.262286 -8.455914)
		(end 302.262286 -9.29132)
		(width 0.14224)
		(layer "In4.Cu")
		(net "M_B_DQS_DP<15>")
	)
	(segment
		(start 301.950628 -8.27532)
		(end 302.081692 -8.27532)
		(width 0.14224)
		(layer "In4.Cu")
		(net "M_B_DQS_DP<15>")
	)
	(segment
		(start 302.262286 -11.68908)
		(end 302.262286 -12.332462)
		(width 0.14224)
		(layer "In4.Cu")
		(net "M_B_DQS_DP<15>")
	)
	(segment
		(start 302.262286 -9.29132)
		(end 301.774606 -9.779)
		(width 0.14224)
		(layer "In4.Cu")
		(net "M_B_DQS_DP<15>")
	)
	(segment
		(start 302.262286 -10.39368)
		(end 302.262286 -10.63752)
		(width 0.14224)
		(layer "In4.Cu")
		(net "M_B_DQS_DP<15>")
	)
	(segment
		(start 301.898558 -10.8204)
		(end 301.77105 -10.947908)
		(width 0.14224)
		(layer "In4.Cu")
		(net "M_B_DQS_DP<15>")
	)
	(segment
		(start 301.742602 -12.573)
		(end 301.241206 -13.074396)
		(width 0.14224)
		(layer "In4.Cu")
		(net "M_B_DQS_DP<15>")
	)
	(segment
		(start 302.23968 -15.79626)
		(end 302.23968 -26.907236)
		(width 0.14224)
		(layer "In4.Cu")
		(net "M_B_DQS_DP<15>")
	)
	(segment
		(start 301.927514 -11.4427)
		(end 302.015906 -11.4427)
		(width 0.14224)
		(layer "In4.Cu")
		(net "M_B_DQS_DP<15>")
	)
	(segment
		(start 301.742602 -8.483346)
		(end 301.950628 -8.27532)
		(width 0.14224)
		(layer "In4.Cu")
		(net "M_B_DQS_DP<15>")
	)
	(segment
		(start 301.73168 -15.28826)
		(end 302.23968 -15.79626)
		(width 0.14224)
		(layer "In4.Cu")
		(net "M_B_DQS_DP<15>")
	)
	(segment
		(start 301.241206 -13.074396)
		(end 301.241206 -14.068806)
		(width 0.14224)
		(layer "In4.Cu")
		(net "M_B_DQS_DP<15>")
	)
	(segment
		(start 301.927006 -10.1854)
		(end 302.054006 -10.1854)
		(width 0.14224)
		(layer "In4.Cu")
		(net "M_B_DQS_DP<15>")
	)
	(segment
		(start 301.77105 -11.286236)
		(end 301.927514 -11.4427)
		(width 0.14224)
		(layer "In4.Cu")
		(net "M_B_DQS_DP<15>")
	)
	(segment
		(start 302.021748 -12.573)
		(end 301.742602 -12.573)
		(width 0.14224)
		(layer "In4.Cu")
		(net "M_B_DQS_DP<15>")
	)
	(segment
		(start 302.054006 -10.1854)
		(end 302.262286 -10.39368)
		(width 0.14224)
		(layer "In4.Cu")
		(net "M_B_DQS_DP<15>")
	)
	(segment
		(start 292.010846 -8.101584)
		(end 291.929312 -7.877302)
		(width 0.1651)
		(layer "F.Cu")
		(net "M_B_DQS_DP<14>")
	)
	(segment
		(start 282.908248 -42.859198)
		(end 278.410924 -47.356522)
		(width 0.1016)
		(layer "F.Cu")
		(net "M_B_DQS_DP<14>")
	)
	(segment
		(start 292.2778 -31.6357)
		(end 292.1508 -31.7627)
		(width 0.1651)
		(layer "F.Cu")
		(net "M_B_DQS_DP<14>")
	)
	(segment
		(start 291.929312 -7.059168)
		(end 292.013894 -6.875272)
		(width 0.1651)
		(layer "F.Cu")
		(net "M_B_DQS_DP<14>")
	)
	(segment
		(start 288.795968 -34.459672)
		(end 289.077908 -34.741612)
		(width 0.1651)
		(layer "F.Cu")
		(net "M_B_DQS_DP<14>")
	)
	(segment
		(start 291.941758 -29.838904)
		(end 292.2778 -30.174946)
		(width 0.1651)
		(layer "F.Cu")
		(net "M_B_DQS_DP<14>")
	)
	(segment
		(start 291.929312 -7.877302)
		(end 291.929312 -7.059168)
		(width 0.1651)
		(layer "F.Cu")
		(net "M_B_DQS_DP<14>")
	)
	(segment
		(start 289.26409 -33.56991)
		(end 288.795968 -34.038032)
		(width 0.1651)
		(layer "F.Cu")
		(net "M_B_DQS_DP<14>")
	)
	(segment
		(start 290.6268 -32.901636)
		(end 290.772342 -33.047178)
		(width 0.1651)
		(layer "F.Cu")
		(net "M_B_DQS_DP<14>")
	)
	(segment
		(start 292.399212 -27.39771)
		(end 291.941758 -27.855164)
		(width 0.1651)
		(layer "F.Cu")
		(net "M_B_DQS_DP<14>")
	)
	(segment
		(start 290.772342 -33.280858)
		(end 290.20135 -33.85185)
		(width 0.1651)
		(layer "F.Cu")
		(net "M_B_DQS_DP<14>")
	)
	(segment
		(start 290.772342 -33.047178)
		(end 290.772342 -33.280858)
		(width 0.1651)
		(layer "F.Cu")
		(net "M_B_DQS_DP<14>")
	)
	(segment
		(start 282.959048 -41.195752)
		(end 282.908248 -41.246552)
		(width 0.1016)
		(layer "F.Cu")
		(net "M_B_DQS_DP<14>")
	)
	(segment
		(start 289.077908 -34.741612)
		(end 289.077908 -34.975292)
		(width 0.1651)
		(layer "F.Cu")
		(net "M_B_DQS_DP<14>")
	)
	(segment
		(start 278.920194 -52.10556)
		(end 278.920194 -52.437538)
		(width 0.0889)
		(layer "F.Cu")
		(net "M_B_DQS_DP<14>")
	)
	(segment
		(start 289.077908 -34.975292)
		(end 287.0962 -36.957)
		(width 0.1651)
		(layer "F.Cu")
		(net "M_B_DQS_DP<14>")
	)
	(segment
		(start 292.1508 -31.7627)
		(end 291.191188 -31.7627)
		(width 0.1651)
		(layer "F.Cu")
		(net "M_B_DQS_DP<14>")
	)
	(segment
		(start 282.908248 -41.246552)
		(end 282.908248 -42.859198)
		(width 0.1016)
		(layer "F.Cu")
		(net "M_B_DQS_DP<14>")
	)
	(segment
		(start 292.013894 -6.875272)
		(end 292.450012 -6.439154)
		(width 0.1651)
		(layer "F.Cu")
		(net "M_B_DQS_DP<14>")
	)
	(segment
		(start 292.2778 -30.174946)
		(end 292.2778 -31.6357)
		(width 0.1651)
		(layer "F.Cu")
		(net "M_B_DQS_DP<14>")
	)
	(segment
		(start 292.010846 -8.101838)
		(end 292.010846 -8.101584)
		(width 0.1651)
		(layer "F.Cu")
		(net "M_B_DQS_DP<14>")
	)
	(segment
		(start 292.450012 -6.439154)
		(end 292.450012 -5.822442)
		(width 0.1651)
		(layer "F.Cu")
		(net "M_B_DQS_DP<14>")
	)
	(segment
		(start 278.511 -50.900584)
		(end 278.346154 -51.06543)
		(width 0.0889)
		(layer "F.Cu")
		(net "M_B_DQS_DP<14>")
	)
	(segment
		(start 289.68573 -33.56991)
		(end 289.26409 -33.56991)
		(width 0.1651)
		(layer "F.Cu")
		(net "M_B_DQS_DP<14>")
	)
	(segment
		(start 278.346154 -51.06543)
		(end 278.346154 -51.466242)
		(width 0.0889)
		(layer "F.Cu")
		(net "M_B_DQS_DP<14>")
	)
	(segment
		(start 278.410924 -47.356522)
		(end 278.410924 -49.60747)
		(width 0.1016)
		(layer "F.Cu")
		(net "M_B_DQS_DP<14>")
	)
	(segment
		(start 278.511 -49.707546)
		(end 278.511 -50.900584)
		(width 0.0889)
		(layer "F.Cu")
		(net "M_B_DQS_DP<14>")
	)
	(segment
		(start 290.6268 -32.327088)
		(end 290.6268 -32.901636)
		(width 0.1651)
		(layer "F.Cu")
		(net "M_B_DQS_DP<14>")
	)
	(segment
		(start 282.959048 -41.0464)
		(end 282.959048 -41.195752)
		(width 0.1016)
		(layer "F.Cu")
		(net "M_B_DQS_DP<14>")
	)
	(segment
		(start 290.20135 -33.85185)
		(end 289.96767 -33.85185)
		(width 0.1651)
		(layer "F.Cu")
		(net "M_B_DQS_DP<14>")
	)
	(segment
		(start 292.450012 -5.822442)
		(end 292.45052 -5.822442)
		(width 0.1651)
		(layer "F.Cu")
		(net "M_B_DQS_DP<14>")
	)
	(segment
		(start 278.826976 -52.029868)
		(end 278.920194 -52.10556)
		(width 0.0889)
		(layer "F.Cu")
		(net "M_B_DQS_DP<14>")
	)
	(segment
		(start 286.105346 -36.957)
		(end 282.959048 -40.103298)
		(width 0.1651)
		(layer "F.Cu")
		(net "M_B_DQS_DP<14>")
	)
	(segment
		(start 289.96767 -33.85185)
		(end 289.68573 -33.56991)
		(width 0.1651)
		(layer "F.Cu")
		(net "M_B_DQS_DP<14>")
	)
	(segment
		(start 282.959048 -40.103298)
		(end 282.959048 -41.0464)
		(width 0.1651)
		(layer "F.Cu")
		(net "M_B_DQS_DP<14>")
	)
	(segment
		(start 291.191188 -31.7627)
		(end 290.6268 -32.327088)
		(width 0.1651)
		(layer "F.Cu")
		(net "M_B_DQS_DP<14>")
	)
	(segment
		(start 291.941758 -27.855164)
		(end 291.941758 -29.838904)
		(width 0.1651)
		(layer "F.Cu")
		(net "M_B_DQS_DP<14>")
	)
	(segment
		(start 278.410924 -49.60747)
		(end 278.511 -49.707546)
		(width 0.0889)
		(layer "F.Cu")
		(net "M_B_DQS_DP<14>")
	)
	(segment
		(start 288.795968 -34.038032)
		(end 288.795968 -34.459672)
		(width 0.1651)
		(layer "F.Cu")
		(net "M_B_DQS_DP<14>")
	)
	(segment
		(start 287.0962 -36.957)
		(end 286.105346 -36.957)
		(width 0.1651)
		(layer "F.Cu")
		(net "M_B_DQS_DP<14>")
	)
	(segment
		(start 292.392354 -8.483346)
		(end 292.010846 -8.101838)
		(width 0.1651)
		(layer "F.Cu")
		(net "M_B_DQS_DP<14>")
	)
	(via
		(at 292.399212 -27.39771)
		(size 0.508)
		(drill 0.254)
		(layers "F.Cu" "B.Cu")
		(net "M_B_DQS_DP<14>")
	)
	(via
		(at 292.392354 -12.573)
		(size 0.508)
		(drill 0.254)
		(layers "F.Cu" "B.Cu")
		(net "M_B_DQS_DP<14>")
	)
	(via
		(at 292.392354 -8.483346)
		(size 0.508)
		(drill 0.254)
		(layers "F.Cu" "B.Cu")
		(net "M_B_DQS_DP<14>")
	)
	(arc
		(start 278.346154 -51.466242)
		(mid 278.482767 -51.836591)
		(end 278.826976 -52.029868)
		(width 0.0889)
		(layer "F.Cu")
		(net "M_B_DQS_DP<14>")
	)
	(segment
		(start 292.003988 -12.96162)
		(end 291.916612 -13.121132)
		(width 0.1651)
		(layer "B.Cu")
		(net "M_B_DQS_DP<14>")
	)
	(segment
		(start 292.450012 -14.605254)
		(end 292.450012 -15.222982)
		(width 0.1651)
		(layer "B.Cu")
		(net "M_B_DQS_DP<14>")
	)
	(segment
		(start 292.392354 -12.573254)
		(end 292.003988 -12.96162)
		(width 0.1651)
		(layer "B.Cu")
		(net "M_B_DQS_DP<14>")
	)
	(segment
		(start 292.450012 -15.222982)
		(end 292.45052 -15.222982)
		(width 0.1651)
		(layer "B.Cu")
		(net "M_B_DQS_DP<14>")
	)
	(segment
		(start 291.993828 -14.14907)
		(end 292.450012 -14.605254)
		(width 0.1651)
		(layer "B.Cu")
		(net "M_B_DQS_DP<14>")
	)
	(segment
		(start 291.916612 -14.016736)
		(end 291.993828 -14.14907)
		(width 0.1651)
		(layer "B.Cu")
		(net "M_B_DQS_DP<14>")
	)
	(segment
		(start 291.916612 -13.121132)
		(end 291.916612 -14.016736)
		(width 0.1651)
		(layer "B.Cu")
		(net "M_B_DQS_DP<14>")
	)
	(segment
		(start 292.392354 -12.573)
		(end 292.392354 -12.573254)
		(width 0.1651)
		(layer "B.Cu")
		(net "M_B_DQS_DP<14>")
	)
	(segment
		(start 292.60038 -8.27532)
		(end 292.731698 -8.27532)
		(width 0.14224)
		(layer "In11.Cu")
		(net "M_B_DQS_DP<14>")
	)
	(segment
		(start 292.731698 -8.27532)
		(end 292.912292 -8.455914)
		(width 0.14224)
		(layer "In11.Cu")
		(net "M_B_DQS_DP<14>")
	)
	(segment
		(start 292.6715 -12.573)
		(end 292.392608 -12.573)
		(width 0.14224)
		(layer "In11.Cu")
		(net "M_B_DQS_DP<14>")
	)
	(segment
		(start 292.424612 -9.779)
		(end 292.424612 -10.033)
		(width 0.14224)
		(layer "In11.Cu")
		(net "M_B_DQS_DP<14>")
	)
	(segment
		(start 292.424612 -10.033)
		(end 292.577012 -10.1854)
		(width 0.14224)
		(layer "In11.Cu")
		(net "M_B_DQS_DP<14>")
	)
	(segment
		(start 292.912292 -10.63752)
		(end 292.729412 -10.8204)
		(width 0.14224)
		(layer "In11.Cu")
		(net "M_B_DQS_DP<14>")
	)
	(segment
		(start 292.548564 -10.8204)
		(end 292.421056 -10.947908)
		(width 0.14224)
		(layer "In11.Cu")
		(net "M_B_DQS_DP<14>")
	)
	(segment
		(start 292.64356 -19.192494)
		(end 292.889686 -18.946368)
		(width 0.14224)
		(layer "In11.Cu")
		(net "M_B_DQS_DP<14>")
	)
	(segment
		(start 292.889686 -21.363686)
		(end 292.64356 -21.11756)
		(width 0.14224)
		(layer "In11.Cu")
		(net "M_B_DQS_DP<14>")
	)
	(segment
		(start 292.912292 -8.455914)
		(end 292.912292 -9.29132)
		(width 0.14224)
		(layer "In11.Cu")
		(net "M_B_DQS_DP<14>")
	)
	(segment
		(start 292.665912 -11.4427)
		(end 292.912292 -11.68908)
		(width 0.14224)
		(layer "In11.Cu")
		(net "M_B_DQS_DP<14>")
	)
	(segment
		(start 292.912292 -10.39368)
		(end 292.912292 -10.63752)
		(width 0.14224)
		(layer "In11.Cu")
		(net "M_B_DQS_DP<14>")
	)
	(segment
		(start 291.891212 -13.074396)
		(end 292.392608 -12.573)
		(width 0.14224)
		(layer "In11.Cu")
		(net "M_B_DQS_DP<14>")
	)
	(segment
		(start 292.729412 -10.8204)
		(end 292.548564 -10.8204)
		(width 0.14224)
		(layer "In11.Cu")
		(net "M_B_DQS_DP<14>")
	)
	(segment
		(start 291.891212 -14.068806)
		(end 291.891212 -13.074396)
		(width 0.14224)
		(layer "In11.Cu")
		(net "M_B_DQS_DP<14>")
	)
	(segment
		(start 292.381686 -15.394686)
		(end 292.381686 -14.55928)
		(width 0.14224)
		(layer "In11.Cu")
		(net "M_B_DQS_DP<14>")
	)
	(segment
		(start 292.57752 -11.4427)
		(end 292.665912 -11.4427)
		(width 0.14224)
		(layer "In11.Cu")
		(net "M_B_DQS_DP<14>")
	)
	(segment
		(start 292.381686 -14.55928)
		(end 291.891212 -14.068806)
		(width 0.14224)
		(layer "In11.Cu")
		(net "M_B_DQS_DP<14>")
	)
	(segment
		(start 292.889686 -18.946368)
		(end 292.889686 -15.902686)
		(width 0.14224)
		(layer "In11.Cu")
		(net "M_B_DQS_DP<14>")
	)
	(segment
		(start 292.912292 -9.29132)
		(end 292.424612 -9.779)
		(width 0.14224)
		(layer "In11.Cu")
		(net "M_B_DQS_DP<14>")
	)
	(segment
		(start 292.421056 -10.947908)
		(end 292.421056 -11.286236)
		(width 0.14224)
		(layer "In11.Cu")
		(net "M_B_DQS_DP<14>")
	)
	(segment
		(start 292.399212 -27.39771)
		(end 292.889686 -26.907236)
		(width 0.14224)
		(layer "In11.Cu")
		(net "M_B_DQS_DP<14>")
	)
	(segment
		(start 292.912292 -11.68908)
		(end 292.912292 -12.332208)
		(width 0.14224)
		(layer "In11.Cu")
		(net "M_B_DQS_DP<14>")
	)
	(segment
		(start 292.392608 -12.573)
		(end 292.392354 -12.573)
		(width 0.14224)
		(layer "In11.Cu")
		(net "M_B_DQS_DP<14>")
	)
	(segment
		(start 292.421056 -11.286236)
		(end 292.57752 -11.4427)
		(width 0.14224)
		(layer "In11.Cu")
		(net "M_B_DQS_DP<14>")
	)
	(segment
		(start 292.64356 -21.11756)
		(end 292.64356 -19.192494)
		(width 0.14224)
		(layer "In11.Cu")
		(net "M_B_DQS_DP<14>")
	)
	(segment
		(start 292.704012 -10.1854)
		(end 292.912292 -10.39368)
		(width 0.14224)
		(layer "In11.Cu")
		(net "M_B_DQS_DP<14>")
	)
	(segment
		(start 292.889686 -26.907236)
		(end 292.889686 -21.363686)
		(width 0.14224)
		(layer "In11.Cu")
		(net "M_B_DQS_DP<14>")
	)
	(segment
		(start 292.889686 -15.902686)
		(end 292.381686 -15.394686)
		(width 0.14224)
		(layer "In11.Cu")
		(net "M_B_DQS_DP<14>")
	)
	(segment
		(start 292.392354 -8.483346)
		(end 292.60038 -8.27532)
		(width 0.14224)
		(layer "In11.Cu")
		(net "M_B_DQS_DP<14>")
	)
	(segment
		(start 292.577012 -10.1854)
		(end 292.704012 -10.1854)
		(width 0.14224)
		(layer "In11.Cu")
		(net "M_B_DQS_DP<14>")
	)
	(segment
		(start 292.912292 -12.332208)
		(end 292.6715 -12.573)
		(width 0.14224)
		(layer "In11.Cu")
		(net "M_B_DQS_DP<14>")
	)
	(segment
		(start 283.099764 -6.454394)
		(end 282.5496 -7.004558)
		(width 0.1651)
		(layer "F.Cu")
		(net "M_B_DQS_DP<13>")
	)
	(segment
		(start 282.5496 -7.796022)
		(end 282.660598 -8.101584)
		(width 0.1651)
		(layer "F.Cu")
		(net "M_B_DQS_DP<13>")
	)
	(segment
		(start 282.660598 -8.101584)
		(end 283.04236 -8.483346)
		(width 0.1651)
		(layer "F.Cu")
		(net "M_B_DQS_DP<13>")
	)
	(segment
		(start 272.052288 -56.399938)
		(end 271.480788 -56.399938)
		(width 0.1016)
		(layer "F.Cu")
		(net "M_B_DQS_DP<13>")
	)
	(segment
		(start 283.100272 -5.822442)
		(end 283.099764 -5.822442)
		(width 0.1651)
		(layer "F.Cu")
		(net "M_B_DQS_DP<13>")
	)
	(segment
		(start 282.5496 -7.004558)
		(end 282.5496 -7.796022)
		(width 0.1651)
		(layer "F.Cu")
		(net "M_B_DQS_DP<13>")
	)
	(segment
		(start 283.099764 -5.822442)
		(end 283.099764 -6.454394)
		(width 0.1651)
		(layer "F.Cu")
		(net "M_B_DQS_DP<13>")
	)
	(via
		(at 283.04236 -12.573)
		(size 0.508)
		(drill 0.254)
		(layers "F.Cu" "B.Cu")
		(net "M_B_DQS_DP<13>")
	)
	(via
		(at 271.480788 -56.399938)
		(size 0.508)
		(drill 0.254)
		(layers "F.Cu" "B.Cu")
		(net "M_B_DQS_DP<13>")
	)
	(via
		(at 283.04236 -8.483346)
		(size 0.508)
		(drill 0.254)
		(layers "F.Cu" "B.Cu")
		(net "M_B_DQS_DP<13>")
	)
	(segment
		(start 283.099764 -14.605254)
		(end 282.64358 -14.14907)
		(width 0.1651)
		(layer "B.Cu")
		(net "M_B_DQS_DP<13>")
	)
	(segment
		(start 282.566364 -13.121132)
		(end 282.65374 -12.96162)
		(width 0.1651)
		(layer "B.Cu")
		(net "M_B_DQS_DP<13>")
	)
	(segment
		(start 282.64358 -14.14907)
		(end 282.566364 -14.016736)
		(width 0.1651)
		(layer "B.Cu")
		(net "M_B_DQS_DP<13>")
	)
	(segment
		(start 282.65374 -12.96162)
		(end 283.04236 -12.573)
		(width 0.1651)
		(layer "B.Cu")
		(net "M_B_DQS_DP<13>")
	)
	(segment
		(start 283.100272 -15.222982)
		(end 283.099764 -15.222982)
		(width 0.1651)
		(layer "B.Cu")
		(net "M_B_DQS_DP<13>")
	)
	(segment
		(start 282.566364 -14.016736)
		(end 282.566364 -13.121132)
		(width 0.1651)
		(layer "B.Cu")
		(net "M_B_DQS_DP<13>")
	)
	(segment
		(start 283.099764 -15.222982)
		(end 283.099764 -14.605254)
		(width 0.1651)
		(layer "B.Cu")
		(net "M_B_DQS_DP<13>")
	)
	(segment
		(start 282.503118 -26.65095)
		(end 282.866338 -27.01417)
		(width 0.14224)
		(layer "In4.Cu")
		(net "M_B_DQS_DP<13>")
	)
	(segment
		(start 279.83688 -30.354778)
		(end 279.83688 -29.488638)
		(width 0.14224)
		(layer "In4.Cu")
		(net "M_B_DQS_DP<13>")
	)
	(segment
		(start 271.459198 -54.818788)
		(end 271.498314 -54.818788)
		(width 0.0889)
		(layer "In4.Cu")
		(net "M_B_DQS_DP<13>")
	)
	(segment
		(start 283.321506 -12.573)
		(end 283.562044 -12.332462)
		(width 0.14224)
		(layer "In4.Cu")
		(net "M_B_DQS_DP<13>")
	)
	(segment
		(start 281.359864 -27.257248)
		(end 281.966162 -26.65095)
		(width 0.14224)
		(layer "In4.Cu")
		(net "M_B_DQS_DP<13>")
	)
	(segment
		(start 281.359864 -27.793696)
		(end 281.359864 -27.257248)
		(width 0.14224)
		(layer "In4.Cu")
		(net "M_B_DQS_DP<13>")
	)
	(segment
		(start 283.177488 -27.01417)
		(end 283.628592 -26.563066)
		(width 0.14224)
		(layer "In4.Cu")
		(net "M_B_DQS_DP<13>")
	)
	(segment
		(start 283.562044 -8.455914)
		(end 283.38145 -8.27532)
		(width 0.14224)
		(layer "In4.Cu")
		(net "M_B_DQS_DP<13>")
	)
	(segment
		(start 283.55544 -16.238474)
		(end 282.571444 -15.254478)
		(width 0.14224)
		(layer "In4.Cu")
		(net "M_B_DQS_DP<13>")
	)
	(segment
		(start 283.074364 -9.779)
		(end 283.562044 -9.29132)
		(width 0.14224)
		(layer "In4.Cu")
		(net "M_B_DQS_DP<13>")
	)
	(segment
		(start 283.04236 -12.573)
		(end 283.321506 -12.573)
		(width 0.14224)
		(layer "In4.Cu")
		(net "M_B_DQS_DP<13>")
	)
	(segment
		(start 283.250386 -8.27532)
		(end 283.04236 -8.483346)
		(width 0.14224)
		(layer "In4.Cu")
		(net "M_B_DQS_DP<13>")
	)
	(segment
		(start 283.379164 -10.8204)
		(end 283.562044 -10.63752)
		(width 0.14224)
		(layer "In4.Cu")
		(net "M_B_DQS_DP<13>")
	)
	(segment
		(start 283.264864 -25.888696)
		(end 283.264864 -25.134062)
		(width 0.14224)
		(layer "In4.Cu")
		(net "M_B_DQS_DP<13>")
	)
	(segment
		(start 282.571444 -13.043916)
		(end 283.04236 -12.573)
		(width 0.14224)
		(layer "In4.Cu")
		(net "M_B_DQS_DP<13>")
	)
	(segment
		(start 281.328622 -28.754324)
		(end 281.669236 -28.41371)
		(width 0.14224)
		(layer "In4.Cu")
		(net "M_B_DQS_DP<13>")
	)
	(segment
		(start 272.79346 -47.399956)
		(end 273.680936 -46.51248)
		(width 0.0889)
		(layer "In4.Cu")
		(net "M_B_DQS_DP<13>")
	)
	(segment
		(start 281.966162 -26.65095)
		(end 282.503118 -26.65095)
		(width 0.14224)
		(layer "In4.Cu")
		(net "M_B_DQS_DP<13>")
	)
	(segment
		(start 279.22728 -30.96514)
		(end 279.61082 -30.5816)
		(width 0.14224)
		(layer "In4.Cu")
		(net "M_B_DQS_DP<13>")
	)
	(segment
		(start 283.070808 -10.947908)
		(end 283.198316 -10.8204)
		(width 0.14224)
		(layer "In4.Cu")
		(net "M_B_DQS_DP<13>")
	)
	(segment
		(start 283.198316 -10.8204)
		(end 283.379164 -10.8204)
		(width 0.14224)
		(layer "In4.Cu")
		(net "M_B_DQS_DP<13>")
	)
	(segment
		(start 279.61082 -30.5816)
		(end 279.61082 -30.580838)
		(width 0.14224)
		(layer "In4.Cu")
		(net "M_B_DQS_DP<13>")
	)
	(segment
		(start 281.669236 -28.103068)
		(end 281.359864 -27.793696)
		(width 0.14224)
		(layer "In4.Cu")
		(net "M_B_DQS_DP<13>")
	)
	(segment
		(start 283.353764 -10.1854)
		(end 283.226764 -10.1854)
		(width 0.14224)
		(layer "In4.Cu")
		(net "M_B_DQS_DP<13>")
	)
	(segment
		(start 271.880838 -53.195728)
		(end 271.758156 -53.073046)
		(width 0.0889)
		(layer "In4.Cu")
		(net "M_B_DQS_DP<13>")
	)
	(segment
		(start 283.628592 -26.563066)
		(end 283.628592 -26.252424)
		(width 0.14224)
		(layer "In4.Cu")
		(net "M_B_DQS_DP<13>")
	)
	(segment
		(start 283.227272 -11.4427)
		(end 283.070808 -11.286236)
		(width 0.14224)
		(layer "In4.Cu")
		(net "M_B_DQS_DP<13>")
	)
	(segment
		(start 283.562044 -9.29132)
		(end 283.562044 -8.455914)
		(width 0.14224)
		(layer "In4.Cu")
		(net "M_B_DQS_DP<13>")
	)
	(segment
		(start 271.827498 -54.61889)
		(end 271.880838 -54.526688)
		(width 0.0889)
		(layer "In4.Cu")
		(net "M_B_DQS_DP<13>")
	)
	(segment
		(start 282.571444 -15.254478)
		(end 282.571444 -13.043916)
		(width 0.14224)
		(layer "In4.Cu")
		(net "M_B_DQS_DP<13>")
	)
	(segment
		(start 283.562044 -10.63752)
		(end 283.562044 -10.39368)
		(width 0.14224)
		(layer "In4.Cu")
		(net "M_B_DQS_DP<13>")
	)
	(segment
		(start 283.074364 -10.033)
		(end 283.074364 -9.779)
		(width 0.14224)
		(layer "In4.Cu")
		(net "M_B_DQS_DP<13>")
	)
	(segment
		(start 283.55544 -24.843486)
		(end 283.55544 -16.238474)
		(width 0.14224)
		(layer "In4.Cu")
		(net "M_B_DQS_DP<13>")
	)
	(segment
		(start 283.562044 -11.68908)
		(end 283.315664 -11.4427)
		(width 0.14224)
		(layer "In4.Cu")
		(net "M_B_DQS_DP<13>")
	)
	(segment
		(start 281.669236 -28.41371)
		(end 281.669236 -28.103068)
		(width 0.14224)
		(layer "In4.Cu")
		(net "M_B_DQS_DP<13>")
	)
	(segment
		(start 273.680936 -46.51248)
		(end 273.680936 -45.537882)
		(width 0.0889)
		(layer "In4.Cu")
		(net "M_B_DQS_DP<13>")
	)
	(segment
		(start 283.562044 -12.332462)
		(end 283.562044 -11.68908)
		(width 0.14224)
		(layer "In4.Cu")
		(net "M_B_DQS_DP<13>")
	)
	(segment
		(start 283.315664 -11.4427)
		(end 283.227272 -11.4427)
		(width 0.14224)
		(layer "In4.Cu")
		(net "M_B_DQS_DP<13>")
	)
	(segment
		(start 283.562044 -10.39368)
		(end 283.353764 -10.1854)
		(width 0.14224)
		(layer "In4.Cu")
		(net "M_B_DQS_DP<13>")
	)
	(segment
		(start 272.79346 -48.726598)
		(end 272.79346 -47.399956)
		(width 0.0889)
		(layer "In4.Cu")
		(net "M_B_DQS_DP<13>")
	)
	(segment
		(start 283.226764 -10.1854)
		(end 283.074364 -10.033)
		(width 0.14224)
		(layer "In4.Cu")
		(net "M_B_DQS_DP<13>")
	)
	(segment
		(start 283.264864 -25.134062)
		(end 283.55544 -24.843486)
		(width 0.14224)
		(layer "In4.Cu")
		(net "M_B_DQS_DP<13>")
	)
	(segment
		(start 279.22728 -31.814008)
		(end 279.22728 -30.96514)
		(width 0.14224)
		(layer "In4.Cu")
		(net "M_B_DQS_DP<13>")
	)
	(segment
		(start 282.866338 -27.01417)
		(end 283.177488 -27.01417)
		(width 0.14224)
		(layer "In4.Cu")
		(net "M_B_DQS_DP<13>")
	)
	(segment
		(start 273.641566 -37.399722)
		(end 279.22728 -31.814008)
		(width 0.14224)
		(layer "In4.Cu")
		(net "M_B_DQS_DP<13>")
	)
	(segment
		(start 279.61082 -30.580838)
		(end 279.83688 -30.354778)
		(width 0.14224)
		(layer "In4.Cu")
		(net "M_B_DQS_DP<13>")
	)
	(segment
		(start 283.38145 -8.27532)
		(end 283.250386 -8.27532)
		(width 0.14224)
		(layer "In4.Cu")
		(net "M_B_DQS_DP<13>")
	)
	(segment
		(start 271.880838 -54.526688)
		(end 271.880838 -53.195728)
		(width 0.0889)
		(layer "In4.Cu")
		(net "M_B_DQS_DP<13>")
	)
	(segment
		(start 283.070808 -11.286236)
		(end 283.070808 -10.947908)
		(width 0.14224)
		(layer "In4.Cu")
		(net "M_B_DQS_DP<13>")
	)
	(segment
		(start 273.641566 -45.498512)
		(end 273.641566 -45.476414)
		(width 0.0889)
		(layer "In4.Cu")
		(net "M_B_DQS_DP<13>")
	)
	(segment
		(start 283.628592 -26.252424)
		(end 283.264864 -25.888696)
		(width 0.14224)
		(layer "In4.Cu")
		(net "M_B_DQS_DP<13>")
	)
	(segment
		(start 280.571194 -28.754324)
		(end 281.328622 -28.754324)
		(width 0.14224)
		(layer "In4.Cu")
		(net "M_B_DQS_DP<13>")
	)
	(segment
		(start 272.510504 -51.073812)
		(end 272.510504 -49.009554)
		(width 0.0889)
		(layer "In4.Cu")
		(net "M_B_DQS_DP<13>")
	)
	(segment
		(start 273.641566 -45.476414)
		(end 273.641566 -37.399722)
		(width 0.14224)
		(layer "In4.Cu")
		(net "M_B_DQS_DP<13>")
	)
	(segment
		(start 272.510504 -49.009554)
		(end 272.79346 -48.726598)
		(width 0.0889)
		(layer "In4.Cu")
		(net "M_B_DQS_DP<13>")
	)
	(segment
		(start 279.83688 -29.488638)
		(end 280.571194 -28.754324)
		(width 0.14224)
		(layer "In4.Cu")
		(net "M_B_DQS_DP<13>")
	)
	(segment
		(start 273.680936 -45.537882)
		(end 273.641566 -45.498512)
		(width 0.0889)
		(layer "In4.Cu")
		(net "M_B_DQS_DP<13>")
	)
	(segment
		(start 271.758156 -53.073046)
		(end 271.758156 -51.82616)
		(width 0.0889)
		(layer "In4.Cu")
		(net "M_B_DQS_DP<13>")
	)
	(segment
		(start 271.758156 -51.82616)
		(end 272.510504 -51.073812)
		(width 0.0889)
		(layer "In4.Cu")
		(net "M_B_DQS_DP<13>")
	)
	(arc
		(start 271.498314 -54.818788)
		(mid 271.688556 -54.761053)
		(end 271.827498 -54.61889)
		(width 0.0889)
		(layer "In4.Cu")
		(net "M_B_DQS_DP<13>")
	)
	(arc
		(start 271.05864 -55.825644)
		(mid 270.917457 -55.186422)
		(end 271.459198 -54.818788)
		(width 0.0889)
		(layer "In4.Cu")
		(net "M_B_DQS_DP<13>")
	)
	(arc
		(start 271.480788 -56.399938)
		(mid 271.292961 -56.095703)
		(end 271.05864 -55.825644)
		(width 0.0889)
		(layer "In4.Cu")
		(net "M_B_DQS_DP<13>")
	)
	(segment
		(start 227.997512 -36.41979)
		(end 227.716842 -36.41979)
		(width 0.1651)
		(layer "F.Cu")
		(net "M_B_DQS_DP<12>")
	)
	(segment
		(start 227.41382 -6.875272)
		(end 227.329238 -7.059168)
		(width 0.1651)
		(layer "F.Cu")
		(net "M_B_DQS_DP<12>")
	)
	(segment
		(start 227.65385 -33.17621)
		(end 228.0285 -33.17621)
		(width 0.1651)
		(layer "F.Cu")
		(net "M_B_DQS_DP<12>")
	)
	(segment
		(start 227.65385 -34.06267)
		(end 227.3046 -34.41192)
		(width 0.1651)
		(layer "F.Cu")
		(net "M_B_DQS_DP<12>")
	)
	(segment
		(start 237.920276 -48.29429)
		(end 237.564676 -47.93869)
		(width 0.1016)
		(layer "F.Cu")
		(net "M_B_DQS_DP<12>")
	)
	(segment
		(start 227.3808 -37.35959)
		(end 228.1682 -38.14699)
		(width 0.1651)
		(layer "F.Cu")
		(net "M_B_DQS_DP<12>")
	)
	(segment
		(start 243.196364 -49.492154)
		(end 243.10594 -49.492154)
		(width 0.0889)
		(layer "F.Cu")
		(net "M_B_DQS_DP<12>")
	)
	(segment
		(start 231.977946 -46.759114)
		(end 232.29443 -46.759114)
		(width 0.1016)
		(layer "F.Cu")
		(net "M_B_DQS_DP<12>")
	)
	(segment
		(start 227.3046 -34.41192)
		(end 227.3046 -35.18408)
		(width 0.1651)
		(layer "F.Cu")
		(net "M_B_DQS_DP<12>")
	)
	(segment
		(start 231.606852 -46.38802)
		(end 231.977946 -46.759114)
		(width 0.1016)
		(layer "F.Cu")
		(net "M_B_DQS_DP<12>")
	)
	(segment
		(start 227.3046 -32.82696)
		(end 227.65385 -33.17621)
		(width 0.1651)
		(layer "F.Cu")
		(net "M_B_DQS_DP<12>")
	)
	(segment
		(start 243.3193 -50.134774)
		(end 243.3193 -49.61509)
		(width 0.0889)
		(layer "F.Cu")
		(net "M_B_DQS_DP<12>")
	)
	(segment
		(start 241.908076 -48.29429)
		(end 237.920276 -48.29429)
		(width 0.1016)
		(layer "F.Cu")
		(net "M_B_DQS_DP<12>")
	)
	(segment
		(start 227.3046 -35.18408)
		(end 227.65385 -35.53333)
		(width 0.1651)
		(layer "F.Cu")
		(net "M_B_DQS_DP<12>")
	)
	(segment
		(start 228.1936 -33.34131)
		(end 228.1936 -33.89757)
		(width 0.1651)
		(layer "F.Cu")
		(net "M_B_DQS_DP<12>")
	)
	(segment
		(start 227.329238 -7.059168)
		(end 227.329238 -7.877302)
		(width 0.1651)
		(layer "F.Cu")
		(net "M_B_DQS_DP<12>")
	)
	(segment
		(start 243.318792 -50.135282)
		(end 243.3193 -50.134774)
		(width 0.0889)
		(layer "F.Cu")
		(net "M_B_DQS_DP<12>")
	)
	(segment
		(start 227.997512 -35.53333)
		(end 228.17582 -35.711638)
		(width 0.1651)
		(layer "F.Cu")
		(net "M_B_DQS_DP<12>")
	)
	(segment
		(start 243.3193 -49.61509)
		(end 243.196364 -49.492154)
		(width 0.0889)
		(layer "F.Cu")
		(net "M_B_DQS_DP<12>")
	)
	(segment
		(start 243.910104 -50.800762)
		(end 243.837968 -50.728626)
		(width 0.0889)
		(layer "F.Cu")
		(net "M_B_DQS_DP<12>")
	)
	(segment
		(start 227.3046 -27.892248)
		(end 227.3046 -31.877)
		(width 0.1651)
		(layer "F.Cu")
		(net "M_B_DQS_DP<12>")
	)
	(segment
		(start 228.17582 -35.711638)
		(end 228.17582 -36.241482)
		(width 0.1651)
		(layer "F.Cu")
		(net "M_B_DQS_DP<12>")
	)
	(segment
		(start 227.3046 -31.877)
		(end 227.3046 -32.82696)
		(width 0.1651)
		(layer "F.Cu")
		(net "M_B_DQS_DP<12>")
	)
	(segment
		(start 227.850446 -5.822442)
		(end 227.849938 -5.822442)
		(width 0.1651)
		(layer "F.Cu")
		(net "M_B_DQS_DP<12>")
	)
	(segment
		(start 243.10594 -49.492154)
		(end 241.908076 -48.29429)
		(width 0.1016)
		(layer "F.Cu")
		(net "M_B_DQS_DP<12>")
	)
	(segment
		(start 228.1682 -42.949368)
		(end 231.606852 -46.38802)
		(width 0.1651)
		(layer "F.Cu")
		(net "M_B_DQS_DP<12>")
	)
	(segment
		(start 243.910104 -51.132486)
		(end 243.910104 -50.800762)
		(width 0.0889)
		(layer "F.Cu")
		(net "M_B_DQS_DP<12>")
	)
	(segment
		(start 228.1936 -33.89757)
		(end 228.0285 -34.06267)
		(width 0.1651)
		(layer "F.Cu")
		(net "M_B_DQS_DP<12>")
	)
	(segment
		(start 228.17582 -36.241482)
		(end 227.997512 -36.41979)
		(width 0.1651)
		(layer "F.Cu")
		(net "M_B_DQS_DP<12>")
	)
	(segment
		(start 227.716842 -36.41979)
		(end 227.3808 -36.755832)
		(width 0.1651)
		(layer "F.Cu")
		(net "M_B_DQS_DP<12>")
	)
	(segment
		(start 227.3808 -36.755832)
		(end 227.3808 -37.35959)
		(width 0.1651)
		(layer "F.Cu")
		(net "M_B_DQS_DP<12>")
	)
	(segment
		(start 228.0285 -34.06267)
		(end 227.65385 -34.06267)
		(width 0.1651)
		(layer "F.Cu")
		(net "M_B_DQS_DP<12>")
	)
	(segment
		(start 237.564676 -47.93869)
		(end 233.474006 -47.93869)
		(width 0.1016)
		(layer "F.Cu")
		(net "M_B_DQS_DP<12>")
	)
	(segment
		(start 227.329238 -7.877302)
		(end 227.410772 -8.101584)
		(width 0.1651)
		(layer "F.Cu")
		(net "M_B_DQS_DP<12>")
	)
	(segment
		(start 227.849938 -6.439154)
		(end 227.41382 -6.875272)
		(width 0.1651)
		(layer "F.Cu")
		(net "M_B_DQS_DP<12>")
	)
	(segment
		(start 227.849938 -5.822442)
		(end 227.849938 -6.439154)
		(width 0.1651)
		(layer "F.Cu")
		(net "M_B_DQS_DP<12>")
	)
	(segment
		(start 228.1682 -38.14699)
		(end 228.1682 -42.949368)
		(width 0.1651)
		(layer "F.Cu")
		(net "M_B_DQS_DP<12>")
	)
	(segment
		(start 227.410772 -8.101584)
		(end 227.792534 -8.483346)
		(width 0.1651)
		(layer "F.Cu")
		(net "M_B_DQS_DP<12>")
	)
	(segment
		(start 233.474006 -47.93869)
		(end 232.29443 -46.759114)
		(width 0.1016)
		(layer "F.Cu")
		(net "M_B_DQS_DP<12>")
	)
	(segment
		(start 227.799138 -27.39771)
		(end 227.3046 -27.892248)
		(width 0.1651)
		(layer "F.Cu")
		(net "M_B_DQS_DP<12>")
	)
	(segment
		(start 227.65385 -35.53333)
		(end 227.997512 -35.53333)
		(width 0.1651)
		(layer "F.Cu")
		(net "M_B_DQS_DP<12>")
	)
	(segment
		(start 228.0285 -33.17621)
		(end 228.1936 -33.34131)
		(width 0.1651)
		(layer "F.Cu")
		(net "M_B_DQS_DP<12>")
	)
	(via
		(at 227.792534 -12.573)
		(size 0.508)
		(drill 0.254)
		(layers "F.Cu" "B.Cu")
		(net "M_B_DQS_DP<12>")
	)
	(via
		(at 227.799138 -27.39771)
		(size 0.508)
		(drill 0.254)
		(layers "F.Cu" "B.Cu")
		(net "M_B_DQS_DP<12>")
	)
	(via
		(at 227.792534 -8.483346)
		(size 0.508)
		(drill 0.254)
		(layers "F.Cu" "B.Cu")
		(net "M_B_DQS_DP<12>")
	)
	(via
		(at 227.3046 -31.877)
		(size 0.508)
		(drill 0.254)
		(layers "F.Cu" "B.Cu")
		(net "M_B_DQS_DP<12>")
	)
	(arc
		(start 243.816632 -50.725578)
		(mid 243.574926 -50.628804)
		(end 243.398294 -50.437542)
		(width 0.0889)
		(layer "F.Cu")
		(net "M_B_DQS_DP<12>")
	)
	(arc
		(start 243.837968 -50.728626)
		(mid 243.827286 -50.727199)
		(end 243.816632 -50.725578)
		(width 0.0889)
		(layer "F.Cu")
		(net "M_B_DQS_DP<12>")
	)
	(arc
		(start 243.398294 -50.437542)
		(mid 243.338197 -50.291763)
		(end 243.318792 -50.135282)
		(width 0.0889)
		(layer "F.Cu")
		(net "M_B_DQS_DP<12>")
	)
	(segment
		(start 227.403914 -12.96162)
		(end 227.792534 -12.573)
		(width 0.1651)
		(layer "B.Cu")
		(net "M_B_DQS_DP<12>")
	)
	(segment
		(start 227.316538 -13.121132)
		(end 227.403914 -12.96162)
		(width 0.1651)
		(layer "B.Cu")
		(net "M_B_DQS_DP<12>")
	)
	(segment
		(start 227.849938 -14.605254)
		(end 227.393754 -14.14907)
		(width 0.1651)
		(layer "B.Cu")
		(net "M_B_DQS_DP<12>")
	)
	(segment
		(start 227.316538 -14.016736)
		(end 227.316538 -13.121132)
		(width 0.1651)
		(layer "B.Cu")
		(net "M_B_DQS_DP<12>")
	)
	(segment
		(start 227.850446 -15.222982)
		(end 227.849938 -15.222982)
		(width 0.1651)
		(layer "B.Cu")
		(net "M_B_DQS_DP<12>")
	)
	(segment
		(start 227.849938 -15.222982)
		(end 227.849938 -14.605254)
		(width 0.1651)
		(layer "B.Cu")
		(net "M_B_DQS_DP<12>")
	)
	(segment
		(start 227.393754 -14.14907)
		(end 227.316538 -14.016736)
		(width 0.1651)
		(layer "B.Cu")
		(net "M_B_DQS_DP<12>")
	)
	(segment
		(start 228.312218 -11.68908)
		(end 228.065838 -11.4427)
		(width 0.14224)
		(layer "In4.Cu")
		(net "M_B_DQS_DP<12>")
	)
	(segment
		(start 228.00056 -8.27532)
		(end 227.792534 -8.483346)
		(width 0.14224)
		(layer "In4.Cu")
		(net "M_B_DQS_DP<12>")
	)
	(segment
		(start 227.291138 -13.074396)
		(end 227.792534 -12.573)
		(width 0.14224)
		(layer "In4.Cu")
		(net "M_B_DQS_DP<12>")
	)
	(segment
		(start 227.781612 -14.55928)
		(end 227.291138 -14.068806)
		(width 0.14224)
		(layer "In4.Cu")
		(net "M_B_DQS_DP<12>")
	)
	(segment
		(start 228.312218 -10.63752)
		(end 228.312218 -10.39368)
		(width 0.14224)
		(layer "In4.Cu")
		(net "M_B_DQS_DP<12>")
	)
	(segment
		(start 228.065838 -11.4427)
		(end 227.977446 -11.4427)
		(width 0.14224)
		(layer "In4.Cu")
		(net "M_B_DQS_DP<12>")
	)
	(segment
		(start 227.291138 -14.068806)
		(end 227.291138 -13.074396)
		(width 0.14224)
		(layer "In4.Cu")
		(net "M_B_DQS_DP<12>")
	)
	(segment
		(start 228.312218 -12.332462)
		(end 228.312218 -11.68908)
		(width 0.14224)
		(layer "In4.Cu")
		(net "M_B_DQS_DP<12>")
	)
	(segment
		(start 228.131624 -8.27532)
		(end 228.00056 -8.27532)
		(width 0.14224)
		(layer "In4.Cu")
		(net "M_B_DQS_DP<12>")
	)
	(segment
		(start 228.312218 -8.455914)
		(end 228.131624 -8.27532)
		(width 0.14224)
		(layer "In4.Cu")
		(net "M_B_DQS_DP<12>")
	)
	(segment
		(start 227.820982 -10.947908)
		(end 227.94849 -10.8204)
		(width 0.14224)
		(layer "In4.Cu")
		(net "M_B_DQS_DP<12>")
	)
	(segment
		(start 228.103938 -10.1854)
		(end 227.976938 -10.1854)
		(width 0.14224)
		(layer "In4.Cu")
		(net "M_B_DQS_DP<12>")
	)
	(segment
		(start 227.781612 -15.28826)
		(end 227.781612 -14.55928)
		(width 0.14224)
		(layer "In4.Cu")
		(net "M_B_DQS_DP<12>")
	)
	(segment
		(start 228.312218 -9.29132)
		(end 228.312218 -8.455914)
		(width 0.14224)
		(layer "In4.Cu")
		(net "M_B_DQS_DP<12>")
	)
	(segment
		(start 228.129338 -10.8204)
		(end 228.312218 -10.63752)
		(width 0.14224)
		(layer "In4.Cu")
		(net "M_B_DQS_DP<12>")
	)
	(segment
		(start 227.792534 -12.573)
		(end 228.07168 -12.573)
		(width 0.14224)
		(layer "In4.Cu")
		(net "M_B_DQS_DP<12>")
	)
	(segment
		(start 228.312218 -10.39368)
		(end 228.103938 -10.1854)
		(width 0.14224)
		(layer "In4.Cu")
		(net "M_B_DQS_DP<12>")
	)
	(segment
		(start 227.820982 -11.286236)
		(end 227.820982 -10.947908)
		(width 0.14224)
		(layer "In4.Cu")
		(net "M_B_DQS_DP<12>")
	)
	(segment
		(start 227.94849 -10.8204)
		(end 228.129338 -10.8204)
		(width 0.14224)
		(layer "In4.Cu")
		(net "M_B_DQS_DP<12>")
	)
	(segment
		(start 227.799138 -27.39771)
		(end 228.289612 -26.907236)
		(width 0.14224)
		(layer "In4.Cu")
		(net "M_B_DQS_DP<12>")
	)
	(segment
		(start 228.07168 -12.573)
		(end 228.312218 -12.332462)
		(width 0.14224)
		(layer "In4.Cu")
		(net "M_B_DQS_DP<12>")
	)
	(segment
		(start 227.824538 -10.033)
		(end 227.824538 -9.779)
		(width 0.14224)
		(layer "In4.Cu")
		(net "M_B_DQS_DP<12>")
	)
	(segment
		(start 228.289612 -15.79626)
		(end 227.781612 -15.28826)
		(width 0.14224)
		(layer "In4.Cu")
		(net "M_B_DQS_DP<12>")
	)
	(segment
		(start 227.976938 -10.1854)
		(end 227.824538 -10.033)
		(width 0.14224)
		(layer "In4.Cu")
		(net "M_B_DQS_DP<12>")
	)
	(segment
		(start 227.824538 -9.779)
		(end 228.312218 -9.29132)
		(width 0.14224)
		(layer "In4.Cu")
		(net "M_B_DQS_DP<12>")
	)
	(segment
		(start 227.977446 -11.4427)
		(end 227.820982 -11.286236)
		(width 0.14224)
		(layer "In4.Cu")
		(net "M_B_DQS_DP<12>")
	)
	(segment
		(start 228.289612 -26.907236)
		(end 228.289612 -15.79626)
		(width 0.14224)
		(layer "In4.Cu")
		(net "M_B_DQS_DP<12>")
	)
	(segment
		(start 217.979244 -7.059168)
		(end 217.979244 -7.877302)
		(width 0.1651)
		(layer "F.Cu")
		(net "M_B_DQS_DP<11>")
	)
	(segment
		(start 218.499944 -6.439154)
		(end 218.063826 -6.875272)
		(width 0.1651)
		(layer "F.Cu")
		(net "M_B_DQS_DP<11>")
	)
	(segment
		(start 218.499944 -5.822442)
		(end 218.499944 -6.439154)
		(width 0.1651)
		(layer "F.Cu")
		(net "M_B_DQS_DP<11>")
	)
	(segment
		(start 218.060778 -8.101584)
		(end 218.44254 -8.483346)
		(width 0.1651)
		(layer "F.Cu")
		(net "M_B_DQS_DP<11>")
	)
	(segment
		(start 218.500452 -5.822442)
		(end 218.499944 -5.822442)
		(width 0.1651)
		(layer "F.Cu")
		(net "M_B_DQS_DP<11>")
	)
	(segment
		(start 218.063826 -6.875272)
		(end 217.979244 -7.059168)
		(width 0.1651)
		(layer "F.Cu")
		(net "M_B_DQS_DP<11>")
	)
	(segment
		(start 238.759238 -52.12334)
		(end 238.187738 -52.12334)
		(width 0.1016)
		(layer "F.Cu")
		(net "M_B_DQS_DP<11>")
	)
	(segment
		(start 217.979244 -7.877302)
		(end 218.060778 -8.101584)
		(width 0.1651)
		(layer "F.Cu")
		(net "M_B_DQS_DP<11>")
	)
	(via
		(at 218.44254 -12.573)
		(size 0.508)
		(drill 0.254)
		(layers "F.Cu" "B.Cu")
		(net "M_B_DQS_DP<11>")
	)
	(via
		(at 238.187738 -52.12334)
		(size 0.508)
		(drill 0.254)
		(layers "F.Cu" "B.Cu")
		(net "M_B_DQS_DP<11>")
	)
	(via
		(at 218.44254 -8.483346)
		(size 0.508)
		(drill 0.254)
		(layers "F.Cu" "B.Cu")
		(net "M_B_DQS_DP<11>")
	)
	(segment
		(start 218.499944 -15.222982)
		(end 218.499944 -14.605254)
		(width 0.1651)
		(layer "B.Cu")
		(net "M_B_DQS_DP<11>")
	)
	(segment
		(start 218.500452 -15.222982)
		(end 218.499944 -15.222982)
		(width 0.1651)
		(layer "B.Cu")
		(net "M_B_DQS_DP<11>")
	)
	(segment
		(start 218.04376 -14.14907)
		(end 217.966544 -14.016736)
		(width 0.1651)
		(layer "B.Cu")
		(net "M_B_DQS_DP<11>")
	)
	(segment
		(start 217.966544 -13.121132)
		(end 218.05392 -12.96162)
		(width 0.1651)
		(layer "B.Cu")
		(net "M_B_DQS_DP<11>")
	)
	(segment
		(start 217.966544 -14.016736)
		(end 217.966544 -13.121132)
		(width 0.1651)
		(layer "B.Cu")
		(net "M_B_DQS_DP<11>")
	)
	(segment
		(start 218.05392 -12.96162)
		(end 218.44254 -12.573)
		(width 0.1651)
		(layer "B.Cu")
		(net "M_B_DQS_DP<11>")
	)
	(segment
		(start 218.499944 -14.605254)
		(end 218.04376 -14.14907)
		(width 0.1651)
		(layer "B.Cu")
		(net "M_B_DQS_DP<11>")
	)
	(segment
		(start 218.650566 -8.27532)
		(end 218.78163 -8.27532)
		(width 0.14224)
		(layer "In4.Cu")
		(net "M_B_DQS_DP<11>")
	)
	(segment
		(start 232.444798 -46.357032)
		(end 232.44556 -46.357032)
		(width 0.14224)
		(layer "In4.Cu")
		(net "M_B_DQS_DP<11>")
	)
	(segment
		(start 218.470988 -10.947908)
		(end 218.470988 -11.286236)
		(width 0.14224)
		(layer "In4.Cu")
		(net "M_B_DQS_DP<11>")
	)
	(segment
		(start 229.017068 -39.525702)
		(end 229.16388 -39.672514)
		(width 0.14224)
		(layer "In4.Cu")
		(net "M_B_DQS_DP<11>")
	)
	(segment
		(start 218.962224 -11.68908)
		(end 218.962224 -12.332462)
		(width 0.14224)
		(layer "In4.Cu")
		(net "M_B_DQS_DP<11>")
	)
	(segment
		(start 226.647502 -37.908484)
		(end 227.39985 -37.908484)
		(width 0.14224)
		(layer "In4.Cu")
		(net "M_B_DQS_DP<11>")
	)
	(segment
		(start 225.782632 -36.291266)
		(end 226.1362 -36.644834)
		(width 0.14224)
		(layer "In4.Cu")
		(net "M_B_DQS_DP<11>")
	)
	(segment
		(start 237.841028 -51.332638)
		(end 238.012224 -51.597814)
		(width 0.0889)
		(layer "In4.Cu")
		(net "M_B_DQS_DP<11>")
	)
	(segment
		(start 228.26472 -39.525702)
		(end 229.017068 -39.525702)
		(width 0.14224)
		(layer "In4.Cu")
		(net "M_B_DQS_DP<11>")
	)
	(segment
		(start 218.474544 -9.779)
		(end 218.474544 -10.033)
		(width 0.14224)
		(layer "In4.Cu")
		(net "M_B_DQS_DP<11>")
	)
	(segment
		(start 218.95562 -29.463492)
		(end 224.518982 -35.026854)
		(width 0.14224)
		(layer "In4.Cu")
		(net "M_B_DQS_DP<11>")
	)
	(segment
		(start 226.1362 -37.397182)
		(end 226.647502 -37.908484)
		(width 0.14224)
		(layer "In4.Cu")
		(net "M_B_DQS_DP<11>")
	)
	(segment
		(start 227.753418 -38.262052)
		(end 227.753418 -39.0144)
		(width 0.14224)
		(layer "In4.Cu")
		(net "M_B_DQS_DP<11>")
	)
	(segment
		(start 217.971624 -15.171674)
		(end 218.95562 -16.15567)
		(width 0.14224)
		(layer "In4.Cu")
		(net "M_B_DQS_DP<11>")
	)
	(segment
		(start 224.518982 -35.026854)
		(end 224.518982 -35.779202)
		(width 0.14224)
		(layer "In4.Cu")
		(net "M_B_DQS_DP<11>")
	)
	(segment
		(start 218.721686 -12.573)
		(end 218.44254 -12.573)
		(width 0.14224)
		(layer "In4.Cu")
		(net "M_B_DQS_DP<11>")
	)
	(segment
		(start 218.626944 -10.1854)
		(end 218.753944 -10.1854)
		(width 0.14224)
		(layer "In4.Cu")
		(net "M_B_DQS_DP<11>")
	)
	(segment
		(start 232.44556 -47.087536)
		(end 233.126534 -47.76851)
		(width 0.14224)
		(layer "In4.Cu")
		(net "M_B_DQS_DP<11>")
	)
	(segment
		(start 232.44556 -46.357032)
		(end 232.44556 -47.087536)
		(width 0.14224)
		(layer "In4.Cu")
		(net "M_B_DQS_DP<11>")
	)
	(segment
		(start 224.952052 -36.213034)
		(end 225.030284 -36.291266)
		(width 0.14224)
		(layer "In4.Cu")
		(net "M_B_DQS_DP<11>")
	)
	(segment
		(start 218.474544 -10.033)
		(end 218.626944 -10.1854)
		(width 0.14224)
		(layer "In4.Cu")
		(net "M_B_DQS_DP<11>")
	)
	(segment
		(start 229.16388 -43.076114)
		(end 232.444798 -46.357032)
		(width 0.14224)
		(layer "In4.Cu")
		(net "M_B_DQS_DP<11>")
	)
	(segment
		(start 218.779344 -10.8204)
		(end 218.598496 -10.8204)
		(width 0.14224)
		(layer "In4.Cu")
		(net "M_B_DQS_DP<11>")
	)
	(segment
		(start 218.962224 -8.455914)
		(end 218.962224 -9.29132)
		(width 0.14224)
		(layer "In4.Cu")
		(net "M_B_DQS_DP<11>")
	)
	(segment
		(start 238.012224 -51.597814)
		(end 238.187738 -52.12334)
		(width 0.0889)
		(layer "In4.Cu")
		(net "M_B_DQS_DP<11>")
	)
	(segment
		(start 218.962224 -10.63752)
		(end 218.779344 -10.8204)
		(width 0.14224)
		(layer "In4.Cu")
		(net "M_B_DQS_DP<11>")
	)
	(segment
		(start 227.753418 -39.0144)
		(end 228.26472 -39.525702)
		(width 0.14224)
		(layer "In4.Cu")
		(net "M_B_DQS_DP<11>")
	)
	(segment
		(start 218.627452 -11.4427)
		(end 218.715844 -11.4427)
		(width 0.14224)
		(layer "In4.Cu")
		(net "M_B_DQS_DP<11>")
	)
	(segment
		(start 218.470988 -11.286236)
		(end 218.627452 -11.4427)
		(width 0.14224)
		(layer "In4.Cu")
		(net "M_B_DQS_DP<11>")
	)
	(segment
		(start 233.126534 -47.76851)
		(end 233.142282 -47.784258)
		(width 0.0889)
		(layer "In4.Cu")
		(net "M_B_DQS_DP<11>")
	)
	(segment
		(start 225.030284 -36.291266)
		(end 225.782632 -36.291266)
		(width 0.14224)
		(layer "In4.Cu")
		(net "M_B_DQS_DP<11>")
	)
	(segment
		(start 224.952052 -36.212272)
		(end 224.952052 -36.213034)
		(width 0.14224)
		(layer "In4.Cu")
		(net "M_B_DQS_DP<11>")
	)
	(segment
		(start 235.248704 -49.835054)
		(end 237.138972 -49.835054)
		(width 0.0889)
		(layer "In4.Cu")
		(net "M_B_DQS_DP<11>")
	)
	(segment
		(start 218.962224 -12.332462)
		(end 218.721686 -12.573)
		(width 0.14224)
		(layer "In4.Cu")
		(net "M_B_DQS_DP<11>")
	)
	(segment
		(start 226.1362 -36.644834)
		(end 226.1362 -37.397182)
		(width 0.14224)
		(layer "In4.Cu")
		(net "M_B_DQS_DP<11>")
	)
	(segment
		(start 218.962224 -10.39368)
		(end 218.962224 -10.63752)
		(width 0.14224)
		(layer "In4.Cu")
		(net "M_B_DQS_DP<11>")
	)
	(segment
		(start 218.44254 -8.483346)
		(end 218.650566 -8.27532)
		(width 0.14224)
		(layer "In4.Cu")
		(net "M_B_DQS_DP<11>")
	)
	(segment
		(start 237.138972 -49.835054)
		(end 237.586012 -50.282094)
		(width 0.0889)
		(layer "In4.Cu")
		(net "M_B_DQS_DP<11>")
	)
	(segment
		(start 218.598496 -10.8204)
		(end 218.470988 -10.947908)
		(width 0.14224)
		(layer "In4.Cu")
		(net "M_B_DQS_DP<11>")
	)
	(segment
		(start 224.518982 -35.779202)
		(end 224.952052 -36.212272)
		(width 0.14224)
		(layer "In4.Cu")
		(net "M_B_DQS_DP<11>")
	)
	(segment
		(start 218.715844 -11.4427)
		(end 218.962224 -11.68908)
		(width 0.14224)
		(layer "In4.Cu")
		(net "M_B_DQS_DP<11>")
	)
	(segment
		(start 218.78163 -8.27532)
		(end 218.962224 -8.455914)
		(width 0.14224)
		(layer "In4.Cu")
		(net "M_B_DQS_DP<11>")
	)
	(segment
		(start 227.39985 -37.908484)
		(end 227.753418 -38.262052)
		(width 0.14224)
		(layer "In4.Cu")
		(net "M_B_DQS_DP<11>")
	)
	(segment
		(start 217.971624 -13.043916)
		(end 217.971624 -15.171674)
		(width 0.14224)
		(layer "In4.Cu")
		(net "M_B_DQS_DP<11>")
	)
	(segment
		(start 229.16388 -39.672514)
		(end 229.16388 -43.076114)
		(width 0.14224)
		(layer "In4.Cu")
		(net "M_B_DQS_DP<11>")
	)
	(segment
		(start 218.44254 -12.573)
		(end 217.971624 -13.043916)
		(width 0.14224)
		(layer "In4.Cu")
		(net "M_B_DQS_DP<11>")
	)
	(segment
		(start 233.197908 -47.784258)
		(end 235.248704 -49.835054)
		(width 0.0889)
		(layer "In4.Cu")
		(net "M_B_DQS_DP<11>")
	)
	(segment
		(start 237.586012 -50.282094)
		(end 237.675928 -50.437542)
		(width 0.0889)
		(layer "In4.Cu")
		(net "M_B_DQS_DP<11>")
	)
	(segment
		(start 233.142282 -47.784258)
		(end 233.197908 -47.784258)
		(width 0.0889)
		(layer "In4.Cu")
		(net "M_B_DQS_DP<11>")
	)
	(segment
		(start 218.753944 -10.1854)
		(end 218.962224 -10.39368)
		(width 0.14224)
		(layer "In4.Cu")
		(net "M_B_DQS_DP<11>")
	)
	(segment
		(start 218.95562 -16.15567)
		(end 218.95562 -29.463492)
		(width 0.14224)
		(layer "In4.Cu")
		(net "M_B_DQS_DP<11>")
	)
	(segment
		(start 218.962224 -9.29132)
		(end 218.474544 -9.779)
		(width 0.14224)
		(layer "In4.Cu")
		(net "M_B_DQS_DP<11>")
	)
	(arc
		(start 237.701074 -50.785014)
		(mid 237.690381 -50.899697)
		(end 237.707424 -51.013614)
		(width 0.0889)
		(layer "In4.Cu")
		(net "M_B_DQS_DP<11>")
	)
	(arc
		(start 237.707424 -51.013614)
		(mid 237.764075 -51.177378)
		(end 237.841028 -51.332638)
		(width 0.0889)
		(layer "In4.Cu")
		(net "M_B_DQS_DP<11>")
	)
	(arc
		(start 237.729268 -50.634138)
		(mid 237.72248 -50.710943)
		(end 237.701074 -50.785014)
		(width 0.0889)
		(layer "In4.Cu")
		(net "M_B_DQS_DP<11>")
	)
	(arc
		(start 237.675928 -50.437542)
		(mid 237.715281 -50.532396)
		(end 237.729268 -50.634138)
		(width 0.0889)
		(layer "In4.Cu")
		(net "M_B_DQS_DP<11>")
	)
	(segment
		(start 208.62925 -7.059168)
		(end 208.62925 -7.877302)
		(width 0.1651)
		(layer "F.Cu")
		(net "M_B_DQS_DP<10>")
	)
	(segment
		(start 209.14995 -6.439154)
		(end 208.713832 -6.875272)
		(width 0.1651)
		(layer "F.Cu")
		(net "M_B_DQS_DP<10>")
	)
	(segment
		(start 237.042198 -62.029086)
		(end 236.470698 -62.029086)
		(width 0.1016)
		(layer "F.Cu")
		(net "M_B_DQS_DP<10>")
	)
	(segment
		(start 208.62925 -7.877302)
		(end 208.710784 -8.101584)
		(width 0.1651)
		(layer "F.Cu")
		(net "M_B_DQS_DP<10>")
	)
	(segment
		(start 209.14995 -5.822442)
		(end 209.14995 -6.439154)
		(width 0.1651)
		(layer "F.Cu")
		(net "M_B_DQS_DP<10>")
	)
	(segment
		(start 208.710784 -8.101584)
		(end 209.092546 -8.483346)
		(width 0.1651)
		(layer "F.Cu")
		(net "M_B_DQS_DP<10>")
	)
	(segment
		(start 209.150458 -5.822442)
		(end 209.14995 -5.822442)
		(width 0.1651)
		(layer "F.Cu")
		(net "M_B_DQS_DP<10>")
	)
	(segment
		(start 208.713832 -6.875272)
		(end 208.62925 -7.059168)
		(width 0.1651)
		(layer "F.Cu")
		(net "M_B_DQS_DP<10>")
	)
	(via
		(at 209.092546 -8.483346)
		(size 0.508)
		(drill 0.254)
		(layers "F.Cu" "B.Cu")
		(net "M_B_DQS_DP<10>")
	)
	(via
		(at 209.092546 -12.573)
		(size 0.508)
		(drill 0.254)
		(layers "F.Cu" "B.Cu")
		(net "M_B_DQS_DP<10>")
	)
	(via
		(at 236.470698 -62.029086)
		(size 0.508)
		(drill 0.254)
		(layers "F.Cu" "B.Cu")
		(net "M_B_DQS_DP<10>")
	)
	(segment
		(start 208.703926 -12.96162)
		(end 209.092546 -12.573)
		(width 0.1651)
		(layer "B.Cu")
		(net "M_B_DQS_DP<10>")
	)
	(segment
		(start 209.14995 -14.605254)
		(end 208.693766 -14.14907)
		(width 0.1651)
		(layer "B.Cu")
		(net "M_B_DQS_DP<10>")
	)
	(segment
		(start 208.693766 -14.14907)
		(end 208.61655 -14.016736)
		(width 0.1651)
		(layer "B.Cu")
		(net "M_B_DQS_DP<10>")
	)
	(segment
		(start 208.61655 -14.016736)
		(end 208.61655 -13.121132)
		(width 0.1651)
		(layer "B.Cu")
		(net "M_B_DQS_DP<10>")
	)
	(segment
		(start 208.61655 -13.121132)
		(end 208.703926 -12.96162)
		(width 0.1651)
		(layer "B.Cu")
		(net "M_B_DQS_DP<10>")
	)
	(segment
		(start 209.150458 -15.222982)
		(end 209.14995 -15.222982)
		(width 0.1651)
		(layer "B.Cu")
		(net "M_B_DQS_DP<10>")
	)
	(segment
		(start 209.14995 -15.222982)
		(end 209.14995 -14.605254)
		(width 0.1651)
		(layer "B.Cu")
		(net "M_B_DQS_DP<10>")
	)
	(segment
		(start 231.372664 -57.789318)
		(end 231.734868 -58.151522)
		(width 0.0889)
		(layer "In4.Cu")
		(net "M_B_DQS_DP<10>")
	)
	(segment
		(start 214.807038 -37.783008)
		(end 213.939374 -38.650672)
		(width 0.14224)
		(layer "In4.Cu")
		(net "M_B_DQS_DP<10>")
	)
	(segment
		(start 208.62163 -14.968474)
		(end 209.605626 -15.95247)
		(width 0.14224)
		(layer "In4.Cu")
		(net "M_B_DQS_DP<10>")
	)
	(segment
		(start 213.729062 -37.9222)
		(end 214.337646 -37.313616)
		(width 0.14224)
		(layer "In4.Cu")
		(net "M_B_DQS_DP<10>")
	)
	(segment
		(start 209.120994 -10.947908)
		(end 209.120994 -11.286236)
		(width 0.14224)
		(layer "In4.Cu")
		(net "M_B_DQS_DP<10>")
	)
	(segment
		(start 213.939374 -38.650672)
		(end 213.939374 -39.09314)
		(width 0.14224)
		(layer "In4.Cu")
		(net "M_B_DQS_DP<10>")
	)
	(segment
		(start 209.605626 -26.285952)
		(end 210.21548 -26.895806)
		(width 0.14224)
		(layer "In4.Cu")
		(net "M_B_DQS_DP<10>")
	)
	(segment
		(start 209.27695 -10.1854)
		(end 209.40395 -10.1854)
		(width 0.14224)
		(layer "In4.Cu")
		(net "M_B_DQS_DP<10>")
	)
	(segment
		(start 209.248502 -10.8204)
		(end 209.120994 -10.947908)
		(width 0.14224)
		(layer "In4.Cu")
		(net "M_B_DQS_DP<10>")
	)
	(segment
		(start 209.61223 -10.39368)
		(end 209.61223 -10.63752)
		(width 0.14224)
		(layer "In4.Cu")
		(net "M_B_DQS_DP<10>")
	)
	(segment
		(start 230.937816 -57.002426)
		(end 230.993696 -57.002426)
		(width 0.0889)
		(layer "In4.Cu")
		(net "M_B_DQS_DP<10>")
	)
	(segment
		(start 231.372664 -57.381394)
		(end 231.372664 -57.789318)
		(width 0.0889)
		(layer "In4.Cu")
		(net "M_B_DQS_DP<10>")
	)
	(segment
		(start 209.277458 -11.4427)
		(end 209.36585 -11.4427)
		(width 0.14224)
		(layer "In4.Cu")
		(net "M_B_DQS_DP<10>")
	)
	(segment
		(start 214.337646 -37.313616)
		(end 214.516716 -37.313616)
		(width 0.14224)
		(layer "In4.Cu")
		(net "M_B_DQS_DP<10>")
	)
	(segment
		(start 209.42935 -10.8204)
		(end 209.248502 -10.8204)
		(width 0.14224)
		(layer "In4.Cu")
		(net "M_B_DQS_DP<10>")
	)
	(segment
		(start 209.120994 -11.286236)
		(end 209.277458 -11.4427)
		(width 0.14224)
		(layer "In4.Cu")
		(net "M_B_DQS_DP<10>")
	)
	(segment
		(start 209.61223 -10.63752)
		(end 209.42935 -10.8204)
		(width 0.14224)
		(layer "In4.Cu")
		(net "M_B_DQS_DP<10>")
	)
	(segment
		(start 209.61223 -9.29132)
		(end 209.12455 -9.779)
		(width 0.14224)
		(layer "In4.Cu")
		(net "M_B_DQS_DP<10>")
	)
	(segment
		(start 209.605626 -15.95247)
		(end 209.605626 -26.285952)
		(width 0.14224)
		(layer "In4.Cu")
		(net "M_B_DQS_DP<10>")
	)
	(segment
		(start 210.21548 -31.97098)
		(end 212.02396 -33.77946)
		(width 0.14224)
		(layer "In4.Cu")
		(net "M_B_DQS_DP<10>")
	)
	(segment
		(start 212.768434 -37.9222)
		(end 213.729062 -37.9222)
		(width 0.14224)
		(layer "In4.Cu")
		(net "M_B_DQS_DP<10>")
	)
	(segment
		(start 231.734868 -58.151522)
		(end 231.891332 -58.151522)
		(width 0.0889)
		(layer "In4.Cu")
		(net "M_B_DQS_DP<10>")
	)
	(segment
		(start 234.732068 -62.619636)
		(end 234.764834 -62.619636)
		(width 0.0889)
		(layer "In4.Cu")
		(net "M_B_DQS_DP<10>")
	)
	(segment
		(start 233.873548 -62.124336)
		(end 233.906314 -62.124336)
		(width 0.0889)
		(layer "In4.Cu")
		(net "M_B_DQS_DP<10>")
	)
	(segment
		(start 209.61223 -8.455914)
		(end 209.61223 -9.29132)
		(width 0.14224)
		(layer "In4.Cu")
		(net "M_B_DQS_DP<10>")
	)
	(segment
		(start 230.993696 -57.002426)
		(end 231.372664 -57.381394)
		(width 0.0889)
		(layer "In4.Cu")
		(net "M_B_DQS_DP<10>")
	)
	(segment
		(start 213.939374 -39.09314)
		(end 230.07066 -55.224426)
		(width 0.14224)
		(layer "In4.Cu")
		(net "M_B_DQS_DP<10>")
	)
	(segment
		(start 209.40395 -10.1854)
		(end 209.61223 -10.39368)
		(width 0.14224)
		(layer "In4.Cu")
		(net "M_B_DQS_DP<10>")
	)
	(segment
		(start 209.12455 -9.779)
		(end 209.12455 -10.033)
		(width 0.14224)
		(layer "In4.Cu")
		(net "M_B_DQS_DP<10>")
	)
	(segment
		(start 210.21548 -26.895806)
		(end 210.21548 -31.97098)
		(width 0.14224)
		(layer "In4.Cu")
		(net "M_B_DQS_DP<10>")
	)
	(segment
		(start 230.07066 -55.224426)
		(end 230.07066 -56.13527)
		(width 0.14224)
		(layer "In4.Cu")
		(net "M_B_DQS_DP<10>")
	)
	(segment
		(start 209.431636 -8.27532)
		(end 209.61223 -8.455914)
		(width 0.14224)
		(layer "In4.Cu")
		(net "M_B_DQS_DP<10>")
	)
	(segment
		(start 209.61223 -12.332462)
		(end 209.371692 -12.573)
		(width 0.14224)
		(layer "In4.Cu")
		(net "M_B_DQS_DP<10>")
	)
	(segment
		(start 230.07066 -56.13527)
		(end 230.922068 -56.986678)
		(width 0.14224)
		(layer "In4.Cu")
		(net "M_B_DQS_DP<10>")
	)
	(segment
		(start 212.02396 -33.77946)
		(end 212.02396 -37.177726)
		(width 0.14224)
		(layer "In4.Cu")
		(net "M_B_DQS_DP<10>")
	)
	(segment
		(start 209.300572 -8.27532)
		(end 209.431636 -8.27532)
		(width 0.14224)
		(layer "In4.Cu")
		(net "M_B_DQS_DP<10>")
	)
	(segment
		(start 209.092546 -12.573)
		(end 208.62163 -13.043916)
		(width 0.14224)
		(layer "In4.Cu")
		(net "M_B_DQS_DP<10>")
	)
	(segment
		(start 209.12455 -10.033)
		(end 209.27695 -10.1854)
		(width 0.14224)
		(layer "In4.Cu")
		(net "M_B_DQS_DP<10>")
	)
	(segment
		(start 233.135678 -59.395868)
		(end 233.383328 -59.834018)
		(width 0.0889)
		(layer "In4.Cu")
		(net "M_B_DQS_DP<10>")
	)
	(segment
		(start 212.02396 -37.177726)
		(end 212.768434 -37.9222)
		(width 0.14224)
		(layer "In4.Cu")
		(net "M_B_DQS_DP<10>")
	)
	(segment
		(start 209.092546 -8.483346)
		(end 209.300572 -8.27532)
		(width 0.14224)
		(layer "In4.Cu")
		(net "M_B_DQS_DP<10>")
	)
	(segment
		(start 209.36585 -11.4427)
		(end 209.61223 -11.68908)
		(width 0.14224)
		(layer "In4.Cu")
		(net "M_B_DQS_DP<10>")
	)
	(segment
		(start 209.371692 -12.573)
		(end 209.092546 -12.573)
		(width 0.14224)
		(layer "In4.Cu")
		(net "M_B_DQS_DP<10>")
	)
	(segment
		(start 208.62163 -13.043916)
		(end 208.62163 -14.968474)
		(width 0.14224)
		(layer "In4.Cu")
		(net "M_B_DQS_DP<10>")
	)
	(segment
		(start 214.516716 -37.313616)
		(end 214.807038 -37.603938)
		(width 0.14224)
		(layer "In4.Cu")
		(net "M_B_DQS_DP<10>")
	)
	(segment
		(start 209.61223 -11.68908)
		(end 209.61223 -12.332462)
		(width 0.14224)
		(layer "In4.Cu")
		(net "M_B_DQS_DP<10>")
	)
	(segment
		(start 230.922068 -56.986678)
		(end 230.937816 -57.002426)
		(width 0.0889)
		(layer "In4.Cu")
		(net "M_B_DQS_DP<10>")
	)
	(segment
		(start 231.891332 -58.151522)
		(end 233.135678 -59.395868)
		(width 0.0889)
		(layer "In4.Cu")
		(net "M_B_DQS_DP<10>")
	)
	(segment
		(start 214.807038 -37.603938)
		(end 214.807038 -37.783008)
		(width 0.14224)
		(layer "In4.Cu")
		(net "M_B_DQS_DP<10>")
	)
	(arc
		(start 233.383328 -60.838588)
		(mid 233.436827 -61.038486)
		(end 233.383328 -61.238384)
		(width 0.0889)
		(layer "In4.Cu")
		(net "M_B_DQS_DP<10>")
	)
	(arc
		(start 234.241848 -62.324488)
		(mid 234.448852 -62.535352)
		(end 234.732068 -62.619636)
		(width 0.0889)
		(layer "In4.Cu")
		(net "M_B_DQS_DP<10>")
	)
	(arc
		(start 234.99826 -62.702948)
		(mid 235.228416 -62.798374)
		(end 235.458508 -62.893956)
		(width 0.0889)
		(layer "In4.Cu")
		(net "M_B_DQS_DP<10>")
	)
	(arc
		(start 233.906314 -62.124336)
		(mid 234.101653 -62.17818)
		(end 234.241848 -62.324488)
		(width 0.0889)
		(layer "In4.Cu")
		(net "M_B_DQS_DP<10>")
	)
	(arc
		(start 234.764834 -62.619636)
		(mid 234.841401 -62.629267)
		(end 234.914694 -62.653418)
		(width 0.0889)
		(layer "In4.Cu")
		(net "M_B_DQS_DP<10>")
	)
	(arc
		(start 233.383328 -61.238384)
		(mid 233.378074 -61.819892)
		(end 233.873548 -62.124336)
		(width 0.0889)
		(layer "In4.Cu")
		(net "M_B_DQS_DP<10>")
	)
	(arc
		(start 233.383328 -59.834018)
		(mid 233.440426 -60.040919)
		(end 233.383328 -60.247784)
		(width 0.0889)
		(layer "In4.Cu")
		(net "M_B_DQS_DP<10>")
	)
	(arc
		(start 235.458508 -62.893956)
		(mid 235.740688 -62.90344)
		(end 235.958888 -62.724284)
		(width 0.0889)
		(layer "In4.Cu")
		(net "M_B_DQS_DP<10>")
	)
	(arc
		(start 235.958888 -62.724284)
		(mid 236.195376 -62.36239)
		(end 236.470698 -62.029086)
		(width 0.0889)
		(layer "In4.Cu")
		(net "M_B_DQS_DP<10>")
	)
	(arc
		(start 233.383328 -60.247784)
		(mid 233.304197 -60.543186)
		(end 233.383328 -60.838588)
		(width 0.0889)
		(layer "In4.Cu")
		(net "M_B_DQS_DP<10>")
	)
	(arc
		(start 234.914694 -62.653418)
		(mid 234.957985 -62.675639)
		(end 234.99826 -62.702948)
		(width 0.0889)
		(layer "In4.Cu")
		(net "M_B_DQS_DP<10>")
	)
	(segment
		(start 201.721466 -9.10209)
		(end 201.500486 -9.32307)
		(width 0.1651)
		(layer "F.Cu")
		(net "M_B_DQS_DP<0>")
	)
	(segment
		(start 201.037952 -8.419846)
		(end 201.311764 -8.146034)
		(width 0.1651)
		(layer "F.Cu")
		(net "M_B_DQS_DP<0>")
	)
	(segment
		(start 201.721466 -8.359902)
		(end 201.721466 -9.10209)
		(width 0.1651)
		(layer "F.Cu")
		(net "M_B_DQS_DP<0>")
	)
	(segment
		(start 201.507598 -8.146034)
		(end 201.721466 -8.359902)
		(width 0.1651)
		(layer "F.Cu")
		(net "M_B_DQS_DP<0>")
	)
	(segment
		(start 237.900718 -66.48704)
		(end 237.329218 -66.48704)
		(width 0.0889)
		(layer "F.Cu")
		(net "M_B_DQS_DP<0>")
	)
	(segment
		(start 201.311764 -8.146034)
		(end 201.507598 -8.146034)
		(width 0.1651)
		(layer "F.Cu")
		(net "M_B_DQS_DP<0>")
	)
	(segment
		(start 201.500486 -9.32307)
		(end 201.500486 -10.422382)
		(width 0.1651)
		(layer "F.Cu")
		(net "M_B_DQS_DP<0>")
	)
	(via
		(at 201.037952 -12.627356)
		(size 0.508)
		(drill 0.254)
		(layers "F.Cu" "B.Cu")
		(net "M_B_DQS_DP<0>")
	)
	(via
		(at 237.329218 -66.48704)
		(size 0.508)
		(drill 0.254)
		(layers "F.Cu" "B.Cu")
		(net "M_B_DQS_DP<0>")
	)
	(via
		(at 201.037952 -8.419846)
		(size 0.508)
		(drill 0.254)
		(layers "F.Cu" "B.Cu")
		(net "M_B_DQS_DP<0>")
	)
	(segment
		(start 201.499724 -12.139168)
		(end 201.679556 -12.319)
		(width 0.1651)
		(layer "B.Cu")
		(net "M_B_DQS_DP<0>")
	)
	(segment
		(start 201.499978 -10.972546)
		(end 201.499724 -10.9728)
		(width 0.1651)
		(layer "B.Cu")
		(net "M_B_DQS_DP<0>")
	)
	(segment
		(start 201.679556 -12.76858)
		(end 201.539856 -12.90828)
		(width 0.1651)
		(layer "B.Cu")
		(net "M_B_DQS_DP<0>")
	)
	(segment
		(start 201.679556 -12.319)
		(end 201.679556 -12.76858)
		(width 0.1651)
		(layer "B.Cu")
		(net "M_B_DQS_DP<0>")
	)
	(segment
		(start 201.318876 -12.90828)
		(end 201.037952 -12.627356)
		(width 0.1651)
		(layer "B.Cu")
		(net "M_B_DQS_DP<0>")
	)
	(segment
		(start 201.500486 -10.623042)
		(end 201.499978 -10.623042)
		(width 0.1651)
		(layer "B.Cu")
		(net "M_B_DQS_DP<0>")
	)
	(segment
		(start 201.499724 -10.9728)
		(end 201.499724 -12.139168)
		(width 0.1651)
		(layer "B.Cu")
		(net "M_B_DQS_DP<0>")
	)
	(segment
		(start 201.539856 -12.90828)
		(end 201.318876 -12.90828)
		(width 0.1651)
		(layer "B.Cu")
		(net "M_B_DQS_DP<0>")
	)
	(segment
		(start 201.499978 -10.623042)
		(end 201.499978 -10.972546)
		(width 0.1651)
		(layer "B.Cu")
		(net "M_B_DQS_DP<0>")
	)
	(segment
		(start 201.037952 -12.62761)
		(end 201.316844 -12.62761)
		(width 0.14224)
		(layer "In4.Cu")
		(net "M_B_DQS_DP<0>")
	)
	(segment
		(start 201.374502 -10.1346)
		(end 201.19721 -10.1346)
		(width 0.14224)
		(layer "In4.Cu")
		(net "M_B_DQS_DP<0>")
	)
	(segment
		(start 201.319638 -8.419846)
		(end 201.037952 -8.419846)
		(width 0.14224)
		(layer "In4.Cu")
		(net "M_B_DQS_DP<0>")
	)
	(segment
		(start 201.19721 -10.1346)
		(end 201.044556 -9.981946)
		(width 0.14224)
		(layer "In4.Cu")
		(net "M_B_DQS_DP<0>")
	)
	(segment
		(start 237.344204 -66.08699)
		(end 237.314232 -66.08699)
		(width 0.0889)
		(layer "In4.Cu")
		(net "M_B_DQS_DP<0>")
	)
	(segment
		(start 201.037952 -12.627356)
		(end 201.037952 -12.62761)
		(width 0.14224)
		(layer "In4.Cu")
		(net "M_B_DQS_DP<0>")
	)
	(segment
		(start 201.551032 -26.325068)
		(end 201.97826 -25.89784)
		(width 0.14224)
		(layer "In4.Cu")
		(net "M_B_DQS_DP<0>")
	)
	(segment
		(start 200.604882 -15.142464)
		(end 200.604882 -13.060426)
		(width 0.14224)
		(layer "In4.Cu")
		(net "M_B_DQS_DP<0>")
	)
	(segment
		(start 235.625894 -67.07759)
		(end 235.597192 -67.07759)
		(width 0.0889)
		(layer "In4.Cu")
		(net "M_B_DQS_DP<0>")
	)
	(segment
		(start 220.41104 -55.74284)
		(end 219.73794 -55.74284)
		(width 0.14224)
		(layer "In4.Cu")
		(net "M_B_DQS_DP<0>")
	)
	(segment
		(start 219.73794 -55.74284)
		(end 205.53426 -41.53916)
		(width 0.14224)
		(layer "In4.Cu")
		(net "M_B_DQS_DP<0>")
	)
	(segment
		(start 201.329544 -35.773106)
		(end 200.941686 -35.773106)
		(width 0.14224)
		(layer "In4.Cu")
		(net "M_B_DQS_DP<0>")
	)
	(segment
		(start 201.3966 -10.8712)
		(end 201.57948 -10.68832)
		(width 0.14224)
		(layer "In4.Cu")
		(net "M_B_DQS_DP<0>")
	)
	(segment
		(start 201.400156 -11.4808)
		(end 201.2696 -11.4808)
		(width 0.14224)
		(layer "In4.Cu")
		(net "M_B_DQS_DP<0>")
	)
	(segment
		(start 200.941686 -35.773106)
		(end 200.56348 -35.3949)
		(width 0.14224)
		(layer "In4.Cu")
		(net "M_B_DQS_DP<0>")
	)
	(segment
		(start 201.316844 -12.62761)
		(end 201.57948 -12.364974)
		(width 0.14224)
		(layer "In4.Cu")
		(net "M_B_DQS_DP<0>")
	)
	(segment
		(start 233.047794 -66.582036)
		(end 232.833418 -66.582036)
		(width 0.0889)
		(layer "In4.Cu")
		(net "M_B_DQS_DP<0>")
	)
	(segment
		(start 201.2696 -11.4808)
		(end 201.09688 -11.30808)
		(width 0.14224)
		(layer "In4.Cu")
		(net "M_B_DQS_DP<0>")
	)
	(segment
		(start 201.57948 -10.68832)
		(end 201.57948 -10.339578)
		(width 0.14224)
		(layer "In4.Cu")
		(net "M_B_DQS_DP<0>")
	)
	(segment
		(start 200.978262 -37.211508)
		(end 200.978262 -36.808664)
		(width 0.14224)
		(layer "In4.Cu")
		(net "M_B_DQS_DP<0>")
	)
	(segment
		(start 201.97826 -25.240488)
		(end 201.551032 -24.81326)
		(width 0.14224)
		(layer "In4.Cu")
		(net "M_B_DQS_DP<0>")
	)
	(segment
		(start 200.56348 -35.3949)
		(end 200.56348 -34.535872)
		(width 0.14224)
		(layer "In4.Cu")
		(net "M_B_DQS_DP<0>")
	)
	(segment
		(start 201.551032 -36.235894)
		(end 201.551032 -35.994594)
		(width 0.14224)
		(layer "In4.Cu")
		(net "M_B_DQS_DP<0>")
	)
	(segment
		(start 231.5083 -66.12636)
		(end 231.486202 -66.12636)
		(width 0.0889)
		(layer "In4.Cu")
		(net "M_B_DQS_DP<0>")
	)
	(segment
		(start 201.911204 -38.14445)
		(end 200.978262 -37.211508)
		(width 0.14224)
		(layer "In4.Cu")
		(net "M_B_DQS_DP<0>")
	)
	(segment
		(start 201.551032 -16.088614)
		(end 200.604882 -15.142464)
		(width 0.14224)
		(layer "In4.Cu")
		(net "M_B_DQS_DP<0>")
	)
	(segment
		(start 201.399902 -9.525)
		(end 201.57948 -9.345422)
		(width 0.14224)
		(layer "In4.Cu")
		(net "M_B_DQS_DP<0>")
	)
	(segment
		(start 200.56348 -34.535872)
		(end 200.941686 -34.157666)
		(width 0.14224)
		(layer "In4.Cu")
		(net "M_B_DQS_DP<0>")
	)
	(segment
		(start 236.492288 -66.582036)
		(end 236.459522 -66.582036)
		(width 0.0889)
		(layer "In4.Cu")
		(net "M_B_DQS_DP<0>")
	)
	(segment
		(start 233.910124 -67.07759)
		(end 233.877358 -67.07759)
		(width 0.0889)
		(layer "In4.Cu")
		(net "M_B_DQS_DP<0>")
	)
	(segment
		(start 231.486202 -66.12636)
		(end 230.45674 -66.12636)
		(width 0.14224)
		(layer "In4.Cu")
		(net "M_B_DQS_DP<0>")
	)
	(segment
		(start 201.57948 -12.364974)
		(end 201.57948 -11.660124)
		(width 0.14224)
		(layer "In4.Cu")
		(net "M_B_DQS_DP<0>")
	)
	(segment
		(start 232.268776 -66.08699)
		(end 231.54767 -66.08699)
		(width 0.0889)
		(layer "In4.Cu")
		(net "M_B_DQS_DP<0>")
	)
	(segment
		(start 201.044556 -9.677654)
		(end 201.19721 -9.525)
		(width 0.14224)
		(layer "In4.Cu")
		(net "M_B_DQS_DP<0>")
	)
	(segment
		(start 230.45674 -66.12636)
		(end 226.73056 -62.40018)
		(width 0.14224)
		(layer "In4.Cu")
		(net "M_B_DQS_DP<0>")
	)
	(segment
		(start 201.2696 -10.8712)
		(end 201.3966 -10.8712)
		(width 0.14224)
		(layer "In4.Cu")
		(net "M_B_DQS_DP<0>")
	)
	(segment
		(start 234.775248 -67.572636)
		(end 234.732068 -67.572636)
		(width 0.0889)
		(layer "In4.Cu")
		(net "M_B_DQS_DP<0>")
	)
	(segment
		(start 201.551032 -33.936178)
		(end 201.551032 -29.33954)
		(width 0.14224)
		(layer "In4.Cu")
		(net "M_B_DQS_DP<0>")
	)
	(segment
		(start 201.57948 -9.345422)
		(end 201.57948 -8.679688)
		(width 0.14224)
		(layer "In4.Cu")
		(net "M_B_DQS_DP<0>")
	)
	(segment
		(start 205.53426 -41.53916)
		(end 205.53426 -39.65956)
		(width 0.14224)
		(layer "In4.Cu")
		(net "M_B_DQS_DP<0>")
	)
	(segment
		(start 201.97826 -25.89784)
		(end 201.97826 -25.240488)
		(width 0.14224)
		(layer "In4.Cu")
		(net "M_B_DQS_DP<0>")
	)
	(segment
		(start 201.09688 -11.04392)
		(end 201.2696 -10.8712)
		(width 0.14224)
		(layer "In4.Cu")
		(net "M_B_DQS_DP<0>")
	)
	(segment
		(start 204.01915 -38.14445)
		(end 201.911204 -38.14445)
		(width 0.14224)
		(layer "In4.Cu")
		(net "M_B_DQS_DP<0>")
	)
	(segment
		(start 201.19721 -9.525)
		(end 201.399902 -9.525)
		(width 0.14224)
		(layer "In4.Cu")
		(net "M_B_DQS_DP<0>")
	)
	(segment
		(start 237.329218 -66.48704)
		(end 237.622334 -66.317876)
		(width 0.0889)
		(layer "In4.Cu")
		(net "M_B_DQS_DP<0>")
	)
	(segment
		(start 201.044556 -9.981946)
		(end 201.044556 -9.677654)
		(width 0.14224)
		(layer "In4.Cu")
		(net "M_B_DQS_DP<0>")
	)
	(segment
		(start 200.941686 -34.157666)
		(end 201.329544 -34.157666)
		(width 0.14224)
		(layer "In4.Cu")
		(net "M_B_DQS_DP<0>")
	)
	(segment
		(start 201.57948 -11.660124)
		(end 201.400156 -11.4808)
		(width 0.14224)
		(layer "In4.Cu")
		(net "M_B_DQS_DP<0>")
	)
	(segment
		(start 237.622334 -66.317876)
		(end 237.643416 -66.239136)
		(width 0.0889)
		(layer "In4.Cu")
		(net "M_B_DQS_DP<0>")
	)
	(segment
		(start 200.604882 -13.060426)
		(end 201.037952 -12.627356)
		(width 0.14224)
		(layer "In4.Cu")
		(net "M_B_DQS_DP<0>")
	)
	(segment
		(start 226.73056 -62.40018)
		(end 226.73056 -62.06236)
		(width 0.14224)
		(layer "In4.Cu")
		(net "M_B_DQS_DP<0>")
	)
	(segment
		(start 201.329544 -34.157666)
		(end 201.551032 -33.936178)
		(width 0.14224)
		(layer "In4.Cu")
		(net "M_B_DQS_DP<0>")
	)
	(segment
		(start 201.09688 -11.30808)
		(end 201.09688 -11.04392)
		(width 0.14224)
		(layer "In4.Cu")
		(net "M_B_DQS_DP<0>")
	)
	(segment
		(start 201.551032 -35.994594)
		(end 201.329544 -35.773106)
		(width 0.14224)
		(layer "In4.Cu")
		(net "M_B_DQS_DP<0>")
	)
	(segment
		(start 201.90206 -28.047188)
		(end 201.551032 -27.69616)
		(width 0.14224)
		(layer "In4.Cu")
		(net "M_B_DQS_DP<0>")
	)
	(segment
		(start 201.551032 -27.69616)
		(end 201.551032 -26.325068)
		(width 0.14224)
		(layer "In4.Cu")
		(net "M_B_DQS_DP<0>")
	)
	(segment
		(start 205.53426 -39.65956)
		(end 204.01915 -38.14445)
		(width 0.14224)
		(layer "In4.Cu")
		(net "M_B_DQS_DP<0>")
	)
	(segment
		(start 201.90206 -28.988512)
		(end 201.90206 -28.047188)
		(width 0.14224)
		(layer "In4.Cu")
		(net "M_B_DQS_DP<0>")
	)
	(segment
		(start 201.551032 -24.81326)
		(end 201.551032 -16.088614)
		(width 0.14224)
		(layer "In4.Cu")
		(net "M_B_DQS_DP<0>")
	)
	(segment
		(start 200.978262 -36.808664)
		(end 201.551032 -36.235894)
		(width 0.14224)
		(layer "In4.Cu")
		(net "M_B_DQS_DP<0>")
	)
	(segment
		(start 201.57948 -8.679688)
		(end 201.319638 -8.419846)
		(width 0.14224)
		(layer "In4.Cu")
		(net "M_B_DQS_DP<0>")
	)
	(segment
		(start 231.54767 -66.08699)
		(end 231.5083 -66.12636)
		(width 0.0889)
		(layer "In4.Cu")
		(net "M_B_DQS_DP<0>")
	)
	(segment
		(start 201.551032 -29.33954)
		(end 201.90206 -28.988512)
		(width 0.14224)
		(layer "In4.Cu")
		(net "M_B_DQS_DP<0>")
	)
	(segment
		(start 201.57948 -10.339578)
		(end 201.374502 -10.1346)
		(width 0.14224)
		(layer "In4.Cu")
		(net "M_B_DQS_DP<0>")
	)
	(segment
		(start 226.73056 -62.06236)
		(end 220.41104 -55.74284)
		(width 0.14224)
		(layer "In4.Cu")
		(net "M_B_DQS_DP<0>")
	)
	(arc
		(start 236.123988 -66.782188)
		(mid 235.913635 -66.99516)
		(end 235.625894 -67.07759)
		(width 0.0889)
		(layer "In4.Cu")
		(net "M_B_DQS_DP<0>")
	)
	(arc
		(start 237.643416 -66.239136)
		(mid 237.510535 -66.130153)
		(end 237.344204 -66.08699)
		(width 0.0889)
		(layer "In4.Cu")
		(net "M_B_DQS_DP<0>")
	)
	(arc
		(start 233.877358 -67.07759)
		(mid 233.591934 -66.994123)
		(end 233.383328 -66.782188)
		(width 0.0889)
		(layer "In4.Cu")
		(net "M_B_DQS_DP<0>")
	)
	(arc
		(start 235.597192 -67.07759)
		(mid 235.40555 -67.134756)
		(end 235.265468 -67.277488)
		(width 0.0889)
		(layer "In4.Cu")
		(net "M_B_DQS_DP<0>")
	)
	(arc
		(start 235.265468 -67.277488)
		(mid 235.058464 -67.488352)
		(end 234.775248 -67.572636)
		(width 0.0889)
		(layer "In4.Cu")
		(net "M_B_DQS_DP<0>")
	)
	(arc
		(start 234.732068 -67.572636)
		(mid 234.448851 -67.488355)
		(end 234.241848 -67.277488)
		(width 0.0889)
		(layer "In4.Cu")
		(net "M_B_DQS_DP<0>")
	)
	(arc
		(start 236.459522 -66.582036)
		(mid 236.265672 -66.638386)
		(end 236.123988 -66.782188)
		(width 0.0889)
		(layer "In4.Cu")
		(net "M_B_DQS_DP<0>")
	)
	(arc
		(start 233.383328 -66.782188)
		(mid 233.241645 -66.638384)
		(end 233.047794 -66.582036)
		(width 0.0889)
		(layer "In4.Cu")
		(net "M_B_DQS_DP<0>")
	)
	(arc
		(start 232.48493 -66.284094)
		(mid 232.393986 -66.166751)
		(end 232.268776 -66.08699)
		(width 0.0889)
		(layer "In4.Cu")
		(net "M_B_DQS_DP<0>")
	)
	(arc
		(start 237.314232 -66.08699)
		(mid 237.12259 -66.144156)
		(end 236.982508 -66.286888)
		(width 0.0889)
		(layer "In4.Cu")
		(net "M_B_DQS_DP<0>")
	)
	(arc
		(start 234.241848 -67.277488)
		(mid 234.101769 -67.134752)
		(end 233.910124 -67.07759)
		(width 0.0889)
		(layer "In4.Cu")
		(net "M_B_DQS_DP<0>")
	)
	(arc
		(start 236.982508 -66.286888)
		(mid 236.775504 -66.497752)
		(end 236.492288 -66.582036)
		(width 0.0889)
		(layer "In4.Cu")
		(net "M_B_DQS_DP<0>")
	)
	(arc
		(start 232.833418 -66.582036)
		(mid 232.630824 -66.466218)
		(end 232.48493 -66.284094)
		(width 0.0889)
		(layer "In4.Cu")
		(net "M_B_DQS_DP<0>")
	)
	(segment
		(start 200.64984 -5.822442)
		(end 200.64984 -6.66496)
		(width 0.1651)
		(layer "F.Cu")
		(net "M_B_DQS_DN<9>")
	)
	(segment
		(start 200.64984 -6.66496)
		(end 200.231756 -7.083044)
		(width 0.1651)
		(layer "F.Cu")
		(net "M_B_DQS_DN<9>")
	)
	(segment
		(start 200.231756 -7.083044)
		(end 200.231756 -7.3152)
		(width 0.1651)
		(layer "F.Cu")
		(net "M_B_DQS_DN<9>")
	)
	(segment
		(start 236.183678 -67.47764)
		(end 235.612178 -67.47764)
		(width 0.0889)
		(layer "F.Cu")
		(net "M_B_DQS_DN<9>")
	)
	(segment
		(start 199.938386 -7.99973)
		(end 199.749156 -7.8105)
		(width 0.1651)
		(layer "F.Cu")
		(net "M_B_DQS_DN<9>")
	)
	(segment
		(start 200.417684 -7.501128)
		(end 200.417684 -7.747762)
		(width 0.1651)
		(layer "F.Cu")
		(net "M_B_DQS_DN<9>")
	)
	(segment
		(start 200.417684 -7.747762)
		(end 200.165716 -7.99973)
		(width 0.1651)
		(layer "F.Cu")
		(net "M_B_DQS_DN<9>")
	)
	(segment
		(start 200.650348 -5.822442)
		(end 200.64984 -5.822442)
		(width 0.1651)
		(layer "F.Cu")
		(net "M_B_DQS_DN<9>")
	)
	(segment
		(start 200.165716 -7.99973)
		(end 199.938386 -7.99973)
		(width 0.1651)
		(layer "F.Cu")
		(net "M_B_DQS_DN<9>")
	)
	(segment
		(start 200.231756 -7.3152)
		(end 200.417684 -7.501128)
		(width 0.1651)
		(layer "F.Cu")
		(net "M_B_DQS_DN<9>")
	)
	(via
		(at 199.742552 -13.2334)
		(size 0.508)
		(drill 0.254)
		(layers "F.Cu" "B.Cu")
		(net "M_B_DQS_DN<9>")
	)
	(via
		(at 235.612178 -67.47764)
		(size 0.508)
		(drill 0.254)
		(layers "F.Cu" "B.Cu")
		(net "M_B_DQS_DN<9>")
	)
	(via
		(at 199.749156 -7.8105)
		(size 0.508)
		(drill 0.254)
		(layers "F.Cu" "B.Cu")
		(net "M_B_DQS_DN<9>")
	)
	(segment
		(start 200.164192 -13.038836)
		(end 199.937116 -13.038836)
		(width 0.1651)
		(layer "B.Cu")
		(net "M_B_DQS_DN<9>")
	)
	(segment
		(start 200.650348 -15.222982)
		(end 200.64984 -15.222982)
		(width 0.1651)
		(layer "B.Cu")
		(net "M_B_DQS_DN<9>")
	)
	(segment
		(start 200.64984 -14.566138)
		(end 200.206356 -14.122654)
		(width 0.1651)
		(layer "B.Cu")
		(net "M_B_DQS_DN<9>")
	)
	(segment
		(start 200.64984 -15.222982)
		(end 200.64984 -14.566138)
		(width 0.1651)
		(layer "B.Cu")
		(net "M_B_DQS_DN<9>")
	)
	(segment
		(start 200.384156 -13.589)
		(end 200.384156 -13.2588)
		(width 0.1651)
		(layer "B.Cu")
		(net "M_B_DQS_DN<9>")
	)
	(segment
		(start 199.937116 -13.038836)
		(end 199.742552 -13.2334)
		(width 0.1651)
		(layer "B.Cu")
		(net "M_B_DQS_DN<9>")
	)
	(segment
		(start 200.206356 -14.122654)
		(end 200.206356 -13.7668)
		(width 0.1651)
		(layer "B.Cu")
		(net "M_B_DQS_DN<9>")
	)
	(segment
		(start 200.384156 -13.2588)
		(end 200.164192 -13.038836)
		(width 0.1651)
		(layer "B.Cu")
		(net "M_B_DQS_DN<9>")
	)
	(segment
		(start 200.206356 -13.7668)
		(end 200.384156 -13.589)
		(width 0.1651)
		(layer "B.Cu")
		(net "M_B_DQS_DN<9>")
	)
	(segment
		(start 230.693468 -66.88709)
		(end 232.158286 -66.88709)
		(width 0.0889)
		(layer "In4.Cu")
		(net "M_B_DQS_DN<9>")
	)
	(segment
		(start 200.682352 -20.8788)
		(end 200.524872 -21.03628)
		(width 0.14224)
		(layer "In4.Cu")
		(net "M_B_DQS_DN<9>")
	)
	(segment
		(start 228.710998 -65.151508)
		(end 228.710998 -65.313052)
		(width 0.14224)
		(layer "In4.Cu")
		(net "M_B_DQS_DN<9>")
	)
	(segment
		(start 227.418392 -63.858902)
		(end 227.418392 -64.020446)
		(width 0.14224)
		(layer "In4.Cu")
		(net "M_B_DQS_DN<9>")
	)
	(segment
		(start 225.075242 -61.677296)
		(end 225.236786 -61.677296)
		(width 0.14224)
		(layer "In4.Cu")
		(net "M_B_DQS_DN<9>")
	)
	(segment
		(start 200.75652 -32.329374)
		(end 200.75652 -33.188402)
		(width 0.14224)
		(layer "In4.Cu")
		(net "M_B_DQS_DN<9>")
	)
	(segment
		(start 200.524872 -23.74392)
		(end 200.682352 -23.9014)
		(width 0.14224)
		(layer "In4.Cu")
		(net "M_B_DQS_DN<9>")
	)
	(segment
		(start 223.298004 -59.738514)
		(end 223.540574 -59.981084)
		(width 0.14224)
		(layer "In4.Cu")
		(net "M_B_DQS_DN<9>")
	)
	(segment
		(start 200.682352 -20.6248)
		(end 200.682352 -20.8788)
		(width 0.14224)
		(layer "In4.Cu")
		(net "M_B_DQS_DN<9>")
	)
	(segment
		(start 220.551248 -57.153302)
		(end 220.712792 -57.153302)
		(width 0.14224)
		(layer "In4.Cu")
		(net "M_B_DQS_DN<9>")
	)
	(segment
		(start 229.357174 -65.797684)
		(end 229.357174 -65.959228)
		(width 0.14224)
		(layer "In4.Cu")
		(net "M_B_DQS_DN<9>")
	)
	(segment
		(start 200.75652 -33.188402)
		(end 199.86752 -34.077402)
		(width 0.14224)
		(layer "In4.Cu")
		(net "M_B_DQS_DN<9>")
	)
	(segment
		(start 199.96912 -28.359354)
		(end 199.96912 -28.824174)
		(width 0.14224)
		(layer "In4.Cu")
		(net "M_B_DQS_DN<9>")
	)
	(segment
		(start 200.378314 -30.874208)
		(end 200.089008 -30.874208)
		(width 0.14224)
		(layer "In4.Cu")
		(net "M_B_DQS_DN<9>")
	)
	(segment
		(start 228.064568 -64.666622)
		(end 228.306884 -64.908938)
		(width 0.14224)
		(layer "In4.Cu")
		(net "M_B_DQS_DN<9>")
	)
	(segment
		(start 222.894144 -59.334654)
		(end 222.894144 -59.496198)
		(width 0.14224)
		(layer "In4.Cu")
		(net "M_B_DQS_DN<9>")
	)
	(segment
		(start 199.742552 -13.2334)
		(end 200.193656 -13.684504)
		(width 0.14224)
		(layer "In4.Cu")
		(net "M_B_DQS_DN<9>")
	)
	(segment
		(start 222.894144 -59.496198)
		(end 223.13646 -59.738514)
		(width 0.14224)
		(layer "In4.Cu")
		(net "M_B_DQS_DN<9>")
	)
	(segment
		(start 221.601538 -58.042048)
		(end 221.601538 -58.203592)
		(width 0.14224)
		(layer "In4.Cu")
		(net "M_B_DQS_DN<9>")
	)
	(segment
		(start 230.003604 -66.444114)
		(end 230.003604 -66.605658)
		(width 0.14224)
		(layer "In4.Cu")
		(net "M_B_DQS_DN<9>")
	)
	(segment
		(start 229.59949 -66.201544)
		(end 229.761034 -66.201544)
		(width 0.14224)
		(layer "In4.Cu")
		(net "M_B_DQS_DN<9>")
	)
	(segment
		(start 228.95306 -65.555114)
		(end 229.114604 -65.555114)
		(width 0.14224)
		(layer "In4.Cu")
		(net "M_B_DQS_DN<9>")
	)
	(segment
		(start 229.114604 -65.555114)
		(end 229.357174 -65.797684)
		(width 0.14224)
		(layer "In4.Cu")
		(net "M_B_DQS_DN<9>")
	)
	(segment
		(start 222.247968 -58.688478)
		(end 222.247968 -58.850022)
		(width 0.14224)
		(layer "In4.Cu")
		(net "M_B_DQS_DN<9>")
	)
	(segment
		(start 227.175822 -63.616332)
		(end 227.418392 -63.858902)
		(width 0.14224)
		(layer "In4.Cu")
		(net "M_B_DQS_DN<9>")
	)
	(segment
		(start 200.531476 -12.444476)
		(end 199.742552 -13.2334)
		(width 0.14224)
		(layer "In4.Cu")
		(net "M_B_DQS_DN<9>")
	)
	(segment
		(start 200.524872 -20.27428)
		(end 200.524872 -20.46732)
		(width 0.14224)
		(layer "In4.Cu")
		(net "M_B_DQS_DN<9>")
	)
	(segment
		(start 199.86752 -34.077402)
		(end 199.86752 -36.913566)
		(width 0.14224)
		(layer "In4.Cu")
		(net "M_B_DQS_DN<9>")
	)
	(segment
		(start 200.524872 -21.03628)
		(end 200.524872 -23.74392)
		(width 0.14224)
		(layer "In4.Cu")
		(net "M_B_DQS_DN<9>")
	)
	(segment
		(start 224.18675 -60.62726)
		(end 224.18675 -60.788804)
		(width 0.14224)
		(layer "In4.Cu")
		(net "M_B_DQS_DN<9>")
	)
	(segment
		(start 223.540574 -59.981084)
		(end 223.540574 -60.142628)
		(width 0.14224)
		(layer "In4.Cu")
		(net "M_B_DQS_DN<9>")
	)
	(segment
		(start 221.601538 -58.203592)
		(end 221.843854 -58.445908)
		(width 0.14224)
		(layer "In4.Cu")
		(net "M_B_DQS_DN<9>")
	)
	(segment
		(start 234.738672 -68.372736)
		(end 234.768644 -68.372736)
		(width 0.0889)
		(layer "In4.Cu")
		(net "M_B_DQS_DN<9>")
	)
	(segment
		(start 200.682352 -20.1168)
		(end 200.524872 -20.27428)
		(width 0.14224)
		(layer "In4.Cu")
		(net "M_B_DQS_DN<9>")
	)
	(segment
		(start 199.540876 -15.109952)
		(end 200.524872 -16.093948)
		(width 0.14224)
		(layer "In4.Cu")
		(net "M_B_DQS_DN<9>")
	)
	(segment
		(start 199.723756 -14.4018)
		(end 199.540876 -14.58468)
		(width 0.14224)
		(layer "In4.Cu")
		(net "M_B_DQS_DN<9>")
	)
	(segment
		(start 219.405454 -56.4515)
		(end 219.849446 -56.4515)
		(width 0.14224)
		(layer "In4.Cu")
		(net "M_B_DQS_DN<9>")
	)
	(segment
		(start 226.125786 -62.72784)
		(end 226.367848 -62.969902)
		(width 0.14224)
		(layer "In4.Cu")
		(net "M_B_DQS_DN<9>")
	)
	(segment
		(start 200.531476 -8.343392)
		(end 200.531476 -12.444476)
		(width 0.14224)
		(layer "In4.Cu")
		(net "M_B_DQS_DN<9>")
	)
	(segment
		(start 227.418392 -64.020446)
		(end 227.660454 -64.262508)
		(width 0.14224)
		(layer "In4.Cu")
		(net "M_B_DQS_DN<9>")
	)
	(segment
		(start 230.245666 -66.84772)
		(end 230.632 -66.84772)
		(width 0.14224)
		(layer "In4.Cu")
		(net "M_B_DQS_DN<9>")
	)
	(segment
		(start 228.064568 -64.505078)
		(end 228.064568 -64.666622)
		(width 0.14224)
		(layer "In4.Cu")
		(net "M_B_DQS_DN<9>")
	)
	(segment
		(start 233.883962 -67.87769)
		(end 233.916728 -67.87769)
		(width 0.0889)
		(layer "In4.Cu")
		(net "M_B_DQS_DN<9>")
	)
	(segment
		(start 222.49003 -59.092084)
		(end 222.651574 -59.092084)
		(width 0.14224)
		(layer "In4.Cu")
		(net "M_B_DQS_DN<9>")
	)
	(segment
		(start 224.59061 -61.03112)
		(end 224.83318 -61.27369)
		(width 0.14224)
		(layer "In4.Cu")
		(net "M_B_DQS_DN<9>")
	)
	(segment
		(start 199.86752 -31.72968)
		(end 200.089008 -31.951168)
		(width 0.14224)
		(layer "In4.Cu")
		(net "M_B_DQS_DN<9>")
	)
	(segment
		(start 226.125786 -62.566296)
		(end 226.125786 -62.72784)
		(width 0.14224)
		(layer "In4.Cu")
		(net "M_B_DQS_DN<9>")
	)
	(segment
		(start 228.306884 -64.908938)
		(end 228.468428 -64.908938)
		(width 0.14224)
		(layer "In4.Cu")
		(net "M_B_DQS_DN<9>")
	)
	(segment
		(start 226.529392 -62.969902)
		(end 226.771962 -63.212472)
		(width 0.14224)
		(layer "In4.Cu")
		(net "M_B_DQS_DN<9>")
	)
	(segment
		(start 230.003604 -66.605658)
		(end 230.245666 -66.84772)
		(width 0.14224)
		(layer "In4.Cu")
		(net "M_B_DQS_DN<9>")
	)
	(segment
		(start 225.883216 -62.323726)
		(end 226.125786 -62.566296)
		(width 0.14224)
		(layer "In4.Cu")
		(net "M_B_DQS_DN<9>")
	)
	(segment
		(start 199.86752 -31.095696)
		(end 199.86752 -31.72968)
		(width 0.14224)
		(layer "In4.Cu")
		(net "M_B_DQS_DN<9>")
	)
	(segment
		(start 200.193656 -13.684504)
		(end 200.193656 -14.1859)
		(width 0.14224)
		(layer "In4.Cu")
		(net "M_B_DQS_DN<9>")
	)
	(segment
		(start 222.005398 -58.445908)
		(end 222.247968 -58.688478)
		(width 0.14224)
		(layer "In4.Cu")
		(net "M_B_DQS_DN<9>")
	)
	(segment
		(start 223.94418 -60.38469)
		(end 224.18675 -60.62726)
		(width 0.14224)
		(layer "In4.Cu")
		(net "M_B_DQS_DN<9>")
	)
	(segment
		(start 230.654098 -66.84772)
		(end 230.693468 -66.88709)
		(width 0.0889)
		(layer "In4.Cu")
		(net "M_B_DQS_DN<9>")
	)
	(segment
		(start 204.705204 -39.79545)
		(end 204.705204 -41.75125)
		(width 0.14224)
		(layer "In4.Cu")
		(net "M_B_DQS_DN<9>")
	)
	(segment
		(start 232.86974 -67.382136)
		(end 233.054398 -67.382136)
		(width 0.0889)
		(layer "In4.Cu")
		(net "M_B_DQS_DN<9>")
	)
	(segment
		(start 227.821998 -64.262508)
		(end 228.064568 -64.505078)
		(width 0.14224)
		(layer "In4.Cu")
		(net "M_B_DQS_DN<9>")
	)
	(segment
		(start 200.524872 -20.46732)
		(end 200.682352 -20.6248)
		(width 0.14224)
		(layer "In4.Cu")
		(net "M_B_DQS_DN<9>")
	)
	(segment
		(start 224.83318 -61.435234)
		(end 225.075242 -61.677296)
		(width 0.14224)
		(layer "In4.Cu")
		(net "M_B_DQS_DN<9>")
	)
	(segment
		(start 225.479356 -62.08141)
		(end 225.721672 -62.323726)
		(width 0.14224)
		(layer "In4.Cu")
		(net "M_B_DQS_DN<9>")
	)
	(segment
		(start 225.479356 -61.919866)
		(end 225.479356 -62.08141)
		(width 0.14224)
		(layer "In4.Cu")
		(net "M_B_DQS_DN<9>")
	)
	(segment
		(start 223.13646 -59.738514)
		(end 223.298004 -59.738514)
		(width 0.14224)
		(layer "In4.Cu")
		(net "M_B_DQS_DN<9>")
	)
	(segment
		(start 224.429066 -61.03112)
		(end 224.59061 -61.03112)
		(width 0.14224)
		(layer "In4.Cu")
		(net "M_B_DQS_DN<9>")
	)
	(segment
		(start 225.236786 -61.677296)
		(end 225.479356 -61.919866)
		(width 0.14224)
		(layer "In4.Cu")
		(net "M_B_DQS_DN<9>")
	)
	(segment
		(start 229.357174 -65.959228)
		(end 229.59949 -66.201544)
		(width 0.14224)
		(layer "In4.Cu")
		(net "M_B_DQS_DN<9>")
	)
	(segment
		(start 227.014278 -63.616332)
		(end 227.175822 -63.616332)
		(width 0.14224)
		(layer "In4.Cu")
		(net "M_B_DQS_DN<9>")
	)
	(segment
		(start 221.843854 -58.445908)
		(end 222.005398 -58.445908)
		(width 0.14224)
		(layer "In4.Cu")
		(net "M_B_DQS_DN<9>")
	)
	(segment
		(start 230.632 -66.84772)
		(end 230.654098 -66.84772)
		(width 0.0889)
		(layer "In4.Cu")
		(net "M_B_DQS_DN<9>")
	)
	(segment
		(start 225.721672 -62.323726)
		(end 225.883216 -62.323726)
		(width 0.14224)
		(layer "In4.Cu")
		(net "M_B_DQS_DN<9>")
	)
	(segment
		(start 203.886054 -38.9763)
		(end 204.705204 -39.79545)
		(width 0.14224)
		(layer "In4.Cu")
		(net "M_B_DQS_DN<9>")
	)
	(segment
		(start 199.540876 -14.58468)
		(end 199.540876 -15.109952)
		(width 0.14224)
		(layer "In4.Cu")
		(net "M_B_DQS_DN<9>")
	)
	(segment
		(start 226.771962 -63.374016)
		(end 227.014278 -63.616332)
		(width 0.14224)
		(layer "In4.Cu")
		(net "M_B_DQS_DN<9>")
	)
	(segment
		(start 199.977756 -14.4018)
		(end 199.723756 -14.4018)
		(width 0.14224)
		(layer "In4.Cu")
		(net "M_B_DQS_DN<9>")
	)
	(segment
		(start 222.651574 -59.092084)
		(end 222.894144 -59.334654)
		(width 0.14224)
		(layer "In4.Cu")
		(net "M_B_DQS_DN<9>")
	)
	(segment
		(start 199.86752 -36.913566)
		(end 201.930254 -38.9763)
		(width 0.14224)
		(layer "In4.Cu")
		(net "M_B_DQS_DN<9>")
	)
	(segment
		(start 222.247968 -58.850022)
		(end 222.49003 -59.092084)
		(width 0.14224)
		(layer "In4.Cu")
		(net "M_B_DQS_DN<9>")
	)
	(segment
		(start 229.761034 -66.201544)
		(end 230.003604 -66.444114)
		(width 0.14224)
		(layer "In4.Cu")
		(net "M_B_DQS_DN<9>")
	)
	(segment
		(start 221.358968 -57.799478)
		(end 221.601538 -58.042048)
		(width 0.14224)
		(layer "In4.Cu")
		(net "M_B_DQS_DN<9>")
	)
	(segment
		(start 200.83272 -29.687774)
		(end 200.83272 -30.419802)
		(width 0.14224)
		(layer "In4.Cu")
		(net "M_B_DQS_DN<9>")
	)
	(segment
		(start 223.782636 -60.38469)
		(end 223.94418 -60.38469)
		(width 0.14224)
		(layer "In4.Cu")
		(net "M_B_DQS_DN<9>")
	)
	(segment
		(start 226.367848 -62.969902)
		(end 226.529392 -62.969902)
		(width 0.14224)
		(layer "In4.Cu")
		(net "M_B_DQS_DN<9>")
	)
	(segment
		(start 199.96912 -28.824174)
		(end 200.83272 -29.687774)
		(width 0.14224)
		(layer "In4.Cu")
		(net "M_B_DQS_DN<9>")
	)
	(segment
		(start 199.944736 -8.00608)
		(end 200.194164 -8.00608)
		(width 0.14224)
		(layer "In4.Cu")
		(net "M_B_DQS_DN<9>")
	)
	(segment
		(start 200.378314 -31.951168)
		(end 200.75652 -32.329374)
		(width 0.14224)
		(layer "In4.Cu")
		(net "M_B_DQS_DN<9>")
	)
	(segment
		(start 235.198666 -68.019422)
		(end 235.329984 -67.834256)
		(width 0.0889)
		(layer "In4.Cu")
		(net "M_B_DQS_DN<9>")
	)
	(segment
		(start 235.329984 -67.834256)
		(end 235.612178 -67.47764)
		(width 0.0889)
		(layer "In4.Cu")
		(net "M_B_DQS_DN<9>")
	)
	(segment
		(start 199.749156 -7.8105)
		(end 199.944736 -8.00608)
		(width 0.14224)
		(layer "In4.Cu")
		(net "M_B_DQS_DN<9>")
	)
	(segment
		(start 200.194164 -8.00608)
		(end 200.531476 -8.343392)
		(width 0.14224)
		(layer "In4.Cu")
		(net "M_B_DQS_DN<9>")
	)
	(segment
		(start 200.682352 -24.1554)
		(end 200.524872 -24.31288)
		(width 0.14224)
		(layer "In4.Cu")
		(net "M_B_DQS_DN<9>")
	)
	(segment
		(start 221.197424 -57.799478)
		(end 221.358968 -57.799478)
		(width 0.14224)
		(layer "In4.Cu")
		(net "M_B_DQS_DN<9>")
	)
	(segment
		(start 226.771962 -63.212472)
		(end 226.771962 -63.374016)
		(width 0.14224)
		(layer "In4.Cu")
		(net "M_B_DQS_DN<9>")
	)
	(segment
		(start 228.468428 -64.908938)
		(end 228.710998 -65.151508)
		(width 0.14224)
		(layer "In4.Cu")
		(net "M_B_DQS_DN<9>")
	)
	(segment
		(start 200.524872 -27.803602)
		(end 199.96912 -28.359354)
		(width 0.14224)
		(layer "In4.Cu")
		(net "M_B_DQS_DN<9>")
	)
	(segment
		(start 201.930254 -38.9763)
		(end 203.886054 -38.9763)
		(width 0.14224)
		(layer "In4.Cu")
		(net "M_B_DQS_DN<9>")
	)
	(segment
		(start 204.705204 -41.75125)
		(end 219.405454 -56.4515)
		(width 0.14224)
		(layer "In4.Cu")
		(net "M_B_DQS_DN<9>")
	)
	(segment
		(start 220.712792 -57.153302)
		(end 220.955362 -57.395872)
		(width 0.14224)
		(layer "In4.Cu")
		(net "M_B_DQS_DN<9>")
	)
	(segment
		(start 228.710998 -65.313052)
		(end 228.95306 -65.555114)
		(width 0.14224)
		(layer "In4.Cu")
		(net "M_B_DQS_DN<9>")
	)
	(segment
		(start 219.849446 -56.4515)
		(end 220.551248 -57.153302)
		(width 0.14224)
		(layer "In4.Cu")
		(net "M_B_DQS_DN<9>")
	)
	(segment
		(start 224.18675 -60.788804)
		(end 224.429066 -61.03112)
		(width 0.14224)
		(layer "In4.Cu")
		(net "M_B_DQS_DN<9>")
	)
	(segment
		(start 200.524872 -24.31288)
		(end 200.524872 -27.803602)
		(width 0.14224)
		(layer "In4.Cu")
		(net "M_B_DQS_DN<9>")
	)
	(segment
		(start 220.955362 -57.557416)
		(end 221.197424 -57.799478)
		(width 0.14224)
		(layer "In4.Cu")
		(net "M_B_DQS_DN<9>")
	)
	(segment
		(start 227.660454 -64.262508)
		(end 227.821998 -64.262508)
		(width 0.14224)
		(layer "In4.Cu")
		(net "M_B_DQS_DN<9>")
	)
	(segment
		(start 200.089008 -30.874208)
		(end 199.86752 -31.095696)
		(width 0.14224)
		(layer "In4.Cu")
		(net "M_B_DQS_DN<9>")
	)
	(segment
		(start 200.83272 -30.419802)
		(end 200.378314 -30.874208)
		(width 0.14224)
		(layer "In4.Cu")
		(net "M_B_DQS_DN<9>")
	)
	(segment
		(start 200.193656 -14.1859)
		(end 199.977756 -14.4018)
		(width 0.14224)
		(layer "In4.Cu")
		(net "M_B_DQS_DN<9>")
	)
	(segment
		(start 220.955362 -57.395872)
		(end 220.955362 -57.557416)
		(width 0.14224)
		(layer "In4.Cu")
		(net "M_B_DQS_DN<9>")
	)
	(segment
		(start 224.83318 -61.27369)
		(end 224.83318 -61.435234)
		(width 0.14224)
		(layer "In4.Cu")
		(net "M_B_DQS_DN<9>")
	)
	(segment
		(start 200.682352 -23.9014)
		(end 200.682352 -24.1554)
		(width 0.14224)
		(layer "In4.Cu")
		(net "M_B_DQS_DN<9>")
	)
	(segment
		(start 200.524872 -19.70532)
		(end 200.682352 -19.8628)
		(width 0.14224)
		(layer "In4.Cu")
		(net "M_B_DQS_DN<9>")
	)
	(segment
		(start 200.524872 -16.093948)
		(end 200.524872 -19.70532)
		(width 0.14224)
		(layer "In4.Cu")
		(net "M_B_DQS_DN<9>")
	)
	(segment
		(start 223.540574 -60.142628)
		(end 223.782636 -60.38469)
		(width 0.14224)
		(layer "In4.Cu")
		(net "M_B_DQS_DN<9>")
	)
	(segment
		(start 200.682352 -19.8628)
		(end 200.682352 -20.1168)
		(width 0.14224)
		(layer "In4.Cu")
		(net "M_B_DQS_DN<9>")
	)
	(segment
		(start 200.089008 -31.951168)
		(end 200.378314 -31.951168)
		(width 0.14224)
		(layer "In4.Cu")
		(net "M_B_DQS_DN<9>")
	)
	(arc
		(start 233.054398 -67.382136)
		(mid 233.339822 -67.465603)
		(end 233.548428 -67.677538)
		(width 0.0889)
		(layer "In4.Cu")
		(net "M_B_DQS_DN<9>")
	)
	(arc
		(start 235.100368 -68.172838)
		(mid 235.147704 -68.094968)
		(end 235.198666 -68.019422)
		(width 0.0889)
		(layer "In4.Cu")
		(net "M_B_DQS_DN<9>")
	)
	(arc
		(start 233.916728 -67.87769)
		(mid 234.199945 -67.961971)
		(end 234.406948 -68.172838)
		(width 0.0889)
		(layer "In4.Cu")
		(net "M_B_DQS_DN<9>")
	)
	(arc
		(start 233.548428 -67.677538)
		(mid 233.690111 -67.821342)
		(end 233.883962 -67.87769)
		(width 0.0889)
		(layer "In4.Cu")
		(net "M_B_DQS_DN<9>")
	)
	(arc
		(start 234.768644 -68.372736)
		(mid 234.960286 -68.31557)
		(end 235.100368 -68.172838)
		(width 0.0889)
		(layer "In4.Cu")
		(net "M_B_DQS_DN<9>")
	)
	(arc
		(start 232.653586 -67.185032)
		(mid 232.74453 -67.302375)
		(end 232.86974 -67.382136)
		(width 0.0889)
		(layer "In4.Cu")
		(net "M_B_DQS_DN<9>")
	)
	(arc
		(start 232.158286 -66.88709)
		(mid 232.447277 -66.967323)
		(end 232.653586 -67.185032)
		(width 0.0889)
		(layer "In4.Cu")
		(net "M_B_DQS_DN<9>")
	)
	(arc
		(start 234.406948 -68.172838)
		(mid 234.547027 -68.315574)
		(end 234.738672 -68.372736)
		(width 0.0889)
		(layer "In4.Cu")
		(net "M_B_DQS_DN<9>")
	)
	(segment
		(start 237.988602 -29.581602)
		(end 239.258602 -30.851602)
		(width 0.1651)
		(layer "F.Cu")
		(net "M_B_DQS_DN<8>")
	)
	(segment
		(start 240.6396 -41.171876)
		(end 240.6396 -41.883076)
		(width 0.1651)
		(layer "F.Cu")
		(net "M_B_DQS_DN<8>")
	)
	(segment
		(start 241.346736 -42.590466)
		(end 241.591338 -42.835068)
		(width 0.1016)
		(layer "F.Cu")
		(net "M_B_DQS_DN<8>")
	)
	(segment
		(start 248.549922 -50.836322)
		(end 248.54916 -50.837084)
		(width 0.0889)
		(layer "F.Cu")
		(net "M_B_DQS_DN<8>")
	)
	(segment
		(start 238.437928 -27.34437)
		(end 237.988602 -27.793696)
		(width 0.1651)
		(layer "F.Cu")
		(net "M_B_DQS_DN<8>")
	)
	(segment
		(start 240.157 -40.689276)
		(end 240.6396 -41.171876)
		(width 0.1651)
		(layer "F.Cu")
		(net "M_B_DQS_DN<8>")
	)
	(segment
		(start 248.6533 -50.651156)
		(end 248.549922 -50.836322)
		(width 0.0889)
		(layer "F.Cu")
		(net "M_B_DQS_DN<8>")
	)
	(segment
		(start 248.548398 -47.996856)
		(end 248.548398 -50.073814)
		(width 0.1016)
		(layer "F.Cu")
		(net "M_B_DQS_DN<8>")
	)
	(segment
		(start 240.157 -37.842444)
		(end 240.157 -40.689276)
		(width 0.1651)
		(layer "F.Cu")
		(net "M_B_DQS_DN<8>")
	)
	(segment
		(start 242.79606 -42.835068)
		(end 243.697506 -43.736514)
		(width 0.1016)
		(layer "F.Cu")
		(net "M_B_DQS_DN<8>")
	)
	(segment
		(start 238.049816 -10.422382)
		(end 238.049816 -9.34847)
		(width 0.1651)
		(layer "F.Cu")
		(net "M_B_DQS_DN<8>")
	)
	(segment
		(start 248.47042 -51.140868)
		(end 248.470166 -51.141122)
		(width 0.0889)
		(layer "F.Cu")
		(net "M_B_DQS_DN<8>")
	)
	(segment
		(start 240.792 -36.3474)
		(end 240.6396 -36.4998)
		(width 0.1651)
		(layer "F.Cu")
		(net "M_B_DQS_DN<8>")
	)
	(segment
		(start 244.288056 -43.736514)
		(end 248.548398 -47.996856)
		(width 0.1016)
		(layer "F.Cu")
		(net "M_B_DQS_DN<8>")
	)
	(segment
		(start 237.650782 -8.949436)
		(end 237.650782 -8.551672)
		(width 0.1651)
		(layer "F.Cu")
		(net "M_B_DQS_DN<8>")
	)
	(segment
		(start 239.258602 -30.851602)
		(end 239.44453 -30.851602)
		(width 0.1651)
		(layer "F.Cu")
		(net "M_B_DQS_DN<8>")
	)
	(segment
		(start 240.02492 -31.431992)
		(end 240.02492 -31.61792)
		(width 0.1651)
		(layer "F.Cu")
		(net "M_B_DQS_DN<8>")
	)
	(segment
		(start 240.792 -33.147)
		(end 240.792 -36.3474)
		(width 0.1651)
		(layer "F.Cu")
		(net "M_B_DQS_DN<8>")
	)
	(segment
		(start 248.54916 -50.837084)
		(end 248.54916 -50.837592)
		(width 0.0889)
		(layer "F.Cu")
		(net "M_B_DQS_DN<8>")
	)
	(segment
		(start 238.049816 -9.34847)
		(end 237.650782 -8.949436)
		(width 0.1651)
		(layer "F.Cu")
		(net "M_B_DQS_DN<8>")
	)
	(segment
		(start 238.222282 -8.2042)
		(end 238.437928 -8.419846)
		(width 0.1651)
		(layer "F.Cu")
		(net "M_B_DQS_DN<8>")
	)
	(segment
		(start 248.548398 -50.221388)
		(end 248.6533 -50.32629)
		(width 0.0889)
		(layer "F.Cu")
		(net "M_B_DQS_DN<8>")
	)
	(segment
		(start 240.02492 -31.61792)
		(end 240.792 -32.385)
		(width 0.1651)
		(layer "F.Cu")
		(net "M_B_DQS_DN<8>")
	)
	(segment
		(start 237.988602 -27.793696)
		(end 237.988602 -29.581602)
		(width 0.1651)
		(layer "F.Cu")
		(net "M_B_DQS_DN<8>")
	)
	(segment
		(start 248.130314 -55.186326)
		(end 248.202704 -55.258716)
		(width 0.0889)
		(layer "F.Cu")
		(net "M_B_DQS_DN<8>")
	)
	(segment
		(start 248.202704 -55.258716)
		(end 248.202704 -55.59044)
		(width 0.0889)
		(layer "F.Cu")
		(net "M_B_DQS_DN<8>")
	)
	(segment
		(start 248.548398 -50.073814)
		(end 248.548398 -50.221388)
		(width 0.0889)
		(layer "F.Cu")
		(net "M_B_DQS_DN<8>")
	)
	(segment
		(start 238.050324 -10.422382)
		(end 238.049816 -10.422382)
		(width 0.1651)
		(layer "F.Cu")
		(net "M_B_DQS_DN<8>")
	)
	(segment
		(start 240.792 -32.385)
		(end 240.792 -33.147)
		(width 0.1651)
		(layer "F.Cu")
		(net "M_B_DQS_DN<8>")
	)
	(segment
		(start 241.346736 -42.590212)
		(end 241.346736 -42.590466)
		(width 0.1016)
		(layer "F.Cu")
		(net "M_B_DQS_DN<8>")
	)
	(segment
		(start 248.6533 -50.32629)
		(end 248.6533 -50.651156)
		(width 0.0889)
		(layer "F.Cu")
		(net "M_B_DQS_DN<8>")
	)
	(segment
		(start 239.44453 -30.851602)
		(end 240.02492 -31.431992)
		(width 0.1651)
		(layer "F.Cu")
		(net "M_B_DQS_DN<8>")
	)
	(segment
		(start 248.21388 -54.00929)
		(end 248.181114 -54.00929)
		(width 0.0889)
		(layer "F.Cu")
		(net "M_B_DQS_DN<8>")
	)
	(segment
		(start 237.998254 -8.2042)
		(end 238.222282 -8.2042)
		(width 0.1651)
		(layer "F.Cu")
		(net "M_B_DQS_DN<8>")
	)
	(segment
		(start 248.470166 -51.141122)
		(end 248.470166 -52.12588)
		(width 0.0889)
		(layer "F.Cu")
		(net "M_B_DQS_DN<8>")
	)
	(segment
		(start 240.6396 -36.4998)
		(end 240.6396 -37.359844)
		(width 0.1651)
		(layer "F.Cu")
		(net "M_B_DQS_DN<8>")
	)
	(segment
		(start 243.697506 -43.736514)
		(end 244.288056 -43.736514)
		(width 0.1016)
		(layer "F.Cu")
		(net "M_B_DQS_DN<8>")
	)
	(segment
		(start 240.6396 -41.883076)
		(end 241.346736 -42.590212)
		(width 0.1651)
		(layer "F.Cu")
		(net "M_B_DQS_DN<8>")
	)
	(segment
		(start 241.591338 -42.835068)
		(end 242.79606 -42.835068)
		(width 0.1016)
		(layer "F.Cu")
		(net "M_B_DQS_DN<8>")
	)
	(segment
		(start 240.6396 -37.359844)
		(end 240.157 -37.842444)
		(width 0.1651)
		(layer "F.Cu")
		(net "M_B_DQS_DN<8>")
	)
	(segment
		(start 237.650782 -8.551672)
		(end 237.998254 -8.2042)
		(width 0.1651)
		(layer "F.Cu")
		(net "M_B_DQS_DN<8>")
	)
	(via
		(at 240.792 -33.147)
		(size 0.508)
		(drill 0.254)
		(layers "F.Cu" "B.Cu")
		(net "M_B_DQS_DN<8>")
	)
	(via
		(at 238.437928 -27.34437)
		(size 0.508)
		(drill 0.254)
		(layers "F.Cu" "B.Cu")
		(net "M_B_DQS_DN<8>")
	)
	(via
		(at 238.437928 -12.627356)
		(size 0.508)
		(drill 0.254)
		(layers "F.Cu" "B.Cu")
		(net "M_B_DQS_DN<8>")
	)
	(via
		(at 238.437928 -8.419846)
		(size 0.508)
		(drill 0.254)
		(layers "F.Cu" "B.Cu")
		(net "M_B_DQS_DN<8>")
	)
	(arc
		(start 248.470166 -52.12588)
		(mid 248.490713 -52.277351)
		(end 248.549414 -52.418488)
		(width 0.0889)
		(layer "F.Cu")
		(net "M_B_DQS_DN<8>")
	)
	(arc
		(start 248.549414 -52.418488)
		(mid 248.602913 -52.618386)
		(end 248.549414 -52.818284)
		(width 0.0889)
		(layer "F.Cu")
		(net "M_B_DQS_DN<8>")
	)
	(arc
		(start 248.549414 -52.818284)
		(mid 248.470283 -53.113686)
		(end 248.549414 -53.409088)
		(width 0.0889)
		(layer "F.Cu")
		(net "M_B_DQS_DN<8>")
	)
	(arc
		(start 248.181114 -54.00929)
		(mid 247.612864 -54.563721)
		(end 248.109232 -55.183278)
		(width 0.0889)
		(layer "F.Cu")
		(net "M_B_DQS_DN<8>")
	)
	(arc
		(start 248.549414 -53.409088)
		(mid 248.552162 -53.804555)
		(end 248.21388 -54.00929)
		(width 0.0889)
		(layer "F.Cu")
		(net "M_B_DQS_DN<8>")
	)
	(arc
		(start 248.109232 -55.183278)
		(mid 248.119759 -55.184896)
		(end 248.130314 -55.186326)
		(width 0.0889)
		(layer "F.Cu")
		(net "M_B_DQS_DN<8>")
	)
	(arc
		(start 248.54916 -50.837592)
		(mid 248.489299 -50.983913)
		(end 248.47042 -51.140868)
		(width 0.0889)
		(layer "F.Cu")
		(net "M_B_DQS_DN<8>")
	)
	(segment
		(start 237.9218 -11.658346)
		(end 237.9218 -11.912346)
		(width 0.1651)
		(layer "B.Cu")
		(net "M_B_DQS_DN<8>")
	)
	(segment
		(start 238.049816 -11.53033)
		(end 237.9218 -11.658346)
		(width 0.1651)
		(layer "B.Cu")
		(net "M_B_DQS_DN<8>")
	)
	(segment
		(start 237.9218 -11.912346)
		(end 237.6678 -12.166346)
		(width 0.1651)
		(layer "B.Cu")
		(net "M_B_DQS_DN<8>")
	)
	(segment
		(start 238.049816 -10.623042)
		(end 238.049816 -11.53033)
		(width 0.1651)
		(layer "B.Cu")
		(net "M_B_DQS_DN<8>")
	)
	(segment
		(start 238.212884 -12.8524)
		(end 238.437928 -12.627356)
		(width 0.1651)
		(layer "B.Cu")
		(net "M_B_DQS_DN<8>")
	)
	(segment
		(start 238.0234 -12.8524)
		(end 238.212884 -12.8524)
		(width 0.1651)
		(layer "B.Cu")
		(net "M_B_DQS_DN<8>")
	)
	(segment
		(start 237.6678 -12.4968)
		(end 238.0234 -12.8524)
		(width 0.1651)
		(layer "B.Cu")
		(net "M_B_DQS_DN<8>")
	)
	(segment
		(start 237.6678 -12.166346)
		(end 237.6678 -12.4968)
		(width 0.1651)
		(layer "B.Cu")
		(net "M_B_DQS_DN<8>")
	)
	(segment
		(start 238.050324 -10.623042)
		(end 238.049816 -10.623042)
		(width 0.1651)
		(layer "B.Cu")
		(net "M_B_DQS_DN<8>")
	)
	(segment
		(start 238.437928 -12.627356)
		(end 238.437928 -12.62761)
		(width 0.14224)
		(layer "In11.Cu")
		(net "M_B_DQS_DN<8>")
	)
	(segment
		(start 238.485934 -9.981946)
		(end 238.485934 -9.677654)
		(width 0.14224)
		(layer "In11.Cu")
		(net "M_B_DQS_DN<8>")
	)
	(segment
		(start 238.935006 -15.263368)
		(end 238.452406 -14.780768)
		(width 0.14224)
		(layer "In11.Cu")
		(net "M_B_DQS_DN<8>")
	)
	(segment
		(start 238.669576 -10.8712)
		(end 238.796576 -10.8712)
		(width 0.14224)
		(layer "In11.Cu")
		(net "M_B_DQS_DN<8>")
	)
	(segment
		(start 238.71682 -12.62761)
		(end 238.979456 -12.364974)
		(width 0.14224)
		(layer "In11.Cu")
		(net "M_B_DQS_DN<8>")
	)
	(segment
		(start 238.979456 -12.364974)
		(end 238.979456 -11.660124)
		(width 0.14224)
		(layer "In11.Cu")
		(net "M_B_DQS_DN<8>")
	)
	(segment
		(start 238.935006 -26.847292)
		(end 238.935006 -15.263368)
		(width 0.14224)
		(layer "In11.Cu")
		(net "M_B_DQS_DN<8>")
	)
	(segment
		(start 238.491776 -11.303)
		(end 238.491776 -11.049)
		(width 0.14224)
		(layer "In11.Cu")
		(net "M_B_DQS_DN<8>")
	)
	(segment
		(start 238.000032 -13.065252)
		(end 238.437928 -12.627356)
		(width 0.14224)
		(layer "In11.Cu")
		(net "M_B_DQS_DN<8>")
	)
	(segment
		(start 238.000032 -14.157706)
		(end 238.000032 -13.065252)
		(width 0.14224)
		(layer "In11.Cu")
		(net "M_B_DQS_DN<8>")
	)
	(segment
		(start 238.719614 -8.419846)
		(end 238.437928 -8.419846)
		(width 0.14224)
		(layer "In11.Cu")
		(net "M_B_DQS_DN<8>")
	)
	(segment
		(start 238.979456 -10.339578)
		(end 238.774478 -10.1346)
		(width 0.14224)
		(layer "In11.Cu")
		(net "M_B_DQS_DN<8>")
	)
	(segment
		(start 238.437928 -27.34437)
		(end 238.935006 -26.847292)
		(width 0.14224)
		(layer "In11.Cu")
		(net "M_B_DQS_DN<8>")
	)
	(segment
		(start 238.491776 -11.049)
		(end 238.669576 -10.8712)
		(width 0.14224)
		(layer "In11.Cu")
		(net "M_B_DQS_DN<8>")
	)
	(segment
		(start 238.485934 -9.677654)
		(end 238.638588 -9.525)
		(width 0.14224)
		(layer "In11.Cu")
		(net "M_B_DQS_DN<8>")
	)
	(segment
		(start 238.774478 -10.1346)
		(end 238.638588 -10.1346)
		(width 0.14224)
		(layer "In11.Cu")
		(net "M_B_DQS_DN<8>")
	)
	(segment
		(start 238.979456 -10.68832)
		(end 238.979456 -10.339578)
		(width 0.14224)
		(layer "In11.Cu")
		(net "M_B_DQS_DN<8>")
	)
	(segment
		(start 238.979456 -11.660124)
		(end 238.800132 -11.4808)
		(width 0.14224)
		(layer "In11.Cu")
		(net "M_B_DQS_DN<8>")
	)
	(segment
		(start 238.979456 -8.679688)
		(end 238.719614 -8.419846)
		(width 0.14224)
		(layer "In11.Cu")
		(net "M_B_DQS_DN<8>")
	)
	(segment
		(start 238.437928 -12.62761)
		(end 238.71682 -12.62761)
		(width 0.14224)
		(layer "In11.Cu")
		(net "M_B_DQS_DN<8>")
	)
	(segment
		(start 238.979456 -9.345422)
		(end 238.979456 -8.679688)
		(width 0.14224)
		(layer "In11.Cu")
		(net "M_B_DQS_DN<8>")
	)
	(segment
		(start 238.796576 -10.8712)
		(end 238.979456 -10.68832)
		(width 0.14224)
		(layer "In11.Cu")
		(net "M_B_DQS_DN<8>")
	)
	(segment
		(start 238.638588 -10.1346)
		(end 238.485934 -9.981946)
		(width 0.14224)
		(layer "In11.Cu")
		(net "M_B_DQS_DN<8>")
	)
	(segment
		(start 238.452406 -14.61008)
		(end 238.000032 -14.157706)
		(width 0.14224)
		(layer "In11.Cu")
		(net "M_B_DQS_DN<8>")
	)
	(segment
		(start 238.799878 -9.525)
		(end 238.979456 -9.345422)
		(width 0.14224)
		(layer "In11.Cu")
		(net "M_B_DQS_DN<8>")
	)
	(segment
		(start 238.669576 -11.4808)
		(end 238.491776 -11.303)
		(width 0.14224)
		(layer "In11.Cu")
		(net "M_B_DQS_DN<8>")
	)
	(segment
		(start 238.800132 -11.4808)
		(end 238.669576 -11.4808)
		(width 0.14224)
		(layer "In11.Cu")
		(net "M_B_DQS_DN<8>")
	)
	(segment
		(start 238.638588 -9.525)
		(end 238.799878 -9.525)
		(width 0.14224)
		(layer "In11.Cu")
		(net "M_B_DQS_DN<8>")
	)
	(segment
		(start 238.452406 -14.780768)
		(end 238.452406 -14.61008)
		(width 0.14224)
		(layer "In11.Cu")
		(net "M_B_DQS_DN<8>")
	)
	(segment
		(start 311.7342 -9.143746)
		(end 311.999884 -9.40943)
		(width 0.1651)
		(layer "F.Cu")
		(net "M_B_DQS_DN<7>")
	)
	(segment
		(start 311.999884 -9.40943)
		(end 311.999884 -10.422382)
		(width 0.1651)
		(layer "F.Cu")
		(net "M_B_DQS_DN<7>")
	)
	(segment
		(start 312.387996 -7.75716)
		(end 311.7342 -8.410956)
		(width 0.1651)
		(layer "F.Cu")
		(net "M_B_DQS_DN<7>")
	)
	(segment
		(start 311.999884 -10.422382)
		(end 312.000392 -10.422382)
		(width 0.1651)
		(layer "F.Cu")
		(net "M_B_DQS_DN<7>")
	)
	(segment
		(start 284.929834 -61.847984)
		(end 284.358334 -61.847984)
		(width 0.1016)
		(layer "F.Cu")
		(net "M_B_DQS_DN<7>")
	)
	(segment
		(start 311.7342 -8.410956)
		(end 311.7342 -9.143746)
		(width 0.1651)
		(layer "F.Cu")
		(net "M_B_DQS_DN<7>")
	)
	(via
		(at 284.358334 -61.847984)
		(size 0.508)
		(drill 0.254)
		(layers "F.Cu" "B.Cu")
		(net "M_B_DQS_DN<7>")
	)
	(via
		(at 312.387996 -7.75716)
		(size 0.508)
		(drill 0.254)
		(layers "F.Cu" "B.Cu")
		(net "M_B_DQS_DN<7>")
	)
	(via
		(at 312.387996 -13.287756)
		(size 0.508)
		(drill 0.254)
		(layers "F.Cu" "B.Cu")
		(net "M_B_DQS_DN<7>")
	)
	(segment
		(start 311.999884 -10.623042)
		(end 311.999884 -11.52017)
		(width 0.1651)
		(layer "B.Cu")
		(net "M_B_DQS_DN<7>")
	)
	(segment
		(start 311.999884 -11.52017)
		(end 311.7469 -11.773154)
		(width 0.1651)
		(layer "B.Cu")
		(net "M_B_DQS_DN<7>")
	)
	(segment
		(start 312.000392 -10.623042)
		(end 311.999884 -10.623042)
		(width 0.1651)
		(layer "B.Cu")
		(net "M_B_DQS_DN<7>")
	)
	(segment
		(start 311.7469 -12.64666)
		(end 312.387996 -13.287756)
		(width 0.1651)
		(layer "B.Cu")
		(net "M_B_DQS_DN<7>")
	)
	(segment
		(start 311.7469 -11.773154)
		(end 311.7469 -12.64666)
		(width 0.1651)
		(layer "B.Cu")
		(net "M_B_DQS_DN<7>")
	)
	(segment
		(start 313.170316 -16.86052)
		(end 313.170316 -15.845028)
		(width 0.14224)
		(layer "In4.Cu")
		(net "M_B_DQS_DN<7>")
	)
	(segment
		(start 289.37204 -51.77536)
		(end 293.95293 -47.19447)
		(width 0.14224)
		(layer "In4.Cu")
		(net "M_B_DQS_DN<7>")
	)
	(segment
		(start 312.6994 -14.4272)
		(end 312.8518 -14.2748)
		(width 0.14224)
		(layer "In4.Cu")
		(net "M_B_DQS_DN<7>")
	)
	(segment
		(start 293.95293 -47.19447)
		(end 295.887648 -47.19447)
		(width 0.14224)
		(layer "In4.Cu")
		(net "M_B_DQS_DN<7>")
	)
	(segment
		(start 312.387996 -13.287756)
		(end 313.198764 -12.476988)
		(width 0.14224)
		(layer "In4.Cu")
		(net "M_B_DQS_DN<7>")
	)
	(segment
		(start 312.21172 -14.63548)
		(end 312.42 -14.4272)
		(width 0.14224)
		(layer "In4.Cu")
		(net "M_B_DQS_DN<7>")
	)
	(segment
		(start 313.198764 -12.476988)
		(end 313.198764 -8.567928)
		(width 0.14224)
		(layer "In4.Cu")
		(net "M_B_DQS_DN<7>")
	)
	(segment
		(start 286.58693 -57.590436)
		(end 286.582104 -57.5818)
		(width 0.0889)
		(layer "In4.Cu")
		(net "M_B_DQS_DN<7>")
	)
	(segment
		(start 313.170316 -15.845028)
		(end 312.21172 -14.886432)
		(width 0.14224)
		(layer "In4.Cu")
		(net "M_B_DQS_DN<7>")
	)
	(segment
		(start 313.170316 -17.62252)
		(end 313.170316 -17.42948)
		(width 0.14224)
		(layer "In4.Cu")
		(net "M_B_DQS_DN<7>")
	)
	(segment
		(start 312.21172 -14.886432)
		(end 312.21172 -14.63548)
		(width 0.14224)
		(layer "In4.Cu")
		(net "M_B_DQS_DN<7>")
	)
	(segment
		(start 286.921194 -53.027834)
		(end 286.955738 -53.027834)
		(width 0.0889)
		(layer "In4.Cu")
		(net "M_B_DQS_DN<7>")
	)
	(segment
		(start 313.327796 -18.034)
		(end 313.327796 -17.78)
		(width 0.14224)
		(layer "In4.Cu")
		(net "M_B_DQS_DN<7>")
	)
	(segment
		(start 313.198764 -8.567928)
		(end 312.387996 -7.75716)
		(width 0.14224)
		(layer "In4.Cu")
		(net "M_B_DQS_DN<7>")
	)
	(segment
		(start 286.59328 -54.629304)
		(end 286.58693 -54.618636)
		(width 0.0889)
		(layer "In4.Cu")
		(net "M_B_DQS_DN<7>")
	)
	(segment
		(start 313.170316 -18.19148)
		(end 313.327796 -18.034)
		(width 0.14224)
		(layer "In4.Cu")
		(net "M_B_DQS_DN<7>")
	)
	(segment
		(start 284.804612 -61.266578)
		(end 284.870144 -61.15304)
		(width 0.0889)
		(layer "In4.Cu")
		(net "M_B_DQS_DN<7>")
	)
	(segment
		(start 286.59328 -56.610504)
		(end 286.58693 -56.599836)
		(width 0.0889)
		(layer "In4.Cu")
		(net "M_B_DQS_DN<7>")
	)
	(segment
		(start 287.431226 -52.756308)
		(end 287.84296 -52.34432)
		(width 0.0889)
		(layer "In4.Cu")
		(net "M_B_DQS_DN<7>")
	)
	(segment
		(start 313.170316 -27.969718)
		(end 313.170316 -18.19148)
		(width 0.14224)
		(layer "In4.Cu")
		(net "M_B_DQS_DN<7>")
	)
	(segment
		(start 313.327796 -17.272)
		(end 313.327796 -17.018)
		(width 0.14224)
		(layer "In4.Cu")
		(net "M_B_DQS_DN<7>")
	)
	(segment
		(start 284.876494 -59.58205)
		(end 284.870144 -59.571382)
		(width 0.0889)
		(layer "In4.Cu")
		(net "M_B_DQS_DN<7>")
	)
	(segment
		(start 288.747454 -52.34432)
		(end 289.301174 -51.7906)
		(width 0.0889)
		(layer "In4.Cu")
		(net "M_B_DQS_DN<7>")
	)
	(segment
		(start 312.8518 -14.2748)
		(end 312.8518 -13.75156)
		(width 0.14224)
		(layer "In4.Cu")
		(net "M_B_DQS_DN<7>")
	)
	(segment
		(start 313.327796 -17.78)
		(end 313.170316 -17.62252)
		(width 0.14224)
		(layer "In4.Cu")
		(net "M_B_DQS_DN<7>")
	)
	(segment
		(start 309.82412 -33.257998)
		(end 309.82412 -31.315914)
		(width 0.14224)
		(layer "In4.Cu")
		(net "M_B_DQS_DN<7>")
	)
	(segment
		(start 286.58693 -55.609236)
		(end 286.582104 -55.6006)
		(width 0.0889)
		(layer "In4.Cu")
		(net "M_B_DQS_DN<7>")
	)
	(segment
		(start 286.063944 -58.476388)
		(end 286.088074 -58.476388)
		(width 0.0889)
		(layer "In4.Cu")
		(net "M_B_DQS_DN<7>")
	)
	(segment
		(start 286.59328 -55.619904)
		(end 286.58693 -55.609236)
		(width 0.0889)
		(layer "In4.Cu")
		(net "M_B_DQS_DN<7>")
	)
	(segment
		(start 286.59328 -57.601104)
		(end 286.58693 -57.590436)
		(width 0.0889)
		(layer "In4.Cu")
		(net "M_B_DQS_DN<7>")
	)
	(segment
		(start 289.301174 -51.7906)
		(end 289.356546 -51.790854)
		(width 0.0889)
		(layer "In4.Cu")
		(net "M_B_DQS_DN<7>")
	)
	(segment
		(start 313.327796 -17.018)
		(end 313.170316 -16.86052)
		(width 0.14224)
		(layer "In4.Cu")
		(net "M_B_DQS_DN<7>")
	)
	(segment
		(start 285.204408 -58.971688)
		(end 285.23819 -58.971688)
		(width 0.0889)
		(layer "In4.Cu")
		(net "M_B_DQS_DN<7>")
	)
	(segment
		(start 310.308244 -30.832044)
		(end 313.170316 -27.969718)
		(width 0.14224)
		(layer "In4.Cu")
		(net "M_B_DQS_DN<7>")
	)
	(segment
		(start 286.58693 -56.599836)
		(end 286.582104 -56.5912)
		(width 0.0889)
		(layer "In4.Cu")
		(net "M_B_DQS_DN<7>")
	)
	(segment
		(start 286.915606 -53.028088)
		(end 286.921194 -53.027834)
		(width 0.0889)
		(layer "In4.Cu")
		(net "M_B_DQS_DN<7>")
	)
	(segment
		(start 287.84296 -52.34432)
		(end 288.747454 -52.34432)
		(width 0.0889)
		(layer "In4.Cu")
		(net "M_B_DQS_DN<7>")
	)
	(segment
		(start 313.170316 -17.42948)
		(end 313.327796 -17.272)
		(width 0.14224)
		(layer "In4.Cu")
		(net "M_B_DQS_DN<7>")
	)
	(segment
		(start 295.887648 -47.19447)
		(end 309.82412 -33.257998)
		(width 0.14224)
		(layer "In4.Cu")
		(net "M_B_DQS_DN<7>")
	)
	(segment
		(start 309.82412 -31.315914)
		(end 310.308244 -30.832044)
		(width 0.14224)
		(layer "In4.Cu")
		(net "M_B_DQS_DN<7>")
	)
	(segment
		(start 289.356546 -51.790854)
		(end 289.37204 -51.77536)
		(width 0.0889)
		(layer "In4.Cu")
		(net "M_B_DQS_DN<7>")
	)
	(segment
		(start 312.8518 -13.75156)
		(end 312.387996 -13.287756)
		(width 0.14224)
		(layer "In4.Cu")
		(net "M_B_DQS_DN<7>")
	)
	(segment
		(start 312.42 -14.4272)
		(end 312.6994 -14.4272)
		(width 0.14224)
		(layer "In4.Cu")
		(net "M_B_DQS_DN<7>")
	)
	(segment
		(start 284.879034 -60.577476)
		(end 284.870144 -60.562236)
		(width 0.0889)
		(layer "In4.Cu")
		(net "M_B_DQS_DN<7>")
	)
	(segment
		(start 286.58693 -54.618636)
		(end 286.582104 -54.61)
		(width 0.0889)
		(layer "In4.Cu")
		(net "M_B_DQS_DN<7>")
	)
	(arc
		(start 286.58693 -54.218586)
		(mid 286.666061 -53.923184)
		(end 286.58693 -53.627782)
		(width 0.0889)
		(layer "In4.Cu")
		(net "M_B_DQS_DN<7>")
	)
	(arc
		(start 286.58693 -53.627782)
		(mid 286.582685 -53.235537)
		(end 286.915606 -53.028088)
		(width 0.0889)
		(layer "In4.Cu")
		(net "M_B_DQS_DN<7>")
	)
	(arc
		(start 286.58693 -55.209186)
		(mid 286.666152 -54.920068)
		(end 286.59328 -54.629304)
		(width 0.0889)
		(layer "In4.Cu")
		(net "M_B_DQS_DN<7>")
	)
	(arc
		(start 285.72841 -58.67654)
		(mid 285.870093 -58.532736)
		(end 286.063944 -58.476388)
		(width 0.0889)
		(layer "In4.Cu")
		(net "M_B_DQS_DN<7>")
	)
	(arc
		(start 286.58693 -56.199786)
		(mid 286.666152 -55.910668)
		(end 286.59328 -55.619904)
		(width 0.0889)
		(layer "In4.Cu")
		(net "M_B_DQS_DN<7>")
	)
	(arc
		(start 284.870144 -59.571382)
		(mid 284.867219 -59.176744)
		(end 285.204408 -58.971688)
		(width 0.0889)
		(layer "In4.Cu")
		(net "M_B_DQS_DN<7>")
	)
	(arc
		(start 286.955738 -53.027834)
		(mid 287.226835 -52.950483)
		(end 287.431226 -52.756308)
		(width 0.0889)
		(layer "In4.Cu")
		(net "M_B_DQS_DN<7>")
	)
	(arc
		(start 286.582104 -54.61)
		(mid 286.533349 -54.413648)
		(end 286.58693 -54.218586)
		(width 0.0889)
		(layer "In4.Cu")
		(net "M_B_DQS_DN<7>")
	)
	(arc
		(start 286.58693 -57.190386)
		(mid 286.666152 -56.901268)
		(end 286.59328 -56.610504)
		(width 0.0889)
		(layer "In4.Cu")
		(net "M_B_DQS_DN<7>")
	)
	(arc
		(start 284.870144 -60.16244)
		(mid 284.949493 -59.873068)
		(end 284.876494 -59.58205)
		(width 0.0889)
		(layer "In4.Cu")
		(net "M_B_DQS_DN<7>")
	)
	(arc
		(start 286.582104 -57.5818)
		(mid 286.533349 -57.385448)
		(end 286.58693 -57.190386)
		(width 0.0889)
		(layer "In4.Cu")
		(net "M_B_DQS_DN<7>")
	)
	(arc
		(start 285.23819 -58.971688)
		(mid 285.521407 -58.887407)
		(end 285.72841 -58.67654)
		(width 0.0889)
		(layer "In4.Cu")
		(net "M_B_DQS_DN<7>")
	)
	(arc
		(start 286.582104 -56.5912)
		(mid 286.533349 -56.394848)
		(end 286.58693 -56.199786)
		(width 0.0889)
		(layer "In4.Cu")
		(net "M_B_DQS_DN<7>")
	)
	(arc
		(start 284.358334 -61.847984)
		(mid 284.600514 -61.571896)
		(end 284.804612 -61.266578)
		(width 0.0889)
		(layer "In4.Cu")
		(net "M_B_DQS_DN<7>")
	)
	(arc
		(start 286.088074 -58.476388)
		(mid 286.586955 -58.180951)
		(end 286.59328 -57.601104)
		(width 0.0889)
		(layer "In4.Cu")
		(net "M_B_DQS_DN<7>")
	)
	(arc
		(start 284.870144 -60.562236)
		(mid 284.816611 -60.362338)
		(end 284.870144 -60.16244)
		(width 0.0889)
		(layer "In4.Cu")
		(net "M_B_DQS_DN<7>")
	)
	(arc
		(start 284.870144 -61.15304)
		(mid 284.949333 -60.866425)
		(end 284.879034 -60.577476)
		(width 0.0889)
		(layer "In4.Cu")
		(net "M_B_DQS_DN<7>")
	)
	(arc
		(start 286.582104 -55.6006)
		(mid 286.533349 -55.404248)
		(end 286.58693 -55.209186)
		(width 0.0889)
		(layer "In4.Cu")
		(net "M_B_DQS_DN<7>")
	)
	(segment
		(start 302.64989 -9.34847)
		(end 302.267874 -8.966454)
		(width 0.1651)
		(layer "F.Cu")
		(net "M_B_DQS_DN<6>")
	)
	(segment
		(start 284.330902 -50.160428)
		(end 285.03753 -49.4538)
		(width 0.0889)
		(layer "F.Cu")
		(net "M_B_DQS_DN<6>")
	)
	(segment
		(start 303.089818 -36.914582)
		(end 303.089818 -32.131)
		(width 0.1651)
		(layer "F.Cu")
		(net "M_B_DQS_DN<6>")
	)
	(segment
		(start 283.69641 -53.88102)
		(end 283.59735 -53.78196)
		(width 0.0889)
		(layer "F.Cu")
		(net "M_B_DQS_DN<6>")
	)
	(segment
		(start 298.5897 -41.4147)
		(end 303.089818 -36.914582)
		(width 0.1651)
		(layer "F.Cu")
		(net "M_B_DQS_DN<6>")
	)
	(segment
		(start 285.191962 -49.377346)
		(end 287.806384 -46.762924)
		(width 0.1016)
		(layer "F.Cu")
		(net "M_B_DQS_DN<6>")
	)
	(segment
		(start 303.089818 -30.460188)
		(end 302.593756 -29.964126)
		(width 0.1651)
		(layer "F.Cu")
		(net "M_B_DQS_DN<6>")
	)
	(segment
		(start 284.330902 -51.065938)
		(end 284.330902 -50.160428)
		(width 0.0889)
		(layer "F.Cu")
		(net "M_B_DQS_DN<6>")
	)
	(segment
		(start 302.593756 -27.788616)
		(end 303.038002 -27.34437)
		(width 0.1651)
		(layer "F.Cu")
		(net "M_B_DQS_DN<6>")
	)
	(segment
		(start 302.267874 -8.966454)
		(end 302.267874 -8.534654)
		(width 0.1651)
		(layer "F.Cu")
		(net "M_B_DQS_DN<6>")
	)
	(segment
		(start 303.089818 -32.131)
		(end 303.089818 -30.460188)
		(width 0.1651)
		(layer "F.Cu")
		(net "M_B_DQS_DN<6>")
	)
	(segment
		(start 285.03753 -49.4538)
		(end 285.115508 -49.4538)
		(width 0.0889)
		(layer "F.Cu")
		(net "M_B_DQS_DN<6>")
	)
	(segment
		(start 302.650398 -10.422382)
		(end 302.64989 -10.422382)
		(width 0.1651)
		(layer "F.Cu")
		(net "M_B_DQS_DN<6>")
	)
	(segment
		(start 298.581572 -41.867328)
		(end 298.5897 -41.8592)
		(width 0.1016)
		(layer "F.Cu")
		(net "M_B_DQS_DN<6>")
	)
	(segment
		(start 284.41777 -51.646582)
		(end 284.418024 -51.646836)
		(width 0.0889)
		(layer "F.Cu")
		(net "M_B_DQS_DN<6>")
	)
	(segment
		(start 298.581572 -42.822876)
		(end 298.581572 -41.867328)
		(width 0.1016)
		(layer "F.Cu")
		(net "M_B_DQS_DN<6>")
	)
	(segment
		(start 294.641524 -46.762924)
		(end 298.581572 -42.822876)
		(width 0.1016)
		(layer "F.Cu")
		(net "M_B_DQS_DN<6>")
	)
	(segment
		(start 284.418024 -51.646836)
		(end 284.423866 -51.636676)
		(width 0.0889)
		(layer "F.Cu")
		(net "M_B_DQS_DN<6>")
	)
	(segment
		(start 288.244026 -46.762924)
		(end 294.641524 -46.762924)
		(width 0.1016)
		(layer "F.Cu")
		(net "M_B_DQS_DN<6>")
	)
	(segment
		(start 284.071314 -54.418738)
		(end 283.817568 -53.88102)
		(width 0.0889)
		(layer "F.Cu")
		(net "M_B_DQS_DN<6>")
	)
	(segment
		(start 302.593756 -29.964126)
		(end 302.593756 -27.788616)
		(width 0.1651)
		(layer "F.Cu")
		(net "M_B_DQS_DN<6>")
	)
	(segment
		(start 284.423866 -51.227228)
		(end 284.330902 -51.065938)
		(width 0.0889)
		(layer "F.Cu")
		(net "M_B_DQS_DN<6>")
	)
	(segment
		(start 284.049724 -52.837334)
		(end 284.071314 -52.837334)
		(width 0.0889)
		(layer "F.Cu")
		(net "M_B_DQS_DN<6>")
	)
	(segment
		(start 283.817568 -53.88102)
		(end 283.69641 -53.88102)
		(width 0.0889)
		(layer "F.Cu")
		(net "M_B_DQS_DN<6>")
	)
	(segment
		(start 302.64989 -10.422382)
		(end 302.64989 -9.34847)
		(width 0.1651)
		(layer "F.Cu")
		(net "M_B_DQS_DN<6>")
	)
	(segment
		(start 302.598328 -8.2042)
		(end 302.822356 -8.2042)
		(width 0.1651)
		(layer "F.Cu")
		(net "M_B_DQS_DN<6>")
	)
	(segment
		(start 287.806384 -46.762924)
		(end 288.244026 -46.762924)
		(width 0.1016)
		(layer "F.Cu")
		(net "M_B_DQS_DN<6>")
	)
	(segment
		(start 302.822356 -8.2042)
		(end 303.038002 -8.419846)
		(width 0.1651)
		(layer "F.Cu")
		(net "M_B_DQS_DN<6>")
	)
	(segment
		(start 283.59735 -53.78196)
		(end 283.590238 -53.772054)
		(width 0.0889)
		(layer "F.Cu")
		(net "M_B_DQS_DN<6>")
	)
	(segment
		(start 285.115508 -49.4538)
		(end 285.191962 -49.377346)
		(width 0.0889)
		(layer "F.Cu")
		(net "M_B_DQS_DN<6>")
	)
	(segment
		(start 302.267874 -8.534654)
		(end 302.598328 -8.2042)
		(width 0.1651)
		(layer "F.Cu")
		(net "M_B_DQS_DN<6>")
	)
	(segment
		(start 284.423612 -51.227482)
		(end 284.423866 -51.227228)
		(width 0.0889)
		(layer "F.Cu")
		(net "M_B_DQS_DN<6>")
	)
	(segment
		(start 298.5897 -41.8592)
		(end 298.5897 -41.4147)
		(width 0.1651)
		(layer "F.Cu")
		(net "M_B_DQS_DN<6>")
	)
	(via
		(at 303.089818 -32.131)
		(size 0.508)
		(drill 0.254)
		(layers "F.Cu" "B.Cu")
		(net "M_B_DQS_DN<6>")
	)
	(via
		(at 303.038002 -12.627356)
		(size 0.508)
		(drill 0.254)
		(layers "F.Cu" "B.Cu")
		(net "M_B_DQS_DN<6>")
	)
	(via
		(at 303.038002 -27.34437)
		(size 0.508)
		(drill 0.254)
		(layers "F.Cu" "B.Cu")
		(net "M_B_DQS_DN<6>")
	)
	(via
		(at 303.038002 -8.419846)
		(size 0.508)
		(drill 0.254)
		(layers "F.Cu" "B.Cu")
		(net "M_B_DQS_DN<6>")
	)
	(arc
		(start 283.590238 -53.772054)
		(mid 283.54054 -53.167338)
		(end 284.049724 -52.837334)
		(width 0.0889)
		(layer "F.Cu")
		(net "M_B_DQS_DN<6>")
	)
	(arc
		(start 284.071314 -52.837334)
		(mid 284.41774 -52.637357)
		(end 284.41777 -52.237386)
		(width 0.0889)
		(layer "F.Cu")
		(net "M_B_DQS_DN<6>")
	)
	(arc
		(start 284.41777 -52.237386)
		(mid 284.338639 -51.941984)
		(end 284.41777 -51.646582)
		(width 0.0889)
		(layer "F.Cu")
		(net "M_B_DQS_DN<6>")
	)
	(arc
		(start 284.423866 -51.636676)
		(mid 284.478596 -51.432032)
		(end 284.423612 -51.227482)
		(width 0.0889)
		(layer "F.Cu")
		(net "M_B_DQS_DN<6>")
	)
	(segment
		(start 302.267874 -12.166346)
		(end 302.267874 -12.4968)
		(width 0.1651)
		(layer "B.Cu")
		(net "M_B_DQS_DN<6>")
	)
	(segment
		(start 302.812958 -12.8524)
		(end 303.038002 -12.627356)
		(width 0.1651)
		(layer "B.Cu")
		(net "M_B_DQS_DN<6>")
	)
	(segment
		(start 302.521874 -11.912346)
		(end 302.267874 -12.166346)
		(width 0.1651)
		(layer "B.Cu")
		(net "M_B_DQS_DN<6>")
	)
	(segment
		(start 302.521874 -11.658346)
		(end 302.521874 -11.912346)
		(width 0.1651)
		(layer "B.Cu")
		(net "M_B_DQS_DN<6>")
	)
	(segment
		(start 302.64989 -10.623042)
		(end 302.64989 -11.53033)
		(width 0.1651)
		(layer "B.Cu")
		(net "M_B_DQS_DN<6>")
	)
	(segment
		(start 302.623474 -12.8524)
		(end 302.812958 -12.8524)
		(width 0.1651)
		(layer "B.Cu")
		(net "M_B_DQS_DN<6>")
	)
	(segment
		(start 302.64989 -11.53033)
		(end 302.521874 -11.658346)
		(width 0.1651)
		(layer "B.Cu")
		(net "M_B_DQS_DN<6>")
	)
	(segment
		(start 302.650398 -10.623042)
		(end 302.64989 -10.623042)
		(width 0.1651)
		(layer "B.Cu")
		(net "M_B_DQS_DN<6>")
	)
	(segment
		(start 302.267874 -12.4968)
		(end 302.623474 -12.8524)
		(width 0.1651)
		(layer "B.Cu")
		(net "M_B_DQS_DN<6>")
	)
	(segment
		(start 303.038002 -12.627356)
		(end 302.600106 -13.065252)
		(width 0.14224)
		(layer "In4.Cu")
		(net "M_B_DQS_DN<6>")
	)
	(segment
		(start 303.57953 -10.339578)
		(end 303.57953 -10.68832)
		(width 0.14224)
		(layer "In4.Cu")
		(net "M_B_DQS_DN<6>")
	)
	(segment
		(start 303.26965 -10.8712)
		(end 303.09185 -11.049)
		(width 0.14224)
		(layer "In4.Cu")
		(net "M_B_DQS_DN<6>")
	)
	(segment
		(start 303.26965 -11.4808)
		(end 303.400206 -11.4808)
		(width 0.14224)
		(layer "In4.Cu")
		(net "M_B_DQS_DN<6>")
	)
	(segment
		(start 303.05248 -14.61008)
		(end 303.05248 -14.780768)
		(width 0.14224)
		(layer "In4.Cu")
		(net "M_B_DQS_DN<6>")
	)
	(segment
		(start 303.19726 -9.525)
		(end 303.044606 -9.677654)
		(width 0.14224)
		(layer "In4.Cu")
		(net "M_B_DQS_DN<6>")
	)
	(segment
		(start 303.57953 -9.345422)
		(end 303.399952 -9.525)
		(width 0.14224)
		(layer "In4.Cu")
		(net "M_B_DQS_DN<6>")
	)
	(segment
		(start 303.319688 -8.419846)
		(end 303.57953 -8.679688)
		(width 0.14224)
		(layer "In4.Cu")
		(net "M_B_DQS_DN<6>")
	)
	(segment
		(start 303.044606 -9.677654)
		(end 303.044606 -9.981946)
		(width 0.14224)
		(layer "In4.Cu")
		(net "M_B_DQS_DN<6>")
	)
	(segment
		(start 303.39665 -10.8712)
		(end 303.26965 -10.8712)
		(width 0.14224)
		(layer "In4.Cu")
		(net "M_B_DQS_DN<6>")
	)
	(segment
		(start 303.038002 -8.419846)
		(end 303.319688 -8.419846)
		(width 0.14224)
		(layer "In4.Cu")
		(net "M_B_DQS_DN<6>")
	)
	(segment
		(start 302.600106 -13.065252)
		(end 302.600106 -14.157706)
		(width 0.14224)
		(layer "In4.Cu")
		(net "M_B_DQS_DN<6>")
	)
	(segment
		(start 303.53508 -26.847292)
		(end 303.038002 -27.34437)
		(width 0.14224)
		(layer "In4.Cu")
		(net "M_B_DQS_DN<6>")
	)
	(segment
		(start 303.09185 -11.049)
		(end 303.09185 -11.303)
		(width 0.14224)
		(layer "In4.Cu")
		(net "M_B_DQS_DN<6>")
	)
	(segment
		(start 303.044606 -9.981946)
		(end 303.19726 -10.1346)
		(width 0.14224)
		(layer "In4.Cu")
		(net "M_B_DQS_DN<6>")
	)
	(segment
		(start 303.400206 -11.4808)
		(end 303.57953 -11.660124)
		(width 0.14224)
		(layer "In4.Cu")
		(net "M_B_DQS_DN<6>")
	)
	(segment
		(start 303.57953 -8.679688)
		(end 303.57953 -9.345422)
		(width 0.14224)
		(layer "In4.Cu")
		(net "M_B_DQS_DN<6>")
	)
	(segment
		(start 303.374552 -10.1346)
		(end 303.57953 -10.339578)
		(width 0.14224)
		(layer "In4.Cu")
		(net "M_B_DQS_DN<6>")
	)
	(segment
		(start 303.038002 -12.62761)
		(end 303.038002 -12.627356)
		(width 0.14224)
		(layer "In4.Cu")
		(net "M_B_DQS_DN<6>")
	)
	(segment
		(start 303.57953 -12.364974)
		(end 303.316894 -12.62761)
		(width 0.14224)
		(layer "In4.Cu")
		(net "M_B_DQS_DN<6>")
	)
	(segment
		(start 303.19726 -10.1346)
		(end 303.374552 -10.1346)
		(width 0.14224)
		(layer "In4.Cu")
		(net "M_B_DQS_DN<6>")
	)
	(segment
		(start 303.05248 -14.780768)
		(end 303.53508 -15.263368)
		(width 0.14224)
		(layer "In4.Cu")
		(net "M_B_DQS_DN<6>")
	)
	(segment
		(start 302.600106 -14.157706)
		(end 303.05248 -14.61008)
		(width 0.14224)
		(layer "In4.Cu")
		(net "M_B_DQS_DN<6>")
	)
	(segment
		(start 303.57953 -10.68832)
		(end 303.39665 -10.8712)
		(width 0.14224)
		(layer "In4.Cu")
		(net "M_B_DQS_DN<6>")
	)
	(segment
		(start 303.316894 -12.62761)
		(end 303.038002 -12.62761)
		(width 0.14224)
		(layer "In4.Cu")
		(net "M_B_DQS_DN<6>")
	)
	(segment
		(start 303.09185 -11.303)
		(end 303.26965 -11.4808)
		(width 0.14224)
		(layer "In4.Cu")
		(net "M_B_DQS_DN<6>")
	)
	(segment
		(start 303.57953 -11.660124)
		(end 303.57953 -12.364974)
		(width 0.14224)
		(layer "In4.Cu")
		(net "M_B_DQS_DN<6>")
	)
	(segment
		(start 303.53508 -15.263368)
		(end 303.53508 -26.847292)
		(width 0.14224)
		(layer "In4.Cu")
		(net "M_B_DQS_DN<6>")
	)
	(segment
		(start 303.399952 -9.525)
		(end 303.19726 -9.525)
		(width 0.14224)
		(layer "In4.Cu")
		(net "M_B_DQS_DN<6>")
	)
	(segment
		(start 292.913054 -8.961882)
		(end 292.913054 -8.539226)
		(width 0.1651)
		(layer "F.Cu")
		(net "M_B_DQS_DN<5>")
	)
	(segment
		(start 293.24808 -8.2042)
		(end 293.472108 -8.2042)
		(width 0.1651)
		(layer "F.Cu")
		(net "M_B_DQS_DN<5>")
	)
	(segment
		(start 284.051248 -41.0718)
		(end 284.051248 -41.246552)
		(width 0.1016)
		(layer "F.Cu")
		(net "M_B_DQS_DN<5>")
	)
	(segment
		(start 289.872674 -35.519614)
		(end 293.233348 -32.15894)
		(width 0.1651)
		(layer "F.Cu")
		(net "M_B_DQS_DN<5>")
	)
	(segment
		(start 287.419288 -37.973)
		(end 286.8168 -37.973)
		(width 0.1651)
		(layer "F.Cu")
		(net "M_B_DQS_DN<5>")
	)
	(segment
		(start 279.297384 -49.70653)
		(end 279.297384 -51.533044)
		(width 0.0889)
		(layer "F.Cu")
		(net "M_B_DQS_DN<5>")
	)
	(segment
		(start 279.266904 -52.23764)
		(end 279.266904 -52.237386)
		(width 0.0889)
		(layer "F.Cu")
		(net "M_B_DQS_DN<5>")
	)
	(segment
		(start 292.913054 -8.539226)
		(end 293.24808 -8.2042)
		(width 0.1651)
		(layer "F.Cu")
		(net "M_B_DQS_DN<5>")
	)
	(segment
		(start 293.300404 -10.422382)
		(end 293.300404 -9.349232)
		(width 0.1651)
		(layer "F.Cu")
		(net "M_B_DQS_DN<5>")
	)
	(segment
		(start 293.238682 -27.793696)
		(end 293.688008 -27.34437)
		(width 0.1651)
		(layer "F.Cu")
		(net "M_B_DQS_DN<5>")
	)
	(segment
		(start 293.472108 -8.2042)
		(end 293.687754 -8.419846)
		(width 0.1651)
		(layer "F.Cu")
		(net "M_B_DQS_DN<5>")
	)
	(segment
		(start 293.238682 -29.250386)
		(end 293.238682 -27.793696)
		(width 0.1651)
		(layer "F.Cu")
		(net "M_B_DQS_DN<5>")
	)
	(segment
		(start 279.198324 -49.60747)
		(end 279.297384 -49.70653)
		(width 0.0889)
		(layer "F.Cu")
		(net "M_B_DQS_DN<5>")
	)
	(segment
		(start 279.198324 -47.683166)
		(end 279.198324 -49.60747)
		(width 0.1016)
		(layer "F.Cu")
		(net "M_B_DQS_DN<5>")
	)
	(segment
		(start 293.233348 -32.15894)
		(end 293.233348 -29.25572)
		(width 0.1651)
		(layer "F.Cu")
		(net "M_B_DQS_DN<5>")
	)
	(segment
		(start 278.93137 -52.837334)
		(end 278.898604 -52.837334)
		(width 0.0889)
		(layer "F.Cu")
		(net "M_B_DQS_DN<5>")
	)
	(segment
		(start 293.233348 -29.25572)
		(end 293.238682 -29.250386)
		(width 0.1651)
		(layer "F.Cu")
		(net "M_B_DQS_DN<5>")
	)
	(segment
		(start 284.000448 -42.881042)
		(end 279.198324 -47.683166)
		(width 0.1016)
		(layer "F.Cu")
		(net "M_B_DQS_DN<5>")
	)
	(segment
		(start 289.872674 -35.519614)
		(end 287.419288 -37.973)
		(width 0.1651)
		(layer "F.Cu")
		(net "M_B_DQS_DN<5>")
	)
	(segment
		(start 284.051248 -41.246552)
		(end 284.000448 -41.297352)
		(width 0.1016)
		(layer "F.Cu")
		(net "M_B_DQS_DN<5>")
	)
	(segment
		(start 293.300404 -9.349232)
		(end 292.913054 -8.961882)
		(width 0.1651)
		(layer "F.Cu")
		(net "M_B_DQS_DN<5>")
	)
	(segment
		(start 286.8168 -37.973)
		(end 284.051248 -40.738552)
		(width 0.1651)
		(layer "F.Cu")
		(net "M_B_DQS_DN<5>")
	)
	(segment
		(start 284.051248 -40.738552)
		(end 284.051248 -41.0718)
		(width 0.1651)
		(layer "F.Cu")
		(net "M_B_DQS_DN<5>")
	)
	(segment
		(start 284.000448 -41.297352)
		(end 284.000448 -42.881042)
		(width 0.1016)
		(layer "F.Cu")
		(net "M_B_DQS_DN<5>")
	)
	(segment
		(start 278.450802 -53.788056)
		(end 278.920194 -54.418738)
		(width 0.0889)
		(layer "F.Cu")
		(net "M_B_DQS_DN<5>")
	)
	(via
		(at 293.688008 -27.34437)
		(size 0.508)
		(drill 0.254)
		(layers "F.Cu" "B.Cu")
		(net "M_B_DQS_DN<5>")
	)
	(via
		(at 293.687754 -12.627356)
		(size 0.508)
		(drill 0.254)
		(layers "F.Cu" "B.Cu")
		(net "M_B_DQS_DN<5>")
	)
	(via
		(at 293.687754 -8.419846)
		(size 0.508)
		(drill 0.254)
		(layers "F.Cu" "B.Cu")
		(net "M_B_DQS_DN<5>")
	)
	(via
		(at 289.872674 -35.519614)
		(size 0.508)
		(drill 0.254)
		(layers "F.Cu" "B.Cu")
		(net "M_B_DQS_DN<5>")
	)
	(arc
		(start 279.297384 -51.533044)
		(mid 279.28963 -51.591945)
		(end 279.266904 -51.646836)
		(width 0.0889)
		(layer "F.Cu")
		(net "M_B_DQS_DN<5>")
	)
	(arc
		(start 279.266904 -52.237386)
		(mid 279.269487 -52.632633)
		(end 278.93137 -52.837334)
		(width 0.0889)
		(layer "F.Cu")
		(net "M_B_DQS_DN<5>")
	)
	(arc
		(start 279.266904 -51.646836)
		(mid 279.187773 -51.942238)
		(end 279.266904 -52.23764)
		(width 0.0889)
		(layer "F.Cu")
		(net "M_B_DQS_DN<5>")
	)
	(arc
		(start 278.898604 -52.837334)
		(mid 278.384872 -53.17621)
		(end 278.450802 -53.788056)
		(width 0.0889)
		(layer "F.Cu")
		(net "M_B_DQS_DN<5>")
	)
	(segment
		(start 293.46271 -12.8524)
		(end 293.687754 -12.627356)
		(width 0.1651)
		(layer "B.Cu")
		(net "M_B_DQS_DN<5>")
	)
	(segment
		(start 293.171626 -11.658346)
		(end 293.171626 -11.912346)
		(width 0.1651)
		(layer "B.Cu")
		(net "M_B_DQS_DN<5>")
	)
	(segment
		(start 292.917626 -12.166346)
		(end 292.917626 -12.4968)
		(width 0.1651)
		(layer "B.Cu")
		(net "M_B_DQS_DN<5>")
	)
	(segment
		(start 293.273226 -12.8524)
		(end 293.46271 -12.8524)
		(width 0.1651)
		(layer "B.Cu")
		(net "M_B_DQS_DN<5>")
	)
	(segment
		(start 293.299896 -11.530076)
		(end 293.171626 -11.658346)
		(width 0.1651)
		(layer "B.Cu")
		(net "M_B_DQS_DN<5>")
	)
	(segment
		(start 292.917626 -12.4968)
		(end 293.273226 -12.8524)
		(width 0.1651)
		(layer "B.Cu")
		(net "M_B_DQS_DN<5>")
	)
	(segment
		(start 293.300404 -10.623042)
		(end 293.299896 -10.623042)
		(width 0.1651)
		(layer "B.Cu")
		(net "M_B_DQS_DN<5>")
	)
	(segment
		(start 293.171626 -11.912346)
		(end 292.917626 -12.166346)
		(width 0.1651)
		(layer "B.Cu")
		(net "M_B_DQS_DN<5>")
	)
	(segment
		(start 293.299896 -10.623042)
		(end 293.299896 -11.530076)
		(width 0.1651)
		(layer "B.Cu")
		(net "M_B_DQS_DN<5>")
	)
	(segment
		(start 293.687754 -12.627356)
		(end 293.687754 -12.62761)
		(width 0.14224)
		(layer "In11.Cu")
		(net "M_B_DQS_DN<5>")
	)
	(segment
		(start 294.229536 -10.68832)
		(end 294.046656 -10.8712)
		(width 0.14224)
		(layer "In11.Cu")
		(net "M_B_DQS_DN<5>")
	)
	(segment
		(start 294.049958 -9.525)
		(end 293.847266 -9.525)
		(width 0.14224)
		(layer "In11.Cu")
		(net "M_B_DQS_DN<5>")
	)
	(segment
		(start 293.694612 -9.981946)
		(end 293.847266 -10.1346)
		(width 0.14224)
		(layer "In11.Cu")
		(net "M_B_DQS_DN<5>")
	)
	(segment
		(start 293.847266 -10.1346)
		(end 294.024558 -10.1346)
		(width 0.14224)
		(layer "In11.Cu")
		(net "M_B_DQS_DN<5>")
	)
	(segment
		(start 294.050212 -11.4808)
		(end 294.229536 -11.660124)
		(width 0.14224)
		(layer "In11.Cu")
		(net "M_B_DQS_DN<5>")
	)
	(segment
		(start 293.9669 -12.62761)
		(end 293.687754 -12.62761)
		(width 0.14224)
		(layer "In11.Cu")
		(net "M_B_DQS_DN<5>")
	)
	(segment
		(start 293.969694 -8.419846)
		(end 294.229536 -8.679688)
		(width 0.14224)
		(layer "In11.Cu")
		(net "M_B_DQS_DN<5>")
	)
	(segment
		(start 293.847266 -9.525)
		(end 293.694612 -9.677654)
		(width 0.14224)
		(layer "In11.Cu")
		(net "M_B_DQS_DN<5>")
	)
	(segment
		(start 293.741856 -11.049)
		(end 293.741856 -11.303)
		(width 0.14224)
		(layer "In11.Cu")
		(net "M_B_DQS_DN<5>")
	)
	(segment
		(start 293.250112 -13.065252)
		(end 293.250112 -14.157706)
		(width 0.14224)
		(layer "In11.Cu")
		(net "M_B_DQS_DN<5>")
	)
	(segment
		(start 294.229536 -10.339578)
		(end 294.229536 -10.68832)
		(width 0.14224)
		(layer "In11.Cu")
		(net "M_B_DQS_DN<5>")
	)
	(segment
		(start 293.919656 -11.4808)
		(end 294.050212 -11.4808)
		(width 0.14224)
		(layer "In11.Cu")
		(net "M_B_DQS_DN<5>")
	)
	(segment
		(start 294.229536 -8.679688)
		(end 294.229536 -9.345422)
		(width 0.14224)
		(layer "In11.Cu")
		(net "M_B_DQS_DN<5>")
	)
	(segment
		(start 293.741856 -11.303)
		(end 293.919656 -11.4808)
		(width 0.14224)
		(layer "In11.Cu")
		(net "M_B_DQS_DN<5>")
	)
	(segment
		(start 294.185086 -26.847292)
		(end 293.688008 -27.34437)
		(width 0.14224)
		(layer "In11.Cu")
		(net "M_B_DQS_DN<5>")
	)
	(segment
		(start 293.687754 -12.62761)
		(end 293.250112 -13.065252)
		(width 0.14224)
		(layer "In11.Cu")
		(net "M_B_DQS_DN<5>")
	)
	(segment
		(start 293.702486 -14.61008)
		(end 293.702486 -14.780768)
		(width 0.14224)
		(layer "In11.Cu")
		(net "M_B_DQS_DN<5>")
	)
	(segment
		(start 293.687754 -8.419846)
		(end 293.969694 -8.419846)
		(width 0.14224)
		(layer "In11.Cu")
		(net "M_B_DQS_DN<5>")
	)
	(segment
		(start 293.702486 -14.780768)
		(end 294.185086 -15.263368)
		(width 0.14224)
		(layer "In11.Cu")
		(net "M_B_DQS_DN<5>")
	)
	(segment
		(start 294.046656 -10.8712)
		(end 293.919656 -10.8712)
		(width 0.14224)
		(layer "In11.Cu")
		(net "M_B_DQS_DN<5>")
	)
	(segment
		(start 294.229536 -9.345422)
		(end 294.049958 -9.525)
		(width 0.14224)
		(layer "In11.Cu")
		(net "M_B_DQS_DN<5>")
	)
	(segment
		(start 294.229536 -11.660124)
		(end 294.229536 -12.364974)
		(width 0.14224)
		(layer "In11.Cu")
		(net "M_B_DQS_DN<5>")
	)
	(segment
		(start 293.694612 -9.677654)
		(end 293.694612 -9.981946)
		(width 0.14224)
		(layer "In11.Cu")
		(net "M_B_DQS_DN<5>")
	)
	(segment
		(start 293.250112 -14.157706)
		(end 293.702486 -14.61008)
		(width 0.14224)
		(layer "In11.Cu")
		(net "M_B_DQS_DN<5>")
	)
	(segment
		(start 293.919656 -10.8712)
		(end 293.741856 -11.049)
		(width 0.14224)
		(layer "In11.Cu")
		(net "M_B_DQS_DN<5>")
	)
	(segment
		(start 294.229536 -12.364974)
		(end 293.9669 -12.62761)
		(width 0.14224)
		(layer "In11.Cu")
		(net "M_B_DQS_DN<5>")
	)
	(segment
		(start 294.024558 -10.1346)
		(end 294.229536 -10.339578)
		(width 0.14224)
		(layer "In11.Cu")
		(net "M_B_DQS_DN<5>")
	)
	(segment
		(start 294.185086 -15.263368)
		(end 294.185086 -26.847292)
		(width 0.14224)
		(layer "In11.Cu")
		(net "M_B_DQS_DN<5>")
	)
	(segment
		(start 283.95041 -9.349232)
		(end 283.567632 -8.966454)
		(width 0.1651)
		(layer "F.Cu")
		(net "M_B_DQS_DN<4>")
	)
	(segment
		(start 284.122114 -8.2042)
		(end 284.33776 -8.419846)
		(width 0.1651)
		(layer "F.Cu")
		(net "M_B_DQS_DN<4>")
	)
	(segment
		(start 283.95041 -10.422382)
		(end 283.95041 -9.349232)
		(width 0.1651)
		(layer "F.Cu")
		(net "M_B_DQS_DN<4>")
	)
	(segment
		(start 283.567632 -8.966454)
		(end 283.567632 -8.534654)
		(width 0.1651)
		(layer "F.Cu")
		(net "M_B_DQS_DN<4>")
	)
	(segment
		(start 283.898086 -8.2042)
		(end 284.122114 -8.2042)
		(width 0.1651)
		(layer "F.Cu")
		(net "M_B_DQS_DN<4>")
	)
	(segment
		(start 283.567632 -8.534654)
		(end 283.898086 -8.2042)
		(width 0.1651)
		(layer "F.Cu")
		(net "M_B_DQS_DN<4>")
	)
	(segment
		(start 272.052288 -57.390538)
		(end 271.480788 -57.390538)
		(width 0.1016)
		(layer "F.Cu")
		(net "M_B_DQS_DN<4>")
	)
	(via
		(at 284.33776 -12.627356)
		(size 0.508)
		(drill 0.254)
		(layers "F.Cu" "B.Cu")
		(net "M_B_DQS_DN<4>")
	)
	(via
		(at 271.480788 -57.390538)
		(size 0.508)
		(drill 0.254)
		(layers "F.Cu" "B.Cu")
		(net "M_B_DQS_DN<4>")
	)
	(via
		(at 284.33776 -8.419846)
		(size 0.508)
		(drill 0.254)
		(layers "F.Cu" "B.Cu")
		(net "M_B_DQS_DN<4>")
	)
	(segment
		(start 283.949902 -10.623042)
		(end 283.949902 -11.530076)
		(width 0.1651)
		(layer "B.Cu")
		(net "M_B_DQS_DN<4>")
	)
	(segment
		(start 283.821632 -11.912346)
		(end 283.567632 -12.166346)
		(width 0.1651)
		(layer "B.Cu")
		(net "M_B_DQS_DN<4>")
	)
	(segment
		(start 283.567632 -12.4968)
		(end 283.923232 -12.8524)
		(width 0.1651)
		(layer "B.Cu")
		(net "M_B_DQS_DN<4>")
	)
	(segment
		(start 283.949902 -11.530076)
		(end 283.821632 -11.658346)
		(width 0.1651)
		(layer "B.Cu")
		(net "M_B_DQS_DN<4>")
	)
	(segment
		(start 283.567632 -12.166346)
		(end 283.567632 -12.4968)
		(width 0.1651)
		(layer "B.Cu")
		(net "M_B_DQS_DN<4>")
	)
	(segment
		(start 283.923232 -12.8524)
		(end 284.112716 -12.8524)
		(width 0.1651)
		(layer "B.Cu")
		(net "M_B_DQS_DN<4>")
	)
	(segment
		(start 283.821632 -11.658346)
		(end 283.821632 -11.912346)
		(width 0.1651)
		(layer "B.Cu")
		(net "M_B_DQS_DN<4>")
	)
	(segment
		(start 283.95041 -10.623042)
		(end 283.949902 -10.623042)
		(width 0.1651)
		(layer "B.Cu")
		(net "M_B_DQS_DN<4>")
	)
	(segment
		(start 284.112716 -12.8524)
		(end 284.33776 -12.627356)
		(width 0.1651)
		(layer "B.Cu")
		(net "M_B_DQS_DN<4>")
	)
	(segment
		(start 280.29408 -31.286196)
		(end 284.851094 -26.729182)
		(width 0.14224)
		(layer "In4.Cu")
		(net "M_B_DQS_DN<4>")
	)
	(segment
		(start 284.391608 -11.303)
		(end 284.391608 -11.049)
		(width 0.14224)
		(layer "In4.Cu")
		(net "M_B_DQS_DN<4>")
	)
	(segment
		(start 284.344364 -9.677654)
		(end 284.497018 -9.525)
		(width 0.14224)
		(layer "In4.Cu")
		(net "M_B_DQS_DN<4>")
	)
	(segment
		(start 274.616418 -44.87037)
		(end 274.616418 -44.61637)
		(width 0.14224)
		(layer "In4.Cu")
		(net "M_B_DQS_DN<4>")
	)
	(segment
		(start 284.497018 -10.1346)
		(end 284.344364 -9.981946)
		(width 0.14224)
		(layer "In4.Cu")
		(net "M_B_DQS_DN<4>")
	)
	(segment
		(start 284.391608 -11.049)
		(end 284.569408 -10.8712)
		(width 0.14224)
		(layer "In4.Cu")
		(net "M_B_DQS_DN<4>")
	)
	(segment
		(start 284.497018 -9.525)
		(end 284.69971 -9.525)
		(width 0.14224)
		(layer "In4.Cu")
		(net "M_B_DQS_DN<4>")
	)
	(segment
		(start 284.879288 -8.679688)
		(end 284.619446 -8.419846)
		(width 0.14224)
		(layer "In4.Cu")
		(net "M_B_DQS_DN<4>")
	)
	(segment
		(start 284.879288 -12.364974)
		(end 284.879288 -11.660124)
		(width 0.14224)
		(layer "In4.Cu")
		(net "M_B_DQS_DN<4>")
	)
	(segment
		(start 283.892244 -15.092426)
		(end 283.892244 -13.072872)
		(width 0.14224)
		(layer "In4.Cu")
		(net "M_B_DQS_DN<4>")
	)
	(segment
		(start 284.879288 -11.660124)
		(end 284.699964 -11.4808)
		(width 0.14224)
		(layer "In4.Cu")
		(net "M_B_DQS_DN<4>")
	)
	(segment
		(start 273.277584 -49.37379)
		(end 273.56054 -49.090834)
		(width 0.0889)
		(layer "In4.Cu")
		(net "M_B_DQS_DN<4>")
	)
	(segment
		(start 274.782788 -45.653198)
		(end 274.743418 -45.613828)
		(width 0.0889)
		(layer "In4.Cu")
		(net "M_B_DQS_DN<4>")
	)
	(segment
		(start 274.616418 -43.791124)
		(end 274.743418 -43.664124)
		(width 0.14224)
		(layer "In4.Cu")
		(net "M_B_DQS_DN<4>")
	)
	(segment
		(start 274.743418 -45.59173)
		(end 274.743418 -44.99737)
		(width 0.14224)
		(layer "In4.Cu")
		(net "M_B_DQS_DN<4>")
	)
	(segment
		(start 274.616418 -44.61637)
		(end 274.743418 -44.48937)
		(width 0.14224)
		(layer "In4.Cu")
		(net "M_B_DQS_DN<4>")
	)
	(segment
		(start 284.67431 -10.1346)
		(end 284.497018 -10.1346)
		(width 0.14224)
		(layer "In4.Cu")
		(net "M_B_DQS_DN<4>")
	)
	(segment
		(start 284.879288 -10.68832)
		(end 284.879288 -10.339578)
		(width 0.14224)
		(layer "In4.Cu")
		(net "M_B_DQS_DN<4>")
	)
	(segment
		(start 272.317718 -55.314088)
		(end 272.350484 -55.314088)
		(width 0.0889)
		(layer "In4.Cu")
		(net "M_B_DQS_DN<4>")
	)
	(segment
		(start 284.851094 -26.729182)
		(end 284.851094 -16.051276)
		(width 0.14224)
		(layer "In4.Cu")
		(net "M_B_DQS_DN<4>")
	)
	(segment
		(start 284.33776 -12.62761)
		(end 284.616652 -12.62761)
		(width 0.14224)
		(layer "In4.Cu")
		(net "M_B_DQS_DN<4>")
	)
	(segment
		(start 284.696408 -10.8712)
		(end 284.879288 -10.68832)
		(width 0.14224)
		(layer "In4.Cu")
		(net "M_B_DQS_DN<4>")
	)
	(segment
		(start 284.879288 -10.339578)
		(end 284.67431 -10.1346)
		(width 0.14224)
		(layer "In4.Cu")
		(net "M_B_DQS_DN<4>")
	)
	(segment
		(start 284.619446 -8.419846)
		(end 284.33776 -8.419846)
		(width 0.14224)
		(layer "In4.Cu")
		(net "M_B_DQS_DN<4>")
	)
	(segment
		(start 271.480788 -57.390538)
		(end 271.480788 -57.728612)
		(width 0.0889)
		(layer "In4.Cu")
		(net "M_B_DQS_DN<4>")
	)
	(segment
		(start 272.563336 -52.857146)
		(end 272.563336 -52.105814)
		(width 0.0889)
		(layer "In4.Cu")
		(net "M_B_DQS_DN<4>")
	)
	(segment
		(start 284.851094 -16.051276)
		(end 283.892244 -15.092426)
		(width 0.14224)
		(layer "In4.Cu")
		(net "M_B_DQS_DN<4>")
	)
	(segment
		(start 273.56054 -47.729648)
		(end 274.782788 -46.5074)
		(width 0.0889)
		(layer "In4.Cu")
		(net "M_B_DQS_DN<4>")
	)
	(segment
		(start 271.480788 -57.728612)
		(end 271.5387 -57.786524)
		(width 0.0889)
		(layer "In4.Cu")
		(net "M_B_DQS_DN<4>")
	)
	(segment
		(start 274.743418 -37.71011)
		(end 280.29408 -32.159448)
		(width 0.14224)
		(layer "In4.Cu")
		(net "M_B_DQS_DN<4>")
	)
	(segment
		(start 284.616652 -12.62761)
		(end 284.879288 -12.364974)
		(width 0.14224)
		(layer "In4.Cu")
		(net "M_B_DQS_DN<4>")
	)
	(segment
		(start 274.782788 -46.5074)
		(end 274.782788 -45.653198)
		(width 0.0889)
		(layer "In4.Cu")
		(net "M_B_DQS_DN<4>")
	)
	(segment
		(start 284.569408 -11.4808)
		(end 284.391608 -11.303)
		(width 0.14224)
		(layer "In4.Cu")
		(net "M_B_DQS_DN<4>")
	)
	(segment
		(start 273.56054 -49.090834)
		(end 273.56054 -47.729648)
		(width 0.0889)
		(layer "In4.Cu")
		(net "M_B_DQS_DN<4>")
	)
	(segment
		(start 284.69971 -9.525)
		(end 284.879288 -9.345422)
		(width 0.14224)
		(layer "In4.Cu")
		(net "M_B_DQS_DN<4>")
	)
	(segment
		(start 272.739358 -53.033168)
		(end 272.563336 -52.857146)
		(width 0.0889)
		(layer "In4.Cu")
		(net "M_B_DQS_DN<4>")
	)
	(segment
		(start 284.879288 -9.345422)
		(end 284.879288 -8.679688)
		(width 0.14224)
		(layer "In4.Cu")
		(net "M_B_DQS_DN<4>")
	)
	(segment
		(start 274.743418 -44.172124)
		(end 274.616418 -44.045124)
		(width 0.14224)
		(layer "In4.Cu")
		(net "M_B_DQS_DN<4>")
	)
	(segment
		(start 284.569408 -10.8712)
		(end 284.696408 -10.8712)
		(width 0.14224)
		(layer "In4.Cu")
		(net "M_B_DQS_DN<4>")
	)
	(segment
		(start 274.743418 -45.613828)
		(end 274.743418 -45.59173)
		(width 0.0889)
		(layer "In4.Cu")
		(net "M_B_DQS_DN<4>")
	)
	(segment
		(start 274.743418 -44.99737)
		(end 274.616418 -44.87037)
		(width 0.14224)
		(layer "In4.Cu")
		(net "M_B_DQS_DN<4>")
	)
	(segment
		(start 283.892244 -13.072872)
		(end 284.33776 -12.627356)
		(width 0.14224)
		(layer "In4.Cu")
		(net "M_B_DQS_DN<4>")
	)
	(segment
		(start 274.743418 -43.664124)
		(end 274.743418 -37.71011)
		(width 0.14224)
		(layer "In4.Cu")
		(net "M_B_DQS_DN<4>")
	)
	(segment
		(start 273.277584 -51.391566)
		(end 273.277584 -49.37379)
		(width 0.0889)
		(layer "In4.Cu")
		(net "M_B_DQS_DN<4>")
	)
	(segment
		(start 274.743418 -44.48937)
		(end 274.743418 -44.172124)
		(width 0.14224)
		(layer "In4.Cu")
		(net "M_B_DQS_DN<4>")
	)
	(segment
		(start 284.344364 -9.981946)
		(end 284.344364 -9.677654)
		(width 0.14224)
		(layer "In4.Cu")
		(net "M_B_DQS_DN<4>")
	)
	(segment
		(start 272.563336 -52.105814)
		(end 273.277584 -51.391566)
		(width 0.0889)
		(layer "In4.Cu")
		(net "M_B_DQS_DN<4>")
	)
	(segment
		(start 284.33776 -12.627356)
		(end 284.33776 -12.62761)
		(width 0.14224)
		(layer "In4.Cu")
		(net "M_B_DQS_DN<4>")
	)
	(segment
		(start 280.29408 -32.159448)
		(end 280.29408 -31.286196)
		(width 0.14224)
		(layer "In4.Cu")
		(net "M_B_DQS_DN<4>")
	)
	(segment
		(start 274.616418 -44.045124)
		(end 274.616418 -43.791124)
		(width 0.14224)
		(layer "In4.Cu")
		(net "M_B_DQS_DN<4>")
	)
	(segment
		(start 272.739358 -54.899306)
		(end 272.739358 -53.033168)
		(width 0.0889)
		(layer "In4.Cu")
		(net "M_B_DQS_DN<4>")
	)
	(segment
		(start 284.699964 -11.4808)
		(end 284.569408 -11.4808)
		(width 0.14224)
		(layer "In4.Cu")
		(net "M_B_DQS_DN<4>")
	)
	(arc
		(start 271.827498 -56.20004)
		(mid 271.822244 -55.618532)
		(end 272.317718 -55.314088)
		(width 0.0889)
		(layer "In4.Cu")
		(net "M_B_DQS_DN<4>")
	)
	(arc
		(start 271.65808 -57.749186)
		(mid 271.863658 -57.506605)
		(end 271.827498 -57.19064)
		(width 0.0889)
		(layer "In4.Cu")
		(net "M_B_DQS_DN<4>")
	)
	(arc
		(start 271.5387 -57.786524)
		(mid 271.599866 -57.772569)
		(end 271.65808 -57.749186)
		(width 0.0889)
		(layer "In4.Cu")
		(net "M_B_DQS_DN<4>")
	)
	(arc
		(start 272.350484 -55.314088)
		(mid 272.631307 -55.18772)
		(end 272.739358 -54.899306)
		(width 0.0889)
		(layer "In4.Cu")
		(net "M_B_DQS_DN<4>")
	)
	(arc
		(start 271.827498 -56.599836)
		(mid 271.880997 -56.399938)
		(end 271.827498 -56.20004)
		(width 0.0889)
		(layer "In4.Cu")
		(net "M_B_DQS_DN<4>")
	)
	(arc
		(start 271.827498 -57.19064)
		(mid 271.748367 -56.895238)
		(end 271.827498 -56.599836)
		(width 0.0889)
		(layer "In4.Cu")
		(net "M_B_DQS_DN<4>")
	)
	(segment
		(start 229.16388 -32.886904)
		(end 229.16388 -34.417)
		(width 0.1651)
		(layer "F.Cu")
		(net "M_B_DQS_DN<3>")
	)
	(segment
		(start 232.519474 -45.870114)
		(end 233.80065 -47.15129)
		(width 0.1016)
		(layer "F.Cu")
		(net "M_B_DQS_DN<3>")
	)
	(segment
		(start 228.70033 -10.422382)
		(end 228.699822 -10.422382)
		(width 0.1651)
		(layer "F.Cu")
		(net "M_B_DQS_DN<3>")
	)
	(segment
		(start 228.6254 -32.348424)
		(end 229.16388 -32.886904)
		(width 0.1651)
		(layer "F.Cu")
		(net "M_B_DQS_DN<3>")
	)
	(segment
		(start 243.910104 -52.782216)
		(end 243.910104 -53.113686)
		(width 0.0889)
		(layer "F.Cu")
		(net "M_B_DQS_DN<3>")
	)
	(segment
		(start 228.64826 -8.2042)
		(end 228.872288 -8.2042)
		(width 0.1651)
		(layer "F.Cu")
		(net "M_B_DQS_DN<3>")
	)
	(segment
		(start 232.273856 -45.723556)
		(end 232.420414 -45.870114)
		(width 0.1016)
		(layer "F.Cu")
		(net "M_B_DQS_DN<3>")
	)
	(segment
		(start 229.087934 -27.34437)
		(end 228.638608 -27.793696)
		(width 0.1651)
		(layer "F.Cu")
		(net "M_B_DQS_DN<3>")
	)
	(segment
		(start 229.16388 -42.61358)
		(end 232.273856 -45.723556)
		(width 0.1651)
		(layer "F.Cu")
		(net "M_B_DQS_DN<3>")
	)
	(segment
		(start 243.950744 -49.415954)
		(end 244.157246 -49.718722)
		(width 0.0889)
		(layer "F.Cu")
		(net "M_B_DQS_DN<3>")
	)
	(segment
		(start 228.699822 -9.34847)
		(end 228.300788 -8.949436)
		(width 0.1651)
		(layer "F.Cu")
		(net "M_B_DQS_DN<3>")
	)
	(segment
		(start 228.300788 -8.551672)
		(end 228.64826 -8.2042)
		(width 0.1651)
		(layer "F.Cu")
		(net "M_B_DQS_DN<3>")
	)
	(segment
		(start 242.16106 -47.68469)
		(end 243.673884 -49.197514)
		(width 0.1016)
		(layer "F.Cu")
		(net "M_B_DQS_DN<3>")
	)
	(segment
		(start 243.732304 -49.197514)
		(end 243.950744 -49.415954)
		(width 0.0889)
		(layer "F.Cu")
		(net "M_B_DQS_DN<3>")
	)
	(segment
		(start 228.300788 -8.949436)
		(end 228.300788 -8.551672)
		(width 0.1651)
		(layer "F.Cu")
		(net "M_B_DQS_DN<3>")
	)
	(segment
		(start 229.16388 -34.417)
		(end 229.16388 -42.61358)
		(width 0.1651)
		(layer "F.Cu")
		(net "M_B_DQS_DN<3>")
	)
	(segment
		(start 243.673884 -49.197514)
		(end 243.732304 -49.197514)
		(width 0.0889)
		(layer "F.Cu")
		(net "M_B_DQS_DN<3>")
	)
	(segment
		(start 244.273832 -50.319178)
		(end 244.260878 -50.345086)
		(width 0.0889)
		(layer "F.Cu")
		(net "M_B_DQS_DN<3>")
	)
	(segment
		(start 228.638608 -29.064712)
		(end 228.6254 -29.07792)
		(width 0.1651)
		(layer "F.Cu")
		(net "M_B_DQS_DN<3>")
	)
	(segment
		(start 228.699822 -10.422382)
		(end 228.699822 -9.34847)
		(width 0.1651)
		(layer "F.Cu")
		(net "M_B_DQS_DN<3>")
	)
	(segment
		(start 233.80065 -47.15129)
		(end 237.63986 -47.15129)
		(width 0.1016)
		(layer "F.Cu")
		(net "M_B_DQS_DN<3>")
	)
	(segment
		(start 228.6254 -29.07792)
		(end 228.6254 -32.348424)
		(width 0.1651)
		(layer "F.Cu")
		(net "M_B_DQS_DN<3>")
	)
	(segment
		(start 228.872288 -8.2042)
		(end 229.087934 -8.419846)
		(width 0.1651)
		(layer "F.Cu")
		(net "M_B_DQS_DN<3>")
	)
	(segment
		(start 243.83746 -52.709572)
		(end 243.910104 -52.782216)
		(width 0.0889)
		(layer "F.Cu")
		(net "M_B_DQS_DN<3>")
	)
	(segment
		(start 237.63986 -47.15129)
		(end 238.17326 -47.68469)
		(width 0.1016)
		(layer "F.Cu")
		(net "M_B_DQS_DN<3>")
	)
	(segment
		(start 228.638608 -27.793696)
		(end 228.638608 -29.064712)
		(width 0.1651)
		(layer "F.Cu")
		(net "M_B_DQS_DN<3>")
	)
	(segment
		(start 238.17326 -47.68469)
		(end 242.16106 -47.68469)
		(width 0.1016)
		(layer "F.Cu")
		(net "M_B_DQS_DN<3>")
	)
	(segment
		(start 244.157246 -49.718722)
		(end 244.266974 -49.920144)
		(width 0.0889)
		(layer "F.Cu")
		(net "M_B_DQS_DN<3>")
	)
	(segment
		(start 232.420414 -45.870114)
		(end 232.519474 -45.870114)
		(width 0.1016)
		(layer "F.Cu")
		(net "M_B_DQS_DN<3>")
	)
	(via
		(at 229.087934 -27.34437)
		(size 0.508)
		(drill 0.254)
		(layers "F.Cu" "B.Cu")
		(net "M_B_DQS_DN<3>")
	)
	(via
		(at 229.087934 -12.627356)
		(size 0.508)
		(drill 0.254)
		(layers "F.Cu" "B.Cu")
		(net "M_B_DQS_DN<3>")
	)
	(via
		(at 229.16388 -34.417)
		(size 0.508)
		(drill 0.254)
		(layers "F.Cu" "B.Cu")
		(net "M_B_DQS_DN<3>")
	)
	(via
		(at 229.087934 -8.419846)
		(size 0.508)
		(drill 0.254)
		(layers "F.Cu" "B.Cu")
		(net "M_B_DQS_DN<3>")
	)
	(arc
		(start 243.910104 -51.533298)
		(mid 243.321936 -52.076593)
		(end 243.816378 -52.706524)
		(width 0.0889)
		(layer "F.Cu")
		(net "M_B_DQS_DN<3>")
	)
	(arc
		(start 243.816378 -52.706524)
		(mid 243.826905 -52.708143)
		(end 243.83746 -52.709572)
		(width 0.0889)
		(layer "F.Cu")
		(net "M_B_DQS_DN<3>")
	)
	(arc
		(start 244.260878 -50.345086)
		(mid 244.179245 -50.63831)
		(end 244.257068 -50.932588)
		(width 0.0889)
		(layer "F.Cu")
		(net "M_B_DQS_DN<3>")
	)
	(arc
		(start 244.257068 -50.932588)
		(mid 244.256959 -51.333081)
		(end 243.910104 -51.533298)
		(width 0.0889)
		(layer "F.Cu")
		(net "M_B_DQS_DN<3>")
	)
	(arc
		(start 244.266974 -49.920144)
		(mid 244.319279 -50.11881)
		(end 244.273832 -50.319178)
		(width 0.0889)
		(layer "F.Cu")
		(net "M_B_DQS_DN<3>")
	)
	(segment
		(start 228.699822 -10.623042)
		(end 228.699822 -11.53033)
		(width 0.1651)
		(layer "B.Cu")
		(net "M_B_DQS_DN<3>")
	)
	(segment
		(start 228.673406 -12.8524)
		(end 228.86289 -12.8524)
		(width 0.1651)
		(layer "B.Cu")
		(net "M_B_DQS_DN<3>")
	)
	(segment
		(start 228.571806 -11.912346)
		(end 228.317806 -12.166346)
		(width 0.1651)
		(layer "B.Cu")
		(net "M_B_DQS_DN<3>")
	)
	(segment
		(start 228.317806 -12.166346)
		(end 228.317806 -12.4968)
		(width 0.1651)
		(layer "B.Cu")
		(net "M_B_DQS_DN<3>")
	)
	(segment
		(start 228.571806 -11.658346)
		(end 228.571806 -11.912346)
		(width 0.1651)
		(layer "B.Cu")
		(net "M_B_DQS_DN<3>")
	)
	(segment
		(start 228.70033 -10.623042)
		(end 228.699822 -10.623042)
		(width 0.1651)
		(layer "B.Cu")
		(net "M_B_DQS_DN<3>")
	)
	(segment
		(start 228.86289 -12.8524)
		(end 229.087934 -12.627356)
		(width 0.1651)
		(layer "B.Cu")
		(net "M_B_DQS_DN<3>")
	)
	(segment
		(start 228.699822 -11.53033)
		(end 228.571806 -11.658346)
		(width 0.1651)
		(layer "B.Cu")
		(net "M_B_DQS_DN<3>")
	)
	(segment
		(start 228.317806 -12.4968)
		(end 228.673406 -12.8524)
		(width 0.1651)
		(layer "B.Cu")
		(net "M_B_DQS_DN<3>")
	)
	(segment
		(start 229.450138 -11.4808)
		(end 229.629462 -11.660124)
		(width 0.14224)
		(layer "In4.Cu")
		(net "M_B_DQS_DN<3>")
	)
	(segment
		(start 229.585012 -15.263368)
		(end 229.585012 -27.107388)
		(width 0.14224)
		(layer "In4.Cu")
		(net "M_B_DQS_DN<3>")
	)
	(segment
		(start 229.094538 -9.981946)
		(end 229.247192 -10.1346)
		(width 0.14224)
		(layer "In4.Cu")
		(net "M_B_DQS_DN<3>")
	)
	(segment
		(start 229.094538 -9.677654)
		(end 229.094538 -9.981946)
		(width 0.14224)
		(layer "In4.Cu")
		(net "M_B_DQS_DN<3>")
	)
	(segment
		(start 229.629462 -11.660124)
		(end 229.629462 -12.364974)
		(width 0.14224)
		(layer "In4.Cu")
		(net "M_B_DQS_DN<3>")
	)
	(segment
		(start 229.629462 -12.364974)
		(end 229.366826 -12.62761)
		(width 0.14224)
		(layer "In4.Cu")
		(net "M_B_DQS_DN<3>")
	)
	(segment
		(start 229.36962 -8.419846)
		(end 229.629462 -8.679688)
		(width 0.14224)
		(layer "In4.Cu")
		(net "M_B_DQS_DN<3>")
	)
	(segment
		(start 229.102412 -14.61008)
		(end 229.102412 -14.780768)
		(width 0.14224)
		(layer "In4.Cu")
		(net "M_B_DQS_DN<3>")
	)
	(segment
		(start 229.424484 -10.1346)
		(end 229.629462 -10.339578)
		(width 0.14224)
		(layer "In4.Cu")
		(net "M_B_DQS_DN<3>")
	)
	(segment
		(start 229.247192 -9.525)
		(end 229.094538 -9.677654)
		(width 0.14224)
		(layer "In4.Cu")
		(net "M_B_DQS_DN<3>")
	)
	(segment
		(start 229.629462 -8.679688)
		(end 229.629462 -9.345422)
		(width 0.14224)
		(layer "In4.Cu")
		(net "M_B_DQS_DN<3>")
	)
	(segment
		(start 229.366826 -12.62761)
		(end 229.087934 -12.62761)
		(width 0.14224)
		(layer "In4.Cu")
		(net "M_B_DQS_DN<3>")
	)
	(segment
		(start 229.087934 -8.419846)
		(end 229.36962 -8.419846)
		(width 0.14224)
		(layer "In4.Cu")
		(net "M_B_DQS_DN<3>")
	)
	(segment
		(start 229.319582 -11.4808)
		(end 229.450138 -11.4808)
		(width 0.14224)
		(layer "In4.Cu")
		(net "M_B_DQS_DN<3>")
	)
	(segment
		(start 229.446582 -10.8712)
		(end 229.319582 -10.8712)
		(width 0.14224)
		(layer "In4.Cu")
		(net "M_B_DQS_DN<3>")
	)
	(segment
		(start 229.629462 -10.68832)
		(end 229.446582 -10.8712)
		(width 0.14224)
		(layer "In4.Cu")
		(net "M_B_DQS_DN<3>")
	)
	(segment
		(start 229.141782 -11.303)
		(end 229.319582 -11.4808)
		(width 0.14224)
		(layer "In4.Cu")
		(net "M_B_DQS_DN<3>")
	)
	(segment
		(start 228.650038 -14.157706)
		(end 229.102412 -14.61008)
		(width 0.14224)
		(layer "In4.Cu")
		(net "M_B_DQS_DN<3>")
	)
	(segment
		(start 229.585012 -27.107388)
		(end 229.34803 -27.34437)
		(width 0.14224)
		(layer "In4.Cu")
		(net "M_B_DQS_DN<3>")
	)
	(segment
		(start 229.629462 -10.339578)
		(end 229.629462 -10.68832)
		(width 0.14224)
		(layer "In4.Cu")
		(net "M_B_DQS_DN<3>")
	)
	(segment
		(start 229.141782 -11.049)
		(end 229.141782 -11.303)
		(width 0.14224)
		(layer "In4.Cu")
		(net "M_B_DQS_DN<3>")
	)
	(segment
		(start 229.34803 -27.34437)
		(end 229.087934 -27.34437)
		(width 0.14224)
		(layer "In4.Cu")
		(net "M_B_DQS_DN<3>")
	)
	(segment
		(start 229.629462 -9.345422)
		(end 229.449884 -9.525)
		(width 0.14224)
		(layer "In4.Cu")
		(net "M_B_DQS_DN<3>")
	)
	(segment
		(start 228.650038 -13.065252)
		(end 228.650038 -14.157706)
		(width 0.14224)
		(layer "In4.Cu")
		(net "M_B_DQS_DN<3>")
	)
	(segment
		(start 229.102412 -14.780768)
		(end 229.585012 -15.263368)
		(width 0.14224)
		(layer "In4.Cu")
		(net "M_B_DQS_DN<3>")
	)
	(segment
		(start 229.247192 -10.1346)
		(end 229.424484 -10.1346)
		(width 0.14224)
		(layer "In4.Cu")
		(net "M_B_DQS_DN<3>")
	)
	(segment
		(start 229.087934 -12.627356)
		(end 228.650038 -13.065252)
		(width 0.14224)
		(layer "In4.Cu")
		(net "M_B_DQS_DN<3>")
	)
	(segment
		(start 229.449884 -9.525)
		(end 229.247192 -9.525)
		(width 0.14224)
		(layer "In4.Cu")
		(net "M_B_DQS_DN<3>")
	)
	(segment
		(start 229.087934 -12.62761)
		(end 229.087934 -12.627356)
		(width 0.14224)
		(layer "In4.Cu")
		(net "M_B_DQS_DN<3>")
	)
	(segment
		(start 229.319582 -10.8712)
		(end 229.141782 -11.049)
		(width 0.14224)
		(layer "In4.Cu")
		(net "M_B_DQS_DN<3>")
	)
	(segment
		(start 219.084144 -8.410956)
		(end 219.73794 -7.75716)
		(width 0.1651)
		(layer "F.Cu")
		(net "M_B_DQS_DN<2>")
	)
	(segment
		(start 238.759238 -54.104286)
		(end 238.187738 -54.104286)
		(width 0.1016)
		(layer "F.Cu")
		(net "M_B_DQS_DN<2>")
	)
	(segment
		(start 219.349828 -9.40943)
		(end 219.084144 -9.143746)
		(width 0.1651)
		(layer "F.Cu")
		(net "M_B_DQS_DN<2>")
	)
	(segment
		(start 219.350336 -10.422382)
		(end 219.349828 -10.422382)
		(width 0.1651)
		(layer "F.Cu")
		(net "M_B_DQS_DN<2>")
	)
	(segment
		(start 219.084144 -9.143746)
		(end 219.084144 -8.410956)
		(width 0.1651)
		(layer "F.Cu")
		(net "M_B_DQS_DN<2>")
	)
	(segment
		(start 219.349828 -10.422382)
		(end 219.349828 -9.40943)
		(width 0.1651)
		(layer "F.Cu")
		(net "M_B_DQS_DN<2>")
	)
	(via
		(at 219.73794 -13.287756)
		(size 0.508)
		(drill 0.254)
		(layers "F.Cu" "B.Cu")
		(net "M_B_DQS_DN<2>")
	)
	(via
		(at 238.187738 -54.104286)
		(size 0.508)
		(drill 0.254)
		(layers "F.Cu" "B.Cu")
		(net "M_B_DQS_DN<2>")
	)
	(via
		(at 219.73794 -7.75716)
		(size 0.508)
		(drill 0.254)
		(layers "F.Cu" "B.Cu")
		(net "M_B_DQS_DN<2>")
	)
	(segment
		(start 219.096844 -12.64666)
		(end 219.73794 -13.287756)
		(width 0.1651)
		(layer "B.Cu")
		(net "M_B_DQS_DN<2>")
	)
	(segment
		(start 219.096844 -11.773154)
		(end 219.096844 -12.64666)
		(width 0.1651)
		(layer "B.Cu")
		(net "M_B_DQS_DN<2>")
	)
	(segment
		(start 219.349828 -10.623042)
		(end 219.349828 -11.52017)
		(width 0.1651)
		(layer "B.Cu")
		(net "M_B_DQS_DN<2>")
	)
	(segment
		(start 219.349828 -11.52017)
		(end 219.096844 -11.773154)
		(width 0.1651)
		(layer "B.Cu")
		(net "M_B_DQS_DN<2>")
	)
	(segment
		(start 219.350336 -10.623042)
		(end 219.349828 -10.623042)
		(width 0.1651)
		(layer "B.Cu")
		(net "M_B_DQS_DN<2>")
	)
	(segment
		(start 238.187738 -53.766212)
		(end 238.187738 -54.104286)
		(width 0.0889)
		(layer "In4.Cu")
		(net "M_B_DQS_DN<2>")
	)
	(segment
		(start 236.209332 -48.83404)
		(end 237.525306 -48.83404)
		(width 0.0889)
		(layer "In4.Cu")
		(net "M_B_DQS_DN<2>")
	)
	(segment
		(start 233.73334 -45.866812)
		(end 233.73334 -46.302168)
		(width 0.14224)
		(layer "In4.Cu")
		(net "M_B_DQS_DN<2>")
	)
	(segment
		(start 238.604298 -50.672238)
		(end 238.705898 -50.848006)
		(width 0.0889)
		(layer "In4.Cu")
		(net "M_B_DQS_DN<2>")
	)
	(segment
		(start 219.73794 -7.75716)
		(end 220.548708 -8.567928)
		(width 0.14224)
		(layer "In4.Cu")
		(net "M_B_DQS_DN<2>")
	)
	(segment
		(start 219.73794 -13.287756)
		(end 220.201744 -13.75156)
		(width 0.14224)
		(layer "In4.Cu")
		(net "M_B_DQS_DN<2>")
	)
	(segment
		(start 238.705898 -52.40782)
		(end 238.699548 -52.418488)
		(width 0.0889)
		(layer "In4.Cu")
		(net "M_B_DQS_DN<2>")
	)
	(segment
		(start 238.252762 -53.701188)
		(end 238.187738 -53.766212)
		(width 0.0889)
		(layer "In4.Cu")
		(net "M_B_DQS_DN<2>")
	)
	(segment
		(start 233.248454 -45.220382)
		(end 233.491024 -45.462952)
		(width 0.14224)
		(layer "In4.Cu")
		(net "M_B_DQS_DN<2>")
	)
	(segment
		(start 232.198418 -44.33189)
		(end 232.440734 -44.574206)
		(width 0.14224)
		(layer "In4.Cu")
		(net "M_B_DQS_DN<2>")
	)
	(segment
		(start 232.844848 -44.97832)
		(end 233.08691 -45.220382)
		(width 0.14224)
		(layer "In4.Cu")
		(net "M_B_DQS_DN<2>")
	)
	(segment
		(start 220.52026 -29.275532)
		(end 230.39832 -39.153592)
		(width 0.14224)
		(layer "In4.Cu")
		(net "M_B_DQS_DN<2>")
	)
	(segment
		(start 220.201744 -14.138656)
		(end 219.688664 -14.651736)
		(width 0.14224)
		(layer "In4.Cu")
		(net "M_B_DQS_DN<2>")
	)
	(segment
		(start 238.694722 -51.819302)
		(end 238.699548 -51.827938)
		(width 0.0889)
		(layer "In4.Cu")
		(net "M_B_DQS_DN<2>")
	)
	(segment
		(start 219.688664 -14.651736)
		(end 219.688664 -14.881352)
		(width 0.14224)
		(layer "In4.Cu")
		(net "M_B_DQS_DN<2>")
	)
	(segment
		(start 234.490006 -47.058834)
		(end 234.490006 -47.114714)
		(width 0.0889)
		(layer "In4.Cu")
		(net "M_B_DQS_DN<2>")
	)
	(segment
		(start 231.925876 -43.927776)
		(end 232.198418 -44.200318)
		(width 0.14224)
		(layer "In4.Cu")
		(net "M_B_DQS_DN<2>")
	)
	(segment
		(start 233.08691 -45.220382)
		(end 233.248454 -45.220382)
		(width 0.14224)
		(layer "In4.Cu")
		(net "M_B_DQS_DN<2>")
	)
	(segment
		(start 220.201744 -13.75156)
		(end 220.201744 -14.138656)
		(width 0.14224)
		(layer "In4.Cu")
		(net "M_B_DQS_DN<2>")
	)
	(segment
		(start 232.440734 -44.574206)
		(end 232.602278 -44.574206)
		(width 0.14224)
		(layer "In4.Cu")
		(net "M_B_DQS_DN<2>")
	)
	(segment
		(start 219.688664 -14.881352)
		(end 220.52026 -15.712948)
		(width 0.14224)
		(layer "In4.Cu")
		(net "M_B_DQS_DN<2>")
	)
	(segment
		(start 232.844848 -44.816776)
		(end 232.844848 -44.97832)
		(width 0.14224)
		(layer "In4.Cu")
		(net "M_B_DQS_DN<2>")
	)
	(segment
		(start 234.490006 -47.114714)
		(end 236.209332 -48.83404)
		(width 0.0889)
		(layer "In4.Cu")
		(net "M_B_DQS_DN<2>")
	)
	(segment
		(start 233.491024 -45.624496)
		(end 233.73334 -45.866812)
		(width 0.14224)
		(layer "In4.Cu")
		(net "M_B_DQS_DN<2>")
	)
	(segment
		(start 237.525306 -48.83404)
		(end 238.604298 -49.913032)
		(width 0.0889)
		(layer "In4.Cu")
		(net "M_B_DQS_DN<2>")
	)
	(segment
		(start 233.73334 -46.302168)
		(end 234.474258 -47.043086)
		(width 0.14224)
		(layer "In4.Cu")
		(net "M_B_DQS_DN<2>")
	)
	(segment
		(start 220.548708 -8.567928)
		(end 220.548708 -12.476988)
		(width 0.14224)
		(layer "In4.Cu")
		(net "M_B_DQS_DN<2>")
	)
	(segment
		(start 230.39832 -42.531792)
		(end 231.794304 -43.927776)
		(width 0.14224)
		(layer "In4.Cu")
		(net "M_B_DQS_DN<2>")
	)
	(segment
		(start 230.39832 -39.153592)
		(end 230.39832 -42.531792)
		(width 0.14224)
		(layer "In4.Cu")
		(net "M_B_DQS_DN<2>")
	)
	(segment
		(start 220.52026 -15.712948)
		(end 220.52026 -29.275532)
		(width 0.14224)
		(layer "In4.Cu")
		(net "M_B_DQS_DN<2>")
	)
	(segment
		(start 232.198418 -44.200318)
		(end 232.198418 -44.33189)
		(width 0.14224)
		(layer "In4.Cu")
		(net "M_B_DQS_DN<2>")
	)
	(segment
		(start 232.602278 -44.574206)
		(end 232.844848 -44.816776)
		(width 0.14224)
		(layer "In4.Cu")
		(net "M_B_DQS_DN<2>")
	)
	(segment
		(start 234.474258 -47.043086)
		(end 234.490006 -47.058834)
		(width 0.0889)
		(layer "In4.Cu")
		(net "M_B_DQS_DN<2>")
	)
	(segment
		(start 238.604298 -49.913032)
		(end 238.604298 -50.672238)
		(width 0.0889)
		(layer "In4.Cu")
		(net "M_B_DQS_DN<2>")
	)
	(segment
		(start 231.794304 -43.927776)
		(end 231.925876 -43.927776)
		(width 0.14224)
		(layer "In4.Cu")
		(net "M_B_DQS_DN<2>")
	)
	(segment
		(start 233.491024 -45.462952)
		(end 233.491024 -45.624496)
		(width 0.14224)
		(layer "In4.Cu")
		(net "M_B_DQS_DN<2>")
	)
	(segment
		(start 220.548708 -12.476988)
		(end 219.73794 -13.287756)
		(width 0.14224)
		(layer "In4.Cu")
		(net "M_B_DQS_DN<2>")
	)
	(arc
		(start 238.699548 -51.427888)
		(mid 238.646078 -51.622951)
		(end 238.694722 -51.819302)
		(width 0.0889)
		(layer "In4.Cu")
		(net "M_B_DQS_DN<2>")
	)
	(arc
		(start 238.705898 -50.848006)
		(mid 238.778696 -51.138769)
		(end 238.699548 -51.427888)
		(width 0.0889)
		(layer "In4.Cu")
		(net "M_B_DQS_DN<2>")
	)
	(arc
		(start 238.699548 -51.827938)
		(mid 238.77877 -52.117056)
		(end 238.705898 -52.40782)
		(width 0.0889)
		(layer "In4.Cu")
		(net "M_B_DQS_DN<2>")
	)
	(arc
		(start 238.699548 -52.418488)
		(mid 238.646049 -52.618386)
		(end 238.699548 -52.818284)
		(width 0.0889)
		(layer "In4.Cu")
		(net "M_B_DQS_DN<2>")
	)
	(arc
		(start 238.699548 -52.818284)
		(mid 238.71499 -53.380552)
		(end 238.252762 -53.701188)
		(width 0.0889)
		(layer "In4.Cu")
		(net "M_B_DQS_DN<2>")
	)
	(segment
		(start 238.759238 -61.038486)
		(end 238.187738 -61.038486)
		(width 0.1016)
		(layer "F.Cu")
		(net "M_B_DQS_DN<1>")
	)
	(segment
		(start 209.73415 -9.143746)
		(end 209.73415 -8.410956)
		(width 0.1651)
		(layer "F.Cu")
		(net "M_B_DQS_DN<1>")
	)
	(segment
		(start 210.000342 -10.422382)
		(end 209.999834 -10.422382)
		(width 0.1651)
		(layer "F.Cu")
		(net "M_B_DQS_DN<1>")
	)
	(segment
		(start 209.73415 -8.410956)
		(end 210.387946 -7.75716)
		(width 0.1651)
		(layer "F.Cu")
		(net "M_B_DQS_DN<1>")
	)
	(segment
		(start 209.999834 -10.422382)
		(end 209.999834 -9.40943)
		(width 0.1651)
		(layer "F.Cu")
		(net "M_B_DQS_DN<1>")
	)
	(segment
		(start 209.999834 -9.40943)
		(end 209.73415 -9.143746)
		(width 0.1651)
		(layer "F.Cu")
		(net "M_B_DQS_DN<1>")
	)
	(via
		(at 210.387946 -13.287756)
		(size 0.508)
		(drill 0.254)
		(layers "F.Cu" "B.Cu")
		(net "M_B_DQS_DN<1>")
	)
	(via
		(at 238.187738 -61.038486)
		(size 0.508)
		(drill 0.254)
		(layers "F.Cu" "B.Cu")
		(net "M_B_DQS_DN<1>")
	)
	(via
		(at 210.387946 -7.75716)
		(size 0.508)
		(drill 0.254)
		(layers "F.Cu" "B.Cu")
		(net "M_B_DQS_DN<1>")
	)
	(segment
		(start 209.74685 -12.64666)
		(end 210.387946 -13.287756)
		(width 0.1651)
		(layer "B.Cu")
		(net "M_B_DQS_DN<1>")
	)
	(segment
		(start 210.000342 -10.623042)
		(end 209.999834 -10.623042)
		(width 0.1651)
		(layer "B.Cu")
		(net "M_B_DQS_DN<1>")
	)
	(segment
		(start 209.999834 -10.623042)
		(end 209.999834 -11.52017)
		(width 0.1651)
		(layer "B.Cu")
		(net "M_B_DQS_DN<1>")
	)
	(segment
		(start 209.74685 -11.773154)
		(end 209.74685 -12.64666)
		(width 0.1651)
		(layer "B.Cu")
		(net "M_B_DQS_DN<1>")
	)
	(segment
		(start 209.999834 -11.52017)
		(end 209.74685 -11.773154)
		(width 0.1651)
		(layer "B.Cu")
		(net "M_B_DQS_DN<1>")
	)
	(segment
		(start 234.266994 -58.583576)
		(end 234.266994 -58.605674)
		(width 0.0889)
		(layer "In4.Cu")
		(net "M_B_DQS_DN<1>")
	)
	(segment
		(start 233.370882 -56.763158)
		(end 233.532426 -56.763158)
		(width 0.14224)
		(layer "In4.Cu")
		(net "M_B_DQS_DN<1>")
	)
	(segment
		(start 211.170266 -20.27428)
		(end 211.170266 -23.760938)
		(width 0.14224)
		(layer "In4.Cu")
		(net "M_B_DQS_DN<1>")
	)
	(segment
		(start 213.956392 -33.946846)
		(end 213.956392 -34.389314)
		(width 0.14224)
		(layer "In4.Cu")
		(net "M_B_DQS_DN<1>")
	)
	(segment
		(start 214.425784 -34.858706)
		(end 214.868252 -34.858706)
		(width 0.14224)
		(layer "In4.Cu")
		(net "M_B_DQS_DN<1>")
	)
	(segment
		(start 210.988402 -15.30858)
		(end 210.988402 -15.531084)
		(width 0.14224)
		(layer "In4.Cu")
		(net "M_B_DQS_DN<1>")
	)
	(segment
		(start 213.956392 -34.389314)
		(end 213.239096 -35.10661)
		(width 0.14224)
		(layer "In4.Cu")
		(net "M_B_DQS_DN<1>")
	)
	(segment
		(start 213.239096 -35.324796)
		(end 213.490556 -35.576256)
		(width 0.14224)
		(layer "In4.Cu")
		(net "M_B_DQS_DN<1>")
	)
	(segment
		(start 237.805214 -61.18352)
		(end 237.894622 -61.20765)
		(width 0.0889)
		(layer "In4.Cu")
		(net "M_B_DQS_DN<1>")
	)
	(segment
		(start 210.33867 -14.66088)
		(end 210.33867 -14.881352)
		(width 0.14224)
		(layer "In4.Cu")
		(net "M_B_DQS_DN<1>")
	)
	(segment
		(start 234.353608 -60.155836)
		(end 234.406948 -60.247784)
		(width 0.0889)
		(layer "In4.Cu")
		(net "M_B_DQS_DN<1>")
	)
	(segment
		(start 233.532426 -56.763158)
		(end 233.774996 -57.005728)
		(width 0.14224)
		(layer "In4.Cu")
		(net "M_B_DQS_DN<1>")
	)
	(segment
		(start 234.266994 -58.605674)
		(end 234.227624 -58.645044)
		(width 0.0889)
		(layer "In4.Cu")
		(net "M_B_DQS_DN<1>")
	)
	(segment
		(start 216.02192 -39.414196)
		(end 233.370882 -56.763158)
		(width 0.14224)
		(layer "In4.Cu")
		(net "M_B_DQS_DN<1>")
	)
	(segment
		(start 211.198714 -12.476988)
		(end 210.387946 -13.287756)
		(width 0.14224)
		(layer "In4.Cu")
		(net "M_B_DQS_DN<1>")
	)
	(segment
		(start 210.85175 -14.1478)
		(end 210.33867 -14.66088)
		(width 0.14224)
		(layer "In4.Cu")
		(net "M_B_DQS_DN<1>")
	)
	(segment
		(start 211.170266 -19.51228)
		(end 211.170266 -19.70532)
		(width 0.14224)
		(layer "In4.Cu")
		(net "M_B_DQS_DN<1>")
	)
	(segment
		(start 216.47912 -38.621208)
		(end 216.02192 -39.078408)
		(width 0.14224)
		(layer "In4.Cu")
		(net "M_B_DQS_DN<1>")
	)
	(segment
		(start 211.170266 -18.94332)
		(end 211.327746 -19.1008)
		(width 0.14224)
		(layer "In4.Cu")
		(net "M_B_DQS_DN<1>")
	)
	(segment
		(start 210.80857 -15.128748)
		(end 210.988402 -15.30858)
		(width 0.14224)
		(layer "In4.Cu")
		(net "M_B_DQS_DN<1>")
	)
	(segment
		(start 210.387946 -7.75716)
		(end 211.198714 -8.567928)
		(width 0.14224)
		(layer "In4.Cu")
		(net "M_B_DQS_DN<1>")
	)
	(segment
		(start 236.456982 -61.438536)
		(end 236.488224 -61.438536)
		(width 0.0889)
		(layer "In4.Cu")
		(net "M_B_DQS_DN<1>")
	)
	(segment
		(start 211.327746 -16.081756)
		(end 211.170266 -16.239236)
		(width 0.14224)
		(layer "In4.Cu")
		(net "M_B_DQS_DN<1>")
	)
	(segment
		(start 211.327746 -20.1168)
		(end 211.170266 -20.27428)
		(width 0.14224)
		(layer "In4.Cu")
		(net "M_B_DQS_DN<1>")
	)
	(segment
		(start 210.85175 -13.75156)
		(end 210.85175 -14.1478)
		(width 0.14224)
		(layer "In4.Cu")
		(net "M_B_DQS_DN<1>")
	)
	(segment
		(start 216.02192 -39.078408)
		(end 216.02192 -39.414196)
		(width 0.14224)
		(layer "In4.Cu")
		(net "M_B_DQS_DN<1>")
	)
	(segment
		(start 211.327746 -19.3548)
		(end 211.170266 -19.51228)
		(width 0.14224)
		(layer "In4.Cu")
		(net "M_B_DQS_DN<1>")
	)
	(segment
		(start 213.708234 -35.576256)
		(end 214.425784 -34.858706)
		(width 0.14224)
		(layer "In4.Cu")
		(net "M_B_DQS_DN<1>")
	)
	(segment
		(start 211.44992 -24.040592)
		(end 211.44992 -31.440374)
		(width 0.14224)
		(layer "In4.Cu")
		(net "M_B_DQS_DN<1>")
	)
	(segment
		(start 211.170266 -23.760938)
		(end 211.44992 -24.040592)
		(width 0.14224)
		(layer "In4.Cu")
		(net "M_B_DQS_DN<1>")
	)
	(segment
		(start 234.227624 -58.983118)
		(end 234.353608 -59.109102)
		(width 0.0889)
		(layer "In4.Cu")
		(net "M_B_DQS_DN<1>")
	)
	(segment
		(start 235.611416 -61.933836)
		(end 235.61294 -61.933836)
		(width 0.0889)
		(layer "In4.Cu")
		(net "M_B_DQS_DN<1>")
	)
	(segment
		(start 211.327746 -19.1008)
		(end 211.327746 -19.3548)
		(width 0.14224)
		(layer "In4.Cu")
		(net "M_B_DQS_DN<1>")
	)
	(segment
		(start 211.327746 -15.870428)
		(end 211.327746 -16.081756)
		(width 0.14224)
		(layer "In4.Cu")
		(net "M_B_DQS_DN<1>")
	)
	(segment
		(start 213.490556 -35.576256)
		(end 213.708234 -35.576256)
		(width 0.14224)
		(layer "In4.Cu")
		(net "M_B_DQS_DN<1>")
	)
	(segment
		(start 210.387946 -13.287756)
		(end 210.85175 -13.75156)
		(width 0.14224)
		(layer "In4.Cu")
		(net "M_B_DQS_DN<1>")
	)
	(segment
		(start 211.170266 -19.70532)
		(end 211.327746 -19.8628)
		(width 0.14224)
		(layer "In4.Cu")
		(net "M_B_DQS_DN<1>")
	)
	(segment
		(start 234.736132 -61.438536)
		(end 234.767374 -61.438536)
		(width 0.0889)
		(layer "In4.Cu")
		(net "M_B_DQS_DN<1>")
	)
	(segment
		(start 233.774996 -57.005728)
		(end 233.774996 -57.167272)
		(width 0.14224)
		(layer "In4.Cu")
		(net "M_B_DQS_DN<1>")
	)
	(segment
		(start 210.33867 -14.881352)
		(end 210.586066 -15.128748)
		(width 0.14224)
		(layer "In4.Cu")
		(net "M_B_DQS_DN<1>")
	)
	(segment
		(start 234.266994 -57.65927)
		(end 234.266994 -58.583576)
		(width 0.14224)
		(layer "In4.Cu")
		(net "M_B_DQS_DN<1>")
	)
	(segment
		(start 237.31093 -60.94349)
		(end 237.347506 -60.94349)
		(width 0.0889)
		(layer "In4.Cu")
		(net "M_B_DQS_DN<1>")
	)
	(segment
		(start 233.774996 -57.167272)
		(end 234.266994 -57.65927)
		(width 0.14224)
		(layer "In4.Cu")
		(net "M_B_DQS_DN<1>")
	)
	(segment
		(start 211.198714 -8.567928)
		(end 211.198714 -12.476988)
		(width 0.14224)
		(layer "In4.Cu")
		(net "M_B_DQS_DN<1>")
	)
	(segment
		(start 234.227624 -58.645044)
		(end 234.227624 -58.983118)
		(width 0.0889)
		(layer "In4.Cu")
		(net "M_B_DQS_DN<1>")
	)
	(segment
		(start 210.586066 -15.128748)
		(end 210.80857 -15.128748)
		(width 0.14224)
		(layer "In4.Cu")
		(net "M_B_DQS_DN<1>")
	)
	(segment
		(start 211.170266 -16.239236)
		(end 211.170266 -18.94332)
		(width 0.14224)
		(layer "In4.Cu")
		(net "M_B_DQS_DN<1>")
	)
	(segment
		(start 216.47912 -36.469574)
		(end 216.47912 -38.621208)
		(width 0.14224)
		(layer "In4.Cu")
		(net "M_B_DQS_DN<1>")
	)
	(segment
		(start 210.988402 -15.531084)
		(end 211.327746 -15.870428)
		(width 0.14224)
		(layer "In4.Cu")
		(net "M_B_DQS_DN<1>")
	)
	(segment
		(start 211.327746 -19.8628)
		(end 211.327746 -20.1168)
		(width 0.14224)
		(layer "In4.Cu")
		(net "M_B_DQS_DN<1>")
	)
	(segment
		(start 214.868252 -34.858706)
		(end 216.47912 -36.469574)
		(width 0.14224)
		(layer "In4.Cu")
		(net "M_B_DQS_DN<1>")
	)
	(segment
		(start 234.353608 -59.109102)
		(end 234.353608 -60.155836)
		(width 0.0889)
		(layer "In4.Cu")
		(net "M_B_DQS_DN<1>")
	)
	(segment
		(start 211.44992 -31.440374)
		(end 213.956392 -33.946846)
		(width 0.14224)
		(layer "In4.Cu")
		(net "M_B_DQS_DN<1>")
	)
	(segment
		(start 237.894622 -61.20765)
		(end 238.187738 -61.038486)
		(width 0.0889)
		(layer "In4.Cu")
		(net "M_B_DQS_DN<1>")
	)
	(segment
		(start 213.239096 -35.10661)
		(end 213.239096 -35.324796)
		(width 0.14224)
		(layer "In4.Cu")
		(net "M_B_DQS_DN<1>")
	)
	(arc
		(start 234.406948 -60.838334)
		(mid 234.402663 -61.231025)
		(end 234.736132 -61.438536)
		(width 0.0889)
		(layer "In4.Cu")
		(net "M_B_DQS_DN<1>")
	)
	(arc
		(start 235.958888 -61.733938)
		(mid 236.169241 -61.520966)
		(end 236.456982 -61.438536)
		(width 0.0889)
		(layer "In4.Cu")
		(net "M_B_DQS_DN<1>")
	)
	(arc
		(start 236.488224 -61.438536)
		(mid 236.678466 -61.380801)
		(end 236.817408 -61.238638)
		(width 0.0889)
		(layer "In4.Cu")
		(net "M_B_DQS_DN<1>")
	)
	(arc
		(start 237.347506 -60.94349)
		(mid 237.603985 -61.010828)
		(end 237.805214 -61.18352)
		(width 0.0889)
		(layer "In4.Cu")
		(net "M_B_DQS_DN<1>")
	)
	(arc
		(start 235.61294 -61.933836)
		(mid 235.812713 -61.880267)
		(end 235.958888 -61.733938)
		(width 0.0889)
		(layer "In4.Cu")
		(net "M_B_DQS_DN<1>")
	)
	(arc
		(start 234.767374 -61.438536)
		(mid 235.055061 -61.521057)
		(end 235.265468 -61.733938)
		(width 0.0889)
		(layer "In4.Cu")
		(net "M_B_DQS_DN<1>")
	)
	(arc
		(start 235.265468 -61.733938)
		(mid 235.41164 -61.880273)
		(end 235.611416 -61.933836)
		(width 0.0889)
		(layer "In4.Cu")
		(net "M_B_DQS_DN<1>")
	)
	(arc
		(start 236.817408 -61.238638)
		(mid 237.025827 -61.026925)
		(end 237.31093 -60.94349)
		(width 0.0889)
		(layer "In4.Cu")
		(net "M_B_DQS_DN<1>")
	)
	(arc
		(start 234.406948 -60.247784)
		(mid 234.486079 -60.543076)
		(end 234.406948 -60.838334)
		(width 0.0889)
		(layer "In4.Cu")
		(net "M_B_DQS_DN<1>")
	)
	(segment
		(start 238.9124 -41.08577)
		(end 239.091978 -41.265348)
		(width 0.1651)
		(layer "F.Cu")
		(net "M_B_DQS_DN<17>")
	)
	(segment
		(start 239.0394 -39.0906)
		(end 238.9124 -39.2176)
		(width 0.1651)
		(layer "F.Cu")
		(net "M_B_DQS_DN<17>")
	)
	(segment
		(start 237.598458 -28.949142)
		(end 237.3376 -29.21)
		(width 0.1651)
		(layer "F.Cu")
		(net "M_B_DQS_DN<17>")
	)
	(segment
		(start 240.908078 -43.081448)
		(end 241.055398 -43.228768)
		(width 0.1016)
		(layer "F.Cu")
		(net "M_B_DQS_DN<17>")
	)
	(segment
		(start 238.477298 -31.039308)
		(end 238.65713 -31.218886)
		(width 0.1651)
		(layer "F.Cu")
		(net "M_B_DQS_DN<17>")
	)
	(segment
		(start 239.0394 -39.5986)
		(end 239.0394 -39.8526)
		(width 0.1651)
		(layer "F.Cu")
		(net "M_B_DQS_DN<17>")
	)
	(segment
		(start 240.1062 -32.847788)
		(end 240.1062 -33.697418)
		(width 0.1651)
		(layer "F.Cu")
		(net "M_B_DQS_DN<17>")
	)
	(segment
		(start 239.770158 -34.70656)
		(end 240.1062 -35.042602)
		(width 0.1651)
		(layer "F.Cu")
		(net "M_B_DQS_DN<17>")
	)
	(segment
		(start 239.630966 -41.804336)
		(end 239.810544 -41.804336)
		(width 0.1651)
		(layer "F.Cu")
		(net "M_B_DQS_DN<17>")
	)
	(segment
		(start 239.451388 -41.444926)
		(end 239.451388 -41.624758)
		(width 0.1651)
		(layer "F.Cu")
		(net "M_B_DQS_DN<17>")
	)
	(segment
		(start 239.810544 -41.804336)
		(end 239.990376 -41.983914)
		(width 0.1651)
		(layer "F.Cu")
		(net "M_B_DQS_DN<17>")
	)
	(segment
		(start 237.579154 -30.320742)
		(end 237.758732 -30.50032)
		(width 0.1651)
		(layer "F.Cu")
		(net "M_B_DQS_DN<17>")
	)
	(segment
		(start 237.631732 -7.083044)
		(end 237.631732 -7.3152)
		(width 0.1651)
		(layer "F.Cu")
		(net "M_B_DQS_DN<17>")
	)
	(segment
		(start 248.203974 -50.83175)
		(end 248.203974 -51.813206)
		(width 0.0889)
		(layer "F.Cu")
		(net "M_B_DQS_DN<17>")
	)
	(segment
		(start 238.9124 -36.668964)
		(end 238.9124 -37.0586)
		(width 0.1651)
		(layer "F.Cu")
		(net "M_B_DQS_DN<17>")
	)
	(segment
		(start 238.050324 -5.822442)
		(end 238.049816 -5.822442)
		(width 0.1651)
		(layer "F.Cu")
		(net "M_B_DQS_DN<17>")
	)
	(segment
		(start 239.0394 -37.973)
		(end 239.0394 -38.227)
		(width 0.1651)
		(layer "F.Cu")
		(net "M_B_DQS_DN<17>")
	)
	(segment
		(start 243.445538 -44.041314)
		(end 244.161564 -44.041314)
		(width 0.1016)
		(layer "F.Cu")
		(net "M_B_DQS_DN<17>")
	)
	(segment
		(start 237.598458 -28.213558)
		(end 237.598458 -28.949142)
		(width 0.1651)
		(layer "F.Cu")
		(net "M_B_DQS_DN<17>")
	)
	(segment
		(start 238.9124 -38.354)
		(end 238.9124 -38.7096)
		(width 0.1651)
		(layer "F.Cu")
		(net "M_B_DQS_DN<17>")
	)
	(segment
		(start 237.81766 -7.747762)
		(end 237.565692 -7.99973)
		(width 0.1651)
		(layer "F.Cu")
		(net "M_B_DQS_DN<17>")
	)
	(segment
		(start 239.196118 -31.757874)
		(end 239.196118 -31.937706)
		(width 0.1651)
		(layer "F.Cu")
		(net "M_B_DQS_DN<17>")
	)
	(segment
		(start 239.091978 -41.265348)
		(end 239.271556 -41.265348)
		(width 0.1651)
		(layer "F.Cu")
		(net "M_B_DQS_DN<17>")
	)
	(segment
		(start 248.291604 -50.591466)
		(end 248.291604 -50.74412)
		(width 0.0889)
		(layer "F.Cu")
		(net "M_B_DQS_DN<17>")
	)
	(segment
		(start 239.990376 -41.983914)
		(end 239.990376 -42.163746)
		(width 0.1651)
		(layer "F.Cu")
		(net "M_B_DQS_DN<17>")
	)
	(segment
		(start 240.1062 -35.56)
		(end 240.1062 -36.045394)
		(width 0.1651)
		(layer "F.Cu")
		(net "M_B_DQS_DN<17>")
	)
	(segment
		(start 238.65713 -31.398718)
		(end 238.836708 -31.578296)
		(width 0.1651)
		(layer "F.Cu")
		(net "M_B_DQS_DN<17>")
	)
	(segment
		(start 239.0394 -38.8366)
		(end 239.0394 -39.0906)
		(width 0.1651)
		(layer "F.Cu")
		(net "M_B_DQS_DN<17>")
	)
	(segment
		(start 238.29772 -31.039308)
		(end 238.477298 -31.039308)
		(width 0.1651)
		(layer "F.Cu")
		(net "M_B_DQS_DN<17>")
	)
	(segment
		(start 248.09831 -52.35321)
		(end 248.09831 -52.513992)
		(width 0.0889)
		(layer "F.Cu")
		(net "M_B_DQS_DN<17>")
	)
	(segment
		(start 240.1062 -33.697418)
		(end 239.770158 -34.03346)
		(width 0.1651)
		(layer "F.Cu")
		(net "M_B_DQS_DN<17>")
	)
	(segment
		(start 238.9124 -39.2176)
		(end 238.9124 -39.4716)
		(width 0.1651)
		(layer "F.Cu")
		(net "M_B_DQS_DN<17>")
	)
	(segment
		(start 239.0394 -40.70477)
		(end 238.9124 -40.83177)
		(width 0.1651)
		(layer "F.Cu")
		(net "M_B_DQS_DN<17>")
	)
	(segment
		(start 241.055398 -43.228768)
		(end 242.632992 -43.228768)
		(width 0.1016)
		(layer "F.Cu")
		(net "M_B_DQS_DN<17>")
	)
	(segment
		(start 239.753394 -36.3982)
		(end 239.183164 -36.3982)
		(width 0.1651)
		(layer "F.Cu")
		(net "M_B_DQS_DN<17>")
	)
	(segment
		(start 238.118142 -30.679898)
		(end 238.118142 -30.85973)
		(width 0.1651)
		(layer "F.Cu")
		(net "M_B_DQS_DN<17>")
	)
	(segment
		(start 248.291604 -50.74412)
		(end 248.203974 -50.83175)
		(width 0.0889)
		(layer "F.Cu")
		(net "M_B_DQS_DN<17>")
	)
	(segment
		(start 237.24362 -29.21)
		(end 237.040166 -29.413454)
		(width 0.1651)
		(layer "F.Cu")
		(net "M_B_DQS_DN<17>")
	)
	(segment
		(start 248.203974 -50.503836)
		(end 248.291604 -50.591466)
		(width 0.0889)
		(layer "F.Cu")
		(net "M_B_DQS_DN<17>")
	)
	(segment
		(start 237.219744 -29.961332)
		(end 237.399322 -29.961332)
		(width 0.1651)
		(layer "F.Cu")
		(net "M_B_DQS_DN<17>")
	)
	(segment
		(start 238.9124 -39.9796)
		(end 238.9124 -40.32377)
		(width 0.1651)
		(layer "F.Cu")
		(net "M_B_DQS_DN<17>")
	)
	(segment
		(start 237.3376 -29.21)
		(end 237.24362 -29.21)
		(width 0.1651)
		(layer "F.Cu")
		(net "M_B_DQS_DN<17>")
	)
	(segment
		(start 248.203974 -50.276506)
		(end 248.203974 -50.503836)
		(width 0.0889)
		(layer "F.Cu")
		(net "M_B_DQS_DN<17>")
	)
	(segment
		(start 239.196118 -31.937706)
		(end 239.375696 -32.117284)
		(width 0.1651)
		(layer "F.Cu")
		(net "M_B_DQS_DN<17>")
	)
	(segment
		(start 239.375696 -32.117284)
		(end 239.555274 -32.117284)
		(width 0.1651)
		(layer "F.Cu")
		(net "M_B_DQS_DN<17>")
	)
	(segment
		(start 240.1062 -36.045394)
		(end 239.753394 -36.3982)
		(width 0.1651)
		(layer "F.Cu")
		(net "M_B_DQS_DN<17>")
	)
	(segment
		(start 237.040166 -29.413454)
		(end 237.040166 -29.781754)
		(width 0.1651)
		(layer "F.Cu")
		(net "M_B_DQS_DN<17>")
	)
	(segment
		(start 238.65713 -31.218886)
		(end 238.65713 -31.398718)
		(width 0.1651)
		(layer "F.Cu")
		(net "M_B_DQS_DN<17>")
	)
	(segment
		(start 248.243598 -50.236882)
		(end 248.203974 -50.276506)
		(width 0.0889)
		(layer "F.Cu")
		(net "M_B_DQS_DN<17>")
	)
	(segment
		(start 239.451388 -41.624758)
		(end 239.630966 -41.804336)
		(width 0.1651)
		(layer "F.Cu")
		(net "M_B_DQS_DN<17>")
	)
	(segment
		(start 239.1537 -34.16046)
		(end 239.1537 -34.57956)
		(width 0.1651)
		(layer "F.Cu")
		(net "M_B_DQS_DN<17>")
	)
	(segment
		(start 239.271556 -41.265348)
		(end 239.451388 -41.444926)
		(width 0.1651)
		(layer "F.Cu")
		(net "M_B_DQS_DN<17>")
	)
	(segment
		(start 237.758732 -30.50032)
		(end 237.93831 -30.50032)
		(width 0.1651)
		(layer "F.Cu")
		(net "M_B_DQS_DN<17>")
	)
	(segment
		(start 239.0394 -40.45077)
		(end 239.0394 -40.70477)
		(width 0.1651)
		(layer "F.Cu")
		(net "M_B_DQS_DN<17>")
	)
	(segment
		(start 238.9124 -39.4716)
		(end 239.0394 -39.5986)
		(width 0.1651)
		(layer "F.Cu")
		(net "M_B_DQS_DN<17>")
	)
	(segment
		(start 248.243598 -48.123348)
		(end 248.243598 -50.073814)
		(width 0.1016)
		(layer "F.Cu")
		(net "M_B_DQS_DN<17>")
	)
	(segment
		(start 244.161564 -44.041314)
		(end 248.243598 -48.123348)
		(width 0.1016)
		(layer "F.Cu")
		(net "M_B_DQS_DN<17>")
	)
	(segment
		(start 242.632992 -43.228768)
		(end 243.445538 -44.041314)
		(width 0.1016)
		(layer "F.Cu")
		(net "M_B_DQS_DN<17>")
	)
	(segment
		(start 239.0394 -39.8526)
		(end 238.9124 -39.9796)
		(width 0.1651)
		(layer "F.Cu")
		(net "M_B_DQS_DN<17>")
	)
	(segment
		(start 239.735106 -32.476694)
		(end 240.1062 -32.847788)
		(width 0.1651)
		(layer "F.Cu")
		(net "M_B_DQS_DN<17>")
	)
	(segment
		(start 238.9124 -40.83177)
		(end 238.9124 -41.08577)
		(width 0.1651)
		(layer "F.Cu")
		(net "M_B_DQS_DN<17>")
	)
	(segment
		(start 238.049816 -5.822442)
		(end 238.049816 -6.66496)
		(width 0.1651)
		(layer "F.Cu")
		(net "M_B_DQS_DN<17>")
	)
	(segment
		(start 237.455456 -28.070556)
		(end 237.598458 -28.213558)
		(width 0.1651)
		(layer "F.Cu")
		(net "M_B_DQS_DN<17>")
	)
	(segment
		(start 239.0394 -37.1856)
		(end 239.0394 -37.4396)
		(width 0.1651)
		(layer "F.Cu")
		(net "M_B_DQS_DN<17>")
	)
	(segment
		(start 238.118142 -30.85973)
		(end 238.29772 -31.039308)
		(width 0.1651)
		(layer "F.Cu")
		(net "M_B_DQS_DN<17>")
	)
	(segment
		(start 238.9124 -37.5666)
		(end 238.9124 -37.846)
		(width 0.1651)
		(layer "F.Cu")
		(net "M_B_DQS_DN<17>")
	)
	(segment
		(start 248.243598 -50.073814)
		(end 248.243598 -50.236882)
		(width 0.0889)
		(layer "F.Cu")
		(net "M_B_DQS_DN<17>")
	)
	(segment
		(start 237.579154 -30.14091)
		(end 237.579154 -30.320742)
		(width 0.1651)
		(layer "F.Cu")
		(net "M_B_DQS_DN<17>")
	)
	(segment
		(start 240.1062 -35.042602)
		(end 240.1062 -35.56)
		(width 0.1651)
		(layer "F.Cu")
		(net "M_B_DQS_DN<17>")
	)
	(segment
		(start 239.0394 -38.227)
		(end 238.9124 -38.354)
		(width 0.1651)
		(layer "F.Cu")
		(net "M_B_DQS_DN<17>")
	)
	(segment
		(start 239.2807 -34.70656)
		(end 239.770158 -34.70656)
		(width 0.1651)
		(layer "F.Cu")
		(net "M_B_DQS_DN<17>")
	)
	(segment
		(start 238.836708 -31.578296)
		(end 239.016286 -31.578296)
		(width 0.1651)
		(layer "F.Cu")
		(net "M_B_DQS_DN<17>")
	)
	(segment
		(start 238.9124 -37.0586)
		(end 239.0394 -37.1856)
		(width 0.1651)
		(layer "F.Cu")
		(net "M_B_DQS_DN<17>")
	)
	(segment
		(start 237.040166 -29.781754)
		(end 237.219744 -29.961332)
		(width 0.1651)
		(layer "F.Cu")
		(net "M_B_DQS_DN<17>")
	)
	(segment
		(start 239.016286 -31.578296)
		(end 239.196118 -31.757874)
		(width 0.1651)
		(layer "F.Cu")
		(net "M_B_DQS_DN<17>")
	)
	(segment
		(start 238.049816 -6.66496)
		(end 237.631732 -7.083044)
		(width 0.1651)
		(layer "F.Cu")
		(net "M_B_DQS_DN<17>")
	)
	(segment
		(start 237.93831 -30.50032)
		(end 238.118142 -30.679898)
		(width 0.1651)
		(layer "F.Cu")
		(net "M_B_DQS_DN<17>")
	)
	(segment
		(start 248.09831 -52.513992)
		(end 248.202704 -52.618386)
		(width 0.0889)
		(layer "F.Cu")
		(net "M_B_DQS_DN<17>")
	)
	(segment
		(start 238.9124 -38.7096)
		(end 239.0394 -38.8366)
		(width 0.1651)
		(layer "F.Cu")
		(net "M_B_DQS_DN<17>")
	)
	(segment
		(start 237.142528 -28.070556)
		(end 237.455456 -28.070556)
		(width 0.1651)
		(layer "F.Cu")
		(net "M_B_DQS_DN<17>")
	)
	(segment
		(start 238.9124 -40.32377)
		(end 239.0394 -40.45077)
		(width 0.1651)
		(layer "F.Cu")
		(net "M_B_DQS_DN<17>")
	)
	(segment
		(start 239.2807 -34.03346)
		(end 239.1537 -34.16046)
		(width 0.1651)
		(layer "F.Cu")
		(net "M_B_DQS_DN<17>")
	)
	(segment
		(start 237.399322 -29.961332)
		(end 237.579154 -30.14091)
		(width 0.1651)
		(layer "F.Cu")
		(net "M_B_DQS_DN<17>")
	)
	(segment
		(start 237.631732 -7.3152)
		(end 237.81766 -7.501128)
		(width 0.1651)
		(layer "F.Cu")
		(net "M_B_DQS_DN<17>")
	)
	(segment
		(start 239.990376 -42.163746)
		(end 240.908078 -43.081448)
		(width 0.1651)
		(layer "F.Cu")
		(net "M_B_DQS_DN<17>")
	)
	(segment
		(start 239.183164 -36.3982)
		(end 238.9124 -36.668964)
		(width 0.1651)
		(layer "F.Cu")
		(net "M_B_DQS_DN<17>")
	)
	(segment
		(start 239.555274 -32.117284)
		(end 239.735106 -32.296862)
		(width 0.1651)
		(layer "F.Cu")
		(net "M_B_DQS_DN<17>")
	)
	(segment
		(start 237.565692 -7.99973)
		(end 237.338362 -7.99973)
		(width 0.1651)
		(layer "F.Cu")
		(net "M_B_DQS_DN<17>")
	)
	(segment
		(start 237.81766 -7.501128)
		(end 237.81766 -7.747762)
		(width 0.1651)
		(layer "F.Cu")
		(net "M_B_DQS_DN<17>")
	)
	(segment
		(start 238.9124 -37.846)
		(end 239.0394 -37.973)
		(width 0.1651)
		(layer "F.Cu")
		(net "M_B_DQS_DN<17>")
	)
	(segment
		(start 239.0394 -37.4396)
		(end 238.9124 -37.5666)
		(width 0.1651)
		(layer "F.Cu")
		(net "M_B_DQS_DN<17>")
	)
	(segment
		(start 239.1537 -34.57956)
		(end 239.2807 -34.70656)
		(width 0.1651)
		(layer "F.Cu")
		(net "M_B_DQS_DN<17>")
	)
	(segment
		(start 239.770158 -34.03346)
		(end 239.2807 -34.03346)
		(width 0.1651)
		(layer "F.Cu")
		(net "M_B_DQS_DN<17>")
	)
	(segment
		(start 237.338362 -7.99973)
		(end 237.149132 -7.8105)
		(width 0.1651)
		(layer "F.Cu")
		(net "M_B_DQS_DN<17>")
	)
	(segment
		(start 239.735106 -32.296862)
		(end 239.735106 -32.476694)
		(width 0.1651)
		(layer "F.Cu")
		(net "M_B_DQS_DN<17>")
	)
	(via
		(at 237.142528 -13.2334)
		(size 0.508)
		(drill 0.254)
		(layers "F.Cu" "B.Cu")
		(net "M_B_DQS_DN<17>")
	)
	(via
		(at 237.149132 -7.8105)
		(size 0.508)
		(drill 0.254)
		(layers "F.Cu" "B.Cu")
		(net "M_B_DQS_DN<17>")
	)
	(via
		(at 237.142528 -28.070556)
		(size 0.508)
		(drill 0.254)
		(layers "F.Cu" "B.Cu")
		(net "M_B_DQS_DN<17>")
	)
	(via
		(at 240.1062 -35.56)
		(size 0.508)
		(drill 0.254)
		(layers "F.Cu" "B.Cu")
		(net "M_B_DQS_DN<17>")
	)
	(arc
		(start 248.203974 -51.813206)
		(mid 248.177299 -52.088324)
		(end 248.09831 -52.35321)
		(width 0.0889)
		(layer "F.Cu")
		(net "M_B_DQS_DN<17>")
	)
	(segment
		(start 237.337092 -13.038836)
		(end 237.564168 -13.038836)
		(width 0.1651)
		(layer "B.Cu")
		(net "M_B_DQS_DN<17>")
	)
	(segment
		(start 237.606332 -13.7668)
		(end 237.606332 -14.122654)
		(width 0.1651)
		(layer "B.Cu")
		(net "M_B_DQS_DN<17>")
	)
	(segment
		(start 238.05007 -15.222728)
		(end 238.050324 -15.222982)
		(width 0.1651)
		(layer "B.Cu")
		(net "M_B_DQS_DN<17>")
	)
	(segment
		(start 237.142528 -13.2334)
		(end 237.337092 -13.038836)
		(width 0.1651)
		(layer "B.Cu")
		(net "M_B_DQS_DN<17>")
	)
	(segment
		(start 238.05007 -14.566392)
		(end 238.05007 -15.222728)
		(width 0.1651)
		(layer "B.Cu")
		(net "M_B_DQS_DN<17>")
	)
	(segment
		(start 237.784132 -13.589)
		(end 237.606332 -13.7668)
		(width 0.1651)
		(layer "B.Cu")
		(net "M_B_DQS_DN<17>")
	)
	(segment
		(start 237.564168 -13.038836)
		(end 237.784132 -13.2588)
		(width 0.1651)
		(layer "B.Cu")
		(net "M_B_DQS_DN<17>")
	)
	(segment
		(start 237.606332 -14.122654)
		(end 238.05007 -14.566392)
		(width 0.1651)
		(layer "B.Cu")
		(net "M_B_DQS_DN<17>")
	)
	(segment
		(start 237.784132 -13.2588)
		(end 237.784132 -13.589)
		(width 0.1651)
		(layer "B.Cu")
		(net "M_B_DQS_DN<17>")
	)
	(segment
		(start 237.142528 -28.070556)
		(end 237.908846 -27.304238)
		(width 0.14224)
		(layer "In11.Cu")
		(net "M_B_DQS_DN<17>")
	)
	(segment
		(start 237.580932 -14.158468)
		(end 237.580932 -13.671804)
		(width 0.14224)
		(layer "In11.Cu")
		(net "M_B_DQS_DN<17>")
	)
	(segment
		(start 237.908846 -27.304238)
		(end 237.908846 -15.683738)
		(width 0.14224)
		(layer "In11.Cu")
		(net "M_B_DQS_DN<17>")
	)
	(segment
		(start 237.344712 -8.00608)
		(end 237.149132 -7.8105)
		(width 0.14224)
		(layer "In11.Cu")
		(net "M_B_DQS_DN<17>")
	)
	(segment
		(start 237.400846 -14.338554)
		(end 237.580932 -14.158468)
		(width 0.14224)
		(layer "In11.Cu")
		(net "M_B_DQS_DN<17>")
	)
	(segment
		(start 237.908846 -15.683738)
		(end 237.400846 -15.175738)
		(width 0.14224)
		(layer "In11.Cu")
		(net "M_B_DQS_DN<17>")
	)
	(segment
		(start 237.580932 -13.671804)
		(end 237.142528 -13.2334)
		(width 0.14224)
		(layer "In11.Cu")
		(net "M_B_DQS_DN<17>")
	)
	(segment
		(start 237.59414 -8.00608)
		(end 237.344712 -8.00608)
		(width 0.14224)
		(layer "In11.Cu")
		(net "M_B_DQS_DN<17>")
	)
	(segment
		(start 237.931452 -12.444476)
		(end 237.931452 -8.343392)
		(width 0.14224)
		(layer "In11.Cu")
		(net "M_B_DQS_DN<17>")
	)
	(segment
		(start 237.400846 -15.175738)
		(end 237.400846 -14.338554)
		(width 0.14224)
		(layer "In11.Cu")
		(net "M_B_DQS_DN<17>")
	)
	(segment
		(start 237.142528 -13.2334)
		(end 237.931452 -12.444476)
		(width 0.14224)
		(layer "In11.Cu")
		(net "M_B_DQS_DN<17>")
	)
	(segment
		(start 237.931452 -8.343392)
		(end 237.59414 -8.00608)
		(width 0.14224)
		(layer "In11.Cu")
		(net "M_B_DQS_DN<17>")
	)
	(segment
		(start 311.51576 -7.99973)
		(end 311.767728 -7.747762)
		(width 0.1651)
		(layer "F.Cu")
		(net "M_B_DQS_DN<16>")
	)
	(segment
		(start 311.999884 -5.822442)
		(end 312.000392 -5.822442)
		(width 0.1651)
		(layer "F.Cu")
		(net "M_B_DQS_DN<16>")
	)
	(segment
		(start 311.767728 -7.747762)
		(end 311.767728 -7.501128)
		(width 0.1651)
		(layer "F.Cu")
		(net "M_B_DQS_DN<16>")
	)
	(segment
		(start 311.11825 -7.8105)
		(end 311.30748 -7.99973)
		(width 0.1651)
		(layer "F.Cu")
		(net "M_B_DQS_DN<16>")
	)
	(segment
		(start 311.767728 -7.501128)
		(end 311.5818 -7.3152)
		(width 0.1651)
		(layer "F.Cu")
		(net "M_B_DQS_DN<16>")
	)
	(segment
		(start 311.0992 -7.8105)
		(end 311.11825 -7.8105)
		(width 0.1651)
		(layer "F.Cu")
		(net "M_B_DQS_DN<16>")
	)
	(segment
		(start 284.929834 -58.876438)
		(end 284.358334 -58.876438)
		(width 0.1016)
		(layer "F.Cu")
		(net "M_B_DQS_DN<16>")
	)
	(segment
		(start 311.5818 -7.3152)
		(end 311.5818 -7.083044)
		(width 0.1651)
		(layer "F.Cu")
		(net "M_B_DQS_DN<16>")
	)
	(segment
		(start 311.30748 -7.99973)
		(end 311.51576 -7.99973)
		(width 0.1651)
		(layer "F.Cu")
		(net "M_B_DQS_DN<16>")
	)
	(segment
		(start 311.999884 -6.66496)
		(end 311.999884 -5.822442)
		(width 0.1651)
		(layer "F.Cu")
		(net "M_B_DQS_DN<16>")
	)
	(segment
		(start 311.5818 -7.083044)
		(end 311.999884 -6.66496)
		(width 0.1651)
		(layer "F.Cu")
		(net "M_B_DQS_DN<16>")
	)
	(via
		(at 311.0992 -7.8105)
		(size 0.508)
		(drill 0.254)
		(layers "F.Cu" "B.Cu")
		(net "M_B_DQS_DN<16>")
	)
	(via
		(at 284.358334 -58.876438)
		(size 0.508)
		(drill 0.254)
		(layers "F.Cu" "B.Cu")
		(net "M_B_DQS_DN<16>")
	)
	(via
		(at 311.092596 -13.2334)
		(size 0.508)
		(drill 0.254)
		(layers "F.Cu" "B.Cu")
		(net "M_B_DQS_DN<16>")
	)
	(segment
		(start 311.092596 -13.2334)
		(end 311.28716 -13.038836)
		(width 0.1651)
		(layer "B.Cu")
		(net "M_B_DQS_DN<16>")
	)
	(segment
		(start 311.999884 -14.566138)
		(end 311.999884 -15.222982)
		(width 0.1651)
		(layer "B.Cu")
		(net "M_B_DQS_DN<16>")
	)
	(segment
		(start 311.7342 -13.2588)
		(end 311.7342 -13.589)
		(width 0.1651)
		(layer "B.Cu")
		(net "M_B_DQS_DN<16>")
	)
	(segment
		(start 311.5564 -13.7668)
		(end 311.5564 -14.122654)
		(width 0.1651)
		(layer "B.Cu")
		(net "M_B_DQS_DN<16>")
	)
	(segment
		(start 311.28716 -13.038836)
		(end 311.514236 -13.038836)
		(width 0.1651)
		(layer "B.Cu")
		(net "M_B_DQS_DN<16>")
	)
	(segment
		(start 311.514236 -13.038836)
		(end 311.7342 -13.2588)
		(width 0.1651)
		(layer "B.Cu")
		(net "M_B_DQS_DN<16>")
	)
	(segment
		(start 311.7342 -13.589)
		(end 311.5564 -13.7668)
		(width 0.1651)
		(layer "B.Cu")
		(net "M_B_DQS_DN<16>")
	)
	(segment
		(start 311.999884 -15.222982)
		(end 312.000392 -15.222982)
		(width 0.1651)
		(layer "B.Cu")
		(net "M_B_DQS_DN<16>")
	)
	(segment
		(start 311.5564 -14.122654)
		(end 311.999884 -14.566138)
		(width 0.1651)
		(layer "B.Cu")
		(net "M_B_DQS_DN<16>")
	)
	(segment
		(start 312.032396 -21.0058)
		(end 312.032396 -20.7518)
		(width 0.14224)
		(layer "In4.Cu")
		(net "M_B_DQS_DN<16>")
	)
	(segment
		(start 311.092596 -13.2334)
		(end 311.88152 -12.444476)
		(width 0.14224)
		(layer "In4.Cu")
		(net "M_B_DQS_DN<16>")
	)
	(segment
		(start 292.030658 -47.298102)
		(end 292.192202 -47.298102)
		(width 0.14224)
		(layer "In4.Cu")
		(net "M_B_DQS_DN<16>")
	)
	(segment
		(start 285.2166 -57.981088)
		(end 285.23438 -57.981088)
		(width 0.0889)
		(layer "In4.Cu")
		(net "M_B_DQS_DN<16>")
	)
	(segment
		(start 289.64382 -49.68494)
		(end 289.823398 -49.505362)
		(width 0.14224)
		(layer "In4.Cu")
		(net "M_B_DQS_DN<16>")
	)
	(segment
		(start 291.090096 -48.400208)
		(end 291.269928 -48.220376)
		(width 0.14224)
		(layer "In4.Cu")
		(net "M_B_DQS_DN<16>")
	)
	(segment
		(start 312.032396 -20.2438)
		(end 312.032396 -19.9898)
		(width 0.14224)
		(layer "In4.Cu")
		(net "M_B_DQS_DN<16>")
	)
	(segment
		(start 289.463988 -50.026316)
		(end 289.64382 -49.846484)
		(width 0.14224)
		(layer "In4.Cu")
		(net "M_B_DQS_DN<16>")
	)
	(segment
		(start 310.89092 -14.58468)
		(end 311.0738 -14.4018)
		(width 0.14224)
		(layer "In4.Cu")
		(net "M_B_DQS_DN<16>")
	)
	(segment
		(start 311.874916 -19.83232)
		(end 311.874916 -19.63928)
		(width 0.14224)
		(layer "In4.Cu")
		(net "M_B_DQS_DN<16>")
	)
	(segment
		(start 289.10788 -50.382424)
		(end 289.10788 -50.22088)
		(width 0.14224)
		(layer "In4.Cu")
		(net "M_B_DQS_DN<16>")
	)
	(segment
		(start 311.874916 -16.032988)
		(end 310.89092 -15.048992)
		(width 0.14224)
		(layer "In4.Cu")
		(net "M_B_DQS_DN<16>")
	)
	(segment
		(start 310.89092 -15.048992)
		(end 310.89092 -14.58468)
		(width 0.14224)
		(layer "In4.Cu")
		(net "M_B_DQS_DN<16>")
	)
	(segment
		(start 291.61105 -47.879254)
		(end 291.790882 -47.699422)
		(width 0.14224)
		(layer "In4.Cu")
		(net "M_B_DQS_DN<16>")
	)
	(segment
		(start 288.586926 -50.741834)
		(end 288.766504 -50.562256)
		(width 0.14224)
		(layer "In4.Cu")
		(net "M_B_DQS_DN<16>")
	)
	(segment
		(start 292.372034 -46.956726)
		(end 292.88232 -46.44644)
		(width 0.14224)
		(layer "In4.Cu")
		(net "M_B_DQS_DN<16>")
	)
	(segment
		(start 312.032396 -19.4818)
		(end 312.032396 -19.2278)
		(width 0.14224)
		(layer "In4.Cu")
		(net "M_B_DQS_DN<16>")
	)
	(segment
		(start 311.874916 -23.82012)
		(end 311.874916 -21.16328)
		(width 0.14224)
		(layer "In4.Cu")
		(net "M_B_DQS_DN<16>")
	)
	(segment
		(start 285.723584 -53.731922)
		(end 285.72841 -53.723286)
		(width 0.0889)
		(layer "In4.Cu")
		(net "M_B_DQS_DN<16>")
	)
	(segment
		(start 291.790882 -47.537878)
		(end 292.030658 -47.298102)
		(width 0.14224)
		(layer "In4.Cu")
		(net "M_B_DQS_DN<16>")
	)
	(segment
		(start 285.72841 -56.695086)
		(end 285.73476 -56.684418)
		(width 0.0889)
		(layer "In4.Cu")
		(net "M_B_DQS_DN<16>")
	)
	(segment
		(start 312.032396 -20.7518)
		(end 311.874916 -20.59432)
		(width 0.14224)
		(layer "In4.Cu")
		(net "M_B_DQS_DN<16>")
	)
	(segment
		(start 285.72841 -53.723286)
		(end 285.73476 -53.712618)
		(width 0.0889)
		(layer "In4.Cu")
		(net "M_B_DQS_DN<16>")
	)
	(segment
		(start 290.367212 -48.961548)
		(end 290.52901 -48.961548)
		(width 0.14224)
		(layer "In4.Cu")
		(net "M_B_DQS_DN<16>")
	)
	(segment
		(start 311.874916 -20.59432)
		(end 311.874916 -20.40128)
		(width 0.14224)
		(layer "In4.Cu")
		(net "M_B_DQS_DN<16>")
	)
	(segment
		(start 306.936648 -34.77387)
		(end 306.936648 -34.237676)
		(width 0.14224)
		(layer "In4.Cu")
		(net "M_B_DQS_DN<16>")
	)
	(segment
		(start 311.874916 -19.07032)
		(end 311.874916 -16.032988)
		(width 0.14224)
		(layer "In4.Cu")
		(net "M_B_DQS_DN<16>")
	)
	(segment
		(start 287.289494 -51.98364)
		(end 288.51606 -50.757074)
		(width 0.0889)
		(layer "In4.Cu")
		(net "M_B_DQS_DN<16>")
	)
	(segment
		(start 311.29478 -8.00608)
		(end 311.0992 -7.8105)
		(width 0.14224)
		(layer "In4.Cu")
		(net "M_B_DQS_DN<16>")
	)
	(segment
		(start 286.76346 -51.98364)
		(end 287.289494 -51.98364)
		(width 0.0889)
		(layer "In4.Cu")
		(net "M_B_DQS_DN<16>")
	)
	(segment
		(start 288.766504 -50.562256)
		(end 288.928048 -50.562256)
		(width 0.14224)
		(layer "In4.Cu")
		(net "M_B_DQS_DN<16>")
	)
	(segment
		(start 295.264078 -46.44644)
		(end 306.936648 -34.77387)
		(width 0.14224)
		(layer "In4.Cu")
		(net "M_B_DQS_DN<16>")
	)
	(segment
		(start 290.708842 -48.781716)
		(end 290.708842 -48.619918)
		(width 0.14224)
		(layer "In4.Cu")
		(net "M_B_DQS_DN<16>")
	)
	(segment
		(start 311.874916 -24.38908)
		(end 312.032396 -24.2316)
		(width 0.14224)
		(layer "In4.Cu")
		(net "M_B_DQS_DN<16>")
	)
	(segment
		(start 288.571432 -50.757328)
		(end 288.586926 -50.741834)
		(width 0.0889)
		(layer "In4.Cu")
		(net "M_B_DQS_DN<16>")
	)
	(segment
		(start 307.62956 -33.405826)
		(end 308.165246 -33.405826)
		(width 0.14224)
		(layer "In4.Cu")
		(net "M_B_DQS_DN<16>")
	)
	(segment
		(start 306.324254 -33.339024)
		(end 306.777136 -32.886142)
		(width 0.14224)
		(layer "In4.Cu")
		(net "M_B_DQS_DN<16>")
	)
	(segment
		(start 285.72841 -54.713886)
		(end 285.73476 -54.703218)
		(width 0.0889)
		(layer "In4.Cu")
		(net "M_B_DQS_DN<16>")
	)
	(segment
		(start 290.708842 -48.619918)
		(end 290.928552 -48.400208)
		(width 0.14224)
		(layer "In4.Cu")
		(net "M_B_DQS_DN<16>")
	)
	(segment
		(start 311.531 -13.671804)
		(end 311.092596 -13.2334)
		(width 0.14224)
		(layer "In4.Cu")
		(net "M_B_DQS_DN<16>")
	)
	(segment
		(start 306.777136 -32.886142)
		(end 307.109876 -32.886142)
		(width 0.14224)
		(layer "In4.Cu")
		(net "M_B_DQS_DN<16>")
	)
	(segment
		(start 308.165246 -33.405826)
		(end 308.771798 -32.799274)
		(width 0.14224)
		(layer "In4.Cu")
		(net "M_B_DQS_DN<16>")
	)
	(segment
		(start 308.771798 -32.262826)
		(end 308.294278 -31.785306)
		(width 0.14224)
		(layer "In4.Cu")
		(net "M_B_DQS_DN<16>")
	)
	(segment
		(start 308.771798 -32.799274)
		(end 308.771798 -32.262826)
		(width 0.14224)
		(layer "In4.Cu")
		(net "M_B_DQS_DN<16>")
	)
	(segment
		(start 286.58693 -52.237386)
		(end 286.69234 -52.055014)
		(width 0.0889)
		(layer "In4.Cu")
		(net "M_B_DQS_DN<16>")
	)
	(segment
		(start 288.51606 -50.757074)
		(end 288.571432 -50.757328)
		(width 0.0889)
		(layer "In4.Cu")
		(net "M_B_DQS_DN<16>")
	)
	(segment
		(start 290.164774 -49.163986)
		(end 290.367212 -48.961548)
		(width 0.14224)
		(layer "In4.Cu")
		(net "M_B_DQS_DN<16>")
	)
	(segment
		(start 286.69234 -52.055014)
		(end 286.76346 -51.98364)
		(width 0.0889)
		(layer "In4.Cu")
		(net "M_B_DQS_DN<16>")
	)
	(segment
		(start 291.790882 -47.699422)
		(end 291.790882 -47.537878)
		(width 0.14224)
		(layer "In4.Cu")
		(net "M_B_DQS_DN<16>")
	)
	(segment
		(start 290.928552 -48.400208)
		(end 291.090096 -48.400208)
		(width 0.14224)
		(layer "In4.Cu")
		(net "M_B_DQS_DN<16>")
	)
	(segment
		(start 312.032396 -23.9776)
		(end 311.874916 -23.82012)
		(width 0.14224)
		(layer "In4.Cu")
		(net "M_B_DQS_DN<16>")
	)
	(segment
		(start 307.109876 -32.886142)
		(end 307.62956 -33.405826)
		(width 0.14224)
		(layer "In4.Cu")
		(net "M_B_DQS_DN<16>")
	)
	(segment
		(start 306.324254 -33.625282)
		(end 306.324254 -33.339024)
		(width 0.14224)
		(layer "In4.Cu")
		(net "M_B_DQS_DN<16>")
	)
	(segment
		(start 308.294278 -31.473902)
		(end 311.874916 -27.893264)
		(width 0.14224)
		(layer "In4.Cu")
		(net "M_B_DQS_DN<16>")
	)
	(segment
		(start 289.10788 -50.22088)
		(end 289.302444 -50.026316)
		(width 0.14224)
		(layer "In4.Cu")
		(net "M_B_DQS_DN<16>")
	)
	(segment
		(start 286.063944 -52.532534)
		(end 286.09671 -52.532534)
		(width 0.0889)
		(layer "In4.Cu")
		(net "M_B_DQS_DN<16>")
	)
	(segment
		(start 285.72841 -55.704486)
		(end 285.73476 -55.693818)
		(width 0.0889)
		(layer "In4.Cu")
		(net "M_B_DQS_DN<16>")
	)
	(segment
		(start 311.544208 -8.00608)
		(end 311.29478 -8.00608)
		(width 0.14224)
		(layer "In4.Cu")
		(net "M_B_DQS_DN<16>")
	)
	(segment
		(start 290.164774 -49.32553)
		(end 290.164774 -49.163986)
		(width 0.14224)
		(layer "In4.Cu")
		(net "M_B_DQS_DN<16>")
	)
	(segment
		(start 312.032396 -19.2278)
		(end 311.874916 -19.07032)
		(width 0.14224)
		(layer "In4.Cu")
		(net "M_B_DQS_DN<16>")
	)
	(segment
		(start 311.3278 -14.4018)
		(end 311.531 -14.1986)
		(width 0.14224)
		(layer "In4.Cu")
		(net "M_B_DQS_DN<16>")
	)
	(segment
		(start 292.192202 -47.298102)
		(end 292.372034 -47.11827)
		(width 0.14224)
		(layer "In4.Cu")
		(net "M_B_DQS_DN<16>")
	)
	(segment
		(start 291.449506 -47.879254)
		(end 291.61105 -47.879254)
		(width 0.14224)
		(layer "In4.Cu")
		(net "M_B_DQS_DN<16>")
	)
	(segment
		(start 311.874916 -19.63928)
		(end 312.032396 -19.4818)
		(width 0.14224)
		(layer "In4.Cu")
		(net "M_B_DQS_DN<16>")
	)
	(segment
		(start 289.823398 -49.505362)
		(end 289.984942 -49.505362)
		(width 0.14224)
		(layer "In4.Cu")
		(net "M_B_DQS_DN<16>")
	)
	(segment
		(start 311.0738 -14.4018)
		(end 311.3278 -14.4018)
		(width 0.14224)
		(layer "In4.Cu")
		(net "M_B_DQS_DN<16>")
	)
	(segment
		(start 284.870144 -58.18124)
		(end 284.873446 -58.175398)
		(width 0.0889)
		(layer "In4.Cu")
		(net "M_B_DQS_DN<16>")
	)
	(segment
		(start 311.874916 -21.16328)
		(end 312.032396 -21.0058)
		(width 0.14224)
		(layer "In4.Cu")
		(net "M_B_DQS_DN<16>")
	)
	(segment
		(start 312.032396 -19.9898)
		(end 311.874916 -19.83232)
		(width 0.14224)
		(layer "In4.Cu")
		(net "M_B_DQS_DN<16>")
	)
	(segment
		(start 290.52901 -48.961548)
		(end 290.708842 -48.781716)
		(width 0.14224)
		(layer "In4.Cu")
		(net "M_B_DQS_DN<16>")
	)
	(segment
		(start 285.723584 -54.722522)
		(end 285.72841 -54.713886)
		(width 0.0889)
		(layer "In4.Cu")
		(net "M_B_DQS_DN<16>")
	)
	(segment
		(start 311.531 -14.1986)
		(end 311.531 -13.671804)
		(width 0.14224)
		(layer "In4.Cu")
		(net "M_B_DQS_DN<16>")
	)
	(segment
		(start 289.64382 -49.846484)
		(end 289.64382 -49.68494)
		(width 0.14224)
		(layer "In4.Cu")
		(net "M_B_DQS_DN<16>")
	)
	(segment
		(start 311.88152 -8.343392)
		(end 311.544208 -8.00608)
		(width 0.14224)
		(layer "In4.Cu")
		(net "M_B_DQS_DN<16>")
	)
	(segment
		(start 289.984942 -49.505362)
		(end 290.164774 -49.32553)
		(width 0.14224)
		(layer "In4.Cu")
		(net "M_B_DQS_DN<16>")
	)
	(segment
		(start 312.032396 -24.2316)
		(end 312.032396 -23.9776)
		(width 0.14224)
		(layer "In4.Cu")
		(net "M_B_DQS_DN<16>")
	)
	(segment
		(start 289.302444 -50.026316)
		(end 289.463988 -50.026316)
		(width 0.14224)
		(layer "In4.Cu")
		(net "M_B_DQS_DN<16>")
	)
	(segment
		(start 284.358334 -58.476388)
		(end 284.376114 -58.476388)
		(width 0.0889)
		(layer "In4.Cu")
		(net "M_B_DQS_DN<16>")
	)
	(segment
		(start 285.723584 -55.713122)
		(end 285.72841 -55.704486)
		(width 0.0889)
		(layer "In4.Cu")
		(net "M_B_DQS_DN<16>")
	)
	(segment
		(start 311.874916 -20.40128)
		(end 312.032396 -20.2438)
		(width 0.14224)
		(layer "In4.Cu")
		(net "M_B_DQS_DN<16>")
	)
	(segment
		(start 285.723584 -56.703722)
		(end 285.72841 -56.695086)
		(width 0.0889)
		(layer "In4.Cu")
		(net "M_B_DQS_DN<16>")
	)
	(segment
		(start 291.269928 -48.058832)
		(end 291.449506 -47.879254)
		(width 0.14224)
		(layer "In4.Cu")
		(net "M_B_DQS_DN<16>")
	)
	(segment
		(start 306.936648 -34.237676)
		(end 306.324254 -33.625282)
		(width 0.14224)
		(layer "In4.Cu")
		(net "M_B_DQS_DN<16>")
	)
	(segment
		(start 311.874916 -27.893264)
		(end 311.874916 -24.38908)
		(width 0.14224)
		(layer "In4.Cu")
		(net "M_B_DQS_DN<16>")
	)
	(segment
		(start 292.372034 -47.11827)
		(end 292.372034 -46.956726)
		(width 0.14224)
		(layer "In4.Cu")
		(net "M_B_DQS_DN<16>")
	)
	(segment
		(start 311.88152 -12.444476)
		(end 311.88152 -8.343392)
		(width 0.14224)
		(layer "In4.Cu")
		(net "M_B_DQS_DN<16>")
	)
	(segment
		(start 288.928048 -50.562256)
		(end 289.10788 -50.382424)
		(width 0.14224)
		(layer "In4.Cu")
		(net "M_B_DQS_DN<16>")
	)
	(segment
		(start 292.88232 -46.44644)
		(end 295.264078 -46.44644)
		(width 0.14224)
		(layer "In4.Cu")
		(net "M_B_DQS_DN<16>")
	)
	(segment
		(start 308.294278 -31.785306)
		(end 308.294278 -31.473902)
		(width 0.14224)
		(layer "In4.Cu")
		(net "M_B_DQS_DN<16>")
	)
	(segment
		(start 291.269928 -48.220376)
		(end 291.269928 -48.058832)
		(width 0.14224)
		(layer "In4.Cu")
		(net "M_B_DQS_DN<16>")
	)
	(arc
		(start 285.73476 -56.684418)
		(mid 285.807558 -56.393655)
		(end 285.72841 -56.104536)
		(width 0.0889)
		(layer "In4.Cu")
		(net "M_B_DQS_DN<16>")
	)
	(arc
		(start 284.358334 -58.876438)
		(mid 284.158436 -58.67654)
		(end 284.358334 -58.476388)
		(width 0.0889)
		(layer "In4.Cu")
		(net "M_B_DQS_DN<16>")
	)
	(arc
		(start 285.72841 -57.095136)
		(mid 285.67494 -56.900073)
		(end 285.723584 -56.703722)
		(width 0.0889)
		(layer "In4.Cu")
		(net "M_B_DQS_DN<16>")
	)
	(arc
		(start 284.873446 -58.175398)
		(mid 285.019412 -58.032999)
		(end 285.2166 -57.981088)
		(width 0.0889)
		(layer "In4.Cu")
		(net "M_B_DQS_DN<16>")
	)
	(arc
		(start 285.73476 -54.703218)
		(mid 285.807558 -54.412455)
		(end 285.72841 -54.123336)
		(width 0.0889)
		(layer "In4.Cu")
		(net "M_B_DQS_DN<16>")
	)
	(arc
		(start 285.73476 -53.712618)
		(mid 285.807558 -53.421855)
		(end 285.72841 -53.132736)
		(width 0.0889)
		(layer "In4.Cu")
		(net "M_B_DQS_DN<16>")
	)
	(arc
		(start 285.72841 -53.132736)
		(mid 285.725662 -52.737269)
		(end 286.063944 -52.532534)
		(width 0.0889)
		(layer "In4.Cu")
		(net "M_B_DQS_DN<16>")
	)
	(arc
		(start 284.376114 -58.476388)
		(mid 284.661476 -58.393)
		(end 284.870144 -58.18124)
		(width 0.0889)
		(layer "In4.Cu")
		(net "M_B_DQS_DN<16>")
	)
	(arc
		(start 285.72841 -55.113936)
		(mid 285.67494 -54.918873)
		(end 285.723584 -54.722522)
		(width 0.0889)
		(layer "In4.Cu")
		(net "M_B_DQS_DN<16>")
	)
	(arc
		(start 285.73476 -55.693818)
		(mid 285.807558 -55.403055)
		(end 285.72841 -55.113936)
		(width 0.0889)
		(layer "In4.Cu")
		(net "M_B_DQS_DN<16>")
	)
	(arc
		(start 286.09671 -52.532534)
		(mid 286.379927 -52.448253)
		(end 286.58693 -52.237386)
		(width 0.0889)
		(layer "In4.Cu")
		(net "M_B_DQS_DN<16>")
	)
	(arc
		(start 285.72841 -56.104536)
		(mid 285.67494 -55.909473)
		(end 285.723584 -55.713122)
		(width 0.0889)
		(layer "In4.Cu")
		(net "M_B_DQS_DN<16>")
	)
	(arc
		(start 285.72841 -54.123336)
		(mid 285.67494 -53.928273)
		(end 285.723584 -53.731922)
		(width 0.0889)
		(layer "In4.Cu")
		(net "M_B_DQS_DN<16>")
	)
	(arc
		(start 285.23438 -57.981088)
		(mid 285.732631 -57.678248)
		(end 285.72841 -57.095136)
		(width 0.0889)
		(layer "In4.Cu")
		(net "M_B_DQS_DN<16>")
	)
	(segment
		(start 284.709616 -49.149)
		(end 284.863286 -49.149)
		(width 0.0889)
		(layer "F.Cu")
		(net "M_B_DQS_DN<15>")
	)
	(segment
		(start 301.5742 -29.21)
		(end 302.081946 -29.21)
		(width 0.1651)
		(layer "F.Cu")
		(net "M_B_DQS_DN<15>")
	)
	(segment
		(start 298.836334 -39.981124)
		(end 302.4124 -36.405058)
		(width 0.1651)
		(layer "F.Cu")
		(net "M_B_DQS_DN<15>")
	)
	(segment
		(start 297.679872 -43.167554)
		(end 297.679872 -41.892728)
		(width 0.1016)
		(layer "F.Cu")
		(net "M_B_DQS_DN<15>")
	)
	(segment
		(start 298.476924 -40.340534)
		(end 298.656756 -40.340534)
		(width 0.1651)
		(layer "F.Cu")
		(net "M_B_DQS_DN<15>")
	)
	(segment
		(start 302.08855 -30.363922)
		(end 301.49292 -30.363922)
		(width 0.1651)
		(layer "F.Cu")
		(net "M_B_DQS_DN<15>")
	)
	(segment
		(start 284.863286 -49.149)
		(end 287.643062 -46.369224)
		(width 0.1016)
		(layer "F.Cu")
		(net "M_B_DQS_DN<15>")
	)
	(segment
		(start 302.4124 -32.83585)
		(end 302.06315 -32.4866)
		(width 0.1651)
		(layer "F.Cu")
		(net "M_B_DQS_DN<15>")
	)
	(segment
		(start 298.836334 -40.160956)
		(end 298.836334 -39.981124)
		(width 0.1651)
		(layer "F.Cu")
		(net "M_B_DQS_DN<15>")
	)
	(segment
		(start 301.957486 -7.99973)
		(end 302.165766 -7.99973)
		(width 0.1651)
		(layer "F.Cu")
		(net "M_B_DQS_DN<15>")
	)
	(segment
		(start 301.749206 -7.8105)
		(end 301.768256 -7.8105)
		(width 0.1651)
		(layer "F.Cu")
		(net "M_B_DQS_DN<15>")
	)
	(segment
		(start 302.64989 -5.822442)
		(end 302.650398 -5.822442)
		(width 0.1651)
		(layer "F.Cu")
		(net "M_B_DQS_DN<15>")
	)
	(segment
		(start 302.4124 -35.814)
		(end 302.4124 -35.311842)
		(width 0.1651)
		(layer "F.Cu")
		(net "M_B_DQS_DN<15>")
	)
	(segment
		(start 283.816044 -51.020726)
		(end 283.816044 -50.042572)
		(width 0.0889)
		(layer "F.Cu")
		(net "M_B_DQS_DN<15>")
	)
	(segment
		(start 302.231806 -6.894068)
		(end 302.64989 -6.475984)
		(width 0.1651)
		(layer "F.Cu")
		(net "M_B_DQS_DN<15>")
	)
	(segment
		(start 294.478202 -46.369224)
		(end 297.679872 -43.167554)
		(width 0.1016)
		(layer "F.Cu")
		(net "M_B_DQS_DN<15>")
	)
	(segment
		(start 297.867578 -40.94988)
		(end 298.047156 -40.94988)
		(width 0.1651)
		(layer "F.Cu")
		(net "M_B_DQS_DN<15>")
	)
	(segment
		(start 301.820326 -33.898332)
		(end 302.4124 -33.306258)
		(width 0.1651)
		(layer "F.Cu")
		(net "M_B_DQS_DN<15>")
	)
	(segment
		(start 301.36592 -29.41828)
		(end 301.5742 -29.21)
		(width 0.1651)
		(layer "F.Cu")
		(net "M_B_DQS_DN<15>")
	)
	(segment
		(start 298.226988 -40.770302)
		(end 298.226988 -40.59047)
		(width 0.1651)
		(layer "F.Cu")
		(net "M_B_DQS_DN<15>")
	)
	(segment
		(start 302.417734 -7.747762)
		(end 302.417734 -7.501128)
		(width 0.1651)
		(layer "F.Cu")
		(net "M_B_DQS_DN<15>")
	)
	(segment
		(start 284.071314 -51.778408)
		(end 284.008068 -51.841654)
		(width 0.0889)
		(layer "F.Cu")
		(net "M_B_DQS_DN<15>")
	)
	(segment
		(start 301.768256 -7.8105)
		(end 301.957486 -7.99973)
		(width 0.1651)
		(layer "F.Cu")
		(net "M_B_DQS_DN<15>")
	)
	(segment
		(start 302.08855 -31.6865)
		(end 302.4378 -31.33725)
		(width 0.1651)
		(layer "F.Cu")
		(net "M_B_DQS_DN<15>")
	)
	(segment
		(start 283.79293 -51.733958)
		(end 283.792676 -51.734466)
		(width 0.0889)
		(layer "F.Cu")
		(net "M_B_DQS_DN<15>")
	)
	(segment
		(start 283.816044 -50.042572)
		(end 284.709616 -49.149)
		(width 0.0889)
		(layer "F.Cu")
		(net "M_B_DQS_DN<15>")
	)
	(segment
		(start 302.64989 -6.475984)
		(end 302.64989 -5.822442)
		(width 0.1651)
		(layer "F.Cu")
		(net "M_B_DQS_DN<15>")
	)
	(segment
		(start 302.231806 -7.3152)
		(end 302.231806 -6.894068)
		(width 0.1651)
		(layer "F.Cu")
		(net "M_B_DQS_DN<15>")
	)
	(segment
		(start 302.198024 -28.525978)
		(end 301.742602 -28.070556)
		(width 0.1651)
		(layer "F.Cu")
		(net "M_B_DQS_DN<15>")
	)
	(segment
		(start 301.36592 -32.308292)
		(end 301.36592 -31.864808)
		(width 0.1651)
		(layer "F.Cu")
		(net "M_B_DQS_DN<15>")
	)
	(segment
		(start 302.198024 -29.093922)
		(end 302.198024 -28.525978)
		(width 0.1651)
		(layer "F.Cu")
		(net "M_B_DQS_DN<15>")
	)
	(segment
		(start 302.417734 -7.501128)
		(end 302.231806 -7.3152)
		(width 0.1651)
		(layer "F.Cu")
		(net "M_B_DQS_DN<15>")
	)
	(segment
		(start 298.047156 -40.94988)
		(end 298.226988 -40.770302)
		(width 0.1651)
		(layer "F.Cu")
		(net "M_B_DQS_DN<15>")
	)
	(segment
		(start 288.244026 -46.369224)
		(end 294.478202 -46.369224)
		(width 0.1016)
		(layer "F.Cu")
		(net "M_B_DQS_DN<15>")
	)
	(segment
		(start 302.081946 -29.21)
		(end 302.198024 -29.093922)
		(width 0.1651)
		(layer "F.Cu")
		(net "M_B_DQS_DN<15>")
	)
	(segment
		(start 283.7053 -51.211988)
		(end 283.816044 -51.020726)
		(width 0.0889)
		(layer "F.Cu")
		(net "M_B_DQS_DN<15>")
	)
	(segment
		(start 302.06315 -32.4866)
		(end 301.544228 -32.4866)
		(width 0.1651)
		(layer "F.Cu")
		(net "M_B_DQS_DN<15>")
	)
	(segment
		(start 301.36592 -30.236922)
		(end 301.36592 -29.41828)
		(width 0.1651)
		(layer "F.Cu")
		(net "M_B_DQS_DN<15>")
	)
	(segment
		(start 301.544228 -32.4866)
		(end 301.36592 -32.308292)
		(width 0.1651)
		(layer "F.Cu")
		(net "M_B_DQS_DN<15>")
	)
	(segment
		(start 302.4124 -36.405058)
		(end 302.4124 -35.814)
		(width 0.1651)
		(layer "F.Cu")
		(net "M_B_DQS_DN<15>")
	)
	(segment
		(start 301.36592 -31.864808)
		(end 301.544228 -31.6865)
		(width 0.1651)
		(layer "F.Cu")
		(net "M_B_DQS_DN<15>")
	)
	(segment
		(start 297.688 -41.129458)
		(end 297.867578 -40.94988)
		(width 0.1651)
		(layer "F.Cu")
		(net "M_B_DQS_DN<15>")
	)
	(segment
		(start 284.071314 -51.446938)
		(end 284.071314 -51.778408)
		(width 0.0889)
		(layer "F.Cu")
		(net "M_B_DQS_DN<15>")
	)
	(segment
		(start 301.544228 -31.6865)
		(end 302.08855 -31.6865)
		(width 0.1651)
		(layer "F.Cu")
		(net "M_B_DQS_DN<15>")
	)
	(segment
		(start 283.792676 -51.734466)
		(end 283.775912 -51.71821)
		(width 0.0889)
		(layer "F.Cu")
		(net "M_B_DQS_DN<15>")
	)
	(segment
		(start 287.643062 -46.369224)
		(end 288.244026 -46.369224)
		(width 0.1016)
		(layer "F.Cu")
		(net "M_B_DQS_DN<15>")
	)
	(segment
		(start 302.4378 -30.713172)
		(end 302.08855 -30.363922)
		(width 0.1651)
		(layer "F.Cu")
		(net "M_B_DQS_DN<15>")
	)
	(segment
		(start 302.4124 -33.306258)
		(end 302.4124 -32.83585)
		(width 0.1651)
		(layer "F.Cu")
		(net "M_B_DQS_DN<15>")
	)
	(segment
		(start 302.4378 -31.33725)
		(end 302.4378 -30.713172)
		(width 0.1651)
		(layer "F.Cu")
		(net "M_B_DQS_DN<15>")
	)
	(segment
		(start 297.679872 -41.892728)
		(end 297.688 -41.8846)
		(width 0.1016)
		(layer "F.Cu")
		(net "M_B_DQS_DN<15>")
	)
	(segment
		(start 297.688 -41.8846)
		(end 297.688 -41.129458)
		(width 0.1651)
		(layer "F.Cu")
		(net "M_B_DQS_DN<15>")
	)
	(segment
		(start 302.165766 -7.99973)
		(end 302.417734 -7.747762)
		(width 0.1651)
		(layer "F.Cu")
		(net "M_B_DQS_DN<15>")
	)
	(segment
		(start 301.49292 -30.363922)
		(end 301.36592 -30.236922)
		(width 0.1651)
		(layer "F.Cu")
		(net "M_B_DQS_DN<15>")
	)
	(segment
		(start 302.4124 -35.311842)
		(end 301.820326 -34.719768)
		(width 0.1651)
		(layer "F.Cu")
		(net "M_B_DQS_DN<15>")
	)
	(segment
		(start 298.656756 -40.340534)
		(end 298.836334 -40.160956)
		(width 0.1651)
		(layer "F.Cu")
		(net "M_B_DQS_DN<15>")
	)
	(segment
		(start 301.820326 -34.719768)
		(end 301.820326 -33.898332)
		(width 0.1651)
		(layer "F.Cu")
		(net "M_B_DQS_DN<15>")
	)
	(segment
		(start 298.226988 -40.59047)
		(end 298.476924 -40.340534)
		(width 0.1651)
		(layer "F.Cu")
		(net "M_B_DQS_DN<15>")
	)
	(via
		(at 302.4124 -35.814)
		(size 0.508)
		(drill 0.254)
		(layers "F.Cu" "B.Cu")
		(net "M_B_DQS_DN<15>")
	)
	(via
		(at 301.742602 -28.070556)
		(size 0.508)
		(drill 0.254)
		(layers "F.Cu" "B.Cu")
		(net "M_B_DQS_DN<15>")
	)
	(via
		(at 301.742602 -13.2334)
		(size 0.508)
		(drill 0.254)
		(layers "F.Cu" "B.Cu")
		(net "M_B_DQS_DN<15>")
	)
	(via
		(at 301.749206 -7.8105)
		(size 0.508)
		(drill 0.254)
		(layers "F.Cu" "B.Cu")
		(net "M_B_DQS_DN<15>")
	)
	(arc
		(start 283.775912 -51.71821)
		(mid 283.653554 -51.477229)
		(end 283.7053 -51.211988)
		(width 0.0889)
		(layer "F.Cu")
		(net "M_B_DQS_DN<15>")
	)
	(arc
		(start 284.008068 -51.841654)
		(mid 283.892203 -51.804371)
		(end 283.79293 -51.733958)
		(width 0.0889)
		(layer "F.Cu")
		(net "M_B_DQS_DN<15>")
	)
	(segment
		(start 301.937166 -13.038836)
		(end 302.164242 -13.038836)
		(width 0.1651)
		(layer "B.Cu")
		(net "M_B_DQS_DN<15>")
	)
	(segment
		(start 302.650144 -14.566392)
		(end 302.650144 -15.222728)
		(width 0.1651)
		(layer "B.Cu")
		(net "M_B_DQS_DN<15>")
	)
	(segment
		(start 302.650144 -15.222728)
		(end 302.650398 -15.222982)
		(width 0.1651)
		(layer "B.Cu")
		(net "M_B_DQS_DN<15>")
	)
	(segment
		(start 302.206406 -14.122654)
		(end 302.650144 -14.566392)
		(width 0.1651)
		(layer "B.Cu")
		(net "M_B_DQS_DN<15>")
	)
	(segment
		(start 302.384206 -13.2588)
		(end 302.384206 -13.589)
		(width 0.1651)
		(layer "B.Cu")
		(net "M_B_DQS_DN<15>")
	)
	(segment
		(start 301.742602 -13.2334)
		(end 301.937166 -13.038836)
		(width 0.1651)
		(layer "B.Cu")
		(net "M_B_DQS_DN<15>")
	)
	(segment
		(start 302.164242 -13.038836)
		(end 302.384206 -13.2588)
		(width 0.1651)
		(layer "B.Cu")
		(net "M_B_DQS_DN<15>")
	)
	(segment
		(start 302.206406 -13.7668)
		(end 302.206406 -14.122654)
		(width 0.1651)
		(layer "B.Cu")
		(net "M_B_DQS_DN<15>")
	)
	(segment
		(start 302.384206 -13.589)
		(end 302.206406 -13.7668)
		(width 0.1651)
		(layer "B.Cu")
		(net "M_B_DQS_DN<15>")
	)
	(segment
		(start 302.00092 -14.422374)
		(end 302.181006 -14.242288)
		(width 0.14224)
		(layer "In4.Cu")
		(net "M_B_DQS_DN<15>")
	)
	(segment
		(start 301.742602 -13.2334)
		(end 302.531526 -12.444476)
		(width 0.14224)
		(layer "In4.Cu")
		(net "M_B_DQS_DN<15>")
	)
	(segment
		(start 302.50892 -27.304238)
		(end 302.50892 -15.683738)
		(width 0.14224)
		(layer "In4.Cu")
		(net "M_B_DQS_DN<15>")
	)
	(segment
		(start 301.742602 -28.070556)
		(end 302.50892 -27.304238)
		(width 0.14224)
		(layer "In4.Cu")
		(net "M_B_DQS_DN<15>")
	)
	(segment
		(start 301.944786 -8.00608)
		(end 301.749206 -7.8105)
		(width 0.14224)
		(layer "In4.Cu")
		(net "M_B_DQS_DN<15>")
	)
	(segment
		(start 302.50892 -15.683738)
		(end 302.00092 -15.175738)
		(width 0.14224)
		(layer "In4.Cu")
		(net "M_B_DQS_DN<15>")
	)
	(segment
		(start 302.531526 -12.444476)
		(end 302.531526 -8.344154)
		(width 0.14224)
		(layer "In4.Cu")
		(net "M_B_DQS_DN<15>")
	)
	(segment
		(start 302.00092 -15.175738)
		(end 302.00092 -14.422374)
		(width 0.14224)
		(layer "In4.Cu")
		(net "M_B_DQS_DN<15>")
	)
	(segment
		(start 302.181006 -14.242288)
		(end 302.181006 -13.671804)
		(width 0.14224)
		(layer "In4.Cu")
		(net "M_B_DQS_DN<15>")
	)
	(segment
		(start 302.531526 -8.344154)
		(end 302.193452 -8.00608)
		(width 0.14224)
		(layer "In4.Cu")
		(net "M_B_DQS_DN<15>")
	)
	(segment
		(start 302.193452 -8.00608)
		(end 301.944786 -8.00608)
		(width 0.14224)
		(layer "In4.Cu")
		(net "M_B_DQS_DN<15>")
	)
	(segment
		(start 302.181006 -13.671804)
		(end 301.742602 -13.2334)
		(width 0.14224)
		(layer "In4.Cu")
		(net "M_B_DQS_DN<15>")
	)
	(segment
		(start 292.233858 -29.355542)
		(end 292.3794 -29.21)
		(width 0.1651)
		(layer "F.Cu")
		(net "M_B_DQS_DN<14>")
	)
	(segment
		(start 284.329124 -39.326312)
		(end 284.149292 -39.50589)
		(width 0.1651)
		(layer "F.Cu")
		(net "M_B_DQS_DN<14>")
	)
	(segment
		(start 278.7015 -50.979578)
		(end 278.536654 -51.144424)
		(width 0.0889)
		(layer "F.Cu")
		(net "M_B_DQS_DN<14>")
	)
	(segment
		(start 292.3794 -29.21)
		(end 292.7096 -29.21)
		(width 0.1651)
		(layer "F.Cu")
		(net "M_B_DQS_DN<14>")
	)
	(segment
		(start 290.9189 -32.448246)
		(end 291.312346 -32.0548)
		(width 0.1651)
		(layer "F.Cu")
		(net "M_B_DQS_DN<14>")
	)
	(segment
		(start 292.271958 -32.0548)
		(end 292.5699 -31.756858)
		(width 0.1651)
		(layer "F.Cu")
		(net "M_B_DQS_DN<14>")
	)
	(segment
		(start 292.5699 -31.756858)
		(end 292.5699 -30.053788)
		(width 0.1651)
		(layer "F.Cu")
		(net "M_B_DQS_DN<14>")
	)
	(segment
		(start 292.815518 -7.99973)
		(end 292.607238 -7.99973)
		(width 0.1651)
		(layer "F.Cu")
		(net "M_B_DQS_DN<14>")
	)
	(segment
		(start 293.067486 -7.501128)
		(end 293.067486 -7.747762)
		(width 0.1651)
		(layer "F.Cu")
		(net "M_B_DQS_DN<14>")
	)
	(segment
		(start 288.128202 -36.338256)
		(end 287.217358 -37.2491)
		(width 0.1651)
		(layer "F.Cu")
		(net "M_B_DQS_DN<14>")
	)
	(segment
		(start 287.217358 -37.2491)
		(end 286.226504 -37.2491)
		(width 0.1651)
		(layer "F.Cu")
		(net "M_B_DQS_DN<14>")
	)
	(segment
		(start 283.301948 -43.02252)
		(end 278.804624 -47.519844)
		(width 0.1016)
		(layer "F.Cu")
		(net "M_B_DQS_DN<14>")
	)
	(segment
		(start 283.251148 -40.224456)
		(end 283.251148 -41.0464)
		(width 0.1651)
		(layer "F.Cu")
		(net "M_B_DQS_DN<14>")
	)
	(segment
		(start 289.564572 -33.86201)
		(end 289.846512 -34.14395)
		(width 0.1651)
		(layer "F.Cu")
		(net "M_B_DQS_DN<14>")
	)
	(segment
		(start 291.064442 -33.402016)
		(end 291.064442 -32.92602)
		(width 0.1651)
		(layer "F.Cu")
		(net "M_B_DQS_DN<14>")
	)
	(segment
		(start 289.846512 -34.14395)
		(end 290.322508 -34.14395)
		(width 0.1651)
		(layer "F.Cu")
		(net "M_B_DQS_DN<14>")
	)
	(segment
		(start 292.7096 -29.21)
		(end 292.848538 -29.071062)
		(width 0.1651)
		(layer "F.Cu")
		(net "M_B_DQS_DN<14>")
	)
	(segment
		(start 289.385248 -33.86201)
		(end 289.564572 -33.86201)
		(width 0.1651)
		(layer "F.Cu")
		(net "M_B_DQS_DN<14>")
	)
	(segment
		(start 278.7015 -49.720246)
		(end 278.7015 -50.979578)
		(width 0.0889)
		(layer "F.Cu")
		(net "M_B_DQS_DN<14>")
	)
	(segment
		(start 283.430726 -40.044878)
		(end 283.251148 -40.224456)
		(width 0.1651)
		(layer "F.Cu")
		(net "M_B_DQS_DN<14>")
	)
	(segment
		(start 283.251148 -41.214548)
		(end 283.301948 -41.265348)
		(width 0.1016)
		(layer "F.Cu")
		(net "M_B_DQS_DN<14>")
	)
	(segment
		(start 283.301948 -41.265348)
		(end 283.301948 -43.02252)
		(width 0.1016)
		(layer "F.Cu")
		(net "M_B_DQS_DN<14>")
	)
	(segment
		(start 278.920194 -51.778408)
		(end 278.920194 -51.446938)
		(width 0.0889)
		(layer "F.Cu")
		(net "M_B_DQS_DN<14>")
	)
	(segment
		(start 285.35249 -38.302692)
		(end 285.172912 -38.302692)
		(width 0.1651)
		(layer "F.Cu")
		(net "M_B_DQS_DN<14>")
	)
	(segment
		(start 284.329124 -39.14648)
		(end 284.329124 -39.326312)
		(width 0.1651)
		(layer "F.Cu")
		(net "M_B_DQS_DN<14>")
	)
	(segment
		(start 290.322508 -34.14395)
		(end 291.064442 -33.402016)
		(width 0.1651)
		(layer "F.Cu")
		(net "M_B_DQS_DN<14>")
	)
	(segment
		(start 292.418008 -7.8105)
		(end 292.398958 -7.8105)
		(width 0.1651)
		(layer "F.Cu")
		(net "M_B_DQS_DN<14>")
	)
	(segment
		(start 293.299642 -6.475984)
		(end 292.881558 -6.894068)
		(width 0.1651)
		(layer "F.Cu")
		(net "M_B_DQS_DN<14>")
	)
	(segment
		(start 292.607238 -7.99973)
		(end 292.418008 -7.8105)
		(width 0.1651)
		(layer "F.Cu")
		(net "M_B_DQS_DN<14>")
	)
	(segment
		(start 286.226504 -37.2491)
		(end 285.532322 -37.943282)
		(width 0.1651)
		(layer "F.Cu")
		(net "M_B_DQS_DN<14>")
	)
	(segment
		(start 283.790136 -39.685468)
		(end 283.790136 -39.8653)
		(width 0.1651)
		(layer "F.Cu")
		(net "M_B_DQS_DN<14>")
	)
	(segment
		(start 285.532322 -37.943282)
		(end 285.532322 -38.123114)
		(width 0.1651)
		(layer "F.Cu")
		(net "M_B_DQS_DN<14>")
	)
	(segment
		(start 278.536654 -51.144424)
		(end 278.536654 -51.465988)
		(width 0.0889)
		(layer "F.Cu")
		(net "M_B_DQS_DN<14>")
	)
	(segment
		(start 289.370008 -34.620454)
		(end 289.088068 -34.338514)
		(width 0.1651)
		(layer "F.Cu")
		(net "M_B_DQS_DN<14>")
	)
	(segment
		(start 289.370008 -35.09645)
		(end 289.370008 -34.620454)
		(width 0.1651)
		(layer "F.Cu")
		(net "M_B_DQS_DN<14>")
	)
	(segment
		(start 289.088068 -34.15919)
		(end 289.385248 -33.86201)
		(width 0.1651)
		(layer "F.Cu")
		(net "M_B_DQS_DN<14>")
	)
	(segment
		(start 278.856948 -51.841654)
		(end 278.920194 -51.778408)
		(width 0.0889)
		(layer "F.Cu")
		(net "M_B_DQS_DN<14>")
	)
	(segment
		(start 290.9189 -32.780478)
		(end 290.9189 -32.448246)
		(width 0.1651)
		(layer "F.Cu")
		(net "M_B_DQS_DN<14>")
	)
	(segment
		(start 284.149292 -39.50589)
		(end 283.969714 -39.50589)
		(width 0.1651)
		(layer "F.Cu")
		(net "M_B_DQS_DN<14>")
	)
	(segment
		(start 293.300404 -5.822442)
		(end 293.299642 -5.822442)
		(width 0.1651)
		(layer "F.Cu")
		(net "M_B_DQS_DN<14>")
	)
	(segment
		(start 283.610304 -40.044878)
		(end 283.430726 -40.044878)
		(width 0.1651)
		(layer "F.Cu")
		(net "M_B_DQS_DN<14>")
	)
	(segment
		(start 278.804624 -49.617122)
		(end 278.7015 -49.720246)
		(width 0.0889)
		(layer "F.Cu")
		(net "M_B_DQS_DN<14>")
	)
	(segment
		(start 283.251148 -41.0464)
		(end 283.251148 -41.214548)
		(width 0.1016)
		(layer "F.Cu")
		(net "M_B_DQS_DN<14>")
	)
	(segment
		(start 292.5699 -30.053788)
		(end 292.233858 -29.717746)
		(width 0.1651)
		(layer "F.Cu")
		(net "M_B_DQS_DN<14>")
	)
	(segment
		(start 284.993334 -38.48227)
		(end 284.993334 -38.662102)
		(width 0.1651)
		(layer "F.Cu")
		(net "M_B_DQS_DN<14>")
	)
	(segment
		(start 292.611556 -28.070556)
		(end 292.392608 -28.070556)
		(width 0.1651)
		(layer "F.Cu")
		(net "M_B_DQS_DN<14>")
	)
	(segment
		(start 278.804624 -47.519844)
		(end 278.804624 -49.617122)
		(width 0.1016)
		(layer "F.Cu")
		(net "M_B_DQS_DN<14>")
	)
	(segment
		(start 293.299642 -5.822442)
		(end 293.299642 -6.475984)
		(width 0.1651)
		(layer "F.Cu")
		(net "M_B_DQS_DN<14>")
	)
	(segment
		(start 284.993334 -38.662102)
		(end 284.813502 -38.841934)
		(width 0.1651)
		(layer "F.Cu")
		(net "M_B_DQS_DN<14>")
	)
	(segment
		(start 293.067486 -7.747762)
		(end 292.815518 -7.99973)
		(width 0.1651)
		(layer "F.Cu")
		(net "M_B_DQS_DN<14>")
	)
	(segment
		(start 283.790136 -39.8653)
		(end 283.610304 -40.044878)
		(width 0.1651)
		(layer "F.Cu")
		(net "M_B_DQS_DN<14>")
	)
	(segment
		(start 285.172912 -38.302692)
		(end 284.993334 -38.48227)
		(width 0.1651)
		(layer "F.Cu")
		(net "M_B_DQS_DN<14>")
	)
	(segment
		(start 292.848538 -28.307538)
		(end 292.611556 -28.070556)
		(width 0.1651)
		(layer "F.Cu")
		(net "M_B_DQS_DN<14>")
	)
	(segment
		(start 292.848538 -29.071062)
		(end 292.848538 -28.307538)
		(width 0.1651)
		(layer "F.Cu")
		(net "M_B_DQS_DN<14>")
	)
	(segment
		(start 285.532322 -38.123114)
		(end 285.35249 -38.302692)
		(width 0.1651)
		(layer "F.Cu")
		(net "M_B_DQS_DN<14>")
	)
	(segment
		(start 284.63367 -38.841934)
		(end 284.329124 -39.14648)
		(width 0.1651)
		(layer "F.Cu")
		(net "M_B_DQS_DN<14>")
	)
	(segment
		(start 292.233858 -29.717746)
		(end 292.233858 -29.355542)
		(width 0.1651)
		(layer "F.Cu")
		(net "M_B_DQS_DN<14>")
	)
	(segment
		(start 292.881558 -7.3152)
		(end 293.067486 -7.501128)
		(width 0.1651)
		(layer "F.Cu")
		(net "M_B_DQS_DN<14>")
	)
	(segment
		(start 291.312346 -32.0548)
		(end 292.271958 -32.0548)
		(width 0.1651)
		(layer "F.Cu")
		(net "M_B_DQS_DN<14>")
	)
	(segment
		(start 283.969714 -39.50589)
		(end 283.790136 -39.685468)
		(width 0.1651)
		(layer "F.Cu")
		(net "M_B_DQS_DN<14>")
	)
	(segment
		(start 291.064442 -32.92602)
		(end 290.9189 -32.780478)
		(width 0.1651)
		(layer "F.Cu")
		(net "M_B_DQS_DN<14>")
	)
	(segment
		(start 288.128202 -36.338256)
		(end 289.370008 -35.09645)
		(width 0.1651)
		(layer "F.Cu")
		(net "M_B_DQS_DN<14>")
	)
	(segment
		(start 284.813502 -38.841934)
		(end 284.63367 -38.841934)
		(width 0.1651)
		(layer "F.Cu")
		(net "M_B_DQS_DN<14>")
	)
	(segment
		(start 292.881558 -6.894068)
		(end 292.881558 -7.3152)
		(width 0.1651)
		(layer "F.Cu")
		(net "M_B_DQS_DN<14>")
	)
	(segment
		(start 289.088068 -34.338514)
		(end 289.088068 -34.15919)
		(width 0.1651)
		(layer "F.Cu")
		(net "M_B_DQS_DN<14>")
	)
	(via
		(at 292.392354 -13.2334)
		(size 0.508)
		(drill 0.254)
		(layers "F.Cu" "B.Cu")
		(net "M_B_DQS_DN<14>")
	)
	(via
		(at 292.398958 -7.8105)
		(size 0.508)
		(drill 0.254)
		(layers "F.Cu" "B.Cu")
		(net "M_B_DQS_DN<14>")
	)
	(via
		(at 292.392608 -28.070556)
		(size 0.508)
		(drill 0.254)
		(layers "F.Cu" "B.Cu")
		(net "M_B_DQS_DN<14>")
	)
	(via
		(at 288.128202 -36.338256)
		(size 0.508)
		(drill 0.254)
		(layers "F.Cu" "B.Cu")
		(net "M_B_DQS_DN<14>")
	)
	(arc
		(start 278.536654 -51.465988)
		(mid 278.627594 -51.712835)
		(end 278.856948 -51.841654)
		(width 0.0889)
		(layer "F.Cu")
		(net "M_B_DQS_DN<14>")
	)
	(segment
		(start 293.033958 -13.2588)
		(end 292.813994 -13.038836)
		(width 0.1651)
		(layer "B.Cu")
		(net "M_B_DQS_DN<14>")
	)
	(segment
		(start 293.033958 -13.589)
		(end 293.033958 -13.2588)
		(width 0.1651)
		(layer "B.Cu")
		(net "M_B_DQS_DN<14>")
	)
	(segment
		(start 292.856158 -13.7668)
		(end 293.033958 -13.589)
		(width 0.1651)
		(layer "B.Cu")
		(net "M_B_DQS_DN<14>")
	)
	(segment
		(start 293.300404 -15.222982)
		(end 293.299896 -15.222982)
		(width 0.1651)
		(layer "B.Cu")
		(net "M_B_DQS_DN<14>")
	)
	(segment
		(start 292.856158 -14.122654)
		(end 292.856158 -13.7668)
		(width 0.1651)
		(layer "B.Cu")
		(net "M_B_DQS_DN<14>")
	)
	(segment
		(start 293.299896 -15.222982)
		(end 293.299896 -14.566392)
		(width 0.1651)
		(layer "B.Cu")
		(net "M_B_DQS_DN<14>")
	)
	(segment
		(start 292.813994 -13.038836)
		(end 292.586918 -13.038836)
		(width 0.1651)
		(layer "B.Cu")
		(net "M_B_DQS_DN<14>")
	)
	(segment
		(start 292.586918 -13.038836)
		(end 292.392354 -13.2334)
		(width 0.1651)
		(layer "B.Cu")
		(net "M_B_DQS_DN<14>")
	)
	(segment
		(start 293.299896 -14.566392)
		(end 292.856158 -14.122654)
		(width 0.1651)
		(layer "B.Cu")
		(net "M_B_DQS_DN<14>")
	)
	(segment
		(start 293.158926 -15.790926)
		(end 293.158926 -19.058128)
		(width 0.14224)
		(layer "In11.Cu")
		(net "M_B_DQS_DN<14>")
	)
	(segment
		(start 293.181532 -8.343392)
		(end 293.181532 -12.444222)
		(width 0.14224)
		(layer "In11.Cu")
		(net "M_B_DQS_DN<14>")
	)
	(segment
		(start 293.158926 -19.058128)
		(end 292.9128 -19.304254)
		(width 0.14224)
		(layer "In11.Cu")
		(net "M_B_DQS_DN<14>")
	)
	(segment
		(start 292.831012 -14.242288)
		(end 292.650926 -14.422374)
		(width 0.14224)
		(layer "In11.Cu")
		(net "M_B_DQS_DN<14>")
	)
	(segment
		(start 292.650926 -15.282926)
		(end 293.158926 -15.790926)
		(width 0.14224)
		(layer "In11.Cu")
		(net "M_B_DQS_DN<14>")
	)
	(segment
		(start 292.398958 -7.8105)
		(end 292.594538 -8.00608)
		(width 0.14224)
		(layer "In11.Cu")
		(net "M_B_DQS_DN<14>")
	)
	(segment
		(start 292.831012 -13.672058)
		(end 292.831012 -14.242288)
		(width 0.14224)
		(layer "In11.Cu")
		(net "M_B_DQS_DN<14>")
	)
	(segment
		(start 292.9128 -21.0058)
		(end 293.158926 -21.251926)
		(width 0.14224)
		(layer "In11.Cu")
		(net "M_B_DQS_DN<14>")
	)
	(segment
		(start 293.158926 -21.251926)
		(end 293.158926 -27.304238)
		(width 0.14224)
		(layer "In11.Cu")
		(net "M_B_DQS_DN<14>")
	)
	(segment
		(start 292.594538 -8.00608)
		(end 292.84422 -8.00608)
		(width 0.14224)
		(layer "In11.Cu")
		(net "M_B_DQS_DN<14>")
	)
	(segment
		(start 292.84422 -8.00608)
		(end 293.181532 -8.343392)
		(width 0.14224)
		(layer "In11.Cu")
		(net "M_B_DQS_DN<14>")
	)
	(segment
		(start 292.392354 -13.2334)
		(end 292.831012 -13.672058)
		(width 0.14224)
		(layer "In11.Cu")
		(net "M_B_DQS_DN<14>")
	)
	(segment
		(start 292.9128 -19.304254)
		(end 292.9128 -21.0058)
		(width 0.14224)
		(layer "In11.Cu")
		(net "M_B_DQS_DN<14>")
	)
	(segment
		(start 293.181532 -12.444222)
		(end 292.392354 -13.2334)
		(width 0.14224)
		(layer "In11.Cu")
		(net "M_B_DQS_DN<14>")
	)
	(segment
		(start 292.650926 -14.422374)
		(end 292.650926 -15.282926)
		(width 0.14224)
		(layer "In11.Cu")
		(net "M_B_DQS_DN<14>")
	)
	(segment
		(start 293.158926 -27.304238)
		(end 292.392608 -28.070556)
		(width 0.14224)
		(layer "In11.Cu")
		(net "M_B_DQS_DN<14>")
	)
	(segment
		(start 283.531564 -6.894068)
		(end 283.531564 -7.3152)
		(width 0.1651)
		(layer "F.Cu")
		(net "M_B_DQS_DN<13>")
	)
	(segment
		(start 283.465524 -7.99973)
		(end 283.238194 -7.99973)
		(width 0.1651)
		(layer "F.Cu")
		(net "M_B_DQS_DN<13>")
	)
	(segment
		(start 283.949902 -5.822442)
		(end 283.949902 -6.47573)
		(width 0.1651)
		(layer "F.Cu")
		(net "M_B_DQS_DN<13>")
	)
	(segment
		(start 283.531564 -7.3152)
		(end 283.717492 -7.501128)
		(width 0.1651)
		(layer "F.Cu")
		(net "M_B_DQS_DN<13>")
	)
	(segment
		(start 283.95041 -5.822442)
		(end 283.949902 -5.822442)
		(width 0.1651)
		(layer "F.Cu")
		(net "M_B_DQS_DN<13>")
	)
	(segment
		(start 283.238194 -7.99973)
		(end 283.048964 -7.8105)
		(width 0.1651)
		(layer "F.Cu")
		(net "M_B_DQS_DN<13>")
	)
	(segment
		(start 283.717492 -7.501128)
		(end 283.717492 -7.747762)
		(width 0.1651)
		(layer "F.Cu")
		(net "M_B_DQS_DN<13>")
	)
	(segment
		(start 272.052288 -55.409338)
		(end 271.480788 -55.409338)
		(width 0.1016)
		(layer "F.Cu")
		(net "M_B_DQS_DN<13>")
	)
	(segment
		(start 283.949902 -6.47573)
		(end 283.531564 -6.894068)
		(width 0.1651)
		(layer "F.Cu")
		(net "M_B_DQS_DN<13>")
	)
	(segment
		(start 283.717492 -7.747762)
		(end 283.465524 -7.99973)
		(width 0.1651)
		(layer "F.Cu")
		(net "M_B_DQS_DN<13>")
	)
	(via
		(at 283.048964 -7.8105)
		(size 0.508)
		(drill 0.254)
		(layers "F.Cu" "B.Cu")
		(net "M_B_DQS_DN<13>")
	)
	(via
		(at 271.480788 -55.409338)
		(size 0.508)
		(drill 0.254)
		(layers "F.Cu" "B.Cu")
		(net "M_B_DQS_DN<13>")
	)
	(via
		(at 283.04236 -13.2334)
		(size 0.508)
		(drill 0.254)
		(layers "F.Cu" "B.Cu")
		(net "M_B_DQS_DN<13>")
	)
	(segment
		(start 283.949902 -15.222982)
		(end 283.949902 -14.566392)
		(width 0.1651)
		(layer "B.Cu")
		(net "M_B_DQS_DN<13>")
	)
	(segment
		(start 283.949902 -14.566392)
		(end 283.506164 -14.122654)
		(width 0.1651)
		(layer "B.Cu")
		(net "M_B_DQS_DN<13>")
	)
	(segment
		(start 283.683964 -13.2588)
		(end 283.464 -13.038836)
		(width 0.1651)
		(layer "B.Cu")
		(net "M_B_DQS_DN<13>")
	)
	(segment
		(start 283.236924 -13.038836)
		(end 283.04236 -13.2334)
		(width 0.1651)
		(layer "B.Cu")
		(net "M_B_DQS_DN<13>")
	)
	(segment
		(start 283.464 -13.038836)
		(end 283.236924 -13.038836)
		(width 0.1651)
		(layer "B.Cu")
		(net "M_B_DQS_DN<13>")
	)
	(segment
		(start 283.506164 -13.7668)
		(end 283.683964 -13.589)
		(width 0.1651)
		(layer "B.Cu")
		(net "M_B_DQS_DN<13>")
	)
	(segment
		(start 283.95041 -15.222982)
		(end 283.949902 -15.222982)
		(width 0.1651)
		(layer "B.Cu")
		(net "M_B_DQS_DN<13>")
	)
	(segment
		(start 283.506164 -14.122654)
		(end 283.506164 -13.7668)
		(width 0.1651)
		(layer "B.Cu")
		(net "M_B_DQS_DN<13>")
	)
	(segment
		(start 283.683964 -13.589)
		(end 283.683964 -13.2588)
		(width 0.1651)
		(layer "B.Cu")
		(net "M_B_DQS_DN<13>")
	)
	(segment
		(start 283.824934 -20.46732)
		(end 283.824934 -20.27428)
		(width 0.14224)
		(layer "In4.Cu")
		(net "M_B_DQS_DN<13>")
	)
	(segment
		(start 283.982414 -19.3548)
		(end 283.982414 -19.1008)
		(width 0.14224)
		(layer "In4.Cu")
		(net "M_B_DQS_DN<13>")
	)
	(segment
		(start 282.077922 -26.92019)
		(end 282.390596 -26.92019)
		(width 0.14224)
		(layer "In4.Cu")
		(net "M_B_DQS_DN<13>")
	)
	(segment
		(start 283.04236 -13.2334)
		(end 283.831284 -12.444476)
		(width 0.14224)
		(layer "In4.Cu")
		(net "M_B_DQS_DN<13>")
	)
	(segment
		(start 273.910806 -44.947586)
		(end 274.037806 -44.820586)
		(width 0.14224)
		(layer "In4.Cu")
		(net "M_B_DQS_DN<13>")
	)
	(segment
		(start 283.480764 -14.1986)
		(end 283.480764 -13.671804)
		(width 0.14224)
		(layer "In4.Cu")
		(net "M_B_DQS_DN<13>")
	)
	(segment
		(start 273.871436 -46.591474)
		(end 273.871436 -45.537882)
		(width 0.0889)
		(layer "In4.Cu")
		(net "M_B_DQS_DN<13>")
	)
	(segment
		(start 283.534104 -25.246584)
		(end 283.824934 -24.955754)
		(width 0.14224)
		(layer "In4.Cu")
		(net "M_B_DQS_DN<13>")
	)
	(segment
		(start 281.629104 -27.681936)
		(end 281.629104 -27.369008)
		(width 0.14224)
		(layer "In4.Cu")
		(net "M_B_DQS_DN<13>")
	)
	(segment
		(start 283.534104 -25.776174)
		(end 283.534104 -25.246584)
		(width 0.14224)
		(layer "In4.Cu")
		(net "M_B_DQS_DN<13>")
	)
	(segment
		(start 271.948656 -51.905154)
		(end 272.701004 -51.152806)
		(width 0.0889)
		(layer "In4.Cu")
		(net "M_B_DQS_DN<13>")
	)
	(segment
		(start 280.682954 -29.023564)
		(end 281.440382 -29.023564)
		(width 0.14224)
		(layer "In4.Cu")
		(net "M_B_DQS_DN<13>")
	)
	(segment
		(start 271.992598 -54.714394)
		(end 272.071338 -54.577996)
		(width 0.0889)
		(layer "In4.Cu")
		(net "M_B_DQS_DN<13>")
	)
	(segment
		(start 281.629104 -27.369008)
		(end 282.077922 -26.92019)
		(width 0.14224)
		(layer "In4.Cu")
		(net "M_B_DQS_DN<13>")
	)
	(segment
		(start 283.982414 -20.1168)
		(end 283.982414 -19.8628)
		(width 0.14224)
		(layer "In4.Cu")
		(net "M_B_DQS_DN<13>")
	)
	(segment
		(start 280.10612 -29.600398)
		(end 280.682954 -29.023564)
		(width 0.14224)
		(layer "In4.Cu")
		(net "M_B_DQS_DN<13>")
	)
	(segment
		(start 283.480764 -13.671804)
		(end 283.04236 -13.2334)
		(width 0.14224)
		(layer "In4.Cu")
		(net "M_B_DQS_DN<13>")
	)
	(segment
		(start 272.701004 -49.088548)
		(end 272.98396 -48.805592)
		(width 0.0889)
		(layer "In4.Cu")
		(net "M_B_DQS_DN<13>")
	)
	(segment
		(start 279.801574 -30.771846)
		(end 279.801574 -30.771084)
		(width 0.14224)
		(layer "In4.Cu")
		(net "M_B_DQS_DN<13>")
	)
	(segment
		(start 282.753816 -27.28341)
		(end 283.29001 -27.28341)
		(width 0.14224)
		(layer "In4.Cu")
		(net "M_B_DQS_DN<13>")
	)
	(segment
		(start 283.982414 -19.8628)
		(end 283.824934 -19.70532)
		(width 0.14224)
		(layer "In4.Cu")
		(net "M_B_DQS_DN<13>")
	)
	(segment
		(start 281.938476 -28.52547)
		(end 281.938476 -27.991308)
		(width 0.14224)
		(layer "In4.Cu")
		(net "M_B_DQS_DN<13>")
	)
	(segment
		(start 283.244544 -8.00608)
		(end 283.048964 -7.8105)
		(width 0.14224)
		(layer "In4.Cu")
		(net "M_B_DQS_DN<13>")
	)
	(segment
		(start 272.071338 -53.116734)
		(end 271.948656 -52.994052)
		(width 0.0889)
		(layer "In4.Cu")
		(net "M_B_DQS_DN<13>")
	)
	(segment
		(start 283.824934 -19.70532)
		(end 283.824934 -19.51228)
		(width 0.14224)
		(layer "In4.Cu")
		(net "M_B_DQS_DN<13>")
	)
	(segment
		(start 273.871436 -45.537882)
		(end 273.910806 -45.498512)
		(width 0.0889)
		(layer "In4.Cu")
		(net "M_B_DQS_DN<13>")
	)
	(segment
		(start 273.910806 -44.439586)
		(end 273.910806 -37.511482)
		(width 0.14224)
		(layer "In4.Cu")
		(net "M_B_DQS_DN<13>")
	)
	(segment
		(start 271.480788 -55.409338)
		(end 271.480788 -55.747412)
		(width 0.0889)
		(layer "In4.Cu")
		(net "M_B_DQS_DN<13>")
	)
	(segment
		(start 280.10612 -30.466538)
		(end 280.10612 -29.600398)
		(width 0.14224)
		(layer "In4.Cu")
		(net "M_B_DQS_DN<13>")
	)
	(segment
		(start 282.840684 -14.58468)
		(end 283.023564 -14.4018)
		(width 0.14224)
		(layer "In4.Cu")
		(net "M_B_DQS_DN<13>")
	)
	(segment
		(start 282.840684 -15.141956)
		(end 282.840684 -14.58468)
		(width 0.14224)
		(layer "In4.Cu")
		(net "M_B_DQS_DN<13>")
	)
	(segment
		(start 283.982414 -19.1008)
		(end 283.82468 -18.943066)
		(width 0.14224)
		(layer "In4.Cu")
		(net "M_B_DQS_DN<13>")
	)
	(segment
		(start 272.98396 -47.47895)
		(end 273.871436 -46.591474)
		(width 0.0889)
		(layer "In4.Cu")
		(net "M_B_DQS_DN<13>")
	)
	(segment
		(start 272.701004 -51.152806)
		(end 272.701004 -49.088548)
		(width 0.0889)
		(layer "In4.Cu")
		(net "M_B_DQS_DN<13>")
	)
	(segment
		(start 272.98396 -48.805592)
		(end 272.98396 -47.47895)
		(width 0.0889)
		(layer "In4.Cu")
		(net "M_B_DQS_DN<13>")
	)
	(segment
		(start 283.831284 -12.444476)
		(end 283.831284 -8.343392)
		(width 0.14224)
		(layer "In4.Cu")
		(net "M_B_DQS_DN<13>")
	)
	(segment
		(start 271.465802 -55.009288)
		(end 271.502124 -55.009288)
		(width 0.0889)
		(layer "In4.Cu")
		(net "M_B_DQS_DN<13>")
	)
	(segment
		(start 274.037806 -44.566586)
		(end 273.910806 -44.439586)
		(width 0.14224)
		(layer "In4.Cu")
		(net "M_B_DQS_DN<13>")
	)
	(segment
		(start 271.480788 -55.747412)
		(end 271.422876 -55.805324)
		(width 0.0889)
		(layer "In4.Cu")
		(net "M_B_DQS_DN<13>")
	)
	(segment
		(start 283.277564 -14.4018)
		(end 283.480764 -14.1986)
		(width 0.14224)
		(layer "In4.Cu")
		(net "M_B_DQS_DN<13>")
	)
	(segment
		(start 273.910806 -45.476414)
		(end 273.910806 -44.947586)
		(width 0.14224)
		(layer "In4.Cu")
		(net "M_B_DQS_DN<13>")
	)
	(segment
		(start 283.023564 -14.4018)
		(end 283.277564 -14.4018)
		(width 0.14224)
		(layer "In4.Cu")
		(net "M_B_DQS_DN<13>")
	)
	(segment
		(start 281.938476 -27.991308)
		(end 281.629104 -27.681936)
		(width 0.14224)
		(layer "In4.Cu")
		(net "M_B_DQS_DN<13>")
	)
	(segment
		(start 279.801574 -30.771084)
		(end 280.10612 -30.466538)
		(width 0.14224)
		(layer "In4.Cu")
		(net "M_B_DQS_DN<13>")
	)
	(segment
		(start 283.493972 -8.00608)
		(end 283.244544 -8.00608)
		(width 0.14224)
		(layer "In4.Cu")
		(net "M_B_DQS_DN<13>")
	)
	(segment
		(start 274.037806 -44.820586)
		(end 274.037806 -44.566586)
		(width 0.14224)
		(layer "In4.Cu")
		(net "M_B_DQS_DN<13>")
	)
	(segment
		(start 279.49652 -31.0769)
		(end 279.801574 -30.771846)
		(width 0.14224)
		(layer "In4.Cu")
		(net "M_B_DQS_DN<13>")
	)
	(segment
		(start 283.824934 -21.03628)
		(end 283.982414 -20.8788)
		(width 0.14224)
		(layer "In4.Cu")
		(net "M_B_DQS_DN<13>")
	)
	(segment
		(start 283.29001 -27.28341)
		(end 283.897832 -26.675588)
		(width 0.14224)
		(layer "In4.Cu")
		(net "M_B_DQS_DN<13>")
	)
	(segment
		(start 273.910806 -45.498512)
		(end 273.910806 -45.476414)
		(width 0.0889)
		(layer "In4.Cu")
		(net "M_B_DQS_DN<13>")
	)
	(segment
		(start 283.824934 -24.955754)
		(end 283.824934 -21.03628)
		(width 0.14224)
		(layer "In4.Cu")
		(net "M_B_DQS_DN<13>")
	)
	(segment
		(start 272.071338 -54.577996)
		(end 272.071338 -53.116734)
		(width 0.0889)
		(layer "In4.Cu")
		(net "M_B_DQS_DN<13>")
	)
	(segment
		(start 283.831284 -8.343392)
		(end 283.493972 -8.00608)
		(width 0.14224)
		(layer "In4.Cu")
		(net "M_B_DQS_DN<13>")
	)
	(segment
		(start 283.824934 -19.51228)
		(end 283.982414 -19.3548)
		(width 0.14224)
		(layer "In4.Cu")
		(net "M_B_DQS_DN<13>")
	)
	(segment
		(start 283.897832 -26.675588)
		(end 283.897832 -26.139648)
		(width 0.14224)
		(layer "In4.Cu")
		(net "M_B_DQS_DN<13>")
	)
	(segment
		(start 283.982414 -20.6248)
		(end 283.824934 -20.46732)
		(width 0.14224)
		(layer "In4.Cu")
		(net "M_B_DQS_DN<13>")
	)
	(segment
		(start 283.897832 -26.139648)
		(end 283.534104 -25.776174)
		(width 0.14224)
		(layer "In4.Cu")
		(net "M_B_DQS_DN<13>")
	)
	(segment
		(start 273.910806 -37.511482)
		(end 279.49652 -31.925768)
		(width 0.14224)
		(layer "In4.Cu")
		(net "M_B_DQS_DN<13>")
	)
	(segment
		(start 281.440382 -29.023564)
		(end 281.938476 -28.52547)
		(width 0.14224)
		(layer "In4.Cu")
		(net "M_B_DQS_DN<13>")
	)
	(segment
		(start 283.82468 -18.943066)
		(end 283.82468 -16.125952)
		(width 0.14224)
		(layer "In4.Cu")
		(net "M_B_DQS_DN<13>")
	)
	(segment
		(start 283.82468 -16.125952)
		(end 282.840684 -15.141956)
		(width 0.14224)
		(layer "In4.Cu")
		(net "M_B_DQS_DN<13>")
	)
	(segment
		(start 271.948656 -52.994052)
		(end 271.948656 -51.905154)
		(width 0.0889)
		(layer "In4.Cu")
		(net "M_B_DQS_DN<13>")
	)
	(segment
		(start 283.824934 -20.27428)
		(end 283.982414 -20.1168)
		(width 0.14224)
		(layer "In4.Cu")
		(net "M_B_DQS_DN<13>")
	)
	(segment
		(start 279.49652 -31.925768)
		(end 279.49652 -31.0769)
		(width 0.14224)
		(layer "In4.Cu")
		(net "M_B_DQS_DN<13>")
	)
	(segment
		(start 283.982414 -20.8788)
		(end 283.982414 -20.6248)
		(width 0.14224)
		(layer "In4.Cu")
		(net "M_B_DQS_DN<13>")
	)
	(segment
		(start 282.390596 -26.92019)
		(end 282.753816 -27.28341)
		(width 0.14224)
		(layer "In4.Cu")
		(net "M_B_DQS_DN<13>")
	)
	(arc
		(start 271.422876 -55.805324)
		(mid 271.080953 -55.387783)
		(end 271.465802 -55.009288)
		(width 0.0889)
		(layer "In4.Cu")
		(net "M_B_DQS_DN<13>")
	)
	(arc
		(start 271.502124 -55.009288)
		(mid 271.785474 -54.925211)
		(end 271.992598 -54.714394)
		(width 0.0889)
		(layer "In4.Cu")
		(net "M_B_DQS_DN<13>")
	)
	(segment
		(start 227.711 -29.2354)
		(end 227.5967 -29.3497)
		(width 0.1651)
		(layer "F.Cu")
		(net "M_B_DQS_DN<12>")
	)
	(segment
		(start 233.637328 -47.54499)
		(end 237.602268 -47.54499)
		(width 0.1016)
		(layer "F.Cu")
		(net "M_B_DQS_DN<12>")
	)
	(segment
		(start 228.149658 -32.88411)
		(end 228.4857 -33.220152)
		(width 0.1651)
		(layer "F.Cu")
		(net "M_B_DQS_DN<12>")
	)
	(segment
		(start 227.838 -36.71189)
		(end 227.6729 -36.87699)
		(width 0.1651)
		(layer "F.Cu")
		(net "M_B_DQS_DN<12>")
	)
	(segment
		(start 228.699822 -6.66496)
		(end 228.281738 -7.083044)
		(width 0.1651)
		(layer "F.Cu")
		(net "M_B_DQS_DN<12>")
	)
	(segment
		(start 227.775008 -35.24123)
		(end 228.11867 -35.24123)
		(width 0.1651)
		(layer "F.Cu")
		(net "M_B_DQS_DN<12>")
	)
	(segment
		(start 232.457752 -46.365414)
		(end 233.637328 -47.54499)
		(width 0.1016)
		(layer "F.Cu")
		(net "M_B_DQS_DN<12>")
	)
	(segment
		(start 228.467666 -7.501128)
		(end 228.467666 -7.747762)
		(width 0.1651)
		(layer "F.Cu")
		(net "M_B_DQS_DN<12>")
	)
	(segment
		(start 227.5967 -31.6357)
		(end 227.5967 -31.87954)
		(width 0.1651)
		(layer "F.Cu")
		(net "M_B_DQS_DN<12>")
	)
	(segment
		(start 231.997504 -46.365414)
		(end 232.457752 -46.365414)
		(width 0.1016)
		(layer "F.Cu")
		(net "M_B_DQS_DN<12>")
	)
	(segment
		(start 227.792534 -28.070556)
		(end 228.054662 -28.070556)
		(width 0.1651)
		(layer "F.Cu")
		(net "M_B_DQS_DN<12>")
	)
	(segment
		(start 228.70033 -5.822442)
		(end 228.699822 -5.822442)
		(width 0.1651)
		(layer "F.Cu")
		(net "M_B_DQS_DN<12>")
	)
	(segment
		(start 227.6729 -37.238432)
		(end 228.4603 -38.025832)
		(width 0.1651)
		(layer "F.Cu")
		(net "M_B_DQS_DN<12>")
	)
	(segment
		(start 228.699822 -5.822442)
		(end 228.699822 -6.66496)
		(width 0.1651)
		(layer "F.Cu")
		(net "M_B_DQS_DN<12>")
	)
	(segment
		(start 243.310664 -49.33696)
		(end 243.310664 -49.265586)
		(width 0.0889)
		(layer "F.Cu")
		(net "M_B_DQS_DN<12>")
	)
	(segment
		(start 227.72878 -31.24962)
		(end 227.72878 -31.50362)
		(width 0.1651)
		(layer "F.Cu")
		(net "M_B_DQS_DN<12>")
	)
	(segment
		(start 227.5967 -30.35554)
		(end 227.72878 -30.48762)
		(width 0.1651)
		(layer "F.Cu")
		(net "M_B_DQS_DN<12>")
	)
	(segment
		(start 228.248464 -28.264358)
		(end 228.248464 -29.041598)
		(width 0.1651)
		(layer "F.Cu")
		(net "M_B_DQS_DN<12>")
	)
	(segment
		(start 243.910104 -50.47361)
		(end 243.846858 -50.536856)
		(width 0.0889)
		(layer "F.Cu")
		(net "M_B_DQS_DN<12>")
	)
	(segment
		(start 228.46792 -35.941)
		(end 228.46792 -36.36264)
		(width 0.1651)
		(layer "F.Cu")
		(net "M_B_DQS_DN<12>")
	)
	(segment
		(start 227.72878 -32.01162)
		(end 227.72878 -32.26562)
		(width 0.1651)
		(layer "F.Cu")
		(net "M_B_DQS_DN<12>")
	)
	(segment
		(start 228.4857 -34.018728)
		(end 228.149658 -34.35477)
		(width 0.1651)
		(layer "F.Cu")
		(net "M_B_DQS_DN<12>")
	)
	(segment
		(start 242.034568 -47.98949)
		(end 238.046768 -47.98949)
		(width 0.1016)
		(layer "F.Cu")
		(net "M_B_DQS_DN<12>")
	)
	(segment
		(start 231.813354 -46.181264)
		(end 231.997504 -46.365414)
		(width 0.1016)
		(layer "F.Cu")
		(net "M_B_DQS_DN<12>")
	)
	(segment
		(start 227.775008 -34.35477)
		(end 227.5967 -34.533078)
		(width 0.1651)
		(layer "F.Cu")
		(net "M_B_DQS_DN<12>")
	)
	(segment
		(start 227.72878 -32.26562)
		(end 227.5967 -32.3977)
		(width 0.1651)
		(layer "F.Cu")
		(net "M_B_DQS_DN<12>")
	)
	(segment
		(start 243.5098 -49.536096)
		(end 243.310664 -49.33696)
		(width 0.0889)
		(layer "F.Cu")
		(net "M_B_DQS_DN<12>")
	)
	(segment
		(start 227.5967 -32.3977)
		(end 227.5967 -32.705802)
		(width 0.1651)
		(layer "F.Cu")
		(net "M_B_DQS_DN<12>")
	)
	(segment
		(start 227.72878 -30.74162)
		(end 227.5967 -30.8737)
		(width 0.1651)
		(layer "F.Cu")
		(net "M_B_DQS_DN<12>")
	)
	(segment
		(start 227.5967 -31.11754)
		(end 227.72878 -31.24962)
		(width 0.1651)
		(layer "F.Cu")
		(net "M_B_DQS_DN<12>")
	)
	(segment
		(start 227.5967 -31.87954)
		(end 227.72878 -32.01162)
		(width 0.1651)
		(layer "F.Cu")
		(net "M_B_DQS_DN<12>")
	)
	(segment
		(start 228.46792 -36.36264)
		(end 228.11867 -36.71189)
		(width 0.1651)
		(layer "F.Cu")
		(net "M_B_DQS_DN<12>")
	)
	(segment
		(start 227.72878 -30.48762)
		(end 227.72878 -30.74162)
		(width 0.1651)
		(layer "F.Cu")
		(net "M_B_DQS_DN<12>")
	)
	(segment
		(start 228.4603 -38.025832)
		(end 228.4603 -42.82821)
		(width 0.1651)
		(layer "F.Cu")
		(net "M_B_DQS_DN<12>")
	)
	(segment
		(start 228.248464 -29.041598)
		(end 228.054662 -29.2354)
		(width 0.1651)
		(layer "F.Cu")
		(net "M_B_DQS_DN<12>")
	)
	(segment
		(start 227.5967 -34.533078)
		(end 227.5967 -35.062922)
		(width 0.1651)
		(layer "F.Cu")
		(net "M_B_DQS_DN<12>")
	)
	(segment
		(start 227.775008 -32.88411)
		(end 228.149658 -32.88411)
		(width 0.1651)
		(layer "F.Cu")
		(net "M_B_DQS_DN<12>")
	)
	(segment
		(start 227.988368 -7.99973)
		(end 227.799138 -7.8105)
		(width 0.1651)
		(layer "F.Cu")
		(net "M_B_DQS_DN<12>")
	)
	(segment
		(start 227.5967 -35.062922)
		(end 227.775008 -35.24123)
		(width 0.1651)
		(layer "F.Cu")
		(net "M_B_DQS_DN<12>")
	)
	(segment
		(start 228.4857 -33.220152)
		(end 228.4857 -34.018728)
		(width 0.1651)
		(layer "F.Cu")
		(net "M_B_DQS_DN<12>")
	)
	(segment
		(start 228.11867 -36.71189)
		(end 227.838 -36.71189)
		(width 0.1651)
		(layer "F.Cu")
		(net "M_B_DQS_DN<12>")
	)
	(segment
		(start 227.72878 -31.50362)
		(end 227.5967 -31.6357)
		(width 0.1651)
		(layer "F.Cu")
		(net "M_B_DQS_DN<12>")
	)
	(segment
		(start 243.5098 -50.137314)
		(end 243.5098 -49.536096)
		(width 0.0889)
		(layer "F.Cu")
		(net "M_B_DQS_DN<12>")
	)
	(segment
		(start 228.054662 -29.2354)
		(end 227.711 -29.2354)
		(width 0.1651)
		(layer "F.Cu")
		(net "M_B_DQS_DN<12>")
	)
	(segment
		(start 228.11867 -35.24123)
		(end 228.46792 -35.59048)
		(width 0.1651)
		(layer "F.Cu")
		(net "M_B_DQS_DN<12>")
	)
	(segment
		(start 227.5967 -32.705802)
		(end 227.775008 -32.88411)
		(width 0.1651)
		(layer "F.Cu")
		(net "M_B_DQS_DN<12>")
	)
	(segment
		(start 227.5967 -29.3497)
		(end 227.5967 -29.59354)
		(width 0.1651)
		(layer "F.Cu")
		(net "M_B_DQS_DN<12>")
	)
	(segment
		(start 228.281738 -7.3152)
		(end 228.467666 -7.501128)
		(width 0.1651)
		(layer "F.Cu")
		(net "M_B_DQS_DN<12>")
	)
	(segment
		(start 227.6729 -36.87699)
		(end 227.6729 -37.238432)
		(width 0.1651)
		(layer "F.Cu")
		(net "M_B_DQS_DN<12>")
	)
	(segment
		(start 243.910104 -50.141886)
		(end 243.910104 -50.47361)
		(width 0.0889)
		(layer "F.Cu")
		(net "M_B_DQS_DN<12>")
	)
	(segment
		(start 227.72878 -29.72562)
		(end 227.72878 -29.97962)
		(width 0.1651)
		(layer "F.Cu")
		(net "M_B_DQS_DN<12>")
	)
	(segment
		(start 228.467666 -7.747762)
		(end 228.215698 -7.99973)
		(width 0.1651)
		(layer "F.Cu")
		(net "M_B_DQS_DN<12>")
	)
	(segment
		(start 228.4603 -42.82821)
		(end 231.813354 -46.181264)
		(width 0.1651)
		(layer "F.Cu")
		(net "M_B_DQS_DN<12>")
	)
	(segment
		(start 238.046768 -47.98949)
		(end 237.602268 -47.54499)
		(width 0.1016)
		(layer "F.Cu")
		(net "M_B_DQS_DN<12>")
	)
	(segment
		(start 228.46792 -35.59048)
		(end 228.46792 -35.941)
		(width 0.1651)
		(layer "F.Cu")
		(net "M_B_DQS_DN<12>")
	)
	(segment
		(start 227.5967 -30.1117)
		(end 227.5967 -30.35554)
		(width 0.1651)
		(layer "F.Cu")
		(net "M_B_DQS_DN<12>")
	)
	(segment
		(start 227.72878 -29.97962)
		(end 227.5967 -30.1117)
		(width 0.1651)
		(layer "F.Cu")
		(net "M_B_DQS_DN<12>")
	)
	(segment
		(start 227.5967 -29.59354)
		(end 227.72878 -29.72562)
		(width 0.1651)
		(layer "F.Cu")
		(net "M_B_DQS_DN<12>")
	)
	(segment
		(start 227.5967 -30.8737)
		(end 227.5967 -31.11754)
		(width 0.1651)
		(layer "F.Cu")
		(net "M_B_DQS_DN<12>")
	)
	(segment
		(start 228.215698 -7.99973)
		(end 227.988368 -7.99973)
		(width 0.1651)
		(layer "F.Cu")
		(net "M_B_DQS_DN<12>")
	)
	(segment
		(start 228.149658 -34.35477)
		(end 227.775008 -34.35477)
		(width 0.1651)
		(layer "F.Cu")
		(net "M_B_DQS_DN<12>")
	)
	(segment
		(start 243.310664 -49.265586)
		(end 242.034568 -47.98949)
		(width 0.1016)
		(layer "F.Cu")
		(net "M_B_DQS_DN<12>")
	)
	(segment
		(start 228.281738 -7.083044)
		(end 228.281738 -7.3152)
		(width 0.1651)
		(layer "F.Cu")
		(net "M_B_DQS_DN<12>")
	)
	(segment
		(start 228.054662 -28.070556)
		(end 228.248464 -28.264358)
		(width 0.1651)
		(layer "F.Cu")
		(net "M_B_DQS_DN<12>")
	)
	(via
		(at 227.792534 -13.2334)
		(size 0.508)
		(drill 0.254)
		(layers "F.Cu" "B.Cu")
		(net "M_B_DQS_DN<12>")
	)
	(via
		(at 227.799138 -7.8105)
		(size 0.508)
		(drill 0.254)
		(layers "F.Cu" "B.Cu")
		(net "M_B_DQS_DN<12>")
	)
	(via
		(at 228.46792 -35.941)
		(size 0.508)
		(drill 0.254)
		(layers "F.Cu" "B.Cu")
		(net "M_B_DQS_DN<12>")
	)
	(via
		(at 227.792534 -28.070556)
		(size 0.508)
		(drill 0.254)
		(layers "F.Cu" "B.Cu")
		(net "M_B_DQS_DN<12>")
	)
	(arc
		(start 243.563394 -50.342038)
		(mid 243.522771 -50.24329)
		(end 243.5098 -50.137314)
		(width 0.0889)
		(layer "F.Cu")
		(net "M_B_DQS_DN<12>")
	)
	(arc
		(start 243.846858 -50.536856)
		(mid 243.683101 -50.471488)
		(end 243.563394 -50.342038)
		(width 0.0889)
		(layer "F.Cu")
		(net "M_B_DQS_DN<12>")
	)
	(segment
		(start 227.792534 -13.2334)
		(end 227.987098 -13.038836)
		(width 0.1651)
		(layer "B.Cu")
		(net "M_B_DQS_DN<12>")
	)
	(segment
		(start 228.256338 -14.122654)
		(end 228.700076 -14.566392)
		(width 0.1651)
		(layer "B.Cu")
		(net "M_B_DQS_DN<12>")
	)
	(segment
		(start 228.434138 -13.2588)
		(end 228.434138 -13.589)
		(width 0.1651)
		(layer "B.Cu")
		(net "M_B_DQS_DN<12>")
	)
	(segment
		(start 228.700076 -14.566392)
		(end 228.700076 -15.222728)
		(width 0.1651)
		(layer "B.Cu")
		(net "M_B_DQS_DN<12>")
	)
	(segment
		(start 227.987098 -13.038836)
		(end 228.214174 -13.038836)
		(width 0.1651)
		(layer "B.Cu")
		(net "M_B_DQS_DN<12>")
	)
	(segment
		(start 228.434138 -13.589)
		(end 228.256338 -13.7668)
		(width 0.1651)
		(layer "B.Cu")
		(net "M_B_DQS_DN<12>")
	)
	(segment
		(start 228.256338 -13.7668)
		(end 228.256338 -14.122654)
		(width 0.1651)
		(layer "B.Cu")
		(net "M_B_DQS_DN<12>")
	)
	(segment
		(start 228.700076 -15.222728)
		(end 228.70033 -15.222982)
		(width 0.1651)
		(layer "B.Cu")
		(net "M_B_DQS_DN<12>")
	)
	(segment
		(start 228.214174 -13.038836)
		(end 228.434138 -13.2588)
		(width 0.1651)
		(layer "B.Cu")
		(net "M_B_DQS_DN<12>")
	)
	(segment
		(start 228.050852 -14.422374)
		(end 228.050852 -15.175738)
		(width 0.14224)
		(layer "In4.Cu")
		(net "M_B_DQS_DN<12>")
	)
	(segment
		(start 227.792534 -13.2334)
		(end 228.230938 -13.671804)
		(width 0.14224)
		(layer "In4.Cu")
		(net "M_B_DQS_DN<12>")
	)
	(segment
		(start 228.581458 -8.343392)
		(end 228.581458 -12.444476)
		(width 0.14224)
		(layer "In4.Cu")
		(net "M_B_DQS_DN<12>")
	)
	(segment
		(start 228.050852 -15.175738)
		(end 228.558852 -15.683738)
		(width 0.14224)
		(layer "In4.Cu")
		(net "M_B_DQS_DN<12>")
	)
	(segment
		(start 228.581458 -12.444476)
		(end 227.792534 -13.2334)
		(width 0.14224)
		(layer "In4.Cu")
		(net "M_B_DQS_DN<12>")
	)
	(segment
		(start 227.799138 -7.8105)
		(end 227.994718 -8.00608)
		(width 0.14224)
		(layer "In4.Cu")
		(net "M_B_DQS_DN<12>")
	)
	(segment
		(start 228.230938 -13.671804)
		(end 228.230938 -14.242288)
		(width 0.14224)
		(layer "In4.Cu")
		(net "M_B_DQS_DN<12>")
	)
	(segment
		(start 228.230938 -14.242288)
		(end 228.050852 -14.422374)
		(width 0.14224)
		(layer "In4.Cu")
		(net "M_B_DQS_DN<12>")
	)
	(segment
		(start 228.558852 -15.683738)
		(end 228.558852 -27.304238)
		(width 0.14224)
		(layer "In4.Cu")
		(net "M_B_DQS_DN<12>")
	)
	(segment
		(start 228.244146 -8.00608)
		(end 228.581458 -8.343392)
		(width 0.14224)
		(layer "In4.Cu")
		(net "M_B_DQS_DN<12>")
	)
	(segment
		(start 227.994718 -8.00608)
		(end 228.244146 -8.00608)
		(width 0.14224)
		(layer "In4.Cu")
		(net "M_B_DQS_DN<12>")
	)
	(segment
		(start 228.558852 -27.304238)
		(end 227.792534 -28.070556)
		(width 0.14224)
		(layer "In4.Cu")
		(net "M_B_DQS_DN<12>")
	)
	(segment
		(start 218.638374 -7.99973)
		(end 218.449144 -7.8105)
		(width 0.1651)
		(layer "F.Cu")
		(net "M_B_DQS_DN<11>")
	)
	(segment
		(start 219.117672 -7.501128)
		(end 219.117672 -7.747762)
		(width 0.1651)
		(layer "F.Cu")
		(net "M_B_DQS_DN<11>")
	)
	(segment
		(start 238.759238 -51.132486)
		(end 238.187738 -51.132486)
		(width 0.1016)
		(layer "F.Cu")
		(net "M_B_DQS_DN<11>")
	)
	(segment
		(start 218.931744 -7.083044)
		(end 218.931744 -7.3152)
		(width 0.1651)
		(layer "F.Cu")
		(net "M_B_DQS_DN<11>")
	)
	(segment
		(start 219.349828 -6.66496)
		(end 218.931744 -7.083044)
		(width 0.1651)
		(layer "F.Cu")
		(net "M_B_DQS_DN<11>")
	)
	(segment
		(start 218.931744 -7.3152)
		(end 219.117672 -7.501128)
		(width 0.1651)
		(layer "F.Cu")
		(net "M_B_DQS_DN<11>")
	)
	(segment
		(start 219.350336 -5.822442)
		(end 219.349828 -5.822442)
		(width 0.1651)
		(layer "F.Cu")
		(net "M_B_DQS_DN<11>")
	)
	(segment
		(start 218.865704 -7.99973)
		(end 218.638374 -7.99973)
		(width 0.1651)
		(layer "F.Cu")
		(net "M_B_DQS_DN<11>")
	)
	(segment
		(start 219.349828 -5.822442)
		(end 219.349828 -6.66496)
		(width 0.1651)
		(layer "F.Cu")
		(net "M_B_DQS_DN<11>")
	)
	(segment
		(start 219.117672 -7.747762)
		(end 218.865704 -7.99973)
		(width 0.1651)
		(layer "F.Cu")
		(net "M_B_DQS_DN<11>")
	)
	(via
		(at 238.187738 -51.132486)
		(size 0.508)
		(drill 0.254)
		(layers "F.Cu" "B.Cu")
		(net "M_B_DQS_DN<11>")
	)
	(via
		(at 218.44254 -13.2334)
		(size 0.508)
		(drill 0.254)
		(layers "F.Cu" "B.Cu")
		(net "M_B_DQS_DN<11>")
	)
	(via
		(at 218.449144 -7.8105)
		(size 0.508)
		(drill 0.254)
		(layers "F.Cu" "B.Cu")
		(net "M_B_DQS_DN<11>")
	)
	(segment
		(start 219.084144 -13.2588)
		(end 218.86418 -13.038836)
		(width 0.1651)
		(layer "B.Cu")
		(net "M_B_DQS_DN<11>")
	)
	(segment
		(start 219.349828 -15.222982)
		(end 219.349828 -14.566138)
		(width 0.1651)
		(layer "B.Cu")
		(net "M_B_DQS_DN<11>")
	)
	(segment
		(start 218.906344 -13.7668)
		(end 219.084144 -13.589)
		(width 0.1651)
		(layer "B.Cu")
		(net "M_B_DQS_DN<11>")
	)
	(segment
		(start 218.86418 -13.038836)
		(end 218.637104 -13.038836)
		(width 0.1651)
		(layer "B.Cu")
		(net "M_B_DQS_DN<11>")
	)
	(segment
		(start 218.637104 -13.038836)
		(end 218.44254 -13.2334)
		(width 0.1651)
		(layer "B.Cu")
		(net "M_B_DQS_DN<11>")
	)
	(segment
		(start 219.349828 -14.566138)
		(end 218.906344 -14.122654)
		(width 0.1651)
		(layer "B.Cu")
		(net "M_B_DQS_DN<11>")
	)
	(segment
		(start 219.084144 -13.589)
		(end 219.084144 -13.2588)
		(width 0.1651)
		(layer "B.Cu")
		(net "M_B_DQS_DN<11>")
	)
	(segment
		(start 218.906344 -14.122654)
		(end 218.906344 -13.7668)
		(width 0.1651)
		(layer "B.Cu")
		(net "M_B_DQS_DN<11>")
	)
	(segment
		(start 219.350336 -15.222982)
		(end 219.349828 -15.222982)
		(width 0.1651)
		(layer "B.Cu")
		(net "M_B_DQS_DN<11>")
	)
	(segment
		(start 229.54742 -42.506646)
		(end 229.43312 -42.620946)
		(width 0.14224)
		(layer "In4.Cu")
		(net "M_B_DQS_DN<11>")
	)
	(segment
		(start 229.43312 -41.135554)
		(end 229.54742 -41.249854)
		(width 0.14224)
		(layer "In4.Cu")
		(net "M_B_DQS_DN<11>")
	)
	(segment
		(start 232.472484 -45.841412)
		(end 232.472484 -46.002956)
		(width 0.14224)
		(layer "In4.Cu")
		(net "M_B_DQS_DN<11>")
	)
	(segment
		(start 219.38234 -25.8064)
		(end 219.22486 -25.96388)
		(width 0.14224)
		(layer "In4.Cu")
		(net "M_B_DQS_DN<11>")
	)
	(segment
		(start 218.5924 -14.4018)
		(end 218.423744 -14.4018)
		(width 0.14224)
		(layer "In4.Cu")
		(net "M_B_DQS_DN<11>")
	)
	(segment
		(start 237.738412 -50.165)
		(end 237.841028 -50.342038)
		(width 0.0889)
		(layer "In4.Cu")
		(net "M_B_DQS_DN<11>")
	)
	(segment
		(start 232.472484 -46.002956)
		(end 232.7148 -46.245272)
		(width 0.14224)
		(layer "In4.Cu")
		(net "M_B_DQS_DN<11>")
	)
	(segment
		(start 229.54742 -40.678608)
		(end 229.43312 -40.792908)
		(width 0.14224)
		(layer "In4.Cu")
		(net "M_B_DQS_DN<11>")
	)
	(segment
		(start 219.38234 -25.5524)
		(end 219.38234 -25.8064)
		(width 0.14224)
		(layer "In4.Cu")
		(net "M_B_DQS_DN<11>")
	)
	(segment
		(start 218.240864 -15.059152)
		(end 218.48318 -15.301468)
		(width 0.14224)
		(layer "In4.Cu")
		(net "M_B_DQS_DN<11>")
	)
	(segment
		(start 226.40544 -36.532312)
		(end 226.40544 -37.28466)
		(width 0.14224)
		(layer "In4.Cu")
		(net "M_B_DQS_DN<11>")
	)
	(segment
		(start 237.920276 -50.632614)
		(end 238.187738 -51.132486)
		(width 0.0889)
		(layer "In4.Cu")
		(net "M_B_DQS_DN<11>")
	)
	(segment
		(start 229.54742 -42.163746)
		(end 229.54742 -42.506646)
		(width 0.14224)
		(layer "In4.Cu")
		(net "M_B_DQS_DN<11>")
	)
	(segment
		(start 229.43312 -42.963592)
		(end 230.129588 -43.66006)
		(width 0.14224)
		(layer "In4.Cu")
		(net "M_B_DQS_DN<11>")
	)
	(segment
		(start 230.533702 -43.90263)
		(end 230.533702 -44.064174)
		(width 0.14224)
		(layer "In4.Cu")
		(net "M_B_DQS_DN<11>")
	)
	(segment
		(start 218.423744 -14.4018)
		(end 218.240864 -14.58468)
		(width 0.14224)
		(layer "In4.Cu")
		(net "M_B_DQS_DN<11>")
	)
	(segment
		(start 225.895154 -36.022026)
		(end 226.40544 -36.532312)
		(width 0.14224)
		(layer "In4.Cu")
		(net "M_B_DQS_DN<11>")
	)
	(segment
		(start 219.33916 -26.763472)
		(end 219.22486 -26.877772)
		(width 0.14224)
		(layer "In4.Cu")
		(net "M_B_DQS_DN<11>")
	)
	(segment
		(start 219.22486 -25.20188)
		(end 219.22486 -25.39492)
		(width 0.14224)
		(layer "In4.Cu")
		(net "M_B_DQS_DN<11>")
	)
	(segment
		(start 219.38234 -24.0284)
		(end 219.38234 -24.2824)
		(width 0.14224)
		(layer "In4.Cu")
		(net "M_B_DQS_DN<11>")
	)
	(segment
		(start 230.291132 -43.66006)
		(end 230.533702 -43.90263)
		(width 0.14224)
		(layer "In4.Cu")
		(net "M_B_DQS_DN<11>")
	)
	(segment
		(start 219.22486 -20.38985)
		(end 219.22486 -23.87092)
		(width 0.14224)
		(layer "In4.Cu")
		(net "M_B_DQS_DN<11>")
	)
	(segment
		(start 230.129588 -43.66006)
		(end 230.291132 -43.66006)
		(width 0.14224)
		(layer "In4.Cu")
		(net "M_B_DQS_DN<11>")
	)
	(segment
		(start 218.644724 -15.301468)
		(end 218.887294 -15.544038)
		(width 0.14224)
		(layer "In4.Cu")
		(net "M_B_DQS_DN<11>")
	)
	(segment
		(start 219.33916 -19.932904)
		(end 219.33916 -20.27555)
		(width 0.14224)
		(layer "In4.Cu")
		(net "M_B_DQS_DN<11>")
	)
	(segment
		(start 218.8718 -14.1224)
		(end 218.5924 -14.4018)
		(width 0.14224)
		(layer "In4.Cu")
		(net "M_B_DQS_DN<11>")
	)
	(segment
		(start 231.179878 -44.71035)
		(end 231.422194 -44.952666)
		(width 0.14224)
		(layer "In4.Cu")
		(net "M_B_DQS_DN<11>")
	)
	(segment
		(start 231.422194 -44.952666)
		(end 231.583738 -44.952666)
		(width 0.14224)
		(layer "In4.Cu")
		(net "M_B_DQS_DN<11>")
	)
	(segment
		(start 219.22486 -25.96388)
		(end 219.22486 -26.306272)
		(width 0.14224)
		(layer "In4.Cu")
		(net "M_B_DQS_DN<11>")
	)
	(segment
		(start 232.06837 -45.598842)
		(end 232.229914 -45.598842)
		(width 0.14224)
		(layer "In4.Cu")
		(net "M_B_DQS_DN<11>")
	)
	(segment
		(start 229.43312 -40.792908)
		(end 229.43312 -41.135554)
		(width 0.14224)
		(layer "In4.Cu")
		(net "M_B_DQS_DN<11>")
	)
	(segment
		(start 219.22486 -24.43988)
		(end 219.22486 -24.63292)
		(width 0.14224)
		(layer "In4.Cu")
		(net "M_B_DQS_DN<11>")
	)
	(segment
		(start 230.937308 -44.306236)
		(end 231.179878 -44.548806)
		(width 0.14224)
		(layer "In4.Cu")
		(net "M_B_DQS_DN<11>")
	)
	(segment
		(start 231.826308 -45.35678)
		(end 232.06837 -45.598842)
		(width 0.14224)
		(layer "In4.Cu")
		(net "M_B_DQS_DN<11>")
	)
	(segment
		(start 219.22486 -18.86585)
		(end 219.33916 -18.98015)
		(width 0.14224)
		(layer "In4.Cu")
		(net "M_B_DQS_DN<11>")
	)
	(segment
		(start 228.022658 -38.14953)
		(end 228.022658 -38.901878)
		(width 0.14224)
		(layer "In4.Cu")
		(net "M_B_DQS_DN<11>")
	)
	(segment
		(start 226.40544 -37.28466)
		(end 226.760024 -37.639244)
		(width 0.14224)
		(layer "In4.Cu")
		(net "M_B_DQS_DN<11>")
	)
	(segment
		(start 229.43312 -42.049446)
		(end 229.54742 -42.163746)
		(width 0.14224)
		(layer "In4.Cu")
		(net "M_B_DQS_DN<11>")
	)
	(segment
		(start 229.43312 -40.221408)
		(end 229.54742 -40.335708)
		(width 0.14224)
		(layer "In4.Cu")
		(net "M_B_DQS_DN<11>")
	)
	(segment
		(start 219.33916 -26.420572)
		(end 219.33916 -26.763472)
		(width 0.14224)
		(layer "In4.Cu")
		(net "M_B_DQS_DN<11>")
	)
	(segment
		(start 219.33916 -18.98015)
		(end 219.33916 -19.322796)
		(width 0.14224)
		(layer "In4.Cu")
		(net "M_B_DQS_DN<11>")
	)
	(segment
		(start 219.33916 -19.322796)
		(end 219.22486 -19.437096)
		(width 0.14224)
		(layer "In4.Cu")
		(net "M_B_DQS_DN<11>")
	)
	(segment
		(start 219.22486 -19.437096)
		(end 219.22486 -19.818604)
		(width 0.14224)
		(layer "In4.Cu")
		(net "M_B_DQS_DN<11>")
	)
	(segment
		(start 224.788222 -34.915094)
		(end 224.788222 -35.667442)
		(width 0.14224)
		(layer "In4.Cu")
		(net "M_B_DQS_DN<11>")
	)
	(segment
		(start 230.775764 -44.306236)
		(end 230.937308 -44.306236)
		(width 0.14224)
		(layer "In4.Cu")
		(net "M_B_DQS_DN<11>")
	)
	(segment
		(start 231.179878 -44.548806)
		(end 231.179878 -44.71035)
		(width 0.14224)
		(layer "In4.Cu")
		(net "M_B_DQS_DN<11>")
	)
	(segment
		(start 218.449144 -7.8105)
		(end 218.644724 -8.00608)
		(width 0.14224)
		(layer "In4.Cu")
		(net "M_B_DQS_DN<11>")
	)
	(segment
		(start 219.33916 -20.27555)
		(end 219.22486 -20.38985)
		(width 0.14224)
		(layer "In4.Cu")
		(net "M_B_DQS_DN<11>")
	)
	(segment
		(start 228.022658 -38.901878)
		(end 228.377242 -39.256462)
		(width 0.14224)
		(layer "In4.Cu")
		(net "M_B_DQS_DN<11>")
	)
	(segment
		(start 224.788222 -35.667442)
		(end 225.142806 -36.022026)
		(width 0.14224)
		(layer "In4.Cu")
		(net "M_B_DQS_DN<11>")
	)
	(segment
		(start 219.22486 -26.306272)
		(end 219.33916 -26.420572)
		(width 0.14224)
		(layer "In4.Cu")
		(net "M_B_DQS_DN<11>")
	)
	(segment
		(start 219.22486 -25.39492)
		(end 219.38234 -25.5524)
		(width 0.14224)
		(layer "In4.Cu")
		(net "M_B_DQS_DN<11>")
	)
	(segment
		(start 219.22486 -16.043148)
		(end 219.22486 -18.86585)
		(width 0.14224)
		(layer "In4.Cu")
		(net "M_B_DQS_DN<11>")
	)
	(segment
		(start 229.54742 -41.592754)
		(end 229.43312 -41.707054)
		(width 0.14224)
		(layer "In4.Cu")
		(net "M_B_DQS_DN<11>")
	)
	(segment
		(start 230.533702 -44.064174)
		(end 230.775764 -44.306236)
		(width 0.14224)
		(layer "In4.Cu")
		(net "M_B_DQS_DN<11>")
	)
	(segment
		(start 219.231464 -12.444476)
		(end 218.44254 -13.2334)
		(width 0.14224)
		(layer "In4.Cu")
		(net "M_B_DQS_DN<11>")
	)
	(segment
		(start 219.38234 -25.0444)
		(end 219.22486 -25.20188)
		(width 0.14224)
		(layer "In4.Cu")
		(net "M_B_DQS_DN<11>")
	)
	(segment
		(start 218.644724 -8.00608)
		(end 218.894152 -8.00608)
		(width 0.14224)
		(layer "In4.Cu")
		(net "M_B_DQS_DN<11>")
	)
	(segment
		(start 233.333036 -47.649892)
		(end 235.327698 -49.644554)
		(width 0.0889)
		(layer "In4.Cu")
		(net "M_B_DQS_DN<11>")
	)
	(segment
		(start 237.217966 -49.644554)
		(end 237.738412 -50.165)
		(width 0.0889)
		(layer "In4.Cu")
		(net "M_B_DQS_DN<11>")
	)
	(segment
		(start 218.8718 -13.66266)
		(end 218.8718 -14.1224)
		(width 0.14224)
		(layer "In4.Cu")
		(net "M_B_DQS_DN<11>")
	)
	(segment
		(start 229.43312 -41.707054)
		(end 229.43312 -42.049446)
		(width 0.14224)
		(layer "In4.Cu")
		(net "M_B_DQS_DN<11>")
	)
	(segment
		(start 218.894152 -8.00608)
		(end 219.231464 -8.343392)
		(width 0.14224)
		(layer "In4.Cu")
		(net "M_B_DQS_DN<11>")
	)
	(segment
		(start 229.54742 -41.249854)
		(end 229.54742 -41.592754)
		(width 0.14224)
		(layer "In4.Cu")
		(net "M_B_DQS_DN<11>")
	)
	(segment
		(start 219.22486 -26.877772)
		(end 219.22486 -29.351732)
		(width 0.14224)
		(layer "In4.Cu")
		(net "M_B_DQS_DN<11>")
	)
	(segment
		(start 219.231464 -8.343392)
		(end 219.231464 -12.444476)
		(width 0.14224)
		(layer "In4.Cu")
		(net "M_B_DQS_DN<11>")
	)
	(segment
		(start 219.22486 -23.87092)
		(end 219.38234 -24.0284)
		(width 0.14224)
		(layer "In4.Cu")
		(net "M_B_DQS_DN<11>")
	)
	(segment
		(start 229.54742 -40.335708)
		(end 229.54742 -40.678608)
		(width 0.14224)
		(layer "In4.Cu")
		(net "M_B_DQS_DN<11>")
	)
	(segment
		(start 218.240864 -14.58468)
		(end 218.240864 -15.059152)
		(width 0.14224)
		(layer "In4.Cu")
		(net "M_B_DQS_DN<11>")
	)
	(segment
		(start 218.44254 -13.2334)
		(end 218.8718 -13.66266)
		(width 0.14224)
		(layer "In4.Cu")
		(net "M_B_DQS_DN<11>")
	)
	(segment
		(start 233.317288 -47.578264)
		(end 233.333036 -47.594012)
		(width 0.0889)
		(layer "In4.Cu")
		(net "M_B_DQS_DN<11>")
	)
	(segment
		(start 218.48318 -15.301468)
		(end 218.644724 -15.301468)
		(width 0.14224)
		(layer "In4.Cu")
		(net "M_B_DQS_DN<11>")
	)
	(segment
		(start 219.22486 -24.63292)
		(end 219.38234 -24.7904)
		(width 0.14224)
		(layer "In4.Cu")
		(net "M_B_DQS_DN<11>")
	)
	(segment
		(start 219.38234 -24.2824)
		(end 219.22486 -24.43988)
		(width 0.14224)
		(layer "In4.Cu")
		(net "M_B_DQS_DN<11>")
	)
	(segment
		(start 227.512372 -37.639244)
		(end 228.022658 -38.14953)
		(width 0.14224)
		(layer "In4.Cu")
		(net "M_B_DQS_DN<11>")
	)
	(segment
		(start 232.229914 -45.598842)
		(end 232.472484 -45.841412)
		(width 0.14224)
		(layer "In4.Cu")
		(net "M_B_DQS_DN<11>")
	)
	(segment
		(start 229.43312 -39.559992)
		(end 229.43312 -40.221408)
		(width 0.14224)
		(layer "In4.Cu")
		(net "M_B_DQS_DN<11>")
	)
	(segment
		(start 229.12959 -39.256462)
		(end 229.43312 -39.559992)
		(width 0.14224)
		(layer "In4.Cu")
		(net "M_B_DQS_DN<11>")
	)
	(segment
		(start 232.7148 -46.975776)
		(end 233.317288 -47.578264)
		(width 0.14224)
		(layer "In4.Cu")
		(net "M_B_DQS_DN<11>")
	)
	(segment
		(start 219.38234 -24.7904)
		(end 219.38234 -25.0444)
		(width 0.14224)
		(layer "In4.Cu")
		(net "M_B_DQS_DN<11>")
	)
	(segment
		(start 228.377242 -39.256462)
		(end 229.12959 -39.256462)
		(width 0.14224)
		(layer "In4.Cu")
		(net "M_B_DQS_DN<11>")
	)
	(segment
		(start 229.43312 -42.620946)
		(end 229.43312 -42.963592)
		(width 0.14224)
		(layer "In4.Cu")
		(net "M_B_DQS_DN<11>")
	)
	(segment
		(start 231.826308 -45.195236)
		(end 231.826308 -45.35678)
		(width 0.14224)
		(layer "In4.Cu")
		(net "M_B_DQS_DN<11>")
	)
	(segment
		(start 226.760024 -37.639244)
		(end 227.512372 -37.639244)
		(width 0.14224)
		(layer "In4.Cu")
		(net "M_B_DQS_DN<11>")
	)
	(segment
		(start 219.22486 -19.818604)
		(end 219.33916 -19.932904)
		(width 0.14224)
		(layer "In4.Cu")
		(net "M_B_DQS_DN<11>")
	)
	(segment
		(start 218.887294 -15.544038)
		(end 218.887294 -15.705582)
		(width 0.14224)
		(layer "In4.Cu")
		(net "M_B_DQS_DN<11>")
	)
	(segment
		(start 219.22486 -29.351732)
		(end 224.788222 -34.915094)
		(width 0.14224)
		(layer "In4.Cu")
		(net "M_B_DQS_DN<11>")
	)
	(segment
		(start 232.7148 -46.245272)
		(end 232.7148 -46.975776)
		(width 0.14224)
		(layer "In4.Cu")
		(net "M_B_DQS_DN<11>")
	)
	(segment
		(start 233.333036 -47.594012)
		(end 233.333036 -47.649892)
		(width 0.0889)
		(layer "In4.Cu")
		(net "M_B_DQS_DN<11>")
	)
	(segment
		(start 218.887294 -15.705582)
		(end 219.22486 -16.043148)
		(width 0.14224)
		(layer "In4.Cu")
		(net "M_B_DQS_DN<11>")
	)
	(segment
		(start 231.583738 -44.952666)
		(end 231.826308 -45.195236)
		(width 0.14224)
		(layer "In4.Cu")
		(net "M_B_DQS_DN<11>")
	)
	(segment
		(start 235.327698 -49.644554)
		(end 237.217966 -49.644554)
		(width 0.0889)
		(layer "In4.Cu")
		(net "M_B_DQS_DN<11>")
	)
	(segment
		(start 225.142806 -36.022026)
		(end 225.895154 -36.022026)
		(width 0.14224)
		(layer "In4.Cu")
		(net "M_B_DQS_DN<11>")
	)
	(arc
		(start 237.841028 -50.342038)
		(mid 237.89949 -50.48219)
		(end 237.920276 -50.632614)
		(width 0.0889)
		(layer "In4.Cu")
		(net "M_B_DQS_DN<11>")
	)
	(segment
		(start 209.28838 -7.99973)
		(end 209.09915 -7.8105)
		(width 0.1651)
		(layer "F.Cu")
		(net "M_B_DQS_DN<10>")
	)
	(segment
		(start 210.000342 -5.822442)
		(end 209.999834 -5.822442)
		(width 0.1651)
		(layer "F.Cu")
		(net "M_B_DQS_DN<10>")
	)
	(segment
		(start 236.183678 -62.52464)
		(end 235.612178 -62.52464)
		(width 0.1016)
		(layer "F.Cu")
		(net "M_B_DQS_DN<10>")
	)
	(segment
		(start 209.767678 -7.501128)
		(end 209.767678 -7.747762)
		(width 0.1651)
		(layer "F.Cu")
		(net "M_B_DQS_DN<10>")
	)
	(segment
		(start 209.58175 -7.083044)
		(end 209.58175 -7.3152)
		(width 0.1651)
		(layer "F.Cu")
		(net "M_B_DQS_DN<10>")
	)
	(segment
		(start 209.58175 -7.3152)
		(end 209.767678 -7.501128)
		(width 0.1651)
		(layer "F.Cu")
		(net "M_B_DQS_DN<10>")
	)
	(segment
		(start 209.999834 -6.66496)
		(end 209.58175 -7.083044)
		(width 0.1651)
		(layer "F.Cu")
		(net "M_B_DQS_DN<10>")
	)
	(segment
		(start 209.999834 -5.822442)
		(end 209.999834 -6.66496)
		(width 0.1651)
		(layer "F.Cu")
		(net "M_B_DQS_DN<10>")
	)
	(segment
		(start 209.51571 -7.99973)
		(end 209.28838 -7.99973)
		(width 0.1651)
		(layer "F.Cu")
		(net "M_B_DQS_DN<10>")
	)
	(segment
		(start 209.767678 -7.747762)
		(end 209.51571 -7.99973)
		(width 0.1651)
		(layer "F.Cu")
		(net "M_B_DQS_DN<10>")
	)
	(via
		(at 209.092546 -13.2334)
		(size 0.508)
		(drill 0.254)
		(layers "F.Cu" "B.Cu")
		(net "M_B_DQS_DN<10>")
	)
	(via
		(at 209.09915 -7.8105)
		(size 0.508)
		(drill 0.254)
		(layers "F.Cu" "B.Cu")
		(net "M_B_DQS_DN<10>")
	)
	(via
		(at 235.612178 -62.52464)
		(size 0.508)
		(drill 0.254)
		(layers "F.Cu" "B.Cu")
		(net "M_B_DQS_DN<10>")
	)
	(segment
		(start 209.55635 -13.7668)
		(end 209.73415 -13.589)
		(width 0.1651)
		(layer "B.Cu")
		(net "M_B_DQS_DN<10>")
	)
	(segment
		(start 209.73415 -13.2588)
		(end 209.514186 -13.038836)
		(width 0.1651)
		(layer "B.Cu")
		(net "M_B_DQS_DN<10>")
	)
	(segment
		(start 209.55635 -14.122654)
		(end 209.55635 -13.7668)
		(width 0.1651)
		(layer "B.Cu")
		(net "M_B_DQS_DN<10>")
	)
	(segment
		(start 209.73415 -13.589)
		(end 209.73415 -13.2588)
		(width 0.1651)
		(layer "B.Cu")
		(net "M_B_DQS_DN<10>")
	)
	(segment
		(start 209.28711 -13.038836)
		(end 209.092546 -13.2334)
		(width 0.1651)
		(layer "B.Cu")
		(net "M_B_DQS_DN<10>")
	)
	(segment
		(start 209.999834 -14.566138)
		(end 209.55635 -14.122654)
		(width 0.1651)
		(layer "B.Cu")
		(net "M_B_DQS_DN<10>")
	)
	(segment
		(start 209.514186 -13.038836)
		(end 209.28711 -13.038836)
		(width 0.1651)
		(layer "B.Cu")
		(net "M_B_DQS_DN<10>")
	)
	(segment
		(start 209.999834 -15.222982)
		(end 209.999834 -14.566138)
		(width 0.1651)
		(layer "B.Cu")
		(net "M_B_DQS_DN<10>")
	)
	(segment
		(start 210.000342 -15.222982)
		(end 209.999834 -15.222982)
		(width 0.1651)
		(layer "B.Cu")
		(net "M_B_DQS_DN<10>")
	)
	(segment
		(start 227.039678 -51.812444)
		(end 226.797362 -51.570128)
		(width 0.14224)
		(layer "In4.Cu")
		(net "M_B_DQS_DN<10>")
	)
	(segment
		(start 225.747072 -50.519838)
		(end 225.504756 -50.277522)
		(width 0.14224)
		(layer "In4.Cu")
		(net "M_B_DQS_DN<10>")
	)
	(segment
		(start 231.128316 -56.867298)
		(end 231.128316 -56.811926)
		(width 0.0889)
		(layer "In4.Cu")
		(net "M_B_DQS_DN<10>")
	)
	(segment
		(start 228.736398 -53.34762)
		(end 228.493828 -53.10505)
		(width 0.14224)
		(layer "In4.Cu")
		(net "M_B_DQS_DN<10>")
	)
	(segment
		(start 209.092546 -13.2334)
		(end 209.88147 -12.444476)
		(width 0.14224)
		(layer "In4.Cu")
		(net "M_B_DQS_DN<10>")
	)
	(segment
		(start 228.736398 -53.509164)
		(end 228.736398 -53.34762)
		(width 0.14224)
		(layer "In4.Cu")
		(net "M_B_DQS_DN<10>")
	)
	(segment
		(start 209.32775 -14.4018)
		(end 209.52079 -14.20876)
		(width 0.14224)
		(layer "In4.Cu")
		(net "M_B_DQS_DN<10>")
	)
	(segment
		(start 233.28884 -59.279536)
		(end 231.970326 -57.961022)
		(width 0.0889)
		(layer "In4.Cu")
		(net "M_B_DQS_DN<10>")
	)
	(segment
		(start 209.874866 -25.26792)
		(end 209.874866 -25.07488)
		(width 0.14224)
		(layer "In4.Cu")
		(net "M_B_DQS_DN<10>")
	)
	(segment
		(start 209.5373 -15.502382)
		(end 209.5373 -15.340838)
		(width 0.14224)
		(layer "In4.Cu")
		(net "M_B_DQS_DN<10>")
	)
	(segment
		(start 209.874866 -15.839948)
		(end 209.5373 -15.502382)
		(width 0.14224)
		(layer "In4.Cu")
		(net "M_B_DQS_DN<10>")
	)
	(segment
		(start 235.09224 -62.535562)
		(end 235.09224 -62.535308)
		(width 0.0889)
		(layer "In4.Cu")
		(net "M_B_DQS_DN<10>")
	)
	(segment
		(start 228.493828 -53.10505)
		(end 228.332284 -53.10505)
		(width 0.14224)
		(layer "In4.Cu")
		(net "M_B_DQS_DN<10>")
	)
	(segment
		(start 209.874866 -25.07488)
		(end 210.032346 -24.9174)
		(width 0.14224)
		(layer "In4.Cu")
		(net "M_B_DQS_DN<10>")
	)
	(segment
		(start 230.3399 -56.02351)
		(end 230.3399 -55.112666)
		(width 0.14224)
		(layer "In4.Cu")
		(net "M_B_DQS_DN<10>")
	)
	(segment
		(start 224.85858 -49.631346)
		(end 224.85858 -49.469802)
		(width 0.14224)
		(layer "In4.Cu")
		(net "M_B_DQS_DN<10>")
	)
	(segment
		(start 209.874866 -26.174192)
		(end 209.874866 -25.83688)
		(width 0.14224)
		(layer "In4.Cu")
		(net "M_B_DQS_DN<10>")
	)
	(segment
		(start 229.382574 -53.993542)
		(end 229.140004 -53.751226)
		(width 0.14224)
		(layer "In4.Cu")
		(net "M_B_DQS_DN<10>")
	)
	(segment
		(start 231.112568 -56.796178)
		(end 230.3399 -56.02351)
		(width 0.14224)
		(layer "In4.Cu")
		(net "M_B_DQS_DN<10>")
	)
	(segment
		(start 209.52079 -14.20876)
		(end 209.52079 -13.661644)
		(width 0.14224)
		(layer "In4.Cu")
		(net "M_B_DQS_DN<10>")
	)
	(segment
		(start 228.332284 -53.10505)
		(end 228.089968 -52.862734)
		(width 0.14224)
		(layer "In4.Cu")
		(net "M_B_DQS_DN<10>")
	)
	(segment
		(start 225.262186 -49.873408)
		(end 225.100642 -49.873408)
		(width 0.14224)
		(layer "In4.Cu")
		(net "M_B_DQS_DN<10>")
	)
	(segment
		(start 224.21215 -48.823372)
		(end 223.96958 -48.580802)
		(width 0.14224)
		(layer "In4.Cu")
		(net "M_B_DQS_DN<10>")
	)
	(segment
		(start 222.030798 -46.64202)
		(end 221.869254 -46.64202)
		(width 0.14224)
		(layer "In4.Cu")
		(net "M_B_DQS_DN<10>")
	)
	(segment
		(start 209.874866 -19.373596)
		(end 209.989166 -19.259296)
		(width 0.14224)
		(layer "In4.Cu")
		(net "M_B_DQS_DN<10>")
	)
	(segment
		(start 224.61601 -49.227232)
		(end 224.454466 -49.227232)
		(width 0.14224)
		(layer "In4.Cu")
		(net "M_B_DQS_DN<10>")
	)
	(segment
		(start 209.88147 -8.343392)
		(end 209.544158 -8.00608)
		(width 0.14224)
		(layer "In4.Cu")
		(net "M_B_DQS_DN<10>")
	)
	(segment
		(start 209.52079 -13.661644)
		(end 209.092546 -13.2334)
		(width 0.14224)
		(layer "In4.Cu")
		(net "M_B_DQS_DN<10>")
	)
	(segment
		(start 222.919544 -47.530766)
		(end 222.676974 -47.288196)
		(width 0.14224)
		(layer "In4.Cu")
		(net "M_B_DQS_DN<10>")
	)
	(segment
		(start 226.797362 -51.570128)
		(end 226.797362 -51.408584)
		(width 0.14224)
		(layer "In4.Cu")
		(net "M_B_DQS_DN<10>")
	)
	(segment
		(start 224.454466 -49.227232)
		(end 224.21215 -48.984916)
		(width 0.14224)
		(layer "In4.Cu")
		(net "M_B_DQS_DN<10>")
	)
	(segment
		(start 231.563164 -57.710324)
		(end 231.563164 -57.302146)
		(width 0.0889)
		(layer "In4.Cu")
		(net "M_B_DQS_DN<10>")
	)
	(segment
		(start 209.874866 -23.74392)
		(end 209.874866 -20.47748)
		(width 0.14224)
		(layer "In4.Cu")
		(net "M_B_DQS_DN<10>")
	)
	(segment
		(start 212.880194 -37.65296)
		(end 212.2932 -37.065966)
		(width 0.14224)
		(layer "In4.Cu")
		(net "M_B_DQS_DN<10>")
	)
	(segment
		(start 233.906314 -61.933836)
		(end 233.877612 -61.933836)
		(width 0.0889)
		(layer "In4.Cu")
		(net "M_B_DQS_DN<10>")
	)
	(segment
		(start 227.847398 -52.45862)
		(end 227.685854 -52.45862)
		(width 0.14224)
		(layer "In4.Cu")
		(net "M_B_DQS_DN<10>")
	)
	(segment
		(start 231.813862 -57.961022)
		(end 231.563164 -57.710324)
		(width 0.0889)
		(layer "In4.Cu")
		(net "M_B_DQS_DN<10>")
	)
	(segment
		(start 222.51543 -47.288196)
		(end 222.273368 -47.046134)
		(width 0.14224)
		(layer "In4.Cu")
		(net "M_B_DQS_DN<10>")
	)
	(segment
		(start 222.919544 -47.69231)
		(end 222.919544 -47.530766)
		(width 0.14224)
		(layer "In4.Cu")
		(net "M_B_DQS_DN<10>")
	)
	(segment
		(start 223.565974 -48.33874)
		(end 223.565974 -48.177196)
		(width 0.14224)
		(layer "In4.Cu")
		(net "M_B_DQS_DN<10>")
	)
	(segment
		(start 209.133186 -15.098268)
		(end 208.89087 -14.855952)
		(width 0.14224)
		(layer "In4.Cu")
		(net "M_B_DQS_DN<10>")
	)
	(segment
		(start 229.382574 -54.15534)
		(end 229.382574 -53.993542)
		(width 0.14224)
		(layer "In4.Cu")
		(net "M_B_DQS_DN<10>")
	)
	(segment
		(start 227.685854 -52.45862)
		(end 227.443792 -52.216558)
		(width 0.14224)
		(layer "In4.Cu")
		(net "M_B_DQS_DN<10>")
	)
	(segment
		(start 233.548174 -59.738514)
		(end 233.28884 -59.279536)
		(width 0.0889)
		(layer "In4.Cu")
		(net "M_B_DQS_DN<10>")
	)
	(segment
		(start 210.032346 -25.6794)
		(end 210.032346 -25.4254)
		(width 0.14224)
		(layer "In4.Cu")
		(net "M_B_DQS_DN<10>")
	)
	(segment
		(start 223.96958 -48.580802)
		(end 223.808036 -48.580802)
		(width 0.14224)
		(layer "In4.Cu")
		(net "M_B_DQS_DN<10>")
	)
	(segment
		(start 235.612178 -62.52464)
		(end 235.30179 -62.62243)
		(width 0.0889)
		(layer "In4.Cu")
		(net "M_B_DQS_DN<10>")
	)
	(segment
		(start 208.89087 -14.58468)
		(end 209.07375 -14.4018)
		(width 0.14224)
		(layer "In4.Cu")
		(net "M_B_DQS_DN<10>")
	)
	(segment
		(start 234.767374 -62.429136)
		(end 234.736132 -62.429136)
		(width 0.0889)
		(layer "In4.Cu")
		(net "M_B_DQS_DN<10>")
	)
	(segment
		(start 210.032346 -24.6634)
		(end 209.874866 -24.50592)
		(width 0.14224)
		(layer "In4.Cu")
		(net "M_B_DQS_DN<10>")
	)
	(segment
		(start 223.808036 -48.580802)
		(end 223.565974 -48.33874)
		(width 0.14224)
		(layer "In4.Cu")
		(net "M_B_DQS_DN<10>")
	)
	(segment
		(start 231.970326 -57.961022)
		(end 231.813862 -57.961022)
		(width 0.0889)
		(layer "In4.Cu")
		(net "M_B_DQS_DN<10>")
	)
	(segment
		(start 231.563164 -57.302146)
		(end 231.128316 -56.867298)
		(width 0.0889)
		(layer "In4.Cu")
		(net "M_B_DQS_DN<10>")
	)
	(segment
		(start 231.128316 -56.811926)
		(end 231.112568 -56.796178)
		(width 0.0889)
		(layer "In4.Cu")
		(net "M_B_DQS_DN<10>")
	)
	(segment
		(start 209.29473 -15.098268)
		(end 209.133186 -15.098268)
		(width 0.14224)
		(layer "In4.Cu")
		(net "M_B_DQS_DN<10>")
	)
	(segment
		(start 223.565974 -48.177196)
		(end 223.323404 -47.934626)
		(width 0.14224)
		(layer "In4.Cu")
		(net "M_B_DQS_DN<10>")
	)
	(segment
		(start 227.443792 -52.216558)
		(end 227.443792 -52.055014)
		(width 0.14224)
		(layer "In4.Cu")
		(net "M_B_DQS_DN<10>")
	)
	(segment
		(start 228.089968 -52.862734)
		(end 228.089968 -52.70119)
		(width 0.14224)
		(layer "In4.Cu")
		(net "M_B_DQS_DN<10>")
	)
	(segment
		(start 210.032346 -24.9174)
		(end 210.032346 -24.6634)
		(width 0.14224)
		(layer "In4.Cu")
		(net "M_B_DQS_DN<10>")
	)
	(segment
		(start 223.323404 -47.934626)
		(end 223.16186 -47.934626)
		(width 0.14224)
		(layer "In4.Cu")
		(net "M_B_DQS_DN<10>")
	)
	(segment
		(start 226.151186 -50.923952)
		(end 226.151186 -50.762408)
		(width 0.14224)
		(layer "In4.Cu")
		(net "M_B_DQS_DN<10>")
	)
	(segment
		(start 228.089968 -52.70119)
		(end 227.847398 -52.45862)
		(width 0.14224)
		(layer "In4.Cu")
		(net "M_B_DQS_DN<10>")
	)
	(segment
		(start 225.504756 -50.115978)
		(end 225.262186 -49.873408)
		(width 0.14224)
		(layer "In4.Cu")
		(net "M_B_DQS_DN<10>")
	)
	(segment
		(start 229.851458 -54.462426)
		(end 229.68966 -54.462426)
		(width 0.14224)
		(layer "In4.Cu")
		(net "M_B_DQS_DN<10>")
	)
	(segment
		(start 224.21215 -48.984916)
		(end 224.21215 -48.823372)
		(width 0.14224)
		(layer "In4.Cu")
		(net "M_B_DQS_DN<10>")
	)
	(segment
		(start 210.032346 -20.066)
		(end 209.874866 -19.90852)
		(width 0.14224)
		(layer "In4.Cu")
		(net "M_B_DQS_DN<10>")
	)
	(segment
		(start 228.97846 -53.751226)
		(end 228.736398 -53.509164)
		(width 0.14224)
		(layer "In4.Cu")
		(net "M_B_DQS_DN<10>")
	)
	(segment
		(start 225.908616 -50.519838)
		(end 225.747072 -50.519838)
		(width 0.14224)
		(layer "In4.Cu")
		(net "M_B_DQS_DN<10>")
	)
	(segment
		(start 209.874866 -20.47748)
		(end 210.032346 -20.32)
		(width 0.14224)
		(layer "In4.Cu")
		(net "M_B_DQS_DN<10>")
	)
	(segment
		(start 212.2932 -37.065966)
		(end 212.2932 -33.6677)
		(width 0.14224)
		(layer "In4.Cu")
		(net "M_B_DQS_DN<10>")
	)
	(segment
		(start 209.874866 -25.83688)
		(end 210.032346 -25.6794)
		(width 0.14224)
		(layer "In4.Cu")
		(net "M_B_DQS_DN<10>")
	)
	(segment
		(start 227.443792 -52.055014)
		(end 227.201222 -51.812444)
		(width 0.14224)
		(layer "In4.Cu")
		(net "M_B_DQS_DN<10>")
	)
	(segment
		(start 209.874866 -24.50592)
		(end 209.874866 -24.31288)
		(width 0.14224)
		(layer "In4.Cu")
		(net "M_B_DQS_DN<10>")
	)
	(segment
		(start 225.504756 -50.277522)
		(end 225.504756 -50.115978)
		(width 0.14224)
		(layer "In4.Cu")
		(net "M_B_DQS_DN<10>")
	)
	(segment
		(start 215.076278 -37.894768)
		(end 215.076278 -37.492178)
		(width 0.14224)
		(layer "In4.Cu")
		(net "M_B_DQS_DN<10>")
	)
	(segment
		(start 209.544158 -8.00608)
		(end 209.29473 -8.00608)
		(width 0.14224)
		(layer "In4.Cu")
		(net "M_B_DQS_DN<10>")
	)
	(segment
		(start 214.208614 -38.762432)
		(end 215.076278 -37.894768)
		(width 0.14224)
		(layer "In4.Cu")
		(net "M_B_DQS_DN<10>")
	)
	(segment
		(start 209.88147 -12.444476)
		(end 209.88147 -8.343392)
		(width 0.14224)
		(layer "In4.Cu")
		(net "M_B_DQS_DN<10>")
	)
	(segment
		(start 226.151186 -50.762408)
		(end 225.908616 -50.519838)
		(width 0.14224)
		(layer "In4.Cu")
		(net "M_B_DQS_DN<10>")
	)
	(segment
		(start 210.032346 -20.32)
		(end 210.032346 -20.066)
		(width 0.14224)
		(layer "In4.Cu")
		(net "M_B_DQS_DN<10>")
	)
	(segment
		(start 214.628476 -37.044376)
		(end 214.225886 -37.044376)
		(width 0.14224)
		(layer "In4.Cu")
		(net "M_B_DQS_DN<10>")
	)
	(segment
		(start 210.48472 -31.85922)
		(end 210.48472 -26.784046)
		(width 0.14224)
		(layer "In4.Cu")
		(net "M_B_DQS_DN<10>")
	)
	(segment
		(start 209.989166 -18.91665)
		(end 209.874866 -18.80235)
		(width 0.14224)
		(layer "In4.Cu")
		(net "M_B_DQS_DN<10>")
	)
	(segment
		(start 229.68966 -54.462426)
		(end 229.382574 -54.15534)
		(width 0.14224)
		(layer "In4.Cu")
		(net "M_B_DQS_DN<10>")
	)
	(segment
		(start 210.032346 -24.1554)
		(end 210.032346 -23.9014)
		(width 0.14224)
		(layer "In4.Cu")
		(net "M_B_DQS_DN<10>")
	)
	(segment
		(start 209.07375 -14.4018)
		(end 209.32775 -14.4018)
		(width 0.14224)
		(layer "In4.Cu")
		(net "M_B_DQS_DN<10>")
	)
	(segment
		(start 209.5373 -15.340838)
		(end 209.29473 -15.098268)
		(width 0.14224)
		(layer "In4.Cu")
		(net "M_B_DQS_DN<10>")
	)
	(segment
		(start 212.2932 -33.6677)
		(end 210.48472 -31.85922)
		(width 0.14224)
		(layer "In4.Cu")
		(net "M_B_DQS_DN<10>")
	)
	(segment
		(start 230.3399 -55.112666)
		(end 230.093774 -54.86654)
		(width 0.14224)
		(layer "In4.Cu")
		(net "M_B_DQS_DN<10>")
	)
	(segment
		(start 208.89087 -14.855952)
		(end 208.89087 -14.58468)
		(width 0.14224)
		(layer "In4.Cu")
		(net "M_B_DQS_DN<10>")
	)
	(segment
		(start 226.393248 -51.166014)
		(end 226.151186 -50.923952)
		(width 0.14224)
		(layer "In4.Cu")
		(net "M_B_DQS_DN<10>")
	)
	(segment
		(start 222.676974 -47.288196)
		(end 222.51543 -47.288196)
		(width 0.14224)
		(layer "In4.Cu")
		(net "M_B_DQS_DN<10>")
	)
	(segment
		(start 229.140004 -53.751226)
		(end 228.97846 -53.751226)
		(width 0.14224)
		(layer "In4.Cu")
		(net "M_B_DQS_DN<10>")
	)
	(segment
		(start 221.869254 -46.64202)
		(end 214.208614 -38.98138)
		(width 0.14224)
		(layer "In4.Cu")
		(net "M_B_DQS_DN<10>")
	)
	(segment
		(start 226.797362 -51.408584)
		(end 226.554792 -51.166014)
		(width 0.14224)
		(layer "In4.Cu")
		(net "M_B_DQS_DN<10>")
	)
	(segment
		(start 225.100642 -49.873408)
		(end 224.85858 -49.631346)
		(width 0.14224)
		(layer "In4.Cu")
		(net "M_B_DQS_DN<10>")
	)
	(segment
		(start 222.273368 -47.046134)
		(end 222.273368 -46.88459)
		(width 0.14224)
		(layer "In4.Cu")
		(net "M_B_DQS_DN<10>")
	)
	(segment
		(start 214.208614 -38.98138)
		(end 214.208614 -38.762432)
		(width 0.14224)
		(layer "In4.Cu")
		(net "M_B_DQS_DN<10>")
	)
	(segment
		(start 226.554792 -51.166014)
		(end 226.393248 -51.166014)
		(width 0.14224)
		(layer "In4.Cu")
		(net "M_B_DQS_DN<10>")
	)
	(segment
		(start 230.093774 -54.704996)
		(end 229.851458 -54.462426)
		(width 0.14224)
		(layer "In4.Cu")
		(net "M_B_DQS_DN<10>")
	)
	(segment
		(start 210.032346 -23.9014)
		(end 209.874866 -23.74392)
		(width 0.14224)
		(layer "In4.Cu")
		(net "M_B_DQS_DN<10>")
	)
	(segment
		(start 235.30179 -62.62243)
		(end 235.213652 -62.585854)
		(width 0.0889)
		(layer "In4.Cu")
		(net "M_B_DQS_DN<10>")
	)
	(segment
		(start 213.617302 -37.65296)
		(end 212.880194 -37.65296)
		(width 0.14224)
		(layer "In4.Cu")
		(net "M_B_DQS_DN<10>")
	)
	(segment
		(start 215.076278 -37.492178)
		(end 214.628476 -37.044376)
		(width 0.14224)
		(layer "In4.Cu")
		(net "M_B_DQS_DN<10>")
	)
	(segment
		(start 209.989166 -19.259296)
		(end 209.989166 -18.91665)
		(width 0.14224)
		(layer "In4.Cu")
		(net "M_B_DQS_DN<10>")
	)
	(segment
		(start 209.874866 -19.90852)
		(end 209.874866 -19.373596)
		(width 0.14224)
		(layer "In4.Cu")
		(net "M_B_DQS_DN<10>")
	)
	(segment
		(start 210.48472 -26.784046)
		(end 209.874866 -26.174192)
		(width 0.14224)
		(layer "In4.Cu")
		(net "M_B_DQS_DN<10>")
	)
	(segment
		(start 223.16186 -47.934626)
		(end 222.919544 -47.69231)
		(width 0.14224)
		(layer "In4.Cu")
		(net "M_B_DQS_DN<10>")
	)
	(segment
		(start 209.874866 -24.31288)
		(end 210.032346 -24.1554)
		(width 0.14224)
		(layer "In4.Cu")
		(net "M_B_DQS_DN<10>")
	)
	(segment
		(start 209.874866 -18.80235)
		(end 209.874866 -15.839948)
		(width 0.14224)
		(layer "In4.Cu")
		(net "M_B_DQS_DN<10>")
	)
	(segment
		(start 230.093774 -54.86654)
		(end 230.093774 -54.704996)
		(width 0.14224)
		(layer "In4.Cu")
		(net "M_B_DQS_DN<10>")
	)
	(segment
		(start 222.273368 -46.88459)
		(end 222.030798 -46.64202)
		(width 0.14224)
		(layer "In4.Cu")
		(net "M_B_DQS_DN<10>")
	)
	(segment
		(start 209.29473 -8.00608)
		(end 209.09915 -7.8105)
		(width 0.14224)
		(layer "In4.Cu")
		(net "M_B_DQS_DN<10>")
	)
	(segment
		(start 210.032346 -25.4254)
		(end 209.874866 -25.26792)
		(width 0.14224)
		(layer "In4.Cu")
		(net "M_B_DQS_DN<10>")
	)
	(segment
		(start 214.225886 -37.044376)
		(end 213.617302 -37.65296)
		(width 0.14224)
		(layer "In4.Cu")
		(net "M_B_DQS_DN<10>")
	)
	(segment
		(start 227.201222 -51.812444)
		(end 227.039678 -51.812444)
		(width 0.14224)
		(layer "In4.Cu")
		(net "M_B_DQS_DN<10>")
	)
	(segment
		(start 224.85858 -49.469802)
		(end 224.61601 -49.227232)
		(width 0.14224)
		(layer "In4.Cu")
		(net "M_B_DQS_DN<10>")
	)
	(arc
		(start 233.548428 -60.743338)
		(mid 233.494803 -60.543753)
		(end 233.54792 -60.34405)
		(width 0.0889)
		(layer "In4.Cu")
		(net "M_B_DQS_DN<10>")
	)
	(arc
		(start 233.877612 -61.933836)
		(mid 233.544057 -61.726372)
		(end 233.548428 -61.333634)
		(width 0.0889)
		(layer "In4.Cu")
		(net "M_B_DQS_DN<10>")
	)
	(arc
		(start 233.54792 -60.34405)
		(mid 233.630968 -60.041311)
		(end 233.548174 -59.738514)
		(width 0.0889)
		(layer "In4.Cu")
		(net "M_B_DQS_DN<10>")
	)
	(arc
		(start 235.09224 -62.535308)
		(mid 235.043202 -62.504644)
		(end 234.991402 -62.47892)
		(width 0.0889)
		(layer "In4.Cu")
		(net "M_B_DQS_DN<10>")
	)
	(arc
		(start 234.736132 -62.429136)
		(mid 234.546767 -62.371932)
		(end 234.407964 -62.231016)
		(width 0.0889)
		(layer "In4.Cu")
		(net "M_B_DQS_DN<10>")
	)
	(arc
		(start 234.991402 -62.47892)
		(mid 234.88183 -62.443039)
		(end 234.767374 -62.429136)
		(width 0.0889)
		(layer "In4.Cu")
		(net "M_B_DQS_DN<10>")
	)
	(arc
		(start 235.213652 -62.585854)
		(mid 235.152948 -62.560703)
		(end 235.09224 -62.535562)
		(width 0.0889)
		(layer "In4.Cu")
		(net "M_B_DQS_DN<10>")
	)
	(arc
		(start 233.548428 -61.333634)
		(mid 233.627433 -61.038486)
		(end 233.548428 -60.743338)
		(width 0.0889)
		(layer "In4.Cu")
		(net "M_B_DQS_DN<10>")
	)
	(arc
		(start 234.407964 -62.231016)
		(mid 234.197846 -62.013714)
		(end 233.906314 -61.933836)
		(width 0.0889)
		(layer "In4.Cu")
		(net "M_B_DQS_DN<10>")
	)
	(segment
		(start 200.384156 -8.410956)
		(end 201.037952 -7.75716)
		(width 0.1651)
		(layer "F.Cu")
		(net "M_B_DQS_DN<0>")
	)
	(segment
		(start 200.64984 -10.422382)
		(end 200.64984 -9.40943)
		(width 0.1651)
		(layer "F.Cu")
		(net "M_B_DQS_DN<0>")
	)
	(segment
		(start 238.759238 -65.991486)
		(end 238.187738 -65.991486)
		(width 0.0889)
		(layer "F.Cu")
		(net "M_B_DQS_DN<0>")
	)
	(segment
		(start 200.650348 -10.422382)
		(end 200.64984 -10.422382)
		(width 0.1651)
		(layer "F.Cu")
		(net "M_B_DQS_DN<0>")
	)
	(segment
		(start 200.64984 -9.40943)
		(end 200.384156 -9.143746)
		(width 0.1651)
		(layer "F.Cu")
		(net "M_B_DQS_DN<0>")
	)
	(segment
		(start 200.384156 -9.143746)
		(end 200.384156 -8.410956)
		(width 0.1651)
		(layer "F.Cu")
		(net "M_B_DQS_DN<0>")
	)
	(via
		(at 201.037952 -7.75716)
		(size 0.508)
		(drill 0.254)
		(layers "F.Cu" "B.Cu")
		(net "M_B_DQS_DN<0>")
	)
	(via
		(at 238.187738 -65.991486)
		(size 0.508)
		(drill 0.254)
		(layers "F.Cu" "B.Cu")
		(net "M_B_DQS_DN<0>")
	)
	(via
		(at 201.037952 -13.287756)
		(size 0.508)
		(drill 0.254)
		(layers "F.Cu" "B.Cu")
		(net "M_B_DQS_DN<0>")
	)
	(segment
		(start 200.64984 -11.52017)
		(end 200.396856 -11.773154)
		(width 0.1651)
		(layer "B.Cu")
		(net "M_B_DQS_DN<0>")
	)
	(segment
		(start 200.650348 -10.623042)
		(end 200.64984 -10.623042)
		(width 0.1651)
		(layer "B.Cu")
		(net "M_B_DQS_DN<0>")
	)
	(segment
		(start 200.64984 -10.623042)
		(end 200.64984 -11.52017)
		(width 0.1651)
		(layer "B.Cu")
		(net "M_B_DQS_DN<0>")
	)
	(segment
		(start 200.396856 -11.773154)
		(end 200.396856 -12.64666)
		(width 0.1651)
		(layer "B.Cu")
		(net "M_B_DQS_DN<0>")
	)
	(segment
		(start 200.396856 -12.64666)
		(end 201.037952 -13.287756)
		(width 0.1651)
		(layer "B.Cu")
		(net "M_B_DQS_DN<0>")
	)
	(segment
		(start 201.820272 -15.976854)
		(end 200.874122 -15.030704)
		(width 0.14224)
		(layer "In4.Cu")
		(net "M_B_DQS_DN<0>")
	)
	(segment
		(start 226.9998 -61.9506)
		(end 220.5228 -55.4736)
		(width 0.14224)
		(layer "In4.Cu")
		(net "M_B_DQS_DN<0>")
	)
	(segment
		(start 201.441304 -34.426906)
		(end 201.820272 -34.047938)
		(width 0.14224)
		(layer "In4.Cu")
		(net "M_B_DQS_DN<0>")
	)
	(segment
		(start 220.5228 -55.4736)
		(end 219.8497 -55.4736)
		(width 0.14224)
		(layer "In4.Cu")
		(net "M_B_DQS_DN<0>")
	)
	(segment
		(start 226.9998 -62.28842)
		(end 226.9998 -61.9506)
		(width 0.14224)
		(layer "In4.Cu")
		(net "M_B_DQS_DN<0>")
	)
	(segment
		(start 228.791262 -63.918338)
		(end 228.629718 -63.918338)
		(width 0.14224)
		(layer "In4.Cu")
		(net "M_B_DQS_DN<0>")
	)
	(segment
		(start 201.820272 -24.7015)
		(end 201.820272 -15.976854)
		(width 0.14224)
		(layer "In4.Cu")
		(net "M_B_DQS_DN<0>")
	)
	(segment
		(start 237.894622 -66.16065)
		(end 237.805214 -66.13652)
		(width 0.0889)
		(layer "In4.Cu")
		(net "M_B_DQS_DN<0>")
	)
	(segment
		(start 201.84872 -8.567928)
		(end 201.037952 -7.75716)
		(width 0.14224)
		(layer "In4.Cu")
		(net "M_B_DQS_DN<0>")
	)
	(segment
		(start 237.350808 -65.89649)
		(end 237.307628 -65.89649)
		(width 0.0889)
		(layer "In4.Cu")
		(net "M_B_DQS_DN<0>")
	)
	(segment
		(start 201.247502 -36.920424)
		(end 201.820272 -36.347654)
		(width 0.14224)
		(layer "In4.Cu")
		(net "M_B_DQS_DN<0>")
	)
	(segment
		(start 231.5083 -65.85712)
		(end 231.486202 -65.85712)
		(width 0.0889)
		(layer "In4.Cu")
		(net "M_B_DQS_DN<0>")
	)
	(segment
		(start 201.041 -14.4272)
		(end 201.3712 -14.4272)
		(width 0.14224)
		(layer "In4.Cu")
		(net "M_B_DQS_DN<0>")
	)
	(segment
		(start 200.83272 -34.648394)
		(end 201.054208 -34.426906)
		(width 0.14224)
		(layer "In4.Cu")
		(net "M_B_DQS_DN<0>")
	)
	(segment
		(start 231.54767 -65.89649)
		(end 231.5083 -65.85712)
		(width 0.0889)
		(layer "In4.Cu")
		(net "M_B_DQS_DN<0>")
	)
	(segment
		(start 230.083868 -65.210944)
		(end 229.922324 -65.210944)
		(width 0.14224)
		(layer "In4.Cu")
		(net "M_B_DQS_DN<0>")
	)
	(segment
		(start 229.437438 -64.564514)
		(end 229.275894 -64.564514)
		(width 0.14224)
		(layer "In4.Cu")
		(net "M_B_DQS_DN<0>")
	)
	(segment
		(start 201.820272 -36.347654)
		(end 201.820272 -35.882072)
		(width 0.14224)
		(layer "In4.Cu")
		(net "M_B_DQS_DN<0>")
	)
	(segment
		(start 229.922324 -65.210944)
		(end 229.680008 -64.968628)
		(width 0.14224)
		(layer "In4.Cu")
		(net "M_B_DQS_DN<0>")
	)
	(segment
		(start 227.741226 -62.868302)
		(end 227.498656 -62.625732)
		(width 0.14224)
		(layer "In4.Cu")
		(net "M_B_DQS_DN<0>")
	)
	(segment
		(start 232.305098 -65.89649)
		(end 231.54767 -65.89649)
		(width 0.0889)
		(layer "In4.Cu")
		(net "M_B_DQS_DN<0>")
	)
	(segment
		(start 202.022964 -37.87521)
		(end 201.247502 -37.099748)
		(width 0.14224)
		(layer "In4.Cu")
		(net "M_B_DQS_DN<0>")
	)
	(segment
		(start 229.680008 -64.807084)
		(end 229.437438 -64.564514)
		(width 0.14224)
		(layer "In4.Cu")
		(net "M_B_DQS_DN<0>")
	)
	(segment
		(start 205.8035 -41.4274)
		(end 205.8035 -39.5478)
		(width 0.14224)
		(layer "In4.Cu")
		(net "M_B_DQS_DN<0>")
	)
	(segment
		(start 204.13091 -37.87521)
		(end 202.022964 -37.87521)
		(width 0.14224)
		(layer "In4.Cu")
		(net "M_B_DQS_DN<0>")
	)
	(segment
		(start 227.498656 -62.625732)
		(end 227.337112 -62.625732)
		(width 0.14224)
		(layer "In4.Cu")
		(net "M_B_DQS_DN<0>")
	)
	(segment
		(start 201.3712 -14.4272)
		(end 201.501756 -14.296644)
		(width 0.14224)
		(layer "In4.Cu")
		(net "M_B_DQS_DN<0>")
	)
	(segment
		(start 200.874122 -15.030704)
		(end 200.874122 -14.594078)
		(width 0.14224)
		(layer "In4.Cu")
		(net "M_B_DQS_DN<0>")
	)
	(segment
		(start 235.623354 -66.88709)
		(end 235.590588 -66.88709)
		(width 0.0889)
		(layer "In4.Cu")
		(net "M_B_DQS_DN<0>")
	)
	(segment
		(start 233.916728 -66.88709)
		(end 233.883962 -66.88709)
		(width 0.0889)
		(layer "In4.Cu")
		(net "M_B_DQS_DN<0>")
	)
	(segment
		(start 238.187738 -65.991486)
		(end 237.894622 -66.16065)
		(width 0.0889)
		(layer "In4.Cu")
		(net "M_B_DQS_DN<0>")
	)
	(segment
		(start 234.768644 -67.382136)
		(end 234.738672 -67.382136)
		(width 0.0889)
		(layer "In4.Cu")
		(net "M_B_DQS_DN<0>")
	)
	(segment
		(start 229.275894 -64.564514)
		(end 229.033832 -64.322452)
		(width 0.14224)
		(layer "In4.Cu")
		(net "M_B_DQS_DN<0>")
	)
	(segment
		(start 200.83272 -35.282378)
		(end 200.83272 -34.648394)
		(width 0.14224)
		(layer "In4.Cu")
		(net "M_B_DQS_DN<0>")
	)
	(segment
		(start 228.145086 -63.272162)
		(end 227.983542 -63.272162)
		(width 0.14224)
		(layer "In4.Cu")
		(net "M_B_DQS_DN<0>")
	)
	(segment
		(start 200.874122 -14.594078)
		(end 201.041 -14.4272)
		(width 0.14224)
		(layer "In4.Cu")
		(net "M_B_DQS_DN<0>")
	)
	(segment
		(start 227.741226 -63.029846)
		(end 227.741226 -62.868302)
		(width 0.14224)
		(layer "In4.Cu")
		(net "M_B_DQS_DN<0>")
	)
	(segment
		(start 201.820272 -29.4513)
		(end 202.1713 -29.100272)
		(width 0.14224)
		(layer "In4.Cu")
		(net "M_B_DQS_DN<0>")
	)
	(segment
		(start 202.1713 -27.935428)
		(end 201.820272 -27.5844)
		(width 0.14224)
		(layer "In4.Cu")
		(net "M_B_DQS_DN<0>")
	)
	(segment
		(start 201.054208 -35.503866)
		(end 200.83272 -35.282378)
		(width 0.14224)
		(layer "In4.Cu")
		(net "M_B_DQS_DN<0>")
	)
	(segment
		(start 228.387656 -63.514732)
		(end 228.145086 -63.272162)
		(width 0.14224)
		(layer "In4.Cu")
		(net "M_B_DQS_DN<0>")
	)
	(segment
		(start 205.8035 -39.5478)
		(end 204.13091 -37.87521)
		(width 0.14224)
		(layer "In4.Cu")
		(net "M_B_DQS_DN<0>")
	)
	(segment
		(start 233.054398 -66.391536)
		(end 232.86974 -66.391536)
		(width 0.0889)
		(layer "In4.Cu")
		(net "M_B_DQS_DN<0>")
	)
	(segment
		(start 219.8497 -55.4736)
		(end 205.8035 -41.4274)
		(width 0.14224)
		(layer "In4.Cu")
		(net "M_B_DQS_DN<0>")
	)
	(segment
		(start 201.442066 -35.503866)
		(end 201.054208 -35.503866)
		(width 0.14224)
		(layer "In4.Cu")
		(net "M_B_DQS_DN<0>")
	)
	(segment
		(start 201.820272 -34.047938)
		(end 201.820272 -29.4513)
		(width 0.14224)
		(layer "In4.Cu")
		(net "M_B_DQS_DN<0>")
	)
	(segment
		(start 230.326438 -65.453514)
		(end 230.083868 -65.210944)
		(width 0.14224)
		(layer "In4.Cu")
		(net "M_B_DQS_DN<0>")
	)
	(segment
		(start 228.387656 -63.676276)
		(end 228.387656 -63.514732)
		(width 0.14224)
		(layer "In4.Cu")
		(net "M_B_DQS_DN<0>")
	)
	(segment
		(start 229.680008 -64.968628)
		(end 229.680008 -64.807084)
		(width 0.14224)
		(layer "In4.Cu")
		(net "M_B_DQS_DN<0>")
	)
	(segment
		(start 201.037952 -13.287756)
		(end 201.84872 -12.476988)
		(width 0.14224)
		(layer "In4.Cu")
		(net "M_B_DQS_DN<0>")
	)
	(segment
		(start 201.820272 -35.882072)
		(end 201.442066 -35.503866)
		(width 0.14224)
		(layer "In4.Cu")
		(net "M_B_DQS_DN<0>")
	)
	(segment
		(start 201.501756 -13.75156)
		(end 201.037952 -13.287756)
		(width 0.14224)
		(layer "In4.Cu")
		(net "M_B_DQS_DN<0>")
	)
	(segment
		(start 201.054208 -34.426906)
		(end 201.441304 -34.426906)
		(width 0.14224)
		(layer "In4.Cu")
		(net "M_B_DQS_DN<0>")
	)
	(segment
		(start 227.337112 -62.625732)
		(end 226.9998 -62.28842)
		(width 0.14224)
		(layer "In4.Cu")
		(net "M_B_DQS_DN<0>")
	)
	(segment
		(start 230.326438 -65.615058)
		(end 230.326438 -65.453514)
		(width 0.14224)
		(layer "In4.Cu")
		(net "M_B_DQS_DN<0>")
	)
	(segment
		(start 201.501756 -14.296644)
		(end 201.501756 -13.75156)
		(width 0.14224)
		(layer "In4.Cu")
		(net "M_B_DQS_DN<0>")
	)
	(segment
		(start 229.033832 -64.160908)
		(end 228.791262 -63.918338)
		(width 0.14224)
		(layer "In4.Cu")
		(net "M_B_DQS_DN<0>")
	)
	(segment
		(start 201.84872 -12.476988)
		(end 201.84872 -8.567928)
		(width 0.14224)
		(layer "In4.Cu")
		(net "M_B_DQS_DN<0>")
	)
	(segment
		(start 227.983542 -63.272162)
		(end 227.741226 -63.029846)
		(width 0.14224)
		(layer "In4.Cu")
		(net "M_B_DQS_DN<0>")
	)
	(segment
		(start 201.247502 -37.099748)
		(end 201.247502 -36.920424)
		(width 0.14224)
		(layer "In4.Cu")
		(net "M_B_DQS_DN<0>")
	)
	(segment
		(start 202.2475 -25.128728)
		(end 201.820272 -24.7015)
		(width 0.14224)
		(layer "In4.Cu")
		(net "M_B_DQS_DN<0>")
	)
	(segment
		(start 202.1713 -29.100272)
		(end 202.1713 -27.935428)
		(width 0.14224)
		(layer "In4.Cu")
		(net "M_B_DQS_DN<0>")
	)
	(segment
		(start 201.820272 -26.436828)
		(end 202.2475 -26.0096)
		(width 0.14224)
		(layer "In4.Cu")
		(net "M_B_DQS_DN<0>")
	)
	(segment
		(start 202.2475 -26.0096)
		(end 202.2475 -25.128728)
		(width 0.14224)
		(layer "In4.Cu")
		(net "M_B_DQS_DN<0>")
	)
	(segment
		(start 201.820272 -27.5844)
		(end 201.820272 -26.436828)
		(width 0.14224)
		(layer "In4.Cu")
		(net "M_B_DQS_DN<0>")
	)
	(segment
		(start 228.629718 -63.918338)
		(end 228.387656 -63.676276)
		(width 0.14224)
		(layer "In4.Cu")
		(net "M_B_DQS_DN<0>")
	)
	(segment
		(start 230.5685 -65.85712)
		(end 230.326438 -65.615058)
		(width 0.14224)
		(layer "In4.Cu")
		(net "M_B_DQS_DN<0>")
	)
	(segment
		(start 236.485684 -66.391536)
		(end 236.452918 -66.391536)
		(width 0.0889)
		(layer "In4.Cu")
		(net "M_B_DQS_DN<0>")
	)
	(segment
		(start 229.033832 -64.322452)
		(end 229.033832 -64.160908)
		(width 0.14224)
		(layer "In4.Cu")
		(net "M_B_DQS_DN<0>")
	)
	(segment
		(start 231.486202 -65.85712)
		(end 230.5685 -65.85712)
		(width 0.14224)
		(layer "In4.Cu")
		(net "M_B_DQS_DN<0>")
	)
	(arc
		(start 237.307628 -65.89649)
		(mid 237.024411 -65.980771)
		(end 236.817408 -66.191638)
		(width 0.0889)
		(layer "In4.Cu")
		(net "M_B_DQS_DN<0>")
	)
	(arc
		(start 233.883962 -66.88709)
		(mid 233.690112 -66.83074)
		(end 233.548428 -66.686938)
		(width 0.0889)
		(layer "In4.Cu")
		(net "M_B_DQS_DN<0>")
	)
	(arc
		(start 232.86974 -66.391536)
		(mid 232.744539 -66.311765)
		(end 232.653586 -66.194432)
		(width 0.0889)
		(layer "In4.Cu")
		(net "M_B_DQS_DN<0>")
	)
	(arc
		(start 235.958888 -66.686938)
		(mid 235.817205 -66.830742)
		(end 235.623354 -66.88709)
		(width 0.0889)
		(layer "In4.Cu")
		(net "M_B_DQS_DN<0>")
	)
	(arc
		(start 234.406948 -67.182238)
		(mid 234.199944 -66.971374)
		(end 233.916728 -66.88709)
		(width 0.0889)
		(layer "In4.Cu")
		(net "M_B_DQS_DN<0>")
	)
	(arc
		(start 232.653586 -66.194432)
		(mid 232.507661 -66.012345)
		(end 232.305098 -65.89649)
		(width 0.0889)
		(layer "In4.Cu")
		(net "M_B_DQS_DN<0>")
	)
	(arc
		(start 237.805214 -66.13652)
		(mid 237.605469 -65.964526)
		(end 237.350808 -65.89649)
		(width 0.0889)
		(layer "In4.Cu")
		(net "M_B_DQS_DN<0>")
	)
	(arc
		(start 236.452918 -66.391536)
		(mid 236.167494 -66.475003)
		(end 235.958888 -66.686938)
		(width 0.0889)
		(layer "In4.Cu")
		(net "M_B_DQS_DN<0>")
	)
	(arc
		(start 235.100368 -67.182238)
		(mid 234.960289 -67.324974)
		(end 234.768644 -67.382136)
		(width 0.0889)
		(layer "In4.Cu")
		(net "M_B_DQS_DN<0>")
	)
	(arc
		(start 236.817408 -66.191638)
		(mid 236.677329 -66.334374)
		(end 236.485684 -66.391536)
		(width 0.0889)
		(layer "In4.Cu")
		(net "M_B_DQS_DN<0>")
	)
	(arc
		(start 235.590588 -66.88709)
		(mid 235.307371 -66.971371)
		(end 235.100368 -67.182238)
		(width 0.0889)
		(layer "In4.Cu")
		(net "M_B_DQS_DN<0>")
	)
	(arc
		(start 234.738672 -67.382136)
		(mid 234.54703 -67.32497)
		(end 234.406948 -67.182238)
		(width 0.0889)
		(layer "In4.Cu")
		(net "M_B_DQS_DN<0>")
	)
	(arc
		(start 233.548428 -66.686938)
		(mid 233.33982 -66.475006)
		(end 233.054398 -66.391536)
		(width 0.0889)
		(layer "In4.Cu")
		(net "M_B_DQS_DN<0>")
	)
	(segment
		(start 207.450436 -5.822442)
		(end 207.449928 -5.822442)
		(width 0.1651)
		(layer "F.Cu")
		(net "M_B_DQ<9>")
	)
	(segment
		(start 207.449928 -5.822442)
		(end 207.449928 -7.086346)
		(width 0.1651)
		(layer "F.Cu")
		(net "M_B_DQ<9>")
	)
	(segment
		(start 238.759238 -62.029086)
		(end 238.187738 -62.029086)
		(width 0.1016)
		(layer "F.Cu")
		(net "M_B_DQ<9>")
	)
	(via
		(at 208.122012 -12.678156)
		(size 0.508)
		(drill 0.254)
		(layers "F.Cu" "B.Cu")
		(net "M_B_DQ<9>")
	)
	(via
		(at 238.187738 -62.029086)
		(size 0.508)
		(drill 0.254)
		(layers "F.Cu" "B.Cu")
		(net "M_B_DQ<9>")
	)
	(via
		(at 207.449928 -7.086346)
		(size 0.508)
		(drill 0.254)
		(layers "F.Cu" "B.Cu")
		(net "M_B_DQ<9>")
	)
	(segment
		(start 208.122012 -12.147042)
		(end 208.122012 -12.678156)
		(width 0.1651)
		(layer "B.Cu")
		(net "M_B_DQ<9>")
	)
	(segment
		(start 208.30032 -10.623042)
		(end 208.299812 -10.623042)
		(width 0.1651)
		(layer "B.Cu")
		(net "M_B_DQ<9>")
	)
	(segment
		(start 208.299812 -10.623042)
		(end 208.299812 -11.969242)
		(width 0.1651)
		(layer "B.Cu")
		(net "M_B_DQ<9>")
	)
	(segment
		(start 208.299812 -11.969242)
		(end 208.122012 -12.147042)
		(width 0.1651)
		(layer "B.Cu")
		(net "M_B_DQ<9>")
	)
	(segment
		(start 211.4931 -34.163254)
		(end 211.246212 -33.916366)
		(width 0.14224)
		(layer "In4.Cu")
		(net "M_B_DQ<9>")
	)
	(segment
		(start 210.532472 -34.192464)
		(end 210.282536 -33.942528)
		(width 0.14224)
		(layer "In4.Cu")
		(net "M_B_DQ<9>")
	)
	(segment
		(start 208.915 -26.5684)
		(end 208.915 -24.425656)
		(width 0.14224)
		(layer "In4.Cu")
		(net "M_B_DQ<9>")
	)
	(segment
		(start 211.4931 -37.6301)
		(end 211.4931 -34.163254)
		(width 0.14224)
		(layer "In4.Cu")
		(net "M_B_DQ<9>")
	)
	(segment
		(start 231.69245 -58.99785)
		(end 229.2223 -56.5277)
		(width 0.14224)
		(layer "In4.Cu")
		(net "M_B_DQ<9>")
	)
	(segment
		(start 232.301288 -59.40425)
		(end 231.894888 -58.99785)
		(width 0.14224)
		(layer "In4.Cu")
		(net "M_B_DQ<9>")
	)
	(segment
		(start 232.534206 -59.979306)
		(end 232.301288 -59.746388)
		(width 0.0889)
		(layer "In4.Cu")
		(net "M_B_DQ<9>")
	)
	(segment
		(start 210.282536 -33.72358)
		(end 210.55838 -33.447482)
		(width 0.14224)
		(layer "In4.Cu")
		(net "M_B_DQ<9>")
	)
	(segment
		(start 236.736636 -62.691518)
		(end 236.589824 -62.619636)
		(width 0.0889)
		(layer "In4.Cu")
		(net "M_B_DQ<9>")
	)
	(segment
		(start 208.282794 -8.1026)
		(end 207.927194 -8.1026)
		(width 0.14224)
		(layer "In4.Cu")
		(net "M_B_DQ<9>")
	)
	(segment
		(start 207.645 -13.512546)
		(end 207.645 -13.155168)
		(width 0.14224)
		(layer "In4.Cu")
		(net "M_B_DQ<9>")
	)
	(segment
		(start 211.027264 -33.916366)
		(end 210.75142 -34.192464)
		(width 0.14224)
		(layer "In4.Cu")
		(net "M_B_DQ<9>")
	)
	(segment
		(start 232.301288 -59.746388)
		(end 232.301288 -59.40425)
		(width 0.0889)
		(layer "In4.Cu")
		(net "M_B_DQ<9>")
	)
	(segment
		(start 235.340144 -63.221616)
		(end 235.281216 -63.280544)
		(width 0.0889)
		(layer "In4.Cu")
		(net "M_B_DQ<9>")
	)
	(segment
		(start 208.496154 -8.970264)
		(end 208.652618 -8.8138)
		(width 0.14224)
		(layer "In4.Cu")
		(net "M_B_DQ<9>")
	)
	(segment
		(start 232.685082 -60.847224)
		(end 232.689908 -60.838588)
		(width 0.0889)
		(layer "In4.Cu")
		(net "M_B_DQ<9>")
	)
	(segment
		(start 233.916728 -62.92469)
		(end 233.883962 -62.92469)
		(width 0.0889)
		(layer "In4.Cu")
		(net "M_B_DQ<9>")
	)
	(segment
		(start 208.609946 -23.612856)
		(end 208.609946 -16.069564)
		(width 0.14224)
		(layer "In4.Cu")
		(net "M_B_DQ<9>")
	)
	(segment
		(start 237.340394 -62.92469)
		(end 237.251494 -62.92469)
		(width 0.0889)
		(layer "In4.Cu")
		(net "M_B_DQ<9>")
	)
	(segment
		(start 208.652618 -8.8138)
		(end 208.652618 -8.472424)
		(width 0.14224)
		(layer "In4.Cu")
		(net "M_B_DQ<9>")
	)
	(segment
		(start 210.75142 -34.192464)
		(end 210.532472 -34.192464)
		(width 0.14224)
		(layer "In4.Cu")
		(net "M_B_DQ<9>")
	)
	(segment
		(start 210.282536 -33.942528)
		(end 210.282536 -33.72358)
		(width 0.14224)
		(layer "In4.Cu")
		(net "M_B_DQ<9>")
	)
	(segment
		(start 208.915 -24.425656)
		(end 208.609946 -23.612856)
		(width 0.14224)
		(layer "In4.Cu")
		(net "M_B_DQ<9>")
	)
	(segment
		(start 209.55 -27.2034)
		(end 208.915 -26.5684)
		(width 0.14224)
		(layer "In4.Cu")
		(net "M_B_DQ<9>")
	)
	(segment
		(start 209.55 -32.220154)
		(end 209.55 -27.2034)
		(width 0.14224)
		(layer "In4.Cu")
		(net "M_B_DQ<9>")
	)
	(segment
		(start 237.692692 -62.695074)
		(end 237.675928 -62.724538)
		(width 0.0889)
		(layer "In4.Cu")
		(net "M_B_DQ<9>")
	)
	(segment
		(start 207.645 -13.155168)
		(end 208.122012 -12.678156)
		(width 0.14224)
		(layer "In4.Cu")
		(net "M_B_DQ<9>")
	)
	(segment
		(start 207.927194 -8.1026)
		(end 207.449928 -7.625334)
		(width 0.14224)
		(layer "In4.Cu")
		(net "M_B_DQ<9>")
	)
	(segment
		(start 229.2223 -55.3593)
		(end 211.4931 -37.6301)
		(width 0.14224)
		(layer "In4.Cu")
		(net "M_B_DQ<9>")
	)
	(segment
		(start 238.187738 -62.029086)
		(end 237.692692 -62.695074)
		(width 0.0889)
		(layer "In4.Cu")
		(net "M_B_DQ<9>")
	)
	(segment
		(start 207.974946 -13.842492)
		(end 207.645 -13.512546)
		(width 0.14224)
		(layer "In4.Cu")
		(net "M_B_DQ<9>")
	)
	(segment
		(start 210.55838 -33.447482)
		(end 210.55838 -33.228534)
		(width 0.14224)
		(layer "In4.Cu")
		(net "M_B_DQ<9>")
	)
	(segment
		(start 235.629958 -63.11519)
		(end 235.597192 -63.11519)
		(width 0.0889)
		(layer "In4.Cu")
		(net "M_B_DQ<9>")
	)
	(segment
		(start 232.689908 -60.838588)
		(end 232.696258 -60.82792)
		(width 0.0889)
		(layer "In4.Cu")
		(net "M_B_DQ<9>")
	)
	(segment
		(start 211.246212 -33.916366)
		(end 211.027264 -33.916366)
		(width 0.14224)
		(layer "In4.Cu")
		(net "M_B_DQ<9>")
	)
	(segment
		(start 207.974946 -15.434564)
		(end 207.974946 -13.842492)
		(width 0.14224)
		(layer "In4.Cu")
		(net "M_B_DQ<9>")
	)
	(segment
		(start 233.054398 -62.429136)
		(end 233.021632 -62.429136)
		(width 0.0889)
		(layer "In4.Cu")
		(net "M_B_DQ<9>")
	)
	(segment
		(start 208.652618 -8.472424)
		(end 208.282794 -8.1026)
		(width 0.14224)
		(layer "In4.Cu")
		(net "M_B_DQ<9>")
	)
	(segment
		(start 210.55838 -33.228534)
		(end 209.55 -32.220154)
		(width 0.14224)
		(layer "In4.Cu")
		(net "M_B_DQ<9>")
	)
	(segment
		(start 232.685082 -61.837824)
		(end 232.689908 -61.829188)
		(width 0.0889)
		(layer "In4.Cu")
		(net "M_B_DQ<9>")
	)
	(segment
		(start 208.122012 -12.678156)
		(end 208.496154 -12.304014)
		(width 0.14224)
		(layer "In4.Cu")
		(net "M_B_DQ<9>")
	)
	(segment
		(start 208.609946 -16.069564)
		(end 207.974946 -15.434564)
		(width 0.14224)
		(layer "In4.Cu")
		(net "M_B_DQ<9>")
	)
	(segment
		(start 229.2223 -56.5277)
		(end 229.2223 -55.3593)
		(width 0.14224)
		(layer "In4.Cu")
		(net "M_B_DQ<9>")
	)
	(segment
		(start 236.589824 -62.619636)
		(end 236.459522 -62.619636)
		(width 0.0889)
		(layer "In4.Cu")
		(net "M_B_DQ<9>")
	)
	(segment
		(start 231.894888 -58.99785)
		(end 231.69245 -58.99785)
		(width 0.14224)
		(layer "In4.Cu")
		(net "M_B_DQ<9>")
	)
	(segment
		(start 234.945174 -63.419736)
		(end 234.738672 -63.419736)
		(width 0.0889)
		(layer "In4.Cu")
		(net "M_B_DQ<9>")
	)
	(segment
		(start 208.496154 -12.304014)
		(end 208.496154 -8.970264)
		(width 0.14224)
		(layer "In4.Cu")
		(net "M_B_DQ<9>")
	)
	(segment
		(start 207.449928 -7.625334)
		(end 207.449928 -7.086346)
		(width 0.14224)
		(layer "In4.Cu")
		(net "M_B_DQ<9>")
	)
	(segment
		(start 237.134654 -62.904624)
		(end 236.736636 -62.691518)
		(width 0.0889)
		(layer "In4.Cu")
		(net "M_B_DQ<9>")
	)
	(segment
		(start 232.689908 -60.248038)
		(end 232.6894 -60.248292)
		(width 0.0889)
		(layer "In4.Cu")
		(net "M_B_DQ<9>")
	)
	(segment
		(start 232.689908 -61.829188)
		(end 232.696258 -61.81852)
		(width 0.0889)
		(layer "In4.Cu")
		(net "M_B_DQ<9>")
	)
	(segment
		(start 232.6894 -60.248292)
		(end 232.534206 -59.979306)
		(width 0.0889)
		(layer "In4.Cu")
		(net "M_B_DQ<9>")
	)
	(arc
		(start 237.251494 -62.92469)
		(mid 237.192224 -62.91961)
		(end 237.134654 -62.904624)
		(width 0.0889)
		(layer "In4.Cu")
		(net "M_B_DQ<9>")
	)
	(arc
		(start 235.597192 -63.11519)
		(mid 235.459109 -63.145329)
		(end 235.340144 -63.221616)
		(width 0.0889)
		(layer "In4.Cu")
		(net "M_B_DQ<9>")
	)
	(arc
		(start 236.123988 -62.819788)
		(mid 235.91538 -63.03172)
		(end 235.629958 -63.11519)
		(width 0.0889)
		(layer "In4.Cu")
		(net "M_B_DQ<9>")
	)
	(arc
		(start 234.406948 -63.219838)
		(mid 234.199944 -63.008974)
		(end 233.916728 -62.92469)
		(width 0.0889)
		(layer "In4.Cu")
		(net "M_B_DQ<9>")
	)
	(arc
		(start 232.696258 -61.81852)
		(mid 232.769056 -61.527757)
		(end 232.689908 -61.238638)
		(width 0.0889)
		(layer "In4.Cu")
		(net "M_B_DQ<9>")
	)
	(arc
		(start 232.689908 -61.238638)
		(mid 232.636438 -61.043575)
		(end 232.685082 -60.847224)
		(width 0.0889)
		(layer "In4.Cu")
		(net "M_B_DQ<9>")
	)
	(arc
		(start 237.675928 -62.724538)
		(mid 237.534245 -62.868342)
		(end 237.340394 -62.92469)
		(width 0.0889)
		(layer "In4.Cu")
		(net "M_B_DQ<9>")
	)
	(arc
		(start 236.459522 -62.619636)
		(mid 236.265672 -62.675986)
		(end 236.123988 -62.819788)
		(width 0.0889)
		(layer "In4.Cu")
		(net "M_B_DQ<9>")
	)
	(arc
		(start 232.696258 -60.82792)
		(mid 232.769056 -60.537157)
		(end 232.689908 -60.248038)
		(width 0.0889)
		(layer "In4.Cu")
		(net "M_B_DQ<9>")
	)
	(arc
		(start 233.021632 -62.429136)
		(mid 232.688714 -62.227145)
		(end 232.685082 -61.837824)
		(width 0.0889)
		(layer "In4.Cu")
		(net "M_B_DQ<9>")
	)
	(arc
		(start 234.738672 -63.419736)
		(mid 234.54703 -63.36257)
		(end 234.406948 -63.219838)
		(width 0.0889)
		(layer "In4.Cu")
		(net "M_B_DQ<9>")
	)
	(arc
		(start 235.281216 -63.280544)
		(mid 235.127039 -63.383562)
		(end 234.945174 -63.419736)
		(width 0.0889)
		(layer "In4.Cu")
		(net "M_B_DQ<9>")
	)
	(arc
		(start 233.883962 -62.92469)
		(mid 233.690112 -62.86834)
		(end 233.548428 -62.724538)
		(width 0.0889)
		(layer "In4.Cu")
		(net "M_B_DQ<9>")
	)
	(arc
		(start 233.548428 -62.724538)
		(mid 233.33982 -62.512606)
		(end 233.054398 -62.429136)
		(width 0.0889)
		(layer "In4.Cu")
		(net "M_B_DQ<9>")
	)
	(segment
		(start 208.299812 -10.422382)
		(end 208.141316 -8.763)
		(width 0.1651)
		(layer "F.Cu")
		(net "M_B_DQ<8>")
	)
	(segment
		(start 208.30032 -10.422382)
		(end 208.299812 -10.422382)
		(width 0.1651)
		(layer "F.Cu")
		(net "M_B_DQ<8>")
	)
	(segment
		(start 208.141316 -8.763)
		(end 208.122012 -8.5598)
		(width 0.1651)
		(layer "F.Cu")
		(net "M_B_DQ<8>")
	)
	(segment
		(start 237.042198 -63.019686)
		(end 236.470698 -63.019686)
		(width 0.1016)
		(layer "F.Cu")
		(net "M_B_DQ<8>")
	)
	(via
		(at 207.449928 -13.959078)
		(size 0.508)
		(drill 0.254)
		(layers "F.Cu" "B.Cu")
		(net "M_B_DQ<8>")
	)
	(via
		(at 208.122012 -8.5598)
		(size 0.508)
		(drill 0.254)
		(layers "F.Cu" "B.Cu")
		(net "M_B_DQ<8>")
	)
	(via
		(at 236.470698 -63.019686)
		(size 0.508)
		(drill 0.254)
		(layers "F.Cu" "B.Cu")
		(net "M_B_DQ<8>")
	)
	(segment
		(start 207.449928 -15.222982)
		(end 207.449928 -13.959078)
		(width 0.1651)
		(layer "B.Cu")
		(net "M_B_DQ<8>")
	)
	(segment
		(start 207.450436 -15.222982)
		(end 207.449928 -15.222982)
		(width 0.1651)
		(layer "B.Cu")
		(net "M_B_DQ<8>")
	)
	(segment
		(start 233.015028 -62.619636)
		(end 233.047794 -62.619636)
		(width 0.0889)
		(layer "In4.Cu")
		(net "M_B_DQ<8>")
	)
	(segment
		(start 207.924146 -16.827754)
		(end 207.632046 -17.119854)
		(width 0.14224)
		(layer "In4.Cu")
		(net "M_B_DQ<8>")
	)
	(segment
		(start 207.901794 -8.780018)
		(end 207.901794 -9.364472)
		(width 0.14224)
		(layer "In4.Cu")
		(net "M_B_DQ<8>")
	)
	(segment
		(start 209.7278 -34.8234)
		(end 210.82 -34.8234)
		(width 0.14224)
		(layer "In4.Cu")
		(net "M_B_DQ<8>")
	)
	(segment
		(start 207.632046 -23.113492)
		(end 207.97266 -23.454106)
		(width 0.14224)
		(layer "In4.Cu")
		(net "M_B_DQ<8>")
	)
	(segment
		(start 210.81746 -36.195)
		(end 210.9724 -36.34994)
		(width 0.14224)
		(layer "In4.Cu")
		(net "M_B_DQ<8>")
	)
	(segment
		(start 207.901794 -9.364472)
		(end 207.487012 -9.779254)
		(width 0.14224)
		(layer "In4.Cu")
		(net "M_B_DQ<8>")
	)
	(segment
		(start 209.5627 -36.04006)
		(end 209.71764 -36.195)
		(width 0.14224)
		(layer "In4.Cu")
		(net "M_B_DQ<8>")
	)
	(segment
		(start 231.56926 -59.573922)
		(end 232.037128 -60.04179)
		(width 0.14224)
		(layer "In4.Cu")
		(net "M_B_DQ<8>")
	)
	(segment
		(start 207.632046 -17.119854)
		(end 207.632046 -18.325846)
		(width 0.14224)
		(layer "In4.Cu")
		(net "M_B_DQ<8>")
	)
	(segment
		(start 209.5627 -35.62604)
		(end 209.5627 -36.04006)
		(width 0.14224)
		(layer "In4.Cu")
		(net "M_B_DQ<8>")
	)
	(segment
		(start 232.529634 -60.734702)
		(end 232.524808 -60.743338)
		(width 0.0889)
		(layer "In4.Cu")
		(net "M_B_DQ<8>")
	)
	(segment
		(start 208.28 -27.0256)
		(end 208.915 -27.6606)
		(width 0.14224)
		(layer "In4.Cu")
		(net "M_B_DQ<8>")
	)
	(segment
		(start 207.97266 -23.454106)
		(end 207.97266 -24.12746)
		(width 0.14224)
		(layer "In4.Cu")
		(net "M_B_DQ<8>")
	)
	(segment
		(start 208.122012 -8.5598)
		(end 207.901794 -8.780018)
		(width 0.14224)
		(layer "In4.Cu")
		(net "M_B_DQ<8>")
	)
	(segment
		(start 232.529634 -61.725302)
		(end 232.524808 -61.733938)
		(width 0.0889)
		(layer "In4.Cu")
		(net "M_B_DQ<8>")
	)
	(segment
		(start 207.901794 -12.192)
		(end 207.165194 -12.9286)
		(width 0.14224)
		(layer "In4.Cu")
		(net "M_B_DQ<8>")
	)
	(segment
		(start 232.524808 -61.733938)
		(end 232.518458 -61.744606)
		(width 0.0889)
		(layer "In4.Cu")
		(net "M_B_DQ<8>")
	)
	(segment
		(start 207.449928 -13.959078)
		(end 207.449928 -15.959074)
		(width 0.14224)
		(layer "In4.Cu")
		(net "M_B_DQ<8>")
	)
	(segment
		(start 231.370378 -59.573922)
		(end 231.56926 -59.573922)
		(width 0.14224)
		(layer "In4.Cu")
		(net "M_B_DQ<8>")
	)
	(segment
		(start 207.901794 -11.692128)
		(end 207.901794 -12.192)
		(width 0.14224)
		(layer "In4.Cu")
		(net "M_B_DQ<8>")
	)
	(segment
		(start 235.958888 -63.715138)
		(end 235.975652 -63.685674)
		(width 0.0889)
		(layer "In4.Cu")
		(net "M_B_DQ<8>")
	)
	(segment
		(start 232.037128 -60.04179)
		(end 232.327958 -60.04179)
		(width 0.0889)
		(layer "In4.Cu")
		(net "M_B_DQ<8>")
	)
	(segment
		(start 210.9724 -35.31616)
		(end 210.81746 -35.4711)
		(width 0.14224)
		(layer "In4.Cu")
		(net "M_B_DQ<8>")
	)
	(segment
		(start 209.4611 -34.5567)
		(end 209.7278 -34.8234)
		(width 0.14224)
		(layer "In4.Cu")
		(net "M_B_DQ<8>")
	)
	(segment
		(start 234.732068 -63.610236)
		(end 234.907074 -63.610236)
		(width 0.0889)
		(layer "In4.Cu")
		(net "M_B_DQ<8>")
	)
	(segment
		(start 209.71764 -36.195)
		(end 210.81746 -36.195)
		(width 0.14224)
		(layer "In4.Cu")
		(net "M_B_DQ<8>")
	)
	(segment
		(start 207.974946 -18.668746)
		(end 207.974946 -21.683472)
		(width 0.14224)
		(layer "In4.Cu")
		(net "M_B_DQ<8>")
	)
	(segment
		(start 207.97266 -24.12746)
		(end 208.28 -24.4348)
		(width 0.14224)
		(layer "In4.Cu")
		(net "M_B_DQ<8>")
	)
	(segment
		(start 232.38206 -60.095892)
		(end 232.524808 -60.343288)
		(width 0.0889)
		(layer "In4.Cu")
		(net "M_B_DQ<8>")
	)
	(segment
		(start 209.4611 -33.223454)
		(end 209.4611 -34.5567)
		(width 0.14224)
		(layer "In4.Cu")
		(net "M_B_DQ<8>")
	)
	(segment
		(start 207.829912 -10.4521)
		(end 207.829912 -10.6807)
		(width 0.14224)
		(layer "In4.Cu")
		(net "M_B_DQ<8>")
	)
	(segment
		(start 235.307124 -63.776098)
		(end 235.321602 -63.790322)
		(width 0.0889)
		(layer "In4.Cu")
		(net "M_B_DQ<8>")
	)
	(segment
		(start 228.5873 -55.622444)
		(end 228.5873 -56.790844)
		(width 0.14224)
		(layer "In4.Cu")
		(net "M_B_DQ<8>")
	)
	(segment
		(start 208.915 -27.6606)
		(end 208.915 -32.677354)
		(width 0.14224)
		(layer "In4.Cu")
		(net "M_B_DQ<8>")
	)
	(segment
		(start 207.632046 -18.325846)
		(end 207.974946 -18.668746)
		(width 0.14224)
		(layer "In4.Cu")
		(net "M_B_DQ<8>")
	)
	(segment
		(start 207.974946 -21.683472)
		(end 207.632046 -22.026372)
		(width 0.14224)
		(layer "In4.Cu")
		(net "M_B_DQ<8>")
	)
	(segment
		(start 209.71764 -35.4711)
		(end 209.5627 -35.62604)
		(width 0.14224)
		(layer "In4.Cu")
		(net "M_B_DQ<8>")
	)
	(segment
		(start 208.28 -24.4348)
		(end 208.28 -27.0256)
		(width 0.14224)
		(layer "In4.Cu")
		(net "M_B_DQ<8>")
	)
	(segment
		(start 207.829912 -10.6807)
		(end 207.512412 -10.9982)
		(width 0.14224)
		(layer "In4.Cu")
		(net "M_B_DQ<8>")
	)
	(segment
		(start 232.524808 -60.743338)
		(end 232.518458 -60.754006)
		(width 0.0889)
		(layer "In4.Cu")
		(net "M_B_DQ<8>")
	)
	(segment
		(start 232.327958 -60.04179)
		(end 232.38206 -60.095892)
		(width 0.0889)
		(layer "In4.Cu")
		(net "M_B_DQ<8>")
	)
	(segment
		(start 210.9724 -38.007544)
		(end 228.5873 -55.622444)
		(width 0.14224)
		(layer "In4.Cu")
		(net "M_B_DQ<8>")
	)
	(segment
		(start 208.915 -32.677354)
		(end 209.4611 -33.223454)
		(width 0.14224)
		(layer "In4.Cu")
		(net "M_B_DQ<8>")
	)
	(segment
		(start 207.924146 -16.433292)
		(end 207.924146 -16.827754)
		(width 0.14224)
		(layer "In4.Cu")
		(net "M_B_DQ<8>")
	)
	(segment
		(start 207.632046 -22.026372)
		(end 207.632046 -23.113492)
		(width 0.14224)
		(layer "In4.Cu")
		(net "M_B_DQ<8>")
	)
	(segment
		(start 210.82 -34.8234)
		(end 210.9724 -34.9758)
		(width 0.14224)
		(layer "In4.Cu")
		(net "M_B_DQ<8>")
	)
	(segment
		(start 210.9724 -34.9758)
		(end 210.9724 -35.31616)
		(width 0.14224)
		(layer "In4.Cu")
		(net "M_B_DQ<8>")
	)
	(segment
		(start 207.165194 -13.674344)
		(end 207.449928 -13.959078)
		(width 0.14224)
		(layer "In4.Cu")
		(net "M_B_DQ<8>")
	)
	(segment
		(start 233.877358 -63.11519)
		(end 233.910124 -63.11519)
		(width 0.0889)
		(layer "In4.Cu")
		(net "M_B_DQ<8>")
	)
	(segment
		(start 228.5873 -56.790844)
		(end 231.370378 -59.573922)
		(width 0.14224)
		(layer "In4.Cu")
		(net "M_B_DQ<8>")
	)
	(segment
		(start 207.449928 -15.959074)
		(end 207.924146 -16.433292)
		(width 0.14224)
		(layer "In4.Cu")
		(net "M_B_DQ<8>")
	)
	(segment
		(start 207.487012 -9.779254)
		(end 207.487012 -10.1092)
		(width 0.14224)
		(layer "In4.Cu")
		(net "M_B_DQ<8>")
	)
	(segment
		(start 235.975652 -63.685674)
		(end 236.470698 -63.019686)
		(width 0.0889)
		(layer "In4.Cu")
		(net "M_B_DQ<8>")
	)
	(segment
		(start 207.165194 -12.9286)
		(end 207.165194 -13.674344)
		(width 0.14224)
		(layer "In4.Cu")
		(net "M_B_DQ<8>")
	)
	(segment
		(start 207.512412 -10.9982)
		(end 207.512412 -11.302746)
		(width 0.14224)
		(layer "In4.Cu")
		(net "M_B_DQ<8>")
	)
	(segment
		(start 207.487012 -10.1092)
		(end 207.829912 -10.4521)
		(width 0.14224)
		(layer "In4.Cu")
		(net "M_B_DQ<8>")
	)
	(segment
		(start 210.81746 -35.4711)
		(end 209.71764 -35.4711)
		(width 0.14224)
		(layer "In4.Cu")
		(net "M_B_DQ<8>")
	)
	(segment
		(start 207.512412 -11.302746)
		(end 207.901794 -11.692128)
		(width 0.14224)
		(layer "In4.Cu")
		(net "M_B_DQ<8>")
	)
	(segment
		(start 210.9724 -36.34994)
		(end 210.9724 -38.007544)
		(width 0.14224)
		(layer "In4.Cu")
		(net "M_B_DQ<8>")
	)
	(arc
		(start 232.524808 -60.343288)
		(mid 232.578278 -60.538351)
		(end 232.529634 -60.734702)
		(width 0.0889)
		(layer "In4.Cu")
		(net "M_B_DQ<8>")
	)
	(arc
		(start 233.047794 -62.619636)
		(mid 233.241644 -62.675986)
		(end 233.383328 -62.819788)
		(width 0.0889)
		(layer "In4.Cu")
		(net "M_B_DQ<8>")
	)
	(arc
		(start 233.383328 -62.819788)
		(mid 233.591936 -63.03172)
		(end 233.877358 -63.11519)
		(width 0.0889)
		(layer "In4.Cu")
		(net "M_B_DQ<8>")
	)
	(arc
		(start 234.907074 -63.610236)
		(mid 235.123585 -63.653396)
		(end 235.307124 -63.776098)
		(width 0.0889)
		(layer "In4.Cu")
		(net "M_B_DQ<8>")
	)
	(arc
		(start 232.518458 -61.744606)
		(mid 232.522489 -62.320788)
		(end 233.015028 -62.619636)
		(width 0.0889)
		(layer "In4.Cu")
		(net "M_B_DQ<8>")
	)
	(arc
		(start 235.321602 -63.790322)
		(mid 235.659087 -63.912611)
		(end 235.958888 -63.715138)
		(width 0.0889)
		(layer "In4.Cu")
		(net "M_B_DQ<8>")
	)
	(arc
		(start 233.910124 -63.11519)
		(mid 234.101766 -63.172356)
		(end 234.241848 -63.315088)
		(width 0.0889)
		(layer "In4.Cu")
		(net "M_B_DQ<8>")
	)
	(arc
		(start 232.518458 -60.754006)
		(mid 232.44566 -61.044769)
		(end 232.524808 -61.333888)
		(width 0.0889)
		(layer "In4.Cu")
		(net "M_B_DQ<8>")
	)
	(arc
		(start 232.524808 -61.333888)
		(mid 232.578278 -61.528951)
		(end 232.529634 -61.725302)
		(width 0.0889)
		(layer "In4.Cu")
		(net "M_B_DQ<8>")
	)
	(arc
		(start 234.241848 -63.315088)
		(mid 234.448852 -63.525952)
		(end 234.732068 -63.610236)
		(width 0.0889)
		(layer "In4.Cu")
		(net "M_B_DQ<8>")
	)
	(segment
		(start 202.35037 -5.822442)
		(end 202.349862 -5.822442)
		(width 0.1651)
		(layer "F.Cu")
		(net "M_B_DQ<7>")
	)
	(segment
		(start 237.900718 -65.49644)
		(end 237.329218 -65.49644)
		(width 0.0889)
		(layer "F.Cu")
		(net "M_B_DQ<7>")
	)
	(segment
		(start 202.349862 -5.822442)
		(end 202.349862 -7.086346)
		(width 0.1651)
		(layer "F.Cu")
		(net "M_B_DQ<7>")
	)
	(via
		(at 237.329218 -65.49644)
		(size 0.508)
		(drill 0.254)
		(layers "F.Cu" "B.Cu")
		(net "M_B_DQ<7>")
	)
	(via
		(at 203.199746 -12.678156)
		(size 0.508)
		(drill 0.254)
		(layers "F.Cu" "B.Cu")
		(net "M_B_DQ<7>")
	)
	(via
		(at 202.349862 -7.086346)
		(size 0.508)
		(drill 0.254)
		(layers "F.Cu" "B.Cu")
		(net "M_B_DQ<7>")
	)
	(segment
		(start 203.200508 -10.623042)
		(end 203.2 -10.623042)
		(width 0.1651)
		(layer "B.Cu")
		(net "M_B_DQ<7>")
	)
	(segment
		(start 203.2 -11.110722)
		(end 203.199746 -11.110976)
		(width 0.1651)
		(layer "B.Cu")
		(net "M_B_DQ<7>")
	)
	(segment
		(start 203.2 -10.623042)
		(end 203.2 -11.110722)
		(width 0.1651)
		(layer "B.Cu")
		(net "M_B_DQ<7>")
	)
	(segment
		(start 203.199746 -11.110976)
		(end 203.199746 -12.678156)
		(width 0.1651)
		(layer "B.Cu")
		(net "M_B_DQ<7>")
	)
	(segment
		(start 202.6666 -7.7216)
		(end 202.9968 -8.0518)
		(width 0.14224)
		(layer "In4.Cu")
		(net "M_B_DQ<7>")
	)
	(segment
		(start 214.571072 -46.635924)
		(end 214.571072 -46.854872)
		(width 0.14224)
		(layer "In4.Cu")
		(net "M_B_DQ<7>")
	)
	(segment
		(start 213.633304 -45.698156)
		(end 213.633304 -45.917104)
		(width 0.14224)
		(layer "In4.Cu")
		(net "M_B_DQ<7>")
	)
	(segment
		(start 202.739752 -13.13815)
		(end 202.739752 -13.603732)
		(width 0.14224)
		(layer "In4.Cu")
		(net "M_B_DQ<7>")
	)
	(segment
		(start 203.108052 -13.972032)
		(end 203.108052 -14.384528)
		(width 0.14224)
		(layer "In4.Cu")
		(net "M_B_DQ<7>")
	)
	(segment
		(start 212.32876 -45.346112)
		(end 212.32876 -45.56506)
		(width 0.14224)
		(layer "In4.Cu")
		(net "M_B_DQ<7>")
	)
	(segment
		(start 236.507782 -65.591436)
		(end 237.329218 -65.49644)
		(width 0.0889)
		(layer "In4.Cu")
		(net "M_B_DQ<7>")
	)
	(segment
		(start 213.266528 -46.28388)
		(end 213.266528 -46.502828)
		(width 0.14224)
		(layer "In4.Cu")
		(net "M_B_DQ<7>")
	)
	(segment
		(start 203.552552 -18.544794)
		(end 203.552552 -21.772372)
		(width 0.14224)
		(layer "In4.Cu")
		(net "M_B_DQ<7>")
	)
	(segment
		(start 202.349862 -7.086346)
		(end 202.6666 -7.403084)
		(width 0.14224)
		(layer "In4.Cu")
		(net "M_B_DQ<7>")
	)
	(segment
		(start 212.695536 -44.760388)
		(end 212.695536 -44.979336)
		(width 0.14224)
		(layer "In4.Cu")
		(net "M_B_DQ<7>")
	)
	(segment
		(start 214.571072 -46.854872)
		(end 214.204296 -47.221648)
		(width 0.14224)
		(layer "In4.Cu")
		(net "M_B_DQ<7>")
	)
	(segment
		(start 214.102188 -46.385988)
		(end 214.321136 -46.385988)
		(width 0.14224)
		(layer "In4.Cu")
		(net "M_B_DQ<7>")
	)
	(segment
		(start 203.552552 -21.772372)
		(end 203.755752 -21.975572)
		(width 0.14224)
		(layer "In4.Cu")
		(net "M_B_DQ<7>")
	)
	(segment
		(start 211.288884 -43.572684)
		(end 211.507832 -43.572684)
		(width 0.14224)
		(layer "In4.Cu")
		(net "M_B_DQ<7>")
	)
	(segment
		(start 211.757768 -44.041568)
		(end 211.390992 -44.408344)
		(width 0.14224)
		(layer "In4.Cu")
		(net "M_B_DQ<7>")
	)
	(segment
		(start 210.922108 -43.93946)
		(end 211.288884 -43.572684)
		(width 0.14224)
		(layer "In4.Cu")
		(net "M_B_DQ<7>")
	)
	(segment
		(start 211.640928 -44.877228)
		(end 211.859876 -44.877228)
		(width 0.14224)
		(layer "In4.Cu")
		(net "M_B_DQ<7>")
	)
	(segment
		(start 203.454 -28.0035)
		(end 203.8477 -28.3972)
		(width 0.14224)
		(layer "In4.Cu")
		(net "M_B_DQ<7>")
	)
	(segment
		(start 211.390992 -44.627292)
		(end 211.640928 -44.877228)
		(width 0.14224)
		(layer "In4.Cu")
		(net "M_B_DQ<7>")
	)
	(segment
		(start 202.6666 -7.403084)
		(end 202.6666 -7.7216)
		(width 0.14224)
		(layer "In4.Cu")
		(net "M_B_DQ<7>")
	)
	(segment
		(start 203.8477 -28.3972)
		(end 203.8477 -35.912552)
		(width 0.14224)
		(layer "In4.Cu")
		(net "M_B_DQ<7>")
	)
	(segment
		(start 215.68156 -47.746412)
		(end 215.68156 -48.21174)
		(width 0.14224)
		(layer "In4.Cu")
		(net "M_B_DQ<7>")
	)
	(segment
		(start 215.68156 -48.21174)
		(end 215.221566 -48.671734)
		(width 0.14224)
		(layer "In4.Cu")
		(net "M_B_DQ<7>")
	)
	(segment
		(start 214.321136 -46.385988)
		(end 214.571072 -46.635924)
		(width 0.14224)
		(layer "In4.Cu")
		(net "M_B_DQ<7>")
	)
	(segment
		(start 235.281724 -66.08699)
		(end 235.629958 -66.08699)
		(width 0.0889)
		(layer "In4.Cu")
		(net "M_B_DQ<7>")
	)
	(segment
		(start 211.390992 -44.408344)
		(end 211.390992 -44.627292)
		(width 0.14224)
		(layer "In4.Cu")
		(net "M_B_DQ<7>")
	)
	(segment
		(start 229.941374 -63.377826)
		(end 231.469438 -64.90589)
		(width 0.0889)
		(layer "In4.Cu")
		(net "M_B_DQ<7>")
	)
	(segment
		(start 210.453224 -43.689524)
		(end 210.70316 -43.93946)
		(width 0.14224)
		(layer "In4.Cu")
		(net "M_B_DQ<7>")
	)
	(segment
		(start 215.221566 -48.671734)
		(end 215.221566 -48.851566)
		(width 0.14224)
		(layer "In4.Cu")
		(net "M_B_DQ<7>")
	)
	(segment
		(start 203.708 -8.8646)
		(end 203.552552 -9.020048)
		(width 0.14224)
		(layer "In4.Cu")
		(net "M_B_DQ<7>")
	)
	(segment
		(start 211.757768 -43.82262)
		(end 211.757768 -44.041568)
		(width 0.14224)
		(layer "In4.Cu")
		(net "M_B_DQ<7>")
	)
	(segment
		(start 215.039956 -47.323756)
		(end 215.258904 -47.323756)
		(width 0.14224)
		(layer "In4.Cu")
		(net "M_B_DQ<7>")
	)
	(segment
		(start 211.507832 -43.572684)
		(end 211.757768 -43.82262)
		(width 0.14224)
		(layer "In4.Cu")
		(net "M_B_DQ<7>")
	)
	(segment
		(start 212.578696 -45.814996)
		(end 212.797644 -45.814996)
		(width 0.14224)
		(layer "In4.Cu")
		(net "M_B_DQ<7>")
	)
	(segment
		(start 215.258904 -47.323756)
		(end 215.68156 -47.746412)
		(width 0.14224)
		(layer "In4.Cu")
		(net "M_B_DQ<7>")
	)
	(segment
		(start 214.204296 -47.221648)
		(end 214.204296 -47.440596)
		(width 0.14224)
		(layer "In4.Cu")
		(net "M_B_DQ<7>")
	)
	(segment
		(start 203.108052 -14.384528)
		(end 203.501752 -14.778228)
		(width 0.14224)
		(layer "In4.Cu")
		(net "M_B_DQ<7>")
	)
	(segment
		(start 222.1484 -53.8607)
		(end 224.824798 -56.537098)
		(width 0.14224)
		(layer "In4.Cu")
		(net "M_B_DQ<7>")
	)
	(segment
		(start 203.755752 -23.118572)
		(end 203.454 -23.420324)
		(width 0.14224)
		(layer "In4.Cu")
		(net "M_B_DQ<7>")
	)
	(segment
		(start 213.633304 -45.917104)
		(end 213.266528 -46.28388)
		(width 0.14224)
		(layer "In4.Cu")
		(net "M_B_DQ<7>")
	)
	(segment
		(start 210.70316 -43.93946)
		(end 210.922108 -43.93946)
		(width 0.14224)
		(layer "In4.Cu")
		(net "M_B_DQ<7>")
	)
	(segment
		(start 203.708 -8.509)
		(end 203.708 -8.8646)
		(width 0.14224)
		(layer "In4.Cu")
		(net "M_B_DQ<7>")
	)
	(segment
		(start 229.941374 -62.993778)
		(end 229.941374 -63.377826)
		(width 0.0889)
		(layer "In4.Cu")
		(net "M_B_DQ<7>")
	)
	(segment
		(start 212.226652 -44.510452)
		(end 212.4456 -44.510452)
		(width 0.14224)
		(layer "In4.Cu")
		(net "M_B_DQ<7>")
	)
	(segment
		(start 211.859876 -44.877228)
		(end 212.226652 -44.510452)
		(width 0.14224)
		(layer "In4.Cu")
		(net "M_B_DQ<7>")
	)
	(segment
		(start 236.459522 -65.591436)
		(end 236.507782 -65.591436)
		(width 0.0889)
		(layer "In4.Cu")
		(net "M_B_DQ<7>")
	)
	(segment
		(start 233.883962 -65.89649)
		(end 233.916728 -65.89649)
		(width 0.0889)
		(layer "In4.Cu")
		(net "M_B_DQ<7>")
	)
	(segment
		(start 210.453224 -43.470576)
		(end 210.453224 -43.689524)
		(width 0.14224)
		(layer "In4.Cu")
		(net "M_B_DQ<7>")
	)
	(segment
		(start 203.552552 -9.020048)
		(end 203.552552 -12.32535)
		(width 0.14224)
		(layer "In4.Cu")
		(net "M_B_DQ<7>")
	)
	(segment
		(start 210.82 -42.884852)
		(end 210.82 -43.1038)
		(width 0.14224)
		(layer "In4.Cu")
		(net "M_B_DQ<7>")
	)
	(segment
		(start 224.824798 -57.877202)
		(end 229.941374 -62.993778)
		(width 0.14224)
		(layer "In4.Cu")
		(net "M_B_DQ<7>")
	)
	(segment
		(start 232.86974 -65.400936)
		(end 233.054398 -65.400936)
		(width 0.0889)
		(layer "In4.Cu")
		(net "M_B_DQ<7>")
	)
	(segment
		(start 203.454 -23.420324)
		(end 203.454 -28.0035)
		(width 0.14224)
		(layer "In4.Cu")
		(net "M_B_DQ<7>")
	)
	(segment
		(start 212.695536 -44.979336)
		(end 212.32876 -45.346112)
		(width 0.14224)
		(layer "In4.Cu")
		(net "M_B_DQ<7>")
	)
	(segment
		(start 210.82 -43.1038)
		(end 210.453224 -43.470576)
		(width 0.14224)
		(layer "In4.Cu")
		(net "M_B_DQ<7>")
	)
	(segment
		(start 212.32876 -45.56506)
		(end 212.578696 -45.814996)
		(width 0.14224)
		(layer "In4.Cu")
		(net "M_B_DQ<7>")
	)
	(segment
		(start 212.797644 -45.814996)
		(end 213.16442 -45.44822)
		(width 0.14224)
		(layer "In4.Cu")
		(net "M_B_DQ<7>")
	)
	(segment
		(start 203.501752 -14.778228)
		(end 203.501752 -16.802862)
		(width 0.14224)
		(layer "In4.Cu")
		(net "M_B_DQ<7>")
	)
	(segment
		(start 203.755752 -21.975572)
		(end 203.755752 -23.118572)
		(width 0.14224)
		(layer "In4.Cu")
		(net "M_B_DQ<7>")
	)
	(segment
		(start 212.4456 -44.510452)
		(end 212.695536 -44.760388)
		(width 0.14224)
		(layer "In4.Cu")
		(net "M_B_DQ<7>")
	)
	(segment
		(start 203.199746 -12.678156)
		(end 202.739752 -13.13815)
		(width 0.14224)
		(layer "In4.Cu")
		(net "M_B_DQ<7>")
	)
	(segment
		(start 203.2508 -8.0518)
		(end 203.708 -8.509)
		(width 0.14224)
		(layer "In4.Cu")
		(net "M_B_DQ<7>")
	)
	(segment
		(start 231.469438 -64.90589)
		(end 232.305098 -64.90589)
		(width 0.0889)
		(layer "In4.Cu")
		(net "M_B_DQ<7>")
	)
	(segment
		(start 214.67318 -47.690532)
		(end 215.039956 -47.323756)
		(width 0.14224)
		(layer "In4.Cu")
		(net "M_B_DQ<7>")
	)
	(segment
		(start 202.9968 -8.0518)
		(end 203.2508 -8.0518)
		(width 0.14224)
		(layer "In4.Cu")
		(net "M_B_DQ<7>")
	)
	(segment
		(start 213.516464 -46.752764)
		(end 213.735412 -46.752764)
		(width 0.14224)
		(layer "In4.Cu")
		(net "M_B_DQ<7>")
	)
	(segment
		(start 203.781152 -18.316194)
		(end 203.552552 -18.544794)
		(width 0.14224)
		(layer "In4.Cu")
		(net "M_B_DQ<7>")
	)
	(segment
		(start 224.824798 -56.537098)
		(end 224.824798 -57.877202)
		(width 0.14224)
		(layer "In4.Cu")
		(net "M_B_DQ<7>")
	)
	(segment
		(start 215.221566 -48.851566)
		(end 220.2307 -53.8607)
		(width 0.14224)
		(layer "In4.Cu")
		(net "M_B_DQ<7>")
	)
	(segment
		(start 203.501752 -16.802862)
		(end 203.781152 -17.082262)
		(width 0.14224)
		(layer "In4.Cu")
		(net "M_B_DQ<7>")
	)
	(segment
		(start 214.454232 -47.690532)
		(end 214.67318 -47.690532)
		(width 0.14224)
		(layer "In4.Cu")
		(net "M_B_DQ<7>")
	)
	(segment
		(start 213.266528 -46.502828)
		(end 213.516464 -46.752764)
		(width 0.14224)
		(layer "In4.Cu")
		(net "M_B_DQ<7>")
	)
	(segment
		(start 213.735412 -46.752764)
		(end 214.102188 -46.385988)
		(width 0.14224)
		(layer "In4.Cu")
		(net "M_B_DQ<7>")
	)
	(segment
		(start 234.738672 -66.391536)
		(end 234.768644 -66.391536)
		(width 0.0889)
		(layer "In4.Cu")
		(net "M_B_DQ<7>")
	)
	(segment
		(start 203.552552 -12.32535)
		(end 203.199746 -12.678156)
		(width 0.14224)
		(layer "In4.Cu")
		(net "M_B_DQ<7>")
	)
	(segment
		(start 214.204296 -47.440596)
		(end 214.454232 -47.690532)
		(width 0.14224)
		(layer "In4.Cu")
		(net "M_B_DQ<7>")
	)
	(segment
		(start 213.16442 -45.44822)
		(end 213.383368 -45.44822)
		(width 0.14224)
		(layer "In4.Cu")
		(net "M_B_DQ<7>")
	)
	(segment
		(start 213.383368 -45.44822)
		(end 213.633304 -45.698156)
		(width 0.14224)
		(layer "In4.Cu")
		(net "M_B_DQ<7>")
	)
	(segment
		(start 220.2307 -53.8607)
		(end 222.1484 -53.8607)
		(width 0.14224)
		(layer "In4.Cu")
		(net "M_B_DQ<7>")
	)
	(segment
		(start 203.8477 -35.912552)
		(end 210.82 -42.884852)
		(width 0.14224)
		(layer "In4.Cu")
		(net "M_B_DQ<7>")
	)
	(segment
		(start 203.781152 -17.082262)
		(end 203.781152 -18.316194)
		(width 0.14224)
		(layer "In4.Cu")
		(net "M_B_DQ<7>")
	)
	(segment
		(start 202.739752 -13.603732)
		(end 203.108052 -13.972032)
		(width 0.14224)
		(layer "In4.Cu")
		(net "M_B_DQ<7>")
	)
	(arc
		(start 233.548428 -65.696338)
		(mid 233.690111 -65.840142)
		(end 233.883962 -65.89649)
		(width 0.0889)
		(layer "In4.Cu")
		(net "M_B_DQ<7>")
	)
	(arc
		(start 232.305098 -64.90589)
		(mid 232.507692 -65.021708)
		(end 232.653586 -65.203832)
		(width 0.0889)
		(layer "In4.Cu")
		(net "M_B_DQ<7>")
	)
	(arc
		(start 235.100368 -66.191638)
		(mid 235.177043 -66.115057)
		(end 235.281724 -66.08699)
		(width 0.0889)
		(layer "In4.Cu")
		(net "M_B_DQ<7>")
	)
	(arc
		(start 233.054398 -65.400936)
		(mid 233.339822 -65.484403)
		(end 233.548428 -65.696338)
		(width 0.0889)
		(layer "In4.Cu")
		(net "M_B_DQ<7>")
	)
	(arc
		(start 235.629958 -66.08699)
		(mid 235.915382 -66.003523)
		(end 236.123988 -65.791588)
		(width 0.0889)
		(layer "In4.Cu")
		(net "M_B_DQ<7>")
	)
	(arc
		(start 233.916728 -65.89649)
		(mid 234.199945 -65.980771)
		(end 234.406948 -66.191638)
		(width 0.0889)
		(layer "In4.Cu")
		(net "M_B_DQ<7>")
	)
	(arc
		(start 234.406948 -66.191638)
		(mid 234.547027 -66.334374)
		(end 234.738672 -66.391536)
		(width 0.0889)
		(layer "In4.Cu")
		(net "M_B_DQ<7>")
	)
	(arc
		(start 236.123988 -65.791588)
		(mid 236.265671 -65.647784)
		(end 236.459522 -65.591436)
		(width 0.0889)
		(layer "In4.Cu")
		(net "M_B_DQ<7>")
	)
	(arc
		(start 234.768644 -66.391536)
		(mid 234.960286 -66.33437)
		(end 235.100368 -66.191638)
		(width 0.0889)
		(layer "In4.Cu")
		(net "M_B_DQ<7>")
	)
	(arc
		(start 232.653586 -65.203832)
		(mid 232.74453 -65.321175)
		(end 232.86974 -65.400936)
		(width 0.0889)
		(layer "In4.Cu")
		(net "M_B_DQ<7>")
	)
	(segment
		(start 203.33208 -9.31672)
		(end 203.33208 -9.09828)
		(width 0.1651)
		(layer "F.Cu")
		(net "M_B_DQ<6>")
	)
	(segment
		(start 203.200508 -10.422382)
		(end 203.2 -10.422382)
		(width 0.1651)
		(layer "F.Cu")
		(net "M_B_DQ<6>")
	)
	(segment
		(start 203.2 -8.661654)
		(end 203.199746 -8.6614)
		(width 0.1651)
		(layer "F.Cu")
		(net "M_B_DQ<6>")
	)
	(segment
		(start 203.2 -9.4488)
		(end 203.33208 -9.31672)
		(width 0.1651)
		(layer "F.Cu")
		(net "M_B_DQ<6>")
	)
	(segment
		(start 203.2 -8.9662)
		(end 203.2 -8.661654)
		(width 0.1651)
		(layer "F.Cu")
		(net "M_B_DQ<6>")
	)
	(segment
		(start 203.33208 -9.09828)
		(end 203.2 -8.9662)
		(width 0.1651)
		(layer "F.Cu")
		(net "M_B_DQ<6>")
	)
	(segment
		(start 236.183678 -66.48704)
		(end 235.612178 -66.48704)
		(width 0.0889)
		(layer "F.Cu")
		(net "M_B_DQ<6>")
	)
	(segment
		(start 203.2 -10.422382)
		(end 203.2 -9.4488)
		(width 0.1651)
		(layer "F.Cu")
		(net "M_B_DQ<6>")
	)
	(via
		(at 203.199746 -8.6614)
		(size 0.508)
		(drill 0.254)
		(layers "F.Cu" "B.Cu")
		(net "M_B_DQ<6>")
	)
	(via
		(at 235.612178 -66.48704)
		(size 0.508)
		(drill 0.254)
		(layers "F.Cu" "B.Cu")
		(net "M_B_DQ<6>")
	)
	(via
		(at 202.349862 -13.959078)
		(size 0.508)
		(drill 0.254)
		(layers "F.Cu" "B.Cu")
		(net "M_B_DQ<6>")
	)
	(segment
		(start 202.35037 -15.222982)
		(end 202.349862 -15.222982)
		(width 0.1651)
		(layer "B.Cu")
		(net "M_B_DQ<6>")
	)
	(segment
		(start 202.349862 -15.222982)
		(end 202.349862 -13.959078)
		(width 0.1651)
		(layer "B.Cu")
		(net "M_B_DQ<6>")
	)
	(segment
		(start 202.4253 -33.274254)
		(end 202.4253 -33.627314)
		(width 0.14224)
		(layer "In4.Cu")
		(net "M_B_DQ<6>")
	)
	(segment
		(start 208.077054 -41.258998)
		(end 208.296002 -41.258998)
		(width 0.14224)
		(layer "In4.Cu")
		(net "M_B_DQ<6>")
	)
	(segment
		(start 208.36636 -42.845228)
		(end 209.014822 -42.196766)
		(width 0.14224)
		(layer "In4.Cu")
		(net "M_B_DQ<6>")
	)
	(segment
		(start 209.526886 -42.669714)
		(end 208.916016 -43.280584)
		(width 0.14224)
		(layer "In4.Cu")
		(net "M_B_DQ<6>")
	)
	(segment
		(start 203.3016 -32.964374)
		(end 203.14666 -33.119314)
		(width 0.14224)
		(layer "In4.Cu")
		(net "M_B_DQ<6>")
	)
	(segment
		(start 203.3016 -35.263074)
		(end 203.3016 -36.264596)
		(width 0.14224)
		(layer "In4.Cu")
		(net "M_B_DQ<6>")
	)
	(segment
		(start 202.4253 -32.301434)
		(end 202.58024 -32.456374)
		(width 0.14224)
		(layer "In4.Cu")
		(net "M_B_DQ<6>")
	)
	(segment
		(start 221.915736 -55.871364)
		(end 222.647764 -55.871364)
		(width 0.14224)
		(layer "In4.Cu")
		(net "M_B_DQ<6>")
	)
	(segment
		(start 203.199746 -8.6614)
		(end 202.82535 -9.035796)
		(width 0.14224)
		(layer "In4.Cu")
		(net "M_B_DQ<6>")
	)
	(segment
		(start 220.882972 -54.8386)
		(end 221.915736 -55.871364)
		(width 0.14224)
		(layer "In4.Cu")
		(net "M_B_DQ<6>")
	)
	(segment
		(start 202.714352 -21.975572)
		(end 202.714352 -23.169372)
		(width 0.14224)
		(layer "In4.Cu")
		(net "M_B_DQ<6>")
	)
	(segment
		(start 202.714352 -23.169372)
		(end 202.815952 -23.270972)
		(width 0.14224)
		(layer "In4.Cu")
		(net "M_B_DQ<6>")
	)
	(segment
		(start 208.916016 -43.280584)
		(end 208.916016 -43.460416)
		(width 0.14224)
		(layer "In4.Cu")
		(net "M_B_DQ<6>")
	)
	(segment
		(start 202.815952 -28.381452)
		(end 203.3016 -28.8671)
		(width 0.14224)
		(layer "In4.Cu")
		(net "M_B_DQ<6>")
	)
	(segment
		(start 203.14666 -35.108134)
		(end 203.3016 -35.263074)
		(width 0.14224)
		(layer "In4.Cu")
		(net "M_B_DQ<6>")
	)
	(segment
		(start 202.866752 -15.041372)
		(end 202.866752 -16.840962)
		(width 0.14224)
		(layer "In4.Cu")
		(net "M_B_DQ<6>")
	)
	(segment
		(start 202.461368 -11.378946)
		(end 202.886818 -11.804396)
		(width 0.14224)
		(layer "In4.Cu")
		(net "M_B_DQ<6>")
	)
	(segment
		(start 203.3016 -34.290254)
		(end 203.14666 -34.445194)
		(width 0.14224)
		(layer "In4.Cu")
		(net "M_B_DQ<6>")
	)
	(segment
		(start 203.14666 -30.467554)
		(end 202.58024 -30.467554)
		(width 0.14224)
		(layer "In4.Cu")
		(net "M_B_DQ<6>")
	)
	(segment
		(start 202.58024 -33.782254)
		(end 203.14666 -33.782254)
		(width 0.14224)
		(layer "In4.Cu")
		(net "M_B_DQ<6>")
	)
	(segment
		(start 222.647764 -55.871364)
		(end 223.338136 -56.561736)
		(width 0.14224)
		(layer "In4.Cu")
		(net "M_B_DQ<6>")
	)
	(segment
		(start 220.2942 -54.8386)
		(end 220.882972 -54.8386)
		(width 0.14224)
		(layer "In4.Cu")
		(net "M_B_DQ<6>")
	)
	(segment
		(start 202.4253 -30.622494)
		(end 202.4253 -30.975554)
		(width 0.14224)
		(layer "In4.Cu")
		(net "M_B_DQ<6>")
	)
	(segment
		(start 202.714352 -18.411698)
		(end 202.917552 -18.614898)
		(width 0.14224)
		(layer "In4.Cu")
		(net "M_B_DQ<6>")
	)
	(segment
		(start 202.349862 -14.524482)
		(end 202.866752 -15.041372)
		(width 0.14224)
		(layer "In4.Cu")
		(net "M_B_DQ<6>")
	)
	(segment
		(start 203.3016 -30.312614)
		(end 203.14666 -30.467554)
		(width 0.14224)
		(layer "In4.Cu")
		(net "M_B_DQ<6>")
	)
	(segment
		(start 207.60817 -40.571166)
		(end 207.60817 -40.790114)
		(width 0.14224)
		(layer "In4.Cu")
		(net "M_B_DQ<6>")
	)
	(segment
		(start 208.186528 -42.845228)
		(end 208.36636 -42.845228)
		(width 0.14224)
		(layer "In4.Cu")
		(net "M_B_DQ<6>")
	)
	(segment
		(start 203.14666 -31.793434)
		(end 202.58024 -31.793434)
		(width 0.14224)
		(layer "In4.Cu")
		(net "M_B_DQ<6>")
	)
	(segment
		(start 202.461368 -9.677654)
		(end 202.461368 -9.988296)
		(width 0.14224)
		(layer "In4.Cu")
		(net "M_B_DQ<6>")
	)
	(segment
		(start 208.296002 -41.258998)
		(end 208.545938 -41.508934)
		(width 0.14224)
		(layer "In4.Cu")
		(net "M_B_DQ<6>")
	)
	(segment
		(start 202.886818 -12.156186)
		(end 202.11415 -12.928854)
		(width 0.14224)
		(layer "In4.Cu")
		(net "M_B_DQ<6>")
	)
	(segment
		(start 202.815952 -23.270972)
		(end 202.815952 -28.381452)
		(width 0.14224)
		(layer "In4.Cu")
		(net "M_B_DQ<6>")
	)
	(segment
		(start 231.391206 -65.09639)
		(end 232.268776 -65.09639)
		(width 0.0889)
		(layer "In4.Cu")
		(net "M_B_DQ<6>")
	)
	(segment
		(start 203.14666 -32.456374)
		(end 203.3016 -32.611314)
		(width 0.14224)
		(layer "In4.Cu")
		(net "M_B_DQ<6>")
	)
	(segment
		(start 209.23377 -42.196766)
		(end 209.526886 -42.489882)
		(width 0.14224)
		(layer "In4.Cu")
		(net "M_B_DQ<6>")
	)
	(segment
		(start 203.3016 -31.638494)
		(end 203.14666 -31.793434)
		(width 0.14224)
		(layer "In4.Cu")
		(net "M_B_DQ<6>")
	)
	(segment
		(start 202.917552 -18.614898)
		(end 202.917552 -21.772372)
		(width 0.14224)
		(layer "In4.Cu")
		(net "M_B_DQ<6>")
	)
	(segment
		(start 229.438962 -63.39459)
		(end 229.689406 -63.39459)
		(width 0.0889)
		(layer "In4.Cu")
		(net "M_B_DQ<6>")
	)
	(segment
		(start 202.349862 -13.959078)
		(end 202.349862 -14.524482)
		(width 0.14224)
		(layer "In4.Cu")
		(net "M_B_DQ<6>")
	)
	(segment
		(start 202.461368 -9.988296)
		(end 202.842368 -10.369296)
		(width 0.14224)
		(layer "In4.Cu")
		(net "M_B_DQ<6>")
	)
	(segment
		(start 202.60564 -35.108134)
		(end 203.14666 -35.108134)
		(width 0.14224)
		(layer "In4.Cu")
		(net "M_B_DQ<6>")
	)
	(segment
		(start 202.58024 -32.456374)
		(end 203.14666 -32.456374)
		(width 0.14224)
		(layer "In4.Cu")
		(net "M_B_DQ<6>")
	)
	(segment
		(start 202.58024 -31.130494)
		(end 203.14666 -31.130494)
		(width 0.14224)
		(layer "In4.Cu")
		(net "M_B_DQ<6>")
	)
	(segment
		(start 207.434942 -41.90111)
		(end 208.077054 -41.258998)
		(width 0.14224)
		(layer "In4.Cu")
		(net "M_B_DQ<6>")
	)
	(segment
		(start 203.14666 -33.782254)
		(end 203.3016 -33.937194)
		(width 0.14224)
		(layer "In4.Cu")
		(net "M_B_DQ<6>")
	)
	(segment
		(start 202.461368 -11.093704)
		(end 202.461368 -11.378946)
		(width 0.14224)
		(layer "In4.Cu")
		(net "M_B_DQ<6>")
	)
	(segment
		(start 202.4253 -31.948374)
		(end 202.4253 -32.301434)
		(width 0.14224)
		(layer "In4.Cu")
		(net "M_B_DQ<6>")
	)
	(segment
		(start 202.58024 -30.467554)
		(end 202.4253 -30.622494)
		(width 0.14224)
		(layer "In4.Cu")
		(net "M_B_DQ<6>")
	)
	(segment
		(start 207.897476 -42.556176)
		(end 208.186528 -42.845228)
		(width 0.14224)
		(layer "In4.Cu")
		(net "M_B_DQ<6>")
	)
	(segment
		(start 202.82535 -9.313672)
		(end 202.461368 -9.677654)
		(width 0.14224)
		(layer "In4.Cu")
		(net "M_B_DQ<6>")
	)
	(segment
		(start 209.014822 -42.196766)
		(end 209.23377 -42.196766)
		(width 0.14224)
		(layer "In4.Cu")
		(net "M_B_DQ<6>")
	)
	(segment
		(start 229.689406 -63.39459)
		(end 231.391206 -65.09639)
		(width 0.0889)
		(layer "In4.Cu")
		(net "M_B_DQ<6>")
	)
	(segment
		(start 203.3016 -36.264596)
		(end 207.60817 -40.571166)
		(width 0.14224)
		(layer "In4.Cu")
		(net "M_B_DQ<6>")
	)
	(segment
		(start 207.25511 -41.90111)
		(end 207.434942 -41.90111)
		(width 0.14224)
		(layer "In4.Cu")
		(net "M_B_DQ<6>")
	)
	(segment
		(start 207.897476 -42.376344)
		(end 207.897476 -42.556176)
		(width 0.14224)
		(layer "In4.Cu")
		(net "M_B_DQ<6>")
	)
	(segment
		(start 202.4507 -34.600134)
		(end 202.4507 -34.953194)
		(width 0.14224)
		(layer "In4.Cu")
		(net "M_B_DQ<6>")
	)
	(segment
		(start 202.842368 -10.712704)
		(end 202.461368 -11.093704)
		(width 0.14224)
		(layer "In4.Cu")
		(net "M_B_DQ<6>")
	)
	(segment
		(start 202.11415 -12.928854)
		(end 202.11415 -13.723366)
		(width 0.14224)
		(layer "In4.Cu")
		(net "M_B_DQ<6>")
	)
	(segment
		(start 208.545938 -41.727882)
		(end 207.897476 -42.376344)
		(width 0.14224)
		(layer "In4.Cu")
		(net "M_B_DQ<6>")
	)
	(segment
		(start 202.58024 -31.793434)
		(end 202.4253 -31.948374)
		(width 0.14224)
		(layer "In4.Cu")
		(net "M_B_DQ<6>")
	)
	(segment
		(start 208.916016 -43.460416)
		(end 220.2942 -54.8386)
		(width 0.14224)
		(layer "In4.Cu")
		(net "M_B_DQ<6>")
	)
	(segment
		(start 233.877358 -66.08699)
		(end 233.910124 -66.08699)
		(width 0.0889)
		(layer "In4.Cu")
		(net "M_B_DQ<6>")
	)
	(segment
		(start 207.60817 -40.790114)
		(end 206.966058 -41.432226)
		(width 0.14224)
		(layer "In4.Cu")
		(net "M_B_DQ<6>")
	)
	(segment
		(start 202.4253 -30.975554)
		(end 202.58024 -31.130494)
		(width 0.14224)
		(layer "In4.Cu")
		(net "M_B_DQ<6>")
	)
	(segment
		(start 203.3016 -33.937194)
		(end 203.3016 -34.290254)
		(width 0.14224)
		(layer "In4.Cu")
		(net "M_B_DQ<6>")
	)
	(segment
		(start 206.966058 -41.432226)
		(end 206.966058 -41.612058)
		(width 0.14224)
		(layer "In4.Cu")
		(net "M_B_DQ<6>")
	)
	(segment
		(start 202.4253 -33.627314)
		(end 202.58024 -33.782254)
		(width 0.14224)
		(layer "In4.Cu")
		(net "M_B_DQ<6>")
	)
	(segment
		(start 202.11415 -13.723366)
		(end 202.349862 -13.959078)
		(width 0.14224)
		(layer "In4.Cu")
		(net "M_B_DQ<6>")
	)
	(segment
		(start 203.14666 -34.445194)
		(end 202.60564 -34.445194)
		(width 0.14224)
		(layer "In4.Cu")
		(net "M_B_DQ<6>")
	)
	(segment
		(start 203.3016 -31.285434)
		(end 203.3016 -31.638494)
		(width 0.14224)
		(layer "In4.Cu")
		(net "M_B_DQ<6>")
	)
	(segment
		(start 232.833418 -65.591436)
		(end 233.047794 -65.591436)
		(width 0.0889)
		(layer "In4.Cu")
		(net "M_B_DQ<6>")
	)
	(segment
		(start 208.545938 -41.508934)
		(end 208.545938 -41.727882)
		(width 0.14224)
		(layer "In4.Cu")
		(net "M_B_DQ<6>")
	)
	(segment
		(start 202.4507 -34.953194)
		(end 202.60564 -35.108134)
		(width 0.14224)
		(layer "In4.Cu")
		(net "M_B_DQ<6>")
	)
	(segment
		(start 209.526886 -42.489882)
		(end 209.526886 -42.669714)
		(width 0.14224)
		(layer "In4.Cu")
		(net "M_B_DQ<6>")
	)
	(segment
		(start 234.790742 -66.582036)
		(end 235.612178 -66.48704)
		(width 0.0889)
		(layer "In4.Cu")
		(net "M_B_DQ<6>")
	)
	(segment
		(start 202.714352 -16.993362)
		(end 202.714352 -18.411698)
		(width 0.14224)
		(layer "In4.Cu")
		(net "M_B_DQ<6>")
	)
	(segment
		(start 202.60564 -34.445194)
		(end 202.4507 -34.600134)
		(width 0.14224)
		(layer "In4.Cu")
		(net "M_B_DQ<6>")
	)
	(segment
		(start 223.338136 -57.293764)
		(end 229.438962 -63.39459)
		(width 0.14224)
		(layer "In4.Cu")
		(net "M_B_DQ<6>")
	)
	(segment
		(start 202.58024 -33.119314)
		(end 202.4253 -33.274254)
		(width 0.14224)
		(layer "In4.Cu")
		(net "M_B_DQ<6>")
	)
	(segment
		(start 203.14666 -33.119314)
		(end 202.58024 -33.119314)
		(width 0.14224)
		(layer "In4.Cu")
		(net "M_B_DQ<6>")
	)
	(segment
		(start 202.842368 -10.369296)
		(end 202.842368 -10.712704)
		(width 0.14224)
		(layer "In4.Cu")
		(net "M_B_DQ<6>")
	)
	(segment
		(start 203.3016 -32.611314)
		(end 203.3016 -32.964374)
		(width 0.14224)
		(layer "In4.Cu")
		(net "M_B_DQ<6>")
	)
	(segment
		(start 234.732068 -66.582036)
		(end 234.790742 -66.582036)
		(width 0.0889)
		(layer "In4.Cu")
		(net "M_B_DQ<6>")
	)
	(segment
		(start 202.886818 -11.804396)
		(end 202.886818 -12.156186)
		(width 0.14224)
		(layer "In4.Cu")
		(net "M_B_DQ<6>")
	)
	(segment
		(start 203.3016 -28.8671)
		(end 203.3016 -30.312614)
		(width 0.14224)
		(layer "In4.Cu")
		(net "M_B_DQ<6>")
	)
	(segment
		(start 202.866752 -16.840962)
		(end 202.714352 -16.993362)
		(width 0.14224)
		(layer "In4.Cu")
		(net "M_B_DQ<6>")
	)
	(segment
		(start 202.917552 -21.772372)
		(end 202.714352 -21.975572)
		(width 0.14224)
		(layer "In4.Cu")
		(net "M_B_DQ<6>")
	)
	(segment
		(start 203.14666 -31.130494)
		(end 203.3016 -31.285434)
		(width 0.14224)
		(layer "In4.Cu")
		(net "M_B_DQ<6>")
	)
	(segment
		(start 202.82535 -9.035796)
		(end 202.82535 -9.313672)
		(width 0.14224)
		(layer "In4.Cu")
		(net "M_B_DQ<6>")
	)
	(segment
		(start 206.966058 -41.612058)
		(end 207.25511 -41.90111)
		(width 0.14224)
		(layer "In4.Cu")
		(net "M_B_DQ<6>")
	)
	(segment
		(start 223.338136 -56.561736)
		(end 223.338136 -57.293764)
		(width 0.14224)
		(layer "In4.Cu")
		(net "M_B_DQ<6>")
	)
	(arc
		(start 233.047794 -65.591436)
		(mid 233.241644 -65.647786)
		(end 233.383328 -65.791588)
		(width 0.0889)
		(layer "In4.Cu")
		(net "M_B_DQ<6>")
	)
	(arc
		(start 233.383328 -65.791588)
		(mid 233.591936 -66.00352)
		(end 233.877358 -66.08699)
		(width 0.0889)
		(layer "In4.Cu")
		(net "M_B_DQ<6>")
	)
	(arc
		(start 234.241848 -66.286888)
		(mid 234.448852 -66.497752)
		(end 234.732068 -66.582036)
		(width 0.0889)
		(layer "In4.Cu")
		(net "M_B_DQ<6>")
	)
	(arc
		(start 232.268776 -65.09639)
		(mid 232.393977 -65.176161)
		(end 232.48493 -65.293494)
		(width 0.0889)
		(layer "In4.Cu")
		(net "M_B_DQ<6>")
	)
	(arc
		(start 232.48493 -65.293494)
		(mid 232.630855 -65.475581)
		(end 232.833418 -65.591436)
		(width 0.0889)
		(layer "In4.Cu")
		(net "M_B_DQ<6>")
	)
	(arc
		(start 233.910124 -66.08699)
		(mid 234.101766 -66.144156)
		(end 234.241848 -66.286888)
		(width 0.0889)
		(layer "In4.Cu")
		(net "M_B_DQ<6>")
	)
	(segment
		(start 313.700414 -5.822442)
		(end 313.699906 -5.822442)
		(width 0.1651)
		(layer "F.Cu")
		(net "M_B_DQ<63>")
	)
	(segment
		(start 285.2166 -61.352938)
		(end 285.7881 -61.352938)
		(width 0.1016)
		(layer "F.Cu")
		(net "M_B_DQ<63>")
	)
	(segment
		(start 313.699906 -5.822442)
		(end 313.699906 -7.086346)
		(width 0.1651)
		(layer "F.Cu")
		(net "M_B_DQ<63>")
	)
	(via
		(at 313.699906 -7.086346)
		(size 0.508)
		(drill 0.254)
		(layers "F.Cu" "B.Cu")
		(net "M_B_DQ<63>")
	)
	(via
		(at 314.54979 -12.678156)
		(size 0.508)
		(drill 0.254)
		(layers "F.Cu" "B.Cu")
		(net "M_B_DQ<63>")
	)
	(via
		(at 285.2166 -61.352938)
		(size 0.508)
		(drill 0.254)
		(layers "F.Cu" "B.Cu")
		(net "M_B_DQ<63>")
	)
	(segment
		(start 314.54979 -10.623042)
		(end 314.54979 -12.678156)
		(width 0.1651)
		(layer "B.Cu")
		(net "M_B_DQ<63>")
	)
	(segment
		(start 314.550298 -10.623042)
		(end 314.54979 -10.623042)
		(width 0.1651)
		(layer "B.Cu")
		(net "M_B_DQ<63>")
	)
	(segment
		(start 314.706 -29.819346)
		(end 314.706 -29.082746)
		(width 0.14224)
		(layer "In4.Cu")
		(net "M_B_DQ<63>")
	)
	(segment
		(start 315.105796 -21.975572)
		(end 314.902596 -21.772372)
		(width 0.14224)
		(layer "In4.Cu")
		(net "M_B_DQ<63>")
	)
	(segment
		(start 314.9092 -14.835632)
		(end 314.458096 -14.384528)
		(width 0.14224)
		(layer "In4.Cu")
		(net "M_B_DQ<63>")
	)
	(segment
		(start 314.4774 -28.422346)
		(end 314.9346 -27.965146)
		(width 0.14224)
		(layer "In4.Cu")
		(net "M_B_DQ<63>")
	)
	(segment
		(start 315.058044 -8.509)
		(end 314.600844 -8.0518)
		(width 0.14224)
		(layer "In4.Cu")
		(net "M_B_DQ<63>")
	)
	(segment
		(start 314.902596 -9.020048)
		(end 315.058044 -8.8646)
		(width 0.14224)
		(layer "In4.Cu")
		(net "M_B_DQ<63>")
	)
	(segment
		(start 315.0108 -18.466054)
		(end 315.0108 -16.961866)
		(width 0.14224)
		(layer "In4.Cu")
		(net "M_B_DQ<63>")
	)
	(segment
		(start 315.105796 -23.118572)
		(end 315.105796 -21.975572)
		(width 0.14224)
		(layer "In4.Cu")
		(net "M_B_DQ<63>")
	)
	(segment
		(start 314.600844 -8.0518)
		(end 314.346844 -8.0518)
		(width 0.14224)
		(layer "In4.Cu")
		(net "M_B_DQ<63>")
	)
	(segment
		(start 290.451794 -52.0954)
		(end 290.859464 -52.0954)
		(width 0.0889)
		(layer "In4.Cu")
		(net "M_B_DQ<63>")
	)
	(segment
		(start 287.440624 -56.703722)
		(end 287.44545 -56.695086)
		(width 0.0889)
		(layer "In4.Cu")
		(net "M_B_DQ<63>")
	)
	(segment
		(start 314.902596 -12.32535)
		(end 314.902596 -9.020048)
		(width 0.14224)
		(layer "In4.Cu")
		(net "M_B_DQ<63>")
	)
	(segment
		(start 314.706 -29.082746)
		(end 314.4774 -28.854146)
		(width 0.14224)
		(layer "In4.Cu")
		(net "M_B_DQ<63>")
	)
	(segment
		(start 296.789602 -48.15205)
		(end 314.4774 -30.464252)
		(width 0.14224)
		(layer "In4.Cu")
		(net "M_B_DQ<63>")
	)
	(segment
		(start 314.016644 -7.7216)
		(end 314.016644 -7.403084)
		(width 0.14224)
		(layer "In4.Cu")
		(net "M_B_DQ<63>")
	)
	(segment
		(start 314.4774 -30.464252)
		(end 314.4774 -30.047946)
		(width 0.14224)
		(layer "In4.Cu")
		(net "M_B_DQ<63>")
	)
	(segment
		(start 314.4774 -30.047946)
		(end 314.706 -29.819346)
		(width 0.14224)
		(layer "In4.Cu")
		(net "M_B_DQ<63>")
	)
	(segment
		(start 314.016644 -7.403084)
		(end 313.699906 -7.086346)
		(width 0.14224)
		(layer "In4.Cu")
		(net "M_B_DQ<63>")
	)
	(segment
		(start 314.458096 -14.384528)
		(end 314.458096 -14.019276)
		(width 0.14224)
		(layer "In4.Cu")
		(net "M_B_DQ<63>")
	)
	(segment
		(start 290.859464 -52.0954)
		(end 294.802814 -48.15205)
		(width 0.14224)
		(layer "In4.Cu")
		(net "M_B_DQ<63>")
	)
	(segment
		(start 314.458096 -14.019276)
		(end 314.064396 -13.625576)
		(width 0.14224)
		(layer "In4.Cu")
		(net "M_B_DQ<63>")
	)
	(segment
		(start 314.346844 -8.0518)
		(end 314.016644 -7.7216)
		(width 0.14224)
		(layer "In4.Cu")
		(net "M_B_DQ<63>")
	)
	(segment
		(start 285.623 -60.56249)
		(end 285.642558 -59.811666)
		(width 0.0889)
		(layer "In4.Cu")
		(net "M_B_DQ<63>")
	)
	(segment
		(start 294.802814 -48.15205)
		(end 296.789602 -48.15205)
		(width 0.14224)
		(layer "In4.Cu")
		(net "M_B_DQ<63>")
	)
	(segment
		(start 287.440624 -57.694322)
		(end 287.44545 -57.685686)
		(width 0.0889)
		(layer "In4.Cu")
		(net "M_B_DQ<63>")
	)
	(segment
		(start 314.9092 -16.860266)
		(end 314.9092 -14.835632)
		(width 0.14224)
		(layer "In4.Cu")
		(net "M_B_DQ<63>")
	)
	(segment
		(start 288.639504 -53.027834)
		(end 289.51936 -53.027834)
		(width 0.0889)
		(layer "In4.Cu")
		(net "M_B_DQ<63>")
	)
	(segment
		(start 287.440624 -55.713122)
		(end 287.44545 -55.704486)
		(width 0.0889)
		(layer "In4.Cu")
		(net "M_B_DQ<63>")
	)
	(segment
		(start 314.9346 -23.289768)
		(end 315.105796 -23.118572)
		(width 0.14224)
		(layer "In4.Cu")
		(net "M_B_DQ<63>")
	)
	(segment
		(start 289.51936 -53.027834)
		(end 290.451794 -52.0954)
		(width 0.0889)
		(layer "In4.Cu")
		(net "M_B_DQ<63>")
	)
	(segment
		(start 286.915606 -58.971688)
		(end 286.95523 -58.971688)
		(width 0.0889)
		(layer "In4.Cu")
		(net "M_B_DQ<63>")
	)
	(segment
		(start 287.44545 -57.685686)
		(end 287.4518 -57.675018)
		(width 0.0889)
		(layer "In4.Cu")
		(net "M_B_DQ<63>")
	)
	(segment
		(start 285.642558 -59.811666)
		(end 285.72841 -59.666886)
		(width 0.0889)
		(layer "In4.Cu")
		(net "M_B_DQ<63>")
	)
	(segment
		(start 287.44545 -55.704486)
		(end 287.4518 -55.693818)
		(width 0.0889)
		(layer "In4.Cu")
		(net "M_B_DQ<63>")
	)
	(segment
		(start 285.2166 -61.352938)
		(end 285.623 -60.56249)
		(width 0.0889)
		(layer "In4.Cu")
		(net "M_B_DQ<63>")
	)
	(segment
		(start 287.440624 -54.722522)
		(end 287.44545 -54.713886)
		(width 0.0889)
		(layer "In4.Cu")
		(net "M_B_DQ<63>")
	)
	(segment
		(start 287.780984 -53.523134)
		(end 287.81375 -53.523134)
		(width 0.0889)
		(layer "In4.Cu")
		(net "M_B_DQ<63>")
	)
	(segment
		(start 314.54979 -12.678156)
		(end 314.902596 -12.32535)
		(width 0.14224)
		(layer "In4.Cu")
		(net "M_B_DQ<63>")
	)
	(segment
		(start 287.44545 -54.713886)
		(end 287.4518 -54.703218)
		(width 0.0889)
		(layer "In4.Cu")
		(net "M_B_DQ<63>")
	)
	(segment
		(start 315.058044 -8.8646)
		(end 315.058044 -8.509)
		(width 0.14224)
		(layer "In4.Cu")
		(net "M_B_DQ<63>")
	)
	(segment
		(start 314.4774 -28.854146)
		(end 314.4774 -28.422346)
		(width 0.14224)
		(layer "In4.Cu")
		(net "M_B_DQ<63>")
	)
	(segment
		(start 287.44545 -56.695086)
		(end 287.4518 -56.684418)
		(width 0.0889)
		(layer "In4.Cu")
		(net "M_B_DQ<63>")
	)
	(segment
		(start 314.064396 -13.625576)
		(end 314.064396 -13.16355)
		(width 0.14224)
		(layer "In4.Cu")
		(net "M_B_DQ<63>")
	)
	(segment
		(start 314.902596 -18.574258)
		(end 315.0108 -18.466054)
		(width 0.14224)
		(layer "In4.Cu")
		(net "M_B_DQ<63>")
	)
	(segment
		(start 315.0108 -16.961866)
		(end 314.9092 -16.860266)
		(width 0.14224)
		(layer "In4.Cu")
		(net "M_B_DQ<63>")
	)
	(segment
		(start 286.057086 -59.466988)
		(end 286.0929 -59.466988)
		(width 0.0889)
		(layer "In4.Cu")
		(net "M_B_DQ<63>")
	)
	(segment
		(start 314.902596 -21.772372)
		(end 314.902596 -18.574258)
		(width 0.14224)
		(layer "In4.Cu")
		(net "M_B_DQ<63>")
	)
	(segment
		(start 314.064396 -13.16355)
		(end 314.54979 -12.678156)
		(width 0.14224)
		(layer "In4.Cu")
		(net "M_B_DQ<63>")
	)
	(segment
		(start 314.9346 -27.965146)
		(end 314.9346 -23.289768)
		(width 0.14224)
		(layer "In4.Cu")
		(net "M_B_DQ<63>")
	)
	(arc
		(start 285.72841 -59.666886)
		(mid 285.867154 -59.524853)
		(end 286.057086 -59.466988)
		(width 0.0889)
		(layer "In4.Cu")
		(net "M_B_DQ<63>")
	)
	(arc
		(start 287.44545 -57.095136)
		(mid 287.39198 -56.900073)
		(end 287.440624 -56.703722)
		(width 0.0889)
		(layer "In4.Cu")
		(net "M_B_DQ<63>")
	)
	(arc
		(start 287.44545 -54.123336)
		(mid 287.442702 -53.727869)
		(end 287.780984 -53.523134)
		(width 0.0889)
		(layer "In4.Cu")
		(net "M_B_DQ<63>")
	)
	(arc
		(start 287.4518 -57.675018)
		(mid 287.524598 -57.384255)
		(end 287.44545 -57.095136)
		(width 0.0889)
		(layer "In4.Cu")
		(net "M_B_DQ<63>")
	)
	(arc
		(start 286.58693 -59.171586)
		(mid 286.725674 -59.029553)
		(end 286.915606 -58.971688)
		(width 0.0889)
		(layer "In4.Cu")
		(net "M_B_DQ<63>")
	)
	(arc
		(start 287.44545 -55.113936)
		(mid 287.39198 -54.918873)
		(end 287.440624 -54.722522)
		(width 0.0889)
		(layer "In4.Cu")
		(net "M_B_DQ<63>")
	)
	(arc
		(start 287.44545 -56.104536)
		(mid 287.39198 -55.909473)
		(end 287.440624 -55.713122)
		(width 0.0889)
		(layer "In4.Cu")
		(net "M_B_DQ<63>")
	)
	(arc
		(start 286.95523 -58.971688)
		(mid 287.450707 -58.667245)
		(end 287.44545 -58.085736)
		(width 0.0889)
		(layer "In4.Cu")
		(net "M_B_DQ<63>")
	)
	(arc
		(start 288.30397 -53.227986)
		(mid 288.445653 -53.084182)
		(end 288.639504 -53.027834)
		(width 0.0889)
		(layer "In4.Cu")
		(net "M_B_DQ<63>")
	)
	(arc
		(start 287.44545 -58.085736)
		(mid 287.39198 -57.890673)
		(end 287.440624 -57.694322)
		(width 0.0889)
		(layer "In4.Cu")
		(net "M_B_DQ<63>")
	)
	(arc
		(start 286.0929 -59.466988)
		(mid 286.378324 -59.383521)
		(end 286.58693 -59.171586)
		(width 0.0889)
		(layer "In4.Cu")
		(net "M_B_DQ<63>")
	)
	(arc
		(start 287.4518 -55.693818)
		(mid 287.524598 -55.403055)
		(end 287.44545 -55.113936)
		(width 0.0889)
		(layer "In4.Cu")
		(net "M_B_DQ<63>")
	)
	(arc
		(start 287.4518 -54.703218)
		(mid 287.524598 -54.412455)
		(end 287.44545 -54.123336)
		(width 0.0889)
		(layer "In4.Cu")
		(net "M_B_DQ<63>")
	)
	(arc
		(start 287.81375 -53.523134)
		(mid 288.096967 -53.438853)
		(end 288.30397 -53.227986)
		(width 0.0889)
		(layer "In4.Cu")
		(net "M_B_DQ<63>")
	)
	(arc
		(start 287.4518 -56.684418)
		(mid 287.524598 -56.393655)
		(end 287.44545 -56.104536)
		(width 0.0889)
		(layer "In4.Cu")
		(net "M_B_DQ<63>")
	)
	(segment
		(start 314.550044 -8.661654)
		(end 314.550044 -8.9662)
		(width 0.1651)
		(layer "F.Cu")
		(net "M_B_DQ<62>")
	)
	(segment
		(start 314.550044 -8.9662)
		(end 314.682124 -9.09828)
		(width 0.1651)
		(layer "F.Cu")
		(net "M_B_DQ<62>")
	)
	(segment
		(start 314.682124 -9.31672)
		(end 314.550044 -9.4488)
		(width 0.1651)
		(layer "F.Cu")
		(net "M_B_DQ<62>")
	)
	(segment
		(start 314.550044 -9.4488)
		(end 314.550044 -10.422128)
		(width 0.1651)
		(layer "F.Cu")
		(net "M_B_DQ<62>")
	)
	(segment
		(start 314.682124 -9.09828)
		(end 314.682124 -9.31672)
		(width 0.1651)
		(layer "F.Cu")
		(net "M_B_DQ<62>")
	)
	(segment
		(start 314.54979 -8.6614)
		(end 314.550044 -8.661654)
		(width 0.1651)
		(layer "F.Cu")
		(net "M_B_DQ<62>")
	)
	(segment
		(start 285.2166 -59.371484)
		(end 285.7881 -59.371484)
		(width 0.1016)
		(layer "F.Cu")
		(net "M_B_DQ<62>")
	)
	(segment
		(start 314.550044 -10.422128)
		(end 314.550298 -10.422382)
		(width 0.1651)
		(layer "F.Cu")
		(net "M_B_DQ<62>")
	)
	(via
		(at 285.2166 -59.371484)
		(size 0.508)
		(drill 0.254)
		(layers "F.Cu" "B.Cu")
		(net "M_B_DQ<62>")
	)
	(via
		(at 313.699906 -13.959078)
		(size 0.508)
		(drill 0.254)
		(layers "F.Cu" "B.Cu")
		(net "M_B_DQ<62>")
	)
	(via
		(at 314.54979 -8.6614)
		(size 0.508)
		(drill 0.254)
		(layers "F.Cu" "B.Cu")
		(net "M_B_DQ<62>")
	)
	(segment
		(start 313.699906 -15.222982)
		(end 313.699906 -13.959078)
		(width 0.1651)
		(layer "B.Cu")
		(net "M_B_DQ<62>")
	)
	(segment
		(start 313.700414 -15.222982)
		(end 313.699906 -15.222982)
		(width 0.1651)
		(layer "B.Cu")
		(net "M_B_DQ<62>")
	)
	(segment
		(start 312.698384 -29.38272)
		(end 313.8424 -28.238704)
		(width 0.14224)
		(layer "In4.Cu")
		(net "M_B_DQ<62>")
	)
	(segment
		(start 311.54878 -30.532324)
		(end 311.836054 -30.24505)
		(width 0.14224)
		(layer "In4.Cu")
		(net "M_B_DQ<62>")
	)
	(segment
		(start 313.811412 -11.093704)
		(end 314.192412 -10.712704)
		(width 0.14224)
		(layer "In4.Cu")
		(net "M_B_DQ<62>")
	)
	(segment
		(start 313.8424 -24.250396)
		(end 314.157106 -23.93569)
		(width 0.14224)
		(layer "In4.Cu")
		(net "M_B_DQ<62>")
	)
	(segment
		(start 313.464194 -13.723366)
		(end 313.464194 -12.928854)
		(width 0.14224)
		(layer "In4.Cu")
		(net "M_B_DQ<62>")
	)
	(segment
		(start 289.440366 -52.837334)
		(end 290.86429 -51.41341)
		(width 0.0889)
		(layer "In4.Cu")
		(net "M_B_DQ<62>")
	)
	(segment
		(start 314.267596 -18.63725)
		(end 314.064396 -18.43405)
		(width 0.14224)
		(layer "In4.Cu")
		(net "M_B_DQ<62>")
	)
	(segment
		(start 313.200034 -30.373066)
		(end 313.200034 -30.171898)
		(width 0.14224)
		(layer "In4.Cu")
		(net "M_B_DQ<62>")
	)
	(segment
		(start 288.62909 -52.837334)
		(end 289.440366 -52.837334)
		(width 0.0889)
		(layer "In4.Cu")
		(net "M_B_DQ<62>")
	)
	(segment
		(start 312.625232 -30.7467)
		(end 312.8264 -30.7467)
		(width 0.14224)
		(layer "In4.Cu")
		(net "M_B_DQ<62>")
	)
	(segment
		(start 312.123582 -30.24505)
		(end 312.625232 -30.7467)
		(width 0.14224)
		(layer "In4.Cu")
		(net "M_B_DQ<62>")
	)
	(segment
		(start 287.28035 -55.609236)
		(end 287.285176 -55.6006)
		(width 0.0889)
		(layer "In4.Cu")
		(net "M_B_DQ<62>")
	)
	(segment
		(start 314.157106 -23.93569)
		(end 314.157106 -23.262082)
		(width 0.14224)
		(layer "In4.Cu")
		(net "M_B_DQ<62>")
	)
	(segment
		(start 311.93613 -31.40837)
		(end 311.93613 -31.207202)
		(width 0.14224)
		(layer "In4.Cu")
		(net "M_B_DQ<62>")
	)
	(segment
		(start 314.175394 -9.313672)
		(end 314.175394 -9.035796)
		(width 0.14224)
		(layer "In4.Cu")
		(net "M_B_DQ<62>")
	)
	(segment
		(start 310.973978 -31.394654)
		(end 311.361328 -31.782004)
		(width 0.14224)
		(layer "In4.Cu")
		(net "M_B_DQ<62>")
	)
	(segment
		(start 314.236862 -11.804396)
		(end 313.811412 -11.378946)
		(width 0.14224)
		(layer "In4.Cu")
		(net "M_B_DQ<62>")
	)
	(segment
		(start 311.562496 -31.782004)
		(end 311.93613 -31.40837)
		(width 0.14224)
		(layer "In4.Cu")
		(net "M_B_DQ<62>")
	)
	(segment
		(start 314.064396 -18.43405)
		(end 314.064396 -16.993362)
		(width 0.14224)
		(layer "In4.Cu")
		(net "M_B_DQ<62>")
	)
	(segment
		(start 314.192412 -10.712704)
		(end 314.192412 -10.369296)
		(width 0.14224)
		(layer "In4.Cu")
		(net "M_B_DQ<62>")
	)
	(segment
		(start 296.5196 -47.476918)
		(end 310.4896 -33.553654)
		(width 0.14224)
		(layer "In4.Cu")
		(net "M_B_DQ<62>")
	)
	(segment
		(start 314.064396 -21.975572)
		(end 314.267596 -21.772372)
		(width 0.14224)
		(layer "In4.Cu")
		(net "M_B_DQ<62>")
	)
	(segment
		(start 286.05353 -59.276234)
		(end 286.093154 -59.276234)
		(width 0.0889)
		(layer "In4.Cu")
		(net "M_B_DQ<62>")
	)
	(segment
		(start 287.28035 -57.590436)
		(end 287.285176 -57.5818)
		(width 0.0889)
		(layer "In4.Cu")
		(net "M_B_DQ<62>")
	)
	(segment
		(start 313.811412 -9.677654)
		(end 314.175394 -9.313672)
		(width 0.14224)
		(layer "In4.Cu")
		(net "M_B_DQ<62>")
	)
	(segment
		(start 313.200034 -30.171898)
		(end 312.698384 -29.670248)
		(width 0.14224)
		(layer "In4.Cu")
		(net "M_B_DQ<62>")
	)
	(segment
		(start 313.699906 -13.959078)
		(end 313.464194 -13.723366)
		(width 0.14224)
		(layer "In4.Cu")
		(net "M_B_DQ<62>")
	)
	(segment
		(start 287.274 -54.629304)
		(end 287.28035 -54.618636)
		(width 0.0889)
		(layer "In4.Cu")
		(net "M_B_DQ<62>")
	)
	(segment
		(start 285.757366 -59.274202)
		(end 286.05353 -59.276234)
		(width 0.0889)
		(layer "In4.Cu")
		(net "M_B_DQ<62>")
	)
	(segment
		(start 311.836054 -30.24505)
		(end 312.123582 -30.24505)
		(width 0.14224)
		(layer "In4.Cu")
		(net "M_B_DQ<62>")
	)
	(segment
		(start 314.192412 -10.369296)
		(end 313.811412 -9.988296)
		(width 0.14224)
		(layer "In4.Cu")
		(net "M_B_DQ<62>")
	)
	(segment
		(start 287.274 -56.610504)
		(end 287.28035 -56.599836)
		(width 0.0889)
		(layer "In4.Cu")
		(net "M_B_DQ<62>")
	)
	(segment
		(start 286.91586 -58.780934)
		(end 286.951674 -58.780934)
		(width 0.0889)
		(layer "In4.Cu")
		(net "M_B_DQ<62>")
	)
	(segment
		(start 310.4896 -33.553654)
		(end 310.4896 -31.591504)
		(width 0.14224)
		(layer "In4.Cu")
		(net "M_B_DQ<62>")
	)
	(segment
		(start 287.274 -57.601104)
		(end 287.28035 -57.590436)
		(width 0.0889)
		(layer "In4.Cu")
		(net "M_B_DQ<62>")
	)
	(segment
		(start 287.77057 -53.332634)
		(end 287.803336 -53.332634)
		(width 0.0889)
		(layer "In4.Cu")
		(net "M_B_DQ<62>")
	)
	(segment
		(start 313.464194 -12.928854)
		(end 314.236862 -12.156186)
		(width 0.14224)
		(layer "In4.Cu")
		(net "M_B_DQ<62>")
	)
	(segment
		(start 314.157106 -23.262082)
		(end 314.064396 -23.169372)
		(width 0.14224)
		(layer "In4.Cu")
		(net "M_B_DQ<62>")
	)
	(segment
		(start 314.175394 -9.035796)
		(end 314.54979 -8.6614)
		(width 0.14224)
		(layer "In4.Cu")
		(net "M_B_DQ<62>")
	)
	(segment
		(start 287.28035 -54.618636)
		(end 287.285176 -54.61)
		(width 0.0889)
		(layer "In4.Cu")
		(net "M_B_DQ<62>")
	)
	(segment
		(start 296.322496 -47.67326)
		(end 296.5196 -47.476918)
		(width 0.14224)
		(layer "In4.Cu")
		(net "M_B_DQ<62>")
	)
	(segment
		(start 312.8264 -30.7467)
		(end 313.200034 -30.373066)
		(width 0.14224)
		(layer "In4.Cu")
		(net "M_B_DQ<62>")
	)
	(segment
		(start 313.811412 -9.988296)
		(end 313.811412 -9.677654)
		(width 0.14224)
		(layer "In4.Cu")
		(net "M_B_DQ<62>")
	)
	(segment
		(start 310.4896 -31.591504)
		(end 310.68645 -31.394654)
		(width 0.14224)
		(layer "In4.Cu")
		(net "M_B_DQ<62>")
	)
	(segment
		(start 311.93613 -31.207202)
		(end 311.54878 -30.819852)
		(width 0.14224)
		(layer "In4.Cu")
		(net "M_B_DQ<62>")
	)
	(segment
		(start 294.60444 -47.67326)
		(end 296.322496 -47.67326)
		(width 0.14224)
		(layer "In4.Cu")
		(net "M_B_DQ<62>")
	)
	(segment
		(start 314.236862 -12.156186)
		(end 314.236862 -11.804396)
		(width 0.14224)
		(layer "In4.Cu")
		(net "M_B_DQ<62>")
	)
	(segment
		(start 314.064396 -23.169372)
		(end 314.064396 -21.975572)
		(width 0.14224)
		(layer "In4.Cu")
		(net "M_B_DQ<62>")
	)
	(segment
		(start 313.699906 -14.524482)
		(end 313.699906 -13.959078)
		(width 0.14224)
		(layer "In4.Cu")
		(net "M_B_DQ<62>")
	)
	(segment
		(start 311.361328 -31.782004)
		(end 311.562496 -31.782004)
		(width 0.14224)
		(layer "In4.Cu")
		(net "M_B_DQ<62>")
	)
	(segment
		(start 314.064396 -16.993362)
		(end 314.1726 -16.885158)
		(width 0.14224)
		(layer "In4.Cu")
		(net "M_B_DQ<62>")
	)
	(segment
		(start 310.68645 -31.394654)
		(end 310.973978 -31.394654)
		(width 0.14224)
		(layer "In4.Cu")
		(net "M_B_DQ<62>")
	)
	(segment
		(start 287.274 -55.619904)
		(end 287.28035 -55.609236)
		(width 0.0889)
		(layer "In4.Cu")
		(net "M_B_DQ<62>")
	)
	(segment
		(start 313.8424 -28.238704)
		(end 313.8424 -24.250396)
		(width 0.14224)
		(layer "In4.Cu")
		(net "M_B_DQ<62>")
	)
	(segment
		(start 314.1726 -14.997176)
		(end 313.699906 -14.524482)
		(width 0.14224)
		(layer "In4.Cu")
		(net "M_B_DQ<62>")
	)
	(segment
		(start 312.698384 -29.670248)
		(end 312.698384 -29.38272)
		(width 0.14224)
		(layer "In4.Cu")
		(net "M_B_DQ<62>")
	)
	(segment
		(start 314.1726 -16.885158)
		(end 314.1726 -14.997176)
		(width 0.14224)
		(layer "In4.Cu")
		(net "M_B_DQ<62>")
	)
	(segment
		(start 287.28035 -56.599836)
		(end 287.285176 -56.5912)
		(width 0.0889)
		(layer "In4.Cu")
		(net "M_B_DQ<62>")
	)
	(segment
		(start 290.86429 -51.41341)
		(end 294.60444 -47.67326)
		(width 0.14224)
		(layer "In4.Cu")
		(net "M_B_DQ<62>")
	)
	(segment
		(start 313.811412 -11.378946)
		(end 313.811412 -11.093704)
		(width 0.14224)
		(layer "In4.Cu")
		(net "M_B_DQ<62>")
	)
	(segment
		(start 285.2166 -59.371484)
		(end 285.757366 -59.274202)
		(width 0.0889)
		(layer "In4.Cu")
		(net "M_B_DQ<62>")
	)
	(segment
		(start 314.267596 -21.772372)
		(end 314.267596 -18.63725)
		(width 0.14224)
		(layer "In4.Cu")
		(net "M_B_DQ<62>")
	)
	(segment
		(start 311.54878 -30.819852)
		(end 311.54878 -30.532324)
		(width 0.14224)
		(layer "In4.Cu")
		(net "M_B_DQ<62>")
	)
	(arc
		(start 286.951674 -58.780934)
		(mid 287.284643 -58.573386)
		(end 287.28035 -58.180986)
		(width 0.0889)
		(layer "In4.Cu")
		(net "M_B_DQ<62>")
	)
	(arc
		(start 287.28035 -57.190386)
		(mid 287.201128 -56.901268)
		(end 287.274 -56.610504)
		(width 0.0889)
		(layer "In4.Cu")
		(net "M_B_DQ<62>")
	)
	(arc
		(start 286.093154 -59.276234)
		(mid 286.283083 -59.218364)
		(end 286.42183 -59.076336)
		(width 0.0889)
		(layer "In4.Cu")
		(net "M_B_DQ<62>")
	)
	(arc
		(start 287.803336 -53.332634)
		(mid 287.997186 -53.276284)
		(end 288.13887 -53.132482)
		(width 0.0889)
		(layer "In4.Cu")
		(net "M_B_DQ<62>")
	)
	(arc
		(start 287.285176 -57.5818)
		(mid 287.333931 -57.385448)
		(end 287.28035 -57.190386)
		(width 0.0889)
		(layer "In4.Cu")
		(net "M_B_DQ<62>")
	)
	(arc
		(start 287.28035 -55.209186)
		(mid 287.201128 -54.920068)
		(end 287.274 -54.629304)
		(width 0.0889)
		(layer "In4.Cu")
		(net "M_B_DQ<62>")
	)
	(arc
		(start 287.28035 -54.218586)
		(mid 287.275096 -53.637078)
		(end 287.77057 -53.332634)
		(width 0.0889)
		(layer "In4.Cu")
		(net "M_B_DQ<62>")
	)
	(arc
		(start 287.28035 -58.180986)
		(mid 287.201128 -57.891868)
		(end 287.274 -57.601104)
		(width 0.0889)
		(layer "In4.Cu")
		(net "M_B_DQ<62>")
	)
	(arc
		(start 286.42183 -59.076336)
		(mid 286.630438 -58.864404)
		(end 286.91586 -58.780934)
		(width 0.0889)
		(layer "In4.Cu")
		(net "M_B_DQ<62>")
	)
	(arc
		(start 287.285176 -55.6006)
		(mid 287.333931 -55.404248)
		(end 287.28035 -55.209186)
		(width 0.0889)
		(layer "In4.Cu")
		(net "M_B_DQ<62>")
	)
	(arc
		(start 287.28035 -56.199786)
		(mid 287.201128 -55.910668)
		(end 287.274 -55.619904)
		(width 0.0889)
		(layer "In4.Cu")
		(net "M_B_DQ<62>")
	)
	(arc
		(start 288.13887 -53.132482)
		(mid 288.345874 -52.921618)
		(end 288.62909 -52.837334)
		(width 0.0889)
		(layer "In4.Cu")
		(net "M_B_DQ<62>")
	)
	(arc
		(start 287.285176 -54.61)
		(mid 287.333931 -54.413648)
		(end 287.28035 -54.218586)
		(width 0.0889)
		(layer "In4.Cu")
		(net "M_B_DQ<62>")
	)
	(arc
		(start 287.285176 -56.5912)
		(mid 287.333931 -56.394848)
		(end 287.28035 -56.199786)
		(width 0.0889)
		(layer "In4.Cu")
		(net "M_B_DQ<62>")
	)
	(segment
		(start 307.750464 -5.822442)
		(end 307.749956 -5.822442)
		(width 0.1651)
		(layer "F.Cu")
		(net "M_B_DQ<61>")
	)
	(segment
		(start 307.749956 -5.822442)
		(end 307.749956 -7.086346)
		(width 0.1651)
		(layer "F.Cu")
		(net "M_B_DQ<61>")
	)
	(segment
		(start 283.212794 -60.857384)
		(end 282.641294 -60.857384)
		(width 0.1016)
		(layer "F.Cu")
		(net "M_B_DQ<61>")
	)
	(via
		(at 307.749956 -7.086346)
		(size 0.508)
		(drill 0.254)
		(layers "F.Cu" "B.Cu")
		(net "M_B_DQ<61>")
	)
	(via
		(at 308.52364 -12.678156)
		(size 0.508)
		(drill 0.254)
		(layers "F.Cu" "B.Cu")
		(net "M_B_DQ<61>")
	)
	(via
		(at 282.641294 -60.857384)
		(size 0.508)
		(drill 0.254)
		(layers "F.Cu" "B.Cu")
		(net "M_B_DQ<61>")
	)
	(segment
		(start 308.59984 -10.623042)
		(end 308.59984 -12.601956)
		(width 0.1651)
		(layer "B.Cu")
		(net "M_B_DQ<61>")
	)
	(segment
		(start 308.600348 -10.623042)
		(end 308.59984 -10.623042)
		(width 0.1651)
		(layer "B.Cu")
		(net "M_B_DQ<61>")
	)
	(segment
		(start 308.59984 -12.601956)
		(end 308.52364 -12.678156)
		(width 0.1651)
		(layer "B.Cu")
		(net "M_B_DQ<61>")
	)
	(segment
		(start 282.97124 -60.095638)
		(end 282.988004 -60.066936)
		(width 0.0889)
		(layer "In4.Cu")
		(net "M_B_DQ<61>")
	)
	(segment
		(start 284.006798 -54.722522)
		(end 284.011624 -54.713886)
		(width 0.0889)
		(layer "In4.Cu")
		(net "M_B_DQ<61>")
	)
	(segment
		(start 284.006798 -55.713122)
		(end 284.011624 -55.704486)
		(width 0.0889)
		(layer "In4.Cu")
		(net "M_B_DQ<61>")
	)
	(segment
		(start 301.544228 -35.907472)
		(end 301.745396 -35.907472)
		(width 0.14224)
		(layer "In4.Cu")
		(net "M_B_DQ<61>")
	)
	(segment
		(start 308.52364 -12.678156)
		(end 308.835044 -12.366752)
		(width 0.14224)
		(layer "In4.Cu")
		(net "M_B_DQ<61>")
	)
	(segment
		(start 308.908196 -21.684996)
		(end 308.908196 -18.593562)
		(width 0.14224)
		(layer "In4.Cu")
		(net "M_B_DQ<61>")
	)
	(segment
		(start 309.162196 -23.055072)
		(end 309.162196 -21.938996)
		(width 0.14224)
		(layer "In4.Cu")
		(net "M_B_DQ<61>")
	)
	(segment
		(start 307.749956 -7.481062)
		(end 307.749956 -7.086346)
		(width 0.14224)
		(layer "In4.Cu")
		(net "M_B_DQ<61>")
	)
	(segment
		(start 308.63159 -8.0518)
		(end 308.320694 -8.0518)
		(width 0.14224)
		(layer "In4.Cu")
		(net "M_B_DQ<61>")
	)
	(segment
		(start 308.7878 -16.720566)
		(end 308.7878 -14.311376)
		(width 0.14224)
		(layer "In4.Cu")
		(net "M_B_DQ<61>")
	)
	(segment
		(start 308.997096 -18.504662)
		(end 308.997096 -16.929862)
		(width 0.14224)
		(layer "In4.Cu")
		(net "M_B_DQ<61>")
	)
	(segment
		(start 309.031894 -8.452104)
		(end 308.63159 -8.0518)
		(width 0.14224)
		(layer "In4.Cu")
		(net "M_B_DQ<61>")
	)
	(segment
		(start 283.055568 -59.81446)
		(end 283.055568 -59.728608)
		(width 0.0889)
		(layer "In4.Cu")
		(net "M_B_DQ<61>")
	)
	(segment
		(start 308.019196 -13.136372)
		(end 308.260496 -12.895072)
		(width 0.14224)
		(layer "In4.Cu")
		(net "M_B_DQ<61>")
	)
	(segment
		(start 300.8122 -37.765736)
		(end 300.8122 -36.6395)
		(width 0.14224)
		(layer "In4.Cu")
		(net "M_B_DQ<61>")
	)
	(segment
		(start 291.841682 -44.74083)
		(end 293.837106 -44.74083)
		(width 0.14224)
		(layer "In4.Cu")
		(net "M_B_DQ<61>")
	)
	(segment
		(start 309.031894 -8.8646)
		(end 309.031894 -8.452104)
		(width 0.14224)
		(layer "In4.Cu")
		(net "M_B_DQ<61>")
	)
	(segment
		(start 284.541214 -51.541934)
		(end 285.23184 -50.851308)
		(width 0.0889)
		(layer "In4.Cu")
		(net "M_B_DQ<61>")
	)
	(segment
		(start 302.602646 -35.615118)
		(end 301.918878 -34.93135)
		(width 0.14224)
		(layer "In4.Cu")
		(net "M_B_DQ<61>")
	)
	(segment
		(start 284.011624 -54.713886)
		(end 284.020514 -54.698646)
		(width 0.0889)
		(layer "In4.Cu")
		(net "M_B_DQ<61>")
	)
	(segment
		(start 285.991554 -49.88052)
		(end 286.701992 -49.88052)
		(width 0.0889)
		(layer "In4.Cu")
		(net "M_B_DQ<61>")
	)
	(segment
		(start 283.484828 -56.990488)
		(end 283.517594 -56.990488)
		(width 0.0889)
		(layer "In4.Cu")
		(net "M_B_DQ<61>")
	)
	(segment
		(start 308.864 -23.353268)
		(end 309.162196 -23.055072)
		(width 0.14224)
		(layer "In4.Cu")
		(net "M_B_DQ<61>")
	)
	(segment
		(start 282.641294 -60.857384)
		(end 282.97124 -60.095638)
		(width 0.0889)
		(layer "In4.Cu")
		(net "M_B_DQ<61>")
	)
	(segment
		(start 309.162196 -21.938996)
		(end 308.908196 -21.684996)
		(width 0.14224)
		(layer "In4.Cu")
		(net "M_B_DQ<61>")
	)
	(segment
		(start 286.701992 -49.88052)
		(end 287.145222 -49.43729)
		(width 0.0889)
		(layer "In4.Cu")
		(net "M_B_DQ<61>")
	)
	(segment
		(start 293.837106 -44.74083)
		(end 300.8122 -37.765736)
		(width 0.14224)
		(layer "In4.Cu")
		(net "M_B_DQ<61>")
	)
	(segment
		(start 308.019196 -13.542772)
		(end 308.019196 -13.136372)
		(width 0.14224)
		(layer "In4.Cu")
		(net "M_B_DQ<61>")
	)
	(segment
		(start 285.23184 -50.640234)
		(end 285.991554 -49.88052)
		(width 0.0889)
		(layer "In4.Cu")
		(net "M_B_DQ<61>")
	)
	(segment
		(start 287.145222 -49.43729)
		(end 291.841682 -44.74083)
		(width 0.14224)
		(layer "In4.Cu")
		(net "M_B_DQ<61>")
	)
	(segment
		(start 285.23184 -50.851308)
		(end 285.23184 -50.640234)
		(width 0.0889)
		(layer "In4.Cu")
		(net "M_B_DQ<61>")
	)
	(segment
		(start 284.35808 -51.541934)
		(end 284.541214 -51.541934)
		(width 0.0889)
		(layer "In4.Cu")
		(net "M_B_DQ<61>")
	)
	(segment
		(start 308.7878 -14.311376)
		(end 308.019196 -13.542772)
		(width 0.14224)
		(layer "In4.Cu")
		(net "M_B_DQ<61>")
	)
	(segment
		(start 308.306724 -12.895072)
		(end 308.52364 -12.678156)
		(width 0.14224)
		(layer "In4.Cu")
		(net "M_B_DQ<61>")
	)
	(segment
		(start 302.027844 -36.18992)
		(end 302.315372 -36.18992)
		(width 0.14224)
		(layer "In4.Cu")
		(net "M_B_DQ<61>")
	)
	(segment
		(start 308.997096 -16.929862)
		(end 308.7878 -16.720566)
		(width 0.14224)
		(layer "In4.Cu")
		(net "M_B_DQ<61>")
	)
	(segment
		(start 300.8122 -36.6395)
		(end 301.544228 -35.907472)
		(width 0.14224)
		(layer "In4.Cu")
		(net "M_B_DQ<61>")
	)
	(segment
		(start 308.908196 -18.593562)
		(end 308.997096 -18.504662)
		(width 0.14224)
		(layer "In4.Cu")
		(net "M_B_DQ<61>")
	)
	(segment
		(start 308.864 -27.6987)
		(end 308.864 -23.353268)
		(width 0.14224)
		(layer "In4.Cu")
		(net "M_B_DQ<61>")
	)
	(segment
		(start 308.835044 -12.366752)
		(end 308.835044 -9.06145)
		(width 0.14224)
		(layer "In4.Cu")
		(net "M_B_DQ<61>")
	)
	(segment
		(start 308.835044 -9.06145)
		(end 309.031894 -8.8646)
		(width 0.14224)
		(layer "In4.Cu")
		(net "M_B_DQ<61>")
	)
	(segment
		(start 302.602646 -35.902646)
		(end 302.602646 -35.615118)
		(width 0.14224)
		(layer "In4.Cu")
		(net "M_B_DQ<61>")
	)
	(segment
		(start 301.745396 -35.907472)
		(end 302.027844 -36.18992)
		(width 0.14224)
		(layer "In4.Cu")
		(net "M_B_DQ<61>")
	)
	(segment
		(start 301.918878 -34.643822)
		(end 308.864 -27.6987)
		(width 0.14224)
		(layer "In4.Cu")
		(net "M_B_DQ<61>")
	)
	(segment
		(start 302.315372 -36.18992)
		(end 302.602646 -35.902646)
		(width 0.14224)
		(layer "In4.Cu")
		(net "M_B_DQ<61>")
	)
	(segment
		(start 284.011624 -55.704486)
		(end 284.017974 -55.693818)
		(width 0.0889)
		(layer "In4.Cu")
		(net "M_B_DQ<61>")
	)
	(segment
		(start 282.311348 -58.114692)
		(end 282.294584 -58.085736)
		(width 0.0889)
		(layer "In4.Cu")
		(net "M_B_DQ<61>")
	)
	(segment
		(start 301.918878 -34.93135)
		(end 301.918878 -34.643822)
		(width 0.14224)
		(layer "In4.Cu")
		(net "M_B_DQ<61>")
	)
	(segment
		(start 308.320694 -8.0518)
		(end 307.749956 -7.481062)
		(width 0.14224)
		(layer "In4.Cu")
		(net "M_B_DQ<61>")
	)
	(segment
		(start 284.011624 -53.723286)
		(end 284.020514 -53.708046)
		(width 0.0889)
		(layer "In4.Cu")
		(net "M_B_DQ<61>")
	)
	(segment
		(start 308.260496 -12.895072)
		(end 308.306724 -12.895072)
		(width 0.14224)
		(layer "In4.Cu")
		(net "M_B_DQ<61>")
	)
	(segment
		(start 282.630118 -57.485534)
		(end 282.662884 -57.485534)
		(width 0.0889)
		(layer "In4.Cu")
		(net "M_B_DQ<61>")
	)
	(arc
		(start 282.294584 -58.085736)
		(mid 282.291836 -57.690269)
		(end 282.630118 -57.485534)
		(width 0.0889)
		(layer "In4.Cu")
		(net "M_B_DQ<61>")
	)
	(arc
		(start 284.020514 -54.698646)
		(mid 284.090911 -54.409695)
		(end 284.011624 -54.123082)
		(width 0.0889)
		(layer "In4.Cu")
		(net "M_B_DQ<61>")
	)
	(arc
		(start 283.153104 -57.190386)
		(mid 283.293183 -57.04765)
		(end 283.484828 -56.990488)
		(width 0.0889)
		(layer "In4.Cu")
		(net "M_B_DQ<61>")
	)
	(arc
		(start 283.055568 -59.728608)
		(mid 282.930116 -59.415731)
		(end 282.62326 -59.276234)
		(width 0.0889)
		(layer "In4.Cu")
		(net "M_B_DQ<61>")
	)
	(arc
		(start 284.017974 -55.693818)
		(mid 284.090772 -55.403055)
		(end 284.011624 -55.113936)
		(width 0.0889)
		(layer "In4.Cu")
		(net "M_B_DQ<61>")
	)
	(arc
		(start 284.011624 -52.732686)
		(mid 284.090755 -52.437284)
		(end 284.011624 -52.141882)
		(width 0.0889)
		(layer "In4.Cu")
		(net "M_B_DQ<61>")
	)
	(arc
		(start 282.62326 -59.276234)
		(mid 282.290344 -59.068782)
		(end 282.294584 -58.67654)
		(width 0.0889)
		(layer "In4.Cu")
		(net "M_B_DQ<61>")
	)
	(arc
		(start 282.662884 -57.485534)
		(mid 282.946101 -57.401253)
		(end 283.153104 -57.190386)
		(width 0.0889)
		(layer "In4.Cu")
		(net "M_B_DQ<61>")
	)
	(arc
		(start 284.011624 -56.104536)
		(mid 283.958154 -55.909473)
		(end 284.006798 -55.713122)
		(width 0.0889)
		(layer "In4.Cu")
		(net "M_B_DQ<61>")
	)
	(arc
		(start 283.517594 -56.990488)
		(mid 284.015845 -56.687648)
		(end 284.011624 -56.104536)
		(width 0.0889)
		(layer "In4.Cu")
		(net "M_B_DQ<61>")
	)
	(arc
		(start 284.011624 -52.141882)
		(mid 284.011707 -51.741941)
		(end 284.35808 -51.541934)
		(width 0.0889)
		(layer "In4.Cu")
		(net "M_B_DQ<61>")
	)
	(arc
		(start 284.011624 -53.132482)
		(mid 283.958091 -52.932584)
		(end 284.011624 -52.732686)
		(width 0.0889)
		(layer "In4.Cu")
		(net "M_B_DQ<61>")
	)
	(arc
		(start 284.011624 -55.113936)
		(mid 283.958154 -54.918873)
		(end 284.006798 -54.722522)
		(width 0.0889)
		(layer "In4.Cu")
		(net "M_B_DQ<61>")
	)
	(arc
		(start 282.988004 -60.066936)
		(mid 283.038365 -59.945137)
		(end 283.055568 -59.81446)
		(width 0.0889)
		(layer "In4.Cu")
		(net "M_B_DQ<61>")
	)
	(arc
		(start 282.294584 -58.67654)
		(mid 282.373622 -58.397736)
		(end 282.311348 -58.114692)
		(width 0.0889)
		(layer "In4.Cu")
		(net "M_B_DQ<61>")
	)
	(arc
		(start 284.011624 -54.123082)
		(mid 283.958091 -53.923184)
		(end 284.011624 -53.723286)
		(width 0.0889)
		(layer "In4.Cu")
		(net "M_B_DQ<61>")
	)
	(arc
		(start 284.020514 -53.708046)
		(mid 284.090911 -53.419095)
		(end 284.011624 -53.132482)
		(width 0.0889)
		(layer "In4.Cu")
		(net "M_B_DQ<61>")
	)
	(segment
		(start 308.59984 -9.091168)
		(end 308.562756 -8.89)
		(width 0.1651)
		(layer "F.Cu")
		(net "M_B_DQ<60>")
	)
	(segment
		(start 308.600348 -10.422382)
		(end 308.59984 -10.422382)
		(width 0.1651)
		(layer "F.Cu")
		(net "M_B_DQ<60>")
	)
	(segment
		(start 283.212794 -59.866784)
		(end 282.641294 -59.866784)
		(width 0.1016)
		(layer "F.Cu")
		(net "M_B_DQ<60>")
	)
	(segment
		(start 308.59984 -10.422382)
		(end 308.59984 -9.091168)
		(width 0.1651)
		(layer "F.Cu")
		(net "M_B_DQ<60>")
	)
	(segment
		(start 308.539388 -8.763)
		(end 308.501796 -8.5598)
		(width 0.1651)
		(layer "F.Cu")
		(net "M_B_DQ<60>")
	)
	(segment
		(start 308.562756 -8.89)
		(end 308.539388 -8.763)
		(width 0.1651)
		(layer "F.Cu")
		(net "M_B_DQ<60>")
	)
	(via
		(at 308.501796 -8.5598)
		(size 0.508)
		(drill 0.254)
		(layers "F.Cu" "B.Cu")
		(net "M_B_DQ<60>")
	)
	(via
		(at 307.749956 -13.959078)
		(size 0.508)
		(drill 0.254)
		(layers "F.Cu" "B.Cu")
		(net "M_B_DQ<60>")
	)
	(via
		(at 282.641294 -59.866784)
		(size 0.508)
		(drill 0.254)
		(layers "F.Cu" "B.Cu")
		(net "M_B_DQ<60>")
	)
	(segment
		(start 307.750464 -15.222982)
		(end 307.749956 -15.222982)
		(width 0.1651)
		(layer "B.Cu")
		(net "M_B_DQ<60>")
	)
	(segment
		(start 307.749956 -15.222982)
		(end 307.749956 -13.959078)
		(width 0.1651)
		(layer "B.Cu")
		(net "M_B_DQ<60>")
	)
	(segment
		(start 307.514244 -12.928854)
		(end 308.225444 -12.217654)
		(width 0.14224)
		(layer "In4.Cu")
		(net "M_B_DQ<60>")
	)
	(segment
		(start 306.014882 -29.649674)
		(end 308.207156 -27.4574)
		(width 0.14224)
		(layer "In4.Cu")
		(net "M_B_DQ<60>")
	)
	(segment
		(start 308.019196 -17.050258)
		(end 308.247796 -16.821658)
		(width 0.14224)
		(layer "In4.Cu")
		(net "M_B_DQ<60>")
	)
	(segment
		(start 301.992792 -32.812736)
		(end 302.278542 -33.098486)
		(width 0.14224)
		(layer "In4.Cu")
		(net "M_B_DQ<60>")
	)
	(segment
		(start 302.853344 -32.523684)
		(end 302.567594 -32.237934)
		(width 0.14224)
		(layer "In4.Cu")
		(net "M_B_DQ<60>")
	)
	(segment
		(start 286.80664 -49.098708)
		(end 291.643308 -44.26204)
		(width 0.14224)
		(layer "In4.Cu")
		(net "M_B_DQ<60>")
	)
	(segment
		(start 308.273196 -18.568162)
		(end 308.019196 -18.314162)
		(width 0.14224)
		(layer "In4.Cu")
		(net "M_B_DQ<60>")
	)
	(segment
		(start 305.152552 -30.224476)
		(end 304.866802 -29.938726)
		(width 0.14224)
		(layer "In4.Cu")
		(net "M_B_DQ<60>")
	)
	(segment
		(start 286.419798 -49.48555)
		(end 286.80664 -49.098708)
		(width 0.0889)
		(layer "In4.Cu")
		(net "M_B_DQ<60>")
	)
	(segment
		(start 285.04134 -50.56124)
		(end 286.11703 -49.48555)
		(width 0.0889)
		(layer "In4.Cu")
		(net "M_B_DQ<60>")
	)
	(segment
		(start 283.846524 -55.609236)
		(end 283.85135 -55.6006)
		(width 0.0889)
		(layer "In4.Cu")
		(net "M_B_DQ<60>")
	)
	(segment
		(start 302.854868 -31.663132)
		(end 303.142396 -31.663132)
		(width 0.14224)
		(layer "In4.Cu")
		(net "M_B_DQ<60>")
	)
	(segment
		(start 308.019196 -23.169372)
		(end 308.019196 -21.913596)
		(width 0.14224)
		(layer "In4.Cu")
		(net "M_B_DQ<60>")
	)
	(segment
		(start 291.643308 -44.26204)
		(end 293.417752 -44.26204)
		(width 0.14224)
		(layer "In4.Cu")
		(net "M_B_DQ<60>")
	)
	(segment
		(start 304.002948 -31.37408)
		(end 303.717198 -31.08833)
		(width 0.14224)
		(layer "In4.Cu")
		(net "M_B_DQ<60>")
	)
	(segment
		(start 308.207156 -23.357332)
		(end 308.019196 -23.169372)
		(width 0.14224)
		(layer "In4.Cu")
		(net "M_B_DQ<60>")
	)
	(segment
		(start 301.70374 -33.960816)
		(end 301.70374 -33.673288)
		(width 0.14224)
		(layer "In4.Cu")
		(net "M_B_DQ<60>")
	)
	(segment
		(start 283.83738 -53.643276)
		(end 283.84627 -53.628036)
		(width 0.0889)
		(layer "In4.Cu")
		(net "M_B_DQ<60>")
	)
	(segment
		(start 282.623514 -57.295034)
		(end 282.65628 -57.295034)
		(width 0.0889)
		(layer "In4.Cu")
		(net "M_B_DQ<60>")
	)
	(segment
		(start 301.70374 -33.673288)
		(end 301.41799 -33.387538)
		(width 0.14224)
		(layer "In4.Cu")
		(net "M_B_DQ<60>")
	)
	(segment
		(start 304.866802 -29.938726)
		(end 304.866802 -29.651198)
		(width 0.14224)
		(layer "In4.Cu")
		(net "M_B_DQ<60>")
	)
	(segment
		(start 302.853344 -32.811212)
		(end 302.853344 -32.523684)
		(width 0.14224)
		(layer "In4.Cu")
		(net "M_B_DQ<60>")
	)
	(segment
		(start 303.142396 -31.663132)
		(end 303.428146 -31.948882)
		(width 0.14224)
		(layer "In4.Cu")
		(net "M_B_DQ<60>")
	)
	(segment
		(start 304.004472 -30.513528)
		(end 304.292 -30.513528)
		(width 0.14224)
		(layer "In4.Cu")
		(net "M_B_DQ<60>")
	)
	(segment
		(start 284.33649 -51.351434)
		(end 284.46222 -51.351434)
		(width 0.0889)
		(layer "In4.Cu")
		(net "M_B_DQ<60>")
	)
	(segment
		(start 302.56607 -33.098486)
		(end 302.853344 -32.811212)
		(width 0.14224)
		(layer "In4.Cu")
		(net "M_B_DQ<60>")
	)
	(segment
		(start 307.749956 -13.959078)
		(end 307.514244 -13.723366)
		(width 0.14224)
		(layer "In4.Cu")
		(net "M_B_DQ<60>")
	)
	(segment
		(start 308.019196 -21.913596)
		(end 308.273196 -21.659596)
		(width 0.14224)
		(layer "In4.Cu")
		(net "M_B_DQ<60>")
	)
	(segment
		(start 304.57775 -30.799278)
		(end 304.865278 -30.799278)
		(width 0.14224)
		(layer "In4.Cu")
		(net "M_B_DQ<60>")
	)
	(segment
		(start 285.04134 -50.772314)
		(end 285.04134 -50.56124)
		(width 0.0889)
		(layer "In4.Cu")
		(net "M_B_DQ<60>")
	)
	(segment
		(start 308.247796 -14.456918)
		(end 307.749956 -13.959078)
		(width 0.14224)
		(layer "In4.Cu")
		(net "M_B_DQ<60>")
	)
	(segment
		(start 282.129484 -59.171586)
		(end 282.123134 -59.160918)
		(width 0.0889)
		(layer "In4.Cu")
		(net "M_B_DQ<60>")
	)
	(segment
		(start 308.225444 -11.742928)
		(end 307.874162 -11.391646)
		(width 0.14224)
		(layer "In4.Cu")
		(net "M_B_DQ<60>")
	)
	(segment
		(start 286.11703 -49.48555)
		(end 286.419798 -49.48555)
		(width 0.0889)
		(layer "In4.Cu")
		(net "M_B_DQ<60>")
	)
	(segment
		(start 308.247796 -16.821658)
		(end 308.247796 -14.456918)
		(width 0.14224)
		(layer "In4.Cu")
		(net "M_B_DQ<60>")
	)
	(segment
		(start 301.41799 -33.387538)
		(end 301.41799 -33.10001)
		(width 0.14224)
		(layer "In4.Cu")
		(net "M_B_DQ<60>")
	)
	(segment
		(start 307.861462 -9.9822)
		(end 307.861462 -9.677654)
		(width 0.14224)
		(layer "In4.Cu")
		(net "M_B_DQ<60>")
	)
	(segment
		(start 302.567594 -32.237934)
		(end 302.567594 -31.950406)
		(width 0.14224)
		(layer "In4.Cu")
		(net "M_B_DQ<60>")
	)
	(segment
		(start 308.225444 -12.217654)
		(end 308.225444 -11.742928)
		(width 0.14224)
		(layer "In4.Cu")
		(net "M_B_DQ<60>")
	)
	(segment
		(start 303.717198 -31.08833)
		(end 303.717198 -30.800802)
		(width 0.14224)
		(layer "In4.Cu")
		(net "M_B_DQ<60>")
	)
	(segment
		(start 307.874162 -11.0363)
		(end 308.242462 -10.668)
		(width 0.14224)
		(layer "In4.Cu")
		(net "M_B_DQ<60>")
	)
	(segment
		(start 308.242462 -10.668)
		(end 308.242462 -10.3632)
		(width 0.14224)
		(layer "In4.Cu")
		(net "M_B_DQ<60>")
	)
	(segment
		(start 283.478224 -56.799988)
		(end 283.51099 -56.799988)
		(width 0.0889)
		(layer "In4.Cu")
		(net "M_B_DQ<60>")
	)
	(segment
		(start 282.146248 -59.20105)
		(end 282.129484 -59.171586)
		(width 0.0889)
		(layer "In4.Cu")
		(net "M_B_DQ<60>")
	)
	(segment
		(start 308.242462 -10.3632)
		(end 307.861462 -9.9822)
		(width 0.14224)
		(layer "In4.Cu")
		(net "M_B_DQ<60>")
	)
	(segment
		(start 307.514244 -13.723366)
		(end 307.514244 -12.928854)
		(width 0.14224)
		(layer "In4.Cu")
		(net "M_B_DQ<60>")
	)
	(segment
		(start 307.861462 -9.677654)
		(end 308.225444 -9.313672)
		(width 0.14224)
		(layer "In4.Cu")
		(net "M_B_DQ<60>")
	)
	(segment
		(start 308.019196 -18.314162)
		(end 308.019196 -17.050258)
		(width 0.14224)
		(layer "In4.Cu")
		(net "M_B_DQ<60>")
	)
	(segment
		(start 305.154076 -29.363924)
		(end 305.441604 -29.363924)
		(width 0.14224)
		(layer "In4.Cu")
		(net "M_B_DQ<60>")
	)
	(segment
		(start 307.874162 -11.391646)
		(end 307.874162 -11.0363)
		(width 0.14224)
		(layer "In4.Cu")
		(net "M_B_DQ<60>")
	)
	(segment
		(start 308.225444 -9.313672)
		(end 308.225444 -8.836152)
		(width 0.14224)
		(layer "In4.Cu")
		(net "M_B_DQ<60>")
	)
	(segment
		(start 308.225444 -8.836152)
		(end 308.501796 -8.5598)
		(width 0.14224)
		(layer "In4.Cu")
		(net "M_B_DQ<60>")
	)
	(segment
		(start 303.715674 -31.948882)
		(end 304.002948 -31.661608)
		(width 0.14224)
		(layer "In4.Cu")
		(net "M_B_DQ<60>")
	)
	(segment
		(start 308.207156 -27.4574)
		(end 308.207156 -23.357332)
		(width 0.14224)
		(layer "In4.Cu")
		(net "M_B_DQ<60>")
	)
	(segment
		(start 283.840174 -54.629304)
		(end 283.846524 -54.618636)
		(width 0.0889)
		(layer "In4.Cu")
		(net "M_B_DQ<60>")
	)
	(segment
		(start 300.1772 -37.502592)
		(end 300.1772 -35.487356)
		(width 0.14224)
		(layer "In4.Cu")
		(net "M_B_DQ<60>")
	)
	(segment
		(start 304.865278 -30.799278)
		(end 305.152552 -30.512004)
		(width 0.14224)
		(layer "In4.Cu")
		(net "M_B_DQ<60>")
	)
	(segment
		(start 304.002948 -31.661608)
		(end 304.002948 -31.37408)
		(width 0.14224)
		(layer "In4.Cu")
		(net "M_B_DQ<60>")
	)
	(segment
		(start 305.152552 -30.512004)
		(end 305.152552 -30.224476)
		(width 0.14224)
		(layer "In4.Cu")
		(net "M_B_DQ<60>")
	)
	(segment
		(start 308.273196 -21.659596)
		(end 308.273196 -18.568162)
		(width 0.14224)
		(layer "In4.Cu")
		(net "M_B_DQ<60>")
	)
	(segment
		(start 302.567594 -31.950406)
		(end 302.854868 -31.663132)
		(width 0.14224)
		(layer "In4.Cu")
		(net "M_B_DQ<60>")
	)
	(segment
		(start 293.417752 -44.26204)
		(end 300.1772 -37.502592)
		(width 0.14224)
		(layer "In4.Cu")
		(net "M_B_DQ<60>")
	)
	(segment
		(start 303.717198 -30.800802)
		(end 304.004472 -30.513528)
		(width 0.14224)
		(layer "In4.Cu")
		(net "M_B_DQ<60>")
	)
	(segment
		(start 300.1772 -35.487356)
		(end 301.70374 -33.960816)
		(width 0.14224)
		(layer "In4.Cu")
		(net "M_B_DQ<60>")
	)
	(segment
		(start 284.46222 -51.351434)
		(end 285.04134 -50.772314)
		(width 0.0889)
		(layer "In4.Cu")
		(net "M_B_DQ<60>")
	)
	(segment
		(start 305.727354 -29.649674)
		(end 306.014882 -29.649674)
		(width 0.14224)
		(layer "In4.Cu")
		(net "M_B_DQ<60>")
	)
	(segment
		(start 304.866802 -29.651198)
		(end 305.154076 -29.363924)
		(width 0.14224)
		(layer "In4.Cu")
		(net "M_B_DQ<60>")
	)
	(segment
		(start 283.840174 -55.619904)
		(end 283.846524 -55.609236)
		(width 0.0889)
		(layer "In4.Cu")
		(net "M_B_DQ<60>")
	)
	(segment
		(start 303.428146 -31.948882)
		(end 303.715674 -31.948882)
		(width 0.14224)
		(layer "In4.Cu")
		(net "M_B_DQ<60>")
	)
	(segment
		(start 283.83992 -52.64785)
		(end 283.84627 -52.637182)
		(width 0.0889)
		(layer "In4.Cu")
		(net "M_B_DQ<60>")
	)
	(segment
		(start 282.641294 -59.866784)
		(end 282.146248 -59.20105)
		(width 0.0889)
		(layer "In4.Cu")
		(net "M_B_DQ<60>")
	)
	(segment
		(start 301.705264 -32.812736)
		(end 301.992792 -32.812736)
		(width 0.14224)
		(layer "In4.Cu")
		(net "M_B_DQ<60>")
	)
	(segment
		(start 283.852874 -54.23027)
		(end 283.84627 -54.21884)
		(width 0.0889)
		(layer "In4.Cu")
		(net "M_B_DQ<60>")
	)
	(segment
		(start 302.278542 -33.098486)
		(end 302.56607 -33.098486)
		(width 0.14224)
		(layer "In4.Cu")
		(net "M_B_DQ<60>")
	)
	(segment
		(start 301.41799 -33.10001)
		(end 301.705264 -32.812736)
		(width 0.14224)
		(layer "In4.Cu")
		(net "M_B_DQ<60>")
	)
	(segment
		(start 305.441604 -29.363924)
		(end 305.727354 -29.649674)
		(width 0.14224)
		(layer "In4.Cu")
		(net "M_B_DQ<60>")
	)
	(segment
		(start 304.292 -30.513528)
		(end 304.57775 -30.799278)
		(width 0.14224)
		(layer "In4.Cu")
		(net "M_B_DQ<60>")
	)
	(arc
		(start 282.129484 -58.581036)
		(mid 282.183051 -58.381028)
		(end 282.129484 -58.180986)
		(width 0.0889)
		(layer "In4.Cu")
		(net "M_B_DQ<60>")
	)
	(arc
		(start 283.85135 -55.6006)
		(mid 283.900105 -55.404248)
		(end 283.846524 -55.209186)
		(width 0.0889)
		(layer "In4.Cu")
		(net "M_B_DQ<60>")
	)
	(arc
		(start 283.846524 -55.209186)
		(mid 283.767302 -54.920068)
		(end 283.840174 -54.629304)
		(width 0.0889)
		(layer "In4.Cu")
		(net "M_B_DQ<60>")
	)
	(arc
		(start 282.123134 -59.160918)
		(mid 282.050336 -58.870155)
		(end 282.129484 -58.581036)
		(width 0.0889)
		(layer "In4.Cu")
		(net "M_B_DQ<60>")
	)
	(arc
		(start 282.65628 -57.295034)
		(mid 282.847922 -57.237868)
		(end 282.988004 -57.095136)
		(width 0.0889)
		(layer "In4.Cu")
		(net "M_B_DQ<60>")
	)
	(arc
		(start 283.51099 -56.799988)
		(mid 283.849159 -56.59519)
		(end 283.846524 -56.199786)
		(width 0.0889)
		(layer "In4.Cu")
		(net "M_B_DQ<60>")
	)
	(arc
		(start 283.84627 -53.628036)
		(mid 283.899803 -53.428138)
		(end 283.84627 -53.22824)
		(width 0.0889)
		(layer "In4.Cu")
		(net "M_B_DQ<60>")
	)
	(arc
		(start 282.129484 -58.180986)
		(mid 282.125155 -57.597814)
		(end 282.623514 -57.295034)
		(width 0.0889)
		(layer "In4.Cu")
		(net "M_B_DQ<60>")
	)
	(arc
		(start 283.84627 -53.22824)
		(mid 283.766921 -52.938868)
		(end 283.83992 -52.64785)
		(width 0.0889)
		(layer "In4.Cu")
		(net "M_B_DQ<60>")
	)
	(arc
		(start 283.846524 -54.618636)
		(mid 283.899969 -54.425276)
		(end 283.852874 -54.23027)
		(width 0.0889)
		(layer "In4.Cu")
		(net "M_B_DQ<60>")
	)
	(arc
		(start 282.988004 -57.095136)
		(mid 283.195008 -56.884272)
		(end 283.478224 -56.799988)
		(width 0.0889)
		(layer "In4.Cu")
		(net "M_B_DQ<60>")
	)
	(arc
		(start 283.846524 -56.199786)
		(mid 283.767302 -55.910668)
		(end 283.840174 -55.619904)
		(width 0.0889)
		(layer "In4.Cu")
		(net "M_B_DQ<60>")
	)
	(arc
		(start 283.84627 -52.637182)
		(mid 283.899803 -52.437284)
		(end 283.84627 -52.237386)
		(width 0.0889)
		(layer "In4.Cu")
		(net "M_B_DQ<60>")
	)
	(arc
		(start 283.84627 -52.237386)
		(mid 283.841016 -51.655878)
		(end 284.33649 -51.351434)
		(width 0.0889)
		(layer "In4.Cu")
		(net "M_B_DQ<60>")
	)
	(arc
		(start 283.84627 -54.21884)
		(mid 283.767081 -53.932225)
		(end 283.83738 -53.643276)
		(width 0.0889)
		(layer "In4.Cu")
		(net "M_B_DQ<60>")
	)
	(segment
		(start 196.399912 -5.822442)
		(end 196.399912 -7.086346)
		(width 0.1651)
		(layer "F.Cu")
		(net "M_B_DQ<5>")
	)
	(segment
		(start 238.759238 -67.972686)
		(end 238.187738 -67.972686)
		(width 0.0889)
		(layer "F.Cu")
		(net "M_B_DQ<5>")
	)
	(segment
		(start 196.40042 -5.822442)
		(end 196.399912 -5.822442)
		(width 0.1651)
		(layer "F.Cu")
		(net "M_B_DQ<5>")
	)
	(via
		(at 238.187738 -67.972686)
		(size 0.508)
		(drill 0.254)
		(layers "F.Cu" "B.Cu")
		(net "M_B_DQ<5>")
	)
	(via
		(at 197.173596 -12.678156)
		(size 0.508)
		(drill 0.254)
		(layers "F.Cu" "B.Cu")
		(net "M_B_DQ<5>")
	)
	(via
		(at 196.399912 -7.086346)
		(size 0.508)
		(drill 0.254)
		(layers "F.Cu" "B.Cu")
		(net "M_B_DQ<5>")
	)
	(segment
		(start 197.173596 -12.148058)
		(end 197.173596 -12.678156)
		(width 0.1651)
		(layer "B.Cu")
		(net "M_B_DQ<5>")
	)
	(segment
		(start 197.249796 -12.071858)
		(end 197.173596 -12.148058)
		(width 0.1651)
		(layer "B.Cu")
		(net "M_B_DQ<5>")
	)
	(segment
		(start 197.249796 -10.623042)
		(end 197.249796 -12.071858)
		(width 0.1651)
		(layer "B.Cu")
		(net "M_B_DQ<5>")
	)
	(segment
		(start 197.250304 -10.623042)
		(end 197.249796 -10.623042)
		(width 0.1651)
		(layer "B.Cu")
		(net "M_B_DQ<5>")
	)
	(segment
		(start 197.485 -14.35862)
		(end 197.485 -16.891)
		(width 0.14224)
		(layer "In4.Cu")
		(net "M_B_DQ<5>")
	)
	(segment
		(start 197.5866 -21.8948)
		(end 197.6374 -21.9456)
		(width 0.14224)
		(layer "In4.Cu")
		(net "M_B_DQ<5>")
	)
	(segment
		(start 235.590588 -69.85889)
		(end 235.623354 -69.85889)
		(width 0.0889)
		(layer "In4.Cu")
		(net "M_B_DQ<5>")
	)
	(segment
		(start 197.485 -16.891)
		(end 197.612 -17.018)
		(width 0.14224)
		(layer "In4.Cu")
		(net "M_B_DQ<5>")
	)
	(segment
		(start 197.68185 -8.8646)
		(end 197.485 -9.06145)
		(width 0.14224)
		(layer "In4.Cu")
		(net "M_B_DQ<5>")
	)
	(segment
		(start 236.817408 -68.763388)
		(end 236.811058 -68.75272)
		(width 0.0889)
		(layer "In4.Cu")
		(net "M_B_DQ<5>")
	)
	(segment
		(start 196.399912 -7.086346)
		(end 196.399912 -7.481062)
		(width 0.14224)
		(layer "In4.Cu")
		(net "M_B_DQ<5>")
	)
	(segment
		(start 197.68185 -8.452104)
		(end 197.68185 -8.8646)
		(width 0.14224)
		(layer "In4.Cu")
		(net "M_B_DQ<5>")
	)
	(segment
		(start 236.822234 -68.772024)
		(end 236.817408 -68.763388)
		(width 0.0889)
		(layer "In4.Cu")
		(net "M_B_DQ<5>")
	)
	(segment
		(start 197.485 -12.366752)
		(end 197.173596 -12.678156)
		(width 0.14224)
		(layer "In4.Cu")
		(net "M_B_DQ<5>")
	)
	(segment
		(start 218.694 -58.2803)
		(end 218.9734 -58.2803)
		(width 0.14224)
		(layer "In4.Cu")
		(net "M_B_DQ<5>")
	)
	(segment
		(start 197.281546 -8.0518)
		(end 197.68185 -8.452104)
		(width 0.14224)
		(layer "In4.Cu")
		(net "M_B_DQ<5>")
	)
	(segment
		(start 232.414826 -68.9991)
		(end 232.638092 -69.222366)
		(width 0.14224)
		(layer "In4.Cu")
		(net "M_B_DQ<5>")
	)
	(segment
		(start 233.00563 -69.388736)
		(end 233.159554 -69.400166)
		(width 0.0889)
		(layer "In4.Cu")
		(net "M_B_DQ<5>")
	)
	(segment
		(start 196.669152 -13.542772)
		(end 197.485 -14.35862)
		(width 0.14224)
		(layer "In4.Cu")
		(net "M_B_DQ<5>")
	)
	(segment
		(start 196.97065 -8.0518)
		(end 197.281546 -8.0518)
		(width 0.14224)
		(layer "In4.Cu")
		(net "M_B_DQ<5>")
	)
	(segment
		(start 197.6374 -37.2237)
		(end 218.694 -58.2803)
		(width 0.14224)
		(layer "In4.Cu")
		(net "M_B_DQ<5>")
	)
	(segment
		(start 233.698288 -69.85889)
		(end 233.916728 -69.85889)
		(width 0.0889)
		(layer "In4.Cu")
		(net "M_B_DQ<5>")
	)
	(segment
		(start 232.804462 -69.388736)
		(end 233.00563 -69.388736)
		(width 0.0889)
		(layer "In4.Cu")
		(net "M_B_DQ<5>")
	)
	(segment
		(start 218.9734 -58.2803)
		(end 229.6922 -68.9991)
		(width 0.14224)
		(layer "In4.Cu")
		(net "M_B_DQ<5>")
	)
	(segment
		(start 237.318042 -68.068444)
		(end 237.365794 -68.068444)
		(width 0.0889)
		(layer "In4.Cu")
		(net "M_B_DQ<5>")
	)
	(segment
		(start 234.738672 -70.353936)
		(end 234.768644 -70.353936)
		(width 0.0889)
		(layer "In4.Cu")
		(net "M_B_DQ<5>")
	)
	(segment
		(start 237.365794 -68.068444)
		(end 238.187738 -67.972686)
		(width 0.0889)
		(layer "In4.Cu")
		(net "M_B_DQ<5>")
	)
	(segment
		(start 232.638092 -69.222366)
		(end 232.804462 -69.388736)
		(width 0.0889)
		(layer "In4.Cu")
		(net "M_B_DQ<5>")
	)
	(segment
		(start 197.5866 -18.3896)
		(end 197.5866 -21.8948)
		(width 0.14224)
		(layer "In4.Cu")
		(net "M_B_DQ<5>")
	)
	(segment
		(start 197.173596 -12.678156)
		(end 196.669152 -13.1826)
		(width 0.14224)
		(layer "In4.Cu")
		(net "M_B_DQ<5>")
	)
	(segment
		(start 229.6922 -68.9991)
		(end 232.414826 -68.9991)
		(width 0.14224)
		(layer "In4.Cu")
		(net "M_B_DQ<5>")
	)
	(segment
		(start 197.6374 -21.9456)
		(end 197.6374 -37.2237)
		(width 0.14224)
		(layer "In4.Cu")
		(net "M_B_DQ<5>")
	)
	(segment
		(start 197.485 -9.06145)
		(end 197.485 -12.366752)
		(width 0.14224)
		(layer "In4.Cu")
		(net "M_B_DQ<5>")
	)
	(segment
		(start 197.612 -18.3642)
		(end 197.5866 -18.3896)
		(width 0.14224)
		(layer "In4.Cu")
		(net "M_B_DQ<5>")
	)
	(segment
		(start 197.612 -17.018)
		(end 197.612 -18.3642)
		(width 0.14224)
		(layer "In4.Cu")
		(net "M_B_DQ<5>")
	)
	(segment
		(start 196.669152 -13.1826)
		(end 196.669152 -13.542772)
		(width 0.14224)
		(layer "In4.Cu")
		(net "M_B_DQ<5>")
	)
	(segment
		(start 196.399912 -7.481062)
		(end 196.97065 -8.0518)
		(width 0.14224)
		(layer "In4.Cu")
		(net "M_B_DQ<5>")
	)
	(segment
		(start 236.452918 -69.363336)
		(end 236.485684 -69.363336)
		(width 0.0889)
		(layer "In4.Cu")
		(net "M_B_DQ<5>")
	)
	(arc
		(start 236.811058 -68.75272)
		(mid 236.751427 -68.516183)
		(end 236.831124 -68.285614)
		(width 0.0889)
		(layer "In4.Cu")
		(net "M_B_DQ<5>")
	)
	(arc
		(start 234.768644 -70.353936)
		(mid 234.960286 -70.29677)
		(end 235.100368 -70.154038)
		(width 0.0889)
		(layer "In4.Cu")
		(net "M_B_DQ<5>")
	)
	(arc
		(start 234.406948 -70.154038)
		(mid 234.547027 -70.296774)
		(end 234.738672 -70.353936)
		(width 0.0889)
		(layer "In4.Cu")
		(net "M_B_DQ<5>")
	)
	(arc
		(start 235.100368 -70.154038)
		(mid 235.307372 -69.943174)
		(end 235.590588 -69.85889)
		(width 0.0889)
		(layer "In4.Cu")
		(net "M_B_DQ<5>")
	)
	(arc
		(start 236.831124 -68.285614)
		(mid 236.981373 -68.153221)
		(end 237.174278 -68.099432)
		(width 0.0889)
		(layer "In4.Cu")
		(net "M_B_DQ<5>")
	)
	(arc
		(start 235.958888 -69.658738)
		(mid 236.167496 -69.446806)
		(end 236.452918 -69.363336)
		(width 0.0889)
		(layer "In4.Cu")
		(net "M_B_DQ<5>")
	)
	(arc
		(start 235.623354 -69.85889)
		(mid 235.817204 -69.80254)
		(end 235.958888 -69.658738)
		(width 0.0889)
		(layer "In4.Cu")
		(net "M_B_DQ<5>")
	)
	(arc
		(start 237.174278 -68.099432)
		(mid 237.244726 -68.077293)
		(end 237.318042 -68.068444)
		(width 0.0889)
		(layer "In4.Cu")
		(net "M_B_DQ<5>")
	)
	(arc
		(start 233.159554 -69.400166)
		(mid 233.360719 -69.509854)
		(end 233.510074 -69.68363)
		(width 0.0889)
		(layer "In4.Cu")
		(net "M_B_DQ<5>")
	)
	(arc
		(start 233.916728 -69.85889)
		(mid 234.199945 -69.943171)
		(end 234.406948 -70.154038)
		(width 0.0889)
		(layer "In4.Cu")
		(net "M_B_DQ<5>")
	)
	(arc
		(start 236.485684 -69.363336)
		(mid 236.818602 -69.161345)
		(end 236.822234 -68.772024)
		(width 0.0889)
		(layer "In4.Cu")
		(net "M_B_DQ<5>")
	)
	(arc
		(start 233.510074 -69.68363)
		(mid 233.591266 -69.785132)
		(end 233.698288 -69.85889)
		(width 0.0889)
		(layer "In4.Cu")
		(net "M_B_DQ<5>")
	)
	(segment
		(start 315.400436 -5.822442)
		(end 315.399928 -5.822442)
		(width 0.1651)
		(layer "F.Cu")
		(net "M_B_DQ<59>")
	)
	(segment
		(start 315.399928 -5.822442)
		(end 315.399928 -7.086346)
		(width 0.1651)
		(layer "F.Cu")
		(net "M_B_DQ<59>")
	)
	(segment
		(start 286.64662 -60.857384)
		(end 286.07512 -60.857384)
		(width 0.1016)
		(layer "F.Cu")
		(net "M_B_DQ<59>")
	)
	(via
		(at 316.249812 -12.678156)
		(size 0.508)
		(drill 0.254)
		(layers "F.Cu" "B.Cu")
		(net "M_B_DQ<59>")
	)
	(via
		(at 315.399928 -7.086346)
		(size 0.508)
		(drill 0.254)
		(layers "F.Cu" "B.Cu")
		(net "M_B_DQ<59>")
	)
	(via
		(at 286.07512 -60.857384)
		(size 0.508)
		(drill 0.254)
		(layers "F.Cu" "B.Cu")
		(net "M_B_DQ<59>")
	)
	(segment
		(start 316.249812 -10.623042)
		(end 316.249812 -12.678156)
		(width 0.1651)
		(layer "B.Cu")
		(net "M_B_DQ<59>")
	)
	(segment
		(start 316.25032 -10.623042)
		(end 316.249812 -10.623042)
		(width 0.1651)
		(layer "B.Cu")
		(net "M_B_DQ<59>")
	)
	(segment
		(start 316.617096 -14.419072)
		(end 315.766196 -13.568172)
		(width 0.14224)
		(layer "In4.Cu")
		(net "M_B_DQ<59>")
	)
	(segment
		(start 316.782196 -23.118572)
		(end 316.782196 -22.000972)
		(width 0.14224)
		(layer "In4.Cu")
		(net "M_B_DQ<59>")
	)
	(segment
		(start 288.31032 -57.601104)
		(end 288.30397 -57.590436)
		(width 0.0889)
		(layer "In4.Cu")
		(net "M_B_DQ<59>")
	)
	(segment
		(start 315.766196 -13.161772)
		(end 316.249812 -12.678156)
		(width 0.14224)
		(layer "In4.Cu")
		(net "M_B_DQ<59>")
	)
	(segment
		(start 315.716666 -7.403084)
		(end 315.399928 -7.086346)
		(width 0.14224)
		(layer "In4.Cu")
		(net "M_B_DQ<59>")
	)
	(segment
		(start 288.30397 -55.609236)
		(end 288.299144 -55.6006)
		(width 0.0889)
		(layer "In4.Cu")
		(net "M_B_DQ<59>")
	)
	(segment
		(start 316.756796 -18.447258)
		(end 316.756796 -17.031462)
		(width 0.14224)
		(layer "In4.Cu")
		(net "M_B_DQ<59>")
	)
	(segment
		(start 288.31032 -54.629304)
		(end 288.30397 -54.618636)
		(width 0.0889)
		(layer "In4.Cu")
		(net "M_B_DQ<59>")
	)
	(segment
		(start 286.07512 -60.51931)
		(end 286.140144 -60.454286)
		(width 0.0889)
		(layer "In4.Cu")
		(net "M_B_DQ<59>")
	)
	(segment
		(start 316.64275 -30.09519)
		(end 316.64275 -23.258018)
		(width 0.14224)
		(layer "In4.Cu")
		(net "M_B_DQ<59>")
	)
	(segment
		(start 288.635694 -54.018688)
		(end 289.704272 -54.018688)
		(width 0.0889)
		(layer "In4.Cu")
		(net "M_B_DQ<59>")
	)
	(segment
		(start 316.249812 -12.678156)
		(end 316.602618 -12.32535)
		(width 0.14224)
		(layer "In4.Cu")
		(net "M_B_DQ<59>")
	)
	(segment
		(start 286.07512 -60.857384)
		(end 286.07512 -60.51931)
		(width 0.0889)
		(layer "In4.Cu")
		(net "M_B_DQ<59>")
	)
	(segment
		(start 316.300866 -8.0518)
		(end 316.046866 -8.0518)
		(width 0.14224)
		(layer "In4.Cu")
		(net "M_B_DQ<59>")
	)
	(segment
		(start 288.30397 -54.618636)
		(end 288.299144 -54.61)
		(width 0.0889)
		(layer "In4.Cu")
		(net "M_B_DQ<59>")
	)
	(segment
		(start 291.03066 -52.6923)
		(end 291.617146 -52.6923)
		(width 0.0889)
		(layer "In4.Cu")
		(net "M_B_DQ<59>")
	)
	(segment
		(start 288.31032 -55.619904)
		(end 288.30397 -55.609236)
		(width 0.0889)
		(layer "In4.Cu")
		(net "M_B_DQ<59>")
	)
	(segment
		(start 316.602618 -9.020048)
		(end 316.758066 -8.8646)
		(width 0.14224)
		(layer "In4.Cu")
		(net "M_B_DQ<59>")
	)
	(segment
		(start 316.758066 -8.509)
		(end 316.300866 -8.0518)
		(width 0.14224)
		(layer "In4.Cu")
		(net "M_B_DQ<59>")
	)
	(segment
		(start 316.756796 -17.031462)
		(end 316.617096 -16.891762)
		(width 0.14224)
		(layer "In4.Cu")
		(net "M_B_DQ<59>")
	)
	(segment
		(start 295.199816 -49.10963)
		(end 297.62831 -49.10963)
		(width 0.14224)
		(layer "In4.Cu")
		(net "M_B_DQ<59>")
	)
	(segment
		(start 316.604396 -21.823172)
		(end 316.604396 -18.599658)
		(width 0.14224)
		(layer "In4.Cu")
		(net "M_B_DQ<59>")
	)
	(segment
		(start 287.774126 -59.466988)
		(end 287.80994 -59.466988)
		(width 0.0889)
		(layer "In4.Cu")
		(net "M_B_DQ<59>")
	)
	(segment
		(start 288.31032 -56.610504)
		(end 288.30397 -56.599836)
		(width 0.0889)
		(layer "In4.Cu")
		(net "M_B_DQ<59>")
	)
	(segment
		(start 316.602618 -12.32535)
		(end 316.602618 -9.020048)
		(width 0.14224)
		(layer "In4.Cu")
		(net "M_B_DQ<59>")
	)
	(segment
		(start 316.782196 -22.000972)
		(end 316.604396 -21.823172)
		(width 0.14224)
		(layer "In4.Cu")
		(net "M_B_DQ<59>")
	)
	(segment
		(start 291.617146 -52.6923)
		(end 295.199816 -49.10963)
		(width 0.14224)
		(layer "In4.Cu")
		(net "M_B_DQ<59>")
	)
	(segment
		(start 316.64275 -23.258018)
		(end 316.782196 -23.118572)
		(width 0.14224)
		(layer "In4.Cu")
		(net "M_B_DQ<59>")
	)
	(segment
		(start 288.30397 -57.590436)
		(end 288.299144 -57.5818)
		(width 0.0889)
		(layer "In4.Cu")
		(net "M_B_DQ<59>")
	)
	(segment
		(start 316.758066 -8.8646)
		(end 316.758066 -8.509)
		(width 0.14224)
		(layer "In4.Cu")
		(net "M_B_DQ<59>")
	)
	(segment
		(start 315.766196 -13.568172)
		(end 315.766196 -13.161772)
		(width 0.14224)
		(layer "In4.Cu")
		(net "M_B_DQ<59>")
	)
	(segment
		(start 289.704272 -54.018688)
		(end 291.03066 -52.6923)
		(width 0.0889)
		(layer "In4.Cu")
		(net "M_B_DQ<59>")
	)
	(segment
		(start 316.604396 -18.599658)
		(end 316.756796 -18.447258)
		(width 0.14224)
		(layer "In4.Cu")
		(net "M_B_DQ<59>")
	)
	(segment
		(start 297.62831 -49.10963)
		(end 316.64275 -30.09519)
		(width 0.14224)
		(layer "In4.Cu")
		(net "M_B_DQ<59>")
	)
	(segment
		(start 316.617096 -16.891762)
		(end 316.617096 -14.419072)
		(width 0.14224)
		(layer "In4.Cu")
		(net "M_B_DQ<59>")
	)
	(segment
		(start 288.30397 -56.599836)
		(end 288.299144 -56.5912)
		(width 0.0889)
		(layer "In4.Cu")
		(net "M_B_DQ<59>")
	)
	(segment
		(start 288.30397 -58.581036)
		(end 288.299144 -58.5724)
		(width 0.0889)
		(layer "In4.Cu")
		(net "M_B_DQ<59>")
	)
	(segment
		(start 316.046866 -8.0518)
		(end 315.716666 -7.7216)
		(width 0.14224)
		(layer "In4.Cu")
		(net "M_B_DQ<59>")
	)
	(segment
		(start 315.716666 -7.7216)
		(end 315.716666 -7.403084)
		(width 0.14224)
		(layer "In4.Cu")
		(net "M_B_DQ<59>")
	)
	(segment
		(start 286.918654 -59.962288)
		(end 286.946594 -59.962288)
		(width 0.0889)
		(layer "In4.Cu")
		(net "M_B_DQ<59>")
	)
	(arc
		(start 288.30397 -57.190386)
		(mid 288.383192 -56.901268)
		(end 288.31032 -56.610504)
		(width 0.0889)
		(layer "In4.Cu")
		(net "M_B_DQ<59>")
	)
	(arc
		(start 286.58693 -60.162186)
		(mid 286.727009 -60.01945)
		(end 286.918654 -59.962288)
		(width 0.0889)
		(layer "In4.Cu")
		(net "M_B_DQ<59>")
	)
	(arc
		(start 288.299144 -55.6006)
		(mid 288.250389 -55.404248)
		(end 288.30397 -55.209186)
		(width 0.0889)
		(layer "In4.Cu")
		(net "M_B_DQ<59>")
	)
	(arc
		(start 287.80994 -59.466988)
		(mid 288.308191 -59.164148)
		(end 288.30397 -58.581036)
		(width 0.0889)
		(layer "In4.Cu")
		(net "M_B_DQ<59>")
	)
	(arc
		(start 288.299144 -54.61)
		(mid 288.302891 -54.220744)
		(end 288.635694 -54.018688)
		(width 0.0889)
		(layer "In4.Cu")
		(net "M_B_DQ<59>")
	)
	(arc
		(start 288.299144 -57.5818)
		(mid 288.250389 -57.385448)
		(end 288.30397 -57.190386)
		(width 0.0889)
		(layer "In4.Cu")
		(net "M_B_DQ<59>")
	)
	(arc
		(start 288.30397 -56.199786)
		(mid 288.383192 -55.910668)
		(end 288.31032 -55.619904)
		(width 0.0889)
		(layer "In4.Cu")
		(net "M_B_DQ<59>")
	)
	(arc
		(start 286.946594 -59.962288)
		(mid 287.234739 -59.879969)
		(end 287.44545 -59.666886)
		(width 0.0889)
		(layer "In4.Cu")
		(net "M_B_DQ<59>")
	)
	(arc
		(start 286.140144 -60.454286)
		(mid 286.398414 -60.361578)
		(end 286.58693 -60.162186)
		(width 0.0889)
		(layer "In4.Cu")
		(net "M_B_DQ<59>")
	)
	(arc
		(start 288.299144 -56.5912)
		(mid 288.250389 -56.394848)
		(end 288.30397 -56.199786)
		(width 0.0889)
		(layer "In4.Cu")
		(net "M_B_DQ<59>")
	)
	(arc
		(start 287.44545 -59.666886)
		(mid 287.584194 -59.524853)
		(end 287.774126 -59.466988)
		(width 0.0889)
		(layer "In4.Cu")
		(net "M_B_DQ<59>")
	)
	(arc
		(start 288.299144 -58.5724)
		(mid 288.250389 -58.376048)
		(end 288.30397 -58.180986)
		(width 0.0889)
		(layer "In4.Cu")
		(net "M_B_DQ<59>")
	)
	(arc
		(start 288.30397 -58.180986)
		(mid 288.383192 -57.891868)
		(end 288.31032 -57.601104)
		(width 0.0889)
		(layer "In4.Cu")
		(net "M_B_DQ<59>")
	)
	(arc
		(start 288.30397 -55.209186)
		(mid 288.383192 -54.920068)
		(end 288.31032 -54.629304)
		(width 0.0889)
		(layer "In4.Cu")
		(net "M_B_DQ<59>")
	)
	(segment
		(start 316.381384 -9.07034)
		(end 316.249812 -8.938768)
		(width 0.1651)
		(layer "F.Cu")
		(net "M_B_DQ<58>")
	)
	(segment
		(start 316.381384 -9.29386)
		(end 316.381384 -9.07034)
		(width 0.1651)
		(layer "F.Cu")
		(net "M_B_DQ<58>")
	)
	(segment
		(start 316.249812 -8.938768)
		(end 316.249812 -8.6614)
		(width 0.1651)
		(layer "F.Cu")
		(net "M_B_DQ<58>")
	)
	(segment
		(start 316.25032 -10.422382)
		(end 316.249812 -10.422382)
		(width 0.1651)
		(layer "F.Cu")
		(net "M_B_DQ<58>")
	)
	(segment
		(start 316.249812 -10.422382)
		(end 316.249812 -9.425432)
		(width 0.1651)
		(layer "F.Cu")
		(net "M_B_DQ<58>")
	)
	(segment
		(start 286.64662 -59.866784)
		(end 286.07512 -59.866784)
		(width 0.1016)
		(layer "F.Cu")
		(net "M_B_DQ<58>")
	)
	(segment
		(start 316.249812 -9.425432)
		(end 316.381384 -9.29386)
		(width 0.1651)
		(layer "F.Cu")
		(net "M_B_DQ<58>")
	)
	(via
		(at 286.07512 -59.866784)
		(size 0.508)
		(drill 0.254)
		(layers "F.Cu" "B.Cu")
		(net "M_B_DQ<58>")
	)
	(via
		(at 315.399928 -13.959078)
		(size 0.508)
		(drill 0.254)
		(layers "F.Cu" "B.Cu")
		(net "M_B_DQ<58>")
	)
	(via
		(at 316.249812 -8.6614)
		(size 0.508)
		(drill 0.254)
		(layers "F.Cu" "B.Cu")
		(net "M_B_DQ<58>")
	)
	(segment
		(start 315.400436 -15.222982)
		(end 315.399928 -15.222982)
		(width 0.1651)
		(layer "B.Cu")
		(net "M_B_DQ<58>")
	)
	(segment
		(start 315.399928 -15.222982)
		(end 315.399928 -13.959078)
		(width 0.1651)
		(layer "B.Cu")
		(net "M_B_DQ<58>")
	)
	(segment
		(start 315.76264 -26.316432)
		(end 315.89726 -26.316432)
		(width 0.14224)
		(layer "In4.Cu")
		(net "M_B_DQ<58>")
	)
	(segment
		(start 316.249812 -8.6614)
		(end 315.851794 -9.059418)
		(width 0.14224)
		(layer "In4.Cu")
		(net "M_B_DQ<58>")
	)
	(segment
		(start 315.93536 -28.754832)
		(end 315.722 -28.754832)
		(width 0.14224)
		(layer "In4.Cu")
		(net "M_B_DQ<58>")
	)
	(segment
		(start 315.969396 -14.82725)
		(end 315.969396 -16.764762)
		(width 0.14224)
		(layer "In4.Cu")
		(net "M_B_DQ<58>")
	)
	(segment
		(start 295.001442 -48.63084)
		(end 291.596572 -52.03571)
		(width 0.14224)
		(layer "In4.Cu")
		(net "M_B_DQ<58>")
	)
	(segment
		(start 315.893196 -21.797772)
		(end 315.740796 -21.950172)
		(width 0.14224)
		(layer "In4.Cu")
		(net "M_B_DQ<58>")
	)
	(segment
		(start 315.722 -27.942032)
		(end 315.93536 -27.942032)
		(width 0.14224)
		(layer "In4.Cu")
		(net "M_B_DQ<58>")
	)
	(segment
		(start 315.893196 -18.56105)
		(end 315.893196 -21.797772)
		(width 0.14224)
		(layer "In4.Cu")
		(net "M_B_DQ<58>")
	)
	(segment
		(start 315.399928 -13.959078)
		(end 315.399928 -14.257782)
		(width 0.14224)
		(layer "In4.Cu")
		(net "M_B_DQ<58>")
	)
	(segment
		(start 315.766196 -16.967962)
		(end 315.766196 -18.43405)
		(width 0.14224)
		(layer "In4.Cu")
		(net "M_B_DQ<58>")
	)
	(segment
		(start 315.811662 -10.362946)
		(end 315.811662 -10.64895)
		(width 0.14224)
		(layer "In4.Cu")
		(net "M_B_DQ<58>")
	)
	(segment
		(start 315.722 -27.129232)
		(end 315.5188 -27.332432)
		(width 0.14224)
		(layer "In4.Cu")
		(net "M_B_DQ<58>")
	)
	(segment
		(start 315.506862 -10.058146)
		(end 315.811662 -10.362946)
		(width 0.14224)
		(layer "In4.Cu")
		(net "M_B_DQ<58>")
	)
	(segment
		(start 287.810194 -59.276234)
		(end 287.77057 -59.276234)
		(width 0.0889)
		(layer "In4.Cu")
		(net "M_B_DQ<58>")
	)
	(segment
		(start 315.5188 -27.738832)
		(end 315.722 -27.942032)
		(width 0.14224)
		(layer "In4.Cu")
		(net "M_B_DQ<58>")
	)
	(segment
		(start 286.07512 -60.204858)
		(end 286.07512 -59.866784)
		(width 0.0889)
		(layer "In4.Cu")
		(net "M_B_DQ<58>")
	)
	(segment
		(start 315.506862 -11.3538)
		(end 315.964062 -11.811)
		(width 0.14224)
		(layer "In4.Cu")
		(net "M_B_DQ<58>")
	)
	(segment
		(start 315.506862 -9.709404)
		(end 315.506862 -10.058146)
		(width 0.14224)
		(layer "In4.Cu")
		(net "M_B_DQ<58>")
	)
	(segment
		(start 315.8744 -23.277576)
		(end 315.8744 -24.617172)
		(width 0.14224)
		(layer "In4.Cu")
		(net "M_B_DQ<58>")
	)
	(segment
		(start 288.13252 -56.684418)
		(end 288.13887 -56.695086)
		(width 0.0889)
		(layer "In4.Cu")
		(net "M_B_DQ<58>")
	)
	(segment
		(start 315.5188 -30.320996)
		(end 297.208956 -48.63084)
		(width 0.14224)
		(layer "In4.Cu")
		(net "M_B_DQ<58>")
	)
	(segment
		(start 286.133032 -60.26277)
		(end 286.07512 -60.204858)
		(width 0.0889)
		(layer "In4.Cu")
		(net "M_B_DQ<58>")
	)
	(segment
		(start 315.93536 -27.942032)
		(end 316.0776 -28.084272)
		(width 0.14224)
		(layer "In4.Cu")
		(net "M_B_DQ<58>")
	)
	(segment
		(start 315.89726 -26.316432)
		(end 316.0395 -26.458672)
		(width 0.14224)
		(layer "In4.Cu")
		(net "M_B_DQ<58>")
	)
	(segment
		(start 288.13887 -54.713886)
		(end 288.143696 -54.722522)
		(width 0.0889)
		(layer "In4.Cu")
		(net "M_B_DQ<58>")
	)
	(segment
		(start 315.969396 -16.764762)
		(end 315.766196 -16.967962)
		(width 0.14224)
		(layer "In4.Cu")
		(net "M_B_DQ<58>")
	)
	(segment
		(start 316.0395 -26.458672)
		(end 316.0395 -26.986992)
		(width 0.14224)
		(layer "In4.Cu")
		(net "M_B_DQ<58>")
	)
	(segment
		(start 288.13252 -57.675018)
		(end 288.13887 -57.685686)
		(width 0.0889)
		(layer "In4.Cu")
		(net "M_B_DQ<58>")
	)
	(segment
		(start 315.89726 -27.129232)
		(end 315.722 -27.129232)
		(width 0.14224)
		(layer "In4.Cu")
		(net "M_B_DQ<58>")
	)
	(segment
		(start 288.13252 -54.703218)
		(end 288.13887 -54.713886)
		(width 0.0889)
		(layer "In4.Cu")
		(net "M_B_DQ<58>")
	)
	(segment
		(start 297.208956 -48.63084)
		(end 295.001442 -48.63084)
		(width 0.14224)
		(layer "In4.Cu")
		(net "M_B_DQ<58>")
	)
	(segment
		(start 315.811662 -10.64895)
		(end 315.506862 -10.95375)
		(width 0.14224)
		(layer "In4.Cu")
		(net "M_B_DQ<58>")
	)
	(segment
		(start 286.944816 -59.771534)
		(end 286.920686 -59.771534)
		(width 0.0889)
		(layer "In4.Cu")
		(net "M_B_DQ<58>")
	)
	(segment
		(start 315.766196 -18.43405)
		(end 315.893196 -18.56105)
		(width 0.14224)
		(layer "In4.Cu")
		(net "M_B_DQ<58>")
	)
	(segment
		(start 315.851794 -9.364472)
		(end 315.506862 -9.709404)
		(width 0.14224)
		(layer "In4.Cu")
		(net "M_B_DQ<58>")
	)
	(segment
		(start 315.851794 -9.059418)
		(end 315.851794 -9.364472)
		(width 0.14224)
		(layer "In4.Cu")
		(net "M_B_DQ<58>")
	)
	(segment
		(start 288.13887 -55.704486)
		(end 288.143696 -55.713122)
		(width 0.0889)
		(layer "In4.Cu")
		(net "M_B_DQ<58>")
	)
	(segment
		(start 288.13252 -55.693818)
		(end 288.13887 -55.704486)
		(width 0.0889)
		(layer "In4.Cu")
		(net "M_B_DQ<58>")
	)
	(segment
		(start 288.13887 -56.695086)
		(end 288.143696 -56.703722)
		(width 0.0889)
		(layer "In4.Cu")
		(net "M_B_DQ<58>")
	)
	(segment
		(start 316.0776 -28.612592)
		(end 315.93536 -28.754832)
		(width 0.14224)
		(layer "In4.Cu")
		(net "M_B_DQ<58>")
	)
	(segment
		(start 315.5188 -28.958032)
		(end 315.5188 -30.320996)
		(width 0.14224)
		(layer "In4.Cu")
		(net "M_B_DQ<58>")
	)
	(segment
		(start 315.5188 -27.332432)
		(end 315.5188 -27.738832)
		(width 0.14224)
		(layer "In4.Cu")
		(net "M_B_DQ<58>")
	)
	(segment
		(start 289.625532 -53.827934)
		(end 288.637726 -53.827934)
		(width 0.0889)
		(layer "In4.Cu")
		(net "M_B_DQ<58>")
	)
	(segment
		(start 315.399928 -14.257782)
		(end 315.969396 -14.82725)
		(width 0.14224)
		(layer "In4.Cu")
		(net "M_B_DQ<58>")
	)
	(segment
		(start 315.94806 -25.503632)
		(end 315.76264 -25.503632)
		(width 0.14224)
		(layer "In4.Cu")
		(net "M_B_DQ<58>")
	)
	(segment
		(start 291.596572 -52.03571)
		(end 291.255196 -52.377086)
		(width 0.0889)
		(layer "In4.Cu")
		(net "M_B_DQ<58>")
	)
	(segment
		(start 315.740796 -21.950172)
		(end 315.740796 -23.143972)
		(width 0.14224)
		(layer "In4.Cu")
		(net "M_B_DQ<58>")
	)
	(segment
		(start 291.255196 -52.377086)
		(end 291.07638 -52.377086)
		(width 0.0889)
		(layer "In4.Cu")
		(net "M_B_DQ<58>")
	)
	(segment
		(start 315.6204 -25.645872)
		(end 315.6204 -26.174192)
		(width 0.14224)
		(layer "In4.Cu")
		(net "M_B_DQ<58>")
	)
	(segment
		(start 315.506862 -10.95375)
		(end 315.506862 -11.3538)
		(width 0.14224)
		(layer "In4.Cu")
		(net "M_B_DQ<58>")
	)
	(segment
		(start 315.115194 -13.674344)
		(end 315.399928 -13.959078)
		(width 0.14224)
		(layer "In4.Cu")
		(net "M_B_DQ<58>")
	)
	(segment
		(start 315.964062 -12.079732)
		(end 315.115194 -12.9286)
		(width 0.14224)
		(layer "In4.Cu")
		(net "M_B_DQ<58>")
	)
	(segment
		(start 315.6204 -26.174192)
		(end 315.76264 -26.316432)
		(width 0.14224)
		(layer "In4.Cu")
		(net "M_B_DQ<58>")
	)
	(segment
		(start 316.0395 -26.986992)
		(end 315.89726 -27.129232)
		(width 0.14224)
		(layer "In4.Cu")
		(net "M_B_DQ<58>")
	)
	(segment
		(start 315.964062 -11.811)
		(end 315.964062 -12.079732)
		(width 0.14224)
		(layer "In4.Cu")
		(net "M_B_DQ<58>")
	)
	(segment
		(start 315.115194 -12.9286)
		(end 315.115194 -13.674344)
		(width 0.14224)
		(layer "In4.Cu")
		(net "M_B_DQ<58>")
	)
	(segment
		(start 291.07638 -52.377086)
		(end 289.625532 -53.827934)
		(width 0.0889)
		(layer "In4.Cu")
		(net "M_B_DQ<58>")
	)
	(segment
		(start 316.0776 -28.084272)
		(end 316.0776 -28.612592)
		(width 0.14224)
		(layer "In4.Cu")
		(net "M_B_DQ<58>")
	)
	(segment
		(start 288.13887 -57.685686)
		(end 288.143696 -57.694322)
		(width 0.0889)
		(layer "In4.Cu")
		(net "M_B_DQ<58>")
	)
	(segment
		(start 316.0903 -25.361392)
		(end 315.94806 -25.503632)
		(width 0.14224)
		(layer "In4.Cu")
		(net "M_B_DQ<58>")
	)
	(segment
		(start 315.722 -28.754832)
		(end 315.5188 -28.958032)
		(width 0.14224)
		(layer "In4.Cu")
		(net "M_B_DQ<58>")
	)
	(segment
		(start 315.8744 -24.617172)
		(end 316.0903 -24.833072)
		(width 0.14224)
		(layer "In4.Cu")
		(net "M_B_DQ<58>")
	)
	(segment
		(start 316.0903 -24.833072)
		(end 316.0903 -25.361392)
		(width 0.14224)
		(layer "In4.Cu")
		(net "M_B_DQ<58>")
	)
	(segment
		(start 315.76264 -25.503632)
		(end 315.6204 -25.645872)
		(width 0.14224)
		(layer "In4.Cu")
		(net "M_B_DQ<58>")
	)
	(segment
		(start 315.740796 -23.143972)
		(end 315.8744 -23.277576)
		(width 0.14224)
		(layer "In4.Cu")
		(net "M_B_DQ<58>")
	)
	(arc
		(start 288.143696 -55.713122)
		(mid 288.192451 -55.909474)
		(end 288.13887 -56.104536)
		(width 0.0889)
		(layer "In4.Cu")
		(net "M_B_DQ<58>")
	)
	(arc
		(start 288.13887 -57.095136)
		(mid 288.059648 -57.384254)
		(end 288.13252 -57.675018)
		(width 0.0889)
		(layer "In4.Cu")
		(net "M_B_DQ<58>")
	)
	(arc
		(start 288.143696 -56.703722)
		(mid 288.192451 -56.900074)
		(end 288.13887 -57.095136)
		(width 0.0889)
		(layer "In4.Cu")
		(net "M_B_DQ<58>")
	)
	(arc
		(start 288.637726 -53.827934)
		(mid 288.138845 -54.123371)
		(end 288.13252 -54.703218)
		(width 0.0889)
		(layer "In4.Cu")
		(net "M_B_DQ<58>")
	)
	(arc
		(start 288.13887 -58.67654)
		(mid 288.143115 -59.068785)
		(end 287.810194 -59.276234)
		(width 0.0889)
		(layer "In4.Cu")
		(net "M_B_DQ<58>")
	)
	(arc
		(start 287.28035 -59.571382)
		(mid 287.138667 -59.715186)
		(end 286.944816 -59.771534)
		(width 0.0889)
		(layer "In4.Cu")
		(net "M_B_DQ<58>")
	)
	(arc
		(start 288.13887 -58.085736)
		(mid 288.059739 -58.381138)
		(end 288.13887 -58.67654)
		(width 0.0889)
		(layer "In4.Cu")
		(net "M_B_DQ<58>")
	)
	(arc
		(start 286.42183 -60.066936)
		(mid 286.299885 -60.197968)
		(end 286.133032 -60.26277)
		(width 0.0889)
		(layer "In4.Cu")
		(net "M_B_DQ<58>")
	)
	(arc
		(start 287.77057 -59.276234)
		(mid 287.487353 -59.360515)
		(end 287.28035 -59.571382)
		(width 0.0889)
		(layer "In4.Cu")
		(net "M_B_DQ<58>")
	)
	(arc
		(start 288.13887 -55.113936)
		(mid 288.059648 -55.403054)
		(end 288.13252 -55.693818)
		(width 0.0889)
		(layer "In4.Cu")
		(net "M_B_DQ<58>")
	)
	(arc
		(start 288.13887 -56.104536)
		(mid 288.059648 -56.393654)
		(end 288.13252 -56.684418)
		(width 0.0889)
		(layer "In4.Cu")
		(net "M_B_DQ<58>")
	)
	(arc
		(start 288.143696 -54.722522)
		(mid 288.192451 -54.918874)
		(end 288.13887 -55.113936)
		(width 0.0889)
		(layer "In4.Cu")
		(net "M_B_DQ<58>")
	)
	(arc
		(start 288.143696 -57.694322)
		(mid 288.192451 -57.890674)
		(end 288.13887 -58.085736)
		(width 0.0889)
		(layer "In4.Cu")
		(net "M_B_DQ<58>")
	)
	(arc
		(start 286.920686 -59.771534)
		(mid 286.632541 -59.853853)
		(end 286.42183 -60.066936)
		(width 0.0889)
		(layer "In4.Cu")
		(net "M_B_DQ<58>")
	)
	(segment
		(start 309.449978 -5.822442)
		(end 309.449978 -7.086346)
		(width 0.1651)
		(layer "F.Cu")
		(net "M_B_DQ<57>")
	)
	(segment
		(start 284.071314 -61.352938)
		(end 283.499814 -61.352938)
		(width 0.1016)
		(layer "F.Cu")
		(net "M_B_DQ<57>")
	)
	(segment
		(start 309.450486 -5.822442)
		(end 309.449978 -5.822442)
		(width 0.1651)
		(layer "F.Cu")
		(net "M_B_DQ<57>")
	)
	(via
		(at 310.122062 -12.678156)
		(size 0.508)
		(drill 0.254)
		(layers "F.Cu" "B.Cu")
		(net "M_B_DQ<57>")
	)
	(via
		(at 309.449978 -7.086346)
		(size 0.508)
		(drill 0.254)
		(layers "F.Cu" "B.Cu")
		(net "M_B_DQ<57>")
	)
	(via
		(at 283.499814 -61.352938)
		(size 0.508)
		(drill 0.254)
		(layers "F.Cu" "B.Cu")
		(net "M_B_DQ<57>")
	)
	(segment
		(start 310.122062 -12.174982)
		(end 310.122062 -12.678156)
		(width 0.1651)
		(layer "B.Cu")
		(net "M_B_DQ<57>")
	)
	(segment
		(start 310.299862 -11.997182)
		(end 310.122062 -12.174982)
		(width 0.1651)
		(layer "B.Cu")
		(net "M_B_DQ<57>")
	)
	(segment
		(start 310.299862 -10.623042)
		(end 310.299862 -11.997182)
		(width 0.1651)
		(layer "B.Cu")
		(net "M_B_DQ<57>")
	)
	(segment
		(start 310.30037 -10.623042)
		(end 310.299862 -10.623042)
		(width 0.1651)
		(layer "B.Cu")
		(net "M_B_DQ<57>")
	)
	(segment
		(start 287.86963 -50.05451)
		(end 287.88233 -50.05451)
		(width 0.0889)
		(layer "In4.Cu")
		(net "M_B_DQ<57>")
	)
	(segment
		(start 310.652668 -8.8138)
		(end 310.652668 -8.472424)
		(width 0.14224)
		(layer "In4.Cu")
		(net "M_B_DQ<57>")
	)
	(segment
		(start 284.879034 -56.615076)
		(end 284.870144 -56.599836)
		(width 0.0889)
		(layer "In4.Cu")
		(net "M_B_DQ<57>")
	)
	(segment
		(start 310.652668 -8.472424)
		(end 310.282844 -8.1026)
		(width 0.14224)
		(layer "In4.Cu")
		(net "M_B_DQ<57>")
	)
	(segment
		(start 310.282844 -8.1026)
		(end 309.927244 -8.1026)
		(width 0.14224)
		(layer "In4.Cu")
		(net "M_B_DQ<57>")
	)
	(segment
		(start 310.9214 -24.2062)
		(end 310.609996 -23.894796)
		(width 0.14224)
		(layer "In4.Cu")
		(net "M_B_DQ<57>")
	)
	(segment
		(start 283.170376 -60.591954)
		(end 283.148278 -60.5536)
		(width 0.0889)
		(layer "In4.Cu")
		(net "M_B_DQ<57>")
	)
	(segment
		(start 305.2826 -33.906206)
		(end 305.011582 -33.635188)
		(width 0.14224)
		(layer "In4.Cu")
		(net "M_B_DQ<57>")
	)
	(segment
		(start 284.879034 -54.633876)
		(end 284.862016 -54.604412)
		(width 0.0889)
		(layer "In4.Cu")
		(net "M_B_DQ<57>")
	)
	(segment
		(start 284.879034 -55.624476)
		(end 284.870144 -55.609236)
		(width 0.0889)
		(layer "In4.Cu")
		(net "M_B_DQ<57>")
	)
	(segment
		(start 283.484828 -57.981088)
		(end 283.517594 -57.981088)
		(width 0.0889)
		(layer "In4.Cu")
		(net "M_B_DQ<57>")
	)
	(segment
		(start 309.59552 -13.204698)
		(end 310.122062 -12.678156)
		(width 0.14224)
		(layer "In4.Cu")
		(net "M_B_DQ<57>")
	)
	(segment
		(start 310.609996 -23.894796)
		(end 310.609996 -16.300196)
		(width 0.14224)
		(layer "In4.Cu")
		(net "M_B_DQ<57>")
	)
	(segment
		(start 284.86989 -53.628036)
		(end 284.865064 -53.6194)
		(width 0.0889)
		(layer "In4.Cu")
		(net "M_B_DQ<57>")
	)
	(segment
		(start 283.499814 -61.352938)
		(end 283.170376 -60.591954)
		(width 0.0889)
		(layer "In4.Cu")
		(net "M_B_DQ<57>")
	)
	(segment
		(start 284.347158 -57.485534)
		(end 284.383226 -57.485534)
		(width 0.0889)
		(layer "In4.Cu")
		(net "M_B_DQ<57>")
	)
	(segment
		(start 310.122062 -12.678156)
		(end 310.496204 -12.304014)
		(width 0.14224)
		(layer "In4.Cu")
		(net "M_B_DQ<57>")
	)
	(segment
		(start 309.974996 -15.665196)
		(end 309.974996 -13.861796)
		(width 0.14224)
		(layer "In4.Cu")
		(net "M_B_DQ<57>")
	)
	(segment
		(start 285.201614 -52.037488)
		(end 285.23438 -52.037488)
		(width 0.0889)
		(layer "In4.Cu")
		(net "M_B_DQ<57>")
	)
	(segment
		(start 287.88233 -50.05451)
		(end 292.23843 -45.69841)
		(width 0.14224)
		(layer "In4.Cu")
		(net "M_B_DQ<57>")
	)
	(segment
		(start 309.449978 -7.625334)
		(end 309.449978 -7.086346)
		(width 0.14224)
		(layer "In4.Cu")
		(net "M_B_DQ<57>")
	)
	(segment
		(start 284.86989 -52.637436)
		(end 284.865064 -52.6288)
		(width 0.0889)
		(layer "In4.Cu")
		(net "M_B_DQ<57>")
	)
	(segment
		(start 310.609996 -16.300196)
		(end 309.974996 -15.665196)
		(width 0.14224)
		(layer "In4.Cu")
		(net "M_B_DQ<57>")
	)
	(segment
		(start 284.87624 -52.648104)
		(end 284.86989 -52.637436)
		(width 0.0889)
		(layer "In4.Cu")
		(net "M_B_DQ<57>")
	)
	(segment
		(start 309.927244 -8.1026)
		(end 309.449978 -7.625334)
		(width 0.14224)
		(layer "In4.Cu")
		(net "M_B_DQ<57>")
	)
	(segment
		(start 309.59552 -13.48232)
		(end 309.59552 -13.204698)
		(width 0.14224)
		(layer "In4.Cu")
		(net "M_B_DQ<57>")
	)
	(segment
		(start 305.011582 -33.635188)
		(end 305.011582 -33.347406)
		(width 0.14224)
		(layer "In4.Cu")
		(net "M_B_DQ<57>")
	)
	(segment
		(start 310.496204 -12.304014)
		(end 310.496204 -8.970264)
		(width 0.14224)
		(layer "In4.Cu")
		(net "M_B_DQ<57>")
	)
	(segment
		(start 310.9214 -27.437588)
		(end 310.9214 -24.2062)
		(width 0.14224)
		(layer "In4.Cu")
		(net "M_B_DQ<57>")
	)
	(segment
		(start 294.675814 -45.69841)
		(end 305.2826 -35.091624)
		(width 0.14224)
		(layer "In4.Cu")
		(net "M_B_DQ<57>")
	)
	(segment
		(start 285.635954 -51.864006)
		(end 286.0167 -51.48326)
		(width 0.0889)
		(layer "In4.Cu")
		(net "M_B_DQ<57>")
	)
	(segment
		(start 284.87624 -53.638704)
		(end 284.86989 -53.628036)
		(width 0.0889)
		(layer "In4.Cu")
		(net "M_B_DQ<57>")
	)
	(segment
		(start 309.974996 -13.861796)
		(end 309.59552 -13.48232)
		(width 0.14224)
		(layer "In4.Cu")
		(net "M_B_DQ<57>")
	)
	(segment
		(start 305.2826 -35.091624)
		(end 305.2826 -33.906206)
		(width 0.14224)
		(layer "In4.Cu")
		(net "M_B_DQ<57>")
	)
	(segment
		(start 305.011582 -33.347406)
		(end 310.9214 -27.437588)
		(width 0.14224)
		(layer "In4.Cu")
		(net "M_B_DQ<57>")
	)
	(segment
		(start 292.23843 -45.69841)
		(end 294.675814 -45.69841)
		(width 0.14224)
		(layer "In4.Cu")
		(net "M_B_DQ<57>")
	)
	(segment
		(start 286.0167 -51.48326)
		(end 286.44088 -51.48326)
		(width 0.0889)
		(layer "In4.Cu")
		(net "M_B_DQ<57>")
	)
	(segment
		(start 286.44088 -51.48326)
		(end 287.86963 -50.05451)
		(width 0.0889)
		(layer "In4.Cu")
		(net "M_B_DQ<57>")
	)
	(segment
		(start 283.846524 -59.171586)
		(end 283.840174 -59.160918)
		(width 0.0889)
		(layer "In4.Cu")
		(net "M_B_DQ<57>")
	)
	(segment
		(start 310.496204 -8.970264)
		(end 310.652668 -8.8138)
		(width 0.14224)
		(layer "In4.Cu")
		(net "M_B_DQ<57>")
	)
	(arc
		(start 284.011624 -57.685686)
		(mid 284.153307 -57.541882)
		(end 284.347158 -57.485534)
		(width 0.0889)
		(layer "In4.Cu")
		(net "M_B_DQ<57>")
	)
	(arc
		(start 284.870144 -55.20944)
		(mid 284.949333 -54.922825)
		(end 284.879034 -54.633876)
		(width 0.0889)
		(layer "In4.Cu")
		(net "M_B_DQ<57>")
	)
	(arc
		(start 283.148278 -60.5536)
		(mid 283.1259 -60.219695)
		(end 283.36494 -59.985402)
		(width 0.0889)
		(layer "In4.Cu")
		(net "M_B_DQ<57>")
	)
	(arc
		(start 284.86989 -54.218586)
		(mid 284.949112 -53.929468)
		(end 284.87624 -53.638704)
		(width 0.0889)
		(layer "In4.Cu")
		(net "M_B_DQ<57>")
	)
	(arc
		(start 284.865064 -52.6288)
		(mid 284.868811 -52.239544)
		(end 285.201614 -52.037488)
		(width 0.0889)
		(layer "In4.Cu")
		(net "M_B_DQ<57>")
	)
	(arc
		(start 283.381958 -58.763408)
		(mid 283.102781 -58.328721)
		(end 283.484828 -57.981088)
		(width 0.0889)
		(layer "In4.Cu")
		(net "M_B_DQ<57>")
	)
	(arc
		(start 284.383226 -57.485534)
		(mid 284.87195 -57.187504)
		(end 284.879034 -56.615076)
		(width 0.0889)
		(layer "In4.Cu")
		(net "M_B_DQ<57>")
	)
	(arc
		(start 284.86989 -53.227986)
		(mid 284.949112 -52.938868)
		(end 284.87624 -52.648104)
		(width 0.0889)
		(layer "In4.Cu")
		(net "M_B_DQ<57>")
	)
	(arc
		(start 284.870144 -56.599836)
		(mid 284.816611 -56.399938)
		(end 284.870144 -56.20004)
		(width 0.0889)
		(layer "In4.Cu")
		(net "M_B_DQ<57>")
	)
	(arc
		(start 283.36494 -59.985402)
		(mid 283.606289 -59.857869)
		(end 283.802074 -59.667648)
		(width 0.0889)
		(layer "In4.Cu")
		(net "M_B_DQ<57>")
	)
	(arc
		(start 283.802074 -59.667648)
		(mid 283.82214 -59.618518)
		(end 283.846524 -59.571382)
		(width 0.0889)
		(layer "In4.Cu")
		(net "M_B_DQ<57>")
	)
	(arc
		(start 283.517594 -57.981088)
		(mid 283.803018 -57.897621)
		(end 284.011624 -57.685686)
		(width 0.0889)
		(layer "In4.Cu")
		(net "M_B_DQ<57>")
	)
	(arc
		(start 283.846524 -59.571382)
		(mid 283.900023 -59.371484)
		(end 283.846524 -59.171586)
		(width 0.0889)
		(layer "In4.Cu")
		(net "M_B_DQ<57>")
	)
	(arc
		(start 284.870144 -55.609236)
		(mid 284.816611 -55.409338)
		(end 284.870144 -55.20944)
		(width 0.0889)
		(layer "In4.Cu")
		(net "M_B_DQ<57>")
	)
	(arc
		(start 284.865064 -53.6194)
		(mid 284.816309 -53.423048)
		(end 284.86989 -53.227986)
		(width 0.0889)
		(layer "In4.Cu")
		(net "M_B_DQ<57>")
	)
	(arc
		(start 284.862016 -54.604412)
		(mid 284.816429 -54.410499)
		(end 284.86989 -54.218586)
		(width 0.0889)
		(layer "In4.Cu")
		(net "M_B_DQ<57>")
	)
	(arc
		(start 283.840174 -59.160918)
		(mid 283.643067 -58.925276)
		(end 283.381958 -58.763408)
		(width 0.0889)
		(layer "In4.Cu")
		(net "M_B_DQ<57>")
	)
	(arc
		(start 284.870144 -56.20004)
		(mid 284.949333 -55.913425)
		(end 284.879034 -55.624476)
		(width 0.0889)
		(layer "In4.Cu")
		(net "M_B_DQ<57>")
	)
	(arc
		(start 285.23438 -52.037488)
		(mid 285.451759 -51.989143)
		(end 285.635954 -51.864006)
		(width 0.0889)
		(layer "In4.Cu")
		(net "M_B_DQ<57>")
	)
	(segment
		(start 310.30037 -10.422382)
		(end 310.299862 -10.422382)
		(width 0.1651)
		(layer "F.Cu")
		(net "M_B_DQ<56>")
	)
	(segment
		(start 310.299862 -10.422382)
		(end 310.153558 -8.89)
		(width 0.1651)
		(layer "F.Cu")
		(net "M_B_DQ<56>")
	)
	(segment
		(start 310.141366 -8.763)
		(end 310.122062 -8.5598)
		(width 0.1651)
		(layer "F.Cu")
		(net "M_B_DQ<56>")
	)
	(segment
		(start 310.153558 -8.89)
		(end 310.141366 -8.763)
		(width 0.1651)
		(layer "F.Cu")
		(net "M_B_DQ<56>")
	)
	(segment
		(start 284.071314 -59.371484)
		(end 283.499814 -59.371484)
		(width 0.1016)
		(layer "F.Cu")
		(net "M_B_DQ<56>")
	)
	(via
		(at 310.122062 -8.5598)
		(size 0.508)
		(drill 0.254)
		(layers "F.Cu" "B.Cu")
		(net "M_B_DQ<56>")
	)
	(via
		(at 309.449978 -13.959078)
		(size 0.508)
		(drill 0.254)
		(layers "F.Cu" "B.Cu")
		(net "M_B_DQ<56>")
	)
	(via
		(at 283.499814 -59.371484)
		(size 0.508)
		(drill 0.254)
		(layers "F.Cu" "B.Cu")
		(net "M_B_DQ<56>")
	)
	(segment
		(start 309.450486 -15.222982)
		(end 309.449978 -15.222982)
		(width 0.1651)
		(layer "B.Cu")
		(net "M_B_DQ<56>")
	)
	(segment
		(start 309.449978 -15.222982)
		(end 309.449978 -13.959078)
		(width 0.1651)
		(layer "B.Cu")
		(net "M_B_DQ<56>")
	)
	(segment
		(start 309.753 -25.740106)
		(end 310.0832 -25.740106)
		(width 0.14224)
		(layer "In4.Cu")
		(net "M_B_DQ<56>")
	)
	(segment
		(start 304.512218 -34.234882)
		(end 304.512218 -34.033714)
		(width 0.14224)
		(layer "In4.Cu")
		(net "M_B_DQ<56>")
	)
	(segment
		(start 309.512462 -11.302746)
		(end 309.512462 -10.9982)
		(width 0.14224)
		(layer "In4.Cu")
		(net "M_B_DQ<56>")
	)
	(segment
		(start 284.709616 -53.731922)
		(end 284.70479 -53.723286)
		(width 0.0889)
		(layer "In4.Cu")
		(net "M_B_DQ<56>")
	)
	(segment
		(start 309.974996 -18.662142)
		(end 309.632096 -18.319242)
		(width 0.14224)
		(layer "In4.Cu")
		(net "M_B_DQ<56>")
	)
	(segment
		(start 310.0832 -24.927306)
		(end 309.753 -24.927306)
		(width 0.14224)
		(layer "In4.Cu")
		(net "M_B_DQ<56>")
	)
	(segment
		(start 304.512218 -34.033714)
		(end 304.1142 -33.635696)
		(width 0.14224)
		(layer "In4.Cu")
		(net "M_B_DQ<56>")
	)
	(segment
		(start 287.5026 -50.151792)
		(end 287.5026 -49.757076)
		(width 0.0889)
		(layer "In4.Cu")
		(net "M_B_DQ<56>")
	)
	(segment
		(start 309.487062 -9.779254)
		(end 309.901844 -9.364472)
		(width 0.14224)
		(layer "In4.Cu")
		(net "M_B_DQ<56>")
	)
	(segment
		(start 309.449978 -15.952978)
		(end 309.449978 -13.959078)
		(width 0.14224)
		(layer "In4.Cu")
		(net "M_B_DQ<56>")
	)
	(segment
		(start 309.632096 -22.026372)
		(end 309.974996 -21.683472)
		(width 0.14224)
		(layer "In4.Cu")
		(net "M_B_DQ<56>")
	)
	(segment
		(start 309.632096 -23.087838)
		(end 309.632096 -22.026372)
		(width 0.14224)
		(layer "In4.Cu")
		(net "M_B_DQ<56>")
	)
	(segment
		(start 284.340554 -57.295034)
		(end 284.358334 -57.295034)
		(width 0.0889)
		(layer "In4.Cu")
		(net "M_B_DQ<56>")
	)
	(segment
		(start 294.25646 -45.21962)
		(end 303.569116 -35.906964)
		(width 0.14224)
		(layer "In4.Cu")
		(net "M_B_DQ<56>")
	)
	(segment
		(start 286.361632 -51.29276)
		(end 287.5026 -50.151792)
		(width 0.0889)
		(layer "In4.Cu")
		(net "M_B_DQ<56>")
	)
	(segment
		(start 309.753 -24.927306)
		(end 309.5498 -24.724106)
		(width 0.14224)
		(layer "In4.Cu")
		(net "M_B_DQ<56>")
	)
	(segment
		(start 285.917386 -51.29276)
		(end 286.361632 -51.29276)
		(width 0.0889)
		(layer "In4.Cu")
		(net "M_B_DQ<56>")
	)
	(segment
		(start 283.478224 -57.790588)
		(end 283.51099 -57.790588)
		(width 0.0889)
		(layer "In4.Cu")
		(net "M_B_DQ<56>")
	)
	(segment
		(start 309.829962 -10.4521)
		(end 309.487062 -10.1092)
		(width 0.14224)
		(layer "In4.Cu")
		(net "M_B_DQ<56>")
	)
	(segment
		(start 309.901844 -9.364472)
		(end 309.901844 -8.780018)
		(width 0.14224)
		(layer "In4.Cu")
		(net "M_B_DQ<56>")
	)
	(segment
		(start 309.9435 -23.924006)
		(end 309.9435 -23.398226)
		(width 0.14224)
		(layer "In4.Cu")
		(net "M_B_DQ<56>")
	)
	(segment
		(start 303.569116 -35.906964)
		(end 303.569116 -35.48888)
		(width 0.14224)
		(layer "In4.Cu")
		(net "M_B_DQ<56>")
	)
	(segment
		(start 304.089054 -34.658046)
		(end 304.512218 -34.234882)
		(width 0.14224)
		(layer "In4.Cu")
		(net "M_B_DQ<56>")
	)
	(segment
		(start 310.2864 -25.536906)
		(end 310.2864 -25.130506)
		(width 0.14224)
		(layer "In4.Cu")
		(net "M_B_DQ<56>")
	)
	(segment
		(start 309.449978 -13.959078)
		(end 309.165244 -13.674344)
		(width 0.14224)
		(layer "In4.Cu")
		(net "M_B_DQ<56>")
	)
	(segment
		(start 283.004514 -58.705496)
		(end 282.988004 -58.67654)
		(width 0.0889)
		(layer "In4.Cu")
		(net "M_B_DQ<56>")
	)
	(segment
		(start 309.829962 -10.6807)
		(end 309.829962 -10.4521)
		(width 0.14224)
		(layer "In4.Cu")
		(net "M_B_DQ<56>")
	)
	(segment
		(start 285.56331 -51.646836)
		(end 285.917386 -51.29276)
		(width 0.0889)
		(layer "In4.Cu")
		(net "M_B_DQ<56>")
	)
	(segment
		(start 284.70479 -53.723286)
		(end 284.69844 -53.712618)
		(width 0.0889)
		(layer "In4.Cu")
		(net "M_B_DQ<56>")
	)
	(segment
		(start 284.70479 -52.732686)
		(end 284.69844 -52.722018)
		(width 0.0889)
		(layer "In4.Cu")
		(net "M_B_DQ<56>")
	)
	(segment
		(start 303.887886 -34.658046)
		(end 304.089054 -34.658046)
		(width 0.14224)
		(layer "In4.Cu")
		(net "M_B_DQ<56>")
	)
	(segment
		(start 303.201578 -34.259266)
		(end 303.489106 -34.259266)
		(width 0.14224)
		(layer "In4.Cu")
		(net "M_B_DQ<56>")
	)
	(segment
		(start 310.2864 -25.130506)
		(end 310.0832 -24.927306)
		(width 0.14224)
		(layer "In4.Cu")
		(net "M_B_DQ<56>")
	)
	(segment
		(start 302.914304 -34.834068)
		(end 302.914304 -34.54654)
		(width 0.14224)
		(layer "In4.Cu")
		(net "M_B_DQ<56>")
	)
	(segment
		(start 309.942484 -23.398226)
		(end 309.632096 -23.087838)
		(width 0.14224)
		(layer "In4.Cu")
		(net "M_B_DQ<56>")
	)
	(segment
		(start 309.165244 -12.9286)
		(end 309.901844 -12.192)
		(width 0.14224)
		(layer "In4.Cu")
		(net "M_B_DQ<56>")
	)
	(segment
		(start 303.569116 -35.48888)
		(end 302.914304 -34.834068)
		(width 0.14224)
		(layer "In4.Cu")
		(net "M_B_DQ<56>")
	)
	(segment
		(start 303.489106 -34.259266)
		(end 303.887886 -34.658046)
		(width 0.14224)
		(layer "In4.Cu")
		(net "M_B_DQ<56>")
	)
	(segment
		(start 287.5026 -49.757076)
		(end 292.040056 -45.21962)
		(width 0.14224)
		(layer "In4.Cu")
		(net "M_B_DQ<56>")
	)
	(segment
		(start 310.0832 -26.552906)
		(end 309.753 -26.552906)
		(width 0.14224)
		(layer "In4.Cu")
		(net "M_B_DQ<56>")
	)
	(segment
		(start 302.914304 -34.54654)
		(end 303.201578 -34.259266)
		(width 0.14224)
		(layer "In4.Cu")
		(net "M_B_DQ<56>")
	)
	(segment
		(start 285.19501 -51.846988)
		(end 285.227776 -51.846988)
		(width 0.0889)
		(layer "In4.Cu")
		(net "M_B_DQ<56>")
	)
	(segment
		(start 309.924196 -16.825976)
		(end 309.924196 -16.427196)
		(width 0.14224)
		(layer "In4.Cu")
		(net "M_B_DQ<56>")
	)
	(segment
		(start 283.499814 -59.371484)
		(end 283.004514 -58.705496)
		(width 0.0889)
		(layer "In4.Cu")
		(net "M_B_DQ<56>")
	)
	(segment
		(start 304.1142 -33.635696)
		(end 304.1142 -33.346644)
		(width 0.14224)
		(layer "In4.Cu")
		(net "M_B_DQ<56>")
	)
	(segment
		(start 310.2864 -26.756106)
		(end 310.0832 -26.552906)
		(width 0.14224)
		(layer "In4.Cu")
		(net "M_B_DQ<56>")
	)
	(segment
		(start 309.165244 -13.674344)
		(end 309.165244 -12.9286)
		(width 0.14224)
		(layer "In4.Cu")
		(net "M_B_DQ<56>")
	)
	(segment
		(start 309.632096 -17.118076)
		(end 309.924196 -16.825976)
		(width 0.14224)
		(layer "In4.Cu")
		(net "M_B_DQ<56>")
	)
	(segment
		(start 309.5498 -24.724106)
		(end 309.5498 -24.317706)
		(width 0.14224)
		(layer "In4.Cu")
		(net "M_B_DQ<56>")
	)
	(segment
		(start 309.632096 -18.319242)
		(end 309.632096 -17.118076)
		(width 0.14224)
		(layer "In4.Cu")
		(net "M_B_DQ<56>")
	)
	(segment
		(start 304.1142 -33.346644)
		(end 310.2864 -27.174444)
		(width 0.14224)
		(layer "In4.Cu")
		(net "M_B_DQ<56>")
	)
	(segment
		(start 309.901844 -12.192)
		(end 309.901844 -11.692128)
		(width 0.14224)
		(layer "In4.Cu")
		(net "M_B_DQ<56>")
	)
	(segment
		(start 309.901844 -8.780018)
		(end 310.122062 -8.5598)
		(width 0.14224)
		(layer "In4.Cu")
		(net "M_B_DQ<56>")
	)
	(segment
		(start 310.2864 -27.174444)
		(end 310.2864 -26.756106)
		(width 0.14224)
		(layer "In4.Cu")
		(net "M_B_DQ<56>")
	)
	(segment
		(start 309.512462 -10.9982)
		(end 309.829962 -10.6807)
		(width 0.14224)
		(layer "In4.Cu")
		(net "M_B_DQ<56>")
	)
	(segment
		(start 309.924196 -16.427196)
		(end 309.449978 -15.952978)
		(width 0.14224)
		(layer "In4.Cu")
		(net "M_B_DQ<56>")
	)
	(segment
		(start 309.753 -26.552906)
		(end 309.5498 -26.349706)
		(width 0.14224)
		(layer "In4.Cu")
		(net "M_B_DQ<56>")
	)
	(segment
		(start 284.70479 -54.713886)
		(end 284.69844 -54.703218)
		(width 0.0889)
		(layer "In4.Cu")
		(net "M_B_DQ<56>")
	)
	(segment
		(start 309.5498 -25.943306)
		(end 309.753 -25.740106)
		(width 0.14224)
		(layer "In4.Cu")
		(net "M_B_DQ<56>")
	)
	(segment
		(start 292.040056 -45.21962)
		(end 294.25646 -45.21962)
		(width 0.14224)
		(layer "In4.Cu")
		(net "M_B_DQ<56>")
	)
	(segment
		(start 309.5498 -24.317706)
		(end 309.9435 -23.924006)
		(width 0.14224)
		(layer "In4.Cu")
		(net "M_B_DQ<56>")
	)
	(segment
		(start 310.0832 -25.740106)
		(end 310.2864 -25.536906)
		(width 0.14224)
		(layer "In4.Cu")
		(net "M_B_DQ<56>")
	)
	(segment
		(start 309.974996 -21.683472)
		(end 309.974996 -18.662142)
		(width 0.14224)
		(layer "In4.Cu")
		(net "M_B_DQ<56>")
	)
	(segment
		(start 284.709616 -52.741322)
		(end 284.70479 -52.732686)
		(width 0.0889)
		(layer "In4.Cu")
		(net "M_B_DQ<56>")
	)
	(segment
		(start 309.901844 -11.692128)
		(end 309.512462 -11.302746)
		(width 0.14224)
		(layer "In4.Cu")
		(net "M_B_DQ<56>")
	)
	(segment
		(start 309.487062 -10.1092)
		(end 309.487062 -9.779254)
		(width 0.14224)
		(layer "In4.Cu")
		(net "M_B_DQ<56>")
	)
	(segment
		(start 309.5498 -26.349706)
		(end 309.5498 -25.943306)
		(width 0.14224)
		(layer "In4.Cu")
		(net "M_B_DQ<56>")
	)
	(segment
		(start 284.70479 -55.704486)
		(end 284.6959 -55.689246)
		(width 0.0889)
		(layer "In4.Cu")
		(net "M_B_DQ<56>")
	)
	(segment
		(start 284.70479 -56.695086)
		(end 284.6959 -56.679846)
		(width 0.0889)
		(layer "In4.Cu")
		(net "M_B_DQ<56>")
	)
	(segment
		(start 309.9435 -23.398226)
		(end 309.942484 -23.398226)
		(width 0.14224)
		(layer "In4.Cu")
		(net "M_B_DQ<56>")
	)
	(arc
		(start 284.69844 -53.712618)
		(mid 284.625642 -53.421855)
		(end 284.70479 -53.132736)
		(width 0.0889)
		(layer "In4.Cu")
		(net "M_B_DQ<56>")
	)
	(arc
		(start 284.70479 -54.123336)
		(mid 284.75826 -53.928273)
		(end 284.709616 -53.731922)
		(width 0.0889)
		(layer "In4.Cu")
		(net "M_B_DQ<56>")
	)
	(arc
		(start 284.69844 -52.722018)
		(mid 284.702471 -52.145836)
		(end 285.19501 -51.846988)
		(width 0.0889)
		(layer "In4.Cu")
		(net "M_B_DQ<56>")
	)
	(arc
		(start 284.358334 -57.295034)
		(mid 284.70476 -57.095057)
		(end 284.70479 -56.695086)
		(width 0.0889)
		(layer "In4.Cu")
		(net "M_B_DQ<56>")
	)
	(arc
		(start 284.6959 -56.679846)
		(mid 284.625503 -56.390895)
		(end 284.70479 -56.104282)
		(width 0.0889)
		(layer "In4.Cu")
		(net "M_B_DQ<56>")
	)
	(arc
		(start 283.51099 -57.790588)
		(mid 283.70484 -57.734238)
		(end 283.846524 -57.590436)
		(width 0.0889)
		(layer "In4.Cu")
		(net "M_B_DQ<56>")
	)
	(arc
		(start 282.988004 -58.67654)
		(mid 282.98275 -58.095032)
		(end 283.478224 -57.790588)
		(width 0.0889)
		(layer "In4.Cu")
		(net "M_B_DQ<56>")
	)
	(arc
		(start 284.69844 -54.703218)
		(mid 284.625642 -54.412455)
		(end 284.70479 -54.123336)
		(width 0.0889)
		(layer "In4.Cu")
		(net "M_B_DQ<56>")
	)
	(arc
		(start 285.227776 -51.846988)
		(mid 285.421626 -51.790638)
		(end 285.56331 -51.646836)
		(width 0.0889)
		(layer "In4.Cu")
		(net "M_B_DQ<56>")
	)
	(arc
		(start 284.70479 -55.113682)
		(mid 284.758323 -54.913784)
		(end 284.70479 -54.713886)
		(width 0.0889)
		(layer "In4.Cu")
		(net "M_B_DQ<56>")
	)
	(arc
		(start 284.70479 -56.104282)
		(mid 284.758323 -55.904384)
		(end 284.70479 -55.704486)
		(width 0.0889)
		(layer "In4.Cu")
		(net "M_B_DQ<56>")
	)
	(arc
		(start 283.846524 -57.590436)
		(mid 284.055132 -57.378504)
		(end 284.340554 -57.295034)
		(width 0.0889)
		(layer "In4.Cu")
		(net "M_B_DQ<56>")
	)
	(arc
		(start 284.70479 -53.132736)
		(mid 284.75826 -52.937673)
		(end 284.709616 -52.741322)
		(width 0.0889)
		(layer "In4.Cu")
		(net "M_B_DQ<56>")
	)
	(arc
		(start 284.6959 -55.689246)
		(mid 284.625503 -55.400295)
		(end 284.70479 -55.113682)
		(width 0.0889)
		(layer "In4.Cu")
		(net "M_B_DQ<56>")
	)
	(segment
		(start 306.00777 -36.938458)
		(end 306.00777 -35.306)
		(width 0.1651)
		(layer "F.Cu")
		(net "M_B_DQ<55>")
	)
	(segment
		(start 306.00777 -35.306)
		(end 306.00777 -33.36417)
		(width 0.1651)
		(layer "F.Cu")
		(net "M_B_DQ<55>")
	)
	(segment
		(start 306.00777 -33.36417)
		(end 304.9778 -32.3342)
		(width 0.1651)
		(layer "F.Cu")
		(net "M_B_DQ<55>")
	)
	(segment
		(start 295.13149 -47.944024)
		(end 300.0248 -43.050714)
		(width 0.1016)
		(layer "F.Cu")
		(net "M_B_DQ<55>")
	)
	(segment
		(start 304.349912 -5.822442)
		(end 304.349912 -7.086346)
		(width 0.1651)
		(layer "F.Cu")
		(net "M_B_DQ<55>")
	)
	(segment
		(start 300.0248 -42.921428)
		(end 306.00777 -36.938458)
		(width 0.1651)
		(layer "F.Cu")
		(net "M_B_DQ<55>")
	)
	(segment
		(start 285.304484 -50.505868)
		(end 285.619698 -50.190654)
		(width 0.0889)
		(layer "F.Cu")
		(net "M_B_DQ<55>")
	)
	(segment
		(start 285.304484 -53.548534)
		(end 285.304484 -50.505868)
		(width 0.0889)
		(layer "F.Cu")
		(net "M_B_DQ<55>")
	)
	(segment
		(start 304.35042 -5.822442)
		(end 304.349912 -5.822442)
		(width 0.1651)
		(layer "F.Cu")
		(net "M_B_DQ<55>")
	)
	(segment
		(start 285.619698 -50.190654)
		(end 286.04972 -50.190654)
		(width 0.0889)
		(layer "F.Cu")
		(net "M_B_DQ<55>")
	)
	(segment
		(start 304.9778 -28.3972)
		(end 304.743866 -28.163266)
		(width 0.1651)
		(layer "F.Cu")
		(net "M_B_DQ<55>")
	)
	(segment
		(start 284.929834 -53.923184)
		(end 285.304484 -53.548534)
		(width 0.0889)
		(layer "F.Cu")
		(net "M_B_DQ<55>")
	)
	(segment
		(start 286.124142 -50.116232)
		(end 288.29635 -47.944024)
		(width 0.1016)
		(layer "F.Cu")
		(net "M_B_DQ<55>")
	)
	(segment
		(start 304.743866 -27.713686)
		(end 305.199796 -27.257756)
		(width 0.1651)
		(layer "F.Cu")
		(net "M_B_DQ<55>")
	)
	(segment
		(start 304.743866 -28.163266)
		(end 304.743866 -27.713686)
		(width 0.1651)
		(layer "F.Cu")
		(net "M_B_DQ<55>")
	)
	(segment
		(start 286.04972 -50.190654)
		(end 286.124142 -50.116232)
		(width 0.0889)
		(layer "F.Cu")
		(net "M_B_DQ<55>")
	)
	(segment
		(start 304.9778 -32.3342)
		(end 304.9778 -28.3972)
		(width 0.1651)
		(layer "F.Cu")
		(net "M_B_DQ<55>")
	)
	(segment
		(start 288.29635 -47.944024)
		(end 295.13149 -47.944024)
		(width 0.1016)
		(layer "F.Cu")
		(net "M_B_DQ<55>")
	)
	(segment
		(start 300.0248 -43.050714)
		(end 300.0248 -42.921428)
		(width 0.1016)
		(layer "F.Cu")
		(net "M_B_DQ<55>")
	)
	(via
		(at 305.199796 -27.257756)
		(size 0.508)
		(drill 0.254)
		(layers "F.Cu" "B.Cu")
		(net "M_B_DQ<55>")
	)
	(via
		(at 305.199796 -12.678156)
		(size 0.508)
		(drill 0.254)
		(layers "F.Cu" "B.Cu")
		(net "M_B_DQ<55>")
	)
	(via
		(at 304.349912 -7.086346)
		(size 0.508)
		(drill 0.254)
		(layers "F.Cu" "B.Cu")
		(net "M_B_DQ<55>")
	)
	(via
		(at 306.00777 -35.306)
		(size 0.508)
		(drill 0.254)
		(layers "F.Cu" "B.Cu")
		(net "M_B_DQ<55>")
	)
	(segment
		(start 305.200304 -10.623042)
		(end 305.199796 -10.623042)
		(width 0.1651)
		(layer "B.Cu")
		(net "M_B_DQ<55>")
	)
	(segment
		(start 305.199796 -10.623042)
		(end 305.199796 -12.678156)
		(width 0.1651)
		(layer "B.Cu")
		(net "M_B_DQ<55>")
	)
	(segment
		(start 305.199796 -12.678156)
		(end 305.552602 -12.32535)
		(width 0.14224)
		(layer "In4.Cu")
		(net "M_B_DQ<55>")
	)
	(segment
		(start 305.529996 -21.804122)
		(end 305.529996 -18.574004)
		(width 0.14224)
		(layer "In4.Cu")
		(net "M_B_DQ<55>")
	)
	(segment
		(start 305.529996 -18.574004)
		(end 305.71567 -18.38833)
		(width 0.14224)
		(layer "In4.Cu")
		(net "M_B_DQ<55>")
	)
	(segment
		(start 305.71567 -17.015714)
		(end 305.41087 -16.710914)
		(width 0.14224)
		(layer "In4.Cu")
		(net "M_B_DQ<55>")
	)
	(segment
		(start 304.66665 -7.7216)
		(end 304.66665 -7.403084)
		(width 0.14224)
		(layer "In4.Cu")
		(net "M_B_DQ<55>")
	)
	(segment
		(start 304.742596 -13.60043)
		(end 304.742596 -13.135356)
		(width 0.14224)
		(layer "In4.Cu")
		(net "M_B_DQ<55>")
	)
	(segment
		(start 304.99685 -8.0518)
		(end 304.66665 -7.7216)
		(width 0.14224)
		(layer "In4.Cu")
		(net "M_B_DQ<55>")
	)
	(segment
		(start 305.552602 -9.020048)
		(end 305.70805 -8.8646)
		(width 0.14224)
		(layer "In4.Cu")
		(net "M_B_DQ<55>")
	)
	(segment
		(start 305.41087 -16.710914)
		(end 305.41087 -14.268704)
		(width 0.14224)
		(layer "In4.Cu")
		(net "M_B_DQ<55>")
	)
	(segment
		(start 304.66665 -7.403084)
		(end 304.349912 -7.086346)
		(width 0.14224)
		(layer "In4.Cu")
		(net "M_B_DQ<55>")
	)
	(segment
		(start 305.56327 -23.294848)
		(end 305.74107 -23.117048)
		(width 0.14224)
		(layer "In4.Cu")
		(net "M_B_DQ<55>")
	)
	(segment
		(start 305.552602 -12.32535)
		(end 305.552602 -9.020048)
		(width 0.14224)
		(layer "In4.Cu")
		(net "M_B_DQ<55>")
	)
	(segment
		(start 305.71567 -18.38833)
		(end 305.71567 -17.015714)
		(width 0.14224)
		(layer "In4.Cu")
		(net "M_B_DQ<55>")
	)
	(segment
		(start 305.199796 -27.257756)
		(end 305.56327 -26.894282)
		(width 0.14224)
		(layer "In4.Cu")
		(net "M_B_DQ<55>")
	)
	(segment
		(start 305.56327 -26.894282)
		(end 305.56327 -23.294848)
		(width 0.14224)
		(layer "In4.Cu")
		(net "M_B_DQ<55>")
	)
	(segment
		(start 305.25085 -8.0518)
		(end 304.99685 -8.0518)
		(width 0.14224)
		(layer "In4.Cu")
		(net "M_B_DQ<55>")
	)
	(segment
		(start 304.742596 -13.135356)
		(end 305.199796 -12.678156)
		(width 0.14224)
		(layer "In4.Cu")
		(net "M_B_DQ<55>")
	)
	(segment
		(start 305.41087 -14.268704)
		(end 304.742596 -13.60043)
		(width 0.14224)
		(layer "In4.Cu")
		(net "M_B_DQ<55>")
	)
	(segment
		(start 305.70805 -8.8646)
		(end 305.70805 -8.509)
		(width 0.14224)
		(layer "In4.Cu")
		(net "M_B_DQ<55>")
	)
	(segment
		(start 305.74107 -23.117048)
		(end 305.74107 -22.015196)
		(width 0.14224)
		(layer "In4.Cu")
		(net "M_B_DQ<55>")
	)
	(segment
		(start 305.70805 -8.509)
		(end 305.25085 -8.0518)
		(width 0.14224)
		(layer "In4.Cu")
		(net "M_B_DQ<55>")
	)
	(segment
		(start 305.74107 -22.015196)
		(end 305.529996 -21.804122)
		(width 0.14224)
		(layer "In4.Cu")
		(net "M_B_DQ<55>")
	)
	(segment
		(start 305.33213 -9.09828)
		(end 305.33213 -9.31672)
		(width 0.1651)
		(layer "F.Cu")
		(net "M_B_DQ<54>")
	)
	(segment
		(start 299.5422 -42.499026)
		(end 304.021744 -38.019482)
		(width 0.1651)
		(layer "F.Cu")
		(net "M_B_DQ<54>")
	)
	(segment
		(start 285.113984 -51.757834)
		(end 285.113984 -50.426874)
		(width 0.0889)
		(layer "F.Cu")
		(net "M_B_DQ<54>")
	)
	(segment
		(start 304.021744 -36.707826)
		(end 304.186844 -36.542726)
		(width 0.1651)
		(layer "F.Cu")
		(net "M_B_DQ<54>")
	)
	(segment
		(start 304.021744 -34.8361)
		(end 304.021744 -30.607)
		(width 0.1651)
		(layer "F.Cu")
		(net "M_B_DQ<54>")
	)
	(segment
		(start 299.5422 -42.976292)
		(end 299.5422 -42.499026)
		(width 0.1016)
		(layer "F.Cu")
		(net "M_B_DQ<54>")
	)
	(segment
		(start 304.349912 -28.949142)
		(end 304.349912 -28.538678)
		(width 0.1651)
		(layer "F.Cu")
		(net "M_B_DQ<54>")
	)
	(segment
		(start 304.859944 -33.9598)
		(end 304.694844 -34.1249)
		(width 0.1651)
		(layer "F.Cu")
		(net "M_B_DQ<54>")
	)
	(segment
		(start 285.540704 -50.000154)
		(end 285.683198 -50.000154)
		(width 0.0889)
		(layer "F.Cu")
		(net "M_B_DQ<54>")
	)
	(segment
		(start 284.929834 -51.941984)
		(end 285.113984 -51.757834)
		(width 0.0889)
		(layer "F.Cu")
		(net "M_B_DQ<54>")
	)
	(segment
		(start 285.888938 -49.794414)
		(end 288.133028 -47.550324)
		(width 0.1016)
		(layer "F.Cu")
		(net "M_B_DQ<54>")
	)
	(segment
		(start 305.367944 -34.1249)
		(end 305.202844 -33.9598)
		(width 0.1651)
		(layer "F.Cu")
		(net "M_B_DQ<54>")
	)
	(segment
		(start 304.694844 -34.1249)
		(end 304.694844 -34.8361)
		(width 0.1651)
		(layer "F.Cu")
		(net "M_B_DQ<54>")
	)
	(segment
		(start 294.968168 -47.550324)
		(end 299.5422 -42.976292)
		(width 0.1016)
		(layer "F.Cu")
		(net "M_B_DQ<54>")
	)
	(segment
		(start 304.186844 -36.542726)
		(end 305.202844 -36.542726)
		(width 0.1651)
		(layer "F.Cu")
		(net "M_B_DQ<54>")
	)
	(segment
		(start 305.199796 -8.6614)
		(end 305.20005 -8.661654)
		(width 0.1651)
		(layer "F.Cu")
		(net "M_B_DQ<54>")
	)
	(segment
		(start 304.021744 -30.607)
		(end 304.021744 -29.27731)
		(width 0.1651)
		(layer "F.Cu")
		(net "M_B_DQ<54>")
	)
	(segment
		(start 304.021744 -29.27731)
		(end 304.349912 -28.949142)
		(width 0.1651)
		(layer "F.Cu")
		(net "M_B_DQ<54>")
	)
	(segment
		(start 305.202844 -33.9598)
		(end 304.859944 -33.9598)
		(width 0.1651)
		(layer "F.Cu")
		(net "M_B_DQ<54>")
	)
	(segment
		(start 305.20005 -9.4488)
		(end 305.20005 -10.422128)
		(width 0.1651)
		(layer "F.Cu")
		(net "M_B_DQ<54>")
	)
	(segment
		(start 304.529744 -35.0012)
		(end 304.186844 -35.0012)
		(width 0.1651)
		(layer "F.Cu")
		(net "M_B_DQ<54>")
	)
	(segment
		(start 305.33213 -9.31672)
		(end 305.20005 -9.4488)
		(width 0.1651)
		(layer "F.Cu")
		(net "M_B_DQ<54>")
	)
	(segment
		(start 285.113984 -50.426874)
		(end 285.540704 -50.000154)
		(width 0.0889)
		(layer "F.Cu")
		(net "M_B_DQ<54>")
	)
	(segment
		(start 305.367944 -36.377626)
		(end 305.367944 -34.1249)
		(width 0.1651)
		(layer "F.Cu")
		(net "M_B_DQ<54>")
	)
	(segment
		(start 304.186844 -35.0012)
		(end 304.021744 -34.8361)
		(width 0.1651)
		(layer "F.Cu")
		(net "M_B_DQ<54>")
	)
	(segment
		(start 305.20005 -8.661654)
		(end 305.20005 -8.9662)
		(width 0.1651)
		(layer "F.Cu")
		(net "M_B_DQ<54>")
	)
	(segment
		(start 305.20005 -8.9662)
		(end 305.33213 -9.09828)
		(width 0.1651)
		(layer "F.Cu")
		(net "M_B_DQ<54>")
	)
	(segment
		(start 288.133028 -47.550324)
		(end 294.968168 -47.550324)
		(width 0.1016)
		(layer "F.Cu")
		(net "M_B_DQ<54>")
	)
	(segment
		(start 305.202844 -36.542726)
		(end 305.367944 -36.377626)
		(width 0.1651)
		(layer "F.Cu")
		(net "M_B_DQ<54>")
	)
	(segment
		(start 305.20005 -10.422128)
		(end 305.200304 -10.422382)
		(width 0.1651)
		(layer "F.Cu")
		(net "M_B_DQ<54>")
	)
	(segment
		(start 304.021744 -38.019482)
		(end 304.021744 -36.707826)
		(width 0.1651)
		(layer "F.Cu")
		(net "M_B_DQ<54>")
	)
	(segment
		(start 304.694844 -34.8361)
		(end 304.529744 -35.0012)
		(width 0.1651)
		(layer "F.Cu")
		(net "M_B_DQ<54>")
	)
	(segment
		(start 285.683198 -50.000154)
		(end 285.888938 -49.794414)
		(width 0.0889)
		(layer "F.Cu")
		(net "M_B_DQ<54>")
	)
	(via
		(at 304.349912 -28.538678)
		(size 0.508)
		(drill 0.254)
		(layers "F.Cu" "B.Cu")
		(net "M_B_DQ<54>")
	)
	(via
		(at 305.199796 -8.6614)
		(size 0.508)
		(drill 0.254)
		(layers "F.Cu" "B.Cu")
		(net "M_B_DQ<54>")
	)
	(via
		(at 304.021744 -30.607)
		(size 0.508)
		(drill 0.254)
		(layers "F.Cu" "B.Cu")
		(net "M_B_DQ<54>")
	)
	(via
		(at 304.349912 -13.959078)
		(size 0.508)
		(drill 0.254)
		(layers "F.Cu" "B.Cu")
		(net "M_B_DQ<54>")
	)
	(segment
		(start 304.349912 -15.222982)
		(end 304.349912 -13.959078)
		(width 0.1651)
		(layer "B.Cu")
		(net "M_B_DQ<54>")
	)
	(segment
		(start 304.35042 -15.222982)
		(end 304.349912 -15.222982)
		(width 0.1651)
		(layer "B.Cu")
		(net "M_B_DQ<54>")
	)
	(segment
		(start 304.85207 -14.461236)
		(end 304.85207 -16.850106)
		(width 0.14224)
		(layer "In4.Cu")
		(net "M_B_DQ<54>")
	)
	(segment
		(start 304.349912 -27.970734)
		(end 304.349912 -28.538678)
		(width 0.14224)
		(layer "In4.Cu")
		(net "M_B_DQ<54>")
	)
	(segment
		(start 304.1142 -12.928854)
		(end 304.1142 -13.723366)
		(width 0.14224)
		(layer "In4.Cu")
		(net "M_B_DQ<54>")
	)
	(segment
		(start 304.461418 -9.677654)
		(end 304.461418 -9.988296)
		(width 0.14224)
		(layer "In4.Cu")
		(net "M_B_DQ<54>")
	)
	(segment
		(start 304.1142 -13.723366)
		(end 304.349912 -13.959078)
		(width 0.14224)
		(layer "In4.Cu")
		(net "M_B_DQ<54>")
	)
	(segment
		(start 304.886868 -11.804396)
		(end 304.886868 -12.156186)
		(width 0.14224)
		(layer "In4.Cu")
		(net "M_B_DQ<54>")
	)
	(segment
		(start 304.64887 -18.41627)
		(end 304.844196 -18.611596)
		(width 0.14224)
		(layer "In4.Cu")
		(net "M_B_DQ<54>")
	)
	(segment
		(start 304.842418 -10.369296)
		(end 304.842418 -10.712704)
		(width 0.14224)
		(layer "In4.Cu")
		(net "M_B_DQ<54>")
	)
	(segment
		(start 304.8254 -9.313672)
		(end 304.461418 -9.677654)
		(width 0.14224)
		(layer "In4.Cu")
		(net "M_B_DQ<54>")
	)
	(segment
		(start 304.461418 -9.988296)
		(end 304.842418 -10.369296)
		(width 0.14224)
		(layer "In4.Cu")
		(net "M_B_DQ<54>")
	)
	(segment
		(start 304.349912 -13.959078)
		(end 304.85207 -14.461236)
		(width 0.14224)
		(layer "In4.Cu")
		(net "M_B_DQ<54>")
	)
	(segment
		(start 304.61839 -26.92273)
		(end 304.61839 -27.702256)
		(width 0.14224)
		(layer "In4.Cu")
		(net "M_B_DQ<54>")
	)
	(segment
		(start 304.461418 -11.378946)
		(end 304.886868 -11.804396)
		(width 0.14224)
		(layer "In4.Cu")
		(net "M_B_DQ<54>")
	)
	(segment
		(start 304.844196 -21.84527)
		(end 304.64887 -22.040596)
		(width 0.14224)
		(layer "In4.Cu")
		(net "M_B_DQ<54>")
	)
	(segment
		(start 304.842418 -10.712704)
		(end 304.461418 -11.093704)
		(width 0.14224)
		(layer "In4.Cu")
		(net "M_B_DQ<54>")
	)
	(segment
		(start 304.61839 -27.702256)
		(end 304.552096 -27.768296)
		(width 0.14224)
		(layer "In4.Cu")
		(net "M_B_DQ<54>")
	)
	(segment
		(start 304.8254 -9.035796)
		(end 304.8254 -9.313672)
		(width 0.14224)
		(layer "In4.Cu")
		(net "M_B_DQ<54>")
	)
	(segment
		(start 304.844196 -18.611596)
		(end 304.844196 -21.84527)
		(width 0.14224)
		(layer "In4.Cu")
		(net "M_B_DQ<54>")
	)
	(segment
		(start 304.64887 -22.040596)
		(end 304.64887 -23.132796)
		(width 0.14224)
		(layer "In4.Cu")
		(net "M_B_DQ<54>")
	)
	(segment
		(start 304.64887 -23.132796)
		(end 304.92827 -23.412196)
		(width 0.14224)
		(layer "In4.Cu")
		(net "M_B_DQ<54>")
	)
	(segment
		(start 304.64887 -17.053306)
		(end 304.64887 -18.41627)
		(width 0.14224)
		(layer "In4.Cu")
		(net "M_B_DQ<54>")
	)
	(segment
		(start 304.886868 -12.156186)
		(end 304.1142 -12.928854)
		(width 0.14224)
		(layer "In4.Cu")
		(net "M_B_DQ<54>")
	)
	(segment
		(start 304.92827 -26.61285)
		(end 304.61839 -26.92273)
		(width 0.14224)
		(layer "In4.Cu")
		(net "M_B_DQ<54>")
	)
	(segment
		(start 304.92827 -23.412196)
		(end 304.92827 -26.61285)
		(width 0.14224)
		(layer "In4.Cu")
		(net "M_B_DQ<54>")
	)
	(segment
		(start 305.199796 -8.6614)
		(end 304.8254 -9.035796)
		(width 0.14224)
		(layer "In4.Cu")
		(net "M_B_DQ<54>")
	)
	(segment
		(start 304.461418 -11.093704)
		(end 304.461418 -11.378946)
		(width 0.14224)
		(layer "In4.Cu")
		(net "M_B_DQ<54>")
	)
	(segment
		(start 304.85207 -16.850106)
		(end 304.64887 -17.053306)
		(width 0.14224)
		(layer "In4.Cu")
		(net "M_B_DQ<54>")
	)
	(segment
		(start 304.552096 -27.768296)
		(end 304.349912 -27.970734)
		(width 0.14224)
		(layer "In4.Cu")
		(net "M_B_DQ<54>")
	)
	(segment
		(start 293.824914 -44.794424)
		(end 288.244026 -44.794424)
		(width 0.1016)
		(layer "F.Cu")
		(net "M_B_DQ<53>")
	)
	(segment
		(start 297.458384 -38.177216)
		(end 295.444672 -40.190928)
		(width 0.1651)
		(layer "F.Cu")
		(net "M_B_DQ<53>")
	)
	(segment
		(start 282.530804 -49.141634)
		(end 282.642564 -49.141634)
		(width 0.0889)
		(layer "F.Cu")
		(net "M_B_DQ<53>")
	)
	(segment
		(start 282.372054 -52.837334)
		(end 282.33624 -52.837334)
		(width 0.0889)
		(layer "F.Cu")
		(net "M_B_DQ<53>")
	)
	(segment
		(start 298.671996 -28.085796)
		(end 299.105574 -28.519374)
		(width 0.1651)
		(layer "F.Cu")
		(net "M_B_DQ<53>")
	)
	(segment
		(start 282.086812 -51.757326)
		(end 281.967686 -51.550824)
		(width 0.0889)
		(layer "F.Cu")
		(net "M_B_DQ<53>")
	)
	(segment
		(start 298.399962 -5.822442)
		(end 298.399962 -7.086346)
		(width 0.1651)
		(layer "F.Cu")
		(net "M_B_DQ<53>")
	)
	(segment
		(start 298.40047 -5.822442)
		(end 298.399962 -5.822442)
		(width 0.1651)
		(layer "F.Cu")
		(net "M_B_DQ<53>")
	)
	(segment
		(start 282.086812 -51.757326)
		(end 282.086812 -51.940714)
		(width 0.0889)
		(layer "F.Cu")
		(net "M_B_DQ<53>")
	)
	(segment
		(start 283.212794 -53.923184)
		(end 282.883102 -53.161946)
		(width 0.0889)
		(layer "F.Cu")
		(net "M_B_DQ<53>")
	)
	(segment
		(start 296.899584 -37.618416)
		(end 297.079416 -37.618416)
		(width 0.1651)
		(layer "F.Cu")
		(net "M_B_DQ<53>")
	)
	(segment
		(start 282.642564 -49.141634)
		(end 286.989774 -44.794424)
		(width 0.1016)
		(layer "F.Cu")
		(net "M_B_DQ<53>")
	)
	(segment
		(start 296.173144 -37.559488)
		(end 296.475912 -37.862256)
		(width 0.1651)
		(layer "F.Cu")
		(net "M_B_DQ<53>")
	)
	(segment
		(start 297.458384 -37.997384)
		(end 297.458384 -38.177216)
		(width 0.1651)
		(layer "F.Cu")
		(net "M_B_DQ<53>")
	)
	(segment
		(start 298.835826 -29.408374)
		(end 298.835826 -31.75)
		(width 0.1651)
		(layer "F.Cu")
		(net "M_B_DQ<53>")
	)
	(segment
		(start 295.444672 -43.174666)
		(end 293.824914 -44.794424)
		(width 0.1016)
		(layer "F.Cu")
		(net "M_B_DQ<53>")
	)
	(segment
		(start 281.967686 -51.290474)
		(end 282.085542 -51.086004)
		(width 0.0889)
		(layer "F.Cu")
		(net "M_B_DQ<53>")
	)
	(segment
		(start 298.835826 -34.681414)
		(end 296.173144 -37.344096)
		(width 0.1651)
		(layer "F.Cu")
		(net "M_B_DQ<53>")
	)
	(segment
		(start 281.967686 -51.550824)
		(end 281.967686 -51.290474)
		(width 0.0889)
		(layer "F.Cu")
		(net "M_B_DQ<53>")
	)
	(segment
		(start 296.655744 -37.862256)
		(end 296.899584 -37.618416)
		(width 0.1651)
		(layer "F.Cu")
		(net "M_B_DQ<53>")
	)
	(segment
		(start 282.883102 -53.161946)
		(end 282.866084 -53.132736)
		(width 0.0889)
		(layer "F.Cu")
		(net "M_B_DQ<53>")
	)
	(segment
		(start 286.989774 -44.794424)
		(end 288.244026 -44.794424)
		(width 0.1016)
		(layer "F.Cu")
		(net "M_B_DQ<53>")
	)
	(segment
		(start 299.105574 -29.138626)
		(end 298.835826 -29.408374)
		(width 0.1651)
		(layer "F.Cu")
		(net "M_B_DQ<53>")
	)
	(segment
		(start 295.444672 -40.190928)
		(end 295.444672 -42.359072)
		(width 0.1651)
		(layer "F.Cu")
		(net "M_B_DQ<53>")
	)
	(segment
		(start 282.085542 -50.769266)
		(end 281.930348 -50.50028)
		(width 0.0889)
		(layer "F.Cu")
		(net "M_B_DQ<53>")
	)
	(segment
		(start 295.444672 -42.359072)
		(end 295.444672 -43.174666)
		(width 0.1016)
		(layer "F.Cu")
		(net "M_B_DQ<53>")
	)
	(segment
		(start 282.085542 -51.086004)
		(end 282.085542 -50.769266)
		(width 0.0889)
		(layer "F.Cu")
		(net "M_B_DQ<53>")
	)
	(segment
		(start 281.930348 -50.062638)
		(end 282.454604 -49.538382)
		(width 0.0889)
		(layer "F.Cu")
		(net "M_B_DQ<53>")
	)
	(segment
		(start 296.475912 -37.862256)
		(end 296.655744 -37.862256)
		(width 0.1651)
		(layer "F.Cu")
		(net "M_B_DQ<53>")
	)
	(segment
		(start 298.671996 -27.759406)
		(end 298.671996 -28.085796)
		(width 0.1651)
		(layer "F.Cu")
		(net "M_B_DQ<53>")
	)
	(segment
		(start 282.454604 -49.217834)
		(end 282.530804 -49.141634)
		(width 0.0889)
		(layer "F.Cu")
		(net "M_B_DQ<53>")
	)
	(segment
		(start 299.105574 -28.519374)
		(end 299.105574 -29.138626)
		(width 0.1651)
		(layer "F.Cu")
		(net "M_B_DQ<53>")
	)
	(segment
		(start 296.173144 -37.344096)
		(end 296.173144 -37.559488)
		(width 0.1651)
		(layer "F.Cu")
		(net "M_B_DQ<53>")
	)
	(segment
		(start 299.173646 -27.257756)
		(end 298.671996 -27.759406)
		(width 0.1651)
		(layer "F.Cu")
		(net "M_B_DQ<53>")
	)
	(segment
		(start 297.079416 -37.618416)
		(end 297.458384 -37.997384)
		(width 0.1651)
		(layer "F.Cu")
		(net "M_B_DQ<53>")
	)
	(segment
		(start 281.930348 -50.50028)
		(end 281.930348 -50.062638)
		(width 0.0889)
		(layer "F.Cu")
		(net "M_B_DQ<53>")
	)
	(segment
		(start 298.835826 -31.75)
		(end 298.835826 -34.681414)
		(width 0.1651)
		(layer "F.Cu")
		(net "M_B_DQ<53>")
	)
	(segment
		(start 282.454604 -49.538382)
		(end 282.454604 -49.217834)
		(width 0.0889)
		(layer "F.Cu")
		(net "M_B_DQ<53>")
	)
	(via
		(at 298.835826 -31.75)
		(size 0.508)
		(drill 0.254)
		(layers "F.Cu" "B.Cu")
		(net "M_B_DQ<53>")
	)
	(via
		(at 298.399962 -7.086346)
		(size 0.508)
		(drill 0.254)
		(layers "F.Cu" "B.Cu")
		(net "M_B_DQ<53>")
	)
	(via
		(at 299.173646 -12.678156)
		(size 0.508)
		(drill 0.254)
		(layers "F.Cu" "B.Cu")
		(net "M_B_DQ<53>")
	)
	(via
		(at 299.173646 -27.257756)
		(size 0.508)
		(drill 0.254)
		(layers "F.Cu" "B.Cu")
		(net "M_B_DQ<53>")
	)
	(arc
		(start 282.866084 -53.132736)
		(mid 282.657476 -52.920804)
		(end 282.372054 -52.837334)
		(width 0.0889)
		(layer "F.Cu")
		(net "M_B_DQ<53>")
	)
	(arc
		(start 282.007564 -52.237386)
		(mid 282.066795 -52.094287)
		(end 282.086812 -51.940714)
		(width 0.0889)
		(layer "F.Cu")
		(net "M_B_DQ<53>")
	)
	(arc
		(start 282.33624 -52.837334)
		(mid 282.003271 -52.629786)
		(end 282.007564 -52.237386)
		(width 0.0889)
		(layer "F.Cu")
		(net "M_B_DQ<53>")
	)
	(segment
		(start 299.249846 -10.623042)
		(end 299.249846 -12.601956)
		(width 0.1651)
		(layer "B.Cu")
		(net "M_B_DQ<53>")
	)
	(segment
		(start 299.249846 -12.601956)
		(end 299.173646 -12.678156)
		(width 0.1651)
		(layer "B.Cu")
		(net "M_B_DQ<53>")
	)
	(segment
		(start 299.250354 -10.623042)
		(end 299.249846 -10.623042)
		(width 0.1651)
		(layer "B.Cu")
		(net "M_B_DQ<53>")
	)
	(segment
		(start 299.6819 -8.452104)
		(end 299.6819 -8.8646)
		(width 0.14224)
		(layer "In4.Cu")
		(net "M_B_DQ<53>")
	)
	(segment
		(start 298.6532 -7.339584)
		(end 298.6532 -7.7343)
		(width 0.14224)
		(layer "In4.Cu")
		(net "M_B_DQ<53>")
	)
	(segment
		(start 299.67047 -23.158196)
		(end 299.59427 -23.234396)
		(width 0.14224)
		(layer "In4.Cu")
		(net "M_B_DQ<53>")
	)
	(segment
		(start 299.56887 -21.862796)
		(end 299.67047 -21.964396)
		(width 0.14224)
		(layer "In4.Cu")
		(net "M_B_DQ<53>")
	)
	(segment
		(start 299.173646 -12.678156)
		(end 299.173646 -14.287246)
		(width 0.14224)
		(layer "In4.Cu")
		(net "M_B_DQ<53>")
	)
	(segment
		(start 299.4406 -16.7894)
		(end 299.64507 -16.99387)
		(width 0.14224)
		(layer "In4.Cu")
		(net "M_B_DQ<53>")
	)
	(segment
		(start 299.59427 -23.234396)
		(end 299.59427 -26.837132)
		(width 0.14224)
		(layer "In4.Cu")
		(net "M_B_DQ<53>")
	)
	(segment
		(start 299.64507 -16.99387)
		(end 299.64507 -18.455386)
		(width 0.14224)
		(layer "In4.Cu")
		(net "M_B_DQ<53>")
	)
	(segment
		(start 299.4406 -14.5542)
		(end 299.4406 -16.7894)
		(width 0.14224)
		(layer "In4.Cu")
		(net "M_B_DQ<53>")
	)
	(segment
		(start 298.399962 -7.086346)
		(end 298.6532 -7.339584)
		(width 0.14224)
		(layer "In4.Cu")
		(net "M_B_DQ<53>")
	)
	(segment
		(start 299.281596 -8.0518)
		(end 299.6819 -8.452104)
		(width 0.14224)
		(layer "In4.Cu")
		(net "M_B_DQ<53>")
	)
	(segment
		(start 299.67047 -21.964396)
		(end 299.67047 -23.158196)
		(width 0.14224)
		(layer "In4.Cu")
		(net "M_B_DQ<53>")
	)
	(segment
		(start 299.48505 -9.06145)
		(end 299.48505 -12.366752)
		(width 0.14224)
		(layer "In4.Cu")
		(net "M_B_DQ<53>")
	)
	(segment
		(start 298.6532 -7.7343)
		(end 298.9707 -8.0518)
		(width 0.14224)
		(layer "In4.Cu")
		(net "M_B_DQ<53>")
	)
	(segment
		(start 298.9707 -8.0518)
		(end 299.281596 -8.0518)
		(width 0.14224)
		(layer "In4.Cu")
		(net "M_B_DQ<53>")
	)
	(segment
		(start 299.173646 -14.287246)
		(end 299.4406 -14.5542)
		(width 0.14224)
		(layer "In4.Cu")
		(net "M_B_DQ<53>")
	)
	(segment
		(start 299.64507 -18.455386)
		(end 299.56887 -18.531586)
		(width 0.14224)
		(layer "In4.Cu")
		(net "M_B_DQ<53>")
	)
	(segment
		(start 299.56887 -18.531586)
		(end 299.56887 -21.862796)
		(width 0.14224)
		(layer "In4.Cu")
		(net "M_B_DQ<53>")
	)
	(segment
		(start 299.59427 -26.837132)
		(end 299.173646 -27.257756)
		(width 0.14224)
		(layer "In4.Cu")
		(net "M_B_DQ<53>")
	)
	(segment
		(start 299.48505 -12.366752)
		(end 299.173646 -12.678156)
		(width 0.14224)
		(layer "In4.Cu")
		(net "M_B_DQ<53>")
	)
	(segment
		(start 299.6819 -8.8646)
		(end 299.48505 -9.06145)
		(width 0.14224)
		(layer "In4.Cu")
		(net "M_B_DQ<53>")
	)
	(segment
		(start 282.264104 -49.459134)
		(end 282.264104 -49.138586)
		(width 0.0889)
		(layer "F.Cu")
		(net "M_B_DQ<52>")
	)
	(segment
		(start 281.777186 -51.608482)
		(end 281.777186 -51.236626)
		(width 0.0889)
		(layer "F.Cu")
		(net "M_B_DQ<52>")
	)
	(segment
		(start 293.661592 -44.400724)
		(end 288.244026 -44.400724)
		(width 0.1016)
		(layer "F.Cu")
		(net "M_B_DQ<52>")
	)
	(segment
		(start 294.990012 -38.60038)
		(end 295.532556 -38.057836)
		(width 0.1651)
		(layer "F.Cu")
		(net "M_B_DQ<52>")
	)
	(segment
		(start 281.858974 -52.761896)
		(end 281.842464 -52.73294)
		(width 0.0889)
		(layer "F.Cu")
		(net "M_B_DQ<52>")
	)
	(segment
		(start 298.196 -33.655)
		(end 298.196 -34.415984)
		(width 0.1651)
		(layer "F.Cu")
		(net "M_B_DQ<52>")
	)
	(segment
		(start 281.739848 -49.98339)
		(end 282.264104 -49.459134)
		(width 0.0889)
		(layer "F.Cu")
		(net "M_B_DQ<52>")
	)
	(segment
		(start 294.069516 -39.739316)
		(end 294.796972 -40.466772)
		(width 0.1651)
		(layer "F.Cu")
		(net "M_B_DQ<52>")
	)
	(segment
		(start 282.354274 -53.427884)
		(end 281.858974 -52.761896)
		(width 0.0889)
		(layer "F.Cu")
		(net "M_B_DQ<52>")
	)
	(segment
		(start 294.990012 -39.513256)
		(end 294.756332 -39.513256)
		(width 0.1651)
		(layer "F.Cu")
		(net "M_B_DQ<52>")
	)
	(segment
		(start 281.777186 -51.236626)
		(end 281.895042 -51.032156)
		(width 0.0889)
		(layer "F.Cu")
		(net "M_B_DQ<52>")
	)
	(segment
		(start 294.552878 -39.309802)
		(end 294.319198 -39.309802)
		(width 0.1651)
		(layer "F.Cu")
		(net "M_B_DQ<52>")
	)
	(segment
		(start 282.368244 -48.858932)
		(end 286.826452 -44.400724)
		(width 0.1016)
		(layer "F.Cu")
		(net "M_B_DQ<52>")
	)
	(segment
		(start 294.319198 -39.309802)
		(end 294.069516 -39.559484)
		(width 0.1651)
		(layer "F.Cu")
		(net "M_B_DQ<52>")
	)
	(segment
		(start 282.264104 -49.138586)
		(end 282.368244 -49.034446)
		(width 0.0889)
		(layer "F.Cu")
		(net "M_B_DQ<52>")
	)
	(segment
		(start 299.212762 -8.89)
		(end 299.189394 -8.763)
		(width 0.1651)
		(layer "F.Cu")
		(net "M_B_DQ<52>")
	)
	(segment
		(start 298.196 -34.415984)
		(end 294.514016 -38.097968)
		(width 0.1651)
		(layer "F.Cu")
		(net "M_B_DQ<52>")
	)
	(segment
		(start 281.896058 -51.814222)
		(end 281.777186 -51.608482)
		(width 0.0889)
		(layer "F.Cu")
		(net "M_B_DQ<52>")
	)
	(segment
		(start 294.069516 -39.559484)
		(end 294.069516 -39.739316)
		(width 0.1651)
		(layer "F.Cu")
		(net "M_B_DQ<52>")
	)
	(segment
		(start 286.826452 -44.400724)
		(end 288.244026 -44.400724)
		(width 0.1016)
		(layer "F.Cu")
		(net "M_B_DQ<52>")
	)
	(segment
		(start 281.896058 -51.941476)
		(end 281.896058 -51.814222)
		(width 0.0889)
		(layer "F.Cu")
		(net "M_B_DQ<52>")
	)
	(segment
		(start 294.514016 -38.358064)
		(end 294.756332 -38.60038)
		(width 0.1651)
		(layer "F.Cu")
		(net "M_B_DQ<52>")
	)
	(segment
		(start 294.756332 -38.60038)
		(end 294.990012 -38.60038)
		(width 0.1651)
		(layer "F.Cu")
		(net "M_B_DQ<52>")
	)
	(segment
		(start 295.532556 -38.057836)
		(end 295.766236 -38.057836)
		(width 0.1651)
		(layer "F.Cu")
		(net "M_B_DQ<52>")
	)
	(segment
		(start 294.756332 -39.513256)
		(end 294.552878 -39.309802)
		(width 0.1651)
		(layer "F.Cu")
		(net "M_B_DQ<52>")
	)
	(segment
		(start 281.895042 -51.032156)
		(end 281.895042 -50.82032)
		(width 0.0889)
		(layer "F.Cu")
		(net "M_B_DQ<52>")
	)
	(segment
		(start 281.895042 -50.82032)
		(end 281.739848 -50.551588)
		(width 0.0889)
		(layer "F.Cu")
		(net "M_B_DQ<52>")
	)
	(segment
		(start 295.988994 -38.514274)
		(end 294.990012 -39.513256)
		(width 0.1651)
		(layer "F.Cu")
		(net "M_B_DQ<52>")
	)
	(segment
		(start 299.249846 -10.422382)
		(end 299.249846 -9.091168)
		(width 0.1651)
		(layer "F.Cu")
		(net "M_B_DQ<52>")
	)
	(segment
		(start 299.249846 -9.091168)
		(end 299.212762 -8.89)
		(width 0.1651)
		(layer "F.Cu")
		(net "M_B_DQ<52>")
	)
	(segment
		(start 295.988994 -38.280594)
		(end 295.988994 -38.514274)
		(width 0.1651)
		(layer "F.Cu")
		(net "M_B_DQ<52>")
	)
	(segment
		(start 299.189394 -8.763)
		(end 299.151802 -8.5598)
		(width 0.1651)
		(layer "F.Cu")
		(net "M_B_DQ<52>")
	)
	(segment
		(start 298.196 -28.727146)
		(end 298.196 -33.655)
		(width 0.1651)
		(layer "F.Cu")
		(net "M_B_DQ<52>")
	)
	(segment
		(start 294.796972 -43.265344)
		(end 293.661592 -44.400724)
		(width 0.1016)
		(layer "F.Cu")
		(net "M_B_DQ<52>")
	)
	(segment
		(start 298.384468 -28.538678)
		(end 298.196 -28.727146)
		(width 0.1651)
		(layer "F.Cu")
		(net "M_B_DQ<52>")
	)
	(segment
		(start 294.514016 -38.097968)
		(end 294.514016 -38.358064)
		(width 0.1651)
		(layer "F.Cu")
		(net "M_B_DQ<52>")
	)
	(segment
		(start 299.250354 -10.422382)
		(end 299.249846 -10.422382)
		(width 0.1651)
		(layer "F.Cu")
		(net "M_B_DQ<52>")
	)
	(segment
		(start 281.739848 -50.551588)
		(end 281.739848 -49.98339)
		(width 0.0889)
		(layer "F.Cu")
		(net "M_B_DQ<52>")
	)
	(segment
		(start 282.368244 -49.034446)
		(end 282.368244 -48.858932)
		(width 0.0889)
		(layer "F.Cu")
		(net "M_B_DQ<52>")
	)
	(segment
		(start 294.796972 -42.498772)
		(end 294.796972 -43.265344)
		(width 0.1016)
		(layer "F.Cu")
		(net "M_B_DQ<52>")
	)
	(segment
		(start 295.766236 -38.057836)
		(end 295.988994 -38.280594)
		(width 0.1651)
		(layer "F.Cu")
		(net "M_B_DQ<52>")
	)
	(segment
		(start 294.796972 -40.466772)
		(end 294.796972 -42.498772)
		(width 0.1651)
		(layer "F.Cu")
		(net "M_B_DQ<52>")
	)
	(via
		(at 299.151802 -8.5598)
		(size 0.508)
		(drill 0.254)
		(layers "F.Cu" "B.Cu")
		(net "M_B_DQ<52>")
	)
	(via
		(at 298.384468 -28.538678)
		(size 0.508)
		(drill 0.254)
		(layers "F.Cu" "B.Cu")
		(net "M_B_DQ<52>")
	)
	(via
		(at 298.399962 -13.959078)
		(size 0.508)
		(drill 0.254)
		(layers "F.Cu" "B.Cu")
		(net "M_B_DQ<52>")
	)
	(via
		(at 298.196 -33.655)
		(size 0.508)
		(drill 0.254)
		(layers "F.Cu" "B.Cu")
		(net "M_B_DQ<52>")
	)
	(arc
		(start 281.842464 -52.142136)
		(mid 281.882517 -52.045344)
		(end 281.896058 -51.941476)
		(width 0.0889)
		(layer "F.Cu")
		(net "M_B_DQ<52>")
	)
	(arc
		(start 281.842464 -52.73294)
		(mid 281.763333 -52.437538)
		(end 281.842464 -52.142136)
		(width 0.0889)
		(layer "F.Cu")
		(net "M_B_DQ<52>")
	)
	(segment
		(start 298.40047 -15.222982)
		(end 298.399962 -15.222982)
		(width 0.1651)
		(layer "B.Cu")
		(net "M_B_DQ<52>")
	)
	(segment
		(start 298.399962 -15.222982)
		(end 298.399962 -13.959078)
		(width 0.1651)
		(layer "B.Cu")
		(net "M_B_DQ<52>")
	)
	(segment
		(start 298.87545 -12.217654)
		(end 298.87545 -11.652504)
		(width 0.14224)
		(layer "In4.Cu")
		(net "M_B_DQ<52>")
	)
	(segment
		(start 298.671996 -26.89987)
		(end 298.88307 -26.688796)
		(width 0.14224)
		(layer "In4.Cu")
		(net "M_B_DQ<52>")
	)
	(segment
		(start 298.399962 -14.453362)
		(end 298.399962 -13.959078)
		(width 0.14224)
		(layer "In4.Cu")
		(net "M_B_DQ<52>")
	)
	(segment
		(start 298.671996 -28.266644)
		(end 298.671996 -26.89987)
		(width 0.14224)
		(layer "In4.Cu")
		(net "M_B_DQ<52>")
	)
	(segment
		(start 298.66717 -17.05483)
		(end 298.88307 -16.83893)
		(width 0.14224)
		(layer "In4.Cu")
		(net "M_B_DQ<52>")
	)
	(segment
		(start 298.87545 -8.836152)
		(end 299.151802 -8.5598)
		(width 0.14224)
		(layer "In4.Cu")
		(net "M_B_DQ<52>")
	)
	(segment
		(start 298.88307 -18.531586)
		(end 298.66717 -18.315686)
		(width 0.14224)
		(layer "In4.Cu")
		(net "M_B_DQ<52>")
	)
	(segment
		(start 298.66717 -21.951696)
		(end 298.70146 -21.91766)
		(width 0.14224)
		(layer "In4.Cu")
		(net "M_B_DQ<52>")
	)
	(segment
		(start 298.70146 -21.91766)
		(end 298.88307 -21.735796)
		(width 0.14224)
		(layer "In4.Cu")
		(net "M_B_DQ<52>")
	)
	(segment
		(start 298.66717 -18.315686)
		(end 298.66717 -17.05483)
		(width 0.14224)
		(layer "In4.Cu")
		(net "M_B_DQ<52>")
	)
	(segment
		(start 298.597066 -10.154666)
		(end 298.511468 -10.069068)
		(width 0.14224)
		(layer "In4.Cu")
		(net "M_B_DQ<52>")
	)
	(segment
		(start 298.749466 -10.154666)
		(end 298.597066 -10.154666)
		(width 0.14224)
		(layer "In4.Cu")
		(net "M_B_DQ<52>")
	)
	(segment
		(start 298.524168 -11.301222)
		(end 298.524168 -10.924032)
		(width 0.14224)
		(layer "In4.Cu")
		(net "M_B_DQ<52>")
	)
	(segment
		(start 298.88307 -21.735796)
		(end 298.88307 -18.531586)
		(width 0.14224)
		(layer "In4.Cu")
		(net "M_B_DQ<52>")
	)
	(segment
		(start 298.6786 -13.68044)
		(end 298.6786 -12.414504)
		(width 0.14224)
		(layer "In4.Cu")
		(net "M_B_DQ<52>")
	)
	(segment
		(start 298.66717 -23.153624)
		(end 298.66717 -21.951696)
		(width 0.14224)
		(layer "In4.Cu")
		(net "M_B_DQ<52>")
	)
	(segment
		(start 298.88307 -26.688796)
		(end 298.88307 -23.369524)
		(width 0.14224)
		(layer "In4.Cu")
		(net "M_B_DQ<52>")
	)
	(segment
		(start 298.511468 -9.793478)
		(end 298.87545 -9.429496)
		(width 0.14224)
		(layer "In4.Cu")
		(net "M_B_DQ<52>")
	)
	(segment
		(start 298.787566 -10.838434)
		(end 298.892468 -10.733532)
		(width 0.14224)
		(layer "In4.Cu")
		(net "M_B_DQ<52>")
	)
	(segment
		(start 298.892468 -10.733532)
		(end 298.892468 -10.297668)
		(width 0.14224)
		(layer "In4.Cu")
		(net "M_B_DQ<52>")
	)
	(segment
		(start 298.6786 -12.414504)
		(end 298.87545 -12.217654)
		(width 0.14224)
		(layer "In4.Cu")
		(net "M_B_DQ<52>")
	)
	(segment
		(start 298.399962 -13.959078)
		(end 298.6786 -13.68044)
		(width 0.14224)
		(layer "In4.Cu")
		(net "M_B_DQ<52>")
	)
	(segment
		(start 298.511468 -10.069068)
		(end 298.511468 -9.793478)
		(width 0.14224)
		(layer "In4.Cu")
		(net "M_B_DQ<52>")
	)
	(segment
		(start 298.88307 -16.83893)
		(end 298.88307 -14.93647)
		(width 0.14224)
		(layer "In4.Cu")
		(net "M_B_DQ<52>")
	)
	(segment
		(start 298.399962 -28.538678)
		(end 298.671996 -28.266644)
		(width 0.14224)
		(layer "In4.Cu")
		(net "M_B_DQ<52>")
	)
	(segment
		(start 298.88307 -23.369524)
		(end 298.66717 -23.153624)
		(width 0.14224)
		(layer "In4.Cu")
		(net "M_B_DQ<52>")
	)
	(segment
		(start 298.87545 -11.652504)
		(end 298.524168 -11.301222)
		(width 0.14224)
		(layer "In4.Cu")
		(net "M_B_DQ<52>")
	)
	(segment
		(start 298.609766 -10.838434)
		(end 298.787566 -10.838434)
		(width 0.14224)
		(layer "In4.Cu")
		(net "M_B_DQ<52>")
	)
	(segment
		(start 298.384468 -28.538678)
		(end 298.399962 -28.538678)
		(width 0.14224)
		(layer "In4.Cu")
		(net "M_B_DQ<52>")
	)
	(segment
		(start 298.88307 -14.93647)
		(end 298.399962 -14.453362)
		(width 0.14224)
		(layer "In4.Cu")
		(net "M_B_DQ<52>")
	)
	(segment
		(start 298.87545 -9.429496)
		(end 298.87545 -8.836152)
		(width 0.14224)
		(layer "In4.Cu")
		(net "M_B_DQ<52>")
	)
	(segment
		(start 298.892468 -10.297668)
		(end 298.749466 -10.154666)
		(width 0.14224)
		(layer "In4.Cu")
		(net "M_B_DQ<52>")
	)
	(segment
		(start 298.524168 -10.924032)
		(end 298.609766 -10.838434)
		(width 0.14224)
		(layer "In4.Cu")
		(net "M_B_DQ<52>")
	)
	(segment
		(start 286.910018 -50.4444)
		(end 288.244026 -49.110392)
		(width 0.1016)
		(layer "F.Cu")
		(net "M_B_DQ<51>")
	)
	(segment
		(start 295.458134 -48.731424)
		(end 300.095158 -44.0944)
		(width 0.1016)
		(layer "F.Cu")
		(net "M_B_DQ<51>")
	)
	(segment
		(start 307.294026 -37.462714)
		(end 307.294026 -35.687)
		(width 0.1651)
		(layer "F.Cu")
		(net "M_B_DQ<51>")
	)
	(segment
		(start 307.547772 -30.531054)
		(end 306.578 -29.561282)
		(width 0.1651)
		(layer "F.Cu")
		(net "M_B_DQ<51>")
	)
	(segment
		(start 286.809942 -50.4444)
		(end 286.910018 -50.4444)
		(width 0.0889)
		(layer "F.Cu")
		(net "M_B_DQ<51>")
	)
	(segment
		(start 306.197 -27.544268)
		(end 306.483512 -27.257756)
		(width 0.1651)
		(layer "F.Cu")
		(net "M_B_DQ<51>")
	)
	(segment
		(start 306.483512 -27.257756)
		(end 306.899818 -27.257756)
		(width 0.1651)
		(layer "F.Cu")
		(net "M_B_DQ<51>")
	)
	(segment
		(start 306.197 -27.991054)
		(end 306.197 -27.544268)
		(width 0.1651)
		(layer "F.Cu")
		(net "M_B_DQ<51>")
	)
	(segment
		(start 306.050442 -5.822442)
		(end 306.049934 -5.822442)
		(width 0.1651)
		(layer "F.Cu")
		(net "M_B_DQ<51>")
	)
	(segment
		(start 286.29991 -51.742086)
		(end 286.664908 -51.10861)
		(width 0.0889)
		(layer "F.Cu")
		(net "M_B_DQ<51>")
	)
	(segment
		(start 286.664908 -51.10861)
		(end 286.664908 -50.589434)
		(width 0.0889)
		(layer "F.Cu")
		(net "M_B_DQ<51>")
	)
	(segment
		(start 306.049934 -5.822442)
		(end 306.049934 -7.086346)
		(width 0.1651)
		(layer "F.Cu")
		(net "M_B_DQ<51>")
	)
	(segment
		(start 288.244026 -49.110392)
		(end 288.622994 -48.731424)
		(width 0.1016)
		(layer "F.Cu")
		(net "M_B_DQ<51>")
	)
	(segment
		(start 286.13481 -52.237386)
		(end 286.29991 -51.742086)
		(width 0.0889)
		(layer "F.Cu")
		(net "M_B_DQ<51>")
	)
	(segment
		(start 306.578 -28.372054)
		(end 306.197 -27.991054)
		(width 0.1651)
		(layer "F.Cu")
		(net "M_B_DQ<51>")
	)
	(segment
		(start 300.66234 -44.0944)
		(end 307.294026 -37.462714)
		(width 0.1651)
		(layer "F.Cu")
		(net "M_B_DQ<51>")
	)
	(segment
		(start 300.095158 -44.0944)
		(end 300.66234 -44.0944)
		(width 0.1016)
		(layer "F.Cu")
		(net "M_B_DQ<51>")
	)
	(segment
		(start 285.7881 -53.427884)
		(end 286.1183 -52.665884)
		(width 0.0889)
		(layer "F.Cu")
		(net "M_B_DQ<51>")
	)
	(segment
		(start 307.294026 -33.386522)
		(end 307.547772 -33.132776)
		(width 0.1651)
		(layer "F.Cu")
		(net "M_B_DQ<51>")
	)
	(segment
		(start 286.1183 -52.665884)
		(end 286.139636 -52.6288)
		(width 0.0889)
		(layer "F.Cu")
		(net "M_B_DQ<51>")
	)
	(segment
		(start 288.622994 -48.731424)
		(end 295.458134 -48.731424)
		(width 0.1016)
		(layer "F.Cu")
		(net "M_B_DQ<51>")
	)
	(segment
		(start 307.547772 -33.132776)
		(end 307.547772 -30.531054)
		(width 0.1651)
		(layer "F.Cu")
		(net "M_B_DQ<51>")
	)
	(segment
		(start 286.664908 -50.589434)
		(end 286.809942 -50.4444)
		(width 0.0889)
		(layer "F.Cu")
		(net "M_B_DQ<51>")
	)
	(segment
		(start 307.294026 -35.687)
		(end 307.294026 -33.386522)
		(width 0.1651)
		(layer "F.Cu")
		(net "M_B_DQ<51>")
	)
	(segment
		(start 306.578 -29.561282)
		(end 306.578 -28.372054)
		(width 0.1651)
		(layer "F.Cu")
		(net "M_B_DQ<51>")
	)
	(via
		(at 307.294026 -35.687)
		(size 0.508)
		(drill 0.254)
		(layers "F.Cu" "B.Cu")
		(net "M_B_DQ<51>")
	)
	(via
		(at 306.899818 -12.678156)
		(size 0.508)
		(drill 0.254)
		(layers "F.Cu" "B.Cu")
		(net "M_B_DQ<51>")
	)
	(via
		(at 306.899818 -27.257756)
		(size 0.508)
		(drill 0.254)
		(layers "F.Cu" "B.Cu")
		(net "M_B_DQ<51>")
	)
	(via
		(at 306.049934 -7.086346)
		(size 0.508)
		(drill 0.254)
		(layers "F.Cu" "B.Cu")
		(net "M_B_DQ<51>")
	)
	(arc
		(start 286.139636 -52.6288)
		(mid 286.188391 -52.432448)
		(end 286.13481 -52.237386)
		(width 0.0889)
		(layer "F.Cu")
		(net "M_B_DQ<51>")
	)
	(segment
		(start 306.899818 -10.623042)
		(end 306.899818 -12.678156)
		(width 0.1651)
		(layer "B.Cu")
		(net "M_B_DQ<51>")
	)
	(segment
		(start 306.900326 -10.623042)
		(end 306.899818 -10.623042)
		(width 0.1651)
		(layer "B.Cu")
		(net "M_B_DQ<51>")
	)
	(segment
		(start 307.252624 -9.020048)
		(end 307.408072 -8.8646)
		(width 0.14224)
		(layer "In4.Cu")
		(net "M_B_DQ<51>")
	)
	(segment
		(start 306.950872 -8.0518)
		(end 306.696872 -8.0518)
		(width 0.14224)
		(layer "In4.Cu")
		(net "M_B_DQ<51>")
	)
	(segment
		(start 306.899818 -27.257756)
		(end 307.21427 -26.943304)
		(width 0.14224)
		(layer "In4.Cu")
		(net "M_B_DQ<51>")
	)
	(segment
		(start 306.696872 -8.0518)
		(end 306.366672 -7.7216)
		(width 0.14224)
		(layer "In4.Cu")
		(net "M_B_DQ<51>")
	)
	(segment
		(start 307.292756 -16.18361)
		(end 306.810156 -15.70101)
		(width 0.14224)
		(layer "In4.Cu")
		(net "M_B_DQ<51>")
	)
	(segment
		(start 307.39207 -17.012666)
		(end 307.292756 -16.913352)
		(width 0.14224)
		(layer "In4.Cu")
		(net "M_B_DQ<51>")
	)
	(segment
		(start 307.21427 -18.56613)
		(end 307.39207 -18.38833)
		(width 0.14224)
		(layer "In4.Cu")
		(net "M_B_DQ<51>")
	)
	(segment
		(start 307.39207 -23.200868)
		(end 307.39207 -21.969476)
		(width 0.14224)
		(layer "In4.Cu")
		(net "M_B_DQ<51>")
	)
	(segment
		(start 306.366672 -7.403084)
		(end 306.049934 -7.086346)
		(width 0.14224)
		(layer "In4.Cu")
		(net "M_B_DQ<51>")
	)
	(segment
		(start 307.408072 -8.8646)
		(end 307.408072 -8.509)
		(width 0.14224)
		(layer "In4.Cu")
		(net "M_B_DQ<51>")
	)
	(segment
		(start 306.810156 -13.96619)
		(end 306.354734 -13.510768)
		(width 0.14224)
		(layer "In4.Cu")
		(net "M_B_DQ<51>")
	)
	(segment
		(start 306.810156 -15.70101)
		(end 306.810156 -13.96619)
		(width 0.14224)
		(layer "In4.Cu")
		(net "M_B_DQ<51>")
	)
	(segment
		(start 307.408072 -8.509)
		(end 306.950872 -8.0518)
		(width 0.14224)
		(layer "In4.Cu")
		(net "M_B_DQ<51>")
	)
	(segment
		(start 307.39207 -21.969476)
		(end 307.21427 -21.791676)
		(width 0.14224)
		(layer "In4.Cu")
		(net "M_B_DQ<51>")
	)
	(segment
		(start 307.252624 -12.32535)
		(end 307.252624 -9.020048)
		(width 0.14224)
		(layer "In4.Cu")
		(net "M_B_DQ<51>")
	)
	(segment
		(start 307.21427 -26.943304)
		(end 307.21427 -23.378668)
		(width 0.14224)
		(layer "In4.Cu")
		(net "M_B_DQ<51>")
	)
	(segment
		(start 306.354734 -13.510768)
		(end 306.354734 -13.22324)
		(width 0.14224)
		(layer "In4.Cu")
		(net "M_B_DQ<51>")
	)
	(segment
		(start 306.354734 -13.22324)
		(end 306.899818 -12.678156)
		(width 0.14224)
		(layer "In4.Cu")
		(net "M_B_DQ<51>")
	)
	(segment
		(start 307.292756 -16.913352)
		(end 307.292756 -16.18361)
		(width 0.14224)
		(layer "In4.Cu")
		(net "M_B_DQ<51>")
	)
	(segment
		(start 306.899818 -12.678156)
		(end 307.252624 -12.32535)
		(width 0.14224)
		(layer "In4.Cu")
		(net "M_B_DQ<51>")
	)
	(segment
		(start 307.39207 -18.38833)
		(end 307.39207 -17.012666)
		(width 0.14224)
		(layer "In4.Cu")
		(net "M_B_DQ<51>")
	)
	(segment
		(start 306.366672 -7.7216)
		(end 306.366672 -7.403084)
		(width 0.14224)
		(layer "In4.Cu")
		(net "M_B_DQ<51>")
	)
	(segment
		(start 307.21427 -23.378668)
		(end 307.39207 -23.200868)
		(width 0.14224)
		(layer "In4.Cu")
		(net "M_B_DQ<51>")
	)
	(segment
		(start 307.21427 -21.791676)
		(end 307.21427 -18.56613)
		(width 0.14224)
		(layer "In4.Cu")
		(net "M_B_DQ<51>")
	)
	(segment
		(start 305.617626 -28.970986)
		(end 306.049934 -28.538678)
		(width 0.1651)
		(layer "F.Cu")
		(net "M_B_DQ<50>")
	)
	(segment
		(start 307.03139 -9.07034)
		(end 306.899818 -8.938768)
		(width 0.1651)
		(layer "F.Cu")
		(net "M_B_DQ<50>")
	)
	(segment
		(start 300.366684 -43.4848)
		(end 306.6542 -37.197284)
		(width 0.1651)
		(layer "F.Cu")
		(net "M_B_DQ<50>")
	)
	(segment
		(start 306.6542 -33.121346)
		(end 306.907946 -32.8676)
		(width 0.1651)
		(layer "F.Cu")
		(net "M_B_DQ<50>")
	)
	(segment
		(start 285.7881 -52.437538)
		(end 286.100774 -51.715416)
		(width 0.0889)
		(layer "F.Cu")
		(net "M_B_DQ<50>")
	)
	(segment
		(start 288.244026 -48.55337)
		(end 288.459672 -48.337724)
		(width 0.1016)
		(layer "F.Cu")
		(net "M_B_DQ<50>")
	)
	(segment
		(start 299.959268 -43.673268)
		(end 300.178216 -43.673268)
		(width 0.1016)
		(layer "F.Cu")
		(net "M_B_DQ<50>")
	)
	(segment
		(start 306.907946 -32.8676)
		(end 306.907946 -31.2166)
		(width 0.1651)
		(layer "F.Cu")
		(net "M_B_DQ<50>")
	)
	(segment
		(start 306.899818 -10.422382)
		(end 306.899818 -9.425432)
		(width 0.1651)
		(layer "F.Cu")
		(net "M_B_DQ<50>")
	)
	(segment
		(start 295.294812 -48.337724)
		(end 299.959268 -43.673268)
		(width 0.1016)
		(layer "F.Cu")
		(net "M_B_DQ<50>")
	)
	(segment
		(start 288.459672 -48.337724)
		(end 295.294812 -48.337724)
		(width 0.1016)
		(layer "F.Cu")
		(net "M_B_DQ<50>")
	)
	(segment
		(start 306.6542 -33.909)
		(end 306.6542 -33.121346)
		(width 0.1651)
		(layer "F.Cu")
		(net "M_B_DQ<50>")
	)
	(segment
		(start 300.178216 -43.673268)
		(end 300.366684 -43.4848)
		(width 0.1016)
		(layer "F.Cu")
		(net "M_B_DQ<50>")
	)
	(segment
		(start 306.389786 -31.0896)
		(end 306.262786 -31.2166)
		(width 0.1651)
		(layer "F.Cu")
		(net "M_B_DQ<50>")
	)
	(segment
		(start 307.03139 -9.29386)
		(end 307.03139 -9.07034)
		(width 0.1651)
		(layer "F.Cu")
		(net "M_B_DQ<50>")
	)
	(segment
		(start 306.780946 -31.0896)
		(end 306.389786 -31.0896)
		(width 0.1651)
		(layer "F.Cu")
		(net "M_B_DQ<50>")
	)
	(segment
		(start 305.617626 -32.019748)
		(end 305.617626 -28.970986)
		(width 0.1651)
		(layer "F.Cu")
		(net "M_B_DQ<50>")
	)
	(segment
		(start 306.899818 -9.425432)
		(end 307.03139 -9.29386)
		(width 0.1651)
		(layer "F.Cu")
		(net "M_B_DQ<50>")
	)
	(segment
		(start 286.474408 -50.322988)
		(end 286.711898 -50.085498)
		(width 0.0889)
		(layer "F.Cu")
		(net "M_B_DQ<50>")
	)
	(segment
		(start 306.262786 -31.2166)
		(end 306.262786 -32.0548)
		(width 0.1651)
		(layer "F.Cu")
		(net "M_B_DQ<50>")
	)
	(segment
		(start 306.6542 -37.197284)
		(end 306.6542 -33.909)
		(width 0.1651)
		(layer "F.Cu")
		(net "M_B_DQ<50>")
	)
	(segment
		(start 286.13481 -51.646582)
		(end 286.474408 -51.055524)
		(width 0.0889)
		(layer "F.Cu")
		(net "M_B_DQ<50>")
	)
	(segment
		(start 306.262786 -32.0548)
		(end 306.135786 -32.1818)
		(width 0.1651)
		(layer "F.Cu")
		(net "M_B_DQ<50>")
	)
	(segment
		(start 306.899818 -8.938768)
		(end 306.899818 -8.6614)
		(width 0.1651)
		(layer "F.Cu")
		(net "M_B_DQ<50>")
	)
	(segment
		(start 286.711898 -50.085498)
		(end 288.244026 -48.55337)
		(width 0.1016)
		(layer "F.Cu")
		(net "M_B_DQ<50>")
	)
	(segment
		(start 306.135786 -32.1818)
		(end 305.779678 -32.1818)
		(width 0.1651)
		(layer "F.Cu")
		(net "M_B_DQ<50>")
	)
	(segment
		(start 306.900326 -10.422382)
		(end 306.899818 -10.422382)
		(width 0.1651)
		(layer "F.Cu")
		(net "M_B_DQ<50>")
	)
	(segment
		(start 286.474408 -51.055524)
		(end 286.474408 -50.322988)
		(width 0.0889)
		(layer "F.Cu")
		(net "M_B_DQ<50>")
	)
	(segment
		(start 305.779678 -32.1818)
		(end 305.617626 -32.019748)
		(width 0.1651)
		(layer "F.Cu")
		(net "M_B_DQ<50>")
	)
	(segment
		(start 306.907946 -31.2166)
		(end 306.780946 -31.0896)
		(width 0.1651)
		(layer "F.Cu")
		(net "M_B_DQ<50>")
	)
	(via
		(at 306.899818 -8.6614)
		(size 0.508)
		(drill 0.254)
		(layers "F.Cu" "B.Cu")
		(net "M_B_DQ<50>")
	)
	(via
		(at 306.049934 -28.538678)
		(size 0.508)
		(drill 0.254)
		(layers "F.Cu" "B.Cu")
		(net "M_B_DQ<50>")
	)
	(via
		(at 306.049934 -13.959078)
		(size 0.508)
		(drill 0.254)
		(layers "F.Cu" "B.Cu")
		(net "M_B_DQ<50>")
	)
	(via
		(at 306.6542 -33.909)
		(size 0.508)
		(drill 0.254)
		(layers "F.Cu" "B.Cu")
		(net "M_B_DQ<50>")
	)
	(arc
		(start 286.100774 -51.715416)
		(mid 286.11668 -51.680449)
		(end 286.13481 -51.646582)
		(width 0.0889)
		(layer "F.Cu")
		(net "M_B_DQ<50>")
	)
	(segment
		(start 306.050442 -15.222982)
		(end 306.049934 -15.222982)
		(width 0.1651)
		(layer "B.Cu")
		(net "M_B_DQ<50>")
	)
	(segment
		(start 306.049934 -15.222982)
		(end 306.049934 -13.959078)
		(width 0.1651)
		(layer "B.Cu")
		(net "M_B_DQ<50>")
	)
	(segment
		(start 306.393596 -21.97227)
		(end 306.393596 -23.18385)
		(width 0.14224)
		(layer "In4.Cu")
		(net "M_B_DQ<50>")
	)
	(segment
		(start 306.5018 -9.059418)
		(end 306.5018 -9.364472)
		(width 0.14224)
		(layer "In4.Cu")
		(net "M_B_DQ<50>")
	)
	(segment
		(start 306.614068 -12.079732)
		(end 305.7652 -12.9286)
		(width 0.14224)
		(layer "In4.Cu")
		(net "M_B_DQ<50>")
	)
	(segment
		(start 306.461668 -10.362946)
		(end 306.461668 -10.64895)
		(width 0.14224)
		(layer "In4.Cu")
		(net "M_B_DQ<50>")
	)
	(segment
		(start 306.393596 -26.81859)
		(end 306.393596 -27.780996)
		(width 0.14224)
		(layer "In4.Cu")
		(net "M_B_DQ<50>")
	)
	(segment
		(start 305.7652 -13.674344)
		(end 306.049934 -13.959078)
		(width 0.14224)
		(layer "In4.Cu")
		(net "M_B_DQ<50>")
	)
	(segment
		(start 306.049934 -28.124658)
		(end 306.049934 -28.538678)
		(width 0.14224)
		(layer "In4.Cu")
		(net "M_B_DQ<50>")
	)
	(segment
		(start 306.156868 -10.95375)
		(end 306.156868 -11.3538)
		(width 0.14224)
		(layer "In4.Cu")
		(net "M_B_DQ<50>")
	)
	(segment
		(start 306.57927 -18.59407)
		(end 306.57927 -21.786596)
		(width 0.14224)
		(layer "In4.Cu")
		(net "M_B_DQ<50>")
	)
	(segment
		(start 306.55387 -26.658316)
		(end 306.393596 -26.81859)
		(width 0.14224)
		(layer "In4.Cu")
		(net "M_B_DQ<50>")
	)
	(segment
		(start 306.049934 -13.959078)
		(end 306.049934 -16.040608)
		(width 0.14224)
		(layer "In4.Cu")
		(net "M_B_DQ<50>")
	)
	(segment
		(start 306.37607 -17.024858)
		(end 306.37607 -18.39087)
		(width 0.14224)
		(layer "In4.Cu")
		(net "M_B_DQ<50>")
	)
	(segment
		(start 306.37607 -18.39087)
		(end 306.57927 -18.59407)
		(width 0.14224)
		(layer "In4.Cu")
		(net "M_B_DQ<50>")
	)
	(segment
		(start 305.7652 -12.9286)
		(end 305.7652 -13.674344)
		(width 0.14224)
		(layer "In4.Cu")
		(net "M_B_DQ<50>")
	)
	(segment
		(start 306.55387 -23.344124)
		(end 306.55387 -26.658316)
		(width 0.14224)
		(layer "In4.Cu")
		(net "M_B_DQ<50>")
	)
	(segment
		(start 306.5018 -9.364472)
		(end 306.156868 -9.709404)
		(width 0.14224)
		(layer "In4.Cu")
		(net "M_B_DQ<50>")
	)
	(segment
		(start 306.461668 -10.64895)
		(end 306.156868 -10.95375)
		(width 0.14224)
		(layer "In4.Cu")
		(net "M_B_DQ<50>")
	)
	(segment
		(start 306.156868 -10.058146)
		(end 306.461668 -10.362946)
		(width 0.14224)
		(layer "In4.Cu")
		(net "M_B_DQ<50>")
	)
	(segment
		(start 306.614068 -11.811)
		(end 306.614068 -12.079732)
		(width 0.14224)
		(layer "In4.Cu")
		(net "M_B_DQ<50>")
	)
	(segment
		(start 306.393596 -23.18385)
		(end 306.55387 -23.344124)
		(width 0.14224)
		(layer "In4.Cu")
		(net "M_B_DQ<50>")
	)
	(segment
		(start 306.156868 -11.3538)
		(end 306.614068 -11.811)
		(width 0.14224)
		(layer "In4.Cu")
		(net "M_B_DQ<50>")
	)
	(segment
		(start 306.507134 -16.497808)
		(end 306.507134 -16.893794)
		(width 0.14224)
		(layer "In4.Cu")
		(net "M_B_DQ<50>")
	)
	(segment
		(start 306.393596 -27.780996)
		(end 306.049934 -28.124658)
		(width 0.14224)
		(layer "In4.Cu")
		(net "M_B_DQ<50>")
	)
	(segment
		(start 306.156868 -9.709404)
		(end 306.156868 -10.058146)
		(width 0.14224)
		(layer "In4.Cu")
		(net "M_B_DQ<50>")
	)
	(segment
		(start 306.507134 -16.893794)
		(end 306.37607 -17.024858)
		(width 0.14224)
		(layer "In4.Cu")
		(net "M_B_DQ<50>")
	)
	(segment
		(start 306.57927 -21.786596)
		(end 306.393596 -21.97227)
		(width 0.14224)
		(layer "In4.Cu")
		(net "M_B_DQ<50>")
	)
	(segment
		(start 306.899818 -8.6614)
		(end 306.5018 -9.059418)
		(width 0.14224)
		(layer "In4.Cu")
		(net "M_B_DQ<50>")
	)
	(segment
		(start 306.049934 -16.040608)
		(end 306.507134 -16.497808)
		(width 0.14224)
		(layer "In4.Cu")
		(net "M_B_DQ<50>")
	)
	(segment
		(start 197.249796 -9.091168)
		(end 197.189344 -8.763)
		(width 0.1651)
		(layer "F.Cu")
		(net "M_B_DQ<4>")
	)
	(segment
		(start 197.250304 -10.422382)
		(end 197.249796 -10.422382)
		(width 0.1651)
		(layer "F.Cu")
		(net "M_B_DQ<4>")
	)
	(segment
		(start 197.189344 -8.763)
		(end 197.151752 -8.5598)
		(width 0.1651)
		(layer "F.Cu")
		(net "M_B_DQ<4>")
	)
	(segment
		(start 197.249796 -10.422382)
		(end 197.249796 -9.091168)
		(width 0.1651)
		(layer "F.Cu")
		(net "M_B_DQ<4>")
	)
	(segment
		(start 237.900718 -68.46824)
		(end 237.329218 -68.46824)
		(width 0.0889)
		(layer "F.Cu")
		(net "M_B_DQ<4>")
	)
	(via
		(at 237.329218 -68.46824)
		(size 0.508)
		(drill 0.254)
		(layers "F.Cu" "B.Cu")
		(net "M_B_DQ<4>")
	)
	(via
		(at 197.151752 -8.5598)
		(size 0.508)
		(drill 0.254)
		(layers "F.Cu" "B.Cu")
		(net "M_B_DQ<4>")
	)
	(via
		(at 196.399912 -13.959078)
		(size 0.508)
		(drill 0.254)
		(layers "F.Cu" "B.Cu")
		(net "M_B_DQ<4>")
	)
	(segment
		(start 196.399912 -15.222982)
		(end 196.399912 -13.959078)
		(width 0.1651)
		(layer "B.Cu")
		(net "M_B_DQ<4>")
	)
	(segment
		(start 196.40042 -15.222982)
		(end 196.399912 -15.222982)
		(width 0.1651)
		(layer "B.Cu")
		(net "M_B_DQ<4>")
	)
	(segment
		(start 196.892418 -10.3632)
		(end 196.892418 -10.668)
		(width 0.14224)
		(layer "In4.Cu")
		(net "M_B_DQ<4>")
	)
	(segment
		(start 196.6468 -17.0688)
		(end 196.6468 -18.3134)
		(width 0.14224)
		(layer "In4.Cu")
		(net "M_B_DQ<4>")
	)
	(segment
		(start 196.6976 -23.1648)
		(end 196.8754 -23.3426)
		(width 0.14224)
		(layer "In4.Cu")
		(net "M_B_DQ<4>")
	)
	(segment
		(start 197.151752 -8.5598)
		(end 196.8754 -8.836152)
		(width 0.14224)
		(layer "In4.Cu")
		(net "M_B_DQ<4>")
	)
	(segment
		(start 196.8754 -37.211)
		(end 218.5924 -58.928)
		(width 0.14224)
		(layer "In4.Cu")
		(net "M_B_DQ<4>")
	)
	(segment
		(start 196.399912 -13.959078)
		(end 196.399912 -15.018512)
		(width 0.14224)
		(layer "In4.Cu")
		(net "M_B_DQ<4>")
	)
	(segment
		(start 196.524118 -11.0363)
		(end 196.524118 -11.391646)
		(width 0.14224)
		(layer "In4.Cu")
		(net "M_B_DQ<4>")
	)
	(segment
		(start 196.8754 -15.494)
		(end 196.8754 -16.8402)
		(width 0.14224)
		(layer "In4.Cu")
		(net "M_B_DQ<4>")
	)
	(segment
		(start 196.399912 -15.018512)
		(end 196.8754 -15.494)
		(width 0.14224)
		(layer "In4.Cu")
		(net "M_B_DQ<4>")
	)
	(segment
		(start 196.8754 -21.7678)
		(end 196.6976 -21.9456)
		(width 0.14224)
		(layer "In4.Cu")
		(net "M_B_DQ<4>")
	)
	(segment
		(start 196.8754 -18.542)
		(end 196.8754 -21.7678)
		(width 0.14224)
		(layer "In4.Cu")
		(net "M_B_DQ<4>")
	)
	(segment
		(start 232.609644 -69.662294)
		(end 232.692448 -69.57949)
		(width 0.0889)
		(layer "In4.Cu")
		(net "M_B_DQ<4>")
	)
	(segment
		(start 196.8754 -11.742928)
		(end 196.8754 -12.217654)
		(width 0.14224)
		(layer "In4.Cu")
		(net "M_B_DQ<4>")
	)
	(segment
		(start 237.052358 -69.06768)
		(end 237.329218 -68.46824)
		(width 0.0889)
		(layer "In4.Cu")
		(net "M_B_DQ<4>")
	)
	(segment
		(start 196.8754 -12.217654)
		(end 196.1642 -12.928854)
		(width 0.14224)
		(layer "In4.Cu")
		(net "M_B_DQ<4>")
	)
	(segment
		(start 196.892418 -10.668)
		(end 196.524118 -11.0363)
		(width 0.14224)
		(layer "In4.Cu")
		(net "M_B_DQ<4>")
	)
	(segment
		(start 196.1642 -12.928854)
		(end 196.1642 -13.723366)
		(width 0.14224)
		(layer "In4.Cu")
		(net "M_B_DQ<4>")
	)
	(segment
		(start 196.6976 -21.9456)
		(end 196.6976 -23.1648)
		(width 0.14224)
		(layer "In4.Cu")
		(net "M_B_DQ<4>")
	)
	(segment
		(start 218.8591 -58.928)
		(end 229.8827 -69.9516)
		(width 0.14224)
		(layer "In4.Cu")
		(net "M_B_DQ<4>")
	)
	(segment
		(start 232.991406 -69.579236)
		(end 233.120692 -69.588634)
		(width 0.0889)
		(layer "In4.Cu")
		(net "M_B_DQ<4>")
	)
	(segment
		(start 218.5924 -58.928)
		(end 218.8591 -58.928)
		(width 0.14224)
		(layer "In4.Cu")
		(net "M_B_DQ<4>")
	)
	(segment
		(start 196.524118 -11.391646)
		(end 196.8754 -11.742928)
		(width 0.14224)
		(layer "In4.Cu")
		(net "M_B_DQ<4>")
	)
	(segment
		(start 196.8754 -23.3426)
		(end 196.8754 -37.211)
		(width 0.14224)
		(layer "In4.Cu")
		(net "M_B_DQ<4>")
	)
	(segment
		(start 236.459522 -69.553836)
		(end 236.492288 -69.553836)
		(width 0.0889)
		(layer "In4.Cu")
		(net "M_B_DQ<4>")
	)
	(segment
		(start 232.692448 -69.57949)
		(end 232.908602 -69.579236)
		(width 0.0889)
		(layer "In4.Cu")
		(net "M_B_DQ<4>")
	)
	(segment
		(start 196.511418 -9.9822)
		(end 196.892418 -10.3632)
		(width 0.14224)
		(layer "In4.Cu")
		(net "M_B_DQ<4>")
	)
	(segment
		(start 196.511418 -9.677654)
		(end 196.511418 -9.9822)
		(width 0.14224)
		(layer "In4.Cu")
		(net "M_B_DQ<4>")
	)
	(segment
		(start 196.6468 -18.3134)
		(end 196.8754 -18.542)
		(width 0.14224)
		(layer "In4.Cu")
		(net "M_B_DQ<4>")
	)
	(segment
		(start 233.657394 -70.04939)
		(end 233.910124 -70.04939)
		(width 0.0889)
		(layer "In4.Cu")
		(net "M_B_DQ<4>")
	)
	(segment
		(start 232.320338 -69.9516)
		(end 232.609644 -69.662294)
		(width 0.14224)
		(layer "In4.Cu")
		(net "M_B_DQ<4>")
	)
	(segment
		(start 196.8754 -9.313672)
		(end 196.511418 -9.677654)
		(width 0.14224)
		(layer "In4.Cu")
		(net "M_B_DQ<4>")
	)
	(segment
		(start 196.8754 -8.836152)
		(end 196.8754 -9.313672)
		(width 0.14224)
		(layer "In4.Cu")
		(net "M_B_DQ<4>")
	)
	(segment
		(start 196.8754 -16.8402)
		(end 196.6468 -17.0688)
		(width 0.14224)
		(layer "In4.Cu")
		(net "M_B_DQ<4>")
	)
	(segment
		(start 232.908602 -69.579236)
		(end 232.991406 -69.579236)
		(width 0.0889)
		(layer "In4.Cu")
		(net "M_B_DQ<4>")
	)
	(segment
		(start 229.8827 -69.9516)
		(end 232.320338 -69.9516)
		(width 0.14224)
		(layer "In4.Cu")
		(net "M_B_DQ<4>")
	)
	(segment
		(start 196.1642 -13.723366)
		(end 196.399912 -13.959078)
		(width 0.14224)
		(layer "In4.Cu")
		(net "M_B_DQ<4>")
	)
	(segment
		(start 235.597192 -70.04939)
		(end 235.629958 -70.04939)
		(width 0.0889)
		(layer "In4.Cu")
		(net "M_B_DQ<4>")
	)
	(arc
		(start 234.241848 -70.249288)
		(mid 234.753658 -70.544827)
		(end 235.265468 -70.249288)
		(width 0.0889)
		(layer "In4.Cu")
		(net "M_B_DQ<4>")
	)
	(arc
		(start 233.345482 -69.779896)
		(mid 233.479036 -69.940564)
		(end 233.657394 -70.04939)
		(width 0.0889)
		(layer "In4.Cu")
		(net "M_B_DQ<4>")
	)
	(arc
		(start 236.123988 -69.753988)
		(mid 236.265671 -69.610184)
		(end 236.459522 -69.553836)
		(width 0.0889)
		(layer "In4.Cu")
		(net "M_B_DQ<4>")
	)
	(arc
		(start 233.120692 -69.588634)
		(mid 233.249364 -69.665132)
		(end 233.345482 -69.779896)
		(width 0.0889)
		(layer "In4.Cu")
		(net "M_B_DQ<4>")
	)
	(arc
		(start 236.492288 -69.553836)
		(mid 236.858077 -69.409552)
		(end 237.052358 -69.06768)
		(width 0.0889)
		(layer "In4.Cu")
		(net "M_B_DQ<4>")
	)
	(arc
		(start 235.265468 -70.249288)
		(mid 235.405547 -70.106552)
		(end 235.597192 -70.04939)
		(width 0.0889)
		(layer "In4.Cu")
		(net "M_B_DQ<4>")
	)
	(arc
		(start 233.910124 -70.04939)
		(mid 234.101766 -70.106556)
		(end 234.241848 -70.249288)
		(width 0.0889)
		(layer "In4.Cu")
		(net "M_B_DQ<4>")
	)
	(arc
		(start 235.629958 -70.04939)
		(mid 235.915382 -69.965923)
		(end 236.123988 -69.753988)
		(width 0.0889)
		(layer "In4.Cu")
		(net "M_B_DQ<4>")
	)
	(segment
		(start 300.100492 -5.822442)
		(end 300.099984 -5.822442)
		(width 0.1651)
		(layer "F.Cu")
		(net "M_B_DQ<49>")
	)
	(segment
		(start 300.5582 -28.321)
		(end 300.5582 -28.7528)
		(width 0.1651)
		(layer "F.Cu")
		(net "M_B_DQ<49>")
	)
	(segment
		(start 300.772068 -26.439368)
		(end 300.2915 -25.9588)
		(width 0.1651)
		(layer "F.Cu")
		(net "M_B_DQ<49>")
	)
	(segment
		(start 300.099984 -5.822442)
		(end 300.099984 -7.086346)
		(width 0.1651)
		(layer "F.Cu")
		(net "M_B_DQ<49>")
	)
	(segment
		(start 296.740072 -42.99331)
		(end 294.151558 -45.581824)
		(width 0.1016)
		(layer "F.Cu")
		(net "M_B_DQ<49>")
	)
	(segment
		(start 299.4914 -26.1239)
		(end 299.4914 -26.7716)
		(width 0.1651)
		(layer "F.Cu")
		(net "M_B_DQ<49>")
	)
	(segment
		(start 299.4914 -26.7716)
		(end 300.0502 -27.3304)
		(width 0.1651)
		(layer "F.Cu")
		(net "M_B_DQ<49>")
	)
	(segment
		(start 287.316418 -45.581824)
		(end 288.244026 -45.581824)
		(width 0.1016)
		(layer "F.Cu")
		(net "M_B_DQ<49>")
	)
	(segment
		(start 301.2567 -35.474656)
		(end 301.2567 -36.2331)
		(width 0.1651)
		(layer "F.Cu")
		(net "M_B_DQ<49>")
	)
	(segment
		(start 296.7482 -40.7416)
		(end 296.7482 -42.013124)
		(width 0.1651)
		(layer "F.Cu")
		(net "M_B_DQ<49>")
	)
	(segment
		(start 300.8884 -33.149286)
		(end 300.8884 -35.106356)
		(width 0.1651)
		(layer "F.Cu")
		(net "M_B_DQ<49>")
	)
	(segment
		(start 300.8884 -35.106356)
		(end 301.2567 -35.474656)
		(width 0.1651)
		(layer "F.Cu")
		(net "M_B_DQ<49>")
	)
	(segment
		(start 300.5582 -28.7528)
		(end 300.433994 -28.877006)
		(width 0.1651)
		(layer "F.Cu")
		(net "M_B_DQ<49>")
	)
	(segment
		(start 300.433994 -32.69488)
		(end 300.8884 -33.149286)
		(width 0.1651)
		(layer "F.Cu")
		(net "M_B_DQ<49>")
	)
	(segment
		(start 283.109924 -51.839114)
		(end 283.109924 -49.788318)
		(width 0.0889)
		(layer "F.Cu")
		(net "M_B_DQ<49>")
	)
	(segment
		(start 296.7482 -42.013124)
		(end 296.740072 -42.021252)
		(width 0.1651)
		(layer "F.Cu")
		(net "M_B_DQ<49>")
	)
	(segment
		(start 296.740072 -42.021252)
		(end 296.740072 -42.99331)
		(width 0.1016)
		(layer "F.Cu")
		(net "M_B_DQ<49>")
	)
	(segment
		(start 283.212794 -51.941984)
		(end 283.109924 -51.839114)
		(width 0.0889)
		(layer "F.Cu")
		(net "M_B_DQ<49>")
	)
	(segment
		(start 300.0502 -27.3304)
		(end 300.0502 -27.813)
		(width 0.1651)
		(layer "F.Cu")
		(net "M_B_DQ<49>")
	)
	(segment
		(start 299.6565 -25.9588)
		(end 299.4914 -26.1239)
		(width 0.1651)
		(layer "F.Cu")
		(net "M_B_DQ<49>")
	)
	(segment
		(start 300.772068 -27.168856)
		(end 300.772068 -26.439368)
		(width 0.1651)
		(layer "F.Cu")
		(net "M_B_DQ<49>")
	)
	(segment
		(start 294.151558 -45.581824)
		(end 288.244026 -45.581824)
		(width 0.1016)
		(layer "F.Cu")
		(net "M_B_DQ<49>")
	)
	(segment
		(start 300.0502 -27.813)
		(end 300.5582 -28.321)
		(width 0.1651)
		(layer "F.Cu")
		(net "M_B_DQ<49>")
	)
	(segment
		(start 283.109924 -49.788318)
		(end 283.273246 -49.624996)
		(width 0.0889)
		(layer "F.Cu")
		(net "M_B_DQ<49>")
	)
	(segment
		(start 300.433994 -30.353)
		(end 300.433994 -32.69488)
		(width 0.1651)
		(layer "F.Cu")
		(net "M_B_DQ<49>")
	)
	(segment
		(start 300.433994 -28.877006)
		(end 300.433994 -30.353)
		(width 0.1651)
		(layer "F.Cu")
		(net "M_B_DQ<49>")
	)
	(segment
		(start 301.2567 -36.2331)
		(end 296.7482 -40.7416)
		(width 0.1651)
		(layer "F.Cu")
		(net "M_B_DQ<49>")
	)
	(segment
		(start 300.2915 -25.9588)
		(end 299.6565 -25.9588)
		(width 0.1651)
		(layer "F.Cu")
		(net "M_B_DQ<49>")
	)
	(segment
		(start 283.273246 -49.624996)
		(end 287.316418 -45.581824)
		(width 0.1016)
		(layer "F.Cu")
		(net "M_B_DQ<49>")
	)
	(via
		(at 300.099984 -7.086346)
		(size 0.508)
		(drill 0.254)
		(layers "F.Cu" "B.Cu")
		(net "M_B_DQ<49>")
	)
	(via
		(at 300.772068 -27.168856)
		(size 0.508)
		(drill 0.254)
		(layers "F.Cu" "B.Cu")
		(net "M_B_DQ<49>")
	)
	(via
		(at 300.772068 -12.678156)
		(size 0.508)
		(drill 0.254)
		(layers "F.Cu" "B.Cu")
		(net "M_B_DQ<49>")
	)
	(via
		(at 300.433994 -30.353)
		(size 0.508)
		(drill 0.254)
		(layers "F.Cu" "B.Cu")
		(net "M_B_DQ<49>")
	)
	(segment
		(start 300.949868 -11.997182)
		(end 300.772068 -12.174982)
		(width 0.1651)
		(layer "B.Cu")
		(net "M_B_DQ<49>")
	)
	(segment
		(start 300.949868 -10.623042)
		(end 300.949868 -11.997182)
		(width 0.1651)
		(layer "B.Cu")
		(net "M_B_DQ<49>")
	)
	(segment
		(start 300.772068 -12.174982)
		(end 300.772068 -12.678156)
		(width 0.1651)
		(layer "B.Cu")
		(net "M_B_DQ<49>")
	)
	(segment
		(start 300.950376 -10.623042)
		(end 300.949868 -10.623042)
		(width 0.1651)
		(layer "B.Cu")
		(net "M_B_DQ<49>")
	)
	(segment
		(start 300.099984 -7.625334)
		(end 300.57725 -8.1026)
		(width 0.14224)
		(layer "In4.Cu")
		(net "M_B_DQ<49>")
	)
	(segment
		(start 301.14621 -8.970264)
		(end 301.14621 -12.304014)
		(width 0.14224)
		(layer "In4.Cu")
		(net "M_B_DQ<49>")
	)
	(segment
		(start 300.3296 -13.120624)
		(end 300.3296 -13.5636)
		(width 0.14224)
		(layer "In4.Cu")
		(net "M_B_DQ<49>")
	)
	(segment
		(start 301.302674 -8.472424)
		(end 301.302674 -8.8138)
		(width 0.14224)
		(layer "In4.Cu")
		(net "M_B_DQ<49>")
	)
	(segment
		(start 301.14621 -12.304014)
		(end 300.772068 -12.678156)
		(width 0.14224)
		(layer "In4.Cu")
		(net "M_B_DQ<49>")
	)
	(segment
		(start 301.302674 -8.8138)
		(end 301.14621 -8.970264)
		(width 0.14224)
		(layer "In4.Cu")
		(net "M_B_DQ<49>")
	)
	(segment
		(start 300.93285 -8.1026)
		(end 301.302674 -8.472424)
		(width 0.14224)
		(layer "In4.Cu")
		(net "M_B_DQ<49>")
	)
	(segment
		(start 300.772068 -12.678156)
		(end 300.3296 -13.120624)
		(width 0.14224)
		(layer "In4.Cu")
		(net "M_B_DQ<49>")
	)
	(segment
		(start 300.3296 -13.5636)
		(end 300.716696 -13.950696)
		(width 0.14224)
		(layer "In4.Cu")
		(net "M_B_DQ<49>")
	)
	(segment
		(start 300.716696 -15.52829)
		(end 301.25797 -16.069564)
		(width 0.14224)
		(layer "In4.Cu")
		(net "M_B_DQ<49>")
	)
	(segment
		(start 300.716696 -13.950696)
		(end 300.716696 -15.52829)
		(width 0.14224)
		(layer "In4.Cu")
		(net "M_B_DQ<49>")
	)
	(segment
		(start 300.099984 -7.086346)
		(end 300.099984 -7.625334)
		(width 0.14224)
		(layer "In4.Cu")
		(net "M_B_DQ<49>")
	)
	(segment
		(start 301.25797 -26.682954)
		(end 300.772068 -27.168856)
		(width 0.14224)
		(layer "In4.Cu")
		(net "M_B_DQ<49>")
	)
	(segment
		(start 301.25797 -16.069564)
		(end 301.25797 -26.682954)
		(width 0.14224)
		(layer "In4.Cu")
		(net "M_B_DQ<49>")
	)
	(segment
		(start 300.57725 -8.1026)
		(end 300.93285 -8.1026)
		(width 0.14224)
		(layer "In4.Cu")
		(net "M_B_DQ<49>")
	)
	(segment
		(start 300.949868 -10.422382)
		(end 300.803564 -8.89)
		(width 0.1651)
		(layer "F.Cu")
		(net "M_B_DQ<48>")
	)
	(segment
		(start 299.638466 -36.100512)
		(end 299.458634 -36.100512)
		(width 0.1651)
		(layer "F.Cu")
		(net "M_B_DQ<48>")
	)
	(segment
		(start 297.685968 -37.142166)
		(end 298.394882 -37.85108)
		(width 0.1651)
		(layer "F.Cu")
		(net "M_B_DQ<48>")
	)
	(segment
		(start 297.685968 -36.958778)
		(end 297.685968 -37.142166)
		(width 0.1651)
		(layer "F.Cu")
		(net "M_B_DQ<48>")
	)
	(segment
		(start 299.6692 -34.929826)
		(end 300.57217 -35.832796)
		(width 0.1651)
		(layer "F.Cu")
		(net "M_B_DQ<48>")
	)
	(segment
		(start 299.6692 -34.348674)
		(end 299.6692 -34.929826)
		(width 0.1651)
		(layer "F.Cu")
		(net "M_B_DQ<48>")
	)
	(segment
		(start 299.110654 -37.474144)
		(end 298.930822 -37.474144)
		(width 0.1651)
		(layer "F.Cu")
		(net "M_B_DQ<48>")
	)
	(segment
		(start 298.140628 -36.68395)
		(end 297.960796 -36.68395)
		(width 0.1651)
		(layer "F.Cu")
		(net "M_B_DQ<48>")
	)
	(segment
		(start 282.751784 -51.783488)
		(end 282.919424 -51.615848)
		(width 0.0889)
		(layer "F.Cu")
		(net "M_B_DQ<48>")
	)
	(segment
		(start 299.13707 -36.602416)
		(end 299.46981 -36.935156)
		(width 0.1651)
		(layer "F.Cu")
		(net "M_B_DQ<48>")
	)
	(segment
		(start 300.248574 -33.414462)
		(end 300.248574 -33.7693)
		(width 0.1651)
		(layer "F.Cu")
		(net "M_B_DQ<48>")
	)
	(segment
		(start 296.0878 -42.116248)
		(end 296.092372 -42.12082)
		(width 0.1651)
		(layer "F.Cu")
		(net "M_B_DQ<48>")
	)
	(segment
		(start 300.57217 -36.012628)
		(end 300.151292 -36.433506)
		(width 0.1651)
		(layer "F.Cu")
		(net "M_B_DQ<48>")
	)
	(segment
		(start 297.960796 -36.68395)
		(end 297.685968 -36.958778)
		(width 0.1651)
		(layer "F.Cu")
		(net "M_B_DQ<48>")
	)
	(segment
		(start 296.092372 -43.083988)
		(end 293.988236 -45.188124)
		(width 0.1016)
		(layer "F.Cu")
		(net "M_B_DQ<48>")
	)
	(segment
		(start 300.57217 -35.832796)
		(end 300.57217 -36.012628)
		(width 0.1651)
		(layer "F.Cu")
		(net "M_B_DQ<48>")
	)
	(segment
		(start 299.7454 -28.893262)
		(end 299.7454 -32.911288)
		(width 0.1651)
		(layer "F.Cu")
		(net "M_B_DQ<48>")
	)
	(segment
		(start 300.791372 -8.763)
		(end 300.772068 -8.5598)
		(width 0.1651)
		(layer "F.Cu")
		(net "M_B_DQ<48>")
	)
	(segment
		(start 282.751784 -52.040028)
		(end 282.751784 -51.783488)
		(width 0.0889)
		(layer "F.Cu")
		(net "M_B_DQ<48>")
	)
	(segment
		(start 299.13707 -36.422076)
		(end 299.13707 -36.602416)
		(width 0.1651)
		(layer "F.Cu")
		(net "M_B_DQ<48>")
	)
	(segment
		(start 299.46981 -36.935156)
		(end 299.46981 -37.114988)
		(width 0.1651)
		(layer "F.Cu")
		(net "M_B_DQ<48>")
	)
	(segment
		(start 300.950376 -10.422382)
		(end 300.949868 -10.422382)
		(width 0.1651)
		(layer "F.Cu")
		(net "M_B_DQ<48>")
	)
	(segment
		(start 282.354274 -52.437538)
		(end 282.751784 -52.040028)
		(width 0.0889)
		(layer "F.Cu")
		(net "M_B_DQ<48>")
	)
	(segment
		(start 300.248574 -33.7693)
		(end 299.6692 -34.348674)
		(width 0.1651)
		(layer "F.Cu")
		(net "M_B_DQ<48>")
	)
	(segment
		(start 282.919424 -51.615848)
		(end 282.919424 -49.421796)
		(width 0.0889)
		(layer "F.Cu")
		(net "M_B_DQ<48>")
	)
	(segment
		(start 282.919424 -49.421796)
		(end 287.153096 -45.188124)
		(width 0.1016)
		(layer "F.Cu")
		(net "M_B_DQ<48>")
	)
	(segment
		(start 300.803564 -8.89)
		(end 300.791372 -8.763)
		(width 0.1651)
		(layer "F.Cu")
		(net "M_B_DQ<48>")
	)
	(segment
		(start 296.0878 -40.487346)
		(end 296.0878 -42.116248)
		(width 0.1651)
		(layer "F.Cu")
		(net "M_B_DQ<48>")
	)
	(segment
		(start 298.930822 -37.474144)
		(end 298.140628 -36.68395)
		(width 0.1651)
		(layer "F.Cu")
		(net "M_B_DQ<48>")
	)
	(segment
		(start 299.46981 -37.114988)
		(end 299.110654 -37.474144)
		(width 0.1651)
		(layer "F.Cu")
		(net "M_B_DQ<48>")
	)
	(segment
		(start 298.394882 -38.180264)
		(end 296.0878 -40.487346)
		(width 0.1651)
		(layer "F.Cu")
		(net "M_B_DQ<48>")
	)
	(segment
		(start 299.97146 -36.433506)
		(end 299.638466 -36.100512)
		(width 0.1651)
		(layer "F.Cu")
		(net "M_B_DQ<48>")
	)
	(segment
		(start 293.988236 -45.188124)
		(end 288.244026 -45.188124)
		(width 0.1016)
		(layer "F.Cu")
		(net "M_B_DQ<48>")
	)
	(segment
		(start 299.7454 -32.911288)
		(end 300.248574 -33.414462)
		(width 0.1651)
		(layer "F.Cu")
		(net "M_B_DQ<48>")
	)
	(segment
		(start 299.458634 -36.100512)
		(end 299.13707 -36.422076)
		(width 0.1651)
		(layer "F.Cu")
		(net "M_B_DQ<48>")
	)
	(segment
		(start 296.092372 -42.12082)
		(end 296.092372 -43.083988)
		(width 0.1016)
		(layer "F.Cu")
		(net "M_B_DQ<48>")
	)
	(segment
		(start 298.394882 -37.85108)
		(end 298.394882 -38.180264)
		(width 0.1651)
		(layer "F.Cu")
		(net "M_B_DQ<48>")
	)
	(segment
		(start 300.151292 -36.433506)
		(end 299.97146 -36.433506)
		(width 0.1651)
		(layer "F.Cu")
		(net "M_B_DQ<48>")
	)
	(segment
		(start 287.153096 -45.188124)
		(end 288.244026 -45.188124)
		(width 0.1016)
		(layer "F.Cu")
		(net "M_B_DQ<48>")
	)
	(segment
		(start 300.099984 -28.538678)
		(end 299.7454 -28.893262)
		(width 0.1651)
		(layer "F.Cu")
		(net "M_B_DQ<48>")
	)
	(via
		(at 300.099984 -13.959078)
		(size 0.508)
		(drill 0.254)
		(layers "F.Cu" "B.Cu")
		(net "M_B_DQ<48>")
	)
	(via
		(at 300.772068 -8.5598)
		(size 0.508)
		(drill 0.254)
		(layers "F.Cu" "B.Cu")
		(net "M_B_DQ<48>")
	)
	(via
		(at 300.099984 -28.538678)
		(size 0.508)
		(drill 0.254)
		(layers "F.Cu" "B.Cu")
		(net "M_B_DQ<48>")
	)
	(segment
		(start 300.099984 -15.222982)
		(end 300.099984 -13.959078)
		(width 0.1651)
		(layer "B.Cu")
		(net "M_B_DQ<48>")
	)
	(segment
		(start 300.100492 -15.222982)
		(end 300.099984 -15.222982)
		(width 0.1651)
		(layer "B.Cu")
		(net "M_B_DQ<48>")
	)
	(segment
		(start 300.162468 -11.302746)
		(end 300.162468 -10.9982)
		(width 0.14224)
		(layer "In4.Cu")
		(net "M_B_DQ<48>")
	)
	(segment
		(start 300.602396 -21.66747)
		(end 300.602396 -18.636996)
		(width 0.14224)
		(layer "In4.Cu")
		(net "M_B_DQ<48>")
	)
	(segment
		(start 300.099984 -27.110182)
		(end 300.55947 -26.650696)
		(width 0.14224)
		(layer "In4.Cu")
		(net "M_B_DQ<48>")
	)
	(segment
		(start 300.602396 -18.636996)
		(end 300.272196 -18.306796)
		(width 0.14224)
		(layer "In4.Cu")
		(net "M_B_DQ<48>")
	)
	(segment
		(start 300.55185 -11.692128)
		(end 300.162468 -11.302746)
		(width 0.14224)
		(layer "In4.Cu")
		(net "M_B_DQ<48>")
	)
	(segment
		(start 300.099984 -13.959078)
		(end 299.81525 -13.674344)
		(width 0.14224)
		(layer "In4.Cu")
		(net "M_B_DQ<48>")
	)
	(segment
		(start 300.099984 -28.538678)
		(end 300.099984 -27.110182)
		(width 0.14224)
		(layer "In4.Cu")
		(net "M_B_DQ<48>")
	)
	(segment
		(start 300.55947 -23.394416)
		(end 300.3042 -23.139146)
		(width 0.14224)
		(layer "In4.Cu")
		(net "M_B_DQ<48>")
	)
	(segment
		(start 300.58487 -16.069564)
		(end 300.099984 -15.584678)
		(width 0.14224)
		(layer "In4.Cu")
		(net "M_B_DQ<48>")
	)
	(segment
		(start 300.58487 -16.815308)
		(end 300.58487 -16.069564)
		(width 0.14224)
		(layer "In4.Cu")
		(net "M_B_DQ<48>")
	)
	(segment
		(start 300.3042 -23.139146)
		(end 300.3042 -21.965666)
		(width 0.14224)
		(layer "In4.Cu")
		(net "M_B_DQ<48>")
	)
	(segment
		(start 300.479968 -10.6807)
		(end 300.479968 -10.4521)
		(width 0.14224)
		(layer "In4.Cu")
		(net "M_B_DQ<48>")
	)
	(segment
		(start 299.81525 -12.9286)
		(end 300.55185 -12.192)
		(width 0.14224)
		(layer "In4.Cu")
		(net "M_B_DQ<48>")
	)
	(segment
		(start 300.099984 -15.584678)
		(end 300.099984 -13.959078)
		(width 0.14224)
		(layer "In4.Cu")
		(net "M_B_DQ<48>")
	)
	(segment
		(start 300.55947 -26.650696)
		(end 300.55947 -23.394416)
		(width 0.14224)
		(layer "In4.Cu")
		(net "M_B_DQ<48>")
	)
	(segment
		(start 300.55185 -9.364472)
		(end 300.55185 -8.780018)
		(width 0.14224)
		(layer "In4.Cu")
		(net "M_B_DQ<48>")
	)
	(segment
		(start 299.81525 -13.674344)
		(end 299.81525 -12.9286)
		(width 0.14224)
		(layer "In4.Cu")
		(net "M_B_DQ<48>")
	)
	(segment
		(start 300.162468 -10.9982)
		(end 300.479968 -10.6807)
		(width 0.14224)
		(layer "In4.Cu")
		(net "M_B_DQ<48>")
	)
	(segment
		(start 300.137068 -10.1092)
		(end 300.137068 -9.779254)
		(width 0.14224)
		(layer "In4.Cu")
		(net "M_B_DQ<48>")
	)
	(segment
		(start 300.55185 -8.780018)
		(end 300.772068 -8.5598)
		(width 0.14224)
		(layer "In4.Cu")
		(net "M_B_DQ<48>")
	)
	(segment
		(start 300.479968 -10.4521)
		(end 300.137068 -10.1092)
		(width 0.14224)
		(layer "In4.Cu")
		(net "M_B_DQ<48>")
	)
	(segment
		(start 300.272196 -17.127982)
		(end 300.58487 -16.815308)
		(width 0.14224)
		(layer "In4.Cu")
		(net "M_B_DQ<48>")
	)
	(segment
		(start 300.55185 -12.192)
		(end 300.55185 -11.692128)
		(width 0.14224)
		(layer "In4.Cu")
		(net "M_B_DQ<48>")
	)
	(segment
		(start 300.272196 -18.306796)
		(end 300.272196 -17.127982)
		(width 0.14224)
		(layer "In4.Cu")
		(net "M_B_DQ<48>")
	)
	(segment
		(start 300.3042 -21.965666)
		(end 300.602396 -21.66747)
		(width 0.14224)
		(layer "In4.Cu")
		(net "M_B_DQ<48>")
	)
	(segment
		(start 300.137068 -9.779254)
		(end 300.55185 -9.364472)
		(width 0.14224)
		(layer "In4.Cu")
		(net "M_B_DQ<48>")
	)
	(segment
		(start 295.000426 -5.822442)
		(end 294.999918 -5.822442)
		(width 0.1651)
		(layer "F.Cu")
		(net "M_B_DQ<47>")
	)
	(segment
		(start 295.2242 -28.028392)
		(end 295.2242 -27.3304)
		(width 0.1651)
		(layer "F.Cu")
		(net "M_B_DQ<47>")
	)
	(segment
		(start 287.528 -40.1066)
		(end 290.449 -37.1856)
		(width 0.1651)
		(layer "F.Cu")
		(net "M_B_DQ<47>")
	)
	(segment
		(start 294.9194 -34.46145)
		(end 294.9194 -33.782)
		(width 0.1651)
		(layer "F.Cu")
		(net "M_B_DQ<47>")
	)
	(segment
		(start 280.379424 -48.173132)
		(end 286.8676 -41.684956)
		(width 0.1016)
		(layer "F.Cu")
		(net "M_B_DQ<47>")
	)
	(segment
		(start 295.2242 -27.3304)
		(end 295.385744 -27.168856)
		(width 0.1651)
		(layer "F.Cu")
		(net "M_B_DQ<47>")
	)
	(segment
		(start 295.729406 -28.533598)
		(end 295.2242 -28.028392)
		(width 0.1651)
		(layer "F.Cu")
		(net "M_B_DQ<47>")
	)
	(segment
		(start 287.528 -40.6654)
		(end 287.528 -40.1066)
		(width 0.1651)
		(layer "F.Cu")
		(net "M_B_DQ<47>")
	)
	(segment
		(start 280.100024 -51.69662)
		(end 280.100024 -50.50663)
		(width 0.0889)
		(layer "F.Cu")
		(net "M_B_DQ<47>")
	)
	(segment
		(start 280.214324 -50.39233)
		(end 280.214324 -50.137822)
		(width 0.0889)
		(layer "F.Cu")
		(net "M_B_DQ<47>")
	)
	(segment
		(start 280.379424 -49.972722)
		(end 280.379424 -48.173132)
		(width 0.1016)
		(layer "F.Cu")
		(net "M_B_DQ<47>")
	)
	(segment
		(start 280.214324 -50.137822)
		(end 280.379424 -49.972722)
		(width 0.0889)
		(layer "F.Cu")
		(net "M_B_DQ<47>")
	)
	(segment
		(start 292.215824 -37.1856)
		(end 294.9194 -34.46145)
		(width 0.1651)
		(layer "F.Cu")
		(net "M_B_DQ<47>")
	)
	(segment
		(start 280.100024 -50.50663)
		(end 280.214324 -50.39233)
		(width 0.0889)
		(layer "F.Cu")
		(net "M_B_DQ<47>")
	)
	(segment
		(start 280.13025 -51.750722)
		(end 280.100024 -51.69662)
		(width 0.0889)
		(layer "F.Cu")
		(net "M_B_DQ<47>")
	)
	(segment
		(start 286.8676 -41.684956)
		(end 286.8676 -41.3258)
		(width 0.1016)
		(layer "F.Cu")
		(net "M_B_DQ<47>")
	)
	(segment
		(start 279.778714 -53.923184)
		(end 280.108406 -53.161946)
		(width 0.0889)
		(layer "F.Cu")
		(net "M_B_DQ<47>")
	)
	(segment
		(start 295.385744 -27.168856)
		(end 295.764712 -27.168856)
		(width 0.1651)
		(layer "F.Cu")
		(net "M_B_DQ<47>")
	)
	(segment
		(start 295.729406 -29.49194)
		(end 295.729406 -28.533598)
		(width 0.1651)
		(layer "F.Cu")
		(net "M_B_DQ<47>")
	)
	(segment
		(start 290.449 -37.1856)
		(end 292.215824 -37.1856)
		(width 0.1651)
		(layer "F.Cu")
		(net "M_B_DQ<47>")
	)
	(segment
		(start 280.108406 -53.161946)
		(end 280.125424 -53.132736)
		(width 0.0889)
		(layer "F.Cu")
		(net "M_B_DQ<47>")
	)
	(segment
		(start 286.8676 -41.3258)
		(end 287.528 -40.6654)
		(width 0.1651)
		(layer "F.Cu")
		(net "M_B_DQ<47>")
	)
	(segment
		(start 294.999918 -5.822442)
		(end 294.999918 -7.086346)
		(width 0.1651)
		(layer "F.Cu")
		(net "M_B_DQ<47>")
	)
	(segment
		(start 294.9194 -33.782)
		(end 294.9194 -30.301946)
		(width 0.1651)
		(layer "F.Cu")
		(net "M_B_DQ<47>")
	)
	(segment
		(start 294.9194 -30.301946)
		(end 295.729406 -29.49194)
		(width 0.1651)
		(layer "F.Cu")
		(net "M_B_DQ<47>")
	)
	(via
		(at 295.849802 -12.678156)
		(size 0.508)
		(drill 0.254)
		(layers "F.Cu" "B.Cu")
		(net "M_B_DQ<47>")
	)
	(via
		(at 294.999918 -7.086346)
		(size 0.508)
		(drill 0.254)
		(layers "F.Cu" "B.Cu")
		(net "M_B_DQ<47>")
	)
	(via
		(at 294.9194 -33.782)
		(size 0.508)
		(drill 0.254)
		(layers "F.Cu" "B.Cu")
		(net "M_B_DQ<47>")
	)
	(via
		(at 295.764712 -27.168856)
		(size 0.508)
		(drill 0.254)
		(layers "F.Cu" "B.Cu")
		(net "M_B_DQ<47>")
	)
	(arc
		(start 280.125424 -52.73294)
		(mid 280.046293 -52.437538)
		(end 280.125424 -52.142136)
		(width 0.0889)
		(layer "F.Cu")
		(net "M_B_DQ<47>")
	)
	(arc
		(start 280.125424 -52.142136)
		(mid 280.178894 -51.947073)
		(end 280.13025 -51.750722)
		(width 0.0889)
		(layer "F.Cu")
		(net "M_B_DQ<47>")
	)
	(arc
		(start 280.125424 -53.132736)
		(mid 280.178923 -52.932838)
		(end 280.125424 -52.73294)
		(width 0.0889)
		(layer "F.Cu")
		(net "M_B_DQ<47>")
	)
	(segment
		(start 295.85031 -10.623042)
		(end 295.849802 -10.623042)
		(width 0.1651)
		(layer "B.Cu")
		(net "M_B_DQ<47>")
	)
	(segment
		(start 295.849802 -10.623042)
		(end 295.849802 -12.678156)
		(width 0.1651)
		(layer "B.Cu")
		(net "M_B_DQ<47>")
	)
	(segment
		(start 296.238676 -18.455386)
		(end 296.365676 -18.328386)
		(width 0.14224)
		(layer "In11.Cu")
		(net "M_B_DQ<47>")
	)
	(segment
		(start 296.358056 -8.8646)
		(end 296.358056 -8.509)
		(width 0.14224)
		(layer "In11.Cu")
		(net "M_B_DQ<47>")
	)
	(segment
		(start 296.238676 -21.3106)
		(end 296.3418 -21.207476)
		(width 0.14224)
		(layer "In11.Cu")
		(net "M_B_DQ<47>")
	)
	(segment
		(start 296.1386 -26.794968)
		(end 296.1386 -23.369524)
		(width 0.14224)
		(layer "In11.Cu")
		(net "M_B_DQ<47>")
	)
	(segment
		(start 296.391076 -23.117048)
		(end 296.391076 -22.015196)
		(width 0.14224)
		(layer "In11.Cu")
		(net "M_B_DQ<47>")
	)
	(segment
		(start 295.900856 -8.0518)
		(end 295.646856 -8.0518)
		(width 0.14224)
		(layer "In11.Cu")
		(net "M_B_DQ<47>")
	)
	(segment
		(start 296.202608 -12.32535)
		(end 296.202608 -9.020048)
		(width 0.14224)
		(layer "In11.Cu")
		(net "M_B_DQ<47>")
	)
	(segment
		(start 296.391076 -22.015196)
		(end 296.238676 -21.862796)
		(width 0.14224)
		(layer "In11.Cu")
		(net "M_B_DQ<47>")
	)
	(segment
		(start 296.358056 -8.509)
		(end 295.900856 -8.0518)
		(width 0.14224)
		(layer "In11.Cu")
		(net "M_B_DQ<47>")
	)
	(segment
		(start 296.3418 -19.1262)
		(end 296.238676 -19.023076)
		(width 0.14224)
		(layer "In11.Cu")
		(net "M_B_DQ<47>")
	)
	(segment
		(start 296.365676 -17.032986)
		(end 296.060876 -16.728186)
		(width 0.14224)
		(layer "In11.Cu")
		(net "M_B_DQ<47>")
	)
	(segment
		(start 296.3418 -21.207476)
		(end 296.3418 -19.1262)
		(width 0.14224)
		(layer "In11.Cu")
		(net "M_B_DQ<47>")
	)
	(segment
		(start 295.382696 -13.612876)
		(end 295.382696 -13.145262)
		(width 0.14224)
		(layer "In11.Cu")
		(net "M_B_DQ<47>")
	)
	(segment
		(start 295.646856 -8.0518)
		(end 295.316656 -7.7216)
		(width 0.14224)
		(layer "In11.Cu")
		(net "M_B_DQ<47>")
	)
	(segment
		(start 296.202608 -9.020048)
		(end 296.358056 -8.8646)
		(width 0.14224)
		(layer "In11.Cu")
		(net "M_B_DQ<47>")
	)
	(segment
		(start 296.238676 -19.023076)
		(end 296.238676 -18.455386)
		(width 0.14224)
		(layer "In11.Cu")
		(net "M_B_DQ<47>")
	)
	(segment
		(start 295.316656 -7.7216)
		(end 295.316656 -7.403084)
		(width 0.14224)
		(layer "In11.Cu")
		(net "M_B_DQ<47>")
	)
	(segment
		(start 295.849802 -12.678156)
		(end 296.202608 -12.32535)
		(width 0.14224)
		(layer "In11.Cu")
		(net "M_B_DQ<47>")
	)
	(segment
		(start 295.764712 -27.168856)
		(end 296.1386 -26.794968)
		(width 0.14224)
		(layer "In11.Cu")
		(net "M_B_DQ<47>")
	)
	(segment
		(start 296.1386 -23.369524)
		(end 296.391076 -23.117048)
		(width 0.14224)
		(layer "In11.Cu")
		(net "M_B_DQ<47>")
	)
	(segment
		(start 296.365676 -18.328386)
		(end 296.365676 -17.032986)
		(width 0.14224)
		(layer "In11.Cu")
		(net "M_B_DQ<47>")
	)
	(segment
		(start 295.316656 -7.403084)
		(end 294.999918 -7.086346)
		(width 0.14224)
		(layer "In11.Cu")
		(net "M_B_DQ<47>")
	)
	(segment
		(start 295.382696 -13.145262)
		(end 295.849802 -12.678156)
		(width 0.14224)
		(layer "In11.Cu")
		(net "M_B_DQ<47>")
	)
	(segment
		(start 296.060876 -16.728186)
		(end 296.060876 -14.291056)
		(width 0.14224)
		(layer "In11.Cu")
		(net "M_B_DQ<47>")
	)
	(segment
		(start 296.060876 -14.291056)
		(end 295.382696 -13.612876)
		(width 0.14224)
		(layer "In11.Cu")
		(net "M_B_DQ<47>")
	)
	(segment
		(start 296.238676 -21.862796)
		(end 296.238676 -21.3106)
		(width 0.14224)
		(layer "In11.Cu")
		(net "M_B_DQ<47>")
	)
	(segment
		(start 286.1564 -41.839134)
		(end 286.1564 -41.1226)
		(width 0.1016)
		(layer "F.Cu")
		(net "M_B_DQ<46>")
	)
	(segment
		(start 291.408104 -36.500816)
		(end 291.641784 -36.500816)
		(width 0.1651)
		(layer "F.Cu")
		(net "M_B_DQ<46>")
	)
	(segment
		(start 295.850056 -10.422128)
		(end 295.85031 -10.422382)
		(width 0.1651)
		(layer "F.Cu")
		(net "M_B_DQ<46>")
	)
	(segment
		(start 279.909524 -51.811174)
		(end 279.909524 -50.036476)
		(width 0.0889)
		(layer "F.Cu")
		(net "M_B_DQ<46>")
	)
	(segment
		(start 295.850056 -9.4488)
		(end 295.850056 -10.422128)
		(width 0.1651)
		(layer "F.Cu")
		(net "M_B_DQ<46>")
	)
	(segment
		(start 291.8841 -36.2585)
		(end 291.8841 -36.02482)
		(width 0.1651)
		(layer "F.Cu")
		(net "M_B_DQ<46>")
	)
	(segment
		(start 293.312088 -34.596832)
		(end 293.545768 -34.596832)
		(width 0.1651)
		(layer "F.Cu")
		(net "M_B_DQ<46>")
	)
	(segment
		(start 292.836092 -35.306508)
		(end 292.836092 -35.072828)
		(width 0.1651)
		(layer "F.Cu")
		(net "M_B_DQ<46>")
	)
	(segment
		(start 286.6898 -40.0304)
		(end 290.696904 -36.023296)
		(width 0.1651)
		(layer "F.Cu")
		(net "M_B_DQ<46>")
	)
	(segment
		(start 292.360096 -35.548824)
		(end 292.593776 -35.548824)
		(width 0.1651)
		(layer "F.Cu")
		(net "M_B_DQ<46>")
	)
	(segment
		(start 291.641784 -36.500816)
		(end 291.8841 -36.2585)
		(width 0.1651)
		(layer "F.Cu")
		(net "M_B_DQ<46>")
	)
	(segment
		(start 286.6898 -40.5892)
		(end 286.6898 -40.0304)
		(width 0.1651)
		(layer "F.Cu")
		(net "M_B_DQ<46>")
	)
	(segment
		(start 295.850056 -8.661654)
		(end 295.850056 -8.9662)
		(width 0.1651)
		(layer "F.Cu")
		(net "M_B_DQ<46>")
	)
	(segment
		(start 291.882576 -35.071304)
		(end 292.360096 -35.548824)
		(width 0.1651)
		(layer "F.Cu")
		(net "M_B_DQ<46>")
	)
	(segment
		(start 292.834568 -34.119312)
		(end 293.312088 -34.596832)
		(width 0.1651)
		(layer "F.Cu")
		(net "M_B_DQ<46>")
	)
	(segment
		(start 291.40658 -35.5473)
		(end 291.40658 -35.31362)
		(width 0.1651)
		(layer "F.Cu")
		(net "M_B_DQ<46>")
	)
	(segment
		(start 292.358572 -34.361628)
		(end 292.600888 -34.119312)
		(width 0.1651)
		(layer "F.Cu")
		(net "M_B_DQ<46>")
	)
	(segment
		(start 293.545768 -34.596832)
		(end 293.788084 -34.354516)
		(width 0.1651)
		(layer "F.Cu")
		(net "M_B_DQ<46>")
	)
	(segment
		(start 292.358572 -34.595308)
		(end 292.358572 -34.361628)
		(width 0.1651)
		(layer "F.Cu")
		(net "M_B_DQ<46>")
	)
	(segment
		(start 279.909524 -50.036476)
		(end 279.985724 -49.960276)
		(width 0.0889)
		(layer "F.Cu")
		(net "M_B_DQ<46>")
	)
	(segment
		(start 294.259 -32.4612)
		(end 294.259 -31.115)
		(width 0.1651)
		(layer "F.Cu")
		(net "M_B_DQ<46>")
	)
	(segment
		(start 293.310564 -33.643316)
		(end 293.310564 -33.409636)
		(width 0.1651)
		(layer "F.Cu")
		(net "M_B_DQ<46>")
	)
	(segment
		(start 292.600888 -34.119312)
		(end 292.834568 -34.119312)
		(width 0.1651)
		(layer "F.Cu")
		(net "M_B_DQ<46>")
	)
	(segment
		(start 293.788084 -34.354516)
		(end 293.788084 -34.120836)
		(width 0.1651)
		(layer "F.Cu")
		(net "M_B_DQ<46>")
	)
	(segment
		(start 295.849802 -8.6614)
		(end 295.850056 -8.661654)
		(width 0.1651)
		(layer "F.Cu")
		(net "M_B_DQ<46>")
	)
	(segment
		(start 279.985724 -48.00981)
		(end 286.1564 -41.839134)
		(width 0.1016)
		(layer "F.Cu")
		(net "M_B_DQ<46>")
	)
	(segment
		(start 291.40658 -35.31362)
		(end 291.648896 -35.071304)
		(width 0.1651)
		(layer "F.Cu")
		(net "M_B_DQ<46>")
	)
	(segment
		(start 290.696904 -36.023296)
		(end 290.930584 -36.023296)
		(width 0.1651)
		(layer "F.Cu")
		(net "M_B_DQ<46>")
	)
	(segment
		(start 293.310564 -33.409636)
		(end 294.259 -32.4612)
		(width 0.1651)
		(layer "F.Cu")
		(net "M_B_DQ<46>")
	)
	(segment
		(start 286.1564 -41.1226)
		(end 286.6898 -40.5892)
		(width 0.1651)
		(layer "F.Cu")
		(net "M_B_DQ<46>")
	)
	(segment
		(start 295.982136 -9.31672)
		(end 295.850056 -9.4488)
		(width 0.1651)
		(layer "F.Cu")
		(net "M_B_DQ<46>")
	)
	(segment
		(start 292.836092 -35.072828)
		(end 292.358572 -34.595308)
		(width 0.1651)
		(layer "F.Cu")
		(net "M_B_DQ<46>")
	)
	(segment
		(start 295.054528 -29.125672)
		(end 295.054528 -28.538678)
		(width 0.1651)
		(layer "F.Cu")
		(net "M_B_DQ<46>")
	)
	(segment
		(start 291.8841 -36.02482)
		(end 291.40658 -35.5473)
		(width 0.1651)
		(layer "F.Cu")
		(net "M_B_DQ<46>")
	)
	(segment
		(start 292.593776 -35.548824)
		(end 292.836092 -35.306508)
		(width 0.1651)
		(layer "F.Cu")
		(net "M_B_DQ<46>")
	)
	(segment
		(start 291.648896 -35.071304)
		(end 291.882576 -35.071304)
		(width 0.1651)
		(layer "F.Cu")
		(net "M_B_DQ<46>")
	)
	(segment
		(start 279.985724 -49.960276)
		(end 279.985724 -48.00981)
		(width 0.1016)
		(layer "F.Cu")
		(net "M_B_DQ<46>")
	)
	(segment
		(start 295.982136 -9.09828)
		(end 295.982136 -9.31672)
		(width 0.1651)
		(layer "F.Cu")
		(net "M_B_DQ<46>")
	)
	(segment
		(start 294.259 -31.115)
		(end 294.259 -29.9212)
		(width 0.1651)
		(layer "F.Cu")
		(net "M_B_DQ<46>")
	)
	(segment
		(start 295.850056 -8.9662)
		(end 295.982136 -9.09828)
		(width 0.1651)
		(layer "F.Cu")
		(net "M_B_DQ<46>")
	)
	(segment
		(start 293.788084 -34.120836)
		(end 293.310564 -33.643316)
		(width 0.1651)
		(layer "F.Cu")
		(net "M_B_DQ<46>")
	)
	(segment
		(start 290.930584 -36.023296)
		(end 291.408104 -36.500816)
		(width 0.1651)
		(layer "F.Cu")
		(net "M_B_DQ<46>")
	)
	(segment
		(start 294.259 -29.9212)
		(end 295.054528 -29.125672)
		(width 0.1651)
		(layer "F.Cu")
		(net "M_B_DQ<46>")
	)
	(segment
		(start 279.778714 -51.941984)
		(end 279.909524 -51.811174)
		(width 0.0889)
		(layer "F.Cu")
		(net "M_B_DQ<46>")
	)
	(via
		(at 294.999918 -13.959078)
		(size 0.508)
		(drill 0.254)
		(layers "F.Cu" "B.Cu")
		(net "M_B_DQ<46>")
	)
	(via
		(at 295.849802 -8.6614)
		(size 0.508)
		(drill 0.254)
		(layers "F.Cu" "B.Cu")
		(net "M_B_DQ<46>")
	)
	(via
		(at 295.054528 -28.538678)
		(size 0.508)
		(drill 0.254)
		(layers "F.Cu" "B.Cu")
		(net "M_B_DQ<46>")
	)
	(via
		(at 294.259 -31.115)
		(size 0.508)
		(drill 0.254)
		(layers "F.Cu" "B.Cu")
		(net "M_B_DQ<46>")
	)
	(segment
		(start 295.000426 -15.222982)
		(end 294.999918 -15.222982)
		(width 0.1651)
		(layer "B.Cu")
		(net "M_B_DQ<46>")
	)
	(segment
		(start 294.999918 -15.222982)
		(end 294.999918 -13.959078)
		(width 0.1651)
		(layer "B.Cu")
		(net "M_B_DQ<46>")
	)
	(segment
		(start 295.298876 -23.132796)
		(end 295.298876 -22.040596)
		(width 0.14224)
		(layer "In11.Cu")
		(net "M_B_DQ<46>")
	)
	(segment
		(start 295.492424 -10.712704)
		(end 295.492424 -10.369296)
		(width 0.14224)
		(layer "In11.Cu")
		(net "M_B_DQ<46>")
	)
	(segment
		(start 295.054528 -28.538678)
		(end 295.054528 -27.170126)
		(width 0.14224)
		(layer "In11.Cu")
		(net "M_B_DQ<46>")
	)
	(segment
		(start 295.111424 -9.677654)
		(end 295.475406 -9.313672)
		(width 0.14224)
		(layer "In11.Cu")
		(net "M_B_DQ<46>")
	)
	(segment
		(start 295.298876 -22.040596)
		(end 295.476676 -21.862796)
		(width 0.14224)
		(layer "In11.Cu")
		(net "M_B_DQ<46>")
	)
	(segment
		(start 295.476676 -18.54073)
		(end 295.298876 -18.36293)
		(width 0.14224)
		(layer "In11.Cu")
		(net "M_B_DQ<46>")
	)
	(segment
		(start 295.502076 -16.850106)
		(end 295.502076 -14.461236)
		(width 0.14224)
		(layer "In11.Cu")
		(net "M_B_DQ<46>")
	)
	(segment
		(start 295.298876 -18.36293)
		(end 295.298876 -17.053306)
		(width 0.14224)
		(layer "In11.Cu")
		(net "M_B_DQ<46>")
	)
	(segment
		(start 294.999918 -13.959078)
		(end 294.764206 -13.723366)
		(width 0.14224)
		(layer "In11.Cu")
		(net "M_B_DQ<46>")
	)
	(segment
		(start 295.536874 -11.804396)
		(end 295.111424 -11.378946)
		(width 0.14224)
		(layer "In11.Cu")
		(net "M_B_DQ<46>")
	)
	(segment
		(start 295.298876 -17.053306)
		(end 295.502076 -16.850106)
		(width 0.14224)
		(layer "In11.Cu")
		(net "M_B_DQ<46>")
	)
	(segment
		(start 295.054528 -27.170126)
		(end 295.578276 -26.646378)
		(width 0.14224)
		(layer "In11.Cu")
		(net "M_B_DQ<46>")
	)
	(segment
		(start 295.502076 -14.461236)
		(end 294.999918 -13.959078)
		(width 0.14224)
		(layer "In11.Cu")
		(net "M_B_DQ<46>")
	)
	(segment
		(start 295.578276 -26.646378)
		(end 295.578276 -23.412196)
		(width 0.14224)
		(layer "In11.Cu")
		(net "M_B_DQ<46>")
	)
	(segment
		(start 295.111424 -9.988296)
		(end 295.111424 -9.677654)
		(width 0.14224)
		(layer "In11.Cu")
		(net "M_B_DQ<46>")
	)
	(segment
		(start 295.536874 -12.156186)
		(end 295.536874 -11.804396)
		(width 0.14224)
		(layer "In11.Cu")
		(net "M_B_DQ<46>")
	)
	(segment
		(start 295.476676 -21.862796)
		(end 295.476676 -21.3106)
		(width 0.14224)
		(layer "In11.Cu")
		(net "M_B_DQ<46>")
	)
	(segment
		(start 294.764206 -13.723366)
		(end 294.764206 -12.928854)
		(width 0.14224)
		(layer "In11.Cu")
		(net "M_B_DQ<46>")
	)
	(segment
		(start 295.476676 -21.3106)
		(end 295.3004 -21.134324)
		(width 0.14224)
		(layer "In11.Cu")
		(net "M_B_DQ<46>")
	)
	(segment
		(start 295.475406 -9.313672)
		(end 295.475406 -9.035796)
		(width 0.14224)
		(layer "In11.Cu")
		(net "M_B_DQ<46>")
	)
	(segment
		(start 295.3004 -21.134324)
		(end 295.3004 -19.2024)
		(width 0.14224)
		(layer "In11.Cu")
		(net "M_B_DQ<46>")
	)
	(segment
		(start 295.475406 -9.035796)
		(end 295.849802 -8.6614)
		(width 0.14224)
		(layer "In11.Cu")
		(net "M_B_DQ<46>")
	)
	(segment
		(start 295.111424 -11.378946)
		(end 295.111424 -11.093704)
		(width 0.14224)
		(layer "In11.Cu")
		(net "M_B_DQ<46>")
	)
	(segment
		(start 295.3004 -19.2024)
		(end 295.476676 -19.026124)
		(width 0.14224)
		(layer "In11.Cu")
		(net "M_B_DQ<46>")
	)
	(segment
		(start 294.764206 -12.928854)
		(end 295.536874 -12.156186)
		(width 0.14224)
		(layer "In11.Cu")
		(net "M_B_DQ<46>")
	)
	(segment
		(start 295.111424 -11.093704)
		(end 295.492424 -10.712704)
		(width 0.14224)
		(layer "In11.Cu")
		(net "M_B_DQ<46>")
	)
	(segment
		(start 295.492424 -10.369296)
		(end 295.111424 -9.988296)
		(width 0.14224)
		(layer "In11.Cu")
		(net "M_B_DQ<46>")
	)
	(segment
		(start 295.578276 -23.412196)
		(end 295.298876 -23.132796)
		(width 0.14224)
		(layer "In11.Cu")
		(net "M_B_DQ<46>")
	)
	(segment
		(start 295.476676 -19.026124)
		(end 295.476676 -18.54073)
		(width 0.14224)
		(layer "In11.Cu")
		(net "M_B_DQ<46>")
	)
	(segment
		(start 289.7124 -28.8544)
		(end 289.7124 -28.3972)
		(width 0.1651)
		(layer "F.Cu")
		(net "M_B_DQ<45>")
	)
	(segment
		(start 289.049968 -5.822442)
		(end 289.049968 -7.086346)
		(width 0.1651)
		(layer "F.Cu")
		(net "M_B_DQ<45>")
	)
	(segment
		(start 277.112476 -49.963578)
		(end 277.229824 -49.84623)
		(width 0.0889)
		(layer "F.Cu")
		(net "M_B_DQ<45>")
	)
	(segment
		(start 277.229824 -46.866556)
		(end 280.9494 -43.14698)
		(width 0.1016)
		(layer "F.Cu")
		(net "M_B_DQ<45>")
	)
	(segment
		(start 288.849308 -27.8765)
		(end 288.849308 -27.333956)
		(width 0.1651)
		(layer "F.Cu")
		(net "M_B_DQ<45>")
	)
	(segment
		(start 280.9494 -41.2242)
		(end 280.797 -41.0718)
		(width 0.1016)
		(layer "F.Cu")
		(net "M_B_DQ<45>")
	)
	(segment
		(start 289.629596 -26.9748)
		(end 289.823652 -27.168856)
		(width 0.1651)
		(layer "F.Cu")
		(net "M_B_DQ<45>")
	)
	(segment
		(start 289.7124 -28.3972)
		(end 289.3568 -28.0416)
		(width 0.1651)
		(layer "F.Cu")
		(net "M_B_DQ<45>")
	)
	(segment
		(start 288.849308 -27.333956)
		(end 289.208464 -26.9748)
		(width 0.1651)
		(layer "F.Cu")
		(net "M_B_DQ<45>")
	)
	(segment
		(start 288.4678 -30.099)
		(end 289.2679 -29.2989)
		(width 0.1651)
		(layer "F.Cu")
		(net "M_B_DQ<45>")
	)
	(segment
		(start 289.3568 -28.0416)
		(end 289.014408 -28.0416)
		(width 0.1651)
		(layer "F.Cu")
		(net "M_B_DQ<45>")
	)
	(segment
		(start 280.9494 -43.14698)
		(end 280.9494 -41.2242)
		(width 0.1016)
		(layer "F.Cu")
		(net "M_B_DQ<45>")
	)
	(segment
		(start 276.798024 -50.599086)
		(end 277.112476 -50.284634)
		(width 0.0889)
		(layer "F.Cu")
		(net "M_B_DQ<45>")
	)
	(segment
		(start 279.908 -39.7002)
		(end 288.4678 -31.1404)
		(width 0.1651)
		(layer "F.Cu")
		(net "M_B_DQ<45>")
	)
	(segment
		(start 289.014408 -28.0416)
		(end 288.849308 -27.8765)
		(width 0.1651)
		(layer "F.Cu")
		(net "M_B_DQ<45>")
	)
	(segment
		(start 278.061674 -53.923184)
		(end 277.643844 -53.271928)
		(width 0.0889)
		(layer "F.Cu")
		(net "M_B_DQ<45>")
	)
	(segment
		(start 289.208464 -26.9748)
		(end 289.629596 -26.9748)
		(width 0.1651)
		(layer "F.Cu")
		(net "M_B_DQ<45>")
	)
	(segment
		(start 277.229824 -49.84623)
		(end 277.229824 -46.866556)
		(width 0.1016)
		(layer "F.Cu")
		(net "M_B_DQ<45>")
	)
	(segment
		(start 277.224744 -52.837334)
		(end 277.191978 -52.837334)
		(width 0.0889)
		(layer "F.Cu")
		(net "M_B_DQ<45>")
	)
	(segment
		(start 276.798024 -51.428396)
		(end 276.798024 -50.599086)
		(width 0.0889)
		(layer "F.Cu")
		(net "M_B_DQ<45>")
	)
	(segment
		(start 279.908 -40.1828)
		(end 279.908 -39.7002)
		(width 0.1651)
		(layer "F.Cu")
		(net "M_B_DQ<45>")
	)
	(segment
		(start 277.112476 -50.284634)
		(end 277.112476 -49.963578)
		(width 0.0889)
		(layer "F.Cu")
		(net "M_B_DQ<45>")
	)
	(segment
		(start 288.4678 -31.1404)
		(end 288.4678 -30.099)
		(width 0.1651)
		(layer "F.Cu")
		(net "M_B_DQ<45>")
	)
	(segment
		(start 289.050476 -5.822442)
		(end 289.049968 -5.822442)
		(width 0.1651)
		(layer "F.Cu")
		(net "M_B_DQ<45>")
	)
	(segment
		(start 280.797 -41.0718)
		(end 279.908 -40.1828)
		(width 0.1651)
		(layer "F.Cu")
		(net "M_B_DQ<45>")
	)
	(segment
		(start 289.2679 -29.2989)
		(end 289.7124 -28.8544)
		(width 0.1651)
		(layer "F.Cu")
		(net "M_B_DQ<45>")
	)
	(via
		(at 289.823652 -12.678156)
		(size 0.508)
		(drill 0.254)
		(layers "F.Cu" "B.Cu")
		(net "M_B_DQ<45>")
	)
	(via
		(at 289.049968 -7.086346)
		(size 0.508)
		(drill 0.254)
		(layers "F.Cu" "B.Cu")
		(net "M_B_DQ<45>")
	)
	(via
		(at 289.823652 -27.168856)
		(size 0.508)
		(drill 0.254)
		(layers "F.Cu" "B.Cu")
		(net "M_B_DQ<45>")
	)
	(via
		(at 289.2679 -29.2989)
		(size 0.508)
		(drill 0.254)
		(layers "F.Cu" "B.Cu")
		(net "M_B_DQ<45>")
	)
	(arc
		(start 276.856444 -51.646582)
		(mid 276.812854 -51.541337)
		(end 276.798024 -51.428396)
		(width 0.0889)
		(layer "F.Cu")
		(net "M_B_DQ<45>")
	)
	(arc
		(start 277.643844 -53.271928)
		(mid 277.522015 -52.969978)
		(end 277.224744 -52.837334)
		(width 0.0889)
		(layer "F.Cu")
		(net "M_B_DQ<45>")
	)
	(arc
		(start 276.856444 -52.237386)
		(mid 276.935575 -51.941984)
		(end 276.856444 -51.646582)
		(width 0.0889)
		(layer "F.Cu")
		(net "M_B_DQ<45>")
	)
	(arc
		(start 277.191978 -52.837334)
		(mid 276.853863 -52.632632)
		(end 276.856444 -52.237386)
		(width 0.0889)
		(layer "F.Cu")
		(net "M_B_DQ<45>")
	)
	(segment
		(start 289.90036 -10.623042)
		(end 289.899852 -10.623042)
		(width 0.1651)
		(layer "B.Cu")
		(net "M_B_DQ<45>")
	)
	(segment
		(start 289.899852 -12.601956)
		(end 289.823652 -12.678156)
		(width 0.1651)
		(layer "B.Cu")
		(net "M_B_DQ<45>")
	)
	(segment
		(start 289.899852 -10.623042)
		(end 289.899852 -12.601956)
		(width 0.1651)
		(layer "B.Cu")
		(net "M_B_DQ<45>")
	)
	(segment
		(start 290.3474 -19.1008)
		(end 290.3474 -21.209)
		(width 0.14224)
		(layer "In11.Cu")
		(net "M_B_DQ<45>")
	)
	(segment
		(start 289.781996 -14.510004)
		(end 289.781996 -15.570708)
		(width 0.14224)
		(layer "In11.Cu")
		(net "M_B_DQ<45>")
	)
	(segment
		(start 290.244276 -26.748232)
		(end 289.823652 -27.168856)
		(width 0.14224)
		(layer "In11.Cu")
		(net "M_B_DQ<45>")
	)
	(segment
		(start 289.3314 -7.762494)
		(end 289.620706 -8.0518)
		(width 0.14224)
		(layer "In11.Cu")
		(net "M_B_DQ<45>")
	)
	(segment
		(start 290.244276 -23.234396)
		(end 290.244276 -26.748232)
		(width 0.14224)
		(layer "In11.Cu")
		(net "M_B_DQ<45>")
	)
	(segment
		(start 290.3474 -21.209)
		(end 290.218876 -21.337524)
		(width 0.14224)
		(layer "In11.Cu")
		(net "M_B_DQ<45>")
	)
	(segment
		(start 290.218876 -17.032986)
		(end 290.295076 -17.109186)
		(width 0.14224)
		(layer "In11.Cu")
		(net "M_B_DQ<45>")
	)
	(segment
		(start 290.135056 -9.06145)
		(end 290.135056 -12.366752)
		(width 0.14224)
		(layer "In11.Cu")
		(net "M_B_DQ<45>")
	)
	(segment
		(start 290.135056 -12.366752)
		(end 289.823652 -12.678156)
		(width 0.14224)
		(layer "In11.Cu")
		(net "M_B_DQ<45>")
	)
	(segment
		(start 290.218876 -16.007588)
		(end 290.218876 -17.032986)
		(width 0.14224)
		(layer "In11.Cu")
		(net "M_B_DQ<45>")
	)
	(segment
		(start 290.331906 -8.452104)
		(end 290.331906 -8.8646)
		(width 0.14224)
		(layer "In11.Cu")
		(net "M_B_DQ<45>")
	)
	(segment
		(start 290.295076 -18.455386)
		(end 290.218876 -18.531586)
		(width 0.14224)
		(layer "In11.Cu")
		(net "M_B_DQ<45>")
	)
	(segment
		(start 289.620706 -8.0518)
		(end 289.931602 -8.0518)
		(width 0.14224)
		(layer "In11.Cu")
		(net "M_B_DQ<45>")
	)
	(segment
		(start 290.320476 -23.158196)
		(end 290.244276 -23.234396)
		(width 0.14224)
		(layer "In11.Cu")
		(net "M_B_DQ<45>")
	)
	(segment
		(start 289.931602 -8.0518)
		(end 290.331906 -8.452104)
		(width 0.14224)
		(layer "In11.Cu")
		(net "M_B_DQ<45>")
	)
	(segment
		(start 289.781996 -15.570708)
		(end 290.218876 -16.007588)
		(width 0.14224)
		(layer "In11.Cu")
		(net "M_B_DQ<45>")
	)
	(segment
		(start 289.3314 -7.367778)
		(end 289.3314 -7.762494)
		(width 0.14224)
		(layer "In11.Cu")
		(net "M_B_DQ<45>")
	)
	(segment
		(start 290.218876 -18.972276)
		(end 290.3474 -19.1008)
		(width 0.14224)
		(layer "In11.Cu")
		(net "M_B_DQ<45>")
	)
	(segment
		(start 289.049968 -7.086346)
		(end 289.3314 -7.367778)
		(width 0.14224)
		(layer "In11.Cu")
		(net "M_B_DQ<45>")
	)
	(segment
		(start 289.823652 -12.678156)
		(end 289.823652 -14.468348)
		(width 0.14224)
		(layer "In11.Cu")
		(net "M_B_DQ<45>")
	)
	(segment
		(start 290.320476 -21.964396)
		(end 290.320476 -23.158196)
		(width 0.14224)
		(layer "In11.Cu")
		(net "M_B_DQ<45>")
	)
	(segment
		(start 290.218876 -21.337524)
		(end 290.218876 -21.862796)
		(width 0.14224)
		(layer "In11.Cu")
		(net "M_B_DQ<45>")
	)
	(segment
		(start 290.218876 -18.531586)
		(end 290.218876 -18.972276)
		(width 0.14224)
		(layer "In11.Cu")
		(net "M_B_DQ<45>")
	)
	(segment
		(start 290.218876 -21.862796)
		(end 290.320476 -21.964396)
		(width 0.14224)
		(layer "In11.Cu")
		(net "M_B_DQ<45>")
	)
	(segment
		(start 289.823652 -14.468348)
		(end 289.781996 -14.510004)
		(width 0.14224)
		(layer "In11.Cu")
		(net "M_B_DQ<45>")
	)
	(segment
		(start 290.295076 -17.109186)
		(end 290.295076 -18.455386)
		(width 0.14224)
		(layer "In11.Cu")
		(net "M_B_DQ<45>")
	)
	(segment
		(start 290.331906 -8.8646)
		(end 290.135056 -9.06145)
		(width 0.14224)
		(layer "In11.Cu")
		(net "M_B_DQ<45>")
	)
	(segment
		(start 276.691344 -52.732686)
		(end 276.707854 -52.761388)
		(width 0.0889)
		(layer "F.Cu")
		(net "M_B_DQ<44>")
	)
	(segment
		(start 276.707854 -52.761388)
		(end 277.203154 -53.427884)
		(width 0.0889)
		(layer "F.Cu")
		(net "M_B_DQ<44>")
	)
	(segment
		(start 278.4221 -41.7576)
		(end 278.9936 -41.7576)
		(width 0.1651)
		(layer "F.Cu")
		(net "M_B_DQ<44>")
	)
	(segment
		(start 278.9936 -41.7576)
		(end 279.1206 -41.6306)
		(width 0.1651)
		(layer "F.Cu")
		(net "M_B_DQ<44>")
	)
	(segment
		(start 279.1206 -41.529)
		(end 279.2476 -41.402)
		(width 0.1651)
		(layer "F.Cu")
		(net "M_B_DQ<44>")
	)
	(segment
		(start 289.90036 -10.422382)
		(end 289.899852 -10.422382)
		(width 0.1651)
		(layer "F.Cu")
		(net "M_B_DQ<44>")
	)
	(segment
		(start 289.899852 -9.091168)
		(end 289.862768 -8.89)
		(width 0.1651)
		(layer "F.Cu")
		(net "M_B_DQ<44>")
	)
	(segment
		(start 278.257 -41.5925)
		(end 278.4221 -41.7576)
		(width 0.1651)
		(layer "F.Cu")
		(net "M_B_DQ<44>")
	)
	(segment
		(start 287.7566 -29.895546)
		(end 287.7566 -30.886654)
		(width 0.1651)
		(layer "F.Cu")
		(net "M_B_DQ<44>")
	)
	(segment
		(start 279.2476 -41.402)
		(end 279.8064 -41.402)
		(width 0.1651)
		(layer "F.Cu")
		(net "M_B_DQ<44>")
	)
	(segment
		(start 280.289 -41.402)
		(end 280.5557 -41.6687)
		(width 0.1016)
		(layer "F.Cu")
		(net "M_B_DQ<44>")
	)
	(segment
		(start 280.5557 -42.983658)
		(end 276.836124 -46.703234)
		(width 0.1016)
		(layer "F.Cu")
		(net "M_B_DQ<44>")
	)
	(segment
		(start 289.8394 -8.763)
		(end 289.801808 -8.5598)
		(width 0.1651)
		(layer "F.Cu")
		(net "M_B_DQ<44>")
	)
	(segment
		(start 276.922484 -49.97323)
		(end 276.922484 -50.205894)
		(width 0.0889)
		(layer "F.Cu")
		(net "M_B_DQ<44>")
	)
	(segment
		(start 289.113468 -28.538678)
		(end 287.7566 -29.895546)
		(width 0.1651)
		(layer "F.Cu")
		(net "M_B_DQ<44>")
	)
	(segment
		(start 287.7566 -30.886654)
		(end 278.257 -40.386254)
		(width 0.1651)
		(layer "F.Cu")
		(net "M_B_DQ<44>")
	)
	(segment
		(start 276.607524 -50.520854)
		(end 276.607524 -51.429412)
		(width 0.0889)
		(layer "F.Cu")
		(net "M_B_DQ<44>")
	)
	(segment
		(start 279.8064 -41.402)
		(end 280.289 -41.402)
		(width 0.1016)
		(layer "F.Cu")
		(net "M_B_DQ<44>")
	)
	(segment
		(start 276.836124 -46.703234)
		(end 276.836124 -49.88687)
		(width 0.1016)
		(layer "F.Cu")
		(net "M_B_DQ<44>")
	)
	(segment
		(start 279.1206 -41.6306)
		(end 279.1206 -41.529)
		(width 0.1651)
		(layer "F.Cu")
		(net "M_B_DQ<44>")
	)
	(segment
		(start 278.257 -40.386254)
		(end 278.257 -41.5925)
		(width 0.1651)
		(layer "F.Cu")
		(net "M_B_DQ<44>")
	)
	(segment
		(start 289.899852 -10.422382)
		(end 289.899852 -9.091168)
		(width 0.1651)
		(layer "F.Cu")
		(net "M_B_DQ<44>")
	)
	(segment
		(start 280.5557 -41.6687)
		(end 280.5557 -42.983658)
		(width 0.1016)
		(layer "F.Cu")
		(net "M_B_DQ<44>")
	)
	(segment
		(start 276.922484 -50.205894)
		(end 276.607524 -50.520854)
		(width 0.0889)
		(layer "F.Cu")
		(net "M_B_DQ<44>")
	)
	(segment
		(start 289.862768 -8.89)
		(end 289.8394 -8.763)
		(width 0.1651)
		(layer "F.Cu")
		(net "M_B_DQ<44>")
	)
	(segment
		(start 276.836124 -49.88687)
		(end 276.922484 -49.97323)
		(width 0.0889)
		(layer "F.Cu")
		(net "M_B_DQ<44>")
	)
	(via
		(at 289.049968 -13.959078)
		(size 0.508)
		(drill 0.254)
		(layers "F.Cu" "B.Cu")
		(net "M_B_DQ<44>")
	)
	(via
		(at 289.801808 -8.5598)
		(size 0.508)
		(drill 0.254)
		(layers "F.Cu" "B.Cu")
		(net "M_B_DQ<44>")
	)
	(via
		(at 289.113468 -28.538678)
		(size 0.508)
		(drill 0.254)
		(layers "F.Cu" "B.Cu")
		(net "M_B_DQ<44>")
	)
	(arc
		(start 276.607524 -51.429412)
		(mid 276.628843 -51.591269)
		(end 276.691344 -51.742086)
		(width 0.0889)
		(layer "F.Cu")
		(net "M_B_DQ<44>")
	)
	(arc
		(start 276.691344 -51.742086)
		(mid 276.744843 -51.941984)
		(end 276.691344 -52.141882)
		(width 0.0889)
		(layer "F.Cu")
		(net "M_B_DQ<44>")
	)
	(arc
		(start 276.691344 -52.141882)
		(mid 276.612213 -52.437284)
		(end 276.691344 -52.732686)
		(width 0.0889)
		(layer "F.Cu")
		(net "M_B_DQ<44>")
	)
	(segment
		(start 289.049968 -15.222982)
		(end 289.049968 -13.959078)
		(width 0.1651)
		(layer "B.Cu")
		(net "M_B_DQ<44>")
	)
	(segment
		(start 289.050476 -15.222982)
		(end 289.049968 -15.222982)
		(width 0.1651)
		(layer "B.Cu")
		(net "M_B_DQ<44>")
	)
	(segment
		(start 289.113468 -27.218132)
		(end 289.5854 -26.7462)
		(width 0.14224)
		(layer "In11.Cu")
		(net "M_B_DQ<44>")
	)
	(segment
		(start 289.525456 -8.836152)
		(end 289.801808 -8.5598)
		(width 0.14224)
		(layer "In11.Cu")
		(net "M_B_DQ<44>")
	)
	(segment
		(start 289.525456 -9.305544)
		(end 289.525456 -8.836152)
		(width 0.14224)
		(layer "In11.Cu")
		(net "M_B_DQ<44>")
	)
	(segment
		(start 289.3822 -19.1262)
		(end 289.533076 -18.975324)
		(width 0.14224)
		(layer "In11.Cu")
		(net "M_B_DQ<44>")
	)
	(segment
		(start 289.052 -11.303)
		(end 289.052 -11.150346)
		(width 0.14224)
		(layer "In11.Cu")
		(net "M_B_DQ<44>")
	)
	(segment
		(start 289.5854 -26.7462)
		(end 289.5854 -23.36292)
		(width 0.14224)
		(layer "In11.Cu")
		(net "M_B_DQ<44>")
	)
	(segment
		(start 289.052 -9.982454)
		(end 289.052 -9.779)
		(width 0.14224)
		(layer "In11.Cu")
		(net "M_B_DQ<44>")
	)
	(segment
		(start 289.542474 -10.472928)
		(end 289.052 -9.982454)
		(width 0.14224)
		(layer "In11.Cu")
		(net "M_B_DQ<44>")
	)
	(segment
		(start 289.5854 -23.36292)
		(end 289.329876 -23.107396)
		(width 0.14224)
		(layer "In11.Cu")
		(net "M_B_DQ<44>")
	)
	(segment
		(start 289.329876 -18.328386)
		(end 289.329876 -17.045178)
		(width 0.14224)
		(layer "In11.Cu")
		(net "M_B_DQ<44>")
	)
	(segment
		(start 289.052 -11.150346)
		(end 289.542474 -10.659872)
		(width 0.14224)
		(layer "In11.Cu")
		(net "M_B_DQ<44>")
	)
	(segment
		(start 289.533076 -21.336)
		(end 289.3822 -21.185124)
		(width 0.14224)
		(layer "In11.Cu")
		(net "M_B_DQ<44>")
	)
	(segment
		(start 289.329876 -23.107396)
		(end 289.329876 -21.938996)
		(width 0.14224)
		(layer "In11.Cu")
		(net "M_B_DQ<44>")
	)
	(segment
		(start 289.329876 -17.045178)
		(end 289.533076 -16.841978)
		(width 0.14224)
		(layer "In11.Cu")
		(net "M_B_DQ<44>")
	)
	(segment
		(start 289.533076 -16.841978)
		(end 289.533076 -16.093186)
		(width 0.14224)
		(layer "In11.Cu")
		(net "M_B_DQ<44>")
	)
	(segment
		(start 289.525456 -11.776456)
		(end 289.052 -11.303)
		(width 0.14224)
		(layer "In11.Cu")
		(net "M_B_DQ<44>")
	)
	(segment
		(start 289.533076 -18.975324)
		(end 289.533076 -18.531586)
		(width 0.14224)
		(layer "In11.Cu")
		(net "M_B_DQ<44>")
	)
	(segment
		(start 289.533076 -18.531586)
		(end 289.329876 -18.328386)
		(width 0.14224)
		(layer "In11.Cu")
		(net "M_B_DQ<44>")
	)
	(segment
		(start 289.525456 -12.217654)
		(end 289.525456 -11.776456)
		(width 0.14224)
		(layer "In11.Cu")
		(net "M_B_DQ<44>")
	)
	(segment
		(start 289.049968 -15.610078)
		(end 289.049968 -13.959078)
		(width 0.14224)
		(layer "In11.Cu")
		(net "M_B_DQ<44>")
	)
	(segment
		(start 289.533076 -21.735796)
		(end 289.533076 -21.336)
		(width 0.14224)
		(layer "In11.Cu")
		(net "M_B_DQ<44>")
	)
	(segment
		(start 289.2298 -13.779246)
		(end 289.2298 -12.51331)
		(width 0.14224)
		(layer "In11.Cu")
		(net "M_B_DQ<44>")
	)
	(segment
		(start 289.329876 -21.938996)
		(end 289.533076 -21.735796)
		(width 0.14224)
		(layer "In11.Cu")
		(net "M_B_DQ<44>")
	)
	(segment
		(start 289.113468 -28.538678)
		(end 289.113468 -27.218132)
		(width 0.14224)
		(layer "In11.Cu")
		(net "M_B_DQ<44>")
	)
	(segment
		(start 289.542474 -10.659872)
		(end 289.542474 -10.472928)
		(width 0.14224)
		(layer "In11.Cu")
		(net "M_B_DQ<44>")
	)
	(segment
		(start 289.052 -9.779)
		(end 289.525456 -9.305544)
		(width 0.14224)
		(layer "In11.Cu")
		(net "M_B_DQ<44>")
	)
	(segment
		(start 289.533076 -16.093186)
		(end 289.049968 -15.610078)
		(width 0.14224)
		(layer "In11.Cu")
		(net "M_B_DQ<44>")
	)
	(segment
		(start 289.2298 -12.51331)
		(end 289.525456 -12.217654)
		(width 0.14224)
		(layer "In11.Cu")
		(net "M_B_DQ<44>")
	)
	(segment
		(start 289.049968 -13.959078)
		(end 289.2298 -13.779246)
		(width 0.14224)
		(layer "In11.Cu")
		(net "M_B_DQ<44>")
	)
	(segment
		(start 289.3822 -21.185124)
		(end 289.3822 -19.1262)
		(width 0.14224)
		(layer "In11.Cu")
		(net "M_B_DQ<44>")
	)
	(segment
		(start 281.203146 -51.645566)
		(end 281.203146 -51.219862)
		(width 0.0889)
		(layer "F.Cu")
		(net "M_B_DQ<43>")
	)
	(segment
		(start 297.8658 -28.02128)
		(end 297.8658 -27.671522)
		(width 0.1651)
		(layer "F.Cu")
		(net "M_B_DQ<43>")
	)
	(segment
		(start 289.006026 -40.482774)
		(end 290.9316 -38.5572)
		(width 0.1651)
		(layer "F.Cu")
		(net "M_B_DQ<43>")
	)
	(segment
		(start 297.34764 -28.53944)
		(end 297.8658 -28.02128)
		(width 0.1651)
		(layer "F.Cu")
		(net "M_B_DQ<43>")
	)
	(segment
		(start 287.528 -42.1386)
		(end 288.036 -42.1386)
		(width 0.1016)
		(layer "F.Cu")
		(net "M_B_DQ<43>")
	)
	(segment
		(start 280.967434 -52.665884)
		(end 280.983944 -52.637436)
		(width 0.0889)
		(layer "F.Cu")
		(net "M_B_DQ<43>")
	)
	(segment
		(start 281.094942 -50.809144)
		(end 281.354784 -50.358548)
		(width 0.0889)
		(layer "F.Cu")
		(net "M_B_DQ<43>")
	)
	(segment
		(start 296.69994 -5.822442)
		(end 296.69994 -7.086346)
		(width 0.1651)
		(layer "F.Cu")
		(net "M_B_DQ<43>")
	)
	(segment
		(start 288.036 -42.1386)
		(end 289.006026 -41.168574)
		(width 0.1651)
		(layer "F.Cu")
		(net "M_B_DQ<43>")
	)
	(segment
		(start 281.144218 -51.750722)
		(end 281.203146 -51.645566)
		(width 0.0889)
		(layer "F.Cu")
		(net "M_B_DQ<43>")
	)
	(segment
		(start 281.094942 -51.03241)
		(end 281.094942 -50.809144)
		(width 0.0889)
		(layer "F.Cu")
		(net "M_B_DQ<43>")
	)
	(segment
		(start 289.006026 -41.168574)
		(end 289.006026 -40.482774)
		(width 0.1651)
		(layer "F.Cu")
		(net "M_B_DQ<43>")
	)
	(segment
		(start 281.166824 -48.499776)
		(end 287.528 -42.1386)
		(width 0.1016)
		(layer "F.Cu")
		(net "M_B_DQ<43>")
	)
	(segment
		(start 281.354784 -50.139854)
		(end 281.354784 -49.630584)
		(width 0.1016)
		(layer "F.Cu")
		(net "M_B_DQ<43>")
	)
	(segment
		(start 297.8658 -27.671522)
		(end 297.363134 -27.168856)
		(width 0.1651)
		(layer "F.Cu")
		(net "M_B_DQ<43>")
	)
	(segment
		(start 280.637234 -53.427884)
		(end 280.967434 -52.665884)
		(width 0.0889)
		(layer "F.Cu")
		(net "M_B_DQ<43>")
	)
	(segment
		(start 281.203146 -51.219862)
		(end 281.094942 -51.03241)
		(width 0.0889)
		(layer "F.Cu")
		(net "M_B_DQ<43>")
	)
	(segment
		(start 281.166824 -49.442624)
		(end 281.166824 -48.499776)
		(width 0.1016)
		(layer "F.Cu")
		(net "M_B_DQ<43>")
	)
	(segment
		(start 292.862 -38.5572)
		(end 297.34764 -34.07156)
		(width 0.1651)
		(layer "F.Cu")
		(net "M_B_DQ<43>")
	)
	(segment
		(start 281.354784 -49.630584)
		(end 281.166824 -49.442624)
		(width 0.1016)
		(layer "F.Cu")
		(net "M_B_DQ<43>")
	)
	(segment
		(start 281.354784 -50.358548)
		(end 281.354784 -50.139854)
		(width 0.0889)
		(layer "F.Cu")
		(net "M_B_DQ<43>")
	)
	(segment
		(start 296.700448 -5.822442)
		(end 296.69994 -5.822442)
		(width 0.1651)
		(layer "F.Cu")
		(net "M_B_DQ<43>")
	)
	(segment
		(start 297.34764 -34.07156)
		(end 297.34764 -29.718)
		(width 0.1651)
		(layer "F.Cu")
		(net "M_B_DQ<43>")
	)
	(segment
		(start 297.34764 -29.718)
		(end 297.34764 -28.53944)
		(width 0.1651)
		(layer "F.Cu")
		(net "M_B_DQ<43>")
	)
	(segment
		(start 290.9316 -38.5572)
		(end 292.862 -38.5572)
		(width 0.1651)
		(layer "F.Cu")
		(net "M_B_DQ<43>")
	)
	(via
		(at 297.34764 -29.718)
		(size 0.508)
		(drill 0.254)
		(layers "F.Cu" "B.Cu")
		(net "M_B_DQ<43>")
	)
	(via
		(at 296.69994 -7.086346)
		(size 0.508)
		(drill 0.254)
		(layers "F.Cu" "B.Cu")
		(net "M_B_DQ<43>")
	)
	(via
		(at 297.549824 -12.678156)
		(size 0.508)
		(drill 0.254)
		(layers "F.Cu" "B.Cu")
		(net "M_B_DQ<43>")
	)
	(via
		(at 297.363134 -27.168856)
		(size 0.508)
		(drill 0.254)
		(layers "F.Cu" "B.Cu")
		(net "M_B_DQ<43>")
	)
	(arc
		(start 280.983944 -52.637436)
		(mid 281.067398 -52.293508)
		(end 281.09545 -51.940714)
		(width 0.0889)
		(layer "F.Cu")
		(net "M_B_DQ<43>")
	)
	(arc
		(start 281.09545 -51.940714)
		(mid 281.108023 -51.842687)
		(end 281.144218 -51.750722)
		(width 0.0889)
		(layer "F.Cu")
		(net "M_B_DQ<43>")
	)
	(segment
		(start 297.549824 -10.623042)
		(end 297.549824 -12.678156)
		(width 0.1651)
		(layer "B.Cu")
		(net "M_B_DQ<43>")
	)
	(segment
		(start 297.550332 -10.623042)
		(end 297.549824 -10.623042)
		(width 0.1651)
		(layer "B.Cu")
		(net "M_B_DQ<43>")
	)
	(segment
		(start 298.0182 -19.2024)
		(end 298.0182 -21.232876)
		(width 0.14224)
		(layer "In11.Cu")
		(net "M_B_DQ<43>")
	)
	(segment
		(start 298.016676 -16.987266)
		(end 298.016676 -18.467578)
		(width 0.14224)
		(layer "In11.Cu")
		(net "M_B_DQ<43>")
	)
	(segment
		(start 297.872912 -14.426692)
		(end 297.872912 -16.843502)
		(width 0.14224)
		(layer "In11.Cu")
		(net "M_B_DQ<43>")
	)
	(segment
		(start 298.042076 -23.153116)
		(end 297.864276 -23.330916)
		(width 0.14224)
		(layer "In11.Cu")
		(net "M_B_DQ<43>")
	)
	(segment
		(start 297.90263 -12.32535)
		(end 297.549824 -12.678156)
		(width 0.14224)
		(layer "In11.Cu")
		(net "M_B_DQ<43>")
	)
	(segment
		(start 297.864276 -23.330916)
		(end 297.864276 -26.667714)
		(width 0.14224)
		(layer "In11.Cu")
		(net "M_B_DQ<43>")
	)
	(segment
		(start 297.600878 -8.0518)
		(end 298.058078 -8.509)
		(width 0.14224)
		(layer "In11.Cu")
		(net "M_B_DQ<43>")
	)
	(segment
		(start 297.864276 -21.3868)
		(end 297.864276 -21.791676)
		(width 0.14224)
		(layer "In11.Cu")
		(net "M_B_DQ<43>")
	)
	(segment
		(start 298.016676 -18.467578)
		(end 297.864276 -18.619978)
		(width 0.14224)
		(layer "In11.Cu")
		(net "M_B_DQ<43>")
	)
	(segment
		(start 298.058078 -8.509)
		(end 298.058078 -8.8646)
		(width 0.14224)
		(layer "In11.Cu")
		(net "M_B_DQ<43>")
	)
	(segment
		(start 298.0182 -21.232876)
		(end 297.864276 -21.3868)
		(width 0.14224)
		(layer "In11.Cu")
		(net "M_B_DQ<43>")
	)
	(segment
		(start 298.042076 -21.969476)
		(end 298.042076 -23.153116)
		(width 0.14224)
		(layer "In11.Cu")
		(net "M_B_DQ<43>")
	)
	(segment
		(start 296.69994 -7.086346)
		(end 297.016678 -7.403084)
		(width 0.14224)
		(layer "In11.Cu")
		(net "M_B_DQ<43>")
	)
	(segment
		(start 297.872912 -16.843502)
		(end 298.016676 -16.987266)
		(width 0.14224)
		(layer "In11.Cu")
		(net "M_B_DQ<43>")
	)
	(segment
		(start 297.016678 -7.7216)
		(end 297.346878 -8.0518)
		(width 0.14224)
		(layer "In11.Cu")
		(net "M_B_DQ<43>")
	)
	(segment
		(start 297.864276 -26.667714)
		(end 297.363134 -27.168856)
		(width 0.14224)
		(layer "In11.Cu")
		(net "M_B_DQ<43>")
	)
	(segment
		(start 297.053 -13.17498)
		(end 297.053 -13.60678)
		(width 0.14224)
		(layer "In11.Cu")
		(net "M_B_DQ<43>")
	)
	(segment
		(start 297.864276 -19.048476)
		(end 298.0182 -19.2024)
		(width 0.14224)
		(layer "In11.Cu")
		(net "M_B_DQ<43>")
	)
	(segment
		(start 297.90263 -9.020048)
		(end 297.90263 -12.32535)
		(width 0.14224)
		(layer "In11.Cu")
		(net "M_B_DQ<43>")
	)
	(segment
		(start 297.346878 -8.0518)
		(end 297.600878 -8.0518)
		(width 0.14224)
		(layer "In11.Cu")
		(net "M_B_DQ<43>")
	)
	(segment
		(start 297.053 -13.60678)
		(end 297.872912 -14.426692)
		(width 0.14224)
		(layer "In11.Cu")
		(net "M_B_DQ<43>")
	)
	(segment
		(start 297.016678 -7.403084)
		(end 297.016678 -7.7216)
		(width 0.14224)
		(layer "In11.Cu")
		(net "M_B_DQ<43>")
	)
	(segment
		(start 297.864276 -21.791676)
		(end 298.042076 -21.969476)
		(width 0.14224)
		(layer "In11.Cu")
		(net "M_B_DQ<43>")
	)
	(segment
		(start 297.549824 -12.678156)
		(end 297.053 -13.17498)
		(width 0.14224)
		(layer "In11.Cu")
		(net "M_B_DQ<43>")
	)
	(segment
		(start 297.864276 -18.619978)
		(end 297.864276 -19.048476)
		(width 0.14224)
		(layer "In11.Cu")
		(net "M_B_DQ<43>")
	)
	(segment
		(start 298.058078 -8.8646)
		(end 297.90263 -9.020048)
		(width 0.14224)
		(layer "In11.Cu")
		(net "M_B_DQ<43>")
	)
	(segment
		(start 296.48785 -30.962346)
		(end 295.8465 -30.962346)
		(width 0.1651)
		(layer "F.Cu")
		(net "M_B_DQ<42>")
	)
	(segment
		(start 288.3662 -40.1828)
		(end 290.6522 -37.8968)
		(width 0.1651)
		(layer "F.Cu")
		(net "M_B_DQ<42>")
	)
	(segment
		(start 295.6052 -32.0421)
		(end 295.7703 -31.877)
		(width 0.1651)
		(layer "F.Cu")
		(net "M_B_DQ<42>")
	)
	(segment
		(start 281.037284 -50.52822)
		(end 281.037284 -50.062384)
		(width 0.0889)
		(layer "F.Cu")
		(net "M_B_DQ<42>")
	)
	(segment
		(start 297.550332 -10.422382)
		(end 297.549824 -10.422382)
		(width 0.1651)
		(layer "F.Cu")
		(net "M_B_DQ<42>")
	)
	(segment
		(start 296.48785 -30.289246)
		(end 296.65295 -30.124146)
		(width 0.1651)
		(layer "F.Cu")
		(net "M_B_DQ<42>")
	)
	(segment
		(start 297.549824 -8.938768)
		(end 297.549824 -8.6614)
		(width 0.1651)
		(layer "F.Cu")
		(net "M_B_DQ<42>")
	)
	(segment
		(start 296.65295 -30.124146)
		(end 296.65295 -28.538678)
		(width 0.1651)
		(layer "F.Cu")
		(net "M_B_DQ<42>")
	)
	(segment
		(start 296.1767 -34.2519)
		(end 296.1767 -33.147)
		(width 0.1651)
		(layer "F.Cu")
		(net "M_B_DQ<42>")
	)
	(segment
		(start 296.1767 -32.721042)
		(end 296.0116 -32.555942)
		(width 0.1651)
		(layer "F.Cu")
		(net "M_B_DQ<42>")
	)
	(segment
		(start 287.503616 -41.605962)
		(end 288.3662 -40.743378)
		(width 0.1651)
		(layer "F.Cu")
		(net "M_B_DQ<42>")
	)
	(segment
		(start 280.773124 -48.336454)
		(end 287.503616 -41.605962)
		(width 0.1016)
		(layer "F.Cu")
		(net "M_B_DQ<42>")
	)
	(segment
		(start 281.012646 -51.570382)
		(end 281.012646 -51.270916)
		(width 0.0889)
		(layer "F.Cu")
		(net "M_B_DQ<42>")
	)
	(segment
		(start 295.6052 -32.390842)
		(end 295.6052 -32.0421)
		(width 0.1651)
		(layer "F.Cu")
		(net "M_B_DQ<42>")
	)
	(segment
		(start 295.8465 -30.962346)
		(end 295.6814 -30.797246)
		(width 0.1651)
		(layer "F.Cu")
		(net "M_B_DQ<42>")
	)
	(segment
		(start 297.681396 -9.07034)
		(end 297.549824 -8.938768)
		(width 0.1651)
		(layer "F.Cu")
		(net "M_B_DQ<42>")
	)
	(segment
		(start 292.5318 -37.8968)
		(end 296.1767 -34.2519)
		(width 0.1651)
		(layer "F.Cu")
		(net "M_B_DQ<42>")
	)
	(segment
		(start 280.904442 -50.758344)
		(end 281.037284 -50.52822)
		(width 0.0889)
		(layer "F.Cu")
		(net "M_B_DQ<42>")
	)
	(segment
		(start 297.549824 -10.422382)
		(end 297.549824 -9.425432)
		(width 0.1651)
		(layer "F.Cu")
		(net "M_B_DQ<42>")
	)
	(segment
		(start 297.549824 -9.425432)
		(end 297.681396 -9.29386)
		(width 0.1651)
		(layer "F.Cu")
		(net "M_B_DQ<42>")
	)
	(segment
		(start 295.6814 -30.797246)
		(end 295.6814 -30.454346)
		(width 0.1651)
		(layer "F.Cu")
		(net "M_B_DQ<42>")
	)
	(segment
		(start 296.65295 -31.127446)
		(end 296.48785 -30.962346)
		(width 0.1651)
		(layer "F.Cu")
		(net "M_B_DQ<42>")
	)
	(segment
		(start 280.773124 -49.798224)
		(end 280.773124 -48.336454)
		(width 0.1016)
		(layer "F.Cu")
		(net "M_B_DQ<42>")
	)
	(segment
		(start 280.904442 -51.083718)
		(end 280.904442 -50.758344)
		(width 0.0889)
		(layer "F.Cu")
		(net "M_B_DQ<42>")
	)
	(segment
		(start 296.65295 -31.7119)
		(end 296.65295 -31.127446)
		(width 0.1651)
		(layer "F.Cu")
		(net "M_B_DQ<42>")
	)
	(segment
		(start 295.7703 -31.877)
		(end 296.48785 -31.877)
		(width 0.1651)
		(layer "F.Cu")
		(net "M_B_DQ<42>")
	)
	(segment
		(start 295.6814 -30.454346)
		(end 295.8465 -30.289246)
		(width 0.1651)
		(layer "F.Cu")
		(net "M_B_DQ<42>")
	)
	(segment
		(start 296.48785 -31.877)
		(end 296.65295 -31.7119)
		(width 0.1651)
		(layer "F.Cu")
		(net "M_B_DQ<42>")
	)
	(segment
		(start 281.037284 -50.062384)
		(end 280.773124 -49.798224)
		(width 0.0889)
		(layer "F.Cu")
		(net "M_B_DQ<42>")
	)
	(segment
		(start 295.7703 -32.555942)
		(end 295.6052 -32.390842)
		(width 0.1651)
		(layer "F.Cu")
		(net "M_B_DQ<42>")
	)
	(segment
		(start 295.8465 -30.289246)
		(end 296.48785 -30.289246)
		(width 0.1651)
		(layer "F.Cu")
		(net "M_B_DQ<42>")
	)
	(segment
		(start 296.0116 -32.555942)
		(end 295.7703 -32.555942)
		(width 0.1651)
		(layer "F.Cu")
		(net "M_B_DQ<42>")
	)
	(segment
		(start 281.012646 -51.270916)
		(end 280.904442 -51.083718)
		(width 0.0889)
		(layer "F.Cu")
		(net "M_B_DQ<42>")
	)
	(segment
		(start 297.681396 -9.29386)
		(end 297.681396 -9.07034)
		(width 0.1651)
		(layer "F.Cu")
		(net "M_B_DQ<42>")
	)
	(segment
		(start 280.637234 -52.437538)
		(end 281.012646 -51.570382)
		(width 0.0889)
		(layer "F.Cu")
		(net "M_B_DQ<42>")
	)
	(segment
		(start 296.1767 -33.147)
		(end 296.1767 -32.721042)
		(width 0.1651)
		(layer "F.Cu")
		(net "M_B_DQ<42>")
	)
	(segment
		(start 288.3662 -40.743378)
		(end 288.3662 -40.1828)
		(width 0.1651)
		(layer "F.Cu")
		(net "M_B_DQ<42>")
	)
	(segment
		(start 290.6522 -37.8968)
		(end 292.5318 -37.8968)
		(width 0.1651)
		(layer "F.Cu")
		(net "M_B_DQ<42>")
	)
	(via
		(at 296.69994 -13.959078)
		(size 0.508)
		(drill 0.254)
		(layers "F.Cu" "B.Cu")
		(net "M_B_DQ<42>")
	)
	(via
		(at 296.1767 -33.147)
		(size 0.508)
		(drill 0.254)
		(layers "F.Cu" "B.Cu")
		(net "M_B_DQ<42>")
	)
	(via
		(at 296.65295 -28.538678)
		(size 0.508)
		(drill 0.254)
		(layers "F.Cu" "B.Cu")
		(net "M_B_DQ<42>")
	)
	(via
		(at 297.549824 -8.6614)
		(size 0.508)
		(drill 0.254)
		(layers "F.Cu" "B.Cu")
		(net "M_B_DQ<42>")
	)
	(segment
		(start 296.700448 -15.222982)
		(end 296.69994 -15.222982)
		(width 0.1651)
		(layer "B.Cu")
		(net "M_B_DQ<42>")
	)
	(segment
		(start 296.69994 -15.222982)
		(end 296.69994 -13.959078)
		(width 0.1651)
		(layer "B.Cu")
		(net "M_B_DQ<42>")
	)
	(segment
		(start 297.0276 -21.159724)
		(end 297.0276 -19.177)
		(width 0.14224)
		(layer "In11.Cu")
		(net "M_B_DQ<42>")
	)
	(segment
		(start 296.415206 -12.9286)
		(end 297.264074 -12.079732)
		(width 0.14224)
		(layer "In11.Cu")
		(net "M_B_DQ<42>")
	)
	(segment
		(start 297.0276 -19.177)
		(end 297.229276 -18.975324)
		(width 0.14224)
		(layer "In11.Cu")
		(net "M_B_DQ<42>")
	)
	(segment
		(start 297.198796 -14.457934)
		(end 296.69994 -13.959078)
		(width 0.14224)
		(layer "In11.Cu")
		(net "M_B_DQ<42>")
	)
	(segment
		(start 296.806874 -11.3538)
		(end 296.806874 -10.95375)
		(width 0.14224)
		(layer "In11.Cu")
		(net "M_B_DQ<42>")
	)
	(segment
		(start 296.65295 -27.19705)
		(end 297.203876 -26.646124)
		(width 0.14224)
		(layer "In11.Cu")
		(net "M_B_DQ<42>")
	)
	(segment
		(start 297.264074 -12.079732)
		(end 297.264074 -11.811)
		(width 0.14224)
		(layer "In11.Cu")
		(net "M_B_DQ<42>")
	)
	(segment
		(start 296.806874 -10.058146)
		(end 296.806874 -9.709404)
		(width 0.14224)
		(layer "In11.Cu")
		(net "M_B_DQ<42>")
	)
	(segment
		(start 296.65295 -28.538678)
		(end 296.65295 -27.19705)
		(width 0.14224)
		(layer "In11.Cu")
		(net "M_B_DQ<42>")
	)
	(segment
		(start 296.415206 -13.674344)
		(end 296.415206 -12.9286)
		(width 0.14224)
		(layer "In11.Cu")
		(net "M_B_DQ<42>")
	)
	(segment
		(start 296.69994 -13.959078)
		(end 296.415206 -13.674344)
		(width 0.14224)
		(layer "In11.Cu")
		(net "M_B_DQ<42>")
	)
	(segment
		(start 296.806874 -10.95375)
		(end 297.111674 -10.64895)
		(width 0.14224)
		(layer "In11.Cu")
		(net "M_B_DQ<42>")
	)
	(segment
		(start 297.076876 -23.208996)
		(end 297.076876 -21.938996)
		(width 0.14224)
		(layer "In11.Cu")
		(net "M_B_DQ<42>")
	)
	(segment
		(start 297.076876 -21.938996)
		(end 297.229276 -21.786596)
		(width 0.14224)
		(layer "In11.Cu")
		(net "M_B_DQ<42>")
	)
	(segment
		(start 297.203876 -23.335996)
		(end 297.076876 -23.208996)
		(width 0.14224)
		(layer "In11.Cu")
		(net "M_B_DQ<42>")
	)
	(segment
		(start 297.111674 -10.64895)
		(end 297.111674 -10.362946)
		(width 0.14224)
		(layer "In11.Cu")
		(net "M_B_DQ<42>")
	)
	(segment
		(start 297.264074 -11.811)
		(end 296.806874 -11.3538)
		(width 0.14224)
		(layer "In11.Cu")
		(net "M_B_DQ<42>")
	)
	(segment
		(start 297.229276 -18.975324)
		(end 297.229276 -18.64233)
		(width 0.14224)
		(layer "In11.Cu")
		(net "M_B_DQ<42>")
	)
	(segment
		(start 297.111674 -10.362946)
		(end 296.806874 -10.058146)
		(width 0.14224)
		(layer "In11.Cu")
		(net "M_B_DQ<42>")
	)
	(segment
		(start 297.026076 -17.083786)
		(end 297.198796 -16.911066)
		(width 0.14224)
		(layer "In11.Cu")
		(net "M_B_DQ<42>")
	)
	(segment
		(start 297.026076 -18.43913)
		(end 297.026076 -17.083786)
		(width 0.14224)
		(layer "In11.Cu")
		(net "M_B_DQ<42>")
	)
	(segment
		(start 297.229276 -21.786596)
		(end 297.229276 -21.3614)
		(width 0.14224)
		(layer "In11.Cu")
		(net "M_B_DQ<42>")
	)
	(segment
		(start 297.151806 -9.364472)
		(end 297.151806 -9.059418)
		(width 0.14224)
		(layer "In11.Cu")
		(net "M_B_DQ<42>")
	)
	(segment
		(start 297.151806 -9.059418)
		(end 297.549824 -8.6614)
		(width 0.14224)
		(layer "In11.Cu")
		(net "M_B_DQ<42>")
	)
	(segment
		(start 297.198796 -16.911066)
		(end 297.198796 -14.457934)
		(width 0.14224)
		(layer "In11.Cu")
		(net "M_B_DQ<42>")
	)
	(segment
		(start 297.203876 -26.646124)
		(end 297.203876 -23.335996)
		(width 0.14224)
		(layer "In11.Cu")
		(net "M_B_DQ<42>")
	)
	(segment
		(start 296.806874 -9.709404)
		(end 297.151806 -9.364472)
		(width 0.14224)
		(layer "In11.Cu")
		(net "M_B_DQ<42>")
	)
	(segment
		(start 297.229276 -18.64233)
		(end 297.026076 -18.43913)
		(width 0.14224)
		(layer "In11.Cu")
		(net "M_B_DQ<42>")
	)
	(segment
		(start 297.229276 -21.3614)
		(end 297.0276 -21.159724)
		(width 0.14224)
		(layer "In11.Cu")
		(net "M_B_DQ<42>")
	)
	(segment
		(start 281.7368 -43.473624)
		(end 281.7368 -41.529)
		(width 0.1016)
		(layer "F.Cu")
		(net "M_B_DQ<41>")
	)
	(segment
		(start 290.6522 -27.742896)
		(end 290.6522 -27.1272)
		(width 0.1651)
		(layer "F.Cu")
		(net "M_B_DQ<41>")
	)
	(segment
		(start 286.7406 -36.2204)
		(end 288.078926 -34.882074)
		(width 0.1651)
		(layer "F.Cu")
		(net "M_B_DQ<41>")
	)
	(segment
		(start 282.2702 -40.9956)
		(end 282.2702 -39.881048)
		(width 0.1651)
		(layer "F.Cu")
		(net "M_B_DQ<41>")
	)
	(segment
		(start 277.975822 -50.103024)
		(end 278.017224 -50.061622)
		(width 0.0889)
		(layer "F.Cu")
		(net "M_B_DQ<41>")
	)
	(segment
		(start 290.957 -30.9626)
		(end 291.338 -30.9626)
		(width 0.1651)
		(layer "F.Cu")
		(net "M_B_DQ<41>")
	)
	(segment
		(start 281.7368 -41.529)
		(end 282.2702 -40.9956)
		(width 0.1016)
		(layer "F.Cu")
		(net "M_B_DQ<41>")
	)
	(segment
		(start 290.74999 -5.822442)
		(end 290.74999 -7.086346)
		(width 0.1651)
		(layer "F.Cu")
		(net "M_B_DQ<41>")
	)
	(segment
		(start 291.256974 -25.781)
		(end 291.422074 -25.9461)
		(width 0.1651)
		(layer "F.Cu")
		(net "M_B_DQ<41>")
	)
	(segment
		(start 291.21354 -29.2608)
		(end 291.21354 -28.304236)
		(width 0.1651)
		(layer "F.Cu")
		(net "M_B_DQ<41>")
	)
	(segment
		(start 291.21354 -30.22854)
		(end 291.21354 -29.2608)
		(width 0.1651)
		(layer "F.Cu")
		(net "M_B_DQ<41>")
	)
	(segment
		(start 288.078926 -33.840674)
		(end 290.957 -30.9626)
		(width 0.1651)
		(layer "F.Cu")
		(net "M_B_DQ<41>")
	)
	(segment
		(start 291.21354 -28.304236)
		(end 290.6522 -27.742896)
		(width 0.1651)
		(layer "F.Cu")
		(net "M_B_DQ<41>")
	)
	(segment
		(start 290.2458 -26.7208)
		(end 290.2458 -26.2382)
		(width 0.1651)
		(layer "F.Cu")
		(net "M_B_DQ<41>")
	)
	(segment
		(start 285.930848 -36.2204)
		(end 286.7406 -36.2204)
		(width 0.1651)
		(layer "F.Cu")
		(net "M_B_DQ<41>")
	)
	(segment
		(start 291.338 -30.9626)
		(end 291.465 -30.8356)
		(width 0.1651)
		(layer "F.Cu")
		(net "M_B_DQ<41>")
	)
	(segment
		(start 290.6522 -27.1272)
		(end 290.2458 -26.7208)
		(width 0.1651)
		(layer "F.Cu")
		(net "M_B_DQ<41>")
	)
	(segment
		(start 282.2702 -39.881048)
		(end 285.930848 -36.2204)
		(width 0.1651)
		(layer "F.Cu")
		(net "M_B_DQ<41>")
	)
	(segment
		(start 277.975822 -51.856132)
		(end 277.975822 -50.103024)
		(width 0.0889)
		(layer "F.Cu")
		(net "M_B_DQ<41>")
	)
	(segment
		(start 290.750498 -5.822442)
		(end 290.74999 -5.822442)
		(width 0.1651)
		(layer "F.Cu")
		(net "M_B_DQ<41>")
	)
	(segment
		(start 278.061674 -51.941984)
		(end 277.975822 -51.856132)
		(width 0.0889)
		(layer "F.Cu")
		(net "M_B_DQ<41>")
	)
	(segment
		(start 290.2458 -26.2382)
		(end 290.703 -25.781)
		(width 0.1651)
		(layer "F.Cu")
		(net "M_B_DQ<41>")
	)
	(segment
		(start 278.017224 -47.1932)
		(end 281.7368 -43.473624)
		(width 0.1016)
		(layer "F.Cu")
		(net "M_B_DQ<41>")
	)
	(segment
		(start 291.422074 -25.9461)
		(end 291.422074 -27.168856)
		(width 0.1651)
		(layer "F.Cu")
		(net "M_B_DQ<41>")
	)
	(segment
		(start 278.017224 -49.959514)
		(end 278.017224 -47.1932)
		(width 0.1016)
		(layer "F.Cu")
		(net "M_B_DQ<41>")
	)
	(segment
		(start 288.078926 -34.882074)
		(end 288.078926 -33.840674)
		(width 0.1651)
		(layer "F.Cu")
		(net "M_B_DQ<41>")
	)
	(segment
		(start 291.465 -30.8356)
		(end 291.465 -30.48)
		(width 0.1651)
		(layer "F.Cu")
		(net "M_B_DQ<41>")
	)
	(segment
		(start 291.465 -30.48)
		(end 291.21354 -30.22854)
		(width 0.1651)
		(layer "F.Cu")
		(net "M_B_DQ<41>")
	)
	(segment
		(start 290.703 -25.781)
		(end 291.256974 -25.781)
		(width 0.1651)
		(layer "F.Cu")
		(net "M_B_DQ<41>")
	)
	(segment
		(start 278.017224 -50.061622)
		(end 278.017224 -49.959514)
		(width 0.0889)
		(layer "F.Cu")
		(net "M_B_DQ<41>")
	)
	(via
		(at 291.422074 -12.678156)
		(size 0.508)
		(drill 0.254)
		(layers "F.Cu" "B.Cu")
		(net "M_B_DQ<41>")
	)
	(via
		(at 291.422074 -27.168856)
		(size 0.508)
		(drill 0.254)
		(layers "F.Cu" "B.Cu")
		(net "M_B_DQ<41>")
	)
	(via
		(at 290.74999 -7.086346)
		(size 0.508)
		(drill 0.254)
		(layers "F.Cu" "B.Cu")
		(net "M_B_DQ<41>")
	)
	(via
		(at 291.21354 -29.2608)
		(size 0.508)
		(drill 0.254)
		(layers "F.Cu" "B.Cu")
		(net "M_B_DQ<41>")
	)
	(segment
		(start 291.599874 -11.997182)
		(end 291.422074 -12.174982)
		(width 0.1651)
		(layer "B.Cu")
		(net "M_B_DQ<41>")
	)
	(segment
		(start 291.600382 -10.623042)
		(end 291.599874 -10.623042)
		(width 0.1651)
		(layer "B.Cu")
		(net "M_B_DQ<41>")
	)
	(segment
		(start 291.422074 -12.174982)
		(end 291.422074 -12.678156)
		(width 0.1651)
		(layer "B.Cu")
		(net "M_B_DQ<41>")
	)
	(segment
		(start 291.599874 -10.623042)
		(end 291.599874 -11.997182)
		(width 0.1651)
		(layer "B.Cu")
		(net "M_B_DQ<41>")
	)
	(segment
		(start 291.895276 -21.3106)
		(end 292.0492 -21.156676)
		(width 0.14224)
		(layer "In11.Cu")
		(net "M_B_DQ<41>")
	)
	(segment
		(start 291.255196 -13.810996)
		(end 290.9824 -13.5382)
		(width 0.14224)
		(layer "In11.Cu")
		(net "M_B_DQ<41>")
	)
	(segment
		(start 291.227256 -8.1026)
		(end 290.74999 -7.625334)
		(width 0.14224)
		(layer "In11.Cu")
		(net "M_B_DQ<41>")
	)
	(segment
		(start 291.255196 -15.580106)
		(end 291.255196 -13.810996)
		(width 0.14224)
		(layer "In11.Cu")
		(net "M_B_DQ<41>")
	)
	(segment
		(start 292.0492 -21.156676)
		(end 292.0492 -19.1008)
		(width 0.14224)
		(layer "In11.Cu")
		(net "M_B_DQ<41>")
	)
	(segment
		(start 290.74999 -7.625334)
		(end 290.74999 -7.086346)
		(width 0.14224)
		(layer "In11.Cu")
		(net "M_B_DQ<41>")
	)
	(segment
		(start 291.895276 -16.220186)
		(end 291.255196 -15.580106)
		(width 0.14224)
		(layer "In11.Cu")
		(net "M_B_DQ<41>")
	)
	(segment
		(start 291.796216 -8.970264)
		(end 291.95268 -8.8138)
		(width 0.14224)
		(layer "In11.Cu")
		(net "M_B_DQ<41>")
	)
	(segment
		(start 291.796216 -12.304014)
		(end 291.796216 -8.970264)
		(width 0.14224)
		(layer "In11.Cu")
		(net "M_B_DQ<41>")
	)
	(segment
		(start 290.9824 -13.11783)
		(end 291.422074 -12.678156)
		(width 0.14224)
		(layer "In11.Cu")
		(net "M_B_DQ<41>")
	)
	(segment
		(start 291.422074 -12.678156)
		(end 291.796216 -12.304014)
		(width 0.14224)
		(layer "In11.Cu")
		(net "M_B_DQ<41>")
	)
	(segment
		(start 291.422074 -27.168856)
		(end 291.895276 -26.695654)
		(width 0.14224)
		(layer "In11.Cu")
		(net "M_B_DQ<41>")
	)
	(segment
		(start 291.582856 -8.1026)
		(end 291.227256 -8.1026)
		(width 0.14224)
		(layer "In11.Cu")
		(net "M_B_DQ<41>")
	)
	(segment
		(start 290.9824 -13.5382)
		(end 290.9824 -13.11783)
		(width 0.14224)
		(layer "In11.Cu")
		(net "M_B_DQ<41>")
	)
	(segment
		(start 291.95268 -8.472424)
		(end 291.582856 -8.1026)
		(width 0.14224)
		(layer "In11.Cu")
		(net "M_B_DQ<41>")
	)
	(segment
		(start 291.95268 -8.8138)
		(end 291.95268 -8.472424)
		(width 0.14224)
		(layer "In11.Cu")
		(net "M_B_DQ<41>")
	)
	(segment
		(start 291.895276 -18.946876)
		(end 291.895276 -16.220186)
		(width 0.14224)
		(layer "In11.Cu")
		(net "M_B_DQ<41>")
	)
	(segment
		(start 291.895276 -26.695654)
		(end 291.895276 -21.3106)
		(width 0.14224)
		(layer "In11.Cu")
		(net "M_B_DQ<41>")
	)
	(segment
		(start 292.0492 -19.1008)
		(end 291.895276 -18.946876)
		(width 0.14224)
		(layer "In11.Cu")
		(net "M_B_DQ<41>")
	)
	(segment
		(start 280.8478 -40.07485)
		(end 281.0129 -40.23995)
		(width 0.1651)
		(layer "F.Cu")
		(net "M_B_DQ<40>")
	)
	(segment
		(start 282.095956 -38.477952)
		(end 282.095956 -38.711632)
		(width 0.1651)
		(layer "F.Cu")
		(net "M_B_DQ<40>")
	)
	(segment
		(start 282.095956 -38.711632)
		(end 282.192222 -38.807898)
		(width 0.1651)
		(layer "F.Cu")
		(net "M_B_DQ<40>")
	)
	(segment
		(start 284.120844 -36.453064)
		(end 283.047948 -37.52596)
		(width 0.1651)
		(layer "F.Cu")
		(net "M_B_DQ<40>")
	)
	(segment
		(start 281.83205 -39.40175)
		(end 281.4828 -39.40175)
		(width 0.1651)
		(layer "F.Cu")
		(net "M_B_DQ<40>")
	)
	(segment
		(start 290.15944 -30.79496)
		(end 289.92576 -30.79496)
		(width 0.1651)
		(layer "F.Cu")
		(net "M_B_DQ<40>")
	)
	(segment
		(start 290.71189 -28.538678)
		(end 290.3982 -28.852368)
		(width 0.1651)
		(layer "F.Cu")
		(net "M_B_DQ<40>")
	)
	(segment
		(start 277.623524 -47.029878)
		(end 277.623524 -49.857914)
		(width 0.1016)
		(layer "F.Cu")
		(net "M_B_DQ<40>")
	)
	(segment
		(start 277.785322 -50.729896)
		(end 277.785322 -51.561492)
		(width 0.0889)
		(layer "F.Cu")
		(net "M_B_DQ<40>")
	)
	(segment
		(start 290.3982 -29.1846)
		(end 290.0426 -29.5402)
		(width 0.1651)
		(layer "F.Cu")
		(net "M_B_DQ<40>")
	)
	(segment
		(start 289.92576 -30.79496)
		(end 289.49904 -30.36824)
		(width 0.1651)
		(layer "F.Cu")
		(net "M_B_DQ<40>")
	)
	(segment
		(start 277.628604 -51.71821)
		(end 277.628604 -52.335938)
		(width 0.0889)
		(layer "F.Cu")
		(net "M_B_DQ<40>")
	)
	(segment
		(start 291.441378 -8.763)
		(end 291.422074 -8.5598)
		(width 0.1651)
		(layer "F.Cu")
		(net "M_B_DQ<40>")
	)
	(segment
		(start 282.668218 -38.331902)
		(end 282.571952 -38.235636)
		(width 0.1651)
		(layer "F.Cu")
		(net "M_B_DQ<40>")
	)
	(segment
		(start 283.144214 -38.089586)
		(end 282.901898 -38.331902)
		(width 0.1651)
		(layer "F.Cu")
		(net "M_B_DQ<40>")
	)
	(segment
		(start 282.338272 -38.235636)
		(end 282.095956 -38.477952)
		(width 0.1651)
		(layer "F.Cu")
		(net "M_B_DQ<40>")
	)
	(segment
		(start 282.571952 -38.235636)
		(end 282.338272 -38.235636)
		(width 0.1651)
		(layer "F.Cu")
		(net "M_B_DQ<40>")
	)
	(segment
		(start 281.3431 -41.0337)
		(end 281.3431 -43.310302)
		(width 0.1016)
		(layer "F.Cu")
		(net "M_B_DQ<40>")
	)
	(segment
		(start 283.047948 -37.75964)
		(end 283.144214 -37.855906)
		(width 0.1651)
		(layer "F.Cu")
		(net "M_B_DQ<40>")
	)
	(segment
		(start 290.0426 -29.5402)
		(end 290.0426 -29.7688)
		(width 0.1651)
		(layer "F.Cu")
		(net "M_B_DQ<40>")
	)
	(segment
		(start 289.319208 -30.36824)
		(end 289.107626 -30.579822)
		(width 0.1651)
		(layer "F.Cu")
		(net "M_B_DQ<40>")
	)
	(segment
		(start 291.599874 -10.422382)
		(end 291.45357 -8.89)
		(width 0.1651)
		(layer "F.Cu")
		(net "M_B_DQ<40>")
	)
	(segment
		(start 281.3431 -43.310302)
		(end 277.623524 -47.029878)
		(width 0.1016)
		(layer "F.Cu")
		(net "M_B_DQ<40>")
	)
	(segment
		(start 283.047948 -37.52596)
		(end 283.047948 -37.75964)
		(width 0.1651)
		(layer "F.Cu")
		(net "M_B_DQ<40>")
	)
	(segment
		(start 281.4828 -40.894)
		(end 281.3431 -41.0337)
		(width 0.1016)
		(layer "F.Cu")
		(net "M_B_DQ<40>")
	)
	(segment
		(start 281.4828 -39.40175)
		(end 281.3177 -39.56685)
		(width 0.1651)
		(layer "F.Cu")
		(net "M_B_DQ<40>")
	)
	(segment
		(start 281.0129 -40.23995)
		(end 281.3177 -40.23995)
		(width 0.1651)
		(layer "F.Cu")
		(net "M_B_DQ<40>")
	)
	(segment
		(start 277.628604 -52.335938)
		(end 277.527004 -52.437538)
		(width 0.0889)
		(layer "F.Cu")
		(net "M_B_DQ<40>")
	)
	(segment
		(start 281.3177 -40.23995)
		(end 281.4828 -40.40505)
		(width 0.1651)
		(layer "F.Cu")
		(net "M_B_DQ<40>")
	)
	(segment
		(start 289.449764 -31.504636)
		(end 287.4391 -33.5153)
		(width 0.1651)
		(layer "F.Cu")
		(net "M_B_DQ<40>")
	)
	(segment
		(start 277.527004 -52.437538)
		(end 277.203154 -52.437538)
		(width 0.0889)
		(layer "F.Cu")
		(net "M_B_DQ<40>")
	)
	(segment
		(start 284.993334 -35.580574)
		(end 284.120844 -36.453064)
		(width 0.1651)
		(layer "F.Cu")
		(net "M_B_DQ<40>")
	)
	(segment
		(start 289.449764 -31.270956)
		(end 289.449764 -31.504636)
		(width 0.1651)
		(layer "F.Cu")
		(net "M_B_DQ<40>")
	)
	(segment
		(start 289.107626 -30.579822)
		(end 289.107626 -30.928818)
		(width 0.1651)
		(layer "F.Cu")
		(net "M_B_DQ<40>")
	)
	(segment
		(start 290.0426 -29.7688)
		(end 290.524184 -30.250384)
		(width 0.1651)
		(layer "F.Cu")
		(net "M_B_DQ<40>")
	)
	(segment
		(start 283.144214 -37.855906)
		(end 283.144214 -38.089586)
		(width 0.1651)
		(layer "F.Cu")
		(net "M_B_DQ<40>")
	)
	(segment
		(start 282.901898 -38.331902)
		(end 282.668218 -38.331902)
		(width 0.1651)
		(layer "F.Cu")
		(net "M_B_DQ<40>")
	)
	(segment
		(start 291.45357 -8.89)
		(end 291.441378 -8.763)
		(width 0.1651)
		(layer "F.Cu")
		(net "M_B_DQ<40>")
	)
	(segment
		(start 277.623524 -50.568098)
		(end 277.785322 -50.729896)
		(width 0.0889)
		(layer "F.Cu")
		(net "M_B_DQ<40>")
	)
	(segment
		(start 277.785322 -51.561492)
		(end 277.628604 -51.71821)
		(width 0.0889)
		(layer "F.Cu")
		(net "M_B_DQ<40>")
	)
	(segment
		(start 282.192222 -38.807898)
		(end 282.192222 -39.041578)
		(width 0.1651)
		(layer "F.Cu")
		(net "M_B_DQ<40>")
	)
	(segment
		(start 290.3982 -28.852368)
		(end 290.3982 -29.1846)
		(width 0.1651)
		(layer "F.Cu")
		(net "M_B_DQ<40>")
	)
	(segment
		(start 282.192222 -39.041578)
		(end 281.83205 -39.40175)
		(width 0.1651)
		(layer "F.Cu")
		(net "M_B_DQ<40>")
	)
	(segment
		(start 281.0129 -39.56685)
		(end 280.8478 -39.73195)
		(width 0.1651)
		(layer "F.Cu")
		(net "M_B_DQ<40>")
	)
	(segment
		(start 291.600382 -10.422382)
		(end 291.599874 -10.422382)
		(width 0.1651)
		(layer "F.Cu")
		(net "M_B_DQ<40>")
	)
	(segment
		(start 290.524184 -30.250384)
		(end 290.524184 -30.430216)
		(width 0.1651)
		(layer "F.Cu")
		(net "M_B_DQ<40>")
	)
	(segment
		(start 281.4828 -40.40505)
		(end 281.4828 -40.894)
		(width 0.1651)
		(layer "F.Cu")
		(net "M_B_DQ<40>")
	)
	(segment
		(start 290.524184 -30.430216)
		(end 290.15944 -30.79496)
		(width 0.1651)
		(layer "F.Cu")
		(net "M_B_DQ<40>")
	)
	(segment
		(start 280.8478 -39.73195)
		(end 280.8478 -40.07485)
		(width 0.1651)
		(layer "F.Cu")
		(net "M_B_DQ<40>")
	)
	(segment
		(start 289.107626 -30.928818)
		(end 289.449764 -31.270956)
		(width 0.1651)
		(layer "F.Cu")
		(net "M_B_DQ<40>")
	)
	(segment
		(start 289.49904 -30.36824)
		(end 289.319208 -30.36824)
		(width 0.1651)
		(layer "F.Cu")
		(net "M_B_DQ<40>")
	)
	(segment
		(start 286.440626 -35.580574)
		(end 284.993334 -35.580574)
		(width 0.1651)
		(layer "F.Cu")
		(net "M_B_DQ<40>")
	)
	(segment
		(start 281.3177 -39.56685)
		(end 281.0129 -39.56685)
		(width 0.1651)
		(layer "F.Cu")
		(net "M_B_DQ<40>")
	)
	(segment
		(start 287.4391 -34.5821)
		(end 286.440626 -35.580574)
		(width 0.1651)
		(layer "F.Cu")
		(net "M_B_DQ<40>")
	)
	(segment
		(start 287.4391 -33.5153)
		(end 287.4391 -34.5821)
		(width 0.1651)
		(layer "F.Cu")
		(net "M_B_DQ<40>")
	)
	(segment
		(start 277.623524 -49.857914)
		(end 277.623524 -50.568098)
		(width 0.0889)
		(layer "F.Cu")
		(net "M_B_DQ<40>")
	)
	(via
		(at 291.422074 -8.5598)
		(size 0.508)
		(drill 0.254)
		(layers "F.Cu" "B.Cu")
		(net "M_B_DQ<40>")
	)
	(via
		(at 290.74999 -13.959078)
		(size 0.508)
		(drill 0.254)
		(layers "F.Cu" "B.Cu")
		(net "M_B_DQ<40>")
	)
	(via
		(at 290.71189 -28.538678)
		(size 0.508)
		(drill 0.254)
		(layers "F.Cu" "B.Cu")
		(net "M_B_DQ<40>")
	)
	(via
		(at 284.120844 -36.453064)
		(size 0.508)
		(drill 0.254)
		(layers "F.Cu" "B.Cu")
		(net "M_B_DQ<40>")
	)
	(segment
		(start 290.74999 -15.222982)
		(end 290.74999 -13.959078)
		(width 0.1651)
		(layer "B.Cu")
		(net "M_B_DQ<40>")
	)
	(segment
		(start 290.750498 -15.222982)
		(end 290.74999 -15.222982)
		(width 0.1651)
		(layer "B.Cu")
		(net "M_B_DQ<40>")
	)
	(segment
		(start 290.853876 -23.036276)
		(end 291.209476 -23.391876)
		(width 0.14224)
		(layer "In11.Cu")
		(net "M_B_DQ<40>")
	)
	(segment
		(start 290.74999 -13.959078)
		(end 290.74999 -15.91818)
		(width 0.14224)
		(layer "In11.Cu")
		(net "M_B_DQ<40>")
	)
	(segment
		(start 290.812474 -11.302746)
		(end 291.201856 -11.692128)
		(width 0.14224)
		(layer "In11.Cu")
		(net "M_B_DQ<40>")
	)
	(segment
		(start 291.209476 -18.59153)
		(end 291.209476 -19.026124)
		(width 0.14224)
		(layer "In11.Cu")
		(net "M_B_DQ<40>")
	)
	(segment
		(start 291.201856 -9.364472)
		(end 290.787074 -9.779254)
		(width 0.14224)
		(layer "In11.Cu")
		(net "M_B_DQ<40>")
	)
	(segment
		(start 291.201856 -8.780018)
		(end 291.201856 -9.364472)
		(width 0.14224)
		(layer "In11.Cu")
		(net "M_B_DQ<40>")
	)
	(segment
		(start 291.201856 -11.692128)
		(end 291.201856 -12.192)
		(width 0.14224)
		(layer "In11.Cu")
		(net "M_B_DQ<40>")
	)
	(segment
		(start 291.234876 -16.816578)
		(end 290.955476 -17.095978)
		(width 0.14224)
		(layer "In11.Cu")
		(net "M_B_DQ<40>")
	)
	(segment
		(start 291.422074 -8.5598)
		(end 291.201856 -8.780018)
		(width 0.14224)
		(layer "In11.Cu")
		(net "M_B_DQ<40>")
	)
	(segment
		(start 290.853876 -22.065996)
		(end 290.853876 -23.036276)
		(width 0.14224)
		(layer "In11.Cu")
		(net "M_B_DQ<40>")
	)
	(segment
		(start 290.955476 -17.095978)
		(end 290.955476 -18.33753)
		(width 0.14224)
		(layer "In11.Cu")
		(net "M_B_DQ<40>")
	)
	(segment
		(start 291.201856 -12.192)
		(end 290.465256 -12.9286)
		(width 0.14224)
		(layer "In11.Cu")
		(net "M_B_DQ<40>")
	)
	(segment
		(start 290.74999 -28.500578)
		(end 290.71189 -28.538678)
		(width 0.14224)
		(layer "In11.Cu")
		(net "M_B_DQ<40>")
	)
	(segment
		(start 291.234876 -16.403066)
		(end 291.234876 -16.816578)
		(width 0.14224)
		(layer "In11.Cu")
		(net "M_B_DQ<40>")
	)
	(segment
		(start 290.812474 -10.9982)
		(end 290.812474 -11.302746)
		(width 0.14224)
		(layer "In11.Cu")
		(net "M_B_DQ<40>")
	)
	(segment
		(start 290.465256 -13.674344)
		(end 290.74999 -13.959078)
		(width 0.14224)
		(layer "In11.Cu")
		(net "M_B_DQ<40>")
	)
	(segment
		(start 291.1348 -21.261324)
		(end 291.209476 -21.336)
		(width 0.14224)
		(layer "In11.Cu")
		(net "M_B_DQ<40>")
	)
	(segment
		(start 290.955476 -18.33753)
		(end 291.209476 -18.59153)
		(width 0.14224)
		(layer "In11.Cu")
		(net "M_B_DQ<40>")
	)
	(segment
		(start 291.209476 -19.026124)
		(end 291.1348 -19.1008)
		(width 0.14224)
		(layer "In11.Cu")
		(net "M_B_DQ<40>")
	)
	(segment
		(start 291.209476 -21.710396)
		(end 290.853876 -22.065996)
		(width 0.14224)
		(layer "In11.Cu")
		(net "M_B_DQ<40>")
	)
	(segment
		(start 291.209476 -23.391876)
		(end 291.209476 -26.696924)
		(width 0.14224)
		(layer "In11.Cu")
		(net "M_B_DQ<40>")
	)
	(segment
		(start 290.74999 -27.15641)
		(end 290.74999 -28.500578)
		(width 0.14224)
		(layer "In11.Cu")
		(net "M_B_DQ<40>")
	)
	(segment
		(start 291.209476 -26.696924)
		(end 290.74999 -27.15641)
		(width 0.14224)
		(layer "In11.Cu")
		(net "M_B_DQ<40>")
	)
	(segment
		(start 290.787074 -9.779254)
		(end 290.787074 -10.1092)
		(width 0.14224)
		(layer "In11.Cu")
		(net "M_B_DQ<40>")
	)
	(segment
		(start 291.129974 -10.4521)
		(end 291.129974 -10.6807)
		(width 0.14224)
		(layer "In11.Cu")
		(net "M_B_DQ<40>")
	)
	(segment
		(start 291.1348 -19.1008)
		(end 291.1348 -21.261324)
		(width 0.14224)
		(layer "In11.Cu")
		(net "M_B_DQ<40>")
	)
	(segment
		(start 290.74999 -15.91818)
		(end 291.234876 -16.403066)
		(width 0.14224)
		(layer "In11.Cu")
		(net "M_B_DQ<40>")
	)
	(segment
		(start 291.209476 -21.336)
		(end 291.209476 -21.710396)
		(width 0.14224)
		(layer "In11.Cu")
		(net "M_B_DQ<40>")
	)
	(segment
		(start 290.465256 -12.9286)
		(end 290.465256 -13.674344)
		(width 0.14224)
		(layer "In11.Cu")
		(net "M_B_DQ<40>")
	)
	(segment
		(start 291.129974 -10.6807)
		(end 290.812474 -10.9982)
		(width 0.14224)
		(layer "In11.Cu")
		(net "M_B_DQ<40>")
	)
	(segment
		(start 290.787074 -10.1092)
		(end 291.129974 -10.4521)
		(width 0.14224)
		(layer "In11.Cu")
		(net "M_B_DQ<40>")
	)
	(segment
		(start 204.050392 -5.822442)
		(end 204.049884 -5.822442)
		(width 0.1651)
		(layer "F.Cu")
		(net "M_B_DQ<3>")
	)
	(segment
		(start 237.042198 -65.000886)
		(end 236.470698 -65.000886)
		(width 0.0889)
		(layer "F.Cu")
		(net "M_B_DQ<3>")
	)
	(segment
		(start 204.049884 -5.822442)
		(end 204.049884 -7.086346)
		(width 0.1651)
		(layer "F.Cu")
		(net "M_B_DQ<3>")
	)
	(via
		(at 204.049884 -7.086346)
		(size 0.508)
		(drill 0.254)
		(layers "F.Cu" "B.Cu")
		(net "M_B_DQ<3>")
	)
	(via
		(at 236.470698 -65.000886)
		(size 0.508)
		(drill 0.254)
		(layers "F.Cu" "B.Cu")
		(net "M_B_DQ<3>")
	)
	(via
		(at 204.899768 -12.678156)
		(size 0.508)
		(drill 0.254)
		(layers "F.Cu" "B.Cu")
		(net "M_B_DQ<3>")
	)
	(segment
		(start 204.900276 -10.623042)
		(end 204.899768 -10.623042)
		(width 0.1651)
		(layer "B.Cu")
		(net "M_B_DQ<3>")
	)
	(segment
		(start 204.899768 -10.623042)
		(end 204.899768 -12.678156)
		(width 0.1651)
		(layer "B.Cu")
		(net "M_B_DQ<3>")
	)
	(segment
		(start 206.8195 -30.207712)
		(end 206.8195 -30.560772)
		(width 0.14224)
		(layer "In4.Cu")
		(net "M_B_DQ<3>")
	)
	(segment
		(start 204.696822 -8.0518)
		(end 204.950822 -8.0518)
		(width 0.14224)
		(layer "In4.Cu")
		(net "M_B_DQ<3>")
	)
	(segment
		(start 205.71206 -26.046684)
		(end 205.867 -26.201624)
		(width 0.14224)
		(layer "In4.Cu")
		(net "M_B_DQ<3>")
	)
	(segment
		(start 206.66456 -29.389832)
		(end 205.55204 -29.389832)
		(width 0.14224)
		(layer "In4.Cu")
		(net "M_B_DQ<3>")
	)
	(segment
		(start 205.52156 -25.383744)
		(end 204.90434 -25.383744)
		(width 0.14224)
		(layer "In4.Cu")
		(net "M_B_DQ<3>")
	)
	(segment
		(start 205.55204 -30.715712)
		(end 205.3971 -30.870652)
		(width 0.14224)
		(layer "In4.Cu")
		(net "M_B_DQ<3>")
	)
	(segment
		(start 205.406752 -18.417794)
		(end 205.254352 -18.570194)
		(width 0.14224)
		(layer "In4.Cu")
		(net "M_B_DQ<3>")
	)
	(segment
		(start 205.994 -28.39085)
		(end 206.534004 -28.39085)
		(width 0.14224)
		(layer "In4.Cu")
		(net "M_B_DQ<3>")
	)
	(segment
		(start 205.867 -26.554684)
		(end 205.71206 -26.709624)
		(width 0.14224)
		(layer "In4.Cu")
		(net "M_B_DQ<3>")
	)
	(segment
		(start 206.66456 -30.715712)
		(end 205.55204 -30.715712)
		(width 0.14224)
		(layer "In4.Cu")
		(net "M_B_DQ<3>")
	)
	(segment
		(start 205.6765 -24.816054)
		(end 205.6765 -25.228804)
		(width 0.14224)
		(layer "In4.Cu")
		(net "M_B_DQ<3>")
	)
	(segment
		(start 205.3971 -29.544772)
		(end 205.3971 -29.897832)
		(width 0.14224)
		(layer "In4.Cu")
		(net "M_B_DQ<3>")
	)
	(segment
		(start 205.71206 -27.372564)
		(end 205.867 -27.527504)
		(width 0.14224)
		(layer "In4.Cu")
		(net "M_B_DQ<3>")
	)
	(segment
		(start 204.366622 -7.7216)
		(end 204.696822 -8.0518)
		(width 0.14224)
		(layer "In4.Cu")
		(net "M_B_DQ<3>")
	)
	(segment
		(start 205.55204 -30.052772)
		(end 206.66456 -30.052772)
		(width 0.14224)
		(layer "In4.Cu")
		(net "M_B_DQ<3>")
	)
	(segment
		(start 235.648246 -65.09639)
		(end 236.470698 -65.000886)
		(width 0.0889)
		(layer "In4.Cu")
		(net "M_B_DQ<3>")
	)
	(segment
		(start 206.8195 -30.560772)
		(end 206.66456 -30.715712)
		(width 0.14224)
		(layer "In4.Cu")
		(net "M_B_DQ<3>")
	)
	(segment
		(start 205.3971 -31.223712)
		(end 205.55204 -31.378652)
		(width 0.14224)
		(layer "In4.Cu")
		(net "M_B_DQ<3>")
	)
	(segment
		(start 205.267052 -23.283672)
		(end 205.267052 -24.406606)
		(width 0.14224)
		(layer "In4.Cu")
		(net "M_B_DQ<3>")
	)
	(segment
		(start 205.408022 -8.509)
		(end 205.408022 -8.8646)
		(width 0.14224)
		(layer "In4.Cu")
		(net "M_B_DQ<3>")
	)
	(segment
		(start 204.90434 -27.372564)
		(end 205.71206 -27.372564)
		(width 0.14224)
		(layer "In4.Cu")
		(net "M_B_DQ<3>")
	)
	(segment
		(start 205.254352 -18.570194)
		(end 205.254352 -21.823172)
		(width 0.14224)
		(layer "In4.Cu")
		(net "M_B_DQ<3>")
	)
	(segment
		(start 234.738672 -65.400936)
		(end 234.869482 -65.400936)
		(width 0.0889)
		(layer "In4.Cu")
		(net "M_B_DQ<3>")
	)
	(segment
		(start 205.267052 -14.419072)
		(end 205.267052 -16.891762)
		(width 0.14224)
		(layer "In4.Cu")
		(net "M_B_DQ<3>")
	)
	(segment
		(start 204.950822 -8.0518)
		(end 205.408022 -8.509)
		(width 0.14224)
		(layer "In4.Cu")
		(net "M_B_DQ<3>")
	)
	(segment
		(start 226.4918 -56.5277)
		(end 226.4918 -57.747916)
		(width 0.14224)
		(layer "In4.Cu")
		(net "M_B_DQ<3>")
	)
	(segment
		(start 231.56672 -63.91529)
		(end 232.305098 -63.91529)
		(width 0.0889)
		(layer "In4.Cu")
		(net "M_B_DQ<3>")
	)
	(segment
		(start 205.432152 -22.000972)
		(end 205.432152 -23.118572)
		(width 0.14224)
		(layer "In4.Cu")
		(net "M_B_DQ<3>")
	)
	(segment
		(start 204.7494 -25.891744)
		(end 204.90434 -26.046684)
		(width 0.14224)
		(layer "In4.Cu")
		(net "M_B_DQ<3>")
	)
	(segment
		(start 205.867 -27.527504)
		(end 205.867 -28.26385)
		(width 0.14224)
		(layer "In4.Cu")
		(net "M_B_DQ<3>")
	)
	(segment
		(start 205.55204 -31.378652)
		(end 206.66456 -31.378652)
		(width 0.14224)
		(layer "In4.Cu")
		(net "M_B_DQ<3>")
	)
	(segment
		(start 230.636318 -61.892434)
		(end 230.636318 -62.194948)
		(width 0.0889)
		(layer "In4.Cu")
		(net "M_B_DQ<3>")
	)
	(segment
		(start 205.55204 -32.704532)
		(end 206.66456 -32.704532)
		(width 0.14224)
		(layer "In4.Cu")
		(net "M_B_DQ<3>")
	)
	(segment
		(start 206.66456 -31.378652)
		(end 206.8195 -31.533592)
		(width 0.14224)
		(layer "In4.Cu")
		(net "M_B_DQ<3>")
	)
	(segment
		(start 204.90434 -25.383744)
		(end 204.7494 -25.538684)
		(width 0.14224)
		(layer "In4.Cu")
		(net "M_B_DQ<3>")
	)
	(segment
		(start 206.66456 -30.052772)
		(end 206.8195 -30.207712)
		(width 0.14224)
		(layer "In4.Cu")
		(net "M_B_DQ<3>")
	)
	(segment
		(start 205.55204 -29.389832)
		(end 205.3971 -29.544772)
		(width 0.14224)
		(layer "In4.Cu")
		(net "M_B_DQ<3>")
	)
	(segment
		(start 230.636318 -62.194948)
		(end 230.811324 -62.369954)
		(width 0.0889)
		(layer "In4.Cu")
		(net "M_B_DQ<3>")
	)
	(segment
		(start 205.867 -26.201624)
		(end 205.867 -26.554684)
		(width 0.14224)
		(layer "In4.Cu")
		(net "M_B_DQ<3>")
	)
	(segment
		(start 205.406752 -17.031462)
		(end 205.406752 -18.417794)
		(width 0.14224)
		(layer "In4.Cu")
		(net "M_B_DQ<3>")
	)
	(segment
		(start 206.66456 -32.041592)
		(end 205.55204 -32.041592)
		(width 0.14224)
		(layer "In4.Cu")
		(net "M_B_DQ<3>")
	)
	(segment
		(start 206.8195 -32.859472)
		(end 206.8195 -36.8554)
		(width 0.14224)
		(layer "In4.Cu")
		(net "M_B_DQ<3>")
	)
	(segment
		(start 204.7494 -27.217624)
		(end 204.90434 -27.372564)
		(width 0.14224)
		(layer "In4.Cu")
		(net "M_B_DQ<3>")
	)
	(segment
		(start 206.8195 -31.533592)
		(end 206.8195 -31.886652)
		(width 0.14224)
		(layer "In4.Cu")
		(net "M_B_DQ<3>")
	)
	(segment
		(start 205.867 -28.26385)
		(end 205.994 -28.39085)
		(width 0.14224)
		(layer "In4.Cu")
		(net "M_B_DQ<3>")
	)
	(segment
		(start 206.8195 -28.676346)
		(end 206.8195 -29.234892)
		(width 0.14224)
		(layer "In4.Cu")
		(net "M_B_DQ<3>")
	)
	(segment
		(start 205.6765 -25.228804)
		(end 205.52156 -25.383744)
		(width 0.14224)
		(layer "In4.Cu")
		(net "M_B_DQ<3>")
	)
	(segment
		(start 206.66456 -32.704532)
		(end 206.8195 -32.859472)
		(width 0.14224)
		(layer "In4.Cu")
		(net "M_B_DQ<3>")
	)
	(segment
		(start 205.267052 -16.891762)
		(end 205.406752 -17.031462)
		(width 0.14224)
		(layer "In4.Cu")
		(net "M_B_DQ<3>")
	)
	(segment
		(start 205.432152 -23.118572)
		(end 205.267052 -23.283672)
		(width 0.14224)
		(layer "In4.Cu")
		(net "M_B_DQ<3>")
	)
	(segment
		(start 235.597192 -65.09639)
		(end 235.648246 -65.09639)
		(width 0.0889)
		(layer "In4.Cu")
		(net "M_B_DQ<3>")
	)
	(segment
		(start 232.86974 -64.410336)
		(end 233.054398 -64.410336)
		(width 0.0889)
		(layer "In4.Cu")
		(net "M_B_DQ<3>")
	)
	(segment
		(start 204.366622 -7.403084)
		(end 204.366622 -7.7216)
		(width 0.14224)
		(layer "In4.Cu")
		(net "M_B_DQ<3>")
	)
	(segment
		(start 205.71206 -26.709624)
		(end 204.90434 -26.709624)
		(width 0.14224)
		(layer "In4.Cu")
		(net "M_B_DQ<3>")
	)
	(segment
		(start 205.267052 -24.406606)
		(end 205.6765 -24.816054)
		(width 0.14224)
		(layer "In4.Cu")
		(net "M_B_DQ<3>")
	)
	(segment
		(start 230.811324 -63.159894)
		(end 231.56672 -63.91529)
		(width 0.0889)
		(layer "In4.Cu")
		(net "M_B_DQ<3>")
	)
	(segment
		(start 206.8195 -36.8554)
		(end 226.4918 -56.5277)
		(width 0.14224)
		(layer "In4.Cu")
		(net "M_B_DQ<3>")
	)
	(segment
		(start 205.252574 -9.020048)
		(end 205.252574 -12.32535)
		(width 0.14224)
		(layer "In4.Cu")
		(net "M_B_DQ<3>")
	)
	(segment
		(start 205.55204 -32.041592)
		(end 205.3971 -32.196532)
		(width 0.14224)
		(layer "In4.Cu")
		(net "M_B_DQ<3>")
	)
	(segment
		(start 205.3971 -32.196532)
		(end 205.3971 -32.549592)
		(width 0.14224)
		(layer "In4.Cu")
		(net "M_B_DQ<3>")
	)
	(segment
		(start 205.408022 -8.8646)
		(end 205.252574 -9.020048)
		(width 0.14224)
		(layer "In4.Cu")
		(net "M_B_DQ<3>")
	)
	(segment
		(start 233.883962 -64.90589)
		(end 233.916728 -64.90589)
		(width 0.0889)
		(layer "In4.Cu")
		(net "M_B_DQ<3>")
	)
	(segment
		(start 204.899768 -12.678156)
		(end 204.416152 -13.161772)
		(width 0.14224)
		(layer "In4.Cu")
		(net "M_B_DQ<3>")
	)
	(segment
		(start 230.811324 -62.369954)
		(end 230.811324 -63.159894)
		(width 0.0889)
		(layer "In4.Cu")
		(net "M_B_DQ<3>")
	)
	(segment
		(start 205.3971 -30.870652)
		(end 205.3971 -31.223712)
		(width 0.14224)
		(layer "In4.Cu")
		(net "M_B_DQ<3>")
	)
	(segment
		(start 205.3971 -32.549592)
		(end 205.55204 -32.704532)
		(width 0.14224)
		(layer "In4.Cu")
		(net "M_B_DQ<3>")
	)
	(segment
		(start 204.416152 -13.568172)
		(end 205.267052 -14.419072)
		(width 0.14224)
		(layer "In4.Cu")
		(net "M_B_DQ<3>")
	)
	(segment
		(start 206.8195 -29.234892)
		(end 206.66456 -29.389832)
		(width 0.14224)
		(layer "In4.Cu")
		(net "M_B_DQ<3>")
	)
	(segment
		(start 205.252574 -12.32535)
		(end 204.899768 -12.678156)
		(width 0.14224)
		(layer "In4.Cu")
		(net "M_B_DQ<3>")
	)
	(segment
		(start 204.7494 -26.864564)
		(end 204.7494 -27.217624)
		(width 0.14224)
		(layer "In4.Cu")
		(net "M_B_DQ<3>")
	)
	(segment
		(start 204.416152 -13.161772)
		(end 204.416152 -13.568172)
		(width 0.14224)
		(layer "In4.Cu")
		(net "M_B_DQ<3>")
	)
	(segment
		(start 226.4918 -57.747916)
		(end 230.636318 -61.892434)
		(width 0.14224)
		(layer "In4.Cu")
		(net "M_B_DQ<3>")
	)
	(segment
		(start 204.7494 -25.538684)
		(end 204.7494 -25.891744)
		(width 0.14224)
		(layer "In4.Cu")
		(net "M_B_DQ<3>")
	)
	(segment
		(start 205.3971 -29.897832)
		(end 205.55204 -30.052772)
		(width 0.14224)
		(layer "In4.Cu")
		(net "M_B_DQ<3>")
	)
	(segment
		(start 204.049884 -7.086346)
		(end 204.366622 -7.403084)
		(width 0.14224)
		(layer "In4.Cu")
		(net "M_B_DQ<3>")
	)
	(segment
		(start 206.8195 -31.886652)
		(end 206.66456 -32.041592)
		(width 0.14224)
		(layer "In4.Cu")
		(net "M_B_DQ<3>")
	)
	(segment
		(start 206.534004 -28.39085)
		(end 206.8195 -28.676346)
		(width 0.14224)
		(layer "In4.Cu")
		(net "M_B_DQ<3>")
	)
	(segment
		(start 204.90434 -26.046684)
		(end 205.71206 -26.046684)
		(width 0.14224)
		(layer "In4.Cu")
		(net "M_B_DQ<3>")
	)
	(segment
		(start 204.90434 -26.709624)
		(end 204.7494 -26.864564)
		(width 0.14224)
		(layer "In4.Cu")
		(net "M_B_DQ<3>")
	)
	(segment
		(start 205.254352 -21.823172)
		(end 205.432152 -22.000972)
		(width 0.14224)
		(layer "In4.Cu")
		(net "M_B_DQ<3>")
	)
	(arc
		(start 233.548428 -64.705738)
		(mid 233.690111 -64.849542)
		(end 233.883962 -64.90589)
		(width 0.0889)
		(layer "In4.Cu")
		(net "M_B_DQ<3>")
	)
	(arc
		(start 233.054398 -64.410336)
		(mid 233.339822 -64.493803)
		(end 233.548428 -64.705738)
		(width 0.0889)
		(layer "In4.Cu")
		(net "M_B_DQ<3>")
	)
	(arc
		(start 234.406948 -65.201038)
		(mid 234.547027 -65.343774)
		(end 234.738672 -65.400936)
		(width 0.0889)
		(layer "In4.Cu")
		(net "M_B_DQ<3>")
	)
	(arc
		(start 233.916728 -64.90589)
		(mid 234.199945 -64.990171)
		(end 234.406948 -65.201038)
		(width 0.0889)
		(layer "In4.Cu")
		(net "M_B_DQ<3>")
	)
	(arc
		(start 234.869482 -65.400936)
		(mid 235.12104 -65.350898)
		(end 235.334302 -65.208404)
		(width 0.0889)
		(layer "In4.Cu")
		(net "M_B_DQ<3>")
	)
	(arc
		(start 232.653586 -64.213232)
		(mid 232.74453 -64.330575)
		(end 232.86974 -64.410336)
		(width 0.0889)
		(layer "In4.Cu")
		(net "M_B_DQ<3>")
	)
	(arc
		(start 232.305098 -63.91529)
		(mid 232.507692 -64.031108)
		(end 232.653586 -64.213232)
		(width 0.0889)
		(layer "In4.Cu")
		(net "M_B_DQ<3>")
	)
	(arc
		(start 235.334302 -65.208404)
		(mid 235.455406 -65.128114)
		(end 235.597192 -65.09639)
		(width 0.0889)
		(layer "In4.Cu")
		(net "M_B_DQ<3>")
	)
	(segment
		(start 272.910808 -57.885584)
		(end 272.339308 -57.885584)
		(width 0.1016)
		(layer "F.Cu")
		(net "M_B_DQ<39>")
	)
	(segment
		(start 285.650432 -5.822442)
		(end 285.649924 -5.822442)
		(width 0.1651)
		(layer "F.Cu")
		(net "M_B_DQ<39>")
	)
	(segment
		(start 285.649924 -5.822442)
		(end 285.649924 -7.086346)
		(width 0.1651)
		(layer "F.Cu")
		(net "M_B_DQ<39>")
	)
	(via
		(at 285.649924 -7.086346)
		(size 0.508)
		(drill 0.254)
		(layers "F.Cu" "B.Cu")
		(net "M_B_DQ<39>")
	)
	(via
		(at 272.339308 -57.885584)
		(size 0.508)
		(drill 0.254)
		(layers "F.Cu" "B.Cu")
		(net "M_B_DQ<39>")
	)
	(via
		(at 286.499808 -12.678156)
		(size 0.508)
		(drill 0.254)
		(layers "F.Cu" "B.Cu")
		(net "M_B_DQ<39>")
	)
	(segment
		(start 286.500316 -10.623042)
		(end 286.499808 -10.623042)
		(width 0.1651)
		(layer "B.Cu")
		(net "M_B_DQ<39>")
	)
	(segment
		(start 286.499808 -10.623042)
		(end 286.499808 -12.678156)
		(width 0.1651)
		(layer "B.Cu")
		(net "M_B_DQ<39>")
	)
	(segment
		(start 286.852614 -12.32535)
		(end 286.852614 -9.020048)
		(width 0.14224)
		(layer "In4.Cu")
		(net "M_B_DQ<39>")
	)
	(segment
		(start 274.235164 -51.864768)
		(end 274.235164 -49.708054)
		(width 0.0889)
		(layer "In4.Cu")
		(net "M_B_DQ<39>")
	)
	(segment
		(start 287.008062 -8.8646)
		(end 287.008062 -8.509)
		(width 0.14224)
		(layer "In4.Cu")
		(net "M_B_DQ<39>")
	)
	(segment
		(start 286.512 -24.384)
		(end 286.892746 -24.003254)
		(width 0.14224)
		(layer "In4.Cu")
		(net "M_B_DQ<39>")
	)
	(segment
		(start 286.408114 -14.155928)
		(end 286.408114 -14.01064)
		(width 0.14224)
		(layer "In4.Cu")
		(net "M_B_DQ<39>")
	)
	(segment
		(start 286.014414 -13.16355)
		(end 286.499808 -12.678156)
		(width 0.14224)
		(layer "In4.Cu")
		(net "M_B_DQ<39>")
	)
	(segment
		(start 274.517612 -48.126142)
		(end 276.040596 -46.603158)
		(width 0.0889)
		(layer "In4.Cu")
		(net "M_B_DQ<39>")
	)
	(segment
		(start 273.882358 -52.217574)
		(end 274.235164 -51.864768)
		(width 0.0889)
		(layer "In4.Cu")
		(net "M_B_DQ<39>")
	)
	(segment
		(start 272.339308 -57.885838)
		(end 272.834608 -57.219342)
		(width 0.0889)
		(layer "In4.Cu")
		(net "M_B_DQ<39>")
	)
	(segment
		(start 287.081214 -17.082262)
		(end 286.892746 -16.893794)
		(width 0.14224)
		(layer "In4.Cu")
		(net "M_B_DQ<39>")
	)
	(segment
		(start 285.966662 -7.7216)
		(end 285.966662 -7.403084)
		(width 0.14224)
		(layer "In4.Cu")
		(net "M_B_DQ<39>")
	)
	(segment
		(start 274.517612 -49.425606)
		(end 274.517612 -48.126142)
		(width 0.0889)
		(layer "In4.Cu")
		(net "M_B_DQ<39>")
	)
	(segment
		(start 286.892746 -14.64056)
		(end 286.408114 -14.155928)
		(width 0.14224)
		(layer "In4.Cu")
		(net "M_B_DQ<39>")
	)
	(segment
		(start 273.709638 -53.722524)
		(end 273.882358 -53.423058)
		(width 0.0889)
		(layer "In4.Cu")
		(net "M_B_DQ<39>")
	)
	(segment
		(start 287.055814 -21.975572)
		(end 286.852614 -21.772372)
		(width 0.14224)
		(layer "In4.Cu")
		(net "M_B_DQ<39>")
	)
	(segment
		(start 286.499808 -12.678156)
		(end 286.852614 -12.32535)
		(width 0.14224)
		(layer "In4.Cu")
		(net "M_B_DQ<39>")
	)
	(segment
		(start 286.408114 -14.01064)
		(end 286.014414 -13.61694)
		(width 0.14224)
		(layer "In4.Cu")
		(net "M_B_DQ<39>")
	)
	(segment
		(start 286.8168 -27.5082)
		(end 286.512 -27.2034)
		(width 0.14224)
		(layer "In4.Cu")
		(net "M_B_DQ<39>")
	)
	(segment
		(start 286.550862 -8.0518)
		(end 286.296862 -8.0518)
		(width 0.14224)
		(layer "In4.Cu")
		(net "M_B_DQ<39>")
	)
	(segment
		(start 286.892746 -24.003254)
		(end 286.892746 -23.28164)
		(width 0.14224)
		(layer "In4.Cu")
		(net "M_B_DQ<39>")
	)
	(segment
		(start 286.892746 -23.28164)
		(end 287.055814 -23.118572)
		(width 0.14224)
		(layer "In4.Cu")
		(net "M_B_DQ<39>")
	)
	(segment
		(start 286.852614 -9.020048)
		(end 287.008062 -8.8646)
		(width 0.14224)
		(layer "In4.Cu")
		(net "M_B_DQ<39>")
	)
	(segment
		(start 273.182842 -55.999888)
		(end 273.215608 -55.999888)
		(width 0.0889)
		(layer "In4.Cu")
		(net "M_B_DQ<39>")
	)
	(segment
		(start 287.081214 -18.328386)
		(end 287.081214 -17.082262)
		(width 0.14224)
		(layer "In4.Cu")
		(net "M_B_DQ<39>")
	)
	(segment
		(start 287.008062 -8.509)
		(end 286.550862 -8.0518)
		(width 0.14224)
		(layer "In4.Cu")
		(net "M_B_DQ<39>")
	)
	(segment
		(start 276.32025 -38.411404)
		(end 286.8168 -27.914854)
		(width 0.14224)
		(layer "In4.Cu")
		(net "M_B_DQ<39>")
	)
	(segment
		(start 286.296862 -8.0518)
		(end 285.966662 -7.7216)
		(width 0.14224)
		(layer "In4.Cu")
		(net "M_B_DQ<39>")
	)
	(segment
		(start 276.040596 -45.94225)
		(end 276.305772 -45.677074)
		(width 0.0889)
		(layer "In4.Cu")
		(net "M_B_DQ<39>")
	)
	(segment
		(start 273.882358 -53.423058)
		(end 273.882358 -52.217574)
		(width 0.0889)
		(layer "In4.Cu")
		(net "M_B_DQ<39>")
	)
	(segment
		(start 276.305772 -45.677074)
		(end 276.32025 -45.662596)
		(width 0.14224)
		(layer "In4.Cu")
		(net "M_B_DQ<39>")
	)
	(segment
		(start 286.512 -27.2034)
		(end 286.512 -24.384)
		(width 0.14224)
		(layer "In4.Cu")
		(net "M_B_DQ<39>")
	)
	(segment
		(start 286.8168 -27.914854)
		(end 286.8168 -27.5082)
		(width 0.14224)
		(layer "In4.Cu")
		(net "M_B_DQ<39>")
	)
	(segment
		(start 285.966662 -7.403084)
		(end 285.649924 -7.086346)
		(width 0.14224)
		(layer "In4.Cu")
		(net "M_B_DQ<39>")
	)
	(segment
		(start 274.235164 -49.708054)
		(end 274.517612 -49.425606)
		(width 0.0889)
		(layer "In4.Cu")
		(net "M_B_DQ<39>")
	)
	(segment
		(start 286.852614 -21.772372)
		(end 286.852614 -18.556986)
		(width 0.14224)
		(layer "In4.Cu")
		(net "M_B_DQ<39>")
	)
	(segment
		(start 276.040596 -46.603158)
		(end 276.040596 -45.94225)
		(width 0.0889)
		(layer "In4.Cu")
		(net "M_B_DQ<39>")
	)
	(segment
		(start 272.834608 -57.219342)
		(end 272.851118 -57.19064)
		(width 0.0889)
		(layer "In4.Cu")
		(net "M_B_DQ<39>")
	)
	(segment
		(start 286.892746 -16.893794)
		(end 286.892746 -14.64056)
		(width 0.14224)
		(layer "In4.Cu")
		(net "M_B_DQ<39>")
	)
	(segment
		(start 276.32025 -45.662596)
		(end 276.32025 -38.411404)
		(width 0.14224)
		(layer "In4.Cu")
		(net "M_B_DQ<39>")
	)
	(segment
		(start 287.055814 -23.118572)
		(end 287.055814 -21.975572)
		(width 0.14224)
		(layer "In4.Cu")
		(net "M_B_DQ<39>")
	)
	(segment
		(start 286.014414 -13.61694)
		(end 286.014414 -13.16355)
		(width 0.14224)
		(layer "In4.Cu")
		(net "M_B_DQ<39>")
	)
	(segment
		(start 286.852614 -18.556986)
		(end 287.081214 -18.328386)
		(width 0.14224)
		(layer "In4.Cu")
		(net "M_B_DQ<39>")
	)
	(segment
		(start 272.339308 -57.885584)
		(end 272.339308 -57.885838)
		(width 0.0889)
		(layer "In4.Cu")
		(net "M_B_DQ<39>")
	)
	(arc
		(start 273.215608 -55.999888)
		(mid 273.713859 -55.697048)
		(end 273.709638 -55.113936)
		(width 0.0889)
		(layer "In4.Cu")
		(net "M_B_DQ<39>")
	)
	(arc
		(start 273.709638 -54.713632)
		(mid 273.788769 -54.41823)
		(end 273.709638 -54.122828)
		(width 0.0889)
		(layer "In4.Cu")
		(net "M_B_DQ<39>")
	)
	(arc
		(start 273.709638 -54.122828)
		(mid 273.656012 -53.922676)
		(end 273.709638 -53.722524)
		(width 0.0889)
		(layer "In4.Cu")
		(net "M_B_DQ<39>")
	)
	(arc
		(start 272.851118 -56.599836)
		(mid 272.847412 -56.206089)
		(end 273.182842 -55.999888)
		(width 0.0889)
		(layer "In4.Cu")
		(net "M_B_DQ<39>")
	)
	(arc
		(start 272.851118 -57.19064)
		(mid 272.930249 -56.895238)
		(end 272.851118 -56.599836)
		(width 0.0889)
		(layer "In4.Cu")
		(net "M_B_DQ<39>")
	)
	(arc
		(start 273.709638 -55.113936)
		(mid 273.656012 -54.913784)
		(end 273.709638 -54.713632)
		(width 0.0889)
		(layer "In4.Cu")
		(net "M_B_DQ<39>")
	)
	(segment
		(start 286.500062 -10.422128)
		(end 286.500316 -10.422382)
		(width 0.1651)
		(layer "F.Cu")
		(net "M_B_DQ<38>")
	)
	(segment
		(start 286.500062 -9.4488)
		(end 286.500062 -10.422128)
		(width 0.1651)
		(layer "F.Cu")
		(net "M_B_DQ<38>")
	)
	(segment
		(start 286.500062 -8.661654)
		(end 286.500062 -8.9662)
		(width 0.1651)
		(layer "F.Cu")
		(net "M_B_DQ<38>")
	)
	(segment
		(start 286.499808 -8.6614)
		(end 286.500062 -8.661654)
		(width 0.1651)
		(layer "F.Cu")
		(net "M_B_DQ<38>")
	)
	(segment
		(start 286.500062 -8.9662)
		(end 286.632142 -9.09828)
		(width 0.1651)
		(layer "F.Cu")
		(net "M_B_DQ<38>")
	)
	(segment
		(start 272.910808 -55.904384)
		(end 272.339308 -55.904384)
		(width 0.1016)
		(layer "F.Cu")
		(net "M_B_DQ<38>")
	)
	(segment
		(start 286.632142 -9.31672)
		(end 286.500062 -9.4488)
		(width 0.1651)
		(layer "F.Cu")
		(net "M_B_DQ<38>")
	)
	(segment
		(start 286.632142 -9.09828)
		(end 286.632142 -9.31672)
		(width 0.1651)
		(layer "F.Cu")
		(net "M_B_DQ<38>")
	)
	(via
		(at 285.649924 -13.959078)
		(size 0.508)
		(drill 0.254)
		(layers "F.Cu" "B.Cu")
		(net "M_B_DQ<38>")
	)
	(via
		(at 286.499808 -8.6614)
		(size 0.508)
		(drill 0.254)
		(layers "F.Cu" "B.Cu")
		(net "M_B_DQ<38>")
	)
	(via
		(at 272.339308 -55.904384)
		(size 0.508)
		(drill 0.254)
		(layers "F.Cu" "B.Cu")
		(net "M_B_DQ<38>")
	)
	(segment
		(start 285.650432 -15.222982)
		(end 285.649924 -15.222982)
		(width 0.1651)
		(layer "B.Cu")
		(net "M_B_DQ<38>")
	)
	(segment
		(start 285.649924 -15.222982)
		(end 285.649924 -13.959078)
		(width 0.1651)
		(layer "B.Cu")
		(net "M_B_DQ<38>")
	)
	(segment
		(start 275.667724 -45.677074)
		(end 275.667724 -38.14953)
		(width 0.14224)
		(layer "In4.Cu")
		(net "M_B_DQ<38>")
	)
	(segment
		(start 286.217614 -18.628614)
		(end 286.014414 -18.425414)
		(width 0.14224)
		(layer "In4.Cu")
		(net "M_B_DQ<38>")
	)
	(segment
		(start 286.125412 -9.035796)
		(end 286.499808 -8.6614)
		(width 0.14224)
		(layer "In4.Cu")
		(net "M_B_DQ<38>")
	)
	(segment
		(start 286.014414 -16.993362)
		(end 286.107124 -16.900652)
		(width 0.14224)
		(layer "In4.Cu")
		(net "M_B_DQ<38>")
	)
	(segment
		(start 286.107124 -15.467076)
		(end 286.107124 -15.089378)
		(width 0.14224)
		(layer "In4.Cu")
		(net "M_B_DQ<38>")
	)
	(segment
		(start 286.18688 -12.156186)
		(end 286.18688 -11.804396)
		(width 0.14224)
		(layer "In4.Cu")
		(net "M_B_DQ<38>")
	)
	(segment
		(start 285.010352 -27.892756)
		(end 285.297372 -27.892756)
		(width 0.14224)
		(layer "In4.Cu")
		(net "M_B_DQ<38>")
	)
	(segment
		(start 285.76143 -9.988296)
		(end 285.76143 -9.677654)
		(width 0.14224)
		(layer "In4.Cu")
		(net "M_B_DQ<38>")
	)
	(segment
		(start 285.9024 -15.6718)
		(end 286.107124 -15.467076)
		(width 0.14224)
		(layer "In4.Cu")
		(net "M_B_DQ<38>")
	)
	(segment
		(start 285.414212 -13.723366)
		(end 285.414212 -12.928854)
		(width 0.14224)
		(layer "In4.Cu")
		(net "M_B_DQ<38>")
	)
	(segment
		(start 273.691858 -52.13858)
		(end 274.044664 -51.785774)
		(width 0.0889)
		(layer "In4.Cu")
		(net "M_B_DQ<38>")
	)
	(segment
		(start 281.56154 -31.341568)
		(end 282.043886 -31.341568)
		(width 0.14224)
		(layer "In4.Cu")
		(net "M_B_DQ<38>")
	)
	(segment
		(start 272.339308 -55.904384)
		(end 272.339308 -56.242458)
		(width 0.0889)
		(layer "In4.Cu")
		(net "M_B_DQ<38>")
	)
	(segment
		(start 286.125412 -9.313672)
		(end 286.125412 -9.035796)
		(width 0.14224)
		(layer "In4.Cu")
		(net "M_B_DQ<38>")
	)
	(segment
		(start 283.16809 -30.362144)
		(end 283.45511 -30.362144)
		(width 0.14224)
		(layer "In4.Cu")
		(net "M_B_DQ<38>")
	)
	(segment
		(start 286.014414 -23.169372)
		(end 286.014414 -21.975572)
		(width 0.14224)
		(layer "In4.Cu")
		(net "M_B_DQ<38>")
	)
	(segment
		(start 286.014414 -21.975572)
		(end 286.217614 -21.772372)
		(width 0.14224)
		(layer "In4.Cu")
		(net "M_B_DQ<38>")
	)
	(segment
		(start 286.18688 -11.804396)
		(end 285.76143 -11.378946)
		(width 0.14224)
		(layer "In4.Cu")
		(net "M_B_DQ<38>")
	)
	(segment
		(start 274.044664 -49.629822)
		(end 274.32762 -49.346866)
		(width 0.0889)
		(layer "In4.Cu")
		(net "M_B_DQ<38>")
	)
	(segment
		(start 274.044664 -51.785774)
		(end 274.044664 -49.629822)
		(width 0.0889)
		(layer "In4.Cu")
		(net "M_B_DQ<38>")
	)
	(segment
		(start 286.107124 -16.333724)
		(end 285.9024 -16.129)
		(width 0.14224)
		(layer "In4.Cu")
		(net "M_B_DQ<38>")
	)
	(segment
		(start 286.116014 -23.270972)
		(end 286.014414 -23.169372)
		(width 0.14224)
		(layer "In4.Cu")
		(net "M_B_DQ<38>")
	)
	(segment
		(start 284.72257 -28.180538)
		(end 285.010352 -27.892756)
		(width 0.14224)
		(layer "In4.Cu")
		(net "M_B_DQ<38>")
	)
	(segment
		(start 283.742892 -30.074362)
		(end 283.742892 -29.787088)
		(width 0.14224)
		(layer "In4.Cu")
		(net "M_B_DQ<38>")
	)
	(segment
		(start 282.998164 -30.191964)
		(end 283.16809 -30.362144)
		(width 0.14224)
		(layer "In4.Cu")
		(net "M_B_DQ<38>")
	)
	(segment
		(start 285.754318 -28.062936)
		(end 285.877 -27.940254)
		(width 0.14224)
		(layer "In4.Cu")
		(net "M_B_DQ<38>")
	)
	(segment
		(start 283.572966 -29.617162)
		(end 283.572966 -29.330142)
		(width 0.14224)
		(layer "In4.Cu")
		(net "M_B_DQ<38>")
	)
	(segment
		(start 284.604714 -29.21254)
		(end 284.892496 -28.924758)
		(width 0.14224)
		(layer "In4.Cu")
		(net "M_B_DQ<38>")
	)
	(segment
		(start 272.339308 -56.242458)
		(end 272.39722 -56.30037)
		(width 0.0889)
		(layer "In4.Cu")
		(net "M_B_DQ<38>")
	)
	(segment
		(start 284.147768 -29.04236)
		(end 284.317694 -29.21254)
		(width 0.14224)
		(layer "In4.Cu")
		(net "M_B_DQ<38>")
	)
	(segment
		(start 286.116014 -23.789386)
		(end 286.116014 -23.270972)
		(width 0.14224)
		(layer "In4.Cu")
		(net "M_B_DQ<38>")
	)
	(segment
		(start 283.45511 -30.362144)
		(end 283.742892 -30.074362)
		(width 0.14224)
		(layer "In4.Cu")
		(net "M_B_DQ<38>")
	)
	(segment
		(start 275.667724 -38.14953)
		(end 281.443684 -32.37357)
		(width 0.14224)
		(layer "In4.Cu")
		(net "M_B_DQ<38>")
	)
	(segment
		(start 283.860748 -29.04236)
		(end 284.147768 -29.04236)
		(width 0.14224)
		(layer "In4.Cu")
		(net "M_B_DQ<38>")
	)
	(segment
		(start 281.273758 -31.62935)
		(end 281.56154 -31.341568)
		(width 0.14224)
		(layer "In4.Cu")
		(net "M_B_DQ<38>")
	)
	(segment
		(start 275.850604 -45.859954)
		(end 275.667724 -45.677074)
		(width 0.0889)
		(layer "In4.Cu")
		(net "M_B_DQ<38>")
	)
	(segment
		(start 285.9024 -16.129)
		(end 285.9024 -15.6718)
		(width 0.14224)
		(layer "In4.Cu")
		(net "M_B_DQ<38>")
	)
	(segment
		(start 281.443684 -32.086296)
		(end 281.273758 -31.91637)
		(width 0.14224)
		(layer "In4.Cu")
		(net "M_B_DQ<38>")
	)
	(segment
		(start 286.014414 -18.425414)
		(end 286.014414 -16.993362)
		(width 0.14224)
		(layer "In4.Cu")
		(net "M_B_DQ<38>")
	)
	(segment
		(start 281.273758 -31.91637)
		(end 281.273758 -31.62935)
		(width 0.14224)
		(layer "In4.Cu")
		(net "M_B_DQ<38>")
	)
	(segment
		(start 282.423362 -30.962092)
		(end 282.423362 -30.479746)
		(width 0.14224)
		(layer "In4.Cu")
		(net "M_B_DQ<38>")
	)
	(segment
		(start 282.043886 -31.341568)
		(end 282.423362 -30.962092)
		(width 0.14224)
		(layer "In4.Cu")
		(net "M_B_DQ<38>")
	)
	(segment
		(start 281.443684 -32.37357)
		(end 281.443684 -32.086296)
		(width 0.14224)
		(layer "In4.Cu")
		(net "M_B_DQ<38>")
	)
	(segment
		(start 285.649924 -13.959078)
		(end 285.414212 -13.723366)
		(width 0.14224)
		(layer "In4.Cu")
		(net "M_B_DQ<38>")
	)
	(segment
		(start 285.877 -27.940254)
		(end 285.877 -24.0284)
		(width 0.14224)
		(layer "In4.Cu")
		(net "M_B_DQ<38>")
	)
	(segment
		(start 275.850604 -46.524418)
		(end 275.850604 -45.859954)
		(width 0.0889)
		(layer "In4.Cu")
		(net "M_B_DQ<38>")
	)
	(segment
		(start 286.14243 -10.712704)
		(end 286.14243 -10.369296)
		(width 0.14224)
		(layer "In4.Cu")
		(net "M_B_DQ<38>")
	)
	(segment
		(start 274.32762 -48.047402)
		(end 275.850604 -46.524418)
		(width 0.0889)
		(layer "In4.Cu")
		(net "M_B_DQ<38>")
	)
	(segment
		(start 285.457138 -14.439392)
		(end 285.457138 -14.151864)
		(width 0.14224)
		(layer "In4.Cu")
		(net "M_B_DQ<38>")
	)
	(segment
		(start 283.572966 -29.330142)
		(end 283.860748 -29.04236)
		(width 0.14224)
		(layer "In4.Cu")
		(net "M_B_DQ<38>")
	)
	(segment
		(start 282.423362 -30.479746)
		(end 282.711144 -30.191964)
		(width 0.14224)
		(layer "In4.Cu")
		(net "M_B_DQ<38>")
	)
	(segment
		(start 282.711144 -30.191964)
		(end 282.998164 -30.191964)
		(width 0.14224)
		(layer "In4.Cu")
		(net "M_B_DQ<38>")
	)
	(segment
		(start 285.414212 -12.928854)
		(end 286.18688 -12.156186)
		(width 0.14224)
		(layer "In4.Cu")
		(net "M_B_DQ<38>")
	)
	(segment
		(start 286.217614 -21.772372)
		(end 286.217614 -18.628614)
		(width 0.14224)
		(layer "In4.Cu")
		(net "M_B_DQ<38>")
	)
	(segment
		(start 273.544538 -53.627274)
		(end 273.691858 -53.37175)
		(width 0.0889)
		(layer "In4.Cu")
		(net "M_B_DQ<38>")
	)
	(segment
		(start 285.76143 -11.378946)
		(end 285.76143 -11.093704)
		(width 0.14224)
		(layer "In4.Cu")
		(net "M_B_DQ<38>")
	)
	(segment
		(start 284.72257 -28.467558)
		(end 284.72257 -28.180538)
		(width 0.14224)
		(layer "In4.Cu")
		(net "M_B_DQ<38>")
	)
	(segment
		(start 285.76143 -11.093704)
		(end 286.14243 -10.712704)
		(width 0.14224)
		(layer "In4.Cu")
		(net "M_B_DQ<38>")
	)
	(segment
		(start 273.176238 -55.809388)
		(end 273.209004 -55.809388)
		(width 0.0889)
		(layer "In4.Cu")
		(net "M_B_DQ<38>")
	)
	(segment
		(start 284.892496 -28.924758)
		(end 284.892496 -28.637484)
		(width 0.14224)
		(layer "In4.Cu")
		(net "M_B_DQ<38>")
	)
	(segment
		(start 273.691858 -53.37175)
		(end 273.691858 -52.13858)
		(width 0.0889)
		(layer "In4.Cu")
		(net "M_B_DQ<38>")
	)
	(segment
		(start 285.467298 -28.062936)
		(end 285.754318 -28.062936)
		(width 0.14224)
		(layer "In4.Cu")
		(net "M_B_DQ<38>")
	)
	(segment
		(start 285.76143 -9.677654)
		(end 286.125412 -9.313672)
		(width 0.14224)
		(layer "In4.Cu")
		(net "M_B_DQ<38>")
	)
	(segment
		(start 285.457138 -14.151864)
		(end 285.649924 -13.959078)
		(width 0.14224)
		(layer "In4.Cu")
		(net "M_B_DQ<38>")
	)
	(segment
		(start 283.742892 -29.787088)
		(end 283.572966 -29.617162)
		(width 0.14224)
		(layer "In4.Cu")
		(net "M_B_DQ<38>")
	)
	(segment
		(start 286.107124 -16.900652)
		(end 286.107124 -16.333724)
		(width 0.14224)
		(layer "In4.Cu")
		(net "M_B_DQ<38>")
	)
	(segment
		(start 285.297372 -27.892756)
		(end 285.467298 -28.062936)
		(width 0.14224)
		(layer "In4.Cu")
		(net "M_B_DQ<38>")
	)
	(segment
		(start 274.32762 -49.346866)
		(end 274.32762 -48.047402)
		(width 0.0889)
		(layer "In4.Cu")
		(net "M_B_DQ<38>")
	)
	(segment
		(start 286.14243 -10.369296)
		(end 285.76143 -9.988296)
		(width 0.14224)
		(layer "In4.Cu")
		(net "M_B_DQ<38>")
	)
	(segment
		(start 284.892496 -28.637484)
		(end 284.72257 -28.467558)
		(width 0.14224)
		(layer "In4.Cu")
		(net "M_B_DQ<38>")
	)
	(segment
		(start 286.107124 -15.089378)
		(end 285.457138 -14.439392)
		(width 0.14224)
		(layer "In4.Cu")
		(net "M_B_DQ<38>")
	)
	(segment
		(start 285.877 -24.0284)
		(end 286.116014 -23.789386)
		(width 0.14224)
		(layer "In4.Cu")
		(net "M_B_DQ<38>")
	)
	(segment
		(start 284.317694 -29.21254)
		(end 284.604714 -29.21254)
		(width 0.14224)
		(layer "In4.Cu")
		(net "M_B_DQ<38>")
	)
	(arc
		(start 273.544538 -54.218078)
		(mid 273.465407 -53.922676)
		(end 273.544538 -53.627274)
		(width 0.0889)
		(layer "In4.Cu")
		(net "M_B_DQ<38>")
	)
	(arc
		(start 273.544538 -55.209186)
		(mid 273.465407 -54.913784)
		(end 273.544538 -54.618382)
		(width 0.0889)
		(layer "In4.Cu")
		(net "M_B_DQ<38>")
	)
	(arc
		(start 273.209004 -55.809388)
		(mid 273.547173 -55.60459)
		(end 273.544538 -55.209186)
		(width 0.0889)
		(layer "In4.Cu")
		(net "M_B_DQ<38>")
	)
	(arc
		(start 272.39722 -56.30037)
		(mid 272.564065 -56.235557)
		(end 272.686018 -56.104536)
		(width 0.0889)
		(layer "In4.Cu")
		(net "M_B_DQ<38>")
	)
	(arc
		(start 272.686018 -56.104536)
		(mid 272.893022 -55.893672)
		(end 273.176238 -55.809388)
		(width 0.0889)
		(layer "In4.Cu")
		(net "M_B_DQ<38>")
	)
	(arc
		(start 273.544538 -54.618382)
		(mid 273.598164 -54.41823)
		(end 273.544538 -54.218078)
		(width 0.0889)
		(layer "In4.Cu")
		(net "M_B_DQ<38>")
	)
	(segment
		(start 279.700482 -5.822442)
		(end 279.699974 -5.822442)
		(width 0.1651)
		(layer "F.Cu")
		(net "M_B_DQ<37>")
	)
	(segment
		(start 271.193768 -58.876438)
		(end 270.571468 -58.876438)
		(width 0.1651)
		(layer "F.Cu")
		(net "M_B_DQ<37>")
	)
	(segment
		(start 279.699974 -5.822442)
		(end 279.699974 -7.086346)
		(width 0.1651)
		(layer "F.Cu")
		(net "M_B_DQ<37>")
	)
	(via
		(at 280.473658 -12.589256)
		(size 0.508)
		(drill 0.254)
		(layers "F.Cu" "B.Cu")
		(net "M_B_DQ<37>")
	)
	(via
		(at 270.571468 -58.876438)
		(size 0.508)
		(drill 0.254)
		(layers "F.Cu" "B.Cu")
		(net "M_B_DQ<37>")
	)
	(via
		(at 279.699974 -7.086346)
		(size 0.508)
		(drill 0.254)
		(layers "F.Cu" "B.Cu")
		(net "M_B_DQ<37>")
	)
	(segment
		(start 280.549858 -12.513056)
		(end 280.473658 -12.589256)
		(width 0.1651)
		(layer "B.Cu")
		(net "M_B_DQ<37>")
	)
	(segment
		(start 280.549858 -10.623042)
		(end 280.549858 -12.513056)
		(width 0.1651)
		(layer "B.Cu")
		(net "M_B_DQ<37>")
	)
	(segment
		(start 280.550366 -10.623042)
		(end 280.549858 -10.623042)
		(width 0.1651)
		(layer "B.Cu")
		(net "M_B_DQ<37>")
	)
	(segment
		(start 271.438116 -45.55363)
		(end 271.652492 -45.339254)
		(width 0.0889)
		(layer "In4.Cu")
		(net "M_B_DQ<37>")
	)
	(segment
		(start 280.3906 -15.824454)
		(end 280.3906 -13.894054)
		(width 0.14224)
		(layer "In4.Cu")
		(net "M_B_DQ<37>")
	)
	(segment
		(start 280.947114 -16.929862)
		(end 280.942796 -16.925544)
		(width 0.14224)
		(layer "In4.Cu")
		(net "M_B_DQ<37>")
	)
	(segment
		(start 270.394938 -50.687732)
		(end 270.396208 -50.686208)
		(width 0.0889)
		(layer "In4.Cu")
		(net "M_B_DQ<37>")
	)
	(segment
		(start 280.942796 -25.04186)
		(end 280.942796 -23.14067)
		(width 0.14224)
		(layer "In4.Cu")
		(net "M_B_DQ<37>")
	)
	(segment
		(start 270.956278 -57.68594)
		(end 270.588232 -57.317894)
		(width 0.0889)
		(layer "In4.Cu")
		(net "M_B_DQ<37>")
	)
	(segment
		(start 271.652492 -45.339254)
		(end 271.652492 -36.65093)
		(width 0.14224)
		(layer "In4.Cu")
		(net "M_B_DQ<37>")
	)
	(segment
		(start 280.947114 -18.504662)
		(end 280.947114 -16.929862)
		(width 0.14224)
		(layer "In4.Cu")
		(net "M_B_DQ<37>")
	)
	(segment
		(start 280.785062 -12.280392)
		(end 280.785062 -9.06145)
		(width 0.14224)
		(layer "In4.Cu")
		(net "M_B_DQ<37>")
	)
	(segment
		(start 273.9644 -34.01949)
		(end 273.1516 -33.20669)
		(width 0.14224)
		(layer "In4.Cu")
		(net "M_B_DQ<37>")
	)
	(segment
		(start 271.15389 -48.548036)
		(end 271.438116 -48.26381)
		(width 0.0889)
		(layer "In4.Cu")
		(net "M_B_DQ<37>")
	)
	(segment
		(start 280.581608 -8.0518)
		(end 280.270712 -8.0518)
		(width 0.14224)
		(layer "In4.Cu")
		(net "M_B_DQ<37>")
	)
	(segment
		(start 280.942796 -23.14067)
		(end 280.943558 -23.139908)
		(width 0.14224)
		(layer "In4.Cu")
		(net "M_B_DQ<37>")
	)
	(segment
		(start 279.699974 -7.481062)
		(end 279.699974 -7.086346)
		(width 0.14224)
		(layer "In4.Cu")
		(net "M_B_DQ<37>")
	)
	(segment
		(start 270.396208 -50.686208)
		(end 271.153382 -49.929288)
		(width 0.0889)
		(layer "In4.Cu")
		(net "M_B_DQ<37>")
	)
	(segment
		(start 280.947114 -21.962872)
		(end 280.858214 -21.873972)
		(width 0.14224)
		(layer "In4.Cu")
		(net "M_B_DQ<37>")
	)
	(segment
		(start 269.634716 -52.260754)
		(end 270.394938 -51.500532)
		(width 0.0889)
		(layer "In4.Cu")
		(net "M_B_DQ<37>")
	)
	(segment
		(start 280.942796 -16.37665)
		(end 280.3906 -15.824454)
		(width 0.14224)
		(layer "In4.Cu")
		(net "M_B_DQ<37>")
	)
	(segment
		(start 271.652492 -36.65093)
		(end 273.9644 -34.339022)
		(width 0.14224)
		(layer "In4.Cu")
		(net "M_B_DQ<37>")
	)
	(segment
		(start 269.635224 -56.678322)
		(end 269.635224 -52.261262)
		(width 0.0889)
		(layer "In4.Cu")
		(net "M_B_DQ<37>")
	)
	(segment
		(start 280.943558 -22.827234)
		(end 280.947114 -22.823678)
		(width 0.14224)
		(layer "In4.Cu")
		(net "M_B_DQ<37>")
	)
	(segment
		(start 280.858214 -18.593562)
		(end 280.947114 -18.504662)
		(width 0.14224)
		(layer "In4.Cu")
		(net "M_B_DQ<37>")
	)
	(segment
		(start 280.476198 -12.589256)
		(end 280.785062 -12.280392)
		(width 0.14224)
		(layer "In4.Cu")
		(net "M_B_DQ<37>")
	)
	(segment
		(start 280.981912 -8.452104)
		(end 280.581608 -8.0518)
		(width 0.14224)
		(layer "In4.Cu")
		(net "M_B_DQ<37>")
	)
	(segment
		(start 271.153382 -49.929288)
		(end 271.15389 -49.929288)
		(width 0.0889)
		(layer "In4.Cu")
		(net "M_B_DQ<37>")
	)
	(segment
		(start 280.3906 -13.894054)
		(end 280.003758 -13.507212)
		(width 0.14224)
		(layer "In4.Cu")
		(net "M_B_DQ<37>")
	)
	(segment
		(start 270.588232 -57.317894)
		(end 270.274796 -57.317894)
		(width 0.0889)
		(layer "In4.Cu")
		(net "M_B_DQ<37>")
	)
	(segment
		(start 273.9644 -34.339022)
		(end 273.9644 -34.01949)
		(width 0.14224)
		(layer "In4.Cu")
		(net "M_B_DQ<37>")
	)
	(segment
		(start 280.942796 -16.925544)
		(end 280.942796 -16.37665)
		(width 0.14224)
		(layer "In4.Cu")
		(net "M_B_DQ<37>")
	)
	(segment
		(start 270.274796 -57.317894)
		(end 269.635224 -56.678322)
		(width 0.0889)
		(layer "In4.Cu")
		(net "M_B_DQ<37>")
	)
	(segment
		(start 280.858214 -21.873972)
		(end 280.858214 -18.593562)
		(width 0.14224)
		(layer "In4.Cu")
		(net "M_B_DQ<37>")
	)
	(segment
		(start 280.003758 -13.059156)
		(end 280.473658 -12.589256)
		(width 0.14224)
		(layer "In4.Cu")
		(net "M_B_DQ<37>")
	)
	(segment
		(start 269.635224 -52.261262)
		(end 269.634716 -52.260754)
		(width 0.0889)
		(layer "In4.Cu")
		(net "M_B_DQ<37>")
	)
	(segment
		(start 280.943558 -23.139908)
		(end 280.943558 -22.827234)
		(width 0.14224)
		(layer "In4.Cu")
		(net "M_B_DQ<37>")
	)
	(segment
		(start 280.785062 -9.06145)
		(end 280.981912 -8.8646)
		(width 0.14224)
		(layer "In4.Cu")
		(net "M_B_DQ<37>")
	)
	(segment
		(start 271.438116 -48.26381)
		(end 271.438116 -45.55363)
		(width 0.0889)
		(layer "In4.Cu")
		(net "M_B_DQ<37>")
	)
	(segment
		(start 280.473658 -12.589256)
		(end 280.476198 -12.589256)
		(width 0.14224)
		(layer "In4.Cu")
		(net "M_B_DQ<37>")
	)
	(segment
		(start 280.003758 -13.507212)
		(end 280.003758 -13.059156)
		(width 0.14224)
		(layer "In4.Cu")
		(net "M_B_DQ<37>")
	)
	(segment
		(start 280.981912 -8.8646)
		(end 280.981912 -8.452104)
		(width 0.14224)
		(layer "In4.Cu")
		(net "M_B_DQ<37>")
	)
	(segment
		(start 273.1516 -33.20669)
		(end 273.1516 -32.833056)
		(width 0.14224)
		(layer "In4.Cu")
		(net "M_B_DQ<37>")
	)
	(segment
		(start 273.1516 -32.833056)
		(end 280.942796 -25.04186)
		(width 0.14224)
		(layer "In4.Cu")
		(net "M_B_DQ<37>")
	)
	(segment
		(start 280.270712 -8.0518)
		(end 279.699974 -7.481062)
		(width 0.14224)
		(layer "In4.Cu")
		(net "M_B_DQ<37>")
	)
	(segment
		(start 280.947114 -22.823678)
		(end 280.947114 -21.962872)
		(width 0.14224)
		(layer "In4.Cu")
		(net "M_B_DQ<37>")
	)
	(segment
		(start 270.394938 -51.500532)
		(end 270.394938 -50.687732)
		(width 0.0889)
		(layer "In4.Cu")
		(net "M_B_DQ<37>")
	)
	(segment
		(start 271.15389 -49.929288)
		(end 271.15389 -48.548036)
		(width 0.0889)
		(layer "In4.Cu")
		(net "M_B_DQ<37>")
	)
	(arc
		(start 270.571468 -58.876438)
		(mid 270.750019 -58.474345)
		(end 270.956278 -58.085736)
		(width 0.0889)
		(layer "In4.Cu")
		(net "M_B_DQ<37>")
	)
	(arc
		(start 270.956278 -58.085736)
		(mid 271.009777 -57.885838)
		(end 270.956278 -57.68594)
		(width 0.0889)
		(layer "In4.Cu")
		(net "M_B_DQ<37>")
	)
	(segment
		(start 280.550366 -10.422382)
		(end 280.550366 -8.658352)
		(width 0.1651)
		(layer "F.Cu")
		(net "M_B_DQ<36>")
	)
	(segment
		(start 280.550366 -8.658352)
		(end 280.451814 -8.5598)
		(width 0.1651)
		(layer "F.Cu")
		(net "M_B_DQ<36>")
	)
	(segment
		(start 271.193768 -57.885584)
		(end 270.571468 -57.885584)
		(width 0.1651)
		(layer "F.Cu")
		(net "M_B_DQ<36>")
	)
	(via
		(at 279.699974 -13.959078)
		(size 0.508)
		(drill 0.254)
		(layers "F.Cu" "B.Cu")
		(net "M_B_DQ<36>")
	)
	(via
		(at 280.451814 -8.5598)
		(size 0.508)
		(drill 0.254)
		(layers "F.Cu" "B.Cu")
		(net "M_B_DQ<36>")
	)
	(via
		(at 270.571468 -57.885584)
		(size 0.508)
		(drill 0.254)
		(layers "F.Cu" "B.Cu")
		(net "M_B_DQ<36>")
	)
	(segment
		(start 279.699974 -15.222982)
		(end 279.699974 -13.959078)
		(width 0.1651)
		(layer "B.Cu")
		(net "M_B_DQ<36>")
	)
	(segment
		(start 279.700482 -15.222982)
		(end 279.699974 -15.222982)
		(width 0.1651)
		(layer "B.Cu")
		(net "M_B_DQ<36>")
	)
	(segment
		(start 279.9842 -24.0284)
		(end 280.3144 -23.6982)
		(width 0.14224)
		(layer "In4.Cu")
		(net "M_B_DQ<36>")
	)
	(segment
		(start 279.969214 -17.058386)
		(end 280.157174 -16.870426)
		(width 0.14224)
		(layer "In4.Cu")
		(net "M_B_DQ<36>")
	)
	(segment
		(start 271.63649 -33.61309)
		(end 271.63649 -33.411922)
		(width 0.14224)
		(layer "In4.Cu")
		(net "M_B_DQ<36>")
	)
	(segment
		(start 270.963644 -48.46955)
		(end 271.248124 -48.18507)
		(width 0.0889)
		(layer "In4.Cu")
		(net "M_B_DQ<36>")
	)
	(segment
		(start 272.178018 -33.95345)
		(end 271.97685 -33.95345)
		(width 0.14224)
		(layer "In4.Cu")
		(net "M_B_DQ<36>")
	)
	(segment
		(start 280.19248 -10.668)
		(end 280.19248 -10.3632)
		(width 0.14224)
		(layer "In4.Cu")
		(net "M_B_DQ<36>")
	)
	(segment
		(start 280.223214 -18.568162)
		(end 279.969214 -18.314162)
		(width 0.14224)
		(layer "In4.Cu")
		(net "M_B_DQ<36>")
	)
	(segment
		(start 269.444724 -56.75884)
		(end 269.444724 -52.182014)
		(width 0.0889)
		(layer "In4.Cu")
		(net "M_B_DQ<36>")
	)
	(segment
		(start 272.66011 -33.727898)
		(end 272.40357 -33.727898)
		(width 0.14224)
		(layer "In4.Cu")
		(net "M_B_DQ<36>")
	)
	(segment
		(start 272.978372 -34.3027)
		(end 272.978372 -34.04616)
		(width 0.14224)
		(layer "In4.Cu")
		(net "M_B_DQ<36>")
	)
	(segment
		(start 270.204946 -50.597308)
		(end 270.963644 -49.83861)
		(width 0.0889)
		(layer "In4.Cu")
		(net "M_B_DQ<36>")
	)
	(segment
		(start 279.81148 -9.677654)
		(end 280.175462 -9.313672)
		(width 0.14224)
		(layer "In4.Cu")
		(net "M_B_DQ<36>")
	)
	(segment
		(start 279.464262 -13.723366)
		(end 279.464262 -12.928854)
		(width 0.14224)
		(layer "In4.Cu")
		(net "M_B_DQ<36>")
	)
	(segment
		(start 280.3144 -24.5364)
		(end 279.9842 -24.2062)
		(width 0.14224)
		(layer "In4.Cu")
		(net "M_B_DQ<36>")
	)
	(segment
		(start 280.157174 -16.870426)
		(end 280.157174 -16.378428)
		(width 0.14224)
		(layer "In4.Cu")
		(net "M_B_DQ<36>")
	)
	(segment
		(start 279.464262 -12.928854)
		(end 280.175462 -12.217654)
		(width 0.14224)
		(layer "In4.Cu")
		(net "M_B_DQ<36>")
	)
	(segment
		(start 279.969214 -23.169372)
		(end 279.969214 -21.950172)
		(width 0.14224)
		(layer "In4.Cu")
		(net "M_B_DQ<36>")
	)
	(segment
		(start 271.63649 -33.411922)
		(end 280.3144 -24.734012)
		(width 0.14224)
		(layer "In4.Cu")
		(net "M_B_DQ<36>")
	)
	(segment
		(start 271.087596 -45.408596)
		(end 271.087596 -36.193476)
		(width 0.14224)
		(layer "In4.Cu")
		(net "M_B_DQ<36>")
	)
	(segment
		(start 270.571468 -57.885584)
		(end 269.444724 -56.75884)
		(width 0.0889)
		(layer "In4.Cu")
		(net "M_B_DQ<36>")
	)
	(segment
		(start 279.699974 -15.921228)
		(end 279.699974 -13.959078)
		(width 0.14224)
		(layer "In4.Cu")
		(net "M_B_DQ<36>")
	)
	(segment
		(start 271.087596 -36.193476)
		(end 272.978372 -34.3027)
		(width 0.14224)
		(layer "In4.Cu")
		(net "M_B_DQ<36>")
	)
	(segment
		(start 279.82418 -11.0363)
		(end 280.19248 -10.668)
		(width 0.14224)
		(layer "In4.Cu")
		(net "M_B_DQ<36>")
	)
	(segment
		(start 280.3144 -23.514558)
		(end 279.969214 -23.169372)
		(width 0.14224)
		(layer "In4.Cu")
		(net "M_B_DQ<36>")
	)
	(segment
		(start 272.40357 -33.727898)
		(end 272.178018 -33.95345)
		(width 0.14224)
		(layer "In4.Cu")
		(net "M_B_DQ<36>")
	)
	(segment
		(start 271.97685 -33.95345)
		(end 271.63649 -33.61309)
		(width 0.14224)
		(layer "In4.Cu")
		(net "M_B_DQ<36>")
	)
	(segment
		(start 279.699974 -13.959078)
		(end 279.464262 -13.723366)
		(width 0.14224)
		(layer "In4.Cu")
		(net "M_B_DQ<36>")
	)
	(segment
		(start 280.175462 -9.313672)
		(end 280.175462 -8.836152)
		(width 0.14224)
		(layer "In4.Cu")
		(net "M_B_DQ<36>")
	)
	(segment
		(start 280.175462 -8.836152)
		(end 280.451814 -8.5598)
		(width 0.14224)
		(layer "In4.Cu")
		(net "M_B_DQ<36>")
	)
	(segment
		(start 279.9842 -24.2062)
		(end 279.9842 -24.0284)
		(width 0.14224)
		(layer "In4.Cu")
		(net "M_B_DQ<36>")
	)
	(segment
		(start 271.248124 -48.18507)
		(end 271.248124 -45.569124)
		(width 0.0889)
		(layer "In4.Cu")
		(net "M_B_DQ<36>")
	)
	(segment
		(start 279.969214 -18.314162)
		(end 279.969214 -17.058386)
		(width 0.14224)
		(layer "In4.Cu")
		(net "M_B_DQ<36>")
	)
	(segment
		(start 280.223214 -21.696172)
		(end 280.223214 -18.568162)
		(width 0.14224)
		(layer "In4.Cu")
		(net "M_B_DQ<36>")
	)
	(segment
		(start 270.204946 -51.421792)
		(end 270.204946 -50.597308)
		(width 0.0889)
		(layer "In4.Cu")
		(net "M_B_DQ<36>")
	)
	(segment
		(start 280.3144 -23.6982)
		(end 280.3144 -23.514558)
		(width 0.14224)
		(layer "In4.Cu")
		(net "M_B_DQ<36>")
	)
	(segment
		(start 280.175462 -12.217654)
		(end 280.175462 -11.742928)
		(width 0.14224)
		(layer "In4.Cu")
		(net "M_B_DQ<36>")
	)
	(segment
		(start 279.82418 -11.391646)
		(end 279.82418 -11.0363)
		(width 0.14224)
		(layer "In4.Cu")
		(net "M_B_DQ<36>")
	)
	(segment
		(start 270.963644 -49.83861)
		(end 270.963644 -48.46955)
		(width 0.0889)
		(layer "In4.Cu")
		(net "M_B_DQ<36>")
	)
	(segment
		(start 269.444724 -52.182014)
		(end 270.204946 -51.421792)
		(width 0.0889)
		(layer "In4.Cu")
		(net "M_B_DQ<36>")
	)
	(segment
		(start 280.3144 -24.734012)
		(end 280.3144 -24.5364)
		(width 0.14224)
		(layer "In4.Cu")
		(net "M_B_DQ<36>")
	)
	(segment
		(start 272.978372 -34.04616)
		(end 272.66011 -33.727898)
		(width 0.14224)
		(layer "In4.Cu")
		(net "M_B_DQ<36>")
	)
	(segment
		(start 271.248124 -45.569124)
		(end 271.087596 -45.408596)
		(width 0.0889)
		(layer "In4.Cu")
		(net "M_B_DQ<36>")
	)
	(segment
		(start 280.175462 -11.742928)
		(end 279.82418 -11.391646)
		(width 0.14224)
		(layer "In4.Cu")
		(net "M_B_DQ<36>")
	)
	(segment
		(start 280.19248 -10.3632)
		(end 279.81148 -9.9822)
		(width 0.14224)
		(layer "In4.Cu")
		(net "M_B_DQ<36>")
	)
	(segment
		(start 279.81148 -9.9822)
		(end 279.81148 -9.677654)
		(width 0.14224)
		(layer "In4.Cu")
		(net "M_B_DQ<36>")
	)
	(segment
		(start 279.969214 -21.950172)
		(end 280.223214 -21.696172)
		(width 0.14224)
		(layer "In4.Cu")
		(net "M_B_DQ<36>")
	)
	(segment
		(start 280.157174 -16.378428)
		(end 279.699974 -15.921228)
		(width 0.14224)
		(layer "In4.Cu")
		(net "M_B_DQ<36>")
	)
	(segment
		(start 287.349946 -5.822442)
		(end 287.349946 -7.086346)
		(width 0.1651)
		(layer "F.Cu")
		(net "M_B_DQ<35>")
	)
	(segment
		(start 273.769328 -57.390538)
		(end 273.197828 -57.390538)
		(width 0.1016)
		(layer "F.Cu")
		(net "M_B_DQ<35>")
	)
	(segment
		(start 287.350454 -5.822442)
		(end 287.349946 -5.822442)
		(width 0.1651)
		(layer "F.Cu")
		(net "M_B_DQ<35>")
	)
	(via
		(at 273.197828 -57.390538)
		(size 0.508)
		(drill 0.254)
		(layers "F.Cu" "B.Cu")
		(net "M_B_DQ<35>")
	)
	(via
		(at 288.19983 -12.678156)
		(size 0.508)
		(drill 0.254)
		(layers "F.Cu" "B.Cu")
		(net "M_B_DQ<35>")
	)
	(via
		(at 287.349946 -7.086346)
		(size 0.508)
		(drill 0.254)
		(layers "F.Cu" "B.Cu")
		(net "M_B_DQ<35>")
	)
	(segment
		(start 288.200338 -10.623042)
		(end 288.19983 -10.623042)
		(width 0.1651)
		(layer "B.Cu")
		(net "M_B_DQ<35>")
	)
	(segment
		(start 288.19983 -10.623042)
		(end 288.19983 -12.678156)
		(width 0.1651)
		(layer "B.Cu")
		(net "M_B_DQ<35>")
	)
	(segment
		(start 275.002244 -52.121562)
		(end 275.002244 -49.760886)
		(width 0.0889)
		(layer "In4.Cu")
		(net "M_B_DQ<35>")
	)
	(segment
		(start 288.732214 -23.118572)
		(end 288.732214 -22.000972)
		(width 0.14224)
		(layer "In4.Cu")
		(net "M_B_DQ<35>")
	)
	(segment
		(start 288.567114 -16.891762)
		(end 288.567114 -14.419072)
		(width 0.14224)
		(layer "In4.Cu")
		(net "M_B_DQ<35>")
	)
	(segment
		(start 288.554414 -18.556986)
		(end 288.706814 -18.404586)
		(width 0.14224)
		(layer "In4.Cu")
		(net "M_B_DQ<35>")
	)
	(segment
		(start 277.59025 -41.233344)
		(end 277.59025 -38.96995)
		(width 0.14224)
		(layer "In4.Cu")
		(net "M_B_DQ<35>")
	)
	(segment
		(start 274.64639 -52.477416)
		(end 275.002244 -52.121562)
		(width 0.0889)
		(layer "In4.Cu")
		(net "M_B_DQ<35>")
	)
	(segment
		(start 288.554414 -21.823172)
		(end 288.554414 -18.556986)
		(width 0.14224)
		(layer "In4.Cu")
		(net "M_B_DQ<35>")
	)
	(segment
		(start 274.045172 -56.494934)
		(end 274.08124 -56.494934)
		(width 0.0889)
		(layer "In4.Cu")
		(net "M_B_DQ<35>")
	)
	(segment
		(start 274.568158 -54.218586)
		(end 274.64639 -54.08295)
		(width 0.0889)
		(layer "In4.Cu")
		(net "M_B_DQ<35>")
	)
	(segment
		(start 274.577048 -54.633876)
		(end 274.568158 -54.618636)
		(width 0.0889)
		(layer "In4.Cu")
		(net "M_B_DQ<35>")
	)
	(segment
		(start 273.197828 -57.390538)
		(end 273.197828 -57.052464)
		(width 0.0889)
		(layer "In4.Cu")
		(net "M_B_DQ<35>")
	)
	(segment
		(start 277.350728 -46.377098)
		(end 277.350728 -45.902118)
		(width 0.0889)
		(layer "In4.Cu")
		(net "M_B_DQ<35>")
	)
	(segment
		(start 288.567114 -14.419072)
		(end 287.716214 -13.568172)
		(width 0.14224)
		(layer "In4.Cu")
		(net "M_B_DQ<35>")
	)
	(segment
		(start 288.567114 -23.283672)
		(end 288.732214 -23.118572)
		(width 0.14224)
		(layer "In4.Cu")
		(net "M_B_DQ<35>")
	)
	(segment
		(start 288.708084 -8.8646)
		(end 288.708084 -8.509)
		(width 0.14224)
		(layer "In4.Cu")
		(net "M_B_DQ<35>")
	)
	(segment
		(start 288.706814 -18.404586)
		(end 288.706814 -17.031462)
		(width 0.14224)
		(layer "In4.Cu")
		(net "M_B_DQ<35>")
	)
	(segment
		(start 288.552636 -9.020048)
		(end 288.708084 -8.8646)
		(width 0.14224)
		(layer "In4.Cu")
		(net "M_B_DQ<35>")
	)
	(segment
		(start 274.64639 -54.08295)
		(end 274.64639 -52.477416)
		(width 0.0889)
		(layer "In4.Cu")
		(net "M_B_DQ<35>")
	)
	(segment
		(start 278.276812 -41.919906)
		(end 277.59025 -41.233344)
		(width 0.14224)
		(layer "In4.Cu")
		(net "M_B_DQ<35>")
	)
	(segment
		(start 277.59025 -45.662596)
		(end 277.59025 -44.759626)
		(width 0.14224)
		(layer "In4.Cu")
		(net "M_B_DQ<35>")
	)
	(segment
		(start 277.59025 -44.759626)
		(end 278.276812 -44.073064)
		(width 0.14224)
		(layer "In4.Cu")
		(net "M_B_DQ<35>")
	)
	(segment
		(start 288.706814 -17.031462)
		(end 288.567114 -16.891762)
		(width 0.14224)
		(layer "In4.Cu")
		(net "M_B_DQ<35>")
	)
	(segment
		(start 274.577048 -55.624476)
		(end 274.568158 -55.609236)
		(width 0.0889)
		(layer "In4.Cu")
		(net "M_B_DQ<35>")
	)
	(segment
		(start 275.002244 -49.760886)
		(end 275.284184 -49.478946)
		(width 0.0889)
		(layer "In4.Cu")
		(net "M_B_DQ<35>")
	)
	(segment
		(start 288.732214 -22.000972)
		(end 288.554414 -21.823172)
		(width 0.14224)
		(layer "In4.Cu")
		(net "M_B_DQ<35>")
	)
	(segment
		(start 287.666684 -7.7216)
		(end 287.666684 -7.403084)
		(width 0.14224)
		(layer "In4.Cu")
		(net "M_B_DQ<35>")
	)
	(segment
		(start 273.197828 -57.052464)
		(end 273.263106 -56.987186)
		(width 0.0889)
		(layer "In4.Cu")
		(net "M_B_DQ<35>")
	)
	(segment
		(start 274.568158 -54.618636)
		(end 274.563332 -54.61)
		(width 0.0889)
		(layer "In4.Cu")
		(net "M_B_DQ<35>")
	)
	(segment
		(start 288.708084 -8.509)
		(end 288.250884 -8.0518)
		(width 0.14224)
		(layer "In4.Cu")
		(net "M_B_DQ<35>")
	)
	(segment
		(start 288.250884 -8.0518)
		(end 287.996884 -8.0518)
		(width 0.14224)
		(layer "In4.Cu")
		(net "M_B_DQ<35>")
	)
	(segment
		(start 287.996884 -8.0518)
		(end 287.666684 -7.7216)
		(width 0.14224)
		(layer "In4.Cu")
		(net "M_B_DQ<35>")
	)
	(segment
		(start 277.350728 -45.902118)
		(end 277.575772 -45.677074)
		(width 0.0889)
		(layer "In4.Cu")
		(net "M_B_DQ<35>")
	)
	(segment
		(start 275.284184 -48.443642)
		(end 277.350728 -46.377098)
		(width 0.0889)
		(layer "In4.Cu")
		(net "M_B_DQ<35>")
	)
	(segment
		(start 287.716214 -13.161772)
		(end 288.19983 -12.678156)
		(width 0.14224)
		(layer "In4.Cu")
		(net "M_B_DQ<35>")
	)
	(segment
		(start 277.59025 -38.96995)
		(end 288.567114 -27.993086)
		(width 0.14224)
		(layer "In4.Cu")
		(net "M_B_DQ<35>")
	)
	(segment
		(start 288.552636 -12.32535)
		(end 288.552636 -9.020048)
		(width 0.14224)
		(layer "In4.Cu")
		(net "M_B_DQ<35>")
	)
	(segment
		(start 288.567114 -27.993086)
		(end 288.567114 -23.283672)
		(width 0.14224)
		(layer "In4.Cu")
		(net "M_B_DQ<35>")
	)
	(segment
		(start 275.284184 -49.478946)
		(end 275.284184 -48.443642)
		(width 0.0889)
		(layer "In4.Cu")
		(net "M_B_DQ<35>")
	)
	(segment
		(start 287.666684 -7.403084)
		(end 287.349946 -7.086346)
		(width 0.14224)
		(layer "In4.Cu")
		(net "M_B_DQ<35>")
	)
	(segment
		(start 277.575772 -45.677074)
		(end 277.59025 -45.662596)
		(width 0.14224)
		(layer "In4.Cu")
		(net "M_B_DQ<35>")
	)
	(segment
		(start 287.716214 -13.568172)
		(end 287.716214 -13.161772)
		(width 0.14224)
		(layer "In4.Cu")
		(net "M_B_DQ<35>")
	)
	(segment
		(start 278.276812 -44.073064)
		(end 278.276812 -41.919906)
		(width 0.14224)
		(layer "In4.Cu")
		(net "M_B_DQ<35>")
	)
	(segment
		(start 288.19983 -12.678156)
		(end 288.552636 -12.32535)
		(width 0.14224)
		(layer "In4.Cu")
		(net "M_B_DQ<35>")
	)
	(arc
		(start 273.709638 -56.695086)
		(mid 273.851321 -56.551282)
		(end 274.045172 -56.494934)
		(width 0.0889)
		(layer "In4.Cu")
		(net "M_B_DQ<35>")
	)
	(arc
		(start 274.08124 -56.494934)
		(mid 274.569964 -56.196904)
		(end 274.577048 -55.624476)
		(width 0.0889)
		(layer "In4.Cu")
		(net "M_B_DQ<35>")
	)
	(arc
		(start 274.563332 -54.61)
		(mid 274.514546 -54.413648)
		(end 274.568158 -54.218586)
		(width 0.0889)
		(layer "In4.Cu")
		(net "M_B_DQ<35>")
	)
	(arc
		(start 273.263106 -56.987186)
		(mid 273.521243 -56.894432)
		(end 273.709638 -56.695086)
		(width 0.0889)
		(layer "In4.Cu")
		(net "M_B_DQ<35>")
	)
	(arc
		(start 274.568158 -55.609236)
		(mid 274.514625 -55.409338)
		(end 274.568158 -55.20944)
		(width 0.0889)
		(layer "In4.Cu")
		(net "M_B_DQ<35>")
	)
	(arc
		(start 274.568158 -55.20944)
		(mid 274.647347 -54.922825)
		(end 274.577048 -54.633876)
		(width 0.0889)
		(layer "In4.Cu")
		(net "M_B_DQ<35>")
	)
	(segment
		(start 288.19983 -10.422382)
		(end 288.19983 -9.425432)
		(width 0.1651)
		(layer "F.Cu")
		(net "M_B_DQ<34>")
	)
	(segment
		(start 288.200338 -10.422382)
		(end 288.19983 -10.422382)
		(width 0.1651)
		(layer "F.Cu")
		(net "M_B_DQ<34>")
	)
	(segment
		(start 288.19983 -9.425432)
		(end 288.331402 -9.29386)
		(width 0.1651)
		(layer "F.Cu")
		(net "M_B_DQ<34>")
	)
	(segment
		(start 288.331402 -9.29386)
		(end 288.331402 -9.07034)
		(width 0.1651)
		(layer "F.Cu")
		(net "M_B_DQ<34>")
	)
	(segment
		(start 288.331402 -9.07034)
		(end 288.19983 -8.938768)
		(width 0.1651)
		(layer "F.Cu")
		(net "M_B_DQ<34>")
	)
	(segment
		(start 288.19983 -8.938768)
		(end 288.19983 -8.6614)
		(width 0.1651)
		(layer "F.Cu")
		(net "M_B_DQ<34>")
	)
	(segment
		(start 273.769328 -56.399938)
		(end 273.197828 -56.399938)
		(width 0.1016)
		(layer "F.Cu")
		(net "M_B_DQ<34>")
	)
	(via
		(at 287.349946 -13.959078)
		(size 0.508)
		(drill 0.254)
		(layers "F.Cu" "B.Cu")
		(net "M_B_DQ<34>")
	)
	(via
		(at 273.197828 -56.399938)
		(size 0.508)
		(drill 0.254)
		(layers "F.Cu" "B.Cu")
		(net "M_B_DQ<34>")
	)
	(via
		(at 288.19983 -8.6614)
		(size 0.508)
		(drill 0.254)
		(layers "F.Cu" "B.Cu")
		(net "M_B_DQ<34>")
	)
	(segment
		(start 287.350454 -15.222982)
		(end 287.349946 -15.222982)
		(width 0.1651)
		(layer "B.Cu")
		(net "M_B_DQ<34>")
	)
	(segment
		(start 287.349946 -15.222982)
		(end 287.349946 -13.959078)
		(width 0.1651)
		(layer "B.Cu")
		(net "M_B_DQ<34>")
	)
	(segment
		(start 287.45434 -24.61387)
		(end 287.728914 -24.61387)
		(width 0.14224)
		(layer "In4.Cu")
		(net "M_B_DQ<34>")
	)
	(segment
		(start 287.932114 -25.62987)
		(end 287.728914 -25.42667)
		(width 0.14224)
		(layer "In4.Cu")
		(net "M_B_DQ<34>")
	)
	(segment
		(start 276.95525 -45.662596)
		(end 276.95525 -43.636946)
		(width 0.14224)
		(layer "In4.Cu")
		(net "M_B_DQ<34>")
	)
	(segment
		(start 276.95525 -43.636946)
		(end 277.11019 -43.482006)
		(width 0.14224)
		(layer "In4.Cu")
		(net "M_B_DQ<34>")
	)
	(segment
		(start 287.3121 -24.75611)
		(end 287.45434 -24.61387)
		(width 0.14224)
		(layer "In4.Cu")
		(net "M_B_DQ<34>")
	)
	(segment
		(start 277.5458 -43.339766)
		(end 277.5458 -42.834306)
		(width 0.14224)
		(layer "In4.Cu")
		(net "M_B_DQ<34>")
	)
	(segment
		(start 287.801812 -9.364472)
		(end 287.801812 -9.059418)
		(width 0.14224)
		(layer "In4.Cu")
		(net "M_B_DQ<34>")
	)
	(segment
		(start 287.728914 -24.61387)
		(end 287.932114 -24.41067)
		(width 0.14224)
		(layer "In4.Cu")
		(net "M_B_DQ<34>")
	)
	(segment
		(start 287.45434 -25.42667)
		(end 287.3121 -25.28443)
		(width 0.14224)
		(layer "In4.Cu")
		(net "M_B_DQ<34>")
	)
	(segment
		(start 287.349946 -13.959078)
		(end 287.065212 -13.674344)
		(width 0.14224)
		(layer "In4.Cu")
		(net "M_B_DQ<34>")
	)
	(segment
		(start 287.45688 -9.709404)
		(end 287.801812 -9.364472)
		(width 0.14224)
		(layer "In4.Cu")
		(net "M_B_DQ<34>")
	)
	(segment
		(start 274.402804 -54.122828)
		(end 274.456398 -54.030118)
		(width 0.0889)
		(layer "In4.Cu")
		(net "M_B_DQ<34>")
	)
	(segment
		(start 277.11019 -43.482006)
		(end 277.40356 -43.482006)
		(width 0.14224)
		(layer "In4.Cu")
		(net "M_B_DQ<34>")
	)
	(segment
		(start 274.456398 -52.397914)
		(end 274.811744 -52.042568)
		(width 0.0889)
		(layer "In4.Cu")
		(net "M_B_DQ<34>")
	)
	(segment
		(start 287.932114 -23.385272)
		(end 287.690814 -23.143972)
		(width 0.14224)
		(layer "In4.Cu")
		(net "M_B_DQ<34>")
	)
	(segment
		(start 287.76168 -10.362946)
		(end 287.45688 -10.058146)
		(width 0.14224)
		(layer "In4.Cu")
		(net "M_B_DQ<34>")
	)
	(segment
		(start 274.811744 -52.042568)
		(end 274.811744 -49.682654)
		(width 0.0889)
		(layer "In4.Cu")
		(net "M_B_DQ<34>")
	)
	(segment
		(start 274.456398 -54.030118)
		(end 274.456398 -52.397914)
		(width 0.0889)
		(layer "In4.Cu")
		(net "M_B_DQ<34>")
	)
	(segment
		(start 287.690814 -21.950172)
		(end 287.843214 -21.797772)
		(width 0.14224)
		(layer "In4.Cu")
		(net "M_B_DQ<34>")
	)
	(segment
		(start 287.919414 -16.764762)
		(end 287.919414 -14.686026)
		(width 0.14224)
		(layer "In4.Cu")
		(net "M_B_DQ<34>")
	)
	(segment
		(start 276.95525 -42.537126)
		(end 276.95525 -38.69055)
		(width 0.14224)
		(layer "In4.Cu")
		(net "M_B_DQ<34>")
	)
	(segment
		(start 287.716214 -18.425414)
		(end 287.716214 -16.967962)
		(width 0.14224)
		(layer "In4.Cu")
		(net "M_B_DQ<34>")
	)
	(segment
		(start 287.728914 -25.42667)
		(end 287.45434 -25.42667)
		(width 0.14224)
		(layer "In4.Cu")
		(net "M_B_DQ<34>")
	)
	(segment
		(start 287.919414 -14.686026)
		(end 287.349946 -14.116558)
		(width 0.14224)
		(layer "In4.Cu")
		(net "M_B_DQ<34>")
	)
	(segment
		(start 277.5458 -42.834306)
		(end 277.40356 -42.692066)
		(width 0.14224)
		(layer "In4.Cu")
		(net "M_B_DQ<34>")
	)
	(segment
		(start 274.811744 -49.682654)
		(end 275.094192 -49.400206)
		(width 0.0889)
		(layer "In4.Cu")
		(net "M_B_DQ<34>")
	)
	(segment
		(start 287.91408 -11.811)
		(end 287.45688 -11.3538)
		(width 0.14224)
		(layer "In4.Cu")
		(net "M_B_DQ<34>")
	)
	(segment
		(start 287.349946 -14.116558)
		(end 287.349946 -13.959078)
		(width 0.14224)
		(layer "In4.Cu")
		(net "M_B_DQ<34>")
	)
	(segment
		(start 275.094192 -49.400206)
		(end 275.094192 -48.364902)
		(width 0.0889)
		(layer "In4.Cu")
		(net "M_B_DQ<34>")
	)
	(segment
		(start 277.160736 -46.298358)
		(end 277.160736 -45.897038)
		(width 0.0889)
		(layer "In4.Cu")
		(net "M_B_DQ<34>")
	)
	(segment
		(start 287.45688 -10.058146)
		(end 287.45688 -9.709404)
		(width 0.14224)
		(layer "In4.Cu")
		(net "M_B_DQ<34>")
	)
	(segment
		(start 277.11019 -42.692066)
		(end 276.95525 -42.537126)
		(width 0.14224)
		(layer "In4.Cu")
		(net "M_B_DQ<34>")
	)
	(segment
		(start 287.91408 -12.079732)
		(end 287.91408 -11.811)
		(width 0.14224)
		(layer "In4.Cu")
		(net "M_B_DQ<34>")
	)
	(segment
		(start 274.038568 -56.304434)
		(end 274.056348 -56.304434)
		(width 0.0889)
		(layer "In4.Cu")
		(net "M_B_DQ<34>")
	)
	(segment
		(start 274.402804 -55.704486)
		(end 274.393914 -55.689246)
		(width 0.0889)
		(layer "In4.Cu")
		(net "M_B_DQ<34>")
	)
	(segment
		(start 274.402804 -54.713886)
		(end 274.392136 -54.695344)
		(width 0.0889)
		(layer "In4.Cu")
		(net "M_B_DQ<34>")
	)
	(segment
		(start 287.690814 -23.143972)
		(end 287.690814 -21.950172)
		(width 0.14224)
		(layer "In4.Cu")
		(net "M_B_DQ<34>")
	)
	(segment
		(start 287.716214 -16.967962)
		(end 287.919414 -16.764762)
		(width 0.14224)
		(layer "In4.Cu")
		(net "M_B_DQ<34>")
	)
	(segment
		(start 276.95525 -38.69055)
		(end 287.932114 -27.713686)
		(width 0.14224)
		(layer "In4.Cu")
		(net "M_B_DQ<34>")
	)
	(segment
		(start 276.940772 -45.677074)
		(end 276.95525 -45.662596)
		(width 0.14224)
		(layer "In4.Cu")
		(net "M_B_DQ<34>")
	)
	(segment
		(start 287.76168 -10.64895)
		(end 287.76168 -10.362946)
		(width 0.14224)
		(layer "In4.Cu")
		(net "M_B_DQ<34>")
	)
	(segment
		(start 287.932114 -27.713686)
		(end 287.932114 -25.62987)
		(width 0.14224)
		(layer "In4.Cu")
		(net "M_B_DQ<34>")
	)
	(segment
		(start 273.197828 -56.399938)
		(end 273.197828 -56.738012)
		(width 0.0889)
		(layer "In4.Cu")
		(net "M_B_DQ<34>")
	)
	(segment
		(start 273.197828 -56.738012)
		(end 273.25574 -56.795924)
		(width 0.0889)
		(layer "In4.Cu")
		(net "M_B_DQ<34>")
	)
	(segment
		(start 287.843214 -21.797772)
		(end 287.843214 -18.552414)
		(width 0.14224)
		(layer "In4.Cu")
		(net "M_B_DQ<34>")
	)
	(segment
		(start 287.843214 -18.552414)
		(end 287.716214 -18.425414)
		(width 0.14224)
		(layer "In4.Cu")
		(net "M_B_DQ<34>")
	)
	(segment
		(start 277.40356 -43.482006)
		(end 277.5458 -43.339766)
		(width 0.14224)
		(layer "In4.Cu")
		(net "M_B_DQ<34>")
	)
	(segment
		(start 287.801812 -9.059418)
		(end 288.19983 -8.6614)
		(width 0.14224)
		(layer "In4.Cu")
		(net "M_B_DQ<34>")
	)
	(segment
		(start 277.40356 -42.692066)
		(end 277.11019 -42.692066)
		(width 0.14224)
		(layer "In4.Cu")
		(net "M_B_DQ<34>")
	)
	(segment
		(start 287.3121 -25.28443)
		(end 287.3121 -24.75611)
		(width 0.14224)
		(layer "In4.Cu")
		(net "M_B_DQ<34>")
	)
	(segment
		(start 287.45688 -11.3538)
		(end 287.45688 -10.95375)
		(width 0.14224)
		(layer "In4.Cu")
		(net "M_B_DQ<34>")
	)
	(segment
		(start 287.065212 -13.674344)
		(end 287.065212 -12.9286)
		(width 0.14224)
		(layer "In4.Cu")
		(net "M_B_DQ<34>")
	)
	(segment
		(start 287.065212 -12.9286)
		(end 287.91408 -12.079732)
		(width 0.14224)
		(layer "In4.Cu")
		(net "M_B_DQ<34>")
	)
	(segment
		(start 275.094192 -48.364902)
		(end 277.160736 -46.298358)
		(width 0.0889)
		(layer "In4.Cu")
		(net "M_B_DQ<34>")
	)
	(segment
		(start 287.932114 -24.41067)
		(end 287.932114 -23.385272)
		(width 0.14224)
		(layer "In4.Cu")
		(net "M_B_DQ<34>")
	)
	(segment
		(start 287.45688 -10.95375)
		(end 287.76168 -10.64895)
		(width 0.14224)
		(layer "In4.Cu")
		(net "M_B_DQ<34>")
	)
	(segment
		(start 277.160736 -45.897038)
		(end 276.940772 -45.677074)
		(width 0.0889)
		(layer "In4.Cu")
		(net "M_B_DQ<34>")
	)
	(arc
		(start 274.393914 -55.689246)
		(mid 274.323517 -55.400295)
		(end 274.402804 -55.113682)
		(width 0.0889)
		(layer "In4.Cu")
		(net "M_B_DQ<34>")
	)
	(arc
		(start 274.402804 -55.113682)
		(mid 274.456337 -54.913784)
		(end 274.402804 -54.713886)
		(width 0.0889)
		(layer "In4.Cu")
		(net "M_B_DQ<34>")
	)
	(arc
		(start 273.25574 -56.795924)
		(mid 273.422641 -56.731024)
		(end 273.544538 -56.599836)
		(width 0.0889)
		(layer "In4.Cu")
		(net "M_B_DQ<34>")
	)
	(arc
		(start 274.056348 -56.304434)
		(mid 274.402774 -56.104457)
		(end 274.402804 -55.704486)
		(width 0.0889)
		(layer "In4.Cu")
		(net "M_B_DQ<34>")
	)
	(arc
		(start 273.544538 -56.599836)
		(mid 273.753146 -56.387904)
		(end 274.038568 -56.304434)
		(width 0.0889)
		(layer "In4.Cu")
		(net "M_B_DQ<34>")
	)
	(arc
		(start 274.392136 -54.695344)
		(mid 274.323537 -54.40771)
		(end 274.402804 -54.122828)
		(width 0.0889)
		(layer "In4.Cu")
		(net "M_B_DQ<34>")
	)
	(segment
		(start 281.399996 -5.822442)
		(end 281.399996 -7.086346)
		(width 0.1651)
		(layer "F.Cu")
		(net "M_B_DQ<33>")
	)
	(segment
		(start 271.193768 -54.913784)
		(end 270.571468 -54.913784)
		(width 0.1651)
		(layer "F.Cu")
		(net "M_B_DQ<33>")
	)
	(segment
		(start 281.400504 -5.822442)
		(end 281.399996 -5.822442)
		(width 0.1651)
		(layer "F.Cu")
		(net "M_B_DQ<33>")
	)
	(via
		(at 282.07208 -12.678156)
		(size 0.508)
		(drill 0.254)
		(layers "F.Cu" "B.Cu")
		(net "M_B_DQ<33>")
	)
	(via
		(at 281.399996 -7.086346)
		(size 0.508)
		(drill 0.254)
		(layers "F.Cu" "B.Cu")
		(net "M_B_DQ<33>")
	)
	(via
		(at 270.571468 -54.913784)
		(size 0.508)
		(drill 0.254)
		(layers "F.Cu" "B.Cu")
		(net "M_B_DQ<33>")
	)
	(segment
		(start 282.24988 -10.623042)
		(end 282.24988 -11.997182)
		(width 0.1651)
		(layer "B.Cu")
		(net "M_B_DQ<33>")
	)
	(segment
		(start 282.250388 -10.623042)
		(end 282.24988 -10.623042)
		(width 0.1651)
		(layer "B.Cu")
		(net "M_B_DQ<33>")
	)
	(segment
		(start 282.07208 -12.174982)
		(end 282.07208 -12.678156)
		(width 0.1651)
		(layer "B.Cu")
		(net "M_B_DQ<33>")
	)
	(segment
		(start 282.24988 -11.997182)
		(end 282.07208 -12.174982)
		(width 0.1651)
		(layer "B.Cu")
		(net "M_B_DQ<33>")
	)
	(segment
		(start 282.602686 -8.8138)
		(end 282.446222 -8.970264)
		(width 0.14224)
		(layer "In4.Cu")
		(net "M_B_DQ<33>")
	)
	(segment
		(start 282.602686 -8.472424)
		(end 282.602686 -8.8138)
		(width 0.14224)
		(layer "In4.Cu")
		(net "M_B_DQ<33>")
	)
	(segment
		(start 270.226028 -55.113682)
		(end 270.239744 -55.137304)
		(width 0.0889)
		(layer "In4.Cu")
		(net "M_B_DQ<33>")
	)
	(segment
		(start 271.921224 -48.940466)
		(end 271.920716 -48.940974)
		(width 0.0889)
		(layer "In4.Cu")
		(net "M_B_DQ<33>")
	)
	(segment
		(start 282.232862 -8.1026)
		(end 282.602686 -8.472424)
		(width 0.14224)
		(layer "In4.Cu")
		(net "M_B_DQ<33>")
	)
	(segment
		(start 272.647156 -45.928534)
		(end 272.204688 -46.371002)
		(width 0.0889)
		(layer "In4.Cu")
		(net "M_B_DQ<33>")
	)
	(segment
		(start 281.545538 -13.204698)
		(end 281.545538 -13.474192)
		(width 0.14224)
		(layer "In4.Cu")
		(net "M_B_DQ<33>")
	)
	(segment
		(start 282.560014 -25.367742)
		(end 276.765512 -31.162244)
		(width 0.14224)
		(layer "In4.Cu")
		(net "M_B_DQ<33>")
	)
	(segment
		(start 277.075646 -31.673546)
		(end 277.276814 -31.673546)
		(width 0.14224)
		(layer "In4.Cu")
		(net "M_B_DQ<33>")
	)
	(segment
		(start 272.204688 -46.371002)
		(end 272.204688 -48.656494)
		(width 0.0889)
		(layer "In4.Cu")
		(net "M_B_DQ<33>")
	)
	(segment
		(start 277.276814 -31.673546)
		(end 277.982934 -30.967426)
		(width 0.14224)
		(layer "In4.Cu")
		(net "M_B_DQ<33>")
	)
	(segment
		(start 272.922492 -37.177218)
		(end 272.922492 -45.339254)
		(width 0.14224)
		(layer "In4.Cu")
		(net "M_B_DQ<33>")
	)
	(segment
		(start 277.982934 -30.967426)
		(end 278.253952 -30.967426)
		(width 0.14224)
		(layer "In4.Cu")
		(net "M_B_DQ<33>")
	)
	(segment
		(start 278.557482 -31.270956)
		(end 278.557482 -31.542228)
		(width 0.14224)
		(layer "In4.Cu")
		(net "M_B_DQ<33>")
	)
	(segment
		(start 281.399996 -7.625334)
		(end 281.877262 -8.1026)
		(width 0.14224)
		(layer "In4.Cu")
		(net "M_B_DQ<33>")
	)
	(segment
		(start 271.103344 -53.62956)
		(end 271.10944 -53.640482)
		(width 0.0889)
		(layer "In4.Cu")
		(net "M_B_DQ<33>")
	)
	(segment
		(start 270.571468 -55.251858)
		(end 270.571468 -54.913784)
		(width 0.0889)
		(layer "In4.Cu")
		(net "M_B_DQ<33>")
	)
	(segment
		(start 271.920716 -50.247296)
		(end 271.16151 -51.006502)
		(width 0.0889)
		(layer "In4.Cu")
		(net "M_B_DQ<33>")
	)
	(segment
		(start 276.765512 -31.162244)
		(end 276.765512 -31.363412)
		(width 0.14224)
		(layer "In4.Cu")
		(net "M_B_DQ<33>")
	)
	(segment
		(start 282.560014 -16.368268)
		(end 282.560014 -25.367742)
		(width 0.14224)
		(layer "In4.Cu")
		(net "M_B_DQ<33>")
	)
	(segment
		(start 272.204688 -48.656494)
		(end 271.921224 -48.939958)
		(width 0.0889)
		(layer "In4.Cu")
		(net "M_B_DQ<33>")
	)
	(segment
		(start 282.446222 -8.970264)
		(end 282.446222 -12.304014)
		(width 0.14224)
		(layer "In4.Cu")
		(net "M_B_DQ<33>")
	)
	(segment
		(start 281.877262 -8.1026)
		(end 282.232862 -8.1026)
		(width 0.14224)
		(layer "In4.Cu")
		(net "M_B_DQ<33>")
	)
	(segment
		(start 276.765512 -31.363412)
		(end 277.075646 -31.673546)
		(width 0.14224)
		(layer "In4.Cu")
		(net "M_B_DQ<33>")
	)
	(segment
		(start 278.557482 -31.542228)
		(end 272.922492 -37.177218)
		(width 0.14224)
		(layer "In4.Cu")
		(net "M_B_DQ<33>")
	)
	(segment
		(start 281.925014 -13.853668)
		(end 281.925014 -15.733268)
		(width 0.14224)
		(layer "In4.Cu")
		(net "M_B_DQ<33>")
	)
	(segment
		(start 281.545538 -13.474192)
		(end 281.925014 -13.853668)
		(width 0.14224)
		(layer "In4.Cu")
		(net "M_B_DQ<33>")
	)
	(segment
		(start 272.922492 -45.339254)
		(end 272.647156 -45.61459)
		(width 0.0889)
		(layer "In4.Cu")
		(net "M_B_DQ<33>")
	)
	(segment
		(start 270.51381 -55.309516)
		(end 270.571468 -55.251858)
		(width 0.0889)
		(layer "In4.Cu")
		(net "M_B_DQ<33>")
	)
	(segment
		(start 282.446222 -12.304014)
		(end 282.07208 -12.678156)
		(width 0.14224)
		(layer "In4.Cu")
		(net "M_B_DQ<33>")
	)
	(segment
		(start 271.921224 -48.939958)
		(end 271.921224 -48.940466)
		(width 0.0889)
		(layer "In4.Cu")
		(net "M_B_DQ<33>")
	)
	(segment
		(start 270.714724 -54.513734)
		(end 270.571468 -54.513734)
		(width 0.0889)
		(layer "In4.Cu")
		(net "M_B_DQ<33>")
	)
	(segment
		(start 278.253952 -30.967426)
		(end 278.557482 -31.270956)
		(width 0.14224)
		(layer "In4.Cu")
		(net "M_B_DQ<33>")
	)
	(segment
		(start 282.07208 -12.678156)
		(end 281.545538 -13.204698)
		(width 0.14224)
		(layer "In4.Cu")
		(net "M_B_DQ<33>")
	)
	(segment
		(start 270.240506 -54.688994)
		(end 270.221202 -54.722776)
		(width 0.0889)
		(layer "In4.Cu")
		(net "M_B_DQ<33>")
	)
	(segment
		(start 281.925014 -15.733268)
		(end 282.560014 -16.368268)
		(width 0.14224)
		(layer "In4.Cu")
		(net "M_B_DQ<33>")
	)
	(segment
		(start 281.399996 -7.086346)
		(end 281.399996 -7.625334)
		(width 0.14224)
		(layer "In4.Cu")
		(net "M_B_DQ<33>")
	)
	(segment
		(start 271.16151 -51.006502)
		(end 271.16151 -53.121814)
		(width 0.0889)
		(layer "In4.Cu")
		(net "M_B_DQ<33>")
	)
	(segment
		(start 271.920716 -48.940974)
		(end 271.920716 -50.247296)
		(width 0.0889)
		(layer "In4.Cu")
		(net "M_B_DQ<33>")
	)
	(segment
		(start 271.16151 -53.121814)
		(end 271.103344 -53.226716)
		(width 0.0889)
		(layer "In4.Cu")
		(net "M_B_DQ<33>")
	)
	(segment
		(start 272.647156 -45.61459)
		(end 272.647156 -45.928534)
		(width 0.0889)
		(layer "In4.Cu")
		(net "M_B_DQ<33>")
	)
	(arc
		(start 270.856456 -54.459886)
		(mid 270.787279 -54.491258)
		(end 270.714724 -54.513734)
		(width 0.0889)
		(layer "In4.Cu")
		(net "M_B_DQ<33>")
	)
	(arc
		(start 271.103344 -53.226716)
		(mid 271.051424 -53.428138)
		(end 271.103344 -53.62956)
		(width 0.0889)
		(layer "In4.Cu")
		(net "M_B_DQ<33>")
	)
	(arc
		(start 270.239744 -55.137304)
		(mid 270.35859 -55.25235)
		(end 270.51381 -55.309516)
		(width 0.0889)
		(layer "In4.Cu")
		(net "M_B_DQ<33>")
	)
	(arc
		(start 270.221202 -54.722776)
		(mid 270.172414 -54.918874)
		(end 270.226028 -55.113682)
		(width 0.0889)
		(layer "In4.Cu")
		(net "M_B_DQ<33>")
	)
	(arc
		(start 270.920464 -54.420516)
		(mid 270.889083 -54.441214)
		(end 270.856456 -54.459886)
		(width 0.0889)
		(layer "In4.Cu")
		(net "M_B_DQ<33>")
	)
	(arc
		(start 271.10944 -53.640482)
		(mid 271.162132 -54.066187)
		(end 270.920464 -54.420516)
		(width 0.0889)
		(layer "In4.Cu")
		(net "M_B_DQ<33>")
	)
	(arc
		(start 270.571468 -54.513734)
		(mid 270.384225 -54.560259)
		(end 270.240506 -54.688994)
		(width 0.0889)
		(layer "In4.Cu")
		(net "M_B_DQ<33>")
	)
	(segment
		(start 271.193768 -55.904384)
		(end 270.571468 -55.904384)
		(width 0.1651)
		(layer "F.Cu")
		(net "M_B_DQ<32>")
	)
	(segment
		(start 282.250388 -10.422382)
		(end 282.250388 -8.738108)
		(width 0.1651)
		(layer "F.Cu")
		(net "M_B_DQ<32>")
	)
	(segment
		(start 282.250388 -8.738108)
		(end 282.07208 -8.5598)
		(width 0.1651)
		(layer "F.Cu")
		(net "M_B_DQ<32>")
	)
	(via
		(at 270.571468 -55.904384)
		(size 0.508)
		(drill 0.254)
		(layers "F.Cu" "B.Cu")
		(net "M_B_DQ<32>")
	)
	(via
		(at 282.07208 -8.5598)
		(size 0.508)
		(drill 0.254)
		(layers "F.Cu" "B.Cu")
		(net "M_B_DQ<32>")
	)
	(via
		(at 281.399996 -13.959078)
		(size 0.508)
		(drill 0.254)
		(layers "F.Cu" "B.Cu")
		(net "M_B_DQ<32>")
	)
	(segment
		(start 281.399996 -15.222982)
		(end 281.399996 -13.959078)
		(width 0.1651)
		(layer "B.Cu")
		(net "M_B_DQ<32>")
	)
	(segment
		(start 281.400504 -15.222982)
		(end 281.399996 -15.222982)
		(width 0.1651)
		(layer "B.Cu")
		(net "M_B_DQ<32>")
	)
	(segment
		(start 271.73047 -48.86198)
		(end 272.014696 -48.577754)
		(width 0.0889)
		(layer "In4.Cu")
		(net "M_B_DQ<32>")
	)
	(segment
		(start 281.46248 -11.302746)
		(end 281.46248 -10.9982)
		(width 0.14224)
		(layer "In4.Cu")
		(net "M_B_DQ<32>")
	)
	(segment
		(start 274.26158 -32.822134)
		(end 274.26158 -32.620966)
		(width 0.14224)
		(layer "In4.Cu")
		(net "M_B_DQ<32>")
	)
	(segment
		(start 281.857196 -23.370794)
		(end 281.582114 -23.095712)
		(width 0.14224)
		(layer "In4.Cu")
		(net "M_B_DQ<32>")
	)
	(segment
		(start 276.204426 -32.99714)
		(end 276.204426 -32.795972)
		(width 0.14224)
		(layer "In4.Cu")
		(net "M_B_DQ<32>")
	)
	(segment
		(start 281.851862 -8.780018)
		(end 282.07208 -8.5598)
		(width 0.14224)
		(layer "In4.Cu")
		(net "M_B_DQ<32>")
	)
	(segment
		(start 281.399996 -13.959078)
		(end 281.115262 -13.674344)
		(width 0.14224)
		(layer "In4.Cu")
		(net "M_B_DQ<32>")
	)
	(segment
		(start 281.925014 -18.628614)
		(end 281.582114 -18.285714)
		(width 0.14224)
		(layer "In4.Cu")
		(net "M_B_DQ<32>")
	)
	(segment
		(start 275.830792 -32.422338)
		(end 275.629624 -32.422338)
		(width 0.14224)
		(layer "In4.Cu")
		(net "M_B_DQ<32>")
	)
	(segment
		(start 270.054578 -54.62905)
		(end 270.060928 -54.618382)
		(width 0.0889)
		(layer "In4.Cu")
		(net "M_B_DQ<32>")
	)
	(segment
		(start 270.941038 -53.730398)
		(end 270.930116 -53.71084)
		(width 0.0889)
		(layer "In4.Cu")
		(net "M_B_DQ<32>")
	)
	(segment
		(start 281.874214 -16.829786)
		(end 281.874214 -16.51508)
		(width 0.14224)
		(layer "In4.Cu")
		(net "M_B_DQ<32>")
	)
	(segment
		(start 281.925014 -21.683472)
		(end 281.925014 -18.628614)
		(width 0.14224)
		(layer "In4.Cu")
		(net "M_B_DQ<32>")
	)
	(segment
		(start 281.0764 -15.717266)
		(end 281.0764 -14.282674)
		(width 0.14224)
		(layer "In4.Cu")
		(net "M_B_DQ<32>")
	)
	(segment
		(start 281.851862 -11.692128)
		(end 281.46248 -11.302746)
		(width 0.14224)
		(layer "In4.Cu")
		(net "M_B_DQ<32>")
	)
	(segment
		(start 272.457164 -45.849794)
		(end 272.457164 -45.508164)
		(width 0.0889)
		(layer "In4.Cu")
		(net "M_B_DQ<32>")
	)
	(segment
		(start 281.77998 -10.6807)
		(end 281.77998 -10.4521)
		(width 0.14224)
		(layer "In4.Cu")
		(net "M_B_DQ<32>")
	)
	(segment
		(start 281.115262 -12.9286)
		(end 281.851862 -12.192)
		(width 0.14224)
		(layer "In4.Cu")
		(net "M_B_DQ<32>")
	)
	(segment
		(start 281.874214 -16.51508)
		(end 281.0764 -15.717266)
		(width 0.14224)
		(layer "In4.Cu")
		(net "M_B_DQ<32>")
	)
	(segment
		(start 270.571468 -54.323234)
		(end 270.688308 -54.323234)
		(width 0.0889)
		(layer "In4.Cu")
		(net "M_B_DQ<32>")
	)
	(segment
		(start 272.287492 -36.914074)
		(end 276.204426 -32.99714)
		(width 0.14224)
		(layer "In4.Cu")
		(net "M_B_DQ<32>")
	)
	(segment
		(start 281.851862 -12.192)
		(end 281.851862 -11.692128)
		(width 0.14224)
		(layer "In4.Cu")
		(net "M_B_DQ<32>")
	)
	(segment
		(start 271.73047 -50.167794)
		(end 271.73047 -48.86198)
		(width 0.0889)
		(layer "In4.Cu")
		(net "M_B_DQ<32>")
	)
	(segment
		(start 281.77998 -10.4521)
		(end 281.43708 -10.1092)
		(width 0.14224)
		(layer "In4.Cu")
		(net "M_B_DQ<32>")
	)
	(segment
		(start 281.851862 -9.364472)
		(end 281.851862 -8.780018)
		(width 0.14224)
		(layer "In4.Cu")
		(net "M_B_DQ<32>")
	)
	(segment
		(start 274.64512 -33.205674)
		(end 274.26158 -32.822134)
		(width 0.14224)
		(layer "In4.Cu")
		(net "M_B_DQ<32>")
	)
	(segment
		(start 281.43708 -9.779254)
		(end 281.851862 -9.364472)
		(width 0.14224)
		(layer "In4.Cu")
		(net "M_B_DQ<32>")
	)
	(segment
		(start 281.582114 -17.121886)
		(end 281.874214 -16.829786)
		(width 0.14224)
		(layer "In4.Cu")
		(net "M_B_DQ<32>")
	)
	(segment
		(start 272.287492 -45.338492)
		(end 272.287492 -36.914074)
		(width 0.14224)
		(layer "In4.Cu")
		(net "M_B_DQ<32>")
	)
	(segment
		(start 281.115262 -13.674344)
		(end 281.115262 -12.9286)
		(width 0.14224)
		(layer "In4.Cu")
		(net "M_B_DQ<32>")
	)
	(segment
		(start 281.582114 -22.026372)
		(end 281.925014 -21.683472)
		(width 0.14224)
		(layer "In4.Cu")
		(net "M_B_DQ<32>")
	)
	(segment
		(start 281.857196 -25.02535)
		(end 281.857196 -23.370794)
		(width 0.14224)
		(layer "In4.Cu")
		(net "M_B_DQ<32>")
	)
	(segment
		(start 281.582114 -18.285714)
		(end 281.582114 -17.121886)
		(width 0.14224)
		(layer "In4.Cu")
		(net "M_B_DQ<32>")
	)
	(segment
		(start 272.457164 -45.508164)
		(end 272.287492 -45.338492)
		(width 0.0889)
		(layer "In4.Cu")
		(net "M_B_DQ<32>")
	)
	(segment
		(start 270.571468 -55.904384)
		(end 270.571468 -55.56631)
		(width 0.0889)
		(layer "In4.Cu")
		(net "M_B_DQ<32>")
	)
	(segment
		(start 274.26158 -32.620966)
		(end 281.857196 -25.02535)
		(width 0.14224)
		(layer "In4.Cu")
		(net "M_B_DQ<32>")
	)
	(segment
		(start 270.971518 -53.07076)
		(end 270.971518 -50.926746)
		(width 0.0889)
		(layer "In4.Cu")
		(net "M_B_DQ<32>")
	)
	(segment
		(start 270.971518 -50.926746)
		(end 271.73047 -50.167794)
		(width 0.0889)
		(layer "In4.Cu")
		(net "M_B_DQ<32>")
	)
	(segment
		(start 275.629624 -32.422338)
		(end 274.846288 -33.205674)
		(width 0.14224)
		(layer "In4.Cu")
		(net "M_B_DQ<32>")
	)
	(segment
		(start 281.0764 -14.282674)
		(end 281.399996 -13.959078)
		(width 0.14224)
		(layer "In4.Cu")
		(net "M_B_DQ<32>")
	)
	(segment
		(start 274.846288 -33.205674)
		(end 274.64512 -33.205674)
		(width 0.14224)
		(layer "In4.Cu")
		(net "M_B_DQ<32>")
	)
	(segment
		(start 281.582114 -23.095712)
		(end 281.582114 -22.026372)
		(width 0.14224)
		(layer "In4.Cu")
		(net "M_B_DQ<32>")
	)
	(segment
		(start 281.46248 -10.9982)
		(end 281.77998 -10.6807)
		(width 0.14224)
		(layer "In4.Cu")
		(net "M_B_DQ<32>")
	)
	(segment
		(start 270.074136 -55.2323)
		(end 270.060928 -55.20944)
		(width 0.0889)
		(layer "In4.Cu")
		(net "M_B_DQ<32>")
	)
	(segment
		(start 270.936212 -53.13426)
		(end 270.971518 -53.07076)
		(width 0.0889)
		(layer "In4.Cu")
		(net "M_B_DQ<32>")
	)
	(segment
		(start 272.014696 -46.292262)
		(end 272.457164 -45.849794)
		(width 0.0889)
		(layer "In4.Cu")
		(net "M_B_DQ<32>")
	)
	(segment
		(start 270.060928 -54.618382)
		(end 270.07566 -54.593236)
		(width 0.0889)
		(layer "In4.Cu")
		(net "M_B_DQ<32>")
	)
	(segment
		(start 270.571468 -55.56631)
		(end 270.505936 -55.500778)
		(width 0.0889)
		(layer "In4.Cu")
		(net "M_B_DQ<32>")
	)
	(segment
		(start 276.204426 -32.795972)
		(end 275.830792 -32.422338)
		(width 0.14224)
		(layer "In4.Cu")
		(net "M_B_DQ<32>")
	)
	(segment
		(start 281.43708 -10.1092)
		(end 281.43708 -9.779254)
		(width 0.14224)
		(layer "In4.Cu")
		(net "M_B_DQ<32>")
	)
	(segment
		(start 272.014696 -48.577754)
		(end 272.014696 -46.292262)
		(width 0.0889)
		(layer "In4.Cu")
		(net "M_B_DQ<32>")
	)
	(arc
		(start 270.688308 -54.323234)
		(mid 270.831881 -54.248571)
		(end 270.936212 -54.12486)
		(width 0.0889)
		(layer "In4.Cu")
		(net "M_B_DQ<32>")
	)
	(arc
		(start 270.07566 -54.593236)
		(mid 270.289196 -54.395132)
		(end 270.571468 -54.323234)
		(width 0.0889)
		(layer "In4.Cu")
		(net "M_B_DQ<32>")
	)
	(arc
		(start 270.505936 -55.500778)
		(mid 270.259646 -55.415405)
		(end 270.074136 -55.2323)
		(width 0.0889)
		(layer "In4.Cu")
		(net "M_B_DQ<32>")
	)
	(arc
		(start 270.060928 -55.20944)
		(mid 269.981408 -54.920068)
		(end 270.054578 -54.62905)
		(width 0.0889)
		(layer "In4.Cu")
		(net "M_B_DQ<32>")
	)
	(arc
		(start 270.936212 -54.12486)
		(mid 270.988224 -53.928241)
		(end 270.941038 -53.730398)
		(width 0.0889)
		(layer "In4.Cu")
		(net "M_B_DQ<32>")
	)
	(arc
		(start 270.930116 -53.71084)
		(mid 270.860393 -53.421773)
		(end 270.936212 -53.13426)
		(width 0.0889)
		(layer "In4.Cu")
		(net "M_B_DQ<32>")
	)
	(segment
		(start 230.9622 -28.843478)
		(end 230.824278 -28.9814)
		(width 0.1651)
		(layer "F.Cu")
		(net "M_B_DQ<31>")
	)
	(segment
		(start 232.190798 -43.392344)
		(end 233.400346 -44.601892)
		(width 0.1651)
		(layer "F.Cu")
		(net "M_B_DQ<31>")
	)
	(segment
		(start 231.249728 -27.250136)
		(end 230.7844 -27.715464)
		(width 0.1651)
		(layer "F.Cu")
		(net "M_B_DQ<31>")
	)
	(segment
		(start 231.332278 -37.4777)
		(end 231.507538 -37.30244)
		(width 0.1651)
		(layer "F.Cu")
		(net "M_B_DQ<31>")
	)
	(segment
		(start 231.507538 -37.30244)
		(end 231.507538 -36.7411)
		(width 0.1651)
		(layer "F.Cu")
		(net "M_B_DQ<31>")
	)
	(segment
		(start 230.824278 -28.9814)
		(end 230.824278 -35.687)
		(width 0.1651)
		(layer "F.Cu")
		(net "M_B_DQ<31>")
	)
	(segment
		(start 233.591862 -44.793408)
		(end 233.591862 -45.271436)
		(width 0.1016)
		(layer "F.Cu")
		(net "M_B_DQ<31>")
	)
	(segment
		(start 237.752636 -45.97019)
		(end 238.552736 -46.77029)
		(width 0.1016)
		(layer "F.Cu")
		(net "M_B_DQ<31>")
	)
	(segment
		(start 234.290616 -45.97019)
		(end 237.752636 -45.97019)
		(width 0.1016)
		(layer "F.Cu")
		(net "M_B_DQ<31>")
	)
	(segment
		(start 230.824278 -37.30244)
		(end 230.999538 -37.4777)
		(width 0.1651)
		(layer "F.Cu")
		(net "M_B_DQ<31>")
	)
	(segment
		(start 245.175024 -52.211986)
		(end 244.768624 -52.618386)
		(width 0.0889)
		(layer "F.Cu")
		(net "M_B_DQ<31>")
	)
	(segment
		(start 230.999538 -37.4777)
		(end 231.332278 -37.4777)
		(width 0.1651)
		(layer "F.Cu")
		(net "M_B_DQ<31>")
	)
	(segment
		(start 245.175024 -49.404778)
		(end 245.175024 -49.455578)
		(width 0.1016)
		(layer "F.Cu")
		(net "M_B_DQ<31>")
	)
	(segment
		(start 230.399844 -5.822442)
		(end 230.399844 -7.086346)
		(width 0.1651)
		(layer "F.Cu")
		(net "M_B_DQ<31>")
	)
	(segment
		(start 230.400352 -5.822442)
		(end 230.399844 -5.822442)
		(width 0.1651)
		(layer "F.Cu")
		(net "M_B_DQ<31>")
	)
	(segment
		(start 231.507538 -36.7411)
		(end 231.672638 -36.576)
		(width 0.1651)
		(layer "F.Cu")
		(net "M_B_DQ<31>")
	)
	(segment
		(start 230.824278 -35.687)
		(end 230.824278 -37.30244)
		(width 0.1651)
		(layer "F.Cu")
		(net "M_B_DQ<31>")
	)
	(segment
		(start 242.540536 -46.77029)
		(end 245.175024 -49.404778)
		(width 0.1016)
		(layer "F.Cu")
		(net "M_B_DQ<31>")
	)
	(segment
		(start 245.175024 -49.455578)
		(end 245.175024 -52.211986)
		(width 0.0889)
		(layer "F.Cu")
		(net "M_B_DQ<31>")
	)
	(segment
		(start 232.190798 -36.7411)
		(end 232.190798 -43.392344)
		(width 0.1651)
		(layer "F.Cu")
		(net "M_B_DQ<31>")
	)
	(segment
		(start 238.552736 -46.77029)
		(end 242.540536 -46.77029)
		(width 0.1016)
		(layer "F.Cu")
		(net "M_B_DQ<31>")
	)
	(segment
		(start 230.7844 -27.715464)
		(end 230.7844 -28.230322)
		(width 0.1651)
		(layer "F.Cu")
		(net "M_B_DQ<31>")
	)
	(segment
		(start 232.025698 -36.576)
		(end 232.190798 -36.7411)
		(width 0.1651)
		(layer "F.Cu")
		(net "M_B_DQ<31>")
	)
	(segment
		(start 230.7844 -28.230322)
		(end 230.9622 -28.408122)
		(width 0.1651)
		(layer "F.Cu")
		(net "M_B_DQ<31>")
	)
	(segment
		(start 233.400346 -44.601892)
		(end 233.591862 -44.793408)
		(width 0.1016)
		(layer "F.Cu")
		(net "M_B_DQ<31>")
	)
	(segment
		(start 231.672638 -36.576)
		(end 232.025698 -36.576)
		(width 0.1651)
		(layer "F.Cu")
		(net "M_B_DQ<31>")
	)
	(segment
		(start 230.9622 -28.408122)
		(end 230.9622 -28.843478)
		(width 0.1651)
		(layer "F.Cu")
		(net "M_B_DQ<31>")
	)
	(segment
		(start 233.591862 -45.271436)
		(end 234.290616 -45.97019)
		(width 0.1016)
		(layer "F.Cu")
		(net "M_B_DQ<31>")
	)
	(via
		(at 231.249728 -27.250136)
		(size 0.508)
		(drill 0.254)
		(layers "F.Cu" "B.Cu")
		(net "M_B_DQ<31>")
	)
	(via
		(at 230.824278 -35.687)
		(size 0.508)
		(drill 0.254)
		(layers "F.Cu" "B.Cu")
		(net "M_B_DQ<31>")
	)
	(via
		(at 230.399844 -7.086346)
		(size 0.508)
		(drill 0.254)
		(layers "F.Cu" "B.Cu")
		(net "M_B_DQ<31>")
	)
	(via
		(at 231.249728 -12.678156)
		(size 0.508)
		(drill 0.254)
		(layers "F.Cu" "B.Cu")
		(net "M_B_DQ<31>")
	)
	(segment
		(start 231.249728 -10.623042)
		(end 231.249728 -12.678156)
		(width 0.1651)
		(layer "B.Cu")
		(net "M_B_DQ<31>")
	)
	(segment
		(start 231.25049 -10.623042)
		(end 231.249728 -10.623042)
		(width 0.1651)
		(layer "B.Cu")
		(net "M_B_DQ<31>")
	)
	(segment
		(start 230.792528 -13.640054)
		(end 230.792528 -13.135356)
		(width 0.14224)
		(layer "In4.Cu")
		(net "M_B_DQ<31>")
	)
	(segment
		(start 231.046782 -8.0518)
		(end 230.716582 -7.7216)
		(width 0.14224)
		(layer "In4.Cu")
		(net "M_B_DQ<31>")
	)
	(segment
		(start 231.460802 -16.699738)
		(end 231.460802 -14.308328)
		(width 0.14224)
		(layer "In4.Cu")
		(net "M_B_DQ<31>")
	)
	(segment
		(start 231.249728 -27.250136)
		(end 231.613202 -26.886662)
		(width 0.14224)
		(layer "In4.Cu")
		(net "M_B_DQ<31>")
	)
	(segment
		(start 231.613202 -26.886662)
		(end 231.613202 -23.294848)
		(width 0.14224)
		(layer "In4.Cu")
		(net "M_B_DQ<31>")
	)
	(segment
		(start 231.602534 -9.020048)
		(end 231.757982 -8.8646)
		(width 0.14224)
		(layer "In4.Cu")
		(net "M_B_DQ<31>")
	)
	(segment
		(start 231.300782 -8.0518)
		(end 231.046782 -8.0518)
		(width 0.14224)
		(layer "In4.Cu")
		(net "M_B_DQ<31>")
	)
	(segment
		(start 231.791002 -23.117048)
		(end 231.791002 -22.015196)
		(width 0.14224)
		(layer "In4.Cu")
		(net "M_B_DQ<31>")
	)
	(segment
		(start 231.613202 -23.294848)
		(end 231.791002 -23.117048)
		(width 0.14224)
		(layer "In4.Cu")
		(net "M_B_DQ<31>")
	)
	(segment
		(start 231.765602 -18.424398)
		(end 231.765602 -17.004538)
		(width 0.14224)
		(layer "In4.Cu")
		(net "M_B_DQ<31>")
	)
	(segment
		(start 230.792528 -13.135356)
		(end 231.249728 -12.678156)
		(width 0.14224)
		(layer "In4.Cu")
		(net "M_B_DQ<31>")
	)
	(segment
		(start 231.615996 -21.84019)
		(end 231.615996 -18.574004)
		(width 0.14224)
		(layer "In4.Cu")
		(net "M_B_DQ<31>")
	)
	(segment
		(start 231.615996 -18.574004)
		(end 231.765602 -18.424398)
		(width 0.14224)
		(layer "In4.Cu")
		(net "M_B_DQ<31>")
	)
	(segment
		(start 231.765602 -17.004538)
		(end 231.460802 -16.699738)
		(width 0.14224)
		(layer "In4.Cu")
		(net "M_B_DQ<31>")
	)
	(segment
		(start 231.757982 -8.8646)
		(end 231.757982 -8.509)
		(width 0.14224)
		(layer "In4.Cu")
		(net "M_B_DQ<31>")
	)
	(segment
		(start 231.460802 -14.308328)
		(end 230.792528 -13.640054)
		(width 0.14224)
		(layer "In4.Cu")
		(net "M_B_DQ<31>")
	)
	(segment
		(start 230.716582 -7.403084)
		(end 230.399844 -7.086346)
		(width 0.14224)
		(layer "In4.Cu")
		(net "M_B_DQ<31>")
	)
	(segment
		(start 230.716582 -7.7216)
		(end 230.716582 -7.403084)
		(width 0.14224)
		(layer "In4.Cu")
		(net "M_B_DQ<31>")
	)
	(segment
		(start 231.757982 -8.509)
		(end 231.300782 -8.0518)
		(width 0.14224)
		(layer "In4.Cu")
		(net "M_B_DQ<31>")
	)
	(segment
		(start 231.249728 -12.678156)
		(end 231.602534 -12.32535)
		(width 0.14224)
		(layer "In4.Cu")
		(net "M_B_DQ<31>")
	)
	(segment
		(start 231.791002 -22.015196)
		(end 231.615996 -21.84019)
		(width 0.14224)
		(layer "In4.Cu")
		(net "M_B_DQ<31>")
	)
	(segment
		(start 231.602534 -12.32535)
		(end 231.602534 -9.020048)
		(width 0.14224)
		(layer "In4.Cu")
		(net "M_B_DQ<31>")
	)
	(segment
		(start 242.414044 -47.07509)
		(end 238.426244 -47.07509)
		(width 0.1016)
		(layer "F.Cu")
		(net "M_B_DQ<30>")
	)
	(segment
		(start 230.1494 -41.4909)
		(end 230.2764 -41.6179)
		(width 0.1651)
		(layer "F.Cu")
		(net "M_B_DQ<30>")
	)
	(segment
		(start 231.249982 -9.4488)
		(end 231.382062 -9.31672)
		(width 0.1651)
		(layer "F.Cu")
		(net "M_B_DQ<30>")
	)
	(segment
		(start 233.128058 -45.246036)
		(end 233.128058 -45.364654)
		(width 0.1016)
		(layer "F.Cu")
		(net "M_B_DQ<30>")
	)
	(segment
		(start 230.2764 -41.6179)
		(end 230.70566 -41.6179)
		(width 0.1651)
		(layer "F.Cu")
		(net "M_B_DQ<30>")
	)
	(segment
		(start 230.1494 -32.231584)
		(end 230.1494 -33.02)
		(width 0.1651)
		(layer "F.Cu")
		(net "M_B_DQ<30>")
	)
	(segment
		(start 229.7938 -30.181804)
		(end 229.7938 -30.514544)
		(width 0.1651)
		(layer "F.Cu")
		(net "M_B_DQ<30>")
	)
	(segment
		(start 244.8052 -49.466246)
		(end 242.414044 -47.07509)
		(width 0.1016)
		(layer "F.Cu")
		(net "M_B_DQ<30>")
	)
	(segment
		(start 232.94213 -45.060108)
		(end 233.128058 -45.246036)
		(width 0.1016)
		(layer "F.Cu")
		(net "M_B_DQ<30>")
	)
	(segment
		(start 231.249982 -10.422382)
		(end 231.249982 -9.4488)
		(width 0.1651)
		(layer "F.Cu")
		(net "M_B_DQ<30>")
	)
	(segment
		(start 230.399844 -28.531058)
		(end 230.1494 -28.781502)
		(width 0.1651)
		(layer "F.Cu")
		(net "M_B_DQ<30>")
	)
	(segment
		(start 230.1494 -33.02)
		(end 230.1494 -41.4909)
		(width 0.1651)
		(layer "F.Cu")
		(net "M_B_DQ<30>")
	)
	(segment
		(start 229.7938 -31.548324)
		(end 229.7938 -31.881064)
		(width 0.1651)
		(layer "F.Cu")
		(net "M_B_DQ<30>")
	)
	(segment
		(start 231.382062 -9.09828)
		(end 231.249982 -8.9662)
		(width 0.1651)
		(layer "F.Cu")
		(net "M_B_DQ<30>")
	)
	(segment
		(start 231.382062 -9.31672)
		(end 231.382062 -9.09828)
		(width 0.1651)
		(layer "F.Cu")
		(net "M_B_DQ<30>")
	)
	(segment
		(start 237.715044 -46.36389)
		(end 234.127294 -46.36389)
		(width 0.1016)
		(layer "F.Cu")
		(net "M_B_DQ<30>")
	)
	(segment
		(start 231.249982 -8.9662)
		(end 231.249982 -8.661654)
		(width 0.1651)
		(layer "F.Cu")
		(net "M_B_DQ<30>")
	)
	(segment
		(start 229.97414 -30.689804)
		(end 230.1494 -30.865064)
		(width 0.1651)
		(layer "F.Cu")
		(net "M_B_DQ<30>")
	)
	(segment
		(start 230.1494 -29.831284)
		(end 229.97414 -30.006544)
		(width 0.1651)
		(layer "F.Cu")
		(net "M_B_DQ<30>")
	)
	(segment
		(start 229.97414 -32.056324)
		(end 230.1494 -32.231584)
		(width 0.1651)
		(layer "F.Cu")
		(net "M_B_DQ<30>")
	)
	(segment
		(start 233.128058 -45.364654)
		(end 234.127294 -46.36389)
		(width 0.1016)
		(layer "F.Cu")
		(net "M_B_DQ<30>")
	)
	(segment
		(start 244.8052 -49.57699)
		(end 244.8052 -49.466246)
		(width 0.1016)
		(layer "F.Cu")
		(net "M_B_DQ<30>")
	)
	(segment
		(start 230.1494 -31.197804)
		(end 229.97414 -31.373064)
		(width 0.1651)
		(layer "F.Cu")
		(net "M_B_DQ<30>")
	)
	(segment
		(start 230.83266 -39.5224)
		(end 230.95966 -39.3954)
		(width 0.1651)
		(layer "F.Cu")
		(net "M_B_DQ<30>")
	)
	(segment
		(start 231.249982 -8.661654)
		(end 231.249728 -8.6614)
		(width 0.1651)
		(layer "F.Cu")
		(net "M_B_DQ<30>")
	)
	(segment
		(start 229.96906 -30.006544)
		(end 229.7938 -30.181804)
		(width 0.1651)
		(layer "F.Cu")
		(net "M_B_DQ<30>")
	)
	(segment
		(start 230.83266 -41.4909)
		(end 230.83266 -39.5224)
		(width 0.1651)
		(layer "F.Cu")
		(net "M_B_DQ<30>")
	)
	(segment
		(start 238.426244 -47.07509)
		(end 237.715044 -46.36389)
		(width 0.1016)
		(layer "F.Cu")
		(net "M_B_DQ<30>")
	)
	(segment
		(start 231.38892 -39.3954)
		(end 231.51592 -39.5224)
		(width 0.1651)
		(layer "F.Cu")
		(net "M_B_DQ<30>")
	)
	(segment
		(start 229.96906 -32.056324)
		(end 229.97414 -32.056324)
		(width 0.1651)
		(layer "F.Cu")
		(net "M_B_DQ<30>")
	)
	(segment
		(start 229.97414 -30.006544)
		(end 229.96906 -30.006544)
		(width 0.1651)
		(layer "F.Cu")
		(net "M_B_DQ<30>")
	)
	(segment
		(start 244.768624 -50.63744)
		(end 244.768624 -50.277776)
		(width 0.0889)
		(layer "F.Cu")
		(net "M_B_DQ<30>")
	)
	(segment
		(start 229.97414 -31.373064)
		(end 229.96906 -31.373064)
		(width 0.1651)
		(layer "F.Cu")
		(net "M_B_DQ<30>")
	)
	(segment
		(start 231.25049 -10.422382)
		(end 231.249982 -10.422382)
		(width 0.1651)
		(layer "F.Cu")
		(net "M_B_DQ<30>")
	)
	(segment
		(start 229.96906 -30.689804)
		(end 229.97414 -30.689804)
		(width 0.1651)
		(layer "F.Cu")
		(net "M_B_DQ<30>")
	)
	(segment
		(start 244.8052 -50.2412)
		(end 244.8052 -49.57699)
		(width 0.0889)
		(layer "F.Cu")
		(net "M_B_DQ<30>")
	)
	(segment
		(start 230.1494 -30.865064)
		(end 230.1494 -31.197804)
		(width 0.1651)
		(layer "F.Cu")
		(net "M_B_DQ<30>")
	)
	(segment
		(start 230.95966 -39.3954)
		(end 231.38892 -39.3954)
		(width 0.1651)
		(layer "F.Cu")
		(net "M_B_DQ<30>")
	)
	(segment
		(start 230.1494 -28.781502)
		(end 230.1494 -29.831284)
		(width 0.1651)
		(layer "F.Cu")
		(net "M_B_DQ<30>")
	)
	(segment
		(start 229.96906 -31.373064)
		(end 229.7938 -31.548324)
		(width 0.1651)
		(layer "F.Cu")
		(net "M_B_DQ<30>")
	)
	(segment
		(start 230.70566 -41.6179)
		(end 230.83266 -41.4909)
		(width 0.1651)
		(layer "F.Cu")
		(net "M_B_DQ<30>")
	)
	(segment
		(start 229.7938 -31.881064)
		(end 229.96906 -32.056324)
		(width 0.1651)
		(layer "F.Cu")
		(net "M_B_DQ<30>")
	)
	(segment
		(start 231.51592 -43.633898)
		(end 232.94213 -45.060108)
		(width 0.1651)
		(layer "F.Cu")
		(net "M_B_DQ<30>")
	)
	(segment
		(start 244.768624 -50.277776)
		(end 244.8052 -50.2412)
		(width 0.0889)
		(layer "F.Cu")
		(net "M_B_DQ<30>")
	)
	(segment
		(start 231.51592 -39.5224)
		(end 231.51592 -43.633898)
		(width 0.1651)
		(layer "F.Cu")
		(net "M_B_DQ<30>")
	)
	(segment
		(start 229.7938 -30.514544)
		(end 229.96906 -30.689804)
		(width 0.1651)
		(layer "F.Cu")
		(net "M_B_DQ<30>")
	)
	(via
		(at 231.249728 -8.6614)
		(size 0.508)
		(drill 0.254)
		(layers "F.Cu" "B.Cu")
		(net "M_B_DQ<30>")
	)
	(via
		(at 230.399844 -28.531058)
		(size 0.508)
		(drill 0.254)
		(layers "F.Cu" "B.Cu")
		(net "M_B_DQ<30>")
	)
	(via
		(at 230.399844 -13.959078)
		(size 0.508)
		(drill 0.254)
		(layers "F.Cu" "B.Cu")
		(net "M_B_DQ<30>")
	)
	(via
		(at 230.1494 -33.02)
		(size 0.508)
		(drill 0.254)
		(layers "F.Cu" "B.Cu")
		(net "M_B_DQ<30>")
	)
	(segment
		(start 230.399844 -15.222982)
		(end 230.399844 -13.959078)
		(width 0.1651)
		(layer "B.Cu")
		(net "M_B_DQ<30>")
	)
	(segment
		(start 230.400352 -15.222982)
		(end 230.399844 -15.222982)
		(width 0.1651)
		(layer "B.Cu")
		(net "M_B_DQ<30>")
	)
	(segment
		(start 230.904796 -21.834602)
		(end 230.698802 -22.040596)
		(width 0.14224)
		(layer "In4.Cu")
		(net "M_B_DQ<30>")
	)
	(segment
		(start 230.902002 -16.832834)
		(end 230.698802 -17.036034)
		(width 0.14224)
		(layer "In4.Cu")
		(net "M_B_DQ<30>")
	)
	(segment
		(start 230.978202 -26.61285)
		(end 230.749602 -26.84145)
		(width 0.14224)
		(layer "In4.Cu")
		(net "M_B_DQ<30>")
	)
	(segment
		(start 230.399844 -13.959078)
		(end 230.902002 -14.461236)
		(width 0.14224)
		(layer "In4.Cu")
		(net "M_B_DQ<30>")
	)
	(segment
		(start 231.249728 -8.6614)
		(end 230.875332 -9.035796)
		(width 0.14224)
		(layer "In4.Cu")
		(net "M_B_DQ<30>")
	)
	(segment
		(start 230.9368 -12.156186)
		(end 230.164132 -12.928854)
		(width 0.14224)
		(layer "In4.Cu")
		(net "M_B_DQ<30>")
	)
	(segment
		(start 230.698802 -22.040596)
		(end 230.698802 -23.132796)
		(width 0.14224)
		(layer "In4.Cu")
		(net "M_B_DQ<30>")
	)
	(segment
		(start 230.9368 -11.804396)
		(end 230.9368 -12.156186)
		(width 0.14224)
		(layer "In4.Cu")
		(net "M_B_DQ<30>")
	)
	(segment
		(start 230.698802 -17.036034)
		(end 230.698802 -18.380202)
		(width 0.14224)
		(layer "In4.Cu")
		(net "M_B_DQ<30>")
	)
	(segment
		(start 230.51135 -11.093704)
		(end 230.51135 -11.378946)
		(width 0.14224)
		(layer "In4.Cu")
		(net "M_B_DQ<30>")
	)
	(segment
		(start 230.749602 -28.1813)
		(end 230.399844 -28.531058)
		(width 0.14224)
		(layer "In4.Cu")
		(net "M_B_DQ<30>")
	)
	(segment
		(start 230.875332 -9.313672)
		(end 230.51135 -9.677654)
		(width 0.14224)
		(layer "In4.Cu")
		(net "M_B_DQ<30>")
	)
	(segment
		(start 230.51135 -11.378946)
		(end 230.9368 -11.804396)
		(width 0.14224)
		(layer "In4.Cu")
		(net "M_B_DQ<30>")
	)
	(segment
		(start 230.51135 -9.988296)
		(end 230.89235 -10.369296)
		(width 0.14224)
		(layer "In4.Cu")
		(net "M_B_DQ<30>")
	)
	(segment
		(start 230.89235 -10.369296)
		(end 230.89235 -10.712704)
		(width 0.14224)
		(layer "In4.Cu")
		(net "M_B_DQ<30>")
	)
	(segment
		(start 230.978202 -23.412196)
		(end 230.978202 -26.61285)
		(width 0.14224)
		(layer "In4.Cu")
		(net "M_B_DQ<30>")
	)
	(segment
		(start 230.904796 -18.586196)
		(end 230.904796 -21.834602)
		(width 0.14224)
		(layer "In4.Cu")
		(net "M_B_DQ<30>")
	)
	(segment
		(start 230.51135 -9.677654)
		(end 230.51135 -9.988296)
		(width 0.14224)
		(layer "In4.Cu")
		(net "M_B_DQ<30>")
	)
	(segment
		(start 230.164132 -13.723366)
		(end 230.399844 -13.959078)
		(width 0.14224)
		(layer "In4.Cu")
		(net "M_B_DQ<30>")
	)
	(segment
		(start 230.698802 -23.132796)
		(end 230.978202 -23.412196)
		(width 0.14224)
		(layer "In4.Cu")
		(net "M_B_DQ<30>")
	)
	(segment
		(start 230.698802 -18.380202)
		(end 230.904796 -18.586196)
		(width 0.14224)
		(layer "In4.Cu")
		(net "M_B_DQ<30>")
	)
	(segment
		(start 230.749602 -26.84145)
		(end 230.749602 -28.1813)
		(width 0.14224)
		(layer "In4.Cu")
		(net "M_B_DQ<30>")
	)
	(segment
		(start 230.89235 -10.712704)
		(end 230.51135 -11.093704)
		(width 0.14224)
		(layer "In4.Cu")
		(net "M_B_DQ<30>")
	)
	(segment
		(start 230.164132 -12.928854)
		(end 230.164132 -13.723366)
		(width 0.14224)
		(layer "In4.Cu")
		(net "M_B_DQ<30>")
	)
	(segment
		(start 230.875332 -9.035796)
		(end 230.875332 -9.313672)
		(width 0.14224)
		(layer "In4.Cu")
		(net "M_B_DQ<30>")
	)
	(segment
		(start 230.902002 -14.461236)
		(end 230.902002 -16.832834)
		(width 0.14224)
		(layer "In4.Cu")
		(net "M_B_DQ<30>")
	)
	(segment
		(start 236.183678 -65.49644)
		(end 235.612178 -65.49644)
		(width 0.0889)
		(layer "F.Cu")
		(net "M_B_DQ<2>")
	)
	(segment
		(start 205.03134 -9.29386)
		(end 205.03134 -9.07034)
		(width 0.1651)
		(layer "F.Cu")
		(net "M_B_DQ<2>")
	)
	(segment
		(start 204.899768 -8.938768)
		(end 204.899768 -8.6614)
		(width 0.1651)
		(layer "F.Cu")
		(net "M_B_DQ<2>")
	)
	(segment
		(start 204.899768 -10.422382)
		(end 204.899768 -9.425432)
		(width 0.1651)
		(layer "F.Cu")
		(net "M_B_DQ<2>")
	)
	(segment
		(start 204.900276 -10.422382)
		(end 204.899768 -10.422382)
		(width 0.1651)
		(layer "F.Cu")
		(net "M_B_DQ<2>")
	)
	(segment
		(start 204.899768 -9.425432)
		(end 205.03134 -9.29386)
		(width 0.1651)
		(layer "F.Cu")
		(net "M_B_DQ<2>")
	)
	(segment
		(start 205.03134 -9.07034)
		(end 204.899768 -8.938768)
		(width 0.1651)
		(layer "F.Cu")
		(net "M_B_DQ<2>")
	)
	(via
		(at 204.899768 -8.6614)
		(size 0.508)
		(drill 0.254)
		(layers "F.Cu" "B.Cu")
		(net "M_B_DQ<2>")
	)
	(via
		(at 204.049884 -13.959078)
		(size 0.508)
		(drill 0.254)
		(layers "F.Cu" "B.Cu")
		(net "M_B_DQ<2>")
	)
	(via
		(at 235.612178 -65.49644)
		(size 0.508)
		(drill 0.254)
		(layers "F.Cu" "B.Cu")
		(net "M_B_DQ<2>")
	)
	(segment
		(start 204.049884 -15.222982)
		(end 204.049884 -13.959078)
		(width 0.1651)
		(layer "B.Cu")
		(net "M_B_DQ<2>")
	)
	(segment
		(start 204.050392 -15.222982)
		(end 204.049884 -15.222982)
		(width 0.1651)
		(layer "B.Cu")
		(net "M_B_DQ<2>")
	)
	(segment
		(start 204.416152 -18.437098)
		(end 204.543152 -18.564098)
		(width 0.14224)
		(layer "In4.Cu")
		(net "M_B_DQ<2>")
	)
	(segment
		(start 204.461618 -10.64895)
		(end 204.156818 -10.95375)
		(width 0.14224)
		(layer "In4.Cu")
		(net "M_B_DQ<2>")
	)
	(segment
		(start 204.8129 -34.546794)
		(end 204.96784 -34.701734)
		(width 0.14224)
		(layer "In4.Cu")
		(net "M_B_DQ<2>")
	)
	(segment
		(start 204.543152 -21.797772)
		(end 204.390752 -21.950172)
		(width 0.14224)
		(layer "In4.Cu")
		(net "M_B_DQ<2>")
	)
	(segment
		(start 217.706956 -48.901604)
		(end 217.925904 -48.901604)
		(width 0.14224)
		(layer "In4.Cu")
		(net "M_B_DQ<2>")
	)
	(segment
		(start 217.601038 -49.94529)
		(end 217.601038 -50.164238)
		(width 0.14224)
		(layer "In4.Cu")
		(net "M_B_DQ<2>")
	)
	(segment
		(start 216.66327 -49.22647)
		(end 216.913206 -49.476406)
		(width 0.14224)
		(layer "In4.Cu")
		(net "M_B_DQ<2>")
	)
	(segment
		(start 230.085646 -62.239906)
		(end 230.412544 -62.239906)
		(width 0.0889)
		(layer "In4.Cu")
		(net "M_B_DQ<2>")
	)
	(segment
		(start 204.614018 -12.079732)
		(end 203.76515 -12.9286)
		(width 0.14224)
		(layer "In4.Cu")
		(net "M_B_DQ<2>")
	)
	(segment
		(start 219.476574 -51.820826)
		(end 219.476574 -52.039774)
		(width 0.14224)
		(layer "In4.Cu")
		(net "M_B_DQ<2>")
	)
	(segment
		(start 219.113608 -50.308256)
		(end 218.538806 -50.883058)
		(width 0.14224)
		(layer "In4.Cu")
		(net "M_B_DQ<2>")
	)
	(segment
		(start 219.00769 -51.351942)
		(end 219.582492 -50.77714)
		(width 0.14224)
		(layer "In4.Cu")
		(net "M_B_DQ<2>")
	)
	(segment
		(start 204.50175 -9.364472)
		(end 204.156818 -9.709404)
		(width 0.14224)
		(layer "In4.Cu")
		(net "M_B_DQ<2>")
	)
	(segment
		(start 204.156818 -11.3538)
		(end 204.614018 -11.811)
		(width 0.14224)
		(layer "In4.Cu")
		(net "M_B_DQ<2>")
	)
	(segment
		(start 204.089 -24.282654)
		(end 204.089 -27.6098)
		(width 0.14224)
		(layer "In4.Cu")
		(net "M_B_DQ<2>")
	)
	(segment
		(start 219.80144 -50.77714)
		(end 220.051376 -51.027076)
		(width 0.14224)
		(layer "In4.Cu")
		(net "M_B_DQ<2>")
	)
	(segment
		(start 204.156818 -10.95375)
		(end 204.156818 -11.3538)
		(width 0.14224)
		(layer "In4.Cu")
		(net "M_B_DQ<2>")
	)
	(segment
		(start 220.739208 -51.714908)
		(end 220.989144 -51.964844)
		(width 0.14224)
		(layer "In4.Cu")
		(net "M_B_DQ<2>")
	)
	(segment
		(start 203.76515 -13.674344)
		(end 204.049884 -13.959078)
		(width 0.14224)
		(layer "In4.Cu")
		(net "M_B_DQ<2>")
	)
	(segment
		(start 204.619352 -14.686026)
		(end 204.619352 -16.764762)
		(width 0.14224)
		(layer "In4.Cu")
		(net "M_B_DQ<2>")
	)
	(segment
		(start 219.72651 -52.28971)
		(end 219.945458 -52.28971)
		(width 0.14224)
		(layer "In4.Cu")
		(net "M_B_DQ<2>")
	)
	(segment
		(start 204.632052 -23.739602)
		(end 204.089 -24.282654)
		(width 0.14224)
		(layer "In4.Cu")
		(net "M_B_DQ<2>")
	)
	(segment
		(start 204.5081 -33.1089)
		(end 204.6351 -33.2359)
		(width 0.14224)
		(layer "In4.Cu")
		(net "M_B_DQ<2>")
	)
	(segment
		(start 218.17584 -49.15154)
		(end 218.17584 -49.370488)
		(width 0.14224)
		(layer "In4.Cu")
		(net "M_B_DQ<2>")
	)
	(segment
		(start 206.0956 -34.856674)
		(end 206.0956 -37.0713)
		(width 0.14224)
		(layer "In4.Cu")
		(net "M_B_DQ<2>")
	)
	(segment
		(start 220.051376 -51.027076)
		(end 220.051376 -51.246024)
		(width 0.14224)
		(layer "In4.Cu")
		(net "M_B_DQ<2>")
	)
	(segment
		(start 234.732068 -65.591436)
		(end 234.92206 -65.591436)
		(width 0.0889)
		(layer "In4.Cu")
		(net "M_B_DQ<2>")
	)
	(segment
		(start 220.883226 -53.227478)
		(end 221.458028 -52.652676)
		(width 0.14224)
		(layer "In4.Cu")
		(net "M_B_DQ<2>")
	)
	(segment
		(start 220.989144 -51.964844)
		(end 220.989144 -52.183792)
		(width 0.14224)
		(layer "In4.Cu")
		(net "M_B_DQ<2>")
	)
	(segment
		(start 225.6536 -57.80786)
		(end 230.085646 -62.239906)
		(width 0.14224)
		(layer "In4.Cu")
		(net "M_B_DQ<2>")
	)
	(segment
		(start 204.96784 -34.038794)
		(end 204.8129 -34.193734)
		(width 0.14224)
		(layer "In4.Cu")
		(net "M_B_DQ<2>")
	)
	(segment
		(start 204.156818 -10.058146)
		(end 204.461618 -10.362946)
		(width 0.14224)
		(layer "In4.Cu")
		(net "M_B_DQ<2>")
	)
	(segment
		(start 231.487726 -64.10579)
		(end 232.268776 -64.10579)
		(width 0.0889)
		(layer "In4.Cu")
		(net "M_B_DQ<2>")
	)
	(segment
		(start 204.619352 -16.764762)
		(end 204.416152 -16.967962)
		(width 0.14224)
		(layer "In4.Cu")
		(net "M_B_DQ<2>")
	)
	(segment
		(start 217.238072 -48.43272)
		(end 216.66327 -49.007522)
		(width 0.14224)
		(layer "In4.Cu")
		(net "M_B_DQ<2>")
	)
	(segment
		(start 204.049884 -14.116558)
		(end 204.619352 -14.686026)
		(width 0.14224)
		(layer "In4.Cu")
		(net "M_B_DQ<2>")
	)
	(segment
		(start 204.5081 -28.0289)
		(end 204.5081 -33.1089)
		(width 0.14224)
		(layer "In4.Cu")
		(net "M_B_DQ<2>")
	)
	(segment
		(start 217.601038 -50.164238)
		(end 217.850974 -50.414174)
		(width 0.14224)
		(layer "In4.Cu")
		(net "M_B_DQ<2>")
	)
	(segment
		(start 218.069922 -50.414174)
		(end 218.644724 -49.839372)
		(width 0.14224)
		(layer "In4.Cu")
		(net "M_B_DQ<2>")
	)
	(segment
		(start 219.582492 -50.77714)
		(end 219.80144 -50.77714)
		(width 0.14224)
		(layer "In4.Cu")
		(net "M_B_DQ<2>")
	)
	(segment
		(start 230.412544 -62.239906)
		(end 230.620824 -62.448186)
		(width 0.0889)
		(layer "In4.Cu")
		(net "M_B_DQ<2>")
	)
	(segment
		(start 204.156818 -9.709404)
		(end 204.156818 -10.058146)
		(width 0.14224)
		(layer "In4.Cu")
		(net "M_B_DQ<2>")
	)
	(segment
		(start 218.17584 -49.370488)
		(end 217.601038 -49.94529)
		(width 0.14224)
		(layer "In4.Cu")
		(net "M_B_DQ<2>")
	)
	(segment
		(start 218.788742 -51.351942)
		(end 219.00769 -51.351942)
		(width 0.14224)
		(layer "In4.Cu")
		(net "M_B_DQ<2>")
	)
	(segment
		(start 217.238072 -48.213772)
		(end 217.238072 -48.43272)
		(width 0.14224)
		(layer "In4.Cu")
		(net "M_B_DQ<2>")
	)
	(segment
		(start 220.664278 -53.227478)
		(end 220.883226 -53.227478)
		(width 0.14224)
		(layer "In4.Cu")
		(net "M_B_DQ<2>")
	)
	(segment
		(start 204.50175 -9.059418)
		(end 204.50175 -9.364472)
		(width 0.14224)
		(layer "In4.Cu")
		(net "M_B_DQ<2>")
	)
	(segment
		(start 206.0956 -33.4391)
		(end 206.0956 -33.883854)
		(width 0.14224)
		(layer "In4.Cu")
		(net "M_B_DQ<2>")
	)
	(segment
		(start 217.850974 -50.414174)
		(end 218.069922 -50.414174)
		(width 0.14224)
		(layer "In4.Cu")
		(net "M_B_DQ<2>")
	)
	(segment
		(start 205.94066 -34.038794)
		(end 204.96784 -34.038794)
		(width 0.14224)
		(layer "In4.Cu")
		(net "M_B_DQ<2>")
	)
	(segment
		(start 204.461618 -10.362946)
		(end 204.461618 -10.64895)
		(width 0.14224)
		(layer "In4.Cu")
		(net "M_B_DQ<2>")
	)
	(segment
		(start 216.66327 -49.007522)
		(end 216.66327 -49.22647)
		(width 0.14224)
		(layer "In4.Cu")
		(net "M_B_DQ<2>")
	)
	(segment
		(start 218.644724 -49.839372)
		(end 218.863672 -49.839372)
		(width 0.14224)
		(layer "In4.Cu")
		(net "M_B_DQ<2>")
	)
	(segment
		(start 204.543152 -18.564098)
		(end 204.543152 -21.797772)
		(width 0.14224)
		(layer "In4.Cu")
		(net "M_B_DQ<2>")
	)
	(segment
		(start 233.877358 -65.09639)
		(end 233.910124 -65.09639)
		(width 0.0889)
		(layer "In4.Cu")
		(net "M_B_DQ<2>")
	)
	(segment
		(start 219.113608 -50.089308)
		(end 219.113608 -50.308256)
		(width 0.14224)
		(layer "In4.Cu")
		(net "M_B_DQ<2>")
	)
	(segment
		(start 234.92206 -65.591436)
		(end 235.59897 -65.513204)
		(width 0.0889)
		(layer "In4.Cu")
		(net "M_B_DQ<2>")
	)
	(segment
		(start 230.620824 -63.238888)
		(end 231.487726 -64.10579)
		(width 0.0889)
		(layer "In4.Cu")
		(net "M_B_DQ<2>")
	)
	(segment
		(start 221.676976 -52.652676)
		(end 225.6536 -56.6293)
		(width 0.14224)
		(layer "In4.Cu")
		(net "M_B_DQ<2>")
	)
	(segment
		(start 206.0956 -37.0713)
		(end 217.238072 -48.213772)
		(width 0.14224)
		(layer "In4.Cu")
		(net "M_B_DQ<2>")
	)
	(segment
		(start 204.390752 -23.143972)
		(end 204.632052 -23.385272)
		(width 0.14224)
		(layer "In4.Cu")
		(net "M_B_DQ<2>")
	)
	(segment
		(start 218.863672 -49.839372)
		(end 219.113608 -50.089308)
		(width 0.14224)
		(layer "In4.Cu")
		(net "M_B_DQ<2>")
	)
	(segment
		(start 204.8129 -34.193734)
		(end 204.8129 -34.546794)
		(width 0.14224)
		(layer "In4.Cu")
		(net "M_B_DQ<2>")
	)
	(segment
		(start 220.414342 -52.977542)
		(end 220.664278 -53.227478)
		(width 0.14224)
		(layer "In4.Cu")
		(net "M_B_DQ<2>")
	)
	(segment
		(start 204.6351 -33.2359)
		(end 205.8924 -33.2359)
		(width 0.14224)
		(layer "In4.Cu")
		(net "M_B_DQ<2>")
	)
	(segment
		(start 204.96784 -34.701734)
		(end 205.94066 -34.701734)
		(width 0.14224)
		(layer "In4.Cu")
		(net "M_B_DQ<2>")
	)
	(segment
		(start 217.925904 -48.901604)
		(end 218.17584 -49.15154)
		(width 0.14224)
		(layer "In4.Cu")
		(net "M_B_DQ<2>")
	)
	(segment
		(start 204.614018 -11.811)
		(end 204.614018 -12.079732)
		(width 0.14224)
		(layer "In4.Cu")
		(net "M_B_DQ<2>")
	)
	(segment
		(start 220.051376 -51.246024)
		(end 219.476574 -51.820826)
		(width 0.14224)
		(layer "In4.Cu")
		(net "M_B_DQ<2>")
	)
	(segment
		(start 206.0956 -33.883854)
		(end 205.94066 -34.038794)
		(width 0.14224)
		(layer "In4.Cu")
		(net "M_B_DQ<2>")
	)
	(segment
		(start 204.899768 -8.6614)
		(end 204.50175 -9.059418)
		(width 0.14224)
		(layer "In4.Cu")
		(net "M_B_DQ<2>")
	)
	(segment
		(start 204.416152 -16.967962)
		(end 204.416152 -18.437098)
		(width 0.14224)
		(layer "In4.Cu")
		(net "M_B_DQ<2>")
	)
	(segment
		(start 217.132154 -49.476406)
		(end 217.706956 -48.901604)
		(width 0.14224)
		(layer "In4.Cu")
		(net "M_B_DQ<2>")
	)
	(segment
		(start 216.913206 -49.476406)
		(end 217.132154 -49.476406)
		(width 0.14224)
		(layer "In4.Cu")
		(net "M_B_DQ<2>")
	)
	(segment
		(start 232.833418 -64.600836)
		(end 233.047794 -64.600836)
		(width 0.0889)
		(layer "In4.Cu")
		(net "M_B_DQ<2>")
	)
	(segment
		(start 204.089 -27.6098)
		(end 204.5081 -28.0289)
		(width 0.14224)
		(layer "In4.Cu")
		(net "M_B_DQ<2>")
	)
	(segment
		(start 204.632052 -23.385272)
		(end 204.632052 -23.739602)
		(width 0.14224)
		(layer "In4.Cu")
		(net "M_B_DQ<2>")
	)
	(segment
		(start 219.945458 -52.28971)
		(end 220.52026 -51.714908)
		(width 0.14224)
		(layer "In4.Cu")
		(net "M_B_DQ<2>")
	)
	(segment
		(start 205.8924 -33.2359)
		(end 206.0956 -33.4391)
		(width 0.14224)
		(layer "In4.Cu")
		(net "M_B_DQ<2>")
	)
	(segment
		(start 204.049884 -13.959078)
		(end 204.049884 -14.116558)
		(width 0.14224)
		(layer "In4.Cu")
		(net "M_B_DQ<2>")
	)
	(segment
		(start 221.458028 -52.652676)
		(end 221.676976 -52.652676)
		(width 0.14224)
		(layer "In4.Cu")
		(net "M_B_DQ<2>")
	)
	(segment
		(start 205.94066 -34.701734)
		(end 206.0956 -34.856674)
		(width 0.14224)
		(layer "In4.Cu")
		(net "M_B_DQ<2>")
	)
	(segment
		(start 230.620824 -62.448186)
		(end 230.620824 -63.238888)
		(width 0.0889)
		(layer "In4.Cu")
		(net "M_B_DQ<2>")
	)
	(segment
		(start 218.538806 -51.102006)
		(end 218.788742 -51.351942)
		(width 0.14224)
		(layer "In4.Cu")
		(net "M_B_DQ<2>")
	)
	(segment
		(start 220.52026 -51.714908)
		(end 220.739208 -51.714908)
		(width 0.14224)
		(layer "In4.Cu")
		(net "M_B_DQ<2>")
	)
	(segment
		(start 235.59897 -65.513204)
		(end 235.612178 -65.49644)
		(width 0.0889)
		(layer "In4.Cu")
		(net "M_B_DQ<2>")
	)
	(segment
		(start 220.414342 -52.758594)
		(end 220.414342 -52.977542)
		(width 0.14224)
		(layer "In4.Cu")
		(net "M_B_DQ<2>")
	)
	(segment
		(start 219.476574 -52.039774)
		(end 219.72651 -52.28971)
		(width 0.14224)
		(layer "In4.Cu")
		(net "M_B_DQ<2>")
	)
	(segment
		(start 218.538806 -50.883058)
		(end 218.538806 -51.102006)
		(width 0.14224)
		(layer "In4.Cu")
		(net "M_B_DQ<2>")
	)
	(segment
		(start 204.390752 -21.950172)
		(end 204.390752 -23.143972)
		(width 0.14224)
		(layer "In4.Cu")
		(net "M_B_DQ<2>")
	)
	(segment
		(start 225.6536 -56.6293)
		(end 225.6536 -57.80786)
		(width 0.14224)
		(layer "In4.Cu")
		(net "M_B_DQ<2>")
	)
	(segment
		(start 203.76515 -12.9286)
		(end 203.76515 -13.674344)
		(width 0.14224)
		(layer "In4.Cu")
		(net "M_B_DQ<2>")
	)
	(segment
		(start 220.989144 -52.183792)
		(end 220.414342 -52.758594)
		(width 0.14224)
		(layer "In4.Cu")
		(net "M_B_DQ<2>")
	)
	(arc
		(start 232.268776 -64.10579)
		(mid 232.393977 -64.185561)
		(end 232.48493 -64.302894)
		(width 0.0889)
		(layer "In4.Cu")
		(net "M_B_DQ<2>")
	)
	(arc
		(start 233.383328 -64.800988)
		(mid 233.591936 -65.01292)
		(end 233.877358 -65.09639)
		(width 0.0889)
		(layer "In4.Cu")
		(net "M_B_DQ<2>")
	)
	(arc
		(start 233.910124 -65.09639)
		(mid 234.101766 -65.153556)
		(end 234.241848 -65.296288)
		(width 0.0889)
		(layer "In4.Cu")
		(net "M_B_DQ<2>")
	)
	(arc
		(start 234.241848 -65.296288)
		(mid 234.448852 -65.507152)
		(end 234.732068 -65.591436)
		(width 0.0889)
		(layer "In4.Cu")
		(net "M_B_DQ<2>")
	)
	(arc
		(start 233.047794 -64.600836)
		(mid 233.241644 -64.657186)
		(end 233.383328 -64.800988)
		(width 0.0889)
		(layer "In4.Cu")
		(net "M_B_DQ<2>")
	)
	(arc
		(start 232.48493 -64.302894)
		(mid 232.630855 -64.484981)
		(end 232.833418 -64.600836)
		(width 0.0889)
		(layer "In4.Cu")
		(net "M_B_DQ<2>")
	)
	(segment
		(start 224.450402 -5.822442)
		(end 224.449894 -5.822442)
		(width 0.1651)
		(layer "F.Cu")
		(net "M_B_DQ<29>")
	)
	(segment
		(start 243.051838 -52.618386)
		(end 242.705128 -51.827938)
		(width 0.0889)
		(layer "F.Cu")
		(net "M_B_DQ<29>")
	)
	(segment
		(start 241.841782 -50.941224)
		(end 241.846608 -50.932588)
		(width 0.0889)
		(layer "F.Cu")
		(net "M_B_DQ<29>")
	)
	(segment
		(start 232.98404 -49.11979)
		(end 231.804464 -47.940214)
		(width 0.1016)
		(layer "F.Cu")
		(net "M_B_DQ<29>")
	)
	(segment
		(start 224.913444 -29.048456)
		(end 224.4852 -29.4767)
		(width 0.1651)
		(layer "F.Cu")
		(net "M_B_DQ<29>")
	)
	(segment
		(start 241.323114 -49.816004)
		(end 240.7158 -49.20869)
		(width 0.1016)
		(layer "F.Cu")
		(net "M_B_DQ<29>")
	)
	(segment
		(start 224.449894 -5.822442)
		(end 224.449894 -7.086346)
		(width 0.1651)
		(layer "F.Cu")
		(net "M_B_DQ<29>")
	)
	(segment
		(start 225.0694 -35.5854)
		(end 225.0694 -42.5958)
		(width 0.1651)
		(layer "F.Cu")
		(net "M_B_DQ<29>")
	)
	(segment
		(start 224.7392 -27.726386)
		(end 224.7392 -28.1432)
		(width 0.1651)
		(layer "F.Cu")
		(net "M_B_DQ<29>")
	)
	(segment
		(start 225.223578 -27.250136)
		(end 225.21545 -27.250136)
		(width 0.1651)
		(layer "F.Cu")
		(net "M_B_DQ<29>")
	)
	(segment
		(start 224.913444 -28.317444)
		(end 224.913444 -29.048456)
		(width 0.1651)
		(layer "F.Cu")
		(net "M_B_DQ<29>")
	)
	(segment
		(start 237.4519 -49.11979)
		(end 232.98404 -49.11979)
		(width 0.1016)
		(layer "F.Cu")
		(net "M_B_DQ<29>")
	)
	(segment
		(start 241.56035 -49.929034)
		(end 241.323114 -49.816004)
		(width 0.0889)
		(layer "F.Cu")
		(net "M_B_DQ<29>")
	)
	(segment
		(start 230.2256 -47.752)
		(end 230.403908 -47.930308)
		(width 0.1016)
		(layer "F.Cu")
		(net "M_B_DQ<29>")
	)
	(segment
		(start 237.5408 -49.20869)
		(end 237.4519 -49.11979)
		(width 0.1016)
		(layer "F.Cu")
		(net "M_B_DQ<29>")
	)
	(segment
		(start 224.4852 -34.036)
		(end 224.4852 -35.0012)
		(width 0.1651)
		(layer "F.Cu")
		(net "M_B_DQ<29>")
	)
	(segment
		(start 241.793522 -50.162206)
		(end 241.56035 -49.929034)
		(width 0.0889)
		(layer "F.Cu")
		(net "M_B_DQ<29>")
	)
	(segment
		(start 241.846608 -50.932588)
		(end 241.852958 -50.92192)
		(width 0.0889)
		(layer "F.Cu")
		(net "M_B_DQ<29>")
	)
	(segment
		(start 231.804464 -47.940214)
		(end 230.403908 -47.940214)
		(width 0.1016)
		(layer "F.Cu")
		(net "M_B_DQ<29>")
	)
	(segment
		(start 224.4852 -35.0012)
		(end 225.0694 -35.5854)
		(width 0.1651)
		(layer "F.Cu")
		(net "M_B_DQ<29>")
	)
	(segment
		(start 224.4852 -29.4767)
		(end 224.4852 -34.036)
		(width 0.1651)
		(layer "F.Cu")
		(net "M_B_DQ<29>")
	)
	(segment
		(start 230.403908 -47.930308)
		(end 230.403908 -47.940214)
		(width 0.1016)
		(layer "F.Cu")
		(net "M_B_DQ<29>")
	)
	(segment
		(start 240.7158 -49.20869)
		(end 237.5408 -49.20869)
		(width 0.1016)
		(layer "F.Cu")
		(net "M_B_DQ<29>")
	)
	(segment
		(start 242.211098 -51.532536)
		(end 242.178332 -51.532536)
		(width 0.0889)
		(layer "F.Cu")
		(net "M_B_DQ<29>")
	)
	(segment
		(start 224.7392 -28.1432)
		(end 224.913444 -28.317444)
		(width 0.1651)
		(layer "F.Cu")
		(net "M_B_DQ<29>")
	)
	(segment
		(start 225.21545 -27.250136)
		(end 224.7392 -27.726386)
		(width 0.1651)
		(layer "F.Cu")
		(net "M_B_DQ<29>")
	)
	(segment
		(start 225.0694 -42.5958)
		(end 230.2256 -47.752)
		(width 0.1651)
		(layer "F.Cu")
		(net "M_B_DQ<29>")
	)
	(via
		(at 225.223578 -12.678156)
		(size 0.508)
		(drill 0.254)
		(layers "F.Cu" "B.Cu")
		(net "M_B_DQ<29>")
	)
	(via
		(at 225.223578 -27.250136)
		(size 0.508)
		(drill 0.254)
		(layers "F.Cu" "B.Cu")
		(net "M_B_DQ<29>")
	)
	(via
		(at 224.4852 -34.036)
		(size 0.508)
		(drill 0.254)
		(layers "F.Cu" "B.Cu")
		(net "M_B_DQ<29>")
	)
	(via
		(at 224.449894 -7.086346)
		(size 0.508)
		(drill 0.254)
		(layers "F.Cu" "B.Cu")
		(net "M_B_DQ<29>")
	)
	(arc
		(start 242.705128 -51.827938)
		(mid 242.49652 -51.616006)
		(end 242.211098 -51.532536)
		(width 0.0889)
		(layer "F.Cu")
		(net "M_B_DQ<29>")
	)
	(arc
		(start 241.846608 -50.342038)
		(mid 241.809376 -50.255276)
		(end 241.793522 -50.162206)
		(width 0.0889)
		(layer "F.Cu")
		(net "M_B_DQ<29>")
	)
	(arc
		(start 242.178332 -51.532536)
		(mid 241.845414 -51.330545)
		(end 241.841782 -50.941224)
		(width 0.0889)
		(layer "F.Cu")
		(net "M_B_DQ<29>")
	)
	(arc
		(start 241.852958 -50.92192)
		(mid 241.925756 -50.631157)
		(end 241.846608 -50.342038)
		(width 0.0889)
		(layer "F.Cu")
		(net "M_B_DQ<29>")
	)
	(segment
		(start 225.299778 -10.623042)
		(end 225.299778 -12.601956)
		(width 0.1651)
		(layer "B.Cu")
		(net "M_B_DQ<29>")
	)
	(segment
		(start 225.300286 -10.623042)
		(end 225.299778 -10.623042)
		(width 0.1651)
		(layer "B.Cu")
		(net "M_B_DQ<29>")
	)
	(segment
		(start 225.299778 -12.601956)
		(end 225.223578 -12.678156)
		(width 0.1651)
		(layer "B.Cu")
		(net "M_B_DQ<29>")
	)
	(segment
		(start 225.731832 -8.8646)
		(end 225.534982 -9.06145)
		(width 0.14224)
		(layer "In4.Cu")
		(net "M_B_DQ<29>")
	)
	(segment
		(start 225.720402 -23.158196)
		(end 225.644202 -23.234396)
		(width 0.14224)
		(layer "In4.Cu")
		(net "M_B_DQ<29>")
	)
	(segment
		(start 225.618802 -14.435582)
		(end 225.618802 -17.032986)
		(width 0.14224)
		(layer "In4.Cu")
		(net "M_B_DQ<29>")
	)
	(segment
		(start 225.331528 -8.0518)
		(end 225.731832 -8.452104)
		(width 0.14224)
		(layer "In4.Cu")
		(net "M_B_DQ<29>")
	)
	(segment
		(start 225.534982 -12.366752)
		(end 225.223578 -12.678156)
		(width 0.14224)
		(layer "In4.Cu")
		(net "M_B_DQ<29>")
	)
	(segment
		(start 225.644202 -23.234396)
		(end 225.644202 -26.829512)
		(width 0.14224)
		(layer "In4.Cu")
		(net "M_B_DQ<29>")
	)
	(segment
		(start 225.695002 -18.455386)
		(end 225.618802 -18.531586)
		(width 0.14224)
		(layer "In4.Cu")
		(net "M_B_DQ<29>")
	)
	(segment
		(start 225.720402 -21.964396)
		(end 225.720402 -23.158196)
		(width 0.14224)
		(layer "In4.Cu")
		(net "M_B_DQ<29>")
	)
	(segment
		(start 224.449894 -7.481062)
		(end 225.020632 -8.0518)
		(width 0.14224)
		(layer "In4.Cu")
		(net "M_B_DQ<29>")
	)
	(segment
		(start 225.618802 -18.531586)
		(end 225.618802 -21.862796)
		(width 0.14224)
		(layer "In4.Cu")
		(net "M_B_DQ<29>")
	)
	(segment
		(start 225.644202 -26.829512)
		(end 225.223578 -27.250136)
		(width 0.14224)
		(layer "In4.Cu")
		(net "M_B_DQ<29>")
	)
	(segment
		(start 225.695002 -17.109186)
		(end 225.695002 -18.455386)
		(width 0.14224)
		(layer "In4.Cu")
		(net "M_B_DQ<29>")
	)
	(segment
		(start 225.095562 -12.678156)
		(end 224.707196 -13.066522)
		(width 0.14224)
		(layer "In4.Cu")
		(net "M_B_DQ<29>")
	)
	(segment
		(start 224.707196 -13.066522)
		(end 224.707196 -13.523976)
		(width 0.14224)
		(layer "In4.Cu")
		(net "M_B_DQ<29>")
	)
	(segment
		(start 225.731832 -8.452104)
		(end 225.731832 -8.8646)
		(width 0.14224)
		(layer "In4.Cu")
		(net "M_B_DQ<29>")
	)
	(segment
		(start 224.449894 -7.086346)
		(end 224.449894 -7.481062)
		(width 0.14224)
		(layer "In4.Cu")
		(net "M_B_DQ<29>")
	)
	(segment
		(start 224.707196 -13.523976)
		(end 225.618802 -14.435582)
		(width 0.14224)
		(layer "In4.Cu")
		(net "M_B_DQ<29>")
	)
	(segment
		(start 225.618802 -17.032986)
		(end 225.695002 -17.109186)
		(width 0.14224)
		(layer "In4.Cu")
		(net "M_B_DQ<29>")
	)
	(segment
		(start 225.020632 -8.0518)
		(end 225.331528 -8.0518)
		(width 0.14224)
		(layer "In4.Cu")
		(net "M_B_DQ<29>")
	)
	(segment
		(start 225.534982 -9.06145)
		(end 225.534982 -12.366752)
		(width 0.14224)
		(layer "In4.Cu")
		(net "M_B_DQ<29>")
	)
	(segment
		(start 225.223578 -12.678156)
		(end 225.095562 -12.678156)
		(width 0.14224)
		(layer "In4.Cu")
		(net "M_B_DQ<29>")
	)
	(segment
		(start 225.618802 -21.862796)
		(end 225.720402 -21.964396)
		(width 0.14224)
		(layer "In4.Cu")
		(net "M_B_DQ<29>")
	)
	(segment
		(start 240.584228 -49.52619)
		(end 232.815638 -49.52619)
		(width 0.127)
		(layer "F.Cu")
		(net "M_B_DQ<28>")
	)
	(segment
		(start 241.103912 -50.045874)
		(end 240.584228 -49.52619)
		(width 0.127)
		(layer "F.Cu")
		(net "M_B_DQ<28>")
	)
	(segment
		(start 223.7867 -40.300148)
		(end 223.6216 -40.465248)
		(width 0.1651)
		(layer "F.Cu")
		(net "M_B_DQ<28>")
	)
	(segment
		(start 224.3328 -38.788848)
		(end 224.1677 -38.953948)
		(width 0.1651)
		(layer "F.Cu")
		(net "M_B_DQ<28>")
	)
	(segment
		(start 241.675158 -50.848006)
		(end 241.681508 -50.837338)
		(width 0.0889)
		(layer "F.Cu")
		(net "M_B_DQ<28>")
	)
	(segment
		(start 224.1677 -40.300148)
		(end 223.7867 -40.300148)
		(width 0.1651)
		(layer "F.Cu")
		(net "M_B_DQ<28>")
	)
	(segment
		(start 224.3328 -42.786046)
		(end 229.774496 -48.227742)
		(width 0.1651)
		(layer "F.Cu")
		(net "M_B_DQ<28>")
	)
	(segment
		(start 225.300286 -10.422382)
		(end 225.299778 -10.422382)
		(width 0.1651)
		(layer "F.Cu")
		(net "M_B_DQ<28>")
	)
	(segment
		(start 223.7994 -29.181552)
		(end 223.7994 -35.687)
		(width 0.1651)
		(layer "F.Cu")
		(net "M_B_DQ<28>")
	)
	(segment
		(start 223.6216 -40.465248)
		(end 223.6216 -40.808148)
		(width 0.1651)
		(layer "F.Cu")
		(net "M_B_DQ<28>")
	)
	(segment
		(start 229.893876 -48.346614)
		(end 231.636062 -48.346614)
		(width 0.127)
		(layer "F.Cu")
		(net "M_B_DQ<28>")
	)
	(segment
		(start 229.774496 -48.227742)
		(end 229.775004 -48.227742)
		(width 0.1651)
		(layer "F.Cu")
		(net "M_B_DQ<28>")
	)
	(segment
		(start 224.3328 -39.792148)
		(end 224.3328 -40.135048)
		(width 0.1651)
		(layer "F.Cu")
		(net "M_B_DQ<28>")
	)
	(segment
		(start 225.299778 -9.091168)
		(end 225.239326 -8.763)
		(width 0.1651)
		(layer "F.Cu")
		(net "M_B_DQ<28>")
	)
	(segment
		(start 224.3328 -40.135048)
		(end 224.1677 -40.300148)
		(width 0.1651)
		(layer "F.Cu")
		(net "M_B_DQ<28>")
	)
	(segment
		(start 225.239326 -8.763)
		(end 225.201734 -8.5598)
		(width 0.1651)
		(layer "F.Cu")
		(net "M_B_DQ<28>")
	)
	(segment
		(start 224.3328 -38.0619)
		(end 224.3328 -38.788848)
		(width 0.1651)
		(layer "F.Cu")
		(net "M_B_DQ<28>")
	)
	(segment
		(start 223.7994 -35.687)
		(end 223.7994 -37.5285)
		(width 0.1651)
		(layer "F.Cu")
		(net "M_B_DQ<28>")
	)
	(segment
		(start 223.6216 -39.119048)
		(end 223.6216 -39.461948)
		(width 0.1651)
		(layer "F.Cu")
		(net "M_B_DQ<28>")
	)
	(segment
		(start 241.681508 -50.837338)
		(end 241.686334 -50.828702)
		(width 0.0889)
		(layer "F.Cu")
		(net "M_B_DQ<28>")
	)
	(segment
		(start 223.7867 -39.627048)
		(end 224.1677 -39.627048)
		(width 0.1651)
		(layer "F.Cu")
		(net "M_B_DQ<28>")
	)
	(segment
		(start 224.1677 -38.953948)
		(end 223.7867 -38.953948)
		(width 0.1651)
		(layer "F.Cu")
		(net "M_B_DQ<28>")
	)
	(segment
		(start 224.3328 -41.138348)
		(end 224.3328 -42.786046)
		(width 0.1651)
		(layer "F.Cu")
		(net "M_B_DQ<28>")
	)
	(segment
		(start 223.7867 -40.973248)
		(end 224.1677 -40.973248)
		(width 0.1651)
		(layer "F.Cu")
		(net "M_B_DQ<28>")
	)
	(segment
		(start 241.551206 -50.286158)
		(end 241.103912 -50.045874)
		(width 0.0889)
		(layer "F.Cu")
		(net "M_B_DQ<28>")
	)
	(segment
		(start 242.193318 -52.12334)
		(end 241.728244 -51.496976)
		(width 0.0889)
		(layer "F.Cu")
		(net "M_B_DQ<28>")
	)
	(segment
		(start 223.6216 -39.461948)
		(end 223.7867 -39.627048)
		(width 0.1651)
		(layer "F.Cu")
		(net "M_B_DQ<28>")
	)
	(segment
		(start 223.7867 -38.953948)
		(end 223.6216 -39.119048)
		(width 0.1651)
		(layer "F.Cu")
		(net "M_B_DQ<28>")
	)
	(segment
		(start 241.639598 -50.388774)
		(end 241.551206 -50.286158)
		(width 0.0889)
		(layer "F.Cu")
		(net "M_B_DQ<28>")
	)
	(segment
		(start 232.815638 -49.52619)
		(end 231.636062 -48.346614)
		(width 0.127)
		(layer "F.Cu")
		(net "M_B_DQ<28>")
	)
	(segment
		(start 229.775004 -48.227742)
		(end 229.893876 -48.346614)
		(width 0.127)
		(layer "F.Cu")
		(net "M_B_DQ<28>")
	)
	(segment
		(start 223.6216 -40.808148)
		(end 223.7867 -40.973248)
		(width 0.1651)
		(layer "F.Cu")
		(net "M_B_DQ<28>")
	)
	(segment
		(start 225.299778 -10.422382)
		(end 225.299778 -9.091168)
		(width 0.1651)
		(layer "F.Cu")
		(net "M_B_DQ<28>")
	)
	(segment
		(start 224.1677 -39.627048)
		(end 224.3328 -39.792148)
		(width 0.1651)
		(layer "F.Cu")
		(net "M_B_DQ<28>")
	)
	(segment
		(start 224.449894 -28.531058)
		(end 223.7994 -29.181552)
		(width 0.1651)
		(layer "F.Cu")
		(net "M_B_DQ<28>")
	)
	(segment
		(start 223.7994 -37.5285)
		(end 224.3328 -38.0619)
		(width 0.1651)
		(layer "F.Cu")
		(net "M_B_DQ<28>")
	)
	(segment
		(start 224.1677 -40.973248)
		(end 224.3328 -41.138348)
		(width 0.1651)
		(layer "F.Cu")
		(net "M_B_DQ<28>")
	)
	(via
		(at 224.449894 -28.531058)
		(size 0.508)
		(drill 0.254)
		(layers "F.Cu" "B.Cu")
		(net "M_B_DQ<28>")
	)
	(via
		(at 223.7994 -35.687)
		(size 0.508)
		(drill 0.254)
		(layers "F.Cu" "B.Cu")
		(net "M_B_DQ<28>")
	)
	(via
		(at 224.449894 -13.959078)
		(size 0.508)
		(drill 0.254)
		(layers "F.Cu" "B.Cu")
		(net "M_B_DQ<28>")
	)
	(via
		(at 225.201734 -8.5598)
		(size 0.508)
		(drill 0.254)
		(layers "F.Cu" "B.Cu")
		(net "M_B_DQ<28>")
	)
	(arc
		(start 241.728244 -51.496976)
		(mid 241.604245 -51.180456)
		(end 241.675158 -50.848006)
		(width 0.0889)
		(layer "F.Cu")
		(net "M_B_DQ<28>")
	)
	(arc
		(start 241.686334 -50.828702)
		(mid 241.731569 -50.60144)
		(end 241.639598 -50.388774)
		(width 0.0889)
		(layer "F.Cu")
		(net "M_B_DQ<28>")
	)
	(segment
		(start 224.449894 -15.222982)
		(end 224.449894 -13.959078)
		(width 0.1651)
		(layer "B.Cu")
		(net "M_B_DQ<28>")
	)
	(segment
		(start 224.450402 -15.222982)
		(end 224.449894 -15.222982)
		(width 0.1651)
		(layer "B.Cu")
		(net "M_B_DQ<28>")
	)
	(segment
		(start 224.925382 -12.217654)
		(end 224.925382 -11.742928)
		(width 0.14224)
		(layer "In4.Cu")
		(net "M_B_DQ<28>")
	)
	(segment
		(start 224.707196 -23.157942)
		(end 224.707196 -21.961602)
		(width 0.14224)
		(layer "In4.Cu")
		(net "M_B_DQ<28>")
	)
	(segment
		(start 224.5741 -11.0363)
		(end 224.9424 -10.668)
		(width 0.14224)
		(layer "In4.Cu")
		(net "M_B_DQ<28>")
	)
	(segment
		(start 224.933002 -21.735796)
		(end 224.933002 -18.531586)
		(width 0.14224)
		(layer "In4.Cu")
		(net "M_B_DQ<28>")
	)
	(segment
		(start 224.5614 -9.9822)
		(end 224.5614 -9.677654)
		(width 0.14224)
		(layer "In4.Cu")
		(net "M_B_DQ<28>")
	)
	(segment
		(start 224.214182 -13.723366)
		(end 224.214182 -12.928854)
		(width 0.14224)
		(layer "In4.Cu")
		(net "M_B_DQ<28>")
	)
	(segment
		(start 224.933002 -16.093186)
		(end 224.449894 -15.610078)
		(width 0.14224)
		(layer "In4.Cu")
		(net "M_B_DQ<28>")
	)
	(segment
		(start 224.707196 -21.961602)
		(end 224.933002 -21.735796)
		(width 0.14224)
		(layer "In4.Cu")
		(net "M_B_DQ<28>")
	)
	(segment
		(start 224.925382 -8.836152)
		(end 225.201734 -8.5598)
		(width 0.14224)
		(layer "In4.Cu")
		(net "M_B_DQ<28>")
	)
	(segment
		(start 224.704402 -28.27655)
		(end 224.704402 -26.971244)
		(width 0.14224)
		(layer "In4.Cu")
		(net "M_B_DQ<28>")
	)
	(segment
		(start 224.707196 -17.050004)
		(end 224.933002 -16.824198)
		(width 0.14224)
		(layer "In4.Cu")
		(net "M_B_DQ<28>")
	)
	(segment
		(start 224.925382 -9.313672)
		(end 224.925382 -8.836152)
		(width 0.14224)
		(layer "In4.Cu")
		(net "M_B_DQ<28>")
	)
	(segment
		(start 224.933002 -26.742644)
		(end 224.933002 -23.383748)
		(width 0.14224)
		(layer "In4.Cu")
		(net "M_B_DQ<28>")
	)
	(segment
		(start 224.925382 -11.742928)
		(end 224.5741 -11.391646)
		(width 0.14224)
		(layer "In4.Cu")
		(net "M_B_DQ<28>")
	)
	(segment
		(start 224.449894 -13.959078)
		(end 224.214182 -13.723366)
		(width 0.14224)
		(layer "In4.Cu")
		(net "M_B_DQ<28>")
	)
	(segment
		(start 224.933002 -18.531586)
		(end 224.707196 -18.30578)
		(width 0.14224)
		(layer "In4.Cu")
		(net "M_B_DQ<28>")
	)
	(segment
		(start 224.449894 -28.531058)
		(end 224.704402 -28.27655)
		(width 0.14224)
		(layer "In4.Cu")
		(net "M_B_DQ<28>")
	)
	(segment
		(start 224.704402 -26.971244)
		(end 224.933002 -26.742644)
		(width 0.14224)
		(layer "In4.Cu")
		(net "M_B_DQ<28>")
	)
	(segment
		(start 224.214182 -12.928854)
		(end 224.925382 -12.217654)
		(width 0.14224)
		(layer "In4.Cu")
		(net "M_B_DQ<28>")
	)
	(segment
		(start 224.707196 -18.30578)
		(end 224.707196 -17.050004)
		(width 0.14224)
		(layer "In4.Cu")
		(net "M_B_DQ<28>")
	)
	(segment
		(start 224.9424 -10.3632)
		(end 224.5614 -9.9822)
		(width 0.14224)
		(layer "In4.Cu")
		(net "M_B_DQ<28>")
	)
	(segment
		(start 224.933002 -16.824198)
		(end 224.933002 -16.093186)
		(width 0.14224)
		(layer "In4.Cu")
		(net "M_B_DQ<28>")
	)
	(segment
		(start 224.5741 -11.391646)
		(end 224.5741 -11.0363)
		(width 0.14224)
		(layer "In4.Cu")
		(net "M_B_DQ<28>")
	)
	(segment
		(start 224.5614 -9.677654)
		(end 224.925382 -9.313672)
		(width 0.14224)
		(layer "In4.Cu")
		(net "M_B_DQ<28>")
	)
	(segment
		(start 224.449894 -15.610078)
		(end 224.449894 -13.959078)
		(width 0.14224)
		(layer "In4.Cu")
		(net "M_B_DQ<28>")
	)
	(segment
		(start 224.933002 -23.383748)
		(end 224.707196 -23.157942)
		(width 0.14224)
		(layer "In4.Cu")
		(net "M_B_DQ<28>")
	)
	(segment
		(start 224.9424 -10.668)
		(end 224.9424 -10.3632)
		(width 0.14224)
		(layer "In4.Cu")
		(net "M_B_DQ<28>")
	)
	(segment
		(start 234.62234 -45.17009)
		(end 237.8329 -45.17009)
		(width 0.127)
		(layer "F.Cu")
		(net "M_B_DQ<27>")
	)
	(segment
		(start 233.703114 -35.98037)
		(end 233.868214 -36.14547)
		(width 0.1651)
		(layer "F.Cu")
		(net "M_B_DQ<27>")
	)
	(segment
		(start 234.3912 -39.34587)
		(end 234.2261 -39.51097)
		(width 0.1651)
		(layer "F.Cu")
		(net "M_B_DQ<27>")
	)
	(segment
		(start 242.7986 -46.14799)
		(end 238.8108 -46.14799)
		(width 0.127)
		(layer "F.Cu")
		(net "M_B_DQ<27>")
	)
	(segment
		(start 234.3912 -39.00297)
		(end 234.3912 -39.34587)
		(width 0.1651)
		(layer "F.Cu")
		(net "M_B_DQ<27>")
	)
	(segment
		(start 234.3912 -37.65677)
		(end 234.3912 -37.99967)
		(width 0.1651)
		(layer "F.Cu")
		(net "M_B_DQ<27>")
	)
	(segment
		(start 245.807484 -48.405034)
		(end 245.581424 -48.405034)
		(width 0.0889)
		(layer "F.Cu")
		(net "M_B_DQ<27>")
	)
	(segment
		(start 234.317794 -43.684444)
		(end 234.409234 -43.775884)
		(width 0.127)
		(layer "F.Cu")
		(net "M_B_DQ<27>")
	)
	(segment
		(start 245.581424 -48.405034)
		(end 245.055644 -48.405034)
		(width 0.127)
		(layer "F.Cu")
		(net "M_B_DQ<27>")
	)
	(segment
		(start 233.703114 -36.98367)
		(end 233.703114 -37.32657)
		(width 0.1651)
		(layer "F.Cu")
		(net "M_B_DQ<27>")
	)
	(segment
		(start 245.627144 -52.12334)
		(end 245.627144 -51.791616)
		(width 0.0889)
		(layer "F.Cu")
		(net "M_B_DQ<27>")
	)
	(segment
		(start 233.703114 -37.32657)
		(end 233.868214 -37.49167)
		(width 0.1651)
		(layer "F.Cu")
		(net "M_B_DQ<27>")
	)
	(segment
		(start 245.914926 -51.383692)
		(end 246.001032 -51.234848)
		(width 0.0889)
		(layer "F.Cu")
		(net "M_B_DQ<27>")
	)
	(segment
		(start 233.868214 -40.85717)
		(end 233.703114 -41.02227)
		(width 0.1651)
		(layer "F.Cu")
		(net "M_B_DQ<27>")
	)
	(segment
		(start 234.2261 -36.81857)
		(end 233.868214 -36.81857)
		(width 0.1651)
		(layer "F.Cu")
		(net "M_B_DQ<27>")
	)
	(segment
		(start 234.061 -40.69207)
		(end 233.8959 -40.85717)
		(width 0.1651)
		(layer "F.Cu")
		(net "M_B_DQ<27>")
	)
	(segment
		(start 233.703114 -43.069764)
		(end 234.317794 -43.684444)
		(width 0.1651)
		(layer "F.Cu")
		(net "M_B_DQ<27>")
	)
	(segment
		(start 234.2261 -38.16477)
		(end 233.868214 -38.16477)
		(width 0.1651)
		(layer "F.Cu")
		(net "M_B_DQ<27>")
	)
	(segment
		(start 234.3912 -36.65347)
		(end 234.2261 -36.81857)
		(width 0.1651)
		(layer "F.Cu")
		(net "M_B_DQ<27>")
	)
	(segment
		(start 233.868214 -36.14547)
		(end 234.2261 -36.14547)
		(width 0.1651)
		(layer "F.Cu")
		(net "M_B_DQ<27>")
	)
	(segment
		(start 234.2261 -36.14547)
		(end 234.3912 -36.31057)
		(width 0.1651)
		(layer "F.Cu")
		(net "M_B_DQ<27>")
	)
	(segment
		(start 234.2261 -38.83787)
		(end 234.3912 -39.00297)
		(width 0.1651)
		(layer "F.Cu")
		(net "M_B_DQ<27>")
	)
	(segment
		(start 233.703114 -38.32987)
		(end 233.703114 -38.67277)
		(width 0.1651)
		(layer "F.Cu")
		(net "M_B_DQ<27>")
	)
	(segment
		(start 234.3912 -37.99967)
		(end 234.2261 -38.16477)
		(width 0.1651)
		(layer "F.Cu")
		(net "M_B_DQ<27>")
	)
	(segment
		(start 233.8959 -40.85717)
		(end 233.868214 -40.85717)
		(width 0.1651)
		(layer "F.Cu")
		(net "M_B_DQ<27>")
	)
	(segment
		(start 233.708448 -32.032702)
		(end 233.708448 -34.544)
		(width 0.1651)
		(layer "F.Cu")
		(net "M_B_DQ<27>")
	)
	(segment
		(start 232.5624 -30.886654)
		(end 233.708448 -32.032702)
		(width 0.1651)
		(layer "F.Cu")
		(net "M_B_DQ<27>")
	)
	(segment
		(start 233.868214 -36.81857)
		(end 233.703114 -36.98367)
		(width 0.1651)
		(layer "F.Cu")
		(net "M_B_DQ<27>")
	)
	(segment
		(start 233.8959 -40.18407)
		(end 234.061 -40.34917)
		(width 0.1651)
		(layer "F.Cu")
		(net "M_B_DQ<27>")
	)
	(segment
		(start 233.868214 -38.83787)
		(end 234.2261 -38.83787)
		(width 0.1651)
		(layer "F.Cu")
		(net "M_B_DQ<27>")
	)
	(segment
		(start 233.703114 -35.793934)
		(end 233.703114 -35.98037)
		(width 0.1651)
		(layer "F.Cu")
		(net "M_B_DQ<27>")
	)
	(segment
		(start 234.409234 -44.956984)
		(end 234.62234 -45.17009)
		(width 0.127)
		(layer "F.Cu")
		(net "M_B_DQ<27>")
	)
	(segment
		(start 232.099866 -5.822442)
		(end 232.099866 -7.086346)
		(width 0.1651)
		(layer "F.Cu")
		(net "M_B_DQ<27>")
	)
	(segment
		(start 234.2261 -37.49167)
		(end 234.3912 -37.65677)
		(width 0.1651)
		(layer "F.Cu")
		(net "M_B_DQ<27>")
	)
	(segment
		(start 233.703114 -39.67607)
		(end 233.703114 -40.01897)
		(width 0.1651)
		(layer "F.Cu")
		(net "M_B_DQ<27>")
	)
	(segment
		(start 233.703114 -38.67277)
		(end 233.868214 -38.83787)
		(width 0.1651)
		(layer "F.Cu")
		(net "M_B_DQ<27>")
	)
	(segment
		(start 232.3592 -27.840686)
		(end 232.3592 -27.9908)
		(width 0.1651)
		(layer "F.Cu")
		(net "M_B_DQ<27>")
	)
	(segment
		(start 246.230394 -50.31232)
		(end 246.230394 -48.827944)
		(width 0.0889)
		(layer "F.Cu")
		(net "M_B_DQ<27>")
	)
	(segment
		(start 232.3592 -27.9908)
		(end 232.5624 -28.194)
		(width 0.1651)
		(layer "F.Cu")
		(net "M_B_DQ<27>")
	)
	(segment
		(start 237.8329 -45.17009)
		(end 238.8108 -46.14799)
		(width 0.127)
		(layer "F.Cu")
		(net "M_B_DQ<27>")
	)
	(segment
		(start 232.5624 -28.194)
		(end 232.5624 -30.886654)
		(width 0.1651)
		(layer "F.Cu")
		(net "M_B_DQ<27>")
	)
	(segment
		(start 232.100374 -5.822442)
		(end 232.099866 -5.822442)
		(width 0.1651)
		(layer "F.Cu")
		(net "M_B_DQ<27>")
	)
	(segment
		(start 233.703114 -40.01897)
		(end 233.868214 -40.18407)
		(width 0.1651)
		(layer "F.Cu")
		(net "M_B_DQ<27>")
	)
	(segment
		(start 234.2261 -39.51097)
		(end 233.868214 -39.51097)
		(width 0.1651)
		(layer "F.Cu")
		(net "M_B_DQ<27>")
	)
	(segment
		(start 246.230394 -48.827944)
		(end 245.807484 -48.405034)
		(width 0.0889)
		(layer "F.Cu")
		(net "M_B_DQ<27>")
	)
	(segment
		(start 245.055644 -48.405034)
		(end 242.7986 -46.14799)
		(width 0.127)
		(layer "F.Cu")
		(net "M_B_DQ<27>")
	)
	(segment
		(start 234.3912 -36.31057)
		(end 234.3912 -36.65347)
		(width 0.1651)
		(layer "F.Cu")
		(net "M_B_DQ<27>")
	)
	(segment
		(start 232.94975 -27.250136)
		(end 232.3592 -27.840686)
		(width 0.1651)
		(layer "F.Cu")
		(net "M_B_DQ<27>")
	)
	(segment
		(start 233.708448 -35.7886)
		(end 233.703114 -35.793934)
		(width 0.1651)
		(layer "F.Cu")
		(net "M_B_DQ<27>")
	)
	(segment
		(start 233.868214 -39.51097)
		(end 233.703114 -39.67607)
		(width 0.1651)
		(layer "F.Cu")
		(net "M_B_DQ<27>")
	)
	(segment
		(start 234.409234 -43.775884)
		(end 234.409234 -44.956984)
		(width 0.127)
		(layer "F.Cu")
		(net "M_B_DQ<27>")
	)
	(segment
		(start 233.868214 -37.49167)
		(end 234.2261 -37.49167)
		(width 0.1651)
		(layer "F.Cu")
		(net "M_B_DQ<27>")
	)
	(segment
		(start 233.703114 -41.02227)
		(end 233.703114 -43.069764)
		(width 0.1651)
		(layer "F.Cu")
		(net "M_B_DQ<27>")
	)
	(segment
		(start 234.061 -40.34917)
		(end 234.061 -40.69207)
		(width 0.1651)
		(layer "F.Cu")
		(net "M_B_DQ<27>")
	)
	(segment
		(start 233.708448 -34.544)
		(end 233.708448 -35.7886)
		(width 0.1651)
		(layer "F.Cu")
		(net "M_B_DQ<27>")
	)
	(segment
		(start 233.868214 -40.18407)
		(end 233.8959 -40.18407)
		(width 0.1651)
		(layer "F.Cu")
		(net "M_B_DQ<27>")
	)
	(segment
		(start 233.868214 -38.16477)
		(end 233.703114 -38.32987)
		(width 0.1651)
		(layer "F.Cu")
		(net "M_B_DQ<27>")
	)
	(via
		(at 232.94975 -27.250136)
		(size 0.508)
		(drill 0.254)
		(layers "F.Cu" "B.Cu")
		(net "M_B_DQ<27>")
	)
	(via
		(at 232.099866 -7.086346)
		(size 0.508)
		(drill 0.254)
		(layers "F.Cu" "B.Cu")
		(net "M_B_DQ<27>")
	)
	(via
		(at 233.708448 -34.544)
		(size 0.508)
		(drill 0.254)
		(layers "F.Cu" "B.Cu")
		(net "M_B_DQ<27>")
	)
	(via
		(at 232.94975 -12.678156)
		(size 0.508)
		(drill 0.254)
		(layers "F.Cu" "B.Cu")
		(net "M_B_DQ<27>")
	)
	(arc
		(start 246.027194 -51.14036)
		(mid 246.03899 -50.924026)
		(end 246.066056 -50.709068)
		(width 0.0889)
		(layer "F.Cu")
		(net "M_B_DQ<27>")
	)
	(arc
		(start 245.627144 -51.791616)
		(mid 245.648524 -51.698117)
		(end 245.708424 -51.623214)
		(width 0.0889)
		(layer "F.Cu")
		(net "M_B_DQ<27>")
	)
	(arc
		(start 245.708424 -51.623214)
		(mid 245.822924 -51.513153)
		(end 245.914926 -51.383692)
		(width 0.0889)
		(layer "F.Cu")
		(net "M_B_DQ<27>")
	)
	(arc
		(start 246.001032 -51.234848)
		(mid 246.020104 -51.18926)
		(end 246.027194 -51.14036)
		(width 0.0889)
		(layer "F.Cu")
		(net "M_B_DQ<27>")
	)
	(arc
		(start 246.066056 -50.709068)
		(mid 246.187684 -50.527038)
		(end 246.230394 -50.31232)
		(width 0.0889)
		(layer "F.Cu")
		(net "M_B_DQ<27>")
	)
	(segment
		(start 232.950512 -10.623042)
		(end 232.950004 -10.623042)
		(width 0.1651)
		(layer "B.Cu")
		(net "M_B_DQ<27>")
	)
	(segment
		(start 232.950004 -10.623042)
		(end 232.950004 -10.755122)
		(width 0.1651)
		(layer "B.Cu")
		(net "M_B_DQ<27>")
	)
	(segment
		(start 232.94975 -10.755376)
		(end 232.94975 -12.678156)
		(width 0.1651)
		(layer "B.Cu")
		(net "M_B_DQ<27>")
	)
	(segment
		(start 232.950004 -10.755122)
		(end 232.94975 -10.755376)
		(width 0.1651)
		(layer "B.Cu")
		(net "M_B_DQ<27>")
	)
	(segment
		(start 233.302556 -12.32535)
		(end 233.302556 -9.020048)
		(width 0.14224)
		(layer "In4.Cu")
		(net "M_B_DQ<27>")
	)
	(segment
		(start 232.416604 -7.403084)
		(end 232.099866 -7.086346)
		(width 0.14224)
		(layer "In4.Cu")
		(net "M_B_DQ<27>")
	)
	(segment
		(start 233.444796 -18.421604)
		(end 233.444796 -17.01038)
		(width 0.14224)
		(layer "In4.Cu")
		(net "M_B_DQ<27>")
	)
	(segment
		(start 233.264202 -21.808948)
		(end 233.264202 -18.602198)
		(width 0.14224)
		(layer "In4.Cu")
		(net "M_B_DQ<27>")
	)
	(segment
		(start 233.458004 -8.8646)
		(end 233.458004 -8.509)
		(width 0.14224)
		(layer "In4.Cu")
		(net "M_B_DQ<27>")
	)
	(segment
		(start 233.000804 -8.0518)
		(end 232.746804 -8.0518)
		(width 0.14224)
		(layer "In4.Cu")
		(net "M_B_DQ<27>")
	)
	(segment
		(start 233.442002 -21.986748)
		(end 233.264202 -21.808948)
		(width 0.14224)
		(layer "In4.Cu")
		(net "M_B_DQ<27>")
	)
	(segment
		(start 233.458004 -8.509)
		(end 233.000804 -8.0518)
		(width 0.14224)
		(layer "In4.Cu")
		(net "M_B_DQ<27>")
	)
	(segment
		(start 233.444796 -17.01038)
		(end 233.289602 -16.855186)
		(width 0.14224)
		(layer "In4.Cu")
		(net "M_B_DQ<27>")
	)
	(segment
		(start 232.94975 -12.678156)
		(end 233.302556 -12.32535)
		(width 0.14224)
		(layer "In4.Cu")
		(net "M_B_DQ<27>")
	)
	(segment
		(start 233.492802 -13.221208)
		(end 232.94975 -12.678156)
		(width 0.14224)
		(layer "In4.Cu")
		(net "M_B_DQ<27>")
	)
	(segment
		(start 233.264202 -23.364444)
		(end 233.442002 -23.186644)
		(width 0.14224)
		(layer "In4.Cu")
		(net "M_B_DQ<27>")
	)
	(segment
		(start 233.302556 -9.020048)
		(end 233.458004 -8.8646)
		(width 0.14224)
		(layer "In4.Cu")
		(net "M_B_DQ<27>")
	)
	(segment
		(start 233.442002 -23.186644)
		(end 233.442002 -21.986748)
		(width 0.14224)
		(layer "In4.Cu")
		(net "M_B_DQ<27>")
	)
	(segment
		(start 233.289602 -13.752576)
		(end 233.492802 -13.549376)
		(width 0.14224)
		(layer "In4.Cu")
		(net "M_B_DQ<27>")
	)
	(segment
		(start 232.94975 -27.250136)
		(end 233.264202 -26.935684)
		(width 0.14224)
		(layer "In4.Cu")
		(net "M_B_DQ<27>")
	)
	(segment
		(start 232.746804 -8.0518)
		(end 232.416604 -7.7216)
		(width 0.14224)
		(layer "In4.Cu")
		(net "M_B_DQ<27>")
	)
	(segment
		(start 233.264202 -26.935684)
		(end 233.264202 -23.364444)
		(width 0.14224)
		(layer "In4.Cu")
		(net "M_B_DQ<27>")
	)
	(segment
		(start 232.416604 -7.7216)
		(end 232.416604 -7.403084)
		(width 0.14224)
		(layer "In4.Cu")
		(net "M_B_DQ<27>")
	)
	(segment
		(start 233.492802 -13.549376)
		(end 233.492802 -13.221208)
		(width 0.14224)
		(layer "In4.Cu")
		(net "M_B_DQ<27>")
	)
	(segment
		(start 233.264202 -18.602198)
		(end 233.444796 -18.421604)
		(width 0.14224)
		(layer "In4.Cu")
		(net "M_B_DQ<27>")
	)
	(segment
		(start 233.289602 -16.855186)
		(end 233.289602 -13.752576)
		(width 0.14224)
		(layer "In4.Cu")
		(net "M_B_DQ<27>")
	)
	(segment
		(start 231.6861 -34.5694)
		(end 232.03916 -34.5694)
		(width 0.1651)
		(layer "F.Cu")
		(net "M_B_DQ<26>")
	)
	(segment
		(start 232.94975 -10.42162)
		(end 232.94975 -9.425432)
		(width 0.1651)
		(layer "F.Cu")
		(net "M_B_DQ<26>")
	)
	(segment
		(start 232.20426 -32.63646)
		(end 232.35412 -32.4866)
		(width 0.1651)
		(layer "F.Cu")
		(net "M_B_DQ<26>")
	)
	(segment
		(start 232.20426 -34.4043)
		(end 232.20426 -32.63646)
		(width 0.1651)
		(layer "F.Cu")
		(net "M_B_DQ<26>")
	)
	(segment
		(start 231.69626 -30.497526)
		(end 231.521 -30.672786)
		(width 0.1651)
		(layer "F.Cu")
		(net "M_B_DQ<26>")
	)
	(segment
		(start 246.039894 -48.977804)
		(end 246.039894 -50.072544)
		(width 0.0889)
		(layer "F.Cu")
		(net "M_B_DQ<26>")
	)
	(segment
		(start 232.94975 -8.938768)
		(end 232.94975 -8.6614)
		(width 0.1651)
		(layer "F.Cu")
		(net "M_B_DQ<26>")
	)
	(segment
		(start 231.521 -30.672786)
		(end 231.521 -34.4043)
		(width 0.1651)
		(layer "F.Cu")
		(net "M_B_DQ<26>")
	)
	(segment
		(start 233.081322 -9.29386)
		(end 233.081322 -9.07034)
		(width 0.1651)
		(layer "F.Cu")
		(net "M_B_DQ<26>")
	)
	(segment
		(start 234.002834 -45.125386)
		(end 234.453938 -45.57649)
		(width 0.1016)
		(layer "F.Cu")
		(net "M_B_DQ<26>")
	)
	(segment
		(start 231.521 -29.639006)
		(end 231.69626 -29.814266)
		(width 0.1651)
		(layer "F.Cu")
		(net "M_B_DQ<26>")
	)
	(segment
		(start 244.924072 -48.722534)
		(end 245.556024 -48.722534)
		(width 0.1016)
		(layer "F.Cu")
		(net "M_B_DQ<26>")
	)
	(segment
		(start 231.69626 -29.814266)
		(end 231.69626 -30.497526)
		(width 0.1651)
		(layer "F.Cu")
		(net "M_B_DQ<26>")
	)
	(segment
		(start 232.68686 -32.4866)
		(end 232.865676 -32.665416)
		(width 0.1651)
		(layer "F.Cu")
		(net "M_B_DQ<26>")
	)
	(segment
		(start 242.667028 -46.46549)
		(end 244.924072 -48.722534)
		(width 0.1016)
		(layer "F.Cu")
		(net "M_B_DQ<26>")
	)
	(segment
		(start 232.865676 -35.814)
		(end 232.865676 -43.148758)
		(width 0.1651)
		(layer "F.Cu")
		(net "M_B_DQ<26>")
	)
	(segment
		(start 232.950512 -10.422382)
		(end 232.94975 -10.42162)
		(width 0.1651)
		(layer "F.Cu")
		(net "M_B_DQ<26>")
	)
	(segment
		(start 245.556024 -48.722534)
		(end 245.784624 -48.722534)
		(width 0.0889)
		(layer "F.Cu")
		(net "M_B_DQ<26>")
	)
	(segment
		(start 238.679228 -46.46549)
		(end 242.667028 -46.46549)
		(width 0.1016)
		(layer "F.Cu")
		(net "M_B_DQ<26>")
	)
	(segment
		(start 234.453938 -45.57649)
		(end 237.790228 -45.57649)
		(width 0.1016)
		(layer "F.Cu")
		(net "M_B_DQ<26>")
	)
	(segment
		(start 237.790228 -45.57649)
		(end 238.679228 -46.46549)
		(width 0.1016)
		(layer "F.Cu")
		(net "M_B_DQ<26>")
	)
	(segment
		(start 232.94975 -9.425432)
		(end 233.081322 -9.29386)
		(width 0.1651)
		(layer "F.Cu")
		(net "M_B_DQ<26>")
	)
	(segment
		(start 232.03916 -34.5694)
		(end 232.20426 -34.4043)
		(width 0.1651)
		(layer "F.Cu")
		(net "M_B_DQ<26>")
	)
	(segment
		(start 231.521 -29.109924)
		(end 231.521 -29.639006)
		(width 0.1651)
		(layer "F.Cu")
		(net "M_B_DQ<26>")
	)
	(segment
		(start 232.865676 -43.148758)
		(end 233.859578 -44.14266)
		(width 0.1651)
		(layer "F.Cu")
		(net "M_B_DQ<26>")
	)
	(segment
		(start 245.784624 -48.722534)
		(end 246.039894 -48.977804)
		(width 0.0889)
		(layer "F.Cu")
		(net "M_B_DQ<26>")
	)
	(segment
		(start 231.521 -34.4043)
		(end 231.6861 -34.5694)
		(width 0.1651)
		(layer "F.Cu")
		(net "M_B_DQ<26>")
	)
	(segment
		(start 232.865676 -32.665416)
		(end 232.865676 -35.814)
		(width 0.1651)
		(layer "F.Cu")
		(net "M_B_DQ<26>")
	)
	(segment
		(start 232.35412 -32.4866)
		(end 232.68686 -32.4866)
		(width 0.1651)
		(layer "F.Cu")
		(net "M_B_DQ<26>")
	)
	(segment
		(start 233.081322 -9.07034)
		(end 232.94975 -8.938768)
		(width 0.1651)
		(layer "F.Cu")
		(net "M_B_DQ<26>")
	)
	(segment
		(start 233.859578 -44.14266)
		(end 234.002834 -44.285916)
		(width 0.1016)
		(layer "F.Cu")
		(net "M_B_DQ<26>")
	)
	(segment
		(start 232.099866 -28.531058)
		(end 231.521 -29.109924)
		(width 0.1651)
		(layer "F.Cu")
		(net "M_B_DQ<26>")
	)
	(segment
		(start 234.002834 -44.285916)
		(end 234.002834 -45.125386)
		(width 0.1016)
		(layer "F.Cu")
		(net "M_B_DQ<26>")
	)
	(via
		(at 232.099866 -28.531058)
		(size 0.508)
		(drill 0.254)
		(layers "F.Cu" "B.Cu")
		(net "M_B_DQ<26>")
	)
	(via
		(at 232.865676 -35.814)
		(size 0.508)
		(drill 0.254)
		(layers "F.Cu" "B.Cu")
		(net "M_B_DQ<26>")
	)
	(via
		(at 232.94975 -8.6614)
		(size 0.508)
		(drill 0.254)
		(layers "F.Cu" "B.Cu")
		(net "M_B_DQ<26>")
	)
	(via
		(at 232.099866 -13.959078)
		(size 0.508)
		(drill 0.254)
		(layers "F.Cu" "B.Cu")
		(net "M_B_DQ<26>")
	)
	(arc
		(start 245.901972 -50.442876)
		(mid 245.706442 -50.764521)
		(end 245.627144 -51.132486)
		(width 0.0889)
		(layer "F.Cu")
		(net "M_B_DQ<26>")
	)
	(arc
		(start 246.039894 -50.072544)
		(mid 246.004295 -50.270135)
		(end 245.901972 -50.442876)
		(width 0.0889)
		(layer "F.Cu")
		(net "M_B_DQ<26>")
	)
	(segment
		(start 232.100374 -15.222982)
		(end 232.099866 -15.222982)
		(width 0.1651)
		(layer "B.Cu")
		(net "M_B_DQ<26>")
	)
	(segment
		(start 232.099866 -15.222982)
		(end 232.099866 -13.959078)
		(width 0.1651)
		(layer "B.Cu")
		(net "M_B_DQ<26>")
	)
	(segment
		(start 232.454196 -23.18639)
		(end 232.454196 -21.961602)
		(width 0.14224)
		(layer "In4.Cu")
		(net "M_B_DQ<26>")
	)
	(segment
		(start 232.603802 -26.742644)
		(end 232.603802 -23.335996)
		(width 0.14224)
		(layer "In4.Cu")
		(net "M_B_DQ<26>")
	)
	(segment
		(start 232.2068 -10.95375)
		(end 232.5116 -10.64895)
		(width 0.14224)
		(layer "In4.Cu")
		(net "M_B_DQ<26>")
	)
	(segment
		(start 232.426002 -18.405602)
		(end 232.426002 -17.036034)
		(width 0.14224)
		(layer "In4.Cu")
		(net "M_B_DQ<26>")
	)
	(segment
		(start 232.5116 -10.64895)
		(end 232.5116 -10.362946)
		(width 0.14224)
		(layer "In4.Cu")
		(net "M_B_DQ<26>")
	)
	(segment
		(start 232.099866 -27.24658)
		(end 232.603802 -26.742644)
		(width 0.14224)
		(layer "In4.Cu")
		(net "M_B_DQ<26>")
	)
	(segment
		(start 232.551732 -9.364472)
		(end 232.551732 -9.059418)
		(width 0.14224)
		(layer "In4.Cu")
		(net "M_B_DQ<26>")
	)
	(segment
		(start 232.551732 -9.059418)
		(end 232.94975 -8.6614)
		(width 0.14224)
		(layer "In4.Cu")
		(net "M_B_DQ<26>")
	)
	(segment
		(start 232.603802 -23.335996)
		(end 232.454196 -23.18639)
		(width 0.14224)
		(layer "In4.Cu")
		(net "M_B_DQ<26>")
	)
	(segment
		(start 232.2068 -11.3538)
		(end 232.2068 -10.95375)
		(width 0.14224)
		(layer "In4.Cu")
		(net "M_B_DQ<26>")
	)
	(segment
		(start 232.581196 -16.88084)
		(end 232.581196 -15.563596)
		(width 0.14224)
		(layer "In4.Cu")
		(net "M_B_DQ<26>")
	)
	(segment
		(start 232.2068 -9.709404)
		(end 232.551732 -9.364472)
		(width 0.14224)
		(layer "In4.Cu")
		(net "M_B_DQ<26>")
	)
	(segment
		(start 231.815132 -13.674344)
		(end 231.815132 -12.9286)
		(width 0.14224)
		(layer "In4.Cu")
		(net "M_B_DQ<26>")
	)
	(segment
		(start 232.099866 -13.959078)
		(end 231.815132 -13.674344)
		(width 0.14224)
		(layer "In4.Cu")
		(net "M_B_DQ<26>")
	)
	(segment
		(start 232.664 -11.811)
		(end 232.2068 -11.3538)
		(width 0.14224)
		(layer "In4.Cu")
		(net "M_B_DQ<26>")
	)
	(segment
		(start 232.629202 -18.608802)
		(end 232.426002 -18.405602)
		(width 0.14224)
		(layer "In4.Cu")
		(net "M_B_DQ<26>")
	)
	(segment
		(start 232.426002 -17.036034)
		(end 232.581196 -16.88084)
		(width 0.14224)
		(layer "In4.Cu")
		(net "M_B_DQ<26>")
	)
	(segment
		(start 232.2068 -10.058146)
		(end 232.2068 -9.709404)
		(width 0.14224)
		(layer "In4.Cu")
		(net "M_B_DQ<26>")
	)
	(segment
		(start 232.454196 -21.961602)
		(end 232.629202 -21.786596)
		(width 0.14224)
		(layer "In4.Cu")
		(net "M_B_DQ<26>")
	)
	(segment
		(start 232.664 -12.079732)
		(end 232.664 -11.811)
		(width 0.14224)
		(layer "In4.Cu")
		(net "M_B_DQ<26>")
	)
	(segment
		(start 232.629202 -21.786596)
		(end 232.629202 -18.608802)
		(width 0.14224)
		(layer "In4.Cu")
		(net "M_B_DQ<26>")
	)
	(segment
		(start 232.581196 -15.563596)
		(end 232.099866 -15.082266)
		(width 0.14224)
		(layer "In4.Cu")
		(net "M_B_DQ<26>")
	)
	(segment
		(start 232.099866 -15.082266)
		(end 232.099866 -13.959078)
		(width 0.14224)
		(layer "In4.Cu")
		(net "M_B_DQ<26>")
	)
	(segment
		(start 232.099866 -28.531058)
		(end 232.099866 -27.24658)
		(width 0.14224)
		(layer "In4.Cu")
		(net "M_B_DQ<26>")
	)
	(segment
		(start 232.5116 -10.362946)
		(end 232.2068 -10.058146)
		(width 0.14224)
		(layer "In4.Cu")
		(net "M_B_DQ<26>")
	)
	(segment
		(start 231.815132 -12.9286)
		(end 232.664 -12.079732)
		(width 0.14224)
		(layer "In4.Cu")
		(net "M_B_DQ<26>")
	)
	(segment
		(start 226.150424 -5.822442)
		(end 226.149916 -5.822442)
		(width 0.1651)
		(layer "F.Cu")
		(net "M_B_DQ<25>")
	)
	(segment
		(start 227.2538 -38.945312)
		(end 227.0379 -38.945312)
		(width 0.1651)
		(layer "F.Cu")
		(net "M_B_DQ<25>")
	)
	(segment
		(start 237.527084 -48.33239)
		(end 233.310684 -48.33239)
		(width 0.1016)
		(layer "F.Cu")
		(net "M_B_DQ<25>")
	)
	(segment
		(start 227.2538 -39.618412)
		(end 227.4189 -39.783512)
		(width 0.1651)
		(layer "F.Cu")
		(net "M_B_DQ<25>")
	)
	(segment
		(start 226.4664 -40.456612)
		(end 226.4664 -40.799512)
		(width 0.1651)
		(layer "F.Cu")
		(net "M_B_DQ<25>")
	)
	(segment
		(start 225.900996 -27.603196)
		(end 226.6188 -28.321)
		(width 0.1651)
		(layer "F.Cu")
		(net "M_B_DQ<25>")
	)
	(segment
		(start 227.4189 -38.417754)
		(end 227.4189 -38.780212)
		(width 0.1651)
		(layer "F.Cu")
		(net "M_B_DQ<25>")
	)
	(segment
		(start 227.0379 -38.945312)
		(end 226.8728 -39.110412)
		(width 0.1651)
		(layer "F.Cu")
		(net "M_B_DQ<25>")
	)
	(segment
		(start 227.4189 -41.129712)
		(end 227.4189 -43.118278)
		(width 0.1651)
		(layer "F.Cu")
		(net "M_B_DQ<25>")
	)
	(segment
		(start 241.781584 -48.59909)
		(end 237.793784 -48.59909)
		(width 0.1016)
		(layer "F.Cu")
		(net "M_B_DQ<25>")
	)
	(segment
		(start 227.4189 -39.783512)
		(end 227.4189 -40.126412)
		(width 0.1651)
		(layer "F.Cu")
		(net "M_B_DQ<25>")
	)
	(segment
		(start 227.2538 -40.291512)
		(end 226.6315 -40.291512)
		(width 0.1651)
		(layer "F.Cu")
		(net "M_B_DQ<25>")
	)
	(segment
		(start 226.6188 -28.321)
		(end 226.6188 -36.068)
		(width 0.1651)
		(layer "F.Cu")
		(net "M_B_DQ<25>")
	)
	(segment
		(start 231.151684 -46.851062)
		(end 231.453436 -47.152814)
		(width 0.1016)
		(layer "F.Cu")
		(net "M_B_DQ<25>")
	)
	(segment
		(start 226.6315 -40.964612)
		(end 227.2538 -40.964612)
		(width 0.1651)
		(layer "F.Cu")
		(net "M_B_DQ<25>")
	)
	(segment
		(start 226.6188 -36.068)
		(end 226.6188 -37.617654)
		(width 0.1651)
		(layer "F.Cu")
		(net "M_B_DQ<25>")
	)
	(segment
		(start 233.310684 -48.33239)
		(end 232.131108 -47.152814)
		(width 0.1016)
		(layer "F.Cu")
		(net "M_B_DQ<25>")
	)
	(segment
		(start 226.6188 -37.617654)
		(end 227.4189 -38.417754)
		(width 0.1651)
		(layer "F.Cu")
		(net "M_B_DQ<25>")
	)
	(segment
		(start 226.8728 -39.453312)
		(end 227.0379 -39.618412)
		(width 0.1651)
		(layer "F.Cu")
		(net "M_B_DQ<25>")
	)
	(segment
		(start 227.4189 -38.780212)
		(end 227.2538 -38.945312)
		(width 0.1651)
		(layer "F.Cu")
		(net "M_B_DQ<25>")
	)
	(segment
		(start 243.051838 -50.316384)
		(end 243.02085 -50.285396)
		(width 0.0889)
		(layer "F.Cu")
		(net "M_B_DQ<25>")
	)
	(segment
		(start 243.02085 -50.285396)
		(end 243.02085 -49.838356)
		(width 0.0889)
		(layer "F.Cu")
		(net "M_B_DQ<25>")
	)
	(segment
		(start 226.8728 -39.110412)
		(end 226.8728 -39.453312)
		(width 0.1651)
		(layer "F.Cu")
		(net "M_B_DQ<25>")
	)
	(segment
		(start 237.793784 -48.59909)
		(end 237.527084 -48.33239)
		(width 0.1016)
		(layer "F.Cu")
		(net "M_B_DQ<25>")
	)
	(segment
		(start 227.4189 -40.126412)
		(end 227.2538 -40.291512)
		(width 0.1651)
		(layer "F.Cu")
		(net "M_B_DQ<25>")
	)
	(segment
		(start 226.4664 -40.799512)
		(end 226.6315 -40.964612)
		(width 0.1651)
		(layer "F.Cu")
		(net "M_B_DQ<25>")
	)
	(segment
		(start 243.051838 -50.63744)
		(end 243.051838 -50.316384)
		(width 0.0889)
		(layer "F.Cu")
		(net "M_B_DQ<25>")
	)
	(segment
		(start 227.2538 -40.964612)
		(end 227.4189 -41.129712)
		(width 0.1651)
		(layer "F.Cu")
		(net "M_B_DQ<25>")
	)
	(segment
		(start 231.453436 -47.152814)
		(end 232.131108 -47.152814)
		(width 0.1016)
		(layer "F.Cu")
		(net "M_B_DQ<25>")
	)
	(segment
		(start 227.4189 -43.118278)
		(end 231.151684 -46.851062)
		(width 0.1651)
		(layer "F.Cu")
		(net "M_B_DQ<25>")
	)
	(segment
		(start 243.02085 -49.838356)
		(end 241.781584 -48.59909)
		(width 0.1016)
		(layer "F.Cu")
		(net "M_B_DQ<25>")
	)
	(segment
		(start 226.822 -27.161236)
		(end 226.066096 -27.161236)
		(width 0.1651)
		(layer "F.Cu")
		(net "M_B_DQ<25>")
	)
	(segment
		(start 226.149916 -5.822442)
		(end 226.149916 -7.086346)
		(width 0.1651)
		(layer "F.Cu")
		(net "M_B_DQ<25>")
	)
	(segment
		(start 226.066096 -27.161236)
		(end 225.900996 -27.326336)
		(width 0.1651)
		(layer "F.Cu")
		(net "M_B_DQ<25>")
	)
	(segment
		(start 226.6315 -40.291512)
		(end 226.4664 -40.456612)
		(width 0.1651)
		(layer "F.Cu")
		(net "M_B_DQ<25>")
	)
	(segment
		(start 225.900996 -27.326336)
		(end 225.900996 -27.603196)
		(width 0.1651)
		(layer "F.Cu")
		(net "M_B_DQ<25>")
	)
	(segment
		(start 227.0379 -39.618412)
		(end 227.2538 -39.618412)
		(width 0.1651)
		(layer "F.Cu")
		(net "M_B_DQ<25>")
	)
	(via
		(at 226.822 -27.161236)
		(size 0.508)
		(drill 0.254)
		(layers "F.Cu" "B.Cu")
		(net "M_B_DQ<25>")
	)
	(via
		(at 226.6188 -36.068)
		(size 0.508)
		(drill 0.254)
		(layers "F.Cu" "B.Cu")
		(net "M_B_DQ<25>")
	)
	(via
		(at 226.149916 -7.086346)
		(size 0.508)
		(drill 0.254)
		(layers "F.Cu" "B.Cu")
		(net "M_B_DQ<25>")
	)
	(via
		(at 226.822 -12.678156)
		(size 0.508)
		(drill 0.254)
		(layers "F.Cu" "B.Cu")
		(net "M_B_DQ<25>")
	)
	(segment
		(start 227.000308 -10.623042)
		(end 226.9998 -10.623042)
		(width 0.1651)
		(layer "B.Cu")
		(net "M_B_DQ<25>")
	)
	(segment
		(start 226.822 -12.174982)
		(end 226.822 -12.678156)
		(width 0.1651)
		(layer "B.Cu")
		(net "M_B_DQ<25>")
	)
	(segment
		(start 226.9998 -11.997182)
		(end 226.822 -12.174982)
		(width 0.1651)
		(layer "B.Cu")
		(net "M_B_DQ<25>")
	)
	(segment
		(start 226.9998 -10.623042)
		(end 226.9998 -11.997182)
		(width 0.1651)
		(layer "B.Cu")
		(net "M_B_DQ<25>")
	)
	(segment
		(start 227.196142 -12.304014)
		(end 227.196142 -8.970264)
		(width 0.14224)
		(layer "In4.Cu")
		(net "M_B_DQ<25>")
	)
	(segment
		(start 227.307902 -16.335502)
		(end 226.662996 -15.690596)
		(width 0.14224)
		(layer "In4.Cu")
		(net "M_B_DQ<25>")
	)
	(segment
		(start 227.196142 -8.970264)
		(end 227.352606 -8.8138)
		(width 0.14224)
		(layer "In4.Cu")
		(net "M_B_DQ<25>")
	)
	(segment
		(start 226.307396 -13.480796)
		(end 226.307396 -13.19276)
		(width 0.14224)
		(layer "In4.Cu")
		(net "M_B_DQ<25>")
	)
	(segment
		(start 226.822 -27.161236)
		(end 227.307902 -26.675334)
		(width 0.14224)
		(layer "In4.Cu")
		(net "M_B_DQ<25>")
	)
	(segment
		(start 227.352606 -8.8138)
		(end 227.352606 -8.472424)
		(width 0.14224)
		(layer "In4.Cu")
		(net "M_B_DQ<25>")
	)
	(segment
		(start 226.662996 -13.836396)
		(end 226.307396 -13.480796)
		(width 0.14224)
		(layer "In4.Cu")
		(net "M_B_DQ<25>")
	)
	(segment
		(start 226.307396 -13.19276)
		(end 226.822 -12.678156)
		(width 0.14224)
		(layer "In4.Cu")
		(net "M_B_DQ<25>")
	)
	(segment
		(start 226.149916 -7.625334)
		(end 226.149916 -7.086346)
		(width 0.14224)
		(layer "In4.Cu")
		(net "M_B_DQ<25>")
	)
	(segment
		(start 227.352606 -8.472424)
		(end 226.982782 -8.1026)
		(width 0.14224)
		(layer "In4.Cu")
		(net "M_B_DQ<25>")
	)
	(segment
		(start 226.627182 -8.1026)
		(end 226.149916 -7.625334)
		(width 0.14224)
		(layer "In4.Cu")
		(net "M_B_DQ<25>")
	)
	(segment
		(start 227.307902 -26.675334)
		(end 227.307902 -16.335502)
		(width 0.14224)
		(layer "In4.Cu")
		(net "M_B_DQ<25>")
	)
	(segment
		(start 226.982782 -8.1026)
		(end 226.627182 -8.1026)
		(width 0.14224)
		(layer "In4.Cu")
		(net "M_B_DQ<25>")
	)
	(segment
		(start 226.662996 -15.690596)
		(end 226.662996 -13.836396)
		(width 0.14224)
		(layer "In4.Cu")
		(net "M_B_DQ<25>")
	)
	(segment
		(start 226.822 -12.678156)
		(end 227.196142 -12.304014)
		(width 0.14224)
		(layer "In4.Cu")
		(net "M_B_DQ<25>")
	)
	(segment
		(start 227.000308 -10.422382)
		(end 226.9998 -10.422382)
		(width 0.1651)
		(layer "F.Cu")
		(net "M_B_DQ<24>")
	)
	(segment
		(start 241.655092 -48.90389)
		(end 242.584224 -49.833022)
		(width 0.1016)
		(layer "F.Cu")
		(net "M_B_DQ<24>")
	)
	(segment
		(start 233.147362 -48.72609)
		(end 237.489492 -48.72609)
		(width 0.1016)
		(layer "F.Cu")
		(net "M_B_DQ<24>")
	)
	(segment
		(start 225.933 -28.747974)
		(end 225.933 -30.007814)
		(width 0.1651)
		(layer "F.Cu")
		(net "M_B_DQ<24>")
	)
	(segment
		(start 242.584224 -50.74158)
		(end 242.193318 -51.132486)
		(width 0.0889)
		(layer "F.Cu")
		(net "M_B_DQ<24>")
	)
	(segment
		(start 225.4123 -30.172914)
		(end 225.2472 -30.338014)
		(width 0.1651)
		(layer "F.Cu")
		(net "M_B_DQ<24>")
	)
	(segment
		(start 225.933 -33.703514)
		(end 225.933 -34.29)
		(width 0.1651)
		(layer "F.Cu")
		(net "M_B_DQ<24>")
	)
	(segment
		(start 237.489492 -48.72609)
		(end 237.667292 -48.90389)
		(width 0.1016)
		(layer "F.Cu")
		(net "M_B_DQ<24>")
	)
	(segment
		(start 230.928672 -47.546514)
		(end 231.967786 -47.546514)
		(width 0.1016)
		(layer "F.Cu")
		(net "M_B_DQ<24>")
	)
	(segment
		(start 226.9998 -10.422382)
		(end 226.841304 -8.763)
		(width 0.1651)
		(layer "F.Cu")
		(net "M_B_DQ<24>")
	)
	(segment
		(start 225.2472 -30.680914)
		(end 225.4123 -30.846014)
		(width 0.1651)
		(layer "F.Cu")
		(net "M_B_DQ<24>")
	)
	(segment
		(start 242.584224 -49.946814)
		(end 242.584224 -50.74158)
		(width 0.0889)
		(layer "F.Cu")
		(net "M_B_DQ<24>")
	)
	(segment
		(start 225.75774 -42.375836)
		(end 230.692198 -47.310294)
		(width 0.1651)
		(layer "F.Cu")
		(net "M_B_DQ<24>")
	)
	(segment
		(start 225.4123 -33.538414)
		(end 225.7679 -33.538414)
		(width 0.1651)
		(layer "F.Cu")
		(net "M_B_DQ<24>")
	)
	(segment
		(start 225.2472 -33.030414)
		(end 225.2472 -33.373314)
		(width 0.1651)
		(layer "F.Cu")
		(net "M_B_DQ<24>")
	)
	(segment
		(start 225.933 -31.354014)
		(end 225.7679 -31.519114)
		(width 0.1651)
		(layer "F.Cu")
		(net "M_B_DQ<24>")
	)
	(segment
		(start 225.7679 -32.192214)
		(end 225.933 -32.357314)
		(width 0.1651)
		(layer "F.Cu")
		(net "M_B_DQ<24>")
	)
	(segment
		(start 225.4123 -32.192214)
		(end 225.7679 -32.192214)
		(width 0.1651)
		(layer "F.Cu")
		(net "M_B_DQ<24>")
	)
	(segment
		(start 225.2472 -31.684214)
		(end 225.2472 -32.027114)
		(width 0.1651)
		(layer "F.Cu")
		(net "M_B_DQ<24>")
	)
	(segment
		(start 225.4123 -32.865314)
		(end 225.2472 -33.030414)
		(width 0.1651)
		(layer "F.Cu")
		(net "M_B_DQ<24>")
	)
	(segment
		(start 225.2472 -32.027114)
		(end 225.4123 -32.192214)
		(width 0.1651)
		(layer "F.Cu")
		(net "M_B_DQ<24>")
	)
	(segment
		(start 230.692198 -47.310294)
		(end 230.692452 -47.310294)
		(width 0.1651)
		(layer "F.Cu")
		(net "M_B_DQ<24>")
	)
	(segment
		(start 225.4123 -30.846014)
		(end 225.7679 -30.846014)
		(width 0.1651)
		(layer "F.Cu")
		(net "M_B_DQ<24>")
	)
	(segment
		(start 225.933 -31.011114)
		(end 225.933 -31.354014)
		(width 0.1651)
		(layer "F.Cu")
		(net "M_B_DQ<24>")
	)
	(segment
		(start 225.933 -30.007814)
		(end 225.7679 -30.172914)
		(width 0.1651)
		(layer "F.Cu")
		(net "M_B_DQ<24>")
	)
	(segment
		(start 225.933 -32.357314)
		(end 225.933 -32.700214)
		(width 0.1651)
		(layer "F.Cu")
		(net "M_B_DQ<24>")
	)
	(segment
		(start 225.7679 -32.865314)
		(end 225.4123 -32.865314)
		(width 0.1651)
		(layer "F.Cu")
		(net "M_B_DQ<24>")
	)
	(segment
		(start 225.933 -32.700214)
		(end 225.7679 -32.865314)
		(width 0.1651)
		(layer "F.Cu")
		(net "M_B_DQ<24>")
	)
	(segment
		(start 225.2472 -30.338014)
		(end 225.2472 -30.680914)
		(width 0.1651)
		(layer "F.Cu")
		(net "M_B_DQ<24>")
	)
	(segment
		(start 226.149916 -28.531058)
		(end 225.933 -28.747974)
		(width 0.1651)
		(layer "F.Cu")
		(net "M_B_DQ<24>")
	)
	(segment
		(start 226.841304 -8.763)
		(end 226.822 -8.5598)
		(width 0.1651)
		(layer "F.Cu")
		(net "M_B_DQ<24>")
	)
	(segment
		(start 225.2472 -33.373314)
		(end 225.4123 -33.538414)
		(width 0.1651)
		(layer "F.Cu")
		(net "M_B_DQ<24>")
	)
	(segment
		(start 225.7679 -30.172914)
		(end 225.4123 -30.172914)
		(width 0.1651)
		(layer "F.Cu")
		(net "M_B_DQ<24>")
	)
	(segment
		(start 225.75774 -38.262814)
		(end 225.75774 -42.375836)
		(width 0.1651)
		(layer "F.Cu")
		(net "M_B_DQ<24>")
	)
	(segment
		(start 225.933 -38.087554)
		(end 225.75774 -38.262814)
		(width 0.1651)
		(layer "F.Cu")
		(net "M_B_DQ<24>")
	)
	(segment
		(start 225.933 -34.29)
		(end 225.933 -38.087554)
		(width 0.1651)
		(layer "F.Cu")
		(net "M_B_DQ<24>")
	)
	(segment
		(start 225.7679 -33.538414)
		(end 225.933 -33.703514)
		(width 0.1651)
		(layer "F.Cu")
		(net "M_B_DQ<24>")
	)
	(segment
		(start 231.967786 -47.546514)
		(end 233.147362 -48.72609)
		(width 0.1016)
		(layer "F.Cu")
		(net "M_B_DQ<24>")
	)
	(segment
		(start 237.667292 -48.90389)
		(end 241.655092 -48.90389)
		(width 0.1016)
		(layer "F.Cu")
		(net "M_B_DQ<24>")
	)
	(segment
		(start 225.7679 -30.846014)
		(end 225.933 -31.011114)
		(width 0.1651)
		(layer "F.Cu")
		(net "M_B_DQ<24>")
	)
	(segment
		(start 225.7679 -31.519114)
		(end 225.4123 -31.519114)
		(width 0.1651)
		(layer "F.Cu")
		(net "M_B_DQ<24>")
	)
	(segment
		(start 225.4123 -31.519114)
		(end 225.2472 -31.684214)
		(width 0.1651)
		(layer "F.Cu")
		(net "M_B_DQ<24>")
	)
	(segment
		(start 242.584224 -49.833022)
		(end 242.584224 -49.946814)
		(width 0.1016)
		(layer "F.Cu")
		(net "M_B_DQ<24>")
	)
	(segment
		(start 230.692452 -47.310294)
		(end 230.928672 -47.546514)
		(width 0.1016)
		(layer "F.Cu")
		(net "M_B_DQ<24>")
	)
	(via
		(at 226.149916 -28.531058)
		(size 0.508)
		(drill 0.254)
		(layers "F.Cu" "B.Cu")
		(net "M_B_DQ<24>")
	)
	(via
		(at 225.933 -34.29)
		(size 0.508)
		(drill 0.254)
		(layers "F.Cu" "B.Cu")
		(net "M_B_DQ<24>")
	)
	(via
		(at 226.822 -8.5598)
		(size 0.508)
		(drill 0.254)
		(layers "F.Cu" "B.Cu")
		(net "M_B_DQ<24>")
	)
	(via
		(at 226.149916 -13.959078)
		(size 0.508)
		(drill 0.254)
		(layers "F.Cu" "B.Cu")
		(net "M_B_DQ<24>")
	)
	(segment
		(start 226.150424 -15.222982)
		(end 226.149916 -15.222982)
		(width 0.1651)
		(layer "B.Cu")
		(net "M_B_DQ<24>")
	)
	(segment
		(start 226.149916 -15.222982)
		(end 226.149916 -13.959078)
		(width 0.1651)
		(layer "B.Cu")
		(net "M_B_DQ<24>")
	)
	(segment
		(start 226.253802 -23.028148)
		(end 226.253802 -22.065996)
		(width 0.14224)
		(layer "In4.Cu")
		(net "M_B_DQ<24>")
	)
	(segment
		(start 226.330002 -28.350972)
		(end 226.330002 -26.955496)
		(width 0.14224)
		(layer "In4.Cu")
		(net "M_B_DQ<24>")
	)
	(segment
		(start 226.601782 -9.364472)
		(end 226.601782 -8.780018)
		(width 0.14224)
		(layer "In4.Cu")
		(net "M_B_DQ<24>")
	)
	(segment
		(start 226.187 -10.1092)
		(end 226.187 -9.779254)
		(width 0.14224)
		(layer "In4.Cu")
		(net "M_B_DQ<24>")
	)
	(segment
		(start 225.865182 -12.9286)
		(end 226.601782 -12.192)
		(width 0.14224)
		(layer "In4.Cu")
		(net "M_B_DQ<24>")
	)
	(segment
		(start 226.637596 -21.682202)
		(end 226.637596 -18.632678)
		(width 0.14224)
		(layer "In4.Cu")
		(net "M_B_DQ<24>")
	)
	(segment
		(start 226.332796 -18.327878)
		(end 226.332796 -17.123156)
		(width 0.14224)
		(layer "In4.Cu")
		(net "M_B_DQ<24>")
	)
	(segment
		(start 226.637596 -18.632678)
		(end 226.332796 -18.327878)
		(width 0.14224)
		(layer "In4.Cu")
		(net "M_B_DQ<24>")
	)
	(segment
		(start 226.601782 -11.692128)
		(end 226.2124 -11.302746)
		(width 0.14224)
		(layer "In4.Cu")
		(net "M_B_DQ<24>")
	)
	(segment
		(start 226.634802 -16.475202)
		(end 226.149916 -15.990316)
		(width 0.14224)
		(layer "In4.Cu")
		(net "M_B_DQ<24>")
	)
	(segment
		(start 226.601782 -8.780018)
		(end 226.822 -8.5598)
		(width 0.14224)
		(layer "In4.Cu")
		(net "M_B_DQ<24>")
	)
	(segment
		(start 226.330002 -26.955496)
		(end 226.609402 -26.676096)
		(width 0.14224)
		(layer "In4.Cu")
		(net "M_B_DQ<24>")
	)
	(segment
		(start 226.5299 -10.4521)
		(end 226.187 -10.1092)
		(width 0.14224)
		(layer "In4.Cu")
		(net "M_B_DQ<24>")
	)
	(segment
		(start 226.149916 -28.531058)
		(end 226.330002 -28.350972)
		(width 0.14224)
		(layer "In4.Cu")
		(net "M_B_DQ<24>")
	)
	(segment
		(start 226.601782 -12.192)
		(end 226.601782 -11.692128)
		(width 0.14224)
		(layer "In4.Cu")
		(net "M_B_DQ<24>")
	)
	(segment
		(start 226.634802 -16.82115)
		(end 226.634802 -16.475202)
		(width 0.14224)
		(layer "In4.Cu")
		(net "M_B_DQ<24>")
	)
	(segment
		(start 225.865182 -13.674344)
		(end 225.865182 -12.9286)
		(width 0.14224)
		(layer "In4.Cu")
		(net "M_B_DQ<24>")
	)
	(segment
		(start 226.187 -9.779254)
		(end 226.601782 -9.364472)
		(width 0.14224)
		(layer "In4.Cu")
		(net "M_B_DQ<24>")
	)
	(segment
		(start 226.609402 -26.676096)
		(end 226.609402 -23.383748)
		(width 0.14224)
		(layer "In4.Cu")
		(net "M_B_DQ<24>")
	)
	(segment
		(start 226.149916 -15.990316)
		(end 226.149916 -13.959078)
		(width 0.14224)
		(layer "In4.Cu")
		(net "M_B_DQ<24>")
	)
	(segment
		(start 226.253802 -22.065996)
		(end 226.637596 -21.682202)
		(width 0.14224)
		(layer "In4.Cu")
		(net "M_B_DQ<24>")
	)
	(segment
		(start 226.2124 -11.302746)
		(end 226.2124 -10.9982)
		(width 0.14224)
		(layer "In4.Cu")
		(net "M_B_DQ<24>")
	)
	(segment
		(start 226.332796 -17.123156)
		(end 226.634802 -16.82115)
		(width 0.14224)
		(layer "In4.Cu")
		(net "M_B_DQ<24>")
	)
	(segment
		(start 226.2124 -10.9982)
		(end 226.5299 -10.6807)
		(width 0.14224)
		(layer "In4.Cu")
		(net "M_B_DQ<24>")
	)
	(segment
		(start 226.5299 -10.6807)
		(end 226.5299 -10.4521)
		(width 0.14224)
		(layer "In4.Cu")
		(net "M_B_DQ<24>")
	)
	(segment
		(start 226.149916 -13.959078)
		(end 225.865182 -13.674344)
		(width 0.14224)
		(layer "In4.Cu")
		(net "M_B_DQ<24>")
	)
	(segment
		(start 226.609402 -23.383748)
		(end 226.253802 -23.028148)
		(width 0.14224)
		(layer "In4.Cu")
		(net "M_B_DQ<24>")
	)
	(segment
		(start 239.617758 -53.60924)
		(end 239.046258 -53.60924)
		(width 0.1016)
		(layer "F.Cu")
		(net "M_B_DQ<23>")
	)
	(segment
		(start 221.04985 -5.822442)
		(end 221.04985 -7.086346)
		(width 0.1651)
		(layer "F.Cu")
		(net "M_B_DQ<23>")
	)
	(segment
		(start 221.050358 -5.822442)
		(end 221.04985 -5.822442)
		(width 0.1651)
		(layer "F.Cu")
		(net "M_B_DQ<23>")
	)
	(via
		(at 221.899734 -12.678156)
		(size 0.508)
		(drill 0.254)
		(layers "F.Cu" "B.Cu")
		(net "M_B_DQ<23>")
	)
	(via
		(at 221.04985 -7.086346)
		(size 0.508)
		(drill 0.254)
		(layers "F.Cu" "B.Cu")
		(net "M_B_DQ<23>")
	)
	(via
		(at 239.046258 -53.60924)
		(size 0.508)
		(drill 0.254)
		(layers "F.Cu" "B.Cu")
		(net "M_B_DQ<23>")
	)
	(segment
		(start 221.900496 -10.623042)
		(end 221.899988 -10.623042)
		(width 0.1651)
		(layer "B.Cu")
		(net "M_B_DQ<23>")
	)
	(segment
		(start 221.899988 -11.110722)
		(end 221.899734 -11.110976)
		(width 0.1651)
		(layer "B.Cu")
		(net "M_B_DQ<23>")
	)
	(segment
		(start 221.899734 -11.110976)
		(end 221.899734 -12.678156)
		(width 0.1651)
		(layer "B.Cu")
		(net "M_B_DQ<23>")
	)
	(segment
		(start 221.899988 -10.623042)
		(end 221.899988 -11.110722)
		(width 0.1651)
		(layer "B.Cu")
		(net "M_B_DQ<23>")
	)
	(segment
		(start 239.485424 -49.710086)
		(end 239.485424 -50.216816)
		(width 0.0889)
		(layer "In4.Cu")
		(net "M_B_DQ<23>")
	)
	(segment
		(start 236.535468 -47.499524)
		(end 237.014258 -47.978314)
		(width 0.0889)
		(layer "In4.Cu")
		(net "M_B_DQ<23>")
	)
	(segment
		(start 222.48114 -18.361914)
		(end 222.25254 -18.590514)
		(width 0.14224)
		(layer "In4.Cu")
		(net "M_B_DQ<23>")
	)
	(segment
		(start 231.867964 -36.608512)
		(end 232.086912 -36.608512)
		(width 0.14224)
		(layer "In4.Cu")
		(net "M_B_DQ<23>")
	)
	(segment
		(start 222.25254 -18.590514)
		(end 222.25254 -18.9738)
		(width 0.14224)
		(layer "In4.Cu")
		(net "M_B_DQ<23>")
	)
	(segment
		(start 221.43974 -13.13815)
		(end 221.43974 -13.60932)
		(width 0.14224)
		(layer "In4.Cu")
		(net "M_B_DQ<23>")
	)
	(segment
		(start 221.950788 -8.0518)
		(end 222.407988 -8.509)
		(width 0.14224)
		(layer "In4.Cu")
		(net "M_B_DQ<23>")
	)
	(segment
		(start 222.2754 -16.4338)
		(end 222.2754 -16.876522)
		(width 0.14224)
		(layer "In4.Cu")
		(net "M_B_DQ<23>")
	)
	(segment
		(start 239.485424 -50.216816)
		(end 239.558068 -50.342038)
		(width 0.0889)
		(layer "In4.Cu")
		(net "M_B_DQ<23>")
	)
	(segment
		(start 232.6005 -42.889424)
		(end 235.9787 -46.267624)
		(width 0.14224)
		(layer "In4.Cu")
		(net "M_B_DQ<23>")
	)
	(segment
		(start 222.48114 -17.082262)
		(end 222.48114 -18.361914)
		(width 0.14224)
		(layer "In4.Cu")
		(net "M_B_DQ<23>")
	)
	(segment
		(start 239.558068 -51.923442)
		(end 239.558068 -51.923696)
		(width 0.0889)
		(layer "In4.Cu")
		(net "M_B_DQ<23>")
	)
	(segment
		(start 232.336848 -37.077396)
		(end 231.990646 -37.423598)
		(width 0.14224)
		(layer "In4.Cu")
		(net "M_B_DQ<23>")
	)
	(segment
		(start 221.696788 -8.0518)
		(end 221.950788 -8.0518)
		(width 0.14224)
		(layer "In4.Cu")
		(net "M_B_DQ<23>")
	)
	(segment
		(start 231.990646 -37.642546)
		(end 232.6005 -38.2524)
		(width 0.14224)
		(layer "In4.Cu")
		(net "M_B_DQ<23>")
	)
	(segment
		(start 222.6818 -29.568902)
		(end 225.332798 -32.2199)
		(width 0.14224)
		(layer "In4.Cu")
		(net "M_B_DQ<23>")
	)
	(segment
		(start 231.521762 -36.954714)
		(end 231.867964 -36.608512)
		(width 0.14224)
		(layer "In4.Cu")
		(net "M_B_DQ<23>")
	)
	(segment
		(start 222.5802 -15.0368)
		(end 222.5802 -16.129)
		(width 0.14224)
		(layer "In4.Cu")
		(net "M_B_DQ<23>")
	)
	(segment
		(start 235.9787 -46.267624)
		(end 235.9787 -46.724062)
		(width 0.14224)
		(layer "In4.Cu")
		(net "M_B_DQ<23>")
	)
	(segment
		(start 231.302814 -36.954714)
		(end 231.521762 -36.954714)
		(width 0.14224)
		(layer "In4.Cu")
		(net "M_B_DQ<23>")
	)
	(segment
		(start 222.2754 -16.876522)
		(end 222.48114 -17.082262)
		(width 0.14224)
		(layer "In4.Cu")
		(net "M_B_DQ<23>")
	)
	(segment
		(start 222.45574 -21.975572)
		(end 222.45574 -23.118572)
		(width 0.14224)
		(layer "In4.Cu")
		(net "M_B_DQ<23>")
	)
	(segment
		(start 232.086912 -36.608512)
		(end 232.336848 -36.858448)
		(width 0.14224)
		(layer "In4.Cu")
		(net "M_B_DQ<23>")
	)
	(segment
		(start 222.407988 -8.8646)
		(end 222.25254 -9.020048)
		(width 0.14224)
		(layer "In4.Cu")
		(net "M_B_DQ<23>")
	)
	(segment
		(start 239.564418 -50.92192)
		(end 239.558068 -50.932588)
		(width 0.0889)
		(layer "In4.Cu")
		(net "M_B_DQ<23>")
	)
	(segment
		(start 221.366588 -7.7216)
		(end 221.696788 -8.0518)
		(width 0.14224)
		(layer "In4.Cu")
		(net "M_B_DQ<23>")
	)
	(segment
		(start 221.43974 -13.60932)
		(end 221.80804 -13.97762)
		(width 0.14224)
		(layer "In4.Cu")
		(net "M_B_DQ<23>")
	)
	(segment
		(start 222.25254 -21.772372)
		(end 222.45574 -21.975572)
		(width 0.14224)
		(layer "In4.Cu")
		(net "M_B_DQ<23>")
	)
	(segment
		(start 235.9787 -46.724062)
		(end 236.535468 -47.28083)
		(width 0.14224)
		(layer "In4.Cu")
		(net "M_B_DQ<23>")
	)
	(segment
		(start 222.6818 -24.1808)
		(end 222.6818 -29.568902)
		(width 0.14224)
		(layer "In4.Cu")
		(net "M_B_DQ<23>")
	)
	(segment
		(start 222.27794 -23.296372)
		(end 222.27794 -23.77694)
		(width 0.14224)
		(layer "In4.Cu")
		(net "M_B_DQ<23>")
	)
	(segment
		(start 221.80804 -14.26464)
		(end 222.5802 -15.0368)
		(width 0.14224)
		(layer "In4.Cu")
		(net "M_B_DQ<23>")
	)
	(segment
		(start 221.366588 -7.403084)
		(end 221.366588 -7.7216)
		(width 0.14224)
		(layer "In4.Cu")
		(net "M_B_DQ<23>")
	)
	(segment
		(start 222.25254 -9.020048)
		(end 222.25254 -12.32535)
		(width 0.14224)
		(layer "In4.Cu")
		(net "M_B_DQ<23>")
	)
	(segment
		(start 222.25254 -18.9738)
		(end 222.631 -19.35226)
		(width 0.14224)
		(layer "In4.Cu")
		(net "M_B_DQ<23>")
	)
	(segment
		(start 222.631 -19.35226)
		(end 222.631 -20.955)
		(width 0.14224)
		(layer "In4.Cu")
		(net "M_B_DQ<23>")
	)
	(segment
		(start 239.392968 -52.818792)
		(end 239.046258 -53.60924)
		(width 0.0889)
		(layer "In4.Cu")
		(net "M_B_DQ<23>")
	)
	(segment
		(start 237.014258 -47.978314)
		(end 237.753652 -47.978314)
		(width 0.0889)
		(layer "In4.Cu")
		(net "M_B_DQ<23>")
	)
	(segment
		(start 222.25254 -12.32535)
		(end 221.899734 -12.678156)
		(width 0.14224)
		(layer "In4.Cu")
		(net "M_B_DQ<23>")
	)
	(segment
		(start 221.80804 -13.97762)
		(end 221.80804 -14.26464)
		(width 0.14224)
		(layer "In4.Cu")
		(net "M_B_DQ<23>")
	)
	(segment
		(start 236.535468 -47.28083)
		(end 236.535468 -47.499524)
		(width 0.0889)
		(layer "In4.Cu")
		(net "M_B_DQ<23>")
	)
	(segment
		(start 232.6005 -38.2524)
		(end 232.6005 -42.889424)
		(width 0.14224)
		(layer "In4.Cu")
		(net "M_B_DQ<23>")
	)
	(segment
		(start 222.5802 -16.129)
		(end 222.2754 -16.4338)
		(width 0.14224)
		(layer "In4.Cu")
		(net "M_B_DQ<23>")
	)
	(segment
		(start 221.899734 -12.678156)
		(end 221.43974 -13.13815)
		(width 0.14224)
		(layer "In4.Cu")
		(net "M_B_DQ<23>")
	)
	(segment
		(start 226.568 -32.2199)
		(end 231.302814 -36.954714)
		(width 0.14224)
		(layer "In4.Cu")
		(net "M_B_DQ<23>")
	)
	(segment
		(start 239.558068 -50.932588)
		(end 239.553242 -50.941224)
		(width 0.0889)
		(layer "In4.Cu")
		(net "M_B_DQ<23>")
	)
	(segment
		(start 232.336848 -36.858448)
		(end 232.336848 -37.077396)
		(width 0.14224)
		(layer "In4.Cu")
		(net "M_B_DQ<23>")
	)
	(segment
		(start 222.45574 -23.118572)
		(end 222.27794 -23.296372)
		(width 0.14224)
		(layer "In4.Cu")
		(net "M_B_DQ<23>")
	)
	(segment
		(start 231.990646 -37.423598)
		(end 231.990646 -37.642546)
		(width 0.14224)
		(layer "In4.Cu")
		(net "M_B_DQ<23>")
	)
	(segment
		(start 222.631 -20.955)
		(end 222.25254 -21.33346)
		(width 0.14224)
		(layer "In4.Cu")
		(net "M_B_DQ<23>")
	)
	(segment
		(start 222.407988 -8.509)
		(end 222.407988 -8.8646)
		(width 0.14224)
		(layer "In4.Cu")
		(net "M_B_DQ<23>")
	)
	(segment
		(start 225.332798 -32.2199)
		(end 226.568 -32.2199)
		(width 0.14224)
		(layer "In4.Cu")
		(net "M_B_DQ<23>")
	)
	(segment
		(start 222.27794 -23.77694)
		(end 222.6818 -24.1808)
		(width 0.14224)
		(layer "In4.Cu")
		(net "M_B_DQ<23>")
	)
	(segment
		(start 237.753652 -47.978314)
		(end 239.485424 -49.710086)
		(width 0.0889)
		(layer "In4.Cu")
		(net "M_B_DQ<23>")
	)
	(segment
		(start 221.04985 -7.086346)
		(end 221.366588 -7.403084)
		(width 0.14224)
		(layer "In4.Cu")
		(net "M_B_DQ<23>")
	)
	(segment
		(start 222.25254 -21.33346)
		(end 222.25254 -21.772372)
		(width 0.14224)
		(layer "In4.Cu")
		(net "M_B_DQ<23>")
	)
	(arc
		(start 239.558068 -51.923696)
		(mid 239.445822 -52.226972)
		(end 239.440466 -52.550314)
		(width 0.0889)
		(layer "In4.Cu")
		(net "M_B_DQ<23>")
	)
	(arc
		(start 239.440466 -52.550314)
		(mid 239.440249 -52.688709)
		(end 239.392968 -52.818792)
		(width 0.0889)
		(layer "In4.Cu")
		(net "M_B_DQ<23>")
	)
	(arc
		(start 239.558068 -50.342038)
		(mid 239.63729 -50.631156)
		(end 239.564418 -50.92192)
		(width 0.0889)
		(layer "In4.Cu")
		(net "M_B_DQ<23>")
	)
	(arc
		(start 239.558068 -51.332638)
		(mid 239.637199 -51.62804)
		(end 239.558068 -51.923442)
		(width 0.0889)
		(layer "In4.Cu")
		(net "M_B_DQ<23>")
	)
	(arc
		(start 239.553242 -50.941224)
		(mid 239.504487 -51.137576)
		(end 239.558068 -51.332638)
		(width 0.0889)
		(layer "In4.Cu")
		(net "M_B_DQ<23>")
	)
	(segment
		(start 221.899988 -10.422382)
		(end 221.899988 -9.4488)
		(width 0.1651)
		(layer "F.Cu")
		(net "M_B_DQ<22>")
	)
	(segment
		(start 221.899988 -9.4488)
		(end 222.032068 -9.31672)
		(width 0.1651)
		(layer "F.Cu")
		(net "M_B_DQ<22>")
	)
	(segment
		(start 221.900496 -10.422382)
		(end 221.899988 -10.422382)
		(width 0.1651)
		(layer "F.Cu")
		(net "M_B_DQ<22>")
	)
	(segment
		(start 221.899988 -8.661654)
		(end 221.899734 -8.6614)
		(width 0.1651)
		(layer "F.Cu")
		(net "M_B_DQ<22>")
	)
	(segment
		(start 221.899988 -8.9662)
		(end 221.899988 -8.661654)
		(width 0.1651)
		(layer "F.Cu")
		(net "M_B_DQ<22>")
	)
	(segment
		(start 222.032068 -9.31672)
		(end 222.032068 -9.09828)
		(width 0.1651)
		(layer "F.Cu")
		(net "M_B_DQ<22>")
	)
	(segment
		(start 239.617758 -51.62804)
		(end 239.046258 -51.62804)
		(width 0.1016)
		(layer "F.Cu")
		(net "M_B_DQ<22>")
	)
	(segment
		(start 222.032068 -9.09828)
		(end 221.899988 -8.9662)
		(width 0.1651)
		(layer "F.Cu")
		(net "M_B_DQ<22>")
	)
	(via
		(at 239.046258 -51.62804)
		(size 0.508)
		(drill 0.254)
		(layers "F.Cu" "B.Cu")
		(net "M_B_DQ<22>")
	)
	(via
		(at 221.04985 -13.959078)
		(size 0.508)
		(drill 0.254)
		(layers "F.Cu" "B.Cu")
		(net "M_B_DQ<22>")
	)
	(via
		(at 221.899734 -8.6614)
		(size 0.508)
		(drill 0.254)
		(layers "F.Cu" "B.Cu")
		(net "M_B_DQ<22>")
	)
	(segment
		(start 221.050358 -15.222982)
		(end 221.04985 -15.222982)
		(width 0.1651)
		(layer "B.Cu")
		(net "M_B_DQ<22>")
	)
	(segment
		(start 221.04985 -15.222982)
		(end 221.04985 -13.959078)
		(width 0.1651)
		(layer "B.Cu")
		(net "M_B_DQ<22>")
	)
	(segment
		(start 239.294924 -49.78908)
		(end 237.674658 -48.168814)
		(width 0.0889)
		(layer "In4.Cu")
		(net "M_B_DQ<22>")
	)
	(segment
		(start 220.814138 -13.723366)
		(end 220.814138 -12.928854)
		(width 0.14224)
		(layer "In4.Cu")
		(net "M_B_DQ<22>")
	)
	(segment
		(start 222.0468 -19.787616)
		(end 221.8436 -19.584416)
		(width 0.14224)
		(layer "In4.Cu")
		(net "M_B_DQ<22>")
	)
	(segment
		(start 221.51594 -23.270972)
		(end 221.41434 -23.169372)
		(width 0.14224)
		(layer "In4.Cu")
		(net "M_B_DQ<22>")
	)
	(segment
		(start 221.5134 -18.542254)
		(end 221.41434 -18.443194)
		(width 0.14224)
		(layer "In4.Cu")
		(net "M_B_DQ<22>")
	)
	(segment
		(start 221.525338 -9.313672)
		(end 221.525338 -9.035796)
		(width 0.14224)
		(layer "In4.Cu")
		(net "M_B_DQ<22>")
	)
	(segment
		(start 236.097826 -47.741332)
		(end 235.2675 -46.911006)
		(width 0.14224)
		(layer "In4.Cu")
		(net "M_B_DQ<22>")
	)
	(segment
		(start 221.5134 -20.600416)
		(end 221.7166 -20.397216)
		(width 0.14224)
		(layer "In4.Cu")
		(net "M_B_DQ<22>")
	)
	(segment
		(start 221.8436 -19.584416)
		(end 221.7166 -19.584416)
		(width 0.14224)
		(layer "In4.Cu")
		(net "M_B_DQ<22>")
	)
	(segment
		(start 236.935264 -48.168814)
		(end 236.507782 -47.741332)
		(width 0.0889)
		(layer "In4.Cu")
		(net "M_B_DQ<22>")
	)
	(segment
		(start 221.41434 -23.169372)
		(end 221.41434 -21.975572)
		(width 0.14224)
		(layer "In4.Cu")
		(net "M_B_DQ<22>")
	)
	(segment
		(start 221.234 -25.905206)
		(end 221.234 -25.498806)
		(width 0.14224)
		(layer "In4.Cu")
		(net "M_B_DQ<22>")
	)
	(segment
		(start 231.9782 -43.165268)
		(end 231.9782 -39.763192)
		(width 0.14224)
		(layer "In4.Cu")
		(net "M_B_DQ<22>")
	)
	(segment
		(start 221.4372 -25.295606)
		(end 221.8182 -25.295606)
		(width 0.14224)
		(layer "In4.Cu")
		(net "M_B_DQ<22>")
	)
	(segment
		(start 221.7166 -19.584416)
		(end 221.5134 -19.381216)
		(width 0.14224)
		(layer "In4.Cu")
		(net "M_B_DQ<22>")
	)
	(segment
		(start 226.434396 -34.219388)
		(end 226.434396 -34.00044)
		(width 0.14224)
		(layer "In4.Cu")
		(net "M_B_DQ<22>")
	)
	(segment
		(start 221.8182 -26.921206)
		(end 222.0214 -26.718006)
		(width 0.14224)
		(layer "In4.Cu")
		(net "M_B_DQ<22>")
	)
	(segment
		(start 225.965512 -33.531556)
		(end 225.746564 -33.531556)
		(width 0.14224)
		(layer "In4.Cu")
		(net "M_B_DQ<22>")
	)
	(segment
		(start 239.392968 -50.837338)
		(end 239.397794 -50.828702)
		(width 0.0889)
		(layer "In4.Cu")
		(net "M_B_DQ<22>")
	)
	(segment
		(start 221.234 -27.530806)
		(end 221.234 -27.124406)
		(width 0.14224)
		(layer "In4.Cu")
		(net "M_B_DQ<22>")
	)
	(segment
		(start 221.41434 -21.975572)
		(end 221.5134 -21.876512)
		(width 0.14224)
		(layer "In4.Cu")
		(net "M_B_DQ<22>")
	)
	(segment
		(start 222.0468 -20.194016)
		(end 222.0468 -19.787616)
		(width 0.14224)
		(layer "In4.Cu")
		(net "M_B_DQ<22>")
	)
	(segment
		(start 221.7166 -20.397216)
		(end 221.8436 -20.397216)
		(width 0.14224)
		(layer "In4.Cu")
		(net "M_B_DQ<22>")
	)
	(segment
		(start 220.814138 -12.928854)
		(end 221.586806 -12.156186)
		(width 0.14224)
		(layer "In4.Cu")
		(net "M_B_DQ<22>")
	)
	(segment
		(start 221.4372 -26.108406)
		(end 221.234 -25.905206)
		(width 0.14224)
		(layer "In4.Cu")
		(net "M_B_DQ<22>")
	)
	(segment
		(start 220.772228 -14.2367)
		(end 221.04985 -13.959078)
		(width 0.14224)
		(layer "In4.Cu")
		(net "M_B_DQ<22>")
	)
	(segment
		(start 239.294924 -50.267616)
		(end 239.294924 -49.78908)
		(width 0.0889)
		(layer "In4.Cu")
		(net "M_B_DQ<22>")
	)
	(segment
		(start 221.8436 -15.6464)
		(end 221.8436 -15.2146)
		(width 0.14224)
		(layer "In4.Cu")
		(net "M_B_DQ<22>")
	)
	(segment
		(start 221.623128 -24.4348)
		(end 221.419928 -24.2316)
		(width 0.14224)
		(layer "In4.Cu")
		(net "M_B_DQ<22>")
	)
	(segment
		(start 221.4118 -28.689046)
		(end 221.55404 -28.546806)
		(width 0.14224)
		(layer "In4.Cu")
		(net "M_B_DQ<22>")
	)
	(segment
		(start 221.4372 -27.734006)
		(end 221.234 -27.530806)
		(width 0.14224)
		(layer "In4.Cu")
		(net "M_B_DQ<22>")
	)
	(segment
		(start 221.542356 -10.369296)
		(end 221.161356 -9.988296)
		(width 0.14224)
		(layer "In4.Cu")
		(net "M_B_DQ<22>")
	)
	(segment
		(start 226.615244 -33.819592)
		(end 226.615244 -33.600644)
		(width 0.14224)
		(layer "In4.Cu")
		(net "M_B_DQ<22>")
	)
	(segment
		(start 235.2675 -46.911006)
		(end 235.2675 -46.454568)
		(width 0.14224)
		(layer "In4.Cu")
		(net "M_B_DQ<22>")
	)
	(segment
		(start 221.8182 -28.546806)
		(end 222.0214 -28.343606)
		(width 0.14224)
		(layer "In4.Cu")
		(net "M_B_DQ<22>")
	)
	(segment
		(start 221.161356 -11.378946)
		(end 221.161356 -11.093704)
		(width 0.14224)
		(layer "In4.Cu")
		(net "M_B_DQ<22>")
	)
	(segment
		(start 226.14636 -33.350708)
		(end 225.965512 -33.531556)
		(width 0.14224)
		(layer "In4.Cu")
		(net "M_B_DQ<22>")
	)
	(segment
		(start 221.8182 -27.734006)
		(end 221.4372 -27.734006)
		(width 0.14224)
		(layer "In4.Cu")
		(net "M_B_DQ<22>")
	)
	(segment
		(start 239.046258 -51.62804)
		(end 239.384332 -51.62804)
		(width 0.0889)
		(layer "In4.Cu")
		(net "M_B_DQ<22>")
	)
	(segment
		(start 221.5134 -21.876512)
		(end 221.5134 -20.600416)
		(width 0.14224)
		(layer "In4.Cu")
		(net "M_B_DQ<22>")
	)
	(segment
		(start 235.2675 -46.454568)
		(end 231.9782 -43.165268)
		(width 0.14224)
		(layer "In4.Cu")
		(net "M_B_DQ<22>")
	)
	(segment
		(start 221.770194 -24.4348)
		(end 221.623128 -24.4348)
		(width 0.14224)
		(layer "In4.Cu")
		(net "M_B_DQ<22>")
	)
	(segment
		(start 222.0214 -25.092406)
		(end 222.0214 -24.686006)
		(width 0.14224)
		(layer "In4.Cu")
		(net "M_B_DQ<22>")
	)
	(segment
		(start 226.434396 -34.00044)
		(end 226.615244 -33.819592)
		(width 0.14224)
		(layer "In4.Cu")
		(net "M_B_DQ<22>")
	)
	(segment
		(start 221.234 -25.498806)
		(end 221.4372 -25.295606)
		(width 0.14224)
		(layer "In4.Cu")
		(net "M_B_DQ<22>")
	)
	(segment
		(start 221.586806 -12.156186)
		(end 221.586806 -11.804396)
		(width 0.14224)
		(layer "In4.Cu")
		(net "M_B_DQ<22>")
	)
	(segment
		(start 221.8182 -25.295606)
		(end 222.0214 -25.092406)
		(width 0.14224)
		(layer "In4.Cu")
		(net "M_B_DQ<22>")
	)
	(segment
		(start 221.542356 -10.712704)
		(end 221.542356 -10.369296)
		(width 0.14224)
		(layer "In4.Cu")
		(net "M_B_DQ<22>")
	)
	(segment
		(start 226.365308 -33.350708)
		(end 226.14636 -33.350708)
		(width 0.14224)
		(layer "In4.Cu")
		(net "M_B_DQ<22>")
	)
	(segment
		(start 221.419928 -23.944072)
		(end 221.51594 -23.84806)
		(width 0.14224)
		(layer "In4.Cu")
		(net "M_B_DQ<22>")
	)
	(segment
		(start 221.161356 -11.093704)
		(end 221.542356 -10.712704)
		(width 0.14224)
		(layer "In4.Cu")
		(net "M_B_DQ<22>")
	)
	(segment
		(start 221.56674 -16.840962)
		(end 221.56674 -15.92326)
		(width 0.14224)
		(layer "In4.Cu")
		(net "M_B_DQ<22>")
	)
	(segment
		(start 236.507782 -47.741332)
		(end 236.097826 -47.741332)
		(width 0.0889)
		(layer "In4.Cu")
		(net "M_B_DQ<22>")
	)
	(segment
		(start 221.4372 -26.921206)
		(end 221.8182 -26.921206)
		(width 0.14224)
		(layer "In4.Cu")
		(net "M_B_DQ<22>")
	)
	(segment
		(start 226.615244 -33.600644)
		(end 226.365308 -33.350708)
		(width 0.14224)
		(layer "In4.Cu")
		(net "M_B_DQ<22>")
	)
	(segment
		(start 221.525338 -9.035796)
		(end 221.899734 -8.6614)
		(width 0.14224)
		(layer "In4.Cu")
		(net "M_B_DQ<22>")
	)
	(segment
		(start 221.4118 -29.196792)
		(end 221.4118 -28.689046)
		(width 0.14224)
		(layer "In4.Cu")
		(net "M_B_DQ<22>")
	)
	(segment
		(start 220.772228 -14.524228)
		(end 220.772228 -14.2367)
		(width 0.14224)
		(layer "In4.Cu")
		(net "M_B_DQ<22>")
	)
	(segment
		(start 221.41434 -18.443194)
		(end 221.41434 -16.993362)
		(width 0.14224)
		(layer "In4.Cu")
		(net "M_B_DQ<22>")
	)
	(segment
		(start 239.392968 -50.437288)
		(end 239.294924 -50.267616)
		(width 0.0889)
		(layer "In4.Cu")
		(net "M_B_DQ<22>")
	)
	(segment
		(start 225.746564 -33.531556)
		(end 221.4118 -29.196792)
		(width 0.14224)
		(layer "In4.Cu")
		(net "M_B_DQ<22>")
	)
	(segment
		(start 221.586806 -11.804396)
		(end 221.161356 -11.378946)
		(width 0.14224)
		(layer "In4.Cu")
		(net "M_B_DQ<22>")
	)
	(segment
		(start 231.9782 -39.763192)
		(end 226.434396 -34.219388)
		(width 0.14224)
		(layer "In4.Cu")
		(net "M_B_DQ<22>")
	)
	(segment
		(start 221.161356 -9.677654)
		(end 221.525338 -9.313672)
		(width 0.14224)
		(layer "In4.Cu")
		(net "M_B_DQ<22>")
	)
	(segment
		(start 221.8436 -15.2146)
		(end 221.3483 -14.7193)
		(width 0.14224)
		(layer "In4.Cu")
		(net "M_B_DQ<22>")
	)
	(segment
		(start 222.0214 -28.343606)
		(end 222.0214 -27.937206)
		(width 0.14224)
		(layer "In4.Cu")
		(net "M_B_DQ<22>")
	)
	(segment
		(start 221.5134 -19.381216)
		(end 221.5134 -18.542254)
		(width 0.14224)
		(layer "In4.Cu")
		(net "M_B_DQ<22>")
	)
	(segment
		(start 221.56674 -15.92326)
		(end 221.8436 -15.6464)
		(width 0.14224)
		(layer "In4.Cu")
		(net "M_B_DQ<22>")
	)
	(segment
		(start 221.8436 -20.397216)
		(end 222.0468 -20.194016)
		(width 0.14224)
		(layer "In4.Cu")
		(net "M_B_DQ<22>")
	)
	(segment
		(start 239.386618 -50.848006)
		(end 239.392968 -50.837338)
		(width 0.0889)
		(layer "In4.Cu")
		(net "M_B_DQ<22>")
	)
	(segment
		(start 221.51594 -23.84806)
		(end 221.51594 -23.270972)
		(width 0.14224)
		(layer "In4.Cu")
		(net "M_B_DQ<22>")
	)
	(segment
		(start 221.161356 -9.988296)
		(end 221.161356 -9.677654)
		(width 0.14224)
		(layer "In4.Cu")
		(net "M_B_DQ<22>")
	)
	(segment
		(start 222.0214 -26.311606)
		(end 221.8182 -26.108406)
		(width 0.14224)
		(layer "In4.Cu")
		(net "M_B_DQ<22>")
	)
	(segment
		(start 222.0214 -24.686006)
		(end 221.770194 -24.4348)
		(width 0.14224)
		(layer "In4.Cu")
		(net "M_B_DQ<22>")
	)
	(segment
		(start 222.0214 -26.718006)
		(end 222.0214 -26.311606)
		(width 0.14224)
		(layer "In4.Cu")
		(net "M_B_DQ<22>")
	)
	(segment
		(start 220.9673 -14.7193)
		(end 220.772228 -14.524228)
		(width 0.14224)
		(layer "In4.Cu")
		(net "M_B_DQ<22>")
	)
	(segment
		(start 239.384332 -51.62804)
		(end 239.442244 -51.570128)
		(width 0.0889)
		(layer "In4.Cu")
		(net "M_B_DQ<22>")
	)
	(segment
		(start 222.0214 -27.937206)
		(end 221.8182 -27.734006)
		(width 0.14224)
		(layer "In4.Cu")
		(net "M_B_DQ<22>")
	)
	(segment
		(start 221.3483 -14.7193)
		(end 220.9673 -14.7193)
		(width 0.14224)
		(layer "In4.Cu")
		(net "M_B_DQ<22>")
	)
	(segment
		(start 221.55404 -28.546806)
		(end 221.8182 -28.546806)
		(width 0.14224)
		(layer "In4.Cu")
		(net "M_B_DQ<22>")
	)
	(segment
		(start 221.41434 -16.993362)
		(end 221.56674 -16.840962)
		(width 0.14224)
		(layer "In4.Cu")
		(net "M_B_DQ<22>")
	)
	(segment
		(start 221.8182 -26.108406)
		(end 221.4372 -26.108406)
		(width 0.14224)
		(layer "In4.Cu")
		(net "M_B_DQ<22>")
	)
	(segment
		(start 221.04985 -13.959078)
		(end 220.814138 -13.723366)
		(width 0.14224)
		(layer "In4.Cu")
		(net "M_B_DQ<22>")
	)
	(segment
		(start 221.234 -27.124406)
		(end 221.4372 -26.921206)
		(width 0.14224)
		(layer "In4.Cu")
		(net "M_B_DQ<22>")
	)
	(segment
		(start 237.674658 -48.168814)
		(end 236.935264 -48.168814)
		(width 0.0889)
		(layer "In4.Cu")
		(net "M_B_DQ<22>")
	)
	(segment
		(start 221.419928 -24.2316)
		(end 221.419928 -23.944072)
		(width 0.14224)
		(layer "In4.Cu")
		(net "M_B_DQ<22>")
	)
	(arc
		(start 239.419892 -51.484276)
		(mid 239.407547 -51.455549)
		(end 239.392968 -51.427888)
		(width 0.0889)
		(layer "In4.Cu")
		(net "M_B_DQ<22>")
	)
	(arc
		(start 239.392968 -51.427888)
		(mid 239.313746 -51.13877)
		(end 239.386618 -50.848006)
		(width 0.0889)
		(layer "In4.Cu")
		(net "M_B_DQ<22>")
	)
	(arc
		(start 239.442244 -51.570128)
		(mid 239.433445 -51.526584)
		(end 239.419892 -51.484276)
		(width 0.0889)
		(layer "In4.Cu")
		(net "M_B_DQ<22>")
	)
	(arc
		(start 239.397794 -50.828702)
		(mid 239.446549 -50.63235)
		(end 239.392968 -50.437288)
		(width 0.0889)
		(layer "In4.Cu")
		(net "M_B_DQ<22>")
	)
	(segment
		(start 237.042198 -53.113686)
		(end 236.470698 -53.113686)
		(width 0.1016)
		(layer "F.Cu")
		(net "M_B_DQ<21>")
	)
	(segment
		(start 215.100408 -5.822442)
		(end 215.0999 -5.822442)
		(width 0.1651)
		(layer "F.Cu")
		(net "M_B_DQ<21>")
	)
	(segment
		(start 215.0999 -5.822442)
		(end 215.0999 -7.086346)
		(width 0.1651)
		(layer "F.Cu")
		(net "M_B_DQ<21>")
	)
	(via
		(at 236.470698 -53.113686)
		(size 0.508)
		(drill 0.254)
		(layers "F.Cu" "B.Cu")
		(net "M_B_DQ<21>")
	)
	(via
		(at 215.0999 -7.086346)
		(size 0.508)
		(drill 0.254)
		(layers "F.Cu" "B.Cu")
		(net "M_B_DQ<21>")
	)
	(via
		(at 215.873584 -12.678156)
		(size 0.508)
		(drill 0.254)
		(layers "F.Cu" "B.Cu")
		(net "M_B_DQ<21>")
	)
	(segment
		(start 215.949784 -12.601956)
		(end 215.873584 -12.678156)
		(width 0.1651)
		(layer "B.Cu")
		(net "M_B_DQ<21>")
	)
	(segment
		(start 215.950292 -10.623042)
		(end 215.949784 -10.623042)
		(width 0.1651)
		(layer "B.Cu")
		(net "M_B_DQ<21>")
	)
	(segment
		(start 215.949784 -10.623042)
		(end 215.949784 -12.601956)
		(width 0.1651)
		(layer "B.Cu")
		(net "M_B_DQ<21>")
	)
	(segment
		(start 216.28354 -16.866362)
		(end 216.28354 -16.069564)
		(width 0.14224)
		(layer "In4.Cu")
		(net "M_B_DQ<21>")
	)
	(segment
		(start 216.381838 -8.452104)
		(end 215.981534 -8.0518)
		(width 0.14224)
		(layer "In4.Cu")
		(net "M_B_DQ<21>")
	)
	(segment
		(start 215.36914 -13.1826)
		(end 215.873584 -12.678156)
		(width 0.14224)
		(layer "In4.Cu")
		(net "M_B_DQ<21>")
	)
	(segment
		(start 215.7984 -15.584424)
		(end 215.7984 -15.2654)
		(width 0.14224)
		(layer "In4.Cu")
		(net "M_B_DQ<21>")
	)
	(segment
		(start 216.28354 -16.069564)
		(end 215.7984 -15.584424)
		(width 0.14224)
		(layer "In4.Cu")
		(net "M_B_DQ<21>")
	)
	(segment
		(start 216.25814 -18.593562)
		(end 216.34704 -18.504662)
		(width 0.14224)
		(layer "In4.Cu")
		(net "M_B_DQ<21>")
	)
	(segment
		(start 230.585518 -48.544988)
		(end 230.585518 -47.845218)
		(width 0.0889)
		(layer "In4.Cu")
		(net "M_B_DQ<21>")
	)
	(segment
		(start 216.34704 -23.220172)
		(end 216.34704 -21.962872)
		(width 0.14224)
		(layer "In4.Cu")
		(net "M_B_DQ<21>")
	)
	(segment
		(start 233.099356 -49.87544)
		(end 231.91597 -49.87544)
		(width 0.0889)
		(layer "In4.Cu")
		(net "M_B_DQ<21>")
	)
	(segment
		(start 216.28354 -23.283672)
		(end 216.34704 -23.220172)
		(width 0.14224)
		(layer "In4.Cu")
		(net "M_B_DQ<21>")
	)
	(segment
		(start 216.34704 -21.962872)
		(end 216.25814 -21.873972)
		(width 0.14224)
		(layer "In4.Cu")
		(net "M_B_DQ<21>")
	)
	(segment
		(start 216.1794 -24.13)
		(end 216.28354 -24.02586)
		(width 0.14224)
		(layer "In4.Cu")
		(net "M_B_DQ<21>")
	)
	(segment
		(start 216.1794 -26.5303)
		(end 216.1794 -24.13)
		(width 0.14224)
		(layer "In4.Cu")
		(net "M_B_DQ<21>")
	)
	(segment
		(start 215.873584 -12.678156)
		(end 216.184988 -12.366752)
		(width 0.14224)
		(layer "In4.Cu")
		(net "M_B_DQ<21>")
	)
	(segment
		(start 216.6112 -19.329146)
		(end 216.25814 -18.976086)
		(width 0.14224)
		(layer "In4.Cu")
		(net "M_B_DQ<21>")
	)
	(segment
		(start 235.914946 -51.965352)
		(end 235.778548 -52.015136)
		(width 0.0889)
		(layer "In4.Cu")
		(net "M_B_DQ<21>")
	)
	(segment
		(start 216.184988 -9.06145)
		(end 216.381838 -8.8646)
		(width 0.14224)
		(layer "In4.Cu")
		(net "M_B_DQ<21>")
	)
	(segment
		(start 218.6813 -31.4833)
		(end 217.0811 -29.8831)
		(width 0.14224)
		(layer "In4.Cu")
		(net "M_B_DQ<21>")
	)
	(segment
		(start 235.778548 -52.015136)
		(end 235.675424 -52.027836)
		(width 0.0889)
		(layer "In4.Cu")
		(net "M_B_DQ<21>")
	)
	(segment
		(start 236.22889 -51.80457)
		(end 235.914946 -51.965352)
		(width 0.0889)
		(layer "In4.Cu")
		(net "M_B_DQ<21>")
	)
	(segment
		(start 215.7984 -15.2654)
		(end 216.03462 -15.02918)
		(width 0.14224)
		(layer "In4.Cu")
		(net "M_B_DQ<21>")
	)
	(segment
		(start 215.670638 -8.0518)
		(end 215.0999 -7.481062)
		(width 0.14224)
		(layer "In4.Cu")
		(net "M_B_DQ<21>")
	)
	(segment
		(start 216.34704 -16.929862)
		(end 216.28354 -16.866362)
		(width 0.14224)
		(layer "In4.Cu")
		(net "M_B_DQ<21>")
	)
	(segment
		(start 216.25814 -21.257514)
		(end 216.6112 -20.904454)
		(width 0.14224)
		(layer "In4.Cu")
		(net "M_B_DQ<21>")
	)
	(segment
		(start 216.34704 -18.504662)
		(end 216.34704 -16.929862)
		(width 0.14224)
		(layer "In4.Cu")
		(net "M_B_DQ<21>")
	)
	(segment
		(start 217.0811 -27.432)
		(end 216.1794 -26.5303)
		(width 0.14224)
		(layer "In4.Cu")
		(net "M_B_DQ<21>")
	)
	(segment
		(start 230.3653 -47.014638)
		(end 227.2284 -43.877738)
		(width 0.14224)
		(layer "In4.Cu")
		(net "M_B_DQ<21>")
	)
	(segment
		(start 216.03462 -14.208252)
		(end 215.36914 -13.542772)
		(width 0.14224)
		(layer "In4.Cu")
		(net "M_B_DQ<21>")
	)
	(segment
		(start 215.0999 -7.481062)
		(end 215.0999 -7.086346)
		(width 0.14224)
		(layer "In4.Cu")
		(net "M_B_DQ<21>")
	)
	(segment
		(start 236.470698 -53.113686)
		(end 236.763814 -52.944776)
		(width 0.0889)
		(layer "In4.Cu")
		(net "M_B_DQ<21>")
	)
	(segment
		(start 216.25814 -18.976086)
		(end 216.25814 -18.593562)
		(width 0.14224)
		(layer "In4.Cu")
		(net "M_B_DQ<21>")
	)
	(segment
		(start 236.763814 -52.944776)
		(end 236.78769 -52.855368)
		(width 0.0889)
		(layer "In4.Cu")
		(net "M_B_DQ<21>")
	)
	(segment
		(start 216.6112 -20.904454)
		(end 216.6112 -19.329146)
		(width 0.14224)
		(layer "In4.Cu")
		(net "M_B_DQ<21>")
	)
	(segment
		(start 218.6813 -32.695642)
		(end 218.6813 -31.4833)
		(width 0.14224)
		(layer "In4.Cu")
		(net "M_B_DQ<21>")
	)
	(segment
		(start 216.381838 -8.8646)
		(end 216.381838 -8.452104)
		(width 0.14224)
		(layer "In4.Cu")
		(net "M_B_DQ<21>")
	)
	(segment
		(start 230.3653 -47.625)
		(end 230.3653 -47.014638)
		(width 0.14224)
		(layer "In4.Cu")
		(net "M_B_DQ<21>")
	)
	(segment
		(start 216.25814 -21.873972)
		(end 216.25814 -21.257514)
		(width 0.14224)
		(layer "In4.Cu")
		(net "M_B_DQ<21>")
	)
	(segment
		(start 216.03462 -15.02918)
		(end 216.03462 -14.208252)
		(width 0.14224)
		(layer "In4.Cu")
		(net "M_B_DQ<21>")
	)
	(segment
		(start 234.766612 -51.532536)
		(end 234.738672 -51.532536)
		(width 0.0889)
		(layer "In4.Cu")
		(net "M_B_DQ<21>")
	)
	(segment
		(start 230.585518 -47.845218)
		(end 230.3653 -47.625)
		(width 0.14224)
		(layer "In4.Cu")
		(net "M_B_DQ<21>")
	)
	(segment
		(start 227.2284 -41.242742)
		(end 218.6813 -32.695642)
		(width 0.14224)
		(layer "In4.Cu")
		(net "M_B_DQ<21>")
	)
	(segment
		(start 231.91597 -49.87544)
		(end 230.585518 -48.544988)
		(width 0.0889)
		(layer "In4.Cu")
		(net "M_B_DQ<21>")
	)
	(segment
		(start 227.2284 -43.877738)
		(end 227.2284 -41.242742)
		(width 0.14224)
		(layer "In4.Cu")
		(net "M_B_DQ<21>")
	)
	(segment
		(start 217.0811 -29.8831)
		(end 217.0811 -27.432)
		(width 0.14224)
		(layer "In4.Cu")
		(net "M_B_DQ<21>")
	)
	(segment
		(start 235.675424 -52.027836)
		(end 235.594144 -52.027836)
		(width 0.0889)
		(layer "In4.Cu")
		(net "M_B_DQ<21>")
	)
	(segment
		(start 215.36914 -13.542772)
		(end 215.36914 -13.1826)
		(width 0.14224)
		(layer "In4.Cu")
		(net "M_B_DQ<21>")
	)
	(segment
		(start 234.406948 -51.332638)
		(end 234.202986 -50.97907)
		(width 0.0889)
		(layer "In4.Cu")
		(net "M_B_DQ<21>")
	)
	(segment
		(start 215.981534 -8.0518)
		(end 215.670638 -8.0518)
		(width 0.14224)
		(layer "In4.Cu")
		(net "M_B_DQ<21>")
	)
	(segment
		(start 216.184988 -12.366752)
		(end 216.184988 -9.06145)
		(width 0.14224)
		(layer "In4.Cu")
		(net "M_B_DQ<21>")
	)
	(segment
		(start 216.28354 -24.02586)
		(end 216.28354 -23.283672)
		(width 0.14224)
		(layer "In4.Cu")
		(net "M_B_DQ<21>")
	)
	(segment
		(start 234.202986 -50.97907)
		(end 233.099356 -49.87544)
		(width 0.0889)
		(layer "In4.Cu")
		(net "M_B_DQ<21>")
	)
	(arc
		(start 235.265468 -51.827938)
		(mid 235.054755 -51.614859)
		(end 234.766612 -51.532536)
		(width 0.0889)
		(layer "In4.Cu")
		(net "M_B_DQ<21>")
	)
	(arc
		(start 234.738672 -51.532536)
		(mid 234.54703 -51.47537)
		(end 234.406948 -51.332638)
		(width 0.0889)
		(layer "In4.Cu")
		(net "M_B_DQ<21>")
	)
	(arc
		(start 236.78769 -52.855368)
		(mid 236.738678 -52.591919)
		(end 236.811058 -52.333906)
		(width 0.0889)
		(layer "In4.Cu")
		(net "M_B_DQ<21>")
	)
	(arc
		(start 236.811058 -52.333906)
		(mid 236.814141 -52.328517)
		(end 236.817408 -52.323238)
		(width 0.0889)
		(layer "In4.Cu")
		(net "M_B_DQ<21>")
	)
	(arc
		(start 235.594144 -52.027836)
		(mid 235.404215 -51.969966)
		(end 235.265468 -51.827938)
		(width 0.0889)
		(layer "In4.Cu")
		(net "M_B_DQ<21>")
	)
	(arc
		(start 236.817408 -52.323238)
		(mid 236.735317 -51.8231)
		(end 236.22889 -51.80457)
		(width 0.0889)
		(layer "In4.Cu")
		(net "M_B_DQ<21>")
	)
	(segment
		(start 215.889332 -8.763)
		(end 215.85174 -8.5598)
		(width 0.1651)
		(layer "F.Cu")
		(net "M_B_DQ<20>")
	)
	(segment
		(start 215.949784 -9.091168)
		(end 215.889332 -8.763)
		(width 0.1651)
		(layer "F.Cu")
		(net "M_B_DQ<20>")
	)
	(segment
		(start 215.950292 -10.422382)
		(end 215.949784 -10.422382)
		(width 0.1651)
		(layer "F.Cu")
		(net "M_B_DQ<20>")
	)
	(segment
		(start 215.949784 -10.422382)
		(end 215.949784 -9.091168)
		(width 0.1651)
		(layer "F.Cu")
		(net "M_B_DQ<20>")
	)
	(segment
		(start 237.042198 -52.12334)
		(end 236.470698 -52.12334)
		(width 0.1016)
		(layer "F.Cu")
		(net "M_B_DQ<20>")
	)
	(via
		(at 215.85174 -8.5598)
		(size 0.508)
		(drill 0.254)
		(layers "F.Cu" "B.Cu")
		(net "M_B_DQ<20>")
	)
	(via
		(at 215.0999 -13.959078)
		(size 0.508)
		(drill 0.254)
		(layers "F.Cu" "B.Cu")
		(net "M_B_DQ<20>")
	)
	(via
		(at 236.470698 -52.12334)
		(size 0.508)
		(drill 0.254)
		(layers "F.Cu" "B.Cu")
		(net "M_B_DQ<20>")
	)
	(segment
		(start 215.0999 -15.222982)
		(end 215.0999 -13.959078)
		(width 0.1651)
		(layer "B.Cu")
		(net "M_B_DQ<20>")
	)
	(segment
		(start 215.100408 -15.222982)
		(end 215.0999 -15.222982)
		(width 0.1651)
		(layer "B.Cu")
		(net "M_B_DQ<20>")
	)
	(segment
		(start 215.0999 -15.6845)
		(end 215.59774 -16.18234)
		(width 0.14224)
		(layer "In4.Cu")
		(net "M_B_DQ<20>")
	)
	(segment
		(start 215.7095 -29.98343)
		(end 215.86444 -30.13837)
		(width 0.14224)
		(layer "In4.Cu")
		(net "M_B_DQ<20>")
	)
	(segment
		(start 216.25306 -30.13837)
		(end 217.8812 -31.76651)
		(width 0.14224)
		(layer "In4.Cu")
		(net "M_B_DQ<20>")
	)
	(segment
		(start 215.0999 -13.959078)
		(end 215.0999 -14.287246)
		(width 0.14224)
		(layer "In4.Cu")
		(net "M_B_DQ<20>")
	)
	(segment
		(start 233.02087 -50.065686)
		(end 234.05084 -51.095656)
		(width 0.0889)
		(layer "In4.Cu")
		(net "M_B_DQ<20>")
	)
	(segment
		(start 215.362536 -14.549882)
		(end 215.362536 -14.837664)
		(width 0.14224)
		(layer "In4.Cu")
		(net "M_B_DQ<20>")
	)
	(segment
		(start 215.62314 -19.2786)
		(end 215.9508 -19.60626)
		(width 0.14224)
		(layer "In4.Cu")
		(net "M_B_DQ<20>")
	)
	(segment
		(start 215.62314 -18.568162)
		(end 215.62314 -19.2786)
		(width 0.14224)
		(layer "In4.Cu")
		(net "M_B_DQ<20>")
	)
	(segment
		(start 215.9508 -20.6248)
		(end 215.62314 -20.95246)
		(width 0.14224)
		(layer "In4.Cu")
		(net "M_B_DQ<20>")
	)
	(segment
		(start 215.62314 -20.95246)
		(end 215.62314 -21.696172)
		(width 0.14224)
		(layer "In4.Cu")
		(net "M_B_DQ<20>")
	)
	(segment
		(start 215.575388 -12.217654)
		(end 214.864188 -12.928854)
		(width 0.14224)
		(layer "In4.Cu")
		(net "M_B_DQ<20>")
	)
	(segment
		(start 215.362536 -14.837664)
		(end 215.0999 -15.1003)
		(width 0.14224)
		(layer "In4.Cu")
		(net "M_B_DQ<20>")
	)
	(segment
		(start 214.864188 -12.928854)
		(end 214.864188 -13.723366)
		(width 0.14224)
		(layer "In4.Cu")
		(net "M_B_DQ<20>")
	)
	(segment
		(start 215.0999 -15.1003)
		(end 215.0999 -15.6845)
		(width 0.14224)
		(layer "In4.Cu")
		(net "M_B_DQ<20>")
	)
	(segment
		(start 215.95334 -28.14955)
		(end 215.8111 -28.29179)
		(width 0.14224)
		(layer "In4.Cu")
		(net "M_B_DQ<20>")
	)
	(segment
		(start 215.224106 -11.0363)
		(end 215.224106 -11.391646)
		(width 0.14224)
		(layer "In4.Cu")
		(net "M_B_DQ<20>")
	)
	(segment
		(start 215.224106 -11.391646)
		(end 215.575388 -11.742928)
		(width 0.14224)
		(layer "In4.Cu")
		(net "M_B_DQ<20>")
	)
	(segment
		(start 215.36914 -18.314162)
		(end 215.62314 -18.568162)
		(width 0.14224)
		(layer "In4.Cu")
		(net "M_B_DQ<20>")
	)
	(segment
		(start 229.8446 -47.392082)
		(end 229.8446 -48.387254)
		(width 0.14224)
		(layer "In4.Cu")
		(net "M_B_DQ<20>")
	)
	(segment
		(start 215.36914 -21.950172)
		(end 215.36914 -23.169372)
		(width 0.14224)
		(layer "In4.Cu")
		(net "M_B_DQ<20>")
	)
	(segment
		(start 216.25306 -28.14955)
		(end 215.95334 -28.14955)
		(width 0.14224)
		(layer "In4.Cu")
		(net "M_B_DQ<20>")
	)
	(segment
		(start 215.519 -26.737056)
		(end 216.408 -27.626056)
		(width 0.14224)
		(layer "In4.Cu")
		(net "M_B_DQ<20>")
	)
	(segment
		(start 235.777786 -52.21859)
		(end 236.10316 -52.180998)
		(width 0.0889)
		(layer "In4.Cu")
		(net "M_B_DQ<20>")
	)
	(segment
		(start 215.575388 -9.313672)
		(end 215.211406 -9.677654)
		(width 0.14224)
		(layer "In4.Cu")
		(net "M_B_DQ<20>")
	)
	(segment
		(start 215.59774 -16.837914)
		(end 215.36914 -17.066514)
		(width 0.14224)
		(layer "In4.Cu")
		(net "M_B_DQ<20>")
	)
	(segment
		(start 215.59774 -23.77186)
		(end 215.519 -23.8506)
		(width 0.14224)
		(layer "In4.Cu")
		(net "M_B_DQ<20>")
	)
	(segment
		(start 226.5934 -44.140882)
		(end 229.8446 -47.392082)
		(width 0.14224)
		(layer "In4.Cu")
		(net "M_B_DQ<20>")
	)
	(segment
		(start 229.8446 -48.387254)
		(end 230.13797 -48.680624)
		(width 0.0889)
		(layer "In4.Cu")
		(net "M_B_DQ<20>")
	)
	(segment
		(start 231.836976 -50.065686)
		(end 233.02087 -50.065686)
		(width 0.0889)
		(layer "In4.Cu")
		(net "M_B_DQ<20>")
	)
	(segment
		(start 214.864188 -13.723366)
		(end 215.0999 -13.959078)
		(width 0.14224)
		(layer "In4.Cu")
		(net "M_B_DQ<20>")
	)
	(segment
		(start 215.592406 -10.3632)
		(end 215.592406 -10.668)
		(width 0.14224)
		(layer "In4.Cu")
		(net "M_B_DQ<20>")
	)
	(segment
		(start 234.05084 -51.095656)
		(end 234.242356 -51.427634)
		(width 0.0889)
		(layer "In4.Cu")
		(net "M_B_DQ<20>")
	)
	(segment
		(start 216.408 -27.99461)
		(end 216.25306 -28.14955)
		(width 0.14224)
		(layer "In4.Cu")
		(net "M_B_DQ<20>")
	)
	(segment
		(start 215.59774 -16.18234)
		(end 215.59774 -16.837914)
		(width 0.14224)
		(layer "In4.Cu")
		(net "M_B_DQ<20>")
	)
	(segment
		(start 216.408 -29.32049)
		(end 216.25306 -29.47543)
		(width 0.14224)
		(layer "In4.Cu")
		(net "M_B_DQ<20>")
	)
	(segment
		(start 215.9508 -19.60626)
		(end 215.9508 -20.6248)
		(width 0.14224)
		(layer "In4.Cu")
		(net "M_B_DQ<20>")
	)
	(segment
		(start 215.592406 -10.668)
		(end 215.224106 -11.0363)
		(width 0.14224)
		(layer "In4.Cu")
		(net "M_B_DQ<20>")
	)
	(segment
		(start 215.85174 -8.5598)
		(end 215.575388 -8.836152)
		(width 0.14224)
		(layer "In4.Cu")
		(net "M_B_DQ<20>")
	)
	(segment
		(start 216.408 -27.626056)
		(end 216.408 -27.99461)
		(width 0.14224)
		(layer "In4.Cu")
		(net "M_B_DQ<20>")
	)
	(segment
		(start 217.8812 -31.76651)
		(end 217.8812 -32.793686)
		(width 0.14224)
		(layer "In4.Cu")
		(net "M_B_DQ<20>")
	)
	(segment
		(start 235.590588 -52.21859)
		(end 235.777786 -52.21859)
		(width 0.0889)
		(layer "In4.Cu")
		(net "M_B_DQ<20>")
	)
	(segment
		(start 215.211406 -9.677654)
		(end 215.211406 -9.9822)
		(width 0.14224)
		(layer "In4.Cu")
		(net "M_B_DQ<20>")
	)
	(segment
		(start 215.86444 -29.47543)
		(end 215.7095 -29.63037)
		(width 0.14224)
		(layer "In4.Cu")
		(net "M_B_DQ<20>")
	)
	(segment
		(start 234.740704 -51.72329)
		(end 234.764834 -51.72329)
		(width 0.0889)
		(layer "In4.Cu")
		(net "M_B_DQ<20>")
	)
	(segment
		(start 215.211406 -9.9822)
		(end 215.592406 -10.3632)
		(width 0.14224)
		(layer "In4.Cu")
		(net "M_B_DQ<20>")
	)
	(segment
		(start 215.86444 -30.13837)
		(end 216.25306 -30.13837)
		(width 0.14224)
		(layer "In4.Cu")
		(net "M_B_DQ<20>")
	)
	(segment
		(start 215.36914 -23.169372)
		(end 215.59774 -23.397972)
		(width 0.14224)
		(layer "In4.Cu")
		(net "M_B_DQ<20>")
	)
	(segment
		(start 216.408 -28.96743)
		(end 216.408 -29.32049)
		(width 0.14224)
		(layer "In4.Cu")
		(net "M_B_DQ<20>")
	)
	(segment
		(start 215.62314 -21.696172)
		(end 215.36914 -21.950172)
		(width 0.14224)
		(layer "In4.Cu")
		(net "M_B_DQ<20>")
	)
	(segment
		(start 216.25306 -28.81249)
		(end 216.408 -28.96743)
		(width 0.14224)
		(layer "In4.Cu")
		(net "M_B_DQ<20>")
	)
	(segment
		(start 217.8812 -32.793686)
		(end 226.5934 -41.505886)
		(width 0.14224)
		(layer "In4.Cu")
		(net "M_B_DQ<20>")
	)
	(segment
		(start 215.8111 -28.67025)
		(end 215.95334 -28.81249)
		(width 0.14224)
		(layer "In4.Cu")
		(net "M_B_DQ<20>")
	)
	(segment
		(start 215.36914 -17.066514)
		(end 215.36914 -18.314162)
		(width 0.14224)
		(layer "In4.Cu")
		(net "M_B_DQ<20>")
	)
	(segment
		(start 230.451914 -48.680624)
		(end 231.836976 -50.065686)
		(width 0.0889)
		(layer "In4.Cu")
		(net "M_B_DQ<20>")
	)
	(segment
		(start 215.95334 -28.81249)
		(end 216.25306 -28.81249)
		(width 0.14224)
		(layer "In4.Cu")
		(net "M_B_DQ<20>")
	)
	(segment
		(start 215.519 -23.8506)
		(end 215.519 -26.737056)
		(width 0.14224)
		(layer "In4.Cu")
		(net "M_B_DQ<20>")
	)
	(segment
		(start 226.5934 -41.505886)
		(end 226.5934 -44.140882)
		(width 0.14224)
		(layer "In4.Cu")
		(net "M_B_DQ<20>")
	)
	(segment
		(start 216.25306 -29.47543)
		(end 215.86444 -29.47543)
		(width 0.14224)
		(layer "In4.Cu")
		(net "M_B_DQ<20>")
	)
	(segment
		(start 215.0999 -14.287246)
		(end 215.362536 -14.549882)
		(width 0.14224)
		(layer "In4.Cu")
		(net "M_B_DQ<20>")
	)
	(segment
		(start 215.59774 -23.397972)
		(end 215.59774 -23.77186)
		(width 0.14224)
		(layer "In4.Cu")
		(net "M_B_DQ<20>")
	)
	(segment
		(start 234.242356 -51.427634)
		(end 234.241848 -51.427888)
		(width 0.0889)
		(layer "In4.Cu")
		(net "M_B_DQ<20>")
	)
	(segment
		(start 236.10316 -52.180998)
		(end 236.470698 -52.12334)
		(width 0.0889)
		(layer "In4.Cu")
		(net "M_B_DQ<20>")
	)
	(segment
		(start 215.575388 -8.836152)
		(end 215.575388 -9.313672)
		(width 0.14224)
		(layer "In4.Cu")
		(net "M_B_DQ<20>")
	)
	(segment
		(start 215.8111 -28.29179)
		(end 215.8111 -28.67025)
		(width 0.14224)
		(layer "In4.Cu")
		(net "M_B_DQ<20>")
	)
	(segment
		(start 215.7095 -29.63037)
		(end 215.7095 -29.98343)
		(width 0.14224)
		(layer "In4.Cu")
		(net "M_B_DQ<20>")
	)
	(segment
		(start 230.13797 -48.680624)
		(end 230.451914 -48.680624)
		(width 0.0889)
		(layer "In4.Cu")
		(net "M_B_DQ<20>")
	)
	(segment
		(start 215.575388 -11.742928)
		(end 215.575388 -12.217654)
		(width 0.14224)
		(layer "In4.Cu")
		(net "M_B_DQ<20>")
	)
	(arc
		(start 234.764834 -51.72329)
		(mid 234.958684 -51.77964)
		(end 235.100368 -51.923442)
		(width 0.0889)
		(layer "In4.Cu")
		(net "M_B_DQ<20>")
	)
	(arc
		(start 234.241848 -51.427888)
		(mid 234.452561 -51.640967)
		(end 234.740704 -51.72329)
		(width 0.0889)
		(layer "In4.Cu")
		(net "M_B_DQ<20>")
	)
	(arc
		(start 235.100368 -51.923442)
		(mid 235.307372 -52.134306)
		(end 235.590588 -52.21859)
		(width 0.0889)
		(layer "In4.Cu")
		(net "M_B_DQ<20>")
	)
	(segment
		(start 238.759238 -66.982086)
		(end 238.187738 -66.982086)
		(width 0.0889)
		(layer "F.Cu")
		(net "M_B_DQ<1>")
	)
	(segment
		(start 198.099934 -5.822442)
		(end 198.099934 -7.086346)
		(width 0.1651)
		(layer "F.Cu")
		(net "M_B_DQ<1>")
	)
	(segment
		(start 198.100442 -5.822442)
		(end 198.099934 -5.822442)
		(width 0.1651)
		(layer "F.Cu")
		(net "M_B_DQ<1>")
	)
	(via
		(at 238.187738 -66.982086)
		(size 0.508)
		(drill 0.254)
		(layers "F.Cu" "B.Cu")
		(net "M_B_DQ<1>")
	)
	(via
		(at 198.772018 -12.678156)
		(size 0.508)
		(drill 0.254)
		(layers "F.Cu" "B.Cu")
		(net "M_B_DQ<1>")
	)
	(via
		(at 198.099934 -7.086346)
		(size 0.508)
		(drill 0.254)
		(layers "F.Cu" "B.Cu")
		(net "M_B_DQ<1>")
	)
	(segment
		(start 198.772018 -12.174982)
		(end 198.772018 -12.678156)
		(width 0.1651)
		(layer "B.Cu")
		(net "M_B_DQ<1>")
	)
	(segment
		(start 198.950326 -10.623042)
		(end 198.949818 -10.623042)
		(width 0.1651)
		(layer "B.Cu")
		(net "M_B_DQ<1>")
	)
	(segment
		(start 198.949818 -10.623042)
		(end 198.949818 -11.997182)
		(width 0.1651)
		(layer "B.Cu")
		(net "M_B_DQ<1>")
	)
	(segment
		(start 198.949818 -11.997182)
		(end 198.772018 -12.174982)
		(width 0.1651)
		(layer "B.Cu")
		(net "M_B_DQ<1>")
	)
	(segment
		(start 198.772018 -12.678156)
		(end 198.245476 -13.204698)
		(width 0.14224)
		(layer "In4.Cu")
		(net "M_B_DQ<1>")
	)
	(segment
		(start 236.459522 -67.572636)
		(end 236.564424 -67.572636)
		(width 0.0889)
		(layer "In4.Cu")
		(net "M_B_DQ<1>")
	)
	(segment
		(start 199.14616 -8.970264)
		(end 199.14616 -12.304014)
		(width 0.14224)
		(layer "In4.Cu")
		(net "M_B_DQ<1>")
	)
	(segment
		(start 199.5424 -24.0792)
		(end 199.5424 -27.3304)
		(width 0.14224)
		(layer "In4.Cu")
		(net "M_B_DQ<1>")
	)
	(segment
		(start 199.0217 -27.8511)
		(end 199.0217 -37.1729)
		(width 0.14224)
		(layer "In4.Cu")
		(net "M_B_DQ<1>")
	)
	(segment
		(start 219.1131 -57.2643)
		(end 219.456 -57.2643)
		(width 0.14224)
		(layer "In4.Cu")
		(net "M_B_DQ<1>")
	)
	(segment
		(start 236.013244 -68.573904)
		(end 236.070902 -67.992244)
		(width 0.0889)
		(layer "In4.Cu")
		(net "M_B_DQ<1>")
	)
	(segment
		(start 199.302624 -8.8138)
		(end 199.14616 -8.970264)
		(width 0.14224)
		(layer "In4.Cu")
		(net "M_B_DQ<1>")
	)
	(segment
		(start 235.590588 -68.86829)
		(end 235.623354 -68.86829)
		(width 0.0889)
		(layer "In4.Cu")
		(net "M_B_DQ<1>")
	)
	(segment
		(start 201.84745 -39.99865)
		(end 202.66025 -39.99865)
		(width 0.14224)
		(layer "In4.Cu")
		(net "M_B_DQ<1>")
	)
	(segment
		(start 198.099934 -7.086346)
		(end 198.099934 -7.625334)
		(width 0.14224)
		(layer "In4.Cu")
		(net "M_B_DQ<1>")
	)
	(segment
		(start 198.099934 -7.625334)
		(end 198.5772 -8.1026)
		(width 0.14224)
		(layer "In4.Cu")
		(net "M_B_DQ<1>")
	)
	(segment
		(start 237.692692 -67.648074)
		(end 238.187738 -66.982086)
		(width 0.0889)
		(layer "In4.Cu")
		(net "M_B_DQ<1>")
	)
	(segment
		(start 235.958888 -68.668138)
		(end 236.013244 -68.573904)
		(width 0.0889)
		(layer "In4.Cu")
		(net "M_B_DQ<1>")
	)
	(segment
		(start 198.624952 -15.617952)
		(end 199.259952 -16.252952)
		(width 0.14224)
		(layer "In4.Cu")
		(net "M_B_DQ<1>")
	)
	(segment
		(start 203.87945 -42.03065)
		(end 219.1131 -57.2643)
		(width 0.14224)
		(layer "In4.Cu")
		(net "M_B_DQ<1>")
	)
	(segment
		(start 198.624952 -13.865352)
		(end 198.624952 -15.617952)
		(width 0.14224)
		(layer "In4.Cu")
		(net "M_B_DQ<1>")
	)
	(segment
		(start 199.302624 -8.472424)
		(end 199.302624 -8.8138)
		(width 0.14224)
		(layer "In4.Cu")
		(net "M_B_DQ<1>")
	)
	(segment
		(start 231.62768 -67.87769)
		(end 232.305098 -67.87769)
		(width 0.0889)
		(layer "In4.Cu")
		(net "M_B_DQ<1>")
	)
	(segment
		(start 237.675928 -67.677538)
		(end 237.692692 -67.648074)
		(width 0.0889)
		(layer "In4.Cu")
		(net "M_B_DQ<1>")
	)
	(segment
		(start 198.245476 -13.485876)
		(end 198.624952 -13.865352)
		(width 0.14224)
		(layer "In4.Cu")
		(net "M_B_DQ<1>")
	)
	(segment
		(start 219.456 -57.2643)
		(end 229.964234 -67.772534)
		(width 0.14224)
		(layer "In4.Cu")
		(net "M_B_DQ<1>")
	)
	(segment
		(start 199.259952 -23.796752)
		(end 199.5424 -24.0792)
		(width 0.14224)
		(layer "In4.Cu")
		(net "M_B_DQ<1>")
	)
	(segment
		(start 199.5424 -27.3304)
		(end 199.0217 -27.8511)
		(width 0.14224)
		(layer "In4.Cu")
		(net "M_B_DQ<1>")
	)
	(segment
		(start 234.738672 -69.363336)
		(end 234.768644 -69.363336)
		(width 0.0889)
		(layer "In4.Cu")
		(net "M_B_DQ<1>")
	)
	(segment
		(start 199.14616 -12.304014)
		(end 198.772018 -12.678156)
		(width 0.14224)
		(layer "In4.Cu")
		(net "M_B_DQ<1>")
	)
	(segment
		(start 203.87945 -41.21785)
		(end 203.87945 -42.03065)
		(width 0.14224)
		(layer "In4.Cu")
		(net "M_B_DQ<1>")
	)
	(segment
		(start 233.883962 -68.86829)
		(end 233.916728 -68.86829)
		(width 0.0889)
		(layer "In4.Cu")
		(net "M_B_DQ<1>")
	)
	(segment
		(start 232.86974 -68.372736)
		(end 233.054398 -68.372736)
		(width 0.0889)
		(layer "In4.Cu")
		(net "M_B_DQ<1>")
	)
	(segment
		(start 236.564424 -67.572636)
		(end 237.111794 -67.813682)
		(width 0.0889)
		(layer "In4.Cu")
		(net "M_B_DQ<1>")
	)
	(segment
		(start 198.5772 -8.1026)
		(end 198.9328 -8.1026)
		(width 0.14224)
		(layer "In4.Cu")
		(net "M_B_DQ<1>")
	)
	(segment
		(start 231.522524 -67.772534)
		(end 231.62768 -67.87769)
		(width 0.0889)
		(layer "In4.Cu")
		(net "M_B_DQ<1>")
	)
	(segment
		(start 199.259952 -16.252952)
		(end 199.259952 -23.796752)
		(width 0.14224)
		(layer "In4.Cu")
		(net "M_B_DQ<1>")
	)
	(segment
		(start 199.0217 -37.1729)
		(end 201.84745 -39.99865)
		(width 0.14224)
		(layer "In4.Cu")
		(net "M_B_DQ<1>")
	)
	(segment
		(start 229.964234 -67.772534)
		(end 231.522524 -67.772534)
		(width 0.14224)
		(layer "In4.Cu")
		(net "M_B_DQ<1>")
	)
	(segment
		(start 202.66025 -39.99865)
		(end 203.87945 -41.21785)
		(width 0.14224)
		(layer "In4.Cu")
		(net "M_B_DQ<1>")
	)
	(segment
		(start 198.245476 -13.204698)
		(end 198.245476 -13.485876)
		(width 0.14224)
		(layer "In4.Cu")
		(net "M_B_DQ<1>")
	)
	(segment
		(start 198.9328 -8.1026)
		(end 199.302624 -8.472424)
		(width 0.14224)
		(layer "In4.Cu")
		(net "M_B_DQ<1>")
	)
	(arc
		(start 236.070902 -67.992244)
		(mid 236.177003 -67.700726)
		(end 236.459522 -67.572636)
		(width 0.0889)
		(layer "In4.Cu")
		(net "M_B_DQ<1>")
	)
	(arc
		(start 235.623354 -68.86829)
		(mid 235.817204 -68.81194)
		(end 235.958888 -68.668138)
		(width 0.0889)
		(layer "In4.Cu")
		(net "M_B_DQ<1>")
	)
	(arc
		(start 233.054398 -68.372736)
		(mid 233.339822 -68.456203)
		(end 233.548428 -68.668138)
		(width 0.0889)
		(layer "In4.Cu")
		(net "M_B_DQ<1>")
	)
	(arc
		(start 233.548428 -68.668138)
		(mid 233.690111 -68.811942)
		(end 233.883962 -68.86829)
		(width 0.0889)
		(layer "In4.Cu")
		(net "M_B_DQ<1>")
	)
	(arc
		(start 232.305098 -67.87769)
		(mid 232.507692 -67.993508)
		(end 232.653586 -68.175632)
		(width 0.0889)
		(layer "In4.Cu")
		(net "M_B_DQ<1>")
	)
	(arc
		(start 237.111794 -67.813682)
		(mid 237.423097 -67.866721)
		(end 237.675928 -67.677538)
		(width 0.0889)
		(layer "In4.Cu")
		(net "M_B_DQ<1>")
	)
	(arc
		(start 233.916728 -68.86829)
		(mid 234.199945 -68.952571)
		(end 234.406948 -69.163438)
		(width 0.0889)
		(layer "In4.Cu")
		(net "M_B_DQ<1>")
	)
	(arc
		(start 235.100368 -69.163438)
		(mid 235.307372 -68.952574)
		(end 235.590588 -68.86829)
		(width 0.0889)
		(layer "In4.Cu")
		(net "M_B_DQ<1>")
	)
	(arc
		(start 234.406948 -69.163438)
		(mid 234.547027 -69.306174)
		(end 234.738672 -69.363336)
		(width 0.0889)
		(layer "In4.Cu")
		(net "M_B_DQ<1>")
	)
	(arc
		(start 234.768644 -69.363336)
		(mid 234.960286 -69.30617)
		(end 235.100368 -69.163438)
		(width 0.0889)
		(layer "In4.Cu")
		(net "M_B_DQ<1>")
	)
	(arc
		(start 232.653586 -68.175632)
		(mid 232.74453 -68.292975)
		(end 232.86974 -68.372736)
		(width 0.0889)
		(layer "In4.Cu")
		(net "M_B_DQ<1>")
	)
	(segment
		(start 222.749872 -5.822442)
		(end 222.749872 -7.086346)
		(width 0.1651)
		(layer "F.Cu")
		(net "M_B_DQ<19>")
	)
	(segment
		(start 222.75038 -5.822442)
		(end 222.749872 -5.822442)
		(width 0.1651)
		(layer "F.Cu")
		(net "M_B_DQ<19>")
	)
	(segment
		(start 240.476278 -53.113686)
		(end 239.904778 -53.113686)
		(width 0.1016)
		(layer "F.Cu")
		(net "M_B_DQ<19>")
	)
	(via
		(at 223.599756 -12.678156)
		(size 0.508)
		(drill 0.254)
		(layers "F.Cu" "B.Cu")
		(net "M_B_DQ<19>")
	)
	(via
		(at 239.904778 -53.113686)
		(size 0.508)
		(drill 0.254)
		(layers "F.Cu" "B.Cu")
		(net "M_B_DQ<19>")
	)
	(via
		(at 222.749872 -7.086346)
		(size 0.508)
		(drill 0.254)
		(layers "F.Cu" "B.Cu")
		(net "M_B_DQ<19>")
	)
	(segment
		(start 223.60001 -10.882122)
		(end 223.599756 -10.882376)
		(width 0.1651)
		(layer "B.Cu")
		(net "M_B_DQ<19>")
	)
	(segment
		(start 223.60001 -10.623042)
		(end 223.60001 -10.882122)
		(width 0.1651)
		(layer "B.Cu")
		(net "M_B_DQ<19>")
	)
	(segment
		(start 223.599756 -10.882376)
		(end 223.599756 -12.678156)
		(width 0.1651)
		(layer "B.Cu")
		(net "M_B_DQ<19>")
	)
	(segment
		(start 223.600518 -10.623042)
		(end 223.60001 -10.623042)
		(width 0.1651)
		(layer "B.Cu")
		(net "M_B_DQ<19>")
	)
	(segment
		(start 223.952562 -12.32535)
		(end 223.599756 -12.678156)
		(width 0.14224)
		(layer "In4.Cu")
		(net "M_B_DQ<19>")
	)
	(segment
		(start 237.420658 -46.556168)
		(end 240.503964 -49.639474)
		(width 0.0889)
		(layer "In4.Cu")
		(net "M_B_DQ<19>")
	)
	(segment
		(start 223.06661 -7.403084)
		(end 223.06661 -7.7216)
		(width 0.14224)
		(layer "In4.Cu")
		(net "M_B_DQ<19>")
	)
	(segment
		(start 223.95434 -21.823172)
		(end 224.13214 -22.000972)
		(width 0.14224)
		(layer "In4.Cu")
		(net "M_B_DQ<19>")
	)
	(segment
		(start 224.10674 -17.031462)
		(end 224.10674 -18.412714)
		(width 0.14224)
		(layer "In4.Cu")
		(net "M_B_DQ<19>")
	)
	(segment
		(start 224.825306 -29.915866)
		(end 226.537774 -29.915866)
		(width 0.14224)
		(layer "In4.Cu")
		(net "M_B_DQ<19>")
	)
	(segment
		(start 224.10801 -8.8646)
		(end 223.952562 -9.020048)
		(width 0.14224)
		(layer "In4.Cu")
		(net "M_B_DQ<19>")
	)
	(segment
		(start 224.10674 -18.412714)
		(end 223.95434 -18.565114)
		(width 0.14224)
		(layer "In4.Cu")
		(net "M_B_DQ<19>")
	)
	(segment
		(start 234.2896 -42.782236)
		(end 237.420658 -45.913294)
		(width 0.14224)
		(layer "In4.Cu")
		(net "M_B_DQ<19>")
	)
	(segment
		(start 222.749872 -7.086346)
		(end 223.06661 -7.403084)
		(width 0.14224)
		(layer "In4.Cu")
		(net "M_B_DQ<19>")
	)
	(segment
		(start 223.96704 -14.419072)
		(end 223.96704 -16.891762)
		(width 0.14224)
		(layer "In4.Cu")
		(net "M_B_DQ<19>")
	)
	(segment
		(start 224.13214 -22.000972)
		(end 224.13214 -23.118572)
		(width 0.14224)
		(layer "In4.Cu")
		(net "M_B_DQ<19>")
	)
	(segment
		(start 224.13214 -23.118572)
		(end 223.96704 -23.283672)
		(width 0.14224)
		(layer "In4.Cu")
		(net "M_B_DQ<19>")
	)
	(segment
		(start 227.510594 -29.915866)
		(end 227.934266 -29.915866)
		(width 0.14224)
		(layer "In4.Cu")
		(net "M_B_DQ<19>")
	)
	(segment
		(start 239.969802 -52.710588)
		(end 239.904778 -52.775612)
		(width 0.0889)
		(layer "In4.Cu")
		(net "M_B_DQ<19>")
	)
	(segment
		(start 223.95434 -18.565114)
		(end 223.95434 -21.823172)
		(width 0.14224)
		(layer "In4.Cu")
		(net "M_B_DQ<19>")
	)
	(segment
		(start 240.416588 -50.837338)
		(end 240.422938 -50.848006)
		(width 0.0889)
		(layer "In4.Cu")
		(net "M_B_DQ<19>")
	)
	(segment
		(start 234.2896 -36.2712)
		(end 234.2896 -42.782236)
		(width 0.14224)
		(layer "In4.Cu")
		(net "M_B_DQ<19>")
	)
	(segment
		(start 223.11614 -13.568172)
		(end 223.96704 -14.419072)
		(width 0.14224)
		(layer "In4.Cu")
		(net "M_B_DQ<19>")
	)
	(segment
		(start 226.692714 -30.65526)
		(end 226.847654 -30.8102)
		(width 0.14224)
		(layer "In4.Cu")
		(net "M_B_DQ<19>")
	)
	(segment
		(start 223.96704 -29.0576)
		(end 224.825306 -29.915866)
		(width 0.14224)
		(layer "In4.Cu")
		(net "M_B_DQ<19>")
	)
	(segment
		(start 224.10801 -8.509)
		(end 224.10801 -8.8646)
		(width 0.14224)
		(layer "In4.Cu")
		(net "M_B_DQ<19>")
	)
	(segment
		(start 223.65081 -8.0518)
		(end 224.10801 -8.509)
		(width 0.14224)
		(layer "In4.Cu")
		(net "M_B_DQ<19>")
	)
	(segment
		(start 237.420658 -45.913294)
		(end 237.420658 -46.367954)
		(width 0.14224)
		(layer "In4.Cu")
		(net "M_B_DQ<19>")
	)
	(segment
		(start 226.847654 -30.8102)
		(end 227.200714 -30.8102)
		(width 0.14224)
		(layer "In4.Cu")
		(net "M_B_DQ<19>")
	)
	(segment
		(start 226.537774 -29.915866)
		(end 226.692714 -30.070806)
		(width 0.14224)
		(layer "In4.Cu")
		(net "M_B_DQ<19>")
	)
	(segment
		(start 223.11614 -13.161772)
		(end 223.11614 -13.568172)
		(width 0.14224)
		(layer "In4.Cu")
		(net "M_B_DQ<19>")
	)
	(segment
		(start 240.503964 -49.639474)
		(end 240.503964 -50.3047)
		(width 0.0889)
		(layer "In4.Cu")
		(net "M_B_DQ<19>")
	)
	(segment
		(start 223.39681 -8.0518)
		(end 223.65081 -8.0518)
		(width 0.14224)
		(layer "In4.Cu")
		(net "M_B_DQ<19>")
	)
	(segment
		(start 237.420658 -46.367954)
		(end 237.420658 -46.556168)
		(width 0.0889)
		(layer "In4.Cu")
		(net "M_B_DQ<19>")
	)
	(segment
		(start 227.934266 -29.915866)
		(end 234.2896 -36.2712)
		(width 0.14224)
		(layer "In4.Cu")
		(net "M_B_DQ<19>")
	)
	(segment
		(start 227.355654 -30.65526)
		(end 227.355654 -30.070806)
		(width 0.14224)
		(layer "In4.Cu")
		(net "M_B_DQ<19>")
	)
	(segment
		(start 223.599756 -12.678156)
		(end 223.11614 -13.161772)
		(width 0.14224)
		(layer "In4.Cu")
		(net "M_B_DQ<19>")
	)
	(segment
		(start 223.952562 -9.020048)
		(end 223.952562 -12.32535)
		(width 0.14224)
		(layer "In4.Cu")
		(net "M_B_DQ<19>")
	)
	(segment
		(start 239.904778 -52.775612)
		(end 239.904778 -53.113686)
		(width 0.0889)
		(layer "In4.Cu")
		(net "M_B_DQ<19>")
	)
	(segment
		(start 226.692714 -30.070806)
		(end 226.692714 -30.65526)
		(width 0.14224)
		(layer "In4.Cu")
		(net "M_B_DQ<19>")
	)
	(segment
		(start 223.96704 -23.283672)
		(end 223.96704 -29.0576)
		(width 0.14224)
		(layer "In4.Cu")
		(net "M_B_DQ<19>")
	)
	(segment
		(start 227.355654 -30.070806)
		(end 227.510594 -29.915866)
		(width 0.14224)
		(layer "In4.Cu")
		(net "M_B_DQ<19>")
	)
	(segment
		(start 223.06661 -7.7216)
		(end 223.39681 -8.0518)
		(width 0.14224)
		(layer "In4.Cu")
		(net "M_B_DQ<19>")
	)
	(segment
		(start 240.411762 -50.828702)
		(end 240.416588 -50.837338)
		(width 0.0889)
		(layer "In4.Cu")
		(net "M_B_DQ<19>")
	)
	(segment
		(start 240.503964 -50.3047)
		(end 240.429542 -50.416968)
		(width 0.0889)
		(layer "In4.Cu")
		(net "M_B_DQ<19>")
	)
	(segment
		(start 223.96704 -16.891762)
		(end 224.10674 -17.031462)
		(width 0.14224)
		(layer "In4.Cu")
		(net "M_B_DQ<19>")
	)
	(segment
		(start 227.200714 -30.8102)
		(end 227.355654 -30.65526)
		(width 0.14224)
		(layer "In4.Cu")
		(net "M_B_DQ<19>")
	)
	(segment
		(start 240.411762 -51.819302)
		(end 240.416588 -51.827938)
		(width 0.0889)
		(layer "In4.Cu")
		(net "M_B_DQ<19>")
	)
	(arc
		(start 240.416588 -51.427888)
		(mid 240.363118 -51.622951)
		(end 240.411762 -51.819302)
		(width 0.0889)
		(layer "In4.Cu")
		(net "M_B_DQ<19>")
	)
	(arc
		(start 240.429542 -50.416968)
		(mid 240.363406 -50.620377)
		(end 240.411762 -50.828702)
		(width 0.0889)
		(layer "In4.Cu")
		(net "M_B_DQ<19>")
	)
	(arc
		(start 240.416588 -51.827938)
		(mid 240.432036 -52.390193)
		(end 239.969802 -52.710588)
		(width 0.0889)
		(layer "In4.Cu")
		(net "M_B_DQ<19>")
	)
	(arc
		(start 240.422938 -50.848006)
		(mid 240.495736 -51.138769)
		(end 240.416588 -51.427888)
		(width 0.0889)
		(layer "In4.Cu")
		(net "M_B_DQ<19>")
	)
	(segment
		(start 223.731328 -9.29386)
		(end 223.731328 -9.07034)
		(width 0.1651)
		(layer "F.Cu")
		(net "M_B_DQ<18>")
	)
	(segment
		(start 240.476278 -52.12334)
		(end 239.904778 -52.12334)
		(width 0.1016)
		(layer "F.Cu")
		(net "M_B_DQ<18>")
	)
	(segment
		(start 223.599756 -8.938768)
		(end 223.599756 -8.6614)
		(width 0.1651)
		(layer "F.Cu")
		(net "M_B_DQ<18>")
	)
	(segment
		(start 223.600518 -9.42467)
		(end 223.731328 -9.29386)
		(width 0.1651)
		(layer "F.Cu")
		(net "M_B_DQ<18>")
	)
	(segment
		(start 223.731328 -9.07034)
		(end 223.599756 -8.938768)
		(width 0.1651)
		(layer "F.Cu")
		(net "M_B_DQ<18>")
	)
	(segment
		(start 223.600518 -10.422382)
		(end 223.600518 -9.42467)
		(width 0.1651)
		(layer "F.Cu")
		(net "M_B_DQ<18>")
	)
	(via
		(at 239.904778 -52.12334)
		(size 0.508)
		(drill 0.254)
		(layers "F.Cu" "B.Cu")
		(net "M_B_DQ<18>")
	)
	(via
		(at 223.599756 -8.6614)
		(size 0.508)
		(drill 0.254)
		(layers "F.Cu" "B.Cu")
		(net "M_B_DQ<18>")
	)
	(via
		(at 222.749872 -13.959078)
		(size 0.508)
		(drill 0.254)
		(layers "F.Cu" "B.Cu")
		(net "M_B_DQ<18>")
	)
	(segment
		(start 222.75038 -13.959586)
		(end 222.749872 -13.959078)
		(width 0.1651)
		(layer "B.Cu")
		(net "M_B_DQ<18>")
	)
	(segment
		(start 222.75038 -15.222982)
		(end 222.75038 -13.959586)
		(width 0.1651)
		(layer "B.Cu")
		(net "M_B_DQ<18>")
	)
	(segment
		(start 236.98835 -46.835568)
		(end 237.430818 -46.835568)
		(width 0.0889)
		(layer "In4.Cu")
		(net "M_B_DQ<18>")
	)
	(segment
		(start 240.251488 -50.932588)
		(end 240.256314 -50.941224)
		(width 0.0889)
		(layer "In4.Cu")
		(net "M_B_DQ<18>")
	)
	(segment
		(start 223.31934 -14.836394)
		(end 223.31934 -16.764762)
		(width 0.14224)
		(layer "In4.Cu")
		(net "M_B_DQ<18>")
	)
	(segment
		(start 223.33204 -29.320744)
		(end 225.405696 -31.3944)
		(width 0.14224)
		(layer "In4.Cu")
		(net "M_B_DQ<18>")
	)
	(segment
		(start 230.551482 -33.59023)
		(end 230.77043 -33.59023)
		(width 0.14224)
		(layer "In4.Cu")
		(net "M_B_DQ<18>")
	)
	(segment
		(start 239.904778 -52.461414)
		(end 239.904778 -52.12334)
		(width 0.0889)
		(layer "In4.Cu")
		(net "M_B_DQ<18>")
	)
	(segment
		(start 228.5746 -31.3944)
		(end 229.14483 -31.96463)
		(width 0.14224)
		(layer "In4.Cu")
		(net "M_B_DQ<18>")
	)
	(segment
		(start 223.31934 -16.764762)
		(end 223.11614 -16.967962)
		(width 0.14224)
		(layer "In4.Cu")
		(net "M_B_DQ<18>")
	)
	(segment
		(start 229.613714 -32.652462)
		(end 229.832662 -32.652462)
		(width 0.14224)
		(layer "In4.Cu")
		(net "M_B_DQ<18>")
	)
	(segment
		(start 231.238298 -34.77895)
		(end 231.48925 -34.527998)
		(width 0.14224)
		(layer "In4.Cu")
		(net "M_B_DQ<18>")
	)
	(segment
		(start 230.081582 -33.841182)
		(end 230.30053 -33.841182)
		(width 0.14224)
		(layer "In4.Cu")
		(net "M_B_DQ<18>")
	)
	(segment
		(start 229.831646 -33.591246)
		(end 230.081582 -33.841182)
		(width 0.14224)
		(layer "In4.Cu")
		(net "M_B_DQ<18>")
	)
	(segment
		(start 223.24314 -18.570194)
		(end 223.24314 -21.797772)
		(width 0.14224)
		(layer "In4.Cu")
		(net "M_B_DQ<18>")
	)
	(segment
		(start 222.749872 -13.959078)
		(end 222.749872 -14.266926)
		(width 0.14224)
		(layer "In4.Cu")
		(net "M_B_DQ<18>")
	)
	(segment
		(start 229.14483 -32.183578)
		(end 228.973888 -32.35452)
		(width 0.14224)
		(layer "In4.Cu")
		(net "M_B_DQ<18>")
	)
	(segment
		(start 237.430818 -46.835568)
		(end 240.313464 -49.718214)
		(width 0.0889)
		(layer "In4.Cu")
		(net "M_B_DQ<18>")
	)
	(segment
		(start 222.856806 -10.95375)
		(end 222.856806 -11.3538)
		(width 0.14224)
		(layer "In4.Cu")
		(net "M_B_DQ<18>")
	)
	(segment
		(start 233.426 -36.2458)
		(end 233.426 -42.81678)
		(width 0.14224)
		(layer "In4.Cu")
		(net "M_B_DQ<18>")
	)
	(segment
		(start 223.201738 -9.364472)
		(end 222.856806 -9.709404)
		(width 0.14224)
		(layer "In4.Cu")
		(net "M_B_DQ<18>")
	)
	(segment
		(start 223.24314 -21.797772)
		(end 223.09074 -21.950172)
		(width 0.14224)
		(layer "In4.Cu")
		(net "M_B_DQ<18>")
	)
	(segment
		(start 223.314006 -12.079732)
		(end 222.465138 -12.9286)
		(width 0.14224)
		(layer "In4.Cu")
		(net "M_B_DQ<18>")
	)
	(segment
		(start 222.856806 -9.709404)
		(end 222.856806 -10.058146)
		(width 0.14224)
		(layer "In4.Cu")
		(net "M_B_DQ<18>")
	)
	(segment
		(start 240.313464 -49.718214)
		(end 240.313464 -50.225198)
		(width 0.0889)
		(layer "In4.Cu")
		(net "M_B_DQ<18>")
	)
	(segment
		(start 223.314006 -11.811)
		(end 223.314006 -12.079732)
		(width 0.14224)
		(layer "In4.Cu")
		(net "M_B_DQ<18>")
	)
	(segment
		(start 223.11614 -18.443194)
		(end 223.24314 -18.570194)
		(width 0.14224)
		(layer "In4.Cu")
		(net "M_B_DQ<18>")
	)
	(segment
		(start 223.201738 -9.059418)
		(end 223.201738 -9.364472)
		(width 0.14224)
		(layer "In4.Cu")
		(net "M_B_DQ<18>")
	)
	(segment
		(start 228.973888 -32.35452)
		(end 228.973888 -32.555688)
		(width 0.14224)
		(layer "In4.Cu")
		(net "M_B_DQ<18>")
	)
	(segment
		(start 240.313464 -50.225198)
		(end 240.251488 -50.342038)
		(width 0.0889)
		(layer "In4.Cu")
		(net "M_B_DQ<18>")
	)
	(segment
		(start 228.973888 -32.555688)
		(end 229.241604 -32.823404)
		(width 0.14224)
		(layer "In4.Cu")
		(net "M_B_DQ<18>")
	)
	(segment
		(start 236.6137 -46.460918)
		(end 236.98835 -46.835568)
		(width 0.14224)
		(layer "In4.Cu")
		(net "M_B_DQ<18>")
	)
	(segment
		(start 222.465138 -12.9286)
		(end 222.465138 -13.674344)
		(width 0.14224)
		(layer "In4.Cu")
		(net "M_B_DQ<18>")
	)
	(segment
		(start 230.082598 -32.902398)
		(end 230.082598 -33.121346)
		(width 0.14224)
		(layer "In4.Cu")
		(net "M_B_DQ<18>")
	)
	(segment
		(start 230.30053 -33.841182)
		(end 230.551482 -33.59023)
		(width 0.14224)
		(layer "In4.Cu")
		(net "M_B_DQ<18>")
	)
	(segment
		(start 231.01935 -34.77895)
		(end 231.238298 -34.77895)
		(width 0.14224)
		(layer "In4.Cu")
		(net "M_B_DQ<18>")
	)
	(segment
		(start 229.14483 -31.96463)
		(end 229.14483 -32.183578)
		(width 0.14224)
		(layer "In4.Cu")
		(net "M_B_DQ<18>")
	)
	(segment
		(start 230.77043 -33.59023)
		(end 231.020366 -33.840166)
		(width 0.14224)
		(layer "In4.Cu")
		(net "M_B_DQ<18>")
	)
	(segment
		(start 229.241604 -32.823404)
		(end 229.442772 -32.823404)
		(width 0.14224)
		(layer "In4.Cu")
		(net "M_B_DQ<18>")
	)
	(segment
		(start 230.082598 -33.121346)
		(end 229.831646 -33.372298)
		(width 0.14224)
		(layer "In4.Cu")
		(net "M_B_DQ<18>")
	)
	(segment
		(start 223.33204 -23.385272)
		(end 223.33204 -29.320744)
		(width 0.14224)
		(layer "In4.Cu")
		(net "M_B_DQ<18>")
	)
	(segment
		(start 223.161606 -10.362946)
		(end 223.161606 -10.64895)
		(width 0.14224)
		(layer "In4.Cu")
		(net "M_B_DQ<18>")
	)
	(segment
		(start 230.769414 -34.310066)
		(end 230.769414 -34.529014)
		(width 0.14224)
		(layer "In4.Cu")
		(net "M_B_DQ<18>")
	)
	(segment
		(start 225.405696 -31.3944)
		(end 228.5746 -31.3944)
		(width 0.14224)
		(layer "In4.Cu")
		(net "M_B_DQ<18>")
	)
	(segment
		(start 222.856806 -10.058146)
		(end 223.161606 -10.362946)
		(width 0.14224)
		(layer "In4.Cu")
		(net "M_B_DQ<18>")
	)
	(segment
		(start 240.245138 -50.92192)
		(end 240.251488 -50.932588)
		(width 0.0889)
		(layer "In4.Cu")
		(net "M_B_DQ<18>")
	)
	(segment
		(start 222.856806 -11.3538)
		(end 223.314006 -11.811)
		(width 0.14224)
		(layer "In4.Cu")
		(net "M_B_DQ<18>")
	)
	(segment
		(start 223.09074 -21.950172)
		(end 223.09074 -23.143972)
		(width 0.14224)
		(layer "In4.Cu")
		(net "M_B_DQ<18>")
	)
	(segment
		(start 236.6137 -46.00448)
		(end 236.6137 -46.460918)
		(width 0.14224)
		(layer "In4.Cu")
		(net "M_B_DQ<18>")
	)
	(segment
		(start 229.832662 -32.652462)
		(end 230.082598 -32.902398)
		(width 0.14224)
		(layer "In4.Cu")
		(net "M_B_DQ<18>")
	)
	(segment
		(start 233.426 -42.81678)
		(end 236.6137 -46.00448)
		(width 0.14224)
		(layer "In4.Cu")
		(net "M_B_DQ<18>")
	)
	(segment
		(start 222.749872 -14.266926)
		(end 223.31934 -14.836394)
		(width 0.14224)
		(layer "In4.Cu")
		(net "M_B_DQ<18>")
	)
	(segment
		(start 223.161606 -10.64895)
		(end 222.856806 -10.95375)
		(width 0.14224)
		(layer "In4.Cu")
		(net "M_B_DQ<18>")
	)
	(segment
		(start 229.831646 -33.372298)
		(end 229.831646 -33.591246)
		(width 0.14224)
		(layer "In4.Cu")
		(net "M_B_DQ<18>")
	)
	(segment
		(start 223.11614 -16.967962)
		(end 223.11614 -18.443194)
		(width 0.14224)
		(layer "In4.Cu")
		(net "M_B_DQ<18>")
	)
	(segment
		(start 223.09074 -23.143972)
		(end 223.33204 -23.385272)
		(width 0.14224)
		(layer "In4.Cu")
		(net "M_B_DQ<18>")
	)
	(segment
		(start 239.96269 -52.519326)
		(end 239.904778 -52.461414)
		(width 0.0889)
		(layer "In4.Cu")
		(net "M_B_DQ<18>")
	)
	(segment
		(start 231.020366 -33.840166)
		(end 231.020366 -34.059114)
		(width 0.14224)
		(layer "In4.Cu")
		(net "M_B_DQ<18>")
	)
	(segment
		(start 230.769414 -34.529014)
		(end 231.01935 -34.77895)
		(width 0.14224)
		(layer "In4.Cu")
		(net "M_B_DQ<18>")
	)
	(segment
		(start 222.465138 -13.674344)
		(end 222.749872 -13.959078)
		(width 0.14224)
		(layer "In4.Cu")
		(net "M_B_DQ<18>")
	)
	(segment
		(start 223.599756 -8.6614)
		(end 223.201738 -9.059418)
		(width 0.14224)
		(layer "In4.Cu")
		(net "M_B_DQ<18>")
	)
	(segment
		(start 231.48925 -34.527998)
		(end 231.708198 -34.527998)
		(width 0.14224)
		(layer "In4.Cu")
		(net "M_B_DQ<18>")
	)
	(segment
		(start 231.708198 -34.527998)
		(end 233.426 -36.2458)
		(width 0.14224)
		(layer "In4.Cu")
		(net "M_B_DQ<18>")
	)
	(segment
		(start 229.442772 -32.823404)
		(end 229.613714 -32.652462)
		(width 0.14224)
		(layer "In4.Cu")
		(net "M_B_DQ<18>")
	)
	(segment
		(start 231.020366 -34.059114)
		(end 230.769414 -34.310066)
		(width 0.14224)
		(layer "In4.Cu")
		(net "M_B_DQ<18>")
	)
	(arc
		(start 240.251488 -51.923442)
		(mid 240.26492 -52.297881)
		(end 239.96269 -52.519326)
		(width 0.0889)
		(layer "In4.Cu")
		(net "M_B_DQ<18>")
	)
	(arc
		(start 240.251488 -50.342038)
		(mid 240.172266 -50.631156)
		(end 240.245138 -50.92192)
		(width 0.0889)
		(layer "In4.Cu")
		(net "M_B_DQ<18>")
	)
	(arc
		(start 240.251488 -51.332638)
		(mid 240.172357 -51.62804)
		(end 240.251488 -51.923442)
		(width 0.0889)
		(layer "In4.Cu")
		(net "M_B_DQ<18>")
	)
	(arc
		(start 240.256314 -50.941224)
		(mid 240.305069 -51.137576)
		(end 240.251488 -51.332638)
		(width 0.0889)
		(layer "In4.Cu")
		(net "M_B_DQ<18>")
	)
	(segment
		(start 216.799922 -5.822442)
		(end 216.799922 -7.086346)
		(width 0.1651)
		(layer "F.Cu")
		(net "M_B_DQ<17>")
	)
	(segment
		(start 216.80043 -5.822442)
		(end 216.799922 -5.822442)
		(width 0.1651)
		(layer "F.Cu")
		(net "M_B_DQ<17>")
	)
	(segment
		(start 237.900718 -53.60924)
		(end 237.329218 -53.60924)
		(width 0.1016)
		(layer "F.Cu")
		(net "M_B_DQ<17>")
	)
	(via
		(at 237.329218 -53.60924)
		(size 0.508)
		(drill 0.254)
		(layers "F.Cu" "B.Cu")
		(net "M_B_DQ<17>")
	)
	(via
		(at 217.472006 -12.678156)
		(size 0.508)
		(drill 0.254)
		(layers "F.Cu" "B.Cu")
		(net "M_B_DQ<17>")
	)
	(via
		(at 216.799922 -7.086346)
		(size 0.508)
		(drill 0.254)
		(layers "F.Cu" "B.Cu")
		(net "M_B_DQ<17>")
	)
	(segment
		(start 217.649806 -10.623042)
		(end 217.649806 -11.997182)
		(width 0.1651)
		(layer "B.Cu")
		(net "M_B_DQ<17>")
	)
	(segment
		(start 217.650314 -10.623042)
		(end 217.649806 -10.623042)
		(width 0.1651)
		(layer "B.Cu")
		(net "M_B_DQ<17>")
	)
	(segment
		(start 217.649806 -11.997182)
		(end 217.472006 -12.174982)
		(width 0.1651)
		(layer "B.Cu")
		(net "M_B_DQ<17>")
	)
	(segment
		(start 217.472006 -12.174982)
		(end 217.472006 -12.678156)
		(width 0.1651)
		(layer "B.Cu")
		(net "M_B_DQ<17>")
	)
	(segment
		(start 237.329218 -53.60924)
		(end 236.999272 -52.84724)
		(width 0.0889)
		(layer "In4.Cu")
		(net "M_B_DQ<17>")
	)
	(segment
		(start 216.945464 -13.204698)
		(end 217.472006 -12.678156)
		(width 0.14224)
		(layer "In4.Cu")
		(net "M_B_DQ<17>")
	)
	(segment
		(start 217.632788 -8.1026)
		(end 217.277188 -8.1026)
		(width 0.14224)
		(layer "In4.Cu")
		(net "M_B_DQ<17>")
	)
	(segment
		(start 216.945464 -13.491464)
		(end 216.945464 -13.204698)
		(width 0.14224)
		(layer "In4.Cu")
		(net "M_B_DQ<17>")
	)
	(segment
		(start 217.32494 -15.64894)
		(end 217.32494 -13.87094)
		(width 0.14224)
		(layer "In4.Cu")
		(net "M_B_DQ<17>")
	)
	(segment
		(start 231.686608 -46.539658)
		(end 228.4984 -43.35145)
		(width 0.14224)
		(layer "In4.Cu")
		(net "M_B_DQ<17>")
	)
	(segment
		(start 217.846148 -12.304014)
		(end 217.846148 -8.970264)
		(width 0.14224)
		(layer "In4.Cu")
		(net "M_B_DQ<17>")
	)
	(segment
		(start 217.472006 -12.678156)
		(end 217.846148 -12.304014)
		(width 0.14224)
		(layer "In4.Cu")
		(net "M_B_DQ<17>")
	)
	(segment
		(start 218.2368 -29.451046)
		(end 218.2368 -26.099516)
		(width 0.14224)
		(layer "In4.Cu")
		(net "M_B_DQ<17>")
	)
	(segment
		(start 237.675928 -51.827938)
		(end 237.680754 -51.819302)
		(width 0.0889)
		(layer "In4.Cu")
		(net "M_B_DQ<17>")
	)
	(segment
		(start 237.632494 -51.903376)
		(end 237.675928 -51.827938)
		(width 0.0889)
		(layer "In4.Cu")
		(net "M_B_DQ<17>")
	)
	(segment
		(start 233.156252 -49.022762)
		(end 231.686608 -47.553118)
		(width 0.0889)
		(layer "In4.Cu")
		(net "M_B_DQ<17>")
	)
	(segment
		(start 236.485684 -50.73269)
		(end 236.455712 -50.73269)
		(width 0.0889)
		(layer "In4.Cu")
		(net "M_B_DQ<17>")
	)
	(segment
		(start 237.571026 -51.951382)
		(end 237.632494 -51.903376)
		(width 0.0889)
		(layer "In4.Cu")
		(net "M_B_DQ<17>")
	)
	(segment
		(start 216.799922 -7.625334)
		(end 216.799922 -7.086346)
		(width 0.14224)
		(layer "In4.Cu")
		(net "M_B_DQ<17>")
	)
	(segment
		(start 231.686608 -47.553118)
		(end 231.686608 -47.269146)
		(width 0.0889)
		(layer "In4.Cu")
		(net "M_B_DQ<17>")
	)
	(segment
		(start 217.846148 -8.970264)
		(end 218.002612 -8.8138)
		(width 0.14224)
		(layer "In4.Cu")
		(net "M_B_DQ<17>")
	)
	(segment
		(start 217.4875 -25.350216)
		(end 217.4875 -24.791416)
		(width 0.14224)
		(layer "In4.Cu")
		(net "M_B_DQ<17>")
	)
	(segment
		(start 237.085632 -52.300886)
		(end 237.571026 -51.951382)
		(width 0.0889)
		(layer "In4.Cu")
		(net "M_B_DQ<17>")
	)
	(segment
		(start 217.277188 -8.1026)
		(end 216.799922 -7.625334)
		(width 0.14224)
		(layer "In4.Cu")
		(net "M_B_DQ<17>")
	)
	(segment
		(start 237.349792 -51.228244)
		(end 237.311438 -51.228244)
		(width 0.0889)
		(layer "In4.Cu")
		(net "M_B_DQ<17>")
	)
	(segment
		(start 235.265468 -50.837338)
		(end 235.11256 -50.57394)
		(width 0.0889)
		(layer "In4.Cu")
		(net "M_B_DQ<17>")
	)
	(segment
		(start 217.4875 -24.791416)
		(end 217.95994 -24.318976)
		(width 0.14224)
		(layer "In4.Cu")
		(net "M_B_DQ<17>")
	)
	(segment
		(start 217.32494 -13.87094)
		(end 216.945464 -13.491464)
		(width 0.14224)
		(layer "In4.Cu")
		(net "M_B_DQ<17>")
	)
	(segment
		(start 217.95994 -24.318976)
		(end 217.95994 -16.28394)
		(width 0.14224)
		(layer "In4.Cu")
		(net "M_B_DQ<17>")
	)
	(segment
		(start 236.999272 -52.84724)
		(end 236.982508 -52.818284)
		(width 0.0889)
		(layer "In4.Cu")
		(net "M_B_DQ<17>")
	)
	(segment
		(start 217.95994 -16.28394)
		(end 217.32494 -15.64894)
		(width 0.14224)
		(layer "In4.Cu")
		(net "M_B_DQ<17>")
	)
	(segment
		(start 223.703896 -35.92195)
		(end 223.703896 -34.918142)
		(width 0.14224)
		(layer "In4.Cu")
		(net "M_B_DQ<17>")
	)
	(segment
		(start 218.2368 -26.099516)
		(end 217.4875 -25.350216)
		(width 0.14224)
		(layer "In4.Cu")
		(net "M_B_DQ<17>")
	)
	(segment
		(start 223.703896 -34.918142)
		(end 218.2368 -29.451046)
		(width 0.14224)
		(layer "In4.Cu")
		(net "M_B_DQ<17>")
	)
	(segment
		(start 231.686608 -47.269146)
		(end 231.686608 -46.539658)
		(width 0.14224)
		(layer "In4.Cu")
		(net "M_B_DQ<17>")
	)
	(segment
		(start 235.11256 -50.57394)
		(end 233.561128 -49.022762)
		(width 0.0889)
		(layer "In4.Cu")
		(net "M_B_DQ<17>")
	)
	(segment
		(start 233.561128 -49.022762)
		(end 233.156252 -49.022762)
		(width 0.0889)
		(layer "In4.Cu")
		(net "M_B_DQ<17>")
	)
	(segment
		(start 218.002612 -8.472424)
		(end 217.632788 -8.1026)
		(width 0.14224)
		(layer "In4.Cu")
		(net "M_B_DQ<17>")
	)
	(segment
		(start 218.002612 -8.8138)
		(end 218.002612 -8.472424)
		(width 0.14224)
		(layer "In4.Cu")
		(net "M_B_DQ<17>")
	)
	(segment
		(start 228.4984 -43.35145)
		(end 228.4984 -40.716454)
		(width 0.14224)
		(layer "In4.Cu")
		(net "M_B_DQ<17>")
	)
	(segment
		(start 236.231938 -50.81143)
		(end 235.700824 -51.03749)
		(width 0.0889)
		(layer "In4.Cu")
		(net "M_B_DQ<17>")
	)
	(segment
		(start 228.4984 -40.716454)
		(end 223.703896 -35.92195)
		(width 0.14224)
		(layer "In4.Cu")
		(net "M_B_DQ<17>")
	)
	(segment
		(start 235.700824 -51.03749)
		(end 235.597192 -51.03749)
		(width 0.0889)
		(layer "In4.Cu")
		(net "M_B_DQ<17>")
	)
	(arc
		(start 235.597192 -51.03749)
		(mid 235.405488 -50.980244)
		(end 235.265468 -50.837338)
		(width 0.0889)
		(layer "In4.Cu")
		(net "M_B_DQ<17>")
	)
	(arc
		(start 236.982508 -52.818284)
		(mid 236.929009 -52.618386)
		(end 236.982508 -52.418488)
		(width 0.0889)
		(layer "In4.Cu")
		(net "M_B_DQ<17>")
	)
	(arc
		(start 237.311438 -51.228244)
		(mid 237.026014 -51.144777)
		(end 236.817408 -50.932842)
		(width 0.0889)
		(layer "In4.Cu")
		(net "M_B_DQ<17>")
	)
	(arc
		(start 237.680754 -51.819302)
		(mid 237.729509 -51.62295)
		(end 237.675928 -51.427888)
		(width 0.0889)
		(layer "In4.Cu")
		(net "M_B_DQ<17>")
	)
	(arc
		(start 236.455712 -50.73269)
		(mid 236.337861 -50.755106)
		(end 236.231938 -50.81143)
		(width 0.0889)
		(layer "In4.Cu")
		(net "M_B_DQ<17>")
	)
	(arc
		(start 237.675928 -51.427888)
		(mid 237.538239 -51.286604)
		(end 237.349792 -51.228244)
		(width 0.0889)
		(layer "In4.Cu")
		(net "M_B_DQ<17>")
	)
	(arc
		(start 236.817408 -50.932842)
		(mid 236.67739 -50.789931)
		(end 236.485684 -50.73269)
		(width 0.0889)
		(layer "In4.Cu")
		(net "M_B_DQ<17>")
	)
	(arc
		(start 236.982508 -52.418488)
		(mid 237.028257 -52.354588)
		(end 237.085632 -52.300886)
		(width 0.0889)
		(layer "In4.Cu")
		(net "M_B_DQ<17>")
	)
	(segment
		(start 217.650314 -10.422382)
		(end 217.649806 -10.422382)
		(width 0.1651)
		(layer "F.Cu")
		(net "M_B_DQ<16>")
	)
	(segment
		(start 217.649806 -10.422382)
		(end 217.49131 -8.763)
		(width 0.1651)
		(layer "F.Cu")
		(net "M_B_DQ<16>")
	)
	(segment
		(start 237.900718 -51.62804)
		(end 237.329218 -51.62804)
		(width 0.1016)
		(layer "F.Cu")
		(net "M_B_DQ<16>")
	)
	(segment
		(start 217.49131 -8.763)
		(end 217.472006 -8.5598)
		(width 0.1651)
		(layer "F.Cu")
		(net "M_B_DQ<16>")
	)
	(via
		(at 237.329218 -51.62804)
		(size 0.508)
		(drill 0.254)
		(layers "F.Cu" "B.Cu")
		(net "M_B_DQ<16>")
	)
	(via
		(at 217.472006 -8.5598)
		(size 0.508)
		(drill 0.254)
		(layers "F.Cu" "B.Cu")
		(net "M_B_DQ<16>")
	)
	(via
		(at 216.799922 -13.959078)
		(size 0.508)
		(drill 0.254)
		(layers "F.Cu" "B.Cu")
		(net "M_B_DQ<16>")
	)
	(segment
		(start 216.799922 -15.222982)
		(end 216.799922 -13.959078)
		(width 0.1651)
		(layer "B.Cu")
		(net "M_B_DQ<16>")
	)
	(segment
		(start 216.80043 -15.222982)
		(end 216.799922 -15.222982)
		(width 0.1651)
		(layer "B.Cu")
		(net "M_B_DQ<16>")
	)
	(segment
		(start 220.71838 -33.938972)
		(end 220.937328 -33.938972)
		(width 0.14224)
		(layer "In4.Cu")
		(net "M_B_DQ<16>")
	)
	(segment
		(start 220.577156 -32.64281)
		(end 220.827092 -32.892746)
		(width 0.14224)
		(layer "In4.Cu")
		(net "M_B_DQ<16>")
	)
	(segment
		(start 216.862406 -10.9982)
		(end 216.862406 -11.302746)
		(width 0.14224)
		(layer "In4.Cu")
		(net "M_B_DQ<16>")
	)
	(segment
		(start 220.468444 -33.470088)
		(end 220.468444 -33.689036)
		(width 0.14224)
		(layer "In4.Cu")
		(net "M_B_DQ<16>")
	)
	(segment
		(start 233.482388 -49.212754)
		(end 234.960414 -50.69078)
		(width 0.0889)
		(layer "In4.Cu")
		(net "M_B_DQ<16>")
	)
	(segment
		(start 233.077258 -49.213008)
		(end 233.48188 -49.213008)
		(width 0.0889)
		(layer "In4.Cu")
		(net "M_B_DQ<16>")
	)
	(segment
		(start 220.827092 -32.892746)
		(end 220.827092 -33.111694)
		(width 0.14224)
		(layer "In4.Cu")
		(net "M_B_DQ<16>")
	)
	(segment
		(start 217.678 -26.679144)
		(end 217.678 -29.743654)
		(width 0.14224)
		(layer "In4.Cu")
		(net "M_B_DQ<16>")
	)
	(segment
		(start 230.9749 -46.726094)
		(end 230.9749 -47.450248)
		(width 0.14224)
		(layer "In4.Cu")
		(net "M_B_DQ<16>")
	)
	(segment
		(start 217.251788 -8.780018)
		(end 217.251788 -9.364472)
		(width 0.14224)
		(layer "In4.Cu")
		(net "M_B_DQ<16>")
	)
	(segment
		(start 216.98204 -18.302986)
		(end 217.32494 -18.645886)
		(width 0.14224)
		(layer "In4.Cu")
		(net "M_B_DQ<16>")
	)
	(segment
		(start 221.524068 -34.491168)
		(end 221.791784 -34.758884)
		(width 0.14224)
		(layer "In4.Cu")
		(net "M_B_DQ<16>")
	)
	(segment
		(start 220.468444 -33.689036)
		(end 220.71838 -33.938972)
		(width 0.14224)
		(layer "In4.Cu")
		(net "M_B_DQ<16>")
	)
	(segment
		(start 216.799922 -15.962122)
		(end 217.27414 -16.43634)
		(width 0.14224)
		(layer "In4.Cu")
		(net "M_B_DQ<16>")
	)
	(segment
		(start 235.594398 -51.228244)
		(end 235.751624 -51.228244)
		(width 0.0889)
		(layer "In4.Cu")
		(net "M_B_DQ<16>")
	)
	(segment
		(start 220.357954 -32.64281)
		(end 220.577156 -32.64281)
		(width 0.14224)
		(layer "In4.Cu")
		(net "M_B_DQ<16>")
	)
	(segment
		(start 222.924624 -36.040822)
		(end 227.8634 -40.979598)
		(width 0.14224)
		(layer "In4.Cu")
		(net "M_B_DQ<16>")
	)
	(segment
		(start 221.992952 -34.758884)
		(end 222.23349 -34.518346)
		(width 0.14224)
		(layer "In4.Cu")
		(net "M_B_DQ<16>")
	)
	(segment
		(start 233.482134 -49.212754)
		(end 233.482388 -49.212754)
		(width 0.0889)
		(layer "In4.Cu")
		(net "M_B_DQ<16>")
	)
	(segment
		(start 217.179906 -10.6807)
		(end 216.862406 -10.9982)
		(width 0.14224)
		(layer "In4.Cu")
		(net "M_B_DQ<16>")
	)
	(segment
		(start 221.514924 -33.580578)
		(end 221.76486 -33.830514)
		(width 0.14224)
		(layer "In4.Cu")
		(net "M_B_DQ<16>")
	)
	(segment
		(start 216.837006 -9.779254)
		(end 216.837006 -10.1092)
		(width 0.14224)
		(layer "In4.Cu")
		(net "M_B_DQ<16>")
	)
	(segment
		(start 217.297 -23.4188)
		(end 217.297 -23.8506)
		(width 0.14224)
		(layer "In4.Cu")
		(net "M_B_DQ<16>")
	)
	(segment
		(start 216.98204 -23.10384)
		(end 217.297 -23.4188)
		(width 0.14224)
		(layer "In4.Cu")
		(net "M_B_DQ<16>")
	)
	(segment
		(start 219.889324 -32.173672)
		(end 219.644214 -32.418782)
		(width 0.14224)
		(layer "In4.Cu")
		(net "M_B_DQ<16>")
	)
	(segment
		(start 230.9749 -47.450248)
		(end 231.240076 -47.715424)
		(width 0.14224)
		(layer "In4.Cu")
		(net "M_B_DQ<16>")
	)
	(segment
		(start 219.933266 -32.887666)
		(end 220.113098 -32.887666)
		(width 0.14224)
		(layer "In4.Cu")
		(net "M_B_DQ<16>")
	)
	(segment
		(start 221.524068 -34.29)
		(end 221.524068 -34.491168)
		(width 0.14224)
		(layer "In4.Cu")
		(net "M_B_DQ<16>")
	)
	(segment
		(start 236.505242 -51.532536)
		(end 237.329218 -51.62804)
		(width 0.0889)
		(layer "In4.Cu")
		(net "M_B_DQ<16>")
	)
	(segment
		(start 219.644214 -32.418782)
		(end 219.644214 -32.598614)
		(width 0.14224)
		(layer "In4.Cu")
		(net "M_B_DQ<16>")
	)
	(segment
		(start 221.295976 -33.580578)
		(end 221.514924 -33.580578)
		(width 0.14224)
		(layer "In4.Cu")
		(net "M_B_DQ<16>")
	)
	(segment
		(start 216.74074 -24.40686)
		(end 216.74074 -25.741884)
		(width 0.14224)
		(layer "In4.Cu")
		(net "M_B_DQ<16>")
	)
	(segment
		(start 217.179906 -10.4521)
		(end 217.179906 -10.6807)
		(width 0.14224)
		(layer "In4.Cu")
		(net "M_B_DQ<16>")
	)
	(segment
		(start 217.251788 -9.364472)
		(end 216.837006 -9.779254)
		(width 0.14224)
		(layer "In4.Cu")
		(net "M_B_DQ<16>")
	)
	(segment
		(start 219.889324 -31.954978)
		(end 219.889324 -32.173672)
		(width 0.14224)
		(layer "In4.Cu")
		(net "M_B_DQ<16>")
	)
	(segment
		(start 216.515188 -12.9286)
		(end 216.515188 -13.674344)
		(width 0.14224)
		(layer "In4.Cu")
		(net "M_B_DQ<16>")
	)
	(segment
		(start 216.799922 -13.959078)
		(end 216.799922 -15.962122)
		(width 0.14224)
		(layer "In4.Cu")
		(net "M_B_DQ<16>")
	)
	(segment
		(start 221.791784 -34.758884)
		(end 221.992952 -34.758884)
		(width 0.14224)
		(layer "In4.Cu")
		(net "M_B_DQ<16>")
	)
	(segment
		(start 219.644214 -32.598614)
		(end 219.933266 -32.887666)
		(width 0.14224)
		(layer "In4.Cu")
		(net "M_B_DQ<16>")
	)
	(segment
		(start 222.452692 -34.518346)
		(end 222.924624 -34.990278)
		(width 0.14224)
		(layer "In4.Cu")
		(net "M_B_DQ<16>")
	)
	(segment
		(start 231.240076 -47.715424)
		(end 231.579674 -47.715424)
		(width 0.0889)
		(layer "In4.Cu")
		(net "M_B_DQ<16>")
	)
	(segment
		(start 236.455712 -51.532536)
		(end 236.505242 -51.532536)
		(width 0.0889)
		(layer "In4.Cu")
		(net "M_B_DQ<16>")
	)
	(segment
		(start 216.98204 -22.026372)
		(end 216.98204 -23.10384)
		(width 0.14224)
		(layer "In4.Cu")
		(net "M_B_DQ<16>")
	)
	(segment
		(start 227.8634 -40.979598)
		(end 227.8634 -43.614594)
		(width 0.14224)
		(layer "In4.Cu")
		(net "M_B_DQ<16>")
	)
	(segment
		(start 216.74074 -25.741884)
		(end 217.678 -26.679144)
		(width 0.14224)
		(layer "In4.Cu")
		(net "M_B_DQ<16>")
	)
	(segment
		(start 217.297 -23.8506)
		(end 216.74074 -24.40686)
		(width 0.14224)
		(layer "In4.Cu")
		(net "M_B_DQ<16>")
	)
	(segment
		(start 216.837006 -10.1092)
		(end 217.179906 -10.4521)
		(width 0.14224)
		(layer "In4.Cu")
		(net "M_B_DQ<16>")
	)
	(segment
		(start 221.76486 -34.049208)
		(end 221.524068 -34.29)
		(width 0.14224)
		(layer "In4.Cu")
		(net "M_B_DQ<16>")
	)
	(segment
		(start 220.827092 -33.111694)
		(end 220.468444 -33.470088)
		(width 0.14224)
		(layer "In4.Cu")
		(net "M_B_DQ<16>")
	)
	(segment
		(start 217.27414 -16.831818)
		(end 216.98204 -17.123918)
		(width 0.14224)
		(layer "In4.Cu")
		(net "M_B_DQ<16>")
	)
	(segment
		(start 221.76486 -33.830514)
		(end 221.76486 -34.049208)
		(width 0.14224)
		(layer "In4.Cu")
		(net "M_B_DQ<16>")
	)
	(segment
		(start 217.251788 -12.192)
		(end 216.515188 -12.9286)
		(width 0.14224)
		(layer "In4.Cu")
		(net "M_B_DQ<16>")
	)
	(segment
		(start 217.472006 -8.5598)
		(end 217.251788 -8.780018)
		(width 0.14224)
		(layer "In4.Cu")
		(net "M_B_DQ<16>")
	)
	(segment
		(start 220.113098 -32.887666)
		(end 220.357954 -32.64281)
		(width 0.14224)
		(layer "In4.Cu")
		(net "M_B_DQ<16>")
	)
	(segment
		(start 217.32494 -18.645886)
		(end 217.32494 -21.683472)
		(width 0.14224)
		(layer "In4.Cu")
		(net "M_B_DQ<16>")
	)
	(segment
		(start 231.579674 -47.715424)
		(end 233.077258 -49.213008)
		(width 0.0889)
		(layer "In4.Cu")
		(net "M_B_DQ<16>")
	)
	(segment
		(start 217.678 -29.743654)
		(end 219.889324 -31.954978)
		(width 0.14224)
		(layer "In4.Cu")
		(net "M_B_DQ<16>")
	)
	(segment
		(start 217.251788 -11.692128)
		(end 217.251788 -12.192)
		(width 0.14224)
		(layer "In4.Cu")
		(net "M_B_DQ<16>")
	)
	(segment
		(start 234.960414 -50.69078)
		(end 235.100368 -50.932842)
		(width 0.0889)
		(layer "In4.Cu")
		(net "M_B_DQ<16>")
	)
	(segment
		(start 216.515188 -13.674344)
		(end 216.799922 -13.959078)
		(width 0.14224)
		(layer "In4.Cu")
		(net "M_B_DQ<16>")
	)
	(segment
		(start 216.862406 -11.302746)
		(end 217.251788 -11.692128)
		(width 0.14224)
		(layer "In4.Cu")
		(net "M_B_DQ<16>")
	)
	(segment
		(start 217.32494 -21.683472)
		(end 216.98204 -22.026372)
		(width 0.14224)
		(layer "In4.Cu")
		(net "M_B_DQ<16>")
	)
	(segment
		(start 227.8634 -43.614594)
		(end 230.9749 -46.726094)
		(width 0.14224)
		(layer "In4.Cu")
		(net "M_B_DQ<16>")
	)
	(segment
		(start 233.48188 -49.213008)
		(end 233.482134 -49.212754)
		(width 0.0889)
		(layer "In4.Cu")
		(net "M_B_DQ<16>")
	)
	(segment
		(start 222.23349 -34.518346)
		(end 222.452692 -34.518346)
		(width 0.14224)
		(layer "In4.Cu")
		(net "M_B_DQ<16>")
	)
	(segment
		(start 222.924624 -34.990278)
		(end 222.924624 -36.040822)
		(width 0.14224)
		(layer "In4.Cu")
		(net "M_B_DQ<16>")
	)
	(segment
		(start 216.98204 -17.123918)
		(end 216.98204 -18.302986)
		(width 0.14224)
		(layer "In4.Cu")
		(net "M_B_DQ<16>")
	)
	(segment
		(start 220.937328 -33.938972)
		(end 221.295976 -33.580578)
		(width 0.14224)
		(layer "In4.Cu")
		(net "M_B_DQ<16>")
	)
	(segment
		(start 217.27414 -16.43634)
		(end 217.27414 -16.831818)
		(width 0.14224)
		(layer "In4.Cu")
		(net "M_B_DQ<16>")
	)
	(arc
		(start 235.100368 -50.932842)
		(mid 235.308976 -51.144774)
		(end 235.594398 -51.228244)
		(width 0.0889)
		(layer "In4.Cu")
		(net "M_B_DQ<16>")
	)
	(arc
		(start 235.751624 -51.228244)
		(mid 236.002287 -51.314829)
		(end 236.229398 -51.451764)
		(width 0.0889)
		(layer "In4.Cu")
		(net "M_B_DQ<16>")
	)
	(arc
		(start 236.229398 -51.451764)
		(mid 236.33635 -51.509539)
		(end 236.455712 -51.532536)
		(width 0.0889)
		(layer "In4.Cu")
		(net "M_B_DQ<16>")
	)
	(segment
		(start 237.900718 -60.54344)
		(end 237.329218 -60.54344)
		(width 0.1016)
		(layer "F.Cu")
		(net "M_B_DQ<15>")
	)
	(segment
		(start 211.699856 -5.822442)
		(end 211.699856 -7.086346)
		(width 0.1651)
		(layer "F.Cu")
		(net "M_B_DQ<15>")
	)
	(segment
		(start 211.700364 -5.822442)
		(end 211.699856 -5.822442)
		(width 0.1651)
		(layer "F.Cu")
		(net "M_B_DQ<15>")
	)
	(via
		(at 237.329218 -60.54344)
		(size 0.508)
		(drill 0.254)
		(layers "F.Cu" "B.Cu")
		(net "M_B_DQ<15>")
	)
	(via
		(at 212.54974 -12.678156)
		(size 0.508)
		(drill 0.254)
		(layers "F.Cu" "B.Cu")
		(net "M_B_DQ<15>")
	)
	(via
		(at 211.699856 -7.086346)
		(size 0.508)
		(drill 0.254)
		(layers "F.Cu" "B.Cu")
		(net "M_B_DQ<15>")
	)
	(segment
		(start 212.549994 -10.780522)
		(end 212.54974 -10.780776)
		(width 0.1651)
		(layer "B.Cu")
		(net "M_B_DQ<15>")
	)
	(segment
		(start 212.550502 -10.623042)
		(end 212.549994 -10.623042)
		(width 0.1651)
		(layer "B.Cu")
		(net "M_B_DQ<15>")
	)
	(segment
		(start 212.54974 -10.780776)
		(end 212.54974 -12.678156)
		(width 0.1651)
		(layer "B.Cu")
		(net "M_B_DQ<15>")
	)
	(segment
		(start 212.549994 -10.623042)
		(end 212.549994 -10.780522)
		(width 0.1651)
		(layer "B.Cu")
		(net "M_B_DQ<15>")
	)
	(segment
		(start 223.450912 -43.698668)
		(end 223.450912 -43.47972)
		(width 0.14224)
		(layer "In4.Cu")
		(net "M_B_DQ<15>")
	)
	(segment
		(start 234.771438 -55.494936)
		(end 234.464606 -55.494936)
		(width 0.0889)
		(layer "In4.Cu")
		(net "M_B_DQ<15>")
	)
	(segment
		(start 212.7504 -30.8229)
		(end 212.7504 -23.748746)
		(width 0.14224)
		(layer "In4.Cu")
		(net "M_B_DQ<15>")
	)
	(segment
		(start 212.600794 -8.0518)
		(end 212.346794 -8.0518)
		(width 0.14224)
		(layer "In4.Cu")
		(net "M_B_DQ<15>")
	)
	(segment
		(start 213.105746 -21.975572)
		(end 212.902546 -21.772372)
		(width 0.14224)
		(layer "In4.Cu")
		(net "M_B_DQ<15>")
	)
	(segment
		(start 212.210396 -14.136878)
		(end 212.210396 -13.75283)
		(width 0.14224)
		(layer "In4.Cu")
		(net "M_B_DQ<15>")
	)
	(segment
		(start 218.786456 -38.159944)
		(end 218.786456 -36.858956)
		(width 0.14224)
		(layer "In4.Cu")
		(net "M_B_DQ<15>")
	)
	(segment
		(start 212.346794 -8.0518)
		(end 212.016594 -7.7216)
		(width 0.14224)
		(layer "In4.Cu")
		(net "M_B_DQ<15>")
	)
	(segment
		(start 222.513144 -42.541952)
		(end 222.263208 -42.292016)
		(width 0.14224)
		(layer "In4.Cu")
		(net "M_B_DQ<15>")
	)
	(segment
		(start 237.329218 -60.54344)
		(end 237.329218 -60.543186)
		(width 0.0889)
		(layer "In4.Cu")
		(net "M_B_DQ<15>")
	)
	(segment
		(start 222.92691 -44.441364)
		(end 222.92691 -44.222416)
		(width 0.14224)
		(layer "In4.Cu")
		(net "M_B_DQ<15>")
	)
	(segment
		(start 223.395794 -44.6913)
		(end 223.176846 -44.6913)
		(width 0.14224)
		(layer "In4.Cu")
		(net "M_B_DQ<15>")
	)
	(segment
		(start 222.263208 -42.292016)
		(end 222.04426 -42.292016)
		(width 0.14224)
		(layer "In4.Cu")
		(net "M_B_DQ<15>")
	)
	(segment
		(start 221.646242 -41.01973)
		(end 218.786456 -38.159944)
		(width 0.14224)
		(layer "In4.Cu")
		(net "M_B_DQ<15>")
	)
	(segment
		(start 213.131146 -17.082262)
		(end 212.851746 -16.802862)
		(width 0.14224)
		(layer "In4.Cu")
		(net "M_B_DQ<15>")
	)
	(segment
		(start 220.876114 -42.077386)
		(end 221.646242 -41.307258)
		(width 0.14224)
		(layer "In4.Cu")
		(net "M_B_DQ<15>")
	)
	(segment
		(start 212.089746 -13.13815)
		(end 212.54974 -12.678156)
		(width 0.14224)
		(layer "In4.Cu")
		(net "M_B_DQ<15>")
	)
	(segment
		(start 234.242864 -55.273194)
		(end 233.75874 -55.273194)
		(width 0.14224)
		(layer "In4.Cu")
		(net "M_B_DQ<15>")
	)
	(segment
		(start 222.92691 -44.222416)
		(end 223.450912 -43.698668)
		(width 0.14224)
		(layer "In4.Cu")
		(net "M_B_DQ<15>")
	)
	(segment
		(start 223.864678 -45.160184)
		(end 224.38868 -44.636436)
		(width 0.14224)
		(layer "In4.Cu")
		(net "M_B_DQ<15>")
	)
	(segment
		(start 222.04426 -42.292016)
		(end 221.520258 -42.815764)
		(width 0.14224)
		(layer "In4.Cu")
		(net "M_B_DQ<15>")
	)
	(segment
		(start 212.927946 -23.5712)
		(end 212.927946 -23.296372)
		(width 0.14224)
		(layer "In4.Cu")
		(net "M_B_DQ<15>")
	)
	(segment
		(start 213.057994 -8.8646)
		(end 213.057994 -8.509)
		(width 0.14224)
		(layer "In4.Cu")
		(net "M_B_DQ<15>")
	)
	(segment
		(start 212.089746 -13.63218)
		(end 212.089746 -13.13815)
		(width 0.14224)
		(layer "In4.Cu")
		(net "M_B_DQ<15>")
	)
	(segment
		(start 223.450912 -43.47972)
		(end 223.200976 -43.229784)
		(width 0.14224)
		(layer "In4.Cu")
		(net "M_B_DQ<15>")
	)
	(segment
		(start 224.38868 -44.636436)
		(end 224.38868 -44.417488)
		(width 0.14224)
		(layer "In4.Cu")
		(net "M_B_DQ<15>")
	)
	(segment
		(start 236.342936 -60.543186)
		(end 235.942886 -60.943236)
		(width 0.0889)
		(layer "In4.Cu")
		(net "M_B_DQ<15>")
	)
	(segment
		(start 212.902546 -18.567654)
		(end 213.131146 -18.339054)
		(width 0.14224)
		(layer "In4.Cu")
		(net "M_B_DQ<15>")
	)
	(segment
		(start 212.210396 -13.75283)
		(end 212.089746 -13.63218)
		(width 0.14224)
		(layer "In4.Cu")
		(net "M_B_DQ<15>")
	)
	(segment
		(start 233.75874 -55.273194)
		(end 223.864678 -45.379132)
		(width 0.14224)
		(layer "In4.Cu")
		(net "M_B_DQ<15>")
	)
	(segment
		(start 222.458026 -43.753532)
		(end 222.239078 -43.753532)
		(width 0.14224)
		(layer "In4.Cu")
		(net "M_B_DQ<15>")
	)
	(segment
		(start 222.239078 -43.753532)
		(end 221.989142 -43.503596)
		(width 0.14224)
		(layer "In4.Cu")
		(net "M_B_DQ<15>")
	)
	(segment
		(start 224.38868 -44.417488)
		(end 224.138744 -44.167552)
		(width 0.14224)
		(layer "In4.Cu")
		(net "M_B_DQ<15>")
	)
	(segment
		(start 212.902546 -12.32535)
		(end 212.902546 -9.020048)
		(width 0.14224)
		(layer "In4.Cu")
		(net "M_B_DQ<15>")
	)
	(segment
		(start 212.54974 -12.678156)
		(end 212.902546 -12.32535)
		(width 0.14224)
		(layer "In4.Cu")
		(net "M_B_DQ<15>")
	)
	(segment
		(start 218.786456 -36.858956)
		(end 212.7504 -30.8229)
		(width 0.14224)
		(layer "In4.Cu")
		(net "M_B_DQ<15>")
	)
	(segment
		(start 234.464606 -55.494936)
		(end 234.242864 -55.273194)
		(width 0.0889)
		(layer "In4.Cu")
		(net "M_B_DQ<15>")
	)
	(segment
		(start 235.942886 -60.943236)
		(end 235.601002 -60.943236)
		(width 0.0889)
		(layer "In4.Cu")
		(net "M_B_DQ<15>")
	)
	(segment
		(start 237.329218 -60.543186)
		(end 236.342936 -60.543186)
		(width 0.0889)
		(layer "In4.Cu")
		(net "M_B_DQ<15>")
	)
	(segment
		(start 224.138744 -44.167552)
		(end 223.919796 -44.167552)
		(width 0.14224)
		(layer "In4.Cu")
		(net "M_B_DQ<15>")
	)
	(segment
		(start 221.30131 -42.815764)
		(end 220.876114 -42.390568)
		(width 0.14224)
		(layer "In4.Cu")
		(net "M_B_DQ<15>")
	)
	(segment
		(start 212.016594 -7.403084)
		(end 211.699856 -7.086346)
		(width 0.14224)
		(layer "In4.Cu")
		(net "M_B_DQ<15>")
	)
	(segment
		(start 220.876114 -42.390568)
		(end 220.876114 -42.077386)
		(width 0.14224)
		(layer "In4.Cu")
		(net "M_B_DQ<15>")
	)
	(segment
		(start 212.927946 -23.296372)
		(end 213.105746 -23.118572)
		(width 0.14224)
		(layer "In4.Cu")
		(net "M_B_DQ<15>")
	)
	(segment
		(start 222.513144 -42.7609)
		(end 222.513144 -42.541952)
		(width 0.14224)
		(layer "In4.Cu")
		(net "M_B_DQ<15>")
	)
	(segment
		(start 222.396812 -42.877232)
		(end 222.513144 -42.7609)
		(width 0.14224)
		(layer "In4.Cu")
		(net "M_B_DQ<15>")
	)
	(segment
		(start 212.851746 -14.778228)
		(end 212.210396 -14.136878)
		(width 0.14224)
		(layer "In4.Cu")
		(net "M_B_DQ<15>")
	)
	(segment
		(start 212.016594 -7.7216)
		(end 212.016594 -7.403084)
		(width 0.14224)
		(layer "In4.Cu")
		(net "M_B_DQ<15>")
	)
	(segment
		(start 213.057994 -8.509)
		(end 212.600794 -8.0518)
		(width 0.14224)
		(layer "In4.Cu")
		(net "M_B_DQ<15>")
	)
	(segment
		(start 213.105746 -23.118572)
		(end 213.105746 -21.975572)
		(width 0.14224)
		(layer "In4.Cu")
		(net "M_B_DQ<15>")
	)
	(segment
		(start 221.646242 -41.307258)
		(end 221.646242 -41.01973)
		(width 0.14224)
		(layer "In4.Cu")
		(net "M_B_DQ<15>")
	)
	(segment
		(start 212.902546 -9.020048)
		(end 213.057994 -8.8646)
		(width 0.14224)
		(layer "In4.Cu")
		(net "M_B_DQ<15>")
	)
	(segment
		(start 213.131146 -18.339054)
		(end 213.131146 -17.082262)
		(width 0.14224)
		(layer "In4.Cu")
		(net "M_B_DQ<15>")
	)
	(segment
		(start 222.982028 -43.229784)
		(end 222.458026 -43.753532)
		(width 0.14224)
		(layer "In4.Cu")
		(net "M_B_DQ<15>")
	)
	(segment
		(start 223.200976 -43.229784)
		(end 222.982028 -43.229784)
		(width 0.14224)
		(layer "In4.Cu")
		(net "M_B_DQ<15>")
	)
	(segment
		(start 223.176846 -44.6913)
		(end 222.92691 -44.441364)
		(width 0.14224)
		(layer "In4.Cu")
		(net "M_B_DQ<15>")
	)
	(segment
		(start 221.989142 -43.503596)
		(end 221.989142 -43.284648)
		(width 0.14224)
		(layer "In4.Cu")
		(net "M_B_DQ<15>")
	)
	(segment
		(start 223.919796 -44.167552)
		(end 223.510094 -44.577)
		(width 0.14224)
		(layer "In4.Cu")
		(net "M_B_DQ<15>")
	)
	(segment
		(start 235.271818 -55.801006)
		(end 235.265468 -55.790338)
		(width 0.0889)
		(layer "In4.Cu")
		(net "M_B_DQ<15>")
	)
	(segment
		(start 223.864678 -45.379132)
		(end 223.864678 -45.160184)
		(width 0.14224)
		(layer "In4.Cu")
		(net "M_B_DQ<15>")
	)
	(segment
		(start 212.7504 -23.748746)
		(end 212.927946 -23.5712)
		(width 0.14224)
		(layer "In4.Cu")
		(net "M_B_DQ<15>")
	)
	(segment
		(start 212.902546 -21.772372)
		(end 212.902546 -18.567654)
		(width 0.14224)
		(layer "In4.Cu")
		(net "M_B_DQ<15>")
	)
	(segment
		(start 212.851746 -16.802862)
		(end 212.851746 -14.778228)
		(width 0.14224)
		(layer "In4.Cu")
		(net "M_B_DQ<15>")
	)
	(segment
		(start 221.520258 -42.815764)
		(end 221.30131 -42.815764)
		(width 0.14224)
		(layer "In4.Cu")
		(net "M_B_DQ<15>")
	)
	(segment
		(start 221.989142 -43.284648)
		(end 222.396812 -42.877232)
		(width 0.14224)
		(layer "In4.Cu")
		(net "M_B_DQ<15>")
	)
	(segment
		(start 223.510094 -44.577)
		(end 223.395794 -44.6913)
		(width 0.14224)
		(layer "In4.Cu")
		(net "M_B_DQ<15>")
	)
	(arc
		(start 235.265468 -56.780684)
		(mid 235.211969 -56.580786)
		(end 235.265468 -56.380888)
		(width 0.0889)
		(layer "In4.Cu")
		(net "M_B_DQ<15>")
	)
	(arc
		(start 235.265468 -55.790338)
		(mid 235.248106 -55.762425)
		(end 235.229654 -55.73522)
		(width 0.0889)
		(layer "In4.Cu")
		(net "M_B_DQ<15>")
	)
	(arc
		(start 235.265468 -58.761884)
		(mid 235.211969 -58.561986)
		(end 235.265468 -58.362088)
		(width 0.0889)
		(layer "In4.Cu")
		(net "M_B_DQ<15>")
	)
	(arc
		(start 235.265468 -57.771284)
		(mid 235.211969 -57.571386)
		(end 235.265468 -57.371488)
		(width 0.0889)
		(layer "In4.Cu")
		(net "M_B_DQ<15>")
	)
	(arc
		(start 235.229654 -55.73522)
		(mid 235.028244 -55.562267)
		(end 234.771438 -55.494936)
		(width 0.0889)
		(layer "In4.Cu")
		(net "M_B_DQ<15>")
	)
	(arc
		(start 235.265468 -57.371488)
		(mid 235.344599 -57.076086)
		(end 235.265468 -56.780684)
		(width 0.0889)
		(layer "In4.Cu")
		(net "M_B_DQ<15>")
	)
	(arc
		(start 235.265468 -59.752484)
		(mid 235.211969 -59.552586)
		(end 235.265468 -59.352688)
		(width 0.0889)
		(layer "In4.Cu")
		(net "M_B_DQ<15>")
	)
	(arc
		(start 235.265468 -60.343288)
		(mid 235.344599 -60.047886)
		(end 235.265468 -59.752484)
		(width 0.0889)
		(layer "In4.Cu")
		(net "M_B_DQ<15>")
	)
	(arc
		(start 235.601002 -60.943236)
		(mid 235.262887 -60.738534)
		(end 235.265468 -60.343288)
		(width 0.0889)
		(layer "In4.Cu")
		(net "M_B_DQ<15>")
	)
	(arc
		(start 235.265468 -59.352688)
		(mid 235.344599 -59.057286)
		(end 235.265468 -58.761884)
		(width 0.0889)
		(layer "In4.Cu")
		(net "M_B_DQ<15>")
	)
	(arc
		(start 235.265468 -56.380888)
		(mid 235.34469 -56.09177)
		(end 235.271818 -55.801006)
		(width 0.0889)
		(layer "In4.Cu")
		(net "M_B_DQ<15>")
	)
	(arc
		(start 235.265468 -58.362088)
		(mid 235.344599 -58.066686)
		(end 235.265468 -57.771284)
		(width 0.0889)
		(layer "In4.Cu")
		(net "M_B_DQ<15>")
	)
	(segment
		(start 236.183678 -61.53404)
		(end 235.612178 -61.53404)
		(width 0.1016)
		(layer "F.Cu")
		(net "M_B_DQ<14>")
	)
	(segment
		(start 212.549994 -9.4488)
		(end 212.682074 -9.31672)
		(width 0.1651)
		(layer "F.Cu")
		(net "M_B_DQ<14>")
	)
	(segment
		(start 212.549994 -8.9662)
		(end 212.549994 -8.661654)
		(width 0.1651)
		(layer "F.Cu")
		(net "M_B_DQ<14>")
	)
	(segment
		(start 212.682074 -9.31672)
		(end 212.682074 -9.09828)
		(width 0.1651)
		(layer "F.Cu")
		(net "M_B_DQ<14>")
	)
	(segment
		(start 212.549994 -8.661654)
		(end 212.54974 -8.6614)
		(width 0.1651)
		(layer "F.Cu")
		(net "M_B_DQ<14>")
	)
	(segment
		(start 212.550502 -10.422382)
		(end 212.549994 -10.422382)
		(width 0.1651)
		(layer "F.Cu")
		(net "M_B_DQ<14>")
	)
	(segment
		(start 212.549994 -10.422382)
		(end 212.549994 -9.4488)
		(width 0.1651)
		(layer "F.Cu")
		(net "M_B_DQ<14>")
	)
	(segment
		(start 212.682074 -9.09828)
		(end 212.549994 -8.9662)
		(width 0.1651)
		(layer "F.Cu")
		(net "M_B_DQ<14>")
	)
	(via
		(at 211.699856 -13.959078)
		(size 0.508)
		(drill 0.254)
		(layers "F.Cu" "B.Cu")
		(net "M_B_DQ<14>")
	)
	(via
		(at 235.612178 -61.53404)
		(size 0.508)
		(drill 0.254)
		(layers "F.Cu" "B.Cu")
		(net "M_B_DQ<14>")
	)
	(via
		(at 212.54974 -8.6614)
		(size 0.508)
		(drill 0.254)
		(layers "F.Cu" "B.Cu")
		(net "M_B_DQ<14>")
	)
	(segment
		(start 211.699856 -15.222982)
		(end 211.699856 -13.959078)
		(width 0.1651)
		(layer "B.Cu")
		(net "M_B_DQ<14>")
	)
	(segment
		(start 211.700364 -15.222982)
		(end 211.699856 -15.222982)
		(width 0.1651)
		(layer "B.Cu")
		(net "M_B_DQ<14>")
	)
	(segment
		(start 211.464144 -13.723366)
		(end 211.699856 -13.959078)
		(width 0.14224)
		(layer "In4.Cu")
		(net "M_B_DQ<14>")
	)
	(segment
		(start 219.92463 -42.157142)
		(end 219.92463 -42.37609)
		(width 0.14224)
		(layer "In4.Cu")
		(net "M_B_DQ<14>")
	)
	(segment
		(start 218.049094 -40.281606)
		(end 218.049094 -40.500554)
		(width 0.14224)
		(layer "In4.Cu")
		(net "M_B_DQ<14>")
	)
	(segment
		(start 212.216746 -15.041372)
		(end 212.216746 -16.840962)
		(width 0.14224)
		(layer "In4.Cu")
		(net "M_B_DQ<14>")
	)
	(segment
		(start 219.36456 -39.903908)
		(end 219.583508 -39.903908)
		(width 0.14224)
		(layer "In4.Cu")
		(net "M_B_DQ<14>")
	)
	(segment
		(start 211.699856 -14.524482)
		(end 212.216746 -15.041372)
		(width 0.14224)
		(layer "In4.Cu")
		(net "M_B_DQ<14>")
	)
	(segment
		(start 218.895676 -39.216076)
		(end 218.895676 -39.435024)
		(width 0.14224)
		(layer "In4.Cu")
		(net "M_B_DQ<14>")
	)
	(segment
		(start 219.833444 -40.153844)
		(end 219.833444 -40.372792)
		(width 0.14224)
		(layer "In4.Cu")
		(net "M_B_DQ<14>")
	)
	(segment
		(start 212.1154 -31.2547)
		(end 217.628978 -36.768278)
		(width 0.14224)
		(layer "In4.Cu")
		(net "M_B_DQ<14>")
	)
	(segment
		(start 211.699856 -13.959078)
		(end 211.699856 -14.524482)
		(width 0.14224)
		(layer "In4.Cu")
		(net "M_B_DQ<14>")
	)
	(segment
		(start 212.236812 -12.156186)
		(end 211.464144 -12.928854)
		(width 0.14224)
		(layer "In4.Cu")
		(net "M_B_DQ<14>")
	)
	(segment
		(start 211.811362 -11.093704)
		(end 211.811362 -11.378946)
		(width 0.14224)
		(layer "In4.Cu")
		(net "M_B_DQ<14>")
	)
	(segment
		(start 212.1154 -23.875746)
		(end 212.1154 -31.2547)
		(width 0.14224)
		(layer "In4.Cu")
		(net "M_B_DQ<14>")
	)
	(segment
		(start 212.267546 -18.668746)
		(end 212.267546 -21.772372)
		(width 0.14224)
		(layer "In4.Cu")
		(net "M_B_DQ<14>")
	)
	(segment
		(start 219.833444 -40.372792)
		(end 218.986862 -41.219374)
		(width 0.14224)
		(layer "In4.Cu")
		(net "M_B_DQ<14>")
	)
	(segment
		(start 216.9414 -38.9001)
		(end 216.9414 -39.39286)
		(width 0.14224)
		(layer "In4.Cu")
		(net "M_B_DQ<14>")
	)
	(segment
		(start 217.628978 -38.212522)
		(end 216.9414 -38.9001)
		(width 0.14224)
		(layer "In4.Cu")
		(net "M_B_DQ<14>")
	)
	(segment
		(start 218.049094 -40.500554)
		(end 218.29903 -40.75049)
		(width 0.14224)
		(layer "In4.Cu")
		(net "M_B_DQ<14>")
	)
	(segment
		(start 235.612178 -61.533786)
		(end 235.612178 -61.53404)
		(width 0.0889)
		(layer "In4.Cu")
		(net "M_B_DQ<14>")
	)
	(segment
		(start 212.165946 -23.270972)
		(end 212.165946 -23.8252)
		(width 0.14224)
		(layer "In4.Cu")
		(net "M_B_DQ<14>")
	)
	(segment
		(start 217.58021 -39.812722)
		(end 218.426792 -38.96614)
		(width 0.14224)
		(layer "In4.Cu")
		(net "M_B_DQ<14>")
	)
	(segment
		(start 212.175344 -9.313672)
		(end 211.811362 -9.677654)
		(width 0.14224)
		(layer "In4.Cu")
		(net "M_B_DQ<14>")
	)
	(segment
		(start 220.521276 -40.841676)
		(end 220.771212 -41.091612)
		(width 0.14224)
		(layer "In4.Cu")
		(net "M_B_DQ<14>")
	)
	(segment
		(start 211.811362 -11.378946)
		(end 212.236812 -11.804396)
		(width 0.14224)
		(layer "In4.Cu")
		(net "M_B_DQ<14>")
	)
	(segment
		(start 212.175344 -9.035796)
		(end 212.175344 -9.313672)
		(width 0.14224)
		(layer "In4.Cu")
		(net "M_B_DQ<14>")
	)
	(segment
		(start 212.064346 -21.975572)
		(end 212.064346 -23.169372)
		(width 0.14224)
		(layer "In4.Cu")
		(net "M_B_DQ<14>")
	)
	(segment
		(start 220.771212 -41.091612)
		(end 220.771212 -41.31056)
		(width 0.14224)
		(layer "In4.Cu")
		(net "M_B_DQ<14>")
	)
	(segment
		(start 235.100368 -55.885588)
		(end 235.105194 -55.894224)
		(width 0.0889)
		(layer "In4.Cu")
		(net "M_B_DQ<14>")
	)
	(segment
		(start 218.517978 -40.75049)
		(end 219.36456 -39.903908)
		(width 0.14224)
		(layer "In4.Cu")
		(net "M_B_DQ<14>")
	)
	(segment
		(start 220.302328 -40.841676)
		(end 220.521276 -40.841676)
		(width 0.14224)
		(layer "In4.Cu")
		(net "M_B_DQ<14>")
	)
	(segment
		(start 219.236798 -41.688258)
		(end 219.455746 -41.688258)
		(width 0.14224)
		(layer "In4.Cu")
		(net "M_B_DQ<14>")
	)
	(segment
		(start 212.54974 -8.6614)
		(end 212.175344 -9.035796)
		(width 0.14224)
		(layer "In4.Cu")
		(net "M_B_DQ<14>")
	)
	(segment
		(start 234.242864 -55.908194)
		(end 234.465622 -55.685436)
		(width 0.0889)
		(layer "In4.Cu")
		(net "M_B_DQ<14>")
	)
	(segment
		(start 218.426792 -38.96614)
		(end 218.64574 -38.96614)
		(width 0.14224)
		(layer "In4.Cu")
		(net "M_B_DQ<14>")
	)
	(segment
		(start 217.361262 -39.812722)
		(end 217.58021 -39.812722)
		(width 0.14224)
		(layer "In4.Cu")
		(net "M_B_DQ<14>")
	)
	(segment
		(start 211.811362 -9.988296)
		(end 212.192362 -10.369296)
		(width 0.14224)
		(layer "In4.Cu")
		(net "M_B_DQ<14>")
	)
	(segment
		(start 212.064346 -23.169372)
		(end 212.165946 -23.270972)
		(width 0.14224)
		(layer "In4.Cu")
		(net "M_B_DQ<14>")
	)
	(segment
		(start 212.267546 -21.772372)
		(end 212.064346 -21.975572)
		(width 0.14224)
		(layer "In4.Cu")
		(net "M_B_DQ<14>")
	)
	(segment
		(start 218.64574 -38.96614)
		(end 218.895676 -39.216076)
		(width 0.14224)
		(layer "In4.Cu")
		(net "M_B_DQ<14>")
	)
	(segment
		(start 216.9414 -39.39286)
		(end 217.361262 -39.812722)
		(width 0.14224)
		(layer "In4.Cu")
		(net "M_B_DQ<14>")
	)
	(segment
		(start 212.064346 -16.993362)
		(end 212.064346 -18.465546)
		(width 0.14224)
		(layer "In4.Cu")
		(net "M_B_DQ<14>")
	)
	(segment
		(start 219.92463 -42.37609)
		(end 233.456734 -55.908194)
		(width 0.14224)
		(layer "In4.Cu")
		(net "M_B_DQ<14>")
	)
	(segment
		(start 212.216746 -16.840962)
		(end 212.064346 -16.993362)
		(width 0.14224)
		(layer "In4.Cu")
		(net "M_B_DQ<14>")
	)
	(segment
		(start 218.895676 -39.435024)
		(end 218.049094 -40.281606)
		(width 0.14224)
		(layer "In4.Cu")
		(net "M_B_DQ<14>")
	)
	(segment
		(start 219.583508 -39.903908)
		(end 219.833444 -40.153844)
		(width 0.14224)
		(layer "In4.Cu")
		(net "M_B_DQ<14>")
	)
	(segment
		(start 211.811362 -9.677654)
		(end 211.811362 -9.988296)
		(width 0.14224)
		(layer "In4.Cu")
		(net "M_B_DQ<14>")
	)
	(segment
		(start 211.464144 -12.928854)
		(end 211.464144 -13.723366)
		(width 0.14224)
		(layer "In4.Cu")
		(net "M_B_DQ<14>")
	)
	(segment
		(start 219.455746 -41.688258)
		(end 220.302328 -40.841676)
		(width 0.14224)
		(layer "In4.Cu")
		(net "M_B_DQ<14>")
	)
	(segment
		(start 212.236812 -11.804396)
		(end 212.236812 -12.156186)
		(width 0.14224)
		(layer "In4.Cu")
		(net "M_B_DQ<14>")
	)
	(segment
		(start 217.628978 -36.768278)
		(end 217.628978 -38.212522)
		(width 0.14224)
		(layer "In4.Cu")
		(net "M_B_DQ<14>")
	)
	(segment
		(start 218.29903 -40.75049)
		(end 218.517978 -40.75049)
		(width 0.14224)
		(layer "In4.Cu")
		(net "M_B_DQ<14>")
	)
	(segment
		(start 212.192362 -10.369296)
		(end 212.192362 -10.712704)
		(width 0.14224)
		(layer "In4.Cu")
		(net "M_B_DQ<14>")
	)
	(segment
		(start 218.986862 -41.438322)
		(end 219.236798 -41.688258)
		(width 0.14224)
		(layer "In4.Cu")
		(net "M_B_DQ<14>")
	)
	(segment
		(start 234.465622 -55.685436)
		(end 234.764834 -55.685436)
		(width 0.0889)
		(layer "In4.Cu")
		(net "M_B_DQ<14>")
	)
	(segment
		(start 212.192362 -10.712704)
		(end 211.811362 -11.093704)
		(width 0.14224)
		(layer "In4.Cu")
		(net "M_B_DQ<14>")
	)
	(segment
		(start 220.771212 -41.31056)
		(end 219.92463 -42.157142)
		(width 0.14224)
		(layer "In4.Cu")
		(net "M_B_DQ<14>")
	)
	(segment
		(start 212.165946 -23.8252)
		(end 212.1154 -23.875746)
		(width 0.14224)
		(layer "In4.Cu")
		(net "M_B_DQ<14>")
	)
	(segment
		(start 218.986862 -41.219374)
		(end 218.986862 -41.438322)
		(width 0.14224)
		(layer "In4.Cu")
		(net "M_B_DQ<14>")
	)
	(segment
		(start 233.456734 -55.908194)
		(end 234.242864 -55.908194)
		(width 0.14224)
		(layer "In4.Cu")
		(net "M_B_DQ<14>")
	)
	(segment
		(start 212.064346 -18.465546)
		(end 212.267546 -18.668746)
		(width 0.14224)
		(layer "In4.Cu")
		(net "M_B_DQ<14>")
	)
	(arc
		(start 235.132626 -56.21401)
		(mid 235.118233 -56.250481)
		(end 235.100368 -56.285384)
		(width 0.0889)
		(layer "In4.Cu")
		(net "M_B_DQ<14>")
	)
	(arc
		(start 235.100368 -60.838588)
		(mid 235.336926 -61.200431)
		(end 235.612178 -61.533786)
		(width 0.0889)
		(layer "In4.Cu")
		(net "M_B_DQ<14>")
	)
	(arc
		(start 235.100368 -57.866788)
		(mid 235.153867 -58.066686)
		(end 235.100368 -58.266584)
		(width 0.0889)
		(layer "In4.Cu")
		(net "M_B_DQ<14>")
	)
	(arc
		(start 235.100368 -56.876188)
		(mid 235.153867 -57.076086)
		(end 235.100368 -57.275984)
		(width 0.0889)
		(layer "In4.Cu")
		(net "M_B_DQ<14>")
	)
	(arc
		(start 235.100368 -60.247784)
		(mid 235.021237 -60.543186)
		(end 235.100368 -60.838588)
		(width 0.0889)
		(layer "In4.Cu")
		(net "M_B_DQ<14>")
	)
	(arc
		(start 235.100368 -59.257184)
		(mid 235.021237 -59.552586)
		(end 235.100368 -59.847988)
		(width 0.0889)
		(layer "In4.Cu")
		(net "M_B_DQ<14>")
	)
	(arc
		(start 235.100368 -58.266584)
		(mid 235.021237 -58.561986)
		(end 235.100368 -58.857388)
		(width 0.0889)
		(layer "In4.Cu")
		(net "M_B_DQ<14>")
	)
	(arc
		(start 235.100368 -57.275984)
		(mid 235.021237 -57.571386)
		(end 235.100368 -57.866788)
		(width 0.0889)
		(layer "In4.Cu")
		(net "M_B_DQ<14>")
	)
	(arc
		(start 235.067856 -55.837836)
		(mid 235.08517 -55.860992)
		(end 235.100368 -55.885588)
		(width 0.0889)
		(layer "In4.Cu")
		(net "M_B_DQ<14>")
	)
	(arc
		(start 234.764834 -55.685436)
		(mid 234.933271 -55.727969)
		(end 235.067856 -55.837836)
		(width 0.0889)
		(layer "In4.Cu")
		(net "M_B_DQ<14>")
	)
	(arc
		(start 235.100368 -59.847988)
		(mid 235.153867 -60.047886)
		(end 235.100368 -60.247784)
		(width 0.0889)
		(layer "In4.Cu")
		(net "M_B_DQ<14>")
	)
	(arc
		(start 235.105194 -55.894224)
		(mid 235.152389 -56.051248)
		(end 235.132626 -56.21401)
		(width 0.0889)
		(layer "In4.Cu")
		(net "M_B_DQ<14>")
	)
	(arc
		(start 235.100368 -56.285384)
		(mid 235.021237 -56.580786)
		(end 235.100368 -56.876188)
		(width 0.0889)
		(layer "In4.Cu")
		(net "M_B_DQ<14>")
	)
	(arc
		(start 235.100368 -58.857388)
		(mid 235.153867 -59.057286)
		(end 235.100368 -59.257184)
		(width 0.0889)
		(layer "In4.Cu")
		(net "M_B_DQ<14>")
	)
	(segment
		(start 205.750414 -5.822442)
		(end 205.749906 -5.822442)
		(width 0.1651)
		(layer "F.Cu")
		(net "M_B_DQ<13>")
	)
	(segment
		(start 238.759238 -63.019686)
		(end 238.187738 -63.019686)
		(width 0.1016)
		(layer "F.Cu")
		(net "M_B_DQ<13>")
	)
	(segment
		(start 205.749906 -5.822442)
		(end 205.749906 -7.086346)
		(width 0.1651)
		(layer "F.Cu")
		(net "M_B_DQ<13>")
	)
	(via
		(at 206.52359 -12.678156)
		(size 0.508)
		(drill 0.254)
		(layers "F.Cu" "B.Cu")
		(net "M_B_DQ<13>")
	)
	(via
		(at 238.187738 -63.019686)
		(size 0.508)
		(drill 0.254)
		(layers "F.Cu" "B.Cu")
		(net "M_B_DQ<13>")
	)
	(via
		(at 205.749906 -7.086346)
		(size 0.508)
		(drill 0.254)
		(layers "F.Cu" "B.Cu")
		(net "M_B_DQ<13>")
	)
	(segment
		(start 206.59979 -12.601956)
		(end 206.52359 -12.678156)
		(width 0.1651)
		(layer "B.Cu")
		(net "M_B_DQ<13>")
	)
	(segment
		(start 206.59979 -10.623042)
		(end 206.59979 -12.601956)
		(width 0.1651)
		(layer "B.Cu")
		(net "M_B_DQ<13>")
	)
	(segment
		(start 206.600298 -10.623042)
		(end 206.59979 -10.623042)
		(width 0.1651)
		(layer "B.Cu")
		(net "M_B_DQ<13>")
	)
	(segment
		(start 236.459522 -63.610236)
		(end 236.492288 -63.610236)
		(width 0.0889)
		(layer "In4.Cu")
		(net "M_B_DQ<13>")
	)
	(segment
		(start 205.749906 -7.086346)
		(end 205.749906 -7.481062)
		(width 0.14224)
		(layer "In4.Cu")
		(net "M_B_DQ<13>")
	)
	(segment
		(start 208.28 -27.9781)
		(end 208.28 -36.213288)
		(width 0.14224)
		(layer "In4.Cu")
		(net "M_B_DQ<13>")
	)
	(segment
		(start 233.021632 -63.419736)
		(end 233.054398 -63.419736)
		(width 0.0889)
		(layer "In4.Cu")
		(net "M_B_DQ<13>")
	)
	(segment
		(start 237.314232 -63.11519)
		(end 237.365286 -63.11519)
		(width 0.0889)
		(layer "In4.Cu")
		(net "M_B_DQ<13>")
	)
	(segment
		(start 206.98079 -23.691088)
		(end 207.583024 -24.761952)
		(width 0.14224)
		(layer "In4.Cu")
		(net "M_B_DQ<13>")
	)
	(segment
		(start 206.05369 -13.577316)
		(end 206.51216 -14.035786)
		(width 0.14224)
		(layer "In4.Cu")
		(net "M_B_DQ<13>")
	)
	(segment
		(start 206.98079 -21.946616)
		(end 206.98079 -23.691088)
		(width 0.14224)
		(layer "In4.Cu")
		(net "M_B_DQ<13>")
	)
	(segment
		(start 231.414574 -60.320936)
		(end 231.414574 -60.659264)
		(width 0.0889)
		(layer "In4.Cu")
		(net "M_B_DQ<13>")
	)
	(segment
		(start 206.05369 -13.148056)
		(end 206.05369 -13.577316)
		(width 0.14224)
		(layer "In4.Cu")
		(net "M_B_DQ<13>")
	)
	(segment
		(start 207.031844 -8.8646)
		(end 206.834994 -9.06145)
		(width 0.14224)
		(layer "In4.Cu")
		(net "M_B_DQ<13>")
	)
	(segment
		(start 206.834994 -9.06145)
		(end 206.834994 -12.366752)
		(width 0.14224)
		(layer "In4.Cu")
		(net "M_B_DQ<13>")
	)
	(segment
		(start 207.583024 -24.761952)
		(end 207.583024 -27.281124)
		(width 0.14224)
		(layer "In4.Cu")
		(net "M_B_DQ<13>")
	)
	(segment
		(start 231.164638 -60.071)
		(end 231.414574 -60.320936)
		(width 0.14224)
		(layer "In4.Cu")
		(net "M_B_DQ<13>")
	)
	(segment
		(start 235.597192 -64.10579)
		(end 235.629958 -64.10579)
		(width 0.0889)
		(layer "In4.Cu")
		(net "M_B_DQ<13>")
	)
	(segment
		(start 230.969312 -60.071)
		(end 231.164638 -60.071)
		(width 0.14224)
		(layer "In4.Cu")
		(net "M_B_DQ<13>")
	)
	(segment
		(start 237.365286 -63.11519)
		(end 238.187738 -63.019686)
		(width 0.0889)
		(layer "In4.Cu")
		(net "M_B_DQ<13>")
	)
	(segment
		(start 227.9523 -55.885588)
		(end 227.9523 -57.053988)
		(width 0.14224)
		(layer "In4.Cu")
		(net "M_B_DQ<13>")
	)
	(segment
		(start 206.958946 -16.306546)
		(end 206.958946 -18.542762)
		(width 0.14224)
		(layer "In4.Cu")
		(net "M_B_DQ<13>")
	)
	(segment
		(start 206.63154 -8.0518)
		(end 207.031844 -8.452104)
		(width 0.14224)
		(layer "In4.Cu")
		(net "M_B_DQ<13>")
	)
	(segment
		(start 235.072174 -64.337438)
		(end 235.364274 -64.191642)
		(width 0.0889)
		(layer "In4.Cu")
		(net "M_B_DQ<13>")
	)
	(segment
		(start 233.883962 -63.91529)
		(end 233.916728 -63.91529)
		(width 0.0889)
		(layer "In4.Cu")
		(net "M_B_DQ<13>")
	)
	(segment
		(start 205.749906 -7.481062)
		(end 206.320644 -8.0518)
		(width 0.14224)
		(layer "In4.Cu")
		(net "M_B_DQ<13>")
	)
	(segment
		(start 208.28 -36.213288)
		(end 227.9523 -55.885588)
		(width 0.14224)
		(layer "In4.Cu")
		(net "M_B_DQ<13>")
	)
	(segment
		(start 206.954628 -18.54708)
		(end 206.954628 -21.920454)
		(width 0.14224)
		(layer "In4.Cu")
		(net "M_B_DQ<13>")
	)
	(segment
		(start 206.52359 -12.678156)
		(end 206.05369 -13.148056)
		(width 0.14224)
		(layer "In4.Cu")
		(net "M_B_DQ<13>")
	)
	(segment
		(start 206.958946 -18.542762)
		(end 206.954628 -18.54708)
		(width 0.14224)
		(layer "In4.Cu")
		(net "M_B_DQ<13>")
	)
	(segment
		(start 206.834994 -12.366752)
		(end 206.52359 -12.678156)
		(width 0.14224)
		(layer "In4.Cu")
		(net "M_B_DQ<13>")
	)
	(segment
		(start 227.9523 -57.053988)
		(end 230.969312 -60.071)
		(width 0.14224)
		(layer "In4.Cu")
		(net "M_B_DQ<13>")
	)
	(segment
		(start 231.680004 -60.924694)
		(end 231.680004 -62.740794)
		(width 0.0889)
		(layer "In4.Cu")
		(net "M_B_DQ<13>")
	)
	(segment
		(start 234.738672 -64.410336)
		(end 234.849924 -64.410336)
		(width 0.0889)
		(layer "In4.Cu")
		(net "M_B_DQ<13>")
	)
	(segment
		(start 207.583024 -27.281124)
		(end 208.28 -27.9781)
		(width 0.14224)
		(layer "In4.Cu")
		(net "M_B_DQ<13>")
	)
	(segment
		(start 207.031844 -8.452104)
		(end 207.031844 -8.8646)
		(width 0.14224)
		(layer "In4.Cu")
		(net "M_B_DQ<13>")
	)
	(segment
		(start 206.51216 -14.035786)
		(end 206.958946 -16.306546)
		(width 0.14224)
		(layer "In4.Cu")
		(net "M_B_DQ<13>")
	)
	(segment
		(start 231.414574 -60.659264)
		(end 231.680004 -60.924694)
		(width 0.0889)
		(layer "In4.Cu")
		(net "M_B_DQ<13>")
	)
	(segment
		(start 231.8639 -62.92469)
		(end 232.199688 -62.92469)
		(width 0.0889)
		(layer "In4.Cu")
		(net "M_B_DQ<13>")
	)
	(segment
		(start 206.320644 -8.0518)
		(end 206.63154 -8.0518)
		(width 0.14224)
		(layer "In4.Cu")
		(net "M_B_DQ<13>")
	)
	(segment
		(start 231.680004 -62.740794)
		(end 231.8639 -62.92469)
		(width 0.0889)
		(layer "In4.Cu")
		(net "M_B_DQ<13>")
	)
	(segment
		(start 234.849924 -64.410336)
		(end 235.072174 -64.337438)
		(width 0.0889)
		(layer "In4.Cu")
		(net "M_B_DQ<13>")
	)
	(segment
		(start 206.954628 -21.920454)
		(end 206.98079 -21.946616)
		(width 0.14224)
		(layer "In4.Cu")
		(net "M_B_DQ<13>")
	)
	(arc
		(start 236.982508 -63.315088)
		(mid 237.122587 -63.172352)
		(end 237.314232 -63.11519)
		(width 0.0889)
		(layer "In4.Cu")
		(net "M_B_DQ<13>")
	)
	(arc
		(start 236.123988 -63.810388)
		(mid 236.265671 -63.666584)
		(end 236.459522 -63.610236)
		(width 0.0889)
		(layer "In4.Cu")
		(net "M_B_DQ<13>")
	)
	(arc
		(start 233.054398 -63.419736)
		(mid 233.339822 -63.503203)
		(end 233.548428 -63.715138)
		(width 0.0889)
		(layer "In4.Cu")
		(net "M_B_DQ<13>")
	)
	(arc
		(start 232.689908 -63.219838)
		(mid 232.829987 -63.362574)
		(end 233.021632 -63.419736)
		(width 0.0889)
		(layer "In4.Cu")
		(net "M_B_DQ<13>")
	)
	(arc
		(start 233.916728 -63.91529)
		(mid 234.199945 -63.999571)
		(end 234.406948 -64.210438)
		(width 0.0889)
		(layer "In4.Cu")
		(net "M_B_DQ<13>")
	)
	(arc
		(start 236.492288 -63.610236)
		(mid 236.775505 -63.525955)
		(end 236.982508 -63.315088)
		(width 0.0889)
		(layer "In4.Cu")
		(net "M_B_DQ<13>")
	)
	(arc
		(start 235.364274 -64.191642)
		(mid 235.473907 -64.130189)
		(end 235.597192 -64.10579)
		(width 0.0889)
		(layer "In4.Cu")
		(net "M_B_DQ<13>")
	)
	(arc
		(start 234.406948 -64.210438)
		(mid 234.547027 -64.353174)
		(end 234.738672 -64.410336)
		(width 0.0889)
		(layer "In4.Cu")
		(net "M_B_DQ<13>")
	)
	(arc
		(start 232.199688 -62.92469)
		(mid 232.482905 -63.008971)
		(end 232.689908 -63.219838)
		(width 0.0889)
		(layer "In4.Cu")
		(net "M_B_DQ<13>")
	)
	(arc
		(start 235.629958 -64.10579)
		(mid 235.915382 -64.022323)
		(end 236.123988 -63.810388)
		(width 0.0889)
		(layer "In4.Cu")
		(net "M_B_DQ<13>")
	)
	(arc
		(start 233.548428 -63.715138)
		(mid 233.690111 -63.858942)
		(end 233.883962 -63.91529)
		(width 0.0889)
		(layer "In4.Cu")
		(net "M_B_DQ<13>")
	)
	(segment
		(start 206.59979 -10.422382)
		(end 206.59979 -9.091168)
		(width 0.1651)
		(layer "F.Cu")
		(net "M_B_DQ<12>")
	)
	(segment
		(start 206.600298 -10.422382)
		(end 206.59979 -10.422382)
		(width 0.1651)
		(layer "F.Cu")
		(net "M_B_DQ<12>")
	)
	(segment
		(start 206.59979 -9.091168)
		(end 206.539338 -8.763)
		(width 0.1651)
		(layer "F.Cu")
		(net "M_B_DQ<12>")
	)
	(segment
		(start 206.539338 -8.763)
		(end 206.501746 -8.5598)
		(width 0.1651)
		(layer "F.Cu")
		(net "M_B_DQ<12>")
	)
	(segment
		(start 237.900718 -63.51524)
		(end 237.329218 -63.51524)
		(width 0.1016)
		(layer "F.Cu")
		(net "M_B_DQ<12>")
	)
	(via
		(at 206.501746 -8.5598)
		(size 0.508)
		(drill 0.254)
		(layers "F.Cu" "B.Cu")
		(net "M_B_DQ<12>")
	)
	(via
		(at 237.329218 -63.51524)
		(size 0.508)
		(drill 0.254)
		(layers "F.Cu" "B.Cu")
		(net "M_B_DQ<12>")
	)
	(via
		(at 205.749906 -13.959078)
		(size 0.508)
		(drill 0.254)
		(layers "F.Cu" "B.Cu")
		(net "M_B_DQ<12>")
	)
	(segment
		(start 205.750414 -15.222982)
		(end 205.749906 -15.222982)
		(width 0.1651)
		(layer "B.Cu")
		(net "M_B_DQ<12>")
	)
	(segment
		(start 205.749906 -15.222982)
		(end 205.749906 -13.959078)
		(width 0.1651)
		(layer "B.Cu")
		(net "M_B_DQ<12>")
	)
	(segment
		(start 206.225394 -12.217654)
		(end 205.514194 -12.928854)
		(width 0.14224)
		(layer "In4.Cu")
		(net "M_B_DQ<12>")
	)
	(segment
		(start 231.111044 -60.919614)
		(end 231.39273 -60.919614)
		(width 0.0889)
		(layer "In4.Cu")
		(net "M_B_DQ<12>")
	)
	(segment
		(start 205.874112 -11.391646)
		(end 206.225394 -11.742928)
		(width 0.14224)
		(layer "In4.Cu")
		(net "M_B_DQ<12>")
	)
	(segment
		(start 233.015028 -63.610236)
		(end 233.047794 -63.610236)
		(width 0.0889)
		(layer "In4.Cu")
		(net "M_B_DQ<12>")
	)
	(segment
		(start 236.187742 -64.593978)
		(end 236.64545 -64.370458)
		(width 0.0889)
		(layer "In4.Cu")
		(net "M_B_DQ<12>")
	)
	(segment
		(start 206.019146 -21.950172)
		(end 206.019146 -23.169372)
		(width 0.14224)
		(layer "In4.Cu")
		(net "M_B_DQ<12>")
	)
	(segment
		(start 206.225394 -11.742928)
		(end 206.225394 -12.217654)
		(width 0.14224)
		(layer "In4.Cu")
		(net "M_B_DQ<12>")
	)
	(segment
		(start 206.247746 -23.397972)
		(end 206.247746 -24.148796)
		(width 0.14224)
		(layer "In4.Cu")
		(net "M_B_DQ<12>")
	)
	(segment
		(start 230.919782 -60.919614)
		(end 231.111044 -60.919614)
		(width 0.14224)
		(layer "In4.Cu")
		(net "M_B_DQ<12>")
	)
	(segment
		(start 236.790484 -64.251078)
		(end 237.042706 -63.9064)
		(width 0.0889)
		(layer "In4.Cu")
		(net "M_B_DQ<12>")
	)
	(segment
		(start 206.0194 -14.559026)
		(end 206.0194 -16.281146)
		(width 0.14224)
		(layer "In4.Cu")
		(net "M_B_DQ<12>")
	)
	(segment
		(start 206.273146 -18.568162)
		(end 206.273146 -21.696172)
		(width 0.14224)
		(layer "In4.Cu")
		(net "M_B_DQ<12>")
	)
	(segment
		(start 205.514194 -13.723366)
		(end 205.749906 -13.959078)
		(width 0.14224)
		(layer "In4.Cu")
		(net "M_B_DQ<12>")
	)
	(segment
		(start 205.861412 -9.677654)
		(end 205.861412 -9.9822)
		(width 0.14224)
		(layer "In4.Cu")
		(net "M_B_DQ<12>")
	)
	(segment
		(start 231.784906 -63.11519)
		(end 232.193084 -63.11519)
		(width 0.0889)
		(layer "In4.Cu")
		(net "M_B_DQ<12>")
	)
	(segment
		(start 205.861412 -9.9822)
		(end 206.242412 -10.3632)
		(width 0.14224)
		(layer "In4.Cu")
		(net "M_B_DQ<12>")
	)
	(segment
		(start 206.242412 -10.3632)
		(end 206.242412 -10.668)
		(width 0.14224)
		(layer "In4.Cu")
		(net "M_B_DQ<12>")
	)
	(segment
		(start 205.874112 -11.0363)
		(end 205.874112 -11.391646)
		(width 0.14224)
		(layer "In4.Cu")
		(net "M_B_DQ<12>")
	)
	(segment
		(start 206.242412 -10.668)
		(end 205.874112 -11.0363)
		(width 0.14224)
		(layer "In4.Cu")
		(net "M_B_DQ<12>")
	)
	(segment
		(start 205.749906 -13.959078)
		(end 205.749906 -14.289532)
		(width 0.14224)
		(layer "In4.Cu")
		(net "M_B_DQ<12>")
	)
	(segment
		(start 231.39273 -60.919614)
		(end 231.489504 -61.016388)
		(width 0.0889)
		(layer "In4.Cu")
		(net "M_B_DQ<12>")
	)
	(segment
		(start 205.514194 -12.928854)
		(end 205.514194 -13.723366)
		(width 0.14224)
		(layer "In4.Cu")
		(net "M_B_DQ<12>")
	)
	(segment
		(start 235.535724 -64.90589)
		(end 235.623354 -64.90589)
		(width 0.0889)
		(layer "In4.Cu")
		(net "M_B_DQ<12>")
	)
	(segment
		(start 206.894938 -24.795988)
		(end 206.894938 -27.431238)
		(width 0.14224)
		(layer "In4.Cu")
		(net "M_B_DQ<12>")
	)
	(segment
		(start 206.019146 -18.314162)
		(end 206.273146 -18.568162)
		(width 0.14224)
		(layer "In4.Cu")
		(net "M_B_DQ<12>")
	)
	(segment
		(start 233.877358 -64.10579)
		(end 233.910124 -64.10579)
		(width 0.0889)
		(layer "In4.Cu")
		(net "M_B_DQ<12>")
	)
	(segment
		(start 234.732068 -64.600836)
		(end 234.764834 -64.600836)
		(width 0.0889)
		(layer "In4.Cu")
		(net "M_B_DQ<12>")
	)
	(segment
		(start 206.247746 -16.509492)
		(end 206.247746 -16.840454)
		(width 0.14224)
		(layer "In4.Cu")
		(net "M_B_DQ<12>")
	)
	(segment
		(start 206.247746 -16.840454)
		(end 206.019146 -17.069054)
		(width 0.14224)
		(layer "In4.Cu")
		(net "M_B_DQ<12>")
	)
	(segment
		(start 231.489504 -61.016388)
		(end 231.489504 -62.819788)
		(width 0.0889)
		(layer "In4.Cu")
		(net "M_B_DQ<12>")
	)
	(segment
		(start 206.019146 -23.169372)
		(end 206.247746 -23.397972)
		(width 0.14224)
		(layer "In4.Cu")
		(net "M_B_DQ<12>")
	)
	(segment
		(start 227.3173 -56.148732)
		(end 227.3173 -57.317132)
		(width 0.14224)
		(layer "In4.Cu")
		(net "M_B_DQ<12>")
	)
	(segment
		(start 206.225394 -8.836152)
		(end 206.225394 -9.313672)
		(width 0.14224)
		(layer "In4.Cu")
		(net "M_B_DQ<12>")
	)
	(segment
		(start 206.247746 -24.148796)
		(end 206.894938 -24.795988)
		(width 0.14224)
		(layer "In4.Cu")
		(net "M_B_DQ<12>")
	)
	(segment
		(start 206.894938 -27.431238)
		(end 207.645 -28.1813)
		(width 0.14224)
		(layer "In4.Cu")
		(net "M_B_DQ<12>")
	)
	(segment
		(start 207.645 -28.1813)
		(end 207.645 -36.476432)
		(width 0.14224)
		(layer "In4.Cu")
		(net "M_B_DQ<12>")
	)
	(segment
		(start 235.901484 -64.782446)
		(end 236.187742 -64.593978)
		(width 0.0889)
		(layer "In4.Cu")
		(net "M_B_DQ<12>")
	)
	(segment
		(start 206.225394 -9.313672)
		(end 205.861412 -9.677654)
		(width 0.14224)
		(layer "In4.Cu")
		(net "M_B_DQ<12>")
	)
	(segment
		(start 234.926886 -64.640206)
		(end 235.192062 -64.769746)
		(width 0.0889)
		(layer "In4.Cu")
		(net "M_B_DQ<12>")
	)
	(segment
		(start 206.019146 -17.069054)
		(end 206.019146 -18.314162)
		(width 0.14224)
		(layer "In4.Cu")
		(net "M_B_DQ<12>")
	)
	(segment
		(start 206.273146 -21.696172)
		(end 206.019146 -21.950172)
		(width 0.14224)
		(layer "In4.Cu")
		(net "M_B_DQ<12>")
	)
	(segment
		(start 227.3173 -57.317132)
		(end 230.919782 -60.919614)
		(width 0.14224)
		(layer "In4.Cu")
		(net "M_B_DQ<12>")
	)
	(segment
		(start 207.645 -36.476432)
		(end 227.3173 -56.148732)
		(width 0.14224)
		(layer "In4.Cu")
		(net "M_B_DQ<12>")
	)
	(segment
		(start 205.749906 -14.289532)
		(end 206.0194 -14.559026)
		(width 0.14224)
		(layer "In4.Cu")
		(net "M_B_DQ<12>")
	)
	(segment
		(start 235.192062 -64.769746)
		(end 235.535724 -64.90589)
		(width 0.0889)
		(layer "In4.Cu")
		(net "M_B_DQ<12>")
	)
	(segment
		(start 206.501746 -8.5598)
		(end 206.225394 -8.836152)
		(width 0.14224)
		(layer "In4.Cu")
		(net "M_B_DQ<12>")
	)
	(segment
		(start 206.0194 -16.281146)
		(end 206.247746 -16.509492)
		(width 0.14224)
		(layer "In4.Cu")
		(net "M_B_DQ<12>")
	)
	(segment
		(start 237.042706 -63.9064)
		(end 237.329218 -63.51524)
		(width 0.0889)
		(layer "In4.Cu")
		(net "M_B_DQ<12>")
	)
	(segment
		(start 231.489504 -62.819788)
		(end 231.784906 -63.11519)
		(width 0.0889)
		(layer "In4.Cu")
		(net "M_B_DQ<12>")
	)
	(arc
		(start 235.623354 -64.90589)
		(mid 235.774592 -64.871608)
		(end 235.901484 -64.782446)
		(width 0.0889)
		(layer "In4.Cu")
		(net "M_B_DQ<12>")
	)
	(arc
		(start 234.764834 -64.600836)
		(mid 234.84793 -64.611996)
		(end 234.926886 -64.640206)
		(width 0.0889)
		(layer "In4.Cu")
		(net "M_B_DQ<12>")
	)
	(arc
		(start 232.193084 -63.11519)
		(mid 232.384726 -63.172356)
		(end 232.524808 -63.315088)
		(width 0.0889)
		(layer "In4.Cu")
		(net "M_B_DQ<12>")
	)
	(arc
		(start 232.524808 -63.315088)
		(mid 232.731812 -63.525952)
		(end 233.015028 -63.610236)
		(width 0.0889)
		(layer "In4.Cu")
		(net "M_B_DQ<12>")
	)
	(arc
		(start 236.64545 -64.370458)
		(mid 236.725077 -64.319403)
		(end 236.790484 -64.251078)
		(width 0.0889)
		(layer "In4.Cu")
		(net "M_B_DQ<12>")
	)
	(arc
		(start 233.047794 -63.610236)
		(mid 233.241644 -63.666586)
		(end 233.383328 -63.810388)
		(width 0.0889)
		(layer "In4.Cu")
		(net "M_B_DQ<12>")
	)
	(arc
		(start 234.241848 -64.305688)
		(mid 234.448852 -64.516552)
		(end 234.732068 -64.600836)
		(width 0.0889)
		(layer "In4.Cu")
		(net "M_B_DQ<12>")
	)
	(arc
		(start 233.910124 -64.10579)
		(mid 234.101766 -64.162956)
		(end 234.241848 -64.305688)
		(width 0.0889)
		(layer "In4.Cu")
		(net "M_B_DQ<12>")
	)
	(arc
		(start 233.383328 -63.810388)
		(mid 233.591936 -64.02232)
		(end 233.877358 -64.10579)
		(width 0.0889)
		(layer "In4.Cu")
		(net "M_B_DQ<12>")
	)
	(segment
		(start 213.400386 -5.822442)
		(end 213.399878 -5.822442)
		(width 0.1651)
		(layer "F.Cu")
		(net "M_B_DQ<11>")
	)
	(segment
		(start 237.042198 -60.047886)
		(end 236.470698 -60.047886)
		(width 0.1016)
		(layer "F.Cu")
		(net "M_B_DQ<11>")
	)
	(segment
		(start 213.399878 -5.822442)
		(end 213.399878 -7.086346)
		(width 0.1651)
		(layer "F.Cu")
		(net "M_B_DQ<11>")
	)
	(via
		(at 213.399878 -7.086346)
		(size 0.508)
		(drill 0.254)
		(layers "F.Cu" "B.Cu")
		(net "M_B_DQ<11>")
	)
	(via
		(at 214.249762 -12.678156)
		(size 0.508)
		(drill 0.254)
		(layers "F.Cu" "B.Cu")
		(net "M_B_DQ<11>")
	)
	(via
		(at 236.470698 -60.047886)
		(size 0.508)
		(drill 0.254)
		(layers "F.Cu" "B.Cu")
		(net "M_B_DQ<11>")
	)
	(segment
		(start 214.249762 -10.806176)
		(end 214.249762 -12.678156)
		(width 0.1651)
		(layer "B.Cu")
		(net "M_B_DQ<11>")
	)
	(segment
		(start 214.250016 -10.805922)
		(end 214.249762 -10.806176)
		(width 0.1651)
		(layer "B.Cu")
		(net "M_B_DQ<11>")
	)
	(segment
		(start 214.250016 -10.623042)
		(end 214.250016 -10.805922)
		(width 0.1651)
		(layer "B.Cu")
		(net "M_B_DQ<11>")
	)
	(segment
		(start 214.250524 -10.623042)
		(end 214.250016 -10.623042)
		(width 0.1651)
		(layer "B.Cu")
		(net "M_B_DQ<11>")
	)
	(segment
		(start 227.408232 -46.900338)
		(end 227.71608 -46.592236)
		(width 0.14224)
		(layer "In4.Cu")
		(net "M_B_DQ<11>")
	)
	(segment
		(start 227.189284 -46.900338)
		(end 227.408232 -46.900338)
		(width 0.14224)
		(layer "In4.Cu")
		(net "M_B_DQ<11>")
	)
	(segment
		(start 213.399878 -7.086346)
		(end 213.716616 -7.403084)
		(width 0.14224)
		(layer "In4.Cu")
		(net "M_B_DQ<11>")
	)
	(segment
		(start 214.17534 -29.48432)
		(end 214.0204 -29.63926)
		(width 0.14224)
		(layer "In4.Cu")
		(net "M_B_DQ<11>")
	)
	(segment
		(start 214.17534 -26.16962)
		(end 214.58936 -26.16962)
		(width 0.14224)
		(layer "In4.Cu")
		(net "M_B_DQ<11>")
	)
	(segment
		(start 226.251516 -45.96257)
		(end 226.470464 -45.96257)
		(width 0.14224)
		(layer "In4.Cu")
		(net "M_B_DQ<11>")
	)
	(segment
		(start 214.249762 -12.678156)
		(end 213.766146 -13.161772)
		(width 0.14224)
		(layer "In4.Cu")
		(net "M_B_DQ<11>")
	)
	(segment
		(start 225.5901 -41.7576)
		(end 225.5901 -45.301154)
		(width 0.14224)
		(layer "In4.Cu")
		(net "M_B_DQ<11>")
	)
	(segment
		(start 235.712 -54.0512)
		(end 236.0676 -54.4068)
		(width 0.14224)
		(layer "In4.Cu")
		(net "M_B_DQ<11>")
	)
	(segment
		(start 214.0204 -25.66162)
		(end 214.0204 -26.01468)
		(width 0.14224)
		(layer "In4.Cu")
		(net "M_B_DQ<11>")
	)
	(segment
		(start 216.07272 -31.16072)
		(end 216.07272 -31.379668)
		(width 0.14224)
		(layer "In4.Cu")
		(net "M_B_DQ<11>")
	)
	(segment
		(start 215.603836 -30.910784)
		(end 215.822784 -30.910784)
		(width 0.14224)
		(layer "In4.Cu")
		(net "M_B_DQ<11>")
	)
	(segment
		(start 226.99726 -45.654468)
		(end 227.247196 -45.904404)
		(width 0.14224)
		(layer "In4.Cu")
		(net "M_B_DQ<11>")
	)
	(segment
		(start 214.604346 -21.823172)
		(end 214.782146 -22.000972)
		(width 0.14224)
		(layer "In4.Cu")
		(net "M_B_DQ<11>")
	)
	(segment
		(start 236.0676 -54.4068)
		(end 236.0676 -54.70271)
		(width 0.14224)
		(layer "In4.Cu")
		(net "M_B_DQ<11>")
	)
	(segment
		(start 214.756746 -18.389854)
		(end 214.604346 -18.542254)
		(width 0.14224)
		(layer "In4.Cu")
		(net "M_B_DQ<11>")
	)
	(segment
		(start 234.5182 -53.594)
		(end 234.9246 -53.594)
		(width 0.14224)
		(layer "In4.Cu")
		(net "M_B_DQ<11>")
	)
	(segment
		(start 227.247196 -45.904404)
		(end 227.247196 -46.123352)
		(width 0.14224)
		(layer "In4.Cu")
		(net "M_B_DQ<11>")
	)
	(segment
		(start 234.0102 -53.086)
		(end 234.5182 -53.594)
		(width 0.14224)
		(layer "In4.Cu")
		(net "M_B_DQ<11>")
	)
	(segment
		(start 236.069378 -55.0926)
		(end 236.069632 -55.153052)
		(width 0.0889)
		(layer "In4.Cu")
		(net "M_B_DQ<11>")
	)
	(segment
		(start 214.80526 -28.15844)
		(end 214.17534 -28.15844)
		(width 0.14224)
		(layer "In4.Cu")
		(net "M_B_DQ<11>")
	)
	(segment
		(start 236.069632 -55.153052)
		(end 236.080808 -55.230776)
		(width 0.0889)
		(layer "In4.Cu")
		(net "M_B_DQ<11>")
	)
	(segment
		(start 228.9302 -48.66386)
		(end 229.08514 -48.8188)
		(width 0.14224)
		(layer "In4.Cu")
		(net "M_B_DQ<11>")
	)
	(segment
		(start 214.9602 -28.0035)
		(end 214.80526 -28.15844)
		(width 0.14224)
		(layer "In4.Cu")
		(net "M_B_DQ<11>")
	)
	(segment
		(start 214.17534 -26.83256)
		(end 214.0204 -26.9875)
		(width 0.14224)
		(layer "In4.Cu")
		(net "M_B_DQ<11>")
	)
	(segment
		(start 214.617046 -23.283672)
		(end 214.617046 -25.37968)
		(width 0.14224)
		(layer "In4.Cu")
		(net "M_B_DQ<11>")
	)
	(segment
		(start 214.14486 -13.946886)
		(end 214.14486 -15.809214)
		(width 0.14224)
		(layer "In4.Cu")
		(net "M_B_DQ<11>")
	)
	(segment
		(start 214.300816 -8.0518)
		(end 214.758016 -8.509)
		(width 0.14224)
		(layer "In4.Cu")
		(net "M_B_DQ<11>")
	)
	(segment
		(start 226.939348 -46.431454)
		(end 226.939348 -46.650402)
		(width 0.14224)
		(layer "In4.Cu")
		(net "M_B_DQ<11>")
	)
	(segment
		(start 235.3818 -54.0512)
		(end 235.712 -54.0512)
		(width 0.14224)
		(layer "In4.Cu")
		(net "M_B_DQ<11>")
	)
	(segment
		(start 214.7316 -28.82138)
		(end 214.8586 -28.94838)
		(width 0.14224)
		(layer "In4.Cu")
		(net "M_B_DQ<11>")
	)
	(segment
		(start 226.778312 -45.654468)
		(end 226.99726 -45.654468)
		(width 0.14224)
		(layer "In4.Cu")
		(net "M_B_DQ<11>")
	)
	(segment
		(start 216.689686 -32.857186)
		(end 225.5901 -41.7576)
		(width 0.14224)
		(layer "In4.Cu")
		(net "M_B_DQ<11>")
	)
	(segment
		(start 214.8586 -29.35732)
		(end 214.7316 -29.48432)
		(width 0.14224)
		(layer "In4.Cu")
		(net "M_B_DQ<11>")
	)
	(segment
		(start 236.130338 -55.87492)
		(end 236.123988 -55.885588)
		(width 0.0889)
		(layer "In4.Cu")
		(net "M_B_DQ<11>")
	)
	(segment
		(start 233.6292 -53.086)
		(end 234.0102 -53.086)
		(width 0.14224)
		(layer "In4.Cu")
		(net "M_B_DQ<11>")
	)
	(segment
		(start 216.689686 -32.638238)
		(end 216.689686 -32.857186)
		(width 0.14224)
		(layer "In4.Cu")
		(net "M_B_DQ<11>")
	)
	(segment
		(start 227.935028 -46.592236)
		(end 228.184964 -46.842172)
		(width 0.14224)
		(layer "In4.Cu")
		(net "M_B_DQ<11>")
	)
	(segment
		(start 214.17534 -28.82138)
		(end 214.7316 -28.82138)
		(width 0.14224)
		(layer "In4.Cu")
		(net "M_B_DQ<11>")
	)
	(segment
		(start 214.617046 -25.37968)
		(end 214.490046 -25.50668)
		(width 0.14224)
		(layer "In4.Cu")
		(net "M_B_DQ<11>")
	)
	(segment
		(start 214.17534 -28.15844)
		(end 214.0204 -28.31338)
		(width 0.14224)
		(layer "In4.Cu")
		(net "M_B_DQ<11>")
	)
	(segment
		(start 214.617046 -16.891762)
		(end 214.756746 -17.031462)
		(width 0.14224)
		(layer "In4.Cu")
		(net "M_B_DQ<11>")
	)
	(segment
		(start 214.7443 -26.67762)
		(end 214.58936 -26.83256)
		(width 0.14224)
		(layer "In4.Cu")
		(net "M_B_DQ<11>")
	)
	(segment
		(start 216.001854 -32.169354)
		(end 216.220802 -32.169354)
		(width 0.14224)
		(layer "In4.Cu")
		(net "M_B_DQ<11>")
	)
	(segment
		(start 236.069378 -54.704488)
		(end 236.069378 -55.0926)
		(width 0.0889)
		(layer "In4.Cu")
		(net "M_B_DQ<11>")
	)
	(segment
		(start 229.362 -48.8188)
		(end 233.6292 -53.086)
		(width 0.14224)
		(layer "In4.Cu")
		(net "M_B_DQ<11>")
	)
	(segment
		(start 227.71608 -46.592236)
		(end 227.935028 -46.592236)
		(width 0.14224)
		(layer "In4.Cu")
		(net "M_B_DQ<11>")
	)
	(segment
		(start 214.0204 -26.9875)
		(end 214.0204 -27.34056)
		(width 0.14224)
		(layer "In4.Cu")
		(net "M_B_DQ<11>")
	)
	(segment
		(start 214.58936 -26.16962)
		(end 214.7443 -26.32456)
		(width 0.14224)
		(layer "In4.Cu")
		(net "M_B_DQ<11>")
	)
	(segment
		(start 214.0204 -27.34056)
		(end 214.17534 -27.4955)
		(width 0.14224)
		(layer "In4.Cu")
		(net "M_B_DQ<11>")
	)
	(segment
		(start 236.098842 -60.195714)
		(end 236.177582 -60.21705)
		(width 0.0889)
		(layer "In4.Cu")
		(net "M_B_DQ<11>")
	)
	(segment
		(start 228.184964 -46.842172)
		(end 228.184964 -47.06112)
		(width 0.14224)
		(layer "In4.Cu")
		(net "M_B_DQ<11>")
	)
	(segment
		(start 236.130338 -59.83732)
		(end 236.123988 -59.847988)
		(width 0.0889)
		(layer "In4.Cu")
		(net "M_B_DQ<11>")
	)
	(segment
		(start 215.751918 -31.70047)
		(end 215.751918 -31.919418)
		(width 0.14224)
		(layer "In4.Cu")
		(net "M_B_DQ<11>")
	)
	(segment
		(start 214.14486 -15.809214)
		(end 214.617046 -16.2814)
		(width 0.14224)
		(layer "In4.Cu")
		(net "M_B_DQ<11>")
	)
	(segment
		(start 214.9602 -27.65044)
		(end 214.9602 -28.0035)
		(width 0.14224)
		(layer "In4.Cu")
		(net "M_B_DQ<11>")
	)
	(segment
		(start 227.247196 -46.123352)
		(end 226.939348 -46.431454)
		(width 0.14224)
		(layer "In4.Cu")
		(net "M_B_DQ<11>")
	)
	(segment
		(start 215.283034 -31.231586)
		(end 215.603836 -30.910784)
		(width 0.14224)
		(layer "In4.Cu")
		(net "M_B_DQ<11>")
	)
	(segment
		(start 214.0204 -30.1879)
		(end 215.064086 -31.231586)
		(width 0.14224)
		(layer "In4.Cu")
		(net "M_B_DQ<11>")
	)
	(segment
		(start 236.123988 -58.266838)
		(end 236.130338 -58.277506)
		(width 0.0889)
		(layer "In4.Cu")
		(net "M_B_DQ<11>")
	)
	(segment
		(start 214.602568 -12.32535)
		(end 214.249762 -12.678156)
		(width 0.14224)
		(layer "In4.Cu")
		(net "M_B_DQ<11>")
	)
	(segment
		(start 214.7316 -29.48432)
		(end 214.17534 -29.48432)
		(width 0.14224)
		(layer "In4.Cu")
		(net "M_B_DQ<11>")
	)
	(segment
		(start 214.782146 -22.000972)
		(end 214.782146 -23.118572)
		(width 0.14224)
		(layer "In4.Cu")
		(net "M_B_DQ<11>")
	)
	(segment
		(start 236.123988 -58.857388)
		(end 236.119162 -58.866024)
		(width 0.0889)
		(layer "In4.Cu")
		(net "M_B_DQ<11>")
	)
	(segment
		(start 216.541604 -31.848552)
		(end 216.760552 -31.848552)
		(width 0.14224)
		(layer "In4.Cu")
		(net "M_B_DQ<11>")
	)
	(segment
		(start 225.5901 -45.301154)
		(end 226.251516 -45.96257)
		(width 0.14224)
		(layer "In4.Cu")
		(net "M_B_DQ<11>")
	)
	(segment
		(start 213.766146 -13.568172)
		(end 214.14486 -13.946886)
		(width 0.14224)
		(layer "In4.Cu")
		(net "M_B_DQ<11>")
	)
	(segment
		(start 226.470464 -45.96257)
		(end 226.778312 -45.654468)
		(width 0.14224)
		(layer "In4.Cu")
		(net "M_B_DQ<11>")
	)
	(segment
		(start 213.766146 -13.161772)
		(end 213.766146 -13.568172)
		(width 0.14224)
		(layer "In4.Cu")
		(net "M_B_DQ<11>")
	)
	(segment
		(start 214.58936 -26.83256)
		(end 214.17534 -26.83256)
		(width 0.14224)
		(layer "In4.Cu")
		(net "M_B_DQ<11>")
	)
	(segment
		(start 214.80526 -27.4955)
		(end 214.9602 -27.65044)
		(width 0.14224)
		(layer "In4.Cu")
		(net "M_B_DQ<11>")
	)
	(segment
		(start 214.602568 -9.020048)
		(end 214.602568 -12.32535)
		(width 0.14224)
		(layer "In4.Cu")
		(net "M_B_DQ<11>")
	)
	(segment
		(start 214.0204 -26.01468)
		(end 214.17534 -26.16962)
		(width 0.14224)
		(layer "In4.Cu")
		(net "M_B_DQ<11>")
	)
	(segment
		(start 228.184964 -47.06112)
		(end 227.877116 -47.369222)
		(width 0.14224)
		(layer "In4.Cu")
		(net "M_B_DQ<11>")
	)
	(segment
		(start 214.0204 -29.63926)
		(end 214.0204 -30.1879)
		(width 0.14224)
		(layer "In4.Cu")
		(net "M_B_DQ<11>")
	)
	(segment
		(start 214.490046 -25.50668)
		(end 214.17534 -25.50668)
		(width 0.14224)
		(layer "In4.Cu")
		(net "M_B_DQ<11>")
	)
	(segment
		(start 216.760552 -31.848552)
		(end 217.010488 -32.098488)
		(width 0.14224)
		(layer "In4.Cu")
		(net "M_B_DQ<11>")
	)
	(segment
		(start 217.010488 -32.317436)
		(end 216.689686 -32.638238)
		(width 0.14224)
		(layer "In4.Cu")
		(net "M_B_DQ<11>")
	)
	(segment
		(start 216.220802 -32.169354)
		(end 216.541604 -31.848552)
		(width 0.14224)
		(layer "In4.Cu")
		(net "M_B_DQ<11>")
	)
	(segment
		(start 214.617046 -16.2814)
		(end 214.617046 -16.891762)
		(width 0.14224)
		(layer "In4.Cu")
		(net "M_B_DQ<11>")
	)
	(segment
		(start 214.604346 -18.542254)
		(end 214.604346 -21.823172)
		(width 0.14224)
		(layer "In4.Cu")
		(net "M_B_DQ<11>")
	)
	(segment
		(start 234.9246 -53.594)
		(end 235.3818 -54.0512)
		(width 0.14224)
		(layer "In4.Cu")
		(net "M_B_DQ<11>")
	)
	(segment
		(start 214.758016 -8.8646)
		(end 214.602568 -9.020048)
		(width 0.14224)
		(layer "In4.Cu")
		(net "M_B_DQ<11>")
	)
	(segment
		(start 236.177582 -60.21705)
		(end 236.470698 -60.047886)
		(width 0.0889)
		(layer "In4.Cu")
		(net "M_B_DQ<11>")
	)
	(segment
		(start 214.758016 -8.509)
		(end 214.758016 -8.8646)
		(width 0.14224)
		(layer "In4.Cu")
		(net "M_B_DQ<11>")
	)
	(segment
		(start 214.0204 -28.31338)
		(end 214.0204 -28.66644)
		(width 0.14224)
		(layer "In4.Cu")
		(net "M_B_DQ<11>")
	)
	(segment
		(start 215.751918 -31.919418)
		(end 216.001854 -32.169354)
		(width 0.14224)
		(layer "In4.Cu")
		(net "M_B_DQ<11>")
	)
	(segment
		(start 214.17534 -27.4955)
		(end 214.80526 -27.4955)
		(width 0.14224)
		(layer "In4.Cu")
		(net "M_B_DQ<11>")
	)
	(segment
		(start 214.756746 -17.031462)
		(end 214.756746 -18.389854)
		(width 0.14224)
		(layer "In4.Cu")
		(net "M_B_DQ<11>")
	)
	(segment
		(start 215.064086 -31.231586)
		(end 215.283034 -31.231586)
		(width 0.14224)
		(layer "In4.Cu")
		(net "M_B_DQ<11>")
	)
	(segment
		(start 214.17534 -25.50668)
		(end 214.0204 -25.66162)
		(width 0.14224)
		(layer "In4.Cu")
		(net "M_B_DQ<11>")
	)
	(segment
		(start 217.010488 -32.098488)
		(end 217.010488 -32.317436)
		(width 0.14224)
		(layer "In4.Cu")
		(net "M_B_DQ<11>")
	)
	(segment
		(start 227.877116 -47.58817)
		(end 228.9302 -48.641254)
		(width 0.14224)
		(layer "In4.Cu")
		(net "M_B_DQ<11>")
	)
	(segment
		(start 213.716616 -7.403084)
		(end 213.716616 -7.7216)
		(width 0.14224)
		(layer "In4.Cu")
		(net "M_B_DQ<11>")
	)
	(segment
		(start 229.08514 -48.8188)
		(end 229.362 -48.8188)
		(width 0.14224)
		(layer "In4.Cu")
		(net "M_B_DQ<11>")
	)
	(segment
		(start 215.822784 -30.910784)
		(end 216.07272 -31.16072)
		(width 0.14224)
		(layer "In4.Cu")
		(net "M_B_DQ<11>")
	)
	(segment
		(start 214.0204 -28.66644)
		(end 214.17534 -28.82138)
		(width 0.14224)
		(layer "In4.Cu")
		(net "M_B_DQ<11>")
	)
	(segment
		(start 213.716616 -7.7216)
		(end 214.046816 -8.0518)
		(width 0.14224)
		(layer "In4.Cu")
		(net "M_B_DQ<11>")
	)
	(segment
		(start 236.123988 -56.876188)
		(end 236.119162 -56.884824)
		(width 0.0889)
		(layer "In4.Cu")
		(net "M_B_DQ<11>")
	)
	(segment
		(start 214.782146 -23.118572)
		(end 214.617046 -23.283672)
		(width 0.14224)
		(layer "In4.Cu")
		(net "M_B_DQ<11>")
	)
	(segment
		(start 236.0676 -54.70271)
		(end 236.069378 -54.704488)
		(width 0.14224)
		(layer "In4.Cu")
		(net "M_B_DQ<11>")
	)
	(segment
		(start 214.046816 -8.0518)
		(end 214.300816 -8.0518)
		(width 0.14224)
		(layer "In4.Cu")
		(net "M_B_DQ<11>")
	)
	(segment
		(start 214.7443 -26.32456)
		(end 214.7443 -26.67762)
		(width 0.14224)
		(layer "In4.Cu")
		(net "M_B_DQ<11>")
	)
	(segment
		(start 226.939348 -46.650402)
		(end 227.189284 -46.900338)
		(width 0.14224)
		(layer "In4.Cu")
		(net "M_B_DQ<11>")
	)
	(segment
		(start 236.130338 -56.86552)
		(end 236.123988 -56.876188)
		(width 0.0889)
		(layer "In4.Cu")
		(net "M_B_DQ<11>")
	)
	(segment
		(start 227.877116 -47.369222)
		(end 227.877116 -47.58817)
		(width 0.14224)
		(layer "In4.Cu")
		(net "M_B_DQ<11>")
	)
	(segment
		(start 236.123988 -59.847988)
		(end 236.119162 -59.856624)
		(width 0.0889)
		(layer "In4.Cu")
		(net "M_B_DQ<11>")
	)
	(segment
		(start 214.8586 -28.94838)
		(end 214.8586 -29.35732)
		(width 0.14224)
		(layer "In4.Cu")
		(net "M_B_DQ<11>")
	)
	(segment
		(start 236.123988 -55.885588)
		(end 236.119162 -55.894224)
		(width 0.0889)
		(layer "In4.Cu")
		(net "M_B_DQ<11>")
	)
	(segment
		(start 216.07272 -31.379668)
		(end 215.751918 -31.70047)
		(width 0.14224)
		(layer "In4.Cu")
		(net "M_B_DQ<11>")
	)
	(segment
		(start 228.9302 -48.641254)
		(end 228.9302 -48.66386)
		(width 0.14224)
		(layer "In4.Cu")
		(net "M_B_DQ<11>")
	)
	(arc
		(start 236.080808 -55.230776)
		(mid 236.201338 -55.545469)
		(end 236.130338 -55.87492)
		(width 0.0889)
		(layer "In4.Cu")
		(net "M_B_DQ<11>")
	)
	(arc
		(start 236.130338 -58.277506)
		(mid 236.203136 -58.568269)
		(end 236.123988 -58.857388)
		(width 0.0889)
		(layer "In4.Cu")
		(net "M_B_DQ<11>")
	)
	(arc
		(start 236.119162 -55.894224)
		(mid 236.070407 -56.090576)
		(end 236.123988 -56.285638)
		(width 0.0889)
		(layer "In4.Cu")
		(net "M_B_DQ<11>")
	)
	(arc
		(start 236.123988 -57.867042)
		(mid 236.070489 -58.06694)
		(end 236.123988 -58.266838)
		(width 0.0889)
		(layer "In4.Cu")
		(net "M_B_DQ<11>")
	)
	(arc
		(start 236.119162 -58.866024)
		(mid 236.070407 -59.062376)
		(end 236.123988 -59.257438)
		(width 0.0889)
		(layer "In4.Cu")
		(net "M_B_DQ<11>")
	)
	(arc
		(start 236.119162 -59.856624)
		(mid 236.071249 -60.023909)
		(end 236.098842 -60.195714)
		(width 0.0889)
		(layer "In4.Cu")
		(net "M_B_DQ<11>")
	)
	(arc
		(start 236.123988 -59.257438)
		(mid 236.20321 -59.546556)
		(end 236.130338 -59.83732)
		(width 0.0889)
		(layer "In4.Cu")
		(net "M_B_DQ<11>")
	)
	(arc
		(start 236.123988 -57.276238)
		(mid 236.203119 -57.57164)
		(end 236.123988 -57.867042)
		(width 0.0889)
		(layer "In4.Cu")
		(net "M_B_DQ<11>")
	)
	(arc
		(start 236.123988 -56.285638)
		(mid 236.20321 -56.574756)
		(end 236.130338 -56.86552)
		(width 0.0889)
		(layer "In4.Cu")
		(net "M_B_DQ<11>")
	)
	(arc
		(start 236.119162 -56.884824)
		(mid 236.070407 -57.081176)
		(end 236.123988 -57.276238)
		(width 0.0889)
		(layer "In4.Cu")
		(net "M_B_DQ<11>")
	)
	(segment
		(start 214.249762 -9.425432)
		(end 214.381334 -9.29386)
		(width 0.1651)
		(layer "F.Cu")
		(net "M_B_DQ<10>")
	)
	(segment
		(start 214.250016 -9.425686)
		(end 214.249762 -9.425432)
		(width 0.1651)
		(layer "F.Cu")
		(net "M_B_DQ<10>")
	)
	(segment
		(start 214.250016 -10.422382)
		(end 214.250016 -9.425686)
		(width 0.1651)
		(layer "F.Cu")
		(net "M_B_DQ<10>")
	)
	(segment
		(start 236.183678 -60.54344)
		(end 235.612178 -60.54344)
		(width 0.1016)
		(layer "F.Cu")
		(net "M_B_DQ<10>")
	)
	(segment
		(start 214.250524 -10.422382)
		(end 214.250016 -10.422382)
		(width 0.1651)
		(layer "F.Cu")
		(net "M_B_DQ<10>")
	)
	(segment
		(start 214.381334 -9.07034)
		(end 214.249762 -8.938768)
		(width 0.1651)
		(layer "F.Cu")
		(net "M_B_DQ<10>")
	)
	(segment
		(start 214.249762 -8.938768)
		(end 214.249762 -8.6614)
		(width 0.1651)
		(layer "F.Cu")
		(net "M_B_DQ<10>")
	)
	(segment
		(start 214.381334 -9.29386)
		(end 214.381334 -9.07034)
		(width 0.1651)
		(layer "F.Cu")
		(net "M_B_DQ<10>")
	)
	(via
		(at 235.612178 -60.54344)
		(size 0.508)
		(drill 0.254)
		(layers "F.Cu" "B.Cu")
		(net "M_B_DQ<10>")
	)
	(via
		(at 213.399878 -13.959078)
		(size 0.508)
		(drill 0.254)
		(layers "F.Cu" "B.Cu")
		(net "M_B_DQ<10>")
	)
	(via
		(at 214.249762 -8.6614)
		(size 0.508)
		(drill 0.254)
		(layers "F.Cu" "B.Cu")
		(net "M_B_DQ<10>")
	)
	(segment
		(start 213.400386 -15.222982)
		(end 213.399878 -15.222982)
		(width 0.1651)
		(layer "B.Cu")
		(net "M_B_DQ<10>")
	)
	(segment
		(start 213.399878 -15.222982)
		(end 213.399878 -13.959078)
		(width 0.1651)
		(layer "B.Cu")
		(net "M_B_DQ<10>")
	)
	(segment
		(start 222.118174 -40.609266)
		(end 222.118174 -40.390318)
		(width 0.14224)
		(layer "In4.Cu")
		(net "M_B_DQ<10>")
	)
	(segment
		(start 219.30487 -37.577014)
		(end 219.860368 -37.021516)
		(width 0.14224)
		(layer "In4.Cu")
		(net "M_B_DQ<10>")
	)
	(segment
		(start 219.30487 -37.795962)
		(end 219.30487 -37.577014)
		(width 0.14224)
		(layer "In4.Cu")
		(net "M_B_DQ<10>")
	)
	(segment
		(start 221.180406 -39.671498)
		(end 221.180406 -39.45255)
		(width 0.14224)
		(layer "In4.Cu")
		(net "M_B_DQ<10>")
	)
	(segment
		(start 235.952538 -55.801006)
		(end 235.958888 -55.790338)
		(width 0.0889)
		(layer "In4.Cu")
		(net "M_B_DQ<10>")
	)
	(segment
		(start 221.180406 -39.45255)
		(end 221.735904 -38.897052)
		(width 0.14224)
		(layer "In4.Cu")
		(net "M_B_DQ<10>")
	)
	(segment
		(start 220.329252 -37.4904)
		(end 219.773754 -38.045898)
		(width 0.14224)
		(layer "In4.Cu")
		(net "M_B_DQ<10>")
	)
	(segment
		(start 235.627164 -55.19039)
		(end 235.594398 -55.19039)
		(width 0.0889)
		(layer "In4.Cu")
		(net "M_B_DQ<10>")
	)
	(segment
		(start 213.115144 -12.9286)
		(end 213.964012 -12.079732)
		(width 0.14224)
		(layer "In4.Cu")
		(net "M_B_DQ<10>")
	)
	(segment
		(start 219.554806 -38.045898)
		(end 219.30487 -37.795962)
		(width 0.14224)
		(layer "In4.Cu")
		(net "M_B_DQ<10>")
	)
	(segment
		(start 224.299272 -41.241472)
		(end 224.080324 -41.241472)
		(width 0.14224)
		(layer "In4.Cu")
		(net "M_B_DQ<10>")
	)
	(segment
		(start 213.399878 -13.959078)
		(end 213.115144 -13.674344)
		(width 0.14224)
		(layer "In4.Cu")
		(net "M_B_DQ<10>")
	)
	(segment
		(start 222.587058 -40.859202)
		(end 222.36811 -40.859202)
		(width 0.14224)
		(layer "In4.Cu")
		(net "M_B_DQ<10>")
	)
	(segment
		(start 220.798136 -37.959284)
		(end 220.798136 -37.740336)
		(width 0.14224)
		(layer "In4.Cu")
		(net "M_B_DQ<10>")
	)
	(segment
		(start 213.766146 -18.440146)
		(end 213.766146 -16.967962)
		(width 0.14224)
		(layer "In4.Cu")
		(net "M_B_DQ<10>")
	)
	(segment
		(start 213.811612 -10.64895)
		(end 213.811612 -10.362946)
		(width 0.14224)
		(layer "In4.Cu")
		(net "M_B_DQ<10>")
	)
	(segment
		(start 224.9424 -45.551598)
		(end 224.9424 -41.8846)
		(width 0.14224)
		(layer "In4.Cu")
		(net "M_B_DQ<10>")
	)
	(segment
		(start 221.735904 -38.897052)
		(end 221.735904 -38.678104)
		(width 0.14224)
		(layer "In4.Cu")
		(net "M_B_DQ<10>")
	)
	(segment
		(start 213.893146 -21.797772)
		(end 213.893146 -18.567146)
		(width 0.14224)
		(layer "In4.Cu")
		(net "M_B_DQ<10>")
	)
	(segment
		(start 213.3854 -24.269192)
		(end 213.861396 -23.793196)
		(width 0.14224)
		(layer "In4.Cu")
		(net "M_B_DQ<10>")
	)
	(segment
		(start 220.5482 -37.4904)
		(end 220.329252 -37.4904)
		(width 0.14224)
		(layer "In4.Cu")
		(net "M_B_DQ<10>")
	)
	(segment
		(start 213.3854 -30.3276)
		(end 213.3854 -24.269192)
		(width 0.14224)
		(layer "In4.Cu")
		(net "M_B_DQ<10>")
	)
	(segment
		(start 222.36811 -40.859202)
		(end 222.118174 -40.609266)
		(width 0.14224)
		(layer "In4.Cu")
		(net "M_B_DQ<10>")
	)
	(segment
		(start 221.26702 -38.428168)
		(end 220.711522 -38.983666)
		(width 0.14224)
		(layer "In4.Cu")
		(net "M_B_DQ<10>")
	)
	(segment
		(start 222.673672 -39.83482)
		(end 222.673672 -39.615872)
		(width 0.14224)
		(layer "In4.Cu")
		(net "M_B_DQ<10>")
	)
	(segment
		(start 235.905294 -60.374276)
		(end 235.92917 -60.284868)
		(width 0.0889)
		(layer "In4.Cu")
		(net "M_B_DQ<10>")
	)
	(segment
		(start 220.711522 -38.983666)
		(end 220.492574 -38.983666)
		(width 0.14224)
		(layer "In4.Cu")
		(net "M_B_DQ<10>")
	)
	(segment
		(start 219.860368 -37.021516)
		(end 219.860368 -36.802568)
		(width 0.14224)
		(layer "In4.Cu")
		(net "M_B_DQ<10>")
	)
	(segment
		(start 235.124244 -54.86527)
		(end 235.124244 -54.851554)
		(width 0.0889)
		(layer "In4.Cu")
		(net "M_B_DQ<10>")
	)
	(segment
		(start 213.811612 -10.362946)
		(end 213.506812 -10.058146)
		(width 0.14224)
		(layer "In4.Cu")
		(net "M_B_DQ<10>")
	)
	(segment
		(start 213.964012 -11.811)
		(end 213.506812 -11.3538)
		(width 0.14224)
		(layer "In4.Cu")
		(net "M_B_DQ<10>")
	)
	(segment
		(start 235.958888 -59.752738)
		(end 235.963714 -59.744102)
		(width 0.0889)
		(layer "In4.Cu")
		(net "M_B_DQ<10>")
	)
	(segment
		(start 213.506812 -11.3538)
		(end 213.506812 -10.95375)
		(width 0.14224)
		(layer "In4.Cu")
		(net "M_B_DQ<10>")
	)
	(segment
		(start 221.485968 -38.428168)
		(end 221.26702 -38.428168)
		(width 0.14224)
		(layer "In4.Cu")
		(net "M_B_DQ<10>")
	)
	(segment
		(start 219.773754 -38.045898)
		(end 219.554806 -38.045898)
		(width 0.14224)
		(layer "In4.Cu")
		(net "M_B_DQ<10>")
	)
	(segment
		(start 213.964012 -12.079732)
		(end 213.964012 -11.811)
		(width 0.14224)
		(layer "In4.Cu")
		(net "M_B_DQ<10>")
	)
	(segment
		(start 222.204788 -39.365936)
		(end 221.64929 -39.921434)
		(width 0.14224)
		(layer "In4.Cu")
		(net "M_B_DQ<10>")
	)
	(segment
		(start 213.861396 -23.793196)
		(end 213.861396 -23.264622)
		(width 0.14224)
		(layer "In4.Cu")
		(net "M_B_DQ<10>")
	)
	(segment
		(start 219.860368 -36.802568)
		(end 213.3854 -30.3276)
		(width 0.14224)
		(layer "In4.Cu")
		(net "M_B_DQ<10>")
	)
	(segment
		(start 222.788988 -41.813988)
		(end 222.788988 -41.59504)
		(width 0.14224)
		(layer "In4.Cu")
		(net "M_B_DQ<10>")
	)
	(segment
		(start 213.506812 -10.95375)
		(end 213.811612 -10.64895)
		(width 0.14224)
		(layer "In4.Cu")
		(net "M_B_DQ<10>")
	)
	(segment
		(start 223.257872 -42.063924)
		(end 223.038924 -42.063924)
		(width 0.14224)
		(layer "In4.Cu")
		(net "M_B_DQ<10>")
	)
	(segment
		(start 235.07573 -54.73446)
		(end 234.95127 -54.61)
		(width 0.0889)
		(layer "In4.Cu")
		(net "M_B_DQ<10>")
	)
	(segment
		(start 213.115144 -13.674344)
		(end 213.115144 -12.9286)
		(width 0.14224)
		(layer "In4.Cu")
		(net "M_B_DQ<10>")
	)
	(segment
		(start 222.423736 -39.365936)
		(end 222.204788 -39.365936)
		(width 0.14224)
		(layer "In4.Cu")
		(net "M_B_DQ<10>")
	)
	(segment
		(start 223.142556 -40.303704)
		(end 222.587058 -40.859202)
		(width 0.14224)
		(layer "In4.Cu")
		(net "M_B_DQ<10>")
	)
	(segment
		(start 224.9424 -41.8846)
		(end 224.299272 -41.241472)
		(width 0.14224)
		(layer "In4.Cu")
		(net "M_B_DQ<10>")
	)
	(segment
		(start 223.61144 -40.772588)
		(end 223.61144 -40.55364)
		(width 0.14224)
		(layer "In4.Cu")
		(net "M_B_DQ<10>")
	)
	(segment
		(start 223.361504 -40.303704)
		(end 223.142556 -40.303704)
		(width 0.14224)
		(layer "In4.Cu")
		(net "M_B_DQ<10>")
	)
	(segment
		(start 213.851744 -9.364472)
		(end 213.851744 -9.059418)
		(width 0.14224)
		(layer "In4.Cu")
		(net "M_B_DQ<10>")
	)
	(segment
		(start 224.080324 -41.241472)
		(end 223.257872 -42.063924)
		(width 0.14224)
		(layer "In4.Cu")
		(net "M_B_DQ<10>")
	)
	(segment
		(start 213.851744 -9.059418)
		(end 214.249762 -8.6614)
		(width 0.14224)
		(layer "In4.Cu")
		(net "M_B_DQ<10>")
	)
	(segment
		(start 235.612178 -60.54344)
		(end 235.905294 -60.374276)
		(width 0.0889)
		(layer "In4.Cu")
		(net "M_B_DQ<10>")
	)
	(segment
		(start 213.766146 -16.967962)
		(end 213.868 -16.866108)
		(width 0.14224)
		(layer "In4.Cu")
		(net "M_B_DQ<10>")
	)
	(segment
		(start 220.242638 -38.514782)
		(end 220.798136 -37.959284)
		(width 0.14224)
		(layer "In4.Cu")
		(net "M_B_DQ<10>")
	)
	(segment
		(start 232.4862 -53.2384)
		(end 232.4862 -53.095398)
		(width 0.14224)
		(layer "In4.Cu")
		(net "M_B_DQ<10>")
	)
	(segment
		(start 222.673672 -39.615872)
		(end 222.423736 -39.365936)
		(width 0.14224)
		(layer "In4.Cu")
		(net "M_B_DQ<10>")
	)
	(segment
		(start 213.861396 -23.264622)
		(end 213.740746 -23.143972)
		(width 0.14224)
		(layer "In4.Cu")
		(net "M_B_DQ<10>")
	)
	(segment
		(start 213.868 -16.4592)
		(end 213.399878 -15.991078)
		(width 0.14224)
		(layer "In4.Cu")
		(net "M_B_DQ<10>")
	)
	(segment
		(start 235.958888 -57.771538)
		(end 235.963714 -57.762902)
		(width 0.0889)
		(layer "In4.Cu")
		(net "M_B_DQ<10>")
	)
	(segment
		(start 221.430342 -39.921434)
		(end 221.180406 -39.671498)
		(width 0.14224)
		(layer "In4.Cu")
		(net "M_B_DQ<10>")
	)
	(segment
		(start 213.893146 -18.567146)
		(end 213.766146 -18.440146)
		(width 0.14224)
		(layer "In4.Cu")
		(net "M_B_DQ<10>")
	)
	(segment
		(start 213.740746 -21.950172)
		(end 213.893146 -21.797772)
		(width 0.14224)
		(layer "In4.Cu")
		(net "M_B_DQ<10>")
	)
	(segment
		(start 233.8578 -54.61)
		(end 232.4862 -53.2384)
		(width 0.14224)
		(layer "In4.Cu")
		(net "M_B_DQ<10>")
	)
	(segment
		(start 223.61144 -40.55364)
		(end 223.361504 -40.303704)
		(width 0.14224)
		(layer "In4.Cu")
		(net "M_B_DQ<10>")
	)
	(segment
		(start 235.958888 -55.790338)
		(end 235.963714 -55.781702)
		(width 0.0889)
		(layer "In4.Cu")
		(net "M_B_DQ<10>")
	)
	(segment
		(start 213.399878 -15.991078)
		(end 213.399878 -13.959078)
		(width 0.14224)
		(layer "In4.Cu")
		(net "M_B_DQ<10>")
	)
	(segment
		(start 235.958888 -58.362088)
		(end 235.952538 -58.35142)
		(width 0.0889)
		(layer "In4.Cu")
		(net "M_B_DQ<10>")
	)
	(segment
		(start 235.952538 -56.791606)
		(end 235.958888 -56.780938)
		(width 0.0889)
		(layer "In4.Cu")
		(net "M_B_DQ<10>")
	)
	(segment
		(start 220.492574 -38.983666)
		(end 220.242638 -38.73373)
		(width 0.14224)
		(layer "In4.Cu")
		(net "M_B_DQ<10>")
	)
	(segment
		(start 234.95127 -54.61)
		(end 233.8578 -54.61)
		(width 0.14224)
		(layer "In4.Cu")
		(net "M_B_DQ<10>")
	)
	(segment
		(start 213.506812 -9.709404)
		(end 213.851744 -9.364472)
		(width 0.14224)
		(layer "In4.Cu")
		(net "M_B_DQ<10>")
	)
	(segment
		(start 222.118174 -40.390318)
		(end 222.673672 -39.83482)
		(width 0.14224)
		(layer "In4.Cu")
		(net "M_B_DQ<10>")
	)
	(segment
		(start 220.242638 -38.73373)
		(end 220.242638 -38.514782)
		(width 0.14224)
		(layer "In4.Cu")
		(net "M_B_DQ<10>")
	)
	(segment
		(start 232.4862 -53.095398)
		(end 224.9424 -45.551598)
		(width 0.14224)
		(layer "In4.Cu")
		(net "M_B_DQ<10>")
	)
	(segment
		(start 235.952538 -59.763406)
		(end 235.958888 -59.752738)
		(width 0.0889)
		(layer "In4.Cu")
		(net "M_B_DQ<10>")
	)
	(segment
		(start 221.64929 -39.921434)
		(end 221.430342 -39.921434)
		(width 0.14224)
		(layer "In4.Cu")
		(net "M_B_DQ<10>")
	)
	(segment
		(start 223.038924 -42.063924)
		(end 222.788988 -41.813988)
		(width 0.14224)
		(layer "In4.Cu")
		(net "M_B_DQ<10>")
	)
	(segment
		(start 213.740746 -23.143972)
		(end 213.740746 -21.950172)
		(width 0.14224)
		(layer "In4.Cu")
		(net "M_B_DQ<10>")
	)
	(segment
		(start 235.958888 -56.780938)
		(end 235.963714 -56.772302)
		(width 0.0889)
		(layer "In4.Cu")
		(net "M_B_DQ<10>")
	)
	(segment
		(start 213.868 -16.866108)
		(end 213.868 -16.4592)
		(width 0.14224)
		(layer "In4.Cu")
		(net "M_B_DQ<10>")
	)
	(segment
		(start 213.506812 -10.058146)
		(end 213.506812 -9.709404)
		(width 0.14224)
		(layer "In4.Cu")
		(net "M_B_DQ<10>")
	)
	(segment
		(start 221.735904 -38.678104)
		(end 221.485968 -38.428168)
		(width 0.14224)
		(layer "In4.Cu")
		(net "M_B_DQ<10>")
	)
	(segment
		(start 220.798136 -37.740336)
		(end 220.5482 -37.4904)
		(width 0.14224)
		(layer "In4.Cu")
		(net "M_B_DQ<10>")
	)
	(segment
		(start 222.788988 -41.59504)
		(end 223.61144 -40.772588)
		(width 0.14224)
		(layer "In4.Cu")
		(net "M_B_DQ<10>")
	)
	(arc
		(start 235.958888 -56.380888)
		(mid 235.879666 -56.09177)
		(end 235.952538 -55.801006)
		(width 0.0889)
		(layer "In4.Cu")
		(net "M_B_DQ<10>")
	)
	(arc
		(start 235.958888 -57.371488)
		(mid 235.879666 -57.08237)
		(end 235.952538 -56.791606)
		(width 0.0889)
		(layer "In4.Cu")
		(net "M_B_DQ<10>")
	)
	(arc
		(start 235.594398 -55.19039)
		(mid 235.365231 -55.136465)
		(end 235.175298 -54.99735)
		(width 0.0889)
		(layer "In4.Cu")
		(net "M_B_DQ<10>")
	)
	(arc
		(start 235.963714 -55.781702)
		(mid 235.959967 -55.392446)
		(end 235.627164 -55.19039)
		(width 0.0889)
		(layer "In4.Cu")
		(net "M_B_DQ<10>")
	)
	(arc
		(start 235.958888 -58.761884)
		(mid 236.012387 -58.561986)
		(end 235.958888 -58.362088)
		(width 0.0889)
		(layer "In4.Cu")
		(net "M_B_DQ<10>")
	)
	(arc
		(start 235.958888 -59.352688)
		(mid 235.879757 -59.057286)
		(end 235.958888 -58.761884)
		(width 0.0889)
		(layer "In4.Cu")
		(net "M_B_DQ<10>")
	)
	(arc
		(start 235.124244 -54.851554)
		(mid 235.111638 -54.788179)
		(end 235.07573 -54.73446)
		(width 0.0889)
		(layer "In4.Cu")
		(net "M_B_DQ<10>")
	)
	(arc
		(start 235.175298 -54.99735)
		(mid 235.137445 -54.936074)
		(end 235.124244 -54.86527)
		(width 0.0889)
		(layer "In4.Cu")
		(net "M_B_DQ<10>")
	)
	(arc
		(start 235.92917 -60.284868)
		(mid 235.880158 -60.021419)
		(end 235.952538 -59.763406)
		(width 0.0889)
		(layer "In4.Cu")
		(net "M_B_DQ<10>")
	)
	(arc
		(start 235.952538 -58.35142)
		(mid 235.87974 -58.060657)
		(end 235.958888 -57.771538)
		(width 0.0889)
		(layer "In4.Cu")
		(net "M_B_DQ<10>")
	)
	(arc
		(start 235.963714 -57.762902)
		(mid 236.012469 -57.56655)
		(end 235.958888 -57.371488)
		(width 0.0889)
		(layer "In4.Cu")
		(net "M_B_DQ<10>")
	)
	(arc
		(start 235.963714 -56.772302)
		(mid 236.012469 -56.57595)
		(end 235.958888 -56.380888)
		(width 0.0889)
		(layer "In4.Cu")
		(net "M_B_DQ<10>")
	)
	(arc
		(start 235.963714 -59.744102)
		(mid 236.012469 -59.54775)
		(end 235.958888 -59.352688)
		(width 0.0889)
		(layer "In4.Cu")
		(net "M_B_DQ<10>")
	)
	(segment
		(start 198.950326 -10.422382)
		(end 198.949818 -10.422382)
		(width 0.1651)
		(layer "F.Cu")
		(net "M_B_DQ<0>")
	)
	(segment
		(start 198.949818 -10.422382)
		(end 198.791322 -8.763)
		(width 0.1651)
		(layer "F.Cu")
		(net "M_B_DQ<0>")
	)
	(segment
		(start 237.042198 -67.972686)
		(end 236.470698 -67.972686)
		(width 0.0889)
		(layer "F.Cu")
		(net "M_B_DQ<0>")
	)
	(segment
		(start 198.791322 -8.763)
		(end 198.772018 -8.5598)
		(width 0.1651)
		(layer "F.Cu")
		(net "M_B_DQ<0>")
	)
	(via
		(at 198.772018 -8.5598)
		(size 0.508)
		(drill 0.254)
		(layers "F.Cu" "B.Cu")
		(net "M_B_DQ<0>")
	)
	(via
		(at 236.470698 -67.972686)
		(size 0.508)
		(drill 0.254)
		(layers "F.Cu" "B.Cu")
		(net "M_B_DQ<0>")
	)
	(via
		(at 198.099934 -13.959078)
		(size 0.508)
		(drill 0.254)
		(layers "F.Cu" "B.Cu")
		(net "M_B_DQ<0>")
	)
	(segment
		(start 198.099934 -15.222982)
		(end 198.099934 -13.959078)
		(width 0.1651)
		(layer "B.Cu")
		(net "M_B_DQ<0>")
	)
	(segment
		(start 198.100442 -15.222982)
		(end 198.099934 -15.222982)
		(width 0.1651)
		(layer "B.Cu")
		(net "M_B_DQ<0>")
	)
	(segment
		(start 198.479918 -10.4521)
		(end 198.137018 -10.1092)
		(width 0.14224)
		(layer "In4.Cu")
		(net "M_B_DQ<0>")
	)
	(segment
		(start 231.861868 -68.06819)
		(end 231.522524 -68.407534)
		(width 0.0889)
		(layer "In4.Cu")
		(net "M_B_DQ<0>")
	)
	(segment
		(start 218.8845 -57.7596)
		(end 203.37145 -42.24655)
		(width 0.14224)
		(layer "In4.Cu")
		(net "M_B_DQ<0>")
	)
	(segment
		(start 198.2089 -34.795968)
		(end 198.501 -34.503868)
		(width 0.14224)
		(layer "In4.Cu")
		(net "M_B_DQ<0>")
	)
	(segment
		(start 229.862634 -68.407534)
		(end 219.2147 -57.7596)
		(width 0.14224)
		(layer "In4.Cu")
		(net "M_B_DQ<0>")
	)
	(segment
		(start 203.37145 -41.42105)
		(end 202.5777 -40.6273)
		(width 0.14224)
		(layer "In4.Cu")
		(net "M_B_DQ<0>")
	)
	(segment
		(start 198.2089 -36.121848)
		(end 198.501 -35.829748)
		(width 0.14224)
		(layer "In4.Cu")
		(net "M_B_DQ<0>")
	)
	(segment
		(start 198.82866 -27.272996)
		(end 198.9836 -27.118056)
		(width 0.14224)
		(layer "In4.Cu")
		(net "M_B_DQ<0>")
	)
	(segment
		(start 198.2724 -26.455116)
		(end 198.2724 -26.102056)
		(width 0.14224)
		(layer "In4.Cu")
		(net "M_B_DQ<0>")
	)
	(segment
		(start 203.37145 -42.24655)
		(end 203.37145 -41.42105)
		(width 0.14224)
		(layer "In4.Cu")
		(net "M_B_DQ<0>")
	)
	(segment
		(start 198.2724 -26.102056)
		(end 198.42734 -25.947116)
		(width 0.14224)
		(layer "In4.Cu")
		(net "M_B_DQ<0>")
	)
	(segment
		(start 198.5518 -9.364472)
		(end 198.5518 -8.780018)
		(width 0.14224)
		(layer "In4.Cu")
		(net "M_B_DQ<0>")
	)
	(segment
		(start 198.42734 -25.284176)
		(end 198.2724 -25.129236)
		(width 0.14224)
		(layer "In4.Cu")
		(net "M_B_DQ<0>")
	)
	(segment
		(start 197.8152 -12.9286)
		(end 198.5518 -12.192)
		(width 0.14224)
		(layer "In4.Cu")
		(net "M_B_DQ<0>")
	)
	(segment
		(start 198.501 -33.177988)
		(end 198.501 -32.807148)
		(width 0.14224)
		(layer "In4.Cu")
		(net "M_B_DQ<0>")
	)
	(segment
		(start 198.5518 -12.192)
		(end 198.5518 -11.692128)
		(width 0.14224)
		(layer "In4.Cu")
		(net "M_B_DQ<0>")
	)
	(segment
		(start 198.501 -37.3761)
		(end 198.501 -36.784788)
		(width 0.14224)
		(layer "In4.Cu")
		(net "M_B_DQ<0>")
	)
	(segment
		(start 198.099934 -15.956534)
		(end 198.099934 -13.959078)
		(width 0.14224)
		(layer "In4.Cu")
		(net "M_B_DQ<0>")
	)
	(segment
		(start 198.2089 -33.840928)
		(end 198.2089 -33.470088)
		(width 0.14224)
		(layer "In4.Cu")
		(net "M_B_DQ<0>")
	)
	(segment
		(start 198.2089 -32.515048)
		(end 198.2089 -32.144208)
		(width 0.14224)
		(layer "In4.Cu")
		(net "M_B_DQ<0>")
	)
	(segment
		(start 198.099934 -13.959078)
		(end 197.8152 -13.674344)
		(width 0.14224)
		(layer "In4.Cu")
		(net "M_B_DQ<0>")
	)
	(segment
		(start 197.8152 -13.674344)
		(end 197.8152 -12.9286)
		(width 0.14224)
		(layer "In4.Cu")
		(net "M_B_DQ<0>")
	)
	(segment
		(start 198.9836 -25.439116)
		(end 198.82866 -25.284176)
		(width 0.14224)
		(layer "In4.Cu")
		(net "M_B_DQ<0>")
	)
	(segment
		(start 201.7522 -40.6273)
		(end 198.501 -37.3761)
		(width 0.14224)
		(layer "In4.Cu")
		(net "M_B_DQ<0>")
	)
	(segment
		(start 198.501 -35.458908)
		(end 198.2089 -35.166808)
		(width 0.14224)
		(layer "In4.Cu")
		(net "M_B_DQ<0>")
	)
	(segment
		(start 198.479918 -10.6807)
		(end 198.479918 -10.4521)
		(width 0.14224)
		(layer "In4.Cu")
		(net "M_B_DQ<0>")
	)
	(segment
		(start 198.9836 -27.118056)
		(end 198.9836 -26.764996)
		(width 0.14224)
		(layer "In4.Cu")
		(net "M_B_DQ<0>")
	)
	(segment
		(start 198.5772 -21.6662)
		(end 198.5772 -18.5928)
		(width 0.14224)
		(layer "In4.Cu")
		(net "M_B_DQ<0>")
	)
	(segment
		(start 198.501 -35.829748)
		(end 198.501 -35.458908)
		(width 0.14224)
		(layer "In4.Cu")
		(net "M_B_DQ<0>")
	)
	(segment
		(start 236.253274 -68.552314)
		(end 236.14126 -68.73367)
		(width 0.0889)
		(layer "In4.Cu")
		(net "M_B_DQ<0>")
	)
	(segment
		(start 234.775248 -69.553836)
		(end 234.732068 -69.553836)
		(width 0.0889)
		(layer "In4.Cu")
		(net "M_B_DQ<0>")
	)
	(segment
		(start 198.2089 -36.492688)
		(end 198.2089 -36.121848)
		(width 0.14224)
		(layer "In4.Cu")
		(net "M_B_DQ<0>")
	)
	(segment
		(start 198.2724 -25.129236)
		(end 198.2724 -24.2824)
		(width 0.14224)
		(layer "In4.Cu")
		(net "M_B_DQ<0>")
	)
	(segment
		(start 236.14126 -68.73367)
		(end 236.123988 -68.763388)
		(width 0.0889)
		(layer "In4.Cu")
		(net "M_B_DQ<0>")
	)
	(segment
		(start 198.628 -27.272996)
		(end 198.82866 -27.272996)
		(width 0.14224)
		(layer "In4.Cu")
		(net "M_B_DQ<0>")
	)
	(segment
		(start 198.82866 -25.284176)
		(end 198.42734 -25.284176)
		(width 0.14224)
		(layer "In4.Cu")
		(net "M_B_DQ<0>")
	)
	(segment
		(start 198.6026 -16.4592)
		(end 198.099934 -15.956534)
		(width 0.14224)
		(layer "In4.Cu")
		(net "M_B_DQ<0>")
	)
	(segment
		(start 198.2724 -17.1323)
		(end 198.6026 -16.8021)
		(width 0.14224)
		(layer "In4.Cu")
		(net "M_B_DQ<0>")
	)
	(segment
		(start 202.5777 -40.6273)
		(end 201.7522 -40.6273)
		(width 0.14224)
		(layer "In4.Cu")
		(net "M_B_DQ<0>")
	)
	(segment
		(start 198.2978 -21.9456)
		(end 198.5772 -21.6662)
		(width 0.14224)
		(layer "In4.Cu")
		(net "M_B_DQ<0>")
	)
	(segment
		(start 198.137018 -9.779254)
		(end 198.5518 -9.364472)
		(width 0.14224)
		(layer "In4.Cu")
		(net "M_B_DQ<0>")
	)
	(segment
		(start 236.470698 -67.972686)
		(end 236.253274 -68.552314)
		(width 0.0889)
		(layer "In4.Cu")
		(net "M_B_DQ<0>")
	)
	(segment
		(start 198.5518 -8.780018)
		(end 198.772018 -8.5598)
		(width 0.14224)
		(layer "In4.Cu")
		(net "M_B_DQ<0>")
	)
	(segment
		(start 198.5772 -18.5928)
		(end 198.2724 -18.288)
		(width 0.14224)
		(layer "In4.Cu")
		(net "M_B_DQ<0>")
	)
	(segment
		(start 198.9836 -25.792176)
		(end 198.9836 -25.439116)
		(width 0.14224)
		(layer "In4.Cu")
		(net "M_B_DQ<0>")
	)
	(segment
		(start 198.42734 -26.610056)
		(end 198.2724 -26.455116)
		(width 0.14224)
		(layer "In4.Cu")
		(net "M_B_DQ<0>")
	)
	(segment
		(start 198.624952 -23.929848)
		(end 198.624952 -23.441152)
		(width 0.14224)
		(layer "In4.Cu")
		(net "M_B_DQ<0>")
	)
	(segment
		(start 198.501 -34.133028)
		(end 198.2089 -33.840928)
		(width 0.14224)
		(layer "In4.Cu")
		(net "M_B_DQ<0>")
	)
	(segment
		(start 198.501 -32.807148)
		(end 198.2089 -32.515048)
		(width 0.14224)
		(layer "In4.Cu")
		(net "M_B_DQ<0>")
	)
	(segment
		(start 198.2724 -18.288)
		(end 198.2724 -17.1323)
		(width 0.14224)
		(layer "In4.Cu")
		(net "M_B_DQ<0>")
	)
	(segment
		(start 219.2147 -57.7596)
		(end 218.8845 -57.7596)
		(width 0.14224)
		(layer "In4.Cu")
		(net "M_B_DQ<0>")
	)
	(segment
		(start 198.137018 -10.1092)
		(end 198.137018 -9.779254)
		(width 0.14224)
		(layer "In4.Cu")
		(net "M_B_DQ<0>")
	)
	(segment
		(start 198.501 -34.503868)
		(end 198.501 -34.133028)
		(width 0.14224)
		(layer "In4.Cu")
		(net "M_B_DQ<0>")
	)
	(segment
		(start 198.82866 -25.947116)
		(end 198.9836 -25.792176)
		(width 0.14224)
		(layer "In4.Cu")
		(net "M_B_DQ<0>")
	)
	(segment
		(start 232.268776 -68.06819)
		(end 231.861868 -68.06819)
		(width 0.0889)
		(layer "In4.Cu")
		(net "M_B_DQ<0>")
	)
	(segment
		(start 235.629958 -69.05879)
		(end 235.597192 -69.05879)
		(width 0.0889)
		(layer "In4.Cu")
		(net "M_B_DQ<0>")
	)
	(segment
		(start 198.9836 -26.764996)
		(end 198.82866 -26.610056)
		(width 0.14224)
		(layer "In4.Cu")
		(net "M_B_DQ<0>")
	)
	(segment
		(start 198.2089 -35.166808)
		(end 198.2089 -34.795968)
		(width 0.14224)
		(layer "In4.Cu")
		(net "M_B_DQ<0>")
	)
	(segment
		(start 198.2089 -33.470088)
		(end 198.501 -33.177988)
		(width 0.14224)
		(layer "In4.Cu")
		(net "M_B_DQ<0>")
	)
	(segment
		(start 198.501 -27.399996)
		(end 198.628 -27.272996)
		(width 0.14224)
		(layer "In4.Cu")
		(net "M_B_DQ<0>")
	)
	(segment
		(start 233.047794 -68.563236)
		(end 232.833418 -68.563236)
		(width 0.0889)
		(layer "In4.Cu")
		(net "M_B_DQ<0>")
	)
	(segment
		(start 198.624952 -23.441152)
		(end 198.2978 -23.114)
		(width 0.14224)
		(layer "In4.Cu")
		(net "M_B_DQ<0>")
	)
	(segment
		(start 198.2978 -23.114)
		(end 198.2978 -21.9456)
		(width 0.14224)
		(layer "In4.Cu")
		(net "M_B_DQ<0>")
	)
	(segment
		(start 198.5518 -11.692128)
		(end 198.162418 -11.302746)
		(width 0.14224)
		(layer "In4.Cu")
		(net "M_B_DQ<0>")
	)
	(segment
		(start 198.42734 -25.947116)
		(end 198.82866 -25.947116)
		(width 0.14224)
		(layer "In4.Cu")
		(net "M_B_DQ<0>")
	)
	(segment
		(start 198.2089 -32.144208)
		(end 198.501 -31.852108)
		(width 0.14224)
		(layer "In4.Cu")
		(net "M_B_DQ<0>")
	)
	(segment
		(start 198.6026 -16.8021)
		(end 198.6026 -16.4592)
		(width 0.14224)
		(layer "In4.Cu")
		(net "M_B_DQ<0>")
	)
	(segment
		(start 233.910124 -69.05879)
		(end 233.877358 -69.05879)
		(width 0.0889)
		(layer "In4.Cu")
		(net "M_B_DQ<0>")
	)
	(segment
		(start 231.522524 -68.407534)
		(end 229.862634 -68.407534)
		(width 0.14224)
		(layer "In4.Cu")
		(net "M_B_DQ<0>")
	)
	(segment
		(start 198.501 -36.784788)
		(end 198.2089 -36.492688)
		(width 0.14224)
		(layer "In4.Cu")
		(net "M_B_DQ<0>")
	)
	(segment
		(start 198.501 -31.852108)
		(end 198.501 -27.399996)
		(width 0.14224)
		(layer "In4.Cu")
		(net "M_B_DQ<0>")
	)
	(segment
		(start 198.82866 -26.610056)
		(end 198.42734 -26.610056)
		(width 0.14224)
		(layer "In4.Cu")
		(net "M_B_DQ<0>")
	)
	(segment
		(start 198.162418 -10.9982)
		(end 198.479918 -10.6807)
		(width 0.14224)
		(layer "In4.Cu")
		(net "M_B_DQ<0>")
	)
	(segment
		(start 198.2724 -24.2824)
		(end 198.624952 -23.929848)
		(width 0.14224)
		(layer "In4.Cu")
		(net "M_B_DQ<0>")
	)
	(segment
		(start 198.162418 -11.302746)
		(end 198.162418 -10.9982)
		(width 0.14224)
		(layer "In4.Cu")
		(net "M_B_DQ<0>")
	)
	(arc
		(start 232.833418 -68.563236)
		(mid 232.630824 -68.447418)
		(end 232.48493 -68.265294)
		(width 0.0889)
		(layer "In4.Cu")
		(net "M_B_DQ<0>")
	)
	(arc
		(start 232.48493 -68.265294)
		(mid 232.393986 -68.147951)
		(end 232.268776 -68.06819)
		(width 0.0889)
		(layer "In4.Cu")
		(net "M_B_DQ<0>")
	)
	(arc
		(start 233.383328 -68.763388)
		(mid 233.241645 -68.619584)
		(end 233.047794 -68.563236)
		(width 0.0889)
		(layer "In4.Cu")
		(net "M_B_DQ<0>")
	)
	(arc
		(start 234.241848 -69.258688)
		(mid 234.101769 -69.115952)
		(end 233.910124 -69.05879)
		(width 0.0889)
		(layer "In4.Cu")
		(net "M_B_DQ<0>")
	)
	(arc
		(start 233.877358 -69.05879)
		(mid 233.591934 -68.975323)
		(end 233.383328 -68.763388)
		(width 0.0889)
		(layer "In4.Cu")
		(net "M_B_DQ<0>")
	)
	(arc
		(start 235.265468 -69.258688)
		(mid 235.058464 -69.469552)
		(end 234.775248 -69.553836)
		(width 0.0889)
		(layer "In4.Cu")
		(net "M_B_DQ<0>")
	)
	(arc
		(start 235.597192 -69.05879)
		(mid 235.40555 -69.115956)
		(end 235.265468 -69.258688)
		(width 0.0889)
		(layer "In4.Cu")
		(net "M_B_DQ<0>")
	)
	(arc
		(start 234.732068 -69.553836)
		(mid 234.448851 -69.469555)
		(end 234.241848 -69.258688)
		(width 0.0889)
		(layer "In4.Cu")
		(net "M_B_DQ<0>")
	)
	(arc
		(start 236.123988 -68.763388)
		(mid 235.91538 -68.97532)
		(end 235.629958 -69.05879)
		(width 0.0889)
		(layer "In4.Cu")
		(net "M_B_DQ<0>")
	)
	(segment
		(start 267.089636 -56.58104)
		(end 266.518136 -56.58104)
		(width 0.1016)
		(layer "F.Cu")
		(net "M_B_CS_N<7>")
	)
	(via
		(at 266.518136 -56.58104)
		(size 0.508)
		(drill 0.254)
		(layers "F.Cu" "B.Cu")
		(net "M_B_CS_N<7>")
	)
	(via
		(at 277.999952 -11.918188)
		(size 0.4572)
		(drill 0.2032)
		(layers "F.Cu" "B.Cu")
		(net "M_B_CS_N<7>")
	)
	(segment
		(start 277.999952 -10.623042)
		(end 277.999952 -11.918188)
		(width 0.1651)
		(layer "B.Cu")
		(net "M_B_CS_N<7>")
	)
	(segment
		(start 278.00046 -10.623042)
		(end 277.999952 -10.623042)
		(width 0.1651)
		(layer "B.Cu")
		(net "M_B_CS_N<7>")
	)
	(segment
		(start 268.925802 -49.2887)
		(end 268.925802 -49.717198)
		(width 0.0889)
		(layer "In4.Cu")
		(net "M_B_CS_N<7>")
	)
	(segment
		(start 278.49576 -17.119854)
		(end 278.49576 -25.033986)
		(width 0.14224)
		(layer "In4.Cu")
		(net "M_B_CS_N<7>")
	)
	(segment
		(start 278.5364 -13.65504)
		(end 278.5364 -17.079214)
		(width 0.14224)
		(layer "In4.Cu")
		(net "M_B_CS_N<7>")
	)
	(segment
		(start 268.097 -51.816)
		(end 268.097 -53.213)
		(width 0.0889)
		(layer "In4.Cu")
		(net "M_B_CS_N<7>")
	)
	(segment
		(start 268.986 -54.991)
		(end 268.986 -55.251604)
		(width 0.0889)
		(layer "In4.Cu")
		(net "M_B_CS_N<7>")
	)
	(segment
		(start 268.605 -51.308)
		(end 268.097 -51.816)
		(width 0.0889)
		(layer "In4.Cu")
		(net "M_B_CS_N<7>")
	)
	(segment
		(start 268.605 -50.038)
		(end 268.605 -51.308)
		(width 0.0889)
		(layer "In4.Cu")
		(net "M_B_CS_N<7>")
	)
	(segment
		(start 277.999952 -11.918188)
		(end 278.075644 -11.99388)
		(width 0.14224)
		(layer "In4.Cu")
		(net "M_B_CS_N<7>")
	)
	(segment
		(start 268.986 -55.251604)
		(end 268.738604 -55.499)
		(width 0.0889)
		(layer "In4.Cu")
		(net "M_B_CS_N<7>")
	)
	(segment
		(start 268.925802 -49.717198)
		(end 268.605 -50.038)
		(width 0.0889)
		(layer "In4.Cu")
		(net "M_B_CS_N<7>")
	)
	(segment
		(start 268.738604 -55.499)
		(end 266.518136 -56.58104)
		(width 0.0889)
		(layer "In4.Cu")
		(net "M_B_CS_N<7>")
	)
	(segment
		(start 278.5364 -17.079214)
		(end 278.49576 -17.119854)
		(width 0.14224)
		(layer "In4.Cu")
		(net "M_B_CS_N<7>")
	)
	(segment
		(start 278.49576 -25.033986)
		(end 268.925802 -34.603944)
		(width 0.14224)
		(layer "In4.Cu")
		(net "M_B_CS_N<7>")
	)
	(segment
		(start 268.925802 -34.603944)
		(end 268.925802 -49.2887)
		(width 0.14224)
		(layer "In4.Cu")
		(net "M_B_CS_N<7>")
	)
	(segment
		(start 278.075644 -13.194284)
		(end 278.5364 -13.65504)
		(width 0.14224)
		(layer "In4.Cu")
		(net "M_B_CS_N<7>")
	)
	(segment
		(start 278.075644 -11.99388)
		(end 278.075644 -13.194284)
		(width 0.14224)
		(layer "In4.Cu")
		(net "M_B_CS_N<7>")
	)
	(segment
		(start 268.097 -53.213)
		(end 268.986 -54.991)
		(width 0.0889)
		(layer "In4.Cu")
		(net "M_B_CS_N<7>")
	)
	(segment
		(start 267.948156 -55.094886)
		(end 268.557756 -55.094886)
		(width 0.1016)
		(layer "F.Cu")
		(net "M_B_CS_N<6>")
	)
	(via
		(at 268.557756 -55.094886)
		(size 0.508)
		(drill 0.254)
		(layers "F.Cu" "B.Cu")
		(net "M_B_CS_N<6>")
	)
	(via
		(at 277.999952 -13.934186)
		(size 0.4572)
		(drill 0.2032)
		(layers "F.Cu" "B.Cu")
		(net "M_B_CS_N<6>")
	)
	(segment
		(start 277.999952 -15.222982)
		(end 277.999952 -13.934186)
		(width 0.1651)
		(layer "B.Cu")
		(net "M_B_CS_N<6>")
	)
	(segment
		(start 278.00046 -15.222982)
		(end 277.999952 -15.222982)
		(width 0.1651)
		(layer "B.Cu")
		(net "M_B_CS_N<6>")
	)
	(segment
		(start 277.592028 -16.44015)
		(end 277.592028 -17.17548)
		(width 0.14224)
		(layer "In4.Cu")
		(net "M_B_CS_N<6>")
	)
	(segment
		(start 277.934928 -16.28521)
		(end 277.746968 -16.28521)
		(width 0.14224)
		(layer "In4.Cu")
		(net "M_B_CS_N<6>")
	)
	(segment
		(start 267.94714 -55.094886)
		(end 268.557756 -55.094886)
		(width 0.0889)
		(layer "In4.Cu")
		(net "M_B_CS_N<6>")
	)
	(segment
		(start 277.92426 -17.33042)
		(end 278.0792 -17.48536)
		(width 0.14224)
		(layer "In4.Cu")
		(net "M_B_CS_N<6>")
	)
	(segment
		(start 277.92426 -17.99336)
		(end 277.746968 -17.99336)
		(width 0.14224)
		(layer "In4.Cu")
		(net "M_B_CS_N<6>")
	)
	(segment
		(start 277.727156 -24.758904)
		(end 276.891496 -24.758904)
		(width 0.14224)
		(layer "In4.Cu")
		(net "M_B_CS_N<6>")
	)
	(segment
		(start 276.358096 -26.165556)
		(end 276.065234 -25.872694)
		(width 0.14224)
		(layer "In4.Cu")
		(net "M_B_CS_N<6>")
	)
	(segment
		(start 275.490432 -26.159968)
		(end 275.490432 -26.447496)
		(width 0.14224)
		(layer "In4.Cu")
		(net "M_B_CS_N<6>")
	)
	(segment
		(start 277.746968 -15.62227)
		(end 277.934928 -15.62227)
		(width 0.14224)
		(layer "In4.Cu")
		(net "M_B_CS_N<6>")
	)
	(segment
		(start 277.993856 -23.567644)
		(end 277.993856 -24.492204)
		(width 0.14224)
		(layer "In4.Cu")
		(net "M_B_CS_N<6>")
	)
	(segment
		(start 277.443438 -22.6949)
		(end 277.443438 -23.017226)
		(width 0.14224)
		(layer "In4.Cu")
		(net "M_B_CS_N<6>")
	)
	(segment
		(start 275.777706 -25.872694)
		(end 275.490432 -26.159968)
		(width 0.14224)
		(layer "In4.Cu")
		(net "M_B_CS_N<6>")
	)
	(segment
		(start 277.934928 -15.62227)
		(end 278.089868 -15.77721)
		(width 0.14224)
		(layer "In4.Cu")
		(net "M_B_CS_N<6>")
	)
	(segment
		(start 268.351 -49.784)
		(end 268.351 -51.181)
		(width 0.0889)
		(layer "In4.Cu")
		(net "M_B_CS_N<6>")
	)
	(segment
		(start 277.746968 -17.33042)
		(end 277.92426 -17.33042)
		(width 0.14224)
		(layer "In4.Cu")
		(net "M_B_CS_N<6>")
	)
	(segment
		(start 277.592028 -15.46733)
		(end 277.746968 -15.62227)
		(width 0.14224)
		(layer "In4.Cu")
		(net "M_B_CS_N<6>")
	)
	(segment
		(start 277.999952 -13.934186)
		(end 277.999952 -14.684248)
		(width 0.14224)
		(layer "In4.Cu")
		(net "M_B_CS_N<6>")
	)
	(segment
		(start 277.592028 -17.17548)
		(end 277.746968 -17.33042)
		(width 0.14224)
		(layer "In4.Cu")
		(net "M_B_CS_N<6>")
	)
	(segment
		(start 277.999952 -14.684248)
		(end 277.592028 -15.092172)
		(width 0.14224)
		(layer "In4.Cu")
		(net "M_B_CS_N<6>")
	)
	(segment
		(start 268.53515 -49.319688)
		(end 268.53515 -49.59985)
		(width 0.0889)
		(layer "In4.Cu")
		(net "M_B_CS_N<6>")
	)
	(segment
		(start 268.53515 -34.27603)
		(end 268.53515 -49.319688)
		(width 0.14224)
		(layer "In4.Cu")
		(net "M_B_CS_N<6>")
	)
	(segment
		(start 268.351 -51.181)
		(end 267.843 -51.689)
		(width 0.0889)
		(layer "In4.Cu")
		(net "M_B_CS_N<6>")
	)
	(segment
		(start 276.640036 -25.010364)
		(end 276.640036 -25.297892)
		(width 0.14224)
		(layer "In4.Cu")
		(net "M_B_CS_N<6>")
	)
	(segment
		(start 278.0792 -17.83842)
		(end 277.92426 -17.99336)
		(width 0.14224)
		(layer "In4.Cu")
		(net "M_B_CS_N<6>")
	)
	(segment
		(start 277.903178 -20.730972)
		(end 277.57628 -20.730972)
		(width 0.14224)
		(layer "In4.Cu")
		(net "M_B_CS_N<6>")
	)
	(segment
		(start 277.37181 -19.312382)
		(end 277.37181 -19.912838)
		(width 0.14224)
		(layer "In4.Cu")
		(net "M_B_CS_N<6>")
	)
	(segment
		(start 277.746968 -16.28521)
		(end 277.592028 -16.44015)
		(width 0.14224)
		(layer "In4.Cu")
		(net "M_B_CS_N<6>")
	)
	(segment
		(start 275.490432 -26.447496)
		(end 275.783294 -26.740358)
		(width 0.14224)
		(layer "In4.Cu")
		(net "M_B_CS_N<6>")
	)
	(segment
		(start 277.412196 -21.660866)
		(end 277.74138 -21.99005)
		(width 0.14224)
		(layer "In4.Cu")
		(net "M_B_CS_N<6>")
	)
	(segment
		(start 277.74138 -21.99005)
		(end 277.74138 -22.396958)
		(width 0.14224)
		(layer "In4.Cu")
		(net "M_B_CS_N<6>")
	)
	(segment
		(start 277.527004 -20.068032)
		(end 277.903178 -20.068032)
		(width 0.14224)
		(layer "In4.Cu")
		(net "M_B_CS_N<6>")
	)
	(segment
		(start 277.412196 -20.895056)
		(end 277.412196 -21.660866)
		(width 0.14224)
		(layer "In4.Cu")
		(net "M_B_CS_N<6>")
	)
	(segment
		(start 276.640036 -25.297892)
		(end 276.932898 -25.590754)
		(width 0.14224)
		(layer "In4.Cu")
		(net "M_B_CS_N<6>")
	)
	(segment
		(start 277.592028 -19.092164)
		(end 277.37181 -19.312382)
		(width 0.14224)
		(layer "In4.Cu")
		(net "M_B_CS_N<6>")
	)
	(segment
		(start 276.645624 -26.165556)
		(end 276.358096 -26.165556)
		(width 0.14224)
		(layer "In4.Cu")
		(net "M_B_CS_N<6>")
	)
	(segment
		(start 267.843 -51.689)
		(end 267.843 -54.990746)
		(width 0.0889)
		(layer "In4.Cu")
		(net "M_B_CS_N<6>")
	)
	(segment
		(start 277.57628 -20.730972)
		(end 277.412196 -20.895056)
		(width 0.14224)
		(layer "In4.Cu")
		(net "M_B_CS_N<6>")
	)
	(segment
		(start 277.903178 -20.068032)
		(end 278.058118 -20.222972)
		(width 0.14224)
		(layer "In4.Cu")
		(net "M_B_CS_N<6>")
	)
	(segment
		(start 277.443438 -23.017226)
		(end 277.993856 -23.567644)
		(width 0.14224)
		(layer "In4.Cu")
		(net "M_B_CS_N<6>")
	)
	(segment
		(start 278.058118 -20.576032)
		(end 277.903178 -20.730972)
		(width 0.14224)
		(layer "In4.Cu")
		(net "M_B_CS_N<6>")
	)
	(segment
		(start 267.843 -54.990746)
		(end 267.94714 -55.094886)
		(width 0.0889)
		(layer "In4.Cu")
		(net "M_B_CS_N<6>")
	)
	(segment
		(start 275.783294 -27.027886)
		(end 268.53515 -34.27603)
		(width 0.14224)
		(layer "In4.Cu")
		(net "M_B_CS_N<6>")
	)
	(segment
		(start 276.932898 -25.878282)
		(end 276.645624 -26.165556)
		(width 0.14224)
		(layer "In4.Cu")
		(net "M_B_CS_N<6>")
	)
	(segment
		(start 277.74138 -22.396958)
		(end 277.443438 -22.6949)
		(width 0.14224)
		(layer "In4.Cu")
		(net "M_B_CS_N<6>")
	)
	(segment
		(start 277.37181 -19.912838)
		(end 277.527004 -20.068032)
		(width 0.14224)
		(layer "In4.Cu")
		(net "M_B_CS_N<6>")
	)
	(segment
		(start 276.065234 -25.872694)
		(end 275.777706 -25.872694)
		(width 0.14224)
		(layer "In4.Cu")
		(net "M_B_CS_N<6>")
	)
	(segment
		(start 277.592028 -18.1483)
		(end 277.592028 -19.092164)
		(width 0.14224)
		(layer "In4.Cu")
		(net "M_B_CS_N<6>")
	)
	(segment
		(start 277.746968 -17.99336)
		(end 277.592028 -18.1483)
		(width 0.14224)
		(layer "In4.Cu")
		(net "M_B_CS_N<6>")
	)
	(segment
		(start 276.932898 -25.590754)
		(end 276.932898 -25.878282)
		(width 0.14224)
		(layer "In4.Cu")
		(net "M_B_CS_N<6>")
	)
	(segment
		(start 277.993856 -24.492204)
		(end 277.727156 -24.758904)
		(width 0.14224)
		(layer "In4.Cu")
		(net "M_B_CS_N<6>")
	)
	(segment
		(start 278.089868 -16.13027)
		(end 277.934928 -16.28521)
		(width 0.14224)
		(layer "In4.Cu")
		(net "M_B_CS_N<6>")
	)
	(segment
		(start 278.089868 -15.77721)
		(end 278.089868 -16.13027)
		(width 0.14224)
		(layer "In4.Cu")
		(net "M_B_CS_N<6>")
	)
	(segment
		(start 275.783294 -26.740358)
		(end 275.783294 -27.027886)
		(width 0.14224)
		(layer "In4.Cu")
		(net "M_B_CS_N<6>")
	)
	(segment
		(start 277.592028 -15.092172)
		(end 277.592028 -15.46733)
		(width 0.14224)
		(layer "In4.Cu")
		(net "M_B_CS_N<6>")
	)
	(segment
		(start 268.53515 -49.59985)
		(end 268.351 -49.784)
		(width 0.0889)
		(layer "In4.Cu")
		(net "M_B_CS_N<6>")
	)
	(segment
		(start 278.058118 -20.222972)
		(end 278.058118 -20.576032)
		(width 0.14224)
		(layer "In4.Cu")
		(net "M_B_CS_N<6>")
	)
	(segment
		(start 276.891496 -24.758904)
		(end 276.640036 -25.010364)
		(width 0.14224)
		(layer "In4.Cu")
		(net "M_B_CS_N<6>")
	)
	(segment
		(start 278.0792 -17.48536)
		(end 278.0792 -17.83842)
		(width 0.14224)
		(layer "In4.Cu")
		(net "M_B_CS_N<6>")
	)
	(segment
		(start 264.51433 -57.076086)
		(end 263.94283 -57.076086)
		(width 0.1016)
		(layer "F.Cu")
		(net "M_B_CS_N<5>")
	)
	(via
		(at 263.94283 -57.076086)
		(size 0.508)
		(drill 0.254)
		(layers "F.Cu" "B.Cu")
		(net "M_B_CS_N<5>")
	)
	(via
		(at 274.599908 -13.929868)
		(size 0.4572)
		(drill 0.2032)
		(layers "F.Cu" "B.Cu")
		(net "M_B_CS_N<5>")
	)
	(segment
		(start 274.599908 -15.222982)
		(end 274.599908 -13.929868)
		(width 0.1651)
		(layer "B.Cu")
		(net "M_B_CS_N<5>")
	)
	(segment
		(start 274.600416 -15.222982)
		(end 274.599908 -15.222982)
		(width 0.1651)
		(layer "B.Cu")
		(net "M_B_CS_N<5>")
	)
	(segment
		(start 266.48283 -32.73425)
		(end 271.399 -27.81808)
		(width 0.14224)
		(layer "In4.Cu")
		(net "M_B_CS_N<5>")
	)
	(segment
		(start 271.399 -26.0096)
		(end 273.1262 -24.2824)
		(width 0.14224)
		(layer "In4.Cu")
		(net "M_B_CS_N<5>")
	)
	(segment
		(start 265.9888 -51.177444)
		(end 266.48283 -50.683414)
		(width 0.0889)
		(layer "In4.Cu")
		(net "M_B_CS_N<5>")
	)
	(segment
		(start 273.449034 -21.68144)
		(end 273.449034 -21.11629)
		(width 0.14224)
		(layer "In4.Cu")
		(net "M_B_CS_N<5>")
	)
	(segment
		(start 273.336512 -21.003768)
		(end 273.336512 -15.193264)
		(width 0.14224)
		(layer "In4.Cu")
		(net "M_B_CS_N<5>")
	)
	(segment
		(start 273.336512 -15.193264)
		(end 274.599908 -13.929868)
		(width 0.14224)
		(layer "In4.Cu")
		(net "M_B_CS_N<5>")
	)
	(segment
		(start 273.449034 -21.11629)
		(end 273.336512 -21.003768)
		(width 0.14224)
		(layer "In4.Cu")
		(net "M_B_CS_N<5>")
	)
	(segment
		(start 266.48283 -49.658778)
		(end 266.48283 -32.73425)
		(width 0.14224)
		(layer "In4.Cu")
		(net "M_B_CS_N<5>")
	)
	(segment
		(start 265.9888 -52.1208)
		(end 265.9888 -51.177444)
		(width 0.0889)
		(layer "In4.Cu")
		(net "M_B_CS_N<5>")
	)
	(segment
		(start 273.166078 -22.408896)
		(end 273.166078 -21.964396)
		(width 0.14224)
		(layer "In4.Cu")
		(net "M_B_CS_N<5>")
	)
	(segment
		(start 273.166078 -21.964396)
		(end 273.449034 -21.68144)
		(width 0.14224)
		(layer "In4.Cu")
		(net "M_B_CS_N<5>")
	)
	(segment
		(start 265.312906 -53.904388)
		(end 265.319256 -53.89372)
		(width 0.0889)
		(layer "In4.Cu")
		(net "M_B_CS_N<5>")
	)
	(segment
		(start 273.420078 -23.124668)
		(end 273.420078 -22.662896)
		(width 0.14224)
		(layer "In4.Cu")
		(net "M_B_CS_N<5>")
	)
	(segment
		(start 266.48283 -50.683414)
		(end 266.48283 -49.658778)
		(width 0.0889)
		(layer "In4.Cu")
		(net "M_B_CS_N<5>")
	)
	(segment
		(start 265.2395 -53.039772)
		(end 265.2395 -52.959)
		(width 0.0889)
		(layer "In4.Cu")
		(net "M_B_CS_N<5>")
	)
	(segment
		(start 264.439146 -56.408574)
		(end 264.45464 -56.381142)
		(width 0.0889)
		(layer "In4.Cu")
		(net "M_B_CS_N<5>")
	)
	(segment
		(start 264.46353 -55.805578)
		(end 264.45464 -55.790338)
		(width 0.0889)
		(layer "In4.Cu")
		(net "M_B_CS_N<5>")
	)
	(segment
		(start 264.801096 -55.19039)
		(end 264.818876 -55.19039)
		(width 0.0889)
		(layer "In4.Cu")
		(net "M_B_CS_N<5>")
	)
	(segment
		(start 271.399 -27.81808)
		(end 271.399 -26.0096)
		(width 0.14224)
		(layer "In4.Cu")
		(net "M_B_CS_N<5>")
	)
	(segment
		(start 273.1262 -24.2824)
		(end 273.1262 -23.418546)
		(width 0.14224)
		(layer "In4.Cu")
		(net "M_B_CS_N<5>")
	)
	(segment
		(start 273.420078 -22.662896)
		(end 273.166078 -22.408896)
		(width 0.14224)
		(layer "In4.Cu")
		(net "M_B_CS_N<5>")
	)
	(segment
		(start 263.94283 -57.076086)
		(end 264.439146 -56.408574)
		(width 0.0889)
		(layer "In4.Cu")
		(net "M_B_CS_N<5>")
	)
	(segment
		(start 265.302238 -52.807108)
		(end 265.9888 -52.1208)
		(width 0.0889)
		(layer "In4.Cu")
		(net "M_B_CS_N<5>")
	)
	(segment
		(start 273.1262 -23.418546)
		(end 273.420078 -23.124668)
		(width 0.14224)
		(layer "In4.Cu")
		(net "M_B_CS_N<5>")
	)
	(segment
		(start 265.30808 -53.913024)
		(end 265.312906 -53.904388)
		(width 0.0889)
		(layer "In4.Cu")
		(net "M_B_CS_N<5>")
	)
	(arc
		(start 265.319256 -53.89372)
		(mid 265.392054 -53.602957)
		(end 265.312906 -53.313838)
		(width 0.0889)
		(layer "In4.Cu")
		(net "M_B_CS_N<5>")
	)
	(arc
		(start 264.45464 -55.790338)
		(mid 264.454723 -55.390397)
		(end 264.801096 -55.19039)
		(width 0.0889)
		(layer "In4.Cu")
		(net "M_B_CS_N<5>")
	)
	(arc
		(start 264.45464 -56.381142)
		(mid 264.533829 -56.094527)
		(end 264.46353 -55.805578)
		(width 0.0889)
		(layer "In4.Cu")
		(net "M_B_CS_N<5>")
	)
	(arc
		(start 264.818876 -55.19039)
		(mid 265.317127 -54.88755)
		(end 265.312906 -54.304438)
		(width 0.0889)
		(layer "In4.Cu")
		(net "M_B_CS_N<5>")
	)
	(arc
		(start 265.312906 -54.304438)
		(mid 265.259436 -54.109375)
		(end 265.30808 -53.913024)
		(width 0.0889)
		(layer "In4.Cu")
		(net "M_B_CS_N<5>")
	)
	(arc
		(start 265.312906 -53.313838)
		(mid 265.2582 -53.18163)
		(end 265.2395 -53.039772)
		(width 0.0889)
		(layer "In4.Cu")
		(net "M_B_CS_N<5>")
	)
	(arc
		(start 265.2395 -52.959)
		(mid 265.255755 -52.876811)
		(end 265.302238 -52.807108)
		(width 0.0889)
		(layer "In4.Cu")
		(net "M_B_CS_N<5>")
	)
	(segment
		(start 263.65581 -53.60924)
		(end 263.08431 -53.60924)
		(width 0.1016)
		(layer "F.Cu")
		(net "M_B_CS_N<4>")
	)
	(via
		(at 263.08431 -53.60924)
		(size 0.508)
		(drill 0.254)
		(layers "F.Cu" "B.Cu")
		(net "M_B_CS_N<4>")
	)
	(via
		(at 270.350234 -13.933678)
		(size 0.4572)
		(drill 0.2032)
		(layers "F.Cu" "B.Cu")
		(net "M_B_CS_N<4>")
	)
	(segment
		(start 270.34998 -15.222982)
		(end 270.34998 -13.933932)
		(width 0.1651)
		(layer "B.Cu")
		(net "M_B_CS_N<4>")
	)
	(segment
		(start 270.350488 -15.222982)
		(end 270.34998 -15.222982)
		(width 0.1651)
		(layer "B.Cu")
		(net "M_B_CS_N<4>")
	)
	(segment
		(start 270.34998 -13.933932)
		(end 270.350234 -13.933678)
		(width 0.1651)
		(layer "B.Cu")
		(net "M_B_CS_N<4>")
	)
	(segment
		(start 267.6144 -25.8572)
		(end 269.128494 -24.343106)
		(width 0.14224)
		(layer "In4.Cu")
		(net "M_B_CS_N<4>")
	)
	(segment
		(start 264.1092 -51.308254)
		(end 264.1092 -49.149254)
		(width 0.0889)
		(layer "In4.Cu")
		(net "M_B_CS_N<4>")
	)
	(segment
		(start 268.947138 -21.06041)
		(end 269.087854 -20.919694)
		(width 0.14224)
		(layer "In4.Cu")
		(net "M_B_CS_N<4>")
	)
	(segment
		(start 269.024608 -22.554184)
		(end 269.120112 -22.45868)
		(width 0.14224)
		(layer "In4.Cu")
		(net "M_B_CS_N<4>")
	)
	(segment
		(start 264.1092 -49.149254)
		(end 264.191496 -49.066958)
		(width 0.0889)
		(layer "In4.Cu")
		(net "M_B_CS_N<4>")
	)
	(segment
		(start 265.166602 -29.372306)
		(end 265.454384 -29.084524)
		(width 0.14224)
		(layer "In4.Cu")
		(net "M_B_CS_N<4>")
	)
	(segment
		(start 269.120112 -22.45868)
		(end 269.120112 -21.952712)
		(width 0.14224)
		(layer "In4.Cu")
		(net "M_B_CS_N<4>")
	)
	(segment
		(start 269.087854 -18.391632)
		(end 269.2654 -18.214086)
		(width 0.14224)
		(layer "In4.Cu")
		(net "M_B_CS_N<4>")
	)
	(segment
		(start 265.421872 -29.914342)
		(end 265.166602 -29.659326)
		(width 0.14224)
		(layer "In4.Cu")
		(net "M_B_CS_N<4>")
	)
	(segment
		(start 266.316206 -28.509722)
		(end 266.316206 -28.222702)
		(width 0.14224)
		(layer "In4.Cu")
		(net "M_B_CS_N<4>")
	)
	(segment
		(start 265.454384 -29.084524)
		(end 265.741404 -29.084524)
		(width 0.14224)
		(layer "In4.Cu")
		(net "M_B_CS_N<4>")
	)
	(segment
		(start 267.6144 -27.95905)
		(end 267.6144 -25.8572)
		(width 0.14224)
		(layer "In4.Cu")
		(net "M_B_CS_N<4>")
	)
	(segment
		(start 264.491216 -30.427676)
		(end 265.195558 -30.427676)
		(width 0.14224)
		(layer "In4.Cu")
		(net "M_B_CS_N<4>")
	)
	(segment
		(start 269.090394 -15.193518)
		(end 270.350234 -13.933678)
		(width 0.14224)
		(layer "In4.Cu")
		(net "M_B_CS_N<4>")
	)
	(segment
		(start 266.316206 -28.222702)
		(end 266.603988 -27.93492)
		(width 0.14224)
		(layer "In4.Cu")
		(net "M_B_CS_N<4>")
	)
	(segment
		(start 266.603988 -27.93492)
		(end 266.891008 -27.93492)
		(width 0.14224)
		(layer "In4.Cu")
		(net "M_B_CS_N<4>")
	)
	(segment
		(start 264.191496 -48.848264)
		(end 264.191496 -30.727396)
		(width 0.14224)
		(layer "In4.Cu")
		(net "M_B_CS_N<4>")
	)
	(segment
		(start 269.2654 -18.214086)
		(end 269.2654 -17.26819)
		(width 0.14224)
		(layer "In4.Cu")
		(net "M_B_CS_N<4>")
	)
	(segment
		(start 266.571476 -28.764738)
		(end 266.316206 -28.509722)
		(width 0.14224)
		(layer "In4.Cu")
		(net "M_B_CS_N<4>")
	)
	(segment
		(start 265.195558 -30.427676)
		(end 265.421872 -30.201362)
		(width 0.14224)
		(layer "In4.Cu")
		(net "M_B_CS_N<4>")
	)
	(segment
		(start 266.571476 -29.051758)
		(end 266.571476 -28.764738)
		(width 0.14224)
		(layer "In4.Cu")
		(net "M_B_CS_N<4>")
	)
	(segment
		(start 269.128494 -23.307294)
		(end 269.024608 -23.203408)
		(width 0.14224)
		(layer "In4.Cu")
		(net "M_B_CS_N<4>")
	)
	(segment
		(start 267.412978 -28.160472)
		(end 267.6144 -27.95905)
		(width 0.14224)
		(layer "In4.Cu")
		(net "M_B_CS_N<4>")
	)
	(segment
		(start 266.283694 -29.33954)
		(end 266.571476 -29.051758)
		(width 0.14224)
		(layer "In4.Cu")
		(net "M_B_CS_N<4>")
	)
	(segment
		(start 263.485884 -52.723542)
		(end 263.485884 -51.93157)
		(width 0.0889)
		(layer "In4.Cu")
		(net "M_B_CS_N<4>")
	)
	(segment
		(start 264.191496 -49.066958)
		(end 264.191496 -48.848264)
		(width 0.0889)
		(layer "In4.Cu")
		(net "M_B_CS_N<4>")
	)
	(segment
		(start 269.024608 -23.203408)
		(end 269.024608 -22.554184)
		(width 0.14224)
		(layer "In4.Cu")
		(net "M_B_CS_N<4>")
	)
	(segment
		(start 263.414256 -52.84724)
		(end 263.485884 -52.723542)
		(width 0.0889)
		(layer "In4.Cu")
		(net "M_B_CS_N<4>")
	)
	(segment
		(start 265.996674 -29.33954)
		(end 266.283694 -29.33954)
		(width 0.14224)
		(layer "In4.Cu")
		(net "M_B_CS_N<4>")
	)
	(segment
		(start 265.421872 -30.201362)
		(end 265.421872 -29.914342)
		(width 0.14224)
		(layer "In4.Cu")
		(net "M_B_CS_N<4>")
	)
	(segment
		(start 269.120112 -21.952712)
		(end 268.947138 -21.779738)
		(width 0.14224)
		(layer "In4.Cu")
		(net "M_B_CS_N<4>")
	)
	(segment
		(start 269.087854 -20.919694)
		(end 269.087854 -18.391632)
		(width 0.14224)
		(layer "In4.Cu")
		(net "M_B_CS_N<4>")
	)
	(segment
		(start 267.11656 -28.160472)
		(end 267.412978 -28.160472)
		(width 0.14224)
		(layer "In4.Cu")
		(net "M_B_CS_N<4>")
	)
	(segment
		(start 264.191496 -30.727396)
		(end 264.491216 -30.427676)
		(width 0.14224)
		(layer "In4.Cu")
		(net "M_B_CS_N<4>")
	)
	(segment
		(start 266.891008 -27.93492)
		(end 267.11656 -28.160472)
		(width 0.14224)
		(layer "In4.Cu")
		(net "M_B_CS_N<4>")
	)
	(segment
		(start 265.741404 -29.084524)
		(end 265.996674 -29.33954)
		(width 0.14224)
		(layer "In4.Cu")
		(net "M_B_CS_N<4>")
	)
	(segment
		(start 269.128494 -24.343106)
		(end 269.128494 -23.307294)
		(width 0.14224)
		(layer "In4.Cu")
		(net "M_B_CS_N<4>")
	)
	(segment
		(start 269.090394 -17.093184)
		(end 269.090394 -15.193518)
		(width 0.14224)
		(layer "In4.Cu")
		(net "M_B_CS_N<4>")
	)
	(segment
		(start 269.2654 -17.26819)
		(end 269.090394 -17.093184)
		(width 0.14224)
		(layer "In4.Cu")
		(net "M_B_CS_N<4>")
	)
	(segment
		(start 268.947138 -21.779738)
		(end 268.947138 -21.06041)
		(width 0.14224)
		(layer "In4.Cu")
		(net "M_B_CS_N<4>")
	)
	(segment
		(start 263.08431 -53.60924)
		(end 263.414256 -52.84724)
		(width 0.0889)
		(layer "In4.Cu")
		(net "M_B_CS_N<4>")
	)
	(segment
		(start 265.166602 -29.659326)
		(end 265.166602 -29.372306)
		(width 0.14224)
		(layer "In4.Cu")
		(net "M_B_CS_N<4>")
	)
	(segment
		(start 263.485884 -51.93157)
		(end 264.1092 -51.308254)
		(width 0.0889)
		(layer "In4.Cu")
		(net "M_B_CS_N<4>")
	)
	(segment
		(start 266.231116 -58.06694)
		(end 265.659616 -58.06694)
		(width 0.1016)
		(layer "F.Cu")
		(net "M_B_CS_N<3>")
	)
	(segment
		(start 277.999952 -9.133586)
		(end 278.00046 -9.133078)
		(width 0.1651)
		(layer "F.Cu")
		(net "M_B_CS_N<3>")
	)
	(segment
		(start 278.00046 -10.422382)
		(end 277.999952 -10.422382)
		(width 0.1651)
		(layer "F.Cu")
		(net "M_B_CS_N<3>")
	)
	(segment
		(start 277.999952 -10.422382)
		(end 277.999952 -9.133586)
		(width 0.1651)
		(layer "F.Cu")
		(net "M_B_CS_N<3>")
	)
	(via
		(at 278.00046 -9.133078)
		(size 0.4572)
		(drill 0.2032)
		(layers "F.Cu" "B.Cu")
		(net "M_B_CS_N<3>")
	)
	(via
		(at 265.659616 -58.06694)
		(size 0.508)
		(drill 0.254)
		(layers "F.Cu" "B.Cu")
		(net "M_B_CS_N<3>")
	)
	(segment
		(start 276.8092 -18.2626)
		(end 276.8092 -17.8054)
		(width 0.14224)
		(layer "In4.Cu")
		(net "M_B_CS_N<3>")
	)
	(segment
		(start 276.571964 -22.317964)
		(end 276.571964 -22.030436)
		(width 0.14224)
		(layer "In4.Cu")
		(net "M_B_CS_N<3>")
	)
	(segment
		(start 276.62124 -24.218646)
		(end 276.62124 -23.30196)
		(width 0.14224)
		(layer "In4.Cu")
		(net "M_B_CS_N<3>")
	)
	(segment
		(start 276.8092 -17.8054)
		(end 276.5806 -17.5768)
		(width 0.14224)
		(layer "In4.Cu")
		(net "M_B_CS_N<3>")
	)
	(segment
		(start 266.171426 -56.780938)
		(end 266.1666 -56.772302)
		(width 0.0889)
		(layer "In4.Cu")
		(net "M_B_CS_N<3>")
	)
	(segment
		(start 274.701 -26.138886)
		(end 276.62124 -24.218646)
		(width 0.14224)
		(layer "In4.Cu")
		(net "M_B_CS_N<3>")
	)
	(segment
		(start 266.177776 -56.791606)
		(end 266.171426 -56.780938)
		(width 0.0889)
		(layer "In4.Cu")
		(net "M_B_CS_N<3>")
	)
	(segment
		(start 276.8854 -22.6314)
		(end 276.571964 -22.317964)
		(width 0.14224)
		(layer "In4.Cu")
		(net "M_B_CS_N<3>")
	)
	(segment
		(start 277.4442 -13.3604)
		(end 277.4442 -12.43838)
		(width 0.14224)
		(layer "In4.Cu")
		(net "M_B_CS_N<3>")
	)
	(segment
		(start 276.8854 -23.0378)
		(end 276.8854 -22.6314)
		(width 0.14224)
		(layer "In4.Cu")
		(net "M_B_CS_N<3>")
	)
	(segment
		(start 277.587456 -9.546082)
		(end 278.00046 -9.133078)
		(width 0.14224)
		(layer "In4.Cu")
		(net "M_B_CS_N<3>")
	)
	(segment
		(start 265.659616 -58.06694)
		(end 266.154662 -57.400698)
		(width 0.0889)
		(layer "In4.Cu")
		(net "M_B_CS_N<3>")
	)
	(segment
		(start 276.8346 -19.0754)
		(end 276.716744 -18.957544)
		(width 0.14224)
		(layer "In4.Cu")
		(net "M_B_CS_N<3>")
	)
	(segment
		(start 266.55141 -56.18099)
		(end 267.489432 -55.242968)
		(width 0.0889)
		(layer "In4.Cu")
		(net "M_B_CS_N<3>")
	)
	(segment
		(start 276.5806 -17.145)
		(end 276.712426 -17.013174)
		(width 0.14224)
		(layer "In4.Cu")
		(net "M_B_CS_N<3>")
	)
	(segment
		(start 277.587456 -13.503656)
		(end 277.4442 -13.3604)
		(width 0.14224)
		(layer "In4.Cu")
		(net "M_B_CS_N<3>")
	)
	(segment
		(start 276.716744 -18.957544)
		(end 276.716744 -18.355056)
		(width 0.14224)
		(layer "In4.Cu")
		(net "M_B_CS_N<3>")
	)
	(segment
		(start 277.4442 -12.43838)
		(end 277.587456 -12.092178)
		(width 0.14224)
		(layer "In4.Cu")
		(net "M_B_CS_N<3>")
	)
	(segment
		(start 276.5806 -17.5768)
		(end 276.5806 -17.145)
		(width 0.14224)
		(layer "In4.Cu")
		(net "M_B_CS_N<3>")
	)
	(segment
		(start 268.1224 -33.96996)
		(end 274.701 -27.39136)
		(width 0.14224)
		(layer "In4.Cu")
		(net "M_B_CS_N<3>")
	)
	(segment
		(start 276.716744 -18.355056)
		(end 276.8092 -18.2626)
		(width 0.14224)
		(layer "In4.Cu")
		(net "M_B_CS_N<3>")
	)
	(segment
		(start 276.571964 -22.030436)
		(end 276.8346 -21.7678)
		(width 0.14224)
		(layer "In4.Cu")
		(net "M_B_CS_N<3>")
	)
	(segment
		(start 266.154662 -57.400698)
		(end 266.171426 -57.371488)
		(width 0.0889)
		(layer "In4.Cu")
		(net "M_B_CS_N<3>")
	)
	(segment
		(start 276.62124 -23.30196)
		(end 276.8854 -23.0378)
		(width 0.14224)
		(layer "In4.Cu")
		(net "M_B_CS_N<3>")
	)
	(segment
		(start 267.489432 -51.534822)
		(end 268.1224 -50.901854)
		(width 0.0889)
		(layer "In4.Cu")
		(net "M_B_CS_N<3>")
	)
	(segment
		(start 276.712426 -17.013174)
		(end 276.712426 -15.209774)
		(width 0.14224)
		(layer "In4.Cu")
		(net "M_B_CS_N<3>")
	)
	(segment
		(start 274.701 -27.39136)
		(end 274.701 -26.138886)
		(width 0.14224)
		(layer "In4.Cu")
		(net "M_B_CS_N<3>")
	)
	(segment
		(start 268.1224 -49.368964)
		(end 268.1224 -33.96996)
		(width 0.14224)
		(layer "In4.Cu")
		(net "M_B_CS_N<3>")
	)
	(segment
		(start 277.587456 -12.092178)
		(end 277.587456 -9.546082)
		(width 0.14224)
		(layer "In4.Cu")
		(net "M_B_CS_N<3>")
	)
	(segment
		(start 267.489432 -55.242968)
		(end 267.489432 -51.534822)
		(width 0.0889)
		(layer "In4.Cu")
		(net "M_B_CS_N<3>")
	)
	(segment
		(start 276.712426 -15.209774)
		(end 277.587456 -14.334744)
		(width 0.14224)
		(layer "In4.Cu")
		(net "M_B_CS_N<3>")
	)
	(segment
		(start 276.8346 -21.7678)
		(end 276.8346 -19.0754)
		(width 0.14224)
		(layer "In4.Cu")
		(net "M_B_CS_N<3>")
	)
	(segment
		(start 266.50315 -56.18099)
		(end 266.55141 -56.18099)
		(width 0.0889)
		(layer "In4.Cu")
		(net "M_B_CS_N<3>")
	)
	(segment
		(start 277.587456 -14.334744)
		(end 277.587456 -13.503656)
		(width 0.14224)
		(layer "In4.Cu")
		(net "M_B_CS_N<3>")
	)
	(segment
		(start 268.1224 -50.901854)
		(end 268.1224 -49.368964)
		(width 0.0889)
		(layer "In4.Cu")
		(net "M_B_CS_N<3>")
	)
	(arc
		(start 266.171426 -57.371488)
		(mid 266.250648 -57.08237)
		(end 266.177776 -56.791606)
		(width 0.0889)
		(layer "In4.Cu")
		(net "M_B_CS_N<3>")
	)
	(arc
		(start 266.1666 -56.772302)
		(mid 266.170347 -56.383046)
		(end 266.50315 -56.18099)
		(width 0.0889)
		(layer "In4.Cu")
		(net "M_B_CS_N<3>")
	)
	(segment
		(start 277.999952 -5.822442)
		(end 277.999952 -7.117588)
		(width 0.1651)
		(layer "F.Cu")
		(net "M_B_CS_N<2>")
	)
	(segment
		(start 278.00046 -5.822442)
		(end 277.999952 -5.822442)
		(width 0.1651)
		(layer "F.Cu")
		(net "M_B_CS_N<2>")
	)
	(segment
		(start 267.089636 -55.59044)
		(end 266.518136 -55.59044)
		(width 0.1016)
		(layer "F.Cu")
		(net "M_B_CS_N<2>")
	)
	(via
		(at 266.518136 -55.59044)
		(size 0.508)
		(drill 0.254)
		(layers "F.Cu" "B.Cu")
		(net "M_B_CS_N<2>")
	)
	(via
		(at 277.999952 -7.117588)
		(size 0.4572)
		(drill 0.2032)
		(layers "F.Cu" "B.Cu")
		(net "M_B_CS_N<2>")
	)
	(segment
		(start 276.712934 -8.910066)
		(end 277.999952 -7.623048)
		(width 0.14224)
		(layer "In4.Cu")
		(net "M_B_CS_N<2>")
	)
	(segment
		(start 267.706094 -33.667446)
		(end 274.1676 -27.20594)
		(width 0.14224)
		(layer "In4.Cu")
		(net "M_B_CS_N<2>")
	)
	(segment
		(start 275.9202 -23.2156)
		(end 275.7678 -23.0632)
		(width 0.14224)
		(layer "In4.Cu")
		(net "M_B_CS_N<2>")
	)
	(segment
		(start 275.8694 -21.082)
		(end 275.8694 -18.415)
		(width 0.14224)
		(layer "In4.Cu")
		(net "M_B_CS_N<2>")
	)
	(segment
		(start 276.710902 -12.600432)
		(end 276.712934 -12.5984)
		(width 0.14224)
		(layer "In4.Cu")
		(net "M_B_CS_N<2>")
	)
	(segment
		(start 275.7424 -21.717)
		(end 275.7424 -21.209)
		(width 0.14224)
		(layer "In4.Cu")
		(net "M_B_CS_N<2>")
	)
	(segment
		(start 267.706094 -49.664874)
		(end 267.706094 -33.667446)
		(width 0.14224)
		(layer "In4.Cu")
		(net "M_B_CS_N<2>")
	)
	(segment
		(start 275.7424 -21.209)
		(end 275.8694 -21.082)
		(width 0.14224)
		(layer "In4.Cu")
		(net "M_B_CS_N<2>")
	)
	(segment
		(start 267.298932 -50.382932)
		(end 267.706094 -49.97577)
		(width 0.0889)
		(layer "In4.Cu")
		(net "M_B_CS_N<2>")
	)
	(segment
		(start 275.9202 -24.20112)
		(end 275.9202 -23.2156)
		(width 0.14224)
		(layer "In4.Cu")
		(net "M_B_CS_N<2>")
	)
	(segment
		(start 275.9456 -17.653)
		(end 275.9456 -17.145)
		(width 0.14224)
		(layer "In4.Cu")
		(net "M_B_CS_N<2>")
	)
	(segment
		(start 275.8694 -18.415)
		(end 275.7424 -18.288)
		(width 0.14224)
		(layer "In4.Cu")
		(net "M_B_CS_N<2>")
	)
	(segment
		(start 274.1676 -25.95372)
		(end 275.9202 -24.20112)
		(width 0.14224)
		(layer "In4.Cu")
		(net "M_B_CS_N<2>")
	)
	(segment
		(start 275.9456 -17.145)
		(end 275.886164 -17.085564)
		(width 0.14224)
		(layer "In4.Cu")
		(net "M_B_CS_N<2>")
	)
	(segment
		(start 277.999952 -7.623048)
		(end 277.999952 -7.117588)
		(width 0.14224)
		(layer "In4.Cu")
		(net "M_B_CS_N<2>")
	)
	(segment
		(start 275.971 -21.9456)
		(end 275.7424 -21.717)
		(width 0.14224)
		(layer "In4.Cu")
		(net "M_B_CS_N<2>")
	)
	(segment
		(start 275.971 -22.479)
		(end 275.971 -21.9456)
		(width 0.14224)
		(layer "In4.Cu")
		(net "M_B_CS_N<2>")
	)
	(segment
		(start 275.7678 -22.6822)
		(end 275.971 -22.479)
		(width 0.14224)
		(layer "In4.Cu")
		(net "M_B_CS_N<2>")
	)
	(segment
		(start 266.518136 -55.59044)
		(end 267.298932 -54.809644)
		(width 0.0889)
		(layer "In4.Cu")
		(net "M_B_CS_N<2>")
	)
	(segment
		(start 275.886164 -17.085564)
		(end 275.886164 -15.22222)
		(width 0.14224)
		(layer "In4.Cu")
		(net "M_B_CS_N<2>")
	)
	(segment
		(start 275.886164 -15.22222)
		(end 276.710902 -14.397482)
		(width 0.14224)
		(layer "In4.Cu")
		(net "M_B_CS_N<2>")
	)
	(segment
		(start 276.712934 -12.5984)
		(end 276.712934 -8.910066)
		(width 0.14224)
		(layer "In4.Cu")
		(net "M_B_CS_N<2>")
	)
	(segment
		(start 275.7424 -17.8562)
		(end 275.9456 -17.653)
		(width 0.14224)
		(layer "In4.Cu")
		(net "M_B_CS_N<2>")
	)
	(segment
		(start 275.7678 -23.0632)
		(end 275.7678 -22.6822)
		(width 0.14224)
		(layer "In4.Cu")
		(net "M_B_CS_N<2>")
	)
	(segment
		(start 267.706094 -49.97577)
		(end 267.706094 -49.664874)
		(width 0.0889)
		(layer "In4.Cu")
		(net "M_B_CS_N<2>")
	)
	(segment
		(start 274.1676 -27.20594)
		(end 274.1676 -25.95372)
		(width 0.14224)
		(layer "In4.Cu")
		(net "M_B_CS_N<2>")
	)
	(segment
		(start 276.710902 -14.397482)
		(end 276.710902 -12.600432)
		(width 0.14224)
		(layer "In4.Cu")
		(net "M_B_CS_N<2>")
	)
	(segment
		(start 267.298932 -54.809644)
		(end 267.298932 -50.382932)
		(width 0.0889)
		(layer "In4.Cu")
		(net "M_B_CS_N<2>")
	)
	(segment
		(start 275.7424 -18.288)
		(end 275.7424 -17.8562)
		(width 0.14224)
		(layer "In4.Cu")
		(net "M_B_CS_N<2>")
	)
	(segment
		(start 263.65581 -56.58104)
		(end 263.08431 -56.58104)
		(width 0.1016)
		(layer "F.Cu")
		(net "M_B_CS_N<1>")
	)
	(segment
		(start 274.600416 -5.822442)
		(end 274.599908 -5.822442)
		(width 0.1651)
		(layer "F.Cu")
		(net "M_B_CS_N<1>")
	)
	(segment
		(start 274.599908 -5.822442)
		(end 274.599908 -7.113778)
		(width 0.1651)
		(layer "F.Cu")
		(net "M_B_CS_N<1>")
	)
	(via
		(at 274.599908 -7.113778)
		(size 0.508)
		(drill 0.254)
		(layers "F.Cu" "B.Cu")
		(net "M_B_CS_N<1>")
	)
	(via
		(at 263.08431 -56.58104)
		(size 0.508)
		(drill 0.254)
		(layers "F.Cu" "B.Cu")
		(net "M_B_CS_N<1>")
	)
	(segment
		(start 272.363184 -22.61489)
		(end 272.521426 -22.456648)
		(width 0.14224)
		(layer "In4.Cu")
		(net "M_B_CS_N<1>")
	)
	(segment
		(start 272.6182 -23.372318)
		(end 272.363184 -23.117302)
		(width 0.14224)
		(layer "In4.Cu")
		(net "M_B_CS_N<1>")
	)
	(segment
		(start 263.92505 -55.494936)
		(end 263.94283 -55.494936)
		(width 0.0889)
		(layer "In4.Cu")
		(net "M_B_CS_N<1>")
	)
	(segment
		(start 272.604738 -18.026126)
		(end 272.604738 -17.132046)
		(width 0.14224)
		(layer "In4.Cu")
		(net "M_B_CS_N<1>")
	)
	(segment
		(start 272.363184 -23.117302)
		(end 272.363184 -22.61489)
		(width 0.14224)
		(layer "In4.Cu")
		(net "M_B_CS_N<1>")
	)
	(segment
		(start 272.461736 -18.169128)
		(end 272.604738 -18.026126)
		(width 0.14224)
		(layer "In4.Cu")
		(net "M_B_CS_N<1>")
	)
	(segment
		(start 264.285984 -55.300626)
		(end 264.289286 -55.294784)
		(width 0.0889)
		(layer "In4.Cu")
		(net "M_B_CS_N<1>")
	)
	(segment
		(start 272.604738 -17.132046)
		(end 272.4658 -16.993108)
		(width 0.14224)
		(layer "In4.Cu")
		(net "M_B_CS_N<1>")
	)
	(segment
		(start 272.521426 -21.903944)
		(end 272.357596 -21.740114)
		(width 0.14224)
		(layer "In4.Cu")
		(net "M_B_CS_N<1>")
	)
	(segment
		(start 273.310604 -13.633196)
		(end 273.339814 -13.603986)
		(width 0.14224)
		(layer "In4.Cu")
		(net "M_B_CS_N<1>")
	)
	(segment
		(start 272.461736 -19.308064)
		(end 272.461736 -18.169128)
		(width 0.14224)
		(layer "In4.Cu")
		(net "M_B_CS_N<1>")
	)
	(segment
		(start 272.4658 -16.993108)
		(end 272.4658 -14.9606)
		(width 0.14224)
		(layer "In4.Cu")
		(net "M_B_CS_N<1>")
	)
	(segment
		(start 265.049 -53.040026)
		(end 265.049 -52.8066)
		(width 0.0889)
		(layer "In4.Cu")
		(net "M_B_CS_N<1>")
	)
	(segment
		(start 273.339814 -8.879586)
		(end 274.599908 -7.619492)
		(width 0.14224)
		(layer "In4.Cu")
		(net "M_B_CS_N<1>")
	)
	(segment
		(start 265.138916 -52.589176)
		(end 265.7602 -51.968146)
		(width 0.0889)
		(layer "In4.Cu")
		(net "M_B_CS_N<1>")
	)
	(segment
		(start 265.7602 -51.136296)
		(end 266.070588 -50.825908)
		(width 0.0889)
		(layer "In4.Cu")
		(net "M_B_CS_N<1>")
	)
	(segment
		(start 266.070588 -32.427672)
		(end 270.872966 -27.625294)
		(width 0.14224)
		(layer "In4.Cu")
		(net "M_B_CS_N<1>")
	)
	(segment
		(start 266.070588 -50.825908)
		(end 266.070588 -49.63414)
		(width 0.0889)
		(layer "In4.Cu")
		(net "M_B_CS_N<1>")
	)
	(segment
		(start 273.339814 -13.603986)
		(end 273.339814 -8.879586)
		(width 0.14224)
		(layer "In4.Cu")
		(net "M_B_CS_N<1>")
	)
	(segment
		(start 263.413748 -55.820056)
		(end 263.43102 -55.790338)
		(width 0.0889)
		(layer "In4.Cu")
		(net "M_B_CS_N<1>")
	)
	(segment
		(start 272.357596 -21.740114)
		(end 272.357596 -19.412204)
		(width 0.14224)
		(layer "In4.Cu")
		(net "M_B_CS_N<1>")
	)
	(segment
		(start 272.357596 -19.412204)
		(end 272.461736 -19.308064)
		(width 0.14224)
		(layer "In4.Cu")
		(net "M_B_CS_N<1>")
	)
	(segment
		(start 272.6182 -24.0284)
		(end 272.6182 -23.372318)
		(width 0.14224)
		(layer "In4.Cu")
		(net "M_B_CS_N<1>")
	)
	(segment
		(start 265.141456 -53.819806)
		(end 265.147806 -53.809138)
		(width 0.0889)
		(layer "In4.Cu")
		(net "M_B_CS_N<1>")
	)
	(segment
		(start 265.7602 -51.968146)
		(end 265.7602 -51.136296)
		(width 0.0889)
		(layer "In4.Cu")
		(net "M_B_CS_N<1>")
	)
	(segment
		(start 265.147806 -53.809138)
		(end 265.152632 -53.800502)
		(width 0.0889)
		(layer "In4.Cu")
		(net "M_B_CS_N<1>")
	)
	(segment
		(start 263.08431 -56.58104)
		(end 263.413748 -55.820056)
		(width 0.0889)
		(layer "In4.Cu")
		(net "M_B_CS_N<1>")
	)
	(segment
		(start 266.070588 -49.63414)
		(end 266.070588 -32.427672)
		(width 0.14224)
		(layer "In4.Cu")
		(net "M_B_CS_N<1>")
	)
	(segment
		(start 272.521426 -22.456648)
		(end 272.521426 -21.903944)
		(width 0.14224)
		(layer "In4.Cu")
		(net "M_B_CS_N<1>")
	)
	(segment
		(start 273.310604 -14.115796)
		(end 273.310604 -13.633196)
		(width 0.14224)
		(layer "In4.Cu")
		(net "M_B_CS_N<1>")
	)
	(segment
		(start 270.872966 -27.625294)
		(end 270.872966 -25.773634)
		(width 0.14224)
		(layer "In4.Cu")
		(net "M_B_CS_N<1>")
	)
	(segment
		(start 274.599908 -7.619492)
		(end 274.599908 -7.113778)
		(width 0.14224)
		(layer "In4.Cu")
		(net "M_B_CS_N<1>")
	)
	(segment
		(start 270.872966 -25.773634)
		(end 272.6182 -24.0284)
		(width 0.14224)
		(layer "In4.Cu")
		(net "M_B_CS_N<1>")
	)
	(segment
		(start 264.776204 -54.99989)
		(end 264.812272 -54.99989)
		(width 0.0889)
		(layer "In4.Cu")
		(net "M_B_CS_N<1>")
	)
	(segment
		(start 272.4658 -14.9606)
		(end 273.310604 -14.115796)
		(width 0.14224)
		(layer "In4.Cu")
		(net "M_B_CS_N<1>")
	)
	(arc
		(start 264.812272 -54.99989)
		(mid 265.150441 -54.795092)
		(end 265.147806 -54.399688)
		(width 0.0889)
		(layer "In4.Cu")
		(net "M_B_CS_N<1>")
	)
	(arc
		(start 263.94283 -55.494936)
		(mid 264.139991 -55.442977)
		(end 264.285984 -55.300626)
		(width 0.0889)
		(layer "In4.Cu")
		(net "M_B_CS_N<1>")
	)
	(arc
		(start 265.049 -52.8066)
		(mid 265.072312 -52.688932)
		(end 265.138916 -52.589176)
		(width 0.0889)
		(layer "In4.Cu")
		(net "M_B_CS_N<1>")
	)
	(arc
		(start 265.147806 -54.399688)
		(mid 265.068584 -54.11057)
		(end 265.141456 -53.819806)
		(width 0.0889)
		(layer "In4.Cu")
		(net "M_B_CS_N<1>")
	)
	(arc
		(start 264.289286 -55.294784)
		(mid 264.494907 -55.084861)
		(end 264.776204 -54.99989)
		(width 0.0889)
		(layer "In4.Cu")
		(net "M_B_CS_N<1>")
	)
	(arc
		(start 265.152632 -53.800502)
		(mid 265.201387 -53.60415)
		(end 265.147806 -53.409088)
		(width 0.0889)
		(layer "In4.Cu")
		(net "M_B_CS_N<1>")
	)
	(arc
		(start 265.147806 -53.409088)
		(mid 265.074176 -53.231048)
		(end 265.049 -53.040026)
		(width 0.0889)
		(layer "In4.Cu")
		(net "M_B_CS_N<1>")
	)
	(arc
		(start 263.43102 -55.790338)
		(mid 263.639628 -55.578406)
		(end 263.92505 -55.494936)
		(width 0.0889)
		(layer "In4.Cu")
		(net "M_B_CS_N<1>")
	)
	(segment
		(start 270.34998 -7.117334)
		(end 270.350234 -7.117588)
		(width 0.1651)
		(layer "F.Cu")
		(net "M_B_CS_N<0>")
	)
	(segment
		(start 270.34998 -5.822442)
		(end 270.34998 -7.117334)
		(width 0.1651)
		(layer "F.Cu")
		(net "M_B_CS_N<0>")
	)
	(segment
		(start 270.350488 -5.822442)
		(end 270.34998 -5.822442)
		(width 0.1651)
		(layer "F.Cu")
		(net "M_B_CS_N<0>")
	)
	(segment
		(start 262.79729 -54.104286)
		(end 262.22579 -54.104286)
		(width 0.1016)
		(layer "F.Cu")
		(net "M_B_CS_N<0>")
	)
	(via
		(at 270.350234 -7.117588)
		(size 0.4572)
		(drill 0.2032)
		(layers "F.Cu" "B.Cu")
		(net "M_B_CS_N<0>")
	)
	(via
		(at 262.22579 -54.104286)
		(size 0.508)
		(drill 0.254)
		(layers "F.Cu" "B.Cu")
		(net "M_B_CS_N<0>")
	)
	(segment
		(start 268.1732 -28.168854)
		(end 268.1732 -26.035)
		(width 0.14224)
		(layer "In4.Cu")
		(net "M_B_CS_N<0>")
	)
	(segment
		(start 263.591294 -52.922424)
		(end 263.59612 -52.913788)
		(width 0.0889)
		(layer "In4.Cu")
		(net "M_B_CS_N<0>")
	)
	(segment
		(start 270.350234 -8.185912)
		(end 270.350234 -7.117588)
		(width 0.14224)
		(layer "In4.Cu")
		(net "M_B_CS_N<0>")
	)
	(segment
		(start 264.61466 -51.18354)
		(end 264.61466 -50.293524)
		(width 0.0889)
		(layer "In4.Cu")
		(net "M_B_CS_N<0>")
	)
	(segment
		(start 271.642078 -11.442954)
		(end 271.801082 -11.28395)
		(width 0.14224)
		(layer "In4.Cu")
		(net "M_B_CS_N<0>")
	)
	(segment
		(start 263.59612 -52.913788)
		(end 263.7282 -52.705508)
		(width 0.0889)
		(layer "In4.Cu")
		(net "M_B_CS_N<0>")
	)
	(segment
		(start 269.942056 -18.356326)
		(end 269.942056 -16.450056)
		(width 0.14224)
		(layer "In4.Cu")
		(net "M_B_CS_N<0>")
	)
	(segment
		(start 269.909036 -18.389346)
		(end 269.942056 -18.356326)
		(width 0.14224)
		(layer "In4.Cu")
		(net "M_B_CS_N<0>")
	)
	(segment
		(start 271.642078 -9.39673)
		(end 271.642078 -8.383524)
		(width 0.14224)
		(layer "In4.Cu")
		(net "M_B_CS_N<0>")
	)
	(segment
		(start 269.942056 -16.450056)
		(end 269.877032 -16.385032)
		(width 0.14224)
		(layer "In4.Cu")
		(net "M_B_CS_N<0>")
	)
	(segment
		(start 270.76146 -13.041376)
		(end 271.642078 -12.160758)
		(width 0.14224)
		(layer "In4.Cu")
		(net "M_B_CS_N<0>")
	)
	(segment
		(start 264.386568 -50.065432)
		(end 264.386568 -49.338484)
		(width 0.0889)
		(layer "In4.Cu")
		(net "M_B_CS_N<0>")
	)
	(segment
		(start 269.877032 -15.187168)
		(end 270.76146 -14.30274)
		(width 0.14224)
		(layer "In4.Cu")
		(net "M_B_CS_N<0>")
	)
	(segment
		(start 270.76146 -14.30274)
		(end 270.76146 -13.041376)
		(width 0.14224)
		(layer "In4.Cu")
		(net "M_B_CS_N<0>")
	)
	(segment
		(start 269.892526 -22.496526)
		(end 269.892526 -21.864066)
		(width 0.14224)
		(layer "In4.Cu")
		(net "M_B_CS_N<0>")
	)
	(segment
		(start 269.957042 -22.561042)
		(end 269.892526 -22.496526)
		(width 0.14224)
		(layer "In4.Cu")
		(net "M_B_CS_N<0>")
	)
	(segment
		(start 264.61466 -50.293524)
		(end 264.386568 -50.065432)
		(width 0.0889)
		(layer "In4.Cu")
		(net "M_B_CS_N<0>")
	)
	(segment
		(start 271.642078 -8.383524)
		(end 271.372584 -8.11403)
		(width 0.14224)
		(layer "In4.Cu")
		(net "M_B_CS_N<0>")
	)
	(segment
		(start 269.892526 -21.864066)
		(end 269.957042 -21.79955)
		(width 0.14224)
		(layer "In4.Cu")
		(net "M_B_CS_N<0>")
	)
	(segment
		(start 263.7282 -52.07)
		(end 264.61466 -51.18354)
		(width 0.0889)
		(layer "In4.Cu")
		(net "M_B_CS_N<0>")
	)
	(segment
		(start 269.957042 -23.133558)
		(end 269.957042 -22.561042)
		(width 0.14224)
		(layer "In4.Cu")
		(net "M_B_CS_N<0>")
	)
	(segment
		(start 271.801082 -11.28395)
		(end 271.801082 -9.555734)
		(width 0.14224)
		(layer "In4.Cu")
		(net "M_B_CS_N<0>")
	)
	(segment
		(start 264.575036 -49.150016)
		(end 264.575036 -48.906938)
		(width 0.0889)
		(layer "In4.Cu")
		(net "M_B_CS_N<0>")
	)
	(segment
		(start 269.957042 -21.291296)
		(end 269.909036 -21.24329)
		(width 0.14224)
		(layer "In4.Cu")
		(net "M_B_CS_N<0>")
	)
	(segment
		(start 271.801082 -9.555734)
		(end 271.642078 -9.39673)
		(width 0.14224)
		(layer "In4.Cu")
		(net "M_B_CS_N<0>")
	)
	(segment
		(start 271.642078 -12.160758)
		(end 271.642078 -11.442954)
		(width 0.14224)
		(layer "In4.Cu")
		(net "M_B_CS_N<0>")
	)
	(segment
		(start 271.372584 -8.11403)
		(end 271.12214 -8.11403)
		(width 0.14224)
		(layer "In4.Cu")
		(net "M_B_CS_N<0>")
	)
	(segment
		(start 270.565118 -8.400796)
		(end 270.350234 -8.185912)
		(width 0.14224)
		(layer "In4.Cu")
		(net "M_B_CS_N<0>")
	)
	(segment
		(start 270.835374 -8.400796)
		(end 270.565118 -8.400796)
		(width 0.14224)
		(layer "In4.Cu")
		(net "M_B_CS_N<0>")
	)
	(segment
		(start 268.1732 -26.035)
		(end 269.875 -24.3332)
		(width 0.14224)
		(layer "In4.Cu")
		(net "M_B_CS_N<0>")
	)
	(segment
		(start 264.575036 -48.906938)
		(end 264.575036 -31.767018)
		(width 0.14224)
		(layer "In4.Cu")
		(net "M_B_CS_N<0>")
	)
	(segment
		(start 262.228076 -54.102)
		(end 263.140952 -54.102)
		(width 0.0889)
		(layer "In4.Cu")
		(net "M_B_CS_N<0>")
	)
	(segment
		(start 269.957042 -21.79955)
		(end 269.957042 -21.291296)
		(width 0.14224)
		(layer "In4.Cu")
		(net "M_B_CS_N<0>")
	)
	(segment
		(start 264.575036 -31.767018)
		(end 268.1732 -28.168854)
		(width 0.14224)
		(layer "In4.Cu")
		(net "M_B_CS_N<0>")
	)
	(segment
		(start 269.877032 -16.385032)
		(end 269.877032 -15.187168)
		(width 0.14224)
		(layer "In4.Cu")
		(net "M_B_CS_N<0>")
	)
	(segment
		(start 262.22579 -54.104286)
		(end 262.228076 -54.102)
		(width 0.0889)
		(layer "In4.Cu")
		(net "M_B_CS_N<0>")
	)
	(segment
		(start 263.7282 -52.705508)
		(end 263.7282 -52.07)
		(width 0.0889)
		(layer "In4.Cu")
		(net "M_B_CS_N<0>")
	)
	(segment
		(start 269.875 -23.2156)
		(end 269.957042 -23.133558)
		(width 0.14224)
		(layer "In4.Cu")
		(net "M_B_CS_N<0>")
	)
	(segment
		(start 269.875 -24.3332)
		(end 269.875 -23.2156)
		(width 0.14224)
		(layer "In4.Cu")
		(net "M_B_CS_N<0>")
	)
	(segment
		(start 269.909036 -21.24329)
		(end 269.909036 -18.389346)
		(width 0.14224)
		(layer "In4.Cu")
		(net "M_B_CS_N<0>")
	)
	(segment
		(start 271.12214 -8.11403)
		(end 270.835374 -8.400796)
		(width 0.14224)
		(layer "In4.Cu")
		(net "M_B_CS_N<0>")
	)
	(segment
		(start 264.386568 -49.338484)
		(end 264.575036 -49.150016)
		(width 0.0889)
		(layer "In4.Cu")
		(net "M_B_CS_N<0>")
	)
	(arc
		(start 263.140952 -54.102)
		(mid 263.596037 -53.839295)
		(end 263.59612 -53.313838)
		(width 0.0889)
		(layer "In4.Cu")
		(net "M_B_CS_N<0>")
	)
	(arc
		(start 263.59612 -53.313838)
		(mid 263.54265 -53.118775)
		(end 263.591294 -52.922424)
		(width 0.0889)
		(layer "In4.Cu")
		(net "M_B_CS_N<0>")
	)
	(segment
		(start 257.64617 -57.076086)
		(end 257.07467 -57.076086)
		(width 0.1016)
		(layer "F.Cu")
		(net "M_B_CLK_DP<3>")
	)
	(via
		(at 257.07467 -57.076086)
		(size 0.508)
		(drill 0.254)
		(layers "F.Cu" "B.Cu")
		(net "M_B_CLK_DP<3>")
	)
	(via
		(at 256.826004 -11.916156)
		(size 0.508)
		(drill 0.254)
		(layers "F.Cu" "B.Cu")
		(net "M_B_CLK_DP<3>")
	)
	(segment
		(start 256.750312 -10.623042)
		(end 256.749804 -10.623042)
		(width 0.1651)
		(layer "B.Cu")
		(net "M_B_CLK_DP<3>")
	)
	(segment
		(start 256.749804 -10.623042)
		(end 256.749804 -11.839956)
		(width 0.1651)
		(layer "B.Cu")
		(net "M_B_CLK_DP<3>")
	)
	(segment
		(start 256.749804 -11.839956)
		(end 256.826004 -11.916156)
		(width 0.1651)
		(layer "B.Cu")
		(net "M_B_CLK_DP<3>")
	)
	(segment
		(start 259.891276 -26.737564)
		(end 259.28828 -26.134568)
		(width 0.14224)
		(layer "In4.Cu")
		(net "M_B_CLK_DP<3>")
	)
	(segment
		(start 259.84708 -17.69872)
		(end 259.84708 -14.714474)
		(width 0.14224)
		(layer "In4.Cu")
		(net "M_B_CLK_DP<3>")
	)
	(segment
		(start 258.3561 -51.101752)
		(end 259.8293 -49.628552)
		(width 0.0889)
		(layer "In4.Cu")
		(net "M_B_CLK_DP<3>")
	)
	(segment
		(start 258.2799 -54.799738)
		(end 258.284726 -54.791102)
		(width 0.0889)
		(layer "In4.Cu")
		(net "M_B_CLK_DP<3>")
	)
	(segment
		(start 257.951986 -13.32484)
		(end 257.021076 -12.39393)
		(width 0.14224)
		(layer "In4.Cu")
		(net "M_B_CLK_DP<3>")
	)
	(segment
		(start 257.021076 -12.111228)
		(end 256.826004 -11.916156)
		(width 0.14224)
		(layer "In4.Cu")
		(net "M_B_CLK_DP<3>")
	)
	(segment
		(start 259.28828 -18.25752)
		(end 259.84708 -17.69872)
		(width 0.14224)
		(layer "In4.Cu")
		(net "M_B_CLK_DP<3>")
	)
	(segment
		(start 257.9116 -55.99049)
		(end 257.944366 -55.99049)
		(width 0.0889)
		(layer "In4.Cu")
		(net "M_B_CLK_DP<3>")
	)
	(segment
		(start 259.891276 -47.936404)
		(end 259.891276 -26.737564)
		(width 0.14224)
		(layer "In4.Cu")
		(net "M_B_CLK_DP<3>")
	)
	(segment
		(start 258.2799 -54.399942)
		(end 258.195318 -54.25313)
		(width 0.0889)
		(layer "In4.Cu")
		(net "M_B_CLK_DP<3>")
	)
	(segment
		(start 259.8293 -49.628552)
		(end 259.8293 -48.68926)
		(width 0.0889)
		(layer "In4.Cu")
		(net "M_B_CLK_DP<3>")
	)
	(segment
		(start 257.021076 -12.39393)
		(end 257.021076 -12.111228)
		(width 0.14224)
		(layer "In4.Cu")
		(net "M_B_CLK_DP<3>")
	)
	(segment
		(start 258.27355 -54.810406)
		(end 258.2799 -54.799738)
		(width 0.0889)
		(layer "In4.Cu")
		(net "M_B_CLK_DP<3>")
	)
	(segment
		(start 258.195064 -54.164484)
		(end 258.195064 -52.657248)
		(width 0.0889)
		(layer "In4.Cu")
		(net "M_B_CLK_DP<3>")
	)
	(segment
		(start 259.927344 -47.99457)
		(end 259.891276 -47.958502)
		(width 0.0889)
		(layer "In4.Cu")
		(net "M_B_CLK_DP<3>")
	)
	(segment
		(start 257.07467 -57.076086)
		(end 257.187954 -56.963056)
		(width 0.0889)
		(layer "In4.Cu")
		(net "M_B_CLK_DP<3>")
	)
	(segment
		(start 259.8293 -48.68926)
		(end 259.927344 -48.591216)
		(width 0.0889)
		(layer "In4.Cu")
		(net "M_B_CLK_DP<3>")
	)
	(segment
		(start 258.195318 -54.25313)
		(end 258.195064 -54.164484)
		(width 0.0889)
		(layer "In4.Cu")
		(net "M_B_CLK_DP<3>")
	)
	(segment
		(start 259.891276 -47.958502)
		(end 259.891276 -47.936404)
		(width 0.0889)
		(layer "In4.Cu")
		(net "M_B_CLK_DP<3>")
	)
	(segment
		(start 259.28828 -26.134568)
		(end 259.28828 -18.25752)
		(width 0.14224)
		(layer "In4.Cu")
		(net "M_B_CLK_DP<3>")
	)
	(segment
		(start 259.927344 -48.591216)
		(end 259.927344 -47.99457)
		(width 0.0889)
		(layer "In4.Cu")
		(net "M_B_CLK_DP<3>")
	)
	(segment
		(start 259.84708 -14.714474)
		(end 258.457446 -13.32484)
		(width 0.14224)
		(layer "In4.Cu")
		(net "M_B_CLK_DP<3>")
	)
	(segment
		(start 258.195064 -52.657248)
		(end 258.3561 -52.496212)
		(width 0.0889)
		(layer "In4.Cu")
		(net "M_B_CLK_DP<3>")
	)
	(segment
		(start 258.3561 -52.496212)
		(end 258.3561 -51.101752)
		(width 0.0889)
		(layer "In4.Cu")
		(net "M_B_CLK_DP<3>")
	)
	(segment
		(start 258.457446 -13.32484)
		(end 257.951986 -13.32484)
		(width 0.14224)
		(layer "In4.Cu")
		(net "M_B_CLK_DP<3>")
	)
	(arc
		(start 258.284726 -54.791102)
		(mid 258.333358 -54.594894)
		(end 258.2799 -54.399942)
		(width 0.0889)
		(layer "In4.Cu")
		(net "M_B_CLK_DP<3>")
	)
	(arc
		(start 257.342132 -56.590438)
		(mid 257.504381 -56.174149)
		(end 257.9116 -55.99049)
		(width 0.0889)
		(layer "In4.Cu")
		(net "M_B_CLK_DP<3>")
	)
	(arc
		(start 257.944366 -55.99049)
		(mid 258.282535 -55.785692)
		(end 258.2799 -55.390288)
		(width 0.0889)
		(layer "In4.Cu")
		(net "M_B_CLK_DP<3>")
	)
	(arc
		(start 257.187954 -56.963056)
		(mid 257.302102 -56.792082)
		(end 257.342132 -56.590438)
		(width 0.0889)
		(layer "In4.Cu")
		(net "M_B_CLK_DP<3>")
	)
	(arc
		(start 258.2799 -55.390288)
		(mid 258.200678 -55.10117)
		(end 258.27355 -54.810406)
		(width 0.0889)
		(layer "In4.Cu")
		(net "M_B_CLK_DP<3>")
	)
	(segment
		(start 256.749804 -10.422382)
		(end 256.749804 -9.129268)
		(width 0.1651)
		(layer "F.Cu")
		(net "M_B_CLK_DP<1>")
	)
	(segment
		(start 259.36321 -57.076086)
		(end 258.79171 -57.076086)
		(width 0.1016)
		(layer "F.Cu")
		(net "M_B_CLK_DP<1>")
	)
	(segment
		(start 256.750312 -10.422382)
		(end 256.749804 -10.422382)
		(width 0.1651)
		(layer "F.Cu")
		(net "M_B_CLK_DP<1>")
	)
	(via
		(at 256.749804 -9.129268)
		(size 0.508)
		(drill 0.254)
		(layers "F.Cu" "B.Cu")
		(net "M_B_CLK_DP<1>")
	)
	(via
		(at 258.79171 -57.076086)
		(size 0.508)
		(drill 0.254)
		(layers "F.Cu" "B.Cu")
		(net "M_B_CLK_DP<1>")
	)
	(segment
		(start 257.482086 -11.275314)
		(end 257.021076 -10.814304)
		(width 0.14224)
		(layer "In4.Cu")
		(net "M_B_CLK_DP<1>")
	)
	(segment
		(start 258.680966 -10.93089)
		(end 258.336542 -11.275314)
		(width 0.14224)
		(layer "In4.Cu")
		(net "M_B_CLK_DP<1>")
	)
	(segment
		(start 258.680966 -10.68578)
		(end 258.680966 -10.93089)
		(width 0.14224)
		(layer "In4.Cu")
		(net "M_B_CLK_DP<1>")
	)
	(segment
		(start 257.021076 -10.814304)
		(end 257.021076 -9.40054)
		(width 0.14224)
		(layer "In4.Cu")
		(net "M_B_CLK_DP<1>")
	)
	(segment
		(start 257.021076 -9.40054)
		(end 256.749804 -9.129268)
		(width 0.14224)
		(layer "In4.Cu")
		(net "M_B_CLK_DP<1>")
	)
	(segment
		(start 258.336542 -11.275314)
		(end 257.482086 -11.275314)
		(width 0.14224)
		(layer "In4.Cu")
		(net "M_B_CLK_DP<1>")
	)
	(segment
		(start 258.807966 -10.55878)
		(end 258.680966 -10.68578)
		(width 0.14224)
		(layer "In4.Cu")
		(net "M_B_CLK_DP<1>")
	)
	(segment
		(start 259.687568 -11.598656)
		(end 259.687568 -10.931906)
		(width 0.14224)
		(layer "In4.Cu")
		(net "M_B_CLK_DP<1>")
	)
	(segment
		(start 260.729476 -47.987204)
		(end 260.729476 -25.867106)
		(width 0.14224)
		(layer "In4.Cu")
		(net "M_B_CLK_DP<1>")
	)
	(segment
		(start 259.314442 -10.55878)
		(end 258.807966 -10.55878)
		(width 0.14224)
		(layer "In4.Cu")
		(net "M_B_CLK_DP<1>")
	)
	(segment
		(start 259.059426 -51.257962)
		(end 260.477 -49.840388)
		(width 0.0889)
		(layer "In4.Cu")
		(net "M_B_CLK_DP<1>")
	)
	(segment
		(start 260.83768 -25.758902)
		(end 260.83768 -12.748768)
		(width 0.14224)
		(layer "In4.Cu")
		(net "M_B_CLK_DP<1>")
	)
	(segment
		(start 259.687568 -10.931906)
		(end 259.314442 -10.55878)
		(width 0.14224)
		(layer "In4.Cu")
		(net "M_B_CLK_DP<1>")
	)
	(segment
		(start 260.7564 -48.036226)
		(end 260.729476 -48.009302)
		(width 0.0889)
		(layer "In4.Cu")
		(net "M_B_CLK_DP<1>")
	)
	(segment
		(start 260.477 -49.840388)
		(end 260.477 -48.904906)
		(width 0.0889)
		(layer "In4.Cu")
		(net "M_B_CLK_DP<1>")
	)
	(segment
		(start 259.059426 -53.595524)
		(end 259.059426 -51.257962)
		(width 0.0889)
		(layer "In4.Cu")
		(net "M_B_CLK_DP<1>")
	)
	(segment
		(start 260.729476 -25.867106)
		(end 260.83768 -25.758902)
		(width 0.14224)
		(layer "In4.Cu")
		(net "M_B_CLK_DP<1>")
	)
	(segment
		(start 260.83768 -12.748768)
		(end 259.687568 -11.598656)
		(width 0.14224)
		(layer "In4.Cu")
		(net "M_B_CLK_DP<1>")
	)
	(segment
		(start 260.477 -48.904906)
		(end 260.7564 -48.625506)
		(width 0.0889)
		(layer "In4.Cu")
		(net "M_B_CLK_DP<1>")
	)
	(segment
		(start 260.729476 -48.009302)
		(end 260.729476 -47.987204)
		(width 0.0889)
		(layer "In4.Cu")
		(net "M_B_CLK_DP<1>")
	)
	(segment
		(start 259.13842 -54.304692)
		(end 259.138674 -54.304692)
		(width 0.0889)
		(layer "In4.Cu")
		(net "M_B_CLK_DP<1>")
	)
	(segment
		(start 260.7564 -48.625506)
		(end 260.7564 -48.036226)
		(width 0.0889)
		(layer "In4.Cu")
		(net "M_B_CLK_DP<1>")
	)
	(segment
		(start 258.79171 -57.076086)
		(end 258.90601 -56.961786)
		(width 0.0889)
		(layer "In4.Cu")
		(net "M_B_CLK_DP<1>")
	)
	(arc
		(start 259.059172 -56.591962)
		(mid 259.077922 -56.433519)
		(end 259.13842 -56.285892)
		(width 0.0889)
		(layer "In4.Cu")
		(net "M_B_CLK_DP<1>")
	)
	(arc
		(start 259.13842 -55.295292)
		(mid 259.191919 -55.095394)
		(end 259.13842 -54.895496)
		(width 0.0889)
		(layer "In4.Cu")
		(net "M_B_CLK_DP<1>")
	)
	(arc
		(start 259.13842 -56.285892)
		(mid 259.191919 -56.085994)
		(end 259.13842 -55.886096)
		(width 0.0889)
		(layer "In4.Cu")
		(net "M_B_CLK_DP<1>")
	)
	(arc
		(start 259.1435 -53.913532)
		(mid 259.078904 -53.760494)
		(end 259.059426 -53.595524)
		(width 0.0889)
		(layer "In4.Cu")
		(net "M_B_CLK_DP<1>")
	)
	(arc
		(start 259.138674 -54.304692)
		(mid 259.192108 -54.109741)
		(end 259.1435 -53.913532)
		(width 0.0889)
		(layer "In4.Cu")
		(net "M_B_CLK_DP<1>")
	)
	(arc
		(start 259.13842 -55.886096)
		(mid 259.059289 -55.590694)
		(end 259.13842 -55.295292)
		(width 0.0889)
		(layer "In4.Cu")
		(net "M_B_CLK_DP<1>")
	)
	(arc
		(start 259.13842 -54.895496)
		(mid 259.059289 -54.600094)
		(end 259.13842 -54.304692)
		(width 0.0889)
		(layer "In4.Cu")
		(net "M_B_CLK_DP<1>")
	)
	(arc
		(start 258.90601 -56.961786)
		(mid 259.019384 -56.792109)
		(end 259.059172 -56.591962)
		(width 0.0889)
		(layer "In4.Cu")
		(net "M_B_CLK_DP<1>")
	)
	(segment
		(start 257.64617 -55.094886)
		(end 257.07467 -55.094886)
		(width 0.1016)
		(layer "F.Cu")
		(net "M_B_CLK_DP<2>")
	)
	(via
		(at 256.749804 -13.929868)
		(size 0.508)
		(drill 0.254)
		(layers "F.Cu" "B.Cu")
		(net "M_B_CLK_DP<2>")
	)
	(via
		(at 257.07467 -55.094886)
		(size 0.508)
		(drill 0.254)
		(layers "F.Cu" "B.Cu")
		(net "M_B_CLK_DP<2>")
	)
	(segment
		(start 256.750312 -15.222982)
		(end 256.749804 -15.222982)
		(width 0.1651)
		(layer "B.Cu")
		(net "M_B_CLK_DP<2>")
	)
	(segment
		(start 256.749804 -15.222982)
		(end 256.749804 -13.929868)
		(width 0.1651)
		(layer "B.Cu")
		(net "M_B_CLK_DP<2>")
	)
	(segment
		(start 257.41503 -54.88432)
		(end 257.42138 -54.894988)
		(width 0.0889)
		(layer "In4.Cu")
		(net "M_B_CLK_DP<2>")
	)
	(segment
		(start 256.356612 -23.211536)
		(end 256.356612 -24.040084)
		(width 0.14224)
		(layer "In4.Cu")
		(net "M_B_CLK_DP<2>")
	)
	(segment
		(start 258.114292 -20.553934)
		(end 257.23342 -20.553934)
		(width 0.14224)
		(layer "In4.Cu")
		(net "M_B_CLK_DP<2>")
	)
	(segment
		(start 258.172204 -15.574264)
		(end 258.672584 -16.074644)
		(width 0.14224)
		(layer "In4.Cu")
		(net "M_B_CLK_DP<2>")
	)
	(segment
		(start 259.053076 -47.987204)
		(end 259.053076 -48.009302)
		(width 0.0889)
		(layer "In4.Cu")
		(net "M_B_CLK_DP<2>")
	)
	(segment
		(start 259.233162 -48.655732)
		(end 259.233162 -49.293018)
		(width 0.0889)
		(layer "In4.Cu")
		(net "M_B_CLK_DP<2>")
	)
	(segment
		(start 256.921 -20.866354)
		(end 256.921 -21.216874)
		(width 0.14224)
		(layer "In4.Cu")
		(net "M_B_CLK_DP<2>")
	)
	(segment
		(start 257.672586 -15.574264)
		(end 258.172204 -15.574264)
		(width 0.14224)
		(layer "In4.Cu")
		(net "M_B_CLK_DP<2>")
	)
	(segment
		(start 258.276598 -20.038568)
		(end 258.276598 -20.391628)
		(width 0.14224)
		(layer "In4.Cu")
		(net "M_B_CLK_DP<2>")
	)
	(segment
		(start 257.539744 -17.6022)
		(end 256.921 -18.220944)
		(width 0.14224)
		(layer "In4.Cu")
		(net "M_B_CLK_DP<2>")
	)
	(segment
		(start 258.373626 -26.464514)
		(end 259.053076 -27.143964)
		(width 0.14224)
		(layer "In4.Cu")
		(net "M_B_CLK_DP<2>")
	)
	(segment
		(start 259.089906 -48.512476)
		(end 259.233162 -48.655732)
		(width 0.0889)
		(layer "In4.Cu")
		(net "M_B_CLK_DP<2>")
	)
	(segment
		(start 257.046476 -14.22654)
		(end 257.046476 -14.948154)
		(width 0.14224)
		(layer "In4.Cu")
		(net "M_B_CLK_DP<2>")
	)
	(segment
		(start 258.672584 -16.074644)
		(end 258.672584 -17.156176)
		(width 0.14224)
		(layer "In4.Cu")
		(net "M_B_CLK_DP<2>")
	)
	(segment
		(start 258.22656 -17.6022)
		(end 257.539744 -17.6022)
		(width 0.14224)
		(layer "In4.Cu")
		(net "M_B_CLK_DP<2>")
	)
	(segment
		(start 259.233162 -49.293018)
		(end 257.331464 -51.194716)
		(width 0.0889)
		(layer "In4.Cu")
		(net "M_B_CLK_DP<2>")
	)
	(segment
		(start 256.921 -18.220944)
		(end 256.921 -19.578574)
		(width 0.14224)
		(layer "In4.Cu")
		(net "M_B_CLK_DP<2>")
	)
	(segment
		(start 258.373626 -26.057098)
		(end 258.373626 -26.464514)
		(width 0.14224)
		(layer "In4.Cu")
		(net "M_B_CLK_DP<2>")
	)
	(segment
		(start 256.3368 -21.801074)
		(end 256.3368 -23.191724)
		(width 0.14224)
		(layer "In4.Cu")
		(net "M_B_CLK_DP<2>")
	)
	(segment
		(start 256.356612 -24.040084)
		(end 258.373626 -26.057098)
		(width 0.14224)
		(layer "In4.Cu")
		(net "M_B_CLK_DP<2>")
	)
	(segment
		(start 257.23342 -20.553934)
		(end 256.921 -20.866354)
		(width 0.14224)
		(layer "In4.Cu")
		(net "M_B_CLK_DP<2>")
	)
	(segment
		(start 256.921 -21.216874)
		(end 256.3368 -21.801074)
		(width 0.14224)
		(layer "In4.Cu")
		(net "M_B_CLK_DP<2>")
	)
	(segment
		(start 257.446526 -55.242714)
		(end 257.367786 -55.26405)
		(width 0.0889)
		(layer "In4.Cu")
		(net "M_B_CLK_DP<2>")
	)
	(segment
		(start 259.089906 -48.046132)
		(end 259.089906 -48.512476)
		(width 0.0889)
		(layer "In4.Cu")
		(net "M_B_CLK_DP<2>")
	)
	(segment
		(start 259.053076 -48.009302)
		(end 259.089906 -48.046132)
		(width 0.0889)
		(layer "In4.Cu")
		(net "M_B_CLK_DP<2>")
	)
	(segment
		(start 257.367786 -55.26405)
		(end 257.07467 -55.094886)
		(width 0.0889)
		(layer "In4.Cu")
		(net "M_B_CLK_DP<2>")
	)
	(segment
		(start 257.557524 -54.068726)
		(end 257.42138 -54.304438)
		(width 0.0889)
		(layer "In4.Cu")
		(net "M_B_CLK_DP<2>")
	)
	(segment
		(start 257.23342 -19.890994)
		(end 258.129024 -19.890994)
		(width 0.14224)
		(layer "In4.Cu")
		(net "M_B_CLK_DP<2>")
	)
	(segment
		(start 256.749804 -13.929868)
		(end 257.046476 -14.22654)
		(width 0.14224)
		(layer "In4.Cu")
		(net "M_B_CLK_DP<2>")
	)
	(segment
		(start 258.129024 -19.890994)
		(end 258.276598 -20.038568)
		(width 0.14224)
		(layer "In4.Cu")
		(net "M_B_CLK_DP<2>")
	)
	(segment
		(start 257.331464 -51.76774)
		(end 257.557524 -52.1589)
		(width 0.0889)
		(layer "In4.Cu")
		(net "M_B_CLK_DP<2>")
	)
	(segment
		(start 257.42138 -54.894988)
		(end 257.426206 -54.903624)
		(width 0.0889)
		(layer "In4.Cu")
		(net "M_B_CLK_DP<2>")
	)
	(segment
		(start 257.331464 -51.194716)
		(end 257.331464 -51.76774)
		(width 0.0889)
		(layer "In4.Cu")
		(net "M_B_CLK_DP<2>")
	)
	(segment
		(start 258.276598 -20.391628)
		(end 258.114292 -20.553934)
		(width 0.14224)
		(layer "In4.Cu")
		(net "M_B_CLK_DP<2>")
	)
	(segment
		(start 258.672584 -17.156176)
		(end 258.22656 -17.6022)
		(width 0.14224)
		(layer "In4.Cu")
		(net "M_B_CLK_DP<2>")
	)
	(segment
		(start 259.053076 -27.143964)
		(end 259.053076 -47.987204)
		(width 0.14224)
		(layer "In4.Cu")
		(net "M_B_CLK_DP<2>")
	)
	(segment
		(start 256.3368 -23.191724)
		(end 256.356612 -23.211536)
		(width 0.14224)
		(layer "In4.Cu")
		(net "M_B_CLK_DP<2>")
	)
	(segment
		(start 257.046476 -14.948154)
		(end 257.672586 -15.574264)
		(width 0.14224)
		(layer "In4.Cu")
		(net "M_B_CLK_DP<2>")
	)
	(segment
		(start 256.921 -19.578574)
		(end 257.23342 -19.890994)
		(width 0.14224)
		(layer "In4.Cu")
		(net "M_B_CLK_DP<2>")
	)
	(segment
		(start 257.557524 -52.1589)
		(end 257.557524 -54.068726)
		(width 0.0889)
		(layer "In4.Cu")
		(net "M_B_CLK_DP<2>")
	)
	(arc
		(start 257.42138 -54.304438)
		(mid 257.342158 -54.593556)
		(end 257.41503 -54.88432)
		(width 0.0889)
		(layer "In4.Cu")
		(net "M_B_CLK_DP<2>")
	)
	(arc
		(start 257.426206 -54.903624)
		(mid 257.462274 -54.995604)
		(end 257.47472 -55.093616)
		(width 0.0889)
		(layer "In4.Cu")
		(net "M_B_CLK_DP<2>")
	)
	(arc
		(start 257.47472 -55.093616)
		(mid 257.467753 -55.169513)
		(end 257.446526 -55.242714)
		(width 0.0889)
		(layer "In4.Cu")
		(net "M_B_CLK_DP<2>")
	)
	(segment
		(start 260.22173 -55.59044)
		(end 259.65023 -55.59044)
		(width 0.1016)
		(layer "F.Cu")
		(net "M_B_CLK_DP<0>")
	)
	(segment
		(start 256.749804 -5.822442)
		(end 256.749804 -7.115556)
		(width 0.1651)
		(layer "F.Cu")
		(net "M_B_CLK_DP<0>")
	)
	(segment
		(start 256.750312 -5.822442)
		(end 256.749804 -5.822442)
		(width 0.1651)
		(layer "F.Cu")
		(net "M_B_CLK_DP<0>")
	)
	(via
		(at 259.65023 -55.59044)
		(size 0.508)
		(drill 0.254)
		(layers "F.Cu" "B.Cu")
		(net "M_B_CLK_DP<0>")
	)
	(via
		(at 256.749804 -7.115556)
		(size 0.508)
		(drill 0.254)
		(layers "F.Cu" "B.Cu")
		(net "M_B_CLK_DP<0>")
	)
	(segment
		(start 257.4925 -8.325866)
		(end 257.021076 -7.854442)
		(width 0.14224)
		(layer "In4.Cu")
		(net "M_B_CLK_DP<0>")
	)
	(segment
		(start 259.99694 -53.809138)
		(end 260.001766 -53.800502)
		(width 0.0889)
		(layer "In4.Cu")
		(net "M_B_CLK_DP<0>")
	)
	(segment
		(start 259.99059 -54.810406)
		(end 259.99694 -54.799738)
		(width 0.0889)
		(layer "In4.Cu")
		(net "M_B_CLK_DP<0>")
	)
	(segment
		(start 259.907024 -51.36007)
		(end 261.516114 -49.75098)
		(width 0.0889)
		(layer "In4.Cu")
		(net "M_B_CLK_DP<0>")
	)
	(segment
		(start 259.99694 -54.799738)
		(end 260.001766 -54.791102)
		(width 0.0889)
		(layer "In4.Cu")
		(net "M_B_CLK_DP<0>")
	)
	(segment
		(start 261.67588 -11.793728)
		(end 260.89356 -11.011408)
		(width 0.14224)
		(layer "In4.Cu")
		(net "M_B_CLK_DP<0>")
	)
	(segment
		(start 261.67588 -13.26388)
		(end 261.67588 -11.793728)
		(width 0.14224)
		(layer "In4.Cu")
		(net "M_B_CLK_DP<0>")
	)
	(segment
		(start 261.516114 -49.75098)
		(end 261.516114 -48.598074)
		(width 0.0889)
		(layer "In4.Cu")
		(net "M_B_CLK_DP<0>")
	)
	(segment
		(start 261.47522 -48.55718)
		(end 261.47522 -26.435304)
		(width 0.14224)
		(layer "In4.Cu")
		(net "M_B_CLK_DP<0>")
	)
	(segment
		(start 259.99059 -53.819806)
		(end 259.99694 -53.809138)
		(width 0.0889)
		(layer "In4.Cu")
		(net "M_B_CLK_DP<0>")
	)
	(segment
		(start 261.67588 -20.41652)
		(end 262.21436 -19.87804)
		(width 0.14224)
		(layer "In4.Cu")
		(net "M_B_CLK_DP<0>")
	)
	(segment
		(start 257.021076 -7.386828)
		(end 256.749804 -7.115556)
		(width 0.14224)
		(layer "In4.Cu")
		(net "M_B_CLK_DP<0>")
	)
	(segment
		(start 259.995416 -52.821332)
		(end 259.99694 -52.818538)
		(width 0.0889)
		(layer "In4.Cu")
		(net "M_B_CLK_DP<0>")
	)
	(segment
		(start 262.21436 -19.87804)
		(end 262.21436 -13.80236)
		(width 0.14224)
		(layer "In4.Cu")
		(net "M_B_CLK_DP<0>")
	)
	(segment
		(start 258.976876 -8.325866)
		(end 257.4925 -8.325866)
		(width 0.14224)
		(layer "In4.Cu")
		(net "M_B_CLK_DP<0>")
	)
	(segment
		(start 262.21436 -13.80236)
		(end 261.67588 -13.26388)
		(width 0.14224)
		(layer "In4.Cu")
		(net "M_B_CLK_DP<0>")
	)
	(segment
		(start 259.907024 -52.262278)
		(end 259.907024 -51.36007)
		(width 0.0889)
		(layer "In4.Cu")
		(net "M_B_CLK_DP<0>")
	)
	(segment
		(start 257.021076 -7.854442)
		(end 257.021076 -7.386828)
		(width 0.14224)
		(layer "In4.Cu")
		(net "M_B_CLK_DP<0>")
	)
	(segment
		(start 259.99694 -52.418488)
		(end 259.907024 -52.262278)
		(width 0.0889)
		(layer "In4.Cu")
		(net "M_B_CLK_DP<0>")
	)
	(segment
		(start 259.990336 -52.830222)
		(end 259.995416 -52.821332)
		(width 0.0889)
		(layer "In4.Cu")
		(net "M_B_CLK_DP<0>")
	)
	(segment
		(start 260.89356 -10.24255)
		(end 258.976876 -8.325866)
		(width 0.14224)
		(layer "In4.Cu")
		(net "M_B_CLK_DP<0>")
	)
	(segment
		(start 261.67588 -26.234644)
		(end 261.67588 -20.41652)
		(width 0.14224)
		(layer "In4.Cu")
		(net "M_B_CLK_DP<0>")
	)
	(segment
		(start 259.65023 -55.59044)
		(end 259.762244 -55.47868)
		(width 0.0889)
		(layer "In4.Cu")
		(net "M_B_CLK_DP<0>")
	)
	(segment
		(start 261.516114 -48.598074)
		(end 261.47522 -48.55718)
		(width 0.0889)
		(layer "In4.Cu")
		(net "M_B_CLK_DP<0>")
	)
	(segment
		(start 260.89356 -11.011408)
		(end 260.89356 -10.24255)
		(width 0.14224)
		(layer "In4.Cu")
		(net "M_B_CLK_DP<0>")
	)
	(segment
		(start 261.47522 -26.435304)
		(end 261.67588 -26.234644)
		(width 0.14224)
		(layer "In4.Cu")
		(net "M_B_CLK_DP<0>")
	)
	(arc
		(start 259.99694 -54.399688)
		(mid 259.917718 -54.11057)
		(end 259.99059 -53.819806)
		(width 0.0889)
		(layer "In4.Cu")
		(net "M_B_CLK_DP<0>")
	)
	(arc
		(start 259.917692 -55.103014)
		(mid 259.935176 -54.951988)
		(end 259.99059 -54.810406)
		(width 0.0889)
		(layer "In4.Cu")
		(net "M_B_CLK_DP<0>")
	)
	(arc
		(start 259.99694 -52.818538)
		(mid 260.050439 -52.61853)
		(end 259.99694 -52.418488)
		(width 0.0889)
		(layer "In4.Cu")
		(net "M_B_CLK_DP<0>")
	)
	(arc
		(start 260.001766 -54.791102)
		(mid 260.050521 -54.59475)
		(end 259.99694 -54.399688)
		(width 0.0889)
		(layer "In4.Cu")
		(net "M_B_CLK_DP<0>")
	)
	(arc
		(start 260.001766 -53.800502)
		(mid 260.050521 -53.60415)
		(end 259.99694 -53.409088)
		(width 0.0889)
		(layer "In4.Cu")
		(net "M_B_CLK_DP<0>")
	)
	(arc
		(start 259.762244 -55.47868)
		(mid 259.877326 -55.306308)
		(end 259.917692 -55.103014)
		(width 0.0889)
		(layer "In4.Cu")
		(net "M_B_CLK_DP<0>")
	)
	(arc
		(start 259.99694 -53.409088)
		(mid 259.917848 -53.120508)
		(end 259.990336 -52.830222)
		(width 0.0889)
		(layer "In4.Cu")
		(net "M_B_CLK_DP<0>")
	)
	(segment
		(start 258.50469 -56.58104)
		(end 257.93319 -56.58104)
		(width 0.1016)
		(layer "F.Cu")
		(net "M_B_CLK_DN<3>")
	)
	(via
		(at 257.523742 -11.916156)
		(size 0.508)
		(drill 0.254)
		(layers "F.Cu" "B.Cu")
		(net "M_B_CLK_DN<3>")
	)
	(via
		(at 257.93319 -56.58104)
		(size 0.508)
		(drill 0.254)
		(layers "F.Cu" "B.Cu")
		(net "M_B_CLK_DN<3>")
	)
	(segment
		(start 257.599942 -10.623042)
		(end 257.599942 -11.839956)
		(width 0.1651)
		(layer "B.Cu")
		(net "M_B_CLK_DN<3>")
	)
	(segment
		(start 257.599942 -11.839956)
		(end 257.523742 -11.916156)
		(width 0.1651)
		(layer "B.Cu")
		(net "M_B_CLK_DN<3>")
	)
	(segment
		(start 257.60045 -10.623042)
		(end 257.599942 -10.623042)
		(width 0.1651)
		(layer "B.Cu")
		(net "M_B_CLK_DN<3>")
	)
	(segment
		(start 258.452112 -54.882288)
		(end 258.45135 -54.88432)
		(width 0.0889)
		(layer "In4.Cu")
		(net "M_B_CLK_DN<3>")
	)
	(segment
		(start 260.117844 -48.67021)
		(end 260.117844 -48.009556)
		(width 0.0889)
		(layer "In4.Cu")
		(net "M_B_CLK_DN<3>")
	)
	(segment
		(start 257.290316 -12.28217)
		(end 257.290316 -12.149582)
		(width 0.14224)
		(layer "In4.Cu")
		(net "M_B_CLK_DN<3>")
	)
	(segment
		(start 260.0198 -49.707546)
		(end 260.0198 -48.768254)
		(width 0.0889)
		(layer "In4.Cu")
		(net "M_B_CLK_DN<3>")
	)
	(segment
		(start 260.160516 -47.966884)
		(end 260.160516 -26.625804)
		(width 0.14224)
		(layer "In4.Cu")
		(net "M_B_CLK_DN<3>")
	)
	(segment
		(start 258.5466 -51.180746)
		(end 260.0198 -49.707546)
		(width 0.0889)
		(layer "In4.Cu")
		(net "M_B_CLK_DN<3>")
	)
	(segment
		(start 260.160516 -26.625804)
		(end 259.55752 -26.022808)
		(width 0.14224)
		(layer "In4.Cu")
		(net "M_B_CLK_DN<3>")
	)
	(segment
		(start 259.55752 -26.022808)
		(end 259.55752 -18.36928)
		(width 0.14224)
		(layer "In4.Cu")
		(net "M_B_CLK_DN<3>")
	)
	(segment
		(start 258.385564 -53.949346)
		(end 258.385564 -52.736242)
		(width 0.0889)
		(layer "In4.Cu")
		(net "M_B_CLK_DN<3>")
	)
	(segment
		(start 260.11632 -14.602714)
		(end 258.569206 -13.0556)
		(width 0.14224)
		(layer "In4.Cu")
		(net "M_B_CLK_DN<3>")
	)
	(segment
		(start 259.55752 -18.36928)
		(end 260.11632 -17.81048)
		(width 0.14224)
		(layer "In4.Cu")
		(net "M_B_CLK_DN<3>")
	)
	(segment
		(start 258.440174 -54.903624)
		(end 258.452112 -54.882288)
		(width 0.0889)
		(layer "In4.Cu")
		(net "M_B_CLK_DN<3>")
	)
	(segment
		(start 260.0198 -48.768254)
		(end 260.117844 -48.67021)
		(width 0.0889)
		(layer "In4.Cu")
		(net "M_B_CLK_DN<3>")
	)
	(segment
		(start 258.063746 -13.0556)
		(end 257.290316 -12.28217)
		(width 0.14224)
		(layer "In4.Cu")
		(net "M_B_CLK_DN<3>")
	)
	(segment
		(start 260.11632 -17.81048)
		(end 260.11632 -14.602714)
		(width 0.14224)
		(layer "In4.Cu")
		(net "M_B_CLK_DN<3>")
	)
	(segment
		(start 258.5466 -52.575206)
		(end 258.5466 -51.180746)
		(width 0.0889)
		(layer "In4.Cu")
		(net "M_B_CLK_DN<3>")
	)
	(segment
		(start 257.640074 -56.74995)
		(end 257.561334 -56.728614)
		(width 0.0889)
		(layer "In4.Cu")
		(net "M_B_CLK_DN<3>")
	)
	(segment
		(start 258.569206 -13.0556)
		(end 258.063746 -13.0556)
		(width 0.14224)
		(layer "In4.Cu")
		(net "M_B_CLK_DN<3>")
	)
	(segment
		(start 260.117844 -48.009556)
		(end 260.160516 -47.966884)
		(width 0.0889)
		(layer "In4.Cu")
		(net "M_B_CLK_DN<3>")
	)
	(segment
		(start 257.290316 -12.149582)
		(end 257.523742 -11.916156)
		(width 0.14224)
		(layer "In4.Cu")
		(net "M_B_CLK_DN<3>")
	)
	(segment
		(start 258.385818 -54.202076)
		(end 258.385564 -53.949346)
		(width 0.0889)
		(layer "In4.Cu")
		(net "M_B_CLK_DN<3>")
	)
	(segment
		(start 257.918204 -56.18099)
		(end 257.95097 -56.18099)
		(width 0.0889)
		(layer "In4.Cu")
		(net "M_B_CLK_DN<3>")
	)
	(segment
		(start 257.93319 -56.58104)
		(end 257.640074 -56.74995)
		(width 0.0889)
		(layer "In4.Cu")
		(net "M_B_CLK_DN<3>")
	)
	(segment
		(start 258.445254 -54.304692)
		(end 258.385818 -54.202076)
		(width 0.0889)
		(layer "In4.Cu")
		(net "M_B_CLK_DN<3>")
	)
	(segment
		(start 258.385564 -52.736242)
		(end 258.5466 -52.575206)
		(width 0.0889)
		(layer "In4.Cu")
		(net "M_B_CLK_DN<3>")
	)
	(arc
		(start 258.445 -55.295038)
		(mid 258.39153 -55.099975)
		(end 258.440174 -54.903624)
		(width 0.0889)
		(layer "In4.Cu")
		(net "M_B_CLK_DN<3>")
	)
	(arc
		(start 258.45135 -54.88432)
		(mid 258.524275 -54.593696)
		(end 258.445254 -54.304692)
		(width 0.0889)
		(layer "In4.Cu")
		(net "M_B_CLK_DN<3>")
	)
	(arc
		(start 257.95097 -56.18099)
		(mid 258.449221 -55.87815)
		(end 258.445 -55.295038)
		(width 0.0889)
		(layer "In4.Cu")
		(net "M_B_CLK_DN<3>")
	)
	(arc
		(start 257.561334 -56.728614)
		(mid 257.540859 -56.659278)
		(end 257.53314 -56.58739)
		(width 0.0889)
		(layer "In4.Cu")
		(net "M_B_CLK_DN<3>")
	)
	(arc
		(start 257.53314 -56.58739)
		(mid 257.64282 -56.305684)
		(end 257.918204 -56.18099)
		(width 0.0889)
		(layer "In4.Cu")
		(net "M_B_CLK_DN<3>")
	)
	(segment
		(start 257.599942 -10.422382)
		(end 257.599942 -9.129268)
		(width 0.1651)
		(layer "F.Cu")
		(net "M_B_CLK_DN<1>")
	)
	(segment
		(start 257.60045 -10.422382)
		(end 257.599942 -10.422382)
		(width 0.1651)
		(layer "F.Cu")
		(net "M_B_CLK_DN<1>")
	)
	(segment
		(start 260.22173 -56.58104)
		(end 259.65023 -56.58104)
		(width 0.1016)
		(layer "F.Cu")
		(net "M_B_CLK_DN<1>")
	)
	(via
		(at 259.65023 -56.58104)
		(size 0.508)
		(drill 0.254)
		(layers "F.Cu" "B.Cu")
		(net "M_B_CLK_DN<1>")
	)
	(via
		(at 257.599942 -9.129268)
		(size 0.508)
		(drill 0.254)
		(layers "F.Cu" "B.Cu")
		(net "M_B_CLK_DN<1>")
	)
	(segment
		(start 259.956808 -10.820146)
		(end 259.426202 -10.28954)
		(width 0.14224)
		(layer "In4.Cu")
		(net "M_B_CLK_DN<1>")
	)
	(segment
		(start 259.249926 -51.336956)
		(end 260.6675 -49.919382)
		(width 0.0889)
		(layer "In4.Cu")
		(net "M_B_CLK_DN<1>")
	)
	(segment
		(start 259.249926 -53.598064)
		(end 259.249926 -51.336956)
		(width 0.0889)
		(layer "In4.Cu")
		(net "M_B_CLK_DN<1>")
	)
	(segment
		(start 258.224782 -11.006074)
		(end 257.593846 -11.006074)
		(width 0.14224)
		(layer "In4.Cu")
		(net "M_B_CLK_DN<1>")
	)
	(segment
		(start 258.696206 -10.28954)
		(end 258.411726 -10.57402)
		(width 0.14224)
		(layer "In4.Cu")
		(net "M_B_CLK_DN<1>")
	)
	(segment
		(start 260.9469 -48.7045)
		(end 260.9469 -48.0695)
		(width 0.0889)
		(layer "In4.Cu")
		(net "M_B_CLK_DN<1>")
	)
	(segment
		(start 260.6675 -49.919382)
		(end 260.6675 -48.9839)
		(width 0.0889)
		(layer "In4.Cu")
		(net "M_B_CLK_DN<1>")
	)
	(segment
		(start 258.411726 -10.81913)
		(end 258.224782 -11.006074)
		(width 0.14224)
		(layer "In4.Cu")
		(net "M_B_CLK_DN<1>")
	)
	(segment
		(start 258.411726 -10.57402)
		(end 258.411726 -10.81913)
		(width 0.14224)
		(layer "In4.Cu")
		(net "M_B_CLK_DN<1>")
	)
	(segment
		(start 257.290316 -10.702544)
		(end 257.290316 -9.438894)
		(width 0.14224)
		(layer "In4.Cu")
		(net "M_B_CLK_DN<1>")
	)
	(segment
		(start 260.998716 -25.978866)
		(end 261.10692 -25.870662)
		(width 0.14224)
		(layer "In4.Cu")
		(net "M_B_CLK_DN<1>")
	)
	(segment
		(start 261.10692 -12.637008)
		(end 259.956808 -11.486896)
		(width 0.14224)
		(layer "In4.Cu")
		(net "M_B_CLK_DN<1>")
	)
	(segment
		(start 257.290316 -9.438894)
		(end 257.599942 -9.129268)
		(width 0.14224)
		(layer "In4.Cu")
		(net "M_B_CLK_DN<1>")
	)
	(segment
		(start 260.998716 -48.017684)
		(end 260.998716 -25.978866)
		(width 0.14224)
		(layer "In4.Cu")
		(net "M_B_CLK_DN<1>")
	)
	(segment
		(start 260.9469 -48.0695)
		(end 260.998716 -48.017684)
		(width 0.0889)
		(layer "In4.Cu")
		(net "M_B_CLK_DN<1>")
	)
	(segment
		(start 259.426202 -10.28954)
		(end 258.696206 -10.28954)
		(width 0.14224)
		(layer "In4.Cu")
		(net "M_B_CLK_DN<1>")
	)
	(segment
		(start 259.303774 -53.809646)
		(end 259.30352 -53.809646)
		(width 0.0889)
		(layer "In4.Cu")
		(net "M_B_CLK_DN<1>")
	)
	(segment
		(start 259.65023 -56.58104)
		(end 259.357114 -56.750204)
		(width 0.0889)
		(layer "In4.Cu")
		(net "M_B_CLK_DN<1>")
	)
	(segment
		(start 260.6675 -48.9839)
		(end 260.9469 -48.7045)
		(width 0.0889)
		(layer "In4.Cu")
		(net "M_B_CLK_DN<1>")
	)
	(segment
		(start 257.593846 -11.006074)
		(end 257.290316 -10.702544)
		(width 0.14224)
		(layer "In4.Cu")
		(net "M_B_CLK_DN<1>")
	)
	(segment
		(start 259.357114 -56.750204)
		(end 259.278374 -56.728868)
		(width 0.0889)
		(layer "In4.Cu")
		(net "M_B_CLK_DN<1>")
	)
	(segment
		(start 261.10692 -25.870662)
		(end 261.10692 -12.637008)
		(width 0.14224)
		(layer "In4.Cu")
		(net "M_B_CLK_DN<1>")
	)
	(segment
		(start 259.956808 -11.486896)
		(end 259.956808 -10.820146)
		(width 0.14224)
		(layer "In4.Cu")
		(net "M_B_CLK_DN<1>")
	)
	(arc
		(start 259.30352 -56.381396)
		(mid 259.382651 -56.085994)
		(end 259.30352 -55.790592)
		(width 0.0889)
		(layer "In4.Cu")
		(net "M_B_CLK_DN<1>")
	)
	(arc
		(start 259.30352 -54.400196)
		(mid 259.382651 -54.104967)
		(end 259.303774 -53.809646)
		(width 0.0889)
		(layer "In4.Cu")
		(net "M_B_CLK_DN<1>")
	)
	(arc
		(start 259.30352 -53.809646)
		(mid 259.262029 -53.707577)
		(end 259.249926 -53.598064)
		(width 0.0889)
		(layer "In4.Cu")
		(net "M_B_CLK_DN<1>")
	)
	(arc
		(start 259.278374 -56.728868)
		(mid 259.251105 -56.552239)
		(end 259.30352 -56.381396)
		(width 0.0889)
		(layer "In4.Cu")
		(net "M_B_CLK_DN<1>")
	)
	(arc
		(start 259.30352 -55.790592)
		(mid 259.250021 -55.590694)
		(end 259.30352 -55.390796)
		(width 0.0889)
		(layer "In4.Cu")
		(net "M_B_CLK_DN<1>")
	)
	(arc
		(start 259.30352 -54.799992)
		(mid 259.250021 -54.600094)
		(end 259.30352 -54.400196)
		(width 0.0889)
		(layer "In4.Cu")
		(net "M_B_CLK_DN<1>")
	)
	(arc
		(start 259.30352 -55.390796)
		(mid 259.382651 -55.095394)
		(end 259.30352 -54.799992)
		(width 0.0889)
		(layer "In4.Cu")
		(net "M_B_CLK_DN<1>")
	)
	(segment
		(start 258.50469 -55.59044)
		(end 257.93319 -55.59044)
		(width 0.1016)
		(layer "F.Cu")
		(net "M_B_CLK_DN<2>")
	)
	(via
		(at 257.599942 -13.929868)
		(size 0.508)
		(drill 0.254)
		(layers "F.Cu" "B.Cu")
		(net "M_B_CLK_DN<2>")
	)
	(via
		(at 257.93319 -55.59044)
		(size 0.508)
		(drill 0.254)
		(layers "F.Cu" "B.Cu")
		(net "M_B_CLK_DN<2>")
	)
	(segment
		(start 257.599942 -15.222982)
		(end 257.599942 -13.929868)
		(width 0.1651)
		(layer "B.Cu")
		(net "M_B_CLK_DN<2>")
	)
	(segment
		(start 257.60045 -15.222982)
		(end 257.599942 -15.222982)
		(width 0.1651)
		(layer "B.Cu")
		(net "M_B_CLK_DN<2>")
	)
	(segment
		(start 258.283964 -15.305024)
		(end 257.784346 -15.305024)
		(width 0.14224)
		(layer "In4.Cu")
		(net "M_B_CLK_DN<2>")
	)
	(segment
		(start 257.19024 -19.466814)
		(end 257.19024 -18.332704)
		(width 0.14224)
		(layer "In4.Cu")
		(net "M_B_CLK_DN<2>")
	)
	(segment
		(start 259.423662 -48.576738)
		(end 259.280406 -48.433482)
		(width 0.0889)
		(layer "In4.Cu")
		(net "M_B_CLK_DN<2>")
	)
	(segment
		(start 257.19024 -18.332704)
		(end 257.651504 -17.87144)
		(width 0.14224)
		(layer "In4.Cu")
		(net "M_B_CLK_DN<2>")
	)
	(segment
		(start 257.58648 -54.399688)
		(end 257.748024 -54.120034)
		(width 0.0889)
		(layer "In4.Cu")
		(net "M_B_CLK_DN<2>")
	)
	(segment
		(start 259.322316 -27.031442)
		(end 258.90474 -26.613866)
		(width 0.14224)
		(layer "In4.Cu")
		(net "M_B_CLK_DN<2>")
	)
	(segment
		(start 257.315716 -14.836394)
		(end 257.315716 -14.214094)
		(width 0.14224)
		(layer "In4.Cu")
		(net "M_B_CLK_DN<2>")
	)
	(segment
		(start 258.240784 -19.621754)
		(end 257.34518 -19.621754)
		(width 0.14224)
		(layer "In4.Cu")
		(net "M_B_CLK_DN<2>")
	)
	(segment
		(start 257.59283 -54.810406)
		(end 257.58648 -54.799738)
		(width 0.0889)
		(layer "In4.Cu")
		(net "M_B_CLK_DN<2>")
	)
	(segment
		(start 257.651504 -17.87144)
		(end 258.33832 -17.87144)
		(width 0.14224)
		(layer "In4.Cu")
		(net "M_B_CLK_DN<2>")
	)
	(segment
		(start 259.280406 -48.433482)
		(end 259.280406 -48.059594)
		(width 0.0889)
		(layer "In4.Cu")
		(net "M_B_CLK_DN<2>")
	)
	(segment
		(start 256.60604 -23.079964)
		(end 256.60604 -21.912834)
		(width 0.14224)
		(layer "In4.Cu")
		(net "M_B_CLK_DN<2>")
	)
	(segment
		(start 257.748024 -52.107592)
		(end 257.521964 -51.716432)
		(width 0.0889)
		(layer "In4.Cu")
		(net "M_B_CLK_DN<2>")
	)
	(segment
		(start 257.521964 -51.716432)
		(end 257.521964 -51.27371)
		(width 0.0889)
		(layer "In4.Cu")
		(net "M_B_CLK_DN<2>")
	)
	(segment
		(start 258.90474 -26.613866)
		(end 258.903978 -26.613866)
		(width 0.14224)
		(layer "In4.Cu")
		(net "M_B_CLK_DN<2>")
	)
	(segment
		(start 256.625852 -23.099776)
		(end 256.60604 -23.079964)
		(width 0.14224)
		(layer "In4.Cu")
		(net "M_B_CLK_DN<2>")
	)
	(segment
		(start 258.941824 -17.267936)
		(end 258.941824 -15.962884)
		(width 0.14224)
		(layer "In4.Cu")
		(net "M_B_CLK_DN<2>")
	)
	(segment
		(start 258.545838 -20.503388)
		(end 258.545838 -19.926808)
		(width 0.14224)
		(layer "In4.Cu")
		(net "M_B_CLK_DN<2>")
	)
	(segment
		(start 258.33832 -17.87144)
		(end 258.941824 -17.267936)
		(width 0.14224)
		(layer "In4.Cu")
		(net "M_B_CLK_DN<2>")
	)
	(segment
		(start 259.322316 -48.017684)
		(end 259.322316 -27.031442)
		(width 0.14224)
		(layer "In4.Cu")
		(net "M_B_CLK_DN<2>")
	)
	(segment
		(start 257.34518 -19.621754)
		(end 257.19024 -19.466814)
		(width 0.14224)
		(layer "In4.Cu")
		(net "M_B_CLK_DN<2>")
	)
	(segment
		(start 259.423662 -49.372012)
		(end 259.423662 -48.576738)
		(width 0.0889)
		(layer "In4.Cu")
		(net "M_B_CLK_DN<2>")
	)
	(segment
		(start 257.19024 -20.978114)
		(end 257.34518 -20.823174)
		(width 0.14224)
		(layer "In4.Cu")
		(net "M_B_CLK_DN<2>")
	)
	(segment
		(start 258.226052 -20.823174)
		(end 258.545838 -20.503388)
		(width 0.14224)
		(layer "In4.Cu")
		(net "M_B_CLK_DN<2>")
	)
	(segment
		(start 258.642866 -25.945338)
		(end 256.625852 -23.928324)
		(width 0.14224)
		(layer "In4.Cu")
		(net "M_B_CLK_DN<2>")
	)
	(segment
		(start 258.903978 -26.613866)
		(end 258.642866 -26.352754)
		(width 0.14224)
		(layer "In4.Cu")
		(net "M_B_CLK_DN<2>")
	)
	(segment
		(start 256.625852 -23.928324)
		(end 256.625852 -23.099776)
		(width 0.14224)
		(layer "In4.Cu")
		(net "M_B_CLK_DN<2>")
	)
	(segment
		(start 257.315716 -14.214094)
		(end 257.599942 -13.929868)
		(width 0.14224)
		(layer "In4.Cu")
		(net "M_B_CLK_DN<2>")
	)
	(segment
		(start 259.280406 -48.059594)
		(end 259.322316 -48.017684)
		(width 0.0889)
		(layer "In4.Cu")
		(net "M_B_CLK_DN<2>")
	)
	(segment
		(start 258.941824 -15.962884)
		(end 258.283964 -15.305024)
		(width 0.14224)
		(layer "In4.Cu")
		(net "M_B_CLK_DN<2>")
	)
	(segment
		(start 258.642866 -26.352754)
		(end 258.642866 -25.945338)
		(width 0.14224)
		(layer "In4.Cu")
		(net "M_B_CLK_DN<2>")
	)
	(segment
		(start 257.58648 -54.799738)
		(end 257.581654 -54.791102)
		(width 0.0889)
		(layer "In4.Cu")
		(net "M_B_CLK_DN<2>")
	)
	(segment
		(start 257.34518 -20.823174)
		(end 258.226052 -20.823174)
		(width 0.14224)
		(layer "In4.Cu")
		(net "M_B_CLK_DN<2>")
	)
	(segment
		(start 257.748024 -54.120034)
		(end 257.748024 -52.107592)
		(width 0.0889)
		(layer "In4.Cu")
		(net "M_B_CLK_DN<2>")
	)
	(segment
		(start 256.60604 -21.912834)
		(end 257.19024 -21.328634)
		(width 0.14224)
		(layer "In4.Cu")
		(net "M_B_CLK_DN<2>")
	)
	(segment
		(start 257.93319 -55.59044)
		(end 257.828542 -55.485538)
		(width 0.0889)
		(layer "In4.Cu")
		(net "M_B_CLK_DN<2>")
	)
	(segment
		(start 258.545838 -19.926808)
		(end 258.240784 -19.621754)
		(width 0.14224)
		(layer "In4.Cu")
		(net "M_B_CLK_DN<2>")
	)
	(segment
		(start 257.784346 -15.305024)
		(end 257.315716 -14.836394)
		(width 0.14224)
		(layer "In4.Cu")
		(net "M_B_CLK_DN<2>")
	)
	(segment
		(start 257.521964 -51.27371)
		(end 259.423662 -49.372012)
		(width 0.0889)
		(layer "In4.Cu")
		(net "M_B_CLK_DN<2>")
	)
	(segment
		(start 257.19024 -21.328634)
		(end 257.19024 -20.978114)
		(width 0.14224)
		(layer "In4.Cu")
		(net "M_B_CLK_DN<2>")
	)
	(arc
		(start 257.581654 -54.791102)
		(mid 257.532899 -54.59475)
		(end 257.58648 -54.399688)
		(width 0.0889)
		(layer "In4.Cu")
		(net "M_B_CLK_DN<2>")
	)
	(arc
		(start 257.828542 -55.485538)
		(mid 257.708077 -55.305388)
		(end 257.665728 -55.092854)
		(width 0.0889)
		(layer "In4.Cu")
		(net "M_B_CLK_DN<2>")
	)
	(arc
		(start 257.665728 -55.092854)
		(mid 257.647002 -54.947054)
		(end 257.59283 -54.810406)
		(width 0.0889)
		(layer "In4.Cu")
		(net "M_B_CLK_DN<2>")
	)
	(segment
		(start 257.599942 -5.822442)
		(end 257.599942 -7.115556)
		(width 0.1651)
		(layer "F.Cu")
		(net "M_B_CLK_DN<0>")
	)
	(segment
		(start 260.50875 -55.094886)
		(end 261.08025 -55.094886)
		(width 0.1016)
		(layer "F.Cu")
		(net "M_B_CLK_DN<0>")
	)
	(segment
		(start 257.60045 -5.822442)
		(end 257.599942 -5.822442)
		(width 0.1651)
		(layer "F.Cu")
		(net "M_B_CLK_DN<0>")
	)
	(via
		(at 260.50875 -55.094886)
		(size 0.508)
		(drill 0.254)
		(layers "F.Cu" "B.Cu")
		(net "M_B_CLK_DN<0>")
	)
	(via
		(at 257.599942 -7.115556)
		(size 0.508)
		(drill 0.254)
		(layers "F.Cu" "B.Cu")
		(net "M_B_CLK_DN<0>")
	)
	(segment
		(start 261.74446 -48.548798)
		(end 261.74446 -48.5267)
		(width 0.0889)
		(layer "In4.Cu")
		(net "M_B_CLK_DN<0>")
	)
	(segment
		(start 257.290316 -7.742682)
		(end 257.290316 -7.425182)
		(width 0.14224)
		(layer "In4.Cu")
		(net "M_B_CLK_DN<0>")
	)
	(segment
		(start 257.60426 -8.056626)
		(end 257.290316 -7.742682)
		(width 0.14224)
		(layer "In4.Cu")
		(net "M_B_CLK_DN<0>")
	)
	(segment
		(start 260.161278 -52.915058)
		(end 260.16204 -52.913788)
		(width 0.0889)
		(layer "In4.Cu")
		(net "M_B_CLK_DN<0>")
	)
	(segment
		(start 261.706614 -49.829974)
		(end 261.706614 -48.586644)
		(width 0.0889)
		(layer "In4.Cu")
		(net "M_B_CLK_DN<0>")
	)
	(segment
		(start 260.50875 -55.094886)
		(end 260.215634 -55.26405)
		(width 0.0889)
		(layer "In4.Cu")
		(net "M_B_CLK_DN<0>")
	)
	(segment
		(start 261.74446 -48.5267)
		(end 261.74446 -26.547064)
		(width 0.14224)
		(layer "In4.Cu")
		(net "M_B_CLK_DN<0>")
	)
	(segment
		(start 261.706614 -48.586644)
		(end 261.74446 -48.548798)
		(width 0.0889)
		(layer "In4.Cu")
		(net "M_B_CLK_DN<0>")
	)
	(segment
		(start 260.097524 -51.439064)
		(end 261.706614 -49.829974)
		(width 0.0889)
		(layer "In4.Cu")
		(net "M_B_CLK_DN<0>")
	)
	(segment
		(start 260.215634 -55.26405)
		(end 260.136894 -55.242714)
		(width 0.0889)
		(layer "In4.Cu")
		(net "M_B_CLK_DN<0>")
	)
	(segment
		(start 261.1628 -10.899648)
		(end 261.1628 -10.13079)
		(width 0.14224)
		(layer "In4.Cu")
		(net "M_B_CLK_DN<0>")
	)
	(segment
		(start 260.157214 -52.922424)
		(end 260.161278 -52.915058)
		(width 0.0889)
		(layer "In4.Cu")
		(net "M_B_CLK_DN<0>")
	)
	(segment
		(start 260.157214 -54.903624)
		(end 260.16204 -54.894988)
		(width 0.0889)
		(layer "In4.Cu")
		(net "M_B_CLK_DN<0>")
	)
	(segment
		(start 260.16204 -52.322984)
		(end 260.097524 -52.211224)
		(width 0.0889)
		(layer "In4.Cu")
		(net "M_B_CLK_DN<0>")
	)
	(segment
		(start 259.088636 -8.056626)
		(end 257.60426 -8.056626)
		(width 0.14224)
		(layer "In4.Cu")
		(net "M_B_CLK_DN<0>")
	)
	(segment
		(start 260.097524 -52.211224)
		(end 260.097524 -51.439064)
		(width 0.0889)
		(layer "In4.Cu")
		(net "M_B_CLK_DN<0>")
	)
	(segment
		(start 262.4836 -19.9898)
		(end 262.4836 -13.6906)
		(width 0.14224)
		(layer "In4.Cu")
		(net "M_B_CLK_DN<0>")
	)
	(segment
		(start 262.4836 -13.6906)
		(end 261.94512 -13.15212)
		(width 0.14224)
		(layer "In4.Cu")
		(net "M_B_CLK_DN<0>")
	)
	(segment
		(start 261.94512 -26.346404)
		(end 261.94512 -20.52828)
		(width 0.14224)
		(layer "In4.Cu")
		(net "M_B_CLK_DN<0>")
	)
	(segment
		(start 261.94512 -11.681968)
		(end 261.1628 -10.899648)
		(width 0.14224)
		(layer "In4.Cu")
		(net "M_B_CLK_DN<0>")
	)
	(segment
		(start 261.74446 -26.547064)
		(end 261.94512 -26.346404)
		(width 0.14224)
		(layer "In4.Cu")
		(net "M_B_CLK_DN<0>")
	)
	(segment
		(start 261.1628 -10.13079)
		(end 259.088636 -8.056626)
		(width 0.14224)
		(layer "In4.Cu")
		(net "M_B_CLK_DN<0>")
	)
	(segment
		(start 261.94512 -20.52828)
		(end 262.4836 -19.9898)
		(width 0.14224)
		(layer "In4.Cu")
		(net "M_B_CLK_DN<0>")
	)
	(segment
		(start 257.290316 -7.425182)
		(end 257.599942 -7.115556)
		(width 0.14224)
		(layer "In4.Cu")
		(net "M_B_CLK_DN<0>")
	)
	(segment
		(start 260.16204 -54.894988)
		(end 260.16839 -54.88432)
		(width 0.0889)
		(layer "In4.Cu")
		(net "M_B_CLK_DN<0>")
	)
	(segment
		(start 261.94512 -13.15212)
		(end 261.94512 -11.681968)
		(width 0.14224)
		(layer "In4.Cu")
		(net "M_B_CLK_DN<0>")
	)
	(segment
		(start 260.157214 -53.913024)
		(end 260.16204 -53.904388)
		(width 0.0889)
		(layer "In4.Cu")
		(net "M_B_CLK_DN<0>")
	)
	(segment
		(start 260.16204 -53.904388)
		(end 260.16839 -53.89372)
		(width 0.0889)
		(layer "In4.Cu")
		(net "M_B_CLK_DN<0>")
	)
	(arc
		(start 260.16204 -53.313838)
		(mid 260.10857 -53.118775)
		(end 260.157214 -52.922424)
		(width 0.0889)
		(layer "In4.Cu")
		(net "M_B_CLK_DN<0>")
	)
	(arc
		(start 260.16839 -53.89372)
		(mid 260.241188 -53.602957)
		(end 260.16204 -53.313838)
		(width 0.0889)
		(layer "In4.Cu")
		(net "M_B_CLK_DN<0>")
	)
	(arc
		(start 260.1087 -55.100474)
		(mid 260.120267 -54.998918)
		(end 260.157214 -54.903624)
		(width 0.0889)
		(layer "In4.Cu")
		(net "M_B_CLK_DN<0>")
	)
	(arc
		(start 260.16204 -54.304438)
		(mid 260.10857 -54.109375)
		(end 260.157214 -53.913024)
		(width 0.0889)
		(layer "In4.Cu")
		(net "M_B_CLK_DN<0>")
	)
	(arc
		(start 260.136894 -55.242714)
		(mid 260.11632 -55.172879)
		(end 260.1087 -55.100474)
		(width 0.0889)
		(layer "In4.Cu")
		(net "M_B_CLK_DN<0>")
	)
	(arc
		(start 260.16204 -52.913788)
		(mid 260.241171 -52.618386)
		(end 260.16204 -52.322984)
		(width 0.0889)
		(layer "In4.Cu")
		(net "M_B_CLK_DN<0>")
	)
	(arc
		(start 260.16839 -54.88432)
		(mid 260.241188 -54.593557)
		(end 260.16204 -54.304438)
		(width 0.0889)
		(layer "In4.Cu")
		(net "M_B_CLK_DN<0>")
	)
	(segment
		(start 251.636784 -54.59984)
		(end 251.065284 -54.59984)
		(width 0.1016)
		(layer "F.Cu")
		(net "M_B_CKE<3>")
	)
	(via
		(at 243.999766 -11.916156)
		(size 0.4572)
		(drill 0.2032)
		(layers "F.Cu" "B.Cu")
		(net "M_B_CKE<3>")
	)
	(via
		(at 251.065284 -54.59984)
		(size 0.508)
		(drill 0.254)
		(layers "F.Cu" "B.Cu")
		(net "M_B_CKE<3>")
	)
	(segment
		(start 244.000274 -10.623042)
		(end 243.999766 -10.623042)
		(width 0.1651)
		(layer "B.Cu")
		(net "M_B_CKE<3>")
	)
	(segment
		(start 243.999766 -10.623042)
		(end 243.999766 -11.916156)
		(width 0.1651)
		(layer "B.Cu")
		(net "M_B_CKE<3>")
	)
	(segment
		(start 251.41682 -53.41747)
		(end 251.411994 -53.408834)
		(width 0.0889)
		(layer "In4.Cu")
		(net "M_B_CKE<3>")
	)
	(segment
		(start 244.438424 -12.354814)
		(end 243.999766 -11.916156)
		(width 0.14224)
		(layer "In4.Cu")
		(net "M_B_CKE<3>")
	)
	(segment
		(start 251.411994 -51.827684)
		(end 251.41682 -51.819048)
		(width 0.0889)
		(layer "In4.Cu")
		(net "M_B_CKE<3>")
	)
	(segment
		(start 251.782072 -50.8635)
		(end 251.782072 -50.268886)
		(width 0.0889)
		(layer "In4.Cu")
		(net "M_B_CKE<3>")
	)
	(segment
		(start 244.438424 -15.731744)
		(end 244.20576 -15.49908)
		(width 0.14224)
		(layer "In4.Cu")
		(net "M_B_CKE<3>")
	)
	(segment
		(start 244.20576 -14.358874)
		(end 244.438424 -14.12621)
		(width 0.14224)
		(layer "In4.Cu")
		(net "M_B_CKE<3>")
	)
	(segment
		(start 244.412262 -18.48612)
		(end 244.493796 -18.404586)
		(width 0.14224)
		(layer "In4.Cu")
		(net "M_B_CKE<3>")
	)
	(segment
		(start 244.412262 -18.987262)
		(end 244.412262 -18.48612)
		(width 0.14224)
		(layer "In4.Cu")
		(net "M_B_CKE<3>")
	)
	(segment
		(start 251.487686 -51.562508)
		(end 251.487686 -51.157886)
		(width 0.0889)
		(layer "In4.Cu")
		(net "M_B_CKE<3>")
	)
	(segment
		(start 244.366796 -22.421596)
		(end 244.366796 -21.938996)
		(width 0.14224)
		(layer "In4.Cu")
		(net "M_B_CKE<3>")
	)
	(segment
		(start 245.774972 -25.150826)
		(end 244.358922 -23.734776)
		(width 0.14224)
		(layer "In4.Cu")
		(net "M_B_CKE<3>")
	)
	(segment
		(start 244.438424 -17.012158)
		(end 244.438424 -15.731744)
		(width 0.14224)
		(layer "In4.Cu")
		(net "M_B_CKE<3>")
	)
	(segment
		(start 245.774972 -27.578812)
		(end 245.774972 -25.150826)
		(width 0.14224)
		(layer "In4.Cu")
		(net "M_B_CKE<3>")
	)
	(segment
		(start 244.493796 -18.404586)
		(end 244.493796 -17.769586)
		(width 0.14224)
		(layer "In4.Cu")
		(net "M_B_CKE<3>")
	)
	(segment
		(start 244.544596 -23.132796)
		(end 244.544596 -22.599396)
		(width 0.14224)
		(layer "In4.Cu")
		(net "M_B_CKE<3>")
	)
	(segment
		(start 244.493796 -17.769586)
		(end 244.341396 -17.617186)
		(width 0.14224)
		(layer "In4.Cu")
		(net "M_B_CKE<3>")
	)
	(segment
		(start 251.782072 -33.585912)
		(end 245.774972 -27.578812)
		(width 0.14224)
		(layer "In4.Cu")
		(net "M_B_CKE<3>")
	)
	(segment
		(start 244.358922 -23.31847)
		(end 244.544596 -23.132796)
		(width 0.14224)
		(layer "In4.Cu")
		(net "M_B_CKE<3>")
	)
	(segment
		(start 244.493796 -21.811996)
		(end 244.493796 -19.068796)
		(width 0.14224)
		(layer "In4.Cu")
		(net "M_B_CKE<3>")
	)
	(segment
		(start 244.493796 -19.068796)
		(end 244.412262 -18.987262)
		(width 0.14224)
		(layer "In4.Cu")
		(net "M_B_CKE<3>")
	)
	(segment
		(start 251.487686 -51.157886)
		(end 251.782072 -50.8635)
		(width 0.0889)
		(layer "In4.Cu")
		(net "M_B_CKE<3>")
	)
	(segment
		(start 244.366796 -21.938996)
		(end 244.493796 -21.811996)
		(width 0.14224)
		(layer "In4.Cu")
		(net "M_B_CKE<3>")
	)
	(segment
		(start 251.065284 -54.59984)
		(end 251.411994 -53.808884)
		(width 0.0889)
		(layer "In4.Cu")
		(net "M_B_CKE<3>")
	)
	(segment
		(start 244.341396 -17.109186)
		(end 244.438424 -17.012158)
		(width 0.14224)
		(layer "In4.Cu")
		(net "M_B_CKE<3>")
	)
	(segment
		(start 244.544596 -22.599396)
		(end 244.366796 -22.421596)
		(width 0.14224)
		(layer "In4.Cu")
		(net "M_B_CKE<3>")
	)
	(segment
		(start 244.438424 -14.12621)
		(end 244.438424 -12.354814)
		(width 0.14224)
		(layer "In4.Cu")
		(net "M_B_CKE<3>")
	)
	(segment
		(start 244.341396 -17.617186)
		(end 244.341396 -17.109186)
		(width 0.14224)
		(layer "In4.Cu")
		(net "M_B_CKE<3>")
	)
	(segment
		(start 251.411994 -53.408834)
		(end 251.405644 -53.398166)
		(width 0.0889)
		(layer "In4.Cu")
		(net "M_B_CKE<3>")
	)
	(segment
		(start 251.782072 -50.268886)
		(end 251.782072 -33.585912)
		(width 0.14224)
		(layer "In4.Cu")
		(net "M_B_CKE<3>")
	)
	(segment
		(start 244.20576 -15.49908)
		(end 244.20576 -14.358874)
		(width 0.14224)
		(layer "In4.Cu")
		(net "M_B_CKE<3>")
	)
	(segment
		(start 244.358922 -23.734776)
		(end 244.358922 -23.31847)
		(width 0.14224)
		(layer "In4.Cu")
		(net "M_B_CKE<3>")
	)
	(segment
		(start 251.418852 -52.43068)
		(end 251.403104 -52.403248)
		(width 0.0889)
		(layer "In4.Cu")
		(net "M_B_CKE<3>")
	)
	(arc
		(start 251.403104 -52.403248)
		(mid 251.332707 -52.114297)
		(end 251.411994 -51.827684)
		(width 0.0889)
		(layer "In4.Cu")
		(net "M_B_CKE<3>")
	)
	(arc
		(start 251.405644 -53.398166)
		(mid 251.332846 -53.107403)
		(end 251.411994 -52.818284)
		(width 0.0889)
		(layer "In4.Cu")
		(net "M_B_CKE<3>")
	)
	(arc
		(start 251.411994 -53.808884)
		(mid 251.465464 -53.613821)
		(end 251.41682 -53.41747)
		(width 0.0889)
		(layer "In4.Cu")
		(net "M_B_CKE<3>")
	)
	(arc
		(start 251.411994 -52.818284)
		(mid 251.465432 -52.625379)
		(end 251.418852 -52.43068)
		(width 0.0889)
		(layer "In4.Cu")
		(net "M_B_CKE<3>")
	)
	(arc
		(start 251.41682 -51.819048)
		(mid 251.468643 -51.695308)
		(end 251.487686 -51.562508)
		(width 0.0889)
		(layer "In4.Cu")
		(net "M_B_CKE<3>")
	)
	(segment
		(start 252.495304 -54.104286)
		(end 251.923804 -54.104286)
		(width 0.1016)
		(layer "F.Cu")
		(net "M_B_CKE<2>")
	)
	(via
		(at 251.923804 -54.104286)
		(size 0.508)
		(drill 0.254)
		(layers "F.Cu" "B.Cu")
		(net "M_B_CKE<2>")
	)
	(via
		(at 244.849904 -13.933678)
		(size 0.4572)
		(drill 0.2032)
		(layers "F.Cu" "B.Cu")
		(net "M_B_CKE<2>")
	)
	(segment
		(start 244.849904 -15.222982)
		(end 244.849904 -13.933678)
		(width 0.1651)
		(layer "B.Cu")
		(net "M_B_CKE<2>")
	)
	(segment
		(start 244.850412 -15.222982)
		(end 244.849904 -15.222982)
		(width 0.1651)
		(layer "B.Cu")
		(net "M_B_CKE<2>")
	)
	(segment
		(start 245.357396 -14.829282)
		(end 244.849904 -14.32179)
		(width 0.14224)
		(layer "In4.Cu")
		(net "M_B_CKE<2>")
	)
	(segment
		(start 245.357396 -23.285196)
		(end 245.179596 -23.107396)
		(width 0.14224)
		(layer "In4.Cu")
		(net "M_B_CKE<2>")
	)
	(segment
		(start 251.577094 -52.322984)
		(end 251.570236 -52.310792)
		(width 0.0889)
		(layer "In4.Cu")
		(net "M_B_CKE<2>")
	)
	(segment
		(start 246.30507 -27.254708)
		(end 246.30507 -24.962358)
		(width 0.14224)
		(layer "In4.Cu")
		(net "M_B_CKE<2>")
	)
	(segment
		(start 252.245876 -33.195514)
		(end 246.30507 -27.254708)
		(width 0.14224)
		(layer "In4.Cu")
		(net "M_B_CKE<2>")
	)
	(segment
		(start 245.264686 -17.041876)
		(end 245.264686 -16.482568)
		(width 0.14224)
		(layer "In4.Cu")
		(net "M_B_CKE<2>")
	)
	(segment
		(start 244.849904 -14.32179)
		(end 244.849904 -13.933678)
		(width 0.14224)
		(layer "In4.Cu")
		(net "M_B_CKE<2>")
	)
	(segment
		(start 251.923804 -54.104286)
		(end 251.594366 -53.343302)
		(width 0.0889)
		(layer "In4.Cu")
		(net "M_B_CKE<2>")
	)
	(segment
		(start 251.594366 -53.343302)
		(end 251.572268 -53.304948)
		(width 0.0889)
		(layer "In4.Cu")
		(net "M_B_CKE<2>")
	)
	(segment
		(start 245.204996 -18.379186)
		(end 245.204996 -17.794986)
		(width 0.14224)
		(layer "In4.Cu")
		(net "M_B_CKE<2>")
	)
	(segment
		(start 252.245876 -50.470562)
		(end 252.245876 -33.195514)
		(width 0.14224)
		(layer "In4.Cu")
		(net "M_B_CKE<2>")
	)
	(segment
		(start 245.287546 -18.461736)
		(end 245.204996 -18.379186)
		(width 0.14224)
		(layer "In4.Cu")
		(net "M_B_CKE<2>")
	)
	(segment
		(start 245.357396 -17.134586)
		(end 245.264686 -17.041876)
		(width 0.14224)
		(layer "In4.Cu")
		(net "M_B_CKE<2>")
	)
	(segment
		(start 251.583444 -52.333652)
		(end 251.577094 -52.322984)
		(width 0.0889)
		(layer "In4.Cu")
		(net "M_B_CKE<2>")
	)
	(segment
		(start 245.357396 -17.642586)
		(end 245.357396 -17.134586)
		(width 0.14224)
		(layer "In4.Cu")
		(net "M_B_CKE<2>")
	)
	(segment
		(start 245.264686 -16.482568)
		(end 245.357396 -16.389858)
		(width 0.14224)
		(layer "In4.Cu")
		(net "M_B_CKE<2>")
	)
	(segment
		(start 245.357396 -21.913596)
		(end 245.204996 -21.761196)
		(width 0.14224)
		(layer "In4.Cu")
		(net "M_B_CKE<2>")
	)
	(segment
		(start 245.204996 -21.761196)
		(end 245.204996 -19.141186)
		(width 0.14224)
		(layer "In4.Cu")
		(net "M_B_CKE<2>")
	)
	(segment
		(start 245.179596 -22.573996)
		(end 245.357396 -22.396196)
		(width 0.14224)
		(layer "In4.Cu")
		(net "M_B_CKE<2>")
	)
	(segment
		(start 245.204996 -19.141186)
		(end 245.287546 -19.058636)
		(width 0.14224)
		(layer "In4.Cu")
		(net "M_B_CKE<2>")
	)
	(segment
		(start 245.357396 -16.389858)
		(end 245.357396 -14.829282)
		(width 0.14224)
		(layer "In4.Cu")
		(net "M_B_CKE<2>")
	)
	(segment
		(start 252.245876 -50.787554)
		(end 252.245876 -50.470562)
		(width 0.0889)
		(layer "In4.Cu")
		(net "M_B_CKE<2>")
	)
	(segment
		(start 245.357396 -22.396196)
		(end 245.357396 -21.913596)
		(width 0.14224)
		(layer "In4.Cu")
		(net "M_B_CKE<2>")
	)
	(segment
		(start 245.357396 -24.014684)
		(end 245.357396 -23.285196)
		(width 0.14224)
		(layer "In4.Cu")
		(net "M_B_CKE<2>")
	)
	(segment
		(start 245.179596 -23.107396)
		(end 245.179596 -22.573996)
		(width 0.14224)
		(layer "In4.Cu")
		(net "M_B_CKE<2>")
	)
	(segment
		(start 251.704602 -51.44643)
		(end 251.704602 -51.328828)
		(width 0.0889)
		(layer "In4.Cu")
		(net "M_B_CKE<2>")
	)
	(segment
		(start 246.30507 -24.962358)
		(end 245.357396 -24.014684)
		(width 0.14224)
		(layer "In4.Cu")
		(net "M_B_CKE<2>")
	)
	(segment
		(start 245.204996 -17.794986)
		(end 245.357396 -17.642586)
		(width 0.14224)
		(layer "In4.Cu")
		(net "M_B_CKE<2>")
	)
	(segment
		(start 251.704602 -51.328828)
		(end 252.245876 -50.787554)
		(width 0.0889)
		(layer "In4.Cu")
		(net "M_B_CKE<2>")
	)
	(segment
		(start 245.287546 -19.058636)
		(end 245.287546 -18.461736)
		(width 0.14224)
		(layer "In4.Cu")
		(net "M_B_CKE<2>")
	)
	(arc
		(start 251.577094 -51.923188)
		(mid 251.672202 -51.693192)
		(end 251.704602 -51.44643)
		(width 0.0889)
		(layer "In4.Cu")
		(net "M_B_CKE<2>")
	)
	(arc
		(start 251.572268 -53.304948)
		(mid 251.523513 -53.108596)
		(end 251.577094 -52.913534)
		(width 0.0889)
		(layer "In4.Cu")
		(net "M_B_CKE<2>")
	)
	(arc
		(start 251.570236 -52.310792)
		(mid 251.52356 -52.116091)
		(end 251.577094 -51.923188)
		(width 0.0889)
		(layer "In4.Cu")
		(net "M_B_CKE<2>")
	)
	(arc
		(start 251.577094 -52.913534)
		(mid 251.656316 -52.624416)
		(end 251.583444 -52.333652)
		(width 0.0889)
		(layer "In4.Cu")
		(net "M_B_CKE<2>")
	)
	(segment
		(start 251.636784 -56.58104)
		(end 251.065284 -56.58104)
		(width 0.1016)
		(layer "F.Cu")
		(net "M_B_CKE<1>")
	)
	(segment
		(start 243.999766 -10.422382)
		(end 243.999766 -9.133078)
		(width 0.1651)
		(layer "F.Cu")
		(net "M_B_CKE<1>")
	)
	(segment
		(start 244.000274 -10.422382)
		(end 243.999766 -10.422382)
		(width 0.1651)
		(layer "F.Cu")
		(net "M_B_CKE<1>")
	)
	(via
		(at 243.999766 -9.133078)
		(size 0.4572)
		(drill 0.2032)
		(layers "F.Cu" "B.Cu")
		(net "M_B_CKE<1>")
	)
	(via
		(at 251.065284 -56.58104)
		(size 0.508)
		(drill 0.254)
		(layers "F.Cu" "B.Cu")
		(net "M_B_CKE<1>")
	)
	(segment
		(start 243.757196 -23.851616)
		(end 243.757196 -23.437596)
		(width 0.14224)
		(layer "In4.Cu")
		(net "M_B_CKE<1>")
	)
	(segment
		(start 243.503196 -22.662896)
		(end 243.757196 -22.408896)
		(width 0.14224)
		(layer "In4.Cu")
		(net "M_B_CKE<1>")
	)
	(segment
		(start 243.503196 -21.710396)
		(end 243.503196 -19.082258)
		(width 0.14224)
		(layer "In4.Cu")
		(net "M_B_CKE<1>")
	)
	(segment
		(start 250.66244 -54.50332)
		(end 250.66244 -51.36896)
		(width 0.0889)
		(layer "In4.Cu")
		(net "M_B_CKE<1>")
	)
	(segment
		(start 243.757196 -18.300954)
		(end 243.757196 -17.159986)
		(width 0.14224)
		(layer "In4.Cu")
		(net "M_B_CKE<1>")
	)
	(segment
		(start 243.586 -9.546844)
		(end 243.999766 -9.133078)
		(width 0.14224)
		(layer "In4.Cu")
		(net "M_B_CKE<1>")
	)
	(segment
		(start 243.586 -12.446)
		(end 243.586 -9.546844)
		(width 0.14224)
		(layer "In4.Cu")
		(net "M_B_CKE<1>")
	)
	(segment
		(start 250.724924 -54.810406)
		(end 250.718574 -54.799738)
		(width 0.0889)
		(layer "In4.Cu")
		(net "M_B_CKE<1>")
	)
	(segment
		(start 243.7384 -12.5984)
		(end 243.586 -12.446)
		(width 0.14224)
		(layer "In4.Cu")
		(net "M_B_CKE<1>")
	)
	(segment
		(start 243.757196 -22.408896)
		(end 243.757196 -21.964396)
		(width 0.14224)
		(layer "In4.Cu")
		(net "M_B_CKE<1>")
	)
	(segment
		(start 243.7384 -13.10894)
		(end 243.7384 -12.5984)
		(width 0.14224)
		(layer "In4.Cu")
		(net "M_B_CKE<1>")
	)
	(segment
		(start 243.566696 -13.280644)
		(end 243.7384 -13.10894)
		(width 0.14224)
		(layer "In4.Cu")
		(net "M_B_CKE<1>")
	)
	(segment
		(start 251.386086 -33.963864)
		(end 245.269766 -27.847544)
		(width 0.14224)
		(layer "In4.Cu")
		(net "M_B_CKE<1>")
	)
	(segment
		(start 243.757196 -21.964396)
		(end 243.503196 -21.710396)
		(width 0.14224)
		(layer "In4.Cu")
		(net "M_B_CKE<1>")
	)
	(segment
		(start 243.59108 -18.994374)
		(end 243.59108 -18.46707)
		(width 0.14224)
		(layer "In4.Cu")
		(net "M_B_CKE<1>")
	)
	(segment
		(start 243.757196 -23.437596)
		(end 243.503196 -23.183596)
		(width 0.14224)
		(layer "In4.Cu")
		(net "M_B_CKE<1>")
	)
	(segment
		(start 245.269766 -25.364186)
		(end 243.757196 -23.851616)
		(width 0.14224)
		(layer "In4.Cu")
		(net "M_B_CKE<1>")
	)
	(segment
		(start 243.566696 -16.969486)
		(end 243.566696 -13.280644)
		(width 0.14224)
		(layer "In4.Cu")
		(net "M_B_CKE<1>")
	)
	(segment
		(start 251.386086 -50.645314)
		(end 251.386086 -50.26279)
		(width 0.0889)
		(layer "In4.Cu")
		(net "M_B_CKE<1>")
	)
	(segment
		(start 243.757196 -17.159986)
		(end 243.566696 -16.969486)
		(width 0.14224)
		(layer "In4.Cu")
		(net "M_B_CKE<1>")
	)
	(segment
		(start 251.386086 -50.26279)
		(end 251.386086 -33.963864)
		(width 0.14224)
		(layer "In4.Cu")
		(net "M_B_CKE<1>")
	)
	(segment
		(start 243.503196 -19.082258)
		(end 243.59108 -18.994374)
		(width 0.14224)
		(layer "In4.Cu")
		(net "M_B_CKE<1>")
	)
	(segment
		(start 250.66244 -51.36896)
		(end 251.386086 -50.645314)
		(width 0.0889)
		(layer "In4.Cu")
		(net "M_B_CKE<1>")
	)
	(segment
		(start 243.59108 -18.46707)
		(end 243.757196 -18.300954)
		(width 0.14224)
		(layer "In4.Cu")
		(net "M_B_CKE<1>")
	)
	(segment
		(start 250.665234 -54.610254)
		(end 250.66244 -54.50332)
		(width 0.0889)
		(layer "In4.Cu")
		(net "M_B_CKE<1>")
	)
	(segment
		(start 243.503196 -23.183596)
		(end 243.503196 -22.662896)
		(width 0.14224)
		(layer "In4.Cu")
		(net "M_B_CKE<1>")
	)
	(segment
		(start 245.269766 -27.847544)
		(end 245.269766 -25.364186)
		(width 0.14224)
		(layer "In4.Cu")
		(net "M_B_CKE<1>")
	)
	(segment
		(start 250.735846 -55.820056)
		(end 250.713748 -55.781702)
		(width 0.0889)
		(layer "In4.Cu")
		(net "M_B_CKE<1>")
	)
	(segment
		(start 251.065284 -56.58104)
		(end 250.735846 -55.820056)
		(width 0.0889)
		(layer "In4.Cu")
		(net "M_B_CKE<1>")
	)
	(arc
		(start 250.718574 -54.799738)
		(mid 250.68006 -54.708329)
		(end 250.665234 -54.610254)
		(width 0.0889)
		(layer "In4.Cu")
		(net "M_B_CKE<1>")
	)
	(arc
		(start 250.713748 -55.781702)
		(mid 250.664993 -55.58535)
		(end 250.718574 -55.390288)
		(width 0.0889)
		(layer "In4.Cu")
		(net "M_B_CKE<1>")
	)
	(arc
		(start 250.718574 -55.390288)
		(mid 250.797796 -55.10117)
		(end 250.724924 -54.810406)
		(width 0.0889)
		(layer "In4.Cu")
		(net "M_B_CKE<1>")
	)
	(segment
		(start 244.849904 -5.822442)
		(end 244.849904 -7.115556)
		(width 0.1651)
		(layer "F.Cu")
		(net "M_B_CKE<0>")
	)
	(segment
		(start 244.850412 -5.822442)
		(end 244.849904 -5.822442)
		(width 0.1651)
		(layer "F.Cu")
		(net "M_B_CKE<0>")
	)
	(segment
		(start 253.353824 -55.59044)
		(end 252.782324 -55.59044)
		(width 0.1016)
		(layer "F.Cu")
		(net "M_B_CKE<0>")
	)
	(via
		(at 252.782324 -55.59044)
		(size 0.508)
		(drill 0.254)
		(layers "F.Cu" "B.Cu")
		(net "M_B_CKE<0>")
	)
	(via
		(at 244.849904 -7.115556)
		(size 0.4572)
		(drill 0.2032)
		(layers "F.Cu" "B.Cu")
		(net "M_B_CKE<0>")
	)
	(segment
		(start 246.043196 -23.981918)
		(end 246.872252 -24.810974)
		(width 0.14224)
		(layer "In4.Cu")
		(net "M_B_CKE<0>")
	)
	(segment
		(start 245.872 -14.74724)
		(end 245.872 -16.230854)
		(width 0.14224)
		(layer "In4.Cu")
		(net "M_B_CKE<0>")
	)
	(segment
		(start 245.992396 -17.566386)
		(end 246.1133 -17.68729)
		(width 0.14224)
		(layer "In4.Cu")
		(net "M_B_CKE<0>")
	)
	(segment
		(start 252.270514 -53.904388)
		(end 252.27534 -53.913024)
		(width 0.0889)
		(layer "In4.Cu")
		(net "M_B_CKE<0>")
	)
	(segment
		(start 246.872252 -24.810974)
		(end 246.872252 -27.009852)
		(width 0.14224)
		(layer "In4.Cu")
		(net "M_B_CKE<0>")
	)
	(segment
		(start 246.195596 -21.278596)
		(end 246.195596 -21.735796)
		(width 0.14224)
		(layer "In4.Cu")
		(net "M_B_CKE<0>")
	)
	(segment
		(start 245.2878 -8.706612)
		(end 245.2878 -12.63396)
		(width 0.14224)
		(layer "In4.Cu")
		(net "M_B_CKE<0>")
	)
	(segment
		(start 246.195596 -21.735796)
		(end 246.043196 -21.888196)
		(width 0.14224)
		(layer "In4.Cu")
		(net "M_B_CKE<0>")
	)
	(segment
		(start 252.264164 -54.88432)
		(end 252.270514 -54.894988)
		(width 0.0889)
		(layer "In4.Cu")
		(net "M_B_CKE<0>")
	)
	(segment
		(start 246.140224 -16.499078)
		(end 246.140224 -17.088358)
		(width 0.14224)
		(layer "In4.Cu")
		(net "M_B_CKE<0>")
	)
	(segment
		(start 252.270514 -54.894988)
		(end 252.35154 -55.037228)
		(width 0.0889)
		(layer "In4.Cu")
		(net "M_B_CKE<0>")
	)
	(segment
		(start 246.140224 -17.088358)
		(end 245.992396 -17.236186)
		(width 0.14224)
		(layer "In4.Cu")
		(net "M_B_CKE<0>")
	)
	(segment
		(start 252.185424 -51.328828)
		(end 252.185424 -51.775614)
		(width 0.0889)
		(layer "In4.Cu")
		(net "M_B_CKE<0>")
	)
	(segment
		(start 245.992396 -17.236186)
		(end 245.992396 -17.566386)
		(width 0.14224)
		(layer "In4.Cu")
		(net "M_B_CKE<0>")
	)
	(segment
		(start 252.744986 -55.553102)
		(end 252.782324 -55.59044)
		(width 0.0889)
		(layer "In4.Cu")
		(net "M_B_CKE<0>")
	)
	(segment
		(start 246.195596 -22.599396)
		(end 246.195596 -23.107396)
		(width 0.14224)
		(layer "In4.Cu")
		(net "M_B_CKE<0>")
	)
	(segment
		(start 244.849904 -7.115556)
		(end 244.849904 -8.268716)
		(width 0.14224)
		(layer "In4.Cu")
		(net "M_B_CKE<0>")
	)
	(segment
		(start 246.872252 -27.009852)
		(end 252.63983 -32.77743)
		(width 0.14224)
		(layer "In4.Cu")
		(net "M_B_CKE<0>")
	)
	(segment
		(start 245.2624 -12.65936)
		(end 245.2624 -14.13764)
		(width 0.14224)
		(layer "In4.Cu")
		(net "M_B_CKE<0>")
	)
	(segment
		(start 246.043196 -22.446996)
		(end 246.195596 -22.599396)
		(width 0.14224)
		(layer "In4.Cu")
		(net "M_B_CKE<0>")
	)
	(segment
		(start 252.264164 -53.89372)
		(end 252.270514 -53.904388)
		(width 0.0889)
		(layer "In4.Cu")
		(net "M_B_CKE<0>")
	)
	(segment
		(start 246.1133 -17.68729)
		(end 246.1133 -21.1963)
		(width 0.14224)
		(layer "In4.Cu")
		(net "M_B_CKE<0>")
	)
	(segment
		(start 246.043196 -23.259796)
		(end 246.043196 -23.981918)
		(width 0.14224)
		(layer "In4.Cu")
		(net "M_B_CKE<0>")
	)
	(segment
		(start 252.63983 -50.874422)
		(end 252.185424 -51.328828)
		(width 0.0889)
		(layer "In4.Cu")
		(net "M_B_CKE<0>")
	)
	(segment
		(start 245.2878 -12.63396)
		(end 245.2624 -12.65936)
		(width 0.14224)
		(layer "In4.Cu")
		(net "M_B_CKE<0>")
	)
	(segment
		(start 252.270514 -52.913788)
		(end 252.27534 -52.922424)
		(width 0.0889)
		(layer "In4.Cu")
		(net "M_B_CKE<0>")
	)
	(segment
		(start 244.849904 -8.268716)
		(end 245.2878 -8.706612)
		(width 0.14224)
		(layer "In4.Cu")
		(net "M_B_CKE<0>")
	)
	(segment
		(start 252.185424 -51.775614)
		(end 252.270514 -51.923442)
		(width 0.0889)
		(layer "In4.Cu")
		(net "M_B_CKE<0>")
	)
	(segment
		(start 252.270514 -52.323238)
		(end 252.264164 -52.333906)
		(width 0.0889)
		(layer "In4.Cu")
		(net "M_B_CKE<0>")
	)
	(segment
		(start 246.1133 -21.1963)
		(end 246.195596 -21.278596)
		(width 0.14224)
		(layer "In4.Cu")
		(net "M_B_CKE<0>")
	)
	(segment
		(start 252.63983 -50.379884)
		(end 252.63983 -50.874422)
		(width 0.0889)
		(layer "In4.Cu")
		(net "M_B_CKE<0>")
	)
	(segment
		(start 245.872 -16.230854)
		(end 246.140224 -16.499078)
		(width 0.14224)
		(layer "In4.Cu")
		(net "M_B_CKE<0>")
	)
	(segment
		(start 245.2624 -14.13764)
		(end 245.872 -14.74724)
		(width 0.14224)
		(layer "In4.Cu")
		(net "M_B_CKE<0>")
	)
	(segment
		(start 252.63983 -32.77743)
		(end 252.63983 -50.379884)
		(width 0.14224)
		(layer "In4.Cu")
		(net "M_B_CKE<0>")
	)
	(segment
		(start 246.195596 -23.107396)
		(end 246.043196 -23.259796)
		(width 0.14224)
		(layer "In4.Cu")
		(net "M_B_CKE<0>")
	)
	(segment
		(start 246.043196 -21.888196)
		(end 246.043196 -22.446996)
		(width 0.14224)
		(layer "In4.Cu")
		(net "M_B_CKE<0>")
	)
	(arc
		(start 252.35154 -55.037228)
		(mid 252.530985 -55.308343)
		(end 252.744986 -55.553102)
		(width 0.0889)
		(layer "In4.Cu")
		(net "M_B_CKE<0>")
	)
	(arc
		(start 252.264164 -52.333906)
		(mid 252.191366 -52.624669)
		(end 252.270514 -52.913788)
		(width 0.0889)
		(layer "In4.Cu")
		(net "M_B_CKE<0>")
	)
	(arc
		(start 252.270514 -54.304438)
		(mid 252.191292 -54.593556)
		(end 252.264164 -54.88432)
		(width 0.0889)
		(layer "In4.Cu")
		(net "M_B_CKE<0>")
	)
	(arc
		(start 252.27534 -53.913024)
		(mid 252.324095 -54.109376)
		(end 252.270514 -54.304438)
		(width 0.0889)
		(layer "In4.Cu")
		(net "M_B_CKE<0>")
	)
	(arc
		(start 252.270514 -51.923442)
		(mid 252.324013 -52.12334)
		(end 252.270514 -52.323238)
		(width 0.0889)
		(layer "In4.Cu")
		(net "M_B_CKE<0>")
	)
	(arc
		(start 252.27534 -52.922424)
		(mid 252.324095 -53.118776)
		(end 252.270514 -53.313838)
		(width 0.0889)
		(layer "In4.Cu")
		(net "M_B_CKE<0>")
	)
	(arc
		(start 252.270514 -53.313838)
		(mid 252.191292 -53.602956)
		(end 252.264164 -53.89372)
		(width 0.0889)
		(layer "In4.Cu")
		(net "M_B_CKE<0>")
	)
	(segment
		(start 276.29993 -9.133586)
		(end 276.300438 -9.133078)
		(width 0.10795)
		(layer "F.Cu")
		(net "M_B_C<2>")
	)
	(segment
		(start 276.300438 -10.422382)
		(end 276.29993 -10.422382)
		(width 0.10795)
		(layer "F.Cu")
		(net "M_B_C<2>")
	)
	(segment
		(start 266.231116 -55.094886)
		(end 265.659616 -55.094886)
		(width 0.1016)
		(layer "F.Cu")
		(net "M_B_C<2>")
	)
	(segment
		(start 276.29993 -10.422382)
		(end 276.29993 -9.133586)
		(width 0.10795)
		(layer "F.Cu")
		(net "M_B_C<2>")
	)
	(via
		(at 265.659616 -55.094886)
		(size 0.508)
		(drill 0.254)
		(layers "F.Cu" "B.Cu")
		(net "M_B_C<2>")
	)
	(via
		(at 276.300438 -9.133078)
		(size 0.4572)
		(drill 0.2032)
		(layers "F.Cu" "B.Cu")
		(net "M_B_C<2>")
	)
	(via
		(at 276.300438 -11.918188)
		(size 0.4572)
		(drill 0.2032)
		(layers "F.Cu" "B.Cu")
		(net "M_B_C<2>")
	)
	(segment
		(start 276.29993 -10.623042)
		(end 276.29993 -11.91768)
		(width 0.10795)
		(layer "B.Cu")
		(net "M_B_C<2>")
	)
	(segment
		(start 276.29993 -11.91768)
		(end 276.300438 -11.918188)
		(width 0.10795)
		(layer "B.Cu")
		(net "M_B_C<2>")
	)
	(segment
		(start 276.300438 -10.623042)
		(end 276.29993 -10.623042)
		(width 0.10795)
		(layer "B.Cu")
		(net "M_B_C<2>")
	)
	(segment
		(start 275.0566 -23.9014)
		(end 275.0566 -25.7048)
		(width 0.14224)
		(layer "In11.Cu")
		(net "M_B_C<2>")
	)
	(segment
		(start 275.082 -21.2598)
		(end 275.082 -21.6916)
		(width 0.14224)
		(layer "In11.Cu")
		(net "M_B_C<2>")
	)
	(segment
		(start 274.9296 -23.7744)
		(end 275.0566 -23.9014)
		(width 0.14224)
		(layer "In11.Cu")
		(net "M_B_C<2>")
	)
	(segment
		(start 274.9296 -19.4691)
		(end 274.9296 -21.1074)
		(width 0.14224)
		(layer "In11.Cu")
		(net "M_B_C<2>")
	)
	(segment
		(start 275.8694 -9.564116)
		(end 276.300438 -9.133078)
		(width 0.14224)
		(layer "In11.Cu")
		(net "M_B_C<2>")
	)
	(segment
		(start 275.776944 -13.572744)
		(end 275.88591 -13.68171)
		(width 0.14224)
		(layer "In11.Cu")
		(net "M_B_C<2>")
	)
	(segment
		(start 276.29993 -11.918696)
		(end 276.29993 -12.57427)
		(width 0.14224)
		(layer "In11.Cu")
		(net "M_B_C<2>")
	)
	(segment
		(start 274.9296 -21.1074)
		(end 275.082 -21.2598)
		(width 0.14224)
		(layer "In11.Cu")
		(net "M_B_C<2>")
	)
	(segment
		(start 274.667726 -18.02638)
		(end 275.037296 -18.39595)
		(width 0.14224)
		(layer "In11.Cu")
		(net "M_B_C<2>")
	)
	(segment
		(start 266.582144 -49.787048)
		(end 266.107926 -51.555142)
		(width 0.0889)
		(layer "In11.Cu")
		(net "M_B_C<2>")
	)
	(segment
		(start 275.88591 -15.533116)
		(end 275.037296 -16.38173)
		(width 0.14224)
		(layer "In11.Cu")
		(net "M_B_C<2>")
	)
	(segment
		(start 275.082 -23.1394)
		(end 274.9296 -23.2918)
		(width 0.14224)
		(layer "In11.Cu")
		(net "M_B_C<2>")
	)
	(segment
		(start 274.8788 -22.479)
		(end 275.082 -22.6822)
		(width 0.14224)
		(layer "In11.Cu")
		(net "M_B_C<2>")
	)
	(segment
		(start 267.336524 -48.641)
		(end 267.336524 -49.032668)
		(width 0.0889)
		(layer "In11.Cu")
		(net "M_B_C<2>")
	)
	(segment
		(start 275.037296 -16.38173)
		(end 275.037296 -16.960596)
		(width 0.14224)
		(layer "In11.Cu")
		(net "M_B_C<2>")
	)
	(segment
		(start 275.037296 -16.960596)
		(end 274.667726 -17.330166)
		(width 0.14224)
		(layer "In11.Cu")
		(net "M_B_C<2>")
	)
	(segment
		(start 276.29993 -12.57427)
		(end 275.776944 -13.097256)
		(width 0.14224)
		(layer "In11.Cu")
		(net "M_B_C<2>")
	)
	(segment
		(start 274.9296 -23.2918)
		(end 274.9296 -23.7744)
		(width 0.14224)
		(layer "In11.Cu")
		(net "M_B_C<2>")
	)
	(segment
		(start 275.8694 -11.48715)
		(end 275.8694 -9.564116)
		(width 0.14224)
		(layer "In11.Cu")
		(net "M_B_C<2>")
	)
	(segment
		(start 274.6502 -26.1112)
		(end 274.6502 -27.960066)
		(width 0.14224)
		(layer "In11.Cu")
		(net "M_B_C<2>")
	)
	(segment
		(start 274.667726 -17.330166)
		(end 274.667726 -18.02638)
		(width 0.14224)
		(layer "In11.Cu")
		(net "M_B_C<2>")
	)
	(segment
		(start 265.329416 -54.33314)
		(end 265.659616 -55.094886)
		(width 0.0889)
		(layer "In11.Cu")
		(net "M_B_C<2>")
	)
	(segment
		(start 275.037296 -18.39595)
		(end 275.037296 -19.361404)
		(width 0.14224)
		(layer "In11.Cu")
		(net "M_B_C<2>")
	)
	(segment
		(start 276.300438 -11.918188)
		(end 276.29993 -11.918696)
		(width 0.14224)
		(layer "In11.Cu")
		(net "M_B_C<2>")
	)
	(segment
		(start 275.037296 -19.361404)
		(end 274.9296 -19.4691)
		(width 0.14224)
		(layer "In11.Cu")
		(net "M_B_C<2>")
	)
	(segment
		(start 275.0566 -25.7048)
		(end 274.6502 -26.1112)
		(width 0.14224)
		(layer "In11.Cu")
		(net "M_B_C<2>")
	)
	(segment
		(start 274.6502 -27.960066)
		(end 267.336524 -35.273742)
		(width 0.14224)
		(layer "In11.Cu")
		(net "M_B_C<2>")
	)
	(segment
		(start 267.336524 -35.273742)
		(end 267.336524 -48.641)
		(width 0.14224)
		(layer "In11.Cu")
		(net "M_B_C<2>")
	)
	(segment
		(start 274.8788 -21.8948)
		(end 274.8788 -22.479)
		(width 0.14224)
		(layer "In11.Cu")
		(net "M_B_C<2>")
	)
	(segment
		(start 275.082 -21.6916)
		(end 274.8788 -21.8948)
		(width 0.14224)
		(layer "In11.Cu")
		(net "M_B_C<2>")
	)
	(segment
		(start 275.082 -22.6822)
		(end 275.082 -23.1394)
		(width 0.14224)
		(layer "In11.Cu")
		(net "M_B_C<2>")
	)
	(segment
		(start 266.107926 -51.555142)
		(end 265.312906 -52.914296)
		(width 0.0889)
		(layer "In11.Cu")
		(net "M_B_C<2>")
	)
	(segment
		(start 276.300438 -11.918188)
		(end 275.8694 -11.48715)
		(width 0.14224)
		(layer "In11.Cu")
		(net "M_B_C<2>")
	)
	(segment
		(start 265.312906 -54.304692)
		(end 265.329416 -54.33314)
		(width 0.0889)
		(layer "In11.Cu")
		(net "M_B_C<2>")
	)
	(segment
		(start 275.88591 -13.68171)
		(end 275.88591 -15.533116)
		(width 0.14224)
		(layer "In11.Cu")
		(net "M_B_C<2>")
	)
	(segment
		(start 275.776944 -13.097256)
		(end 275.776944 -13.572744)
		(width 0.14224)
		(layer "In11.Cu")
		(net "M_B_C<2>")
	)
	(segment
		(start 267.336524 -49.032668)
		(end 266.582144 -49.787048)
		(width 0.0889)
		(layer "In11.Cu")
		(net "M_B_C<2>")
	)
	(arc
		(start 265.312906 -53.314092)
		(mid 265.392037 -53.609494)
		(end 265.312906 -53.904896)
		(width 0.0889)
		(layer "In11.Cu")
		(net "M_B_C<2>")
	)
	(arc
		(start 265.312906 -52.914296)
		(mid 265.259407 -53.114194)
		(end 265.312906 -53.314092)
		(width 0.0889)
		(layer "In11.Cu")
		(net "M_B_C<2>")
	)
	(arc
		(start 265.312906 -53.904896)
		(mid 265.259407 -54.104794)
		(end 265.312906 -54.304692)
		(width 0.0889)
		(layer "In11.Cu")
		(net "M_B_C<2>")
	)
	(segment
		(start 247.39981 -10.422382)
		(end 247.39981 -9.133078)
		(width 0.1651)
		(layer "F.Cu")
		(net "M_B_BG<1>")
	)
	(segment
		(start 247.400318 -10.422382)
		(end 247.39981 -10.422382)
		(width 0.1651)
		(layer "F.Cu")
		(net "M_B_BG<1>")
	)
	(segment
		(start 255.07061 -55.59044)
		(end 254.49911 -55.59044)
		(width 0.1016)
		(layer "F.Cu")
		(net "M_B_BG<1>")
	)
	(via
		(at 254.49911 -55.59044)
		(size 0.508)
		(drill 0.254)
		(layers "F.Cu" "B.Cu")
		(net "M_B_BG<1>")
	)
	(via
		(at 247.39981 -11.916156)
		(size 0.4572)
		(drill 0.2032)
		(layers "F.Cu" "B.Cu")
		(net "M_B_BG<1>")
	)
	(via
		(at 247.39981 -9.133078)
		(size 0.4572)
		(drill 0.2032)
		(layers "F.Cu" "B.Cu")
		(net "M_B_BG<1>")
	)
	(segment
		(start 247.39981 -10.623042)
		(end 247.39981 -11.916156)
		(width 0.1651)
		(layer "B.Cu")
		(net "M_B_BG<1>")
	)
	(segment
		(start 247.400318 -10.623042)
		(end 247.39981 -10.623042)
		(width 0.1651)
		(layer "B.Cu")
		(net "M_B_BG<1>")
	)
	(segment
		(start 251.236734 -16.40967)
		(end 251.236734 -17.001998)
		(width 0.14224)
		(layer "In11.Cu")
		(net "M_B_BG<1>")
	)
	(segment
		(start 251.2314 -23.7744)
		(end 251.2314 -25.8826)
		(width 0.14224)
		(layer "In11.Cu")
		(net "M_B_BG<1>")
	)
	(segment
		(start 251.236734 -17.001998)
		(end 251.333 -17.098264)
		(width 0.14224)
		(layer "In11.Cu")
		(net "M_B_BG<1>")
	)
	(segment
		(start 251.9934 -27.000454)
		(end 251.7902 -27.203654)
		(width 0.14224)
		(layer "In11.Cu")
		(net "M_B_BG<1>")
	)
	(segment
		(start 254.0508 -50.927)
		(end 254.0508 -53.076856)
		(width 0.0889)
		(layer "In11.Cu")
		(net "M_B_BG<1>")
	)
	(segment
		(start 251.1044 -23.3172)
		(end 251.1044 -23.6474)
		(width 0.14224)
		(layer "In11.Cu")
		(net "M_B_BG<1>")
	)
	(segment
		(start 253.97841 -54.879748)
		(end 254.003556 -54.92369)
		(width 0.0889)
		(layer "In11.Cu")
		(net "M_B_BG<1>")
	)
	(segment
		(start 251.20981 -19.10461)
		(end 251.333 -19.2278)
		(width 0.14224)
		(layer "In11.Cu")
		(net "M_B_BG<1>")
	)
	(segment
		(start 251.46 -27.406854)
		(end 251.46 -27.813254)
		(width 0.14224)
		(layer "In11.Cu")
		(net "M_B_BG<1>")
	)
	(segment
		(start 251.333 -19.2278)
		(end 251.333 -21.7932)
		(width 0.14224)
		(layer "In11.Cu")
		(net "M_B_BG<1>")
	)
	(segment
		(start 247.942354 -14.414754)
		(end 247.942354 -15.444216)
		(width 0.14224)
		(layer "In11.Cu")
		(net "M_B_BG<1>")
	)
	(segment
		(start 253.948184 -50.62347)
		(end 253.948184 -50.824384)
		(width 0.0889)
		(layer "In11.Cu")
		(net "M_B_BG<1>")
	)
	(segment
		(start 251.1806 -22.4282)
		(end 251.333 -22.5806)
		(width 0.14224)
		(layer "In11.Cu")
		(net "M_B_BG<1>")
	)
	(segment
		(start 253.97841 -53.889148)
		(end 253.9873 -53.904388)
		(width 0.0889)
		(layer "In11.Cu")
		(net "M_B_BG<1>")
	)
	(segment
		(start 251.7902 -27.203654)
		(end 251.6632 -27.203654)
		(width 0.14224)
		(layer "In11.Cu")
		(net "M_B_BG<1>")
	)
	(segment
		(start 251.2314 -25.8826)
		(end 251.9934 -26.6446)
		(width 0.14224)
		(layer "In11.Cu")
		(net "M_B_BG<1>")
	)
	(segment
		(start 248.627392 -16.129254)
		(end 250.956318 -16.129254)
		(width 0.14224)
		(layer "In11.Cu")
		(net "M_B_BG<1>")
	)
	(segment
		(start 254.003556 -54.92369)
		(end 254.49911 -55.59044)
		(width 0.0889)
		(layer "In11.Cu")
		(net "M_B_BG<1>")
	)
	(segment
		(start 251.6632 -28.016454)
		(end 251.7902 -28.016454)
		(width 0.14224)
		(layer "In11.Cu")
		(net "M_B_BG<1>")
	)
	(segment
		(start 253.948184 -50.824384)
		(end 254.0508 -50.927)
		(width 0.0889)
		(layer "In11.Cu")
		(net "M_B_BG<1>")
	)
	(segment
		(start 251.333 -17.098264)
		(end 251.333 -18.288)
		(width 0.14224)
		(layer "In11.Cu")
		(net "M_B_BG<1>")
	)
	(segment
		(start 251.333 -22.5806)
		(end 251.333 -23.0886)
		(width 0.14224)
		(layer "In11.Cu")
		(net "M_B_BG<1>")
	)
	(segment
		(start 247.8151 -12.9159)
		(end 247.8151 -14.2875)
		(width 0.14224)
		(layer "In11.Cu")
		(net "M_B_BG<1>")
	)
	(segment
		(start 251.1044 -23.6474)
		(end 251.2314 -23.7744)
		(width 0.14224)
		(layer "In11.Cu")
		(net "M_B_BG<1>")
	)
	(segment
		(start 253.948184 -32.663384)
		(end 253.948184 -50.62347)
		(width 0.14224)
		(layer "In11.Cu")
		(net "M_B_BG<1>")
	)
	(segment
		(start 251.9934 -28.219654)
		(end 251.9934 -30.7086)
		(width 0.14224)
		(layer "In11.Cu")
		(net "M_B_BG<1>")
	)
	(segment
		(start 247.39981 -9.133078)
		(end 247.39981 -11.916156)
		(width 0.14224)
		(layer "In11.Cu")
		(net "M_B_BG<1>")
	)
	(segment
		(start 251.9934 -30.7086)
		(end 253.948184 -32.663384)
		(width 0.14224)
		(layer "In11.Cu")
		(net "M_B_BG<1>")
	)
	(segment
		(start 251.1806 -21.9456)
		(end 251.1806 -22.4282)
		(width 0.14224)
		(layer "In11.Cu")
		(net "M_B_BG<1>")
	)
	(segment
		(start 250.956318 -16.129254)
		(end 251.236734 -16.40967)
		(width 0.14224)
		(layer "In11.Cu")
		(net "M_B_BG<1>")
	)
	(segment
		(start 251.20981 -18.41119)
		(end 251.20981 -19.10461)
		(width 0.14224)
		(layer "In11.Cu")
		(net "M_B_BG<1>")
	)
	(segment
		(start 251.333 -23.0886)
		(end 251.1044 -23.3172)
		(width 0.14224)
		(layer "In11.Cu")
		(net "M_B_BG<1>")
	)
	(segment
		(start 247.39981 -11.916156)
		(end 247.39981 -12.50061)
		(width 0.14224)
		(layer "In11.Cu")
		(net "M_B_BG<1>")
	)
	(segment
		(start 247.942354 -15.444216)
		(end 248.627392 -16.129254)
		(width 0.14224)
		(layer "In11.Cu")
		(net "M_B_BG<1>")
	)
	(segment
		(start 251.333 -18.288)
		(end 251.20981 -18.41119)
		(width 0.14224)
		(layer "In11.Cu")
		(net "M_B_BG<1>")
	)
	(segment
		(start 251.7902 -28.016454)
		(end 251.9934 -28.219654)
		(width 0.14224)
		(layer "In11.Cu")
		(net "M_B_BG<1>")
	)
	(segment
		(start 251.9934 -26.6446)
		(end 251.9934 -27.000454)
		(width 0.14224)
		(layer "In11.Cu")
		(net "M_B_BG<1>")
	)
	(segment
		(start 247.8151 -14.2875)
		(end 247.942354 -14.414754)
		(width 0.14224)
		(layer "In11.Cu")
		(net "M_B_BG<1>")
	)
	(segment
		(start 251.333 -21.7932)
		(end 251.1806 -21.9456)
		(width 0.14224)
		(layer "In11.Cu")
		(net "M_B_BG<1>")
	)
	(segment
		(start 251.46 -27.813254)
		(end 251.6632 -28.016454)
		(width 0.14224)
		(layer "In11.Cu")
		(net "M_B_BG<1>")
	)
	(segment
		(start 247.39981 -12.50061)
		(end 247.8151 -12.9159)
		(width 0.14224)
		(layer "In11.Cu")
		(net "M_B_BG<1>")
	)
	(segment
		(start 251.6632 -27.203654)
		(end 251.46 -27.406854)
		(width 0.14224)
		(layer "In11.Cu")
		(net "M_B_BG<1>")
	)
	(arc
		(start 253.9873 -54.304184)
		(mid 253.908111 -54.590799)
		(end 253.97841 -54.879748)
		(width 0.0889)
		(layer "In11.Cu")
		(net "M_B_BG<1>")
	)
	(arc
		(start 253.9873 -53.313584)
		(mid 253.908111 -53.600199)
		(end 253.97841 -53.889148)
		(width 0.0889)
		(layer "In11.Cu")
		(net "M_B_BG<1>")
	)
	(arc
		(start 253.9873 -53.904388)
		(mid 254.040833 -54.104286)
		(end 253.9873 -54.304184)
		(width 0.0889)
		(layer "In11.Cu")
		(net "M_B_BG<1>")
	)
	(arc
		(start 254.0508 -53.076856)
		(mid 254.034663 -53.199412)
		(end 253.9873 -53.313584)
		(width 0.0889)
		(layer "In11.Cu")
		(net "M_B_BG<1>")
	)
	(segment
		(start 247.39981 -5.822442)
		(end 247.39981 -7.115556)
		(width 0.1651)
		(layer "F.Cu")
		(net "M_B_BG<0>")
	)
	(segment
		(start 247.400318 -5.822442)
		(end 247.39981 -5.822442)
		(width 0.1651)
		(layer "F.Cu")
		(net "M_B_BG<0>")
	)
	(segment
		(start 254.212344 -55.094886)
		(end 253.640844 -55.094886)
		(width 0.1016)
		(layer "F.Cu")
		(net "M_B_BG<0>")
	)
	(via
		(at 247.39981 -13.933678)
		(size 0.4572)
		(drill 0.2032)
		(layers "F.Cu" "B.Cu")
		(net "M_B_BG<0>")
	)
	(via
		(at 247.39981 -7.115556)
		(size 0.4572)
		(drill 0.2032)
		(layers "F.Cu" "B.Cu")
		(net "M_B_BG<0>")
	)
	(via
		(at 253.640844 -55.094886)
		(size 0.508)
		(drill 0.254)
		(layers "F.Cu" "B.Cu")
		(net "M_B_BG<0>")
	)
	(segment
		(start 247.400318 -15.222982)
		(end 247.39981 -15.222982)
		(width 0.1651)
		(layer "B.Cu")
		(net "M_B_BG<0>")
	)
	(segment
		(start 247.39981 -15.222982)
		(end 247.39981 -13.933678)
		(width 0.1651)
		(layer "B.Cu")
		(net "M_B_BG<0>")
	)
	(segment
		(start 248.75744 -22.396196)
		(end 248.75744 -21.913596)
		(width 0.14224)
		(layer "In4.Cu")
		(net "M_B_BG<0>")
	)
	(segment
		(start 252.378464 -28.154884)
		(end 252.036834 -27.813254)
		(width 0.14224)
		(layer "In4.Cu")
		(net "M_B_BG<0>")
	)
	(segment
		(start 248.75744 -21.913596)
		(end 248.60504 -21.761196)
		(width 0.14224)
		(layer "In4.Cu")
		(net "M_B_BG<0>")
	)
	(segment
		(start 250.453398 -26.93543)
		(end 250.273566 -26.93543)
		(width 0.14224)
		(layer "In4.Cu")
		(net "M_B_BG<0>")
	)
	(segment
		(start 250.97867 -27.531314)
		(end 251.257308 -27.252676)
		(width 0.14224)
		(layer "In4.Cu")
		(net "M_B_BG<0>")
	)
	(segment
		(start 248.57964 -23.107396)
		(end 248.57964 -22.573996)
		(width 0.14224)
		(layer "In4.Cu")
		(net "M_B_BG<0>")
	)
	(segment
		(start 248.75744 -17.642586)
		(end 248.75744 -17.134586)
		(width 0.14224)
		(layer "In4.Cu")
		(net "M_B_BG<0>")
	)
	(segment
		(start 250.97867 -27.750262)
		(end 250.97867 -27.531314)
		(width 0.14224)
		(layer "In4.Cu")
		(net "M_B_BG<0>")
	)
	(segment
		(start 248.69013 -15.48257)
		(end 247.39981 -14.19225)
		(width 0.14224)
		(layer "In4.Cu")
		(net "M_B_BG<0>")
	)
	(segment
		(start 251.539248 -28.091892)
		(end 251.3203 -28.091892)
		(width 0.14224)
		(layer "In4.Cu")
		(net "M_B_BG<0>")
	)
	(segment
		(start 248.93524 -23.462996)
		(end 248.57964 -23.107396)
		(width 0.14224)
		(layer "In4.Cu")
		(net "M_B_BG<0>")
	)
	(segment
		(start 252.378464 -28.373832)
		(end 252.378464 -28.154884)
		(width 0.14224)
		(layer "In4.Cu")
		(net "M_B_BG<0>")
	)
	(segment
		(start 253.3904 -51.802792)
		(end 253.3904 -51.4096)
		(width 0.0889)
		(layer "In4.Cu")
		(net "M_B_BG<0>")
	)
	(segment
		(start 252.866652 -29.0068)
		(end 252.660404 -29.213048)
		(width 0.14224)
		(layer "In4.Cu")
		(net "M_B_BG<0>")
	)
	(segment
		(start 251.817886 -27.813254)
		(end 251.539248 -28.091892)
		(width 0.14224)
		(layer "In4.Cu")
		(net "M_B_BG<0>")
	)
	(segment
		(start 253.948184 -50.527712)
		(end 253.948184 -29.9085)
		(width 0.14224)
		(layer "In4.Cu")
		(net "M_B_BG<0>")
	)
	(segment
		(start 253.046484 -29.0068)
		(end 252.866652 -29.0068)
		(width 0.14224)
		(layer "In4.Cu")
		(net "M_B_BG<0>")
	)
	(segment
		(start 250.69673 -26.692098)
		(end 250.453398 -26.93543)
		(width 0.14224)
		(layer "In4.Cu")
		(net "M_B_BG<0>")
	)
	(segment
		(start 247.39981 -13.933678)
		(end 247.39981 -13.585444)
		(width 0.14224)
		(layer "In4.Cu")
		(net "M_B_BG<0>")
	)
	(segment
		(start 252.441456 -29.213048)
		(end 252.099826 -28.871418)
		(width 0.14224)
		(layer "In4.Cu")
		(net "M_B_BG<0>")
	)
	(segment
		(start 252.099826 -28.65247)
		(end 252.378464 -28.373832)
		(width 0.14224)
		(layer "In4.Cu")
		(net "M_B_BG<0>")
	)
	(segment
		(start 250.084336 -26.183336)
		(end 250.084336 -25.860756)
		(width 0.14224)
		(layer "In4.Cu")
		(net "M_B_BG<0>")
	)
	(segment
		(start 253.327662 -51.86553)
		(end 253.3904 -51.802792)
		(width 0.0889)
		(layer "In4.Cu")
		(net "M_B_BG<0>")
	)
	(segment
		(start 253.948184 -29.9085)
		(end 253.046484 -29.0068)
		(width 0.14224)
		(layer "In4.Cu")
		(net "M_B_BG<0>")
	)
	(segment
		(start 253.948184 -50.851816)
		(end 253.948184 -50.527712)
		(width 0.0889)
		(layer "In4.Cu")
		(net "M_B_BG<0>")
	)
	(segment
		(start 248.65838 -12.326874)
		(end 248.65838 -8.374126)
		(width 0.14224)
		(layer "In4.Cu")
		(net "M_B_BG<0>")
	)
	(segment
		(start 252.036834 -27.813254)
		(end 251.817886 -27.813254)
		(width 0.14224)
		(layer "In4.Cu")
		(net "M_B_BG<0>")
	)
	(segment
		(start 251.257308 -27.033728)
		(end 250.915678 -26.692098)
		(width 0.14224)
		(layer "In4.Cu")
		(net "M_B_BG<0>")
	)
	(segment
		(start 252.660404 -29.213048)
		(end 252.441456 -29.213048)
		(width 0.14224)
		(layer "In4.Cu")
		(net "M_B_BG<0>")
	)
	(segment
		(start 249.89282 -26.554684)
		(end 249.89282 -26.374852)
		(width 0.14224)
		(layer "In4.Cu")
		(net "M_B_BG<0>")
	)
	(segment
		(start 248.69013 -17.067276)
		(end 248.69013 -15.48257)
		(width 0.14224)
		(layer "In4.Cu")
		(net "M_B_BG<0>")
	)
	(segment
		(start 252.099826 -28.871418)
		(end 252.099826 -28.65247)
		(width 0.14224)
		(layer "In4.Cu")
		(net "M_B_BG<0>")
	)
	(segment
		(start 248.666254 -21.284692)
		(end 248.666254 -18.4404)
		(width 0.14224)
		(layer "In4.Cu")
		(net "M_B_BG<0>")
	)
	(segment
		(start 249.89282 -26.374852)
		(end 250.084336 -26.183336)
		(width 0.14224)
		(layer "In4.Cu")
		(net "M_B_BG<0>")
	)
	(segment
		(start 251.3203 -28.091892)
		(end 250.97867 -27.750262)
		(width 0.14224)
		(layer "In4.Cu")
		(net "M_B_BG<0>")
	)
	(segment
		(start 248.75744 -17.134586)
		(end 248.69013 -17.067276)
		(width 0.14224)
		(layer "In4.Cu")
		(net "M_B_BG<0>")
	)
	(segment
		(start 248.65838 -8.374126)
		(end 247.39981 -7.115556)
		(width 0.14224)
		(layer "In4.Cu")
		(net "M_B_BG<0>")
	)
	(segment
		(start 247.39981 -14.19225)
		(end 247.39981 -13.933678)
		(width 0.14224)
		(layer "In4.Cu")
		(net "M_B_BG<0>")
	)
	(segment
		(start 253.640844 -55.094886)
		(end 253.353316 -54.447694)
		(width 0.0889)
		(layer "In4.Cu")
		(net "M_B_BG<0>")
	)
	(segment
		(start 253.3904 -51.4096)
		(end 253.948184 -50.851816)
		(width 0.0889)
		(layer "In4.Cu")
		(net "M_B_BG<0>")
	)
	(segment
		(start 248.60504 -21.345906)
		(end 248.666254 -21.284692)
		(width 0.14224)
		(layer "In4.Cu")
		(net "M_B_BG<0>")
	)
	(segment
		(start 253.294134 -51.923696)
		(end 253.327662 -51.86553)
		(width 0.0889)
		(layer "In4.Cu")
		(net "M_B_BG<0>")
	)
	(segment
		(start 248.93524 -24.71166)
		(end 248.93524 -23.462996)
		(width 0.14224)
		(layer "In4.Cu")
		(net "M_B_BG<0>")
	)
	(segment
		(start 247.39981 -13.585444)
		(end 248.65838 -12.326874)
		(width 0.14224)
		(layer "In4.Cu")
		(net "M_B_BG<0>")
	)
	(segment
		(start 248.666254 -18.4404)
		(end 248.60504 -18.379186)
		(width 0.14224)
		(layer "In4.Cu")
		(net "M_B_BG<0>")
	)
	(segment
		(start 248.60504 -17.794986)
		(end 248.75744 -17.642586)
		(width 0.14224)
		(layer "In4.Cu")
		(net "M_B_BG<0>")
	)
	(segment
		(start 251.257308 -27.252676)
		(end 251.257308 -27.033728)
		(width 0.14224)
		(layer "In4.Cu")
		(net "M_B_BG<0>")
	)
	(segment
		(start 250.084336 -25.860756)
		(end 248.93524 -24.71166)
		(width 0.14224)
		(layer "In4.Cu")
		(net "M_B_BG<0>")
	)
	(segment
		(start 248.57964 -22.573996)
		(end 248.75744 -22.396196)
		(width 0.14224)
		(layer "In4.Cu")
		(net "M_B_BG<0>")
	)
	(segment
		(start 250.915678 -26.692098)
		(end 250.69673 -26.692098)
		(width 0.14224)
		(layer "In4.Cu")
		(net "M_B_BG<0>")
	)
	(segment
		(start 248.60504 -21.761196)
		(end 248.60504 -21.345906)
		(width 0.14224)
		(layer "In4.Cu")
		(net "M_B_BG<0>")
	)
	(segment
		(start 250.273566 -26.93543)
		(end 249.89282 -26.554684)
		(width 0.14224)
		(layer "In4.Cu")
		(net "M_B_BG<0>")
	)
	(segment
		(start 248.60504 -18.379186)
		(end 248.60504 -17.794986)
		(width 0.14224)
		(layer "In4.Cu")
		(net "M_B_BG<0>")
	)
	(arc
		(start 253.294134 -53.904896)
		(mid 253.373265 -53.609494)
		(end 253.294134 -53.314092)
		(width 0.0889)
		(layer "In4.Cu")
		(net "M_B_BG<0>")
	)
	(arc
		(start 253.294134 -52.323492)
		(mid 253.240635 -52.123594)
		(end 253.294134 -51.923696)
		(width 0.0889)
		(layer "In4.Cu")
		(net "M_B_BG<0>")
	)
	(arc
		(start 253.294134 -52.914296)
		(mid 253.373265 -52.618894)
		(end 253.294134 -52.323492)
		(width 0.0889)
		(layer "In4.Cu")
		(net "M_B_BG<0>")
	)
	(arc
		(start 253.294134 -54.304692)
		(mid 253.240635 -54.104794)
		(end 253.294134 -53.904896)
		(width 0.0889)
		(layer "In4.Cu")
		(net "M_B_BG<0>")
	)
	(arc
		(start 253.294134 -53.314092)
		(mid 253.240635 -53.114194)
		(end 253.294134 -52.914296)
		(width 0.0889)
		(layer "In4.Cu")
		(net "M_B_BG<0>")
	)
	(arc
		(start 253.353316 -54.447694)
		(mid 253.328416 -54.374253)
		(end 253.294134 -54.304692)
		(width 0.0889)
		(layer "In4.Cu")
		(net "M_B_BG<0>")
	)
	(segment
		(start 259.36321 -54.104286)
		(end 258.79171 -54.104286)
		(width 0.1016)
		(layer "F.Cu")
		(net "M_B_BA<1>")
	)
	(segment
		(start 266.949936 -9.133332)
		(end 266.95019 -9.133078)
		(width 0.1651)
		(layer "F.Cu")
		(net "M_B_BA<1>")
	)
	(segment
		(start 266.949936 -10.422382)
		(end 266.949936 -9.133332)
		(width 0.1651)
		(layer "F.Cu")
		(net "M_B_BA<1>")
	)
	(segment
		(start 266.950444 -10.422382)
		(end 266.949936 -10.422382)
		(width 0.1651)
		(layer "F.Cu")
		(net "M_B_BA<1>")
	)
	(via
		(at 266.95019 -9.133078)
		(size 0.4572)
		(drill 0.2032)
		(layers "F.Cu" "B.Cu")
		(net "M_B_BA<1>")
	)
	(via
		(at 266.95019 -11.918188)
		(size 0.4572)
		(drill 0.2032)
		(layers "F.Cu" "B.Cu")
		(net "M_B_BA<1>")
	)
	(via
		(at 258.79171 -54.104286)
		(size 0.508)
		(drill 0.254)
		(layers "F.Cu" "B.Cu")
		(net "M_B_BA<1>")
	)
	(segment
		(start 266.949936 -10.623042)
		(end 266.949936 -11.917934)
		(width 0.1651)
		(layer "B.Cu")
		(net "M_B_BA<1>")
	)
	(segment
		(start 266.950444 -10.623042)
		(end 266.949936 -10.623042)
		(width 0.1651)
		(layer "B.Cu")
		(net "M_B_BA<1>")
	)
	(segment
		(start 266.949936 -11.917934)
		(end 266.95019 -11.918188)
		(width 0.1651)
		(layer "B.Cu")
		(net "M_B_BA<1>")
	)
	(segment
		(start 263.9822 -15.4432)
		(end 263.140444 -15.4432)
		(width 0.14224)
		(layer "In11.Cu")
		(net "M_B_BA<1>")
	)
	(segment
		(start 262.1026 -16.481044)
		(end 262.1026 -18.542)
		(width 0.14224)
		(layer "In11.Cu")
		(net "M_B_BA<1>")
	)
	(segment
		(start 260.585458 -29.950918)
		(end 260.026404 -30.509972)
		(width 0.14224)
		(layer "In11.Cu")
		(net "M_B_BA<1>")
	)
	(segment
		(start 266.264136 -11.232134)
		(end 266.264136 -9.819132)
		(width 0.14224)
		(layer "In11.Cu")
		(net "M_B_BA<1>")
	)
	(segment
		(start 266.76985 -12.7762)
		(end 265.684 -12.7762)
		(width 0.14224)
		(layer "In11.Cu")
		(net "M_B_BA<1>")
	)
	(segment
		(start 258.98094 -51.358038)
		(end 258.98094 -53.667914)
		(width 0.0889)
		(layer "In11.Cu")
		(net "M_B_BA<1>")
	)
	(segment
		(start 263.140444 -15.4432)
		(end 262.1026 -16.481044)
		(width 0.14224)
		(layer "In11.Cu")
		(net "M_B_BA<1>")
	)
	(segment
		(start 266.95019 -11.918188)
		(end 266.264136 -11.232134)
		(width 0.14224)
		(layer "In11.Cu")
		(net "M_B_BA<1>")
	)
	(segment
		(start 266.95019 -11.918188)
		(end 266.949682 -11.918696)
		(width 0.14224)
		(layer "In11.Cu")
		(net "M_B_BA<1>")
	)
	(segment
		(start 260.8707 -28.799028)
		(end 260.583172 -28.799028)
		(width 0.14224)
		(layer "In11.Cu")
		(net "M_B_BA<1>")
	)
	(segment
		(start 259.614416 -50.724816)
		(end 258.98094 -51.358038)
		(width 0.0889)
		(layer "In11.Cu")
		(net "M_B_BA<1>")
	)
	(segment
		(start 260.026404 -30.509972)
		(end 260.026404 -50.134774)
		(width 0.14224)
		(layer "In11.Cu")
		(net "M_B_BA<1>")
	)
	(segment
		(start 264.7442 -13.716)
		(end 264.7442 -14.6812)
		(width 0.14224)
		(layer "In11.Cu")
		(net "M_B_BA<1>")
	)
	(segment
		(start 264.7442 -14.6812)
		(end 263.9822 -15.4432)
		(width 0.14224)
		(layer "In11.Cu")
		(net "M_B_BA<1>")
	)
	(segment
		(start 265.684 -12.7762)
		(end 264.7442 -13.716)
		(width 0.14224)
		(layer "In11.Cu")
		(net "M_B_BA<1>")
	)
	(segment
		(start 260.295898 -29.37383)
		(end 260.585458 -29.66339)
		(width 0.14224)
		(layer "In11.Cu")
		(net "M_B_BA<1>")
	)
	(segment
		(start 260.026404 -50.312574)
		(end 259.614416 -50.724816)
		(width 0.0889)
		(layer "In11.Cu")
		(net "M_B_BA<1>")
	)
	(segment
		(start 261.16026 -29.088588)
		(end 260.8707 -28.799028)
		(width 0.14224)
		(layer "In11.Cu")
		(net "M_B_BA<1>")
	)
	(segment
		(start 261.6708 -28.865576)
		(end 261.447788 -29.088588)
		(width 0.14224)
		(layer "In11.Cu")
		(net "M_B_BA<1>")
	)
	(segment
		(start 262.4328 -19.2024)
		(end 261.6708 -19.9644)
		(width 0.14224)
		(layer "In11.Cu")
		(net "M_B_BA<1>")
	)
	(segment
		(start 258.98094 -53.667914)
		(end 258.79171 -54.104286)
		(width 0.0889)
		(layer "In11.Cu")
		(net "M_B_BA<1>")
	)
	(segment
		(start 260.295898 -29.086302)
		(end 260.295898 -29.37383)
		(width 0.14224)
		(layer "In11.Cu")
		(net "M_B_BA<1>")
	)
	(segment
		(start 261.6708 -19.9644)
		(end 261.6708 -28.865576)
		(width 0.14224)
		(layer "In11.Cu")
		(net "M_B_BA<1>")
	)
	(segment
		(start 260.583172 -28.799028)
		(end 260.295898 -29.086302)
		(width 0.14224)
		(layer "In11.Cu")
		(net "M_B_BA<1>")
	)
	(segment
		(start 266.949682 -12.596368)
		(end 266.76985 -12.7762)
		(width 0.14224)
		(layer "In11.Cu")
		(net "M_B_BA<1>")
	)
	(segment
		(start 260.585458 -29.66339)
		(end 260.585458 -29.950918)
		(width 0.14224)
		(layer "In11.Cu")
		(net "M_B_BA<1>")
	)
	(segment
		(start 262.4328 -18.8722)
		(end 262.4328 -19.2024)
		(width 0.14224)
		(layer "In11.Cu")
		(net "M_B_BA<1>")
	)
	(segment
		(start 260.026404 -50.134774)
		(end 260.026404 -50.312574)
		(width 0.0889)
		(layer "In11.Cu")
		(net "M_B_BA<1>")
	)
	(segment
		(start 266.264136 -9.819132)
		(end 266.95019 -9.133078)
		(width 0.14224)
		(layer "In11.Cu")
		(net "M_B_BA<1>")
	)
	(segment
		(start 266.949682 -11.918696)
		(end 266.949682 -12.596368)
		(width 0.14224)
		(layer "In11.Cu")
		(net "M_B_BA<1>")
	)
	(segment
		(start 261.447788 -29.088588)
		(end 261.16026 -29.088588)
		(width 0.14224)
		(layer "In11.Cu")
		(net "M_B_BA<1>")
	)
	(segment
		(start 262.1026 -18.542)
		(end 262.4328 -18.8722)
		(width 0.14224)
		(layer "In11.Cu")
		(net "M_B_BA<1>")
	)
	(segment
		(start 267.800328 -5.822442)
		(end 267.79982 -5.822442)
		(width 0.1651)
		(layer "F.Cu")
		(net "M_B_BA<0>")
	)
	(segment
		(start 267.79982 -7.117334)
		(end 267.800074 -7.117588)
		(width 0.1651)
		(layer "F.Cu")
		(net "M_B_BA<0>")
	)
	(segment
		(start 260.50875 -57.076086)
		(end 261.08025 -57.076086)
		(width 0.1016)
		(layer "F.Cu")
		(net "M_B_BA<0>")
	)
	(segment
		(start 267.79982 -5.822442)
		(end 267.79982 -7.117334)
		(width 0.1651)
		(layer "F.Cu")
		(net "M_B_BA<0>")
	)
	(via
		(at 260.50875 -57.076086)
		(size 0.508)
		(drill 0.254)
		(layers "F.Cu" "B.Cu")
		(net "M_B_BA<0>")
	)
	(via
		(at 267.800074 -13.933678)
		(size 0.4572)
		(drill 0.2032)
		(layers "F.Cu" "B.Cu")
		(net "M_B_BA<0>")
	)
	(via
		(at 267.800074 -7.117588)
		(size 0.4572)
		(drill 0.2032)
		(layers "F.Cu" "B.Cu")
		(net "M_B_BA<0>")
	)
	(segment
		(start 267.79982 -15.222982)
		(end 267.79982 -13.933932)
		(width 0.1651)
		(layer "B.Cu")
		(net "M_B_BA<0>")
	)
	(segment
		(start 267.800328 -15.222982)
		(end 267.79982 -15.222982)
		(width 0.1651)
		(layer "B.Cu")
		(net "M_B_BA<0>")
	)
	(segment
		(start 267.79982 -13.933932)
		(end 267.800074 -13.933678)
		(width 0.1651)
		(layer "B.Cu")
		(net "M_B_BA<0>")
	)
	(segment
		(start 267.377672 -13.355828)
		(end 267.800074 -13.77823)
		(width 0.14224)
		(layer "In4.Cu")
		(net "M_B_BA<0>")
	)
	(segment
		(start 262.973058 -50.842164)
		(end 262.973058 -51.351942)
		(width 0.0889)
		(layer "In4.Cu")
		(net "M_B_BA<0>")
	)
	(segment
		(start 266.446 -22.360382)
		(end 266.777978 -22.69236)
		(width 0.14224)
		(layer "In4.Cu")
		(net "M_B_BA<0>")
	)
	(segment
		(start 266.540742 -17.010634)
		(end 266.539472 -17.016476)
		(width 0.14224)
		(layer "In4.Cu")
		(net "M_B_BA<0>")
	)
	(segment
		(start 262.973058 -27.954986)
		(end 262.973058 -50.842164)
		(width 0.14224)
		(layer "In4.Cu")
		(net "M_B_BA<0>")
	)
	(segment
		(start 267.650722 -13.933678)
		(end 266.8397 -14.7447)
		(width 0.14224)
		(layer "In4.Cu")
		(net "M_B_BA<0>")
	)
	(segment
		(start 266.8397 -14.7447)
		(end 266.540742 -15.993364)
		(width 0.14224)
		(layer "In4.Cu")
		(net "M_B_BA<0>")
	)
	(segment
		(start 261.631938 -52.91836)
		(end 261.388352 -53.328316)
		(width 0.0889)
		(layer "In4.Cu")
		(net "M_B_BA<0>")
	)
	(segment
		(start 260.84911 -54.88432)
		(end 260.85546 -54.894988)
		(width 0.0889)
		(layer "In4.Cu")
		(net "M_B_BA<0>")
	)
	(segment
		(start 266.777978 -22.69236)
		(end 266.777978 -23.031196)
		(width 0.14224)
		(layer "In4.Cu")
		(net "M_B_BA<0>")
	)
	(segment
		(start 266.697714 -21.676106)
		(end 266.446 -21.92782)
		(width 0.14224)
		(layer "In4.Cu")
		(net "M_B_BA<0>")
	)
	(segment
		(start 267.79982 -8.302244)
		(end 267.377672 -8.724392)
		(width 0.14224)
		(layer "In4.Cu")
		(net "M_B_BA<0>")
	)
	(segment
		(start 267.79982 -7.117842)
		(end 267.79982 -8.302244)
		(width 0.14224)
		(layer "In4.Cu")
		(net "M_B_BA<0>")
	)
	(segment
		(start 266.697714 -21.194522)
		(end 266.697714 -21.676106)
		(width 0.14224)
		(layer "In4.Cu")
		(net "M_B_BA<0>")
	)
	(segment
		(start 266.777978 -23.031196)
		(end 265.9888 -23.820374)
		(width 0.14224)
		(layer "In4.Cu")
		(net "M_B_BA<0>")
	)
	(segment
		(start 260.838696 -56.31434)
		(end 260.50875 -57.076086)
		(width 0.0889)
		(layer "In4.Cu")
		(net "M_B_BA<0>")
	)
	(segment
		(start 261.388352 -53.328316)
		(end 261.239 -53.638958)
		(width 0.0889)
		(layer "In4.Cu")
		(net "M_B_BA<0>")
	)
	(segment
		(start 260.85546 -55.885588)
		(end 260.860286 -55.894224)
		(width 0.0889)
		(layer "In4.Cu")
		(net "M_B_BA<0>")
	)
	(segment
		(start 261.897622 -52.500784)
		(end 261.71398 -52.818284)
		(width 0.0889)
		(layer "In4.Cu")
		(net "M_B_BA<0>")
	)
	(segment
		(start 266.539472 -17.016476)
		(end 266.539472 -18.90903)
		(width 0.14224)
		(layer "In4.Cu")
		(net "M_B_BA<0>")
	)
	(segment
		(start 260.84911 -55.87492)
		(end 260.85546 -55.885588)
		(width 0.0889)
		(layer "In4.Cu")
		(net "M_B_BA<0>")
	)
	(segment
		(start 266.539472 -18.90903)
		(end 266.446 -19.002502)
		(width 0.14224)
		(layer "In4.Cu")
		(net "M_B_BA<0>")
	)
	(segment
		(start 266.446 -20.942808)
		(end 266.697714 -21.194522)
		(width 0.14224)
		(layer "In4.Cu")
		(net "M_B_BA<0>")
	)
	(segment
		(start 260.85546 -54.894988)
		(end 260.860286 -54.903624)
		(width 0.0889)
		(layer "In4.Cu")
		(net "M_B_BA<0>")
	)
	(segment
		(start 265.9888 -23.820374)
		(end 265.9888 -24.939244)
		(width 0.14224)
		(layer "In4.Cu")
		(net "M_B_BA<0>")
	)
	(segment
		(start 261.239 -53.638958)
		(end 260.85546 -54.304438)
		(width 0.0889)
		(layer "In4.Cu")
		(net "M_B_BA<0>")
	)
	(segment
		(start 267.800074 -7.117588)
		(end 267.79982 -7.117842)
		(width 0.14224)
		(layer "In4.Cu")
		(net "M_B_BA<0>")
	)
	(segment
		(start 267.800074 -13.77823)
		(end 267.800074 -13.933678)
		(width 0.14224)
		(layer "In4.Cu")
		(net "M_B_BA<0>")
	)
	(segment
		(start 266.446 -19.002502)
		(end 266.446 -20.942808)
		(width 0.14224)
		(layer "In4.Cu")
		(net "M_B_BA<0>")
	)
	(segment
		(start 265.9888 -24.939244)
		(end 262.973058 -27.954986)
		(width 0.14224)
		(layer "In4.Cu")
		(net "M_B_BA<0>")
	)
	(segment
		(start 266.540742 -15.993364)
		(end 266.540742 -17.010634)
		(width 0.14224)
		(layer "In4.Cu")
		(net "M_B_BA<0>")
	)
	(segment
		(start 266.446 -21.92782)
		(end 266.446 -22.360382)
		(width 0.14224)
		(layer "In4.Cu")
		(net "M_B_BA<0>")
	)
	(segment
		(start 262.973058 -51.351942)
		(end 262.1407 -52.1843)
		(width 0.0889)
		(layer "In4.Cu")
		(net "M_B_BA<0>")
	)
	(segment
		(start 267.377672 -8.724392)
		(end 267.377672 -13.355828)
		(width 0.14224)
		(layer "In4.Cu")
		(net "M_B_BA<0>")
	)
	(segment
		(start 260.85546 -56.285638)
		(end 260.838696 -56.31434)
		(width 0.0889)
		(layer "In4.Cu")
		(net "M_B_BA<0>")
	)
	(segment
		(start 267.800074 -13.933678)
		(end 267.650722 -13.933678)
		(width 0.14224)
		(layer "In4.Cu")
		(net "M_B_BA<0>")
	)
	(arc
		(start 260.860286 -54.903624)
		(mid 260.909041 -55.099976)
		(end 260.85546 -55.295038)
		(width 0.0889)
		(layer "In4.Cu")
		(net "M_B_BA<0>")
	)
	(arc
		(start 260.860286 -55.894224)
		(mid 260.909041 -56.090576)
		(end 260.85546 -56.285638)
		(width 0.0889)
		(layer "In4.Cu")
		(net "M_B_BA<0>")
	)
	(arc
		(start 262.1407 -52.1843)
		(mid 262.008809 -52.334593)
		(end 261.897622 -52.500784)
		(width 0.0889)
		(layer "In4.Cu")
		(net "M_B_BA<0>")
	)
	(arc
		(start 261.71398 -52.818284)
		(mid 261.677026 -52.871655)
		(end 261.631938 -52.91836)
		(width 0.0889)
		(layer "In4.Cu")
		(net "M_B_BA<0>")
	)
	(arc
		(start 260.85546 -54.304438)
		(mid 260.776238 -54.593556)
		(end 260.84911 -54.88432)
		(width 0.0889)
		(layer "In4.Cu")
		(net "M_B_BA<0>")
	)
	(arc
		(start 260.85546 -55.295038)
		(mid 260.776238 -55.584156)
		(end 260.84911 -55.87492)
		(width 0.0889)
		(layer "In4.Cu")
		(net "M_B_BA<0>")
	)
	(segment
		(start 248.250456 -10.422382)
		(end 248.249948 -10.422382)
		(width 0.1651)
		(layer "F.Cu")
		(net "M_B_ALERT_N")
	)
	(segment
		(start 253.353824 -58.561986)
		(end 252.782324 -58.561986)
		(width 0.1651)
		(layer "F.Cu")
		(net "M_B_ALERT_N")
	)
	(segment
		(start 248.249948 -10.422382)
		(end 248.249948 -9.133078)
		(width 0.1651)
		(layer "F.Cu")
		(net "M_B_ALERT_N")
	)
	(via
		(at 248.249948 -11.916156)
		(size 0.4572)
		(drill 0.2032)
		(layers "F.Cu" "B.Cu")
		(net "M_B_ALERT_N")
	)
	(via
		(at 248.249948 -9.133078)
		(size 0.4572)
		(drill 0.2032)
		(layers "F.Cu" "B.Cu")
		(net "M_B_ALERT_N")
	)
	(via
		(at 252.782324 -58.561986)
		(size 0.508)
		(drill 0.254)
		(layers "F.Cu" "B.Cu")
		(net "M_B_ALERT_N")
	)
	(segment
		(start 248.250456 -10.623042)
		(end 248.249948 -10.623042)
		(width 0.1651)
		(layer "B.Cu")
		(net "M_B_ALERT_N")
	)
	(segment
		(start 248.249948 -10.623042)
		(end 248.249948 -11.916156)
		(width 0.1651)
		(layer "B.Cu")
		(net "M_B_ALERT_N")
	)
	(segment
		(start 247.8278 -9.361678)
		(end 248.0564 -9.133078)
		(width 0.14224)
		(layer "In4.Cu")
		(net "M_B_ALERT_N")
	)
	(segment
		(start 253.277624 -57.895998)
		(end 253.294134 -57.867296)
		(width 0.0889)
		(layer "In4.Cu")
		(net "M_B_ALERT_N")
	)
	(segment
		(start 246.9896 -13.176504)
		(end 248.249948 -11.916156)
		(width 0.14224)
		(layer "In4.Cu")
		(net "M_B_ALERT_N")
	)
	(segment
		(start 247.839484 -18.458942)
		(end 247.89384 -18.404586)
		(width 0.14224)
		(layer "In4.Cu")
		(net "M_B_ALERT_N")
	)
	(segment
		(start 247.74144 -17.109186)
		(end 247.809258 -17.041368)
		(width 0.14224)
		(layer "In4.Cu")
		(net "M_B_ALERT_N")
	)
	(segment
		(start 248.0564 -9.133078)
		(end 248.249948 -9.133078)
		(width 0.14224)
		(layer "In4.Cu")
		(net "M_B_ALERT_N")
	)
	(segment
		(start 247.89384 -21.811996)
		(end 247.89384 -21.3106)
		(width 0.14224)
		(layer "In4.Cu")
		(net "M_B_ALERT_N")
	)
	(segment
		(start 249.226832 -26.628598)
		(end 249.226832 -25.721818)
		(width 0.14224)
		(layer "In4.Cu")
		(net "M_B_ALERT_N")
	)
	(segment
		(start 253.440184 -50.348896)
		(end 253.440184 -30.84195)
		(width 0.14224)
		(layer "In4.Cu")
		(net "M_B_ALERT_N")
	)
	(segment
		(start 247.839484 -21.256244)
		(end 247.839484 -18.458942)
		(width 0.14224)
		(layer "In4.Cu")
		(net "M_B_ALERT_N")
	)
	(segment
		(start 253.440184 -30.84195)
		(end 249.226832 -26.628598)
		(width 0.14224)
		(layer "In4.Cu")
		(net "M_B_ALERT_N")
	)
	(segment
		(start 246.9896 -14.666214)
		(end 246.9896 -13.176504)
		(width 0.14224)
		(layer "In4.Cu")
		(net "M_B_ALERT_N")
	)
	(segment
		(start 247.809258 -17.041368)
		(end 247.809258 -15.485872)
		(width 0.14224)
		(layer "In4.Cu")
		(net "M_B_ALERT_N")
	)
	(segment
		(start 247.89384 -18.404586)
		(end 247.89384 -17.769586)
		(width 0.14224)
		(layer "In4.Cu")
		(net "M_B_ALERT_N")
	)
	(segment
		(start 252.782324 -58.561986)
		(end 253.277624 -57.895998)
		(width 0.0889)
		(layer "In4.Cu")
		(net "M_B_ALERT_N")
	)
	(segment
		(start 247.89384 -21.3106)
		(end 247.839484 -21.256244)
		(width 0.14224)
		(layer "In4.Cu")
		(net "M_B_ALERT_N")
	)
	(segment
		(start 247.76684 -22.421596)
		(end 247.76684 -21.938996)
		(width 0.14224)
		(layer "In4.Cu")
		(net "M_B_ALERT_N")
	)
	(segment
		(start 247.809258 -15.485872)
		(end 246.9896 -14.666214)
		(width 0.14224)
		(layer "In4.Cu")
		(net "M_B_ALERT_N")
	)
	(segment
		(start 247.94464 -22.599396)
		(end 247.76684 -22.421596)
		(width 0.14224)
		(layer "In4.Cu")
		(net "M_B_ALERT_N")
	)
	(segment
		(start 253.440184 -50.851562)
		(end 253.440184 -50.348896)
		(width 0.0889)
		(layer "In4.Cu")
		(net "M_B_ALERT_N")
	)
	(segment
		(start 249.226832 -25.721818)
		(end 247.758966 -24.253952)
		(width 0.14224)
		(layer "In4.Cu")
		(net "M_B_ALERT_N")
	)
	(segment
		(start 247.758966 -24.253952)
		(end 247.758966 -23.31847)
		(width 0.14224)
		(layer "In4.Cu")
		(net "M_B_ALERT_N")
	)
	(segment
		(start 247.89384 -17.769586)
		(end 247.74144 -17.617186)
		(width 0.14224)
		(layer "In4.Cu")
		(net "M_B_ALERT_N")
	)
	(segment
		(start 247.74144 -17.617186)
		(end 247.74144 -17.109186)
		(width 0.14224)
		(layer "In4.Cu")
		(net "M_B_ALERT_N")
	)
	(segment
		(start 247.758966 -23.31847)
		(end 247.94464 -23.132796)
		(width 0.14224)
		(layer "In4.Cu")
		(net "M_B_ALERT_N")
	)
	(segment
		(start 247.94464 -23.132796)
		(end 247.94464 -22.599396)
		(width 0.14224)
		(layer "In4.Cu")
		(net "M_B_ALERT_N")
	)
	(segment
		(start 253.188724 -51.103022)
		(end 253.440184 -50.851562)
		(width 0.0889)
		(layer "In4.Cu")
		(net "M_B_ALERT_N")
	)
	(segment
		(start 253.188724 -51.724814)
		(end 253.188724 -51.103022)
		(width 0.0889)
		(layer "In4.Cu")
		(net "M_B_ALERT_N")
	)
	(segment
		(start 248.249948 -11.916156)
		(end 247.8278 -11.494008)
		(width 0.14224)
		(layer "In4.Cu")
		(net "M_B_ALERT_N")
	)
	(segment
		(start 253.129034 -51.828192)
		(end 253.188724 -51.724814)
		(width 0.0889)
		(layer "In4.Cu")
		(net "M_B_ALERT_N")
	)
	(segment
		(start 247.8278 -11.494008)
		(end 247.8278 -9.361678)
		(width 0.14224)
		(layer "In4.Cu")
		(net "M_B_ALERT_N")
	)
	(segment
		(start 247.76684 -21.938996)
		(end 247.89384 -21.811996)
		(width 0.14224)
		(layer "In4.Cu")
		(net "M_B_ALERT_N")
	)
	(arc
		(start 253.178564 -54.928516)
		(mid 253.18901 -54.74544)
		(end 253.18085 -54.562248)
		(width 0.0889)
		(layer "In4.Cu")
		(net "M_B_ALERT_N")
	)
	(arc
		(start 253.18085 -54.562248)
		(mid 253.163653 -54.478436)
		(end 253.129034 -54.400196)
		(width 0.0889)
		(layer "In4.Cu")
		(net "M_B_ALERT_N")
	)
	(arc
		(start 253.129034 -52.418996)
		(mid 253.049903 -52.123594)
		(end 253.129034 -51.828192)
		(width 0.0889)
		(layer "In4.Cu")
		(net "M_B_ALERT_N")
	)
	(arc
		(start 253.129034 -53.409596)
		(mid 253.049903 -53.114194)
		(end 253.129034 -52.818792)
		(width 0.0889)
		(layer "In4.Cu")
		(net "M_B_ALERT_N")
	)
	(arc
		(start 253.294134 -55.295292)
		(mid 253.216247 -55.118237)
		(end 253.178564 -54.928516)
		(width 0.0889)
		(layer "In4.Cu")
		(net "M_B_ALERT_N")
	)
	(arc
		(start 253.294134 -55.886096)
		(mid 253.373265 -55.590694)
		(end 253.294134 -55.295292)
		(width 0.0889)
		(layer "In4.Cu")
		(net "M_B_ALERT_N")
	)
	(arc
		(start 253.294134 -56.285892)
		(mid 253.240635 -56.085994)
		(end 253.294134 -55.886096)
		(width 0.0889)
		(layer "In4.Cu")
		(net "M_B_ALERT_N")
	)
	(arc
		(start 253.294134 -57.276492)
		(mid 253.240635 -57.076594)
		(end 253.294134 -56.876696)
		(width 0.0889)
		(layer "In4.Cu")
		(net "M_B_ALERT_N")
	)
	(arc
		(start 253.294134 -56.876696)
		(mid 253.373265 -56.581294)
		(end 253.294134 -56.285892)
		(width 0.0889)
		(layer "In4.Cu")
		(net "M_B_ALERT_N")
	)
	(arc
		(start 253.129034 -52.818792)
		(mid 253.182567 -52.618894)
		(end 253.129034 -52.418996)
		(width 0.0889)
		(layer "In4.Cu")
		(net "M_B_ALERT_N")
	)
	(arc
		(start 253.129034 -53.809392)
		(mid 253.182567 -53.609494)
		(end 253.129034 -53.409596)
		(width 0.0889)
		(layer "In4.Cu")
		(net "M_B_ALERT_N")
	)
	(arc
		(start 253.129034 -54.400196)
		(mid 253.049903 -54.104794)
		(end 253.129034 -53.809392)
		(width 0.0889)
		(layer "In4.Cu")
		(net "M_B_ALERT_N")
	)
	(arc
		(start 253.294134 -57.867296)
		(mid 253.373265 -57.571894)
		(end 253.294134 -57.276492)
		(width 0.0889)
		(layer "In4.Cu")
		(net "M_B_ALERT_N")
	)
	(segment
		(start 252.495304 -57.076086)
		(end 251.923804 -57.076086)
		(width 0.1651)
		(layer "F.Cu")
		(net "M_B_ACT_N")
	)
	(segment
		(start 246.550434 -5.822442)
		(end 246.549926 -5.822442)
		(width 0.1651)
		(layer "F.Cu")
		(net "M_B_ACT_N")
	)
	(segment
		(start 246.549926 -5.822442)
		(end 246.549926 -7.115556)
		(width 0.1651)
		(layer "F.Cu")
		(net "M_B_ACT_N")
	)
	(via
		(at 251.923804 -57.076086)
		(size 0.508)
		(drill 0.254)
		(layers "F.Cu" "B.Cu")
		(net "M_B_ACT_N")
	)
	(via
		(at 246.549926 -7.115556)
		(size 0.4572)
		(drill 0.2032)
		(layers "F.Cu" "B.Cu")
		(net "M_B_ACT_N")
	)
	(via
		(at 246.549926 -13.933678)
		(size 0.4572)
		(drill 0.2032)
		(layers "F.Cu" "B.Cu")
		(net "M_B_ACT_N")
	)
	(segment
		(start 246.550434 -15.222982)
		(end 246.549926 -15.222982)
		(width 0.1651)
		(layer "B.Cu")
		(net "M_B_ACT_N")
	)
	(segment
		(start 246.549926 -15.222982)
		(end 246.549926 -13.933678)
		(width 0.1651)
		(layer "B.Cu")
		(net "M_B_ACT_N")
	)
	(segment
		(start 247.15724 -23.437596)
		(end 246.90324 -23.183596)
		(width 0.14224)
		(layer "In4.Cu")
		(net "M_B_ACT_N")
	)
	(segment
		(start 246.9896 -15.37462)
		(end 246.549926 -14.934946)
		(width 0.14224)
		(layer "In4.Cu")
		(net "M_B_ACT_N")
	)
	(segment
		(start 252.468126 -56.19877)
		(end 252.943868 -55.956962)
		(width 0.0889)
		(layer "In4.Cu")
		(net "M_B_ACT_N")
	)
	(segment
		(start 253.030736 -31.151068)
		(end 248.6914 -26.811732)
		(width 0.14224)
		(layer "In4.Cu")
		(net "M_B_ACT_N")
	)
	(segment
		(start 246.235728 -7.874)
		(end 246.549926 -7.115556)
		(width 0.14224)
		(layer "In4.Cu")
		(net "M_B_ACT_N")
	)
	(segment
		(start 253.030736 -50.305716)
		(end 253.030736 -31.151068)
		(width 0.14224)
		(layer "In4.Cu")
		(net "M_B_ACT_N")
	)
	(segment
		(start 246.90324 -19.110706)
		(end 246.991378 -19.022568)
		(width 0.14224)
		(layer "In4.Cu")
		(net "M_B_ACT_N")
	)
	(segment
		(start 247.15724 -24.370792)
		(end 247.15724 -23.437596)
		(width 0.14224)
		(layer "In4.Cu")
		(net "M_B_ACT_N")
	)
	(segment
		(start 252.441964 -53.819806)
		(end 252.435614 -53.809138)
		(width 0.0889)
		(layer "In4.Cu")
		(net "M_B_ACT_N")
	)
	(segment
		(start 248.6914 -26.811732)
		(end 248.6914 -25.904952)
		(width 0.14224)
		(layer "In4.Cu")
		(net "M_B_ACT_N")
	)
	(segment
		(start 247.15724 -21.964396)
		(end 246.90324 -21.710396)
		(width 0.14224)
		(layer "In4.Cu")
		(net "M_B_ACT_N")
	)
	(segment
		(start 251.923804 -57.076086)
		(end 252.468126 -56.19877)
		(width 0.0889)
		(layer "In4.Cu")
		(net "M_B_ACT_N")
	)
	(segment
		(start 246.657622 -10.854182)
		(end 246.657622 -10.371582)
		(width 0.14224)
		(layer "In4.Cu")
		(net "M_B_ACT_N")
	)
	(segment
		(start 246.549926 -13.933678)
		(end 246.524526 -13.933678)
		(width 0.14224)
		(layer "In4.Cu")
		(net "M_B_ACT_N")
	)
	(segment
		(start 248.6914 -25.904952)
		(end 247.15724 -24.370792)
		(width 0.14224)
		(layer "In4.Cu")
		(net "M_B_ACT_N")
	)
	(segment
		(start 246.90324 -23.183596)
		(end 246.90324 -22.662896)
		(width 0.14224)
		(layer "In4.Cu")
		(net "M_B_ACT_N")
	)
	(segment
		(start 246.991378 -19.022568)
		(end 246.991378 -18.467324)
		(width 0.14224)
		(layer "In4.Cu")
		(net "M_B_ACT_N")
	)
	(segment
		(start 246.26824 -10.216642)
		(end 246.1133 -10.061702)
		(width 0.14224)
		(layer "In4.Cu")
		(net "M_B_ACT_N")
	)
	(segment
		(start 247.15724 -22.408896)
		(end 247.15724 -21.964396)
		(width 0.14224)
		(layer "In4.Cu")
		(net "M_B_ACT_N")
	)
	(segment
		(start 247.15724 -17.159986)
		(end 246.9896 -16.992346)
		(width 0.14224)
		(layer "In4.Cu")
		(net "M_B_ACT_N")
	)
	(segment
		(start 252.805946 -55.106824)
		(end 252.794008 -55.094886)
		(width 0.0889)
		(layer "In4.Cu")
		(net "M_B_ACT_N")
	)
	(segment
		(start 253.030736 -50.753264)
		(end 253.030736 -50.305716)
		(width 0.0889)
		(layer "In4.Cu")
		(net "M_B_ACT_N")
	)
	(segment
		(start 246.657622 -10.371582)
		(end 246.502682 -10.216642)
		(width 0.14224)
		(layer "In4.Cu")
		(net "M_B_ACT_N")
	)
	(segment
		(start 246.991378 -18.467324)
		(end 247.15724 -18.301462)
		(width 0.14224)
		(layer "In4.Cu")
		(net "M_B_ACT_N")
	)
	(segment
		(start 252.375924 -51.60391)
		(end 252.375924 -51.408076)
		(width 0.0889)
		(layer "In4.Cu")
		(net "M_B_ACT_N")
	)
	(segment
		(start 246.549926 -14.934946)
		(end 246.549926 -13.933678)
		(width 0.14224)
		(layer "In4.Cu")
		(net "M_B_ACT_N")
	)
	(segment
		(start 246.26824 -11.009122)
		(end 246.502682 -11.009122)
		(width 0.14224)
		(layer "In4.Cu")
		(net "M_B_ACT_N")
	)
	(segment
		(start 246.524526 -13.933678)
		(end 246.1133 -13.522452)
		(width 0.14224)
		(layer "In4.Cu")
		(net "M_B_ACT_N")
	)
	(segment
		(start 246.502682 -10.216642)
		(end 246.26824 -10.216642)
		(width 0.14224)
		(layer "In4.Cu")
		(net "M_B_ACT_N")
	)
	(segment
		(start 252.375924 -51.408076)
		(end 253.030736 -50.753264)
		(width 0.0889)
		(layer "In4.Cu")
		(net "M_B_ACT_N")
	)
	(segment
		(start 246.90324 -22.662896)
		(end 247.15724 -22.408896)
		(width 0.14224)
		(layer "In4.Cu")
		(net "M_B_ACT_N")
	)
	(segment
		(start 247.15724 -18.301462)
		(end 247.15724 -17.159986)
		(width 0.14224)
		(layer "In4.Cu")
		(net "M_B_ACT_N")
	)
	(segment
		(start 246.1133 -11.164062)
		(end 246.26824 -11.009122)
		(width 0.14224)
		(layer "In4.Cu")
		(net "M_B_ACT_N")
	)
	(segment
		(start 252.435614 -53.809138)
		(end 252.430788 -53.800502)
		(width 0.0889)
		(layer "In4.Cu")
		(net "M_B_ACT_N")
	)
	(segment
		(start 246.9896 -16.992346)
		(end 246.9896 -15.37462)
		(width 0.14224)
		(layer "In4.Cu")
		(net "M_B_ACT_N")
	)
	(segment
		(start 246.1133 -8.16991)
		(end 246.235728 -7.874)
		(width 0.14224)
		(layer "In4.Cu")
		(net "M_B_ACT_N")
	)
	(segment
		(start 252.435614 -52.418488)
		(end 252.441964 -52.40782)
		(width 0.0889)
		(layer "In4.Cu")
		(net "M_B_ACT_N")
	)
	(segment
		(start 246.90324 -21.710396)
		(end 246.90324 -19.110706)
		(width 0.14224)
		(layer "In4.Cu")
		(net "M_B_ACT_N")
	)
	(segment
		(start 246.1133 -13.522452)
		(end 246.1133 -11.164062)
		(width 0.14224)
		(layer "In4.Cu")
		(net "M_B_ACT_N")
	)
	(segment
		(start 246.502682 -11.009122)
		(end 246.657622 -10.854182)
		(width 0.14224)
		(layer "In4.Cu")
		(net "M_B_ACT_N")
	)
	(segment
		(start 246.1133 -10.061702)
		(end 246.1133 -8.16991)
		(width 0.14224)
		(layer "In4.Cu")
		(net "M_B_ACT_N")
	)
	(arc
		(start 252.62332 -54.973982)
		(mid 252.512653 -54.897702)
		(end 252.430788 -54.791102)
		(width 0.0889)
		(layer "In4.Cu")
		(net "M_B_ACT_N")
	)
	(arc
		(start 252.435614 -52.818284)
		(mid 252.382115 -52.618386)
		(end 252.435614 -52.418488)
		(width 0.0889)
		(layer "In4.Cu")
		(net "M_B_ACT_N")
	)
	(arc
		(start 252.435868 -51.828192)
		(mid 252.391196 -51.719982)
		(end 252.375924 -51.60391)
		(width 0.0889)
		(layer "In4.Cu")
		(net "M_B_ACT_N")
	)
	(arc
		(start 252.435614 -53.409088)
		(mid 252.514745 -53.113686)
		(end 252.435614 -52.818284)
		(width 0.0889)
		(layer "In4.Cu")
		(net "M_B_ACT_N")
	)
	(arc
		(start 252.441964 -52.40782)
		(mid 252.510579 -52.194084)
		(end 252.494542 -51.970178)
		(width 0.0889)
		(layer "In4.Cu")
		(net "M_B_ACT_N")
	)
	(arc
		(start 252.430788 -53.800502)
		(mid 252.382033 -53.60415)
		(end 252.435614 -53.409088)
		(width 0.0889)
		(layer "In4.Cu")
		(net "M_B_ACT_N")
	)
	(arc
		(start 252.943868 -55.956962)
		(mid 253.182581 -55.597285)
		(end 252.955806 -55.230014)
		(width 0.0889)
		(layer "In4.Cu")
		(net "M_B_ACT_N")
	)
	(arc
		(start 252.955806 -55.230014)
		(mid 252.873463 -55.177439)
		(end 252.805946 -55.106824)
		(width 0.0889)
		(layer "In4.Cu")
		(net "M_B_ACT_N")
	)
	(arc
		(start 252.794008 -55.094886)
		(mid 252.713775 -55.02722)
		(end 252.62332 -54.973982)
		(width 0.0889)
		(layer "In4.Cu")
		(net "M_B_ACT_N")
	)
	(arc
		(start 252.494542 -51.970178)
		(mid 252.469849 -51.897265)
		(end 252.435868 -51.828192)
		(width 0.0889)
		(layer "In4.Cu")
		(net "M_B_ACT_N")
	)
	(arc
		(start 252.435614 -54.399688)
		(mid 252.514836 -54.11057)
		(end 252.441964 -53.819806)
		(width 0.0889)
		(layer "In4.Cu")
		(net "M_B_ACT_N")
	)
	(arc
		(start 252.430788 -54.791102)
		(mid 252.382033 -54.59475)
		(end 252.435614 -54.399688)
		(width 0.0889)
		(layer "In4.Cu")
		(net "M_B_ACT_N")
	)
	(segment
		(start 262.520684 -26.353516)
		(end 261.62381 -27.25039)
		(width 0.1651)
		(layer "F.Cu")
		(net "M_A_PAR")
	)
	(segment
		(start 261.493 -48.8442)
		(end 261.493 -50.179478)
		(width 0.0889)
		(layer "F.Cu")
		(net "M_A_PAR")
	)
	(segment
		(start 265.250422 -20.023582)
		(end 265.249914 -20.023582)
		(width 0.1651)
		(layer "F.Cu")
		(net "M_A_PAR")
	)
	(segment
		(start 261.62381 -46.009814)
		(end 261.62381 -46.325536)
		(width 0.0889)
		(layer "F.Cu")
		(net "M_A_PAR")
	)
	(segment
		(start 265.24966 -22.197568)
		(end 265.24966 -23.62454)
		(width 0.1651)
		(layer "F.Cu")
		(net "M_A_PAR")
	)
	(segment
		(start 265.249914 -20.023582)
		(end 265.249914 -22.197314)
		(width 0.1651)
		(layer "F.Cu")
		(net "M_A_PAR")
	)
	(segment
		(start 262.083804 -46.78553)
		(end 262.083804 -48.253396)
		(width 0.0889)
		(layer "F.Cu")
		(net "M_A_PAR")
	)
	(segment
		(start 265.24966 -23.62454)
		(end 262.520684 -26.353516)
		(width 0.1651)
		(layer "F.Cu")
		(net "M_A_PAR")
	)
	(segment
		(start 261.62381 -46.325536)
		(end 262.083804 -46.78553)
		(width 0.0889)
		(layer "F.Cu")
		(net "M_A_PAR")
	)
	(segment
		(start 265.249914 -22.197314)
		(end 265.24966 -22.197568)
		(width 0.1651)
		(layer "F.Cu")
		(net "M_A_PAR")
	)
	(segment
		(start 262.083804 -48.253396)
		(end 261.493 -48.8442)
		(width 0.0889)
		(layer "F.Cu")
		(net "M_A_PAR")
	)
	(segment
		(start 261.493 -50.179478)
		(end 261.08025 -51.132486)
		(width 0.0889)
		(layer "F.Cu")
		(net "M_A_PAR")
	)
	(segment
		(start 261.62381 -27.25039)
		(end 261.62381 -46.009814)
		(width 0.1651)
		(layer "F.Cu")
		(net "M_A_PAR")
	)
	(via
		(at 265.24966 -22.197568)
		(size 0.508)
		(drill 0.254)
		(layers "F.Cu" "B.Cu")
		(net "M_A_PAR")
	)
	(via
		(at 262.520684 -26.353516)
		(size 0.508)
		(drill 0.254)
		(layers "F.Cu" "B.Cu")
		(net "M_A_PAR")
	)
	(segment
		(start 265.249914 -22.197314)
		(end 265.24966 -22.197568)
		(width 0.1651)
		(layer "B.Cu")
		(net "M_A_PAR")
	)
	(segment
		(start 265.250422 -20.224242)
		(end 265.249914 -20.224242)
		(width 0.1651)
		(layer "B.Cu")
		(net "M_A_PAR")
	)
	(segment
		(start 265.249914 -20.224242)
		(end 265.249914 -22.197314)
		(width 0.1651)
		(layer "B.Cu")
		(net "M_A_PAR")
	)
	(segment
		(start 267.67409 -48.632364)
		(end 267.67409 -48.136302)
		(width 0.0889)
		(layer "F.Cu")
		(net "M_A_ODT<3>")
	)
	(segment
		(start 273.0754 -26.622248)
		(end 273.0754 -26.035)
		(width 0.1651)
		(layer "F.Cu")
		(net "M_A_ODT<3>")
	)
	(segment
		(start 273.0754 -27.257502)
		(end 273.0754 -26.622248)
		(width 0.1651)
		(layer "F.Cu")
		(net "M_A_ODT<3>")
	)
	(segment
		(start 267.67409 -48.136302)
		(end 267.67409 -32.658812)
		(width 0.1651)
		(layer "F.Cu")
		(net "M_A_ODT<3>")
	)
	(segment
		(start 275.9202 -23.230586)
		(end 276.29993 -22.850856)
		(width 0.1651)
		(layer "F.Cu")
		(net "M_A_ODT<3>")
	)
	(segment
		(start 266.72159 -50.084736)
		(end 266.72159 -49.584864)
		(width 0.0889)
		(layer "F.Cu")
		(net "M_A_ODT<3>")
	)
	(segment
		(start 267.67409 -32.658812)
		(end 273.0754 -27.257502)
		(width 0.1651)
		(layer "F.Cu")
		(net "M_A_ODT<3>")
	)
	(segment
		(start 265.372596 -52.618386)
		(end 265.702796 -51.856386)
		(width 0.0889)
		(layer "F.Cu")
		(net "M_A_ODT<3>")
	)
	(segment
		(start 275.9202 -23.8506)
		(end 275.9202 -23.230586)
		(width 0.1651)
		(layer "F.Cu")
		(net "M_A_ODT<3>")
	)
	(segment
		(start 266.72159 -49.584864)
		(end 267.67409 -48.632364)
		(width 0.0889)
		(layer "F.Cu")
		(net "M_A_ODT<3>")
	)
	(segment
		(start 265.702796 -51.856386)
		(end 265.724132 -51.819302)
		(width 0.0889)
		(layer "F.Cu")
		(net "M_A_ODT<3>")
	)
	(segment
		(start 266.578842 -50.32756)
		(end 266.72159 -50.084736)
		(width 0.0889)
		(layer "F.Cu")
		(net "M_A_ODT<3>")
	)
	(segment
		(start 265.772646 -51.637184)
		(end 265.772646 -51.015392)
		(width 0.0889)
		(layer "F.Cu")
		(net "M_A_ODT<3>")
	)
	(segment
		(start 274.2946 -25.4762)
		(end 275.9202 -23.8506)
		(width 0.1651)
		(layer "F.Cu")
		(net "M_A_ODT<3>")
	)
	(segment
		(start 273.6342 -25.4762)
		(end 274.2946 -25.4762)
		(width 0.1651)
		(layer "F.Cu")
		(net "M_A_ODT<3>")
	)
	(segment
		(start 265.772646 -51.015392)
		(end 266.246102 -50.541936)
		(width 0.0889)
		(layer "F.Cu")
		(net "M_A_ODT<3>")
	)
	(segment
		(start 273.0754 -26.035)
		(end 273.6342 -25.4762)
		(width 0.1651)
		(layer "F.Cu")
		(net "M_A_ODT<3>")
	)
	(via
		(at 276.29993 -22.850856)
		(size 0.508)
		(drill 0.254)
		(layers "F.Cu" "B.Cu")
		(net "M_A_ODT<3>")
	)
	(via
		(at 273.0754 -26.622248)
		(size 0.508)
		(drill 0.254)
		(layers "F.Cu" "B.Cu")
		(net "M_A_ODT<3>")
	)
	(arc
		(start 265.724132 -51.819302)
		(mid 265.759285 -51.731143)
		(end 265.772646 -51.637184)
		(width 0.0889)
		(layer "F.Cu")
		(net "M_A_ODT<3>")
	)
	(arc
		(start 266.246102 -50.541936)
		(mid 266.441846 -50.480345)
		(end 266.578842 -50.32756)
		(width 0.0889)
		(layer "F.Cu")
		(net "M_A_ODT<3>")
	)
	(segment
		(start 276.300438 -24.824182)
		(end 276.29993 -24.824182)
		(width 0.1651)
		(layer "B.Cu")
		(net "M_A_ODT<3>")
	)
	(segment
		(start 276.29993 -24.824182)
		(end 276.29993 -22.850856)
		(width 0.1651)
		(layer "B.Cu")
		(net "M_A_ODT<3>")
	)
	(segment
		(start 264.007346 -50.828702)
		(end 264.00252 -50.837338)
		(width 0.0889)
		(layer "F.Cu")
		(net "M_A_ODT<2>")
	)
	(segment
		(start 272.899886 -23.548594)
		(end 272.156174 -24.292306)
		(width 0.1651)
		(layer "F.Cu")
		(net "M_A_ODT<2>")
	)
	(segment
		(start 271.373346 -24.79167)
		(end 271.373346 -25.118314)
		(width 0.1651)
		(layer "F.Cu")
		(net "M_A_ODT<2>")
	)
	(segment
		(start 265.65733 -47.727616)
		(end 263.887204 -49.497742)
		(width 0.0889)
		(layer "F.Cu")
		(net "M_A_ODT<2>")
	)
	(segment
		(start 264.00252 -50.837338)
		(end 263.99617 -50.848006)
		(width 0.0889)
		(layer "F.Cu")
		(net "M_A_ODT<2>")
	)
	(segment
		(start 272.899886 -22.850856)
		(end 272.899886 -23.548594)
		(width 0.1651)
		(layer "F.Cu")
		(net "M_A_ODT<2>")
	)
	(segment
		(start 264.007346 -51.819302)
		(end 263.98601 -51.856386)
		(width 0.0889)
		(layer "F.Cu")
		(net "M_A_ODT<2>")
	)
	(segment
		(start 263.887204 -49.497742)
		(end 263.887204 -50.006758)
		(width 0.0889)
		(layer "F.Cu")
		(net "M_A_ODT<2>")
	)
	(segment
		(start 272.156174 -24.292306)
		(end 271.87271 -24.292306)
		(width 0.1651)
		(layer "F.Cu")
		(net "M_A_ODT<2>")
	)
	(segment
		(start 271.87271 -24.292306)
		(end 271.373346 -24.79167)
		(width 0.1651)
		(layer "F.Cu")
		(net "M_A_ODT<2>")
	)
	(segment
		(start 269.8496 -26.0096)
		(end 269.8496 -26.560272)
		(width 0.1651)
		(layer "F.Cu")
		(net "M_A_ODT<2>")
	)
	(segment
		(start 263.98601 -51.856386)
		(end 263.65581 -52.618386)
		(width 0.0889)
		(layer "F.Cu")
		(net "M_A_ODT<2>")
	)
	(segment
		(start 265.65733 -31.411672)
		(end 265.65733 -47.43958)
		(width 0.1651)
		(layer "F.Cu")
		(net "M_A_ODT<2>")
	)
	(segment
		(start 269.8496 -27.219402)
		(end 265.65733 -31.411672)
		(width 0.1651)
		(layer "F.Cu")
		(net "M_A_ODT<2>")
	)
	(segment
		(start 271.373346 -25.118314)
		(end 270.91386 -25.5778)
		(width 0.1651)
		(layer "F.Cu")
		(net "M_A_ODT<2>")
	)
	(segment
		(start 269.8496 -26.560272)
		(end 269.8496 -27.219402)
		(width 0.1651)
		(layer "F.Cu")
		(net "M_A_ODT<2>")
	)
	(segment
		(start 265.65733 -47.43958)
		(end 265.65733 -47.727616)
		(width 0.0889)
		(layer "F.Cu")
		(net "M_A_ODT<2>")
	)
	(segment
		(start 270.2814 -25.5778)
		(end 269.8496 -26.0096)
		(width 0.1651)
		(layer "F.Cu")
		(net "M_A_ODT<2>")
	)
	(segment
		(start 270.91386 -25.5778)
		(end 270.2814 -25.5778)
		(width 0.1651)
		(layer "F.Cu")
		(net "M_A_ODT<2>")
	)
	(via
		(at 269.8496 -26.560272)
		(size 0.508)
		(drill 0.254)
		(layers "F.Cu" "B.Cu")
		(net "M_A_ODT<2>")
	)
	(via
		(at 272.899886 -22.850856)
		(size 0.508)
		(drill 0.254)
		(layers "F.Cu" "B.Cu")
		(net "M_A_ODT<2>")
	)
	(arc
		(start 264.00252 -51.427888)
		(mid 264.05599 -51.622951)
		(end 264.007346 -51.819302)
		(width 0.0889)
		(layer "F.Cu")
		(net "M_A_ODT<2>")
	)
	(arc
		(start 263.887204 -50.006758)
		(mid 263.916541 -50.229606)
		(end 264.00252 -50.437288)
		(width 0.0889)
		(layer "F.Cu")
		(net "M_A_ODT<2>")
	)
	(arc
		(start 263.99617 -50.848006)
		(mid 263.923372 -51.138769)
		(end 264.00252 -51.427888)
		(width 0.0889)
		(layer "F.Cu")
		(net "M_A_ODT<2>")
	)
	(arc
		(start 264.00252 -50.437288)
		(mid 264.05599 -50.632351)
		(end 264.007346 -50.828702)
		(width 0.0889)
		(layer "F.Cu")
		(net "M_A_ODT<2>")
	)
	(segment
		(start 272.900394 -24.824182)
		(end 272.899886 -24.824182)
		(width 0.1651)
		(layer "B.Cu")
		(net "M_A_ODT<2>")
	)
	(segment
		(start 272.899886 -24.824182)
		(end 272.899886 -22.850856)
		(width 0.1651)
		(layer "B.Cu")
		(net "M_A_ODT<2>")
	)
	(segment
		(start 276.300438 -15.423642)
		(end 276.29993 -15.423642)
		(width 0.1651)
		(layer "F.Cu")
		(net "M_A_ODT<1>")
	)
	(segment
		(start 266.118848 -49.425352)
		(end 265.737848 -49.425352)
		(width 0.0889)
		(layer "F.Cu")
		(net "M_A_ODT<1>")
	)
	(segment
		(start 265.42111 -49.74209)
		(end 265.305032 -49.942496)
		(width 0.0889)
		(layer "F.Cu")
		(net "M_A_ODT<1>")
	)
	(segment
		(start 265.266678 -50.216308)
		(end 265.372596 -50.63744)
		(width 0.0889)
		(layer "F.Cu")
		(net "M_A_ODT<1>")
	)
	(segment
		(start 276.29993 -15.423642)
		(end 276.29993 -16.71828)
		(width 0.1651)
		(layer "F.Cu")
		(net "M_A_ODT<1>")
	)
	(segment
		(start 267.1699 -32.4104)
		(end 267.1699 -47.815754)
		(width 0.1651)
		(layer "F.Cu")
		(net "M_A_ODT<1>")
	)
	(segment
		(start 270.966692 -28.613608)
		(end 267.1699 -32.4104)
		(width 0.1651)
		(layer "F.Cu")
		(net "M_A_ODT<1>")
	)
	(segment
		(start 272.542 -27.0383)
		(end 270.966692 -28.613608)
		(width 0.1651)
		(layer "F.Cu")
		(net "M_A_ODT<1>")
	)
	(segment
		(start 272.542 -26.668984)
		(end 272.542 -27.0383)
		(width 0.1651)
		(layer "F.Cu")
		(net "M_A_ODT<1>")
	)
	(segment
		(start 265.737848 -49.425352)
		(end 265.42111 -49.74209)
		(width 0.0889)
		(layer "F.Cu")
		(net "M_A_ODT<1>")
	)
	(segment
		(start 267.1699 -48.3743)
		(end 266.118848 -49.425352)
		(width 0.0889)
		(layer "F.Cu")
		(net "M_A_ODT<1>")
	)
	(segment
		(start 267.1699 -47.815754)
		(end 267.1699 -48.3743)
		(width 0.0889)
		(layer "F.Cu")
		(net "M_A_ODT<1>")
	)
	(segment
		(start 276.29993 -16.71828)
		(end 276.300438 -16.718788)
		(width 0.1651)
		(layer "F.Cu")
		(net "M_A_ODT<1>")
	)
	(segment
		(start 272.06448 -26.191464)
		(end 272.542 -26.668984)
		(width 0.1651)
		(layer "F.Cu")
		(net "M_A_ODT<1>")
	)
	(via
		(at 276.300438 -16.718788)
		(size 0.4572)
		(drill 0.2032)
		(layers "F.Cu" "B.Cu")
		(net "M_A_ODT<1>")
	)
	(via
		(at 272.06448 -26.191464)
		(size 0.508)
		(drill 0.254)
		(layers "F.Cu" "B.Cu")
		(net "M_A_ODT<1>")
	)
	(via
		(at 270.966692 -28.613608)
		(size 0.508)
		(drill 0.254)
		(layers "F.Cu" "B.Cu")
		(net "M_A_ODT<1>")
	)
	(arc
		(start 265.305032 -49.942496)
		(mid 265.259084 -50.075656)
		(end 265.266678 -50.216308)
		(width 0.0889)
		(layer "F.Cu")
		(net "M_A_ODT<1>")
	)
	(segment
		(start 276.29993 -16.719296)
		(end 276.300438 -16.718788)
		(width 0.14224)
		(layer "In9.Cu")
		(net "M_A_ODT<1>")
	)
	(segment
		(start 275.9964 -19.741388)
		(end 275.7932 -19.538188)
		(width 0.14224)
		(layer "In9.Cu")
		(net "M_A_ODT<1>")
	)
	(segment
		(start 275.9964 -21.9202)
		(end 275.7932 -21.717)
		(width 0.14224)
		(layer "In9.Cu")
		(net "M_A_ODT<1>")
	)
	(segment
		(start 272.576544 -25.6794)
		(end 272.6182 -25.6794)
		(width 0.14224)
		(layer "In9.Cu")
		(net "M_A_ODT<1>")
	)
	(segment
		(start 276.527514 -19.741388)
		(end 275.9964 -19.741388)
		(width 0.14224)
		(layer "In9.Cu")
		(net "M_A_ODT<1>")
	)
	(segment
		(start 275.733002 -17.865598)
		(end 276.29993 -17.29867)
		(width 0.14224)
		(layer "In9.Cu")
		(net "M_A_ODT<1>")
	)
	(segment
		(start 276.739096 -19.95297)
		(end 276.527514 -19.741388)
		(width 0.14224)
		(layer "In9.Cu")
		(net "M_A_ODT<1>")
	)
	(segment
		(start 275.7932 -19.538188)
		(end 275.7932 -19.177)
		(width 0.14224)
		(layer "In9.Cu")
		(net "M_A_ODT<1>")
	)
	(segment
		(start 276.29993 -17.29867)
		(end 276.29993 -16.719296)
		(width 0.14224)
		(layer "In9.Cu")
		(net "M_A_ODT<1>")
	)
	(segment
		(start 275.9964 -20.579588)
		(end 276.544278 -20.579588)
		(width 0.14224)
		(layer "In9.Cu")
		(net "M_A_ODT<1>")
	)
	(segment
		(start 275.871432 -18.442432)
		(end 275.733002 -18.304002)
		(width 0.14224)
		(layer "In9.Cu")
		(net "M_A_ODT<1>")
	)
	(segment
		(start 272.06448 -26.191464)
		(end 272.576544 -25.6794)
		(width 0.14224)
		(layer "In9.Cu")
		(net "M_A_ODT<1>")
	)
	(segment
		(start 275.7932 -20.782788)
		(end 275.9964 -20.579588)
		(width 0.14224)
		(layer "In9.Cu")
		(net "M_A_ODT<1>")
	)
	(segment
		(start 276.544278 -20.579588)
		(end 276.739096 -20.38477)
		(width 0.14224)
		(layer "In9.Cu")
		(net "M_A_ODT<1>")
	)
	(segment
		(start 275.733002 -18.304002)
		(end 275.733002 -17.865598)
		(width 0.14224)
		(layer "In9.Cu")
		(net "M_A_ODT<1>")
	)
	(segment
		(start 276.739096 -20.38477)
		(end 276.739096 -19.95297)
		(width 0.14224)
		(layer "In9.Cu")
		(net "M_A_ODT<1>")
	)
	(segment
		(start 275.871432 -19.098768)
		(end 275.871432 -18.442432)
		(width 0.14224)
		(layer "In9.Cu")
		(net "M_A_ODT<1>")
	)
	(segment
		(start 275.7932 -19.177)
		(end 275.871432 -19.098768)
		(width 0.14224)
		(layer "In9.Cu")
		(net "M_A_ODT<1>")
	)
	(segment
		(start 275.9964 -22.3012)
		(end 275.9964 -21.9202)
		(width 0.14224)
		(layer "In9.Cu")
		(net "M_A_ODT<1>")
	)
	(segment
		(start 275.7932 -21.717)
		(end 275.7932 -20.782788)
		(width 0.14224)
		(layer "In9.Cu")
		(net "M_A_ODT<1>")
	)
	(segment
		(start 272.6182 -25.6794)
		(end 275.9964 -22.3012)
		(width 0.14224)
		(layer "In9.Cu")
		(net "M_A_ODT<1>")
	)
	(segment
		(start 272.899886 -15.423642)
		(end 272.899886 -16.714978)
		(width 0.1651)
		(layer "F.Cu")
		(net "M_A_ODT<0>")
	)
	(segment
		(start 265.15314 -47.851314)
		(end 265.15314 -47.501302)
		(width 0.0889)
		(layer "F.Cu")
		(net "M_A_ODT<0>")
	)
	(segment
		(start 263.65581 -50.63744)
		(end 263.65581 -49.348644)
		(width 0.0889)
		(layer "F.Cu")
		(net "M_A_ODT<0>")
	)
	(segment
		(start 269.3162 -27.0002)
		(end 269.3162 -26.356564)
		(width 0.1651)
		(layer "F.Cu")
		(net "M_A_ODT<0>")
	)
	(segment
		(start 263.65581 -49.348644)
		(end 265.15314 -47.851314)
		(width 0.0889)
		(layer "F.Cu")
		(net "M_A_ODT<0>")
	)
	(segment
		(start 272.900394 -15.423642)
		(end 272.899886 -15.423642)
		(width 0.1651)
		(layer "F.Cu")
		(net "M_A_ODT<0>")
	)
	(segment
		(start 269.1511 -26.191464)
		(end 268.664436 -26.191464)
		(width 0.1651)
		(layer "F.Cu")
		(net "M_A_ODT<0>")
	)
	(segment
		(start 265.15314 -47.501302)
		(end 265.15314 -31.16326)
		(width 0.1651)
		(layer "F.Cu")
		(net "M_A_ODT<0>")
	)
	(segment
		(start 269.3162 -26.356564)
		(end 269.1511 -26.191464)
		(width 0.1651)
		(layer "F.Cu")
		(net "M_A_ODT<0>")
	)
	(segment
		(start 265.15314 -31.16326)
		(end 267.62202 -28.69438)
		(width 0.1651)
		(layer "F.Cu")
		(net "M_A_ODT<0>")
	)
	(segment
		(start 267.62202 -28.69438)
		(end 269.3162 -27.0002)
		(width 0.1651)
		(layer "F.Cu")
		(net "M_A_ODT<0>")
	)
	(via
		(at 272.899886 -16.714978)
		(size 0.508)
		(drill 0.254)
		(layers "F.Cu" "B.Cu")
		(net "M_A_ODT<0>")
	)
	(via
		(at 268.664436 -26.191464)
		(size 0.508)
		(drill 0.254)
		(layers "F.Cu" "B.Cu")
		(net "M_A_ODT<0>")
	)
	(via
		(at 267.62202 -28.69438)
		(size 0.508)
		(drill 0.254)
		(layers "F.Cu" "B.Cu")
		(net "M_A_ODT<0>")
	)
	(segment
		(start 272.5166 -21.9202)
		(end 272.4404 -21.844)
		(width 0.14224)
		(layer "In9.Cu")
		(net "M_A_ODT<0>")
	)
	(segment
		(start 273.3802 -20.8153)
		(end 273.5834 -20.6121)
		(width 0.14224)
		(layer "In9.Cu")
		(net "M_A_ODT<0>")
	)
	(segment
		(start 272.6436 -20.8153)
		(end 273.3802 -20.8153)
		(width 0.14224)
		(layer "In9.Cu")
		(net "M_A_ODT<0>")
	)
	(segment
		(start 272.4404 -21.0185)
		(end 272.6436 -20.8153)
		(width 0.14224)
		(layer "In9.Cu")
		(net "M_A_ODT<0>")
	)
	(segment
		(start 272.6436 -20.0025)
		(end 272.462244 -19.821144)
		(width 0.14224)
		(layer "In9.Cu")
		(net "M_A_ODT<0>")
	)
	(segment
		(start 272.462244 -19.821144)
		(end 272.462244 -18.155412)
		(width 0.14224)
		(layer "In9.Cu")
		(net "M_A_ODT<0>")
	)
	(segment
		(start 268.664436 -26.191464)
		(end 269.2908 -25.5651)
		(width 0.14224)
		(layer "In9.Cu")
		(net "M_A_ODT<0>")
	)
	(segment
		(start 272.4404 -21.844)
		(end 272.4404 -21.0185)
		(width 0.14224)
		(layer "In9.Cu")
		(net "M_A_ODT<0>")
	)
	(segment
		(start 269.2908 -25.5651)
		(end 269.3289 -25.5651)
		(width 0.14224)
		(layer "In9.Cu")
		(net "M_A_ODT<0>")
	)
	(segment
		(start 272.5166 -22.3774)
		(end 272.5166 -21.9202)
		(width 0.14224)
		(layer "In9.Cu")
		(net "M_A_ODT<0>")
	)
	(segment
		(start 273.5834 -20.6121)
		(end 273.5834 -20.2057)
		(width 0.14224)
		(layer "In9.Cu")
		(net "M_A_ODT<0>")
	)
	(segment
		(start 269.3289 -25.5651)
		(end 272.5166 -22.3774)
		(width 0.14224)
		(layer "In9.Cu")
		(net "M_A_ODT<0>")
	)
	(segment
		(start 273.3802 -20.0025)
		(end 272.6436 -20.0025)
		(width 0.14224)
		(layer "In9.Cu")
		(net "M_A_ODT<0>")
	)
	(segment
		(start 272.899886 -17.71777)
		(end 272.899886 -16.714978)
		(width 0.14224)
		(layer "In9.Cu")
		(net "M_A_ODT<0>")
	)
	(segment
		(start 273.5834 -20.2057)
		(end 273.3802 -20.0025)
		(width 0.14224)
		(layer "In9.Cu")
		(net "M_A_ODT<0>")
	)
	(segment
		(start 272.462244 -18.155412)
		(end 272.899886 -17.71777)
		(width 0.14224)
		(layer "In9.Cu")
		(net "M_A_ODT<0>")
	)
	(segment
		(start 249.950478 -15.423642)
		(end 249.94997 -15.423642)
		(width 0.1651)
		(layer "F.Cu")
		(net "M_A_MA<9>")
	)
	(segment
		(start 249.94997 -16.716502)
		(end 249.949716 -16.716756)
		(width 0.1651)
		(layer "F.Cu")
		(net "M_A_MA<9>")
	)
	(segment
		(start 254.212344 -52.12334)
		(end 253.640844 -52.12334)
		(width 0.1016)
		(layer "F.Cu")
		(net "M_A_MA<9>")
	)
	(segment
		(start 249.94997 -15.423642)
		(end 249.94997 -16.716502)
		(width 0.1651)
		(layer "F.Cu")
		(net "M_A_MA<9>")
	)
	(via
		(at 249.94997 -23.560278)
		(size 0.508)
		(drill 0.254)
		(layers "F.Cu" "B.Cu")
		(net "M_A_MA<9>")
	)
	(via
		(at 253.640844 -52.12334)
		(size 0.508)
		(drill 0.254)
		(layers "F.Cu" "B.Cu")
		(net "M_A_MA<9>")
	)
	(via
		(at 249.949716 -16.716756)
		(size 0.4572)
		(drill 0.2032)
		(layers "F.Cu" "B.Cu")
		(net "M_A_MA<9>")
	)
	(segment
		(start 249.950478 -24.824182)
		(end 249.94997 -24.824182)
		(width 0.1651)
		(layer "B.Cu")
		(net "M_A_MA<9>")
	)
	(segment
		(start 249.94997 -24.824182)
		(end 249.94997 -23.560278)
		(width 0.1651)
		(layer "B.Cu")
		(net "M_A_MA<9>")
	)
	(segment
		(start 253.135384 -33.13938)
		(end 253.135384 -50.561748)
		(width 0.14224)
		(layer "In11.Cu")
		(net "M_A_MA<9>")
	)
	(segment
		(start 250.435364 -21.962364)
		(end 250.435364 -22.462236)
		(width 0.14224)
		(layer "In11.Cu")
		(net "M_A_MA<9>")
	)
	(segment
		(start 250.2916 -22.606)
		(end 250.2916 -23.218648)
		(width 0.14224)
		(layer "In11.Cu")
		(net "M_A_MA<9>")
	)
	(segment
		(start 249.94997 -23.969726)
		(end 250.3678 -24.387556)
		(width 0.14224)
		(layer "In11.Cu")
		(net "M_A_MA<9>")
	)
	(segment
		(start 250.3424 -21.8694)
		(end 250.435364 -21.962364)
		(width 0.14224)
		(layer "In11.Cu")
		(net "M_A_MA<9>")
	)
	(segment
		(start 251.124212 -29.354526)
		(end 250.0884 -29.354526)
		(width 0.14224)
		(layer "In11.Cu")
		(net "M_A_MA<9>")
	)
	(segment
		(start 249.94997 -23.560278)
		(end 249.94997 -23.969726)
		(width 0.14224)
		(layer "In11.Cu")
		(net "M_A_MA<9>")
	)
	(segment
		(start 250.388628 -21.238972)
		(end 250.3424 -21.2852)
		(width 0.14224)
		(layer "In11.Cu")
		(net "M_A_MA<9>")
	)
	(segment
		(start 250.435364 -22.462236)
		(end 250.2916 -22.606)
		(width 0.14224)
		(layer "In11.Cu")
		(net "M_A_MA<9>")
	)
	(segment
		(start 249.8852 -27.80792)
		(end 249.8852 -28.190698)
		(width 0.14224)
		(layer "In11.Cu")
		(net "M_A_MA<9>")
	)
	(segment
		(start 249.949716 -16.716756)
		(end 250.388628 -17.155668)
		(width 0.14224)
		(layer "In11.Cu")
		(net "M_A_MA<9>")
	)
	(segment
		(start 250.2916 -23.218648)
		(end 249.94997 -23.560278)
		(width 0.14224)
		(layer "In11.Cu")
		(net "M_A_MA<9>")
	)
	(segment
		(start 250.3678 -26.4668)
		(end 250.5456 -26.6446)
		(width 0.14224)
		(layer "In11.Cu")
		(net "M_A_MA<9>")
	)
	(segment
		(start 251.123196 -28.393898)
		(end 251.326904 -28.597606)
		(width 0.14224)
		(layer "In11.Cu")
		(net "M_A_MA<9>")
	)
	(segment
		(start 250.5456 -26.6446)
		(end 250.5456 -27.14752)
		(width 0.14224)
		(layer "In11.Cu")
		(net "M_A_MA<9>")
	)
	(segment
		(start 250.0884 -29.354526)
		(end 249.8852 -29.557726)
		(width 0.14224)
		(layer "In11.Cu")
		(net "M_A_MA<9>")
	)
	(segment
		(start 249.8852 -29.889196)
		(end 253.135384 -33.13938)
		(width 0.14224)
		(layer "In11.Cu")
		(net "M_A_MA<9>")
	)
	(segment
		(start 250.3678 -24.387556)
		(end 250.3678 -26.4668)
		(width 0.14224)
		(layer "In11.Cu")
		(net "M_A_MA<9>")
	)
	(segment
		(start 250.5456 -27.14752)
		(end 249.8852 -27.80792)
		(width 0.14224)
		(layer "In11.Cu")
		(net "M_A_MA<9>")
	)
	(segment
		(start 249.8852 -29.557726)
		(end 249.8852 -29.889196)
		(width 0.14224)
		(layer "In11.Cu")
		(net "M_A_MA<9>")
	)
	(segment
		(start 250.388628 -17.155668)
		(end 250.388628 -21.238972)
		(width 0.14224)
		(layer "In11.Cu")
		(net "M_A_MA<9>")
	)
	(segment
		(start 253.135384 -50.852324)
		(end 253.640844 -51.357784)
		(width 0.0889)
		(layer "In11.Cu")
		(net "M_A_MA<9>")
	)
	(segment
		(start 250.0884 -28.393898)
		(end 251.123196 -28.393898)
		(width 0.14224)
		(layer "In11.Cu")
		(net "M_A_MA<9>")
	)
	(segment
		(start 251.326904 -28.597606)
		(end 251.326904 -29.151834)
		(width 0.14224)
		(layer "In11.Cu")
		(net "M_A_MA<9>")
	)
	(segment
		(start 249.8852 -28.190698)
		(end 250.0884 -28.393898)
		(width 0.14224)
		(layer "In11.Cu")
		(net "M_A_MA<9>")
	)
	(segment
		(start 253.135384 -50.561748)
		(end 253.135384 -50.852324)
		(width 0.0889)
		(layer "In11.Cu")
		(net "M_A_MA<9>")
	)
	(segment
		(start 251.326904 -29.151834)
		(end 251.124212 -29.354526)
		(width 0.14224)
		(layer "In11.Cu")
		(net "M_A_MA<9>")
	)
	(segment
		(start 250.3424 -21.2852)
		(end 250.3424 -21.8694)
		(width 0.14224)
		(layer "In11.Cu")
		(net "M_A_MA<9>")
	)
	(segment
		(start 253.640844 -51.357784)
		(end 253.640844 -52.12334)
		(width 0.0889)
		(layer "In11.Cu")
		(net "M_A_MA<9>")
	)
	(segment
		(start 251.831094 -28.843732)
		(end 252.000004 -28.674822)
		(width 0.1651)
		(layer "F.Cu")
		(net "M_A_MA<8>")
	)
	(segment
		(start 255.07061 -50.63744)
		(end 255.208278 -50.499772)
		(width 0.0889)
		(layer "F.Cu")
		(net "M_A_MA<8>")
	)
	(segment
		(start 252.068076 -25.528016)
		(end 251.512832 -25.528016)
		(width 0.1651)
		(layer "F.Cu")
		(net "M_A_MA<8>")
	)
	(segment
		(start 251.649992 -15.423642)
		(end 251.649992 -16.718788)
		(width 0.1651)
		(layer "F.Cu")
		(net "M_A_MA<8>")
	)
	(segment
		(start 252.167136 -24.686514)
		(end 252.167136 -24.3967)
		(width 0.1651)
		(layer "F.Cu")
		(net "M_A_MA<8>")
	)
	(segment
		(start 251.32919 -28.005532)
		(end 251.32919 -27.640788)
		(width 0.1651)
		(layer "F.Cu")
		(net "M_A_MA<8>")
	)
	(segment
		(start 254.90932 -47.360078)
		(end 254.90932 -35.157918)
		(width 0.1651)
		(layer "F.Cu")
		(net "M_A_MA<8>")
	)
	(segment
		(start 251.557536 -26.188416)
		(end 252.068076 -26.188416)
		(width 0.1651)
		(layer "F.Cu")
		(net "M_A_MA<8>")
	)
	(segment
		(start 252.217682 -27.013916)
		(end 252.052582 -26.848816)
		(width 0.1651)
		(layer "F.Cu")
		(net "M_A_MA<8>")
	)
	(segment
		(start 251.45619 -27.513788)
		(end 252.03785 -27.513788)
		(width 0.1651)
		(layer "F.Cu")
		(net "M_A_MA<8>")
	)
	(segment
		(start 251.838714 -28.170632)
		(end 251.49429 -28.170632)
		(width 0.1651)
		(layer "F.Cu")
		(net "M_A_MA<8>")
	)
	(segment
		(start 251.955808 -24.185372)
		(end 251.815092 -24.185372)
		(width 0.1651)
		(layer "F.Cu")
		(net "M_A_MA<8>")
	)
	(segment
		(start 251.32919 -27.640788)
		(end 251.45619 -27.513788)
		(width 0.1651)
		(layer "F.Cu")
		(net "M_A_MA<8>")
	)
	(segment
		(start 252.068076 -26.188416)
		(end 252.233176 -26.023316)
		(width 0.1651)
		(layer "F.Cu")
		(net "M_A_MA<8>")
	)
	(segment
		(start 251.335794 -25.000966)
		(end 251.462794 -24.873966)
		(width 0.1651)
		(layer "F.Cu")
		(net "M_A_MA<8>")
	)
	(segment
		(start 251.595636 -26.848816)
		(end 251.411486 -26.664666)
		(width 0.1651)
		(layer "F.Cu")
		(net "M_A_MA<8>")
	)
	(segment
		(start 251.49429 -28.170632)
		(end 251.32919 -28.005532)
		(width 0.1651)
		(layer "F.Cu")
		(net "M_A_MA<8>")
	)
	(segment
		(start 251.512832 -25.528016)
		(end 251.335794 -25.350978)
		(width 0.1651)
		(layer "F.Cu")
		(net "M_A_MA<8>")
	)
	(segment
		(start 251.411486 -26.334466)
		(end 251.557536 -26.188416)
		(width 0.1651)
		(layer "F.Cu")
		(net "M_A_MA<8>")
	)
	(segment
		(start 251.815092 -24.185372)
		(end 251.649992 -24.020272)
		(width 0.1651)
		(layer "F.Cu")
		(net "M_A_MA<8>")
	)
	(segment
		(start 254.90932 -32.934148)
		(end 251.418852 -29.44368)
		(width 0.1651)
		(layer "F.Cu")
		(net "M_A_MA<8>")
	)
	(segment
		(start 252.167136 -24.3967)
		(end 251.955808 -24.185372)
		(width 0.1651)
		(layer "F.Cu")
		(net "M_A_MA<8>")
	)
	(segment
		(start 254.90932 -47.710344)
		(end 254.90932 -47.360078)
		(width 0.0889)
		(layer "F.Cu")
		(net "M_A_MA<8>")
	)
	(segment
		(start 252.03785 -27.513788)
		(end 252.217682 -27.333956)
		(width 0.1651)
		(layer "F.Cu")
		(net "M_A_MA<8>")
	)
	(segment
		(start 252.233176 -25.693116)
		(end 252.068076 -25.528016)
		(width 0.1651)
		(layer "F.Cu")
		(net "M_A_MA<8>")
	)
	(segment
		(start 252.052582 -26.848816)
		(end 251.595636 -26.848816)
		(width 0.1651)
		(layer "F.Cu")
		(net "M_A_MA<8>")
	)
	(segment
		(start 251.335794 -25.350978)
		(end 251.335794 -25.000966)
		(width 0.1651)
		(layer "F.Cu")
		(net "M_A_MA<8>")
	)
	(segment
		(start 251.411486 -26.664666)
		(end 251.411486 -26.334466)
		(width 0.1651)
		(layer "F.Cu")
		(net "M_A_MA<8>")
	)
	(segment
		(start 254.90932 -35.157918)
		(end 254.90932 -32.934148)
		(width 0.1651)
		(layer "F.Cu")
		(net "M_A_MA<8>")
	)
	(segment
		(start 252.217682 -27.333956)
		(end 252.217682 -27.013916)
		(width 0.1651)
		(layer "F.Cu")
		(net "M_A_MA<8>")
	)
	(segment
		(start 251.462794 -24.873966)
		(end 251.979684 -24.873966)
		(width 0.1651)
		(layer "F.Cu")
		(net "M_A_MA<8>")
	)
	(segment
		(start 252.000004 -28.674822)
		(end 252.000004 -28.331922)
		(width 0.1651)
		(layer "F.Cu")
		(net "M_A_MA<8>")
	)
	(segment
		(start 251.979684 -24.873966)
		(end 252.167136 -24.686514)
		(width 0.1651)
		(layer "F.Cu")
		(net "M_A_MA<8>")
	)
	(segment
		(start 251.418852 -29.44368)
		(end 251.418852 -28.997656)
		(width 0.1651)
		(layer "F.Cu")
		(net "M_A_MA<8>")
	)
	(segment
		(start 255.208278 -48.009302)
		(end 254.90932 -47.710344)
		(width 0.0889)
		(layer "F.Cu")
		(net "M_A_MA<8>")
	)
	(segment
		(start 252.233176 -26.023316)
		(end 252.233176 -25.693116)
		(width 0.1651)
		(layer "F.Cu")
		(net "M_A_MA<8>")
	)
	(segment
		(start 252.000004 -28.331922)
		(end 251.838714 -28.170632)
		(width 0.1651)
		(layer "F.Cu")
		(net "M_A_MA<8>")
	)
	(segment
		(start 251.572776 -28.843732)
		(end 251.831094 -28.843732)
		(width 0.1651)
		(layer "F.Cu")
		(net "M_A_MA<8>")
	)
	(segment
		(start 255.208278 -50.499772)
		(end 255.208278 -48.009302)
		(width 0.0889)
		(layer "F.Cu")
		(net "M_A_MA<8>")
	)
	(segment
		(start 251.6505 -15.423642)
		(end 251.649992 -15.423642)
		(width 0.1651)
		(layer "F.Cu")
		(net "M_A_MA<8>")
	)
	(segment
		(start 251.649992 -24.020272)
		(end 251.649992 -23.560278)
		(width 0.1651)
		(layer "F.Cu")
		(net "M_A_MA<8>")
	)
	(segment
		(start 251.418852 -28.997656)
		(end 251.572776 -28.843732)
		(width 0.1651)
		(layer "F.Cu")
		(net "M_A_MA<8>")
	)
	(via
		(at 251.649992 -23.560278)
		(size 0.508)
		(drill 0.254)
		(layers "F.Cu" "B.Cu")
		(net "M_A_MA<8>")
	)
	(via
		(at 254.90932 -35.157918)
		(size 0.508)
		(drill 0.254)
		(layers "F.Cu" "B.Cu")
		(net "M_A_MA<8>")
	)
	(via
		(at 251.649992 -16.718788)
		(size 0.4572)
		(drill 0.2032)
		(layers "F.Cu" "B.Cu")
		(net "M_A_MA<8>")
	)
	(segment
		(start 251.649992 -24.824182)
		(end 251.649992 -23.560278)
		(width 0.1651)
		(layer "B.Cu")
		(net "M_A_MA<8>")
	)
	(segment
		(start 251.6505 -24.824182)
		(end 251.649992 -24.824182)
		(width 0.1651)
		(layer "B.Cu")
		(net "M_A_MA<8>")
	)
	(segment
		(start 251.3076 -21.7678)
		(end 251.3076 -19.6977)
		(width 0.14224)
		(layer "In9.Cu")
		(net "M_A_MA<8>")
	)
	(segment
		(start 251.174504 -22.388576)
		(end 251.174504 -21.900896)
		(width 0.14224)
		(layer "In9.Cu")
		(net "M_A_MA<8>")
	)
	(segment
		(start 251.209048 -17.783556)
		(end 251.649992 -16.718788)
		(width 0.14224)
		(layer "In9.Cu")
		(net "M_A_MA<8>")
	)
	(segment
		(start 251.649992 -23.560278)
		(end 251.429012 -22.836632)
		(width 0.14224)
		(layer "In9.Cu")
		(net "M_A_MA<8>")
	)
	(segment
		(start 251.209048 -19.365214)
		(end 251.209048 -17.783556)
		(width 0.14224)
		(layer "In9.Cu")
		(net "M_A_MA<8>")
	)
	(segment
		(start 251.174504 -21.900896)
		(end 251.3076 -21.7678)
		(width 0.14224)
		(layer "In9.Cu")
		(net "M_A_MA<8>")
	)
	(segment
		(start 251.429012 -22.836632)
		(end 251.174504 -22.388576)
		(width 0.14224)
		(layer "In9.Cu")
		(net "M_A_MA<8>")
	)
	(segment
		(start 251.3076 -19.6977)
		(end 251.209048 -19.365214)
		(width 0.14224)
		(layer "In9.Cu")
		(net "M_A_MA<8>")
	)
	(segment
		(start 254.724154 -51.827938)
		(end 254.740156 -51.85537)
		(width 0.0889)
		(layer "F.Cu")
		(net "M_A_MA<7>")
	)
	(segment
		(start 250.825 -29.56306)
		(end 254.40513 -33.14319)
		(width 0.1651)
		(layer "F.Cu")
		(net "M_A_MA<7>")
	)
	(segment
		(start 250.2916 -22.6822)
		(end 250.2916 -23.114)
		(width 0.1651)
		(layer "F.Cu")
		(net "M_A_MA<7>")
	)
	(segment
		(start 250.825 -23.6474)
		(end 250.825 -28.944824)
		(width 0.1651)
		(layer "F.Cu")
		(net "M_A_MA<7>")
	)
	(segment
		(start 250.2916 -23.114)
		(end 250.825 -23.6474)
		(width 0.1651)
		(layer "F.Cu")
		(net "M_A_MA<7>")
	)
	(segment
		(start 254.40513 -47.323248)
		(end 254.40513 -47.597822)
		(width 0.0889)
		(layer "F.Cu")
		(net "M_A_MA<7>")
	)
	(segment
		(start 254.40513 -33.14319)
		(end 254.40513 -47.323248)
		(width 0.1651)
		(layer "F.Cu")
		(net "M_A_MA<7>")
	)
	(segment
		(start 250.799854 -20.023582)
		(end 250.799854 -18.734278)
		(width 0.1651)
		(layer "F.Cu")
		(net "M_A_MA<7>")
	)
	(segment
		(start 250.825 -28.944824)
		(end 250.825 -29.56306)
		(width 0.1651)
		(layer "F.Cu")
		(net "M_A_MA<7>")
	)
	(segment
		(start 250.799854 -22.173946)
		(end 250.2916 -22.6822)
		(width 0.1651)
		(layer "F.Cu")
		(net "M_A_MA<7>")
	)
	(segment
		(start 254.40513 -47.597822)
		(end 254.680212 -47.872904)
		(width 0.0889)
		(layer "F.Cu")
		(net "M_A_MA<7>")
	)
	(segment
		(start 254.740156 -51.85537)
		(end 255.07061 -52.618386)
		(width 0.0889)
		(layer "F.Cu")
		(net "M_A_MA<7>")
	)
	(segment
		(start 250.799854 -21.488146)
		(end 250.799854 -22.173946)
		(width 0.1651)
		(layer "F.Cu")
		(net "M_A_MA<7>")
	)
	(segment
		(start 254.724154 -50.837338)
		(end 254.733044 -50.852578)
		(width 0.0889)
		(layer "F.Cu")
		(net "M_A_MA<7>")
	)
	(segment
		(start 254.680212 -47.872904)
		(end 254.680212 -50.72507)
		(width 0.0889)
		(layer "F.Cu")
		(net "M_A_MA<7>")
	)
	(segment
		(start 250.800362 -20.023582)
		(end 250.799854 -20.023582)
		(width 0.1651)
		(layer "F.Cu")
		(net "M_A_MA<7>")
	)
	(via
		(at 250.799854 -18.734278)
		(size 0.4572)
		(drill 0.2032)
		(layers "F.Cu" "B.Cu")
		(net "M_A_MA<7>")
	)
	(via
		(at 250.799854 -21.488146)
		(size 0.508)
		(drill 0.254)
		(layers "F.Cu" "B.Cu")
		(net "M_A_MA<7>")
	)
	(via
		(at 250.825 -28.944824)
		(size 0.508)
		(drill 0.254)
		(layers "F.Cu" "B.Cu")
		(net "M_A_MA<7>")
	)
	(arc
		(start 254.733044 -50.852578)
		(mid 254.803441 -51.141529)
		(end 254.724154 -51.428142)
		(width 0.0889)
		(layer "F.Cu")
		(net "M_A_MA<7>")
	)
	(arc
		(start 254.680212 -50.72507)
		(mid 254.697917 -50.782875)
		(end 254.724154 -50.837338)
		(width 0.0889)
		(layer "F.Cu")
		(net "M_A_MA<7>")
	)
	(arc
		(start 254.724154 -51.428142)
		(mid 254.670621 -51.62804)
		(end 254.724154 -51.827938)
		(width 0.0889)
		(layer "F.Cu")
		(net "M_A_MA<7>")
	)
	(segment
		(start 250.799854 -20.224242)
		(end 250.799854 -21.488146)
		(width 0.1651)
		(layer "B.Cu")
		(net "M_A_MA<7>")
	)
	(segment
		(start 250.800362 -20.224242)
		(end 250.799854 -20.224242)
		(width 0.1651)
		(layer "B.Cu")
		(net "M_A_MA<7>")
	)
	(segment
		(start 250.799854 -18.734278)
		(end 250.306332 -19.2278)
		(width 0.14224)
		(layer "In9.Cu")
		(net "M_A_MA<7>")
	)
	(segment
		(start 249.17654 -19.813778)
		(end 249.327162 -19.9644)
		(width 0.14224)
		(layer "In9.Cu")
		(net "M_A_MA<7>")
	)
	(segment
		(start 250.57989 -20.528026)
		(end 250.406916 -20.701)
		(width 0.14224)
		(layer "In9.Cu")
		(net "M_A_MA<7>")
	)
	(segment
		(start 250.406916 -20.701)
		(end 249.768614 -20.701)
		(width 0.14224)
		(layer "In9.Cu")
		(net "M_A_MA<7>")
	)
	(segment
		(start 250.397264 -19.9644)
		(end 250.57989 -20.147026)
		(width 0.14224)
		(layer "In9.Cu")
		(net "M_A_MA<7>")
	)
	(segment
		(start 249.316494 -19.2278)
		(end 249.17654 -19.367754)
		(width 0.14224)
		(layer "In9.Cu")
		(net "M_A_MA<7>")
	)
	(segment
		(start 249.327162 -19.9644)
		(end 250.397264 -19.9644)
		(width 0.14224)
		(layer "In9.Cu")
		(net "M_A_MA<7>")
	)
	(segment
		(start 249.598688 -21.285454)
		(end 249.80138 -21.488146)
		(width 0.14224)
		(layer "In9.Cu")
		(net "M_A_MA<7>")
	)
	(segment
		(start 250.306332 -19.2278)
		(end 249.316494 -19.2278)
		(width 0.14224)
		(layer "In9.Cu")
		(net "M_A_MA<7>")
	)
	(segment
		(start 249.80138 -21.488146)
		(end 250.799854 -21.488146)
		(width 0.14224)
		(layer "In9.Cu")
		(net "M_A_MA<7>")
	)
	(segment
		(start 249.17654 -19.367754)
		(end 249.17654 -19.813778)
		(width 0.14224)
		(layer "In9.Cu")
		(net "M_A_MA<7>")
	)
	(segment
		(start 249.768614 -20.701)
		(end 249.598688 -20.870926)
		(width 0.14224)
		(layer "In9.Cu")
		(net "M_A_MA<7>")
	)
	(segment
		(start 249.598688 -20.870926)
		(end 249.598688 -21.285454)
		(width 0.14224)
		(layer "In9.Cu")
		(net "M_A_MA<7>")
	)
	(segment
		(start 250.57989 -20.147026)
		(end 250.57989 -20.528026)
		(width 0.14224)
		(layer "In9.Cu")
		(net "M_A_MA<7>")
	)
	(segment
		(start 255.41351 -47.233332)
		(end 255.41351 -32.656272)
		(width 0.1651)
		(layer "F.Cu")
		(net "M_A_MA<6>")
	)
	(segment
		(start 252.500384 -15.423642)
		(end 252.499876 -15.423642)
		(width 0.1651)
		(layer "F.Cu")
		(net "M_A_MA<6>")
	)
	(segment
		(start 253.240286 -30.483048)
		(end 253.240286 -30.249622)
		(width 0.1651)
		(layer "F.Cu")
		(net "M_A_MA<6>")
	)
	(segment
		(start 255.334008 -31.659576)
		(end 255.100074 -31.425642)
		(width 0.1651)
		(layer "F.Cu")
		(net "M_A_MA<6>")
	)
	(segment
		(start 254.161036 -31.472378)
		(end 254.161036 -31.19755)
		(width 0.1651)
		(layer "F.Cu")
		(net "M_A_MA<6>")
	)
	(segment
		(start 253.707392 -30.716982)
		(end 253.47422 -30.716982)
		(width 0.1651)
		(layer "F.Cu")
		(net "M_A_MA<6>")
	)
	(segment
		(start 254.165862 -30.49143)
		(end 253.932944 -30.49143)
		(width 0.1651)
		(layer "F.Cu")
		(net "M_A_MA<6>")
	)
	(segment
		(start 252.7554 -28.617926)
		(end 252.7554 -24.340058)
		(width 0.1651)
		(layer "F.Cu")
		(net "M_A_MA<6>")
	)
	(segment
		(start 253.465584 -30.024324)
		(end 253.465584 -29.791152)
		(width 0.1651)
		(layer "F.Cu")
		(net "M_A_MA<6>")
	)
	(segment
		(start 254.161036 -31.19755)
		(end 254.399796 -30.95879)
		(width 0.1651)
		(layer "F.Cu")
		(net "M_A_MA<6>")
	)
	(segment
		(start 253.240286 -30.249622)
		(end 253.465584 -30.024324)
		(width 0.1651)
		(layer "F.Cu")
		(net "M_A_MA<6>")
	)
	(segment
		(start 252.499876 -15.423642)
		(end 252.499876 -16.718788)
		(width 0.1651)
		(layer "F.Cu")
		(net "M_A_MA<6>")
	)
	(segment
		(start 252.7554 -29.080968)
		(end 252.7554 -28.617926)
		(width 0.1651)
		(layer "F.Cu")
		(net "M_A_MA<6>")
	)
	(segment
		(start 254.867156 -31.425642)
		(end 254.607568 -31.68523)
		(width 0.1651)
		(layer "F.Cu")
		(net "M_A_MA<6>")
	)
	(segment
		(start 255.479804 -50.18532)
		(end 255.479804 -47.719996)
		(width 0.0889)
		(layer "F.Cu")
		(net "M_A_MA<6>")
	)
	(segment
		(start 255.10871 -32.118046)
		(end 255.334008 -31.892748)
		(width 0.1651)
		(layer "F.Cu")
		(net "M_A_MA<6>")
	)
	(segment
		(start 255.479804 -47.719996)
		(end 255.41351 -47.653702)
		(width 0.0889)
		(layer "F.Cu")
		(net "M_A_MA<6>")
	)
	(segment
		(start 254.399796 -30.725364)
		(end 254.165862 -30.49143)
		(width 0.1651)
		(layer "F.Cu")
		(net "M_A_MA<6>")
	)
	(segment
		(start 254.373888 -31.68523)
		(end 254.161036 -31.472378)
		(width 0.1651)
		(layer "F.Cu")
		(net "M_A_MA<6>")
	)
	(segment
		(start 252.1966 -23.781258)
		(end 252.1966 -23.465028)
		(width 0.1651)
		(layer "F.Cu")
		(net "M_A_MA<6>")
	)
	(segment
		(start 252.29566 -22.64664)
		(end 252.499876 -22.850856)
		(width 0.1651)
		(layer "F.Cu")
		(net "M_A_MA<6>")
	)
	(segment
		(start 253.932944 -30.49143)
		(end 253.707392 -30.716982)
		(width 0.1651)
		(layer "F.Cu")
		(net "M_A_MA<6>")
	)
	(segment
		(start 254.607568 -31.68523)
		(end 254.373888 -31.68523)
		(width 0.1651)
		(layer "F.Cu")
		(net "M_A_MA<6>")
	)
	(segment
		(start 251.859542 -22.848824)
		(end 252.061726 -22.64664)
		(width 0.1651)
		(layer "F.Cu")
		(net "M_A_MA<6>")
	)
	(segment
		(start 252.1966 -23.465028)
		(end 251.859542 -23.12797)
		(width 0.1651)
		(layer "F.Cu")
		(net "M_A_MA<6>")
	)
	(segment
		(start 255.334008 -31.892748)
		(end 255.334008 -31.659576)
		(width 0.1651)
		(layer "F.Cu")
		(net "M_A_MA<6>")
	)
	(segment
		(start 255.100074 -31.425642)
		(end 254.867156 -31.425642)
		(width 0.1651)
		(layer "F.Cu")
		(net "M_A_MA<6>")
	)
	(segment
		(start 251.859542 -23.12797)
		(end 251.859542 -22.848824)
		(width 0.1651)
		(layer "F.Cu")
		(net "M_A_MA<6>")
	)
	(segment
		(start 253.47422 -30.716982)
		(end 253.240286 -30.483048)
		(width 0.1651)
		(layer "F.Cu")
		(net "M_A_MA<6>")
	)
	(segment
		(start 252.061726 -22.64664)
		(end 252.29566 -22.64664)
		(width 0.1651)
		(layer "F.Cu")
		(net "M_A_MA<6>")
	)
	(segment
		(start 254.399796 -30.95879)
		(end 254.399796 -30.725364)
		(width 0.1651)
		(layer "F.Cu")
		(net "M_A_MA<6>")
	)
	(segment
		(start 255.41351 -32.656272)
		(end 255.10871 -32.351472)
		(width 0.1651)
		(layer "F.Cu")
		(net "M_A_MA<6>")
	)
	(segment
		(start 255.41351 -47.653702)
		(end 255.41351 -47.233332)
		(width 0.0889)
		(layer "F.Cu")
		(net "M_A_MA<6>")
	)
	(segment
		(start 255.10871 -32.351472)
		(end 255.10871 -32.118046)
		(width 0.1651)
		(layer "F.Cu")
		(net "M_A_MA<6>")
	)
	(segment
		(start 252.7554 -24.340058)
		(end 252.1966 -23.781258)
		(width 0.1651)
		(layer "F.Cu")
		(net "M_A_MA<6>")
	)
	(segment
		(start 253.465584 -29.791152)
		(end 252.7554 -29.080968)
		(width 0.1651)
		(layer "F.Cu")
		(net "M_A_MA<6>")
	)
	(segment
		(start 255.92913 -51.132486)
		(end 255.479804 -50.18532)
		(width 0.0889)
		(layer "F.Cu")
		(net "M_A_MA<6>")
	)
	(via
		(at 252.499876 -22.850856)
		(size 0.508)
		(drill 0.254)
		(layers "F.Cu" "B.Cu")
		(net "M_A_MA<6>")
	)
	(via
		(at 252.7554 -28.617926)
		(size 0.508)
		(drill 0.254)
		(layers "F.Cu" "B.Cu")
		(net "M_A_MA<6>")
	)
	(via
		(at 252.499876 -16.718788)
		(size 0.4572)
		(drill 0.2032)
		(layers "F.Cu" "B.Cu")
		(net "M_A_MA<6>")
	)
	(segment
		(start 252.499876 -24.824182)
		(end 252.499876 -22.850856)
		(width 0.1651)
		(layer "B.Cu")
		(net "M_A_MA<6>")
	)
	(segment
		(start 252.500384 -24.824182)
		(end 252.499876 -24.824182)
		(width 0.1651)
		(layer "B.Cu")
		(net "M_A_MA<6>")
	)
	(segment
		(start 251.859034 -21.30425)
		(end 251.859034 -19.376136)
		(width 0.14224)
		(layer "In9.Cu")
		(net "M_A_MA<6>")
	)
	(segment
		(start 252.084586 -18.832068)
		(end 252.084586 -18.542508)
		(width 0.14224)
		(layer "In9.Cu")
		(net "M_A_MA<6>")
	)
	(segment
		(start 252.499876 -22.850856)
		(end 251.859034 -21.30425)
		(width 0.14224)
		(layer "In9.Cu")
		(net "M_A_MA<6>")
	)
	(segment
		(start 251.859034 -19.376136)
		(end 252.084586 -18.832068)
		(width 0.14224)
		(layer "In9.Cu")
		(net "M_A_MA<6>")
	)
	(segment
		(start 252.39853 -16.96339)
		(end 252.499876 -16.718788)
		(width 0.14224)
		(layer "In9.Cu")
		(net "M_A_MA<6>")
	)
	(segment
		(start 252.084586 -18.542508)
		(end 252.39853 -16.96339)
		(width 0.14224)
		(layer "In9.Cu")
		(net "M_A_MA<6>")
	)
	(segment
		(start 256.26949 -50.92192)
		(end 256.27584 -50.932588)
		(width 0.0889)
		(layer "F.Cu")
		(net "M_A_MA<5>")
	)
	(segment
		(start 255.9177 -48.167036)
		(end 255.9177 -48.500284)
		(width 0.0889)
		(layer "F.Cu")
		(net "M_A_MA<5>")
	)
	(segment
		(start 256.402078 -52.142136)
		(end 256.402078 -52.511452)
		(width 0.0889)
		(layer "F.Cu")
		(net "M_A_MA<5>")
	)
	(segment
		(start 252.963426 -22.534626)
		(end 252.963426 -23.304246)
		(width 0.1651)
		(layer "F.Cu")
		(net "M_A_MA<5>")
	)
	(segment
		(start 253.2888 -26.363422)
		(end 253.2888 -28.901136)
		(width 0.1651)
		(layer "F.Cu")
		(net "M_A_MA<5>")
	)
	(segment
		(start 253.2888 -28.901136)
		(end 255.9177 -31.530036)
		(width 0.1651)
		(layer "F.Cu")
		(net "M_A_MA<5>")
	)
	(segment
		(start 252.500384 -20.023582)
		(end 252.499876 -20.023582)
		(width 0.1651)
		(layer "F.Cu")
		(net "M_A_MA<5>")
	)
	(segment
		(start 255.9177 -31.530036)
		(end 255.9177 -48.167036)
		(width 0.1651)
		(layer "F.Cu")
		(net "M_A_MA<5>")
	)
	(segment
		(start 256.19583 -52.7177)
		(end 256.186686 -52.7177)
		(width 0.0889)
		(layer "F.Cu")
		(net "M_A_MA<5>")
	)
	(segment
		(start 252.963426 -23.304246)
		(end 252.886464 -23.381208)
		(width 0.1651)
		(layer "F.Cu")
		(net "M_A_MA<5>")
	)
	(segment
		(start 252.886464 -23.381208)
		(end 252.886464 -23.752556)
		(width 0.1651)
		(layer "F.Cu")
		(net "M_A_MA<5>")
	)
	(segment
		(start 255.9177 -48.500284)
		(end 256.3368 -48.919384)
		(width 0.0889)
		(layer "F.Cu")
		(net "M_A_MA<5>")
	)
	(segment
		(start 256.05105 -52.661566)
		(end 256.025904 -52.63642)
		(width 0.0889)
		(layer "F.Cu")
		(net "M_A_MA<5>")
	)
	(segment
		(start 256.27584 -51.923442)
		(end 256.40157 -52.141628)
		(width 0.0889)
		(layer "F.Cu")
		(net "M_A_MA<5>")
	)
	(segment
		(start 255.92913 -52.40274)
		(end 255.92913 -52.12334)
		(width 0.0889)
		(layer "F.Cu")
		(net "M_A_MA<5>")
	)
	(segment
		(start 252.499876 -21.517356)
		(end 252.499876 -22.071076)
		(width 0.1651)
		(layer "F.Cu")
		(net "M_A_MA<5>")
	)
	(segment
		(start 256.40157 -52.141628)
		(end 256.402078 -52.142136)
		(width 0.0889)
		(layer "F.Cu")
		(net "M_A_MA<5>")
	)
	(segment
		(start 256.3368 -48.919384)
		(end 256.3368 -50.114454)
		(width 0.0889)
		(layer "F.Cu")
		(net "M_A_MA<5>")
	)
	(segment
		(start 256.27584 -50.932588)
		(end 256.280666 -50.941224)
		(width 0.0889)
		(layer "F.Cu")
		(net "M_A_MA<5>")
	)
	(segment
		(start 252.499876 -22.071076)
		(end 252.963426 -22.534626)
		(width 0.1651)
		(layer "F.Cu")
		(net "M_A_MA<5>")
	)
	(segment
		(start 253.2888 -24.154892)
		(end 253.2888 -26.363422)
		(width 0.1651)
		(layer "F.Cu")
		(net "M_A_MA<5>")
	)
	(segment
		(start 252.499876 -20.023582)
		(end 252.499876 -18.734278)
		(width 0.1651)
		(layer "F.Cu")
		(net "M_A_MA<5>")
	)
	(segment
		(start 252.886464 -23.752556)
		(end 253.2888 -24.154892)
		(width 0.1651)
		(layer "F.Cu")
		(net "M_A_MA<5>")
	)
	(via
		(at 253.2888 -26.363422)
		(size 0.508)
		(drill 0.254)
		(layers "F.Cu" "B.Cu")
		(net "M_A_MA<5>")
	)
	(via
		(at 252.499876 -21.517356)
		(size 0.508)
		(drill 0.254)
		(layers "F.Cu" "B.Cu")
		(net "M_A_MA<5>")
	)
	(via
		(at 252.499876 -18.734278)
		(size 0.4572)
		(drill 0.2032)
		(layers "F.Cu" "B.Cu")
		(net "M_A_MA<5>")
	)
	(arc
		(start 256.186686 -52.7177)
		(mid 256.113285 -52.703117)
		(end 256.05105 -52.661566)
		(width 0.0889)
		(layer "F.Cu")
		(net "M_A_MA<5>")
	)
	(arc
		(start 256.025904 -52.63642)
		(mid 255.954266 -52.529207)
		(end 255.92913 -52.40274)
		(width 0.0889)
		(layer "F.Cu")
		(net "M_A_MA<5>")
	)
	(arc
		(start 256.402078 -52.511452)
		(mid 256.341669 -52.657291)
		(end 256.19583 -52.7177)
		(width 0.0889)
		(layer "F.Cu")
		(net "M_A_MA<5>")
	)
	(arc
		(start 256.3368 -50.114454)
		(mid 256.3213 -50.232259)
		(end 256.27584 -50.342038)
		(width 0.0889)
		(layer "F.Cu")
		(net "M_A_MA<5>")
	)
	(arc
		(start 256.27584 -50.342038)
		(mid 256.196618 -50.631156)
		(end 256.26949 -50.92192)
		(width 0.0889)
		(layer "F.Cu")
		(net "M_A_MA<5>")
	)
	(arc
		(start 256.27584 -51.332638)
		(mid 256.196709 -51.62804)
		(end 256.27584 -51.923442)
		(width 0.0889)
		(layer "F.Cu")
		(net "M_A_MA<5>")
	)
	(arc
		(start 256.280666 -50.941224)
		(mid 256.329421 -51.137576)
		(end 256.27584 -51.332638)
		(width 0.0889)
		(layer "F.Cu")
		(net "M_A_MA<5>")
	)
	(segment
		(start 252.499876 -20.224242)
		(end 252.499876 -21.517356)
		(width 0.1651)
		(layer "B.Cu")
		(net "M_A_MA<5>")
	)
	(segment
		(start 252.500384 -20.224242)
		(end 252.499876 -20.224242)
		(width 0.1651)
		(layer "B.Cu")
		(net "M_A_MA<5>")
	)
	(segment
		(start 252.78715 -19.844258)
		(end 252.92939 -19.986498)
		(width 0.14224)
		(layer "In9.Cu")
		(net "M_A_MA<5>")
	)
	(segment
		(start 252.282706 -20.81657)
		(end 252.44171 -20.975574)
		(width 0.14224)
		(layer "In9.Cu")
		(net "M_A_MA<5>")
	)
	(segment
		(start 252.802136 -18.734278)
		(end 252.933454 -18.865596)
		(width 0.14224)
		(layer "In9.Cu")
		(net "M_A_MA<5>")
	)
	(segment
		(start 252.282706 -20.58543)
		(end 252.282706 -20.81657)
		(width 0.14224)
		(layer "In9.Cu")
		(net "M_A_MA<5>")
	)
	(segment
		(start 252.433582 -20.434554)
		(end 252.282706 -20.58543)
		(width 0.14224)
		(layer "In9.Cu")
		(net "M_A_MA<5>")
	)
	(segment
		(start 252.278896 -19.689318)
		(end 252.433836 -19.844258)
		(width 0.14224)
		(layer "In9.Cu")
		(net "M_A_MA<5>")
	)
	(segment
		(start 252.758448 -21.517356)
		(end 252.499876 -21.517356)
		(width 0.14224)
		(layer "In9.Cu")
		(net "M_A_MA<5>")
	)
	(segment
		(start 252.891798 -21.384006)
		(end 252.758448 -21.517356)
		(width 0.14224)
		(layer "In9.Cu")
		(net "M_A_MA<5>")
	)
	(segment
		(start 252.44171 -20.975574)
		(end 252.764798 -20.975574)
		(width 0.14224)
		(layer "In9.Cu")
		(net "M_A_MA<5>")
	)
	(segment
		(start 252.776736 -20.434554)
		(end 252.433582 -20.434554)
		(width 0.14224)
		(layer "In9.Cu")
		(net "M_A_MA<5>")
	)
	(segment
		(start 252.764798 -20.975574)
		(end 252.891798 -21.102574)
		(width 0.14224)
		(layer "In9.Cu")
		(net "M_A_MA<5>")
	)
	(segment
		(start 252.499876 -18.734278)
		(end 252.802136 -18.734278)
		(width 0.14224)
		(layer "In9.Cu")
		(net "M_A_MA<5>")
	)
	(segment
		(start 252.278896 -19.437858)
		(end 252.278896 -19.689318)
		(width 0.14224)
		(layer "In9.Cu")
		(net "M_A_MA<5>")
	)
	(segment
		(start 252.433836 -19.844258)
		(end 252.78715 -19.844258)
		(width 0.14224)
		(layer "In9.Cu")
		(net "M_A_MA<5>")
	)
	(segment
		(start 252.92939 -19.986498)
		(end 252.92939 -20.2819)
		(width 0.14224)
		(layer "In9.Cu")
		(net "M_A_MA<5>")
	)
	(segment
		(start 252.933454 -18.865596)
		(end 252.933454 -19.151854)
		(width 0.14224)
		(layer "In9.Cu")
		(net "M_A_MA<5>")
	)
	(segment
		(start 252.80239 -19.282918)
		(end 252.433836 -19.282918)
		(width 0.14224)
		(layer "In9.Cu")
		(net "M_A_MA<5>")
	)
	(segment
		(start 252.891798 -21.102574)
		(end 252.891798 -21.384006)
		(width 0.14224)
		(layer "In9.Cu")
		(net "M_A_MA<5>")
	)
	(segment
		(start 252.92939 -20.2819)
		(end 252.776736 -20.434554)
		(width 0.14224)
		(layer "In9.Cu")
		(net "M_A_MA<5>")
	)
	(segment
		(start 252.933454 -19.151854)
		(end 252.80239 -19.282918)
		(width 0.14224)
		(layer "In9.Cu")
		(net "M_A_MA<5>")
	)
	(segment
		(start 252.433836 -19.282918)
		(end 252.278896 -19.437858)
		(width 0.14224)
		(layer "In9.Cu")
		(net "M_A_MA<5>")
	)
	(segment
		(start 253.8222 -23.2664)
		(end 253.586996 -23.031196)
		(width 0.1651)
		(layer "F.Cu")
		(net "M_A_MA<4>")
	)
	(segment
		(start 253.8222 -27.620722)
		(end 253.8222 -23.2664)
		(width 0.1651)
		(layer "F.Cu")
		(net "M_A_MA<4>")
	)
	(segment
		(start 256.546604 -48.654716)
		(end 256.42189 -48.530002)
		(width 0.0889)
		(layer "F.Cu")
		(net "M_A_MA<4>")
	)
	(segment
		(start 256.42189 -31.32074)
		(end 253.8222 -28.72105)
		(width 0.1651)
		(layer "F.Cu")
		(net "M_A_MA<4>")
	)
	(segment
		(start 256.546604 -50.04308)
		(end 256.546604 -48.654716)
		(width 0.0889)
		(layer "F.Cu")
		(net "M_A_MA<4>")
	)
	(segment
		(start 256.620264 -52.139342)
		(end 256.436114 -51.819302)
		(width 0.0889)
		(layer "F.Cu")
		(net "M_A_MA<4>")
	)
	(segment
		(start 253.586996 -22.43455)
		(end 253.350014 -22.197568)
		(width 0.1651)
		(layer "F.Cu")
		(net "M_A_MA<4>")
	)
	(segment
		(start 256.42189 -48.237902)
		(end 256.42189 -31.32074)
		(width 0.1651)
		(layer "F.Cu")
		(net "M_A_MA<4>")
	)
	(segment
		(start 256.44094 -50.837338)
		(end 256.436114 -50.828702)
		(width 0.0889)
		(layer "F.Cu")
		(net "M_A_MA<4>")
	)
	(segment
		(start 256.78765 -52.618386)
		(end 256.702052 -52.328064)
		(width 0.0889)
		(layer "F.Cu")
		(net "M_A_MA<4>")
	)
	(segment
		(start 253.350014 -20.023582)
		(end 253.350014 -18.734278)
		(width 0.1651)
		(layer "F.Cu")
		(net "M_A_MA<4>")
	)
	(segment
		(start 256.44729 -50.848006)
		(end 256.44094 -50.837338)
		(width 0.0889)
		(layer "F.Cu")
		(net "M_A_MA<4>")
	)
	(segment
		(start 253.8222 -28.72105)
		(end 253.8222 -27.620722)
		(width 0.1651)
		(layer "F.Cu")
		(net "M_A_MA<4>")
	)
	(segment
		(start 256.702052 -52.328064)
		(end 256.620264 -52.139342)
		(width 0.0889)
		(layer "F.Cu")
		(net "M_A_MA<4>")
	)
	(segment
		(start 253.350522 -20.023582)
		(end 253.350014 -20.023582)
		(width 0.1651)
		(layer "F.Cu")
		(net "M_A_MA<4>")
	)
	(segment
		(start 256.42189 -48.530002)
		(end 256.42189 -48.237902)
		(width 0.0889)
		(layer "F.Cu")
		(net "M_A_MA<4>")
	)
	(segment
		(start 253.586996 -23.031196)
		(end 253.586996 -22.43455)
		(width 0.1651)
		(layer "F.Cu")
		(net "M_A_MA<4>")
	)
	(via
		(at 253.350014 -18.734278)
		(size 0.4572)
		(drill 0.2032)
		(layers "F.Cu" "B.Cu")
		(net "M_A_MA<4>")
	)
	(via
		(at 253.350014 -22.197568)
		(size 0.508)
		(drill 0.254)
		(layers "F.Cu" "B.Cu")
		(net "M_A_MA<4>")
	)
	(via
		(at 253.8222 -27.620722)
		(size 0.508)
		(drill 0.254)
		(layers "F.Cu" "B.Cu")
		(net "M_A_MA<4>")
	)
	(arc
		(start 256.436114 -51.819302)
		(mid 256.387359 -51.62295)
		(end 256.44094 -51.427888)
		(width 0.0889)
		(layer "F.Cu")
		(net "M_A_MA<4>")
	)
	(arc
		(start 256.436114 -50.828702)
		(mid 256.387359 -50.63235)
		(end 256.44094 -50.437288)
		(width 0.0889)
		(layer "F.Cu")
		(net "M_A_MA<4>")
	)
	(arc
		(start 256.44094 -50.437288)
		(mid 256.519757 -50.247147)
		(end 256.546604 -50.04308)
		(width 0.0889)
		(layer "F.Cu")
		(net "M_A_MA<4>")
	)
	(arc
		(start 256.44094 -51.427888)
		(mid 256.520162 -51.13877)
		(end 256.44729 -50.848006)
		(width 0.0889)
		(layer "F.Cu")
		(net "M_A_MA<4>")
	)
	(segment
		(start 253.350014 -20.224242)
		(end 253.350014 -22.197568)
		(width 0.1651)
		(layer "B.Cu")
		(net "M_A_MA<4>")
	)
	(segment
		(start 253.350522 -20.224242)
		(end 253.350014 -20.224242)
		(width 0.1651)
		(layer "B.Cu")
		(net "M_A_MA<4>")
	)
	(segment
		(start 253.761748 -20.235418)
		(end 253.761748 -19.956018)
		(width 0.14224)
		(layer "In9.Cu")
		(net "M_A_MA<4>")
	)
	(segment
		(start 253.350014 -22.197568)
		(end 253.311406 -22.15896)
		(width 0.14224)
		(layer "In9.Cu")
		(net "M_A_MA<4>")
	)
	(segment
		(start 253.463806 -20.390358)
		(end 253.606808 -20.390358)
		(width 0.14224)
		(layer "In9.Cu")
		(net "M_A_MA<4>")
	)
	(segment
		(start 253.504954 -19.829018)
		(end 253.350014 -19.674078)
		(width 0.14224)
		(layer "In9.Cu")
		(net "M_A_MA<4>")
	)
	(segment
		(start 253.761748 -19.956018)
		(end 253.634748 -19.829018)
		(width 0.14224)
		(layer "In9.Cu")
		(net "M_A_MA<4>")
	)
	(segment
		(start 253.350014 -19.674078)
		(end 253.350014 -18.734278)
		(width 0.14224)
		(layer "In9.Cu")
		(net "M_A_MA<4>")
	)
	(segment
		(start 253.634748 -19.829018)
		(end 253.504954 -19.829018)
		(width 0.14224)
		(layer "In9.Cu")
		(net "M_A_MA<4>")
	)
	(segment
		(start 253.311406 -22.15896)
		(end 253.311406 -20.542758)
		(width 0.14224)
		(layer "In9.Cu")
		(net "M_A_MA<4>")
	)
	(segment
		(start 253.606808 -20.390358)
		(end 253.761748 -20.235418)
		(width 0.14224)
		(layer "In9.Cu")
		(net "M_A_MA<4>")
	)
	(segment
		(start 253.311406 -20.542758)
		(end 253.463806 -20.390358)
		(width 0.14224)
		(layer "In9.Cu")
		(net "M_A_MA<4>")
	)
	(segment
		(start 256.862834 -48.300386)
		(end 256.862834 -50.562256)
		(width 0.0889)
		(layer "F.Cu")
		(net "M_A_MA<3>")
	)
	(segment
		(start 256.92608 -31.111444)
		(end 256.92608 -47.914306)
		(width 0.1651)
		(layer "F.Cu")
		(net "M_A_MA<3>")
	)
	(segment
		(start 254.199898 -15.423642)
		(end 254.199898 -16.718788)
		(width 0.1651)
		(layer "F.Cu")
		(net "M_A_MA<3>")
	)
	(segment
		(start 254.200406 -15.423642)
		(end 254.199898 -15.423642)
		(width 0.1651)
		(layer "F.Cu")
		(net "M_A_MA<3>")
	)
	(segment
		(start 254.429514 -22.850856)
		(end 254.570992 -22.992334)
		(width 0.1651)
		(layer "F.Cu")
		(net "M_A_MA<3>")
	)
	(segment
		(start 256.92608 -47.914306)
		(end 256.92608 -48.23714)
		(width 0.0889)
		(layer "F.Cu")
		(net "M_A_MA<3>")
	)
	(segment
		(start 254.570992 -22.992334)
		(end 254.570992 -23.84806)
		(width 0.1651)
		(layer "F.Cu")
		(net "M_A_MA<3>")
	)
	(segment
		(start 254.32639 -28.511754)
		(end 255.0795 -29.264864)
		(width 0.1651)
		(layer "F.Cu")
		(net "M_A_MA<3>")
	)
	(segment
		(start 254.199898 -22.850856)
		(end 254.429514 -22.850856)
		(width 0.1651)
		(layer "F.Cu")
		(net "M_A_MA<3>")
	)
	(segment
		(start 256.92608 -48.23714)
		(end 256.862834 -48.300386)
		(width 0.0889)
		(layer "F.Cu")
		(net "M_A_MA<3>")
	)
	(segment
		(start 256.862834 -50.562256)
		(end 256.78765 -50.63744)
		(width 0.0889)
		(layer "F.Cu")
		(net "M_A_MA<3>")
	)
	(segment
		(start 254.570992 -23.84806)
		(end 254.32639 -24.092662)
		(width 0.1651)
		(layer "F.Cu")
		(net "M_A_MA<3>")
	)
	(segment
		(start 254.32639 -24.092662)
		(end 254.32639 -28.511754)
		(width 0.1651)
		(layer "F.Cu")
		(net "M_A_MA<3>")
	)
	(segment
		(start 255.0795 -29.264864)
		(end 256.92608 -31.111444)
		(width 0.1651)
		(layer "F.Cu")
		(net "M_A_MA<3>")
	)
	(via
		(at 254.199898 -22.850856)
		(size 0.508)
		(drill 0.254)
		(layers "F.Cu" "B.Cu")
		(net "M_A_MA<3>")
	)
	(via
		(at 254.199898 -16.718788)
		(size 0.4572)
		(drill 0.2032)
		(layers "F.Cu" "B.Cu")
		(net "M_A_MA<3>")
	)
	(via
		(at 255.0795 -29.264864)
		(size 0.508)
		(drill 0.254)
		(layers "F.Cu" "B.Cu")
		(net "M_A_MA<3>")
	)
	(segment
		(start 254.199898 -24.824182)
		(end 254.199898 -22.850856)
		(width 0.1651)
		(layer "B.Cu")
		(net "M_A_MA<3>")
	)
	(segment
		(start 254.200406 -24.824182)
		(end 254.199898 -24.824182)
		(width 0.1651)
		(layer "B.Cu")
		(net "M_A_MA<3>")
	)
	(segment
		(start 253.508256 -17.585182)
		(end 253.508256 -17.232122)
		(width 0.14224)
		(layer "In9.Cu")
		(net "M_A_MA<3>")
	)
	(segment
		(start 253.8476 -21.844)
		(end 253.731268 -21.727668)
		(width 0.14224)
		(layer "In9.Cu")
		(net "M_A_MA<3>")
	)
	(segment
		(start 253.761494 -18.537936)
		(end 254.199898 -18.099532)
		(width 0.14224)
		(layer "In9.Cu")
		(net "M_A_MA<3>")
	)
	(segment
		(start 254.044958 -17.077182)
		(end 254.199898 -16.922242)
		(width 0.14224)
		(layer "In9.Cu")
		(net "M_A_MA<3>")
	)
	(segment
		(start 254.199898 -16.922242)
		(end 254.199898 -16.718788)
		(width 0.14224)
		(layer "In9.Cu")
		(net "M_A_MA<3>")
	)
	(segment
		(start 254.1778 -20.89531)
		(end 254.1778 -19.43862)
		(width 0.14224)
		(layer "In9.Cu")
		(net "M_A_MA<3>")
	)
	(segment
		(start 253.8476 -22.498558)
		(end 253.8476 -21.844)
		(width 0.14224)
		(layer "In9.Cu")
		(net "M_A_MA<3>")
	)
	(segment
		(start 254.044958 -17.740122)
		(end 253.663196 -17.740122)
		(width 0.14224)
		(layer "In9.Cu")
		(net "M_A_MA<3>")
	)
	(segment
		(start 253.663196 -17.077182)
		(end 254.044958 -17.077182)
		(width 0.14224)
		(layer "In9.Cu")
		(net "M_A_MA<3>")
	)
	(segment
		(start 253.731268 -21.727668)
		(end 253.731268 -21.341842)
		(width 0.14224)
		(layer "In9.Cu")
		(net "M_A_MA<3>")
	)
	(segment
		(start 253.761494 -19.022314)
		(end 253.761494 -18.537936)
		(width 0.14224)
		(layer "In9.Cu")
		(net "M_A_MA<3>")
	)
	(segment
		(start 254.199898 -18.099532)
		(end 254.199898 -17.895062)
		(width 0.14224)
		(layer "In9.Cu")
		(net "M_A_MA<3>")
	)
	(segment
		(start 253.663196 -17.740122)
		(end 253.508256 -17.585182)
		(width 0.14224)
		(layer "In9.Cu")
		(net "M_A_MA<3>")
	)
	(segment
		(start 254.199898 -22.850856)
		(end 253.8476 -22.498558)
		(width 0.14224)
		(layer "In9.Cu")
		(net "M_A_MA<3>")
	)
	(segment
		(start 253.731268 -21.341842)
		(end 254.1778 -20.89531)
		(width 0.14224)
		(layer "In9.Cu")
		(net "M_A_MA<3>")
	)
	(segment
		(start 254.199898 -17.895062)
		(end 254.044958 -17.740122)
		(width 0.14224)
		(layer "In9.Cu")
		(net "M_A_MA<3>")
	)
	(segment
		(start 254.1778 -19.43862)
		(end 253.761494 -19.022314)
		(width 0.14224)
		(layer "In9.Cu")
		(net "M_A_MA<3>")
	)
	(segment
		(start 253.508256 -17.232122)
		(end 253.663196 -17.077182)
		(width 0.14224)
		(layer "In9.Cu")
		(net "M_A_MA<3>")
	)
	(segment
		(start 255.513078 -26.944066)
		(end 255.347978 -26.778966)
		(width 0.1651)
		(layer "F.Cu")
		(net "M_A_MA<2>")
	)
	(segment
		(start 255.765554 -24.641556)
		(end 255.765554 -24.151844)
		(width 0.1651)
		(layer "F.Cu")
		(net "M_A_MA<2>")
	)
	(segment
		(start 255.472692 -23.18131)
		(end 255.2954 -23.004018)
		(width 0.1651)
		(layer "F.Cu")
		(net "M_A_MA<2>")
	)
	(segment
		(start 255.67386 -27.617166)
		(end 255.80086 -27.490166)
		(width 0.1651)
		(layer "F.Cu")
		(net "M_A_MA<2>")
	)
	(segment
		(start 257.93446 -30.693106)
		(end 255.347978 -28.106624)
		(width 0.1651)
		(layer "F.Cu")
		(net "M_A_MA<2>")
	)
	(segment
		(start 255.05029 -20.023582)
		(end 255.049782 -20.023582)
		(width 0.1651)
		(layer "F.Cu")
		(net "M_A_MA<2>")
	)
	(segment
		(start 255.457452 -22.362668)
		(end 255.292352 -22.197568)
		(width 0.1651)
		(layer "F.Cu")
		(net "M_A_MA<2>")
	)
	(segment
		(start 255.67386 -26.944066)
		(end 255.513078 -26.944066)
		(width 0.1651)
		(layer "F.Cu")
		(net "M_A_MA<2>")
	)
	(segment
		(start 255.2954 -23.004018)
		(end 255.2954 -22.7584)
		(width 0.1651)
		(layer "F.Cu")
		(net "M_A_MA<2>")
	)
	(segment
		(start 255.2954 -22.7584)
		(end 255.457452 -22.596348)
		(width 0.1651)
		(layer "F.Cu")
		(net "M_A_MA<2>")
	)
	(segment
		(start 255.513078 -27.617166)
		(end 255.67386 -27.617166)
		(width 0.1651)
		(layer "F.Cu")
		(net "M_A_MA<2>")
	)
	(segment
		(start 257.64617 -51.132486)
		(end 257.267456 -50.25771)
		(width 0.0889)
		(layer "F.Cu")
		(net "M_A_MA<2>")
	)
	(segment
		(start 255.80086 -27.490166)
		(end 255.80086 -27.071066)
		(width 0.1651)
		(layer "F.Cu")
		(net "M_A_MA<2>")
	)
	(segment
		(start 255.347978 -25.432766)
		(end 255.347978 -25.059132)
		(width 0.1651)
		(layer "F.Cu")
		(net "M_A_MA<2>")
	)
	(segment
		(start 255.78181 -25.762966)
		(end 255.61671 -25.597866)
		(width 0.1651)
		(layer "F.Cu")
		(net "M_A_MA<2>")
	)
	(segment
		(start 255.513078 -25.597866)
		(end 255.347978 -25.432766)
		(width 0.1651)
		(layer "F.Cu")
		(net "M_A_MA<2>")
	)
	(segment
		(start 255.765554 -24.151844)
		(end 255.472692 -23.858982)
		(width 0.1651)
		(layer "F.Cu")
		(net "M_A_MA<2>")
	)
	(segment
		(start 257.93446 -47.80661)
		(end 257.93446 -30.693106)
		(width 0.1651)
		(layer "F.Cu")
		(net "M_A_MA<2>")
	)
	(segment
		(start 255.049782 -18.759932)
		(end 255.050036 -18.759678)
		(width 0.1651)
		(layer "F.Cu")
		(net "M_A_MA<2>")
	)
	(segment
		(start 255.347978 -26.436066)
		(end 255.513078 -26.270966)
		(width 0.1651)
		(layer "F.Cu")
		(net "M_A_MA<2>")
	)
	(segment
		(start 255.80086 -27.071066)
		(end 255.67386 -26.944066)
		(width 0.1651)
		(layer "F.Cu")
		(net "M_A_MA<2>")
	)
	(segment
		(start 255.347978 -25.059132)
		(end 255.765554 -24.641556)
		(width 0.1651)
		(layer "F.Cu")
		(net "M_A_MA<2>")
	)
	(segment
		(start 257.250184 -50.174652)
		(end 257.250184 -48.768762)
		(width 0.0889)
		(layer "F.Cu")
		(net "M_A_MA<2>")
	)
	(segment
		(start 255.61671 -25.597866)
		(end 255.513078 -25.597866)
		(width 0.1651)
		(layer "F.Cu")
		(net "M_A_MA<2>")
	)
	(segment
		(start 255.347978 -27.782266)
		(end 255.513078 -27.617166)
		(width 0.1651)
		(layer "F.Cu")
		(net "M_A_MA<2>")
	)
	(segment
		(start 255.347978 -26.778966)
		(end 255.347978 -26.436066)
		(width 0.1651)
		(layer "F.Cu")
		(net "M_A_MA<2>")
	)
	(segment
		(start 255.513078 -26.270966)
		(end 255.61671 -26.270966)
		(width 0.1651)
		(layer "F.Cu")
		(net "M_A_MA<2>")
	)
	(segment
		(start 255.292352 -22.197568)
		(end 255.021842 -22.197568)
		(width 0.1651)
		(layer "F.Cu")
		(net "M_A_MA<2>")
	)
	(segment
		(start 255.78181 -26.105866)
		(end 255.78181 -25.762966)
		(width 0.1651)
		(layer "F.Cu")
		(net "M_A_MA<2>")
	)
	(segment
		(start 255.61671 -26.270966)
		(end 255.78181 -26.105866)
		(width 0.1651)
		(layer "F.Cu")
		(net "M_A_MA<2>")
	)
	(segment
		(start 255.049782 -20.023582)
		(end 255.049782 -18.759932)
		(width 0.1651)
		(layer "F.Cu")
		(net "M_A_MA<2>")
	)
	(segment
		(start 257.93446 -48.08474)
		(end 257.93446 -47.80661)
		(width 0.0889)
		(layer "F.Cu")
		(net "M_A_MA<2>")
	)
	(segment
		(start 255.472692 -23.858982)
		(end 255.472692 -23.18131)
		(width 0.1651)
		(layer "F.Cu")
		(net "M_A_MA<2>")
	)
	(segment
		(start 257.250184 -48.768762)
		(end 257.93446 -48.08474)
		(width 0.0889)
		(layer "F.Cu")
		(net "M_A_MA<2>")
	)
	(segment
		(start 255.457452 -22.596348)
		(end 255.457452 -22.362668)
		(width 0.1651)
		(layer "F.Cu")
		(net "M_A_MA<2>")
	)
	(segment
		(start 255.050036 -18.759678)
		(end 255.050036 -18.734278)
		(width 0.1651)
		(layer "F.Cu")
		(net "M_A_MA<2>")
	)
	(segment
		(start 255.347978 -28.106624)
		(end 255.347978 -27.782266)
		(width 0.1651)
		(layer "F.Cu")
		(net "M_A_MA<2>")
	)
	(via
		(at 255.050036 -18.734278)
		(size 0.4572)
		(drill 0.2032)
		(layers "F.Cu" "B.Cu")
		(net "M_A_MA<2>")
	)
	(via
		(at 255.021842 -22.197568)
		(size 0.508)
		(drill 0.254)
		(layers "F.Cu" "B.Cu")
		(net "M_A_MA<2>")
	)
	(arc
		(start 257.267456 -50.25771)
		(mid 257.254541 -50.217069)
		(end 257.250184 -50.174652)
		(width 0.0889)
		(layer "F.Cu")
		(net "M_A_MA<2>")
	)
	(segment
		(start 255.049782 -22.169628)
		(end 255.021842 -22.197568)
		(width 0.1651)
		(layer "B.Cu")
		(net "M_A_MA<2>")
	)
	(segment
		(start 255.049782 -20.224242)
		(end 255.049782 -22.169628)
		(width 0.1651)
		(layer "B.Cu")
		(net "M_A_MA<2>")
	)
	(segment
		(start 255.05029 -20.224242)
		(end 255.049782 -20.224242)
		(width 0.1651)
		(layer "B.Cu")
		(net "M_A_MA<2>")
	)
	(segment
		(start 255.02489 -22.197568)
		(end 255.15189 -22.070568)
		(width 0.14224)
		(layer "In9.Cu")
		(net "M_A_MA<2>")
	)
	(segment
		(start 255.15189 -22.070568)
		(end 255.15189 -18.836132)
		(width 0.14224)
		(layer "In9.Cu")
		(net "M_A_MA<2>")
	)
	(segment
		(start 255.15189 -18.836132)
		(end 255.050036 -18.734278)
		(width 0.14224)
		(layer "In9.Cu")
		(net "M_A_MA<2>")
	)
	(segment
		(start 255.021842 -22.197568)
		(end 255.02489 -22.197568)
		(width 0.14224)
		(layer "In9.Cu")
		(net "M_A_MA<2>")
	)
	(segment
		(start 257.43027 -48.164242)
		(end 257.43027 -47.788068)
		(width 0.0889)
		(layer "F.Cu")
		(net "M_A_MA<1>")
	)
	(segment
		(start 257.43027 -30.902148)
		(end 254.843788 -28.315666)
		(width 0.1651)
		(layer "F.Cu")
		(net "M_A_MA<1>")
	)
	(segment
		(start 254.843788 -26.399744)
		(end 254.843788 -24.505412)
		(width 0.1651)
		(layer "F.Cu")
		(net "M_A_MA<1>")
	)
	(segment
		(start 255.05029 -15.423642)
		(end 255.049782 -15.423642)
		(width 0.1651)
		(layer "F.Cu")
		(net "M_A_MA<1>")
	)
	(segment
		(start 254.843788 -28.315666)
		(end 254.843788 -26.399744)
		(width 0.1651)
		(layer "F.Cu")
		(net "M_A_MA<1>")
	)
	(segment
		(start 257.059684 -48.534828)
		(end 257.43027 -48.164242)
		(width 0.0889)
		(layer "F.Cu")
		(net "M_A_MA<1>")
	)
	(segment
		(start 254.843788 -24.505412)
		(end 255.021842 -24.07539)
		(width 0.1651)
		(layer "F.Cu")
		(net "M_A_MA<1>")
	)
	(segment
		(start 255.021842 -24.07539)
		(end 255.021842 -23.560278)
		(width 0.1651)
		(layer "F.Cu")
		(net "M_A_MA<1>")
	)
	(segment
		(start 257.181604 -50.65522)
		(end 257.168904 -50.51552)
		(width 0.0889)
		(layer "F.Cu")
		(net "M_A_MA<1>")
	)
	(segment
		(start 257.130804 -50.45202)
		(end 257.059684 -50.35042)
		(width 0.0889)
		(layer "F.Cu")
		(net "M_A_MA<1>")
	)
	(segment
		(start 257.43027 -47.788068)
		(end 257.43027 -30.902148)
		(width 0.1651)
		(layer "F.Cu")
		(net "M_A_MA<1>")
	)
	(segment
		(start 257.194304 -51.34102)
		(end 257.181604 -50.65522)
		(width 0.0889)
		(layer "F.Cu")
		(net "M_A_MA<1>")
	)
	(segment
		(start 257.64617 -52.12334)
		(end 257.194304 -51.34102)
		(width 0.0889)
		(layer "F.Cu")
		(net "M_A_MA<1>")
	)
	(segment
		(start 255.049782 -15.423642)
		(end 255.049782 -16.718788)
		(width 0.1651)
		(layer "F.Cu")
		(net "M_A_MA<1>")
	)
	(segment
		(start 257.059684 -50.35042)
		(end 257.059684 -48.534828)
		(width 0.0889)
		(layer "F.Cu")
		(net "M_A_MA<1>")
	)
	(segment
		(start 257.168904 -50.51552)
		(end 257.130804 -50.45202)
		(width 0.0889)
		(layer "F.Cu")
		(net "M_A_MA<1>")
	)
	(via
		(at 255.049782 -16.718788)
		(size 0.4572)
		(drill 0.2032)
		(layers "F.Cu" "B.Cu")
		(net "M_A_MA<1>")
	)
	(via
		(at 254.843788 -26.399744)
		(size 0.508)
		(drill 0.254)
		(layers "F.Cu" "B.Cu")
		(net "M_A_MA<1>")
	)
	(via
		(at 255.021842 -23.560278)
		(size 0.508)
		(drill 0.254)
		(layers "F.Cu" "B.Cu")
		(net "M_A_MA<1>")
	)
	(segment
		(start 255.049782 -24.824182)
		(end 255.049782 -23.588218)
		(width 0.1651)
		(layer "B.Cu")
		(net "M_A_MA<1>")
	)
	(segment
		(start 255.049782 -23.588218)
		(end 255.021842 -23.560278)
		(width 0.1651)
		(layer "B.Cu")
		(net "M_A_MA<1>")
	)
	(segment
		(start 255.05029 -24.824182)
		(end 255.049782 -24.824182)
		(width 0.1651)
		(layer "B.Cu")
		(net "M_A_MA<1>")
	)
	(segment
		(start 254.642366 -18.357088)
		(end 255.050036 -17.949418)
		(width 0.14224)
		(layer "In9.Cu")
		(net "M_A_MA<1>")
	)
	(segment
		(start 255.050036 -17.949418)
		(end 255.050036 -17.396968)
		(width 0.14224)
		(layer "In9.Cu")
		(net "M_A_MA<1>")
	)
	(segment
		(start 254.54991 -22.47011)
		(end 254.54991 -21.85289)
		(width 0.14224)
		(layer "In9.Cu")
		(net "M_A_MA<1>")
	)
	(segment
		(start 255.021842 -22.942042)
		(end 254.54991 -22.47011)
		(width 0.14224)
		(layer "In9.Cu")
		(net "M_A_MA<1>")
	)
	(segment
		(start 255.021842 -23.560278)
		(end 255.021842 -22.942042)
		(width 0.14224)
		(layer "In9.Cu")
		(net "M_A_MA<1>")
	)
	(segment
		(start 255.050036 -17.396968)
		(end 255.049782 -17.396714)
		(width 0.14224)
		(layer "In9.Cu")
		(net "M_A_MA<1>")
	)
	(segment
		(start 254.6858 -19.228054)
		(end 254.642366 -19.18462)
		(width 0.14224)
		(layer "In9.Cu")
		(net "M_A_MA<1>")
	)
	(segment
		(start 254.54991 -21.85289)
		(end 254.6858 -21.717)
		(width 0.14224)
		(layer "In9.Cu")
		(net "M_A_MA<1>")
	)
	(segment
		(start 254.6858 -21.717)
		(end 254.6858 -19.228054)
		(width 0.14224)
		(layer "In9.Cu")
		(net "M_A_MA<1>")
	)
	(segment
		(start 254.642366 -19.18462)
		(end 254.642366 -18.357088)
		(width 0.14224)
		(layer "In9.Cu")
		(net "M_A_MA<1>")
	)
	(segment
		(start 255.049782 -17.396714)
		(end 255.049782 -16.718788)
		(width 0.14224)
		(layer "In9.Cu")
		(net "M_A_MA<1>")
	)
	(segment
		(start 266.231116 -54.104286)
		(end 265.659616 -54.104286)
		(width 0.1016)
		(layer "F.Cu")
		(net "M_A_MA<17>")
	)
	(segment
		(start 275.449792 -20.023582)
		(end 275.449792 -18.734786)
		(width 0.1651)
		(layer "F.Cu")
		(net "M_A_MA<17>")
	)
	(segment
		(start 275.4503 -20.023582)
		(end 275.449792 -20.023582)
		(width 0.1651)
		(layer "F.Cu")
		(net "M_A_MA<17>")
	)
	(segment
		(start 275.449792 -18.734786)
		(end 275.4503 -18.734278)
		(width 0.1651)
		(layer "F.Cu")
		(net "M_A_MA<17>")
	)
	(via
		(at 275.4503 -18.734278)
		(size 0.4572)
		(drill 0.2032)
		(layers "F.Cu" "B.Cu")
		(net "M_A_MA<17>")
	)
	(via
		(at 265.659616 -54.104286)
		(size 0.508)
		(drill 0.254)
		(layers "F.Cu" "B.Cu")
		(net "M_A_MA<17>")
	)
	(via
		(at 275.449792 -22.197568)
		(size 0.508)
		(drill 0.254)
		(layers "F.Cu" "B.Cu")
		(net "M_A_MA<17>")
	)
	(segment
		(start 275.4503 -20.224242)
		(end 275.449792 -20.224242)
		(width 0.1651)
		(layer "B.Cu")
		(net "M_A_MA<17>")
	)
	(segment
		(start 275.449792 -20.224242)
		(end 275.449792 -22.197568)
		(width 0.1651)
		(layer "B.Cu")
		(net "M_A_MA<17>")
	)
	(segment
		(start 275.784564 -21.675344)
		(end 275.784564 -19.068542)
		(width 0.14224)
		(layer "In11.Cu")
		(net "M_A_MA<17>")
	)
	(segment
		(start 275.8186 -22.733)
		(end 275.449792 -22.364192)
		(width 0.14224)
		(layer "In11.Cu")
		(net "M_A_MA<17>")
	)
	(segment
		(start 275.449792 -22.364192)
		(end 275.449792 -22.197568)
		(width 0.14224)
		(layer "In11.Cu")
		(net "M_A_MA<17>")
	)
	(segment
		(start 268.174724 -48.893476)
		(end 268.174724 -48.509174)
		(width 0.0889)
		(layer "In11.Cu")
		(net "M_A_MA<17>")
	)
	(segment
		(start 268.174724 -48.509174)
		(end 268.174724 -35.585146)
		(width 0.14224)
		(layer "In11.Cu")
		(net "M_A_MA<17>")
	)
	(segment
		(start 275.463 -26.289)
		(end 275.8694 -25.8826)
		(width 0.14224)
		(layer "In11.Cu")
		(net "M_A_MA<17>")
	)
	(segment
		(start 266.954 -51.73599)
		(end 266.954 -50.1142)
		(width 0.0889)
		(layer "In11.Cu")
		(net "M_A_MA<17>")
	)
	(segment
		(start 266.084304 -52.585874)
		(end 266.228068 -52.270406)
		(width 0.0889)
		(layer "In11.Cu")
		(net "M_A_MA<17>")
	)
	(segment
		(start 265.659616 -54.104286)
		(end 266.084304 -53.15712)
		(width 0.0889)
		(layer "In11.Cu")
		(net "M_A_MA<17>")
	)
	(segment
		(start 275.9202 -21.994368)
		(end 275.9202 -21.81098)
		(width 0.14224)
		(layer "In11.Cu")
		(net "M_A_MA<17>")
	)
	(segment
		(start 275.449792 -22.197568)
		(end 275.717 -22.197568)
		(width 0.14224)
		(layer "In11.Cu")
		(net "M_A_MA<17>")
	)
	(segment
		(start 266.768834 -51.991768)
		(end 266.954 -51.73599)
		(width 0.0889)
		(layer "In11.Cu")
		(net "M_A_MA<17>")
	)
	(segment
		(start 275.9202 -23.7998)
		(end 275.9202 -23.1902)
		(width 0.14224)
		(layer "In11.Cu")
		(net "M_A_MA<17>")
	)
	(segment
		(start 275.9202 -23.1902)
		(end 275.8186 -23.0886)
		(width 0.14224)
		(layer "In11.Cu")
		(net "M_A_MA<17>")
	)
	(segment
		(start 266.954 -50.1142)
		(end 268.174724 -48.893476)
		(width 0.0889)
		(layer "In11.Cu")
		(net "M_A_MA<17>")
	)
	(segment
		(start 275.717 -22.197568)
		(end 275.9202 -21.994368)
		(width 0.14224)
		(layer "In11.Cu")
		(net "M_A_MA<17>")
	)
	(segment
		(start 275.8694 -25.8826)
		(end 275.8694 -23.8506)
		(width 0.14224)
		(layer "In11.Cu")
		(net "M_A_MA<17>")
	)
	(segment
		(start 275.784564 -19.068542)
		(end 275.4503 -18.734278)
		(width 0.14224)
		(layer "In11.Cu")
		(net "M_A_MA<17>")
	)
	(segment
		(start 275.8186 -23.0886)
		(end 275.8186 -22.733)
		(width 0.14224)
		(layer "In11.Cu")
		(net "M_A_MA<17>")
	)
	(segment
		(start 266.228068 -52.270406)
		(end 266.768834 -51.991768)
		(width 0.0889)
		(layer "In11.Cu")
		(net "M_A_MA<17>")
	)
	(segment
		(start 275.463 -28.29687)
		(end 275.463 -26.289)
		(width 0.14224)
		(layer "In11.Cu")
		(net "M_A_MA<17>")
	)
	(segment
		(start 266.084304 -53.15712)
		(end 266.084304 -52.585874)
		(width 0.0889)
		(layer "In11.Cu")
		(net "M_A_MA<17>")
	)
	(segment
		(start 275.8694 -23.8506)
		(end 275.9202 -23.7998)
		(width 0.14224)
		(layer "In11.Cu")
		(net "M_A_MA<17>")
	)
	(segment
		(start 268.174724 -35.585146)
		(end 275.463 -28.29687)
		(width 0.14224)
		(layer "In11.Cu")
		(net "M_A_MA<17>")
	)
	(segment
		(start 275.9202 -21.81098)
		(end 275.784564 -21.675344)
		(width 0.14224)
		(layer "In11.Cu")
		(net "M_A_MA<17>")
	)
	(segment
		(start 263.13638 -29.243274)
		(end 263.13638 -45.72)
		(width 0.1651)
		(layer "F.Cu")
		(net "M_A_MA<16>")
	)
	(segment
		(start 263.13638 -46.078902)
		(end 263.303004 -46.245526)
		(width 0.0889)
		(layer "F.Cu")
		(net "M_A_MA<16>")
	)
	(segment
		(start 262.170164 -49.28489)
		(end 262.170164 -50.303684)
		(width 0.0889)
		(layer "F.Cu")
		(net "M_A_MA<16>")
	)
	(segment
		(start 266.450826 -25.875996)
		(end 266.217146 -25.875996)
		(width 0.1651)
		(layer "F.Cu")
		(net "M_A_MA<16>")
	)
	(segment
		(start 264.606024 -27.067256)
		(end 264.757662 -27.218894)
		(width 0.1651)
		(layer "F.Cu")
		(net "M_A_MA<16>")
	)
	(segment
		(start 265.224768 -26.752042)
		(end 265.072876 -26.60015)
		(width 0.1651)
		(layer "F.Cu")
		(net "M_A_MA<16>")
	)
	(segment
		(start 266.684252 -25.40889)
		(end 266.684252 -25.64257)
		(width 0.1651)
		(layer "F.Cu")
		(net "M_A_MA<16>")
	)
	(segment
		(start 267.791692 -23.368508)
		(end 267.362178 -23.798022)
		(width 0.1651)
		(layer "F.Cu")
		(net "M_A_MA<16>")
	)
	(segment
		(start 263.844024 -28.53563)
		(end 263.13638 -29.243274)
		(width 0.1651)
		(layer "F.Cu")
		(net "M_A_MA<16>")
	)
	(segment
		(start 262.170164 -50.303684)
		(end 262.79729 -51.132486)
		(width 0.0889)
		(layer "F.Cu")
		(net "M_A_MA<16>")
	)
	(segment
		(start 268.649958 -15.423642)
		(end 268.649958 -16.714978)
		(width 0.1651)
		(layer "F.Cu")
		(net "M_A_MA<16>")
	)
	(segment
		(start 267.64107 -24.33574)
		(end 267.64107 -24.718518)
		(width 0.1651)
		(layer "F.Cu")
		(net "M_A_MA<16>")
	)
	(segment
		(start 264.606024 -26.834084)
		(end 264.606024 -27.067256)
		(width 0.1651)
		(layer "F.Cu")
		(net "M_A_MA<16>")
	)
	(segment
		(start 265.691874 -26.284936)
		(end 265.691874 -26.586688)
		(width 0.1651)
		(layer "F.Cu")
		(net "M_A_MA<16>")
	)
	(segment
		(start 268.457934 -23.368508)
		(end 267.791692 -23.368508)
		(width 0.1651)
		(layer "F.Cu")
		(net "M_A_MA<16>")
	)
	(segment
		(start 264.757662 -27.218894)
		(end 264.757662 -27.621992)
		(width 0.1651)
		(layer "F.Cu")
		(net "M_A_MA<16>")
	)
	(segment
		(start 265.387836 -25.747472)
		(end 265.387836 -25.980644)
		(width 0.1651)
		(layer "F.Cu")
		(net "M_A_MA<16>")
	)
	(segment
		(start 267.47597 -24.883618)
		(end 267.093446 -24.883618)
		(width 0.1651)
		(layer "F.Cu")
		(net "M_A_MA<16>")
	)
	(segment
		(start 265.52652 -26.752042)
		(end 265.224768 -26.752042)
		(width 0.1651)
		(layer "F.Cu")
		(net "M_A_MA<16>")
	)
	(segment
		(start 266.684252 -25.64257)
		(end 266.450826 -25.875996)
		(width 0.1651)
		(layer "F.Cu")
		(net "M_A_MA<16>")
	)
	(segment
		(start 265.072876 -26.60015)
		(end 264.839958 -26.60015)
		(width 0.1651)
		(layer "F.Cu")
		(net "M_A_MA<16>")
	)
	(segment
		(start 265.387836 -25.980644)
		(end 265.691874 -26.284936)
		(width 0.1651)
		(layer "F.Cu")
		(net "M_A_MA<16>")
	)
	(segment
		(start 266.217146 -25.875996)
		(end 265.854688 -25.513538)
		(width 0.1651)
		(layer "F.Cu")
		(net "M_A_MA<16>")
	)
	(segment
		(start 266.789154 -24.579326)
		(end 266.555474 -24.579326)
		(width 0.1651)
		(layer "F.Cu")
		(net "M_A_MA<16>")
	)
	(segment
		(start 265.854688 -25.513538)
		(end 265.62177 -25.513538)
		(width 0.1651)
		(layer "F.Cu")
		(net "M_A_MA<16>")
	)
	(segment
		(start 263.303004 -48.15205)
		(end 262.170164 -49.28489)
		(width 0.0889)
		(layer "F.Cu")
		(net "M_A_MA<16>")
	)
	(segment
		(start 265.691874 -26.586688)
		(end 265.52652 -26.752042)
		(width 0.1651)
		(layer "F.Cu")
		(net "M_A_MA<16>")
	)
	(segment
		(start 266.322048 -25.046686)
		(end 266.684252 -25.40889)
		(width 0.1651)
		(layer "F.Cu")
		(net "M_A_MA<16>")
	)
	(segment
		(start 265.62177 -25.513538)
		(end 265.387836 -25.747472)
		(width 0.1651)
		(layer "F.Cu")
		(net "M_A_MA<16>")
	)
	(segment
		(start 263.13638 -45.72)
		(end 263.13638 -46.078902)
		(width 0.0889)
		(layer "F.Cu")
		(net "M_A_MA<16>")
	)
	(segment
		(start 268.650466 -15.423642)
		(end 268.649958 -15.423642)
		(width 0.1651)
		(layer "F.Cu")
		(net "M_A_MA<16>")
	)
	(segment
		(start 266.322048 -24.812752)
		(end 266.322048 -25.046686)
		(width 0.1651)
		(layer "F.Cu")
		(net "M_A_MA<16>")
	)
	(segment
		(start 268.649704 -23.560278)
		(end 268.457934 -23.368508)
		(width 0.1651)
		(layer "F.Cu")
		(net "M_A_MA<16>")
	)
	(segment
		(start 264.757662 -27.621992)
		(end 263.844024 -28.53563)
		(width 0.1651)
		(layer "F.Cu")
		(net "M_A_MA<16>")
	)
	(segment
		(start 267.64107 -24.718518)
		(end 267.47597 -24.883618)
		(width 0.1651)
		(layer "F.Cu")
		(net "M_A_MA<16>")
	)
	(segment
		(start 264.839958 -26.60015)
		(end 264.606024 -26.834084)
		(width 0.1651)
		(layer "F.Cu")
		(net "M_A_MA<16>")
	)
	(segment
		(start 267.093446 -24.883618)
		(end 266.789154 -24.579326)
		(width 0.1651)
		(layer "F.Cu")
		(net "M_A_MA<16>")
	)
	(segment
		(start 263.303004 -46.245526)
		(end 263.303004 -48.15205)
		(width 0.0889)
		(layer "F.Cu")
		(net "M_A_MA<16>")
	)
	(segment
		(start 267.362178 -23.798022)
		(end 267.362178 -24.056848)
		(width 0.1651)
		(layer "F.Cu")
		(net "M_A_MA<16>")
	)
	(segment
		(start 267.362178 -24.056848)
		(end 267.64107 -24.33574)
		(width 0.1651)
		(layer "F.Cu")
		(net "M_A_MA<16>")
	)
	(segment
		(start 266.555474 -24.579326)
		(end 266.322048 -24.812752)
		(width 0.1651)
		(layer "F.Cu")
		(net "M_A_MA<16>")
	)
	(via
		(at 263.844024 -28.53563)
		(size 0.508)
		(drill 0.254)
		(layers "F.Cu" "B.Cu")
		(net "M_A_MA<16>")
	)
	(via
		(at 268.649958 -16.714978)
		(size 0.508)
		(drill 0.254)
		(layers "F.Cu" "B.Cu")
		(net "M_A_MA<16>")
	)
	(via
		(at 268.649704 -23.560278)
		(size 0.508)
		(drill 0.254)
		(layers "F.Cu" "B.Cu")
		(net "M_A_MA<16>")
	)
	(segment
		(start 268.649958 -24.824182)
		(end 268.649958 -23.560532)
		(width 0.1651)
		(layer "B.Cu")
		(net "M_A_MA<16>")
	)
	(segment
		(start 268.649958 -23.560532)
		(end 268.649704 -23.560278)
		(width 0.1651)
		(layer "B.Cu")
		(net "M_A_MA<16>")
	)
	(segment
		(start 268.650466 -24.824182)
		(end 268.649958 -24.824182)
		(width 0.1651)
		(layer "B.Cu")
		(net "M_A_MA<16>")
	)
	(segment
		(start 268.263116 -21.770848)
		(end 268.263116 -19.253962)
		(width 0.14224)
		(layer "In9.Cu")
		(net "M_A_MA<16>")
	)
	(segment
		(start 268.211046 -17.638522)
		(end 268.553692 -16.811244)
		(width 0.14224)
		(layer "In9.Cu")
		(net "M_A_MA<16>")
	)
	(segment
		(start 268.211046 -19.135852)
		(end 268.211046 -17.638522)
		(width 0.14224)
		(layer "In9.Cu")
		(net "M_A_MA<16>")
	)
	(segment
		(start 268.203172 -21.915628)
		(end 268.263116 -21.770848)
		(width 0.14224)
		(layer "In9.Cu")
		(net "M_A_MA<16>")
	)
	(segment
		(start 268.203172 -22.482302)
		(end 268.203172 -21.915628)
		(width 0.14224)
		(layer "In9.Cu")
		(net "M_A_MA<16>")
	)
	(segment
		(start 268.649704 -23.560278)
		(end 268.203172 -22.482302)
		(width 0.14224)
		(layer "In9.Cu")
		(net "M_A_MA<16>")
	)
	(segment
		(start 268.553692 -16.811244)
		(end 268.649958 -16.714978)
		(width 0.14224)
		(layer "In9.Cu")
		(net "M_A_MA<16>")
	)
	(segment
		(start 268.263116 -19.253962)
		(end 268.211046 -19.135852)
		(width 0.14224)
		(layer "In9.Cu")
		(net "M_A_MA<16>")
	)
	(segment
		(start 272.050002 -15.423642)
		(end 272.050002 -16.718534)
		(width 0.1651)
		(layer "F.Cu")
		(net "M_A_MA<15>")
	)
	(segment
		(start 264.51433 -54.104286)
		(end 263.94283 -54.104286)
		(width 0.1016)
		(layer "F.Cu")
		(net "M_A_MA<15>")
	)
	(segment
		(start 272.05051 -15.423642)
		(end 272.050002 -15.423642)
		(width 0.1651)
		(layer "F.Cu")
		(net "M_A_MA<15>")
	)
	(segment
		(start 272.050002 -16.718534)
		(end 272.050256 -16.718788)
		(width 0.1651)
		(layer "F.Cu")
		(net "M_A_MA<15>")
	)
	(via
		(at 263.94283 -54.104286)
		(size 0.508)
		(drill 0.254)
		(layers "F.Cu" "B.Cu")
		(net "M_A_MA<15>")
	)
	(via
		(at 272.050256 -16.718788)
		(size 0.4572)
		(drill 0.2032)
		(layers "F.Cu" "B.Cu")
		(net "M_A_MA<15>")
	)
	(via
		(at 272.049748 -23.560278)
		(size 0.508)
		(drill 0.254)
		(layers "F.Cu" "B.Cu")
		(net "M_A_MA<15>")
	)
	(segment
		(start 272.050002 -24.824182)
		(end 272.050002 -23.560532)
		(width 0.1651)
		(layer "B.Cu")
		(net "M_A_MA<15>")
	)
	(segment
		(start 272.05051 -24.824182)
		(end 272.050002 -24.824182)
		(width 0.1651)
		(layer "B.Cu")
		(net "M_A_MA<15>")
	)
	(segment
		(start 272.050002 -23.560532)
		(end 272.049748 -23.560278)
		(width 0.1651)
		(layer "B.Cu")
		(net "M_A_MA<15>")
	)
	(segment
		(start 266.306808 -33.09239)
		(end 266.306808 -33.716722)
		(width 0.14224)
		(layer "In11.Cu")
		(net "M_A_MA<15>")
	)
	(segment
		(start 264.1854 -52.7558)
		(end 264.344404 -52.914804)
		(width 0.0889)
		(layer "In11.Cu")
		(net "M_A_MA<15>")
	)
	(segment
		(start 264.344404 -53.24602)
		(end 263.94283 -54.104286)
		(width 0.0889)
		(layer "In11.Cu")
		(net "M_A_MA<15>")
	)
	(segment
		(start 272.100548 -24.95423)
		(end 272.100548 -25.390094)
		(width 0.14224)
		(layer "In11.Cu")
		(net "M_A_MA<15>")
	)
	(segment
		(start 268.62278 -30.776418)
		(end 268.62278 -31.40075)
		(width 0.14224)
		(layer "In11.Cu")
		(net "M_A_MA<15>")
	)
	(segment
		(start 271.538954 -18.243296)
		(end 271.640046 -18.344388)
		(width 0.14224)
		(layer "In11.Cu")
		(net "M_A_MA<15>")
	)
	(segment
		(start 266.306808 -33.716722)
		(end 266.140438 -33.883092)
		(width 0.14224)
		(layer "In11.Cu")
		(net "M_A_MA<15>")
	)
	(segment
		(start 266.140438 -33.883092)
		(end 265.698224 -33.883092)
		(width 0.14224)
		(layer "In11.Cu")
		(net "M_A_MA<15>")
	)
	(segment
		(start 264.1854 -50.9524)
		(end 264.1854 -52.7558)
		(width 0.0889)
		(layer "In11.Cu")
		(net "M_A_MA<15>")
	)
	(segment
		(start 271.640046 -19.755612)
		(end 272.179542 -20.295108)
		(width 0.14224)
		(layer "In11.Cu")
		(net "M_A_MA<15>")
	)
	(segment
		(start 267.456412 -31.942786)
		(end 267.456412 -32.567118)
		(width 0.14224)
		(layer "In11.Cu")
		(net "M_A_MA<15>")
	)
	(segment
		(start 272.100548 -25.390094)
		(end 272.633948 -25.923494)
		(width 0.14224)
		(layer "In11.Cu")
		(net "M_A_MA<15>")
	)
	(segment
		(start 265.495024 -49.14392)
		(end 264.812272 -50.325528)
		(width 0.0889)
		(layer "In11.Cu")
		(net "M_A_MA<15>")
	)
	(segment
		(start 272.049748 -24.08301)
		(end 272.204688 -24.23795)
		(width 0.14224)
		(layer "In11.Cu")
		(net "M_A_MA<15>")
	)
	(segment
		(start 265.698224 -33.883092)
		(end 265.495024 -34.086292)
		(width 0.14224)
		(layer "In11.Cu")
		(net "M_A_MA<15>")
	)
	(segment
		(start 272.050256 -17.103344)
		(end 271.538954 -17.614646)
		(width 0.14224)
		(layer "In11.Cu")
		(net "M_A_MA<15>")
	)
	(segment
		(start 264.812272 -50.325528)
		(end 264.1854 -50.9524)
		(width 0.0889)
		(layer "In11.Cu")
		(net "M_A_MA<15>")
	)
	(segment
		(start 265.495024 -48.610774)
		(end 265.495024 -49.14392)
		(width 0.0889)
		(layer "In11.Cu")
		(net "M_A_MA<15>")
	)
	(segment
		(start 265.495024 -34.086292)
		(end 265.495024 -48.610774)
		(width 0.14224)
		(layer "In11.Cu")
		(net "M_A_MA<15>")
	)
	(segment
		(start 272.603468 -24.639778)
		(end 272.443956 -24.79929)
		(width 0.14224)
		(layer "In11.Cu")
		(net "M_A_MA<15>")
	)
	(segment
		(start 271.640046 -18.344388)
		(end 271.640046 -19.755612)
		(width 0.14224)
		(layer "In11.Cu")
		(net "M_A_MA<15>")
	)
	(segment
		(start 267.202666 -32.820864)
		(end 266.578334 -32.820864)
		(width 0.14224)
		(layer "In11.Cu")
		(net "M_A_MA<15>")
	)
	(segment
		(start 267.727938 -31.67126)
		(end 267.456412 -31.942786)
		(width 0.14224)
		(layer "In11.Cu")
		(net "M_A_MA<15>")
	)
	(segment
		(start 272.179542 -20.295108)
		(end 272.179542 -23.430484)
		(width 0.14224)
		(layer "In11.Cu")
		(net "M_A_MA<15>")
	)
	(segment
		(start 271.538954 -17.614646)
		(end 271.538954 -18.243296)
		(width 0.14224)
		(layer "In11.Cu")
		(net "M_A_MA<15>")
	)
	(segment
		(start 264.344404 -52.914804)
		(end 264.344404 -53.24602)
		(width 0.0889)
		(layer "In11.Cu")
		(net "M_A_MA<15>")
	)
	(segment
		(start 272.443956 -24.79929)
		(end 272.255488 -24.79929)
		(width 0.14224)
		(layer "In11.Cu")
		(net "M_A_MA<15>")
	)
	(segment
		(start 272.633948 -27.389582)
		(end 269.501874 -30.521656)
		(width 0.14224)
		(layer "In11.Cu")
		(net "M_A_MA<15>")
	)
	(segment
		(start 268.877542 -30.521656)
		(end 268.62278 -30.776418)
		(width 0.14224)
		(layer "In11.Cu")
		(net "M_A_MA<15>")
	)
	(segment
		(start 272.633948 -25.923494)
		(end 272.633948 -27.389582)
		(width 0.14224)
		(layer "In11.Cu")
		(net "M_A_MA<15>")
	)
	(segment
		(start 272.4531 -24.23795)
		(end 272.603468 -24.388318)
		(width 0.14224)
		(layer "In11.Cu")
		(net "M_A_MA<15>")
	)
	(segment
		(start 272.179542 -23.430484)
		(end 272.049748 -23.560278)
		(width 0.14224)
		(layer "In11.Cu")
		(net "M_A_MA<15>")
	)
	(segment
		(start 272.050256 -16.718788)
		(end 272.050256 -17.103344)
		(width 0.14224)
		(layer "In11.Cu")
		(net "M_A_MA<15>")
	)
	(segment
		(start 268.35227 -31.67126)
		(end 267.727938 -31.67126)
		(width 0.14224)
		(layer "In11.Cu")
		(net "M_A_MA<15>")
	)
	(segment
		(start 267.456412 -32.567118)
		(end 267.202666 -32.820864)
		(width 0.14224)
		(layer "In11.Cu")
		(net "M_A_MA<15>")
	)
	(segment
		(start 272.255488 -24.79929)
		(end 272.100548 -24.95423)
		(width 0.14224)
		(layer "In11.Cu")
		(net "M_A_MA<15>")
	)
	(segment
		(start 272.204688 -24.23795)
		(end 272.4531 -24.23795)
		(width 0.14224)
		(layer "In11.Cu")
		(net "M_A_MA<15>")
	)
	(segment
		(start 268.62278 -31.40075)
		(end 268.35227 -31.67126)
		(width 0.14224)
		(layer "In11.Cu")
		(net "M_A_MA<15>")
	)
	(segment
		(start 269.501874 -30.521656)
		(end 268.877542 -30.521656)
		(width 0.14224)
		(layer "In11.Cu")
		(net "M_A_MA<15>")
	)
	(segment
		(start 272.049748 -23.560278)
		(end 272.049748 -24.08301)
		(width 0.14224)
		(layer "In11.Cu")
		(net "M_A_MA<15>")
	)
	(segment
		(start 272.603468 -24.388318)
		(end 272.603468 -24.639778)
		(width 0.14224)
		(layer "In11.Cu")
		(net "M_A_MA<15>")
	)
	(segment
		(start 266.578334 -32.820864)
		(end 266.306808 -33.09239)
		(width 0.14224)
		(layer "In11.Cu")
		(net "M_A_MA<15>")
	)
	(segment
		(start 268.056614 -26.535888)
		(end 268.056614 -25.795986)
		(width 0.1651)
		(layer "F.Cu")
		(net "M_A_MA<14>")
	)
	(segment
		(start 263.239504 -50.574194)
		(end 263.239504 -49.38395)
		(width 0.0889)
		(layer "F.Cu")
		(net "M_A_MA<14>")
	)
	(segment
		(start 268.533118 -25.319482)
		(end 269.558262 -25.319482)
		(width 0.1651)
		(layer "F.Cu")
		(net "M_A_MA<14>")
	)
	(segment
		(start 268.056614 -27.497786)
		(end 268.056614 -26.535888)
		(width 0.1651)
		(layer "F.Cu")
		(net "M_A_MA<14>")
	)
	(segment
		(start 269.558262 -25.319482)
		(end 270.921734 -23.95601)
		(width 0.1651)
		(layer "F.Cu")
		(net "M_A_MA<14>")
	)
	(segment
		(start 264.64895 -30.90545)
		(end 268.056614 -27.497786)
		(width 0.1651)
		(layer "F.Cu")
		(net "M_A_MA<14>")
	)
	(segment
		(start 270.921734 -23.95601)
		(end 270.921734 -23.322534)
		(width 0.1651)
		(layer "F.Cu")
		(net "M_A_MA<14>")
	)
	(segment
		(start 263.31545 -50.848006)
		(end 263.3091 -50.837338)
		(width 0.0889)
		(layer "F.Cu")
		(net "M_A_MA<14>")
	)
	(segment
		(start 264.64895 -47.501302)
		(end 264.64895 -30.90545)
		(width 0.1651)
		(layer "F.Cu")
		(net "M_A_MA<14>")
	)
	(segment
		(start 262.79729 -52.12334)
		(end 263.25449 -51.66614)
		(width 0.0889)
		(layer "F.Cu")
		(net "M_A_MA<14>")
	)
	(segment
		(start 270.34998 -18.734532)
		(end 270.350234 -18.734278)
		(width 0.1651)
		(layer "F.Cu")
		(net "M_A_MA<14>")
	)
	(segment
		(start 263.3091 -50.837338)
		(end 263.304274 -50.828702)
		(width 0.0889)
		(layer "F.Cu")
		(net "M_A_MA<14>")
	)
	(segment
		(start 270.34998 -20.023582)
		(end 270.34998 -18.734532)
		(width 0.1651)
		(layer "F.Cu")
		(net "M_A_MA<14>")
	)
	(segment
		(start 270.921734 -23.322534)
		(end 270.7386 -23.1394)
		(width 0.1651)
		(layer "F.Cu")
		(net "M_A_MA<14>")
	)
	(segment
		(start 263.239504 -49.38395)
		(end 264.64895 -47.974504)
		(width 0.0889)
		(layer "F.Cu")
		(net "M_A_MA<14>")
	)
	(segment
		(start 270.7386 -22.586442)
		(end 270.349726 -22.197568)
		(width 0.1651)
		(layer "F.Cu")
		(net "M_A_MA<14>")
	)
	(segment
		(start 264.64895 -47.974504)
		(end 264.64895 -47.501302)
		(width 0.0889)
		(layer "F.Cu")
		(net "M_A_MA<14>")
	)
	(segment
		(start 270.350488 -20.023582)
		(end 270.34998 -20.023582)
		(width 0.1651)
		(layer "F.Cu")
		(net "M_A_MA<14>")
	)
	(segment
		(start 263.25449 -51.66614)
		(end 263.25449 -51.573684)
		(width 0.0889)
		(layer "F.Cu")
		(net "M_A_MA<14>")
	)
	(segment
		(start 270.7386 -23.1394)
		(end 270.7386 -22.586442)
		(width 0.1651)
		(layer "F.Cu")
		(net "M_A_MA<14>")
	)
	(segment
		(start 268.056614 -25.795986)
		(end 268.533118 -25.319482)
		(width 0.1651)
		(layer "F.Cu")
		(net "M_A_MA<14>")
	)
	(via
		(at 270.350234 -18.734278)
		(size 0.4572)
		(drill 0.2032)
		(layers "F.Cu" "B.Cu")
		(net "M_A_MA<14>")
	)
	(via
		(at 268.056614 -26.535888)
		(size 0.508)
		(drill 0.254)
		(layers "F.Cu" "B.Cu")
		(net "M_A_MA<14>")
	)
	(via
		(at 270.349726 -22.197568)
		(size 0.508)
		(drill 0.254)
		(layers "F.Cu" "B.Cu")
		(net "M_A_MA<14>")
	)
	(arc
		(start 263.304274 -50.828702)
		(mid 263.255925 -50.705509)
		(end 263.239504 -50.574194)
		(width 0.0889)
		(layer "F.Cu")
		(net "M_A_MA<14>")
	)
	(arc
		(start 263.25449 -51.573684)
		(mid 263.275767 -51.498529)
		(end 263.3091 -51.427888)
		(width 0.0889)
		(layer "F.Cu")
		(net "M_A_MA<14>")
	)
	(arc
		(start 263.3091 -51.427888)
		(mid 263.388322 -51.13877)
		(end 263.31545 -50.848006)
		(width 0.0889)
		(layer "F.Cu")
		(net "M_A_MA<14>")
	)
	(segment
		(start 270.350488 -20.224242)
		(end 270.350488 -22.196806)
		(width 0.1651)
		(layer "B.Cu")
		(net "M_A_MA<14>")
	)
	(segment
		(start 270.350488 -22.196806)
		(end 270.349726 -22.197568)
		(width 0.1651)
		(layer "B.Cu")
		(net "M_A_MA<14>")
	)
	(segment
		(start 268.983968 -19.73453)
		(end 268.983968 -19.48307)
		(width 0.14224)
		(layer "In9.Cu")
		(net "M_A_MA<14>")
	)
	(segment
		(start 270.067024 -19.88947)
		(end 269.138908 -19.88947)
		(width 0.14224)
		(layer "In9.Cu")
		(net "M_A_MA<14>")
	)
	(segment
		(start 269.17904 -21.01215)
		(end 269.005812 -20.838922)
		(width 0.14224)
		(layer "In9.Cu")
		(net "M_A_MA<14>")
	)
	(segment
		(start 269.142464 -20.45081)
		(end 270.067024 -20.45081)
		(width 0.14224)
		(layer "In9.Cu")
		(net "M_A_MA<14>")
	)
	(segment
		(start 269.005812 -20.587462)
		(end 269.142464 -20.45081)
		(width 0.14224)
		(layer "In9.Cu")
		(net "M_A_MA<14>")
	)
	(segment
		(start 270.221964 -20.04441)
		(end 270.067024 -19.88947)
		(width 0.14224)
		(layer "In9.Cu")
		(net "M_A_MA<14>")
	)
	(segment
		(start 270.067024 -20.45081)
		(end 270.221964 -20.29587)
		(width 0.14224)
		(layer "In9.Cu")
		(net "M_A_MA<14>")
	)
	(segment
		(start 270.350234 -19.1516)
		(end 270.350234 -18.734278)
		(width 0.14224)
		(layer "In9.Cu")
		(net "M_A_MA<14>")
	)
	(segment
		(start 268.983968 -19.48307)
		(end 269.138908 -19.32813)
		(width 0.14224)
		(layer "In9.Cu")
		(net "M_A_MA<14>")
	)
	(segment
		(start 269.138908 -19.88947)
		(end 268.983968 -19.73453)
		(width 0.14224)
		(layer "In9.Cu")
		(net "M_A_MA<14>")
	)
	(segment
		(start 270.173704 -19.32813)
		(end 270.350234 -19.1516)
		(width 0.14224)
		(layer "In9.Cu")
		(net "M_A_MA<14>")
	)
	(segment
		(start 270.160496 -22.008338)
		(end 270.160496 -21.203158)
		(width 0.14224)
		(layer "In9.Cu")
		(net "M_A_MA<14>")
	)
	(segment
		(start 269.005812 -20.838922)
		(end 269.005812 -20.587462)
		(width 0.14224)
		(layer "In9.Cu")
		(net "M_A_MA<14>")
	)
	(segment
		(start 270.349726 -22.197568)
		(end 270.160496 -22.008338)
		(width 0.14224)
		(layer "In9.Cu")
		(net "M_A_MA<14>")
	)
	(segment
		(start 269.138908 -19.32813)
		(end 270.173704 -19.32813)
		(width 0.14224)
		(layer "In9.Cu")
		(net "M_A_MA<14>")
	)
	(segment
		(start 270.221964 -20.29587)
		(end 270.221964 -20.04441)
		(width 0.14224)
		(layer "In9.Cu")
		(net "M_A_MA<14>")
	)
	(segment
		(start 270.160496 -21.203158)
		(end 269.969488 -21.01215)
		(width 0.14224)
		(layer "In9.Cu")
		(net "M_A_MA<14>")
	)
	(segment
		(start 269.969488 -21.01215)
		(end 269.17904 -21.01215)
		(width 0.14224)
		(layer "In9.Cu")
		(net "M_A_MA<14>")
	)
	(segment
		(start 265.372596 -53.60924)
		(end 264.801096 -53.60924)
		(width 0.1016)
		(layer "F.Cu")
		(net "M_A_MA<13>")
	)
	(segment
		(start 273.74977 -18.734786)
		(end 273.750278 -18.734278)
		(width 0.1651)
		(layer "F.Cu")
		(net "M_A_MA<13>")
	)
	(segment
		(start 273.750278 -20.023582)
		(end 273.74977 -20.023582)
		(width 0.1651)
		(layer "F.Cu")
		(net "M_A_MA<13>")
	)
	(segment
		(start 273.74977 -20.023582)
		(end 273.74977 -18.734786)
		(width 0.1651)
		(layer "F.Cu")
		(net "M_A_MA<13>")
	)
	(via
		(at 273.74977 -22.197568)
		(size 0.508)
		(drill 0.254)
		(layers "F.Cu" "B.Cu")
		(net "M_A_MA<13>")
	)
	(via
		(at 273.750278 -18.734278)
		(size 0.4572)
		(drill 0.2032)
		(layers "F.Cu" "B.Cu")
		(net "M_A_MA<13>")
	)
	(via
		(at 264.801096 -53.60924)
		(size 0.508)
		(drill 0.254)
		(layers "F.Cu" "B.Cu")
		(net "M_A_MA<13>")
	)
	(segment
		(start 273.750278 -20.224242)
		(end 273.74977 -20.224242)
		(width 0.1651)
		(layer "B.Cu")
		(net "M_A_MA<13>")
	)
	(segment
		(start 273.74977 -20.224242)
		(end 273.74977 -22.197568)
		(width 0.1651)
		(layer "B.Cu")
		(net "M_A_MA<13>")
	)
	(segment
		(start 273.6596 -22.4536)
		(end 273.74977 -22.36343)
		(width 0.14224)
		(layer "In11.Cu")
		(net "M_A_MA<13>")
	)
	(segment
		(start 272.639028 -20.730464)
		(end 272.639028 -20.479004)
		(width 0.14224)
		(layer "In11.Cu")
		(net "M_A_MA<13>")
	)
	(segment
		(start 264.4013 -52.6923)
		(end 264.4013 -51.045364)
		(width 0.0889)
		(layer "In11.Cu")
		(net "M_A_MA<13>")
	)
	(segment
		(start 272.082006 -19.594322)
		(end 272.082006 -19.342862)
		(width 0.14224)
		(layer "In11.Cu")
		(net "M_A_MA<13>")
	)
	(segment
		(start 272.793968 -20.885404)
		(end 272.639028 -20.730464)
		(width 0.14224)
		(layer "In11.Cu")
		(net "M_A_MA<13>")
	)
	(segment
		(start 273.809968 -20.178014)
		(end 273.809968 -19.926554)
		(width 0.14224)
		(layer "In11.Cu")
		(net "M_A_MA<13>")
	)
	(segment
		(start 266.003024 -34.739072)
		(end 273.141948 -27.600148)
		(width 0.14224)
		(layer "In11.Cu")
		(net "M_A_MA<13>")
	)
	(segment
		(start 272.639028 -20.479004)
		(end 272.793968 -20.324064)
		(width 0.14224)
		(layer "In11.Cu")
		(net "M_A_MA<13>")
	)
	(segment
		(start 273.663918 -20.324064)
		(end 273.809968 -20.178014)
		(width 0.14224)
		(layer "In11.Cu")
		(net "M_A_MA<13>")
	)
	(segment
		(start 266.003024 -48.506126)
		(end 266.003024 -34.739072)
		(width 0.14224)
		(layer "In11.Cu")
		(net "M_A_MA<13>")
	)
	(segment
		(start 273.750278 -19.050254)
		(end 273.750278 -18.734278)
		(width 0.14224)
		(layer "In11.Cu")
		(net "M_A_MA<13>")
	)
	(segment
		(start 273.74977 -22.36343)
		(end 273.74977 -22.197568)
		(width 0.14224)
		(layer "In11.Cu")
		(net "M_A_MA<13>")
	)
	(segment
		(start 264.4013 -51.045364)
		(end 265.032998 -50.413666)
		(width 0.0889)
		(layer "In11.Cu")
		(net "M_A_MA<13>")
	)
	(segment
		(start 272.250408 -19.762724)
		(end 272.082006 -19.594322)
		(width 0.14224)
		(layer "In11.Cu")
		(net "M_A_MA<13>")
	)
	(segment
		(start 273.3294 -25.8318)
		(end 273.3294 -23.7998)
		(width 0.14224)
		(layer "In11.Cu")
		(net "M_A_MA<13>")
	)
	(segment
		(start 264.5918 -52.8828)
		(end 264.4013 -52.6923)
		(width 0.0889)
		(layer "In11.Cu")
		(net "M_A_MA<13>")
	)
	(segment
		(start 273.672808 -21.040344)
		(end 273.517868 -20.885404)
		(width 0.14224)
		(layer "In11.Cu")
		(net "M_A_MA<13>")
	)
	(segment
		(start 273.141948 -26.019252)
		(end 273.3294 -25.8318)
		(width 0.14224)
		(layer "In11.Cu")
		(net "M_A_MA<13>")
	)
	(segment
		(start 273.221958 -23.692358)
		(end 273.221958 -23.323042)
		(width 0.14224)
		(layer "In11.Cu")
		(net "M_A_MA<13>")
	)
	(segment
		(start 272.223484 -19.201384)
		(end 273.599148 -19.201384)
		(width 0.14224)
		(layer "In11.Cu")
		(net "M_A_MA<13>")
	)
	(segment
		(start 273.672808 -22.120606)
		(end 273.672808 -21.040344)
		(width 0.14224)
		(layer "In11.Cu")
		(net "M_A_MA<13>")
	)
	(segment
		(start 266.003024 -48.73371)
		(end 266.003024 -48.506126)
		(width 0.0889)
		(layer "In11.Cu")
		(net "M_A_MA<13>")
	)
	(segment
		(start 272.082006 -19.342862)
		(end 272.223484 -19.201384)
		(width 0.14224)
		(layer "In11.Cu")
		(net "M_A_MA<13>")
	)
	(segment
		(start 273.646138 -19.762724)
		(end 272.250408 -19.762724)
		(width 0.14224)
		(layer "In11.Cu")
		(net "M_A_MA<13>")
	)
	(segment
		(start 272.793968 -20.324064)
		(end 273.663918 -20.324064)
		(width 0.14224)
		(layer "In11.Cu")
		(net "M_A_MA<13>")
	)
	(segment
		(start 264.801096 -53.60924)
		(end 264.5918 -53.399944)
		(width 0.0889)
		(layer "In11.Cu")
		(net "M_A_MA<13>")
	)
	(segment
		(start 273.3294 -23.7998)
		(end 273.221958 -23.692358)
		(width 0.14224)
		(layer "In11.Cu")
		(net "M_A_MA<13>")
	)
	(segment
		(start 273.517868 -20.885404)
		(end 272.793968 -20.885404)
		(width 0.14224)
		(layer "In11.Cu")
		(net "M_A_MA<13>")
	)
	(segment
		(start 264.5918 -53.399944)
		(end 264.5918 -52.8828)
		(width 0.0889)
		(layer "In11.Cu")
		(net "M_A_MA<13>")
	)
	(segment
		(start 273.221958 -23.323042)
		(end 273.6596 -22.8854)
		(width 0.14224)
		(layer "In11.Cu")
		(net "M_A_MA<13>")
	)
	(segment
		(start 273.599148 -19.201384)
		(end 273.750278 -19.050254)
		(width 0.14224)
		(layer "In11.Cu")
		(net "M_A_MA<13>")
	)
	(segment
		(start 273.141948 -27.600148)
		(end 273.141948 -26.019252)
		(width 0.14224)
		(layer "In11.Cu")
		(net "M_A_MA<13>")
	)
	(segment
		(start 265.032998 -50.413666)
		(end 266.003024 -48.73371)
		(width 0.0889)
		(layer "In11.Cu")
		(net "M_A_MA<13>")
	)
	(segment
		(start 273.809968 -19.926554)
		(end 273.646138 -19.762724)
		(width 0.14224)
		(layer "In11.Cu")
		(net "M_A_MA<13>")
	)
	(segment
		(start 273.74977 -22.197568)
		(end 273.672808 -22.120606)
		(width 0.14224)
		(layer "In11.Cu")
		(net "M_A_MA<13>")
	)
	(segment
		(start 273.6596 -22.8854)
		(end 273.6596 -22.4536)
		(width 0.14224)
		(layer "In11.Cu")
		(net "M_A_MA<13>")
	)
	(segment
		(start 249.099832 -15.423642)
		(end 249.099832 -16.716756)
		(width 0.1651)
		(layer "F.Cu")
		(net "M_A_MA<12>")
	)
	(segment
		(start 251.636784 -53.400706)
		(end 251.923804 -53.113686)
		(width 0.1651)
		(layer "F.Cu")
		(net "M_A_MA<12>")
	)
	(segment
		(start 249.10034 -15.423642)
		(end 249.099832 -15.423642)
		(width 0.1651)
		(layer "F.Cu")
		(net "M_A_MA<12>")
	)
	(segment
		(start 251.636784 -53.60924)
		(end 251.636784 -53.400706)
		(width 0.1651)
		(layer "F.Cu")
		(net "M_A_MA<12>")
	)
	(via
		(at 251.923804 -53.113686)
		(size 0.508)
		(drill 0.254)
		(layers "F.Cu" "B.Cu")
		(net "M_A_MA<12>")
	)
	(via
		(at 249.099832 -16.716756)
		(size 0.4572)
		(drill 0.2032)
		(layers "F.Cu" "B.Cu")
		(net "M_A_MA<12>")
	)
	(via
		(at 249.099832 -22.850856)
		(size 0.508)
		(drill 0.254)
		(layers "F.Cu" "B.Cu")
		(net "M_A_MA<12>")
	)
	(segment
		(start 249.10034 -24.824182)
		(end 249.099832 -24.824182)
		(width 0.1651)
		(layer "B.Cu")
		(net "M_A_MA<12>")
	)
	(segment
		(start 249.099832 -24.824182)
		(end 249.099832 -22.850856)
		(width 0.1651)
		(layer "B.Cu")
		(net "M_A_MA<12>")
	)
	(segment
		(start 249.099832 -22.850856)
		(end 248.8184 -23.132288)
		(width 0.14224)
		(layer "In11.Cu")
		(net "M_A_MA<12>")
	)
	(segment
		(start 249.099832 -17.276572)
		(end 248.901966 -17.474438)
		(width 0.14224)
		(layer "In11.Cu")
		(net "M_A_MA<12>")
	)
	(segment
		(start 248.52122 -21.678392)
		(end 249.099832 -22.257004)
		(width 0.14224)
		(layer "In11.Cu")
		(net "M_A_MA<12>")
	)
	(segment
		(start 248.901966 -17.474438)
		(end 248.115328 -17.474438)
		(width 0.14224)
		(layer "In11.Cu")
		(net "M_A_MA<12>")
	)
	(segment
		(start 252.119384 -51.002184)
		(end 252.371352 -51.254152)
		(width 0.0889)
		(layer "In11.Cu")
		(net "M_A_MA<12>")
	)
	(segment
		(start 249.099832 -16.716756)
		(end 249.099832 -17.276572)
		(width 0.14224)
		(layer "In11.Cu")
		(net "M_A_MA<12>")
	)
	(segment
		(start 248.7676 -30.208728)
		(end 252.119384 -33.560512)
		(width 0.14224)
		(layer "In11.Cu")
		(net "M_A_MA<12>")
	)
	(segment
		(start 249.1867 -27.0764)
		(end 248.7676 -27.4955)
		(width 0.14224)
		(layer "In11.Cu")
		(net "M_A_MA<12>")
	)
	(segment
		(start 252.371352 -51.254152)
		(end 252.371352 -52.666138)
		(width 0.0889)
		(layer "In11.Cu")
		(net "M_A_MA<12>")
	)
	(segment
		(start 247.960388 -17.629378)
		(end 247.960388 -17.982438)
		(width 0.14224)
		(layer "In11.Cu")
		(net "M_A_MA<12>")
	)
	(segment
		(start 252.119384 -33.560512)
		(end 252.119384 -50.700432)
		(width 0.14224)
		(layer "In11.Cu")
		(net "M_A_MA<12>")
	)
	(segment
		(start 248.510044 -18.137378)
		(end 248.664984 -18.292318)
		(width 0.14224)
		(layer "In11.Cu")
		(net "M_A_MA<12>")
	)
	(segment
		(start 248.115328 -18.137378)
		(end 248.510044 -18.137378)
		(width 0.14224)
		(layer "In11.Cu")
		(net "M_A_MA<12>")
	)
	(segment
		(start 248.664984 -20.561554)
		(end 248.52122 -20.705318)
		(width 0.14224)
		(layer "In11.Cu")
		(net "M_A_MA<12>")
	)
	(segment
		(start 249.099832 -22.257004)
		(end 249.099832 -22.850856)
		(width 0.14224)
		(layer "In11.Cu")
		(net "M_A_MA<12>")
	)
	(segment
		(start 248.8184 -24.7142)
		(end 249.1867 -25.0825)
		(width 0.14224)
		(layer "In11.Cu")
		(net "M_A_MA<12>")
	)
	(segment
		(start 252.371352 -52.666138)
		(end 251.923804 -53.113686)
		(width 0.0889)
		(layer "In11.Cu")
		(net "M_A_MA<12>")
	)
	(segment
		(start 247.960388 -17.982438)
		(end 248.115328 -18.137378)
		(width 0.14224)
		(layer "In11.Cu")
		(net "M_A_MA<12>")
	)
	(segment
		(start 248.7676 -27.4955)
		(end 248.7676 -30.208728)
		(width 0.14224)
		(layer "In11.Cu")
		(net "M_A_MA<12>")
	)
	(segment
		(start 249.1867 -25.0825)
		(end 249.1867 -27.0764)
		(width 0.14224)
		(layer "In11.Cu")
		(net "M_A_MA<12>")
	)
	(segment
		(start 248.8184 -23.132288)
		(end 248.8184 -24.7142)
		(width 0.14224)
		(layer "In11.Cu")
		(net "M_A_MA<12>")
	)
	(segment
		(start 248.52122 -20.705318)
		(end 248.52122 -21.678392)
		(width 0.14224)
		(layer "In11.Cu")
		(net "M_A_MA<12>")
	)
	(segment
		(start 248.115328 -17.474438)
		(end 247.960388 -17.629378)
		(width 0.14224)
		(layer "In11.Cu")
		(net "M_A_MA<12>")
	)
	(segment
		(start 252.119384 -50.700432)
		(end 252.119384 -51.002184)
		(width 0.0889)
		(layer "In11.Cu")
		(net "M_A_MA<12>")
	)
	(segment
		(start 248.664984 -18.292318)
		(end 248.664984 -20.561554)
		(width 0.14224)
		(layer "In11.Cu")
		(net "M_A_MA<12>")
	)
	(segment
		(start 253.353824 -52.618386)
		(end 252.782324 -52.618386)
		(width 0.1016)
		(layer "F.Cu")
		(net "M_A_MA<11>")
	)
	(segment
		(start 249.94997 -20.023582)
		(end 249.94997 -18.734278)
		(width 0.1651)
		(layer "F.Cu")
		(net "M_A_MA<11>")
	)
	(segment
		(start 249.950478 -20.023582)
		(end 249.94997 -20.023582)
		(width 0.1651)
		(layer "F.Cu")
		(net "M_A_MA<11>")
	)
	(via
		(at 252.782324 -52.618386)
		(size 0.508)
		(drill 0.254)
		(layers "F.Cu" "B.Cu")
		(net "M_A_MA<11>")
	)
	(via
		(at 249.94997 -22.197568)
		(size 0.508)
		(drill 0.254)
		(layers "F.Cu" "B.Cu")
		(net "M_A_MA<11>")
	)
	(via
		(at 249.94997 -18.734278)
		(size 0.4572)
		(drill 0.2032)
		(layers "F.Cu" "B.Cu")
		(net "M_A_MA<11>")
	)
	(segment
		(start 249.950478 -20.224242)
		(end 249.94997 -20.224242)
		(width 0.1651)
		(layer "B.Cu")
		(net "M_A_MA<11>")
	)
	(segment
		(start 249.94997 -20.224242)
		(end 249.94997 -22.197568)
		(width 0.1651)
		(layer "B.Cu")
		(net "M_A_MA<11>")
	)
	(segment
		(start 253.193804 -52.206906)
		(end 253.193804 -51.467258)
		(width 0.0889)
		(layer "In11.Cu")
		(net "M_A_MA<11>")
	)
	(segment
		(start 253.193804 -51.467258)
		(end 252.627384 -50.900838)
		(width 0.0889)
		(layer "In11.Cu")
		(net "M_A_MA<11>")
	)
	(segment
		(start 252.627384 -50.900838)
		(end 252.627384 -50.672492)
		(width 0.0889)
		(layer "In11.Cu")
		(net "M_A_MA<11>")
	)
	(segment
		(start 249.3518 -27.660346)
		(end 249.8598 -27.152346)
		(width 0.14224)
		(layer "In11.Cu")
		(net "M_A_MA<11>")
	)
	(segment
		(start 249.6312 -23.114)
		(end 249.6312 -22.516338)
		(width 0.14224)
		(layer "In11.Cu")
		(net "M_A_MA<11>")
	)
	(segment
		(start 249.651774 -21.899372)
		(end 249.651774 -19.032474)
		(width 0.14224)
		(layer "In11.Cu")
		(net "M_A_MA<11>")
	)
	(segment
		(start 249.3518 -30.074362)
		(end 249.3518 -27.660346)
		(width 0.14224)
		(layer "In11.Cu")
		(net "M_A_MA<11>")
	)
	(segment
		(start 249.428 -23.3172)
		(end 249.6312 -23.114)
		(width 0.14224)
		(layer "In11.Cu")
		(net "M_A_MA<11>")
	)
	(segment
		(start 249.6312 -22.516338)
		(end 249.94997 -22.197568)
		(width 0.14224)
		(layer "In11.Cu")
		(net "M_A_MA<11>")
	)
	(segment
		(start 249.94997 -22.197568)
		(end 249.651774 -21.899372)
		(width 0.14224)
		(layer "In11.Cu")
		(net "M_A_MA<11>")
	)
	(segment
		(start 252.627384 -50.672492)
		(end 252.627384 -33.349946)
		(width 0.14224)
		(layer "In11.Cu")
		(net "M_A_MA<11>")
	)
	(segment
		(start 252.782324 -52.618386)
		(end 253.193804 -52.206906)
		(width 0.0889)
		(layer "In11.Cu")
		(net "M_A_MA<11>")
	)
	(segment
		(start 249.428 -24.316944)
		(end 249.428 -23.3172)
		(width 0.14224)
		(layer "In11.Cu")
		(net "M_A_MA<11>")
	)
	(segment
		(start 249.8598 -27.152346)
		(end 249.8598 -24.748744)
		(width 0.14224)
		(layer "In11.Cu")
		(net "M_A_MA<11>")
	)
	(segment
		(start 252.627384 -33.349946)
		(end 249.3518 -30.074362)
		(width 0.14224)
		(layer "In11.Cu")
		(net "M_A_MA<11>")
	)
	(segment
		(start 249.8598 -24.748744)
		(end 249.428 -24.316944)
		(width 0.14224)
		(layer "In11.Cu")
		(net "M_A_MA<11>")
	)
	(segment
		(start 249.651774 -19.032474)
		(end 249.94997 -18.734278)
		(width 0.14224)
		(layer "In11.Cu")
		(net "M_A_MA<11>")
	)
	(segment
		(start 267.800328 -20.023582)
		(end 267.79982 -20.023582)
		(width 0.1651)
		(layer "F.Cu")
		(net "M_A_MA<10>")
	)
	(segment
		(start 267.79982 -20.023582)
		(end 267.79982 -18.734532)
		(width 0.1651)
		(layer "F.Cu")
		(net "M_A_MA<10>")
	)
	(segment
		(start 260.22173 -53.60924)
		(end 259.65023 -53.60924)
		(width 0.1016)
		(layer "F.Cu")
		(net "M_A_MA<10>")
	)
	(segment
		(start 267.79982 -18.734532)
		(end 267.800074 -18.734278)
		(width 0.1651)
		(layer "F.Cu")
		(net "M_A_MA<10>")
	)
	(via
		(at 267.800074 -18.734278)
		(size 0.4572)
		(drill 0.2032)
		(layers "F.Cu" "B.Cu")
		(net "M_A_MA<10>")
	)
	(via
		(at 259.65023 -53.60924)
		(size 0.508)
		(drill 0.254)
		(layers "F.Cu" "B.Cu")
		(net "M_A_MA<10>")
	)
	(via
		(at 267.79982 -21.488146)
		(size 0.508)
		(drill 0.254)
		(layers "F.Cu" "B.Cu")
		(net "M_A_MA<10>")
	)
	(segment
		(start 267.800328 -20.224242)
		(end 267.79982 -20.224242)
		(width 0.1651)
		(layer "B.Cu")
		(net "M_A_MA<10>")
	)
	(segment
		(start 267.79982 -20.224242)
		(end 267.79982 -21.488146)
		(width 0.1651)
		(layer "B.Cu")
		(net "M_A_MA<10>")
	)
	(segment
		(start 267.4112 -23.749)
		(end 267.4112 -23.2664)
		(width 0.14224)
		(layer "In11.Cu")
		(net "M_A_MA<10>")
	)
	(segment
		(start 259.65023 -53.609494)
		(end 259.98043 -52.84724)
		(width 0.0889)
		(layer "In11.Cu")
		(net "M_A_MA<10>")
	)
	(segment
		(start 267.800074 -21.487892)
		(end 267.800074 -21.267674)
		(width 0.14224)
		(layer "In11.Cu")
		(net "M_A_MA<10>")
	)
	(segment
		(start 260.063488 -51.769772)
		(end 261.855204 -49.978056)
		(width 0.0889)
		(layer "In11.Cu")
		(net "M_A_MA<10>")
	)
	(segment
		(start 267.800074 -21.267674)
		(end 267.65377 -21.12137)
		(width 0.14224)
		(layer "In11.Cu")
		(net "M_A_MA<10>")
	)
	(segment
		(start 267.335 -23.1902)
		(end 267.335 -22.6314)
		(width 0.14224)
		(layer "In11.Cu")
		(net "M_A_MA<10>")
	)
	(segment
		(start 260.063488 -52.570126)
		(end 260.063488 -51.769772)
		(width 0.0889)
		(layer "In11.Cu")
		(net "M_A_MA<10>")
	)
	(segment
		(start 267.79982 -21.488146)
		(end 267.800074 -21.487892)
		(width 0.14224)
		(layer "In11.Cu")
		(net "M_A_MA<10>")
	)
	(segment
		(start 266.4206 -26.8224)
		(end 266.4206 -25.795224)
		(width 0.14224)
		(layer "In11.Cu")
		(net "M_A_MA<10>")
	)
	(segment
		(start 267.208 -23.9522)
		(end 267.4112 -23.749)
		(width 0.14224)
		(layer "In11.Cu")
		(net "M_A_MA<10>")
	)
	(segment
		(start 266.4206 -25.795224)
		(end 267.208 -25.007824)
		(width 0.14224)
		(layer "In11.Cu")
		(net "M_A_MA<10>")
	)
	(segment
		(start 261.855204 -31.387796)
		(end 266.4206 -26.8224)
		(width 0.14224)
		(layer "In11.Cu")
		(net "M_A_MA<10>")
	)
	(segment
		(start 267.4112 -23.2664)
		(end 267.335 -23.1902)
		(width 0.14224)
		(layer "In11.Cu")
		(net "M_A_MA<10>")
	)
	(segment
		(start 267.65377 -20.243546)
		(end 267.715746 -20.18157)
		(width 0.14224)
		(layer "In11.Cu")
		(net "M_A_MA<10>")
	)
	(segment
		(start 267.715746 -18.818606)
		(end 267.800074 -18.734278)
		(width 0.14224)
		(layer "In11.Cu")
		(net "M_A_MA<10>")
	)
	(segment
		(start 261.855204 -49.978056)
		(end 261.855204 -48.42002)
		(width 0.0889)
		(layer "In11.Cu")
		(net "M_A_MA<10>")
	)
	(segment
		(start 267.65377 -21.12137)
		(end 267.65377 -20.243546)
		(width 0.14224)
		(layer "In11.Cu")
		(net "M_A_MA<10>")
	)
	(segment
		(start 259.65023 -53.60924)
		(end 259.65023 -53.609494)
		(width 0.0889)
		(layer "In11.Cu")
		(net "M_A_MA<10>")
	)
	(segment
		(start 267.208 -25.007824)
		(end 267.208 -23.9522)
		(width 0.14224)
		(layer "In11.Cu")
		(net "M_A_MA<10>")
	)
	(segment
		(start 259.98043 -52.84724)
		(end 259.99694 -52.818792)
		(width 0.0889)
		(layer "In11.Cu")
		(net "M_A_MA<10>")
	)
	(segment
		(start 267.715746 -20.18157)
		(end 267.715746 -18.818606)
		(width 0.14224)
		(layer "In11.Cu")
		(net "M_A_MA<10>")
	)
	(segment
		(start 267.4112 -22.5552)
		(end 267.4112 -21.876766)
		(width 0.14224)
		(layer "In11.Cu")
		(net "M_A_MA<10>")
	)
	(segment
		(start 267.4112 -21.876766)
		(end 267.79982 -21.488146)
		(width 0.14224)
		(layer "In11.Cu")
		(net "M_A_MA<10>")
	)
	(segment
		(start 261.855204 -48.42002)
		(end 261.855204 -31.387796)
		(width 0.14224)
		(layer "In11.Cu")
		(net "M_A_MA<10>")
	)
	(segment
		(start 267.335 -22.6314)
		(end 267.4112 -22.5552)
		(width 0.14224)
		(layer "In11.Cu")
		(net "M_A_MA<10>")
	)
	(arc
		(start 259.99694 -52.818792)
		(mid 260.046565 -52.698835)
		(end 260.063488 -52.570126)
		(width 0.0889)
		(layer "In11.Cu")
		(net "M_A_MA<10>")
	)
	(segment
		(start 262.128 -27.483054)
		(end 262.128 -28.047188)
		(width 0.1651)
		(layer "F.Cu")
		(net "M_A_MA<0>")
	)
	(segment
		(start 262.490204 -48.202596)
		(end 261.700264 -48.992536)
		(width 0.0889)
		(layer "F.Cu")
		(net "M_A_MA<0>")
	)
	(segment
		(start 262.490204 -46.52645)
		(end 262.490204 -48.202596)
		(width 0.0889)
		(layer "F.Cu")
		(net "M_A_MA<0>")
	)
	(segment
		(start 266.099798 -15.423642)
		(end 266.099798 -16.714978)
		(width 0.1651)
		(layer "F.Cu")
		(net "M_A_MA<0>")
	)
	(segment
		(start 261.700264 -48.992536)
		(end 261.700264 -50.308764)
		(width 0.0889)
		(layer "F.Cu")
		(net "M_A_MA<0>")
	)
	(segment
		(start 261.53872 -51.66487)
		(end 261.08025 -52.12334)
		(width 0.0889)
		(layer "F.Cu")
		(net "M_A_MA<0>")
	)
	(segment
		(start 266.100306 -15.423642)
		(end 266.099798 -15.423642)
		(width 0.1651)
		(layer "F.Cu")
		(net "M_A_MA<0>")
	)
	(segment
		(start 262.128 -46.164246)
		(end 262.490204 -46.52645)
		(width 0.0889)
		(layer "F.Cu")
		(net "M_A_MA<0>")
	)
	(segment
		(start 261.700264 -50.308764)
		(end 261.656322 -50.352706)
		(width 0.0889)
		(layer "F.Cu")
		(net "M_A_MA<0>")
	)
	(segment
		(start 262.128 -45.923454)
		(end 262.128 -46.164246)
		(width 0.0889)
		(layer "F.Cu")
		(net "M_A_MA<0>")
	)
	(segment
		(start 265.632438 -23.978616)
		(end 262.128 -27.483054)
		(width 0.1651)
		(layer "F.Cu")
		(net "M_A_MA<0>")
	)
	(segment
		(start 261.53872 -50.648362)
		(end 261.53872 -51.66487)
		(width 0.0889)
		(layer "F.Cu")
		(net "M_A_MA<0>")
	)
	(segment
		(start 266.099798 -22.850856)
		(end 265.632438 -23.978616)
		(width 0.1651)
		(layer "F.Cu")
		(net "M_A_MA<0>")
	)
	(segment
		(start 262.128 -28.047188)
		(end 262.128 -45.923454)
		(width 0.1651)
		(layer "F.Cu")
		(net "M_A_MA<0>")
	)
	(via
		(at 262.128 -28.047188)
		(size 0.508)
		(drill 0.254)
		(layers "F.Cu" "B.Cu")
		(net "M_A_MA<0>")
	)
	(via
		(at 266.099798 -22.850856)
		(size 0.508)
		(drill 0.254)
		(layers "F.Cu" "B.Cu")
		(net "M_A_MA<0>")
	)
	(via
		(at 266.099798 -16.714978)
		(size 0.508)
		(drill 0.254)
		(layers "F.Cu" "B.Cu")
		(net "M_A_MA<0>")
	)
	(arc
		(start 261.656322 -50.352706)
		(mid 261.567063 -50.488419)
		(end 261.53872 -50.648362)
		(width 0.0889)
		(layer "F.Cu")
		(net "M_A_MA<0>")
	)
	(segment
		(start 266.099798 -24.824182)
		(end 266.099798 -22.850856)
		(width 0.1651)
		(layer "B.Cu")
		(net "M_A_MA<0>")
	)
	(segment
		(start 266.100306 -24.824182)
		(end 266.099798 -24.824182)
		(width 0.1651)
		(layer "B.Cu")
		(net "M_A_MA<0>")
	)
	(segment
		(start 266.540742 -17.155922)
		(end 266.099798 -16.714978)
		(width 0.14224)
		(layer "In9.Cu")
		(net "M_A_MA<0>")
	)
	(segment
		(start 266.540742 -21.779484)
		(end 266.540742 -17.155922)
		(width 0.14224)
		(layer "In9.Cu")
		(net "M_A_MA<0>")
	)
	(segment
		(start 266.099798 -22.220428)
		(end 266.540742 -21.779484)
		(width 0.14224)
		(layer "In9.Cu")
		(net "M_A_MA<0>")
	)
	(segment
		(start 266.099798 -22.850856)
		(end 266.099798 -22.220428)
		(width 0.14224)
		(layer "In9.Cu")
		(net "M_A_MA<0>")
	)
	(segment
		(start 239.749838 -15.423642)
		(end 239.749838 -16.687546)
		(width 0.1651)
		(layer "F.Cu")
		(net "M_A_ECC<7>")
	)
	(segment
		(start 249.919744 -62.52464)
		(end 249.348244 -62.52464)
		(width 0.1016)
		(layer "F.Cu")
		(net "M_A_ECC<7>")
	)
	(segment
		(start 239.750346 -15.423642)
		(end 239.749838 -15.423642)
		(width 0.1651)
		(layer "F.Cu")
		(net "M_A_ECC<7>")
	)
	(via
		(at 239.749838 -16.687546)
		(size 0.508)
		(drill 0.254)
		(layers "F.Cu" "B.Cu")
		(net "M_A_ECC<7>")
	)
	(via
		(at 249.348244 -62.52464)
		(size 0.508)
		(drill 0.254)
		(layers "F.Cu" "B.Cu")
		(net "M_A_ECC<7>")
	)
	(via
		(at 240.599722 -22.279356)
		(size 0.508)
		(drill 0.254)
		(layers "F.Cu" "B.Cu")
		(net "M_A_ECC<7>")
	)
	(segment
		(start 240.600484 -20.224242)
		(end 240.600484 -22.278594)
		(width 0.1651)
		(layer "B.Cu")
		(net "M_A_ECC<7>")
	)
	(segment
		(start 240.600484 -22.278594)
		(end 240.599722 -22.279356)
		(width 0.1651)
		(layer "B.Cu")
		(net "M_A_ECC<7>")
	)
	(segment
		(start 241.090196 -26.460196)
		(end 241.090196 -27.540204)
		(width 0.14224)
		(layer "In2.Cu")
		(net "M_A_ECC<7>")
	)
	(segment
		(start 240.840768 -23.899368)
		(end 240.840768 -26.210768)
		(width 0.14224)
		(layer "In2.Cu")
		(net "M_A_ECC<7>")
	)
	(segment
		(start 249.85091 -61.506862)
		(end 249.348244 -62.52464)
		(width 0.0889)
		(layer "In2.Cu")
		(net "M_A_ECC<7>")
	)
	(segment
		(start 248.149364 -56.86552)
		(end 248.143014 -56.876188)
		(width 0.0889)
		(layer "In2.Cu")
		(net "M_A_ECC<7>")
	)
	(segment
		(start 249.860054 -61.238638)
		(end 249.85091 -61.506862)
		(width 0.0889)
		(layer "In2.Cu")
		(net "M_A_ECC<7>")
	)
	(segment
		(start 240.967768 -28.970224)
		(end 240.612168 -29.325824)
		(width 0.14224)
		(layer "In2.Cu")
		(net "M_A_ECC<7>")
	)
	(segment
		(start 240.612168 -29.325824)
		(end 240.612168 -31.40456)
		(width 0.14224)
		(layer "In2.Cu")
		(net "M_A_ECC<7>")
	)
	(segment
		(start 248.362724 -55.504588)
		(end 248.138188 -55.894224)
		(width 0.0889)
		(layer "In2.Cu")
		(net "M_A_ECC<7>")
	)
	(segment
		(start 240.599722 -22.279356)
		(end 240.1316 -22.747478)
		(width 0.14224)
		(layer "In2.Cu")
		(net "M_A_ECC<7>")
	)
	(segment
		(start 249.860054 -58.857388)
		(end 249.855228 -58.866024)
		(width 0.0889)
		(layer "In2.Cu")
		(net "M_A_ECC<7>")
	)
	(segment
		(start 246.77878 -45.10278)
		(end 247.951244 -46.275244)
		(width 0.14224)
		(layer "In2.Cu")
		(net "M_A_ECC<7>")
	)
	(segment
		(start 248.143014 -56.876188)
		(end 248.138188 -56.884824)
		(width 0.0889)
		(layer "In2.Cu")
		(net "M_A_ECC<7>")
	)
	(segment
		(start 239.749838 -16.687546)
		(end 240.066576 -17.004284)
		(width 0.14224)
		(layer "In2.Cu")
		(net "M_A_ECC<7>")
	)
	(segment
		(start 240.754408 -31.5468)
		(end 242.171728 -31.5468)
		(width 0.14224)
		(layer "In2.Cu")
		(net "M_A_ECC<7>")
	)
	(segment
		(start 240.650776 -17.653)
		(end 241.107976 -18.1102)
		(width 0.14224)
		(layer "In2.Cu")
		(net "M_A_ECC<7>")
	)
	(segment
		(start 241.090196 -27.540204)
		(end 240.967768 -27.662632)
		(width 0.14224)
		(layer "In2.Cu")
		(net "M_A_ECC<7>")
	)
	(segment
		(start 240.1316 -22.747478)
		(end 240.1316 -23.1902)
		(width 0.14224)
		(layer "In2.Cu")
		(net "M_A_ECC<7>")
	)
	(segment
		(start 240.952528 -21.92655)
		(end 240.599722 -22.279356)
		(width 0.14224)
		(layer "In2.Cu")
		(net "M_A_ECC<7>")
	)
	(segment
		(start 247.750584 -49.004474)
		(end 247.750584 -49.4157)
		(width 0.0889)
		(layer "In2.Cu")
		(net "M_A_ECC<7>")
	)
	(segment
		(start 241.107976 -18.1102)
		(end 241.107976 -18.4658)
		(width 0.14224)
		(layer "In2.Cu")
		(net "M_A_ECC<7>")
	)
	(segment
		(start 247.750584 -49.4157)
		(end 248.452132 -50.117248)
		(width 0.0889)
		(layer "In2.Cu")
		(net "M_A_ECC<7>")
	)
	(segment
		(start 247.951244 -48.803814)
		(end 247.750584 -49.004474)
		(width 0.0889)
		(layer "In2.Cu")
		(net "M_A_ECC<7>")
	)
	(segment
		(start 240.066576 -17.004284)
		(end 240.066576 -17.3228)
		(width 0.14224)
		(layer "In2.Cu")
		(net "M_A_ECC<7>")
	)
	(segment
		(start 240.396776 -17.653)
		(end 240.650776 -17.653)
		(width 0.14224)
		(layer "In2.Cu")
		(net "M_A_ECC<7>")
	)
	(segment
		(start 248.474738 -57.476136)
		(end 248.502678 -57.476136)
		(width 0.0889)
		(layer "In2.Cu")
		(net "M_A_ECC<7>")
	)
	(segment
		(start 248.656856 -54.143656)
		(end 248.362724 -54.437788)
		(width 0.0889)
		(layer "In2.Cu")
		(net "M_A_ECC<7>")
	)
	(segment
		(start 240.066576 -17.3228)
		(end 240.396776 -17.653)
		(width 0.14224)
		(layer "In2.Cu")
		(net "M_A_ECC<7>")
	)
	(segment
		(start 240.1316 -23.1902)
		(end 240.840768 -23.899368)
		(width 0.14224)
		(layer "In2.Cu")
		(net "M_A_ECC<7>")
	)
	(segment
		(start 249.866404 -60.82792)
		(end 249.860054 -60.838588)
		(width 0.0889)
		(layer "In2.Cu")
		(net "M_A_ECC<7>")
	)
	(segment
		(start 249.866404 -59.83732)
		(end 249.860054 -59.847988)
		(width 0.0889)
		(layer "In2.Cu")
		(net "M_A_ECC<7>")
	)
	(segment
		(start 249.33021 -57.971436)
		(end 249.366024 -57.971436)
		(width 0.0889)
		(layer "In2.Cu")
		(net "M_A_ECC<7>")
	)
	(segment
		(start 242.313968 -31.68904)
		(end 242.313968 -41.433496)
		(width 0.14224)
		(layer "In2.Cu")
		(net "M_A_ECC<7>")
	)
	(segment
		(start 248.452132 -50.81905)
		(end 248.656856 -51.023774)
		(width 0.0889)
		(layer "In2.Cu")
		(net "M_A_ECC<7>")
	)
	(segment
		(start 240.967768 -27.662632)
		(end 240.967768 -28.970224)
		(width 0.14224)
		(layer "In2.Cu")
		(net "M_A_ECC<7>")
	)
	(segment
		(start 240.952528 -18.621248)
		(end 240.952528 -21.92655)
		(width 0.14224)
		(layer "In2.Cu")
		(net "M_A_ECC<7>")
	)
	(segment
		(start 249.860054 -59.847988)
		(end 249.855228 -59.856624)
		(width 0.0889)
		(layer "In2.Cu")
		(net "M_A_ECC<7>")
	)
	(segment
		(start 242.313968 -41.433496)
		(end 245.983252 -45.10278)
		(width 0.14224)
		(layer "In2.Cu")
		(net "M_A_ECC<7>")
	)
	(segment
		(start 248.452132 -50.117248)
		(end 248.452132 -50.81905)
		(width 0.0889)
		(layer "In2.Cu")
		(net "M_A_ECC<7>")
	)
	(segment
		(start 240.612168 -31.40456)
		(end 240.754408 -31.5468)
		(width 0.14224)
		(layer "In2.Cu")
		(net "M_A_ECC<7>")
	)
	(segment
		(start 240.840768 -26.210768)
		(end 241.090196 -26.460196)
		(width 0.14224)
		(layer "In2.Cu")
		(net "M_A_ECC<7>")
	)
	(segment
		(start 247.951244 -46.275244)
		(end 247.951244 -48.803814)
		(width 0.14224)
		(layer "In2.Cu")
		(net "M_A_ECC<7>")
	)
	(segment
		(start 242.171728 -31.5468)
		(end 242.313968 -31.68904)
		(width 0.14224)
		(layer "In2.Cu")
		(net "M_A_ECC<7>")
	)
	(segment
		(start 248.656856 -51.023774)
		(end 248.656856 -54.143656)
		(width 0.0889)
		(layer "In2.Cu")
		(net "M_A_ECC<7>")
	)
	(segment
		(start 245.983252 -45.10278)
		(end 246.77878 -45.10278)
		(width 0.14224)
		(layer "In2.Cu")
		(net "M_A_ECC<7>")
	)
	(segment
		(start 241.107976 -18.4658)
		(end 240.952528 -18.621248)
		(width 0.14224)
		(layer "In2.Cu")
		(net "M_A_ECC<7>")
	)
	(segment
		(start 249.860054 -60.838588)
		(end 249.855228 -60.847224)
		(width 0.0889)
		(layer "In2.Cu")
		(net "M_A_ECC<7>")
	)
	(segment
		(start 248.362724 -54.437788)
		(end 248.362724 -55.504588)
		(width 0.0889)
		(layer "In2.Cu")
		(net "M_A_ECC<7>")
	)
	(arc
		(start 248.138188 -56.884824)
		(mid 248.141935 -57.27408)
		(end 248.474738 -57.476136)
		(width 0.0889)
		(layer "In2.Cu")
		(net "M_A_ECC<7>")
	)
	(arc
		(start 249.001534 -57.771538)
		(mid 249.140278 -57.913571)
		(end 249.33021 -57.971436)
		(width 0.0889)
		(layer "In2.Cu")
		(net "M_A_ECC<7>")
	)
	(arc
		(start 249.860054 -60.248038)
		(mid 249.939276 -60.537156)
		(end 249.866404 -60.82792)
		(width 0.0889)
		(layer "In2.Cu")
		(net "M_A_ECC<7>")
	)
	(arc
		(start 248.143014 -56.285638)
		(mid 248.222236 -56.574756)
		(end 248.149364 -56.86552)
		(width 0.0889)
		(layer "In2.Cu")
		(net "M_A_ECC<7>")
	)
	(arc
		(start 249.860054 -59.257438)
		(mid 249.939276 -59.546556)
		(end 249.866404 -59.83732)
		(width 0.0889)
		(layer "In2.Cu")
		(net "M_A_ECC<7>")
	)
	(arc
		(start 249.855228 -58.866024)
		(mid 249.806473 -59.062376)
		(end 249.860054 -59.257438)
		(width 0.0889)
		(layer "In2.Cu")
		(net "M_A_ECC<7>")
	)
	(arc
		(start 249.855228 -59.856624)
		(mid 249.806473 -60.052976)
		(end 249.860054 -60.248038)
		(width 0.0889)
		(layer "In2.Cu")
		(net "M_A_ECC<7>")
	)
	(arc
		(start 249.855228 -60.847224)
		(mid 249.806473 -61.043576)
		(end 249.860054 -61.238638)
		(width 0.0889)
		(layer "In2.Cu")
		(net "M_A_ECC<7>")
	)
	(arc
		(start 249.366024 -57.971436)
		(mid 249.864275 -58.274276)
		(end 249.860054 -58.857388)
		(width 0.0889)
		(layer "In2.Cu")
		(net "M_A_ECC<7>")
	)
	(arc
		(start 248.502678 -57.476136)
		(mid 248.790823 -57.558455)
		(end 249.001534 -57.771538)
		(width 0.0889)
		(layer "In2.Cu")
		(net "M_A_ECC<7>")
	)
	(arc
		(start 248.138188 -55.894224)
		(mid 248.089433 -56.090576)
		(end 248.143014 -56.285638)
		(width 0.0889)
		(layer "In2.Cu")
		(net "M_A_ECC<7>")
	)
	(segment
		(start 240.599976 -19.05)
		(end 240.732056 -18.91792)
		(width 0.1651)
		(layer "F.Cu")
		(net "M_A_ECC<6>")
	)
	(segment
		(start 240.599976 -20.023582)
		(end 240.599976 -19.05)
		(width 0.1651)
		(layer "F.Cu")
		(net "M_A_ECC<6>")
	)
	(segment
		(start 249.919744 -60.54344)
		(end 249.348244 -60.54344)
		(width 0.1016)
		(layer "F.Cu")
		(net "M_A_ECC<6>")
	)
	(segment
		(start 240.732056 -18.91792)
		(end 240.732056 -18.69948)
		(width 0.1651)
		(layer "F.Cu")
		(net "M_A_ECC<6>")
	)
	(segment
		(start 240.599976 -18.262854)
		(end 240.599722 -18.2626)
		(width 0.1651)
		(layer "F.Cu")
		(net "M_A_ECC<6>")
	)
	(segment
		(start 240.600484 -20.023582)
		(end 240.599976 -20.023582)
		(width 0.1651)
		(layer "F.Cu")
		(net "M_A_ECC<6>")
	)
	(segment
		(start 240.732056 -18.69948)
		(end 240.599976 -18.5674)
		(width 0.1651)
		(layer "F.Cu")
		(net "M_A_ECC<6>")
	)
	(segment
		(start 240.599976 -18.5674)
		(end 240.599976 -18.262854)
		(width 0.1651)
		(layer "F.Cu")
		(net "M_A_ECC<6>")
	)
	(via
		(at 239.749838 -23.560278)
		(size 0.508)
		(drill 0.254)
		(layers "F.Cu" "B.Cu")
		(net "M_A_ECC<6>")
	)
	(via
		(at 249.348244 -60.54344)
		(size 0.508)
		(drill 0.254)
		(layers "F.Cu" "B.Cu")
		(net "M_A_ECC<6>")
	)
	(via
		(at 240.599722 -18.2626)
		(size 0.508)
		(drill 0.254)
		(layers "F.Cu" "B.Cu")
		(net "M_A_ECC<6>")
	)
	(segment
		(start 239.749838 -24.824182)
		(end 239.749838 -23.560278)
		(width 0.1651)
		(layer "B.Cu")
		(net "M_A_ECC<6>")
	)
	(segment
		(start 239.750346 -24.824182)
		(end 239.749838 -24.824182)
		(width 0.1651)
		(layer "B.Cu")
		(net "M_A_ECC<6>")
	)
	(segment
		(start 241.043968 -38.428422)
		(end 240.840768 -38.225222)
		(width 0.14224)
		(layer "In2.Cu")
		(net "M_A_ECC<6>")
	)
	(segment
		(start 241.043968 -36.802822)
		(end 240.840768 -36.599622)
		(width 0.14224)
		(layer "In2.Cu")
		(net "M_A_ECC<6>")
	)
	(segment
		(start 241.4778 -35.990022)
		(end 241.681 -35.786822)
		(width 0.14224)
		(layer "In2.Cu")
		(net "M_A_ECC<6>")
	)
	(segment
		(start 241.808 -39.038022)
		(end 241.808 -38.631622)
		(width 0.14224)
		(layer "In2.Cu")
		(net "M_A_ECC<6>")
	)
	(segment
		(start 240.231168 -24.042624)
		(end 239.749838 -23.561294)
		(width 0.14224)
		(layer "In2.Cu")
		(net "M_A_ECC<6>")
	)
	(segment
		(start 240.193576 -18.668746)
		(end 240.599722 -18.2626)
		(width 0.14224)
		(layer "In2.Cu")
		(net "M_A_ECC<6>")
	)
	(segment
		(start 241.043968 -35.177222)
		(end 240.840768 -34.974022)
		(width 0.14224)
		(layer "In2.Cu")
		(net "M_A_ECC<6>")
	)
	(segment
		(start 248.261632 -50.897282)
		(end 248.261632 -50.196242)
		(width 0.0889)
		(layer "In2.Cu")
		(net "M_A_ECC<6>")
	)
	(segment
		(start 241.043968 -35.990022)
		(end 241.4778 -35.990022)
		(width 0.14224)
		(layer "In2.Cu")
		(net "M_A_ECC<6>")
	)
	(segment
		(start 247.303544 -48.801274)
		(end 247.303544 -46.414944)
		(width 0.14224)
		(layer "In2.Cu")
		(net "M_A_ECC<6>")
	)
	(segment
		(start 247.977914 -56.780938)
		(end 247.98274 -56.772302)
		(width 0.0889)
		(layer "In2.Cu")
		(net "M_A_ECC<6>")
	)
	(segment
		(start 241.678968 -40.558974)
		(end 241.441224 -40.32123)
		(width 0.14224)
		(layer "In2.Cu")
		(net "M_A_ECC<6>")
	)
	(segment
		(start 241.4778 -35.177222)
		(end 241.043968 -35.177222)
		(width 0.14224)
		(layer "In2.Cu")
		(net "M_A_ECC<6>")
	)
	(segment
		(start 239.977168 -29.021024)
		(end 240.378996 -28.619196)
		(width 0.14224)
		(layer "In2.Cu")
		(net "M_A_ECC<6>")
	)
	(segment
		(start 241.7826 -37.412422)
		(end 241.7826 -37.006022)
		(width 0.14224)
		(layer "In2.Cu")
		(net "M_A_ECC<6>")
	)
	(segment
		(start 241.5794 -37.615622)
		(end 241.7826 -37.412422)
		(width 0.14224)
		(layer "In2.Cu")
		(net "M_A_ECC<6>")
	)
	(segment
		(start 239.431576 -22.7965)
		(end 240.193576 -22.0345)
		(width 0.14224)
		(layer "In2.Cu")
		(net "M_A_ECC<6>")
	)
	(segment
		(start 248.172224 -55.454042)
		(end 248.172224 -54.358794)
		(width 0.0889)
		(layer "In2.Cu")
		(net "M_A_ECC<6>")
	)
	(segment
		(start 248.5009 -57.66689)
		(end 248.47677 -57.66689)
		(width 0.0889)
		(layer "In2.Cu")
		(net "M_A_ECC<6>")
	)
	(segment
		(start 239.749838 -23.561294)
		(end 239.749838 -23.560278)
		(width 0.14224)
		(layer "In2.Cu")
		(net "M_A_ECC<6>")
	)
	(segment
		(start 239.749838 -23.560278)
		(end 239.431576 -23.242016)
		(width 0.14224)
		(layer "In2.Cu")
		(net "M_A_ECC<6>")
	)
	(segment
		(start 247.971564 -55.801006)
		(end 248.172224 -55.454042)
		(width 0.0889)
		(layer "In2.Cu")
		(net "M_A_ECC<6>")
	)
	(segment
		(start 241.441224 -40.32123)
		(end 241.006376 -40.32123)
		(width 0.14224)
		(layer "In2.Cu")
		(net "M_A_ECC<6>")
	)
	(segment
		(start 240.099596 -27.577796)
		(end 240.099596 -26.422604)
		(width 0.14224)
		(layer "In2.Cu")
		(net "M_A_ECC<6>")
	)
	(segment
		(start 240.840768 -36.599622)
		(end 240.840768 -36.193222)
		(width 0.14224)
		(layer "In2.Cu")
		(net "M_A_ECC<6>")
	)
	(segment
		(start 241.6048 -38.428422)
		(end 241.043968 -38.428422)
		(width 0.14224)
		(layer "In2.Cu")
		(net "M_A_ECC<6>")
	)
	(segment
		(start 241.6048 -39.241222)
		(end 241.808 -39.038022)
		(width 0.14224)
		(layer "In2.Cu")
		(net "M_A_ECC<6>")
	)
	(segment
		(start 249.366278 -58.16219)
		(end 249.326654 -58.16219)
		(width 0.0889)
		(layer "In2.Cu")
		(net "M_A_ECC<6>")
	)
	(segment
		(start 248.172224 -54.358794)
		(end 248.466864 -54.064154)
		(width 0.0889)
		(layer "In2.Cu")
		(net "M_A_ECC<6>")
	)
	(segment
		(start 239.431576 -23.242016)
		(end 239.431576 -22.7965)
		(width 0.14224)
		(layer "In2.Cu")
		(net "M_A_ECC<6>")
	)
	(segment
		(start 241.678968 -41.475914)
		(end 241.678968 -40.558974)
		(width 0.14224)
		(layer "In2.Cu")
		(net "M_A_ECC<6>")
	)
	(segment
		(start 247.560084 -49.057814)
		(end 247.303544 -48.801274)
		(width 0.0889)
		(layer "In2.Cu")
		(net "M_A_ECC<6>")
	)
	(segment
		(start 241.006376 -40.32123)
		(end 240.840768 -40.155622)
		(width 0.14224)
		(layer "In2.Cu")
		(net "M_A_ECC<6>")
	)
	(segment
		(start 240.231168 -26.291032)
		(end 240.231168 -24.042624)
		(width 0.14224)
		(layer "In2.Cu")
		(net "M_A_ECC<6>")
	)
	(segment
		(start 241.043968 -39.241222)
		(end 241.6048 -39.241222)
		(width 0.14224)
		(layer "In2.Cu")
		(net "M_A_ECC<6>")
	)
	(segment
		(start 240.840768 -34.974022)
		(end 240.840768 -34.567622)
		(width 0.14224)
		(layer "In2.Cu")
		(net "M_A_ECC<6>")
	)
	(segment
		(start 240.378996 -27.857196)
		(end 240.099596 -27.577796)
		(width 0.14224)
		(layer "In2.Cu")
		(net "M_A_ECC<6>")
	)
	(segment
		(start 240.840768 -36.193222)
		(end 241.043968 -35.990022)
		(width 0.14224)
		(layer "In2.Cu")
		(net "M_A_ECC<6>")
	)
	(segment
		(start 241.681 -35.380422)
		(end 241.4778 -35.177222)
		(width 0.14224)
		(layer "In2.Cu")
		(net "M_A_ECC<6>")
	)
	(segment
		(start 247.560084 -49.494694)
		(end 247.560084 -49.057814)
		(width 0.0889)
		(layer "In2.Cu")
		(net "M_A_ECC<6>")
	)
	(segment
		(start 246.47017 -45.58157)
		(end 245.784624 -45.58157)
		(width 0.14224)
		(layer "In2.Cu")
		(net "M_A_ECC<6>")
	)
	(segment
		(start 240.378996 -28.619196)
		(end 240.378996 -27.857196)
		(width 0.14224)
		(layer "In2.Cu")
		(net "M_A_ECC<6>")
	)
	(segment
		(start 240.840768 -38.225222)
		(end 240.840768 -37.818822)
		(width 0.14224)
		(layer "In2.Cu")
		(net "M_A_ECC<6>")
	)
	(segment
		(start 240.099596 -26.422604)
		(end 240.231168 -26.291032)
		(width 0.14224)
		(layer "In2.Cu")
		(net "M_A_ECC<6>")
	)
	(segment
		(start 240.840768 -37.818822)
		(end 241.043968 -37.615622)
		(width 0.14224)
		(layer "In2.Cu")
		(net "M_A_ECC<6>")
	)
	(segment
		(start 241.043968 -37.615622)
		(end 241.5794 -37.615622)
		(width 0.14224)
		(layer "In2.Cu")
		(net "M_A_ECC<6>")
	)
	(segment
		(start 241.681 -35.786822)
		(end 241.681 -35.380422)
		(width 0.14224)
		(layer "In2.Cu")
		(net "M_A_ECC<6>")
	)
	(segment
		(start 248.466864 -54.064154)
		(end 248.466864 -51.102514)
		(width 0.0889)
		(layer "In2.Cu")
		(net "M_A_ECC<6>")
	)
	(segment
		(start 248.466864 -51.102514)
		(end 248.261632 -50.897282)
		(width 0.0889)
		(layer "In2.Cu")
		(net "M_A_ECC<6>")
	)
	(segment
		(start 240.840768 -34.567622)
		(end 240.919 -34.48939)
		(width 0.14224)
		(layer "In2.Cu")
		(net "M_A_ECC<6>")
	)
	(segment
		(start 240.919 -34.48939)
		(end 240.919 -33.67151)
		(width 0.14224)
		(layer "In2.Cu")
		(net "M_A_ECC<6>")
	)
	(segment
		(start 240.840768 -40.155622)
		(end 240.840768 -39.444422)
		(width 0.14224)
		(layer "In2.Cu")
		(net "M_A_ECC<6>")
	)
	(segment
		(start 240.840768 -39.444422)
		(end 241.043968 -39.241222)
		(width 0.14224)
		(layer "In2.Cu")
		(net "M_A_ECC<6>")
	)
	(segment
		(start 240.193576 -22.0345)
		(end 240.193576 -18.668746)
		(width 0.14224)
		(layer "In2.Cu")
		(net "M_A_ECC<6>")
	)
	(segment
		(start 240.919 -33.67151)
		(end 239.977168 -32.729678)
		(width 0.14224)
		(layer "In2.Cu")
		(net "M_A_ECC<6>")
	)
	(segment
		(start 247.303544 -46.414944)
		(end 246.47017 -45.58157)
		(width 0.14224)
		(layer "In2.Cu")
		(net "M_A_ECC<6>")
	)
	(segment
		(start 248.261632 -50.196242)
		(end 247.560084 -49.494694)
		(width 0.0889)
		(layer "In2.Cu")
		(net "M_A_ECC<6>")
	)
	(segment
		(start 249.348244 -60.54344)
		(end 249.677682 -59.782456)
		(width 0.0889)
		(layer "In2.Cu")
		(net "M_A_ECC<6>")
	)
	(segment
		(start 247.971564 -56.791606)
		(end 247.977914 -56.780938)
		(width 0.0889)
		(layer "In2.Cu")
		(net "M_A_ECC<6>")
	)
	(segment
		(start 245.784624 -45.58157)
		(end 241.678968 -41.475914)
		(width 0.14224)
		(layer "In2.Cu")
		(net "M_A_ECC<6>")
	)
	(segment
		(start 249.677682 -59.782456)
		(end 249.69978 -59.744102)
		(width 0.0889)
		(layer "In2.Cu")
		(net "M_A_ECC<6>")
	)
	(segment
		(start 241.808 -38.631622)
		(end 241.6048 -38.428422)
		(width 0.14224)
		(layer "In2.Cu")
		(net "M_A_ECC<6>")
	)
	(segment
		(start 241.5794 -36.802822)
		(end 241.043968 -36.802822)
		(width 0.14224)
		(layer "In2.Cu")
		(net "M_A_ECC<6>")
	)
	(segment
		(start 239.977168 -32.729678)
		(end 239.977168 -29.021024)
		(width 0.14224)
		(layer "In2.Cu")
		(net "M_A_ECC<6>")
	)
	(segment
		(start 241.7826 -37.006022)
		(end 241.5794 -36.802822)
		(width 0.14224)
		(layer "In2.Cu")
		(net "M_A_ECC<6>")
	)
	(arc
		(start 249.694954 -58.761884)
		(mid 249.699199 -58.369639)
		(end 249.366278 -58.16219)
		(width 0.0889)
		(layer "In2.Cu")
		(net "M_A_ECC<6>")
	)
	(arc
		(start 248.47677 -57.66689)
		(mid 247.977889 -57.371453)
		(end 247.971564 -56.791606)
		(width 0.0889)
		(layer "In2.Cu")
		(net "M_A_ECC<6>")
	)
	(arc
		(start 249.694954 -59.352688)
		(mid 249.615823 -59.057286)
		(end 249.694954 -58.761884)
		(width 0.0889)
		(layer "In2.Cu")
		(net "M_A_ECC<6>")
	)
	(arc
		(start 249.326654 -58.16219)
		(mid 249.043437 -58.077909)
		(end 248.836434 -57.867042)
		(width 0.0889)
		(layer "In2.Cu")
		(net "M_A_ECC<6>")
	)
	(arc
		(start 248.836434 -57.867042)
		(mid 248.694751 -57.723238)
		(end 248.5009 -57.66689)
		(width 0.0889)
		(layer "In2.Cu")
		(net "M_A_ECC<6>")
	)
	(arc
		(start 247.98274 -56.772302)
		(mid 248.031495 -56.57595)
		(end 247.977914 -56.380888)
		(width 0.0889)
		(layer "In2.Cu")
		(net "M_A_ECC<6>")
	)
	(arc
		(start 249.69978 -59.744102)
		(mid 249.748535 -59.54775)
		(end 249.694954 -59.352688)
		(width 0.0889)
		(layer "In2.Cu")
		(net "M_A_ECC<6>")
	)
	(arc
		(start 247.977914 -56.380888)
		(mid 247.898692 -56.09177)
		(end 247.971564 -55.801006)
		(width 0.0889)
		(layer "In2.Cu")
		(net "M_A_ECC<6>")
	)
	(segment
		(start 233.799888 -15.423642)
		(end 233.799888 -16.687546)
		(width 0.1651)
		(layer "F.Cu")
		(net "M_A_ECC<5>")
	)
	(segment
		(start 233.800396 -15.423642)
		(end 233.799888 -15.423642)
		(width 0.1651)
		(layer "F.Cu")
		(net "M_A_ECC<5>")
	)
	(segment
		(start 247.344184 -62.029086)
		(end 246.772684 -62.029086)
		(width 0.1016)
		(layer "F.Cu")
		(net "M_A_ECC<5>")
	)
	(via
		(at 246.772684 -62.029086)
		(size 0.508)
		(drill 0.254)
		(layers "F.Cu" "B.Cu")
		(net "M_A_ECC<5>")
	)
	(via
		(at 233.799888 -16.687546)
		(size 0.508)
		(drill 0.254)
		(layers "F.Cu" "B.Cu")
		(net "M_A_ECC<5>")
	)
	(via
		(at 234.573572 -22.279356)
		(size 0.508)
		(drill 0.254)
		(layers "F.Cu" "B.Cu")
		(net "M_A_ECC<5>")
	)
	(segment
		(start 234.649772 -20.224242)
		(end 234.649772 -22.203156)
		(width 0.1651)
		(layer "B.Cu")
		(net "M_A_ECC<5>")
	)
	(segment
		(start 234.65028 -20.224242)
		(end 234.649772 -20.224242)
		(width 0.1651)
		(layer "B.Cu")
		(net "M_A_ECC<5>")
	)
	(segment
		(start 234.649772 -22.203156)
		(end 234.573572 -22.279356)
		(width 0.1651)
		(layer "B.Cu")
		(net "M_A_ECC<5>")
	)
	(segment
		(start 244.708934 -56.876188)
		(end 244.704108 -56.884824)
		(width 0.0889)
		(layer "In2.Cu")
		(net "M_A_ECC<5>")
	)
	(segment
		(start 244.708934 -58.266838)
		(end 244.715284 -58.277506)
		(width 0.0889)
		(layer "In2.Cu")
		(net "M_A_ECC<5>")
	)
	(segment
		(start 247.065292 -61.3537)
		(end 247.065292 -61.355732)
		(width 0.0889)
		(layer "In2.Cu")
		(net "M_A_ECC<5>")
	)
	(segment
		(start 242.679728 -49.628552)
		(end 244.882924 -51.831748)
		(width 0.0889)
		(layer "In2.Cu")
		(net "M_A_ECC<5>")
	)
	(segment
		(start 244.882924 -52.369974)
		(end 244.585998 -52.6669)
		(width 0.0889)
		(layer "In2.Cu")
		(net "M_A_ECC<5>")
	)
	(segment
		(start 235.081826 -18.053304)
		(end 235.081826 -18.4658)
		(width 0.14224)
		(layer "In2.Cu")
		(net "M_A_ECC<5>")
	)
	(segment
		(start 233.799888 -16.687546)
		(end 233.799888 -17.082262)
		(width 0.14224)
		(layer "In2.Cu")
		(net "M_A_ECC<5>")
	)
	(segment
		(start 244.715284 -56.86552)
		(end 244.708934 -56.876188)
		(width 0.0889)
		(layer "In2.Cu")
		(net "M_A_ECC<5>")
	)
	(segment
		(start 244.882924 -51.831748)
		(end 244.882924 -52.369974)
		(width 0.0889)
		(layer "In2.Cu")
		(net "M_A_ECC<5>")
	)
	(segment
		(start 242.919504 -49.151794)
		(end 242.679728 -49.39157)
		(width 0.0889)
		(layer "In2.Cu")
		(net "M_A_ECC<5>")
	)
	(segment
		(start 235.044996 -28.187396)
		(end 234.994196 -28.238196)
		(width 0.14224)
		(layer "In2.Cu")
		(net "M_A_ECC<5>")
	)
	(segment
		(start 244.715284 -53.89372)
		(end 244.708934 -53.904388)
		(width 0.0889)
		(layer "In2.Cu")
		(net "M_A_ECC<5>")
	)
	(segment
		(start 244.715284 -54.88432)
		(end 244.708934 -54.894988)
		(width 0.0889)
		(layer "In2.Cu")
		(net "M_A_ECC<5>")
	)
	(segment
		(start 247.119394 -61.238638)
		(end 247.10263 -61.26734)
		(width 0.0889)
		(layer "In2.Cu")
		(net "M_A_ECC<5>")
	)
	(segment
		(start 234.968796 -24.034496)
		(end 234.968796 -26.917396)
		(width 0.14224)
		(layer "In2.Cu")
		(net "M_A_ECC<5>")
	)
	(segment
		(start 234.994196 -28.238196)
		(end 234.994196 -29.101796)
		(width 0.14224)
		(layer "In2.Cu")
		(net "M_A_ECC<5>")
	)
	(segment
		(start 244.708934 -54.894988)
		(end 244.704108 -54.903624)
		(width 0.0889)
		(layer "In2.Cu")
		(net "M_A_ECC<5>")
	)
	(segment
		(start 234.994196 -29.101796)
		(end 235.6612 -29.7688)
		(width 0.14224)
		(layer "In2.Cu")
		(net "M_A_ECC<5>")
	)
	(segment
		(start 244.585998 -53.100732)
		(end 244.708934 -53.313838)
		(width 0.0889)
		(layer "In2.Cu")
		(net "M_A_ECC<5>")
	)
	(segment
		(start 246.855742 -60.58154)
		(end 247.074182 -60.754006)
		(width 0.0889)
		(layer "In2.Cu")
		(net "M_A_ECC<5>")
	)
	(segment
		(start 247.065292 -61.355732)
		(end 246.772684 -61.64834)
		(width 0.0889)
		(layer "In2.Cu")
		(net "M_A_ECC<5>")
	)
	(segment
		(start 247.074182 -60.754006)
		(end 247.122188 -60.837318)
		(width 0.0889)
		(layer "In2.Cu")
		(net "M_A_ECC<5>")
	)
	(segment
		(start 235.6612 -41.084754)
		(end 242.919504 -48.343058)
		(width 0.14224)
		(layer "In2.Cu")
		(net "M_A_ECC<5>")
	)
	(segment
		(start 246.55907 -60.386468)
		(end 246.855742 -60.58154)
		(width 0.0889)
		(layer "In2.Cu")
		(net "M_A_ECC<5>")
	)
	(segment
		(start 234.056428 -23.122128)
		(end 234.968796 -24.034496)
		(width 0.14224)
		(layer "In2.Cu")
		(net "M_A_ECC<5>")
	)
	(segment
		(start 245.040658 -59.457336)
		(end 245.073424 -59.457336)
		(width 0.0889)
		(layer "In2.Cu")
		(net "M_A_ECC<5>")
	)
	(segment
		(start 234.681522 -17.653)
		(end 235.081826 -18.053304)
		(width 0.14224)
		(layer "In2.Cu")
		(net "M_A_ECC<5>")
	)
	(segment
		(start 234.526836 -22.279356)
		(end 234.056428 -22.749764)
		(width 0.14224)
		(layer "In2.Cu")
		(net "M_A_ECC<5>")
	)
	(segment
		(start 246.772684 -61.64834)
		(end 246.772684 -62.029086)
		(width 0.0889)
		(layer "In2.Cu")
		(net "M_A_ECC<5>")
	)
	(segment
		(start 247.10263 -61.26734)
		(end 247.065292 -61.3537)
		(width 0.0889)
		(layer "In2.Cu")
		(net "M_A_ECC<5>")
	)
	(segment
		(start 233.799888 -17.082262)
		(end 234.370626 -17.653)
		(width 0.14224)
		(layer "In2.Cu")
		(net "M_A_ECC<5>")
	)
	(segment
		(start 244.715284 -55.87492)
		(end 244.708934 -55.885588)
		(width 0.0889)
		(layer "In2.Cu")
		(net "M_A_ECC<5>")
	)
	(segment
		(start 244.708934 -55.885588)
		(end 244.704108 -55.894224)
		(width 0.0889)
		(layer "In2.Cu")
		(net "M_A_ECC<5>")
	)
	(segment
		(start 244.585998 -52.6669)
		(end 244.585998 -53.100732)
		(width 0.0889)
		(layer "In2.Cu")
		(net "M_A_ECC<5>")
	)
	(segment
		(start 245.902988 -59.95289)
		(end 245.935754 -59.95289)
		(width 0.0889)
		(layer "In2.Cu")
		(net "M_A_ECC<5>")
	)
	(segment
		(start 234.056428 -22.749764)
		(end 234.056428 -23.122128)
		(width 0.14224)
		(layer "In2.Cu")
		(net "M_A_ECC<5>")
	)
	(segment
		(start 235.6612 -29.7688)
		(end 235.6612 -41.084754)
		(width 0.14224)
		(layer "In2.Cu")
		(net "M_A_ECC<5>")
	)
	(segment
		(start 234.573572 -22.279356)
		(end 234.526836 -22.279356)
		(width 0.14224)
		(layer "In2.Cu")
		(net "M_A_ECC<5>")
	)
	(segment
		(start 234.370626 -17.653)
		(end 234.681522 -17.653)
		(width 0.14224)
		(layer "In2.Cu")
		(net "M_A_ECC<5>")
	)
	(segment
		(start 242.679728 -49.39157)
		(end 242.679728 -49.628552)
		(width 0.0889)
		(layer "In2.Cu")
		(net "M_A_ECC<5>")
	)
	(segment
		(start 244.708934 -53.904388)
		(end 244.704108 -53.913024)
		(width 0.0889)
		(layer "In2.Cu")
		(net "M_A_ECC<5>")
	)
	(segment
		(start 234.968796 -26.917396)
		(end 235.044996 -26.993596)
		(width 0.14224)
		(layer "In2.Cu")
		(net "M_A_ECC<5>")
	)
	(segment
		(start 242.919504 -48.343058)
		(end 242.919504 -49.151794)
		(width 0.14224)
		(layer "In2.Cu")
		(net "M_A_ECC<5>")
	)
	(segment
		(start 235.044996 -26.993596)
		(end 235.044996 -28.187396)
		(width 0.14224)
		(layer "In2.Cu")
		(net "M_A_ECC<5>")
	)
	(segment
		(start 234.884976 -18.66265)
		(end 234.884976 -21.967952)
		(width 0.14224)
		(layer "In2.Cu")
		(net "M_A_ECC<5>")
	)
	(segment
		(start 244.708934 -58.857388)
		(end 244.704108 -58.866024)
		(width 0.0889)
		(layer "In2.Cu")
		(net "M_A_ECC<5>")
	)
	(segment
		(start 234.884976 -21.967952)
		(end 234.573572 -22.279356)
		(width 0.14224)
		(layer "In2.Cu")
		(net "M_A_ECC<5>")
	)
	(segment
		(start 235.081826 -18.4658)
		(end 234.884976 -18.66265)
		(width 0.14224)
		(layer "In2.Cu")
		(net "M_A_ECC<5>")
	)
	(arc
		(start 245.073424 -59.457336)
		(mid 245.358848 -59.540803)
		(end 245.567454 -59.752738)
		(width 0.0889)
		(layer "In2.Cu")
		(net "M_A_ECC<5>")
	)
	(arc
		(start 244.708934 -53.313838)
		(mid 244.788156 -53.602956)
		(end 244.715284 -53.89372)
		(width 0.0889)
		(layer "In2.Cu")
		(net "M_A_ECC<5>")
	)
	(arc
		(start 244.704108 -55.894224)
		(mid 244.655353 -56.090576)
		(end 244.708934 -56.285638)
		(width 0.0889)
		(layer "In2.Cu")
		(net "M_A_ECC<5>")
	)
	(arc
		(start 244.715284 -58.277506)
		(mid 244.788082 -58.568269)
		(end 244.708934 -58.857388)
		(width 0.0889)
		(layer "In2.Cu")
		(net "M_A_ECC<5>")
	)
	(arc
		(start 244.704108 -54.903624)
		(mid 244.655353 -55.099976)
		(end 244.708934 -55.295038)
		(width 0.0889)
		(layer "In2.Cu")
		(net "M_A_ECC<5>")
	)
	(arc
		(start 245.935754 -59.95289)
		(mid 246.218971 -60.037171)
		(end 246.425974 -60.248038)
		(width 0.0889)
		(layer "In2.Cu")
		(net "M_A_ECC<5>")
	)
	(arc
		(start 245.567454 -59.752738)
		(mid 245.709137 -59.896542)
		(end 245.902988 -59.95289)
		(width 0.0889)
		(layer "In2.Cu")
		(net "M_A_ECC<5>")
	)
	(arc
		(start 244.704108 -56.884824)
		(mid 244.655353 -57.081176)
		(end 244.708934 -57.276238)
		(width 0.0889)
		(layer "In2.Cu")
		(net "M_A_ECC<5>")
	)
	(arc
		(start 247.122188 -60.837318)
		(mid 247.17374 -61.038336)
		(end 247.119394 -61.238638)
		(width 0.0889)
		(layer "In2.Cu")
		(net "M_A_ECC<5>")
	)
	(arc
		(start 244.708934 -57.276238)
		(mid 244.788065 -57.57164)
		(end 244.708934 -57.867042)
		(width 0.0889)
		(layer "In2.Cu")
		(net "M_A_ECC<5>")
	)
	(arc
		(start 244.708934 -55.295038)
		(mid 244.788156 -55.584156)
		(end 244.715284 -55.87492)
		(width 0.0889)
		(layer "In2.Cu")
		(net "M_A_ECC<5>")
	)
	(arc
		(start 244.704108 -58.866024)
		(mid 244.707855 -59.25528)
		(end 245.040658 -59.457336)
		(width 0.0889)
		(layer "In2.Cu")
		(net "M_A_ECC<5>")
	)
	(arc
		(start 244.704108 -53.913024)
		(mid 244.655353 -54.109376)
		(end 244.708934 -54.304438)
		(width 0.0889)
		(layer "In2.Cu")
		(net "M_A_ECC<5>")
	)
	(arc
		(start 244.708934 -54.304438)
		(mid 244.788156 -54.593556)
		(end 244.715284 -54.88432)
		(width 0.0889)
		(layer "In2.Cu")
		(net "M_A_ECC<5>")
	)
	(arc
		(start 244.708934 -56.285638)
		(mid 244.788156 -56.574756)
		(end 244.715284 -56.86552)
		(width 0.0889)
		(layer "In2.Cu")
		(net "M_A_ECC<5>")
	)
	(arc
		(start 246.425974 -60.248038)
		(mid 246.484099 -60.325352)
		(end 246.55907 -60.386468)
		(width 0.0889)
		(layer "In2.Cu")
		(net "M_A_ECC<5>")
	)
	(arc
		(start 244.708934 -57.867042)
		(mid 244.655435 -58.06694)
		(end 244.708934 -58.266838)
		(width 0.0889)
		(layer "In2.Cu")
		(net "M_A_ECC<5>")
	)
	(segment
		(start 234.649772 -18.692368)
		(end 234.551728 -18.161)
		(width 0.1651)
		(layer "F.Cu")
		(net "M_A_ECC<4>")
	)
	(segment
		(start 234.649772 -20.023582)
		(end 234.649772 -18.692368)
		(width 0.1651)
		(layer "F.Cu")
		(net "M_A_ECC<4>")
	)
	(segment
		(start 247.344184 -61.038486)
		(end 246.772684 -61.038486)
		(width 0.1016)
		(layer "F.Cu")
		(net "M_A_ECC<4>")
	)
	(segment
		(start 234.65028 -20.023582)
		(end 234.649772 -20.023582)
		(width 0.1651)
		(layer "F.Cu")
		(net "M_A_ECC<4>")
	)
	(via
		(at 234.551728 -18.161)
		(size 0.508)
		(drill 0.254)
		(layers "F.Cu" "B.Cu")
		(net "M_A_ECC<4>")
	)
	(via
		(at 233.799888 -23.560278)
		(size 0.508)
		(drill 0.254)
		(layers "F.Cu" "B.Cu")
		(net "M_A_ECC<4>")
	)
	(via
		(at 246.772684 -61.038486)
		(size 0.508)
		(drill 0.254)
		(layers "F.Cu" "B.Cu")
		(net "M_A_ECC<4>")
	)
	(segment
		(start 233.799888 -24.824182)
		(end 233.799888 -23.560278)
		(width 0.1651)
		(layer "B.Cu")
		(net "M_A_ECC<4>")
	)
	(segment
		(start 233.800396 -24.824182)
		(end 233.799888 -24.824182)
		(width 0.1651)
		(layer "B.Cu")
		(net "M_A_ECC<4>")
	)
	(segment
		(start 244.54866 -54.791102)
		(end 244.543834 -54.799738)
		(width 0.0889)
		(layer "In2.Cu")
		(net "M_A_ECC<4>")
	)
	(segment
		(start 244.54866 -57.762902)
		(end 244.543834 -57.771538)
		(width 0.0889)
		(layer "In2.Cu")
		(net "M_A_ECC<4>")
	)
	(segment
		(start 234.054396 -28.136596)
		(end 234.338368 -28.420568)
		(width 0.14224)
		(layer "In2.Cu")
		(net "M_A_ECC<4>")
	)
	(segment
		(start 234.287568 -25.594056)
		(end 234.490768 -25.797256)
		(width 0.14224)
		(layer "In2.Cu")
		(net "M_A_ECC<4>")
	)
	(segment
		(start 244.543834 -53.809138)
		(end 244.537484 -53.819806)
		(width 0.0889)
		(layer "In2.Cu")
		(net "M_A_ECC<4>")
	)
	(segment
		(start 242.271804 -48.372776)
		(end 242.271804 -49.177194)
		(width 0.14224)
		(layer "In2.Cu")
		(net "M_A_ECC<4>")
	)
	(segment
		(start 244.072664 -51.775614)
		(end 244.072664 -52.298854)
		(width 0.0889)
		(layer "In2.Cu")
		(net "M_A_ECC<4>")
	)
	(segment
		(start 234.338368 -28.420568)
		(end 234.338368 -29.360622)
		(width 0.14224)
		(layer "In2.Cu")
		(net "M_A_ECC<4>")
	)
	(segment
		(start 244.395498 -53.151786)
		(end 244.543834 -53.409088)
		(width 0.0889)
		(layer "In2.Cu")
		(net "M_A_ECC<4>")
	)
	(segment
		(start 233.84764 -30.325822)
		(end 233.7054 -30.468062)
		(width 0.14224)
		(layer "In2.Cu")
		(net "M_A_ECC<4>")
	)
	(segment
		(start 233.855768 -24.806656)
		(end 233.677968 -24.984456)
		(width 0.14224)
		(layer "In2.Cu")
		(net "M_A_ECC<4>")
	)
	(segment
		(start 242.271804 -49.177194)
		(end 242.487704 -49.393094)
		(width 0.0889)
		(layer "In2.Cu")
		(net "M_A_ECC<4>")
	)
	(segment
		(start 234.872276 -30.325822)
		(end 233.84764 -30.325822)
		(width 0.14224)
		(layer "In2.Cu")
		(net "M_A_ECC<4>")
	)
	(segment
		(start 234.551728 -18.161)
		(end 234.275376 -18.437352)
		(width 0.14224)
		(layer "In2.Cu")
		(net "M_A_ECC<4>")
	)
	(segment
		(start 234.490768 -24.578056)
		(end 234.262168 -24.806656)
		(width 0.14224)
		(layer "In2.Cu")
		(net "M_A_ECC<4>")
	)
	(segment
		(start 234.275376 -21.818854)
		(end 233.564176 -22.530054)
		(width 0.14224)
		(layer "In2.Cu")
		(net "M_A_ECC<4>")
	)
	(segment
		(start 234.953556 -31.138622)
		(end 235.095796 -31.280862)
		(width 0.14224)
		(layer "In2.Cu")
		(net "M_A_ECC<4>")
	)
	(segment
		(start 233.7054 -30.996382)
		(end 233.84764 -31.138622)
		(width 0.14224)
		(layer "In2.Cu")
		(net "M_A_ECC<4>")
	)
	(segment
		(start 244.54866 -56.772302)
		(end 244.543834 -56.780938)
		(width 0.0889)
		(layer "In2.Cu")
		(net "M_A_ECC<4>")
	)
	(segment
		(start 234.262168 -24.806656)
		(end 233.855768 -24.806656)
		(width 0.14224)
		(layer "In2.Cu")
		(net "M_A_ECC<4>")
	)
	(segment
		(start 244.54866 -55.781702)
		(end 244.543834 -55.790338)
		(width 0.0889)
		(layer "In2.Cu")
		(net "M_A_ECC<4>")
	)
	(segment
		(start 235.095796 -41.196768)
		(end 242.271804 -48.372776)
		(width 0.14224)
		(layer "In2.Cu")
		(net "M_A_ECC<4>")
	)
	(segment
		(start 233.564176 -23.324566)
		(end 233.799888 -23.560278)
		(width 0.14224)
		(layer "In2.Cu")
		(net "M_A_ECC<4>")
	)
	(segment
		(start 244.184424 -51.405028)
		(end 244.184424 -51.663854)
		(width 0.0889)
		(layer "In2.Cu")
		(net "M_A_ECC<4>")
	)
	(segment
		(start 233.564176 -22.530054)
		(end 233.564176 -23.324566)
		(width 0.14224)
		(layer "In2.Cu")
		(net "M_A_ECC<4>")
	)
	(segment
		(start 234.490768 -24.251158)
		(end 234.490768 -24.578056)
		(width 0.14224)
		(layer "In2.Cu")
		(net "M_A_ECC<4>")
	)
	(segment
		(start 244.072664 -52.298854)
		(end 244.395498 -52.621688)
		(width 0.0889)
		(layer "In2.Cu")
		(net "M_A_ECC<4>")
	)
	(segment
		(start 233.84764 -31.138622)
		(end 234.953556 -31.138622)
		(width 0.14224)
		(layer "In2.Cu")
		(net "M_A_ECC<4>")
	)
	(segment
		(start 233.677968 -25.390856)
		(end 233.881168 -25.594056)
		(width 0.14224)
		(layer "In2.Cu")
		(net "M_A_ECC<4>")
	)
	(segment
		(start 242.487704 -49.708308)
		(end 244.184424 -51.405028)
		(width 0.0889)
		(layer "In2.Cu")
		(net "M_A_ECC<4>")
	)
	(segment
		(start 244.543834 -54.799738)
		(end 244.537484 -54.810406)
		(width 0.0889)
		(layer "In2.Cu")
		(net "M_A_ECC<4>")
	)
	(segment
		(start 233.881168 -25.594056)
		(end 234.287568 -25.594056)
		(width 0.14224)
		(layer "In2.Cu")
		(net "M_A_ECC<4>")
	)
	(segment
		(start 244.184424 -51.663854)
		(end 244.072664 -51.775614)
		(width 0.0889)
		(layer "In2.Cu")
		(net "M_A_ECC<4>")
	)
	(segment
		(start 244.54866 -53.800502)
		(end 244.543834 -53.809138)
		(width 0.0889)
		(layer "In2.Cu")
		(net "M_A_ECC<4>")
	)
	(segment
		(start 235.020104 -30.042358)
		(end 235.020104 -30.177994)
		(width 0.14224)
		(layer "In2.Cu")
		(net "M_A_ECC<4>")
	)
	(segment
		(start 234.490768 -25.797256)
		(end 234.490768 -26.633424)
		(width 0.14224)
		(layer "In2.Cu")
		(net "M_A_ECC<4>")
	)
	(segment
		(start 234.054396 -27.069796)
		(end 234.054396 -28.136596)
		(width 0.14224)
		(layer "In2.Cu")
		(net "M_A_ECC<4>")
	)
	(segment
		(start 246.324374 -60.43295)
		(end 246.772684 -61.038486)
		(width 0.0889)
		(layer "In2.Cu")
		(net "M_A_ECC<4>")
	)
	(segment
		(start 234.490768 -26.633424)
		(end 234.054396 -27.069796)
		(width 0.14224)
		(layer "In2.Cu")
		(net "M_A_ECC<4>")
	)
	(segment
		(start 244.395498 -52.621688)
		(end 244.395498 -53.151786)
		(width 0.0889)
		(layer "In2.Cu")
		(net "M_A_ECC<4>")
	)
	(segment
		(start 233.677968 -24.984456)
		(end 233.677968 -25.390856)
		(width 0.14224)
		(layer "In2.Cu")
		(net "M_A_ECC<4>")
	)
	(segment
		(start 233.799888 -23.560278)
		(end 234.490768 -24.251158)
		(width 0.14224)
		(layer "In2.Cu")
		(net "M_A_ECC<4>")
	)
	(segment
		(start 245.896384 -60.14339)
		(end 245.92915 -60.14339)
		(width 0.0889)
		(layer "In2.Cu")
		(net "M_A_ECC<4>")
	)
	(segment
		(start 244.543834 -55.790338)
		(end 244.537484 -55.801006)
		(width 0.0889)
		(layer "In2.Cu")
		(net "M_A_ECC<4>")
	)
	(segment
		(start 244.543834 -56.780938)
		(end 244.537484 -56.791606)
		(width 0.0889)
		(layer "In2.Cu")
		(net "M_A_ECC<4>")
	)
	(segment
		(start 242.487704 -49.393094)
		(end 242.487704 -49.708308)
		(width 0.0889)
		(layer "In2.Cu")
		(net "M_A_ECC<4>")
	)
	(segment
		(start 234.275376 -18.437352)
		(end 234.275376 -21.818854)
		(width 0.14224)
		(layer "In2.Cu")
		(net "M_A_ECC<4>")
	)
	(segment
		(start 235.095796 -31.280862)
		(end 235.095796 -41.196768)
		(width 0.14224)
		(layer "In2.Cu")
		(net "M_A_ECC<4>")
	)
	(segment
		(start 233.7054 -30.468062)
		(end 233.7054 -30.996382)
		(width 0.14224)
		(layer "In2.Cu")
		(net "M_A_ECC<4>")
	)
	(segment
		(start 244.537484 -58.35142)
		(end 244.543834 -58.362088)
		(width 0.0889)
		(layer "In2.Cu")
		(net "M_A_ECC<4>")
	)
	(segment
		(start 235.020104 -30.177994)
		(end 234.872276 -30.325822)
		(width 0.14224)
		(layer "In2.Cu")
		(net "M_A_ECC<4>")
	)
	(segment
		(start 245.034054 -59.647836)
		(end 245.06682 -59.647836)
		(width 0.0889)
		(layer "In2.Cu")
		(net "M_A_ECC<4>")
	)
	(segment
		(start 234.338368 -29.360622)
		(end 235.020104 -30.042358)
		(width 0.14224)
		(layer "In2.Cu")
		(net "M_A_ECC<4>")
	)
	(arc
		(start 244.543834 -58.362088)
		(mid 244.597333 -58.561986)
		(end 244.543834 -58.761884)
		(width 0.0889)
		(layer "In2.Cu")
		(net "M_A_ECC<4>")
	)
	(arc
		(start 244.543834 -53.409088)
		(mid 244.597304 -53.604151)
		(end 244.54866 -53.800502)
		(width 0.0889)
		(layer "In2.Cu")
		(net "M_A_ECC<4>")
	)
	(arc
		(start 244.543834 -57.771538)
		(mid 244.464612 -58.060656)
		(end 244.537484 -58.35142)
		(width 0.0889)
		(layer "In2.Cu")
		(net "M_A_ECC<4>")
	)
	(arc
		(start 245.402354 -59.847988)
		(mid 245.610962 -60.05992)
		(end 245.896384 -60.14339)
		(width 0.0889)
		(layer "In2.Cu")
		(net "M_A_ECC<4>")
	)
	(arc
		(start 244.543834 -58.761884)
		(mid 244.53858 -59.343392)
		(end 245.034054 -59.647836)
		(width 0.0889)
		(layer "In2.Cu")
		(net "M_A_ECC<4>")
	)
	(arc
		(start 244.537484 -55.801006)
		(mid 244.464686 -56.091769)
		(end 244.543834 -56.380888)
		(width 0.0889)
		(layer "In2.Cu")
		(net "M_A_ECC<4>")
	)
	(arc
		(start 245.06682 -59.647836)
		(mid 245.26067 -59.704186)
		(end 245.402354 -59.847988)
		(width 0.0889)
		(layer "In2.Cu")
		(net "M_A_ECC<4>")
	)
	(arc
		(start 244.543834 -55.390288)
		(mid 244.597304 -55.585351)
		(end 244.54866 -55.781702)
		(width 0.0889)
		(layer "In2.Cu")
		(net "M_A_ECC<4>")
	)
	(arc
		(start 244.537484 -54.810406)
		(mid 244.464686 -55.101169)
		(end 244.543834 -55.390288)
		(width 0.0889)
		(layer "In2.Cu")
		(net "M_A_ECC<4>")
	)
	(arc
		(start 244.543834 -54.399688)
		(mid 244.597304 -54.594751)
		(end 244.54866 -54.791102)
		(width 0.0889)
		(layer "In2.Cu")
		(net "M_A_ECC<4>")
	)
	(arc
		(start 246.260874 -60.343288)
		(mid 246.290535 -60.389599)
		(end 246.324374 -60.43295)
		(width 0.0889)
		(layer "In2.Cu")
		(net "M_A_ECC<4>")
	)
	(arc
		(start 244.543834 -57.371488)
		(mid 244.597304 -57.566551)
		(end 244.54866 -57.762902)
		(width 0.0889)
		(layer "In2.Cu")
		(net "M_A_ECC<4>")
	)
	(arc
		(start 244.543834 -56.380888)
		(mid 244.597304 -56.575951)
		(end 244.54866 -56.772302)
		(width 0.0889)
		(layer "In2.Cu")
		(net "M_A_ECC<4>")
	)
	(arc
		(start 244.537484 -56.791606)
		(mid 244.464686 -57.082369)
		(end 244.543834 -57.371488)
		(width 0.0889)
		(layer "In2.Cu")
		(net "M_A_ECC<4>")
	)
	(arc
		(start 244.537484 -53.819806)
		(mid 244.464686 -54.110569)
		(end 244.543834 -54.399688)
		(width 0.0889)
		(layer "In2.Cu")
		(net "M_A_ECC<4>")
	)
	(arc
		(start 245.92915 -60.14339)
		(mid 246.120792 -60.200556)
		(end 246.260874 -60.343288)
		(width 0.0889)
		(layer "In2.Cu")
		(net "M_A_ECC<4>")
	)
	(segment
		(start 241.450368 -15.423642)
		(end 241.44986 -15.423642)
		(width 0.1651)
		(layer "F.Cu")
		(net "M_A_ECC<3>")
	)
	(segment
		(start 241.44986 -15.423642)
		(end 241.44986 -16.687546)
		(width 0.1651)
		(layer "F.Cu")
		(net "M_A_ECC<3>")
	)
	(segment
		(start 250.778264 -62.029086)
		(end 250.206764 -62.029086)
		(width 0.1016)
		(layer "F.Cu")
		(net "M_A_ECC<3>")
	)
	(via
		(at 242.299744 -22.279356)
		(size 0.508)
		(drill 0.254)
		(layers "F.Cu" "B.Cu")
		(net "M_A_ECC<3>")
	)
	(via
		(at 241.44986 -16.687546)
		(size 0.508)
		(drill 0.254)
		(layers "F.Cu" "B.Cu")
		(net "M_A_ECC<3>")
	)
	(via
		(at 250.206764 -62.029086)
		(size 0.508)
		(drill 0.254)
		(layers "F.Cu" "B.Cu")
		(net "M_A_ECC<3>")
	)
	(segment
		(start 242.299998 -20.224242)
		(end 242.299998 -20.973542)
		(width 0.1651)
		(layer "B.Cu")
		(net "M_A_ECC<3>")
	)
	(segment
		(start 242.300506 -20.224242)
		(end 242.299998 -20.224242)
		(width 0.1651)
		(layer "B.Cu")
		(net "M_A_ECC<3>")
	)
	(segment
		(start 242.299998 -20.973542)
		(end 242.299744 -20.973796)
		(width 0.1651)
		(layer "B.Cu")
		(net "M_A_ECC<3>")
	)
	(segment
		(start 242.299744 -20.973796)
		(end 242.299744 -22.279356)
		(width 0.1651)
		(layer "B.Cu")
		(net "M_A_ECC<3>")
	)
	(segment
		(start 242.872768 -27.57678)
		(end 243.075968 -27.77998)
		(width 0.14224)
		(layer "In2.Cu")
		(net "M_A_ECC<3>")
	)
	(segment
		(start 249.147076 -50.366422)
		(end 249.655076 -50.874422)
		(width 0.0889)
		(layer "In2.Cu")
		(net "M_A_ECC<3>")
	)
	(segment
		(start 250.59132 -61.487304)
		(end 250.59132 -61.670692)
		(width 0.0889)
		(layer "In2.Cu")
		(net "M_A_ECC<3>")
	)
	(segment
		(start 250.724924 -58.35142)
		(end 250.718574 -58.362088)
		(width 0.0889)
		(layer "In2.Cu")
		(net "M_A_ECC<3>")
	)
	(segment
		(start 249.423936 -51.626516)
		(end 249.423936 -54.657244)
		(width 0.0889)
		(layer "In2.Cu")
		(net "M_A_ECC<3>")
	)
	(segment
		(start 249.274838 -49.323244)
		(end 249.147076 -49.451006)
		(width 0.0889)
		(layer "In2.Cu")
		(net "M_A_ECC<3>")
	)
	(segment
		(start 243.583968 -28.025344)
		(end 243.583968 -39.587424)
		(width 0.14224)
		(layer "In2.Cu")
		(net "M_A_ECC<3>")
	)
	(segment
		(start 249.655076 -51.395376)
		(end 249.423936 -51.626516)
		(width 0.0889)
		(layer "In2.Cu")
		(net "M_A_ECC<3>")
	)
	(segment
		(start 249.001534 -55.790338)
		(end 249.007884 -55.801006)
		(width 0.0889)
		(layer "In2.Cu")
		(net "M_A_ECC<3>")
	)
	(segment
		(start 242.807998 -18.380456)
		(end 242.65255 -18.535904)
		(width 0.14224)
		(layer "In2.Cu")
		(net "M_A_ECC<3>")
	)
	(segment
		(start 249.274838 -45.871638)
		(end 249.274838 -49.323244)
		(width 0.14224)
		(layer "In2.Cu")
		(net "M_A_ECC<3>")
	)
	(segment
		(start 242.299744 -22.279356)
		(end 242.791996 -22.771608)
		(width 0.14224)
		(layer "In2.Cu")
		(net "M_A_ECC<3>")
	)
	(segment
		(start 250.206764 -62.43828)
		(end 250.206764 -62.029086)
		(width 0.0889)
		(layer "In2.Cu")
		(net "M_A_ECC<3>")
	)
	(segment
		(start 250.191778 -57.476136)
		(end 250.219718 -57.476136)
		(width 0.0889)
		(layer "In2.Cu")
		(net "M_A_ECC<3>")
	)
	(segment
		(start 243.075968 -27.77998)
		(end 243.338604 -27.77998)
		(width 0.14224)
		(layer "In2.Cu")
		(net "M_A_ECC<3>")
	)
	(segment
		(start 250.718574 -59.752738)
		(end 250.724924 -59.763406)
		(width 0.0889)
		(layer "In2.Cu")
		(net "M_A_ECC<3>")
	)
	(segment
		(start 242.096798 -17.653)
		(end 242.350798 -17.653)
		(width 0.14224)
		(layer "In2.Cu")
		(net "M_A_ECC<3>")
	)
	(segment
		(start 250.59132 -61.670692)
		(end 250.831604 -61.910976)
		(width 0.0889)
		(layer "In2.Cu")
		(net "M_A_ECC<3>")
	)
	(segment
		(start 242.791996 -23.183596)
		(end 242.161568 -23.814024)
		(width 0.14224)
		(layer "In2.Cu")
		(net "M_A_ECC<3>")
	)
	(segment
		(start 242.791996 -22.771608)
		(end 242.791996 -23.183596)
		(width 0.14224)
		(layer "In2.Cu")
		(net "M_A_ECC<3>")
	)
	(segment
		(start 243.1796 -25.6794)
		(end 243.1796 -26.863548)
		(width 0.14224)
		(layer "In2.Cu")
		(net "M_A_ECC<3>")
	)
	(segment
		(start 244.9576 -42.722546)
		(end 246.380254 -44.1452)
		(width 0.14224)
		(layer "In2.Cu")
		(net "M_A_ECC<3>")
	)
	(segment
		(start 242.807998 -18.1102)
		(end 242.807998 -18.380456)
		(width 0.14224)
		(layer "In2.Cu")
		(net "M_A_ECC<3>")
	)
	(segment
		(start 242.161568 -24.661368)
		(end 243.1796 -25.6794)
		(width 0.14224)
		(layer "In2.Cu")
		(net "M_A_ECC<3>")
	)
	(segment
		(start 246.380254 -44.1452)
		(end 247.5484 -44.1452)
		(width 0.14224)
		(layer "In2.Cu")
		(net "M_A_ECC<3>")
	)
	(segment
		(start 242.872768 -27.17038)
		(end 242.872768 -27.57678)
		(width 0.14224)
		(layer "In2.Cu")
		(net "M_A_ECC<3>")
	)
	(segment
		(start 242.65255 -18.535904)
		(end 242.65255 -21.92655)
		(width 0.14224)
		(layer "In2.Cu")
		(net "M_A_ECC<3>")
	)
	(segment
		(start 250.713748 -59.744102)
		(end 250.718574 -59.752738)
		(width 0.0889)
		(layer "In2.Cu")
		(net "M_A_ECC<3>")
	)
	(segment
		(start 250.45416 -62.53734)
		(end 250.305824 -62.53734)
		(width 0.0889)
		(layer "In2.Cu")
		(net "M_A_ECC<3>")
	)
	(segment
		(start 247.5484 -44.1452)
		(end 249.274838 -45.871638)
		(width 0.14224)
		(layer "In2.Cu")
		(net "M_A_ECC<3>")
	)
	(segment
		(start 249.655076 -50.874422)
		(end 249.655076 -51.395376)
		(width 0.0889)
		(layer "In2.Cu")
		(net "M_A_ECC<3>")
	)
	(segment
		(start 250.831604 -61.910976)
		(end 250.831604 -62.159896)
		(width 0.0889)
		(layer "In2.Cu")
		(net "M_A_ECC<3>")
	)
	(segment
		(start 243.583968 -39.587424)
		(end 244.9576 -40.961056)
		(width 0.14224)
		(layer "In2.Cu")
		(net "M_A_ECC<3>")
	)
	(segment
		(start 241.766598 -17.3228)
		(end 242.096798 -17.653)
		(width 0.14224)
		(layer "In2.Cu")
		(net "M_A_ECC<3>")
	)
	(segment
		(start 241.44986 -16.687546)
		(end 241.766598 -17.004284)
		(width 0.14224)
		(layer "In2.Cu")
		(net "M_A_ECC<3>")
	)
	(segment
		(start 250.305824 -62.53734)
		(end 250.206764 -62.43828)
		(width 0.0889)
		(layer "In2.Cu")
		(net "M_A_ECC<3>")
	)
	(segment
		(start 250.713748 -60.734702)
		(end 250.718574 -60.743338)
		(width 0.0889)
		(layer "In2.Cu")
		(net "M_A_ECC<3>")
	)
	(segment
		(start 249.147076 -49.451006)
		(end 249.147076 -50.366422)
		(width 0.0889)
		(layer "In2.Cu")
		(net "M_A_ECC<3>")
	)
	(segment
		(start 243.1796 -26.863548)
		(end 242.872768 -27.17038)
		(width 0.14224)
		(layer "In2.Cu")
		(net "M_A_ECC<3>")
	)
	(segment
		(start 249.337068 -56.98109)
		(end 249.369834 -56.98109)
		(width 0.0889)
		(layer "In2.Cu")
		(net "M_A_ECC<3>")
	)
	(segment
		(start 242.350798 -17.653)
		(end 242.807998 -18.1102)
		(width 0.14224)
		(layer "In2.Cu")
		(net "M_A_ECC<3>")
	)
	(segment
		(start 250.831604 -62.159896)
		(end 250.45416 -62.53734)
		(width 0.0889)
		(layer "In2.Cu")
		(net "M_A_ECC<3>")
	)
	(segment
		(start 242.65255 -21.92655)
		(end 242.299744 -22.279356)
		(width 0.14224)
		(layer "In2.Cu")
		(net "M_A_ECC<3>")
	)
	(segment
		(start 244.9576 -40.961056)
		(end 244.9576 -42.722546)
		(width 0.14224)
		(layer "In2.Cu")
		(net "M_A_ECC<3>")
	)
	(segment
		(start 249.423936 -54.657244)
		(end 249.001534 -55.390542)
		(width 0.0889)
		(layer "In2.Cu")
		(net "M_A_ECC<3>")
	)
	(segment
		(start 243.338604 -27.77998)
		(end 243.583968 -28.025344)
		(width 0.14224)
		(layer "In2.Cu")
		(net "M_A_ECC<3>")
	)
	(segment
		(start 241.766598 -17.004284)
		(end 241.766598 -17.3228)
		(width 0.14224)
		(layer "In2.Cu")
		(net "M_A_ECC<3>")
	)
	(segment
		(start 242.161568 -23.814024)
		(end 242.161568 -24.661368)
		(width 0.14224)
		(layer "In2.Cu")
		(net "M_A_ECC<3>")
	)
	(segment
		(start 250.718574 -60.743338)
		(end 250.724924 -60.754006)
		(width 0.0889)
		(layer "In2.Cu")
		(net "M_A_ECC<3>")
	)
	(arc
		(start 250.718574 -58.362088)
		(mid 250.665075 -58.561986)
		(end 250.718574 -58.761884)
		(width 0.0889)
		(layer "In2.Cu")
		(net "M_A_ECC<3>")
	)
	(arc
		(start 250.718574 -59.352688)
		(mid 250.665104 -59.547751)
		(end 250.713748 -59.744102)
		(width 0.0889)
		(layer "In2.Cu")
		(net "M_A_ECC<3>")
	)
	(arc
		(start 250.718574 -58.761884)
		(mid 250.797705 -59.057286)
		(end 250.718574 -59.352688)
		(width 0.0889)
		(layer "In2.Cu")
		(net "M_A_ECC<3>")
	)
	(arc
		(start 249.001534 -56.380888)
		(mid 248.998786 -56.776355)
		(end 249.337068 -56.98109)
		(width 0.0889)
		(layer "In2.Cu")
		(net "M_A_ECC<3>")
	)
	(arc
		(start 249.369834 -56.98109)
		(mid 249.653051 -57.065371)
		(end 249.860054 -57.276238)
		(width 0.0889)
		(layer "In2.Cu")
		(net "M_A_ECC<3>")
	)
	(arc
		(start 249.007884 -55.801006)
		(mid 249.080682 -56.091769)
		(end 249.001534 -56.380888)
		(width 0.0889)
		(layer "In2.Cu")
		(net "M_A_ECC<3>")
	)
	(arc
		(start 250.724924 -59.763406)
		(mid 250.797722 -60.054169)
		(end 250.718574 -60.343288)
		(width 0.0889)
		(layer "In2.Cu")
		(net "M_A_ECC<3>")
	)
	(arc
		(start 250.718574 -60.343288)
		(mid 250.665104 -60.538351)
		(end 250.713748 -60.734702)
		(width 0.0889)
		(layer "In2.Cu")
		(net "M_A_ECC<3>")
	)
	(arc
		(start 250.219718 -57.476136)
		(mid 250.718599 -57.771573)
		(end 250.724924 -58.35142)
		(width 0.0889)
		(layer "In2.Cu")
		(net "M_A_ECC<3>")
	)
	(arc
		(start 250.724924 -60.754006)
		(mid 250.788316 -61.144391)
		(end 250.59132 -61.487304)
		(width 0.0889)
		(layer "In2.Cu")
		(net "M_A_ECC<3>")
	)
	(arc
		(start 249.001534 -55.390542)
		(mid 248.948035 -55.59044)
		(end 249.001534 -55.790338)
		(width 0.0889)
		(layer "In2.Cu")
		(net "M_A_ECC<3>")
	)
	(arc
		(start 249.860054 -57.276238)
		(mid 250.000133 -57.418974)
		(end 250.191778 -57.476136)
		(width 0.0889)
		(layer "In2.Cu")
		(net "M_A_ECC<3>")
	)
	(segment
		(start 242.431316 -18.89506)
		(end 242.431316 -18.67154)
		(width 0.1651)
		(layer "F.Cu")
		(net "M_A_ECC<2>")
	)
	(segment
		(start 242.300506 -20.023582)
		(end 242.300506 -19.027394)
		(width 0.1651)
		(layer "F.Cu")
		(net "M_A_ECC<2>")
	)
	(segment
		(start 250.778264 -61.038486)
		(end 250.206764 -61.038486)
		(width 0.1016)
		(layer "F.Cu")
		(net "M_A_ECC<2>")
	)
	(segment
		(start 242.431316 -18.67154)
		(end 242.299744 -18.539968)
		(width 0.1651)
		(layer "F.Cu")
		(net "M_A_ECC<2>")
	)
	(segment
		(start 242.300506 -19.027394)
		(end 242.299744 -19.026632)
		(width 0.1651)
		(layer "F.Cu")
		(net "M_A_ECC<2>")
	)
	(segment
		(start 242.299744 -18.539968)
		(end 242.299744 -18.2626)
		(width 0.1651)
		(layer "F.Cu")
		(net "M_A_ECC<2>")
	)
	(segment
		(start 242.299744 -19.026632)
		(end 242.431316 -18.89506)
		(width 0.1651)
		(layer "F.Cu")
		(net "M_A_ECC<2>")
	)
	(via
		(at 250.206764 -61.038486)
		(size 0.508)
		(drill 0.254)
		(layers "F.Cu" "B.Cu")
		(net "M_A_ECC<2>")
	)
	(via
		(at 242.299744 -18.2626)
		(size 0.508)
		(drill 0.254)
		(layers "F.Cu" "B.Cu")
		(net "M_A_ECC<2>")
	)
	(via
		(at 241.44986 -23.560278)
		(size 0.508)
		(drill 0.254)
		(layers "F.Cu" "B.Cu")
		(net "M_A_ECC<2>")
	)
	(segment
		(start 241.44986 -24.824182)
		(end 241.44986 -23.560278)
		(width 0.1651)
		(layer "B.Cu")
		(net "M_A_ECC<2>")
	)
	(segment
		(start 241.450368 -24.824182)
		(end 241.44986 -24.824182)
		(width 0.1651)
		(layer "B.Cu")
		(net "M_A_ECC<2>")
	)
	(segment
		(start 241.133376 -23.243794)
		(end 241.44986 -23.560278)
		(width 0.14224)
		(layer "In2.Cu")
		(net "M_A_ECC<2>")
	)
	(segment
		(start 242.720368 -28.640024)
		(end 242.948968 -28.868624)
		(width 0.14224)
		(layer "In2.Cu")
		(net "M_A_ECC<2>")
	)
	(segment
		(start 241.893598 -18.668746)
		(end 241.893598 -21.921724)
		(width 0.14224)
		(layer "In2.Cu")
		(net "M_A_ECC<2>")
	)
	(segment
		(start 242.948968 -41.391332)
		(end 243.290852 -41.733216)
		(width 0.14224)
		(layer "In2.Cu")
		(net "M_A_ECC<2>")
	)
	(segment
		(start 250.553474 -59.847988)
		(end 250.5583 -59.856624)
		(width 0.0889)
		(layer "In2.Cu")
		(net "M_A_ECC<2>")
	)
	(segment
		(start 242.745768 -29.568648)
		(end 241.72164 -29.568648)
		(width 0.14224)
		(layer "In2.Cu")
		(net "M_A_ECC<2>")
	)
	(segment
		(start 242.036854 -25.654)
		(end 242.2144 -25.831546)
		(width 0.14224)
		(layer "In2.Cu")
		(net "M_A_ECC<2>")
	)
	(segment
		(start 242.254024 -28.640024)
		(end 242.720368 -28.640024)
		(width 0.14224)
		(layer "In2.Cu")
		(net "M_A_ECC<2>")
	)
	(segment
		(start 241.72164 -30.4292)
		(end 242.745768 -30.4292)
		(width 0.14224)
		(layer "In2.Cu")
		(net "M_A_ECC<2>")
	)
	(segment
		(start 241.5794 -29.710888)
		(end 241.5794 -30.28696)
		(width 0.14224)
		(layer "In2.Cu")
		(net "M_A_ECC<2>")
	)
	(segment
		(start 243.49202 -41.733216)
		(end 243.908834 -41.316402)
		(width 0.14224)
		(layer "In2.Cu")
		(net "M_A_ECC<2>")
	)
	(segment
		(start 241.6302 -25.654)
		(end 242.036854 -25.654)
		(width 0.14224)
		(layer "In2.Cu")
		(net "M_A_ECC<2>")
	)
	(segment
		(start 250.547124 -59.83732)
		(end 250.553474 -59.847988)
		(width 0.0889)
		(layer "In2.Cu")
		(net "M_A_ECC<2>")
	)
	(segment
		(start 243.908834 -41.316402)
		(end 244.110002 -41.316402)
		(width 0.14224)
		(layer "In2.Cu")
		(net "M_A_ECC<2>")
	)
	(segment
		(start 244.368828 -41.575228)
		(end 244.368828 -41.776396)
		(width 0.14224)
		(layer "In2.Cu")
		(net "M_A_ECC<2>")
	)
	(segment
		(start 249.233436 -51.547522)
		(end 249.233436 -54.606698)
		(width 0.0889)
		(layer "In2.Cu")
		(net "M_A_ECC<2>")
	)
	(segment
		(start 242.948968 -28.868624)
		(end 242.948968 -29.365448)
		(width 0.14224)
		(layer "In2.Cu")
		(net "M_A_ECC<2>")
	)
	(segment
		(start 250.553474 -58.266838)
		(end 250.547124 -58.277506)
		(width 0.0889)
		(layer "In2.Cu")
		(net "M_A_ECC<2>")
	)
	(segment
		(start 241.44986 -25.47366)
		(end 241.6302 -25.654)
		(width 0.14224)
		(layer "In2.Cu")
		(net "M_A_ECC<2>")
	)
	(segment
		(start 241.44986 -23.560278)
		(end 241.44986 -25.47366)
		(width 0.14224)
		(layer "In2.Cu")
		(net "M_A_ECC<2>")
	)
	(segment
		(start 249.233436 -54.606698)
		(end 248.836434 -55.295292)
		(width 0.0889)
		(layer "In2.Cu")
		(net "M_A_ECC<2>")
	)
	(segment
		(start 249.465084 -50.95621)
		(end 249.465084 -51.315874)
		(width 0.0889)
		(layer "In2.Cu")
		(net "M_A_ECC<2>")
	)
	(segment
		(start 243.290852 -41.733216)
		(end 243.49202 -41.733216)
		(width 0.14224)
		(layer "In2.Cu")
		(net "M_A_ECC<2>")
	)
	(segment
		(start 248.957084 -49.658016)
		(end 248.957084 -50.44821)
		(width 0.0889)
		(layer "In2.Cu")
		(net "M_A_ECC<2>")
	)
	(segment
		(start 248.836434 -55.885588)
		(end 248.84126 -55.894224)
		(width 0.0889)
		(layer "In2.Cu")
		(net "M_A_ECC<2>")
	)
	(segment
		(start 244.368828 -41.776396)
		(end 243.952014 -42.19321)
		(width 0.14224)
		(layer "In2.Cu")
		(net "M_A_ECC<2>")
	)
	(segment
		(start 247.16359 -44.62399)
		(end 248.622312 -46.082712)
		(width 0.14224)
		(layer "In2.Cu")
		(net "M_A_ECC<2>")
	)
	(segment
		(start 249.465084 -51.315874)
		(end 249.233436 -51.547522)
		(width 0.0889)
		(layer "In2.Cu")
		(net "M_A_ECC<2>")
	)
	(segment
		(start 241.72164 -29.568648)
		(end 241.5794 -29.710888)
		(width 0.14224)
		(layer "In2.Cu")
		(net "M_A_ECC<2>")
	)
	(segment
		(start 248.957084 -50.44821)
		(end 249.465084 -50.95621)
		(width 0.0889)
		(layer "In2.Cu")
		(net "M_A_ECC<2>")
	)
	(segment
		(start 246.181626 -44.62399)
		(end 247.16359 -44.62399)
		(width 0.14224)
		(layer "In2.Cu")
		(net "M_A_ECC<2>")
	)
	(segment
		(start 241.935 -28.321)
		(end 242.254024 -28.640024)
		(width 0.14224)
		(layer "In2.Cu")
		(net "M_A_ECC<2>")
	)
	(segment
		(start 241.935 -27.686)
		(end 241.935 -28.321)
		(width 0.14224)
		(layer "In2.Cu")
		(net "M_A_ECC<2>")
	)
	(segment
		(start 242.948968 -30.6324)
		(end 242.948968 -41.391332)
		(width 0.14224)
		(layer "In2.Cu")
		(net "M_A_ECC<2>")
	)
	(segment
		(start 242.2144 -26.035)
		(end 241.775996 -26.473404)
		(width 0.14224)
		(layer "In2.Cu")
		(net "M_A_ECC<2>")
	)
	(segment
		(start 242.299744 -18.2626)
		(end 241.893598 -18.668746)
		(width 0.14224)
		(layer "In2.Cu")
		(net "M_A_ECC<2>")
	)
	(segment
		(start 250.553474 -58.857388)
		(end 250.5583 -58.866024)
		(width 0.0889)
		(layer "In2.Cu")
		(net "M_A_ECC<2>")
	)
	(segment
		(start 250.19381 -57.66689)
		(end 250.21794 -57.66689)
		(width 0.0889)
		(layer "In2.Cu")
		(net "M_A_ECC<2>")
	)
	(segment
		(start 243.952014 -42.394378)
		(end 246.181626 -44.62399)
		(width 0.14224)
		(layer "In2.Cu")
		(net "M_A_ECC<2>")
	)
	(segment
		(start 244.110002 -41.316402)
		(end 244.368828 -41.575228)
		(width 0.14224)
		(layer "In2.Cu")
		(net "M_A_ECC<2>")
	)
	(segment
		(start 243.952014 -42.19321)
		(end 243.952014 -42.394378)
		(width 0.14224)
		(layer "In2.Cu")
		(net "M_A_ECC<2>")
	)
	(segment
		(start 242.2144 -25.831546)
		(end 242.2144 -26.035)
		(width 0.14224)
		(layer "In2.Cu")
		(net "M_A_ECC<2>")
	)
	(segment
		(start 242.745768 -30.4292)
		(end 242.948968 -30.6324)
		(width 0.14224)
		(layer "In2.Cu")
		(net "M_A_ECC<2>")
	)
	(segment
		(start 242.948968 -29.365448)
		(end 242.745768 -29.568648)
		(width 0.14224)
		(layer "In2.Cu")
		(net "M_A_ECC<2>")
	)
	(segment
		(start 241.893598 -21.921724)
		(end 241.133376 -22.681946)
		(width 0.14224)
		(layer "In2.Cu")
		(net "M_A_ECC<2>")
	)
	(segment
		(start 248.622312 -49.323244)
		(end 248.957084 -49.658016)
		(width 0.0889)
		(layer "In2.Cu")
		(net "M_A_ECC<2>")
	)
	(segment
		(start 241.775996 -26.473404)
		(end 241.775996 -27.526996)
		(width 0.14224)
		(layer "In2.Cu")
		(net "M_A_ECC<2>")
	)
	(segment
		(start 241.133376 -22.681946)
		(end 241.133376 -23.243794)
		(width 0.14224)
		(layer "In2.Cu")
		(net "M_A_ECC<2>")
	)
	(segment
		(start 241.775996 -27.526996)
		(end 241.935 -27.686)
		(width 0.14224)
		(layer "In2.Cu")
		(net "M_A_ECC<2>")
	)
	(segment
		(start 250.49734 -60.380372)
		(end 250.206764 -61.038486)
		(width 0.0889)
		(layer "In2.Cu")
		(net "M_A_ECC<2>")
	)
	(segment
		(start 248.622312 -46.082712)
		(end 248.622312 -49.323244)
		(width 0.14224)
		(layer "In2.Cu")
		(net "M_A_ECC<2>")
	)
	(segment
		(start 241.5794 -30.28696)
		(end 241.72164 -30.4292)
		(width 0.14224)
		(layer "In2.Cu")
		(net "M_A_ECC<2>")
	)
	(segment
		(start 249.330464 -57.17159)
		(end 249.36323 -57.17159)
		(width 0.0889)
		(layer "In2.Cu")
		(net "M_A_ECC<2>")
	)
	(arc
		(start 248.836434 -56.285638)
		(mid 248.832105 -56.86881)
		(end 249.330464 -57.17159)
		(width 0.0889)
		(layer "In2.Cu")
		(net "M_A_ECC<2>")
	)
	(arc
		(start 250.5583 -59.856624)
		(mid 250.607055 -60.052976)
		(end 250.553474 -60.248038)
		(width 0.0889)
		(layer "In2.Cu")
		(net "M_A_ECC<2>")
	)
	(arc
		(start 250.5583 -58.866024)
		(mid 250.607055 -59.062376)
		(end 250.553474 -59.257438)
		(width 0.0889)
		(layer "In2.Cu")
		(net "M_A_ECC<2>")
	)
	(arc
		(start 250.547124 -58.277506)
		(mid 250.474326 -58.568269)
		(end 250.553474 -58.857388)
		(width 0.0889)
		(layer "In2.Cu")
		(net "M_A_ECC<2>")
	)
	(arc
		(start 248.84126 -55.894224)
		(mid 248.890015 -56.090576)
		(end 248.836434 -56.285638)
		(width 0.0889)
		(layer "In2.Cu")
		(net "M_A_ECC<2>")
	)
	(arc
		(start 249.694954 -57.371488)
		(mid 249.905667 -57.584567)
		(end 250.19381 -57.66689)
		(width 0.0889)
		(layer "In2.Cu")
		(net "M_A_ECC<2>")
	)
	(arc
		(start 250.553474 -59.257438)
		(mid 250.474252 -59.546556)
		(end 250.547124 -59.83732)
		(width 0.0889)
		(layer "In2.Cu")
		(net "M_A_ECC<2>")
	)
	(arc
		(start 248.836434 -55.295292)
		(mid 248.757429 -55.59044)
		(end 248.836434 -55.885588)
		(width 0.0889)
		(layer "In2.Cu")
		(net "M_A_ECC<2>")
	)
	(arc
		(start 249.36323 -57.17159)
		(mid 249.554872 -57.228756)
		(end 249.694954 -57.371488)
		(width 0.0889)
		(layer "In2.Cu")
		(net "M_A_ECC<2>")
	)
	(arc
		(start 250.21794 -57.66689)
		(mid 250.556055 -57.871592)
		(end 250.553474 -58.266838)
		(width 0.0889)
		(layer "In2.Cu")
		(net "M_A_ECC<2>")
	)
	(arc
		(start 250.553474 -60.248038)
		(mid 250.521383 -60.312497)
		(end 250.49734 -60.380372)
		(width 0.0889)
		(layer "In2.Cu")
		(net "M_A_ECC<2>")
	)
	(segment
		(start 248.202704 -62.52464)
		(end 247.631204 -62.52464)
		(width 0.1016)
		(layer "F.Cu")
		(net "M_A_ECC<1>")
	)
	(segment
		(start 235.500418 -15.423642)
		(end 235.49991 -15.423642)
		(width 0.1651)
		(layer "F.Cu")
		(net "M_A_ECC<1>")
	)
	(segment
		(start 235.49991 -15.423642)
		(end 235.49991 -16.687546)
		(width 0.1651)
		(layer "F.Cu")
		(net "M_A_ECC<1>")
	)
	(via
		(at 247.631204 -62.52464)
		(size 0.508)
		(drill 0.254)
		(layers "F.Cu" "B.Cu")
		(net "M_A_ECC<1>")
	)
	(via
		(at 235.49991 -16.687546)
		(size 0.508)
		(drill 0.254)
		(layers "F.Cu" "B.Cu")
		(net "M_A_ECC<1>")
	)
	(via
		(at 236.171994 -22.279356)
		(size 0.508)
		(drill 0.254)
		(layers "F.Cu" "B.Cu")
		(net "M_A_ECC<1>")
	)
	(segment
		(start 236.171994 -21.776182)
		(end 236.171994 -22.279356)
		(width 0.1651)
		(layer "B.Cu")
		(net "M_A_ECC<1>")
	)
	(segment
		(start 236.350302 -20.224242)
		(end 236.349794 -20.224242)
		(width 0.1651)
		(layer "B.Cu")
		(net "M_A_ECC<1>")
	)
	(segment
		(start 236.349794 -20.224242)
		(end 236.349794 -21.598382)
		(width 0.1651)
		(layer "B.Cu")
		(net "M_A_ECC<1>")
	)
	(segment
		(start 236.349794 -21.598382)
		(end 236.171994 -21.776182)
		(width 0.1651)
		(layer "B.Cu")
		(net "M_A_ECC<1>")
	)
	(segment
		(start 236.7026 -18.073624)
		(end 236.7026 -18.415)
		(width 0.14224)
		(layer "In2.Cu")
		(net "M_A_ECC<1>")
	)
	(segment
		(start 247.231154 -61.740034)
		(end 247.382284 -61.891164)
		(width 0.0889)
		(layer "In2.Cu")
		(net "M_A_ECC<1>")
	)
	(segment
		(start 237.208568 -29.461714)
		(end 237.208568 -40.31234)
		(width 0.14224)
		(layer "In2.Cu")
		(net "M_A_ECC<1>")
	)
	(segment
		(start 247.231154 -63.057024)
		(end 247.283224 -63.109094)
		(width 0.0889)
		(layer "In2.Cu")
		(net "M_A_ECC<1>")
	)
	(segment
		(start 236.546136 -18.571464)
		(end 236.546136 -21.905214)
		(width 0.14224)
		(layer "In2.Cu")
		(net "M_A_ECC<1>")
	)
	(segment
		(start 236.546136 -21.905214)
		(end 236.171994 -22.279356)
		(width 0.14224)
		(layer "In2.Cu")
		(net "M_A_ECC<1>")
	)
	(segment
		(start 245.573804 -58.35142)
		(end 245.567454 -58.362088)
		(width 0.0889)
		(layer "In2.Cu")
		(net "M_A_ECC<1>")
	)
	(segment
		(start 245.902988 -58.962036)
		(end 245.927118 -58.962036)
		(width 0.0889)
		(layer "In2.Cu")
		(net "M_A_ECC<1>")
	)
	(segment
		(start 245.562628 -57.762902)
		(end 245.567454 -57.771538)
		(width 0.0889)
		(layer "In2.Cu")
		(net "M_A_ECC<1>")
	)
	(segment
		(start 246.757698 -59.457336)
		(end 246.790464 -59.457336)
		(width 0.0889)
		(layer "In2.Cu")
		(net "M_A_ECC<1>")
	)
	(segment
		(start 245.794276 -51.648614)
		(end 245.794276 -52.698396)
		(width 0.0889)
		(layer "In2.Cu")
		(net "M_A_ECC<1>")
	)
	(segment
		(start 245.567454 -55.790338)
		(end 245.573804 -55.801006)
		(width 0.0889)
		(layer "In2.Cu")
		(net "M_A_ECC<1>")
	)
	(segment
		(start 244.214904 -47.318676)
		(end 244.214904 -49.273714)
		(width 0.14224)
		(layer "In2.Cu")
		(net "M_A_ECC<1>")
	)
	(segment
		(start 247.504204 -63.109094)
		(end 247.631204 -62.982094)
		(width 0.0889)
		(layer "In2.Cu")
		(net "M_A_ECC<1>")
	)
	(segment
		(start 236.171994 -22.279356)
		(end 235.654596 -22.796754)
		(width 0.14224)
		(layer "In2.Cu")
		(net "M_A_ECC<1>")
	)
	(segment
		(start 247.631204 -62.982094)
		(end 247.631204 -62.52464)
		(width 0.0889)
		(layer "In2.Cu")
		(net "M_A_ECC<1>")
	)
	(segment
		(start 235.49991 -16.687546)
		(end 235.49991 -17.226534)
		(width 0.14224)
		(layer "In2.Cu")
		(net "M_A_ECC<1>")
	)
	(segment
		(start 243.975636 -49.829974)
		(end 245.794276 -51.648614)
		(width 0.0889)
		(layer "In2.Cu")
		(net "M_A_ECC<1>")
	)
	(segment
		(start 247.231154 -61.538866)
		(end 247.231154 -61.740034)
		(width 0.0889)
		(layer "In2.Cu")
		(net "M_A_ECC<1>")
	)
	(segment
		(start 247.283224 -63.109094)
		(end 247.504204 -63.109094)
		(width 0.0889)
		(layer "In2.Cu")
		(net "M_A_ECC<1>")
	)
	(segment
		(start 237.208568 -40.31234)
		(end 244.214904 -47.318676)
		(width 0.14224)
		(layer "In2.Cu")
		(net "M_A_ECC<1>")
	)
	(segment
		(start 236.657896 -26.285952)
		(end 236.657896 -28.911042)
		(width 0.14224)
		(layer "In2.Cu")
		(net "M_A_ECC<1>")
	)
	(segment
		(start 235.49991 -17.226534)
		(end 235.977176 -17.7038)
		(width 0.14224)
		(layer "In2.Cu")
		(net "M_A_ECC<1>")
	)
	(segment
		(start 235.977176 -17.7038)
		(end 236.332776 -17.7038)
		(width 0.14224)
		(layer "In2.Cu")
		(net "M_A_ECC<1>")
	)
	(segment
		(start 247.382284 -62.103254)
		(end 247.231154 -62.254384)
		(width 0.0889)
		(layer "In2.Cu")
		(net "M_A_ECC<1>")
	)
	(segment
		(start 245.794276 -52.698396)
		(end 245.676674 -52.815998)
		(width 0.0889)
		(layer "In2.Cu")
		(net "M_A_ECC<1>")
	)
	(segment
		(start 245.567454 -56.780938)
		(end 245.573804 -56.791606)
		(width 0.0889)
		(layer "In2.Cu")
		(net "M_A_ECC<1>")
	)
	(segment
		(start 245.676674 -55.215282)
		(end 245.567454 -55.390542)
		(width 0.0889)
		(layer "In2.Cu")
		(net "M_A_ECC<1>")
	)
	(segment
		(start 236.111796 -25.739852)
		(end 236.657896 -26.285952)
		(width 0.14224)
		(layer "In2.Cu")
		(net "M_A_ECC<1>")
	)
	(segment
		(start 236.7026 -18.415)
		(end 236.546136 -18.571464)
		(width 0.14224)
		(layer "In2.Cu")
		(net "M_A_ECC<1>")
	)
	(segment
		(start 244.214904 -49.273714)
		(end 243.975636 -49.512982)
		(width 0.0889)
		(layer "In2.Cu")
		(net "M_A_ECC<1>")
	)
	(segment
		(start 245.562628 -56.772302)
		(end 245.567454 -56.780938)
		(width 0.0889)
		(layer "In2.Cu")
		(net "M_A_ECC<1>")
	)
	(segment
		(start 236.657896 -28.911042)
		(end 237.208568 -29.461714)
		(width 0.14224)
		(layer "In2.Cu")
		(net "M_A_ECC<1>")
	)
	(segment
		(start 236.111796 -23.539196)
		(end 236.111796 -25.739852)
		(width 0.14224)
		(layer "In2.Cu")
		(net "M_A_ECC<1>")
	)
	(segment
		(start 247.382284 -61.891164)
		(end 247.382284 -62.103254)
		(width 0.0889)
		(layer "In2.Cu")
		(net "M_A_ECC<1>")
	)
	(segment
		(start 236.332776 -17.7038)
		(end 236.7026 -18.073624)
		(width 0.14224)
		(layer "In2.Cu")
		(net "M_A_ECC<1>")
	)
	(segment
		(start 245.676674 -52.815998)
		(end 245.676674 -55.215282)
		(width 0.0889)
		(layer "In2.Cu")
		(net "M_A_ECC<1>")
	)
	(segment
		(start 243.975636 -49.512982)
		(end 243.975636 -49.829974)
		(width 0.0889)
		(layer "In2.Cu")
		(net "M_A_ECC<1>")
	)
	(segment
		(start 235.654596 -23.081996)
		(end 236.111796 -23.539196)
		(width 0.14224)
		(layer "In2.Cu")
		(net "M_A_ECC<1>")
	)
	(segment
		(start 235.654596 -22.796754)
		(end 235.654596 -23.081996)
		(width 0.14224)
		(layer "In2.Cu")
		(net "M_A_ECC<1>")
	)
	(segment
		(start 247.231154 -62.254384)
		(end 247.231154 -63.057024)
		(width 0.0889)
		(layer "In2.Cu")
		(net "M_A_ECC<1>")
	)
	(arc
		(start 245.927118 -58.962036)
		(mid 246.215263 -59.044355)
		(end 246.425974 -59.257438)
		(width 0.0889)
		(layer "In2.Cu")
		(net "M_A_ECC<1>")
	)
	(arc
		(start 245.567454 -56.380888)
		(mid 245.513984 -56.575951)
		(end 245.562628 -56.772302)
		(width 0.0889)
		(layer "In2.Cu")
		(net "M_A_ECC<1>")
	)
	(arc
		(start 245.567454 -57.371488)
		(mid 245.513984 -57.566551)
		(end 245.562628 -57.762902)
		(width 0.0889)
		(layer "In2.Cu")
		(net "M_A_ECC<1>")
	)
	(arc
		(start 246.425974 -59.257438)
		(mid 246.566053 -59.400174)
		(end 246.757698 -59.457336)
		(width 0.0889)
		(layer "In2.Cu")
		(net "M_A_ECC<1>")
	)
	(arc
		(start 247.477788 -61.164216)
		(mid 247.297003 -61.313722)
		(end 247.231154 -61.538866)
		(width 0.0889)
		(layer "In2.Cu")
		(net "M_A_ECC<1>")
	)
	(arc
		(start 245.567454 -57.771538)
		(mid 245.646676 -58.060656)
		(end 245.573804 -58.35142)
		(width 0.0889)
		(layer "In2.Cu")
		(net "M_A_ECC<1>")
	)
	(arc
		(start 245.567454 -58.362088)
		(mid 245.564871 -58.757335)
		(end 245.902988 -58.962036)
		(width 0.0889)
		(layer "In2.Cu")
		(net "M_A_ECC<1>")
	)
	(arc
		(start 247.284494 -59.752484)
		(mid 247.494455 -60.004271)
		(end 247.777 -60.170568)
		(width 0.0889)
		(layer "In2.Cu")
		(net "M_A_ECC<1>")
	)
	(arc
		(start 245.573804 -55.801006)
		(mid 245.646602 -56.091769)
		(end 245.567454 -56.380888)
		(width 0.0889)
		(layer "In2.Cu")
		(net "M_A_ECC<1>")
	)
	(arc
		(start 246.790464 -59.457336)
		(mid 247.075901 -59.540609)
		(end 247.284494 -59.752484)
		(width 0.0889)
		(layer "In2.Cu")
		(net "M_A_ECC<1>")
	)
	(arc
		(start 247.948704 -60.786772)
		(mid 247.740069 -61.008966)
		(end 247.477788 -61.164216)
		(width 0.0889)
		(layer "In2.Cu")
		(net "M_A_ECC<1>")
	)
	(arc
		(start 247.777 -60.170568)
		(mid 248.016651 -60.435801)
		(end 247.948704 -60.786772)
		(width 0.0889)
		(layer "In2.Cu")
		(net "M_A_ECC<1>")
	)
	(arc
		(start 245.573804 -56.791606)
		(mid 245.646602 -57.082369)
		(end 245.567454 -57.371488)
		(width 0.0889)
		(layer "In2.Cu")
		(net "M_A_ECC<1>")
	)
	(arc
		(start 245.567454 -55.390542)
		(mid 245.513955 -55.59044)
		(end 245.567454 -55.790338)
		(width 0.0889)
		(layer "In2.Cu")
		(net "M_A_ECC<1>")
	)
	(segment
		(start 236.350302 -20.023582)
		(end 236.349794 -20.023582)
		(width 0.1651)
		(layer "F.Cu")
		(net "M_A_ECC<0>")
	)
	(segment
		(start 236.349794 -20.023582)
		(end 236.269022 -19.177)
		(width 0.1651)
		(layer "F.Cu")
		(net "M_A_ECC<0>")
	)
	(segment
		(start 236.269022 -19.177)
		(end 236.171994 -18.161)
		(width 0.1651)
		(layer "F.Cu")
		(net "M_A_ECC<0>")
	)
	(segment
		(start 248.202704 -60.54344)
		(end 247.631204 -60.54344)
		(width 0.1016)
		(layer "F.Cu")
		(net "M_A_ECC<0>")
	)
	(via
		(at 235.49991 -23.560278)
		(size 0.508)
		(drill 0.254)
		(layers "F.Cu" "B.Cu")
		(net "M_A_ECC<0>")
	)
	(via
		(at 247.631204 -60.54344)
		(size 0.508)
		(drill 0.254)
		(layers "F.Cu" "B.Cu")
		(net "M_A_ECC<0>")
	)
	(via
		(at 236.171994 -18.161)
		(size 0.508)
		(drill 0.254)
		(layers "F.Cu" "B.Cu")
		(net "M_A_ECC<0>")
	)
	(segment
		(start 235.49991 -24.824182)
		(end 235.49991 -23.560278)
		(width 0.1651)
		(layer "B.Cu")
		(net "M_A_ECC<0>")
	)
	(segment
		(start 235.500418 -24.824182)
		(end 235.49991 -24.824182)
		(width 0.1651)
		(layer "B.Cu")
		(net "M_A_ECC<0>")
	)
	(segment
		(start 247.224042 -60.343796)
		(end 247.224042 -60.469272)
		(width 0.0889)
		(layer "In2.Cu")
		(net "M_A_ECC<0>")
	)
	(segment
		(start 241.848894 -46.522894)
		(end 242.067842 -46.522894)
		(width 0.14224)
		(layer "In2.Cu")
		(net "M_A_ECC<0>")
	)
	(segment
		(start 237.122208 -40.903144)
		(end 237.122208 -41.122092)
		(width 0.14224)
		(layer "In2.Cu")
		(net "M_A_ECC<0>")
	)
	(segment
		(start 240.918238 -45.37329)
		(end 241.145822 -45.145706)
		(width 0.14224)
		(layer "In2.Cu")
		(net "M_A_ECC<0>")
	)
	(segment
		(start 242.067842 -46.522894)
		(end 242.295426 -46.29531)
		(width 0.14224)
		(layer "In2.Cu")
		(net "M_A_ECC<0>")
	)
	(segment
		(start 239.768634 -44.223686)
		(end 239.996218 -43.996102)
		(width 0.14224)
		(layer "In2.Cu")
		(net "M_A_ECC<0>")
	)
	(segment
		(start 240.57102 -44.351956)
		(end 240.57102 -44.570904)
		(width 0.14224)
		(layer "In2.Cu")
		(net "M_A_ECC<0>")
	)
	(segment
		(start 237.250478 -41.924478)
		(end 237.469426 -41.924478)
		(width 0.14224)
		(layer "In2.Cu")
		(net "M_A_ECC<0>")
	)
	(segment
		(start 238.400082 -43.074082)
		(end 238.61903 -43.074082)
		(width 0.14224)
		(layer "In2.Cu")
		(net "M_A_ECC<0>")
	)
	(segment
		(start 237.469426 -41.924478)
		(end 237.69701 -41.696894)
		(width 0.14224)
		(layer "In2.Cu")
		(net "M_A_ECC<0>")
	)
	(segment
		(start 246.751094 -59.647836)
		(end 246.78386 -59.647836)
		(width 0.0889)
		(layer "In2.Cu")
		(net "M_A_ECC<0>")
	)
	(segment
		(start 245.402354 -58.266838)
		(end 245.396004 -58.277506)
		(width 0.0889)
		(layer "In2.Cu")
		(net "M_A_ECC<0>")
	)
	(segment
		(start 245.396004 -56.86552)
		(end 245.402354 -56.876188)
		(width 0.0889)
		(layer "In2.Cu")
		(net "M_A_ECC<0>")
	)
	(segment
		(start 236.040168 -26.419556)
		(end 236.040168 -26.633424)
		(width 0.14224)
		(layer "In2.Cu")
		(net "M_A_ECC<0>")
	)
	(segment
		(start 240.343436 -45.017436)
		(end 240.69929 -45.37329)
		(width 0.14224)
		(layer "In2.Cu")
		(net "M_A_ECC<0>")
	)
	(segment
		(start 235.49991 -23.560278)
		(end 235.578396 -23.638764)
		(width 0.14224)
		(layer "In2.Cu")
		(net "M_A_ECC<0>")
	)
	(segment
		(start 235.984796 -29.177742)
		(end 236.1692 -29.362146)
		(width 0.14224)
		(layer "In2.Cu")
		(net "M_A_ECC<0>")
	)
	(segment
		(start 241.145822 -45.145706)
		(end 241.36477 -45.145706)
		(width 0.14224)
		(layer "In2.Cu")
		(net "M_A_ECC<0>")
	)
	(segment
		(start 236.1692 -39.950136)
		(end 237.122208 -40.903144)
		(width 0.14224)
		(layer "In2.Cu")
		(net "M_A_ECC<0>")
	)
	(segment
		(start 236.171994 -18.161)
		(end 235.951776 -18.381218)
		(width 0.14224)
		(layer "In2.Cu")
		(net "M_A_ECC<0>")
	)
	(segment
		(start 238.271812 -42.271696)
		(end 238.044228 -42.49928)
		(width 0.14224)
		(layer "In2.Cu")
		(net "M_A_ECC<0>")
	)
	(segment
		(start 239.193832 -43.648884)
		(end 239.193832 -43.867832)
		(width 0.14224)
		(layer "In2.Cu")
		(net "M_A_ECC<0>")
	)
	(segment
		(start 245.604284 -51.727354)
		(end 245.604284 -52.618894)
		(width 0.0889)
		(layer "In2.Cu")
		(net "M_A_ECC<0>")
	)
	(segment
		(start 241.720624 -45.720508)
		(end 241.49304 -45.948092)
		(width 0.14224)
		(layer "In2.Cu")
		(net "M_A_ECC<0>")
	)
	(segment
		(start 239.193832 -43.867832)
		(end 239.549686 -44.223686)
		(width 0.14224)
		(layer "In2.Cu")
		(net "M_A_ECC<0>")
	)
	(segment
		(start 240.57102 -44.570904)
		(end 240.343436 -44.798488)
		(width 0.14224)
		(layer "In2.Cu")
		(net "M_A_ECC<0>")
	)
	(segment
		(start 242.514374 -46.29531)
		(end 243.6368 -47.417736)
		(width 0.14224)
		(layer "In2.Cu")
		(net "M_A_ECC<0>")
	)
	(segment
		(start 235.215176 -22.5298)
		(end 235.215176 -23.275544)
		(width 0.14224)
		(layer "In2.Cu")
		(net "M_A_ECC<0>")
	)
	(segment
		(start 240.69929 -45.37329)
		(end 240.918238 -45.37329)
		(width 0.14224)
		(layer "In2.Cu")
		(net "M_A_ECC<0>")
	)
	(segment
		(start 245.604284 -52.618894)
		(end 245.486174 -52.737004)
		(width 0.0889)
		(layer "In2.Cu")
		(net "M_A_ECC<0>")
	)
	(segment
		(start 245.402354 -56.876188)
		(end 245.40718 -56.884824)
		(width 0.0889)
		(layer "In2.Cu")
		(net "M_A_ECC<0>")
	)
	(segment
		(start 235.679996 -26.993596)
		(end 235.679996 -28.034996)
		(width 0.14224)
		(layer "In2.Cu")
		(net "M_A_ECC<0>")
	)
	(segment
		(start 243.785644 -49.908714)
		(end 245.604284 -51.727354)
		(width 0.0889)
		(layer "In2.Cu")
		(net "M_A_ECC<0>")
	)
	(segment
		(start 245.402354 -55.885588)
		(end 245.40718 -55.894224)
		(width 0.0889)
		(layer "In2.Cu")
		(net "M_A_ECC<0>")
	)
	(segment
		(start 247.29821 -60.54344)
		(end 247.631204 -60.54344)
		(width 0.0889)
		(layer "In2.Cu")
		(net "M_A_ECC<0>")
	)
	(segment
		(start 247.28043 -60.150248)
		(end 247.28043 -60.287408)
		(width 0.0889)
		(layer "In2.Cu")
		(net "M_A_ECC<0>")
	)
	(segment
		(start 235.215176 -23.275544)
		(end 235.49991 -23.560278)
		(width 0.14224)
		(layer "In2.Cu")
		(net "M_A_ECC<0>")
	)
	(segment
		(start 237.69701 -41.696894)
		(end 237.915958 -41.696894)
		(width 0.14224)
		(layer "In2.Cu")
		(net "M_A_ECC<0>")
	)
	(segment
		(start 241.49304 -46.16704)
		(end 241.848894 -46.522894)
		(width 0.14224)
		(layer "In2.Cu")
		(net "M_A_ECC<0>")
	)
	(segment
		(start 247.119394 -59.847988)
		(end 247.123458 -59.8551)
		(width 0.0889)
		(layer "In2.Cu")
		(net "M_A_ECC<0>")
	)
	(segment
		(start 238.044228 -42.718228)
		(end 238.400082 -43.074082)
		(width 0.14224)
		(layer "In2.Cu")
		(net "M_A_ECC<0>")
	)
	(segment
		(start 238.846614 -42.846498)
		(end 239.065562 -42.846498)
		(width 0.14224)
		(layer "In2.Cu")
		(net "M_A_ECC<0>")
	)
	(segment
		(start 241.49304 -45.948092)
		(end 241.49304 -46.16704)
		(width 0.14224)
		(layer "In2.Cu")
		(net "M_A_ECC<0>")
	)
	(segment
		(start 235.679996 -28.034996)
		(end 235.984796 -28.339796)
		(width 0.14224)
		(layer "In2.Cu")
		(net "M_A_ECC<0>")
	)
	(segment
		(start 235.578396 -25.957784)
		(end 236.040168 -26.419556)
		(width 0.14224)
		(layer "In2.Cu")
		(net "M_A_ECC<0>")
	)
	(segment
		(start 235.951776 -18.381218)
		(end 235.951776 -21.7932)
		(width 0.14224)
		(layer "In2.Cu")
		(net "M_A_ECC<0>")
	)
	(segment
		(start 236.894624 -41.568624)
		(end 237.250478 -41.924478)
		(width 0.14224)
		(layer "In2.Cu")
		(net "M_A_ECC<0>")
	)
	(segment
		(start 236.1692 -29.362146)
		(end 236.1692 -39.950136)
		(width 0.14224)
		(layer "In2.Cu")
		(net "M_A_ECC<0>")
	)
	(segment
		(start 235.984796 -28.339796)
		(end 235.984796 -29.177742)
		(width 0.14224)
		(layer "In2.Cu")
		(net "M_A_ECC<0>")
	)
	(segment
		(start 239.549686 -44.223686)
		(end 239.768634 -44.223686)
		(width 0.14224)
		(layer "In2.Cu")
		(net "M_A_ECC<0>")
	)
	(segment
		(start 239.996218 -43.996102)
		(end 240.215166 -43.996102)
		(width 0.14224)
		(layer "In2.Cu")
		(net "M_A_ECC<0>")
	)
	(segment
		(start 236.040168 -26.633424)
		(end 235.679996 -26.993596)
		(width 0.14224)
		(layer "In2.Cu")
		(net "M_A_ECC<0>")
	)
	(segment
		(start 247.224042 -60.469272)
		(end 247.29821 -60.54344)
		(width 0.0889)
		(layer "In2.Cu")
		(net "M_A_ECC<0>")
	)
	(segment
		(start 236.894624 -41.349676)
		(end 236.894624 -41.568624)
		(width 0.14224)
		(layer "In2.Cu")
		(net "M_A_ECC<0>")
	)
	(segment
		(start 235.578396 -23.638764)
		(end 235.578396 -25.957784)
		(width 0.14224)
		(layer "In2.Cu")
		(net "M_A_ECC<0>")
	)
	(segment
		(start 245.486174 -55.136542)
		(end 245.402354 -55.295292)
		(width 0.0889)
		(layer "In2.Cu")
		(net "M_A_ECC<0>")
	)
	(segment
		(start 247.28043 -60.287408)
		(end 247.224042 -60.343796)
		(width 0.0889)
		(layer "In2.Cu")
		(net "M_A_ECC<0>")
	)
	(segment
		(start 241.720624 -45.50156)
		(end 241.720624 -45.720508)
		(width 0.14224)
		(layer "In2.Cu")
		(net "M_A_ECC<0>")
	)
	(segment
		(start 245.90121 -59.15279)
		(end 245.92915 -59.15279)
		(width 0.0889)
		(layer "In2.Cu")
		(net "M_A_ECC<0>")
	)
	(segment
		(start 239.065562 -42.846498)
		(end 239.421416 -43.202352)
		(width 0.14224)
		(layer "In2.Cu")
		(net "M_A_ECC<0>")
	)
	(segment
		(start 245.486174 -52.737004)
		(end 245.486174 -55.136542)
		(width 0.0889)
		(layer "In2.Cu")
		(net "M_A_ECC<0>")
	)
	(segment
		(start 235.951776 -21.7932)
		(end 235.215176 -22.5298)
		(width 0.14224)
		(layer "In2.Cu")
		(net "M_A_ECC<0>")
	)
	(segment
		(start 243.6368 -49.34331)
		(end 243.785644 -49.492154)
		(width 0.0889)
		(layer "In2.Cu")
		(net "M_A_ECC<0>")
	)
	(segment
		(start 243.785644 -49.492154)
		(end 243.785644 -49.908714)
		(width 0.0889)
		(layer "In2.Cu")
		(net "M_A_ECC<0>")
	)
	(segment
		(start 239.421416 -43.4213)
		(end 239.193832 -43.648884)
		(width 0.14224)
		(layer "In2.Cu")
		(net "M_A_ECC<0>")
	)
	(segment
		(start 240.215166 -43.996102)
		(end 240.57102 -44.351956)
		(width 0.14224)
		(layer "In2.Cu")
		(net "M_A_ECC<0>")
	)
	(segment
		(start 237.915958 -41.696894)
		(end 238.271812 -42.052748)
		(width 0.14224)
		(layer "In2.Cu")
		(net "M_A_ECC<0>")
	)
	(segment
		(start 237.122208 -41.122092)
		(end 236.894624 -41.349676)
		(width 0.14224)
		(layer "In2.Cu")
		(net "M_A_ECC<0>")
	)
	(segment
		(start 238.61903 -43.074082)
		(end 238.846614 -42.846498)
		(width 0.14224)
		(layer "In2.Cu")
		(net "M_A_ECC<0>")
	)
	(segment
		(start 241.36477 -45.145706)
		(end 241.720624 -45.50156)
		(width 0.14224)
		(layer "In2.Cu")
		(net "M_A_ECC<0>")
	)
	(segment
		(start 242.295426 -46.29531)
		(end 242.514374 -46.29531)
		(width 0.14224)
		(layer "In2.Cu")
		(net "M_A_ECC<0>")
	)
	(segment
		(start 238.044228 -42.49928)
		(end 238.044228 -42.718228)
		(width 0.14224)
		(layer "In2.Cu")
		(net "M_A_ECC<0>")
	)
	(segment
		(start 243.6368 -47.417736)
		(end 243.6368 -49.34331)
		(width 0.14224)
		(layer "In2.Cu")
		(net "M_A_ECC<0>")
	)
	(segment
		(start 240.343436 -44.798488)
		(end 240.343436 -45.017436)
		(width 0.14224)
		(layer "In2.Cu")
		(net "M_A_ECC<0>")
	)
	(segment
		(start 238.271812 -42.052748)
		(end 238.271812 -42.271696)
		(width 0.14224)
		(layer "In2.Cu")
		(net "M_A_ECC<0>")
	)
	(segment
		(start 239.421416 -43.202352)
		(end 239.421416 -43.4213)
		(width 0.14224)
		(layer "In2.Cu")
		(net "M_A_ECC<0>")
	)
	(arc
		(start 245.40718 -56.884824)
		(mid 245.455935 -57.081176)
		(end 245.402354 -57.276238)
		(width 0.0889)
		(layer "In2.Cu")
		(net "M_A_ECC<0>")
	)
	(arc
		(start 245.402354 -57.867042)
		(mid 245.455853 -58.06694)
		(end 245.402354 -58.266838)
		(width 0.0889)
		(layer "In2.Cu")
		(net "M_A_ECC<0>")
	)
	(arc
		(start 245.92915 -59.15279)
		(mid 246.120792 -59.209956)
		(end 246.260874 -59.352688)
		(width 0.0889)
		(layer "In2.Cu")
		(net "M_A_ECC<0>")
	)
	(arc
		(start 246.78386 -59.647836)
		(mid 246.977874 -59.70388)
		(end 247.119394 -59.847988)
		(width 0.0889)
		(layer "In2.Cu")
		(net "M_A_ECC<0>")
	)
	(arc
		(start 246.260874 -59.352688)
		(mid 246.467878 -59.563552)
		(end 246.751094 -59.647836)
		(width 0.0889)
		(layer "In2.Cu")
		(net "M_A_ECC<0>")
	)
	(arc
		(start 245.402354 -56.285638)
		(mid 245.323132 -56.574756)
		(end 245.396004 -56.86552)
		(width 0.0889)
		(layer "In2.Cu")
		(net "M_A_ECC<0>")
	)
	(arc
		(start 245.396004 -58.277506)
		(mid 245.402181 -58.857438)
		(end 245.90121 -59.15279)
		(width 0.0889)
		(layer "In2.Cu")
		(net "M_A_ECC<0>")
	)
	(arc
		(start 247.123458 -59.8551)
		(mid 247.187414 -59.961822)
		(end 247.254776 -60.066428)
		(width 0.0889)
		(layer "In2.Cu")
		(net "M_A_ECC<0>")
	)
	(arc
		(start 247.254776 -60.066428)
		(mid 247.273779 -60.106449)
		(end 247.28043 -60.150248)
		(width 0.0889)
		(layer "In2.Cu")
		(net "M_A_ECC<0>")
	)
	(arc
		(start 245.402354 -57.276238)
		(mid 245.323223 -57.57164)
		(end 245.402354 -57.867042)
		(width 0.0889)
		(layer "In2.Cu")
		(net "M_A_ECC<0>")
	)
	(arc
		(start 245.402354 -55.295292)
		(mid 245.323349 -55.59044)
		(end 245.402354 -55.885588)
		(width 0.0889)
		(layer "In2.Cu")
		(net "M_A_ECC<0>")
	)
	(arc
		(start 245.40718 -55.894224)
		(mid 245.455935 -56.090576)
		(end 245.402354 -56.285638)
		(width 0.0889)
		(layer "In2.Cu")
		(net "M_A_ECC<0>")
	)
	(segment
		(start 199.799956 -16.040354)
		(end 199.363838 -16.476472)
		(width 0.1651)
		(layer "F.Cu")
		(net "M_A_DQS_DP<9>")
	)
	(segment
		(start 199.279256 -17.478502)
		(end 199.36079 -17.702784)
		(width 0.1651)
		(layer "F.Cu")
		(net "M_A_DQS_DP<9>")
	)
	(segment
		(start 199.800464 -15.423642)
		(end 199.799956 -15.423642)
		(width 0.1651)
		(layer "F.Cu")
		(net "M_A_DQS_DP<9>")
	)
	(segment
		(start 199.799956 -15.423642)
		(end 199.799956 -16.040354)
		(width 0.1651)
		(layer "F.Cu")
		(net "M_A_DQS_DP<9>")
	)
	(segment
		(start 233.608118 -65.000886)
		(end 233.036618 -65.000886)
		(width 0.1016)
		(layer "F.Cu")
		(net "M_A_DQS_DP<9>")
	)
	(segment
		(start 199.36079 -17.702784)
		(end 199.742552 -18.084546)
		(width 0.1651)
		(layer "F.Cu")
		(net "M_A_DQS_DP<9>")
	)
	(segment
		(start 199.279256 -16.660368)
		(end 199.279256 -17.478502)
		(width 0.1651)
		(layer "F.Cu")
		(net "M_A_DQS_DP<9>")
	)
	(segment
		(start 199.363838 -16.476472)
		(end 199.279256 -16.660368)
		(width 0.1651)
		(layer "F.Cu")
		(net "M_A_DQS_DP<9>")
	)
	(via
		(at 233.036618 -65.000886)
		(size 0.508)
		(drill 0.254)
		(layers "F.Cu" "B.Cu")
		(net "M_A_DQS_DP<9>")
	)
	(via
		(at 199.742552 -18.084546)
		(size 0.508)
		(drill 0.254)
		(layers "F.Cu" "B.Cu")
		(net "M_A_DQS_DP<9>")
	)
	(via
		(at 199.742552 -22.1742)
		(size 0.508)
		(drill 0.254)
		(layers "F.Cu" "B.Cu")
		(net "M_A_DQS_DP<9>")
	)
	(segment
		(start 199.799956 -24.206454)
		(end 199.343772 -23.75027)
		(width 0.1651)
		(layer "B.Cu")
		(net "M_A_DQS_DP<9>")
	)
	(segment
		(start 199.353932 -22.56282)
		(end 199.742552 -22.1742)
		(width 0.1651)
		(layer "B.Cu")
		(net "M_A_DQS_DP<9>")
	)
	(segment
		(start 199.266556 -23.617936)
		(end 199.266556 -22.722332)
		(width 0.1651)
		(layer "B.Cu")
		(net "M_A_DQS_DP<9>")
	)
	(segment
		(start 199.799956 -24.824182)
		(end 199.799956 -24.206454)
		(width 0.1651)
		(layer "B.Cu")
		(net "M_A_DQS_DP<9>")
	)
	(segment
		(start 199.800464 -24.824182)
		(end 199.799956 -24.824182)
		(width 0.1651)
		(layer "B.Cu")
		(net "M_A_DQS_DP<9>")
	)
	(segment
		(start 199.266556 -22.722332)
		(end 199.353932 -22.56282)
		(width 0.1651)
		(layer "B.Cu")
		(net "M_A_DQS_DP<9>")
	)
	(segment
		(start 199.343772 -23.75027)
		(end 199.266556 -23.617936)
		(width 0.1651)
		(layer "B.Cu")
		(net "M_A_DQS_DP<9>")
	)
	(segment
		(start 200.081642 -17.87652)
		(end 199.950578 -17.87652)
		(width 0.14224)
		(layer "In2.Cu")
		(net "M_A_DQS_DP<9>")
	)
	(segment
		(start 199.271636 -24.895302)
		(end 199.271636 -22.645116)
		(width 0.14224)
		(layer "In2.Cu")
		(net "M_A_DQS_DP<9>")
	)
	(segment
		(start 200.262236 -21.29028)
		(end 200.015856 -21.0439)
		(width 0.14224)
		(layer "In2.Cu")
		(net "M_A_DQS_DP<9>")
	)
	(segment
		(start 199.774556 -19.6342)
		(end 199.774556 -19.3802)
		(width 0.14224)
		(layer "In2.Cu")
		(net "M_A_DQS_DP<9>")
	)
	(segment
		(start 230.972614 -64.771524)
		(end 230.912416 -64.831722)
		(width 0.0889)
		(layer "In2.Cu")
		(net "M_A_DQS_DP<9>")
	)
	(segment
		(start 199.271636 -22.645116)
		(end 199.742552 -22.1742)
		(width 0.14224)
		(layer "In2.Cu")
		(net "M_A_DQS_DP<9>")
	)
	(segment
		(start 228.57841 -64.831722)
		(end 201.30008 -37.553392)
		(width 0.14224)
		(layer "In2.Cu")
		(net "M_A_DQS_DP<9>")
	)
	(segment
		(start 200.262236 -18.89252)
		(end 200.262236 -18.057114)
		(width 0.14224)
		(layer "In2.Cu")
		(net "M_A_DQS_DP<9>")
	)
	(segment
		(start 199.927464 -21.0439)
		(end 199.771 -20.887436)
		(width 0.14224)
		(layer "In2.Cu")
		(net "M_A_DQS_DP<9>")
	)
	(segment
		(start 200.015856 -21.0439)
		(end 199.927464 -21.0439)
		(width 0.14224)
		(layer "In2.Cu")
		(net "M_A_DQS_DP<9>")
	)
	(segment
		(start 200.262236 -20.23872)
		(end 200.262236 -19.99488)
		(width 0.14224)
		(layer "In2.Cu")
		(net "M_A_DQS_DP<9>")
	)
	(segment
		(start 199.799448 -25.423114)
		(end 199.271636 -24.895302)
		(width 0.14224)
		(layer "In2.Cu")
		(net "M_A_DQS_DP<9>")
	)
	(segment
		(start 200.079356 -20.4216)
		(end 200.262236 -20.23872)
		(width 0.14224)
		(layer "In2.Cu")
		(net "M_A_DQS_DP<9>")
	)
	(segment
		(start 200.262236 -19.99488)
		(end 200.053956 -19.7866)
		(width 0.14224)
		(layer "In2.Cu")
		(net "M_A_DQS_DP<9>")
	)
	(segment
		(start 199.799448 -36.05276)
		(end 199.799448 -25.423114)
		(width 0.14224)
		(layer "In2.Cu")
		(net "M_A_DQS_DP<9>")
	)
	(segment
		(start 199.898508 -20.4216)
		(end 200.079356 -20.4216)
		(width 0.14224)
		(layer "In2.Cu")
		(net "M_A_DQS_DP<9>")
	)
	(segment
		(start 233.311954 -64.911986)
		(end 233.311954 -64.689736)
		(width 0.0889)
		(layer "In2.Cu")
		(net "M_A_DQS_DP<9>")
	)
	(segment
		(start 199.771 -20.549108)
		(end 199.898508 -20.4216)
		(width 0.14224)
		(layer "In2.Cu")
		(net "M_A_DQS_DP<9>")
	)
	(segment
		(start 199.771 -20.887436)
		(end 199.771 -20.549108)
		(width 0.14224)
		(layer "In2.Cu")
		(net "M_A_DQS_DP<9>")
	)
	(segment
		(start 200.262236 -18.057114)
		(end 200.081642 -17.87652)
		(width 0.14224)
		(layer "In2.Cu")
		(net "M_A_DQS_DP<9>")
	)
	(segment
		(start 200.39965 -36.652962)
		(end 199.799448 -36.05276)
		(width 0.14224)
		(layer "In2.Cu")
		(net "M_A_DQS_DP<9>")
	)
	(segment
		(start 200.262236 -21.933662)
		(end 200.262236 -21.29028)
		(width 0.14224)
		(layer "In2.Cu")
		(net "M_A_DQS_DP<9>")
	)
	(segment
		(start 200.053956 -19.7866)
		(end 199.926956 -19.7866)
		(width 0.14224)
		(layer "In2.Cu")
		(net "M_A_DQS_DP<9>")
	)
	(segment
		(start 233.223054 -64.600836)
		(end 232.78338 -64.600836)
		(width 0.0889)
		(layer "In2.Cu")
		(net "M_A_DQS_DP<9>")
	)
	(segment
		(start 233.036618 -65.000886)
		(end 233.223054 -65.000886)
		(width 0.0889)
		(layer "In2.Cu")
		(net "M_A_DQS_DP<9>")
	)
	(segment
		(start 201.30008 -37.553392)
		(end 201.30008 -37.275262)
		(width 0.14224)
		(layer "In2.Cu")
		(net "M_A_DQS_DP<9>")
	)
	(segment
		(start 200.021698 -22.1742)
		(end 200.262236 -21.933662)
		(width 0.14224)
		(layer "In2.Cu")
		(net "M_A_DQS_DP<9>")
	)
	(segment
		(start 200.67778 -36.652962)
		(end 200.39965 -36.652962)
		(width 0.14224)
		(layer "In2.Cu")
		(net "M_A_DQS_DP<9>")
	)
	(segment
		(start 199.742552 -22.1742)
		(end 200.021698 -22.1742)
		(width 0.14224)
		(layer "In2.Cu")
		(net "M_A_DQS_DP<9>")
	)
	(segment
		(start 232.288334 -64.10579)
		(end 231.933496 -64.10579)
		(width 0.0889)
		(layer "In2.Cu")
		(net "M_A_DQS_DP<9>")
	)
	(segment
		(start 199.774556 -19.3802)
		(end 200.262236 -18.89252)
		(width 0.14224)
		(layer "In2.Cu")
		(net "M_A_DQS_DP<9>")
	)
	(segment
		(start 231.933496 -64.10579)
		(end 231.267762 -64.771524)
		(width 0.0889)
		(layer "In2.Cu")
		(net "M_A_DQS_DP<9>")
	)
	(segment
		(start 201.30008 -37.275262)
		(end 200.67778 -36.652962)
		(width 0.14224)
		(layer "In2.Cu")
		(net "M_A_DQS_DP<9>")
	)
	(segment
		(start 230.912416 -64.831722)
		(end 228.57841 -64.831722)
		(width 0.14224)
		(layer "In2.Cu")
		(net "M_A_DQS_DP<9>")
	)
	(segment
		(start 199.926956 -19.7866)
		(end 199.774556 -19.6342)
		(width 0.14224)
		(layer "In2.Cu")
		(net "M_A_DQS_DP<9>")
	)
	(segment
		(start 199.950578 -17.87652)
		(end 199.742552 -18.084546)
		(width 0.14224)
		(layer "In2.Cu")
		(net "M_A_DQS_DP<9>")
	)
	(segment
		(start 231.267762 -64.771524)
		(end 230.972614 -64.771524)
		(width 0.0889)
		(layer "In2.Cu")
		(net "M_A_DQS_DP<9>")
	)
	(segment
		(start 232.78338 -64.600836)
		(end 232.288334 -64.10579)
		(width 0.0889)
		(layer "In2.Cu")
		(net "M_A_DQS_DP<9>")
	)
	(arc
		(start 233.281982 -64.623188)
		(mid 233.254564 -64.60662)
		(end 233.223054 -64.600836)
		(width 0.0889)
		(layer "In2.Cu")
		(net "M_A_DQS_DP<9>")
	)
	(arc
		(start 233.223054 -65.000886)
		(mid 233.285916 -64.974848)
		(end 233.311954 -64.911986)
		(width 0.0889)
		(layer "In2.Cu")
		(net "M_A_DQS_DP<9>")
	)
	(arc
		(start 233.311954 -64.689736)
		(mid 233.304118 -64.653241)
		(end 233.281982 -64.623188)
		(width 0.0889)
		(layer "In2.Cu")
		(net "M_A_DQS_DP<9>")
	)
	(segment
		(start 238.9378 -18.9738)
		(end 238.9378 -17.6022)
		(width 0.1651)
		(layer "F.Cu")
		(net "M_A_DQS_DP<8>")
	)
	(segment
		(start 238.899954 -19.011646)
		(end 238.9378 -18.9738)
		(width 0.1651)
		(layer "F.Cu")
		(net "M_A_DQS_DP<8>")
	)
	(segment
		(start 238.900462 -20.023582)
		(end 238.899954 -20.023582)
		(width 0.1651)
		(layer "F.Cu")
		(net "M_A_DQS_DP<8>")
	)
	(segment
		(start 238.899954 -20.023582)
		(end 238.899954 -19.011646)
		(width 0.1651)
		(layer "F.Cu")
		(net "M_A_DQS_DP<8>")
	)
	(segment
		(start 249.061224 -62.029086)
		(end 248.489724 -62.029086)
		(width 0.1016)
		(layer "F.Cu")
		(net "M_A_DQS_DP<8>")
	)
	(segment
		(start 238.69396 -17.35836)
		(end 238.437928 -17.35836)
		(width 0.1651)
		(layer "F.Cu")
		(net "M_A_DQS_DP<8>")
	)
	(segment
		(start 238.9378 -17.6022)
		(end 238.69396 -17.35836)
		(width 0.1651)
		(layer "F.Cu")
		(net "M_A_DQS_DP<8>")
	)
	(via
		(at 248.489724 -62.029086)
		(size 0.508)
		(drill 0.254)
		(layers "F.Cu" "B.Cu")
		(net "M_A_DQS_DP<8>")
	)
	(via
		(at 238.437928 -22.888956)
		(size 0.508)
		(drill 0.254)
		(layers "F.Cu" "B.Cu")
		(net "M_A_DQS_DP<8>")
	)
	(via
		(at 238.437928 -17.35836)
		(size 0.508)
		(drill 0.254)
		(layers "F.Cu" "B.Cu")
		(net "M_A_DQS_DP<8>")
	)
	(segment
		(start 238.9378 -22.6314)
		(end 238.680244 -22.888956)
		(width 0.1651)
		(layer "B.Cu")
		(net "M_A_DQS_DP<8>")
	)
	(segment
		(start 238.680244 -22.888956)
		(end 238.437928 -22.888956)
		(width 0.1651)
		(layer "B.Cu")
		(net "M_A_DQS_DP<8>")
	)
	(segment
		(start 238.899954 -20.224242)
		(end 238.899954 -21.374354)
		(width 0.1651)
		(layer "B.Cu")
		(net "M_A_DQS_DP<8>")
	)
	(segment
		(start 238.899954 -21.374354)
		(end 238.9378 -21.4122)
		(width 0.1651)
		(layer "B.Cu")
		(net "M_A_DQS_DP<8>")
	)
	(segment
		(start 238.900462 -20.224242)
		(end 238.899954 -20.224242)
		(width 0.1651)
		(layer "B.Cu")
		(net "M_A_DQS_DP<8>")
	)
	(segment
		(start 238.9378 -21.4122)
		(end 238.9378 -22.6314)
		(width 0.1651)
		(layer "B.Cu")
		(net "M_A_DQS_DP<8>")
	)
	(segment
		(start 238.437928 -17.35836)
		(end 239.248696 -18.169128)
		(width 0.14224)
		(layer "In2.Cu")
		(net "M_A_DQS_DP<8>")
	)
	(segment
		(start 248.511314 -61.629036)
		(end 248.478548 -61.629036)
		(width 0.0889)
		(layer "In2.Cu")
		(net "M_A_DQS_DP<8>")
	)
	(segment
		(start 238.261652 -24.604472)
		(end 238.453422 -24.796242)
		(width 0.14224)
		(layer "In2.Cu")
		(net "M_A_DQS_DP<8>")
	)
	(segment
		(start 240.175288 -33.90011)
		(end 240.175288 -40.988488)
		(width 0.14224)
		(layer "In2.Cu")
		(net "M_A_DQS_DP<8>")
	)
	(segment
		(start 239.311688 -33.03651)
		(end 240.175288 -33.90011)
		(width 0.14224)
		(layer "In2.Cu")
		(net "M_A_DQS_DP<8>")
	)
	(segment
		(start 243.374672 -44.044362)
		(end 243.374672 -44.187872)
		(width 0.14224)
		(layer "In2.Cu")
		(net "M_A_DQS_DP<8>")
	)
	(segment
		(start 239.220248 -28.687776)
		(end 239.311688 -28.779216)
		(width 0.14224)
		(layer "In2.Cu")
		(net "M_A_DQS_DP<8>")
	)
	(segment
		(start 239.220248 -25.563068)
		(end 239.220248 -26.28392)
		(width 0.14224)
		(layer "In2.Cu")
		(net "M_A_DQS_DP<8>")
	)
	(segment
		(start 239.248696 -18.169128)
		(end 239.248696 -22.078188)
		(width 0.14224)
		(layer "In2.Cu")
		(net "M_A_DQS_DP<8>")
	)
	(segment
		(start 243.703348 -44.516548)
		(end 243.846858 -44.516548)
		(width 0.14224)
		(layer "In2.Cu")
		(net "M_A_DQS_DP<8>")
	)
	(segment
		(start 238.4552 -24.0284)
		(end 238.261652 -24.221948)
		(width 0.14224)
		(layer "In2.Cu")
		(net "M_A_DQS_DP<8>")
	)
	(segment
		(start 247.61317 -57.971436)
		(end 247.648984 -57.971436)
		(width 0.0889)
		(layer "In2.Cu")
		(net "M_A_DQS_DP<8>")
	)
	(segment
		(start 248.47169 -58.466736)
		(end 248.511314 -58.466736)
		(width 0.0889)
		(layer "In2.Cu")
		(net "M_A_DQS_DP<8>")
	)
	(segment
		(start 238.901732 -23.35276)
		(end 238.901732 -23.861268)
		(width 0.14224)
		(layer "In2.Cu")
		(net "M_A_DQS_DP<8>")
	)
	(segment
		(start 239.311688 -28.779216)
		(end 239.311688 -33.03651)
		(width 0.14224)
		(layer "In2.Cu")
		(net "M_A_DQS_DP<8>")
	)
	(segment
		(start 239.377728 -26.6954)
		(end 239.220248 -26.85288)
		(width 0.14224)
		(layer "In2.Cu")
		(net "M_A_DQS_DP<8>")
	)
	(segment
		(start 239.220248 -26.85288)
		(end 239.220248 -28.687776)
		(width 0.14224)
		(layer "In2.Cu")
		(net "M_A_DQS_DP<8>")
	)
	(segment
		(start 239.377728 -26.4414)
		(end 239.377728 -26.6954)
		(width 0.14224)
		(layer "In2.Cu")
		(net "M_A_DQS_DP<8>")
	)
	(segment
		(start 247.279668 -56.772302)
		(end 247.279414 -56.772556)
		(width 0.0889)
		(layer "In2.Cu")
		(net "M_A_DQS_DP<8>")
	)
	(segment
		(start 242.573556 -43.386756)
		(end 242.902232 -43.715432)
		(width 0.14224)
		(layer "In2.Cu")
		(net "M_A_DQS_DP<8>")
	)
	(segment
		(start 246.5832 -48.403002)
		(end 246.5832 -49.01311)
		(width 0.14224)
		(layer "In2.Cu")
		(net "M_A_DQS_DP<8>")
	)
	(segment
		(start 243.846858 -44.516548)
		(end 244.175788 -44.845478)
		(width 0.14224)
		(layer "In2.Cu")
		(net "M_A_DQS_DP<8>")
	)
	(segment
		(start 242.902232 -43.715432)
		(end 243.045742 -43.715432)
		(width 0.14224)
		(layer "In2.Cu")
		(net "M_A_DQS_DP<8>")
	)
	(segment
		(start 242.573556 -43.243246)
		(end 242.573556 -43.386756)
		(width 0.14224)
		(layer "In2.Cu")
		(net "M_A_DQS_DP<8>")
	)
	(segment
		(start 238.855758 -25.198578)
		(end 239.220248 -25.563068)
		(width 0.14224)
		(layer "In2.Cu")
		(net "M_A_DQS_DP<8>")
	)
	(segment
		(start 239.248696 -22.078188)
		(end 238.437928 -22.888956)
		(width 0.14224)
		(layer "In2.Cu")
		(net "M_A_DQS_DP<8>")
	)
	(segment
		(start 238.901732 -23.861268)
		(end 238.7346 -24.0284)
		(width 0.14224)
		(layer "In2.Cu")
		(net "M_A_DQS_DP<8>")
	)
	(segment
		(start 249.001534 -59.752738)
		(end 249.007884 -59.763406)
		(width 0.0889)
		(layer "In2.Cu")
		(net "M_A_DQS_DP<8>")
	)
	(segment
		(start 242.244626 -42.914316)
		(end 242.573556 -43.243246)
		(width 0.14224)
		(layer "In2.Cu")
		(net "M_A_DQS_DP<8>")
	)
	(segment
		(start 248.996708 -59.744102)
		(end 249.001534 -59.752738)
		(width 0.0889)
		(layer "In2.Cu")
		(net "M_A_DQS_DP<8>")
	)
	(segment
		(start 248.489724 -62.36716)
		(end 248.489724 -62.029086)
		(width 0.0889)
		(layer "In2.Cu")
		(net "M_A_DQS_DP<8>")
	)
	(segment
		(start 247.230392 -55.707026)
		(end 247.25376 -55.730394)
		(width 0.0889)
		(layer "In2.Cu")
		(net "M_A_DQS_DP<8>")
	)
	(segment
		(start 247.230392 -53.19522)
		(end 247.230392 -55.707026)
		(width 0.0889)
		(layer "In2.Cu")
		(net "M_A_DQS_DP<8>")
	)
	(segment
		(start 238.437928 -22.888956)
		(end 238.901732 -23.35276)
		(width 0.14224)
		(layer "In2.Cu")
		(net "M_A_DQS_DP<8>")
	)
	(segment
		(start 238.675926 -24.796242)
		(end 238.855758 -24.976074)
		(width 0.14224)
		(layer "In2.Cu")
		(net "M_A_DQS_DP<8>")
	)
	(segment
		(start 238.7346 -24.0284)
		(end 238.4552 -24.0284)
		(width 0.14224)
		(layer "In2.Cu")
		(net "M_A_DQS_DP<8>")
	)
	(segment
		(start 247.279922 -56.773318)
		(end 247.290844 -56.791606)
		(width 0.0889)
		(layer "In2.Cu")
		(net "M_A_DQS_DP<8>")
	)
	(segment
		(start 248.431812 -62.425072)
		(end 248.489724 -62.36716)
		(width 0.0889)
		(layer "In2.Cu")
		(net "M_A_DQS_DP<8>")
	)
	(segment
		(start 244.175788 -44.988988)
		(end 245.871492 -46.684692)
		(width 0.14224)
		(layer "In2.Cu")
		(net "M_A_DQS_DP<8>")
	)
	(segment
		(start 239.220248 -26.28392)
		(end 239.377728 -26.4414)
		(width 0.14224)
		(layer "In2.Cu")
		(net "M_A_DQS_DP<8>")
	)
	(segment
		(start 240.175288 -40.988488)
		(end 242.101116 -42.914316)
		(width 0.14224)
		(layer "In2.Cu")
		(net "M_A_DQS_DP<8>")
	)
	(segment
		(start 248.996708 -60.734702)
		(end 249.001534 -60.743338)
		(width 0.0889)
		(layer "In2.Cu")
		(net "M_A_DQS_DP<8>")
	)
	(segment
		(start 245.871492 -46.684692)
		(end 246.5832 -48.403002)
		(width 0.14224)
		(layer "In2.Cu")
		(net "M_A_DQS_DP<8>")
	)
	(segment
		(start 249.001534 -60.743338)
		(end 249.007884 -60.754006)
		(width 0.0889)
		(layer "In2.Cu")
		(net "M_A_DQS_DP<8>")
	)
	(segment
		(start 246.539004 -49.057306)
		(end 246.539004 -49.48428)
		(width 0.0889)
		(layer "In2.Cu")
		(net "M_A_DQS_DP<8>")
	)
	(segment
		(start 244.175788 -44.845478)
		(end 244.175788 -44.988988)
		(width 0.14224)
		(layer "In2.Cu")
		(net "M_A_DQS_DP<8>")
	)
	(segment
		(start 247.279414 -56.772556)
		(end 247.279922 -56.773318)
		(width 0.0889)
		(layer "In2.Cu")
		(net "M_A_DQS_DP<8>")
	)
	(segment
		(start 242.101116 -42.914316)
		(end 242.244626 -42.914316)
		(width 0.14224)
		(layer "In2.Cu")
		(net "M_A_DQS_DP<8>")
	)
	(segment
		(start 238.261652 -24.221948)
		(end 238.261652 -24.604472)
		(width 0.14224)
		(layer "In2.Cu")
		(net "M_A_DQS_DP<8>")
	)
	(segment
		(start 247.941084 -52.484528)
		(end 247.230392 -53.19522)
		(width 0.0889)
		(layer "In2.Cu")
		(net "M_A_DQS_DP<8>")
	)
	(segment
		(start 247.941084 -50.88636)
		(end 247.941084 -52.484528)
		(width 0.0889)
		(layer "In2.Cu")
		(net "M_A_DQS_DP<8>")
	)
	(segment
		(start 243.374672 -44.187872)
		(end 243.703348 -44.516548)
		(width 0.14224)
		(layer "In2.Cu")
		(net "M_A_DQS_DP<8>")
	)
	(segment
		(start 238.855758 -24.976074)
		(end 238.855758 -25.198578)
		(width 0.14224)
		(layer "In2.Cu")
		(net "M_A_DQS_DP<8>")
	)
	(segment
		(start 238.453422 -24.796242)
		(end 238.675926 -24.796242)
		(width 0.14224)
		(layer "In2.Cu")
		(net "M_A_DQS_DP<8>")
	)
	(segment
		(start 246.5832 -49.01311)
		(end 246.539004 -49.057306)
		(width 0.0889)
		(layer "In2.Cu")
		(net "M_A_DQS_DP<8>")
	)
	(segment
		(start 246.539004 -49.48428)
		(end 247.941084 -50.88636)
		(width 0.0889)
		(layer "In2.Cu")
		(net "M_A_DQS_DP<8>")
	)
	(segment
		(start 243.045742 -43.715432)
		(end 243.374672 -44.044362)
		(width 0.14224)
		(layer "In2.Cu")
		(net "M_A_DQS_DP<8>")
	)
	(arc
		(start 247.284494 -57.371488)
		(mid 247.280084 -57.763951)
		(end 247.61317 -57.971436)
		(width 0.0889)
		(layer "In2.Cu")
		(net "M_A_DQS_DP<8>")
	)
	(arc
		(start 248.511314 -58.466736)
		(mid 249.006791 -58.771179)
		(end 249.001534 -59.352688)
		(width 0.0889)
		(layer "In2.Cu")
		(net "M_A_DQS_DP<8>")
	)
	(arc
		(start 249.007884 -59.763406)
		(mid 249.080682 -60.054169)
		(end 249.001534 -60.343288)
		(width 0.0889)
		(layer "In2.Cu")
		(net "M_A_DQS_DP<8>")
	)
	(arc
		(start 248.143014 -58.266838)
		(mid 248.281758 -58.408871)
		(end 248.47169 -58.466736)
		(width 0.0889)
		(layer "In2.Cu")
		(net "M_A_DQS_DP<8>")
	)
	(arc
		(start 247.290844 -56.791606)
		(mid 247.363642 -57.082369)
		(end 247.284494 -57.371488)
		(width 0.0889)
		(layer "In2.Cu")
		(net "M_A_DQS_DP<8>")
	)
	(arc
		(start 247.648984 -57.971436)
		(mid 247.934408 -58.054903)
		(end 248.143014 -58.266838)
		(width 0.0889)
		(layer "In2.Cu")
		(net "M_A_DQS_DP<8>")
	)
	(arc
		(start 248.478548 -61.629036)
		(mid 248.090206 -62.00563)
		(end 248.431812 -62.425072)
		(width 0.0889)
		(layer "In2.Cu")
		(net "M_A_DQS_DP<8>")
	)
	(arc
		(start 249.001534 -59.352688)
		(mid 248.948064 -59.547751)
		(end 248.996708 -59.744102)
		(width 0.0889)
		(layer "In2.Cu")
		(net "M_A_DQS_DP<8>")
	)
	(arc
		(start 249.001534 -60.343288)
		(mid 248.948064 -60.538351)
		(end 248.996708 -60.734702)
		(width 0.0889)
		(layer "In2.Cu")
		(net "M_A_DQS_DP<8>")
	)
	(arc
		(start 247.25376 -55.730394)
		(mid 247.364631 -56.051141)
		(end 247.284494 -56.380888)
		(width 0.0889)
		(layer "In2.Cu")
		(net "M_A_DQS_DP<8>")
	)
	(arc
		(start 247.284494 -56.380888)
		(mid 247.231024 -56.575951)
		(end 247.279668 -56.772302)
		(width 0.0889)
		(layer "In2.Cu")
		(net "M_A_DQS_DP<8>")
	)
	(arc
		(start 249.007884 -60.754006)
		(mid 249.003853 -61.330188)
		(end 248.511314 -61.629036)
		(width 0.0889)
		(layer "In2.Cu")
		(net "M_A_DQS_DP<8>")
	)
	(segment
		(start 287.50514 -58.381138)
		(end 286.93364 -58.381138)
		(width 0.1016)
		(layer "F.Cu")
		(net "M_A_DQS_DP<7>")
	)
	(segment
		(start 312.644028 -17.35836)
		(end 312.887868 -17.6022)
		(width 0.1651)
		(layer "F.Cu")
		(net "M_A_DQS_DP<7>")
	)
	(segment
		(start 312.887868 -18.9738)
		(end 312.850022 -19.011646)
		(width 0.1651)
		(layer "F.Cu")
		(net "M_A_DQS_DP<7>")
	)
	(segment
		(start 312.387996 -17.35836)
		(end 312.644028 -17.35836)
		(width 0.1651)
		(layer "F.Cu")
		(net "M_A_DQS_DP<7>")
	)
	(segment
		(start 312.850022 -20.023328)
		(end 312.850276 -20.023582)
		(width 0.1651)
		(layer "F.Cu")
		(net "M_A_DQS_DP<7>")
	)
	(segment
		(start 312.887868 -17.6022)
		(end 312.887868 -18.9738)
		(width 0.1651)
		(layer "F.Cu")
		(net "M_A_DQS_DP<7>")
	)
	(segment
		(start 312.850022 -19.011646)
		(end 312.850022 -20.023328)
		(width 0.1651)
		(layer "F.Cu")
		(net "M_A_DQS_DP<7>")
	)
	(via
		(at 312.387996 -17.35836)
		(size 0.508)
		(drill 0.254)
		(layers "F.Cu" "B.Cu")
		(net "M_A_DQS_DP<7>")
	)
	(via
		(at 312.387996 -22.888956)
		(size 0.508)
		(drill 0.254)
		(layers "F.Cu" "B.Cu")
		(net "M_A_DQS_DP<7>")
	)
	(via
		(at 286.93364 -58.381138)
		(size 0.508)
		(drill 0.254)
		(layers "F.Cu" "B.Cu")
		(net "M_A_DQS_DP<7>")
	)
	(segment
		(start 312.850022 -21.374354)
		(end 312.850022 -20.224496)
		(width 0.1651)
		(layer "B.Cu")
		(net "M_A_DQS_DP<7>")
	)
	(segment
		(start 312.387996 -22.888956)
		(end 312.630312 -22.888956)
		(width 0.1651)
		(layer "B.Cu")
		(net "M_A_DQS_DP<7>")
	)
	(segment
		(start 312.630312 -22.888956)
		(end 312.887868 -22.6314)
		(width 0.1651)
		(layer "B.Cu")
		(net "M_A_DQS_DP<7>")
	)
	(segment
		(start 312.887868 -22.6314)
		(end 312.887868 -21.4122)
		(width 0.1651)
		(layer "B.Cu")
		(net "M_A_DQS_DP<7>")
	)
	(segment
		(start 312.887868 -21.4122)
		(end 312.850022 -21.374354)
		(width 0.1651)
		(layer "B.Cu")
		(net "M_A_DQS_DP<7>")
	)
	(segment
		(start 312.850022 -20.224496)
		(end 312.850276 -20.224242)
		(width 0.1651)
		(layer "B.Cu")
		(net "M_A_DQS_DP<7>")
	)
	(segment
		(start 294.196262 -47.405036)
		(end 295.444164 -47.405036)
		(width 0.14224)
		(layer "In2.Cu")
		(net "M_A_DQS_DP<7>")
	)
	(segment
		(start 288.4805 -53.065426)
		(end 289.641026 -51.9049)
		(width 0.0889)
		(layer "In2.Cu")
		(net "M_A_DQS_DP<7>")
	)
	(segment
		(start 308.728364 -38.76929)
		(end 311.34431 -38.76929)
		(width 0.14224)
		(layer "In2.Cu")
		(net "M_A_DQS_DP<7>")
	)
	(segment
		(start 289.696398 -51.9049)
		(end 289.712146 -51.889152)
		(width 0.0889)
		(layer "In2.Cu")
		(net "M_A_DQS_DP<7>")
	)
	(segment
		(start 312.21934 -24.20366)
		(end 312.42 -24.003)
		(width 0.14224)
		(layer "In2.Cu")
		(net "M_A_DQS_DP<7>")
	)
	(segment
		(start 312.21934 -24.36114)
		(end 312.21934 -24.20366)
		(width 0.14224)
		(layer "In2.Cu")
		(net "M_A_DQS_DP<7>")
	)
	(segment
		(start 312.8264 -23.7236)
		(end 312.8264 -23.32736)
		(width 0.14224)
		(layer "In2.Cu")
		(net "M_A_DQS_DP<7>")
	)
	(segment
		(start 289.641026 -51.9049)
		(end 289.696398 -51.9049)
		(width 0.0889)
		(layer "In2.Cu")
		(net "M_A_DQS_DP<7>")
	)
	(segment
		(start 296.83456 -46.01464)
		(end 301.483014 -46.01464)
		(width 0.14224)
		(layer "In2.Cu")
		(net "M_A_DQS_DP<7>")
	)
	(segment
		(start 313.198764 -22.078188)
		(end 313.198764 -18.169128)
		(width 0.14224)
		(layer "In2.Cu")
		(net "M_A_DQS_DP<7>")
	)
	(segment
		(start 312.68924 -37.42436)
		(end 312.68924 -24.83104)
		(width 0.14224)
		(layer "In2.Cu")
		(net "M_A_DQS_DP<7>")
	)
	(segment
		(start 288.45637 -53.07838)
		(end 288.4805 -53.065172)
		(width 0.0889)
		(layer "In2.Cu")
		(net "M_A_DQS_DP<7>")
	)
	(segment
		(start 289.712146 -51.889152)
		(end 294.196262 -47.405036)
		(width 0.14224)
		(layer "In2.Cu")
		(net "M_A_DQS_DP<7>")
	)
	(segment
		(start 288.4805 -53.065172)
		(end 288.4805 -53.065426)
		(width 0.0889)
		(layer "In2.Cu")
		(net "M_A_DQS_DP<7>")
	)
	(segment
		(start 311.34431 -38.76929)
		(end 312.68924 -37.42436)
		(width 0.14224)
		(layer "In2.Cu")
		(net "M_A_DQS_DP<7>")
	)
	(segment
		(start 295.444164 -47.405036)
		(end 296.83456 -46.01464)
		(width 0.14224)
		(layer "In2.Cu")
		(net "M_A_DQS_DP<7>")
	)
	(segment
		(start 301.483014 -46.01464)
		(end 308.728364 -38.76929)
		(width 0.14224)
		(layer "In2.Cu")
		(net "M_A_DQS_DP<7>")
	)
	(segment
		(start 286.93364 -58.381138)
		(end 286.93364 -58.043064)
		(width 0.0889)
		(layer "In2.Cu")
		(net "M_A_DQS_DP<7>")
	)
	(segment
		(start 287.440624 -56.703722)
		(end 287.44545 -56.695086)
		(width 0.0889)
		(layer "In2.Cu")
		(net "M_A_DQS_DP<7>")
	)
	(segment
		(start 287.780984 -54.513734)
		(end 287.81375 -54.513734)
		(width 0.0889)
		(layer "In2.Cu")
		(net "M_A_DQS_DP<7>")
	)
	(segment
		(start 312.68924 -24.83104)
		(end 312.21934 -24.36114)
		(width 0.14224)
		(layer "In2.Cu")
		(net "M_A_DQS_DP<7>")
	)
	(segment
		(start 287.44545 -56.695086)
		(end 287.4518 -56.684418)
		(width 0.0889)
		(layer "In2.Cu")
		(net "M_A_DQS_DP<7>")
	)
	(segment
		(start 312.8264 -23.32736)
		(end 312.387996 -22.888956)
		(width 0.14224)
		(layer "In2.Cu")
		(net "M_A_DQS_DP<7>")
	)
	(segment
		(start 312.547 -24.003)
		(end 312.8264 -23.7236)
		(width 0.14224)
		(layer "In2.Cu")
		(net "M_A_DQS_DP<7>")
	)
	(segment
		(start 287.440624 -55.713122)
		(end 287.44545 -55.704486)
		(width 0.0889)
		(layer "In2.Cu")
		(net "M_A_DQS_DP<7>")
	)
	(segment
		(start 286.93364 -58.043064)
		(end 286.998918 -57.977786)
		(width 0.0889)
		(layer "In2.Cu")
		(net "M_A_DQS_DP<7>")
	)
	(segment
		(start 312.42 -24.003)
		(end 312.547 -24.003)
		(width 0.14224)
		(layer "In2.Cu")
		(net "M_A_DQS_DP<7>")
	)
	(segment
		(start 312.387996 -22.888956)
		(end 313.198764 -22.078188)
		(width 0.14224)
		(layer "In2.Cu")
		(net "M_A_DQS_DP<7>")
	)
	(segment
		(start 313.198764 -18.169128)
		(end 312.387996 -17.35836)
		(width 0.14224)
		(layer "In2.Cu")
		(net "M_A_DQS_DP<7>")
	)
	(segment
		(start 287.44545 -55.704486)
		(end 287.4518 -55.693818)
		(width 0.0889)
		(layer "In2.Cu")
		(net "M_A_DQS_DP<7>")
	)
	(segment
		(start 287.44545 -57.685686)
		(end 287.4518 -57.675018)
		(width 0.0889)
		(layer "In2.Cu")
		(net "M_A_DQS_DP<7>")
	)
	(arc
		(start 288.30397 -53.227732)
		(mid 288.369958 -53.14264)
		(end 288.45637 -53.07838)
		(width 0.0889)
		(layer "In2.Cu")
		(net "M_A_DQS_DP<7>")
	)
	(arc
		(start 287.44545 -57.095136)
		(mid 287.39198 -56.900073)
		(end 287.440624 -56.703722)
		(width 0.0889)
		(layer "In2.Cu")
		(net "M_A_DQS_DP<7>")
	)
	(arc
		(start 287.4518 -56.684418)
		(mid 287.524598 -56.393655)
		(end 287.44545 -56.104536)
		(width 0.0889)
		(layer "In2.Cu")
		(net "M_A_DQS_DP<7>")
	)
	(arc
		(start 286.998918 -57.977786)
		(mid 287.257055 -57.885032)
		(end 287.44545 -57.685686)
		(width 0.0889)
		(layer "In2.Cu")
		(net "M_A_DQS_DP<7>")
	)
	(arc
		(start 287.44545 -56.104536)
		(mid 287.39198 -55.909473)
		(end 287.440624 -55.713122)
		(width 0.0889)
		(layer "In2.Cu")
		(net "M_A_DQS_DP<7>")
	)
	(arc
		(start 287.440624 -54.722522)
		(mid 287.455836 -54.696912)
		(end 287.472882 -54.672484)
		(width 0.0889)
		(layer "In2.Cu")
		(net "M_A_DQS_DP<7>")
	)
	(arc
		(start 287.472882 -54.672484)
		(mid 287.608856 -54.558026)
		(end 287.780984 -54.513734)
		(width 0.0889)
		(layer "In2.Cu")
		(net "M_A_DQS_DP<7>")
	)
	(arc
		(start 287.44545 -55.113936)
		(mid 287.39198 -54.918873)
		(end 287.440624 -54.722522)
		(width 0.0889)
		(layer "In2.Cu")
		(net "M_A_DQS_DP<7>")
	)
	(arc
		(start 287.4518 -57.675018)
		(mid 287.524598 -57.384255)
		(end 287.44545 -57.095136)
		(width 0.0889)
		(layer "In2.Cu")
		(net "M_A_DQS_DP<7>")
	)
	(arc
		(start 288.30397 -53.627782)
		(mid 288.250437 -53.427774)
		(end 288.30397 -53.227732)
		(width 0.0889)
		(layer "In2.Cu")
		(net "M_A_DQS_DP<7>")
	)
	(arc
		(start 287.81375 -54.513734)
		(mid 288.309227 -54.209291)
		(end 288.30397 -53.627782)
		(width 0.0889)
		(layer "In2.Cu")
		(net "M_A_DQS_DP<7>")
	)
	(arc
		(start 287.4518 -55.693818)
		(mid 287.524598 -55.403055)
		(end 287.44545 -55.113936)
		(width 0.0889)
		(layer "In2.Cu")
		(net "M_A_DQS_DP<7>")
	)
	(segment
		(start 303.500028 -20.023328)
		(end 303.500282 -20.023582)
		(width 0.1651)
		(layer "F.Cu")
		(net "M_A_DQS_DP<6>")
	)
	(segment
		(start 303.500028 -19.011646)
		(end 303.500028 -20.023328)
		(width 0.1651)
		(layer "F.Cu")
		(net "M_A_DQS_DP<6>")
	)
	(segment
		(start 282.354274 -57.390538)
		(end 281.782774 -57.390538)
		(width 0.1016)
		(layer "F.Cu")
		(net "M_A_DQS_DP<6>")
	)
	(segment
		(start 303.537874 -18.9738)
		(end 303.500028 -19.011646)
		(width 0.1651)
		(layer "F.Cu")
		(net "M_A_DQS_DP<6>")
	)
	(segment
		(start 303.038002 -17.35836)
		(end 303.294034 -17.35836)
		(width 0.1651)
		(layer "F.Cu")
		(net "M_A_DQS_DP<6>")
	)
	(segment
		(start 303.537874 -17.6022)
		(end 303.537874 -18.9738)
		(width 0.1651)
		(layer "F.Cu")
		(net "M_A_DQS_DP<6>")
	)
	(segment
		(start 303.294034 -17.35836)
		(end 303.537874 -17.6022)
		(width 0.1651)
		(layer "F.Cu")
		(net "M_A_DQS_DP<6>")
	)
	(via
		(at 303.038002 -22.888956)
		(size 0.508)
		(drill 0.254)
		(layers "F.Cu" "B.Cu")
		(net "M_A_DQS_DP<6>")
	)
	(via
		(at 281.782774 -57.390538)
		(size 0.508)
		(drill 0.254)
		(layers "F.Cu" "B.Cu")
		(net "M_A_DQS_DP<6>")
	)
	(via
		(at 303.038002 -17.35836)
		(size 0.508)
		(drill 0.254)
		(layers "F.Cu" "B.Cu")
		(net "M_A_DQS_DP<6>")
	)
	(segment
		(start 303.280318 -22.888956)
		(end 303.432464 -22.737064)
		(width 0.1651)
		(layer "B.Cu")
		(net "M_A_DQS_DP<6>")
	)
	(segment
		(start 303.537874 -21.4122)
		(end 303.500028 -21.374354)
		(width 0.1651)
		(layer "B.Cu")
		(net "M_A_DQS_DP<6>")
	)
	(segment
		(start 303.500028 -20.224496)
		(end 303.500282 -20.224242)
		(width 0.1651)
		(layer "B.Cu")
		(net "M_A_DQS_DP<6>")
	)
	(segment
		(start 303.537874 -22.6314)
		(end 303.537874 -21.4122)
		(width 0.1651)
		(layer "B.Cu")
		(net "M_A_DQS_DP<6>")
	)
	(segment
		(start 303.500028 -21.374354)
		(end 303.500028 -20.224496)
		(width 0.1651)
		(layer "B.Cu")
		(net "M_A_DQS_DP<6>")
	)
	(segment
		(start 303.43602 -22.733508)
		(end 303.537874 -22.6314)
		(width 0.1651)
		(layer "B.Cu")
		(net "M_A_DQS_DP<6>")
	)
	(segment
		(start 303.432464 -22.737064)
		(end 303.43602 -22.733508)
		(width 0.1651)
		(layer "B.Cu")
		(net "M_A_DQS_DP<6>")
	)
	(segment
		(start 303.038002 -22.888956)
		(end 303.280318 -22.888956)
		(width 0.1651)
		(layer "B.Cu")
		(net "M_A_DQS_DP<6>")
	)
	(segment
		(start 282.826714 -45.3644)
		(end 282.712414 -45.2501)
		(width 0.14224)
		(layer "In2.Cu")
		(net "M_A_DQS_DP<6>")
	)
	(segment
		(start 282.450794 -54.149244)
		(end 282.33243 -54.03088)
		(width 0.0889)
		(layer "In2.Cu")
		(net "M_A_DQS_DP<6>")
	)
	(segment
		(start 282.1686 -51.182016)
		(end 282.1686 -50.7746)
		(width 0.0889)
		(layer "In2.Cu")
		(net "M_A_DQS_DP<6>")
	)
	(segment
		(start 283.233368 -43.39463)
		(end 283.233368 -43.233086)
		(width 0.14224)
		(layer "In2.Cu")
		(net "M_A_DQS_DP<6>")
	)
	(segment
		(start 282.826714 -47.7774)
		(end 282.712414 -47.6631)
		(width 0.14224)
		(layer "In2.Cu")
		(net "M_A_DQS_DP<6>")
	)
	(segment
		(start 283.053536 -43.574462)
		(end 283.233368 -43.39463)
		(width 0.14224)
		(layer "In2.Cu")
		(net "M_A_DQS_DP<6>")
	)
	(segment
		(start 282.712414 -45.9867)
		(end 282.712414 -45.7327)
		(width 0.14224)
		(layer "In2.Cu")
		(net "M_A_DQS_DP<6>")
	)
	(segment
		(start 302.861726 -24.520144)
		(end 302.861726 -24.201374)
		(width 0.14224)
		(layer "In2.Cu")
		(net "M_A_DQS_DP<6>")
	)
	(segment
		(start 282.33243 -54.03088)
		(end 282.33243 -51.345846)
		(width 0.0889)
		(layer "In2.Cu")
		(net "M_A_DQS_DP<6>")
	)
	(segment
		(start 282.712414 -46.7995)
		(end 282.712414 -46.4693)
		(width 0.14224)
		(layer "In2.Cu")
		(net "M_A_DQS_DP<6>")
	)
	(segment
		(start 303.43602 -23.814786)
		(end 303.501806 -23.749)
		(width 0.14224)
		(layer "In2.Cu")
		(net "M_A_DQS_DP<6>")
	)
	(segment
		(start 282.712414 -44.8945)
		(end 282.826714 -44.7802)
		(width 0.14224)
		(layer "In2.Cu")
		(net "M_A_DQS_DP<6>")
	)
	(segment
		(start 303.038002 -22.888956)
		(end 303.311052 -22.615652)
		(width 0.14224)
		(layer "In2.Cu")
		(net "M_A_DQS_DP<6>")
	)
	(segment
		(start 282.673044 -48.47717)
		(end 282.712414 -48.4378)
		(width 0.0889)
		(layer "In2.Cu")
		(net "M_A_DQS_DP<6>")
	)
	(segment
		(start 303.43602 -22.490684)
		(end 303.761394 -22.165564)
		(width 0.14224)
		(layer "In2.Cu")
		(net "M_A_DQS_DP<6>")
	)
	(segment
		(start 289.468814 -36.99764)
		(end 297.62196 -36.99764)
		(width 0.14224)
		(layer "In2.Cu")
		(net "M_A_DQS_DP<6>")
	)
	(segment
		(start 282.712414 -45.2501)
		(end 282.712414 -44.8945)
		(width 0.14224)
		(layer "In2.Cu")
		(net "M_A_DQS_DP<6>")
	)
	(segment
		(start 282.673044 -49.482756)
		(end 282.673044 -48.47717)
		(width 0.0889)
		(layer "In2.Cu")
		(net "M_A_DQS_DP<6>")
	)
	(segment
		(start 281.436064 -57.590436)
		(end 281.431238 -57.5818)
		(width 0.0889)
		(layer "In2.Cu")
		(net "M_A_DQS_DP<6>")
	)
	(segment
		(start 282.826714 -44.5262)
		(end 282.712414 -44.4119)
		(width 0.14224)
		(layer "In2.Cu")
		(net "M_A_DQS_DP<6>")
	)
	(segment
		(start 282.294584 -54.713886)
		(end 282.450794 -54.444646)
		(width 0.0889)
		(layer "In2.Cu")
		(net "M_A_DQS_DP<6>")
	)
	(segment
		(start 282.1686 -50.7746)
		(end 281.94 -50.546)
		(width 0.0889)
		(layer "In2.Cu")
		(net "M_A_DQS_DP<6>")
	)
	(segment
		(start 282.826714 -46.355)
		(end 282.826714 -46.101)
		(width 0.14224)
		(layer "In2.Cu")
		(net "M_A_DQS_DP<6>")
	)
	(segment
		(start 282.712414 -44.4119)
		(end 282.712414 -43.75404)
		(width 0.14224)
		(layer "In2.Cu")
		(net "M_A_DQS_DP<6>")
	)
	(segment
		(start 303.761394 -22.165564)
		(end 303.84877 -22.078188)
		(width 0.14224)
		(layer "In2.Cu")
		(net "M_A_DQS_DP<6>")
	)
	(segment
		(start 303.84877 -18.169128)
		(end 303.038002 -17.35836)
		(width 0.14224)
		(layer "In2.Cu")
		(net "M_A_DQS_DP<6>")
	)
	(segment
		(start 282.712414 -47.6631)
		(end 282.712414 -47.2821)
		(width 0.14224)
		(layer "In2.Cu")
		(net "M_A_DQS_DP<6>")
	)
	(segment
		(start 303.311052 -22.615652)
		(end 303.43602 -22.490684)
		(width 0.14224)
		(layer "In2.Cu")
		(net "M_A_DQS_DP<6>")
	)
	(segment
		(start 281.94 -50.546)
		(end 281.94 -50.2158)
		(width 0.0889)
		(layer "In2.Cu")
		(net "M_A_DQS_DP<6>")
	)
	(segment
		(start 282.826714 -46.9138)
		(end 282.712414 -46.7995)
		(width 0.14224)
		(layer "In2.Cu")
		(net "M_A_DQS_DP<6>")
	)
	(segment
		(start 281.782774 -57.390538)
		(end 281.782774 -57.728612)
		(width 0.0889)
		(layer "In2.Cu")
		(net "M_A_DQS_DP<6>")
	)
	(segment
		(start 303.501806 -23.35276)
		(end 303.038002 -22.888956)
		(width 0.14224)
		(layer "In2.Cu")
		(net "M_A_DQS_DP<6>")
	)
	(segment
		(start 281.94 -50.2158)
		(end 282.673044 -49.482756)
		(width 0.0889)
		(layer "In2.Cu")
		(net "M_A_DQS_DP<6>")
	)
	(segment
		(start 282.826714 -45.6184)
		(end 282.826714 -45.3644)
		(width 0.14224)
		(layer "In2.Cu")
		(net "M_A_DQS_DP<6>")
	)
	(segment
		(start 281.782774 -57.728612)
		(end 281.724862 -57.786524)
		(width 0.0889)
		(layer "In2.Cu")
		(net "M_A_DQS_DP<6>")
	)
	(segment
		(start 303.823116 -30.796484)
		(end 303.823116 -25.481534)
		(width 0.14224)
		(layer "In2.Cu")
		(net "M_A_DQS_DP<6>")
	)
	(segment
		(start 303.501806 -23.749)
		(end 303.501806 -23.35276)
		(width 0.14224)
		(layer "In2.Cu")
		(net "M_A_DQS_DP<6>")
	)
	(segment
		(start 282.33243 -51.345846)
		(end 282.1686 -51.182016)
		(width 0.0889)
		(layer "In2.Cu")
		(net "M_A_DQS_DP<6>")
	)
	(segment
		(start 282.826714 -46.101)
		(end 282.712414 -45.9867)
		(width 0.14224)
		(layer "In2.Cu")
		(net "M_A_DQS_DP<6>")
	)
	(segment
		(start 303.0347 -24.0284)
		(end 303.222406 -24.0284)
		(width 0.14224)
		(layer "In2.Cu")
		(net "M_A_DQS_DP<6>")
	)
	(segment
		(start 282.826714 -44.7802)
		(end 282.826714 -44.5262)
		(width 0.14224)
		(layer "In2.Cu")
		(net "M_A_DQS_DP<6>")
	)
	(segment
		(start 303.222406 -24.0284)
		(end 303.363376 -23.887176)
		(width 0.14224)
		(layer "In2.Cu")
		(net "M_A_DQS_DP<6>")
	)
	(segment
		(start 283.233368 -43.233086)
		(end 289.468814 -36.99764)
		(width 0.14224)
		(layer "In2.Cu")
		(net "M_A_DQS_DP<6>")
	)
	(segment
		(start 281.767788 -56.990488)
		(end 281.804364 -56.990488)
		(width 0.0889)
		(layer "In2.Cu")
		(net "M_A_DQS_DP<6>")
	)
	(segment
		(start 282.826714 -47.1678)
		(end 282.826714 -46.9138)
		(width 0.14224)
		(layer "In2.Cu")
		(net "M_A_DQS_DP<6>")
	)
	(segment
		(start 302.861726 -24.201374)
		(end 303.0347 -24.0284)
		(width 0.14224)
		(layer "In2.Cu")
		(net "M_A_DQS_DP<6>")
	)
	(segment
		(start 282.712414 -48.415702)
		(end 282.712414 -48.1457)
		(width 0.14224)
		(layer "In2.Cu")
		(net "M_A_DQS_DP<6>")
	)
	(segment
		(start 282.712414 -47.2821)
		(end 282.826714 -47.1678)
		(width 0.14224)
		(layer "In2.Cu")
		(net "M_A_DQS_DP<6>")
	)
	(segment
		(start 282.712414 -43.75404)
		(end 282.891992 -43.574462)
		(width 0.14224)
		(layer "In2.Cu")
		(net "M_A_DQS_DP<6>")
	)
	(segment
		(start 282.712414 -48.4378)
		(end 282.712414 -48.415702)
		(width 0.0889)
		(layer "In2.Cu")
		(net "M_A_DQS_DP<6>")
	)
	(segment
		(start 282.450794 -54.444646)
		(end 282.450794 -54.149244)
		(width 0.0889)
		(layer "In2.Cu")
		(net "M_A_DQS_DP<6>")
	)
	(segment
		(start 303.823116 -25.481534)
		(end 302.861726 -24.520144)
		(width 0.14224)
		(layer "In2.Cu")
		(net "M_A_DQS_DP<6>")
	)
	(segment
		(start 297.62196 -36.99764)
		(end 303.823116 -30.796484)
		(width 0.14224)
		(layer "In2.Cu")
		(net "M_A_DQS_DP<6>")
	)
	(segment
		(start 282.712414 -45.7327)
		(end 282.826714 -45.6184)
		(width 0.14224)
		(layer "In2.Cu")
		(net "M_A_DQS_DP<6>")
	)
	(segment
		(start 282.826714 -48.0314)
		(end 282.826714 -47.7774)
		(width 0.14224)
		(layer "In2.Cu")
		(net "M_A_DQS_DP<6>")
	)
	(segment
		(start 282.712414 -46.4693)
		(end 282.826714 -46.355)
		(width 0.14224)
		(layer "In2.Cu")
		(net "M_A_DQS_DP<6>")
	)
	(segment
		(start 303.84877 -22.078188)
		(end 303.84877 -18.169128)
		(width 0.14224)
		(layer "In2.Cu")
		(net "M_A_DQS_DP<6>")
	)
	(segment
		(start 282.891992 -43.574462)
		(end 283.053536 -43.574462)
		(width 0.14224)
		(layer "In2.Cu")
		(net "M_A_DQS_DP<6>")
	)
	(segment
		(start 282.712414 -48.1457)
		(end 282.826714 -48.0314)
		(width 0.14224)
		(layer "In2.Cu")
		(net "M_A_DQS_DP<6>")
	)
	(segment
		(start 303.363376 -23.887176)
		(end 303.43602 -23.814786)
		(width 0.14224)
		(layer "In2.Cu")
		(net "M_A_DQS_DP<6>")
	)
	(arc
		(start 282.294584 -55.70474)
		(mid 282.373555 -55.409482)
		(end 282.294584 -55.11419)
		(width 0.0889)
		(layer "In2.Cu")
		(net "M_A_DQS_DP<6>")
	)
	(arc
		(start 281.436064 -57.190386)
		(mid 281.576143 -57.04765)
		(end 281.767788 -56.990488)
		(width 0.0889)
		(layer "In2.Cu")
		(net "M_A_DQS_DP<6>")
	)
	(arc
		(start 281.804364 -56.990488)
		(mid 282.299841 -56.686045)
		(end 282.294584 -56.104536)
		(width 0.0889)
		(layer "In2.Cu")
		(net "M_A_DQS_DP<6>")
	)
	(arc
		(start 281.724862 -57.786524)
		(mid 281.557961 -57.721624)
		(end 281.436064 -57.590436)
		(width 0.0889)
		(layer "In2.Cu")
		(net "M_A_DQS_DP<6>")
	)
	(arc
		(start 281.431238 -57.5818)
		(mid 281.382483 -57.385448)
		(end 281.436064 -57.190386)
		(width 0.0889)
		(layer "In2.Cu")
		(net "M_A_DQS_DP<6>")
	)
	(arc
		(start 282.294584 -56.104536)
		(mid 282.241085 -55.904638)
		(end 282.294584 -55.70474)
		(width 0.0889)
		(layer "In2.Cu")
		(net "M_A_DQS_DP<6>")
	)
	(arc
		(start 282.294584 -55.11419)
		(mid 282.240958 -54.914038)
		(end 282.294584 -54.713886)
		(width 0.0889)
		(layer "In2.Cu")
		(net "M_A_DQS_DP<6>")
	)
	(segment
		(start 293.94404 -17.35836)
		(end 294.18788 -17.6022)
		(width 0.1651)
		(layer "F.Cu")
		(net "M_A_DQS_DP<5>")
	)
	(segment
		(start 294.18788 -17.6022)
		(end 294.18788 -18.9738)
		(width 0.1651)
		(layer "F.Cu")
		(net "M_A_DQS_DP<5>")
	)
	(segment
		(start 277.203154 -57.390538)
		(end 276.631654 -57.390538)
		(width 0.1016)
		(layer "F.Cu")
		(net "M_A_DQS_DP<5>")
	)
	(segment
		(start 294.150034 -20.023328)
		(end 294.150288 -20.023582)
		(width 0.1651)
		(layer "F.Cu")
		(net "M_A_DQS_DP<5>")
	)
	(segment
		(start 293.688008 -17.35836)
		(end 293.94404 -17.35836)
		(width 0.1651)
		(layer "F.Cu")
		(net "M_A_DQS_DP<5>")
	)
	(segment
		(start 294.150034 -19.011646)
		(end 294.150034 -20.023328)
		(width 0.1651)
		(layer "F.Cu")
		(net "M_A_DQS_DP<5>")
	)
	(segment
		(start 294.18788 -18.9738)
		(end 294.150034 -19.011646)
		(width 0.1651)
		(layer "F.Cu")
		(net "M_A_DQS_DP<5>")
	)
	(via
		(at 276.631654 -57.390538)
		(size 0.508)
		(drill 0.254)
		(layers "F.Cu" "B.Cu")
		(net "M_A_DQS_DP<5>")
	)
	(via
		(at 293.688008 -22.888956)
		(size 0.508)
		(drill 0.254)
		(layers "F.Cu" "B.Cu")
		(net "M_A_DQS_DP<5>")
	)
	(via
		(at 293.688008 -17.35836)
		(size 0.508)
		(drill 0.254)
		(layers "F.Cu" "B.Cu")
		(net "M_A_DQS_DP<5>")
	)
	(segment
		(start 294.150034 -20.224496)
		(end 294.150034 -21.374354)
		(width 0.1651)
		(layer "B.Cu")
		(net "M_A_DQS_DP<5>")
	)
	(segment
		(start 294.18788 -21.4122)
		(end 294.18788 -22.6314)
		(width 0.1651)
		(layer "B.Cu")
		(net "M_A_DQS_DP<5>")
	)
	(segment
		(start 294.150034 -21.374354)
		(end 294.18788 -21.4122)
		(width 0.1651)
		(layer "B.Cu")
		(net "M_A_DQS_DP<5>")
	)
	(segment
		(start 294.18788 -22.6314)
		(end 293.930324 -22.888956)
		(width 0.1651)
		(layer "B.Cu")
		(net "M_A_DQS_DP<5>")
	)
	(segment
		(start 294.150288 -20.224242)
		(end 294.150034 -20.224496)
		(width 0.1651)
		(layer "B.Cu")
		(net "M_A_DQS_DP<5>")
	)
	(segment
		(start 293.930324 -22.888956)
		(end 293.688008 -22.888956)
		(width 0.1651)
		(layer "B.Cu")
		(net "M_A_DQS_DP<5>")
	)
	(segment
		(start 275.099272 -49.240186)
		(end 275.099272 -47.102268)
		(width 0.0889)
		(layer "In2.Cu")
		(net "M_A_DQS_DP<5>")
	)
	(segment
		(start 275.138642 -37.687504)
		(end 283.296106 -29.53004)
		(width 0.14224)
		(layer "In2.Cu")
		(net "M_A_DQS_DP<5>")
	)
	(segment
		(start 283.296106 -29.53004)
		(end 292.676326 -29.53004)
		(width 0.14224)
		(layer "In2.Cu")
		(net "M_A_DQS_DP<5>")
	)
	(segment
		(start 294.2082 -23.876254)
		(end 294.2082 -23.409148)
		(width 0.14224)
		(layer "In2.Cu")
		(net "M_A_DQS_DP<5>")
	)
	(segment
		(start 275.138642 -47.062898)
		(end 275.138642 -37.687504)
		(width 0.14224)
		(layer "In2.Cu")
		(net "M_A_DQS_DP<5>")
	)
	(segment
		(start 293.511732 -24.267668)
		(end 293.7256 -24.0538)
		(width 0.14224)
		(layer "In2.Cu")
		(net "M_A_DQS_DP<5>")
	)
	(segment
		(start 292.676326 -29.53004)
		(end 293.16172 -29.044646)
		(width 0.14224)
		(layer "In2.Cu")
		(net "M_A_DQS_DP<5>")
	)
	(segment
		(start 293.16172 -25.159208)
		(end 293.511732 -24.809196)
		(width 0.14224)
		(layer "In2.Cu")
		(net "M_A_DQS_DP<5>")
	)
	(segment
		(start 293.511732 -24.809196)
		(end 293.511732 -24.267668)
		(width 0.14224)
		(layer "In2.Cu")
		(net "M_A_DQS_DP<5>")
	)
	(segment
		(start 294.030654 -24.0538)
		(end 294.2082 -23.876254)
		(width 0.14224)
		(layer "In2.Cu")
		(net "M_A_DQS_DP<5>")
	)
	(segment
		(start 277.229824 -53.08092)
		(end 276.079458 -51.930554)
		(width 0.0889)
		(layer "In2.Cu")
		(net "M_A_DQS_DP<5>")
	)
	(segment
		(start 276.079458 -50.220372)
		(end 275.099272 -49.240186)
		(width 0.0889)
		(layer "In2.Cu")
		(net "M_A_DQS_DP<5>")
	)
	(segment
		(start 294.2082 -23.409148)
		(end 293.688008 -22.888956)
		(width 0.14224)
		(layer "In2.Cu")
		(net "M_A_DQS_DP<5>")
	)
	(segment
		(start 276.8346 -57.593484)
		(end 276.8346 -57.682384)
		(width 0.0889)
		(layer "In2.Cu")
		(net "M_A_DQS_DP<5>")
	)
	(segment
		(start 293.3192 -25.5524)
		(end 293.16172 -25.39492)
		(width 0.14224)
		(layer "In2.Cu")
		(net "M_A_DQS_DP<5>")
	)
	(segment
		(start 276.620478 -56.990488)
		(end 276.653244 -56.990488)
		(width 0.0889)
		(layer "In2.Cu")
		(net "M_A_DQS_DP<5>")
	)
	(segment
		(start 293.688008 -22.888956)
		(end 294.498776 -22.078188)
		(width 0.14224)
		(layer "In2.Cu")
		(net "M_A_DQS_DP<5>")
	)
	(segment
		(start 276.079458 -51.930554)
		(end 276.079458 -50.220372)
		(width 0.0889)
		(layer "In2.Cu")
		(net "M_A_DQS_DP<5>")
	)
	(segment
		(start 293.7256 -24.0538)
		(end 294.030654 -24.0538)
		(width 0.14224)
		(layer "In2.Cu")
		(net "M_A_DQS_DP<5>")
	)
	(segment
		(start 276.631654 -57.390538)
		(end 276.8346 -57.593484)
		(width 0.0889)
		(layer "In2.Cu")
		(net "M_A_DQS_DP<5>")
	)
	(segment
		(start 293.3192 -25.8064)
		(end 293.3192 -25.5524)
		(width 0.14224)
		(layer "In2.Cu")
		(net "M_A_DQS_DP<5>")
	)
	(segment
		(start 293.16172 -25.39492)
		(end 293.16172 -25.159208)
		(width 0.14224)
		(layer "In2.Cu")
		(net "M_A_DQS_DP<5>")
	)
	(segment
		(start 293.16172 -25.96388)
		(end 293.3192 -25.8064)
		(width 0.14224)
		(layer "In2.Cu")
		(net "M_A_DQS_DP<5>")
	)
	(segment
		(start 293.16172 -29.044646)
		(end 293.16172 -25.96388)
		(width 0.14224)
		(layer "In2.Cu")
		(net "M_A_DQS_DP<5>")
	)
	(segment
		(start 277.229824 -54.564788)
		(end 277.229824 -53.08092)
		(width 0.0889)
		(layer "In2.Cu")
		(net "M_A_DQS_DP<5>")
	)
	(segment
		(start 294.498776 -18.169128)
		(end 293.688008 -17.35836)
		(width 0.14224)
		(layer "In2.Cu")
		(net "M_A_DQS_DP<5>")
	)
	(segment
		(start 294.498776 -22.078188)
		(end 294.498776 -18.169128)
		(width 0.14224)
		(layer "In2.Cu")
		(net "M_A_DQS_DP<5>")
	)
	(segment
		(start 277.143464 -54.714394)
		(end 277.229824 -54.564788)
		(width 0.0889)
		(layer "In2.Cu")
		(net "M_A_DQS_DP<5>")
	)
	(segment
		(start 275.099272 -47.102268)
		(end 275.138642 -47.062898)
		(width 0.0889)
		(layer "In2.Cu")
		(net "M_A_DQS_DP<5>")
	)
	(arc
		(start 276.653244 -56.990488)
		(mid 277.148721 -56.686045)
		(end 277.143464 -56.104536)
		(width 0.0889)
		(layer "In2.Cu")
		(net "M_A_DQS_DP<5>")
	)
	(arc
		(start 277.143464 -55.113936)
		(mid 277.10351 -55.017512)
		(end 277.08987 -54.914038)
		(width 0.0889)
		(layer "In2.Cu")
		(net "M_A_DQS_DP<5>")
	)
	(arc
		(start 277.143464 -56.104536)
		(mid 277.089965 -55.904638)
		(end 277.143464 -55.70474)
		(width 0.0889)
		(layer "In2.Cu")
		(net "M_A_DQS_DP<5>")
	)
	(arc
		(start 277.08987 -54.914038)
		(mid 277.103581 -54.810708)
		(end 277.143464 -54.714394)
		(width 0.0889)
		(layer "In2.Cu")
		(net "M_A_DQS_DP<5>")
	)
	(arc
		(start 276.8346 -57.682384)
		(mid 276.801315 -57.734275)
		(end 276.74951 -57.767728)
		(width 0.0889)
		(layer "In2.Cu")
		(net "M_A_DQS_DP<5>")
	)
	(arc
		(start 276.573742 -57.786524)
		(mid 276.445138 -57.744615)
		(end 276.337776 -57.662318)
		(width 0.0889)
		(layer "In2.Cu")
		(net "M_A_DQS_DP<5>")
	)
	(arc
		(start 276.74951 -57.767728)
		(mid 276.662815 -57.78826)
		(end 276.573742 -57.786524)
		(width 0.0889)
		(layer "In2.Cu")
		(net "M_A_DQS_DP<5>")
	)
	(arc
		(start 276.337776 -57.662318)
		(mid 276.262695 -57.235302)
		(end 276.620478 -56.990488)
		(width 0.0889)
		(layer "In2.Cu")
		(net "M_A_DQS_DP<5>")
	)
	(arc
		(start 277.143464 -55.70474)
		(mid 277.222595 -55.409338)
		(end 277.143464 -55.113936)
		(width 0.0889)
		(layer "In2.Cu")
		(net "M_A_DQS_DP<5>")
	)
	(segment
		(start 284.9372 -23.054056)
		(end 284.7721 -22.888956)
		(width 0.1651)
		(layer "F.Cu")
		(net "M_A_DQS_DP<4>")
	)
	(segment
		(start 274.277074 -50.3936)
		(end 274.175474 -50.292)
		(width 0.0889)
		(layer "F.Cu")
		(net "M_A_DQS_DP<4>")
	)
	(segment
		(start 274.281138 -52.141882)
		(end 274.280884 -52.142136)
		(width 0.0889)
		(layer "F.Cu")
		(net "M_A_DQS_DP<4>")
	)
	(segment
		(start 273.769328 -53.427884)
		(end 273.769328 -53.636672)
		(width 0.0889)
		(layer "F.Cu")
		(net "M_A_DQS_DP<4>")
	)
	(segment
		(start 284.9372 -23.692358)
		(end 284.9372 -23.054056)
		(width 0.1651)
		(layer "F.Cu")
		(net "M_A_DQS_DP<4>")
	)
	(segment
		(start 274.175474 -50.86096)
		(end 274.175474 -50.6476)
		(width 0.0889)
		(layer "F.Cu")
		(net "M_A_DQS_DP<4>")
	)
	(segment
		(start 284.593792 -17.35836)
		(end 284.33776 -17.35836)
		(width 0.1651)
		(layer "F.Cu")
		(net "M_A_DQS_DP<4>")
	)
	(segment
		(start 273.663918 -53.742082)
		(end 273.528028 -53.742082)
		(width 0.0889)
		(layer "F.Cu")
		(net "M_A_DQS_DP<4>")
	)
	(segment
		(start 283.68498 -29.91739)
		(end 283.68498 -27.686)
		(width 0.1651)
		(layer "F.Cu")
		(net "M_A_DQS_DP<4>")
	)
	(segment
		(start 284.799786 -20.023582)
		(end 284.799786 -19.011646)
		(width 0.1651)
		(layer "F.Cu")
		(net "M_A_DQS_DP<4>")
	)
	(segment
		(start 273.528028 -53.742082)
		(end 273.486118 -53.700172)
		(width 0.0889)
		(layer "F.Cu")
		(net "M_A_DQS_DP<4>")
	)
	(segment
		(start 274.45208 -40.405812)
		(end 274.45208 -40.316404)
		(width 0.1016)
		(layer "F.Cu")
		(net "M_A_DQS_DP<4>")
	)
	(segment
		(start 274.378674 -40.479218)
		(end 274.45208 -40.405812)
		(width 0.1016)
		(layer "F.Cu")
		(net "M_A_DQS_DP<4>")
	)
	(segment
		(start 284.799786 -19.011646)
		(end 284.837632 -18.9738)
		(width 0.1651)
		(layer "F.Cu")
		(net "M_A_DQS_DP<4>")
	)
	(segment
		(start 274.175474 -50.6476)
		(end 274.277074 -50.546)
		(width 0.0889)
		(layer "F.Cu")
		(net "M_A_DQS_DP<4>")
	)
	(segment
		(start 274.45208 -40.316404)
		(end 274.45208 -39.15029)
		(width 0.1651)
		(layer "F.Cu")
		(net "M_A_DQS_DP<4>")
	)
	(segment
		(start 274.45208 -39.15029)
		(end 283.68498 -29.91739)
		(width 0.1651)
		(layer "F.Cu")
		(net "M_A_DQS_DP<4>")
	)
	(segment
		(start 274.232116 -50.957226)
		(end 274.175474 -50.86096)
		(width 0.0889)
		(layer "F.Cu")
		(net "M_A_DQS_DP<4>")
	)
	(segment
		(start 274.35937 -51.474878)
		(end 274.35937 -51.47437)
		(width 0.0889)
		(layer "F.Cu")
		(net "M_A_DQS_DP<4>")
	)
	(segment
		(start 284.207458 -24.0284)
		(end 284.601158 -24.0284)
		(width 0.1651)
		(layer "F.Cu")
		(net "M_A_DQS_DP<4>")
	)
	(segment
		(start 284.7721 -22.888956)
		(end 284.33776 -22.888956)
		(width 0.1651)
		(layer "F.Cu")
		(net "M_A_DQS_DP<4>")
	)
	(segment
		(start 273.769328 -53.636672)
		(end 273.663918 -53.742082)
		(width 0.0889)
		(layer "F.Cu")
		(net "M_A_DQS_DP<4>")
	)
	(segment
		(start 274.378674 -49.8856)
		(end 274.378674 -40.479218)
		(width 0.1016)
		(layer "F.Cu")
		(net "M_A_DQS_DP<4>")
	)
	(segment
		(start 283.68498 -27.686)
		(end 283.68498 -24.550878)
		(width 0.1651)
		(layer "F.Cu")
		(net "M_A_DQS_DP<4>")
	)
	(segment
		(start 284.601158 -24.0284)
		(end 284.9372 -23.692358)
		(width 0.1651)
		(layer "F.Cu")
		(net "M_A_DQS_DP<4>")
	)
	(segment
		(start 283.68498 -24.550878)
		(end 284.207458 -24.0284)
		(width 0.1651)
		(layer "F.Cu")
		(net "M_A_DQS_DP<4>")
	)
	(segment
		(start 284.837632 -17.6022)
		(end 284.593792 -17.35836)
		(width 0.1651)
		(layer "F.Cu")
		(net "M_A_DQS_DP<4>")
	)
	(segment
		(start 274.175474 -50.292)
		(end 274.175474 -50.0888)
		(width 0.0889)
		(layer "F.Cu")
		(net "M_A_DQS_DP<4>")
	)
	(segment
		(start 273.758152 -53.027834)
		(end 273.790918 -53.027834)
		(width 0.0889)
		(layer "F.Cu")
		(net "M_A_DQS_DP<4>")
	)
	(segment
		(start 274.175474 -50.0888)
		(end 274.378674 -49.8856)
		(width 0.0889)
		(layer "F.Cu")
		(net "M_A_DQS_DP<4>")
	)
	(segment
		(start 274.277074 -50.546)
		(end 274.277074 -50.3936)
		(width 0.0889)
		(layer "F.Cu")
		(net "M_A_DQS_DP<4>")
	)
	(segment
		(start 284.837632 -18.9738)
		(end 284.837632 -17.6022)
		(width 0.1651)
		(layer "F.Cu")
		(net "M_A_DQS_DP<4>")
	)
	(segment
		(start 284.800294 -20.023582)
		(end 284.799786 -20.023582)
		(width 0.1651)
		(layer "F.Cu")
		(net "M_A_DQS_DP<4>")
	)
	(via
		(at 283.68498 -27.686)
		(size 0.508)
		(drill 0.254)
		(layers "F.Cu" "B.Cu")
		(net "M_A_DQS_DP<4>")
	)
	(via
		(at 284.33776 -22.888956)
		(size 0.508)
		(drill 0.254)
		(layers "F.Cu" "B.Cu")
		(net "M_A_DQS_DP<4>")
	)
	(via
		(at 284.33776 -17.35836)
		(size 0.508)
		(drill 0.254)
		(layers "F.Cu" "B.Cu")
		(net "M_A_DQS_DP<4>")
	)
	(arc
		(start 274.35937 -51.47437)
		(mid 274.333488 -51.206505)
		(end 274.232116 -50.957226)
		(width 0.0889)
		(layer "F.Cu")
		(net "M_A_DQS_DP<4>")
	)
	(arc
		(start 274.280884 -51.741832)
		(mid 274.336066 -51.613042)
		(end 274.35937 -51.474878)
		(width 0.0889)
		(layer "F.Cu")
		(net "M_A_DQS_DP<4>")
	)
	(arc
		(start 273.486118 -53.700172)
		(mid 273.371482 -53.436908)
		(end 273.466814 -53.16601)
		(width 0.0889)
		(layer "F.Cu")
		(net "M_A_DQS_DP<4>")
	)
	(arc
		(start 273.790918 -53.027834)
		(mid 274.286395 -52.723391)
		(end 274.281138 -52.141882)
		(width 0.0889)
		(layer "F.Cu")
		(net "M_A_DQS_DP<4>")
	)
	(arc
		(start 273.466814 -53.16601)
		(mid 273.59796 -53.066324)
		(end 273.758152 -53.027834)
		(width 0.0889)
		(layer "F.Cu")
		(net "M_A_DQS_DP<4>")
	)
	(arc
		(start 274.280884 -52.142136)
		(mid 274.227258 -51.941984)
		(end 274.280884 -51.741832)
		(width 0.0889)
		(layer "F.Cu")
		(net "M_A_DQS_DP<4>")
	)
	(segment
		(start 284.799786 -20.224242)
		(end 284.799786 -21.374354)
		(width 0.1651)
		(layer "B.Cu")
		(net "M_A_DQS_DP<4>")
	)
	(segment
		(start 284.800294 -20.224242)
		(end 284.799786 -20.224242)
		(width 0.1651)
		(layer "B.Cu")
		(net "M_A_DQS_DP<4>")
	)
	(segment
		(start 284.799786 -21.374354)
		(end 284.837632 -21.4122)
		(width 0.1651)
		(layer "B.Cu")
		(net "M_A_DQS_DP<4>")
	)
	(segment
		(start 284.837632 -21.4122)
		(end 284.837632 -22.6314)
		(width 0.1651)
		(layer "B.Cu")
		(net "M_A_DQS_DP<4>")
	)
	(segment
		(start 284.580076 -22.888956)
		(end 284.33776 -22.888956)
		(width 0.1651)
		(layer "B.Cu")
		(net "M_A_DQS_DP<4>")
	)
	(segment
		(start 284.837632 -22.6314)
		(end 284.580076 -22.888956)
		(width 0.1651)
		(layer "B.Cu")
		(net "M_A_DQS_DP<4>")
	)
	(segment
		(start 284.33776 -22.888956)
		(end 285.148528 -22.078188)
		(width 0.14224)
		(layer "In2.Cu")
		(net "M_A_DQS_DP<4>")
	)
	(segment
		(start 285.148528 -22.078188)
		(end 285.148528 -18.169128)
		(width 0.14224)
		(layer "In2.Cu")
		(net "M_A_DQS_DP<4>")
	)
	(segment
		(start 285.148528 -18.169128)
		(end 284.33776 -17.35836)
		(width 0.14224)
		(layer "In2.Cu")
		(net "M_A_DQS_DP<4>")
	)
	(segment
		(start 229.54996 -19.011646)
		(end 229.587806 -18.9738)
		(width 0.1651)
		(layer "F.Cu")
		(net "M_A_DQS_DP<3>")
	)
	(segment
		(start 242.193318 -56.085486)
		(end 241.621818 -56.085486)
		(width 0.1016)
		(layer "F.Cu")
		(net "M_A_DQS_DP<3>")
	)
	(segment
		(start 229.54996 -20.023582)
		(end 229.54996 -19.011646)
		(width 0.1651)
		(layer "F.Cu")
		(net "M_A_DQS_DP<3>")
	)
	(segment
		(start 229.550468 -20.023582)
		(end 229.54996 -20.023582)
		(width 0.1651)
		(layer "F.Cu")
		(net "M_A_DQS_DP<3>")
	)
	(segment
		(start 229.343966 -17.35836)
		(end 229.087934 -17.35836)
		(width 0.1651)
		(layer "F.Cu")
		(net "M_A_DQS_DP<3>")
	)
	(segment
		(start 229.587806 -18.9738)
		(end 229.587806 -17.6022)
		(width 0.1651)
		(layer "F.Cu")
		(net "M_A_DQS_DP<3>")
	)
	(segment
		(start 229.587806 -17.6022)
		(end 229.343966 -17.35836)
		(width 0.1651)
		(layer "F.Cu")
		(net "M_A_DQS_DP<3>")
	)
	(via
		(at 229.087934 -17.35836)
		(size 0.508)
		(drill 0.254)
		(layers "F.Cu" "B.Cu")
		(net "M_A_DQS_DP<3>")
	)
	(via
		(at 241.621818 -56.085486)
		(size 0.508)
		(drill 0.254)
		(layers "F.Cu" "B.Cu")
		(net "M_A_DQS_DP<3>")
	)
	(via
		(at 229.087934 -22.888956)
		(size 0.508)
		(drill 0.254)
		(layers "F.Cu" "B.Cu")
		(net "M_A_DQS_DP<3>")
	)
	(segment
		(start 229.54996 -20.224242)
		(end 229.54996 -21.374354)
		(width 0.1651)
		(layer "B.Cu")
		(net "M_A_DQS_DP<3>")
	)
	(segment
		(start 229.33025 -22.888956)
		(end 229.087934 -22.888956)
		(width 0.1651)
		(layer "B.Cu")
		(net "M_A_DQS_DP<3>")
	)
	(segment
		(start 229.54996 -21.374354)
		(end 229.587806 -21.4122)
		(width 0.1651)
		(layer "B.Cu")
		(net "M_A_DQS_DP<3>")
	)
	(segment
		(start 229.587806 -21.4122)
		(end 229.587806 -22.6314)
		(width 0.1651)
		(layer "B.Cu")
		(net "M_A_DQS_DP<3>")
	)
	(segment
		(start 229.550468 -20.224242)
		(end 229.54996 -20.224242)
		(width 0.1651)
		(layer "B.Cu")
		(net "M_A_DQS_DP<3>")
	)
	(segment
		(start 229.587806 -22.6314)
		(end 229.33025 -22.888956)
		(width 0.1651)
		(layer "B.Cu")
		(net "M_A_DQS_DP<3>")
	)
	(segment
		(start 242.133628 -53.809138)
		(end 242.139978 -53.819806)
		(width 0.0889)
		(layer "In2.Cu")
		(net "M_A_DQS_DP<3>")
	)
	(segment
		(start 241.606832 -52.523136)
		(end 241.639598 -52.523136)
		(width 0.0889)
		(layer "In2.Cu")
		(net "M_A_DQS_DP<3>")
	)
	(segment
		(start 241.621818 -56.42356)
		(end 241.621818 -56.085486)
		(width 0.0889)
		(layer "In2.Cu")
		(net "M_A_DQS_DP<3>")
	)
	(segment
		(start 229.68839 -24.90978)
		(end 229.68839 -25.132284)
		(width 0.14224)
		(layer "In2.Cu")
		(net "M_A_DQS_DP<3>")
	)
	(segment
		(start 242.128802 -54.791102)
		(end 242.133628 -54.799738)
		(width 0.0889)
		(layer "In2.Cu")
		(net "M_A_DQS_DP<3>")
	)
	(segment
		(start 230.041196 -29.1846)
		(end 229.883716 -29.34208)
		(width 0.14224)
		(layer "In2.Cu")
		(net "M_A_DQS_DP<3>")
	)
	(segment
		(start 229.883716 -32.39008)
		(end 229.883716 -41.002712)
		(width 0.14224)
		(layer "In2.Cu")
		(net "M_A_DQS_DP<3>")
	)
	(segment
		(start 230.041196 -31.9786)
		(end 230.041196 -32.2326)
		(width 0.14224)
		(layer "In2.Cu")
		(net "M_A_DQS_DP<3>")
	)
	(segment
		(start 230.041196 -32.2326)
		(end 229.883716 -32.39008)
		(width 0.14224)
		(layer "In2.Cu")
		(net "M_A_DQS_DP<3>")
	)
	(segment
		(start 230.041196 -30.7086)
		(end 229.883716 -30.86608)
		(width 0.14224)
		(layer "In2.Cu")
		(net "M_A_DQS_DP<3>")
	)
	(segment
		(start 229.551738 -23.749)
		(end 229.038658 -24.26208)
		(width 0.14224)
		(layer "In2.Cu")
		(net "M_A_DQS_DP<3>")
	)
	(segment
		(start 229.898702 -18.169128)
		(end 229.898702 -22.078188)
		(width 0.14224)
		(layer "In2.Cu")
		(net "M_A_DQS_DP<3>")
	)
	(segment
		(start 229.883716 -30.86608)
		(end 229.883716 -31.05912)
		(width 0.14224)
		(layer "In2.Cu")
		(net "M_A_DQS_DP<3>")
	)
	(segment
		(start 229.883716 -41.002712)
		(end 237.866682 -48.985678)
		(width 0.14224)
		(layer "In2.Cu")
		(net "M_A_DQS_DP<3>")
	)
	(segment
		(start 237.866682 -48.985678)
		(end 237.866682 -49.449482)
		(width 0.14224)
		(layer "In2.Cu")
		(net "M_A_DQS_DP<3>")
	)
	(segment
		(start 229.883716 -29.34208)
		(end 229.883716 -29.53512)
		(width 0.14224)
		(layer "In2.Cu")
		(net "M_A_DQS_DP<3>")
	)
	(segment
		(start 240.752122 -52.02809)
		(end 240.784888 -52.02809)
		(width 0.0889)
		(layer "In2.Cu")
		(net "M_A_DQS_DP<3>")
	)
	(segment
		(start 229.898702 -22.078188)
		(end 229.087934 -22.888956)
		(width 0.14224)
		(layer "In2.Cu")
		(net "M_A_DQS_DP<3>")
	)
	(segment
		(start 229.883716 -25.32761)
		(end 229.883716 -28.77312)
		(width 0.14224)
		(layer "In2.Cu")
		(net "M_A_DQS_DP<3>")
	)
	(segment
		(start 230.041196 -31.2166)
		(end 230.041196 -31.4706)
		(width 0.14224)
		(layer "In2.Cu")
		(net "M_A_DQS_DP<3>")
	)
	(segment
		(start 229.883716 -28.77312)
		(end 230.041196 -28.9306)
		(width 0.14224)
		(layer "In2.Cu")
		(net "M_A_DQS_DP<3>")
	)
	(segment
		(start 230.041196 -31.4706)
		(end 229.883716 -31.62808)
		(width 0.14224)
		(layer "In2.Cu")
		(net "M_A_DQS_DP<3>")
	)
	(segment
		(start 241.643408 -55.685436)
		(end 241.610642 -55.685436)
		(width 0.0889)
		(layer "In2.Cu")
		(net "M_A_DQS_DP<3>")
	)
	(segment
		(start 229.286054 -24.729948)
		(end 229.508558 -24.729948)
		(width 0.14224)
		(layer "In2.Cu")
		(net "M_A_DQS_DP<3>")
	)
	(segment
		(start 230.041196 -29.6926)
		(end 230.041196 -29.9466)
		(width 0.14224)
		(layer "In2.Cu")
		(net "M_A_DQS_DP<3>")
	)
	(segment
		(start 239.035082 -51.03749)
		(end 239.067848 -51.03749)
		(width 0.0889)
		(layer "In2.Cu")
		(net "M_A_DQS_DP<3>")
	)
	(segment
		(start 238.172752 -50.541936)
		(end 238.205518 -50.541936)
		(width 0.0889)
		(layer "In2.Cu")
		(net "M_A_DQS_DP<3>")
	)
	(segment
		(start 229.508558 -24.729948)
		(end 229.68839 -24.90978)
		(width 0.14224)
		(layer "In2.Cu")
		(net "M_A_DQS_DP<3>")
	)
	(segment
		(start 229.038658 -24.482552)
		(end 229.286054 -24.729948)
		(width 0.14224)
		(layer "In2.Cu")
		(net "M_A_DQS_DP<3>")
	)
	(segment
		(start 242.128802 -53.800502)
		(end 242.133628 -53.809138)
		(width 0.0889)
		(layer "In2.Cu")
		(net "M_A_DQS_DP<3>")
	)
	(segment
		(start 229.883716 -31.05912)
		(end 230.041196 -31.2166)
		(width 0.14224)
		(layer "In2.Cu")
		(net "M_A_DQS_DP<3>")
	)
	(segment
		(start 230.041196 -28.9306)
		(end 230.041196 -29.1846)
		(width 0.14224)
		(layer "In2.Cu")
		(net "M_A_DQS_DP<3>")
	)
	(segment
		(start 229.883716 -31.82112)
		(end 230.041196 -31.9786)
		(width 0.14224)
		(layer "In2.Cu")
		(net "M_A_DQS_DP<3>")
	)
	(segment
		(start 242.133628 -54.799738)
		(end 242.139978 -54.810406)
		(width 0.0889)
		(layer "In2.Cu")
		(net "M_A_DQS_DP<3>")
	)
	(segment
		(start 239.889792 -51.532536)
		(end 239.922558 -51.532536)
		(width 0.0889)
		(layer "In2.Cu")
		(net "M_A_DQS_DP<3>")
	)
	(segment
		(start 230.041196 -29.9466)
		(end 229.883716 -30.10408)
		(width 0.14224)
		(layer "In2.Cu")
		(net "M_A_DQS_DP<3>")
	)
	(segment
		(start 229.087934 -22.888956)
		(end 229.551738 -23.35276)
		(width 0.14224)
		(layer "In2.Cu")
		(net "M_A_DQS_DP<3>")
	)
	(segment
		(start 237.866682 -49.449482)
		(end 237.827312 -49.488852)
		(width 0.0889)
		(layer "In2.Cu")
		(net "M_A_DQS_DP<3>")
	)
	(segment
		(start 229.551738 -23.35276)
		(end 229.551738 -23.749)
		(width 0.14224)
		(layer "In2.Cu")
		(net "M_A_DQS_DP<3>")
	)
	(segment
		(start 237.827312 -49.488852)
		(end 237.827312 -50.290984)
		(width 0.0889)
		(layer "In2.Cu")
		(net "M_A_DQS_DP<3>")
	)
	(segment
		(start 229.087934 -17.35836)
		(end 229.898702 -18.169128)
		(width 0.14224)
		(layer "In2.Cu")
		(net "M_A_DQS_DP<3>")
	)
	(segment
		(start 229.883716 -29.53512)
		(end 230.041196 -29.6926)
		(width 0.14224)
		(layer "In2.Cu")
		(net "M_A_DQS_DP<3>")
	)
	(segment
		(start 229.883716 -31.62808)
		(end 229.883716 -31.82112)
		(width 0.14224)
		(layer "In2.Cu")
		(net "M_A_DQS_DP<3>")
	)
	(segment
		(start 229.883716 -30.10408)
		(end 229.883716 -30.29712)
		(width 0.14224)
		(layer "In2.Cu")
		(net "M_A_DQS_DP<3>")
	)
	(segment
		(start 229.68839 -25.132284)
		(end 229.883716 -25.32761)
		(width 0.14224)
		(layer "In2.Cu")
		(net "M_A_DQS_DP<3>")
	)
	(segment
		(start 241.563906 -56.481472)
		(end 241.621818 -56.42356)
		(width 0.0889)
		(layer "In2.Cu")
		(net "M_A_DQS_DP<3>")
	)
	(segment
		(start 229.883716 -30.29712)
		(end 230.041196 -30.4546)
		(width 0.14224)
		(layer "In2.Cu")
		(net "M_A_DQS_DP<3>")
	)
	(segment
		(start 229.038658 -24.26208)
		(end 229.038658 -24.482552)
		(width 0.14224)
		(layer "In2.Cu")
		(net "M_A_DQS_DP<3>")
	)
	(segment
		(start 230.041196 -30.4546)
		(end 230.041196 -30.7086)
		(width 0.14224)
		(layer "In2.Cu")
		(net "M_A_DQS_DP<3>")
	)
	(arc
		(start 239.067848 -51.03749)
		(mid 239.351065 -51.121771)
		(end 239.558068 -51.332638)
		(width 0.0889)
		(layer "In2.Cu")
		(net "M_A_DQS_DP<3>")
	)
	(arc
		(start 241.275108 -52.323238)
		(mid 241.415187 -52.465974)
		(end 241.606832 -52.523136)
		(width 0.0889)
		(layer "In2.Cu")
		(net "M_A_DQS_DP<3>")
	)
	(arc
		(start 241.610642 -55.685436)
		(mid 241.2223 -56.06203)
		(end 241.563906 -56.481472)
		(width 0.0889)
		(layer "In2.Cu")
		(net "M_A_DQS_DP<3>")
	)
	(arc
		(start 239.558068 -51.332638)
		(mid 239.698147 -51.475374)
		(end 239.889792 -51.532536)
		(width 0.0889)
		(layer "In2.Cu")
		(net "M_A_DQS_DP<3>")
	)
	(arc
		(start 240.416588 -51.827938)
		(mid 240.558271 -51.971742)
		(end 240.752122 -52.02809)
		(width 0.0889)
		(layer "In2.Cu")
		(net "M_A_DQS_DP<3>")
	)
	(arc
		(start 242.133628 -53.409088)
		(mid 242.080158 -53.604151)
		(end 242.128802 -53.800502)
		(width 0.0889)
		(layer "In2.Cu")
		(net "M_A_DQS_DP<3>")
	)
	(arc
		(start 242.139978 -53.819806)
		(mid 242.212776 -54.110569)
		(end 242.133628 -54.399688)
		(width 0.0889)
		(layer "In2.Cu")
		(net "M_A_DQS_DP<3>")
	)
	(arc
		(start 242.133628 -54.399688)
		(mid 242.080158 -54.594751)
		(end 242.128802 -54.791102)
		(width 0.0889)
		(layer "In2.Cu")
		(net "M_A_DQS_DP<3>")
	)
	(arc
		(start 238.699548 -50.837338)
		(mid 238.841231 -50.981142)
		(end 239.035082 -51.03749)
		(width 0.0889)
		(layer "In2.Cu")
		(net "M_A_DQS_DP<3>")
	)
	(arc
		(start 241.639598 -52.523136)
		(mid 242.137849 -52.825976)
		(end 242.133628 -53.409088)
		(width 0.0889)
		(layer "In2.Cu")
		(net "M_A_DQS_DP<3>")
	)
	(arc
		(start 239.922558 -51.532536)
		(mid 240.207982 -51.616003)
		(end 240.416588 -51.827938)
		(width 0.0889)
		(layer "In2.Cu")
		(net "M_A_DQS_DP<3>")
	)
	(arc
		(start 237.841028 -50.342038)
		(mid 237.981107 -50.484774)
		(end 238.172752 -50.541936)
		(width 0.0889)
		(layer "In2.Cu")
		(net "M_A_DQS_DP<3>")
	)
	(arc
		(start 238.205518 -50.541936)
		(mid 238.490942 -50.625403)
		(end 238.699548 -50.837338)
		(width 0.0889)
		(layer "In2.Cu")
		(net "M_A_DQS_DP<3>")
	)
	(arc
		(start 237.827312 -50.290984)
		(mid 237.830801 -50.317416)
		(end 237.841028 -50.342038)
		(width 0.0889)
		(layer "In2.Cu")
		(net "M_A_DQS_DP<3>")
	)
	(arc
		(start 242.139978 -54.810406)
		(mid 242.135947 -55.386588)
		(end 241.643408 -55.685436)
		(width 0.0889)
		(layer "In2.Cu")
		(net "M_A_DQS_DP<3>")
	)
	(arc
		(start 240.784888 -52.02809)
		(mid 241.068105 -52.112371)
		(end 241.275108 -52.323238)
		(width 0.0889)
		(layer "In2.Cu")
		(net "M_A_DQS_DP<3>")
	)
	(segment
		(start 220.199966 -19.011646)
		(end 220.237812 -18.9738)
		(width 0.1651)
		(layer "F.Cu")
		(net "M_A_DQS_DP<2>")
	)
	(segment
		(start 237.900718 -56.58104)
		(end 237.329218 -56.58104)
		(width 0.1016)
		(layer "F.Cu")
		(net "M_A_DQS_DP<2>")
	)
	(segment
		(start 219.993972 -17.35836)
		(end 219.73794 -17.35836)
		(width 0.1651)
		(layer "F.Cu")
		(net "M_A_DQS_DP<2>")
	)
	(segment
		(start 220.199966 -20.023582)
		(end 220.199966 -19.011646)
		(width 0.1651)
		(layer "F.Cu")
		(net "M_A_DQS_DP<2>")
	)
	(segment
		(start 220.200474 -20.023582)
		(end 220.199966 -20.023582)
		(width 0.1651)
		(layer "F.Cu")
		(net "M_A_DQS_DP<2>")
	)
	(segment
		(start 220.237812 -17.6022)
		(end 219.993972 -17.35836)
		(width 0.1651)
		(layer "F.Cu")
		(net "M_A_DQS_DP<2>")
	)
	(segment
		(start 220.237812 -18.9738)
		(end 220.237812 -17.6022)
		(width 0.1651)
		(layer "F.Cu")
		(net "M_A_DQS_DP<2>")
	)
	(via
		(at 237.329218 -56.58104)
		(size 0.508)
		(drill 0.254)
		(layers "F.Cu" "B.Cu")
		(net "M_A_DQS_DP<2>")
	)
	(via
		(at 219.73794 -17.35836)
		(size 0.508)
		(drill 0.254)
		(layers "F.Cu" "B.Cu")
		(net "M_A_DQS_DP<2>")
	)
	(via
		(at 219.73794 -22.888956)
		(size 0.508)
		(drill 0.254)
		(layers "F.Cu" "B.Cu")
		(net "M_A_DQS_DP<2>")
	)
	(segment
		(start 220.200474 -20.224242)
		(end 220.199966 -20.224242)
		(width 0.1651)
		(layer "B.Cu")
		(net "M_A_DQS_DP<2>")
	)
	(segment
		(start 220.199966 -21.374354)
		(end 220.237812 -21.4122)
		(width 0.1651)
		(layer "B.Cu")
		(net "M_A_DQS_DP<2>")
	)
	(segment
		(start 220.237812 -22.6314)
		(end 219.980256 -22.888956)
		(width 0.1651)
		(layer "B.Cu")
		(net "M_A_DQS_DP<2>")
	)
	(segment
		(start 220.237812 -21.4122)
		(end 220.237812 -22.6314)
		(width 0.1651)
		(layer "B.Cu")
		(net "M_A_DQS_DP<2>")
	)
	(segment
		(start 220.199966 -20.224242)
		(end 220.199966 -21.374354)
		(width 0.1651)
		(layer "B.Cu")
		(net "M_A_DQS_DP<2>")
	)
	(segment
		(start 219.980256 -22.888956)
		(end 219.73794 -22.888956)
		(width 0.1651)
		(layer "B.Cu")
		(net "M_A_DQS_DP<2>")
	)
	(segment
		(start 219.385896 -28.1432)
		(end 219.385896 -28.3972)
		(width 0.14224)
		(layer "In2.Cu")
		(net "M_A_DQS_DP<2>")
	)
	(segment
		(start 218.585288 -36.185856)
		(end 218.585288 -36.74364)
		(width 0.14224)
		(layer "In2.Cu")
		(net "M_A_DQS_DP<2>")
	)
	(segment
		(start 228.895402 -51.999134)
		(end 229.056946 -52.160678)
		(width 0.14224)
		(layer "In2.Cu")
		(net "M_A_DQS_DP<2>")
	)
	(segment
		(start 232.449624 -55.203344)
		(end 232.488994 -55.242714)
		(width 0.0889)
		(layer "In2.Cu")
		(net "M_A_DQS_DP<2>")
	)
	(segment
		(start 219.228416 -27.008328)
		(end 219.228416 -27.201368)
		(width 0.14224)
		(layer "In2.Cu")
		(net "M_A_DQS_DP<2>")
	)
	(segment
		(start 219.423488 -37.419534)
		(end 219.423488 -42.707052)
		(width 0.14224)
		(layer "In2.Cu")
		(net "M_A_DQS_DP<2>")
	)
	(segment
		(start 237.701074 -56.433212)
		(end 237.622334 -56.411876)
		(width 0.0889)
		(layer "In2.Cu")
		(net "M_A_DQS_DP<2>")
	)
	(segment
		(start 229.559866 -52.663598)
		(end 229.559866 -52.84343)
		(width 0.14224)
		(layer "In2.Cu")
		(net "M_A_DQS_DP<2>")
	)
	(segment
		(start 230.404162 -53.507894)
		(end 230.565706 -53.669438)
		(width 0.14224)
		(layer "In2.Cu")
		(net "M_A_DQS_DP<2>")
	)
	(segment
		(start 219.73794 -22.888956)
		(end 220.201744 -23.35276)
		(width 0.14224)
		(layer "In2.Cu")
		(net "M_A_DQS_DP<2>")
	)
	(segment
		(start 218.806776 -35.964368)
		(end 218.585288 -36.185856)
		(width 0.14224)
		(layer "In2.Cu")
		(net "M_A_DQS_DP<2>")
	)
	(segment
		(start 229.056946 -52.34051)
		(end 229.21849 -52.502054)
		(width 0.14224)
		(layer "In2.Cu")
		(net "M_A_DQS_DP<2>")
	)
	(segment
		(start 219.385896 -27.358848)
		(end 219.385896 -27.612848)
		(width 0.14224)
		(layer "In2.Cu")
		(net "M_A_DQS_DP<2>")
	)
	(segment
		(start 236.47019 -56.485536)
		(end 236.470698 -56.485536)
		(width 0.0889)
		(layer "In2.Cu")
		(net "M_A_DQS_DP<2>")
	)
	(segment
		(start 218.661488 -34.103056)
		(end 218.90736 -34.348928)
		(width 0.14224)
		(layer "In2.Cu")
		(net "M_A_DQS_DP<2>")
	)
	(segment
		(start 219.423488 -31.99384)
		(end 219.423488 -32.960056)
		(width 0.14224)
		(layer "In2.Cu")
		(net "M_A_DQS_DP<2>")
	)
	(segment
		(start 219.228416 -24.915368)
		(end 219.385896 -25.072848)
		(width 0.14224)
		(layer "In2.Cu")
		(net "M_A_DQS_DP<2>")
	)
	(segment
		(start 219.228416 -28.55468)
		(end 219.228416 -28.906216)
		(width 0.14224)
		(layer "In2.Cu")
		(net "M_A_DQS_DP<2>")
	)
	(segment
		(start 229.901242 -53.004974)
		(end 230.062786 -53.166518)
		(width 0.14224)
		(layer "In2.Cu")
		(net "M_A_DQS_DP<2>")
	)
	(segment
		(start 219.423488 -30.31236)
		(end 218.86164 -30.874208)
		(width 0.14224)
		(layer "In2.Cu")
		(net "M_A_DQS_DP<2>")
	)
	(segment
		(start 219.228416 -24.679656)
		(end 219.228416 -24.915368)
		(width 0.14224)
		(layer "In2.Cu")
		(net "M_A_DQS_DP<2>")
	)
	(segment
		(start 218.86164 -31.431992)
		(end 219.423488 -31.99384)
		(width 0.14224)
		(layer "In2.Cu")
		(net "M_A_DQS_DP<2>")
	)
	(segment
		(start 231.36733 -54.650894)
		(end 231.547162 -54.650894)
		(width 0.14224)
		(layer "In2.Cu")
		(net "M_A_DQS_DP<2>")
	)
	(segment
		(start 232.488994 -55.242714)
		(end 233.071924 -55.242714)
		(width 0.0889)
		(layer "In2.Cu")
		(net "M_A_DQS_DP<2>")
	)
	(segment
		(start 233.071924 -55.242714)
		(end 234.314746 -56.485536)
		(width 0.0889)
		(layer "In2.Cu")
		(net "M_A_DQS_DP<2>")
	)
	(segment
		(start 231.708706 -54.99227)
		(end 231.91978 -55.203344)
		(width 0.14224)
		(layer "In2.Cu")
		(net "M_A_DQS_DP<2>")
	)
	(segment
		(start 218.90736 -34.348928)
		(end 219.045282 -34.348928)
		(width 0.14224)
		(layer "In2.Cu")
		(net "M_A_DQS_DP<2>")
	)
	(segment
		(start 230.86441 -54.147974)
		(end 231.044242 -54.147974)
		(width 0.14224)
		(layer "In2.Cu")
		(net "M_A_DQS_DP<2>")
	)
	(segment
		(start 218.882976 -37.041328)
		(end 219.045282 -37.041328)
		(width 0.14224)
		(layer "In2.Cu")
		(net "M_A_DQS_DP<2>")
	)
	(segment
		(start 232.427526 -55.203344)
		(end 232.449624 -55.203344)
		(width 0.0889)
		(layer "In2.Cu")
		(net "M_A_DQS_DP<2>")
	)
	(segment
		(start 231.205786 -54.48935)
		(end 231.36733 -54.650894)
		(width 0.14224)
		(layer "In2.Cu")
		(net "M_A_DQS_DP<2>")
	)
	(segment
		(start 219.045282 -37.041328)
		(end 219.423488 -37.419534)
		(width 0.14224)
		(layer "In2.Cu")
		(net "M_A_DQS_DP<2>")
	)
	(segment
		(start 219.385896 -25.326848)
		(end 219.228416 -25.484328)
		(width 0.14224)
		(layer "In2.Cu")
		(net "M_A_DQS_DP<2>")
	)
	(segment
		(start 219.228416 -27.770328)
		(end 219.228416 -27.98572)
		(width 0.14224)
		(layer "In2.Cu")
		(net "M_A_DQS_DP<2>")
	)
	(segment
		(start 231.547162 -54.650894)
		(end 231.708706 -54.812438)
		(width 0.14224)
		(layer "In2.Cu")
		(net "M_A_DQS_DP<2>")
	)
	(segment
		(start 219.385896 -26.850848)
		(end 219.228416 -27.008328)
		(width 0.14224)
		(layer "In2.Cu")
		(net "M_A_DQS_DP<2>")
	)
	(segment
		(start 219.423488 -42.707052)
		(end 228.71557 -51.999134)
		(width 0.14224)
		(layer "In2.Cu")
		(net "M_A_DQS_DP<2>")
	)
	(segment
		(start 218.661488 -33.722056)
		(end 218.661488 -34.103056)
		(width 0.14224)
		(layer "In2.Cu")
		(net "M_A_DQS_DP<2>")
	)
	(segment
		(start 220.201744 -23.706328)
		(end 219.228416 -24.679656)
		(width 0.14224)
		(layer "In2.Cu")
		(net "M_A_DQS_DP<2>")
	)
	(segment
		(start 219.423488 -34.727134)
		(end 219.423488 -35.586162)
		(width 0.14224)
		(layer "In2.Cu")
		(net "M_A_DQS_DP<2>")
	)
	(segment
		(start 220.548708 -18.169128)
		(end 220.548708 -22.078188)
		(width 0.14224)
		(layer "In2.Cu")
		(net "M_A_DQS_DP<2>")
	)
	(segment
		(start 219.045282 -35.964368)
		(end 218.806776 -35.964368)
		(width 0.14224)
		(layer "In2.Cu")
		(net "M_A_DQS_DP<2>")
	)
	(segment
		(start 230.062786 -53.166518)
		(end 230.062786 -53.34635)
		(width 0.14224)
		(layer "In2.Cu")
		(net "M_A_DQS_DP<2>")
	)
	(segment
		(start 219.423488 -35.586162)
		(end 219.045282 -35.964368)
		(width 0.14224)
		(layer "In2.Cu")
		(net "M_A_DQS_DP<2>")
	)
	(segment
		(start 219.228416 -26.246328)
		(end 219.228416 -26.439368)
		(width 0.14224)
		(layer "In2.Cu")
		(net "M_A_DQS_DP<2>")
	)
	(segment
		(start 219.228416 -28.906216)
		(end 219.423488 -29.101288)
		(width 0.14224)
		(layer "In2.Cu")
		(net "M_A_DQS_DP<2>")
	)
	(segment
		(start 219.385896 -28.3972)
		(end 219.228416 -28.55468)
		(width 0.14224)
		(layer "In2.Cu")
		(net "M_A_DQS_DP<2>")
	)
	(segment
		(start 229.056946 -52.160678)
		(end 229.056946 -52.34051)
		(width 0.14224)
		(layer "In2.Cu")
		(net "M_A_DQS_DP<2>")
	)
	(segment
		(start 219.228416 -27.201368)
		(end 219.385896 -27.358848)
		(width 0.14224)
		(layer "In2.Cu")
		(net "M_A_DQS_DP<2>")
	)
	(segment
		(start 219.385896 -25.072848)
		(end 219.385896 -25.326848)
		(width 0.14224)
		(layer "In2.Cu")
		(net "M_A_DQS_DP<2>")
	)
	(segment
		(start 219.385896 -25.834848)
		(end 219.385896 -26.088848)
		(width 0.14224)
		(layer "In2.Cu")
		(net "M_A_DQS_DP<2>")
	)
	(segment
		(start 219.423488 -29.101288)
		(end 219.423488 -30.31236)
		(width 0.14224)
		(layer "In2.Cu")
		(net "M_A_DQS_DP<2>")
	)
	(segment
		(start 231.205786 -54.309518)
		(end 231.205786 -54.48935)
		(width 0.14224)
		(layer "In2.Cu")
		(net "M_A_DQS_DP<2>")
	)
	(segment
		(start 229.559866 -52.84343)
		(end 229.72141 -53.004974)
		(width 0.14224)
		(layer "In2.Cu")
		(net "M_A_DQS_DP<2>")
	)
	(segment
		(start 219.385896 -26.596848)
		(end 219.385896 -26.850848)
		(width 0.14224)
		(layer "In2.Cu")
		(net "M_A_DQS_DP<2>")
	)
	(segment
		(start 220.201744 -23.35276)
		(end 220.201744 -23.706328)
		(width 0.14224)
		(layer "In2.Cu")
		(net "M_A_DQS_DP<2>")
	)
	(segment
		(start 234.314746 -56.485536)
		(end 234.767374 -56.485536)
		(width 0.0889)
		(layer "In2.Cu")
		(net "M_A_DQS_DP<2>")
	)
	(segment
		(start 219.228416 -25.484328)
		(end 219.228416 -25.677368)
		(width 0.14224)
		(layer "In2.Cu")
		(net "M_A_DQS_DP<2>")
	)
	(segment
		(start 228.71557 -51.999134)
		(end 228.895402 -51.999134)
		(width 0.14224)
		(layer "In2.Cu")
		(net "M_A_DQS_DP<2>")
	)
	(segment
		(start 218.585288 -36.74364)
		(end 218.882976 -37.041328)
		(width 0.14224)
		(layer "In2.Cu")
		(net "M_A_DQS_DP<2>")
	)
	(segment
		(start 219.045282 -34.348928)
		(end 219.423488 -34.727134)
		(width 0.14224)
		(layer "In2.Cu")
		(net "M_A_DQS_DP<2>")
	)
	(segment
		(start 231.044242 -54.147974)
		(end 231.205786 -54.309518)
		(width 0.14224)
		(layer "In2.Cu")
		(net "M_A_DQS_DP<2>")
	)
	(segment
		(start 229.72141 -53.004974)
		(end 229.901242 -53.004974)
		(width 0.14224)
		(layer "In2.Cu")
		(net "M_A_DQS_DP<2>")
	)
	(segment
		(start 229.398322 -52.502054)
		(end 229.559866 -52.663598)
		(width 0.14224)
		(layer "In2.Cu")
		(net "M_A_DQS_DP<2>")
	)
	(segment
		(start 219.73794 -17.35836)
		(end 220.548708 -18.169128)
		(width 0.14224)
		(layer "In2.Cu")
		(net "M_A_DQS_DP<2>")
	)
	(segment
		(start 220.548708 -22.078188)
		(end 219.73794 -22.888956)
		(width 0.14224)
		(layer "In2.Cu")
		(net "M_A_DQS_DP<2>")
	)
	(segment
		(start 219.385896 -27.612848)
		(end 219.228416 -27.770328)
		(width 0.14224)
		(layer "In2.Cu")
		(net "M_A_DQS_DP<2>")
	)
	(segment
		(start 230.565706 -53.84927)
		(end 230.86441 -54.147974)
		(width 0.14224)
		(layer "In2.Cu")
		(net "M_A_DQS_DP<2>")
	)
	(segment
		(start 229.21849 -52.502054)
		(end 229.398322 -52.502054)
		(width 0.14224)
		(layer "In2.Cu")
		(net "M_A_DQS_DP<2>")
	)
	(segment
		(start 219.228416 -26.439368)
		(end 219.385896 -26.596848)
		(width 0.14224)
		(layer "In2.Cu")
		(net "M_A_DQS_DP<2>")
	)
	(segment
		(start 219.423488 -32.960056)
		(end 218.661488 -33.722056)
		(width 0.14224)
		(layer "In2.Cu")
		(net "M_A_DQS_DP<2>")
	)
	(segment
		(start 231.708706 -54.812438)
		(end 231.708706 -54.99227)
		(width 0.14224)
		(layer "In2.Cu")
		(net "M_A_DQS_DP<2>")
	)
	(segment
		(start 235.611924 -56.98109)
		(end 235.612686 -56.98109)
		(width 0.0889)
		(layer "In2.Cu")
		(net "M_A_DQS_DP<2>")
	)
	(segment
		(start 230.22433 -53.507894)
		(end 230.404162 -53.507894)
		(width 0.14224)
		(layer "In2.Cu")
		(net "M_A_DQS_DP<2>")
	)
	(segment
		(start 219.228416 -25.677368)
		(end 219.385896 -25.834848)
		(width 0.14224)
		(layer "In2.Cu")
		(net "M_A_DQS_DP<2>")
	)
	(segment
		(start 231.91978 -55.203344)
		(end 232.427526 -55.203344)
		(width 0.14224)
		(layer "In2.Cu")
		(net "M_A_DQS_DP<2>")
	)
	(segment
		(start 230.565706 -53.669438)
		(end 230.565706 -53.84927)
		(width 0.14224)
		(layer "In2.Cu")
		(net "M_A_DQS_DP<2>")
	)
	(segment
		(start 230.062786 -53.34635)
		(end 230.22433 -53.507894)
		(width 0.14224)
		(layer "In2.Cu")
		(net "M_A_DQS_DP<2>")
	)
	(segment
		(start 219.385896 -26.088848)
		(end 219.228416 -26.246328)
		(width 0.14224)
		(layer "In2.Cu")
		(net "M_A_DQS_DP<2>")
	)
	(segment
		(start 218.86164 -30.874208)
		(end 218.86164 -31.431992)
		(width 0.14224)
		(layer "In2.Cu")
		(net "M_A_DQS_DP<2>")
	)
	(segment
		(start 219.228416 -27.98572)
		(end 219.385896 -28.1432)
		(width 0.14224)
		(layer "In2.Cu")
		(net "M_A_DQS_DP<2>")
	)
	(segment
		(start 237.622334 -56.411876)
		(end 237.329218 -56.58104)
		(width 0.0889)
		(layer "In2.Cu")
		(net "M_A_DQS_DP<2>")
	)
	(arc
		(start 235.612686 -56.98109)
		(mid 235.812583 -56.927381)
		(end 235.958888 -56.780938)
		(width 0.0889)
		(layer "In2.Cu")
		(net "M_A_DQS_DP<2>")
	)
	(arc
		(start 234.767374 -56.485536)
		(mid 235.055061 -56.568057)
		(end 235.265468 -56.780938)
		(width 0.0889)
		(layer "In2.Cu")
		(net "M_A_DQS_DP<2>")
	)
	(arc
		(start 237.341156 -56.980836)
		(mid 237.663646 -56.800651)
		(end 237.701074 -56.433212)
		(width 0.0889)
		(layer "In2.Cu")
		(net "M_A_DQS_DP<2>")
	)
	(arc
		(start 237.317026 -56.980836)
		(mid 237.329091 -56.981022)
		(end 237.341156 -56.980836)
		(width 0.0889)
		(layer "In2.Cu")
		(net "M_A_DQS_DP<2>")
	)
	(arc
		(start 236.470698 -56.485536)
		(mid 236.766249 -56.56456)
		(end 236.982508 -56.780938)
		(width 0.0889)
		(layer "In2.Cu")
		(net "M_A_DQS_DP<2>")
	)
	(arc
		(start 235.265468 -56.780938)
		(mid 235.41185 -56.927502)
		(end 235.611924 -56.98109)
		(width 0.0889)
		(layer "In2.Cu")
		(net "M_A_DQS_DP<2>")
	)
	(arc
		(start 236.982508 -56.780938)
		(mid 237.123807 -56.924302)
		(end 237.317026 -56.980836)
		(width 0.0889)
		(layer "In2.Cu")
		(net "M_A_DQS_DP<2>")
	)
	(arc
		(start 235.958888 -56.780938)
		(mid 236.174951 -56.564729)
		(end 236.47019 -56.485536)
		(width 0.0889)
		(layer "In2.Cu")
		(net "M_A_DQS_DP<2>")
	)
	(segment
		(start 213.3346 -30.34284)
		(end 213.3346 -30.935676)
		(width 0.1651)
		(layer "F.Cu")
		(net "M_A_DQS_DP<1>")
	)
	(segment
		(start 213.3346 -33.729676)
		(end 213.3346 -33.983676)
		(width 0.1651)
		(layer "F.Cu")
		(net "M_A_DQS_DP<1>")
	)
	(segment
		(start 230.343202 -55.858664)
		(end 231.839008 -55.858664)
		(width 0.1651)
		(layer "F.Cu")
		(net "M_A_DQS_DP<1>")
	)
	(segment
		(start 214.020654 -34.148776)
		(end 214.318596 -34.446718)
		(width 0.1651)
		(layer "F.Cu")
		(net "M_A_DQS_DP<1>")
	)
	(segment
		(start 209.886296 -24.708104)
		(end 209.886296 -26.894536)
		(width 0.1651)
		(layer "F.Cu")
		(net "M_A_DQS_DP<1>")
	)
	(segment
		(start 213.4616 -33.348676)
		(end 213.4616 -33.602676)
		(width 0.1651)
		(layer "F.Cu")
		(net "M_A_DQS_DP<1>")
	)
	(segment
		(start 209.886296 -26.894536)
		(end 210.684364 -27.692604)
		(width 0.1651)
		(layer "F.Cu")
		(net "M_A_DQS_DP<1>")
	)
	(segment
		(start 213.3346 -36.519866)
		(end 213.4997 -36.684966)
		(width 0.1651)
		(layer "F.Cu")
		(net "M_A_DQS_DP<1>")
	)
	(segment
		(start 214.318596 -35.108134)
		(end 214.020654 -35.406076)
		(width 0.1651)
		(layer "F.Cu")
		(net "M_A_DQS_DP<1>")
	)
	(segment
		(start 210.849972 -20.023582)
		(end 210.849972 -19.011646)
		(width 0.1651)
		(layer "F.Cu")
		(net "M_A_DQS_DP<1>")
	)
	(segment
		(start 233.779568 -56.085486)
		(end 233.608118 -56.085486)
		(width 0.0889)
		(layer "F.Cu")
		(net "M_A_DQS_DP<1>")
	)
	(segment
		(start 210.85048 -20.023582)
		(end 210.849972 -20.023582)
		(width 0.1651)
		(layer "F.Cu")
		(net "M_A_DQS_DP<1>")
	)
	(segment
		(start 210.74761 -22.888956)
		(end 210.8708 -23.012146)
		(width 0.1651)
		(layer "F.Cu")
		(net "M_A_DQS_DP<1>")
	)
	(segment
		(start 213.3346 -32.967676)
		(end 213.3346 -33.221676)
		(width 0.1651)
		(layer "F.Cu")
		(net "M_A_DQS_DP<1>")
	)
	(segment
		(start 214.020654 -35.406076)
		(end 213.4997 -35.406076)
		(width 0.1651)
		(layer "F.Cu")
		(net "M_A_DQS_DP<1>")
	)
	(segment
		(start 210.2612 -24.1046)
		(end 210.2612 -24.3332)
		(width 0.1651)
		(layer "F.Cu")
		(net "M_A_DQS_DP<1>")
	)
	(segment
		(start 213.4616 -31.824676)
		(end 213.4616 -32.078676)
		(width 0.1651)
		(layer "F.Cu")
		(net "M_A_DQS_DP<1>")
	)
	(segment
		(start 231.839008 -55.858664)
		(end 231.896158 -55.915814)
		(width 0.0889)
		(layer "F.Cu")
		(net "M_A_DQS_DP<1>")
	)
	(segment
		(start 213.4616 -33.602676)
		(end 213.3346 -33.729676)
		(width 0.1651)
		(layer "F.Cu")
		(net "M_A_DQS_DP<1>")
	)
	(segment
		(start 210.2612 -24.3332)
		(end 209.886296 -24.708104)
		(width 0.1651)
		(layer "F.Cu")
		(net "M_A_DQS_DP<1>")
	)
	(segment
		(start 210.887818 -17.6022)
		(end 210.643978 -17.35836)
		(width 0.1651)
		(layer "F.Cu")
		(net "M_A_DQS_DP<1>")
	)
	(segment
		(start 213.4616 -31.062676)
		(end 213.4616 -31.316676)
		(width 0.1651)
		(layer "F.Cu")
		(net "M_A_DQS_DP<1>")
	)
	(segment
		(start 213.3346 -31.697676)
		(end 213.4616 -31.824676)
		(width 0.1651)
		(layer "F.Cu")
		(net "M_A_DQS_DP<1>")
	)
	(segment
		(start 210.8708 -23.012146)
		(end 210.8708 -23.876)
		(width 0.1651)
		(layer "F.Cu")
		(net "M_A_DQS_DP<1>")
	)
	(segment
		(start 231.896158 -55.915814)
		(end 232.424224 -55.915814)
		(width 0.0889)
		(layer "F.Cu")
		(net "M_A_DQS_DP<1>")
	)
	(segment
		(start 210.849972 -19.011646)
		(end 210.887818 -18.9738)
		(width 0.1651)
		(layer "F.Cu")
		(net "M_A_DQS_DP<1>")
	)
	(segment
		(start 214.318596 -34.446718)
		(end 214.318596 -35.108134)
		(width 0.1651)
		(layer "F.Cu")
		(net "M_A_DQS_DP<1>")
	)
	(segment
		(start 210.7438 -24.003)
		(end 210.3628 -24.003)
		(width 0.1651)
		(layer "F.Cu")
		(net "M_A_DQS_DP<1>")
	)
	(segment
		(start 213.4997 -36.684966)
		(end 214.236046 -36.684966)
		(width 0.1651)
		(layer "F.Cu")
		(net "M_A_DQS_DP<1>")
	)
	(segment
		(start 210.684364 -27.692604)
		(end 213.3346 -30.34284)
		(width 0.1651)
		(layer "F.Cu")
		(net "M_A_DQS_DP<1>")
	)
	(segment
		(start 213.3346 -31.443676)
		(end 213.3346 -31.697676)
		(width 0.1651)
		(layer "F.Cu")
		(net "M_A_DQS_DP<1>")
	)
	(segment
		(start 213.3346 -32.205676)
		(end 213.3346 -32.459676)
		(width 0.1651)
		(layer "F.Cu")
		(net "M_A_DQS_DP<1>")
	)
	(segment
		(start 214.236046 -37.942266)
		(end 213.4997 -37.942266)
		(width 0.1651)
		(layer "F.Cu")
		(net "M_A_DQS_DP<1>")
	)
	(segment
		(start 213.4616 -31.316676)
		(end 213.3346 -31.443676)
		(width 0.1651)
		(layer "F.Cu")
		(net "M_A_DQS_DP<1>")
	)
	(segment
		(start 213.3346 -33.983676)
		(end 213.4997 -34.148776)
		(width 0.1651)
		(layer "F.Cu")
		(net "M_A_DQS_DP<1>")
	)
	(segment
		(start 213.3346 -32.459676)
		(end 213.4616 -32.586676)
		(width 0.1651)
		(layer "F.Cu")
		(net "M_A_DQS_DP<1>")
	)
	(segment
		(start 213.4616 -32.078676)
		(end 213.3346 -32.205676)
		(width 0.1651)
		(layer "F.Cu")
		(net "M_A_DQS_DP<1>")
	)
	(segment
		(start 210.643978 -17.35836)
		(end 210.387946 -17.35836)
		(width 0.1651)
		(layer "F.Cu")
		(net "M_A_DQS_DP<1>")
	)
	(segment
		(start 213.4997 -35.406076)
		(end 213.3346 -35.571176)
		(width 0.1651)
		(layer "F.Cu")
		(net "M_A_DQS_DP<1>")
	)
	(segment
		(start 233.906568 -56.361838)
		(end 233.906568 -56.212486)
		(width 0.0889)
		(layer "F.Cu")
		(net "M_A_DQS_DP<1>")
	)
	(segment
		(start 233.59872 -56.488838)
		(end 233.779568 -56.488838)
		(width 0.0889)
		(layer "F.Cu")
		(net "M_A_DQS_DP<1>")
	)
	(segment
		(start 210.3628 -24.003)
		(end 210.2612 -24.1046)
		(width 0.1651)
		(layer "F.Cu")
		(net "M_A_DQS_DP<1>")
	)
	(segment
		(start 213.4616 -32.586676)
		(end 213.4616 -32.840676)
		(width 0.1651)
		(layer "F.Cu")
		(net "M_A_DQS_DP<1>")
	)
	(segment
		(start 213.3346 -33.221676)
		(end 213.4616 -33.348676)
		(width 0.1651)
		(layer "F.Cu")
		(net "M_A_DQS_DP<1>")
	)
	(segment
		(start 213.4997 -37.942266)
		(end 213.3346 -38.107366)
		(width 0.1651)
		(layer "F.Cu")
		(net "M_A_DQS_DP<1>")
	)
	(segment
		(start 213.3346 -30.935676)
		(end 213.4616 -31.062676)
		(width 0.1651)
		(layer "F.Cu")
		(net "M_A_DQS_DP<1>")
	)
	(segment
		(start 213.3346 -38.850062)
		(end 230.343202 -55.858664)
		(width 0.1651)
		(layer "F.Cu")
		(net "M_A_DQS_DP<1>")
	)
	(segment
		(start 214.533988 -36.982908)
		(end 214.533988 -37.644324)
		(width 0.1651)
		(layer "F.Cu")
		(net "M_A_DQS_DP<1>")
	)
	(segment
		(start 210.387946 -22.888956)
		(end 210.74761 -22.888956)
		(width 0.1651)
		(layer "F.Cu")
		(net "M_A_DQS_DP<1>")
	)
	(segment
		(start 210.887818 -18.9738)
		(end 210.887818 -17.6022)
		(width 0.1651)
		(layer "F.Cu")
		(net "M_A_DQS_DP<1>")
	)
	(segment
		(start 213.4997 -34.148776)
		(end 214.020654 -34.148776)
		(width 0.1651)
		(layer "F.Cu")
		(net "M_A_DQS_DP<1>")
	)
	(segment
		(start 232.424224 -55.915814)
		(end 232.4989 -55.99049)
		(width 0.0889)
		(layer "F.Cu")
		(net "M_A_DQS_DP<1>")
	)
	(segment
		(start 213.3346 -35.571176)
		(end 213.3346 -36.519866)
		(width 0.1651)
		(layer "F.Cu")
		(net "M_A_DQS_DP<1>")
	)
	(segment
		(start 210.8708 -23.876)
		(end 210.7438 -24.003)
		(width 0.1651)
		(layer "F.Cu")
		(net "M_A_DQS_DP<1>")
	)
	(segment
		(start 214.236046 -36.684966)
		(end 214.533988 -36.982908)
		(width 0.1651)
		(layer "F.Cu")
		(net "M_A_DQS_DP<1>")
	)
	(segment
		(start 214.533988 -37.644324)
		(end 214.236046 -37.942266)
		(width 0.1651)
		(layer "F.Cu")
		(net "M_A_DQS_DP<1>")
	)
	(segment
		(start 213.4616 -32.840676)
		(end 213.3346 -32.967676)
		(width 0.1651)
		(layer "F.Cu")
		(net "M_A_DQS_DP<1>")
	)
	(segment
		(start 232.4989 -55.99049)
		(end 232.771188 -55.99049)
		(width 0.0889)
		(layer "F.Cu")
		(net "M_A_DQS_DP<1>")
	)
	(segment
		(start 213.3346 -38.107366)
		(end 213.3346 -38.850062)
		(width 0.1651)
		(layer "F.Cu")
		(net "M_A_DQS_DP<1>")
	)
	(via
		(at 210.684364 -27.692604)
		(size 0.508)
		(drill 0.254)
		(layers "F.Cu" "B.Cu")
		(net "M_A_DQS_DP<1>")
	)
	(via
		(at 210.387946 -17.35836)
		(size 0.508)
		(drill 0.254)
		(layers "F.Cu" "B.Cu")
		(net "M_A_DQS_DP<1>")
	)
	(via
		(at 210.387946 -22.888956)
		(size 0.508)
		(drill 0.254)
		(layers "F.Cu" "B.Cu")
		(net "M_A_DQS_DP<1>")
	)
	(arc
		(start 233.261408 -56.285638)
		(mid 233.403859 -56.430712)
		(end 233.59872 -56.488838)
		(width 0.0889)
		(layer "F.Cu")
		(net "M_A_DQS_DP<1>")
	)
	(arc
		(start 232.771188 -55.99049)
		(mid 233.054405 -56.074771)
		(end 233.261408 -56.285638)
		(width 0.0889)
		(layer "F.Cu")
		(net "M_A_DQS_DP<1>")
	)
	(arc
		(start 233.779568 -56.488838)
		(mid 233.869371 -56.451641)
		(end 233.906568 -56.361838)
		(width 0.0889)
		(layer "F.Cu")
		(net "M_A_DQS_DP<1>")
	)
	(arc
		(start 233.906568 -56.212486)
		(mid 233.869371 -56.122683)
		(end 233.779568 -56.085486)
		(width 0.0889)
		(layer "F.Cu")
		(net "M_A_DQS_DP<1>")
	)
	(segment
		(start 210.887818 -21.4122)
		(end 210.887818 -22.6314)
		(width 0.1651)
		(layer "B.Cu")
		(net "M_A_DQS_DP<1>")
	)
	(segment
		(start 210.630262 -22.888956)
		(end 210.387946 -22.888956)
		(width 0.1651)
		(layer "B.Cu")
		(net "M_A_DQS_DP<1>")
	)
	(segment
		(start 210.849972 -21.374354)
		(end 210.887818 -21.4122)
		(width 0.1651)
		(layer "B.Cu")
		(net "M_A_DQS_DP<1>")
	)
	(segment
		(start 210.887818 -22.6314)
		(end 210.630262 -22.888956)
		(width 0.1651)
		(layer "B.Cu")
		(net "M_A_DQS_DP<1>")
	)
	(segment
		(start 210.849972 -20.224242)
		(end 210.849972 -21.374354)
		(width 0.1651)
		(layer "B.Cu")
		(net "M_A_DQS_DP<1>")
	)
	(segment
		(start 210.85048 -20.224242)
		(end 210.849972 -20.224242)
		(width 0.1651)
		(layer "B.Cu")
		(net "M_A_DQS_DP<1>")
	)
	(segment
		(start 211.198714 -18.169128)
		(end 210.387946 -17.35836)
		(width 0.14224)
		(layer "In2.Cu")
		(net "M_A_DQS_DP<1>")
	)
	(segment
		(start 210.387946 -22.888956)
		(end 211.198714 -22.078188)
		(width 0.14224)
		(layer "In2.Cu")
		(net "M_A_DQS_DP<1>")
	)
	(segment
		(start 211.198714 -22.078188)
		(end 211.198714 -18.169128)
		(width 0.14224)
		(layer "In2.Cu")
		(net "M_A_DQS_DP<1>")
	)
	(segment
		(start 237.199932 -15.423642)
		(end 237.199932 -16.040354)
		(width 0.1651)
		(layer "F.Cu")
		(net "M_A_DQS_DP<17>")
	)
	(segment
		(start 237.20044 -15.423642)
		(end 237.199932 -15.423642)
		(width 0.1651)
		(layer "F.Cu")
		(net "M_A_DQS_DP<17>")
	)
	(segment
		(start 236.679232 -17.478502)
		(end 236.760766 -17.702784)
		(width 0.1651)
		(layer "F.Cu")
		(net "M_A_DQS_DP<17>")
	)
	(segment
		(start 236.760766 -17.702784)
		(end 237.142528 -18.084546)
		(width 0.1651)
		(layer "F.Cu")
		(net "M_A_DQS_DP<17>")
	)
	(segment
		(start 249.061224 -61.038486)
		(end 248.489724 -61.038486)
		(width 0.1016)
		(layer "F.Cu")
		(net "M_A_DQS_DP<17>")
	)
	(segment
		(start 236.763814 -16.476472)
		(end 236.679232 -16.660368)
		(width 0.1651)
		(layer "F.Cu")
		(net "M_A_DQS_DP<17>")
	)
	(segment
		(start 237.199932 -16.040354)
		(end 236.763814 -16.476472)
		(width 0.1651)
		(layer "F.Cu")
		(net "M_A_DQS_DP<17>")
	)
	(segment
		(start 236.679232 -16.660368)
		(end 236.679232 -17.478502)
		(width 0.1651)
		(layer "F.Cu")
		(net "M_A_DQS_DP<17>")
	)
	(via
		(at 237.142528 -18.084546)
		(size 0.508)
		(drill 0.254)
		(layers "F.Cu" "B.Cu")
		(net "M_A_DQS_DP<17>")
	)
	(via
		(at 237.142528 -22.1742)
		(size 0.508)
		(drill 0.254)
		(layers "F.Cu" "B.Cu")
		(net "M_A_DQS_DP<17>")
	)
	(via
		(at 248.489724 -61.038486)
		(size 0.508)
		(drill 0.254)
		(layers "F.Cu" "B.Cu")
		(net "M_A_DQS_DP<17>")
	)
	(segment
		(start 237.20044 -24.824182)
		(end 237.199932 -24.824182)
		(width 0.1651)
		(layer "B.Cu")
		(net "M_A_DQS_DP<17>")
	)
	(segment
		(start 236.666532 -22.722332)
		(end 236.753908 -22.56282)
		(width 0.1651)
		(layer "B.Cu")
		(net "M_A_DQS_DP<17>")
	)
	(segment
		(start 236.743748 -23.75027)
		(end 236.666532 -23.617936)
		(width 0.1651)
		(layer "B.Cu")
		(net "M_A_DQS_DP<17>")
	)
	(segment
		(start 236.753908 -22.56282)
		(end 237.142528 -22.1742)
		(width 0.1651)
		(layer "B.Cu")
		(net "M_A_DQS_DP<17>")
	)
	(segment
		(start 237.199932 -24.824182)
		(end 237.199932 -24.206454)
		(width 0.1651)
		(layer "B.Cu")
		(net "M_A_DQS_DP<17>")
	)
	(segment
		(start 237.199932 -24.206454)
		(end 236.743748 -23.75027)
		(width 0.1651)
		(layer "B.Cu")
		(net "M_A_DQS_DP<17>")
	)
	(segment
		(start 236.666532 -23.617936)
		(end 236.666532 -22.722332)
		(width 0.1651)
		(layer "B.Cu")
		(net "M_A_DQS_DP<17>")
	)
	(segment
		(start 238.940848 -37.740844)
		(end 238.940848 -37.106098)
		(width 0.14224)
		(layer "In2.Cu")
		(net "M_A_DQS_DP<17>")
	)
	(segment
		(start 238.734854 -34.248344)
		(end 238.262414 -34.248344)
		(width 0.14224)
		(layer "In2.Cu")
		(net "M_A_DQS_DP<17>")
	)
	(segment
		(start 246.253508 -55.802784)
		(end 246.318786 -55.687976)
		(width 0.0889)
		(layer "In2.Cu")
		(net "M_A_DQS_DP<17>")
	)
	(segment
		(start 237.415832 -21.0439)
		(end 237.32744 -21.0439)
		(width 0.14224)
		(layer "In2.Cu")
		(net "M_A_DQS_DP<17>")
	)
	(segment
		(start 238.940848 -34.454338)
		(end 238.734854 -34.248344)
		(width 0.14224)
		(layer "In2.Cu")
		(net "M_A_DQS_DP<17>")
	)
	(segment
		(start 238.253016 -35.269932)
		(end 238.71936 -35.269932)
		(width 0.14224)
		(layer "In2.Cu")
		(net "M_A_DQS_DP<17>")
	)
	(segment
		(start 237.174532 -19.3802)
		(end 237.662212 -18.89252)
		(width 0.14224)
		(layer "In2.Cu")
		(net "M_A_DQS_DP<17>")
	)
	(segment
		(start 237.874048 -29.170376)
		(end 237.640876 -28.937204)
		(width 0.14224)
		(layer "In2.Cu")
		(net "M_A_DQS_DP<17>")
	)
	(segment
		(start 237.453932 -19.7866)
		(end 237.326932 -19.7866)
		(width 0.14224)
		(layer "In2.Cu")
		(net "M_A_DQS_DP<17>")
	)
	(segment
		(start 238.71936 -35.269932)
		(end 238.940848 -35.048444)
		(width 0.14224)
		(layer "In2.Cu")
		(net "M_A_DQS_DP<17>")
	)
	(segment
		(start 246.318786 -55.687976)
		(end 246.318786 -55.324756)
		(width 0.0889)
		(layer "In2.Cu")
		(net "M_A_DQS_DP<17>")
	)
	(segment
		(start 238.720122 -36.885372)
		(end 238.253016 -36.885372)
		(width 0.14224)
		(layer "In2.Cu")
		(net "M_A_DQS_DP<17>")
	)
	(segment
		(start 246.318786 -55.324756)
		(end 246.267224 -55.273194)
		(width 0.0889)
		(layer "In2.Cu")
		(net "M_A_DQS_DP<17>")
	)
	(segment
		(start 246.754396 -51.293014)
		(end 244.93093 -49.469548)
		(width 0.0889)
		(layer "In2.Cu")
		(net "M_A_DQS_DP<17>")
	)
	(segment
		(start 246.882412 -52.191666)
		(end 246.882412 -51.51374)
		(width 0.0889)
		(layer "In2.Cu")
		(net "M_A_DQS_DP<17>")
	)
	(segment
		(start 246.267224 -55.273194)
		(end 246.267224 -52.806854)
		(width 0.0889)
		(layer "In2.Cu")
		(net "M_A_DQS_DP<17>")
	)
	(segment
		(start 238.940848 -37.106098)
		(end 238.720122 -36.885372)
		(width 0.14224)
		(layer "In2.Cu")
		(net "M_A_DQS_DP<17>")
	)
	(segment
		(start 237.662212 -18.057114)
		(end 237.481618 -17.87652)
		(width 0.14224)
		(layer "In2.Cu")
		(net "M_A_DQS_DP<17>")
	)
	(segment
		(start 246.254524 -56.791606)
		(end 246.260874 -56.780938)
		(width 0.0889)
		(layer "In2.Cu")
		(net "M_A_DQS_DP<17>")
	)
	(segment
		(start 237.479332 -20.4216)
		(end 237.662212 -20.23872)
		(width 0.14224)
		(layer "In2.Cu")
		(net "M_A_DQS_DP<17>")
	)
	(segment
		(start 237.662212 -21.29028)
		(end 237.415832 -21.0439)
		(width 0.14224)
		(layer "In2.Cu")
		(net "M_A_DQS_DP<17>")
	)
	(segment
		(start 244.89156 -47.288196)
		(end 238.2266 -40.623236)
		(width 0.14224)
		(layer "In2.Cu")
		(net "M_A_DQS_DP<17>")
	)
	(segment
		(start 238.71936 -37.962332)
		(end 238.940848 -37.740844)
		(width 0.14224)
		(layer "In2.Cu")
		(net "M_A_DQS_DP<17>")
	)
	(segment
		(start 238.253016 -36.885372)
		(end 237.80496 -36.437316)
		(width 0.14224)
		(layer "In2.Cu")
		(net "M_A_DQS_DP<17>")
	)
	(segment
		(start 244.89156 -47.9806)
		(end 244.89156 -47.288196)
		(width 0.14224)
		(layer "In2.Cu")
		(net "M_A_DQS_DP<17>")
	)
	(segment
		(start 237.298484 -20.4216)
		(end 237.479332 -20.4216)
		(width 0.14224)
		(layer "In2.Cu")
		(net "M_A_DQS_DP<17>")
	)
	(segment
		(start 237.350554 -17.87652)
		(end 237.142528 -18.084546)
		(width 0.14224)
		(layer "In2.Cu")
		(net "M_A_DQS_DP<17>")
	)
	(segment
		(start 237.640876 -25.869138)
		(end 236.671612 -24.899874)
		(width 0.14224)
		(layer "In2.Cu")
		(net "M_A_DQS_DP<17>")
	)
	(segment
		(start 238.2266 -38.285928)
		(end 238.550196 -37.962332)
		(width 0.14224)
		(layer "In2.Cu")
		(net "M_A_DQS_DP<17>")
	)
	(segment
		(start 246.790718 -58.65749)
		(end 246.754904 -58.65749)
		(width 0.0889)
		(layer "In2.Cu")
		(net "M_A_DQS_DP<17>")
	)
	(segment
		(start 238.550196 -37.962332)
		(end 238.71936 -37.962332)
		(width 0.14224)
		(layer "In2.Cu")
		(net "M_A_DQS_DP<17>")
	)
	(segment
		(start 236.671612 -22.645116)
		(end 237.142528 -22.1742)
		(width 0.14224)
		(layer "In2.Cu")
		(net "M_A_DQS_DP<17>")
	)
	(segment
		(start 246.267224 -52.806854)
		(end 246.882412 -52.191666)
		(width 0.0889)
		(layer "In2.Cu")
		(net "M_A_DQS_DP<17>")
	)
	(segment
		(start 237.662212 -19.99488)
		(end 237.453932 -19.7866)
		(width 0.14224)
		(layer "In2.Cu")
		(net "M_A_DQS_DP<17>")
	)
	(segment
		(start 237.640876 -28.937204)
		(end 237.640876 -25.869138)
		(width 0.14224)
		(layer "In2.Cu")
		(net "M_A_DQS_DP<17>")
	)
	(segment
		(start 237.421674 -22.1742)
		(end 237.662212 -21.933662)
		(width 0.14224)
		(layer "In2.Cu")
		(net "M_A_DQS_DP<17>")
	)
	(segment
		(start 237.32744 -21.0439)
		(end 237.170976 -20.887436)
		(width 0.14224)
		(layer "In2.Cu")
		(net "M_A_DQS_DP<17>")
	)
	(segment
		(start 237.170976 -20.887436)
		(end 237.170976 -20.549108)
		(width 0.14224)
		(layer "In2.Cu")
		(net "M_A_DQS_DP<17>")
	)
	(segment
		(start 237.662212 -20.23872)
		(end 237.662212 -19.99488)
		(width 0.14224)
		(layer "In2.Cu")
		(net "M_A_DQS_DP<17>")
	)
	(segment
		(start 237.142528 -22.1742)
		(end 237.421674 -22.1742)
		(width 0.14224)
		(layer "In2.Cu")
		(net "M_A_DQS_DP<17>")
	)
	(segment
		(start 236.671612 -24.899874)
		(end 236.671612 -22.645116)
		(width 0.14224)
		(layer "In2.Cu")
		(net "M_A_DQS_DP<17>")
	)
	(segment
		(start 246.882412 -51.51374)
		(end 246.754396 -51.293014)
		(width 0.0889)
		(layer "In2.Cu")
		(net "M_A_DQS_DP<17>")
	)
	(segment
		(start 238.940848 -35.048444)
		(end 238.940848 -34.454338)
		(width 0.14224)
		(layer "In2.Cu")
		(net "M_A_DQS_DP<17>")
	)
	(segment
		(start 237.662212 -18.89252)
		(end 237.662212 -18.057114)
		(width 0.14224)
		(layer "In2.Cu")
		(net "M_A_DQS_DP<17>")
	)
	(segment
		(start 244.93093 -48.042068)
		(end 244.89156 -48.002698)
		(width 0.0889)
		(layer "In2.Cu")
		(net "M_A_DQS_DP<17>")
	)
	(segment
		(start 247.64619 -59.15279)
		(end 247.61825 -59.15279)
		(width 0.0889)
		(layer "In2.Cu")
		(net "M_A_DQS_DP<17>")
	)
	(segment
		(start 237.662212 -21.933662)
		(end 237.662212 -21.29028)
		(width 0.14224)
		(layer "In2.Cu")
		(net "M_A_DQS_DP<17>")
	)
	(segment
		(start 244.89156 -48.002698)
		(end 244.89156 -47.9806)
		(width 0.0889)
		(layer "In2.Cu")
		(net "M_A_DQS_DP<17>")
	)
	(segment
		(start 238.262414 -34.248344)
		(end 237.874048 -33.859978)
		(width 0.14224)
		(layer "In2.Cu")
		(net "M_A_DQS_DP<17>")
	)
	(segment
		(start 237.481618 -17.87652)
		(end 237.350554 -17.87652)
		(width 0.14224)
		(layer "In2.Cu")
		(net "M_A_DQS_DP<17>")
	)
	(segment
		(start 246.260874 -56.780938)
		(end 246.2657 -56.772302)
		(width 0.0889)
		(layer "In2.Cu")
		(net "M_A_DQS_DP<17>")
	)
	(segment
		(start 237.170976 -20.549108)
		(end 237.298484 -20.4216)
		(width 0.14224)
		(layer "In2.Cu")
		(net "M_A_DQS_DP<17>")
	)
	(segment
		(start 244.93093 -49.469548)
		(end 244.93093 -48.042068)
		(width 0.0889)
		(layer "In2.Cu")
		(net "M_A_DQS_DP<17>")
	)
	(segment
		(start 238.2266 -40.623236)
		(end 238.2266 -38.285928)
		(width 0.14224)
		(layer "In2.Cu")
		(net "M_A_DQS_DP<17>")
	)
	(segment
		(start 237.80496 -35.717988)
		(end 238.253016 -35.269932)
		(width 0.14224)
		(layer "In2.Cu")
		(net "M_A_DQS_DP<17>")
	)
	(segment
		(start 246.260874 -57.771538)
		(end 246.2657 -57.762902)
		(width 0.0889)
		(layer "In2.Cu")
		(net "M_A_DQS_DP<17>")
	)
	(segment
		(start 237.874048 -33.859978)
		(end 237.874048 -29.170376)
		(width 0.14224)
		(layer "In2.Cu")
		(net "M_A_DQS_DP<17>")
	)
	(segment
		(start 237.80496 -36.437316)
		(end 237.80496 -35.717988)
		(width 0.14224)
		(layer "In2.Cu")
		(net "M_A_DQS_DP<17>")
	)
	(segment
		(start 237.174532 -19.6342)
		(end 237.174532 -19.3802)
		(width 0.14224)
		(layer "In2.Cu")
		(net "M_A_DQS_DP<17>")
	)
	(segment
		(start 237.326932 -19.7866)
		(end 237.174532 -19.6342)
		(width 0.14224)
		(layer "In2.Cu")
		(net "M_A_DQS_DP<17>")
	)
	(segment
		(start 248.489724 -61.038486)
		(end 248.487946 -61.034676)
		(width 0.0889)
		(layer "In2.Cu")
		(net "M_A_DQS_DP<17>")
	)
	(arc
		(start 248.143014 -60.247784)
		(mid 248.093199 -60.102059)
		(end 248.10212 -59.948318)
		(width 0.0889)
		(layer "In2.Cu")
		(net "M_A_DQS_DP<17>")
	)
	(arc
		(start 248.037604 -59.475116)
		(mid 248.009903 -59.412857)
		(end 247.977914 -59.352688)
		(width 0.0889)
		(layer "In2.Cu")
		(net "M_A_DQS_DP<17>")
	)
	(arc
		(start 246.754904 -58.65749)
		(mid 246.256653 -58.35465)
		(end 246.260874 -57.771538)
		(width 0.0889)
		(layer "In2.Cu")
		(net "M_A_DQS_DP<17>")
	)
	(arc
		(start 247.61825 -59.15279)
		(mid 247.330105 -59.070471)
		(end 247.119394 -58.857388)
		(width 0.0889)
		(layer "In2.Cu")
		(net "M_A_DQS_DP<17>")
	)
	(arc
		(start 248.487946 -61.034676)
		(mid 248.337128 -60.63174)
		(end 248.143014 -60.247784)
		(width 0.0889)
		(layer "In2.Cu")
		(net "M_A_DQS_DP<17>")
	)
	(arc
		(start 246.260874 -56.380888)
		(mid 246.181664 -56.092794)
		(end 246.253508 -55.802784)
		(width 0.0889)
		(layer "In2.Cu")
		(net "M_A_DQS_DP<17>")
	)
	(arc
		(start 246.260874 -57.371488)
		(mid 246.181652 -57.08237)
		(end 246.254524 -56.791606)
		(width 0.0889)
		(layer "In2.Cu")
		(net "M_A_DQS_DP<17>")
	)
	(arc
		(start 247.977914 -59.352688)
		(mid 247.837835 -59.209952)
		(end 247.64619 -59.15279)
		(width 0.0889)
		(layer "In2.Cu")
		(net "M_A_DQS_DP<17>")
	)
	(arc
		(start 246.2657 -57.762902)
		(mid 246.314455 -57.56655)
		(end 246.260874 -57.371488)
		(width 0.0889)
		(layer "In2.Cu")
		(net "M_A_DQS_DP<17>")
	)
	(arc
		(start 247.119394 -58.857388)
		(mid 246.98065 -58.715355)
		(end 246.790718 -58.65749)
		(width 0.0889)
		(layer "In2.Cu")
		(net "M_A_DQS_DP<17>")
	)
	(arc
		(start 248.10212 -59.948318)
		(mid 248.099356 -59.707693)
		(end 248.037604 -59.475116)
		(width 0.0889)
		(layer "In2.Cu")
		(net "M_A_DQS_DP<17>")
	)
	(arc
		(start 246.2657 -56.772302)
		(mid 246.314455 -56.57595)
		(end 246.260874 -56.380888)
		(width 0.0889)
		(layer "In2.Cu")
		(net "M_A_DQS_DP<17>")
	)
	(segment
		(start 310.6293 -17.478502)
		(end 310.710834 -17.702784)
		(width 0.1651)
		(layer "F.Cu")
		(net "M_A_DQS_DP<16>")
	)
	(segment
		(start 311.150508 -15.423642)
		(end 311.15 -15.423642)
		(width 0.1651)
		(layer "F.Cu")
		(net "M_A_DQS_DP<16>")
	)
	(segment
		(start 311.15 -16.040354)
		(end 310.713882 -16.476472)
		(width 0.1651)
		(layer "F.Cu")
		(net "M_A_DQS_DP<16>")
	)
	(segment
		(start 287.50514 -56.399938)
		(end 286.93364 -56.399938)
		(width 0.1016)
		(layer "F.Cu")
		(net "M_A_DQS_DP<16>")
	)
	(segment
		(start 310.713882 -16.476472)
		(end 310.6293 -16.660368)
		(width 0.1651)
		(layer "F.Cu")
		(net "M_A_DQS_DP<16>")
	)
	(segment
		(start 310.710834 -17.702784)
		(end 311.092596 -18.084546)
		(width 0.1651)
		(layer "F.Cu")
		(net "M_A_DQS_DP<16>")
	)
	(segment
		(start 310.6293 -16.660368)
		(end 310.6293 -17.478502)
		(width 0.1651)
		(layer "F.Cu")
		(net "M_A_DQS_DP<16>")
	)
	(segment
		(start 311.15 -15.423642)
		(end 311.15 -16.040354)
		(width 0.1651)
		(layer "F.Cu")
		(net "M_A_DQS_DP<16>")
	)
	(via
		(at 286.93364 -56.399938)
		(size 0.508)
		(drill 0.254)
		(layers "F.Cu" "B.Cu")
		(net "M_A_DQS_DP<16>")
	)
	(via
		(at 311.092596 -22.1742)
		(size 0.508)
		(drill 0.254)
		(layers "F.Cu" "B.Cu")
		(net "M_A_DQS_DP<16>")
	)
	(via
		(at 311.092596 -18.084546)
		(size 0.508)
		(drill 0.254)
		(layers "F.Cu" "B.Cu")
		(net "M_A_DQS_DP<16>")
	)
	(segment
		(start 311.15 -24.206454)
		(end 310.693816 -23.75027)
		(width 0.1651)
		(layer "B.Cu")
		(net "M_A_DQS_DP<16>")
	)
	(segment
		(start 311.150508 -24.824182)
		(end 311.15 -24.824182)
		(width 0.1651)
		(layer "B.Cu")
		(net "M_A_DQS_DP<16>")
	)
	(segment
		(start 310.6166 -22.722332)
		(end 310.703976 -22.56282)
		(width 0.1651)
		(layer "B.Cu")
		(net "M_A_DQS_DP<16>")
	)
	(segment
		(start 310.6166 -23.617936)
		(end 310.6166 -22.722332)
		(width 0.1651)
		(layer "B.Cu")
		(net "M_A_DQS_DP<16>")
	)
	(segment
		(start 311.15 -24.824182)
		(end 311.15 -24.206454)
		(width 0.1651)
		(layer "B.Cu")
		(net "M_A_DQS_DP<16>")
	)
	(segment
		(start 310.693816 -23.75027)
		(end 310.6166 -23.617936)
		(width 0.1651)
		(layer "B.Cu")
		(net "M_A_DQS_DP<16>")
	)
	(segment
		(start 310.703976 -22.56282)
		(end 311.092596 -22.1742)
		(width 0.1651)
		(layer "B.Cu")
		(net "M_A_DQS_DP<16>")
	)
	(segment
		(start 286.58693 -55.609236)
		(end 286.399224 -55.255414)
		(width 0.0889)
		(layer "In2.Cu")
		(net "M_A_DQS_DP<16>")
	)
	(segment
		(start 311.248552 -20.4216)
		(end 311.4294 -20.4216)
		(width 0.14224)
		(layer "In2.Cu")
		(net "M_A_DQS_DP<16>")
	)
	(segment
		(start 311.61228 -18.057114)
		(end 311.431686 -17.87652)
		(width 0.14224)
		(layer "In2.Cu")
		(net "M_A_DQS_DP<16>")
	)
	(segment
		(start 298.640754 -44.83862)
		(end 298.640754 -44.07662)
		(width 0.14224)
		(layer "In2.Cu")
		(net "M_A_DQS_DP<16>")
	)
	(segment
		(start 310.6928 -24.6126)
		(end 310.6928 -23.789894)
		(width 0.14224)
		(layer "In2.Cu")
		(net "M_A_DQS_DP<16>")
	)
	(segment
		(start 297.665394 -43.7642)
		(end 297.977814 -44.07662)
		(width 0.14224)
		(layer "In2.Cu")
		(net "M_A_DQS_DP<16>")
	)
	(segment
		(start 297.977814 -44.07662)
		(end 297.977814 -44.83862)
		(width 0.14224)
		(layer "In2.Cu")
		(net "M_A_DQS_DP<16>")
	)
	(segment
		(start 293.364666 -46.387766)
		(end 294.150288 -46.387766)
		(width 0.14224)
		(layer "In2.Cu")
		(net "M_A_DQS_DP<16>")
	)
	(segment
		(start 311.092596 -22.1742)
		(end 311.371742 -22.1742)
		(width 0.14224)
		(layer "In2.Cu")
		(net "M_A_DQS_DP<16>")
	)
	(segment
		(start 297.977814 -44.83862)
		(end 298.132754 -44.99356)
		(width 0.14224)
		(layer "In2.Cu")
		(net "M_A_DQS_DP<16>")
	)
	(segment
		(start 296.773854 -43.7642)
		(end 297.665394 -43.7642)
		(width 0.14224)
		(layer "In2.Cu")
		(net "M_A_DQS_DP<16>")
	)
	(segment
		(start 311.3659 -21.0439)
		(end 311.277508 -21.0439)
		(width 0.14224)
		(layer "In2.Cu")
		(net "M_A_DQS_DP<16>")
	)
	(segment
		(start 288.799016 -50.953416)
		(end 288.814764 -50.937668)
		(width 0.0889)
		(layer "In2.Cu")
		(net "M_A_DQS_DP<16>")
	)
	(segment
		(start 311.404 -19.7866)
		(end 311.277 -19.7866)
		(width 0.14224)
		(layer "In2.Cu")
		(net "M_A_DQS_DP<16>")
	)
	(segment
		(start 310.5912 -22.675596)
		(end 311.092596 -22.1742)
		(width 0.14224)
		(layer "In2.Cu")
		(net "M_A_DQS_DP<16>")
	)
	(segment
		(start 311.61228 -21.933662)
		(end 311.61228 -21.29028)
		(width 0.14224)
		(layer "In2.Cu")
		(net "M_A_DQS_DP<16>")
	)
	(segment
		(start 298.132754 -44.99356)
		(end 298.485814 -44.99356)
		(width 0.14224)
		(layer "In2.Cu")
		(net "M_A_DQS_DP<16>")
	)
	(segment
		(start 311.61228 -19.99488)
		(end 311.404 -19.7866)
		(width 0.14224)
		(layer "In2.Cu")
		(net "M_A_DQS_DP<16>")
	)
	(segment
		(start 287.28035 -52.637182)
		(end 287.43275 -52.37353)
		(width 0.0889)
		(layer "In2.Cu")
		(net "M_A_DQS_DP<16>")
	)
	(segment
		(start 286.920686 -53.827934)
		(end 286.944816 -53.827934)
		(width 0.0889)
		(layer "In2.Cu")
		(net "M_A_DQS_DP<16>")
	)
	(segment
		(start 288.814764 -50.937668)
		(end 293.364666 -46.387766)
		(width 0.14224)
		(layer "In2.Cu")
		(net "M_A_DQS_DP<16>")
	)
	(segment
		(start 311.431686 -17.87652)
		(end 311.300622 -17.87652)
		(width 0.14224)
		(layer "In2.Cu")
		(net "M_A_DQS_DP<16>")
	)
	(segment
		(start 311.1246 -19.3802)
		(end 311.61228 -18.89252)
		(width 0.14224)
		(layer "In2.Cu")
		(net "M_A_DQS_DP<16>")
	)
	(segment
		(start 286.93364 -56.399938)
		(end 286.716724 -56.012588)
		(width 0.0889)
		(layer "In2.Cu")
		(net "M_A_DQS_DP<16>")
	)
	(segment
		(start 286.59328 -55.619904)
		(end 286.58693 -55.609236)
		(width 0.0889)
		(layer "In2.Cu")
		(net "M_A_DQS_DP<16>")
	)
	(segment
		(start 294.150288 -46.387766)
		(end 296.773854 -43.7642)
		(width 0.14224)
		(layer "In2.Cu")
		(net "M_A_DQS_DP<16>")
	)
	(segment
		(start 298.485814 -44.99356)
		(end 298.640754 -44.83862)
		(width 0.14224)
		(layer "In2.Cu")
		(net "M_A_DQS_DP<16>")
	)
	(segment
		(start 310.860186 -37.399214)
		(end 311.404 -36.8554)
		(width 0.14224)
		(layer "In2.Cu")
		(net "M_A_DQS_DP<16>")
	)
	(segment
		(start 308.116986 -37.399214)
		(end 310.860186 -37.399214)
		(width 0.14224)
		(layer "In2.Cu")
		(net "M_A_DQS_DP<16>")
	)
	(segment
		(start 287.43275 -52.37353)
		(end 288.799016 -51.007264)
		(width 0.0889)
		(layer "In2.Cu")
		(net "M_A_DQS_DP<16>")
	)
	(segment
		(start 311.277 -19.7866)
		(end 311.1246 -19.6342)
		(width 0.14224)
		(layer "In2.Cu")
		(net "M_A_DQS_DP<16>")
	)
	(segment
		(start 311.404 -36.8554)
		(end 311.404 -25.3238)
		(width 0.14224)
		(layer "In2.Cu")
		(net "M_A_DQS_DP<16>")
	)
	(segment
		(start 311.4294 -20.4216)
		(end 311.61228 -20.23872)
		(width 0.14224)
		(layer "In2.Cu")
		(net "M_A_DQS_DP<16>")
	)
	(segment
		(start 298.953174 -43.7642)
		(end 301.752 -43.7642)
		(width 0.14224)
		(layer "In2.Cu")
		(net "M_A_DQS_DP<16>")
	)
	(segment
		(start 298.640754 -44.07662)
		(end 298.953174 -43.7642)
		(width 0.14224)
		(layer "In2.Cu")
		(net "M_A_DQS_DP<16>")
	)
	(segment
		(start 311.61228 -21.29028)
		(end 311.3659 -21.0439)
		(width 0.14224)
		(layer "In2.Cu")
		(net "M_A_DQS_DP<16>")
	)
	(segment
		(start 311.1246 -19.6342)
		(end 311.1246 -19.3802)
		(width 0.14224)
		(layer "In2.Cu")
		(net "M_A_DQS_DP<16>")
	)
	(segment
		(start 301.752 -43.7642)
		(end 308.116986 -37.399214)
		(width 0.14224)
		(layer "In2.Cu")
		(net "M_A_DQS_DP<16>")
	)
	(segment
		(start 311.121044 -20.887436)
		(end 311.121044 -20.549108)
		(width 0.14224)
		(layer "In2.Cu")
		(net "M_A_DQS_DP<16>")
	)
	(segment
		(start 311.300622 -17.87652)
		(end 311.092596 -18.084546)
		(width 0.14224)
		(layer "In2.Cu")
		(net "M_A_DQS_DP<16>")
	)
	(segment
		(start 311.61228 -20.23872)
		(end 311.61228 -19.99488)
		(width 0.14224)
		(layer "In2.Cu")
		(net "M_A_DQS_DP<16>")
	)
	(segment
		(start 311.371742 -22.1742)
		(end 311.61228 -21.933662)
		(width 0.14224)
		(layer "In2.Cu")
		(net "M_A_DQS_DP<16>")
	)
	(segment
		(start 310.6928 -23.789894)
		(end 310.5912 -23.688294)
		(width 0.14224)
		(layer "In2.Cu")
		(net "M_A_DQS_DP<16>")
	)
	(segment
		(start 311.404 -25.3238)
		(end 310.6928 -24.6126)
		(width 0.14224)
		(layer "In2.Cu")
		(net "M_A_DQS_DP<16>")
	)
	(segment
		(start 310.5912 -23.688294)
		(end 310.5912 -22.675596)
		(width 0.14224)
		(layer "In2.Cu")
		(net "M_A_DQS_DP<16>")
	)
	(segment
		(start 311.121044 -20.549108)
		(end 311.248552 -20.4216)
		(width 0.14224)
		(layer "In2.Cu")
		(net "M_A_DQS_DP<16>")
	)
	(segment
		(start 311.61228 -18.89252)
		(end 311.61228 -18.057114)
		(width 0.14224)
		(layer "In2.Cu")
		(net "M_A_DQS_DP<16>")
	)
	(segment
		(start 288.799016 -51.007264)
		(end 288.799016 -50.953416)
		(width 0.0889)
		(layer "In2.Cu")
		(net "M_A_DQS_DP<16>")
	)
	(segment
		(start 311.277508 -21.0439)
		(end 311.121044 -20.887436)
		(width 0.14224)
		(layer "In2.Cu")
		(net "M_A_DQS_DP<16>")
	)
	(segment
		(start 286.399224 -55.255414)
		(end 286.42183 -55.113936)
		(width 0.0889)
		(layer "In2.Cu")
		(net "M_A_DQS_DP<16>")
	)
	(arc
		(start 286.42183 -55.113936)
		(mid 286.434738 -55.089711)
		(end 286.44596 -55.06466)
		(width 0.0889)
		(layer "In2.Cu")
		(net "M_A_DQS_DP<16>")
	)
	(arc
		(start 286.944816 -53.827934)
		(mid 287.282931 -53.623232)
		(end 287.28035 -53.227986)
		(width 0.0889)
		(layer "In2.Cu")
		(net "M_A_DQS_DP<16>")
	)
	(arc
		(start 286.41548 -54.703218)
		(mid 286.421657 -54.123286)
		(end 286.920686 -53.827934)
		(width 0.0889)
		(layer "In2.Cu")
		(net "M_A_DQS_DP<16>")
	)
	(arc
		(start 287.28035 -53.227986)
		(mid 287.201219 -52.932584)
		(end 287.28035 -52.637182)
		(width 0.0889)
		(layer "In2.Cu")
		(net "M_A_DQS_DP<16>")
	)
	(arc
		(start 286.44596 -55.06466)
		(mid 286.474761 -54.891429)
		(end 286.426656 -54.722522)
		(width 0.0889)
		(layer "In2.Cu")
		(net "M_A_DQS_DP<16>")
	)
	(arc
		(start 286.716724 -56.012588)
		(mid 286.6744 -55.81015)
		(end 286.59328 -55.619904)
		(width 0.0889)
		(layer "In2.Cu")
		(net "M_A_DQS_DP<16>")
	)
	(arc
		(start 286.426656 -54.722522)
		(mid 286.421196 -54.712796)
		(end 286.41548 -54.703218)
		(width 0.0889)
		(layer "In2.Cu")
		(net "M_A_DQS_DP<16>")
	)
	(segment
		(start 282.354274 -56.399938)
		(end 281.782774 -56.399938)
		(width 0.1016)
		(layer "F.Cu")
		(net "M_A_DQS_DP<15>")
	)
	(segment
		(start 301.36084 -17.702784)
		(end 301.742602 -18.084546)
		(width 0.1651)
		(layer "F.Cu")
		(net "M_A_DQS_DP<15>")
	)
	(segment
		(start 301.363888 -16.476472)
		(end 301.279306 -16.660368)
		(width 0.1651)
		(layer "F.Cu")
		(net "M_A_DQS_DP<15>")
	)
	(segment
		(start 301.800006 -15.423642)
		(end 301.800006 -16.040354)
		(width 0.1651)
		(layer "F.Cu")
		(net "M_A_DQS_DP<15>")
	)
	(segment
		(start 301.800514 -15.423642)
		(end 301.800006 -15.423642)
		(width 0.1651)
		(layer "F.Cu")
		(net "M_A_DQS_DP<15>")
	)
	(segment
		(start 301.279306 -16.660368)
		(end 301.279306 -17.478502)
		(width 0.1651)
		(layer "F.Cu")
		(net "M_A_DQS_DP<15>")
	)
	(segment
		(start 301.279306 -17.478502)
		(end 301.36084 -17.702784)
		(width 0.1651)
		(layer "F.Cu")
		(net "M_A_DQS_DP<15>")
	)
	(segment
		(start 301.800006 -16.040354)
		(end 301.363888 -16.476472)
		(width 0.1651)
		(layer "F.Cu")
		(net "M_A_DQS_DP<15>")
	)
	(via
		(at 301.742602 -22.1742)
		(size 0.508)
		(drill 0.254)
		(layers "F.Cu" "B.Cu")
		(net "M_A_DQS_DP<15>")
	)
	(via
		(at 281.782774 -56.399938)
		(size 0.508)
		(drill 0.254)
		(layers "F.Cu" "B.Cu")
		(net "M_A_DQS_DP<15>")
	)
	(via
		(at 301.742602 -18.084546)
		(size 0.508)
		(drill 0.254)
		(layers "F.Cu" "B.Cu")
		(net "M_A_DQS_DP<15>")
	)
	(segment
		(start 301.696628 -22.220428)
		(end 301.742602 -22.1742)
		(width 0.1651)
		(layer "B.Cu")
		(net "M_A_DQS_DP<15>")
	)
	(segment
		(start 301.353982 -22.56282)
		(end 301.696628 -22.220428)
		(width 0.1651)
		(layer "B.Cu")
		(net "M_A_DQS_DP<15>")
	)
	(segment
		(start 301.266606 -23.617936)
		(end 301.266606 -22.722332)
		(width 0.1651)
		(layer "B.Cu")
		(net "M_A_DQS_DP<15>")
	)
	(segment
		(start 301.266606 -22.722332)
		(end 301.353982 -22.56282)
		(width 0.1651)
		(layer "B.Cu")
		(net "M_A_DQS_DP<15>")
	)
	(segment
		(start 301.800514 -24.824182)
		(end 301.800006 -24.824182)
		(width 0.1651)
		(layer "B.Cu")
		(net "M_A_DQS_DP<15>")
	)
	(segment
		(start 301.800006 -24.206454)
		(end 301.343822 -23.75027)
		(width 0.1651)
		(layer "B.Cu")
		(net "M_A_DQS_DP<15>")
	)
	(segment
		(start 301.800006 -24.824182)
		(end 301.800006 -24.206454)
		(width 0.1651)
		(layer "B.Cu")
		(net "M_A_DQS_DP<15>")
	)
	(segment
		(start 301.343822 -23.75027)
		(end 301.266606 -23.617936)
		(width 0.1651)
		(layer "B.Cu")
		(net "M_A_DQS_DP<15>")
	)
	(segment
		(start 281.329384 -54.02199)
		(end 281.329384 -51.823366)
		(width 0.0889)
		(layer "In2.Cu")
		(net "M_A_DQS_DP<15>")
	)
	(segment
		(start 302.079406 -20.4216)
		(end 302.262286 -20.23872)
		(width 0.14224)
		(layer "In2.Cu")
		(net "M_A_DQS_DP<15>")
	)
	(segment
		(start 301.927006 -19.7866)
		(end 301.774606 -19.6342)
		(width 0.14224)
		(layer "In2.Cu")
		(net "M_A_DQS_DP<15>")
	)
	(segment
		(start 299.711364 -32.593026)
		(end 299.921422 -32.803084)
		(width 0.14224)
		(layer "In2.Cu")
		(net "M_A_DQS_DP<15>")
	)
	(segment
		(start 302.262286 -18.89252)
		(end 302.262286 -18.057114)
		(width 0.14224)
		(layer "In2.Cu")
		(net "M_A_DQS_DP<15>")
	)
	(segment
		(start 281.1907 -48.212502)
		(end 281.1907 -48.190404)
		(width 0.0889)
		(layer "In2.Cu")
		(net "M_A_DQS_DP<15>")
	)
	(segment
		(start 298.002452 -33.925002)
		(end 298.404788 -33.925002)
		(width 0.14224)
		(layer "In2.Cu")
		(net "M_A_DQS_DP<15>")
	)
	(segment
		(start 302.022256 -22.1742)
		(end 302.262286 -21.93417)
		(width 0.14224)
		(layer "In2.Cu")
		(net "M_A_DQS_DP<15>")
	)
	(segment
		(start 300.142148 -32.086042)
		(end 300.142148 -31.683706)
		(width 0.14224)
		(layer "In2.Cu")
		(net "M_A_DQS_DP<15>")
	)
	(segment
		(start 281.270964 -54.71414)
		(end 281.269694 -54.711854)
		(width 0.0889)
		(layer "In2.Cu")
		(net "M_A_DQS_DP<15>")
	)
	(segment
		(start 281.27071 -54.124098)
		(end 281.329384 -54.02199)
		(width 0.0889)
		(layer "In2.Cu")
		(net "M_A_DQS_DP<15>")
	)
	(segment
		(start 302.015906 -21.0439)
		(end 301.927514 -21.0439)
		(width 0.14224)
		(layer "In2.Cu")
		(net "M_A_DQS_DP<15>")
	)
	(segment
		(start 300.390306 -32.553148)
		(end 300.390306 -32.3342)
		(width 0.14224)
		(layer "In2.Cu")
		(net "M_A_DQS_DP<15>")
	)
	(segment
		(start 302.262286 -19.99488)
		(end 302.054006 -19.7866)
		(width 0.14224)
		(layer "In2.Cu")
		(net "M_A_DQS_DP<15>")
	)
	(segment
		(start 301.77105 -20.887436)
		(end 301.77105 -20.549108)
		(width 0.14224)
		(layer "In2.Cu")
		(net "M_A_DQS_DP<15>")
	)
	(segment
		(start 299.07103 -33.872424)
		(end 299.07103 -33.653476)
		(width 0.14224)
		(layer "In2.Cu")
		(net "M_A_DQS_DP<15>")
	)
	(segment
		(start 288.8488 -35.7632)
		(end 297.180254 -35.7632)
		(width 0.14224)
		(layer "In2.Cu")
		(net "M_A_DQS_DP<15>")
	)
	(segment
		(start 297.751754 -34.972752)
		(end 297.554396 -34.775394)
		(width 0.14224)
		(layer "In2.Cu")
		(net "M_A_DQS_DP<15>")
	)
	(segment
		(start 281.782774 -56.399938)
		(end 281.780996 -56.396128)
		(width 0.0889)
		(layer "In2.Cu")
		(net "M_A_DQS_DP<15>")
	)
	(segment
		(start 300.590204 -31.23565)
		(end 301.707804 -31.23565)
		(width 0.14224)
		(layer "In2.Cu")
		(net "M_A_DQS_DP<15>")
	)
	(segment
		(start 302.262286 -20.23872)
		(end 302.262286 -19.99488)
		(width 0.14224)
		(layer "In2.Cu")
		(net "M_A_DQS_DP<15>")
	)
	(segment
		(start 298.404788 -33.925002)
		(end 298.602146 -34.12236)
		(width 0.14224)
		(layer "In2.Cu")
		(net "M_A_DQS_DP<15>")
	)
	(segment
		(start 301.707804 -31.23565)
		(end 302.258476 -30.684978)
		(width 0.14224)
		(layer "In2.Cu")
		(net "M_A_DQS_DP<15>")
	)
	(segment
		(start 281.1907 -48.190404)
		(end 281.1907 -43.4213)
		(width 0.14224)
		(layer "In2.Cu")
		(net "M_A_DQS_DP<15>")
	)
	(segment
		(start 302.258476 -30.684978)
		(end 302.258476 -25.771856)
		(width 0.14224)
		(layer "In2.Cu")
		(net "M_A_DQS_DP<15>")
	)
	(segment
		(start 300.142148 -31.683706)
		(end 300.590204 -31.23565)
		(width 0.14224)
		(layer "In2.Cu")
		(net "M_A_DQS_DP<15>")
	)
	(segment
		(start 298.860972 -33.443418)
		(end 298.860972 -33.041082)
		(width 0.14224)
		(layer "In2.Cu")
		(net "M_A_DQS_DP<15>")
	)
	(segment
		(start 301.696628 -22.220428)
		(end 301.742602 -22.1742)
		(width 0.14224)
		(layer "In2.Cu")
		(net "M_A_DQS_DP<15>")
	)
	(segment
		(start 281.23007 -50.300636)
		(end 281.23007 -48.251872)
		(width 0.0889)
		(layer "In2.Cu")
		(net "M_A_DQS_DP<15>")
	)
	(segment
		(start 301.898558 -20.4216)
		(end 302.079406 -20.4216)
		(width 0.14224)
		(layer "In2.Cu")
		(net "M_A_DQS_DP<15>")
	)
	(segment
		(start 281.1907 -43.4213)
		(end 288.8488 -35.7632)
		(width 0.14224)
		(layer "In2.Cu")
		(net "M_A_DQS_DP<15>")
	)
	(segment
		(start 301.774606 -19.3802)
		(end 302.262286 -18.89252)
		(width 0.14224)
		(layer "In2.Cu")
		(net "M_A_DQS_DP<15>")
	)
	(segment
		(start 281.23007 -48.251872)
		(end 281.1907 -48.212502)
		(width 0.0889)
		(layer "In2.Cu")
		(net "M_A_DQS_DP<15>")
	)
	(segment
		(start 300.390306 -32.3342)
		(end 300.142148 -32.086042)
		(width 0.14224)
		(layer "In2.Cu")
		(net "M_A_DQS_DP<15>")
	)
	(segment
		(start 281.269694 -54.711854)
		(end 281.263598 -54.70144)
		(width 0.0889)
		(layer "In2.Cu")
		(net "M_A_DQS_DP<15>")
	)
	(segment
		(start 301.774606 -19.6342)
		(end 301.774606 -19.3802)
		(width 0.14224)
		(layer "In2.Cu")
		(net "M_A_DQS_DP<15>")
	)
	(segment
		(start 300.14037 -32.803084)
		(end 300.390306 -32.553148)
		(width 0.14224)
		(layer "In2.Cu")
		(net "M_A_DQS_DP<15>")
	)
	(segment
		(start 297.554396 -34.775394)
		(end 297.554396 -34.373058)
		(width 0.14224)
		(layer "In2.Cu")
		(net "M_A_DQS_DP<15>")
	)
	(segment
		(start 297.751754 -35.1917)
		(end 297.751754 -34.972752)
		(width 0.14224)
		(layer "In2.Cu")
		(net "M_A_DQS_DP<15>")
	)
	(segment
		(start 301.77105 -20.549108)
		(end 301.898558 -20.4216)
		(width 0.14224)
		(layer "In2.Cu")
		(net "M_A_DQS_DP<15>")
	)
	(segment
		(start 301.950628 -17.87652)
		(end 301.742602 -18.084546)
		(width 0.14224)
		(layer "In2.Cu")
		(net "M_A_DQS_DP<15>")
	)
	(segment
		(start 299.07103 -33.653476)
		(end 298.860972 -33.443418)
		(width 0.14224)
		(layer "In2.Cu")
		(net "M_A_DQS_DP<15>")
	)
	(segment
		(start 301.271686 -24.785066)
		(end 301.271686 -22.645116)
		(width 0.14224)
		(layer "In2.Cu")
		(net "M_A_DQS_DP<15>")
	)
	(segment
		(start 280.886408 -50.644298)
		(end 281.23007 -50.300636)
		(width 0.0889)
		(layer "In2.Cu")
		(net "M_A_DQS_DP<15>")
	)
	(segment
		(start 302.262286 -21.93417)
		(end 302.262286 -21.29028)
		(width 0.14224)
		(layer "In2.Cu")
		(net "M_A_DQS_DP<15>")
	)
	(segment
		(start 302.054006 -19.7866)
		(end 301.927006 -19.7866)
		(width 0.14224)
		(layer "In2.Cu")
		(net "M_A_DQS_DP<15>")
	)
	(segment
		(start 302.262286 -18.057114)
		(end 302.081692 -17.87652)
		(width 0.14224)
		(layer "In2.Cu")
		(net "M_A_DQS_DP<15>")
	)
	(segment
		(start 301.927514 -21.0439)
		(end 301.77105 -20.887436)
		(width 0.14224)
		(layer "In2.Cu")
		(net "M_A_DQS_DP<15>")
	)
	(segment
		(start 280.886408 -51.38039)
		(end 280.886408 -50.644298)
		(width 0.0889)
		(layer "In2.Cu")
		(net "M_A_DQS_DP<15>")
	)
	(segment
		(start 301.742602 -22.1742)
		(end 302.022256 -22.1742)
		(width 0.14224)
		(layer "In2.Cu")
		(net "M_A_DQS_DP<15>")
	)
	(segment
		(start 302.258476 -25.771856)
		(end 301.271686 -24.785066)
		(width 0.14224)
		(layer "In2.Cu")
		(net "M_A_DQS_DP<15>")
	)
	(segment
		(start 299.921422 -32.803084)
		(end 300.14037 -32.803084)
		(width 0.14224)
		(layer "In2.Cu")
		(net "M_A_DQS_DP<15>")
	)
	(segment
		(start 302.262286 -21.29028)
		(end 302.015906 -21.0439)
		(width 0.14224)
		(layer "In2.Cu")
		(net "M_A_DQS_DP<15>")
	)
	(segment
		(start 298.860972 -33.041082)
		(end 299.309028 -32.593026)
		(width 0.14224)
		(layer "In2.Cu")
		(net "M_A_DQS_DP<15>")
	)
	(segment
		(start 281.329384 -51.823366)
		(end 280.886408 -51.38039)
		(width 0.0889)
		(layer "In2.Cu")
		(net "M_A_DQS_DP<15>")
	)
	(segment
		(start 297.554396 -34.373058)
		(end 298.002452 -33.925002)
		(width 0.14224)
		(layer "In2.Cu")
		(net "M_A_DQS_DP<15>")
	)
	(segment
		(start 297.180254 -35.7632)
		(end 297.751754 -35.1917)
		(width 0.14224)
		(layer "In2.Cu")
		(net "M_A_DQS_DP<15>")
	)
	(segment
		(start 299.309028 -32.593026)
		(end 299.711364 -32.593026)
		(width 0.14224)
		(layer "In2.Cu")
		(net "M_A_DQS_DP<15>")
	)
	(segment
		(start 302.081692 -17.87652)
		(end 301.950628 -17.87652)
		(width 0.14224)
		(layer "In2.Cu")
		(net "M_A_DQS_DP<15>")
	)
	(segment
		(start 301.271686 -22.645116)
		(end 301.696628 -22.220428)
		(width 0.14224)
		(layer "In2.Cu")
		(net "M_A_DQS_DP<15>")
	)
	(segment
		(start 298.602146 -34.12236)
		(end 298.821094 -34.12236)
		(width 0.14224)
		(layer "In2.Cu")
		(net "M_A_DQS_DP<15>")
	)
	(segment
		(start 298.821094 -34.12236)
		(end 299.07103 -33.872424)
		(width 0.14224)
		(layer "In2.Cu")
		(net "M_A_DQS_DP<15>")
	)
	(arc
		(start 281.780996 -56.396128)
		(mid 281.630178 -55.993192)
		(end 281.436064 -55.609236)
		(width 0.0889)
		(layer "In2.Cu")
		(net "M_A_DQS_DP<15>")
	)
	(arc
		(start 281.39517 -55.30977)
		(mid 281.380772 -55.002012)
		(end 281.270964 -54.71414)
		(width 0.0889)
		(layer "In2.Cu")
		(net "M_A_DQS_DP<15>")
	)
	(arc
		(start 281.263598 -54.70144)
		(mid 281.191908 -54.411858)
		(end 281.27071 -54.124098)
		(width 0.0889)
		(layer "In2.Cu")
		(net "M_A_DQS_DP<15>")
	)
	(arc
		(start 281.436064 -55.609236)
		(mid 281.386249 -55.463511)
		(end 281.39517 -55.30977)
		(width 0.0889)
		(layer "In2.Cu")
		(net "M_A_DQS_DP<15>")
	)
	(segment
		(start 292.013894 -16.476472)
		(end 292.450012 -16.040354)
		(width 0.1651)
		(layer "F.Cu")
		(net "M_A_DQS_DP<14>")
	)
	(segment
		(start 292.010846 -17.702784)
		(end 291.929312 -17.478502)
		(width 0.1651)
		(layer "F.Cu")
		(net "M_A_DQS_DP<14>")
	)
	(segment
		(start 292.450012 -15.423642)
		(end 292.45052 -15.423642)
		(width 0.1651)
		(layer "F.Cu")
		(net "M_A_DQS_DP<14>")
	)
	(segment
		(start 291.929312 -17.478502)
		(end 291.929312 -16.660368)
		(width 0.1651)
		(layer "F.Cu")
		(net "M_A_DQS_DP<14>")
	)
	(segment
		(start 277.203154 -56.399938)
		(end 276.631654 -56.399938)
		(width 0.1016)
		(layer "F.Cu")
		(net "M_A_DQS_DP<14>")
	)
	(segment
		(start 291.929312 -16.660368)
		(end 292.013894 -16.476472)
		(width 0.1651)
		(layer "F.Cu")
		(net "M_A_DQS_DP<14>")
	)
	(segment
		(start 292.450012 -16.040354)
		(end 292.450012 -15.423642)
		(width 0.1651)
		(layer "F.Cu")
		(net "M_A_DQS_DP<14>")
	)
	(segment
		(start 292.392608 -18.084546)
		(end 292.010846 -17.702784)
		(width 0.1651)
		(layer "F.Cu")
		(net "M_A_DQS_DP<14>")
	)
	(via
		(at 292.392608 -22.1742)
		(size 0.508)
		(drill 0.254)
		(layers "F.Cu" "B.Cu")
		(net "M_A_DQS_DP<14>")
	)
	(via
		(at 276.631654 -56.399938)
		(size 0.508)
		(drill 0.254)
		(layers "F.Cu" "B.Cu")
		(net "M_A_DQS_DP<14>")
	)
	(via
		(at 292.392608 -18.084546)
		(size 0.508)
		(drill 0.254)
		(layers "F.Cu" "B.Cu")
		(net "M_A_DQS_DP<14>")
	)
	(segment
		(start 292.450012 -24.206454)
		(end 291.993828 -23.75027)
		(width 0.1651)
		(layer "B.Cu")
		(net "M_A_DQS_DP<14>")
	)
	(segment
		(start 291.916612 -22.722332)
		(end 292.003988 -22.56282)
		(width 0.1651)
		(layer "B.Cu")
		(net "M_A_DQS_DP<14>")
	)
	(segment
		(start 291.993828 -23.75027)
		(end 291.916612 -23.617936)
		(width 0.1651)
		(layer "B.Cu")
		(net "M_A_DQS_DP<14>")
	)
	(segment
		(start 292.003988 -22.56282)
		(end 292.392608 -22.1742)
		(width 0.1651)
		(layer "B.Cu")
		(net "M_A_DQS_DP<14>")
	)
	(segment
		(start 292.45052 -24.824182)
		(end 292.450012 -24.824182)
		(width 0.1651)
		(layer "B.Cu")
		(net "M_A_DQS_DP<14>")
	)
	(segment
		(start 292.450012 -24.824182)
		(end 292.450012 -24.206454)
		(width 0.1651)
		(layer "B.Cu")
		(net "M_A_DQS_DP<14>")
	)
	(segment
		(start 291.916612 -23.617936)
		(end 291.916612 -22.722332)
		(width 0.1651)
		(layer "B.Cu")
		(net "M_A_DQS_DP<14>")
	)
	(segment
		(start 276.116034 -54.707536)
		(end 276.115018 -54.706012)
		(width 0.0889)
		(layer "In2.Cu")
		(net "M_A_DQS_DP<14>")
	)
	(segment
		(start 292.731698 -17.87652)
		(end 292.600634 -17.87652)
		(width 0.14224)
		(layer "In2.Cu")
		(net "M_A_DQS_DP<14>")
	)
	(segment
		(start 291.355272 -25.7302)
		(end 291.891212 -25.19426)
		(width 0.14224)
		(layer "In2.Cu")
		(net "M_A_DQS_DP<14>")
	)
	(segment
		(start 291.891212 -25.19426)
		(end 291.891212 -22.675596)
		(width 0.14224)
		(layer "In2.Cu")
		(net "M_A_DQS_DP<14>")
	)
	(segment
		(start 276.119844 -54.71414)
		(end 276.11832 -54.7116)
		(width 0.0889)
		(layer "In2.Cu")
		(net "M_A_DQS_DP<14>")
	)
	(segment
		(start 278.592026 -32.354774)
		(end 278.592026 -32.136334)
		(width 0.14224)
		(layer "In2.Cu")
		(net "M_A_DQS_DP<14>")
	)
	(segment
		(start 275.165058 -52.316888)
		(end 275.165058 -51.21402)
		(width 0.0889)
		(layer "In2.Cu")
		(net "M_A_DQS_DP<14>")
	)
	(segment
		(start 292.912292 -18.89252)
		(end 292.912292 -18.057114)
		(width 0.14224)
		(layer "In2.Cu")
		(net "M_A_DQS_DP<14>")
	)
	(segment
		(start 274.517612 -35.413188)
		(end 274.96008 -35.413188)
		(width 0.14224)
		(layer "In2.Cu")
		(net "M_A_DQS_DP<14>")
	)
	(segment
		(start 275.429472 -34.501328)
		(end 275.836888 -34.093912)
		(width 0.14224)
		(layer "In2.Cu")
		(net "M_A_DQS_DP<14>")
	)
	(segment
		(start 275.201126 -35.654234)
		(end 275.419566 -35.654234)
		(width 0.14224)
		(layer "In2.Cu")
		(net "M_A_DQS_DP<14>")
	)
	(segment
		(start 276.989794 -34.084006)
		(end 276.989794 -33.865566)
		(width 0.14224)
		(layer "In2.Cu")
		(net "M_A_DQS_DP<14>")
	)
	(segment
		(start 292.392608 -22.1742)
		(end 292.671246 -22.1742)
		(width 0.14224)
		(layer "In2.Cu")
		(net "M_A_DQS_DP<14>")
	)
	(segment
		(start 292.424612 -19.6342)
		(end 292.424612 -19.3802)
		(width 0.14224)
		(layer "In2.Cu")
		(net "M_A_DQS_DP<14>")
	)
	(segment
		(start 285.32328 -27.84856)
		(end 285.58744 -27.5844)
		(width 0.14224)
		(layer "In2.Cu")
		(net "M_A_DQS_DP<14>")
	)
	(segment
		(start 275.904706 -53.056536)
		(end 275.165058 -52.316888)
		(width 0.0889)
		(layer "In2.Cu")
		(net "M_A_DQS_DP<14>")
	)
	(segment
		(start 273.87296 -46.62805)
		(end 273.87296 -36.05784)
		(width 0.14224)
		(layer "In2.Cu")
		(net "M_A_DQS_DP<14>")
	)
	(segment
		(start 279.911302 -31.035498)
		(end 279.911302 -30.817058)
		(width 0.14224)
		(layer "In2.Cu")
		(net "M_A_DQS_DP<14>")
	)
	(segment
		(start 285.58744 -27.5844)
		(end 286.842454 -27.5844)
		(width 0.14224)
		(layer "In2.Cu")
		(net "M_A_DQS_DP<14>")
	)
	(segment
		(start 277.945088 -32.42818)
		(end 278.122634 -32.605726)
		(width 0.14224)
		(layer "In2.Cu")
		(net "M_A_DQS_DP<14>")
	)
	(segment
		(start 292.421056 -20.887436)
		(end 292.421056 -20.549108)
		(width 0.14224)
		(layer "In2.Cu")
		(net "M_A_DQS_DP<14>")
	)
	(segment
		(start 279.66035 -31.28645)
		(end 279.911302 -31.035498)
		(width 0.14224)
		(layer "In2.Cu")
		(net "M_A_DQS_DP<14>")
	)
	(segment
		(start 292.57752 -21.0439)
		(end 292.421056 -20.887436)
		(width 0.14224)
		(layer "In2.Cu")
		(net "M_A_DQS_DP<14>")
	)
	(segment
		(start 275.419566 -35.654234)
		(end 275.670518 -35.403282)
		(width 0.14224)
		(layer "In2.Cu")
		(net "M_A_DQS_DP<14>")
	)
	(segment
		(start 278.592026 -32.136334)
		(end 278.41448 -31.958788)
		(width 0.14224)
		(layer "In2.Cu")
		(net "M_A_DQS_DP<14>")
	)
	(segment
		(start 292.600634 -17.87652)
		(end 292.392608 -18.084546)
		(width 0.14224)
		(layer "In2.Cu")
		(net "M_A_DQS_DP<14>")
	)
	(segment
		(start 279.911302 -30.817058)
		(end 279.733756 -30.639512)
		(width 0.14224)
		(layer "In2.Cu")
		(net "M_A_DQS_DP<14>")
	)
	(segment
		(start 276.748748 -33.62452)
		(end 276.748748 -33.182052)
		(width 0.14224)
		(layer "In2.Cu")
		(net "M_A_DQS_DP<14>")
	)
	(segment
		(start 274.089622 -47.08525)
		(end 274.078446 -47.08525)
		(width 0.0889)
		(layer "In2.Cu")
		(net "M_A_DQS_DP<14>")
	)
	(segment
		(start 279.264364 -31.108904)
		(end 279.44191 -31.28645)
		(width 0.14224)
		(layer "In2.Cu")
		(net "M_A_DQS_DP<14>")
	)
	(segment
		(start 276.748748 -33.182052)
		(end 277.50262 -32.42818)
		(width 0.14224)
		(layer "In2.Cu")
		(net "M_A_DQS_DP<14>")
	)
	(segment
		(start 283.49956 -27.5844)
		(end 283.76372 -27.84856)
		(width 0.14224)
		(layer "In2.Cu")
		(net "M_A_DQS_DP<14>")
	)
	(segment
		(start 275.904706 -53.35016)
		(end 275.904706 -53.056536)
		(width 0.0889)
		(layer "In2.Cu")
		(net "M_A_DQS_DP<14>")
	)
	(segment
		(start 292.912292 -19.99488)
		(end 292.704012 -19.7866)
		(width 0.14224)
		(layer "In2.Cu")
		(net "M_A_DQS_DP<14>")
	)
	(segment
		(start 279.733756 -30.639512)
		(end 279.733756 -30.197044)
		(width 0.14224)
		(layer "In2.Cu")
		(net "M_A_DQS_DP<14>")
	)
	(segment
		(start 291.891212 -22.675596)
		(end 292.392608 -22.1742)
		(width 0.14224)
		(layer "In2.Cu")
		(net "M_A_DQS_DP<14>")
	)
	(segment
		(start 292.577012 -19.7866)
		(end 292.424612 -19.6342)
		(width 0.14224)
		(layer "In2.Cu")
		(net "M_A_DQS_DP<14>")
	)
	(segment
		(start 273.87296 -36.05784)
		(end 274.517612 -35.413188)
		(width 0.14224)
		(layer "In2.Cu")
		(net "M_A_DQS_DP<14>")
	)
	(segment
		(start 288.696654 -25.7302)
		(end 291.355272 -25.7302)
		(width 0.14224)
		(layer "In2.Cu")
		(net "M_A_DQS_DP<14>")
	)
	(segment
		(start 292.665912 -21.0439)
		(end 292.57752 -21.0439)
		(width 0.14224)
		(layer "In2.Cu")
		(net "M_A_DQS_DP<14>")
	)
	(segment
		(start 276.115018 -54.706012)
		(end 276.113494 -54.703218)
		(width 0.0889)
		(layer "In2.Cu")
		(net "M_A_DQS_DP<14>")
	)
	(segment
		(start 282.3464 -27.5844)
		(end 283.49956 -27.5844)
		(width 0.14224)
		(layer "In2.Cu")
		(net "M_A_DQS_DP<14>")
	)
	(segment
		(start 275.836888 -34.093912)
		(end 276.279356 -34.093912)
		(width 0.14224)
		(layer "In2.Cu")
		(net "M_A_DQS_DP<14>")
	)
	(segment
		(start 274.06727 -47.074074)
		(end 274.06727 -47.062898)
		(width 0.0889)
		(layer "In2.Cu")
		(net "M_A_DQS_DP<14>")
	)
	(segment
		(start 274.06727 -47.062898)
		(end 274.06727 -46.82236)
		(width 0.14224)
		(layer "In2.Cu")
		(net "M_A_DQS_DP<14>")
	)
	(segment
		(start 274.10664 -50.155602)
		(end 274.10664 -47.102268)
		(width 0.0889)
		(layer "In2.Cu")
		(net "M_A_DQS_DP<14>")
	)
	(segment
		(start 278.341074 -32.605726)
		(end 278.592026 -32.354774)
		(width 0.14224)
		(layer "In2.Cu")
		(net "M_A_DQS_DP<14>")
	)
	(segment
		(start 276.989794 -33.865566)
		(end 276.748748 -33.62452)
		(width 0.14224)
		(layer "In2.Cu")
		(net "M_A_DQS_DP<14>")
	)
	(segment
		(start 275.670518 -35.403282)
		(end 275.670518 -35.184842)
		(width 0.14224)
		(layer "In2.Cu")
		(net "M_A_DQS_DP<14>")
	)
	(segment
		(start 278.41448 -31.51632)
		(end 278.821896 -31.108904)
		(width 0.14224)
		(layer "In2.Cu")
		(net "M_A_DQS_DP<14>")
	)
	(segment
		(start 274.96008 -35.413188)
		(end 275.201126 -35.654234)
		(width 0.14224)
		(layer "In2.Cu")
		(net "M_A_DQS_DP<14>")
	)
	(segment
		(start 292.912292 -18.057114)
		(end 292.731698 -17.87652)
		(width 0.14224)
		(layer "In2.Cu")
		(net "M_A_DQS_DP<14>")
	)
	(segment
		(start 283.76372 -27.84856)
		(end 285.32328 -27.84856)
		(width 0.14224)
		(layer "In2.Cu")
		(net "M_A_DQS_DP<14>")
	)
	(segment
		(start 292.548564 -20.4216)
		(end 292.729412 -20.4216)
		(width 0.14224)
		(layer "In2.Cu")
		(net "M_A_DQS_DP<14>")
	)
	(segment
		(start 292.912292 -21.933154)
		(end 292.912292 -21.29028)
		(width 0.14224)
		(layer "In2.Cu")
		(net "M_A_DQS_DP<14>")
	)
	(segment
		(start 292.704012 -19.7866)
		(end 292.577012 -19.7866)
		(width 0.14224)
		(layer "In2.Cu")
		(net "M_A_DQS_DP<14>")
	)
	(segment
		(start 276.631654 -56.399938)
		(end 276.629876 -56.396128)
		(width 0.0889)
		(layer "In2.Cu")
		(net "M_A_DQS_DP<14>")
	)
	(segment
		(start 278.122634 -32.605726)
		(end 278.341074 -32.605726)
		(width 0.14224)
		(layer "In2.Cu")
		(net "M_A_DQS_DP<14>")
	)
	(segment
		(start 274.078446 -47.08525)
		(end 274.06727 -47.074074)
		(width 0.0889)
		(layer "In2.Cu")
		(net "M_A_DQS_DP<14>")
	)
	(segment
		(start 292.729412 -20.4216)
		(end 292.912292 -20.23872)
		(width 0.14224)
		(layer "In2.Cu")
		(net "M_A_DQS_DP<14>")
	)
	(segment
		(start 292.421056 -20.549108)
		(end 292.548564 -20.4216)
		(width 0.14224)
		(layer "In2.Cu")
		(net "M_A_DQS_DP<14>")
	)
	(segment
		(start 274.06727 -46.82236)
		(end 273.87296 -46.62805)
		(width 0.14224)
		(layer "In2.Cu")
		(net "M_A_DQS_DP<14>")
	)
	(segment
		(start 292.671246 -22.1742)
		(end 292.912292 -21.933154)
		(width 0.14224)
		(layer "In2.Cu")
		(net "M_A_DQS_DP<14>")
	)
	(segment
		(start 275.670518 -35.184842)
		(end 275.429472 -34.943796)
		(width 0.14224)
		(layer "In2.Cu")
		(net "M_A_DQS_DP<14>")
	)
	(segment
		(start 292.912292 -21.29028)
		(end 292.665912 -21.0439)
		(width 0.14224)
		(layer "In2.Cu")
		(net "M_A_DQS_DP<14>")
	)
	(segment
		(start 276.520402 -34.334958)
		(end 276.738842 -34.334958)
		(width 0.14224)
		(layer "In2.Cu")
		(net "M_A_DQS_DP<14>")
	)
	(segment
		(start 276.119844 -53.723286)
		(end 275.904706 -53.35016)
		(width 0.0889)
		(layer "In2.Cu")
		(net "M_A_DQS_DP<14>")
	)
	(segment
		(start 278.821896 -31.108904)
		(end 279.264364 -31.108904)
		(width 0.14224)
		(layer "In2.Cu")
		(net "M_A_DQS_DP<14>")
	)
	(segment
		(start 276.738842 -34.334958)
		(end 276.989794 -34.084006)
		(width 0.14224)
		(layer "In2.Cu")
		(net "M_A_DQS_DP<14>")
	)
	(segment
		(start 292.912292 -20.23872)
		(end 292.912292 -19.99488)
		(width 0.14224)
		(layer "In2.Cu")
		(net "M_A_DQS_DP<14>")
	)
	(segment
		(start 275.165058 -51.21402)
		(end 274.10664 -50.155602)
		(width 0.0889)
		(layer "In2.Cu")
		(net "M_A_DQS_DP<14>")
	)
	(segment
		(start 277.50262 -32.42818)
		(end 277.945088 -32.42818)
		(width 0.14224)
		(layer "In2.Cu")
		(net "M_A_DQS_DP<14>")
	)
	(segment
		(start 276.279356 -34.093912)
		(end 276.520402 -34.334958)
		(width 0.14224)
		(layer "In2.Cu")
		(net "M_A_DQS_DP<14>")
	)
	(segment
		(start 286.842454 -27.5844)
		(end 288.696654 -25.7302)
		(width 0.14224)
		(layer "In2.Cu")
		(net "M_A_DQS_DP<14>")
	)
	(segment
		(start 279.733756 -30.197044)
		(end 282.3464 -27.5844)
		(width 0.14224)
		(layer "In2.Cu")
		(net "M_A_DQS_DP<14>")
	)
	(segment
		(start 279.44191 -31.28645)
		(end 279.66035 -31.28645)
		(width 0.14224)
		(layer "In2.Cu")
		(net "M_A_DQS_DP<14>")
	)
	(segment
		(start 276.11832 -54.7116)
		(end 276.116034 -54.707536)
		(width 0.0889)
		(layer "In2.Cu")
		(net "M_A_DQS_DP<14>")
	)
	(segment
		(start 278.41448 -31.958788)
		(end 278.41448 -31.51632)
		(width 0.14224)
		(layer "In2.Cu")
		(net "M_A_DQS_DP<14>")
	)
	(segment
		(start 274.10664 -47.102268)
		(end 274.089622 -47.08525)
		(width 0.0889)
		(layer "In2.Cu")
		(net "M_A_DQS_DP<14>")
	)
	(segment
		(start 292.424612 -19.3802)
		(end 292.912292 -18.89252)
		(width 0.14224)
		(layer "In2.Cu")
		(net "M_A_DQS_DP<14>")
	)
	(segment
		(start 275.429472 -34.943796)
		(end 275.429472 -34.501328)
		(width 0.14224)
		(layer "In2.Cu")
		(net "M_A_DQS_DP<14>")
	)
	(arc
		(start 276.119844 -54.123336)
		(mid 276.173377 -53.923328)
		(end 276.119844 -53.723286)
		(width 0.0889)
		(layer "In2.Cu")
		(net "M_A_DQS_DP<14>")
	)
	(arc
		(start 276.629876 -56.396128)
		(mid 276.479058 -55.993192)
		(end 276.284944 -55.609236)
		(width 0.0889)
		(layer "In2.Cu")
		(net "M_A_DQS_DP<14>")
	)
	(arc
		(start 276.24405 -55.30977)
		(mid 276.229652 -55.002012)
		(end 276.119844 -54.71414)
		(width 0.0889)
		(layer "In2.Cu")
		(net "M_A_DQS_DP<14>")
	)
	(arc
		(start 276.113494 -54.703218)
		(mid 276.040696 -54.412455)
		(end 276.119844 -54.123336)
		(width 0.0889)
		(layer "In2.Cu")
		(net "M_A_DQS_DP<14>")
	)
	(arc
		(start 276.284944 -55.609236)
		(mid 276.235129 -55.463511)
		(end 276.24405 -55.30977)
		(width 0.0889)
		(layer "In2.Cu")
		(net "M_A_DQS_DP<14>")
	)
	(segment
		(start 276.846538 -34.698178)
		(end 276.760178 -34.611818)
		(width 0.1651)
		(layer "F.Cu")
		(net "M_A_DQS_DP<13>")
	)
	(segment
		(start 280.641044 -30.236668)
		(end 281.135328 -30.236668)
		(width 0.1651)
		(layer "F.Cu")
		(net "M_A_DQS_DP<13>")
	)
	(segment
		(start 279.554178 -31.990538)
		(end 279.806146 -31.990538)
		(width 0.1651)
		(layer "F.Cu")
		(net "M_A_DQS_DP<13>")
	)
	(segment
		(start 277.306024 -33.571688)
		(end 277.800308 -33.571688)
		(width 0.1651)
		(layer "F.Cu")
		(net "M_A_DQS_DP<13>")
	)
	(segment
		(start 273.769328 -52.437538)
		(end 273.508978 -52.115212)
		(width 0.0889)
		(layer "F.Cu")
		(net "M_A_DQS_DP<13>")
	)
	(segment
		(start 280.181558 -31.363158)
		(end 280.095198 -31.276798)
		(width 0.1651)
		(layer "F.Cu")
		(net "M_A_DQS_DP<13>")
	)
	(segment
		(start 282.663646 -16.476726)
		(end 282.579064 -16.660368)
		(width 0.1651)
		(layer "F.Cu")
		(net "M_A_DQS_DP<13>")
	)
	(segment
		(start 273.201638 -51.527456)
		(end 273.201638 -51.097942)
		(width 0.0889)
		(layer "F.Cu")
		(net "M_A_DQS_DP<13>")
	)
	(segment
		(start 278.514048 -33.282636)
		(end 278.514048 -33.030668)
		(width 0.1651)
		(layer "F.Cu")
		(net "M_A_DQS_DP<13>")
	)
	(segment
		(start 283.099764 -15.423642)
		(end 283.099764 -16.040608)
		(width 0.1651)
		(layer "F.Cu")
		(net "M_A_DQS_DP<13>")
	)
	(segment
		(start 281.9146 -28.403804)
		(end 281.7114 -28.200604)
		(width 0.1651)
		(layer "F.Cu")
		(net "M_A_DQS_DP<13>")
	)
	(segment
		(start 283.100272 -15.423642)
		(end 283.099764 -15.423642)
		(width 0.1651)
		(layer "F.Cu")
		(net "M_A_DQS_DP<13>")
	)
	(segment
		(start 281.135328 -30.236668)
		(end 281.221688 -30.323028)
		(width 0.1651)
		(layer "F.Cu")
		(net "M_A_DQS_DP<13>")
	)
	(segment
		(start 278.427688 -32.944308)
		(end 278.427688 -32.450024)
		(width 0.1651)
		(layer "F.Cu")
		(net "M_A_DQS_DP<13>")
	)
	(segment
		(start 278.138636 -33.658048)
		(end 278.514048 -33.282636)
		(width 0.1651)
		(layer "F.Cu")
		(net "M_A_DQS_DP<13>")
	)
	(segment
		(start 283.099764 -16.040608)
		(end 282.663646 -16.476726)
		(width 0.1651)
		(layer "F.Cu")
		(net "M_A_DQS_DP<13>")
	)
	(segment
		(start 281.473656 -30.323028)
		(end 281.9146 -29.882084)
		(width 0.1651)
		(layer "F.Cu")
		(net "M_A_DQS_DP<13>")
	)
	(segment
		(start 278.514048 -33.030668)
		(end 278.427688 -32.944308)
		(width 0.1651)
		(layer "F.Cu")
		(net "M_A_DQS_DP<13>")
	)
	(segment
		(start 281.9146 -29.21)
		(end 281.9146 -28.403804)
		(width 0.1651)
		(layer "F.Cu")
		(net "M_A_DQS_DP<13>")
	)
	(segment
		(start 278.427688 -32.450024)
		(end 278.973534 -31.904178)
		(width 0.1651)
		(layer "F.Cu")
		(net "M_A_DQS_DP<13>")
	)
	(segment
		(start 273.310604 -49.925478)
		(end 273.197574 -49.812448)
		(width 0.0889)
		(layer "F.Cu")
		(net "M_A_DQS_DP<13>")
	)
	(segment
		(start 282.579064 -17.478502)
		(end 282.660598 -17.702784)
		(width 0.1651)
		(layer "F.Cu")
		(net "M_A_DQS_DP<13>")
	)
	(segment
		(start 275.623528 -35.325558)
		(end 276.471126 -35.325558)
		(width 0.1651)
		(layer "F.Cu")
		(net "M_A_DQS_DP<13>")
	)
	(segment
		(start 282.3845 -26.7589)
		(end 282.3845 -24.168354)
		(width 0.1651)
		(layer "F.Cu")
		(net "M_A_DQS_DP<13>")
	)
	(segment
		(start 280.095198 -31.276798)
		(end 280.095198 -30.782514)
		(width 0.1651)
		(layer "F.Cu")
		(net "M_A_DQS_DP<13>")
	)
	(segment
		(start 279.467818 -31.904178)
		(end 279.554178 -31.990538)
		(width 0.1651)
		(layer "F.Cu")
		(net "M_A_DQS_DP<13>")
	)
	(segment
		(start 273.197574 -49.812448)
		(end 273.197574 -40.381174)
		(width 0.1016)
		(layer "F.Cu")
		(net "M_A_DQS_DP<13>")
	)
	(segment
		(start 277.886668 -33.658048)
		(end 278.138636 -33.658048)
		(width 0.1651)
		(layer "F.Cu")
		(net "M_A_DQS_DP<13>")
	)
	(segment
		(start 282.579064 -16.660368)
		(end 282.579064 -17.478502)
		(width 0.1651)
		(layer "F.Cu")
		(net "M_A_DQS_DP<13>")
	)
	(segment
		(start 282.3845 -24.168354)
		(end 282.5623 -23.990554)
		(width 0.1651)
		(layer "F.Cu")
		(net "M_A_DQS_DP<13>")
	)
	(segment
		(start 273.2659 -51.755802)
		(end 273.266154 -51.755802)
		(width 0.0889)
		(layer "F.Cu")
		(net "M_A_DQS_DP<13>")
	)
	(segment
		(start 276.471126 -35.325558)
		(end 276.846538 -34.950146)
		(width 0.1651)
		(layer "F.Cu")
		(net "M_A_DQS_DP<13>")
	)
	(segment
		(start 277.800308 -33.571688)
		(end 277.886668 -33.658048)
		(width 0.1651)
		(layer "F.Cu")
		(net "M_A_DQS_DP<13>")
	)
	(segment
		(start 273.201638 -51.097942)
		(end 273.310604 -50.90795)
		(width 0.0889)
		(layer "F.Cu")
		(net "M_A_DQS_DP<13>")
	)
	(segment
		(start 282.660598 -17.702784)
		(end 283.04236 -18.084546)
		(width 0.1651)
		(layer "F.Cu")
		(net "M_A_DQS_DP<13>")
	)
	(segment
		(start 278.973534 -31.904178)
		(end 279.467818 -31.904178)
		(width 0.1651)
		(layer "F.Cu")
		(net "M_A_DQS_DP<13>")
	)
	(segment
		(start 281.7114 -28.200604)
		(end 281.7114 -27.432)
		(width 0.1651)
		(layer "F.Cu")
		(net "M_A_DQS_DP<13>")
	)
	(segment
		(start 276.760178 -34.611818)
		(end 276.760178 -34.117534)
		(width 0.1651)
		(layer "F.Cu")
		(net "M_A_DQS_DP<13>")
	)
	(segment
		(start 276.760178 -34.117534)
		(end 277.306024 -33.571688)
		(width 0.1651)
		(layer "F.Cu")
		(net "M_A_DQS_DP<13>")
	)
	(segment
		(start 281.9146 -29.882084)
		(end 281.9146 -29.21)
		(width 0.1651)
		(layer "F.Cu")
		(net "M_A_DQS_DP<13>")
	)
	(segment
		(start 279.806146 -31.990538)
		(end 280.181558 -31.615126)
		(width 0.1651)
		(layer "F.Cu")
		(net "M_A_DQS_DP<13>")
	)
	(segment
		(start 273.197574 -40.381174)
		(end 273.228054 -40.350694)
		(width 0.1016)
		(layer "F.Cu")
		(net "M_A_DQS_DP<13>")
	)
	(segment
		(start 280.095198 -30.782514)
		(end 280.641044 -30.236668)
		(width 0.1651)
		(layer "F.Cu")
		(net "M_A_DQS_DP<13>")
	)
	(segment
		(start 273.228054 -40.350694)
		(end 273.228054 -37.721032)
		(width 0.1651)
		(layer "F.Cu")
		(net "M_A_DQS_DP<13>")
	)
	(segment
		(start 280.181558 -31.615126)
		(end 280.181558 -31.363158)
		(width 0.1651)
		(layer "F.Cu")
		(net "M_A_DQS_DP<13>")
	)
	(segment
		(start 281.221688 -30.323028)
		(end 281.473656 -30.323028)
		(width 0.1651)
		(layer "F.Cu")
		(net "M_A_DQS_DP<13>")
	)
	(segment
		(start 282.5623 -23.990554)
		(end 282.5623 -22.65426)
		(width 0.1651)
		(layer "F.Cu")
		(net "M_A_DQS_DP<13>")
	)
	(segment
		(start 276.846538 -34.950146)
		(end 276.846538 -34.698178)
		(width 0.1651)
		(layer "F.Cu")
		(net "M_A_DQS_DP<13>")
	)
	(segment
		(start 273.228054 -37.721032)
		(end 275.623528 -35.325558)
		(width 0.1651)
		(layer "F.Cu")
		(net "M_A_DQS_DP<13>")
	)
	(segment
		(start 281.7114 -27.432)
		(end 282.3845 -26.7589)
		(width 0.1651)
		(layer "F.Cu")
		(net "M_A_DQS_DP<13>")
	)
	(segment
		(start 273.310604 -50.90795)
		(end 273.310604 -49.925478)
		(width 0.0889)
		(layer "F.Cu")
		(net "M_A_DQS_DP<13>")
	)
	(segment
		(start 282.5623 -22.65426)
		(end 283.04236 -22.1742)
		(width 0.1651)
		(layer "F.Cu")
		(net "M_A_DQS_DP<13>")
	)
	(via
		(at 281.9146 -29.21)
		(size 0.508)
		(drill 0.254)
		(layers "F.Cu" "B.Cu")
		(net "M_A_DQS_DP<13>")
	)
	(via
		(at 283.04236 -22.1742)
		(size 0.508)
		(drill 0.254)
		(layers "F.Cu" "B.Cu")
		(net "M_A_DQS_DP<13>")
	)
	(via
		(at 283.04236 -18.084546)
		(size 0.508)
		(drill 0.254)
		(layers "F.Cu" "B.Cu")
		(net "M_A_DQS_DP<13>")
	)
	(arc
		(start 273.266154 -51.755802)
		(mid 273.218023 -51.646108)
		(end 273.201638 -51.527456)
		(width 0.0889)
		(layer "F.Cu")
		(net "M_A_DQS_DP<13>")
	)
	(arc
		(start 273.508978 -52.115212)
		(mid 273.383508 -51.938165)
		(end 273.2659 -51.755802)
		(width 0.0889)
		(layer "F.Cu")
		(net "M_A_DQS_DP<13>")
	)
	(segment
		(start 283.100272 -24.824182)
		(end 283.099764 -24.824182)
		(width 0.1651)
		(layer "B.Cu")
		(net "M_A_DQS_DP<13>")
	)
	(segment
		(start 282.566364 -22.722332)
		(end 282.65374 -22.56282)
		(width 0.1651)
		(layer "B.Cu")
		(net "M_A_DQS_DP<13>")
	)
	(segment
		(start 282.65374 -22.56282)
		(end 283.04236 -22.1742)
		(width 0.1651)
		(layer "B.Cu")
		(net "M_A_DQS_DP<13>")
	)
	(segment
		(start 283.099764 -24.206454)
		(end 282.64358 -23.75027)
		(width 0.1651)
		(layer "B.Cu")
		(net "M_A_DQS_DP<13>")
	)
	(segment
		(start 282.64358 -23.75027)
		(end 282.566364 -23.617936)
		(width 0.1651)
		(layer "B.Cu")
		(net "M_A_DQS_DP<13>")
	)
	(segment
		(start 283.099764 -24.824182)
		(end 283.099764 -24.206454)
		(width 0.1651)
		(layer "B.Cu")
		(net "M_A_DQS_DP<13>")
	)
	(segment
		(start 282.566364 -23.617936)
		(end 282.566364 -22.722332)
		(width 0.1651)
		(layer "B.Cu")
		(net "M_A_DQS_DP<13>")
	)
	(segment
		(start 283.353764 -19.7866)
		(end 283.226764 -19.7866)
		(width 0.14224)
		(layer "In2.Cu")
		(net "M_A_DQS_DP<13>")
	)
	(segment
		(start 283.226764 -19.7866)
		(end 283.074364 -19.6342)
		(width 0.14224)
		(layer "In2.Cu")
		(net "M_A_DQS_DP<13>")
	)
	(segment
		(start 283.070808 -20.549108)
		(end 283.198316 -20.4216)
		(width 0.14224)
		(layer "In2.Cu")
		(net "M_A_DQS_DP<13>")
	)
	(segment
		(start 283.562044 -18.89252)
		(end 283.562044 -18.057114)
		(width 0.14224)
		(layer "In2.Cu")
		(net "M_A_DQS_DP<13>")
	)
	(segment
		(start 283.379164 -20.4216)
		(end 283.562044 -20.23872)
		(width 0.14224)
		(layer "In2.Cu")
		(net "M_A_DQS_DP<13>")
	)
	(segment
		(start 283.562044 -19.99488)
		(end 283.353764 -19.7866)
		(width 0.14224)
		(layer "In2.Cu")
		(net "M_A_DQS_DP<13>")
	)
	(segment
		(start 283.198316 -20.4216)
		(end 283.379164 -20.4216)
		(width 0.14224)
		(layer "In2.Cu")
		(net "M_A_DQS_DP<13>")
	)
	(segment
		(start 283.321506 -22.1742)
		(end 283.562044 -21.933662)
		(width 0.14224)
		(layer "In2.Cu")
		(net "M_A_DQS_DP<13>")
	)
	(segment
		(start 283.562044 -21.29028)
		(end 283.315664 -21.0439)
		(width 0.14224)
		(layer "In2.Cu")
		(net "M_A_DQS_DP<13>")
	)
	(segment
		(start 283.562044 -18.057114)
		(end 283.38145 -17.87652)
		(width 0.14224)
		(layer "In2.Cu")
		(net "M_A_DQS_DP<13>")
	)
	(segment
		(start 283.070808 -20.887436)
		(end 283.070808 -20.549108)
		(width 0.14224)
		(layer "In2.Cu")
		(net "M_A_DQS_DP<13>")
	)
	(segment
		(start 283.562044 -21.933662)
		(end 283.562044 -21.29028)
		(width 0.14224)
		(layer "In2.Cu")
		(net "M_A_DQS_DP<13>")
	)
	(segment
		(start 283.250386 -17.87652)
		(end 283.04236 -18.084546)
		(width 0.14224)
		(layer "In2.Cu")
		(net "M_A_DQS_DP<13>")
	)
	(segment
		(start 283.04236 -22.1742)
		(end 283.321506 -22.1742)
		(width 0.14224)
		(layer "In2.Cu")
		(net "M_A_DQS_DP<13>")
	)
	(segment
		(start 283.562044 -20.23872)
		(end 283.562044 -19.99488)
		(width 0.14224)
		(layer "In2.Cu")
		(net "M_A_DQS_DP<13>")
	)
	(segment
		(start 283.315664 -21.0439)
		(end 283.227272 -21.0439)
		(width 0.14224)
		(layer "In2.Cu")
		(net "M_A_DQS_DP<13>")
	)
	(segment
		(start 283.38145 -17.87652)
		(end 283.250386 -17.87652)
		(width 0.14224)
		(layer "In2.Cu")
		(net "M_A_DQS_DP<13>")
	)
	(segment
		(start 283.074364 -19.3802)
		(end 283.562044 -18.89252)
		(width 0.14224)
		(layer "In2.Cu")
		(net "M_A_DQS_DP<13>")
	)
	(segment
		(start 283.074364 -19.6342)
		(end 283.074364 -19.3802)
		(width 0.14224)
		(layer "In2.Cu")
		(net "M_A_DQS_DP<13>")
	)
	(segment
		(start 283.227272 -21.0439)
		(end 283.070808 -20.887436)
		(width 0.14224)
		(layer "In2.Cu")
		(net "M_A_DQS_DP<13>")
	)
	(segment
		(start 227.410772 -17.702784)
		(end 227.792534 -18.084546)
		(width 0.1651)
		(layer "F.Cu")
		(net "M_A_DQS_DP<12>")
	)
	(segment
		(start 227.329238 -17.478502)
		(end 227.410772 -17.702784)
		(width 0.1651)
		(layer "F.Cu")
		(net "M_A_DQS_DP<12>")
	)
	(segment
		(start 227.41382 -16.476472)
		(end 227.329238 -16.660368)
		(width 0.1651)
		(layer "F.Cu")
		(net "M_A_DQS_DP<12>")
	)
	(segment
		(start 227.850446 -15.423642)
		(end 227.849938 -15.423642)
		(width 0.1651)
		(layer "F.Cu")
		(net "M_A_DQS_DP<12>")
	)
	(segment
		(start 242.193318 -55.094886)
		(end 241.621818 -55.094886)
		(width 0.1016)
		(layer "F.Cu")
		(net "M_A_DQS_DP<12>")
	)
	(segment
		(start 227.849938 -16.040354)
		(end 227.41382 -16.476472)
		(width 0.1651)
		(layer "F.Cu")
		(net "M_A_DQS_DP<12>")
	)
	(segment
		(start 227.329238 -16.660368)
		(end 227.329238 -17.478502)
		(width 0.1651)
		(layer "F.Cu")
		(net "M_A_DQS_DP<12>")
	)
	(segment
		(start 227.849938 -15.423642)
		(end 227.849938 -16.040354)
		(width 0.1651)
		(layer "F.Cu")
		(net "M_A_DQS_DP<12>")
	)
	(via
		(at 227.792534 -22.1742)
		(size 0.508)
		(drill 0.254)
		(layers "F.Cu" "B.Cu")
		(net "M_A_DQS_DP<12>")
	)
	(via
		(at 227.792534 -18.084546)
		(size 0.508)
		(drill 0.254)
		(layers "F.Cu" "B.Cu")
		(net "M_A_DQS_DP<12>")
	)
	(via
		(at 241.621818 -55.094886)
		(size 0.508)
		(drill 0.254)
		(layers "F.Cu" "B.Cu")
		(net "M_A_DQS_DP<12>")
	)
	(segment
		(start 227.849938 -24.206454)
		(end 227.393754 -23.75027)
		(width 0.1651)
		(layer "B.Cu")
		(net "M_A_DQS_DP<12>")
	)
	(segment
		(start 227.849938 -24.824182)
		(end 227.849938 -24.206454)
		(width 0.1651)
		(layer "B.Cu")
		(net "M_A_DQS_DP<12>")
	)
	(segment
		(start 227.403914 -22.56282)
		(end 227.792534 -22.1742)
		(width 0.1651)
		(layer "B.Cu")
		(net "M_A_DQS_DP<12>")
	)
	(segment
		(start 227.316538 -23.617936)
		(end 227.316538 -22.722332)
		(width 0.1651)
		(layer "B.Cu")
		(net "M_A_DQS_DP<12>")
	)
	(segment
		(start 227.316538 -22.722332)
		(end 227.403914 -22.56282)
		(width 0.1651)
		(layer "B.Cu")
		(net "M_A_DQS_DP<12>")
	)
	(segment
		(start 227.850446 -24.824182)
		(end 227.849938 -24.824182)
		(width 0.1651)
		(layer "B.Cu")
		(net "M_A_DQS_DP<12>")
	)
	(segment
		(start 227.393754 -23.75027)
		(end 227.316538 -23.617936)
		(width 0.1651)
		(layer "B.Cu")
		(net "M_A_DQS_DP<12>")
	)
	(segment
		(start 228.312218 -18.057114)
		(end 228.131624 -17.87652)
		(width 0.14224)
		(layer "In2.Cu")
		(net "M_A_DQS_DP<12>")
	)
	(segment
		(start 236.171994 -49.481994)
		(end 236.1184 -49.4284)
		(width 0.1016)
		(layer "In2.Cu")
		(net "M_A_DQS_DP<12>")
	)
	(segment
		(start 227.939854 -36.740592)
		(end 228.17836 -36.740592)
		(width 0.14224)
		(layer "In2.Cu")
		(net "M_A_DQS_DP<12>")
	)
	(segment
		(start 228.129338 -20.4216)
		(end 228.312218 -20.23872)
		(width 0.14224)
		(layer "In2.Cu")
		(net "M_A_DQS_DP<12>")
	)
	(segment
		(start 227.976938 -19.7866)
		(end 227.824538 -19.6342)
		(width 0.14224)
		(layer "In2.Cu")
		(net "M_A_DQS_DP<12>")
	)
	(segment
		(start 228.293676 -33.79851)
		(end 228.293676 -25.694132)
		(width 0.14224)
		(layer "In2.Cu")
		(net "M_A_DQS_DP<12>")
	)
	(segment
		(start 228.374448 -33.879282)
		(end 228.293676 -33.79851)
		(width 0.14224)
		(layer "In2.Cu")
		(net "M_A_DQS_DP<12>")
	)
	(segment
		(start 227.977446 -21.0439)
		(end 227.820982 -20.887436)
		(width 0.14224)
		(layer "In2.Cu")
		(net "M_A_DQS_DP<12>")
	)
	(segment
		(start 227.820982 -20.887436)
		(end 227.820982 -20.549108)
		(width 0.14224)
		(layer "In2.Cu")
		(net "M_A_DQS_DP<12>")
	)
	(segment
		(start 228.103938 -19.7866)
		(end 227.976938 -19.7866)
		(width 0.14224)
		(layer "In2.Cu")
		(net "M_A_DQS_DP<12>")
	)
	(segment
		(start 227.561648 -37.977826)
		(end 227.561648 -37.118798)
		(width 0.14224)
		(layer "In2.Cu")
		(net "M_A_DQS_DP<12>")
	)
	(segment
		(start 227.939854 -38.356032)
		(end 227.561648 -37.977826)
		(width 0.14224)
		(layer "In2.Cu")
		(net "M_A_DQS_DP<12>")
	)
	(segment
		(start 228.628448 -41.269158)
		(end 228.407722 -41.048432)
		(width 0.14224)
		(layer "In2.Cu")
		(net "M_A_DQS_DP<12>")
	)
	(segment
		(start 239.064292 -52.21859)
		(end 239.024668 -52.21859)
		(width 0.0889)
		(layer "In2.Cu")
		(net "M_A_DQS_DP<12>")
	)
	(segment
		(start 241.260376 -53.669438)
		(end 241.110008 -53.409088)
		(width 0.0889)
		(layer "In2.Cu")
		(net "M_A_DQS_DP<12>")
	)
	(segment
		(start 236.199426 -49.481994)
		(end 236.171994 -49.481994)
		(width 0.0889)
		(layer "In2.Cu")
		(net "M_A_DQS_DP<12>")
	)
	(segment
		(start 236.737144 -50.019712)
		(end 236.199426 -49.481994)
		(width 0.0889)
		(layer "In2.Cu")
		(net "M_A_DQS_DP<12>")
	)
	(segment
		(start 228.312218 -19.99488)
		(end 228.103938 -19.7866)
		(width 0.14224)
		(layer "In2.Cu")
		(net "M_A_DQS_DP<12>")
	)
	(segment
		(start 228.40696 -38.356032)
		(end 227.939854 -38.356032)
		(width 0.14224)
		(layer "In2.Cu")
		(net "M_A_DQS_DP<12>")
	)
	(segment
		(start 227.321618 -24.722074)
		(end 227.321618 -22.645116)
		(width 0.14224)
		(layer "In2.Cu")
		(net "M_A_DQS_DP<12>")
	)
	(segment
		(start 241.292126 -54.333648)
		(end 241.275108 -54.304438)
		(width 0.0889)
		(layer "In2.Cu")
		(net "M_A_DQS_DP<12>")
	)
	(segment
		(start 228.628448 -41.938448)
		(end 228.628448 -41.269158)
		(width 0.14224)
		(layer "In2.Cu")
		(net "M_A_DQS_DP<12>")
	)
	(segment
		(start 239.922812 -52.71389)
		(end 239.886998 -52.71389)
		(width 0.0889)
		(layer "In2.Cu")
		(net "M_A_DQS_DP<12>")
	)
	(segment
		(start 227.561648 -40.670226)
		(end 227.561648 -39.811198)
		(width 0.14224)
		(layer "In2.Cu")
		(net "M_A_DQS_DP<12>")
	)
	(segment
		(start 228.40696 -39.432992)
		(end 228.628448 -39.211504)
		(width 0.14224)
		(layer "In2.Cu")
		(net "M_A_DQS_DP<12>")
	)
	(segment
		(start 228.312218 -18.89252)
		(end 228.312218 -18.057114)
		(width 0.14224)
		(layer "In2.Cu")
		(net "M_A_DQS_DP<12>")
	)
	(segment
		(start 227.94849 -20.4216)
		(end 228.129338 -20.4216)
		(width 0.14224)
		(layer "In2.Cu")
		(net "M_A_DQS_DP<12>")
	)
	(segment
		(start 227.561648 -37.118798)
		(end 227.939854 -36.740592)
		(width 0.14224)
		(layer "In2.Cu")
		(net "M_A_DQS_DP<12>")
	)
	(segment
		(start 228.312218 -21.933662)
		(end 228.312218 -21.29028)
		(width 0.14224)
		(layer "In2.Cu")
		(net "M_A_DQS_DP<12>")
	)
	(segment
		(start 228.07168 -22.1742)
		(end 228.312218 -21.933662)
		(width 0.14224)
		(layer "In2.Cu")
		(net "M_A_DQS_DP<12>")
	)
	(segment
		(start 236.1184 -49.4284)
		(end 228.628448 -41.938448)
		(width 0.14224)
		(layer "In2.Cu")
		(net "M_A_DQS_DP<12>")
	)
	(segment
		(start 237.344204 -51.22799)
		(end 237.315502 -51.22799)
		(width 0.0889)
		(layer "In2.Cu")
		(net "M_A_DQS_DP<12>")
	)
	(segment
		(start 228.407722 -41.048432)
		(end 227.939854 -41.048432)
		(width 0.14224)
		(layer "In2.Cu")
		(net "M_A_DQS_DP<12>")
	)
	(segment
		(start 228.628448 -39.211504)
		(end 228.628448 -38.57752)
		(width 0.14224)
		(layer "In2.Cu")
		(net "M_A_DQS_DP<12>")
	)
	(segment
		(start 227.824538 -19.6342)
		(end 227.824538 -19.3802)
		(width 0.14224)
		(layer "In2.Cu")
		(net "M_A_DQS_DP<12>")
	)
	(segment
		(start 228.065838 -21.0439)
		(end 227.977446 -21.0439)
		(width 0.14224)
		(layer "In2.Cu")
		(net "M_A_DQS_DP<12>")
	)
	(segment
		(start 236.737144 -50.793142)
		(end 236.737144 -50.019712)
		(width 0.0889)
		(layer "In2.Cu")
		(net "M_A_DQS_DP<12>")
	)
	(segment
		(start 227.561648 -39.811198)
		(end 227.939854 -39.432992)
		(width 0.14224)
		(layer "In2.Cu")
		(net "M_A_DQS_DP<12>")
	)
	(segment
		(start 228.131624 -17.87652)
		(end 228.00056 -17.87652)
		(width 0.14224)
		(layer "In2.Cu")
		(net "M_A_DQS_DP<12>")
	)
	(segment
		(start 227.824538 -19.3802)
		(end 228.312218 -18.89252)
		(width 0.14224)
		(layer "In2.Cu")
		(net "M_A_DQS_DP<12>")
	)
	(segment
		(start 238.198914 -51.72329)
		(end 238.174784 -51.72329)
		(width 0.0889)
		(layer "In2.Cu")
		(net "M_A_DQS_DP<12>")
	)
	(segment
		(start 236.817154 -50.932588)
		(end 236.737144 -50.793142)
		(width 0.0889)
		(layer "In2.Cu")
		(net "M_A_DQS_DP<12>")
	)
	(segment
		(start 227.820982 -20.549108)
		(end 227.94849 -20.4216)
		(width 0.14224)
		(layer "In2.Cu")
		(net "M_A_DQS_DP<12>")
	)
	(segment
		(start 228.628448 -38.57752)
		(end 228.40696 -38.356032)
		(width 0.14224)
		(layer "In2.Cu")
		(net "M_A_DQS_DP<12>")
	)
	(segment
		(start 228.17836 -36.740592)
		(end 228.374448 -36.544504)
		(width 0.14224)
		(layer "In2.Cu")
		(net "M_A_DQS_DP<12>")
	)
	(segment
		(start 227.939854 -41.048432)
		(end 227.561648 -40.670226)
		(width 0.14224)
		(layer "In2.Cu")
		(net "M_A_DQS_DP<12>")
	)
	(segment
		(start 227.321618 -22.645116)
		(end 227.792534 -22.1742)
		(width 0.14224)
		(layer "In2.Cu")
		(net "M_A_DQS_DP<12>")
	)
	(segment
		(start 227.939854 -39.432992)
		(end 228.40696 -39.432992)
		(width 0.14224)
		(layer "In2.Cu")
		(net "M_A_DQS_DP<12>")
	)
	(segment
		(start 241.621818 -55.094886)
		(end 241.292126 -54.333648)
		(width 0.0889)
		(layer "In2.Cu")
		(net "M_A_DQS_DP<12>")
	)
	(segment
		(start 240.778284 -53.20919)
		(end 240.750344 -53.20919)
		(width 0.0889)
		(layer "In2.Cu")
		(net "M_A_DQS_DP<12>")
	)
	(segment
		(start 227.792534 -22.1742)
		(end 228.07168 -22.1742)
		(width 0.14224)
		(layer "In2.Cu")
		(net "M_A_DQS_DP<12>")
	)
	(segment
		(start 228.374448 -36.544504)
		(end 228.374448 -33.879282)
		(width 0.14224)
		(layer "In2.Cu")
		(net "M_A_DQS_DP<12>")
	)
	(segment
		(start 228.312218 -20.23872)
		(end 228.312218 -19.99488)
		(width 0.14224)
		(layer "In2.Cu")
		(net "M_A_DQS_DP<12>")
	)
	(segment
		(start 228.00056 -17.87652)
		(end 227.792534 -18.084546)
		(width 0.14224)
		(layer "In2.Cu")
		(net "M_A_DQS_DP<12>")
	)
	(segment
		(start 228.312218 -21.29028)
		(end 228.065838 -21.0439)
		(width 0.14224)
		(layer "In2.Cu")
		(net "M_A_DQS_DP<12>")
	)
	(segment
		(start 228.293676 -25.694132)
		(end 227.321618 -24.722074)
		(width 0.14224)
		(layer "In2.Cu")
		(net "M_A_DQS_DP<12>")
	)
	(arc
		(start 240.251488 -52.913788)
		(mid 240.112744 -52.771755)
		(end 239.922812 -52.71389)
		(width 0.0889)
		(layer "In2.Cu")
		(net "M_A_DQS_DP<12>")
	)
	(arc
		(start 237.675928 -51.427888)
		(mid 237.535849 -51.285152)
		(end 237.344204 -51.22799)
		(width 0.0889)
		(layer "In2.Cu")
		(net "M_A_DQS_DP<12>")
	)
	(arc
		(start 241.110008 -53.409088)
		(mid 240.969929 -53.266352)
		(end 240.778284 -53.20919)
		(width 0.0889)
		(layer "In2.Cu")
		(net "M_A_DQS_DP<12>")
	)
	(arc
		(start 239.024668 -52.21859)
		(mid 238.741451 -52.134309)
		(end 238.534448 -51.923442)
		(width 0.0889)
		(layer "In2.Cu")
		(net "M_A_DQS_DP<12>")
	)
	(arc
		(start 237.315502 -51.22799)
		(mid 237.027673 -51.145529)
		(end 236.817154 -50.932588)
		(width 0.0889)
		(layer "In2.Cu")
		(net "M_A_DQS_DP<12>")
	)
	(arc
		(start 241.268504 -53.68544)
		(mid 241.26462 -53.677347)
		(end 241.260376 -53.669438)
		(width 0.0889)
		(layer "In2.Cu")
		(net "M_A_DQS_DP<12>")
	)
	(arc
		(start 238.534448 -51.923442)
		(mid 238.392765 -51.779638)
		(end 238.198914 -51.72329)
		(width 0.0889)
		(layer "In2.Cu")
		(net "M_A_DQS_DP<12>")
	)
	(arc
		(start 238.174784 -51.72329)
		(mid 237.886639 -51.640971)
		(end 237.675928 -51.427888)
		(width 0.0889)
		(layer "In2.Cu")
		(net "M_A_DQS_DP<12>")
	)
	(arc
		(start 239.886998 -52.71389)
		(mid 239.601574 -52.630423)
		(end 239.392968 -52.418488)
		(width 0.0889)
		(layer "In2.Cu")
		(net "M_A_DQS_DP<12>")
	)
	(arc
		(start 241.275108 -53.904642)
		(mid 241.29369 -53.794387)
		(end 241.268504 -53.68544)
		(width 0.0889)
		(layer "In2.Cu")
		(net "M_A_DQS_DP<12>")
	)
	(arc
		(start 239.392968 -52.418488)
		(mid 239.254224 -52.276455)
		(end 239.064292 -52.21859)
		(width 0.0889)
		(layer "In2.Cu")
		(net "M_A_DQS_DP<12>")
	)
	(arc
		(start 241.275108 -54.304438)
		(mid 241.221609 -54.10454)
		(end 241.275108 -53.904642)
		(width 0.0889)
		(layer "In2.Cu")
		(net "M_A_DQS_DP<12>")
	)
	(arc
		(start 240.750344 -53.20919)
		(mid 240.462199 -53.126871)
		(end 240.251488 -52.913788)
		(width 0.0889)
		(layer "In2.Cu")
		(net "M_A_DQS_DP<12>")
	)
	(segment
		(start 218.500452 -15.423642)
		(end 218.499944 -15.423642)
		(width 0.1651)
		(layer "F.Cu")
		(net "M_A_DQS_DP<11>")
	)
	(segment
		(start 218.499944 -15.423642)
		(end 218.499944 -16.040354)
		(width 0.1651)
		(layer "F.Cu")
		(net "M_A_DQS_DP<11>")
	)
	(segment
		(start 218.060778 -17.702784)
		(end 218.44254 -18.084546)
		(width 0.1651)
		(layer "F.Cu")
		(net "M_A_DQS_DP<11>")
	)
	(segment
		(start 218.063826 -16.476472)
		(end 217.979244 -16.660368)
		(width 0.1651)
		(layer "F.Cu")
		(net "M_A_DQS_DP<11>")
	)
	(segment
		(start 237.042198 -57.076086)
		(end 236.470698 -57.076086)
		(width 0.1016)
		(layer "F.Cu")
		(net "M_A_DQS_DP<11>")
	)
	(segment
		(start 217.979244 -16.660368)
		(end 217.979244 -17.478502)
		(width 0.1651)
		(layer "F.Cu")
		(net "M_A_DQS_DP<11>")
	)
	(segment
		(start 217.979244 -17.478502)
		(end 218.060778 -17.702784)
		(width 0.1651)
		(layer "F.Cu")
		(net "M_A_DQS_DP<11>")
	)
	(segment
		(start 218.499944 -16.040354)
		(end 218.063826 -16.476472)
		(width 0.1651)
		(layer "F.Cu")
		(net "M_A_DQS_DP<11>")
	)
	(via
		(at 236.470698 -57.076086)
		(size 0.508)
		(drill 0.254)
		(layers "F.Cu" "B.Cu")
		(net "M_A_DQS_DP<11>")
	)
	(via
		(at 218.44254 -22.1742)
		(size 0.508)
		(drill 0.254)
		(layers "F.Cu" "B.Cu")
		(net "M_A_DQS_DP<11>")
	)
	(via
		(at 218.44254 -18.084546)
		(size 0.508)
		(drill 0.254)
		(layers "F.Cu" "B.Cu")
		(net "M_A_DQS_DP<11>")
	)
	(segment
		(start 217.966544 -23.617936)
		(end 217.966544 -22.722332)
		(width 0.1651)
		(layer "B.Cu")
		(net "M_A_DQS_DP<11>")
	)
	(segment
		(start 218.499944 -24.206454)
		(end 218.04376 -23.75027)
		(width 0.1651)
		(layer "B.Cu")
		(net "M_A_DQS_DP<11>")
	)
	(segment
		(start 218.04376 -23.75027)
		(end 217.966544 -23.617936)
		(width 0.1651)
		(layer "B.Cu")
		(net "M_A_DQS_DP<11>")
	)
	(segment
		(start 218.500452 -24.824182)
		(end 218.499944 -24.824182)
		(width 0.1651)
		(layer "B.Cu")
		(net "M_A_DQS_DP<11>")
	)
	(segment
		(start 217.966544 -22.722332)
		(end 218.05392 -22.56282)
		(width 0.1651)
		(layer "B.Cu")
		(net "M_A_DQS_DP<11>")
	)
	(segment
		(start 218.499944 -24.824182)
		(end 218.499944 -24.206454)
		(width 0.1651)
		(layer "B.Cu")
		(net "M_A_DQS_DP<11>")
	)
	(segment
		(start 218.05392 -22.56282)
		(end 218.44254 -22.1742)
		(width 0.1651)
		(layer "B.Cu")
		(net "M_A_DQS_DP<11>")
	)
	(segment
		(start 218.598496 -20.4216)
		(end 218.779344 -20.4216)
		(width 0.14224)
		(layer "In2.Cu")
		(net "M_A_DQS_DP<11>")
	)
	(segment
		(start 234.764072 -57.666636)
		(end 233.702352 -57.666636)
		(width 0.0889)
		(layer "In2.Cu")
		(net "M_A_DQS_DP<11>")
	)
	(segment
		(start 218.721686 -22.1742)
		(end 218.962224 -21.933662)
		(width 0.14224)
		(layer "In2.Cu")
		(net "M_A_DQS_DP<11>")
	)
	(segment
		(start 218.626944 -19.7866)
		(end 218.474544 -19.6342)
		(width 0.14224)
		(layer "In2.Cu")
		(net "M_A_DQS_DP<11>")
	)
	(segment
		(start 217.541348 -39.28999)
		(end 218.140534 -39.28999)
		(width 0.14224)
		(layer "In2.Cu")
		(net "M_A_DQS_DP<11>")
	)
	(segment
		(start 217.20556 -40.526462)
		(end 217.20556 -39.625778)
		(width 0.14224)
		(layer "In2.Cu")
		(net "M_A_DQS_DP<11>")
	)
	(segment
		(start 218.962224 -21.933662)
		(end 218.962224 -21.29028)
		(width 0.14224)
		(layer "In2.Cu")
		(net "M_A_DQS_DP<11>")
	)
	(segment
		(start 217.705686 -38.21303)
		(end 217.350848 -37.858192)
		(width 0.14224)
		(layer "In2.Cu")
		(net "M_A_DQS_DP<11>")
	)
	(segment
		(start 218.962224 -18.057114)
		(end 218.78163 -17.87652)
		(width 0.14224)
		(layer "In2.Cu")
		(net "M_A_DQS_DP<11>")
	)
	(segment
		(start 218.753944 -19.7866)
		(end 218.626944 -19.7866)
		(width 0.14224)
		(layer "In2.Cu")
		(net "M_A_DQS_DP<11>")
	)
	(segment
		(start 218.470988 -20.549108)
		(end 218.598496 -20.4216)
		(width 0.14224)
		(layer "In2.Cu")
		(net "M_A_DQS_DP<11>")
	)
	(segment
		(start 218.140534 -39.28999)
		(end 218.36126 -39.069264)
		(width 0.14224)
		(layer "In2.Cu")
		(net "M_A_DQS_DP<11>")
	)
	(segment
		(start 217.941144 -24.061166)
		(end 217.941144 -22.675596)
		(width 0.14224)
		(layer "In2.Cu")
		(net "M_A_DQS_DP<11>")
	)
	(segment
		(start 218.779344 -20.4216)
		(end 218.962224 -20.23872)
		(width 0.14224)
		(layer "In2.Cu")
		(net "M_A_DQS_DP<11>")
	)
	(segment
		(start 217.96756 -40.90543)
		(end 217.584528 -40.90543)
		(width 0.14224)
		(layer "In2.Cu")
		(net "M_A_DQS_DP<11>")
	)
	(segment
		(start 230.435404 -55.82285)
		(end 218.189048 -43.576494)
		(width 0.14224)
		(layer "In2.Cu")
		(net "M_A_DQS_DP<11>")
	)
	(segment
		(start 218.44254 -22.1742)
		(end 218.721686 -22.1742)
		(width 0.14224)
		(layer "In2.Cu")
		(net "M_A_DQS_DP<11>")
	)
	(segment
		(start 236.5121 -57.420764)
		(end 236.457744 -57.476136)
		(width 0.0889)
		(layer "In2.Cu")
		(net "M_A_DQS_DP<11>")
	)
	(segment
		(start 217.58148 -42.13352)
		(end 218.189048 -41.525952)
		(width 0.14224)
		(layer "In2.Cu")
		(net "M_A_DQS_DP<11>")
	)
	(segment
		(start 217.706448 -24.295862)
		(end 217.941144 -24.061166)
		(width 0.14224)
		(layer "In2.Cu")
		(net "M_A_DQS_DP<11>")
	)
	(segment
		(start 236.470698 -57.076086)
		(end 236.5121 -57.117488)
		(width 0.0889)
		(layer "In2.Cu")
		(net "M_A_DQS_DP<11>")
	)
	(segment
		(start 217.58148 -42.57548)
		(end 217.58148 -42.13352)
		(width 0.14224)
		(layer "In2.Cu")
		(net "M_A_DQS_DP<11>")
	)
	(segment
		(start 233.702352 -57.666636)
		(end 233.207306 -57.17159)
		(width 0.0889)
		(layer "In2.Cu")
		(net "M_A_DQS_DP<11>")
	)
	(segment
		(start 218.189048 -43.576494)
		(end 218.189048 -43.183048)
		(width 0.14224)
		(layer "In2.Cu")
		(net "M_A_DQS_DP<11>")
	)
	(segment
		(start 217.350848 -37.858192)
		(end 217.350848 -33.212278)
		(width 0.14224)
		(layer "In2.Cu")
		(net "M_A_DQS_DP<11>")
	)
	(segment
		(start 218.627452 -21.0439)
		(end 218.470988 -20.887436)
		(width 0.14224)
		(layer "In2.Cu")
		(net "M_A_DQS_DP<11>")
	)
	(segment
		(start 218.36126 -38.415976)
		(end 218.158314 -38.21303)
		(width 0.14224)
		(layer "In2.Cu")
		(net "M_A_DQS_DP<11>")
	)
	(segment
		(start 231.838754 -57.17159)
		(end 230.506524 -55.838598)
		(width 0.0889)
		(layer "In2.Cu")
		(net "M_A_DQS_DP<11>")
	)
	(segment
		(start 218.962224 -21.29028)
		(end 218.715844 -21.0439)
		(width 0.14224)
		(layer "In2.Cu")
		(net "M_A_DQS_DP<11>")
	)
	(segment
		(start 218.470988 -20.887436)
		(end 218.470988 -20.549108)
		(width 0.14224)
		(layer "In2.Cu")
		(net "M_A_DQS_DP<11>")
	)
	(segment
		(start 218.36126 -39.069264)
		(end 218.36126 -38.415976)
		(width 0.14224)
		(layer "In2.Cu")
		(net "M_A_DQS_DP<11>")
	)
	(segment
		(start 230.451152 -55.838598)
		(end 230.435404 -55.82285)
		(width 0.0889)
		(layer "In2.Cu")
		(net "M_A_DQS_DP<11>")
	)
	(segment
		(start 236.5121 -57.117488)
		(end 236.5121 -57.420764)
		(width 0.0889)
		(layer "In2.Cu")
		(net "M_A_DQS_DP<11>")
	)
	(segment
		(start 218.962224 -19.99488)
		(end 218.753944 -19.7866)
		(width 0.14224)
		(layer "In2.Cu")
		(net "M_A_DQS_DP<11>")
	)
	(segment
		(start 218.962224 -20.23872)
		(end 218.962224 -19.99488)
		(width 0.14224)
		(layer "In2.Cu")
		(net "M_A_DQS_DP<11>")
	)
	(segment
		(start 233.207306 -57.17159)
		(end 231.838754 -57.17159)
		(width 0.0889)
		(layer "In2.Cu")
		(net "M_A_DQS_DP<11>")
	)
	(segment
		(start 218.158314 -38.21303)
		(end 217.705686 -38.21303)
		(width 0.14224)
		(layer "In2.Cu")
		(net "M_A_DQS_DP<11>")
	)
	(segment
		(start 230.506524 -55.838598)
		(end 230.451152 -55.838598)
		(width 0.0889)
		(layer "In2.Cu")
		(net "M_A_DQS_DP<11>")
	)
	(segment
		(start 218.650566 -17.87652)
		(end 218.44254 -18.084546)
		(width 0.14224)
		(layer "In2.Cu")
		(net "M_A_DQS_DP<11>")
	)
	(segment
		(start 218.962224 -18.89252)
		(end 218.962224 -18.057114)
		(width 0.14224)
		(layer "In2.Cu")
		(net "M_A_DQS_DP<11>")
	)
	(segment
		(start 218.474544 -19.3802)
		(end 218.962224 -18.89252)
		(width 0.14224)
		(layer "In2.Cu")
		(net "M_A_DQS_DP<11>")
	)
	(segment
		(start 217.941144 -22.675596)
		(end 218.44254 -22.1742)
		(width 0.14224)
		(layer "In2.Cu")
		(net "M_A_DQS_DP<11>")
	)
	(segment
		(start 217.584528 -40.90543)
		(end 217.20556 -40.526462)
		(width 0.14224)
		(layer "In2.Cu")
		(net "M_A_DQS_DP<11>")
	)
	(segment
		(start 218.189048 -43.183048)
		(end 217.58148 -42.57548)
		(width 0.14224)
		(layer "In2.Cu")
		(net "M_A_DQS_DP<11>")
	)
	(segment
		(start 218.189048 -41.525952)
		(end 218.189048 -41.126918)
		(width 0.14224)
		(layer "In2.Cu")
		(net "M_A_DQS_DP<11>")
	)
	(segment
		(start 217.20556 -39.625778)
		(end 217.541348 -39.28999)
		(width 0.14224)
		(layer "In2.Cu")
		(net "M_A_DQS_DP<11>")
	)
	(segment
		(start 235.630212 -57.971436)
		(end 235.594144 -57.971436)
		(width 0.0889)
		(layer "In2.Cu")
		(net "M_A_DQS_DP<11>")
	)
	(segment
		(start 218.78163 -17.87652)
		(end 218.650566 -17.87652)
		(width 0.14224)
		(layer "In2.Cu")
		(net "M_A_DQS_DP<11>")
	)
	(segment
		(start 218.715844 -21.0439)
		(end 218.627452 -21.0439)
		(width 0.14224)
		(layer "In2.Cu")
		(net "M_A_DQS_DP<11>")
	)
	(segment
		(start 217.350848 -33.212278)
		(end 217.706448 -32.856678)
		(width 0.14224)
		(layer "In2.Cu")
		(net "M_A_DQS_DP<11>")
	)
	(segment
		(start 218.474544 -19.6342)
		(end 218.474544 -19.3802)
		(width 0.14224)
		(layer "In2.Cu")
		(net "M_A_DQS_DP<11>")
	)
	(segment
		(start 218.189048 -41.126918)
		(end 217.96756 -40.90543)
		(width 0.14224)
		(layer "In2.Cu")
		(net "M_A_DQS_DP<11>")
	)
	(segment
		(start 217.706448 -32.856678)
		(end 217.706448 -24.295862)
		(width 0.14224)
		(layer "In2.Cu")
		(net "M_A_DQS_DP<11>")
	)
	(arc
		(start 235.594144 -57.971436)
		(mid 235.276567 -57.89914)
		(end 234.990132 -57.744106)
		(width 0.0889)
		(layer "In2.Cu")
		(net "M_A_DQS_DP<11>")
	)
	(arc
		(start 234.958128 -57.72277)
		(mid 234.86505 -57.682485)
		(end 234.764834 -57.66689)
		(width 0.0889)
		(layer "In2.Cu")
		(net "M_A_DQS_DP<11>")
	)
	(arc
		(start 236.457744 -57.476136)
		(mid 236.169599 -57.558455)
		(end 235.958888 -57.771538)
		(width 0.0889)
		(layer "In2.Cu")
		(net "M_A_DQS_DP<11>")
	)
	(arc
		(start 234.764834 -57.66689)
		(mid 234.764453 -57.666763)
		(end 234.764072 -57.666636)
		(width 0.0889)
		(layer "In2.Cu")
		(net "M_A_DQS_DP<11>")
	)
	(arc
		(start 234.990132 -57.744106)
		(mid 234.974385 -57.733056)
		(end 234.958128 -57.72277)
		(width 0.0889)
		(layer "In2.Cu")
		(net "M_A_DQS_DP<11>")
	)
	(arc
		(start 235.958888 -57.771538)
		(mid 235.820144 -57.913571)
		(end 235.630212 -57.971436)
		(width 0.0889)
		(layer "In2.Cu")
		(net "M_A_DQS_DP<11>")
	)
	(segment
		(start 211.201 -32.41675)
		(end 210.864958 -32.752792)
		(width 0.1651)
		(layer "F.Cu")
		(net "M_A_DQS_DP<10>")
	)
	(segment
		(start 209.14995 -16.040354)
		(end 208.713832 -16.476472)
		(width 0.1651)
		(layer "F.Cu")
		(net "M_A_DQS_DP<10>")
	)
	(segment
		(start 233.716068 -58.06694)
		(end 233.608118 -58.06694)
		(width 0.0889)
		(layer "F.Cu")
		(net "M_A_DQS_DP<10>")
	)
	(segment
		(start 211.10575 -30.340808)
		(end 211.956396 -31.191454)
		(width 0.1651)
		(layer "F.Cu")
		(net "M_A_DQS_DP<10>")
	)
	(segment
		(start 211.791296 -33.67405)
		(end 211.956396 -33.83915)
		(width 0.1651)
		(layer "F.Cu")
		(net "M_A_DQS_DP<10>")
	)
	(segment
		(start 208.710784 -17.702784)
		(end 209.092546 -18.084546)
		(width 0.1651)
		(layer "F.Cu")
		(net "M_A_DQS_DP<10>")
	)
	(segment
		(start 210.864958 -32.752792)
		(end 210.864958 -33.338008)
		(width 0.1651)
		(layer "F.Cu")
		(net "M_A_DQS_DP<10>")
	)
	(segment
		(start 211.956396 -33.83915)
		(end 211.956396 -39.291006)
		(width 0.1651)
		(layer "F.Cu")
		(net "M_A_DQS_DP<10>")
	)
	(segment
		(start 208.713832 -16.476472)
		(end 208.62925 -16.660368)
		(width 0.1651)
		(layer "F.Cu")
		(net "M_A_DQS_DP<10>")
	)
	(segment
		(start 208.430368 -24.048974)
		(end 208.430368 -27.665426)
		(width 0.1651)
		(layer "F.Cu")
		(net "M_A_DQS_DP<10>")
	)
	(segment
		(start 209.14995 -15.423642)
		(end 209.14995 -16.040354)
		(width 0.1651)
		(layer "F.Cu")
		(net "M_A_DQS_DP<10>")
	)
	(segment
		(start 231.67848 -57.223914)
		(end 231.730804 -57.17159)
		(width 0.0889)
		(layer "F.Cu")
		(net "M_A_DQS_DP<10>")
	)
	(segment
		(start 208.430368 -27.665426)
		(end 211.10575 -30.340808)
		(width 0.1651)
		(layer "F.Cu")
		(net "M_A_DQS_DP<10>")
	)
	(segment
		(start 208.6229 -23.856442)
		(end 208.430368 -24.048974)
		(width 0.1651)
		(layer "F.Cu")
		(net "M_A_DQS_DP<10>")
	)
	(segment
		(start 211.956396 -32.25165)
		(end 211.791296 -32.41675)
		(width 0.1651)
		(layer "F.Cu")
		(net "M_A_DQS_DP<10>")
	)
	(segment
		(start 231.730804 -57.17159)
		(end 232.764584 -57.17159)
		(width 0.0889)
		(layer "F.Cu")
		(net "M_A_DQS_DP<10>")
	)
	(segment
		(start 209.092546 -22.1742)
		(end 208.6229 -22.643846)
		(width 0.1651)
		(layer "F.Cu")
		(net "M_A_DQS_DP<10>")
	)
	(segment
		(start 211.201 -33.67405)
		(end 211.791296 -33.67405)
		(width 0.1651)
		(layer "F.Cu")
		(net "M_A_DQS_DP<10>")
	)
	(segment
		(start 211.791296 -32.41675)
		(end 211.201 -32.41675)
		(width 0.1651)
		(layer "F.Cu")
		(net "M_A_DQS_DP<10>")
	)
	(segment
		(start 210.864958 -33.338008)
		(end 211.201 -33.67405)
		(width 0.1651)
		(layer "F.Cu")
		(net "M_A_DQS_DP<10>")
	)
	(segment
		(start 209.150458 -15.423642)
		(end 209.14995 -15.423642)
		(width 0.1651)
		(layer "F.Cu")
		(net "M_A_DQS_DP<10>")
	)
	(segment
		(start 211.956396 -39.291006)
		(end 229.889304 -57.223914)
		(width 0.1651)
		(layer "F.Cu")
		(net "M_A_DQS_DP<10>")
	)
	(segment
		(start 229.889304 -57.223914)
		(end 231.67848 -57.223914)
		(width 0.1651)
		(layer "F.Cu")
		(net "M_A_DQS_DP<10>")
	)
	(segment
		(start 208.6229 -22.643846)
		(end 208.6229 -23.856442)
		(width 0.1651)
		(layer "F.Cu")
		(net "M_A_DQS_DP<10>")
	)
	(segment
		(start 211.956396 -31.191454)
		(end 211.956396 -32.25165)
		(width 0.1651)
		(layer "F.Cu")
		(net "M_A_DQS_DP<10>")
	)
	(segment
		(start 208.62925 -17.478502)
		(end 208.710784 -17.702784)
		(width 0.1651)
		(layer "F.Cu")
		(net "M_A_DQS_DP<10>")
	)
	(segment
		(start 208.62925 -16.660368)
		(end 208.62925 -17.478502)
		(width 0.1651)
		(layer "F.Cu")
		(net "M_A_DQS_DP<10>")
	)
	(segment
		(start 233.595164 -57.66689)
		(end 233.716576 -57.66689)
		(width 0.0889)
		(layer "F.Cu")
		(net "M_A_DQS_DP<10>")
	)
	(via
		(at 209.092546 -22.1742)
		(size 0.508)
		(drill 0.254)
		(layers "F.Cu" "B.Cu")
		(net "M_A_DQS_DP<10>")
	)
	(via
		(at 209.092546 -18.084546)
		(size 0.508)
		(drill 0.254)
		(layers "F.Cu" "B.Cu")
		(net "M_A_DQS_DP<10>")
	)
	(via
		(at 211.10575 -30.340808)
		(size 0.508)
		(drill 0.254)
		(layers "F.Cu" "B.Cu")
		(net "M_A_DQS_DP<10>")
	)
	(arc
		(start 233.096308 -57.371488)
		(mid 233.307021 -57.584567)
		(end 233.595164 -57.66689)
		(width 0.0889)
		(layer "F.Cu")
		(net "M_A_DQS_DP<10>")
	)
	(arc
		(start 233.716576 -57.66689)
		(mid 233.760569 -57.671785)
		(end 233.802428 -57.686194)
		(width 0.0889)
		(layer "F.Cu")
		(net "M_A_DQS_DP<10>")
	)
	(arc
		(start 232.764584 -57.17159)
		(mid 232.956226 -57.228756)
		(end 233.096308 -57.371488)
		(width 0.0889)
		(layer "F.Cu")
		(net "M_A_DQS_DP<10>")
	)
	(arc
		(start 233.802428 -57.686194)
		(mid 233.91158 -57.91104)
		(end 233.716068 -58.06694)
		(width 0.0889)
		(layer "F.Cu")
		(net "M_A_DQS_DP<10>")
	)
	(segment
		(start 209.14995 -24.206454)
		(end 208.693766 -23.75027)
		(width 0.1651)
		(layer "B.Cu")
		(net "M_A_DQS_DP<10>")
	)
	(segment
		(start 209.150458 -24.824182)
		(end 209.14995 -24.824182)
		(width 0.1651)
		(layer "B.Cu")
		(net "M_A_DQS_DP<10>")
	)
	(segment
		(start 208.61655 -22.722332)
		(end 208.703926 -22.56282)
		(width 0.1651)
		(layer "B.Cu")
		(net "M_A_DQS_DP<10>")
	)
	(segment
		(start 208.703926 -22.56282)
		(end 209.092546 -22.1742)
		(width 0.1651)
		(layer "B.Cu")
		(net "M_A_DQS_DP<10>")
	)
	(segment
		(start 209.14995 -24.824182)
		(end 209.14995 -24.206454)
		(width 0.1651)
		(layer "B.Cu")
		(net "M_A_DQS_DP<10>")
	)
	(segment
		(start 208.693766 -23.75027)
		(end 208.61655 -23.617936)
		(width 0.1651)
		(layer "B.Cu")
		(net "M_A_DQS_DP<10>")
	)
	(segment
		(start 208.61655 -23.617936)
		(end 208.61655 -22.722332)
		(width 0.1651)
		(layer "B.Cu")
		(net "M_A_DQS_DP<10>")
	)
	(segment
		(start 209.371692 -22.1742)
		(end 209.61223 -21.933662)
		(width 0.14224)
		(layer "In2.Cu")
		(net "M_A_DQS_DP<10>")
	)
	(segment
		(start 209.12455 -19.3802)
		(end 209.61223 -18.89252)
		(width 0.14224)
		(layer "In2.Cu")
		(net "M_A_DQS_DP<10>")
	)
	(segment
		(start 209.120994 -20.549108)
		(end 209.248502 -20.4216)
		(width 0.14224)
		(layer "In2.Cu")
		(net "M_A_DQS_DP<10>")
	)
	(segment
		(start 209.42935 -20.4216)
		(end 209.61223 -20.23872)
		(width 0.14224)
		(layer "In2.Cu")
		(net "M_A_DQS_DP<10>")
	)
	(segment
		(start 209.61223 -21.29028)
		(end 209.36585 -21.0439)
		(width 0.14224)
		(layer "In2.Cu")
		(net "M_A_DQS_DP<10>")
	)
	(segment
		(start 209.248502 -20.4216)
		(end 209.42935 -20.4216)
		(width 0.14224)
		(layer "In2.Cu")
		(net "M_A_DQS_DP<10>")
	)
	(segment
		(start 209.120994 -20.887436)
		(end 209.120994 -20.549108)
		(width 0.14224)
		(layer "In2.Cu")
		(net "M_A_DQS_DP<10>")
	)
	(segment
		(start 209.092546 -22.1742)
		(end 209.371692 -22.1742)
		(width 0.14224)
		(layer "In2.Cu")
		(net "M_A_DQS_DP<10>")
	)
	(segment
		(start 209.277458 -21.0439)
		(end 209.120994 -20.887436)
		(width 0.14224)
		(layer "In2.Cu")
		(net "M_A_DQS_DP<10>")
	)
	(segment
		(start 209.61223 -20.23872)
		(end 209.61223 -19.99488)
		(width 0.14224)
		(layer "In2.Cu")
		(net "M_A_DQS_DP<10>")
	)
	(segment
		(start 209.12455 -19.6342)
		(end 209.12455 -19.3802)
		(width 0.14224)
		(layer "In2.Cu")
		(net "M_A_DQS_DP<10>")
	)
	(segment
		(start 209.61223 -18.057114)
		(end 209.431636 -17.87652)
		(width 0.14224)
		(layer "In2.Cu")
		(net "M_A_DQS_DP<10>")
	)
	(segment
		(start 209.27695 -19.7866)
		(end 209.12455 -19.6342)
		(width 0.14224)
		(layer "In2.Cu")
		(net "M_A_DQS_DP<10>")
	)
	(segment
		(start 209.431636 -17.87652)
		(end 209.300572 -17.87652)
		(width 0.14224)
		(layer "In2.Cu")
		(net "M_A_DQS_DP<10>")
	)
	(segment
		(start 209.300572 -17.87652)
		(end 209.092546 -18.084546)
		(width 0.14224)
		(layer "In2.Cu")
		(net "M_A_DQS_DP<10>")
	)
	(segment
		(start 209.61223 -18.89252)
		(end 209.61223 -18.057114)
		(width 0.14224)
		(layer "In2.Cu")
		(net "M_A_DQS_DP<10>")
	)
	(segment
		(start 209.61223 -19.99488)
		(end 209.40395 -19.7866)
		(width 0.14224)
		(layer "In2.Cu")
		(net "M_A_DQS_DP<10>")
	)
	(segment
		(start 209.40395 -19.7866)
		(end 209.27695 -19.7866)
		(width 0.14224)
		(layer "In2.Cu")
		(net "M_A_DQS_DP<10>")
	)
	(segment
		(start 209.61223 -21.933662)
		(end 209.61223 -21.29028)
		(width 0.14224)
		(layer "In2.Cu")
		(net "M_A_DQS_DP<10>")
	)
	(segment
		(start 209.36585 -21.0439)
		(end 209.277458 -21.0439)
		(width 0.14224)
		(layer "In2.Cu")
		(net "M_A_DQS_DP<10>")
	)
	(segment
		(start 201.500486 -20.023582)
		(end 201.499978 -20.023582)
		(width 0.1651)
		(layer "F.Cu")
		(net "M_A_DQS_DP<0>")
	)
	(segment
		(start 201.499978 -20.023582)
		(end 201.499978 -19.011646)
		(width 0.1651)
		(layer "F.Cu")
		(net "M_A_DQS_DP<0>")
	)
	(segment
		(start 201.537824 -17.6022)
		(end 201.293984 -17.35836)
		(width 0.1651)
		(layer "F.Cu")
		(net "M_A_DQS_DP<0>")
	)
	(segment
		(start 233.608118 -63.019686)
		(end 233.036618 -63.019686)
		(width 0.1016)
		(layer "F.Cu")
		(net "M_A_DQS_DP<0>")
	)
	(segment
		(start 201.537824 -18.9738)
		(end 201.537824 -17.6022)
		(width 0.1651)
		(layer "F.Cu")
		(net "M_A_DQS_DP<0>")
	)
	(segment
		(start 201.293984 -17.35836)
		(end 201.037952 -17.35836)
		(width 0.1651)
		(layer "F.Cu")
		(net "M_A_DQS_DP<0>")
	)
	(segment
		(start 201.499978 -19.011646)
		(end 201.537824 -18.9738)
		(width 0.1651)
		(layer "F.Cu")
		(net "M_A_DQS_DP<0>")
	)
	(via
		(at 201.037952 -22.888956)
		(size 0.508)
		(drill 0.254)
		(layers "F.Cu" "B.Cu")
		(net "M_A_DQS_DP<0>")
	)
	(via
		(at 201.037952 -17.35836)
		(size 0.508)
		(drill 0.254)
		(layers "F.Cu" "B.Cu")
		(net "M_A_DQS_DP<0>")
	)
	(via
		(at 233.036618 -63.019686)
		(size 0.508)
		(drill 0.254)
		(layers "F.Cu" "B.Cu")
		(net "M_A_DQS_DP<0>")
	)
	(segment
		(start 201.537824 -22.6314)
		(end 201.280268 -22.888956)
		(width 0.1651)
		(layer "B.Cu")
		(net "M_A_DQS_DP<0>")
	)
	(segment
		(start 201.280268 -22.888956)
		(end 201.037952 -22.888956)
		(width 0.1651)
		(layer "B.Cu")
		(net "M_A_DQS_DP<0>")
	)
	(segment
		(start 201.500486 -20.224242)
		(end 201.499978 -20.224242)
		(width 0.1651)
		(layer "B.Cu")
		(net "M_A_DQS_DP<0>")
	)
	(segment
		(start 201.499978 -21.374354)
		(end 201.537824 -21.4122)
		(width 0.1651)
		(layer "B.Cu")
		(net "M_A_DQS_DP<0>")
	)
	(segment
		(start 201.499978 -20.224242)
		(end 201.499978 -21.374354)
		(width 0.1651)
		(layer "B.Cu")
		(net "M_A_DQS_DP<0>")
	)
	(segment
		(start 201.537824 -21.4122)
		(end 201.537824 -22.6314)
		(width 0.1651)
		(layer "B.Cu")
		(net "M_A_DQS_DP<0>")
	)
	(segment
		(start 232.367074 -62.92469)
		(end 232.86212 -63.419736)
		(width 0.0889)
		(layer "In2.Cu")
		(net "M_A_DQS_DP<0>")
	)
	(segment
		(start 201.237088 -28.288488)
		(end 201.394568 -28.445968)
		(width 0.14224)
		(layer "In2.Cu")
		(net "M_A_DQS_DP<0>")
	)
	(segment
		(start 201.0664 -24.0538)
		(end 200.861676 -24.258524)
		(width 0.14224)
		(layer "In2.Cu")
		(net "M_A_DQS_DP<0>")
	)
	(segment
		(start 201.237088 -25.240488)
		(end 201.394568 -25.397968)
		(width 0.14224)
		(layer "In2.Cu")
		(net "M_A_DQS_DP<0>")
	)
	(segment
		(start 201.394568 -26.159968)
		(end 201.394568 -26.413968)
		(width 0.14224)
		(layer "In2.Cu")
		(net "M_A_DQS_DP<0>")
	)
	(segment
		(start 203.218288 -36.664138)
		(end 203.218288 -37.202872)
		(width 0.14224)
		(layer "In2.Cu")
		(net "M_A_DQS_DP<0>")
	)
	(segment
		(start 201.237088 -25.02916)
		(end 201.237088 -25.240488)
		(width 0.14224)
		(layer "In2.Cu")
		(net "M_A_DQS_DP<0>")
	)
	(segment
		(start 201.394568 -26.921968)
		(end 201.394568 -27.175968)
		(width 0.14224)
		(layer "In2.Cu")
		(net "M_A_DQS_DP<0>")
	)
	(segment
		(start 201.394568 -27.175968)
		(end 201.237088 -27.333448)
		(width 0.14224)
		(layer "In2.Cu")
		(net "M_A_DQS_DP<0>")
	)
	(segment
		(start 231.83469 -62.92469)
		(end 232.367074 -62.92469)
		(width 0.0889)
		(layer "In2.Cu")
		(net "M_A_DQS_DP<0>")
	)
	(segment
		(start 233.172508 -63.019686)
		(end 233.036618 -63.019686)
		(width 0.0889)
		(layer "In2.Cu")
		(net "M_A_DQS_DP<0>")
	)
	(segment
		(start 201.549 -23.400004)
		(end 201.549 -23.7998)
		(width 0.14224)
		(layer "In2.Cu")
		(net "M_A_DQS_DP<0>")
	)
	(segment
		(start 201.84872 -18.169128)
		(end 201.84872 -22.078188)
		(width 0.14224)
		(layer "In2.Cu")
		(net "M_A_DQS_DP<0>")
	)
	(segment
		(start 201.237088 -28.095448)
		(end 201.237088 -28.288488)
		(width 0.14224)
		(layer "In2.Cu")
		(net "M_A_DQS_DP<0>")
	)
	(segment
		(start 201.394568 -28.445968)
		(end 201.394568 -28.699968)
		(width 0.14224)
		(layer "In2.Cu")
		(net "M_A_DQS_DP<0>")
	)
	(segment
		(start 201.394568 -25.397968)
		(end 201.394568 -25.651968)
		(width 0.14224)
		(layer "In2.Cu")
		(net "M_A_DQS_DP<0>")
	)
	(segment
		(start 231.143556 -63.615824)
		(end 231.83469 -62.92469)
		(width 0.0889)
		(layer "In2.Cu")
		(net "M_A_DQS_DP<0>")
	)
	(segment
		(start 201.549 -23.7998)
		(end 201.295 -24.0538)
		(width 0.14224)
		(layer "In2.Cu")
		(net "M_A_DQS_DP<0>")
	)
	(segment
		(start 204.056488 -35.14471)
		(end 204.056488 -35.825938)
		(width 0.14224)
		(layer "In2.Cu")
		(net "M_A_DQS_DP<0>")
	)
	(segment
		(start 231.001316 -63.584836)
		(end 231.032304 -63.615824)
		(width 0.0889)
		(layer "In2.Cu")
		(net "M_A_DQS_DP<0>")
	)
	(segment
		(start 201.237088 -26.002488)
		(end 201.394568 -26.159968)
		(width 0.14224)
		(layer "In2.Cu")
		(net "M_A_DQS_DP<0>")
	)
	(segment
		(start 203.322682 -34.410904)
		(end 204.056488 -35.14471)
		(width 0.14224)
		(layer "In2.Cu")
		(net "M_A_DQS_DP<0>")
	)
	(segment
		(start 201.394568 -27.683968)
		(end 201.394568 -27.937968)
		(width 0.14224)
		(layer "In2.Cu")
		(net "M_A_DQS_DP<0>")
	)
	(segment
		(start 204.183488 -38.685216)
		(end 229.083108 -63.584836)
		(width 0.14224)
		(layer "In2.Cu")
		(net "M_A_DQS_DP<0>")
	)
	(segment
		(start 203.218288 -37.202872)
		(end 203.490576 -37.47516)
		(width 0.14224)
		(layer "In2.Cu")
		(net "M_A_DQS_DP<0>")
	)
	(segment
		(start 201.237088 -26.764488)
		(end 201.394568 -26.921968)
		(width 0.14224)
		(layer "In2.Cu")
		(net "M_A_DQS_DP<0>")
	)
	(segment
		(start 201.237088 -27.526488)
		(end 201.394568 -27.683968)
		(width 0.14224)
		(layer "In2.Cu")
		(net "M_A_DQS_DP<0>")
	)
	(segment
		(start 201.394568 -25.651968)
		(end 201.237088 -25.809448)
		(width 0.14224)
		(layer "In2.Cu")
		(net "M_A_DQS_DP<0>")
	)
	(segment
		(start 200.861676 -24.653748)
		(end 201.237088 -25.02916)
		(width 0.14224)
		(layer "In2.Cu")
		(net "M_A_DQS_DP<0>")
	)
	(segment
		(start 201.483722 -34.410904)
		(end 203.322682 -34.410904)
		(width 0.14224)
		(layer "In2.Cu")
		(net "M_A_DQS_DP<0>")
	)
	(segment
		(start 201.237088 -26.571448)
		(end 201.237088 -26.764488)
		(width 0.14224)
		(layer "In2.Cu")
		(net "M_A_DQS_DP<0>")
	)
	(segment
		(start 203.805282 -37.47516)
		(end 204.183488 -37.853366)
		(width 0.14224)
		(layer "In2.Cu")
		(net "M_A_DQS_DP<0>")
	)
	(segment
		(start 231.032304 -63.615824)
		(end 231.143556 -63.615824)
		(width 0.0889)
		(layer "In2.Cu")
		(net "M_A_DQS_DP<0>")
	)
	(segment
		(start 204.056488 -35.825938)
		(end 203.218288 -36.664138)
		(width 0.14224)
		(layer "In2.Cu")
		(net "M_A_DQS_DP<0>")
	)
	(segment
		(start 201.295 -24.0538)
		(end 201.0664 -24.0538)
		(width 0.14224)
		(layer "In2.Cu")
		(net "M_A_DQS_DP<0>")
	)
	(segment
		(start 201.237088 -28.857448)
		(end 201.237088 -34.16427)
		(width 0.14224)
		(layer "In2.Cu")
		(net "M_A_DQS_DP<0>")
	)
	(segment
		(start 201.394568 -27.937968)
		(end 201.237088 -28.095448)
		(width 0.14224)
		(layer "In2.Cu")
		(net "M_A_DQS_DP<0>")
	)
	(segment
		(start 200.861676 -24.258524)
		(end 200.861676 -24.653748)
		(width 0.14224)
		(layer "In2.Cu")
		(net "M_A_DQS_DP<0>")
	)
	(segment
		(start 201.037952 -17.35836)
		(end 201.84872 -18.169128)
		(width 0.14224)
		(layer "In2.Cu")
		(net "M_A_DQS_DP<0>")
	)
	(segment
		(start 204.183488 -37.853366)
		(end 204.183488 -38.685216)
		(width 0.14224)
		(layer "In2.Cu")
		(net "M_A_DQS_DP<0>")
	)
	(segment
		(start 203.490576 -37.47516)
		(end 203.805282 -37.47516)
		(width 0.14224)
		(layer "In2.Cu")
		(net "M_A_DQS_DP<0>")
	)
	(segment
		(start 201.84872 -22.078188)
		(end 201.037952 -22.888956)
		(width 0.14224)
		(layer "In2.Cu")
		(net "M_A_DQS_DP<0>")
	)
	(segment
		(start 201.037952 -22.888956)
		(end 201.549 -23.400004)
		(width 0.14224)
		(layer "In2.Cu")
		(net "M_A_DQS_DP<0>")
	)
	(segment
		(start 201.237088 -34.16427)
		(end 201.483722 -34.410904)
		(width 0.14224)
		(layer "In2.Cu")
		(net "M_A_DQS_DP<0>")
	)
	(segment
		(start 201.394568 -28.699968)
		(end 201.237088 -28.857448)
		(width 0.14224)
		(layer "In2.Cu")
		(net "M_A_DQS_DP<0>")
	)
	(segment
		(start 201.394568 -26.413968)
		(end 201.237088 -26.571448)
		(width 0.14224)
		(layer "In2.Cu")
		(net "M_A_DQS_DP<0>")
	)
	(segment
		(start 201.237088 -27.333448)
		(end 201.237088 -27.526488)
		(width 0.14224)
		(layer "In2.Cu")
		(net "M_A_DQS_DP<0>")
	)
	(segment
		(start 232.86212 -63.419736)
		(end 233.172508 -63.419736)
		(width 0.0889)
		(layer "In2.Cu")
		(net "M_A_DQS_DP<0>")
	)
	(segment
		(start 229.083108 -63.584836)
		(end 231.001316 -63.584836)
		(width 0.14224)
		(layer "In2.Cu")
		(net "M_A_DQS_DP<0>")
	)
	(segment
		(start 201.237088 -25.809448)
		(end 201.237088 -26.002488)
		(width 0.14224)
		(layer "In2.Cu")
		(net "M_A_DQS_DP<0>")
	)
	(arc
		(start 233.243882 -63.406528)
		(mid 233.369296 -63.183295)
		(end 233.172508 -63.019686)
		(width 0.0889)
		(layer "In2.Cu")
		(net "M_A_DQS_DP<0>")
	)
	(arc
		(start 233.172508 -63.419736)
		(mid 233.208804 -63.416413)
		(end 233.243882 -63.406528)
		(width 0.0889)
		(layer "In2.Cu")
		(net "M_A_DQS_DP<0>")
	)
	(segment
		(start 234.466638 -64.50584)
		(end 233.895138 -64.50584)
		(width 0.1016)
		(layer "F.Cu")
		(net "M_A_DQS_DN<9>")
	)
	(segment
		(start 200.165716 -17.60093)
		(end 199.957436 -17.60093)
		(width 0.1651)
		(layer "F.Cu")
		(net "M_A_DQS_DN<9>")
	)
	(segment
		(start 200.417684 -17.348962)
		(end 200.165716 -17.60093)
		(width 0.1651)
		(layer "F.Cu")
		(net "M_A_DQS_DN<9>")
	)
	(segment
		(start 200.64984 -15.423642)
		(end 200.64984 -16.077184)
		(width 0.1651)
		(layer "F.Cu")
		(net "M_A_DQS_DN<9>")
	)
	(segment
		(start 200.231756 -16.9164)
		(end 200.417684 -17.102328)
		(width 0.1651)
		(layer "F.Cu")
		(net "M_A_DQS_DN<9>")
	)
	(segment
		(start 199.957436 -17.60093)
		(end 199.768206 -17.4117)
		(width 0.1651)
		(layer "F.Cu")
		(net "M_A_DQS_DN<9>")
	)
	(segment
		(start 200.231756 -16.495268)
		(end 200.231756 -16.9164)
		(width 0.1651)
		(layer "F.Cu")
		(net "M_A_DQS_DN<9>")
	)
	(segment
		(start 200.64984 -16.077184)
		(end 200.231756 -16.495268)
		(width 0.1651)
		(layer "F.Cu")
		(net "M_A_DQS_DN<9>")
	)
	(segment
		(start 199.768206 -17.4117)
		(end 199.749156 -17.4117)
		(width 0.1651)
		(layer "F.Cu")
		(net "M_A_DQS_DN<9>")
	)
	(segment
		(start 200.650348 -15.423642)
		(end 200.64984 -15.423642)
		(width 0.1651)
		(layer "F.Cu")
		(net "M_A_DQS_DN<9>")
	)
	(segment
		(start 200.417684 -17.102328)
		(end 200.417684 -17.348962)
		(width 0.1651)
		(layer "F.Cu")
		(net "M_A_DQS_DN<9>")
	)
	(via
		(at 199.749156 -17.4117)
		(size 0.508)
		(drill 0.254)
		(layers "F.Cu" "B.Cu")
		(net "M_A_DQS_DN<9>")
	)
	(via
		(at 233.895138 -64.50584)
		(size 0.508)
		(drill 0.254)
		(layers "F.Cu" "B.Cu")
		(net "M_A_DQS_DN<9>")
	)
	(via
		(at 199.742552 -22.8346)
		(size 0.508)
		(drill 0.254)
		(layers "F.Cu" "B.Cu")
		(net "M_A_DQS_DN<9>")
	)
	(segment
		(start 199.742552 -22.8346)
		(end 199.937116 -22.640036)
		(width 0.1651)
		(layer "B.Cu")
		(net "M_A_DQS_DN<9>")
	)
	(segment
		(start 200.384156 -22.86)
		(end 200.384156 -23.1902)
		(width 0.1651)
		(layer "B.Cu")
		(net "M_A_DQS_DN<9>")
	)
	(segment
		(start 199.937116 -22.640036)
		(end 200.164192 -22.640036)
		(width 0.1651)
		(layer "B.Cu")
		(net "M_A_DQS_DN<9>")
	)
	(segment
		(start 200.650094 -24.823928)
		(end 200.650348 -24.824182)
		(width 0.1651)
		(layer "B.Cu")
		(net "M_A_DQS_DN<9>")
	)
	(segment
		(start 200.384156 -23.1902)
		(end 200.206356 -23.368)
		(width 0.1651)
		(layer "B.Cu")
		(net "M_A_DQS_DN<9>")
	)
	(segment
		(start 200.206356 -23.368)
		(end 200.206356 -23.723854)
		(width 0.1651)
		(layer "B.Cu")
		(net "M_A_DQS_DN<9>")
	)
	(segment
		(start 200.650094 -24.167592)
		(end 200.650094 -24.823928)
		(width 0.1651)
		(layer "B.Cu")
		(net "M_A_DQS_DN<9>")
	)
	(segment
		(start 200.164192 -22.640036)
		(end 200.384156 -22.86)
		(width 0.1651)
		(layer "B.Cu")
		(net "M_A_DQS_DN<9>")
	)
	(segment
		(start 200.206356 -23.723854)
		(end 200.650094 -24.167592)
		(width 0.1651)
		(layer "B.Cu")
		(net "M_A_DQS_DN<9>")
	)
	(segment
		(start 200.068688 -28.36672)
		(end 200.226168 -28.5242)
		(width 0.14224)
		(layer "In2.Cu")
		(net "M_A_DQS_DN<9>")
	)
	(segment
		(start 200.180956 -23.273004)
		(end 200.180956 -23.720044)
		(width 0.14224)
		(layer "In2.Cu")
		(net "M_A_DQS_DN<9>")
	)
	(segment
		(start 200.068688 -35.940238)
		(end 200.512172 -36.383722)
		(width 0.14224)
		(layer "In2.Cu")
		(net "M_A_DQS_DN<9>")
	)
	(segment
		(start 200.068688 -27.60472)
		(end 200.226168 -27.7622)
		(width 0.14224)
		(layer "In2.Cu")
		(net "M_A_DQS_DN<9>")
	)
	(segment
		(start 200.790302 -36.383722)
		(end 201.56932 -37.16274)
		(width 0.14224)
		(layer "In2.Cu")
		(net "M_A_DQS_DN<9>")
	)
	(segment
		(start 200.531476 -22.045676)
		(end 199.742552 -22.8346)
		(width 0.14224)
		(layer "In2.Cu")
		(net "M_A_DQS_DN<9>")
	)
	(segment
		(start 201.56932 -37.44087)
		(end 228.690932 -64.562482)
		(width 0.14224)
		(layer "In2.Cu")
		(net "M_A_DQS_DN<9>")
	)
	(segment
		(start 231.854502 -63.91529)
		(end 232.367328 -63.91529)
		(width 0.0889)
		(layer "In2.Cu")
		(net "M_A_DQS_DN<9>")
	)
	(segment
		(start 201.56932 -37.16274)
		(end 201.56932 -37.44087)
		(width 0.14224)
		(layer "In2.Cu")
		(net "M_A_DQS_DN<9>")
	)
	(segment
		(start 200.512172 -36.383722)
		(end 200.790302 -36.383722)
		(width 0.14224)
		(layer "In2.Cu")
		(net "M_A_DQS_DN<9>")
	)
	(segment
		(start 200.068688 -28.17368)
		(end 200.068688 -28.36672)
		(width 0.14224)
		(layer "In2.Cu")
		(net "M_A_DQS_DN<9>")
	)
	(segment
		(start 200.226168 -26.2382)
		(end 200.226168 -26.4922)
		(width 0.14224)
		(layer "In2.Cu")
		(net "M_A_DQS_DN<9>")
	)
	(segment
		(start 199.749156 -17.4117)
		(end 199.944736 -17.60728)
		(width 0.14224)
		(layer "In2.Cu")
		(net "M_A_DQS_DN<9>")
	)
	(segment
		(start 200.226168 -29.2862)
		(end 200.226168 -29.5402)
		(width 0.14224)
		(layer "In2.Cu")
		(net "M_A_DQS_DN<9>")
	)
	(segment
		(start 199.898 -24.003)
		(end 199.723756 -24.003)
		(width 0.14224)
		(layer "In2.Cu")
		(net "M_A_DQS_DN<9>")
	)
	(segment
		(start 200.068688 -29.69768)
		(end 200.068688 -35.940238)
		(width 0.14224)
		(layer "In2.Cu")
		(net "M_A_DQS_DN<9>")
	)
	(segment
		(start 232.367328 -63.91529)
		(end 232.862374 -64.410336)
		(width 0.0889)
		(layer "In2.Cu")
		(net "M_A_DQS_DN<9>")
	)
	(segment
		(start 200.068688 -25.83688)
		(end 200.068688 -26.08072)
		(width 0.14224)
		(layer "In2.Cu")
		(net "M_A_DQS_DN<9>")
	)
	(segment
		(start 200.068688 -26.64968)
		(end 200.068688 -26.84272)
		(width 0.14224)
		(layer "In2.Cu")
		(net "M_A_DQS_DN<9>")
	)
	(segment
		(start 200.226168 -28.5242)
		(end 200.226168 -28.7782)
		(width 0.14224)
		(layer "In2.Cu")
		(net "M_A_DQS_DN<9>")
	)
	(segment
		(start 200.194164 -17.60728)
		(end 200.531476 -17.944592)
		(width 0.14224)
		(layer "In2.Cu")
		(net "M_A_DQS_DN<9>")
	)
	(segment
		(start 200.226168 -27.0002)
		(end 200.226168 -27.2542)
		(width 0.14224)
		(layer "In2.Cu")
		(net "M_A_DQS_DN<9>")
	)
	(segment
		(start 199.540876 -24.18588)
		(end 199.540876 -24.78278)
		(width 0.14224)
		(layer "In2.Cu")
		(net "M_A_DQS_DN<9>")
	)
	(segment
		(start 200.180956 -23.720044)
		(end 199.898 -24.003)
		(width 0.14224)
		(layer "In2.Cu")
		(net "M_A_DQS_DN<9>")
	)
	(segment
		(start 200.226168 -28.7782)
		(end 200.068688 -28.93568)
		(width 0.14224)
		(layer "In2.Cu")
		(net "M_A_DQS_DN<9>")
	)
	(segment
		(start 233.475276 -64.50584)
		(end 233.895138 -64.50584)
		(width 0.0889)
		(layer "In2.Cu")
		(net "M_A_DQS_DN<9>")
	)
	(segment
		(start 199.944736 -17.60728)
		(end 200.194164 -17.60728)
		(width 0.14224)
		(layer "In2.Cu")
		(net "M_A_DQS_DN<9>")
	)
	(segment
		(start 232.862374 -64.410336)
		(end 233.223054 -64.410336)
		(width 0.0889)
		(layer "In2.Cu")
		(net "M_A_DQS_DN<9>")
	)
	(segment
		(start 199.723756 -24.003)
		(end 199.540876 -24.18588)
		(width 0.14224)
		(layer "In2.Cu")
		(net "M_A_DQS_DN<9>")
	)
	(segment
		(start 228.690932 -64.562482)
		(end 230.881936 -64.562482)
		(width 0.14224)
		(layer "In2.Cu")
		(net "M_A_DQS_DN<9>")
	)
	(segment
		(start 200.226168 -27.2542)
		(end 200.068688 -27.41168)
		(width 0.14224)
		(layer "In2.Cu")
		(net "M_A_DQS_DN<9>")
	)
	(segment
		(start 200.068688 -28.93568)
		(end 200.068688 -29.12872)
		(width 0.14224)
		(layer "In2.Cu")
		(net "M_A_DQS_DN<9>")
	)
	(segment
		(start 200.068688 -29.12872)
		(end 200.226168 -29.2862)
		(width 0.14224)
		(layer "In2.Cu")
		(net "M_A_DQS_DN<9>")
	)
	(segment
		(start 200.226168 -25.6794)
		(end 200.068688 -25.83688)
		(width 0.14224)
		(layer "In2.Cu")
		(net "M_A_DQS_DN<9>")
	)
	(segment
		(start 200.226168 -26.4922)
		(end 200.068688 -26.64968)
		(width 0.14224)
		(layer "In2.Cu")
		(net "M_A_DQS_DN<9>")
	)
	(segment
		(start 199.742552 -22.8346)
		(end 200.180956 -23.273004)
		(width 0.14224)
		(layer "In2.Cu")
		(net "M_A_DQS_DN<9>")
	)
	(segment
		(start 200.068688 -26.84272)
		(end 200.226168 -27.0002)
		(width 0.14224)
		(layer "In2.Cu")
		(net "M_A_DQS_DN<9>")
	)
	(segment
		(start 200.226168 -25.468072)
		(end 200.226168 -25.6794)
		(width 0.14224)
		(layer "In2.Cu")
		(net "M_A_DQS_DN<9>")
	)
	(segment
		(start 200.068688 -26.08072)
		(end 200.226168 -26.2382)
		(width 0.14224)
		(layer "In2.Cu")
		(net "M_A_DQS_DN<9>")
	)
	(segment
		(start 200.226168 -28.0162)
		(end 200.068688 -28.17368)
		(width 0.14224)
		(layer "In2.Cu")
		(net "M_A_DQS_DN<9>")
	)
	(segment
		(start 200.068688 -27.41168)
		(end 200.068688 -27.60472)
		(width 0.14224)
		(layer "In2.Cu")
		(net "M_A_DQS_DN<9>")
	)
	(segment
		(start 231.188768 -64.581024)
		(end 231.854502 -63.91529)
		(width 0.0889)
		(layer "In2.Cu")
		(net "M_A_DQS_DN<9>")
	)
	(segment
		(start 200.226168 -27.7622)
		(end 200.226168 -28.0162)
		(width 0.14224)
		(layer "In2.Cu")
		(net "M_A_DQS_DN<9>")
	)
	(segment
		(start 199.540876 -24.78278)
		(end 200.226168 -25.468072)
		(width 0.14224)
		(layer "In2.Cu")
		(net "M_A_DQS_DN<9>")
	)
	(segment
		(start 230.881936 -64.562482)
		(end 230.904034 -64.562482)
		(width 0.0889)
		(layer "In2.Cu")
		(net "M_A_DQS_DN<9>")
	)
	(segment
		(start 200.531476 -17.944592)
		(end 200.531476 -22.045676)
		(width 0.14224)
		(layer "In2.Cu")
		(net "M_A_DQS_DN<9>")
	)
	(segment
		(start 230.904034 -64.562482)
		(end 230.922576 -64.581024)
		(width 0.0889)
		(layer "In2.Cu")
		(net "M_A_DQS_DN<9>")
	)
	(segment
		(start 230.922576 -64.581024)
		(end 231.188768 -64.581024)
		(width 0.0889)
		(layer "In2.Cu")
		(net "M_A_DQS_DN<9>")
	)
	(segment
		(start 200.226168 -29.5402)
		(end 200.068688 -29.69768)
		(width 0.14224)
		(layer "In2.Cu")
		(net "M_A_DQS_DN<9>")
	)
	(arc
		(start 233.223054 -64.410336)
		(mid 233.322053 -64.428445)
		(end 233.40822 -64.48044)
		(width 0.0889)
		(layer "In2.Cu")
		(net "M_A_DQS_DN<9>")
	)
	(arc
		(start 233.40822 -64.48044)
		(mid 233.439429 -64.499253)
		(end 233.475276 -64.50584)
		(width 0.0889)
		(layer "In2.Cu")
		(net "M_A_DQS_DN<9>")
	)
	(segment
		(start 238.049816 -20.023582)
		(end 238.049816 -18.94967)
		(width 0.1651)
		(layer "F.Cu")
		(net "M_A_DQS_DN<8>")
	)
	(segment
		(start 237.6678 -18.135854)
		(end 237.998254 -17.8054)
		(width 0.1651)
		(layer "F.Cu")
		(net "M_A_DQS_DN<8>")
	)
	(segment
		(start 237.998254 -17.8054)
		(end 238.222282 -17.8054)
		(width 0.1651)
		(layer "F.Cu")
		(net "M_A_DQS_DN<8>")
	)
	(segment
		(start 249.061224 -63.019686)
		(end 248.489724 -63.019686)
		(width 0.1016)
		(layer "F.Cu")
		(net "M_A_DQS_DN<8>")
	)
	(segment
		(start 237.6678 -18.567654)
		(end 237.6678 -18.135854)
		(width 0.1651)
		(layer "F.Cu")
		(net "M_A_DQS_DN<8>")
	)
	(segment
		(start 238.222282 -17.8054)
		(end 238.437928 -18.021046)
		(width 0.1651)
		(layer "F.Cu")
		(net "M_A_DQS_DN<8>")
	)
	(segment
		(start 238.050324 -20.023582)
		(end 238.049816 -20.023582)
		(width 0.1651)
		(layer "F.Cu")
		(net "M_A_DQS_DN<8>")
	)
	(segment
		(start 238.049816 -18.94967)
		(end 237.6678 -18.567654)
		(width 0.1651)
		(layer "F.Cu")
		(net "M_A_DQS_DN<8>")
	)
	(via
		(at 238.437928 -18.021046)
		(size 0.508)
		(drill 0.254)
		(layers "F.Cu" "B.Cu")
		(net "M_A_DQS_DN<8>")
	)
	(via
		(at 248.489724 -63.019686)
		(size 0.508)
		(drill 0.254)
		(layers "F.Cu" "B.Cu")
		(net "M_A_DQS_DN<8>")
	)
	(via
		(at 238.437928 -22.228556)
		(size 0.508)
		(drill 0.254)
		(layers "F.Cu" "B.Cu")
		(net "M_A_DQS_DN<8>")
	)
	(segment
		(start 237.9218 -21.513546)
		(end 237.6678 -21.767546)
		(width 0.1651)
		(layer "B.Cu")
		(net "M_A_DQS_DN<8>")
	)
	(segment
		(start 238.049816 -21.13153)
		(end 237.9218 -21.259546)
		(width 0.1651)
		(layer "B.Cu")
		(net "M_A_DQS_DN<8>")
	)
	(segment
		(start 238.049816 -20.224242)
		(end 238.049816 -21.13153)
		(width 0.1651)
		(layer "B.Cu")
		(net "M_A_DQS_DN<8>")
	)
	(segment
		(start 237.9218 -21.259546)
		(end 237.9218 -21.513546)
		(width 0.1651)
		(layer "B.Cu")
		(net "M_A_DQS_DN<8>")
	)
	(segment
		(start 237.6678 -21.767546)
		(end 237.6678 -22.098)
		(width 0.1651)
		(layer "B.Cu")
		(net "M_A_DQS_DN<8>")
	)
	(segment
		(start 238.0234 -22.4536)
		(end 238.212884 -22.4536)
		(width 0.1651)
		(layer "B.Cu")
		(net "M_A_DQS_DN<8>")
	)
	(segment
		(start 238.212884 -22.4536)
		(end 238.437928 -22.228556)
		(width 0.1651)
		(layer "B.Cu")
		(net "M_A_DQS_DN<8>")
	)
	(segment
		(start 237.6678 -22.098)
		(end 238.0234 -22.4536)
		(width 0.1651)
		(layer "B.Cu")
		(net "M_A_DQS_DN<8>")
	)
	(segment
		(start 238.050324 -20.224242)
		(end 238.049816 -20.224242)
		(width 0.1651)
		(layer "B.Cu")
		(net "M_A_DQS_DN<8>")
	)
	(segment
		(start 238.597186 -19.1262)
		(end 238.799878 -19.1262)
		(width 0.14224)
		(layer "In2.Cu")
		(net "M_A_DQS_DN<8>")
	)
	(segment
		(start 239.906048 -34.012632)
		(end 239.042448 -33.149032)
		(width 0.14224)
		(layer "In2.Cu")
		(net "M_A_DQS_DN<8>")
	)
	(segment
		(start 248.84126 -60.847224)
		(end 248.836434 -60.838588)
		(width 0.0889)
		(layer "In2.Cu")
		(net "M_A_DQS_DN<8>")
	)
	(segment
		(start 238.262922 -24.987504)
		(end 238.262922 -24.986742)
		(width 0.14224)
		(layer "In2.Cu")
		(net "M_A_DQS_DN<8>")
	)
	(segment
		(start 238.979456 -20.28952)
		(end 238.979456 -19.940778)
		(width 0.14224)
		(layer "In2.Cu")
		(net "M_A_DQS_DN<8>")
	)
	(segment
		(start 247.039892 -53.116226)
		(end 247.750584 -52.405534)
		(width 0.0889)
		(layer "In2.Cu")
		(net "M_A_DQS_DN<8>")
	)
	(segment
		(start 246.31396 -49.007522)
		(end 246.31396 -48.456596)
		(width 0.14224)
		(layer "In2.Cu")
		(net "M_A_DQS_DN<8>")
	)
	(segment
		(start 239.906048 -41.100248)
		(end 239.906048 -34.012632)
		(width 0.14224)
		(layer "In2.Cu")
		(net "M_A_DQS_DN<8>")
	)
	(segment
		(start 238.669576 -21.082)
		(end 238.491776 -20.9042)
		(width 0.14224)
		(layer "In2.Cu")
		(net "M_A_DQS_DN<8>")
	)
	(segment
		(start 239.042448 -28.891738)
		(end 238.951008 -28.800298)
		(width 0.14224)
		(layer "In2.Cu")
		(net "M_A_DQS_DN<8>")
	)
	(segment
		(start 238.979456 -19.940778)
		(end 238.774478 -19.7358)
		(width 0.14224)
		(layer "In2.Cu")
		(net "M_A_DQS_DN<8>")
	)
	(segment
		(start 247.115838 -56.870092)
		(end 247.113044 -56.86552)
		(width 0.0889)
		(layer "In2.Cu")
		(net "M_A_DQS_DN<8>")
	)
	(segment
		(start 238.979456 -21.261324)
		(end 238.800132 -21.082)
		(width 0.14224)
		(layer "In2.Cu")
		(net "M_A_DQS_DN<8>")
	)
	(segment
		(start 238.979456 -18.946622)
		(end 238.979456 -18.280888)
		(width 0.14224)
		(layer "In2.Cu")
		(net "M_A_DQS_DN<8>")
	)
	(segment
		(start 248.489724 -63.019686)
		(end 248.489724 -62.681612)
		(width 0.0889)
		(layer "In2.Cu")
		(net "M_A_DQS_DN<8>")
	)
	(segment
		(start 248.84126 -59.856624)
		(end 248.836434 -59.847988)
		(width 0.0889)
		(layer "In2.Cu")
		(net "M_A_DQS_DN<8>")
	)
	(segment
		(start 238.719614 -18.021046)
		(end 238.437928 -18.021046)
		(width 0.14224)
		(layer "In2.Cu")
		(net "M_A_DQS_DN<8>")
	)
	(segment
		(start 238.444532 -19.583146)
		(end 238.444532 -19.278854)
		(width 0.14224)
		(layer "In2.Cu")
		(net "M_A_DQS_DN<8>")
	)
	(segment
		(start 246.348504 -49.563274)
		(end 246.348504 -49.042066)
		(width 0.0889)
		(layer "In2.Cu")
		(net "M_A_DQS_DN<8>")
	)
	(segment
		(start 247.039892 -55.78602)
		(end 247.039892 -53.116226)
		(width 0.0889)
		(layer "In2.Cu")
		(net "M_A_DQS_DN<8>")
	)
	(segment
		(start 238.796576 -20.4724)
		(end 238.979456 -20.28952)
		(width 0.14224)
		(layer "In2.Cu")
		(net "M_A_DQS_DN<8>")
	)
	(segment
		(start 238.491776 -20.9042)
		(end 238.491776 -20.6502)
		(width 0.14224)
		(layer "In2.Cu")
		(net "M_A_DQS_DN<8>")
	)
	(segment
		(start 238.597186 -19.7358)
		(end 238.444532 -19.583146)
		(width 0.14224)
		(layer "In2.Cu")
		(net "M_A_DQS_DN<8>")
	)
	(segment
		(start 248.836434 -60.838588)
		(end 248.830084 -60.82792)
		(width 0.0889)
		(layer "In2.Cu")
		(net "M_A_DQS_DN<8>")
	)
	(segment
		(start 238.491776 -20.6502)
		(end 238.669576 -20.4724)
		(width 0.14224)
		(layer "In2.Cu")
		(net "M_A_DQS_DN<8>")
	)
	(segment
		(start 239.042448 -33.149032)
		(end 239.042448 -28.891738)
		(width 0.14224)
		(layer "In2.Cu")
		(net "M_A_DQS_DN<8>")
	)
	(segment
		(start 238.71682 -22.22881)
		(end 238.979456 -21.966174)
		(width 0.14224)
		(layer "In2.Cu")
		(net "M_A_DQS_DN<8>")
	)
	(segment
		(start 238.979456 -18.280888)
		(end 238.719614 -18.021046)
		(width 0.14224)
		(layer "In2.Cu")
		(net "M_A_DQS_DN<8>")
	)
	(segment
		(start 247.119394 -56.876188)
		(end 247.118124 -56.874156)
		(width 0.0889)
		(layer "In2.Cu")
		(net "M_A_DQS_DN<8>")
	)
	(segment
		(start 245.643146 -46.837346)
		(end 239.906048 -41.100248)
		(width 0.14224)
		(layer "In2.Cu")
		(net "M_A_DQS_DN<8>")
	)
	(segment
		(start 237.992412 -24.716232)
		(end 237.992412 -22.674072)
		(width 0.14224)
		(layer "In2.Cu")
		(net "M_A_DQS_DN<8>")
	)
	(segment
		(start 238.444532 -19.278854)
		(end 238.597186 -19.1262)
		(width 0.14224)
		(layer "In2.Cu")
		(net "M_A_DQS_DN<8>")
	)
	(segment
		(start 238.800132 -21.082)
		(end 238.669576 -21.082)
		(width 0.14224)
		(layer "In2.Cu")
		(net "M_A_DQS_DN<8>")
	)
	(segment
		(start 248.836434 -59.847988)
		(end 248.830084 -59.83732)
		(width 0.0889)
		(layer "In2.Cu")
		(net "M_A_DQS_DN<8>")
	)
	(segment
		(start 247.106694 -55.852822)
		(end 247.039892 -55.78602)
		(width 0.0889)
		(layer "In2.Cu")
		(net "M_A_DQS_DN<8>")
	)
	(segment
		(start 238.979456 -21.966174)
		(end 238.979456 -21.261324)
		(width 0.14224)
		(layer "In2.Cu")
		(net "M_A_DQS_DN<8>")
	)
	(segment
		(start 238.951008 -28.800298)
		(end 238.951008 -25.67559)
		(width 0.14224)
		(layer "In2.Cu")
		(net "M_A_DQS_DN<8>")
	)
	(segment
		(start 248.471944 -61.438536)
		(end 248.50471 -61.438536)
		(width 0.0889)
		(layer "In2.Cu")
		(net "M_A_DQS_DN<8>")
	)
	(segment
		(start 238.437928 -22.228556)
		(end 238.437928 -22.22881)
		(width 0.14224)
		(layer "In2.Cu")
		(net "M_A_DQS_DN<8>")
	)
	(segment
		(start 238.437928 -22.22881)
		(end 238.71682 -22.22881)
		(width 0.14224)
		(layer "In2.Cu")
		(net "M_A_DQS_DN<8>")
	)
	(segment
		(start 247.117108 -56.872632)
		(end 247.115838 -56.870092)
		(width 0.0889)
		(layer "In2.Cu")
		(net "M_A_DQS_DN<8>")
	)
	(segment
		(start 247.649238 -58.16219)
		(end 247.609614 -58.16219)
		(width 0.0889)
		(layer "In2.Cu")
		(net "M_A_DQS_DN<8>")
	)
	(segment
		(start 246.31396 -48.456596)
		(end 245.643146 -46.837346)
		(width 0.14224)
		(layer "In2.Cu")
		(net "M_A_DQS_DN<8>")
	)
	(segment
		(start 248.507758 -58.65749)
		(end 248.471944 -58.65749)
		(width 0.0889)
		(layer "In2.Cu")
		(net "M_A_DQS_DN<8>")
	)
	(segment
		(start 247.12422 -56.884824)
		(end 247.119394 -56.876188)
		(width 0.0889)
		(layer "In2.Cu")
		(net "M_A_DQS_DN<8>")
	)
	(segment
		(start 238.262922 -24.986742)
		(end 237.992412 -24.716232)
		(width 0.14224)
		(layer "In2.Cu")
		(net "M_A_DQS_DN<8>")
	)
	(segment
		(start 238.774478 -19.7358)
		(end 238.597186 -19.7358)
		(width 0.14224)
		(layer "In2.Cu")
		(net "M_A_DQS_DN<8>")
	)
	(segment
		(start 238.951008 -25.67559)
		(end 238.262922 -24.987504)
		(width 0.14224)
		(layer "In2.Cu")
		(net "M_A_DQS_DN<8>")
	)
	(segment
		(start 247.750584 -50.965354)
		(end 246.348504 -49.563274)
		(width 0.0889)
		(layer "In2.Cu")
		(net "M_A_DQS_DN<8>")
	)
	(segment
		(start 247.750584 -52.405534)
		(end 247.750584 -50.965354)
		(width 0.0889)
		(layer "In2.Cu")
		(net "M_A_DQS_DN<8>")
	)
	(segment
		(start 238.799878 -19.1262)
		(end 238.979456 -18.946622)
		(width 0.14224)
		(layer "In2.Cu")
		(net "M_A_DQS_DN<8>")
	)
	(segment
		(start 238.669576 -20.4724)
		(end 238.796576 -20.4724)
		(width 0.14224)
		(layer "In2.Cu")
		(net "M_A_DQS_DN<8>")
	)
	(segment
		(start 237.992412 -22.674072)
		(end 238.437928 -22.228556)
		(width 0.14224)
		(layer "In2.Cu")
		(net "M_A_DQS_DN<8>")
	)
	(segment
		(start 246.348504 -49.042066)
		(end 246.31396 -49.007522)
		(width 0.0889)
		(layer "In2.Cu")
		(net "M_A_DQS_DN<8>")
	)
	(segment
		(start 248.489724 -62.681612)
		(end 248.4247 -62.616588)
		(width 0.0889)
		(layer "In2.Cu")
		(net "M_A_DQS_DN<8>")
	)
	(segment
		(start 247.118124 -56.874156)
		(end 247.117108 -56.872632)
		(width 0.0889)
		(layer "In2.Cu")
		(net "M_A_DQS_DN<8>")
	)
	(arc
		(start 248.4247 -62.616588)
		(mid 247.899362 -62.005656)
		(end 248.471944 -61.438536)
		(width 0.0889)
		(layer "In2.Cu")
		(net "M_A_DQS_DN<8>")
	)
	(arc
		(start 247.119394 -57.276238)
		(mid 247.172864 -57.081175)
		(end 247.12422 -56.884824)
		(width 0.0889)
		(layer "In2.Cu")
		(net "M_A_DQS_DN<8>")
	)
	(arc
		(start 248.50471 -61.438536)
		(mid 248.837628 -61.236545)
		(end 248.84126 -60.847224)
		(width 0.0889)
		(layer "In2.Cu")
		(net "M_A_DQS_DN<8>")
	)
	(arc
		(start 247.609614 -58.16219)
		(mid 247.114137 -57.857747)
		(end 247.119394 -57.276238)
		(width 0.0889)
		(layer "In2.Cu")
		(net "M_A_DQS_DN<8>")
	)
	(arc
		(start 247.119394 -56.285638)
		(mid 247.174532 -56.067407)
		(end 247.106694 -55.852822)
		(width 0.0889)
		(layer "In2.Cu")
		(net "M_A_DQS_DN<8>")
	)
	(arc
		(start 248.830084 -59.83732)
		(mid 248.757286 -59.546557)
		(end 248.836434 -59.257438)
		(width 0.0889)
		(layer "In2.Cu")
		(net "M_A_DQS_DN<8>")
	)
	(arc
		(start 247.113044 -56.86552)
		(mid 247.040246 -56.574757)
		(end 247.119394 -56.285638)
		(width 0.0889)
		(layer "In2.Cu")
		(net "M_A_DQS_DN<8>")
	)
	(arc
		(start 248.836434 -60.248038)
		(mid 248.889904 -60.052975)
		(end 248.84126 -59.856624)
		(width 0.0889)
		(layer "In2.Cu")
		(net "M_A_DQS_DN<8>")
	)
	(arc
		(start 248.471944 -58.65749)
		(mid 248.18652 -58.574023)
		(end 247.977914 -58.362088)
		(width 0.0889)
		(layer "In2.Cu")
		(net "M_A_DQS_DN<8>")
	)
	(arc
		(start 248.836434 -59.257438)
		(mid 248.840844 -58.864975)
		(end 248.507758 -58.65749)
		(width 0.0889)
		(layer "In2.Cu")
		(net "M_A_DQS_DN<8>")
	)
	(arc
		(start 247.977914 -58.362088)
		(mid 247.83917 -58.220055)
		(end 247.649238 -58.16219)
		(width 0.0889)
		(layer "In2.Cu")
		(net "M_A_DQS_DN<8>")
	)
	(arc
		(start 248.830084 -60.82792)
		(mid 248.757286 -60.537157)
		(end 248.836434 -60.248038)
		(width 0.0889)
		(layer "In2.Cu")
		(net "M_A_DQS_DN<8>")
	)
	(segment
		(start 311.999884 -20.023582)
		(end 312.000392 -20.023582)
		(width 0.1651)
		(layer "F.Cu")
		(net "M_A_DQS_DN<7>")
	)
	(segment
		(start 312.387996 -18.021046)
		(end 312.17235 -17.8054)
		(width 0.1651)
		(layer "F.Cu")
		(net "M_A_DQS_DN<7>")
	)
	(segment
		(start 312.17235 -17.8054)
		(end 311.948322 -17.8054)
		(width 0.1651)
		(layer "F.Cu")
		(net "M_A_DQS_DN<7>")
	)
	(segment
		(start 311.999884 -18.94967)
		(end 311.999884 -20.023582)
		(width 0.1651)
		(layer "F.Cu")
		(net "M_A_DQS_DN<7>")
	)
	(segment
		(start 287.50514 -57.390538)
		(end 286.93364 -57.390538)
		(width 0.1016)
		(layer "F.Cu")
		(net "M_A_DQS_DN<7>")
	)
	(segment
		(start 311.617868 -18.135854)
		(end 311.617868 -18.567654)
		(width 0.1651)
		(layer "F.Cu")
		(net "M_A_DQS_DN<7>")
	)
	(segment
		(start 311.617868 -18.567654)
		(end 311.999884 -18.94967)
		(width 0.1651)
		(layer "F.Cu")
		(net "M_A_DQS_DN<7>")
	)
	(segment
		(start 311.948322 -17.8054)
		(end 311.617868 -18.135854)
		(width 0.1651)
		(layer "F.Cu")
		(net "M_A_DQS_DN<7>")
	)
	(via
		(at 286.93364 -57.390538)
		(size 0.508)
		(drill 0.254)
		(layers "F.Cu" "B.Cu")
		(net "M_A_DQS_DN<7>")
	)
	(via
		(at 312.387996 -18.021046)
		(size 0.508)
		(drill 0.254)
		(layers "F.Cu" "B.Cu")
		(net "M_A_DQS_DN<7>")
	)
	(via
		(at 312.387996 -22.228556)
		(size 0.508)
		(drill 0.254)
		(layers "F.Cu" "B.Cu")
		(net "M_A_DQS_DN<7>")
	)
	(segment
		(start 311.617868 -21.767546)
		(end 311.871868 -21.513546)
		(width 0.1651)
		(layer "B.Cu")
		(net "M_A_DQS_DN<7>")
	)
	(segment
		(start 311.617868 -22.098)
		(end 311.617868 -21.767546)
		(width 0.1651)
		(layer "B.Cu")
		(net "M_A_DQS_DN<7>")
	)
	(segment
		(start 311.999884 -21.13153)
		(end 311.999884 -20.224242)
		(width 0.1651)
		(layer "B.Cu")
		(net "M_A_DQS_DN<7>")
	)
	(segment
		(start 312.162952 -22.4536)
		(end 311.973468 -22.4536)
		(width 0.1651)
		(layer "B.Cu")
		(net "M_A_DQS_DN<7>")
	)
	(segment
		(start 311.871868 -21.259546)
		(end 311.999884 -21.13153)
		(width 0.1651)
		(layer "B.Cu")
		(net "M_A_DQS_DN<7>")
	)
	(segment
		(start 312.387996 -22.228556)
		(end 312.162952 -22.4536)
		(width 0.1651)
		(layer "B.Cu")
		(net "M_A_DQS_DN<7>")
	)
	(segment
		(start 311.973468 -22.4536)
		(end 311.617868 -22.098)
		(width 0.1651)
		(layer "B.Cu")
		(net "M_A_DQS_DN<7>")
	)
	(segment
		(start 311.871868 -21.513546)
		(end 311.871868 -21.259546)
		(width 0.1651)
		(layer "B.Cu")
		(net "M_A_DQS_DN<7>")
	)
	(segment
		(start 311.999884 -20.224242)
		(end 312.000392 -20.224242)
		(width 0.1651)
		(layer "B.Cu")
		(net "M_A_DQS_DN<7>")
	)
	(segment
		(start 312.929524 -21.966174)
		(end 312.929524 -21.261324)
		(width 0.14224)
		(layer "In2.Cu")
		(net "M_A_DQS_DN<7>")
	)
	(segment
		(start 312.3946 -19.583146)
		(end 312.3946 -19.278854)
		(width 0.14224)
		(layer "In2.Cu")
		(net "M_A_DQS_DN<7>")
	)
	(segment
		(start 287.28035 -55.609236)
		(end 287.285176 -55.6006)
		(width 0.0889)
		(layer "In2.Cu")
		(net "M_A_DQS_DN<7>")
	)
	(segment
		(start 312.547254 -19.7358)
		(end 312.3946 -19.583146)
		(width 0.14224)
		(layer "In2.Cu")
		(net "M_A_DQS_DN<7>")
	)
	(segment
		(start 287.274 -56.610504)
		(end 287.28035 -56.599836)
		(width 0.0889)
		(layer "In2.Cu")
		(net "M_A_DQS_DN<7>")
	)
	(segment
		(start 312.42 -24.9428)
		(end 311.9501 -24.4729)
		(width 0.14224)
		(layer "In2.Cu")
		(net "M_A_DQS_DN<7>")
	)
	(segment
		(start 311.23255 -38.50005)
		(end 312.42 -37.3126)
		(width 0.14224)
		(layer "In2.Cu")
		(net "M_A_DQS_DN<7>")
	)
	(segment
		(start 312.387996 -22.22881)
		(end 312.666888 -22.22881)
		(width 0.14224)
		(layer "In2.Cu")
		(net "M_A_DQS_DN<7>")
	)
	(segment
		(start 286.93364 -57.390538)
		(end 286.93364 -57.728612)
		(width 0.0889)
		(layer "In2.Cu")
		(net "M_A_DQS_DN<7>")
	)
	(segment
		(start 312.3946 -19.278854)
		(end 312.547254 -19.1262)
		(width 0.14224)
		(layer "In2.Cu")
		(net "M_A_DQS_DN<7>")
	)
	(segment
		(start 294.084502 -47.135796)
		(end 295.332404 -47.135796)
		(width 0.14224)
		(layer "In2.Cu")
		(net "M_A_DQS_DN<7>")
	)
	(segment
		(start 296.7228 -45.7454)
		(end 301.371254 -45.7454)
		(width 0.14224)
		(layer "In2.Cu")
		(net "M_A_DQS_DN<7>")
	)
	(segment
		(start 312.619644 -21.082)
		(end 312.441844 -20.9042)
		(width 0.14224)
		(layer "In2.Cu")
		(net "M_A_DQS_DN<7>")
	)
	(segment
		(start 301.371254 -45.7454)
		(end 308.616604 -38.50005)
		(width 0.14224)
		(layer "In2.Cu")
		(net "M_A_DQS_DN<7>")
	)
	(segment
		(start 312.724546 -19.7358)
		(end 312.547254 -19.7358)
		(width 0.14224)
		(layer "In2.Cu")
		(net "M_A_DQS_DN<7>")
	)
	(segment
		(start 287.274 -55.619904)
		(end 287.28035 -55.609236)
		(width 0.0889)
		(layer "In2.Cu")
		(net "M_A_DQS_DN<7>")
	)
	(segment
		(start 312.7502 -21.082)
		(end 312.619644 -21.082)
		(width 0.14224)
		(layer "In2.Cu")
		(net "M_A_DQS_DN<7>")
	)
	(segment
		(start 312.749946 -19.1262)
		(end 312.929524 -18.946622)
		(width 0.14224)
		(layer "In2.Cu")
		(net "M_A_DQS_DN<7>")
	)
	(segment
		(start 287.28035 -57.590436)
		(end 287.285176 -57.5818)
		(width 0.0889)
		(layer "In2.Cu")
		(net "M_A_DQS_DN<7>")
	)
	(segment
		(start 288.36493 -52.911248)
		(end 289.505898 -51.77028)
		(width 0.0889)
		(layer "In2.Cu")
		(net "M_A_DQS_DN<7>")
	)
	(segment
		(start 312.669682 -18.021046)
		(end 312.387996 -18.021046)
		(width 0.14224)
		(layer "In2.Cu")
		(net "M_A_DQS_DN<7>")
	)
	(segment
		(start 312.929524 -19.940778)
		(end 312.724546 -19.7358)
		(width 0.14224)
		(layer "In2.Cu")
		(net "M_A_DQS_DN<7>")
	)
	(segment
		(start 311.9501 -22.666452)
		(end 312.387996 -22.228556)
		(width 0.14224)
		(layer "In2.Cu")
		(net "M_A_DQS_DN<7>")
	)
	(segment
		(start 289.505898 -51.77028)
		(end 289.505898 -51.7144)
		(width 0.0889)
		(layer "In2.Cu")
		(net "M_A_DQS_DN<7>")
	)
	(segment
		(start 312.387996 -22.228556)
		(end 312.387996 -22.22881)
		(width 0.14224)
		(layer "In2.Cu")
		(net "M_A_DQS_DN<7>")
	)
	(segment
		(start 312.42 -37.3126)
		(end 312.42 -24.9428)
		(width 0.14224)
		(layer "In2.Cu")
		(net "M_A_DQS_DN<7>")
	)
	(segment
		(start 295.332404 -47.135796)
		(end 296.7228 -45.7454)
		(width 0.14224)
		(layer "In2.Cu")
		(net "M_A_DQS_DN<7>")
	)
	(segment
		(start 312.441844 -20.6502)
		(end 312.619644 -20.4724)
		(width 0.14224)
		(layer "In2.Cu")
		(net "M_A_DQS_DN<7>")
	)
	(segment
		(start 286.93364 -57.728612)
		(end 286.991552 -57.786524)
		(width 0.0889)
		(layer "In2.Cu")
		(net "M_A_DQS_DN<7>")
	)
	(segment
		(start 312.929524 -18.280888)
		(end 312.669682 -18.021046)
		(width 0.14224)
		(layer "In2.Cu")
		(net "M_A_DQS_DN<7>")
	)
	(segment
		(start 312.929524 -18.946622)
		(end 312.929524 -18.280888)
		(width 0.14224)
		(layer "In2.Cu")
		(net "M_A_DQS_DN<7>")
	)
	(segment
		(start 312.619644 -20.4724)
		(end 312.746644 -20.4724)
		(width 0.14224)
		(layer "In2.Cu")
		(net "M_A_DQS_DN<7>")
	)
	(segment
		(start 287.77438 -54.323234)
		(end 287.807146 -54.323234)
		(width 0.0889)
		(layer "In2.Cu")
		(net "M_A_DQS_DN<7>")
	)
	(segment
		(start 289.521646 -51.698652)
		(end 294.084502 -47.135796)
		(width 0.14224)
		(layer "In2.Cu")
		(net "M_A_DQS_DN<7>")
	)
	(segment
		(start 312.441844 -20.9042)
		(end 312.441844 -20.6502)
		(width 0.14224)
		(layer "In2.Cu")
		(net "M_A_DQS_DN<7>")
	)
	(segment
		(start 311.9501 -24.4729)
		(end 311.9501 -22.666452)
		(width 0.14224)
		(layer "In2.Cu")
		(net "M_A_DQS_DN<7>")
	)
	(segment
		(start 289.505898 -51.7144)
		(end 289.521646 -51.698652)
		(width 0.0889)
		(layer "In2.Cu")
		(net "M_A_DQS_DN<7>")
	)
	(segment
		(start 288.364422 -52.911502)
		(end 288.36493 -52.911248)
		(width 0.0889)
		(layer "In2.Cu")
		(net "M_A_DQS_DN<7>")
	)
	(segment
		(start 312.547254 -19.1262)
		(end 312.749946 -19.1262)
		(width 0.14224)
		(layer "In2.Cu")
		(net "M_A_DQS_DN<7>")
	)
	(segment
		(start 312.929524 -20.28952)
		(end 312.929524 -19.940778)
		(width 0.14224)
		(layer "In2.Cu")
		(net "M_A_DQS_DN<7>")
	)
	(segment
		(start 287.28035 -56.599836)
		(end 287.285176 -56.5912)
		(width 0.0889)
		(layer "In2.Cu")
		(net "M_A_DQS_DN<7>")
	)
	(segment
		(start 308.616604 -38.50005)
		(end 311.23255 -38.50005)
		(width 0.14224)
		(layer "In2.Cu")
		(net "M_A_DQS_DN<7>")
	)
	(segment
		(start 312.666888 -22.22881)
		(end 312.929524 -21.966174)
		(width 0.14224)
		(layer "In2.Cu")
		(net "M_A_DQS_DN<7>")
	)
	(segment
		(start 312.746644 -20.4724)
		(end 312.929524 -20.28952)
		(width 0.14224)
		(layer "In2.Cu")
		(net "M_A_DQS_DN<7>")
	)
	(segment
		(start 312.929524 -21.261324)
		(end 312.7502 -21.082)
		(width 0.14224)
		(layer "In2.Cu")
		(net "M_A_DQS_DN<7>")
	)
	(arc
		(start 287.320736 -54.557676)
		(mid 287.520923 -54.388918)
		(end 287.77438 -54.323234)
		(width 0.0889)
		(layer "In2.Cu")
		(net "M_A_DQS_DN<7>")
	)
	(arc
		(start 287.28035 -55.209186)
		(mid 287.201389 -54.921204)
		(end 287.273238 -54.631336)
		(width 0.0889)
		(layer "In2.Cu")
		(net "M_A_DQS_DN<7>")
	)
	(arc
		(start 288.13887 -53.132482)
		(mid 288.236512 -53.006542)
		(end 288.364422 -52.911502)
		(width 0.0889)
		(layer "In2.Cu")
		(net "M_A_DQS_DN<7>")
	)
	(arc
		(start 287.28035 -56.199786)
		(mid 287.201128 -55.910668)
		(end 287.274 -55.619904)
		(width 0.0889)
		(layer "In2.Cu")
		(net "M_A_DQS_DN<7>")
	)
	(arc
		(start 287.285176 -56.5912)
		(mid 287.333931 -56.394848)
		(end 287.28035 -56.199786)
		(width 0.0889)
		(layer "In2.Cu")
		(net "M_A_DQS_DN<7>")
	)
	(arc
		(start 287.285176 -57.5818)
		(mid 287.333931 -57.385448)
		(end 287.28035 -57.190386)
		(width 0.0889)
		(layer "In2.Cu")
		(net "M_A_DQS_DN<7>")
	)
	(arc
		(start 286.991552 -57.786524)
		(mid 287.158453 -57.721624)
		(end 287.28035 -57.590436)
		(width 0.0889)
		(layer "In2.Cu")
		(net "M_A_DQS_DN<7>")
	)
	(arc
		(start 287.273238 -54.631336)
		(mid 287.295618 -54.593623)
		(end 287.320736 -54.557676)
		(width 0.0889)
		(layer "In2.Cu")
		(net "M_A_DQS_DN<7>")
	)
	(arc
		(start 288.143696 -53.731922)
		(mid 288.05974 -53.432864)
		(end 288.13887 -53.132482)
		(width 0.0889)
		(layer "In2.Cu")
		(net "M_A_DQS_DN<7>")
	)
	(arc
		(start 287.285176 -55.6006)
		(mid 287.333931 -55.404248)
		(end 287.28035 -55.209186)
		(width 0.0889)
		(layer "In2.Cu")
		(net "M_A_DQS_DN<7>")
	)
	(arc
		(start 287.28035 -57.190386)
		(mid 287.201128 -56.901268)
		(end 287.274 -56.610504)
		(width 0.0889)
		(layer "In2.Cu")
		(net "M_A_DQS_DN<7>")
	)
	(arc
		(start 287.807146 -54.323234)
		(mid 288.140064 -54.121243)
		(end 288.143696 -53.731922)
		(width 0.0889)
		(layer "In2.Cu")
		(net "M_A_DQS_DN<7>")
	)
	(segment
		(start 282.354274 -58.381138)
		(end 281.782774 -58.381138)
		(width 0.1016)
		(layer "F.Cu")
		(net "M_A_DQS_DN<6>")
	)
	(segment
		(start 302.598328 -17.8054)
		(end 302.822356 -17.8054)
		(width 0.1651)
		(layer "F.Cu")
		(net "M_A_DQS_DN<6>")
	)
	(segment
		(start 302.650398 -20.023582)
		(end 302.64989 -20.023582)
		(width 0.1651)
		(layer "F.Cu")
		(net "M_A_DQS_DN<6>")
	)
	(segment
		(start 302.267874 -18.135854)
		(end 302.598328 -17.8054)
		(width 0.1651)
		(layer "F.Cu")
		(net "M_A_DQS_DN<6>")
	)
	(segment
		(start 302.822356 -17.8054)
		(end 303.038002 -18.021046)
		(width 0.1651)
		(layer "F.Cu")
		(net "M_A_DQS_DN<6>")
	)
	(segment
		(start 302.64989 -20.023582)
		(end 302.64989 -18.94967)
		(width 0.1651)
		(layer "F.Cu")
		(net "M_A_DQS_DN<6>")
	)
	(segment
		(start 302.267874 -18.567654)
		(end 302.267874 -18.135854)
		(width 0.1651)
		(layer "F.Cu")
		(net "M_A_DQS_DN<6>")
	)
	(segment
		(start 302.64989 -18.94967)
		(end 302.267874 -18.567654)
		(width 0.1651)
		(layer "F.Cu")
		(net "M_A_DQS_DN<6>")
	)
	(via
		(at 303.038002 -18.021046)
		(size 0.508)
		(drill 0.254)
		(layers "F.Cu" "B.Cu")
		(net "M_A_DQS_DN<6>")
	)
	(via
		(at 281.782774 -58.381138)
		(size 0.508)
		(drill 0.254)
		(layers "F.Cu" "B.Cu")
		(net "M_A_DQS_DN<6>")
	)
	(via
		(at 303.038002 -22.228556)
		(size 0.508)
		(drill 0.254)
		(layers "F.Cu" "B.Cu")
		(net "M_A_DQS_DN<6>")
	)
	(segment
		(start 302.64989 -21.13153)
		(end 302.521874 -21.259546)
		(width 0.1651)
		(layer "B.Cu")
		(net "M_A_DQS_DN<6>")
	)
	(segment
		(start 302.812958 -22.4536)
		(end 302.980852 -22.285452)
		(width 0.1651)
		(layer "B.Cu")
		(net "M_A_DQS_DN<6>")
	)
	(segment
		(start 302.267874 -21.767546)
		(end 302.267874 -22.098)
		(width 0.1651)
		(layer "B.Cu")
		(net "M_A_DQS_DN<6>")
	)
	(segment
		(start 302.650398 -20.224242)
		(end 302.64989 -20.224242)
		(width 0.1651)
		(layer "B.Cu")
		(net "M_A_DQS_DN<6>")
	)
	(segment
		(start 302.980852 -22.285452)
		(end 303.038002 -22.228556)
		(width 0.1651)
		(layer "B.Cu")
		(net "M_A_DQS_DN<6>")
	)
	(segment
		(start 302.267874 -22.098)
		(end 302.623474 -22.4536)
		(width 0.1651)
		(layer "B.Cu")
		(net "M_A_DQS_DN<6>")
	)
	(segment
		(start 302.623474 -22.4536)
		(end 302.812958 -22.4536)
		(width 0.1651)
		(layer "B.Cu")
		(net "M_A_DQS_DN<6>")
	)
	(segment
		(start 302.521874 -21.259546)
		(end 302.521874 -21.513546)
		(width 0.1651)
		(layer "B.Cu")
		(net "M_A_DQS_DN<6>")
	)
	(segment
		(start 302.64989 -20.224242)
		(end 302.64989 -21.13153)
		(width 0.1651)
		(layer "B.Cu")
		(net "M_A_DQS_DN<6>")
	)
	(segment
		(start 302.521874 -21.513546)
		(end 302.267874 -21.767546)
		(width 0.1651)
		(layer "B.Cu")
		(net "M_A_DQS_DN<6>")
	)
	(segment
		(start 303.038002 -22.228556)
		(end 303.038002 -22.22881)
		(width 0.14224)
		(layer "In2.Cu")
		(net "M_A_DQS_DN<6>")
	)
	(segment
		(start 303.19726 -19.7358)
		(end 303.044606 -19.583146)
		(width 0.14224)
		(layer "In2.Cu")
		(net "M_A_DQS_DN<6>")
	)
	(segment
		(start 302.980852 -22.285452)
		(end 303.038002 -22.228556)
		(width 0.14224)
		(layer "In2.Cu")
		(net "M_A_DQS_DN<6>")
	)
	(segment
		(start 303.044606 -19.583146)
		(end 303.044606 -19.278854)
		(width 0.14224)
		(layer "In2.Cu")
		(net "M_A_DQS_DN<6>")
	)
	(segment
		(start 303.57953 -21.966174)
		(end 303.57953 -21.261324)
		(width 0.14224)
		(layer "In2.Cu")
		(net "M_A_DQS_DN<6>")
	)
	(segment
		(start 303.09185 -20.9042)
		(end 303.09185 -20.6502)
		(width 0.14224)
		(layer "In2.Cu")
		(net "M_A_DQS_DN<6>")
	)
	(segment
		(start 303.57953 -18.946622)
		(end 303.57953 -18.280888)
		(width 0.14224)
		(layer "In2.Cu")
		(net "M_A_DQS_DN<6>")
	)
	(segment
		(start 303.044606 -19.278854)
		(end 303.19726 -19.1262)
		(width 0.14224)
		(layer "In2.Cu")
		(net "M_A_DQS_DN<6>")
	)
	(segment
		(start 303.399952 -19.1262)
		(end 303.57953 -18.946622)
		(width 0.14224)
		(layer "In2.Cu")
		(net "M_A_DQS_DN<6>")
	)
	(segment
		(start 281.782774 -58.043064)
		(end 281.717496 -57.977786)
		(width 0.0889)
		(layer "In2.Cu")
		(net "M_A_DQS_DN<6>")
	)
	(segment
		(start 302.592486 -24.631904)
		(end 302.592486 -22.674072)
		(width 0.14224)
		(layer "In2.Cu")
		(net "M_A_DQS_DN<6>")
	)
	(segment
		(start 282.482544 -48.47717)
		(end 282.443174 -48.4378)
		(width 0.0889)
		(layer "In2.Cu")
		(net "M_A_DQS_DN<6>")
	)
	(segment
		(start 282.443174 -48.415702)
		(end 282.443174 -43.64228)
		(width 0.14224)
		(layer "In2.Cu")
		(net "M_A_DQS_DN<6>")
	)
	(segment
		(start 303.553876 -25.593294)
		(end 302.592486 -24.631904)
		(width 0.14224)
		(layer "In2.Cu")
		(net "M_A_DQS_DN<6>")
	)
	(segment
		(start 303.374552 -19.7358)
		(end 303.19726 -19.7358)
		(width 0.14224)
		(layer "In2.Cu")
		(net "M_A_DQS_DN<6>")
	)
	(segment
		(start 297.5102 -36.7284)
		(end 303.553876 -30.684724)
		(width 0.14224)
		(layer "In2.Cu")
		(net "M_A_DQS_DN<6>")
	)
	(segment
		(start 282.14193 -51.42484)
		(end 281.9781 -51.26101)
		(width 0.0889)
		(layer "In2.Cu")
		(net "M_A_DQS_DN<6>")
	)
	(segment
		(start 281.761184 -56.799988)
		(end 281.79395 -56.799988)
		(width 0.0889)
		(layer "In2.Cu")
		(net "M_A_DQS_DN<6>")
	)
	(segment
		(start 282.482544 -49.403762)
		(end 282.482544 -48.47717)
		(width 0.0889)
		(layer "In2.Cu")
		(net "M_A_DQS_DN<6>")
	)
	(segment
		(start 303.400206 -21.082)
		(end 303.26965 -21.082)
		(width 0.14224)
		(layer "In2.Cu")
		(net "M_A_DQS_DN<6>")
	)
	(segment
		(start 302.592486 -22.674072)
		(end 302.980852 -22.285452)
		(width 0.14224)
		(layer "In2.Cu")
		(net "M_A_DQS_DN<6>")
	)
	(segment
		(start 303.57953 -20.28952)
		(end 303.57953 -19.940778)
		(width 0.14224)
		(layer "In2.Cu")
		(net "M_A_DQS_DN<6>")
	)
	(segment
		(start 281.9781 -51.26101)
		(end 281.9781 -50.853594)
		(width 0.0889)
		(layer "In2.Cu")
		(net "M_A_DQS_DN<6>")
	)
	(segment
		(start 282.14193 -54.109874)
		(end 282.14193 -51.42484)
		(width 0.0889)
		(layer "In2.Cu")
		(net "M_A_DQS_DN<6>")
	)
	(segment
		(start 303.26965 -21.082)
		(end 303.09185 -20.9042)
		(width 0.14224)
		(layer "In2.Cu")
		(net "M_A_DQS_DN<6>")
	)
	(segment
		(start 281.7495 -50.624994)
		(end 281.7495 -50.136806)
		(width 0.0889)
		(layer "In2.Cu")
		(net "M_A_DQS_DN<6>")
	)
	(segment
		(start 303.19726 -19.1262)
		(end 303.399952 -19.1262)
		(width 0.14224)
		(layer "In2.Cu")
		(net "M_A_DQS_DN<6>")
	)
	(segment
		(start 303.39665 -20.4724)
		(end 303.57953 -20.28952)
		(width 0.14224)
		(layer "In2.Cu")
		(net "M_A_DQS_DN<6>")
	)
	(segment
		(start 282.260294 -54.393338)
		(end 282.260294 -54.228238)
		(width 0.0889)
		(layer "In2.Cu")
		(net "M_A_DQS_DN<6>")
	)
	(segment
		(start 282.443174 -43.64228)
		(end 289.357054 -36.7284)
		(width 0.14224)
		(layer "In2.Cu")
		(net "M_A_DQS_DN<6>")
	)
	(segment
		(start 303.09185 -20.6502)
		(end 303.26965 -20.4724)
		(width 0.14224)
		(layer "In2.Cu")
		(net "M_A_DQS_DN<6>")
	)
	(segment
		(start 303.038002 -22.22881)
		(end 303.316894 -22.22881)
		(width 0.14224)
		(layer "In2.Cu")
		(net "M_A_DQS_DN<6>")
	)
	(segment
		(start 281.9781 -50.853594)
		(end 281.7495 -50.624994)
		(width 0.0889)
		(layer "In2.Cu")
		(net "M_A_DQS_DN<6>")
	)
	(segment
		(start 281.7495 -50.136806)
		(end 282.482544 -49.403762)
		(width 0.0889)
		(layer "In2.Cu")
		(net "M_A_DQS_DN<6>")
	)
	(segment
		(start 303.57953 -21.261324)
		(end 303.400206 -21.082)
		(width 0.14224)
		(layer "In2.Cu")
		(net "M_A_DQS_DN<6>")
	)
	(segment
		(start 282.260294 -54.228238)
		(end 282.14193 -54.109874)
		(width 0.0889)
		(layer "In2.Cu")
		(net "M_A_DQS_DN<6>")
	)
	(segment
		(start 282.443174 -48.4378)
		(end 282.443174 -48.415702)
		(width 0.0889)
		(layer "In2.Cu")
		(net "M_A_DQS_DN<6>")
	)
	(segment
		(start 303.553876 -30.684724)
		(end 303.553876 -25.593294)
		(width 0.14224)
		(layer "In2.Cu")
		(net "M_A_DQS_DN<6>")
	)
	(segment
		(start 281.782774 -58.381138)
		(end 281.782774 -58.043064)
		(width 0.0889)
		(layer "In2.Cu")
		(net "M_A_DQS_DN<6>")
	)
	(segment
		(start 289.357054 -36.7284)
		(end 297.5102 -36.7284)
		(width 0.14224)
		(layer "In2.Cu")
		(net "M_A_DQS_DN<6>")
	)
	(segment
		(start 281.270964 -57.685686)
		(end 281.264614 -57.675018)
		(width 0.0889)
		(layer "In2.Cu")
		(net "M_A_DQS_DN<6>")
	)
	(segment
		(start 303.57953 -19.940778)
		(end 303.374552 -19.7358)
		(width 0.14224)
		(layer "In2.Cu")
		(net "M_A_DQS_DN<6>")
	)
	(segment
		(start 282.129484 -54.618636)
		(end 282.260294 -54.393338)
		(width 0.0889)
		(layer "In2.Cu")
		(net "M_A_DQS_DN<6>")
	)
	(segment
		(start 303.26965 -20.4724)
		(end 303.39665 -20.4724)
		(width 0.14224)
		(layer "In2.Cu")
		(net "M_A_DQS_DN<6>")
	)
	(segment
		(start 303.319688 -18.021046)
		(end 303.038002 -18.021046)
		(width 0.14224)
		(layer "In2.Cu")
		(net "M_A_DQS_DN<6>")
	)
	(segment
		(start 303.57953 -18.280888)
		(end 303.319688 -18.021046)
		(width 0.14224)
		(layer "In2.Cu")
		(net "M_A_DQS_DN<6>")
	)
	(segment
		(start 303.316894 -22.22881)
		(end 303.57953 -21.966174)
		(width 0.14224)
		(layer "In2.Cu")
		(net "M_A_DQS_DN<6>")
	)
	(arc
		(start 281.717496 -57.977786)
		(mid 281.459359 -57.885032)
		(end 281.270964 -57.685686)
		(width 0.0889)
		(layer "In2.Cu")
		(net "M_A_DQS_DN<6>")
	)
	(arc
		(start 282.129484 -56.20004)
		(mid 282.050353 -55.904638)
		(end 282.129484 -55.609236)
		(width 0.0889)
		(layer "In2.Cu")
		(net "M_A_DQS_DN<6>")
	)
	(arc
		(start 281.270964 -57.095136)
		(mid 281.477968 -56.884272)
		(end 281.761184 -56.799988)
		(width 0.0889)
		(layer "In2.Cu")
		(net "M_A_DQS_DN<6>")
	)
	(arc
		(start 281.79395 -56.799988)
		(mid 282.132065 -56.595286)
		(end 282.129484 -56.20004)
		(width 0.0889)
		(layer "In2.Cu")
		(net "M_A_DQS_DN<6>")
	)
	(arc
		(start 282.129484 -55.20944)
		(mid 282.050353 -54.914038)
		(end 282.129484 -54.618636)
		(width 0.0889)
		(layer "In2.Cu")
		(net "M_A_DQS_DN<6>")
	)
	(arc
		(start 281.264614 -57.675018)
		(mid 281.191816 -57.384255)
		(end 281.270964 -57.095136)
		(width 0.0889)
		(layer "In2.Cu")
		(net "M_A_DQS_DN<6>")
	)
	(arc
		(start 282.129484 -55.609236)
		(mid 282.182983 -55.409338)
		(end 282.129484 -55.20944)
		(width 0.0889)
		(layer "In2.Cu")
		(net "M_A_DQS_DN<6>")
	)
	(segment
		(start 293.248334 -17.8054)
		(end 293.472362 -17.8054)
		(width 0.1651)
		(layer "F.Cu")
		(net "M_A_DQS_DN<5>")
	)
	(segment
		(start 293.299896 -18.94967)
		(end 292.91788 -18.567654)
		(width 0.1651)
		(layer "F.Cu")
		(net "M_A_DQS_DN<5>")
	)
	(segment
		(start 293.300404 -20.023582)
		(end 293.299896 -20.023582)
		(width 0.1651)
		(layer "F.Cu")
		(net "M_A_DQS_DN<5>")
	)
	(segment
		(start 277.203154 -58.381138)
		(end 276.631654 -58.381138)
		(width 0.1016)
		(layer "F.Cu")
		(net "M_A_DQS_DN<5>")
	)
	(segment
		(start 292.91788 -18.567654)
		(end 292.91788 -18.135854)
		(width 0.1651)
		(layer "F.Cu")
		(net "M_A_DQS_DN<5>")
	)
	(segment
		(start 293.472362 -17.8054)
		(end 293.688008 -18.021046)
		(width 0.1651)
		(layer "F.Cu")
		(net "M_A_DQS_DN<5>")
	)
	(segment
		(start 292.91788 -18.135854)
		(end 293.248334 -17.8054)
		(width 0.1651)
		(layer "F.Cu")
		(net "M_A_DQS_DN<5>")
	)
	(segment
		(start 293.299896 -20.023582)
		(end 293.299896 -18.94967)
		(width 0.1651)
		(layer "F.Cu")
		(net "M_A_DQS_DN<5>")
	)
	(via
		(at 293.688008 -22.228556)
		(size 0.508)
		(drill 0.254)
		(layers "F.Cu" "B.Cu")
		(net "M_A_DQS_DN<5>")
	)
	(via
		(at 293.688008 -18.021046)
		(size 0.508)
		(drill 0.254)
		(layers "F.Cu" "B.Cu")
		(net "M_A_DQS_DN<5>")
	)
	(via
		(at 276.631654 -58.381138)
		(size 0.508)
		(drill 0.254)
		(layers "F.Cu" "B.Cu")
		(net "M_A_DQS_DN<5>")
	)
	(segment
		(start 293.27348 -22.4536)
		(end 293.462964 -22.4536)
		(width 0.1651)
		(layer "B.Cu")
		(net "M_A_DQS_DN<5>")
	)
	(segment
		(start 293.299896 -21.13153)
		(end 293.17188 -21.259546)
		(width 0.1651)
		(layer "B.Cu")
		(net "M_A_DQS_DN<5>")
	)
	(segment
		(start 293.17188 -21.513546)
		(end 292.91788 -21.767546)
		(width 0.1651)
		(layer "B.Cu")
		(net "M_A_DQS_DN<5>")
	)
	(segment
		(start 292.91788 -21.767546)
		(end 292.91788 -22.098)
		(width 0.1651)
		(layer "B.Cu")
		(net "M_A_DQS_DN<5>")
	)
	(segment
		(start 293.462964 -22.4536)
		(end 293.688008 -22.228556)
		(width 0.1651)
		(layer "B.Cu")
		(net "M_A_DQS_DN<5>")
	)
	(segment
		(start 293.300404 -20.224242)
		(end 293.299896 -20.224242)
		(width 0.1651)
		(layer "B.Cu")
		(net "M_A_DQS_DN<5>")
	)
	(segment
		(start 293.299896 -20.224242)
		(end 293.299896 -21.13153)
		(width 0.1651)
		(layer "B.Cu")
		(net "M_A_DQS_DN<5>")
	)
	(segment
		(start 292.91788 -22.098)
		(end 293.27348 -22.4536)
		(width 0.1651)
		(layer "B.Cu")
		(net "M_A_DQS_DN<5>")
	)
	(segment
		(start 293.17188 -21.259546)
		(end 293.17188 -21.513546)
		(width 0.1651)
		(layer "B.Cu")
		(net "M_A_DQS_DN<5>")
	)
	(segment
		(start 293.847266 -19.7358)
		(end 293.694612 -19.583146)
		(width 0.14224)
		(layer "In2.Cu")
		(net "M_A_DQS_DN<5>")
	)
	(segment
		(start 293.242492 -24.697436)
		(end 293.242492 -22.674072)
		(width 0.14224)
		(layer "In2.Cu")
		(net "M_A_DQS_DN<5>")
	)
	(segment
		(start 294.050212 -21.082)
		(end 293.919656 -21.082)
		(width 0.14224)
		(layer "In2.Cu")
		(net "M_A_DQS_DN<5>")
	)
	(segment
		(start 274.908772 -47.102268)
		(end 274.891754 -47.08525)
		(width 0.0889)
		(layer "In2.Cu")
		(net "M_A_DQS_DN<5>")
	)
	(segment
		(start 275.888958 -52.009548)
		(end 275.888958 -50.299366)
		(width 0.0889)
		(layer "In2.Cu")
		(net "M_A_DQS_DN<5>")
	)
	(segment
		(start 293.688008 -22.228556)
		(end 293.688008 -22.22881)
		(width 0.14224)
		(layer "In2.Cu")
		(net "M_A_DQS_DN<5>")
	)
	(segment
		(start 293.919656 -20.4724)
		(end 294.046656 -20.4724)
		(width 0.14224)
		(layer "In2.Cu")
		(net "M_A_DQS_DN<5>")
	)
	(segment
		(start 292.564566 -29.2608)
		(end 292.89248 -28.932886)
		(width 0.14224)
		(layer "In2.Cu")
		(net "M_A_DQS_DN<5>")
	)
	(segment
		(start 294.229536 -18.946622)
		(end 294.229536 -18.280888)
		(width 0.14224)
		(layer "In2.Cu")
		(net "M_A_DQS_DN<5>")
	)
	(segment
		(start 293.919656 -21.082)
		(end 293.741856 -20.9042)
		(width 0.14224)
		(layer "In2.Cu")
		(net "M_A_DQS_DN<5>")
	)
	(segment
		(start 294.229536 -18.280888)
		(end 293.969694 -18.021046)
		(width 0.14224)
		(layer "In2.Cu")
		(net "M_A_DQS_DN<5>")
	)
	(segment
		(start 293.741856 -20.9042)
		(end 293.741856 -20.6502)
		(width 0.14224)
		(layer "In2.Cu")
		(net "M_A_DQS_DN<5>")
	)
	(segment
		(start 274.908772 -49.31918)
		(end 274.908772 -47.102268)
		(width 0.0889)
		(layer "In2.Cu")
		(net "M_A_DQS_DN<5>")
	)
	(segment
		(start 274.880578 -47.08525)
		(end 274.869402 -47.074074)
		(width 0.0889)
		(layer "In2.Cu")
		(net "M_A_DQS_DN<5>")
	)
	(segment
		(start 293.847266 -19.1262)
		(end 294.049958 -19.1262)
		(width 0.14224)
		(layer "In2.Cu")
		(net "M_A_DQS_DN<5>")
	)
	(segment
		(start 274.869402 -47.062898)
		(end 274.869402 -37.575744)
		(width 0.14224)
		(layer "In2.Cu")
		(net "M_A_DQS_DN<5>")
	)
	(segment
		(start 277.039324 -54.51348)
		(end 277.039324 -53.159914)
		(width 0.0889)
		(layer "In2.Cu")
		(net "M_A_DQS_DN<5>")
	)
	(segment
		(start 292.89248 -25.047448)
		(end 293.242492 -24.697436)
		(width 0.14224)
		(layer "In2.Cu")
		(net "M_A_DQS_DN<5>")
	)
	(segment
		(start 293.969694 -18.021046)
		(end 293.688008 -18.021046)
		(width 0.14224)
		(layer "In2.Cu")
		(net "M_A_DQS_DN<5>")
	)
	(segment
		(start 293.741856 -20.6502)
		(end 293.919656 -20.4724)
		(width 0.14224)
		(layer "In2.Cu")
		(net "M_A_DQS_DN<5>")
	)
	(segment
		(start 276.610064 -56.799988)
		(end 276.64283 -56.799988)
		(width 0.0889)
		(layer "In2.Cu")
		(net "M_A_DQS_DN<5>")
	)
	(segment
		(start 274.891754 -47.08525)
		(end 274.880578 -47.08525)
		(width 0.0889)
		(layer "In2.Cu")
		(net "M_A_DQS_DN<5>")
	)
	(segment
		(start 276.978364 -55.20944)
		(end 276.97811 -55.208932)
		(width 0.0889)
		(layer "In2.Cu")
		(net "M_A_DQS_DN<5>")
	)
	(segment
		(start 277.039324 -53.159914)
		(end 275.888958 -52.009548)
		(width 0.0889)
		(layer "In2.Cu")
		(net "M_A_DQS_DN<5>")
	)
	(segment
		(start 294.049958 -19.1262)
		(end 294.229536 -18.946622)
		(width 0.14224)
		(layer "In2.Cu")
		(net "M_A_DQS_DN<5>")
	)
	(segment
		(start 293.688008 -22.22881)
		(end 293.9669 -22.22881)
		(width 0.14224)
		(layer "In2.Cu")
		(net "M_A_DQS_DN<5>")
	)
	(segment
		(start 293.694612 -19.583146)
		(end 293.694612 -19.278854)
		(width 0.14224)
		(layer "In2.Cu")
		(net "M_A_DQS_DN<5>")
	)
	(segment
		(start 293.694612 -19.278854)
		(end 293.847266 -19.1262)
		(width 0.14224)
		(layer "In2.Cu")
		(net "M_A_DQS_DN<5>")
	)
	(segment
		(start 294.229536 -21.966174)
		(end 294.229536 -21.261324)
		(width 0.14224)
		(layer "In2.Cu")
		(net "M_A_DQS_DN<5>")
	)
	(segment
		(start 292.89248 -28.932886)
		(end 292.89248 -25.047448)
		(width 0.14224)
		(layer "In2.Cu")
		(net "M_A_DQS_DN<5>")
	)
	(segment
		(start 294.229536 -21.261324)
		(end 294.050212 -21.082)
		(width 0.14224)
		(layer "In2.Cu")
		(net "M_A_DQS_DN<5>")
	)
	(segment
		(start 275.888958 -50.299366)
		(end 274.908772 -49.31918)
		(width 0.0889)
		(layer "In2.Cu")
		(net "M_A_DQS_DN<5>")
	)
	(segment
		(start 276.978364 -54.61889)
		(end 277.039324 -54.51348)
		(width 0.0889)
		(layer "In2.Cu")
		(net "M_A_DQS_DN<5>")
	)
	(segment
		(start 293.9669 -22.22881)
		(end 294.229536 -21.966174)
		(width 0.14224)
		(layer "In2.Cu")
		(net "M_A_DQS_DN<5>")
	)
	(segment
		(start 294.229536 -20.28952)
		(end 294.229536 -19.940778)
		(width 0.14224)
		(layer "In2.Cu")
		(net "M_A_DQS_DN<5>")
	)
	(segment
		(start 293.242492 -22.674072)
		(end 293.688008 -22.228556)
		(width 0.14224)
		(layer "In2.Cu")
		(net "M_A_DQS_DN<5>")
	)
	(segment
		(start 274.869402 -47.074074)
		(end 274.869402 -47.062898)
		(width 0.0889)
		(layer "In2.Cu")
		(net "M_A_DQS_DN<5>")
	)
	(segment
		(start 294.024558 -19.7358)
		(end 293.847266 -19.7358)
		(width 0.14224)
		(layer "In2.Cu")
		(net "M_A_DQS_DN<5>")
	)
	(segment
		(start 294.046656 -20.4724)
		(end 294.229536 -20.28952)
		(width 0.14224)
		(layer "In2.Cu")
		(net "M_A_DQS_DN<5>")
	)
	(segment
		(start 274.869402 -37.575744)
		(end 283.184346 -29.2608)
		(width 0.14224)
		(layer "In2.Cu")
		(net "M_A_DQS_DN<5>")
	)
	(segment
		(start 294.229536 -19.940778)
		(end 294.024558 -19.7358)
		(width 0.14224)
		(layer "In2.Cu")
		(net "M_A_DQS_DN<5>")
	)
	(segment
		(start 283.184346 -29.2608)
		(end 292.564566 -29.2608)
		(width 0.14224)
		(layer "In2.Cu")
		(net "M_A_DQS_DN<5>")
	)
	(arc
		(start 276.64283 -56.799988)
		(mid 276.980945 -56.595286)
		(end 276.978364 -56.20004)
		(width 0.0889)
		(layer "In2.Cu")
		(net "M_A_DQS_DN<5>")
	)
	(arc
		(start 276.97811 -55.208932)
		(mid 276.919242 -55.066677)
		(end 276.899116 -54.914038)
		(width 0.0889)
		(layer "In2.Cu")
		(net "M_A_DQS_DN<5>")
	)
	(arc
		(start 276.197822 -57.791604)
		(mid 276.086114 -57.16371)
		(end 276.610064 -56.799988)
		(width 0.0889)
		(layer "In2.Cu")
		(net "M_A_DQS_DN<5>")
	)
	(arc
		(start 276.978364 -56.20004)
		(mid 276.899233 -55.904638)
		(end 276.978364 -55.609236)
		(width 0.0889)
		(layer "In2.Cu")
		(net "M_A_DQS_DN<5>")
	)
	(arc
		(start 276.899116 -54.914038)
		(mid 276.919347 -54.76126)
		(end 276.978364 -54.61889)
		(width 0.0889)
		(layer "In2.Cu")
		(net "M_A_DQS_DN<5>")
	)
	(arc
		(start 276.631654 -58.381138)
		(mid 276.43122 -58.074242)
		(end 276.197822 -57.791604)
		(width 0.0889)
		(layer "In2.Cu")
		(net "M_A_DQS_DN<5>")
	)
	(arc
		(start 276.978364 -55.609236)
		(mid 277.031863 -55.409338)
		(end 276.978364 -55.20944)
		(width 0.0889)
		(layer "In2.Cu")
		(net "M_A_DQS_DN<5>")
	)
	(segment
		(start 274.16887 -51.469798)
		(end 274.16887 -51.465226)
		(width 0.0889)
		(layer "F.Cu")
		(net "M_A_DQS_DN<4>")
	)
	(segment
		(start 283.88183 -22.684486)
		(end 283.88183 -23.94077)
		(width 0.1651)
		(layer "F.Cu")
		(net "M_A_DQS_DN<4>")
	)
	(segment
		(start 283.95041 -20.023582)
		(end 283.95041 -18.950432)
		(width 0.1651)
		(layer "F.Cu")
		(net "M_A_DQS_DN<4>")
	)
	(segment
		(start 273.984974 -50.91303)
		(end 273.984974 -49.8856)
		(width 0.0889)
		(layer "F.Cu")
		(net "M_A_DQS_DN<4>")
	)
	(segment
		(start 283.567632 -18.135854)
		(end 283.898086 -17.8054)
		(width 0.1651)
		(layer "F.Cu")
		(net "M_A_DQS_DN<4>")
	)
	(segment
		(start 284.33776 -22.228556)
		(end 283.88183 -22.684486)
		(width 0.1651)
		(layer "F.Cu")
		(net "M_A_DQS_DN<4>")
	)
	(segment
		(start 283.95041 -18.950432)
		(end 283.567632 -18.567654)
		(width 0.1651)
		(layer "F.Cu")
		(net "M_A_DQS_DN<4>")
	)
	(segment
		(start 283.39288 -24.42972)
		(end 283.39288 -29.796232)
		(width 0.1651)
		(layer "F.Cu")
		(net "M_A_DQS_DN<4>")
	)
	(segment
		(start 274.15998 -39.029132)
		(end 274.15998 -40.32504)
		(width 0.1651)
		(layer "F.Cu")
		(net "M_A_DQS_DN<4>")
	)
	(segment
		(start 283.567632 -18.567654)
		(end 283.567632 -18.135854)
		(width 0.1651)
		(layer "F.Cu")
		(net "M_A_DQS_DN<4>")
	)
	(segment
		(start 273.984974 -40.500046)
		(end 273.984974 -43.1419)
		(width 0.1016)
		(layer "F.Cu")
		(net "M_A_DQS_DN<4>")
	)
	(segment
		(start 283.898086 -17.8054)
		(end 284.122114 -17.8054)
		(width 0.1651)
		(layer "F.Cu")
		(net "M_A_DQS_DN<4>")
	)
	(segment
		(start 283.88183 -23.94077)
		(end 283.39288 -24.42972)
		(width 0.1651)
		(layer "F.Cu")
		(net "M_A_DQS_DN<4>")
	)
	(segment
		(start 273.984974 -49.8856)
		(end 273.984974 -43.1419)
		(width 0.1016)
		(layer "F.Cu")
		(net "M_A_DQS_DN<4>")
	)
	(segment
		(start 273.747738 -52.837334)
		(end 273.769328 -52.837334)
		(width 0.0889)
		(layer "F.Cu")
		(net "M_A_DQS_DN<4>")
	)
	(segment
		(start 274.067778 -51.053746)
		(end 273.984974 -50.91303)
		(width 0.0889)
		(layer "F.Cu")
		(net "M_A_DQS_DN<4>")
	)
	(segment
		(start 281.743912 -31.4452)
		(end 274.15998 -39.029132)
		(width 0.1651)
		(layer "F.Cu")
		(net "M_A_DQS_DN<4>")
	)
	(segment
		(start 284.122114 -17.8054)
		(end 284.33776 -18.021046)
		(width 0.1651)
		(layer "F.Cu")
		(net "M_A_DQS_DN<4>")
	)
	(segment
		(start 274.15998 -40.32504)
		(end 273.984974 -40.500046)
		(width 0.1016)
		(layer "F.Cu")
		(net "M_A_DQS_DN<4>")
	)
	(segment
		(start 283.39288 -29.796232)
		(end 281.743912 -31.4452)
		(width 0.1651)
		(layer "F.Cu")
		(net "M_A_DQS_DN<4>")
	)
	(via
		(at 284.33776 -22.228556)
		(size 0.508)
		(drill 0.254)
		(layers "F.Cu" "B.Cu")
		(net "M_A_DQS_DN<4>")
	)
	(via
		(at 281.743912 -31.4452)
		(size 0.508)
		(drill 0.254)
		(layers "F.Cu" "B.Cu")
		(net "M_A_DQS_DN<4>")
	)
	(via
		(at 284.33776 -18.021046)
		(size 0.508)
		(drill 0.254)
		(layers "F.Cu" "B.Cu")
		(net "M_A_DQS_DN<4>")
	)
	(arc
		(start 274.16887 -51.465226)
		(mid 274.148306 -51.252125)
		(end 274.067778 -51.053746)
		(width 0.0889)
		(layer "F.Cu")
		(net "M_A_DQS_DN<4>")
	)
	(arc
		(start 273.322542 -53.041296)
		(mid 273.513907 -52.895037)
		(end 273.747738 -52.837334)
		(width 0.0889)
		(layer "F.Cu")
		(net "M_A_DQS_DN<4>")
	)
	(arc
		(start 273.769328 -54.418738)
		(mid 273.54714 -54.104616)
		(end 273.311112 -53.800756)
		(width 0.0889)
		(layer "F.Cu")
		(net "M_A_DQS_DN<4>")
	)
	(arc
		(start 273.311112 -53.800756)
		(mid 273.178694 -53.418957)
		(end 273.322542 -53.041296)
		(width 0.0889)
		(layer "F.Cu")
		(net "M_A_DQS_DN<4>")
	)
	(arc
		(start 273.769328 -52.837334)
		(mid 274.115754 -52.637357)
		(end 274.115784 -52.237386)
		(width 0.0889)
		(layer "F.Cu")
		(net "M_A_DQS_DN<4>")
	)
	(arc
		(start 274.115784 -51.646582)
		(mid 274.152682 -51.561297)
		(end 274.16887 -51.469798)
		(width 0.0889)
		(layer "F.Cu")
		(net "M_A_DQS_DN<4>")
	)
	(arc
		(start 274.115784 -52.237386)
		(mid 274.036653 -51.941984)
		(end 274.115784 -51.646582)
		(width 0.0889)
		(layer "F.Cu")
		(net "M_A_DQS_DN<4>")
	)
	(segment
		(start 283.821632 -21.513546)
		(end 283.567632 -21.767546)
		(width 0.1651)
		(layer "B.Cu")
		(net "M_A_DQS_DN<4>")
	)
	(segment
		(start 283.923232 -22.4536)
		(end 284.112716 -22.4536)
		(width 0.1651)
		(layer "B.Cu")
		(net "M_A_DQS_DN<4>")
	)
	(segment
		(start 284.112716 -22.4536)
		(end 284.33776 -22.228556)
		(width 0.1651)
		(layer "B.Cu")
		(net "M_A_DQS_DN<4>")
	)
	(segment
		(start 283.949902 -20.224242)
		(end 283.949902 -21.131276)
		(width 0.1651)
		(layer "B.Cu")
		(net "M_A_DQS_DN<4>")
	)
	(segment
		(start 283.567632 -22.098)
		(end 283.923232 -22.4536)
		(width 0.1651)
		(layer "B.Cu")
		(net "M_A_DQS_DN<4>")
	)
	(segment
		(start 283.95041 -20.224242)
		(end 283.949902 -20.224242)
		(width 0.1651)
		(layer "B.Cu")
		(net "M_A_DQS_DN<4>")
	)
	(segment
		(start 283.567632 -21.767546)
		(end 283.567632 -22.098)
		(width 0.1651)
		(layer "B.Cu")
		(net "M_A_DQS_DN<4>")
	)
	(segment
		(start 283.821632 -21.259546)
		(end 283.821632 -21.513546)
		(width 0.1651)
		(layer "B.Cu")
		(net "M_A_DQS_DN<4>")
	)
	(segment
		(start 283.949902 -21.131276)
		(end 283.821632 -21.259546)
		(width 0.1651)
		(layer "B.Cu")
		(net "M_A_DQS_DN<4>")
	)
	(segment
		(start 284.391608 -20.6502)
		(end 284.569408 -20.4724)
		(width 0.14224)
		(layer "In2.Cu")
		(net "M_A_DQS_DN<4>")
	)
	(segment
		(start 284.616652 -22.22881)
		(end 284.879288 -21.966174)
		(width 0.14224)
		(layer "In2.Cu")
		(net "M_A_DQS_DN<4>")
	)
	(segment
		(start 284.879288 -20.28952)
		(end 284.879288 -19.940778)
		(width 0.14224)
		(layer "In2.Cu")
		(net "M_A_DQS_DN<4>")
	)
	(segment
		(start 284.879288 -18.280888)
		(end 284.619446 -18.021046)
		(width 0.14224)
		(layer "In2.Cu")
		(net "M_A_DQS_DN<4>")
	)
	(segment
		(start 284.569408 -21.082)
		(end 284.391608 -20.9042)
		(width 0.14224)
		(layer "In2.Cu")
		(net "M_A_DQS_DN<4>")
	)
	(segment
		(start 284.33776 -22.22881)
		(end 284.616652 -22.22881)
		(width 0.14224)
		(layer "In2.Cu")
		(net "M_A_DQS_DN<4>")
	)
	(segment
		(start 284.497018 -19.7358)
		(end 284.344364 -19.583146)
		(width 0.14224)
		(layer "In2.Cu")
		(net "M_A_DQS_DN<4>")
	)
	(segment
		(start 284.391608 -20.9042)
		(end 284.391608 -20.6502)
		(width 0.14224)
		(layer "In2.Cu")
		(net "M_A_DQS_DN<4>")
	)
	(segment
		(start 284.33776 -22.228556)
		(end 284.33776 -22.22881)
		(width 0.14224)
		(layer "In2.Cu")
		(net "M_A_DQS_DN<4>")
	)
	(segment
		(start 284.344364 -19.583146)
		(end 284.344364 -19.278854)
		(width 0.14224)
		(layer "In2.Cu")
		(net "M_A_DQS_DN<4>")
	)
	(segment
		(start 284.619446 -18.021046)
		(end 284.33776 -18.021046)
		(width 0.14224)
		(layer "In2.Cu")
		(net "M_A_DQS_DN<4>")
	)
	(segment
		(start 284.696408 -20.4724)
		(end 284.879288 -20.28952)
		(width 0.14224)
		(layer "In2.Cu")
		(net "M_A_DQS_DN<4>")
	)
	(segment
		(start 284.879288 -21.261324)
		(end 284.699964 -21.082)
		(width 0.14224)
		(layer "In2.Cu")
		(net "M_A_DQS_DN<4>")
	)
	(segment
		(start 284.879288 -21.966174)
		(end 284.879288 -21.261324)
		(width 0.14224)
		(layer "In2.Cu")
		(net "M_A_DQS_DN<4>")
	)
	(segment
		(start 284.67431 -19.7358)
		(end 284.497018 -19.7358)
		(width 0.14224)
		(layer "In2.Cu")
		(net "M_A_DQS_DN<4>")
	)
	(segment
		(start 284.69971 -19.1262)
		(end 284.879288 -18.946622)
		(width 0.14224)
		(layer "In2.Cu")
		(net "M_A_DQS_DN<4>")
	)
	(segment
		(start 284.344364 -19.278854)
		(end 284.497018 -19.1262)
		(width 0.14224)
		(layer "In2.Cu")
		(net "M_A_DQS_DN<4>")
	)
	(segment
		(start 284.569408 -20.4724)
		(end 284.696408 -20.4724)
		(width 0.14224)
		(layer "In2.Cu")
		(net "M_A_DQS_DN<4>")
	)
	(segment
		(start 284.879288 -19.940778)
		(end 284.67431 -19.7358)
		(width 0.14224)
		(layer "In2.Cu")
		(net "M_A_DQS_DN<4>")
	)
	(segment
		(start 284.699964 -21.082)
		(end 284.569408 -21.082)
		(width 0.14224)
		(layer "In2.Cu")
		(net "M_A_DQS_DN<4>")
	)
	(segment
		(start 284.879288 -18.946622)
		(end 284.879288 -18.280888)
		(width 0.14224)
		(layer "In2.Cu")
		(net "M_A_DQS_DN<4>")
	)
	(segment
		(start 284.497018 -19.1262)
		(end 284.69971 -19.1262)
		(width 0.14224)
		(layer "In2.Cu")
		(net "M_A_DQS_DN<4>")
	)
	(segment
		(start 228.699822 -20.023582)
		(end 228.699822 -18.94967)
		(width 0.1651)
		(layer "F.Cu")
		(net "M_A_DQS_DN<3>")
	)
	(segment
		(start 228.64826 -17.8054)
		(end 228.872288 -17.8054)
		(width 0.1651)
		(layer "F.Cu")
		(net "M_A_DQS_DN<3>")
	)
	(segment
		(start 242.193318 -57.076086)
		(end 241.621818 -57.076086)
		(width 0.1016)
		(layer "F.Cu")
		(net "M_A_DQS_DN<3>")
	)
	(segment
		(start 228.317806 -18.135854)
		(end 228.64826 -17.8054)
		(width 0.1651)
		(layer "F.Cu")
		(net "M_A_DQS_DN<3>")
	)
	(segment
		(start 228.317806 -18.567654)
		(end 228.317806 -18.135854)
		(width 0.1651)
		(layer "F.Cu")
		(net "M_A_DQS_DN<3>")
	)
	(segment
		(start 228.872288 -17.8054)
		(end 229.087934 -18.021046)
		(width 0.1651)
		(layer "F.Cu")
		(net "M_A_DQS_DN<3>")
	)
	(segment
		(start 228.699822 -18.94967)
		(end 228.317806 -18.567654)
		(width 0.1651)
		(layer "F.Cu")
		(net "M_A_DQS_DN<3>")
	)
	(segment
		(start 228.70033 -20.023582)
		(end 228.699822 -20.023582)
		(width 0.1651)
		(layer "F.Cu")
		(net "M_A_DQS_DN<3>")
	)
	(via
		(at 229.087934 -22.228556)
		(size 0.508)
		(drill 0.254)
		(layers "F.Cu" "B.Cu")
		(net "M_A_DQS_DN<3>")
	)
	(via
		(at 241.621818 -57.076086)
		(size 0.508)
		(drill 0.254)
		(layers "F.Cu" "B.Cu")
		(net "M_A_DQS_DN<3>")
	)
	(via
		(at 229.087934 -18.021046)
		(size 0.508)
		(drill 0.254)
		(layers "F.Cu" "B.Cu")
		(net "M_A_DQS_DN<3>")
	)
	(segment
		(start 228.86289 -22.4536)
		(end 229.087934 -22.228556)
		(width 0.1651)
		(layer "B.Cu")
		(net "M_A_DQS_DN<3>")
	)
	(segment
		(start 228.571806 -21.259546)
		(end 228.571806 -21.513546)
		(width 0.1651)
		(layer "B.Cu")
		(net "M_A_DQS_DN<3>")
	)
	(segment
		(start 228.699822 -21.13153)
		(end 228.571806 -21.259546)
		(width 0.1651)
		(layer "B.Cu")
		(net "M_A_DQS_DN<3>")
	)
	(segment
		(start 228.70033 -20.224242)
		(end 228.699822 -20.224242)
		(width 0.1651)
		(layer "B.Cu")
		(net "M_A_DQS_DN<3>")
	)
	(segment
		(start 228.699822 -20.224242)
		(end 228.699822 -21.13153)
		(width 0.1651)
		(layer "B.Cu")
		(net "M_A_DQS_DN<3>")
	)
	(segment
		(start 228.317806 -22.098)
		(end 228.673406 -22.4536)
		(width 0.1651)
		(layer "B.Cu")
		(net "M_A_DQS_DN<3>")
	)
	(segment
		(start 228.317806 -21.767546)
		(end 228.317806 -22.098)
		(width 0.1651)
		(layer "B.Cu")
		(net "M_A_DQS_DN<3>")
	)
	(segment
		(start 228.673406 -22.4536)
		(end 228.86289 -22.4536)
		(width 0.1651)
		(layer "B.Cu")
		(net "M_A_DQS_DN<3>")
	)
	(segment
		(start 228.571806 -21.513546)
		(end 228.317806 -21.767546)
		(width 0.1651)
		(layer "B.Cu")
		(net "M_A_DQS_DN<3>")
	)
	(segment
		(start 229.614476 -25.440132)
		(end 228.769418 -24.595074)
		(width 0.14224)
		(layer "In2.Cu")
		(net "M_A_DQS_DN<3>")
	)
	(segment
		(start 229.141782 -20.9042)
		(end 229.141782 -20.6502)
		(width 0.14224)
		(layer "In2.Cu")
		(net "M_A_DQS_DN<3>")
	)
	(segment
		(start 241.973354 -53.913024)
		(end 241.968528 -53.904388)
		(width 0.0889)
		(layer "In2.Cu")
		(net "M_A_DQS_DN<3>")
	)
	(segment
		(start 237.597442 -49.449482)
		(end 237.597442 -49.097438)
		(width 0.14224)
		(layer "In2.Cu")
		(net "M_A_DQS_DN<3>")
	)
	(segment
		(start 241.604038 -55.494936)
		(end 241.636804 -55.494936)
		(width 0.0889)
		(layer "In2.Cu")
		(net "M_A_DQS_DN<3>")
	)
	(segment
		(start 240.778284 -52.21859)
		(end 240.745518 -52.21859)
		(width 0.0889)
		(layer "In2.Cu")
		(net "M_A_DQS_DN<3>")
	)
	(segment
		(start 229.247192 -19.7358)
		(end 229.094538 -19.583146)
		(width 0.14224)
		(layer "In2.Cu")
		(net "M_A_DQS_DN<3>")
	)
	(segment
		(start 239.915954 -51.723036)
		(end 239.883188 -51.723036)
		(width 0.0889)
		(layer "In2.Cu")
		(net "M_A_DQS_DN<3>")
	)
	(segment
		(start 241.621818 -57.076086)
		(end 241.621818 -56.738012)
		(width 0.0889)
		(layer "In2.Cu")
		(net "M_A_DQS_DN<3>")
	)
	(segment
		(start 241.632994 -52.713636)
		(end 241.600228 -52.713636)
		(width 0.0889)
		(layer "In2.Cu")
		(net "M_A_DQS_DN<3>")
	)
	(segment
		(start 229.629462 -21.261324)
		(end 229.450138 -21.082)
		(width 0.14224)
		(layer "In2.Cu")
		(net "M_A_DQS_DN<3>")
	)
	(segment
		(start 229.141782 -20.6502)
		(end 229.319582 -20.4724)
		(width 0.14224)
		(layer "In2.Cu")
		(net "M_A_DQS_DN<3>")
	)
	(segment
		(start 239.061244 -51.22799)
		(end 239.028478 -51.22799)
		(width 0.0889)
		(layer "In2.Cu")
		(net "M_A_DQS_DN<3>")
	)
	(segment
		(start 241.621818 -56.738012)
		(end 241.556794 -56.672988)
		(width 0.0889)
		(layer "In2.Cu")
		(net "M_A_DQS_DN<3>")
	)
	(segment
		(start 229.087934 -22.228556)
		(end 229.087934 -22.22881)
		(width 0.14224)
		(layer "In2.Cu")
		(net "M_A_DQS_DN<3>")
	)
	(segment
		(start 237.636812 -49.488852)
		(end 237.597442 -49.449482)
		(width 0.0889)
		(layer "In2.Cu")
		(net "M_A_DQS_DN<3>")
	)
	(segment
		(start 228.650038 -23.900638)
		(end 228.650038 -22.666452)
		(width 0.14224)
		(layer "In2.Cu")
		(net "M_A_DQS_DN<3>")
	)
	(segment
		(start 229.247192 -19.1262)
		(end 229.449884 -19.1262)
		(width 0.14224)
		(layer "In2.Cu")
		(net "M_A_DQS_DN<3>")
	)
	(segment
		(start 229.449884 -19.1262)
		(end 229.629462 -18.946622)
		(width 0.14224)
		(layer "In2.Cu")
		(net "M_A_DQS_DN<3>")
	)
	(segment
		(start 229.094538 -19.583146)
		(end 229.094538 -19.278854)
		(width 0.14224)
		(layer "In2.Cu")
		(net "M_A_DQS_DN<3>")
	)
	(segment
		(start 228.769418 -24.595074)
		(end 228.769418 -24.020018)
		(width 0.14224)
		(layer "In2.Cu")
		(net "M_A_DQS_DN<3>")
	)
	(segment
		(start 241.968528 -53.904388)
		(end 241.962178 -53.89372)
		(width 0.0889)
		(layer "In2.Cu")
		(net "M_A_DQS_DN<3>")
	)
	(segment
		(start 229.450138 -21.082)
		(end 229.319582 -21.082)
		(width 0.14224)
		(layer "In2.Cu")
		(net "M_A_DQS_DN<3>")
	)
	(segment
		(start 229.629462 -19.940778)
		(end 229.424484 -19.7358)
		(width 0.14224)
		(layer "In2.Cu")
		(net "M_A_DQS_DN<3>")
	)
	(segment
		(start 229.446582 -20.4724)
		(end 229.629462 -20.28952)
		(width 0.14224)
		(layer "In2.Cu")
		(net "M_A_DQS_DN<3>")
	)
	(segment
		(start 229.319582 -20.4724)
		(end 229.446582 -20.4724)
		(width 0.14224)
		(layer "In2.Cu")
		(net "M_A_DQS_DN<3>")
	)
	(segment
		(start 229.319582 -21.082)
		(end 229.141782 -20.9042)
		(width 0.14224)
		(layer "In2.Cu")
		(net "M_A_DQS_DN<3>")
	)
	(segment
		(start 237.597442 -49.097438)
		(end 229.614476 -41.114472)
		(width 0.14224)
		(layer "In2.Cu")
		(net "M_A_DQS_DN<3>")
	)
	(segment
		(start 238.198914 -50.732436)
		(end 238.166148 -50.732436)
		(width 0.0889)
		(layer "In2.Cu")
		(net "M_A_DQS_DN<3>")
	)
	(segment
		(start 241.968528 -54.894988)
		(end 241.962178 -54.88432)
		(width 0.0889)
		(layer "In2.Cu")
		(net "M_A_DQS_DN<3>")
	)
	(segment
		(start 241.973354 -54.903624)
		(end 241.968528 -54.894988)
		(width 0.0889)
		(layer "In2.Cu")
		(net "M_A_DQS_DN<3>")
	)
	(segment
		(start 229.629462 -18.280888)
		(end 229.36962 -18.021046)
		(width 0.14224)
		(layer "In2.Cu")
		(net "M_A_DQS_DN<3>")
	)
	(segment
		(start 228.650038 -22.666452)
		(end 229.087934 -22.228556)
		(width 0.14224)
		(layer "In2.Cu")
		(net "M_A_DQS_DN<3>")
	)
	(segment
		(start 229.629462 -18.946622)
		(end 229.629462 -18.280888)
		(width 0.14224)
		(layer "In2.Cu")
		(net "M_A_DQS_DN<3>")
	)
	(segment
		(start 229.424484 -19.7358)
		(end 229.247192 -19.7358)
		(width 0.14224)
		(layer "In2.Cu")
		(net "M_A_DQS_DN<3>")
	)
	(segment
		(start 229.094538 -19.278854)
		(end 229.247192 -19.1262)
		(width 0.14224)
		(layer "In2.Cu")
		(net "M_A_DQS_DN<3>")
	)
	(segment
		(start 237.636812 -50.291238)
		(end 237.636812 -49.488852)
		(width 0.0889)
		(layer "In2.Cu")
		(net "M_A_DQS_DN<3>")
	)
	(segment
		(start 229.614476 -41.114472)
		(end 229.614476 -25.440132)
		(width 0.14224)
		(layer "In2.Cu")
		(net "M_A_DQS_DN<3>")
	)
	(segment
		(start 229.366826 -22.22881)
		(end 229.629462 -21.966174)
		(width 0.14224)
		(layer "In2.Cu")
		(net "M_A_DQS_DN<3>")
	)
	(segment
		(start 228.769418 -24.020018)
		(end 228.650038 -23.900638)
		(width 0.14224)
		(layer "In2.Cu")
		(net "M_A_DQS_DN<3>")
	)
	(segment
		(start 229.629462 -21.966174)
		(end 229.629462 -21.261324)
		(width 0.14224)
		(layer "In2.Cu")
		(net "M_A_DQS_DN<3>")
	)
	(segment
		(start 229.36962 -18.021046)
		(end 229.087934 -18.021046)
		(width 0.14224)
		(layer "In2.Cu")
		(net "M_A_DQS_DN<3>")
	)
	(segment
		(start 229.629462 -20.28952)
		(end 229.629462 -19.940778)
		(width 0.14224)
		(layer "In2.Cu")
		(net "M_A_DQS_DN<3>")
	)
	(segment
		(start 229.087934 -22.22881)
		(end 229.366826 -22.22881)
		(width 0.14224)
		(layer "In2.Cu")
		(net "M_A_DQS_DN<3>")
	)
	(arc
		(start 238.534448 -50.932588)
		(mid 238.392765 -50.788784)
		(end 238.198914 -50.732436)
		(width 0.0889)
		(layer "In2.Cu")
		(net "M_A_DQS_DN<3>")
	)
	(arc
		(start 241.968528 -54.304438)
		(mid 242.021998 -54.109375)
		(end 241.973354 -53.913024)
		(width 0.0889)
		(layer "In2.Cu")
		(net "M_A_DQS_DN<3>")
	)
	(arc
		(start 241.556794 -56.672988)
		(mid 241.031456 -56.062056)
		(end 241.604038 -55.494936)
		(width 0.0889)
		(layer "In2.Cu")
		(net "M_A_DQS_DN<3>")
	)
	(arc
		(start 241.962178 -53.89372)
		(mid 241.88938 -53.602957)
		(end 241.968528 -53.313838)
		(width 0.0889)
		(layer "In2.Cu")
		(net "M_A_DQS_DN<3>")
	)
	(arc
		(start 241.110008 -52.418488)
		(mid 240.969929 -52.275752)
		(end 240.778284 -52.21859)
		(width 0.0889)
		(layer "In2.Cu")
		(net "M_A_DQS_DN<3>")
	)
	(arc
		(start 238.166148 -50.732436)
		(mid 237.882931 -50.648155)
		(end 237.675928 -50.437288)
		(width 0.0889)
		(layer "In2.Cu")
		(net "M_A_DQS_DN<3>")
	)
	(arc
		(start 240.251488 -51.923188)
		(mid 240.109805 -51.779384)
		(end 239.915954 -51.723036)
		(width 0.0889)
		(layer "In2.Cu")
		(net "M_A_DQS_DN<3>")
	)
	(arc
		(start 240.745518 -52.21859)
		(mid 240.460094 -52.135123)
		(end 240.251488 -51.923188)
		(width 0.0889)
		(layer "In2.Cu")
		(net "M_A_DQS_DN<3>")
	)
	(arc
		(start 241.600228 -52.713636)
		(mid 241.317011 -52.629355)
		(end 241.110008 -52.418488)
		(width 0.0889)
		(layer "In2.Cu")
		(net "M_A_DQS_DN<3>")
	)
	(arc
		(start 241.636804 -55.494936)
		(mid 241.969722 -55.292945)
		(end 241.973354 -54.903624)
		(width 0.0889)
		(layer "In2.Cu")
		(net "M_A_DQS_DN<3>")
	)
	(arc
		(start 241.968528 -53.313838)
		(mid 241.971276 -52.918371)
		(end 241.632994 -52.713636)
		(width 0.0889)
		(layer "In2.Cu")
		(net "M_A_DQS_DN<3>")
	)
	(arc
		(start 239.392968 -51.427888)
		(mid 239.252889 -51.285152)
		(end 239.061244 -51.22799)
		(width 0.0889)
		(layer "In2.Cu")
		(net "M_A_DQS_DN<3>")
	)
	(arc
		(start 239.883188 -51.723036)
		(mid 239.599971 -51.638755)
		(end 239.392968 -51.427888)
		(width 0.0889)
		(layer "In2.Cu")
		(net "M_A_DQS_DN<3>")
	)
	(arc
		(start 241.962178 -54.88432)
		(mid 241.88938 -54.593557)
		(end 241.968528 -54.304438)
		(width 0.0889)
		(layer "In2.Cu")
		(net "M_A_DQS_DN<3>")
	)
	(arc
		(start 239.028478 -51.22799)
		(mid 238.743054 -51.144523)
		(end 238.534448 -50.932588)
		(width 0.0889)
		(layer "In2.Cu")
		(net "M_A_DQS_DN<3>")
	)
	(arc
		(start 237.675928 -50.437288)
		(mid 237.646774 -50.366834)
		(end 237.636812 -50.291238)
		(width 0.0889)
		(layer "In2.Cu")
		(net "M_A_DQS_DN<3>")
	)
	(segment
		(start 218.967812 -18.567654)
		(end 218.967812 -18.135854)
		(width 0.1651)
		(layer "F.Cu")
		(net "M_A_DQS_DN<2>")
	)
	(segment
		(start 219.349828 -18.94967)
		(end 218.967812 -18.567654)
		(width 0.1651)
		(layer "F.Cu")
		(net "M_A_DQS_DN<2>")
	)
	(segment
		(start 219.350336 -20.023582)
		(end 219.349828 -20.023582)
		(width 0.1651)
		(layer "F.Cu")
		(net "M_A_DQS_DN<2>")
	)
	(segment
		(start 219.349828 -20.023582)
		(end 219.349828 -18.94967)
		(width 0.1651)
		(layer "F.Cu")
		(net "M_A_DQS_DN<2>")
	)
	(segment
		(start 218.967812 -18.135854)
		(end 219.298266 -17.8054)
		(width 0.1651)
		(layer "F.Cu")
		(net "M_A_DQS_DN<2>")
	)
	(segment
		(start 219.522294 -17.8054)
		(end 219.73794 -18.021046)
		(width 0.1651)
		(layer "F.Cu")
		(net "M_A_DQS_DN<2>")
	)
	(segment
		(start 238.759238 -56.085486)
		(end 238.187738 -56.085486)
		(width 0.1016)
		(layer "F.Cu")
		(net "M_A_DQS_DN<2>")
	)
	(segment
		(start 219.298266 -17.8054)
		(end 219.522294 -17.8054)
		(width 0.1651)
		(layer "F.Cu")
		(net "M_A_DQS_DN<2>")
	)
	(via
		(at 238.187738 -56.085486)
		(size 0.508)
		(drill 0.254)
		(layers "F.Cu" "B.Cu")
		(net "M_A_DQS_DN<2>")
	)
	(via
		(at 219.73794 -22.228556)
		(size 0.508)
		(drill 0.254)
		(layers "F.Cu" "B.Cu")
		(net "M_A_DQS_DN<2>")
	)
	(via
		(at 219.73794 -18.021046)
		(size 0.508)
		(drill 0.254)
		(layers "F.Cu" "B.Cu")
		(net "M_A_DQS_DN<2>")
	)
	(segment
		(start 219.512896 -22.4536)
		(end 219.73794 -22.228556)
		(width 0.1651)
		(layer "B.Cu")
		(net "M_A_DQS_DN<2>")
	)
	(segment
		(start 219.323412 -22.4536)
		(end 219.512896 -22.4536)
		(width 0.1651)
		(layer "B.Cu")
		(net "M_A_DQS_DN<2>")
	)
	(segment
		(start 219.349828 -21.13153)
		(end 219.221812 -21.259546)
		(width 0.1651)
		(layer "B.Cu")
		(net "M_A_DQS_DN<2>")
	)
	(segment
		(start 219.349828 -20.224242)
		(end 219.349828 -21.13153)
		(width 0.1651)
		(layer "B.Cu")
		(net "M_A_DQS_DN<2>")
	)
	(segment
		(start 219.221812 -21.513546)
		(end 218.967812 -21.767546)
		(width 0.1651)
		(layer "B.Cu")
		(net "M_A_DQS_DN<2>")
	)
	(segment
		(start 218.967812 -22.098)
		(end 219.323412 -22.4536)
		(width 0.1651)
		(layer "B.Cu")
		(net "M_A_DQS_DN<2>")
	)
	(segment
		(start 219.350336 -20.224242)
		(end 219.349828 -20.224242)
		(width 0.1651)
		(layer "B.Cu")
		(net "M_A_DQS_DN<2>")
	)
	(segment
		(start 218.967812 -21.767546)
		(end 218.967812 -22.098)
		(width 0.1651)
		(layer "B.Cu")
		(net "M_A_DQS_DN<2>")
	)
	(segment
		(start 219.221812 -21.259546)
		(end 219.221812 -21.513546)
		(width 0.1651)
		(layer "B.Cu")
		(net "M_A_DQS_DN<2>")
	)
	(segment
		(start 220.279468 -21.966174)
		(end 220.279468 -21.261324)
		(width 0.14224)
		(layer "In2.Cu")
		(net "M_A_DQS_DN<2>")
	)
	(segment
		(start 220.09989 -19.1262)
		(end 220.279468 -18.946622)
		(width 0.14224)
		(layer "In2.Cu")
		(net "M_A_DQS_DN<2>")
	)
	(segment
		(start 219.154248 -30.2006)
		(end 219.154248 -29.213048)
		(width 0.14224)
		(layer "In2.Cu")
		(net "M_A_DQS_DN<2>")
	)
	(segment
		(start 219.154248 -37.532056)
		(end 218.93276 -37.310568)
		(width 0.14224)
		(layer "In2.Cu")
		(net "M_A_DQS_DN<2>")
	)
	(segment
		(start 237.346998 -57.17159)
		(end 237.311438 -57.17159)
		(width 0.0889)
		(layer "In2.Cu")
		(net "M_A_DQS_DN<2>")
	)
	(segment
		(start 219.969588 -20.4724)
		(end 220.096588 -20.4724)
		(width 0.14224)
		(layer "In2.Cu")
		(net "M_A_DQS_DN<2>")
	)
	(segment
		(start 220.096588 -20.4724)
		(end 220.279468 -20.28952)
		(width 0.14224)
		(layer "In2.Cu")
		(net "M_A_DQS_DN<2>")
	)
	(segment
		(start 219.154248 -34.839656)
		(end 218.93276 -34.618168)
		(width 0.14224)
		(layer "In2.Cu")
		(net "M_A_DQS_DN<2>")
	)
	(segment
		(start 219.744544 -19.278854)
		(end 219.897198 -19.1262)
		(width 0.14224)
		(layer "In2.Cu")
		(net "M_A_DQS_DN<2>")
	)
	(segment
		(start 218.959176 -24.567134)
		(end 219.300044 -24.226266)
		(width 0.14224)
		(layer "In2.Cu")
		(net "M_A_DQS_DN<2>")
	)
	(segment
		(start 220.279468 -19.940778)
		(end 220.07449 -19.7358)
		(width 0.14224)
		(layer "In2.Cu")
		(net "M_A_DQS_DN<2>")
	)
	(segment
		(start 219.897198 -19.7358)
		(end 219.744544 -19.583146)
		(width 0.14224)
		(layer "In2.Cu")
		(net "M_A_DQS_DN<2>")
	)
	(segment
		(start 234.235752 -56.676036)
		(end 232.99293 -55.433214)
		(width 0.0889)
		(layer "In2.Cu")
		(net "M_A_DQS_DN<2>")
	)
	(segment
		(start 218.93276 -35.695128)
		(end 219.154248 -35.47364)
		(width 0.14224)
		(layer "In2.Cu")
		(net "M_A_DQS_DN<2>")
	)
	(segment
		(start 218.392248 -33.610296)
		(end 219.154248 -32.848296)
		(width 0.14224)
		(layer "In2.Cu")
		(net "M_A_DQS_DN<2>")
	)
	(segment
		(start 219.897198 -19.1262)
		(end 220.09989 -19.1262)
		(width 0.14224)
		(layer "In2.Cu")
		(net "M_A_DQS_DN<2>")
	)
	(segment
		(start 218.770454 -37.310568)
		(end 218.316048 -36.856162)
		(width 0.14224)
		(layer "In2.Cu")
		(net "M_A_DQS_DN<2>")
	)
	(segment
		(start 219.791788 -20.6502)
		(end 219.969588 -20.4724)
		(width 0.14224)
		(layer "In2.Cu")
		(net "M_A_DQS_DN<2>")
	)
	(segment
		(start 218.316048 -36.073334)
		(end 218.694254 -35.695128)
		(width 0.14224)
		(layer "In2.Cu")
		(net "M_A_DQS_DN<2>")
	)
	(segment
		(start 219.154248 -32.848296)
		(end 219.154248 -32.1056)
		(width 0.14224)
		(layer "In2.Cu")
		(net "M_A_DQS_DN<2>")
	)
	(segment
		(start 232.427526 -55.472584)
		(end 231.80802 -55.472584)
		(width 0.14224)
		(layer "In2.Cu")
		(net "M_A_DQS_DN<2>")
	)
	(segment
		(start 232.99293 -55.433214)
		(end 232.488994 -55.433214)
		(width 0.0889)
		(layer "In2.Cu")
		(net "M_A_DQS_DN<2>")
	)
	(segment
		(start 236.470952 -56.676036)
		(end 236.470444 -56.676036)
		(width 0.0889)
		(layer "In2.Cu")
		(net "M_A_DQS_DN<2>")
	)
	(segment
		(start 219.154248 -42.818812)
		(end 219.154248 -37.532056)
		(width 0.14224)
		(layer "In2.Cu")
		(net "M_A_DQS_DN<2>")
	)
	(segment
		(start 219.154248 -32.1056)
		(end 218.5924 -31.543752)
		(width 0.14224)
		(layer "In2.Cu")
		(net "M_A_DQS_DN<2>")
	)
	(segment
		(start 219.791788 -20.9042)
		(end 219.791788 -20.6502)
		(width 0.14224)
		(layer "In2.Cu")
		(net "M_A_DQS_DN<2>")
	)
	(segment
		(start 220.279468 -21.261324)
		(end 220.100144 -21.082)
		(width 0.14224)
		(layer "In2.Cu")
		(net "M_A_DQS_DN<2>")
	)
	(segment
		(start 236.817408 -56.876188)
		(end 236.817154 -56.876188)
		(width 0.0889)
		(layer "In2.Cu")
		(net "M_A_DQS_DN<2>")
	)
	(segment
		(start 220.07449 -19.7358)
		(end 219.897198 -19.7358)
		(width 0.14224)
		(layer "In2.Cu")
		(net "M_A_DQS_DN<2>")
	)
	(segment
		(start 232.449624 -55.472584)
		(end 232.427526 -55.472584)
		(width 0.0889)
		(layer "In2.Cu")
		(net "M_A_DQS_DN<2>")
	)
	(segment
		(start 219.154248 -35.47364)
		(end 219.154248 -34.839656)
		(width 0.14224)
		(layer "In2.Cu")
		(net "M_A_DQS_DN<2>")
	)
	(segment
		(start 220.279468 -18.946622)
		(end 220.279468 -18.280888)
		(width 0.14224)
		(layer "In2.Cu")
		(net "M_A_DQS_DN<2>")
	)
	(segment
		(start 219.300044 -22.666452)
		(end 219.73794 -22.228556)
		(width 0.14224)
		(layer "In2.Cu")
		(net "M_A_DQS_DN<2>")
	)
	(segment
		(start 235.612432 -57.17159)
		(end 235.61167 -57.17159)
		(width 0.0889)
		(layer "In2.Cu")
		(net "M_A_DQS_DN<2>")
	)
	(segment
		(start 218.794838 -34.618168)
		(end 218.392248 -34.215578)
		(width 0.14224)
		(layer "In2.Cu")
		(net "M_A_DQS_DN<2>")
	)
	(segment
		(start 218.694254 -35.695128)
		(end 218.93276 -35.695128)
		(width 0.14224)
		(layer "In2.Cu")
		(net "M_A_DQS_DN<2>")
	)
	(segment
		(start 219.154248 -29.213048)
		(end 218.959176 -29.017976)
		(width 0.14224)
		(layer "In2.Cu")
		(net "M_A_DQS_DN<2>")
	)
	(segment
		(start 220.279468 -18.280888)
		(end 220.019626 -18.021046)
		(width 0.14224)
		(layer "In2.Cu")
		(net "M_A_DQS_DN<2>")
	)
	(segment
		(start 218.5924 -30.762448)
		(end 219.154248 -30.2006)
		(width 0.14224)
		(layer "In2.Cu")
		(net "M_A_DQS_DN<2>")
	)
	(segment
		(start 234.764834 -56.676036)
		(end 234.235752 -56.676036)
		(width 0.0889)
		(layer "In2.Cu")
		(net "M_A_DQS_DN<2>")
	)
	(segment
		(start 231.80802 -55.472584)
		(end 219.154248 -42.818812)
		(width 0.14224)
		(layer "In2.Cu")
		(net "M_A_DQS_DN<2>")
	)
	(segment
		(start 218.392248 -34.215578)
		(end 218.392248 -33.610296)
		(width 0.14224)
		(layer "In2.Cu")
		(net "M_A_DQS_DN<2>")
	)
	(segment
		(start 220.279468 -20.28952)
		(end 220.279468 -19.940778)
		(width 0.14224)
		(layer "In2.Cu")
		(net "M_A_DQS_DN<2>")
	)
	(segment
		(start 219.300044 -24.226266)
		(end 219.300044 -22.666452)
		(width 0.14224)
		(layer "In2.Cu")
		(net "M_A_DQS_DN<2>")
	)
	(segment
		(start 220.019626 -18.021046)
		(end 219.73794 -18.021046)
		(width 0.14224)
		(layer "In2.Cu")
		(net "M_A_DQS_DN<2>")
	)
	(segment
		(start 219.969588 -21.082)
		(end 219.791788 -20.9042)
		(width 0.14224)
		(layer "In2.Cu")
		(net "M_A_DQS_DN<2>")
	)
	(segment
		(start 218.316048 -36.856162)
		(end 218.316048 -36.073334)
		(width 0.14224)
		(layer "In2.Cu")
		(net "M_A_DQS_DN<2>")
	)
	(segment
		(start 219.73794 -22.22881)
		(end 220.016832 -22.22881)
		(width 0.14224)
		(layer "In2.Cu")
		(net "M_A_DQS_DN<2>")
	)
	(segment
		(start 218.93276 -34.618168)
		(end 218.794838 -34.618168)
		(width 0.14224)
		(layer "In2.Cu")
		(net "M_A_DQS_DN<2>")
	)
	(segment
		(start 232.488994 -55.433214)
		(end 232.449624 -55.472584)
		(width 0.0889)
		(layer "In2.Cu")
		(net "M_A_DQS_DN<2>")
	)
	(segment
		(start 218.959176 -29.017976)
		(end 218.959176 -24.567134)
		(width 0.14224)
		(layer "In2.Cu")
		(net "M_A_DQS_DN<2>")
	)
	(segment
		(start 219.73794 -22.228556)
		(end 219.73794 -22.22881)
		(width 0.14224)
		(layer "In2.Cu")
		(net "M_A_DQS_DN<2>")
	)
	(segment
		(start 219.744544 -19.583146)
		(end 219.744544 -19.278854)
		(width 0.14224)
		(layer "In2.Cu")
		(net "M_A_DQS_DN<2>")
	)
	(segment
		(start 218.93276 -37.310568)
		(end 218.770454 -37.310568)
		(width 0.14224)
		(layer "In2.Cu")
		(net "M_A_DQS_DN<2>")
	)
	(segment
		(start 220.100144 -21.082)
		(end 219.969588 -21.082)
		(width 0.14224)
		(layer "In2.Cu")
		(net "M_A_DQS_DN<2>")
	)
	(segment
		(start 238.187738 -56.085486)
		(end 237.894622 -56.25465)
		(width 0.0889)
		(layer "In2.Cu")
		(net "M_A_DQS_DN<2>")
	)
	(segment
		(start 237.894622 -56.25465)
		(end 237.870746 -56.344058)
		(width 0.0889)
		(layer "In2.Cu")
		(net "M_A_DQS_DN<2>")
	)
	(segment
		(start 218.5924 -31.543752)
		(end 218.5924 -30.762448)
		(width 0.14224)
		(layer "In2.Cu")
		(net "M_A_DQS_DN<2>")
	)
	(segment
		(start 220.016832 -22.22881)
		(end 220.279468 -21.966174)
		(width 0.14224)
		(layer "In2.Cu")
		(net "M_A_DQS_DN<2>")
	)
	(arc
		(start 235.61167 -57.17159)
		(mid 235.316407 -57.092439)
		(end 235.100368 -56.876188)
		(width 0.0889)
		(layer "In2.Cu")
		(net "M_A_DQS_DN<2>")
	)
	(arc
		(start 237.870746 -56.344058)
		(mid 237.828767 -56.897018)
		(end 237.346998 -57.17159)
		(width 0.0889)
		(layer "In2.Cu")
		(net "M_A_DQS_DN<2>")
	)
	(arc
		(start 236.123988 -56.876188)
		(mid 235.907804 -57.092467)
		(end 235.612432 -57.17159)
		(width 0.0889)
		(layer "In2.Cu")
		(net "M_A_DQS_DN<2>")
	)
	(arc
		(start 236.817154 -56.876188)
		(mid 236.670861 -56.729783)
		(end 236.470952 -56.676036)
		(width 0.0889)
		(layer "In2.Cu")
		(net "M_A_DQS_DN<2>")
	)
	(arc
		(start 236.470444 -56.676036)
		(mid 236.270403 -56.729681)
		(end 236.123988 -56.876188)
		(width 0.0889)
		(layer "In2.Cu")
		(net "M_A_DQS_DN<2>")
	)
	(arc
		(start 235.100368 -56.876188)
		(mid 234.958685 -56.732384)
		(end 234.764834 -56.676036)
		(width 0.0889)
		(layer "In2.Cu")
		(net "M_A_DQS_DN<2>")
	)
	(arc
		(start 237.311438 -57.17159)
		(mid 237.026014 -57.088123)
		(end 236.817408 -56.876188)
		(width 0.0889)
		(layer "In2.Cu")
		(net "M_A_DQS_DN<2>")
	)
	(segment
		(start 231.883458 -56.106314)
		(end 231.839008 -56.150764)
		(width 0.0889)
		(layer "F.Cu")
		(net "M_A_DQS_DN<1>")
	)
	(segment
		(start 231.839008 -56.150764)
		(end 230.222044 -56.150764)
		(width 0.1651)
		(layer "F.Cu")
		(net "M_A_DQS_DN<1>")
	)
	(segment
		(start 214.114888 -37.650166)
		(end 214.241888 -37.523166)
		(width 0.1651)
		(layer "F.Cu")
		(net "M_A_DQS_DN<1>")
	)
	(segment
		(start 213.0425 -37.986208)
		(end 213.378542 -37.650166)
		(width 0.1651)
		(layer "F.Cu")
		(net "M_A_DQS_DN<1>")
	)
	(segment
		(start 213.378542 -37.650166)
		(end 214.114888 -37.650166)
		(width 0.1651)
		(layer "F.Cu")
		(net "M_A_DQS_DN<1>")
	)
	(segment
		(start 209.999834 -20.023582)
		(end 209.999834 -18.94967)
		(width 0.1651)
		(layer "F.Cu")
		(net "M_A_DQS_DN<1>")
	)
	(segment
		(start 209.932016 -22.684486)
		(end 210.387946 -22.228556)
		(width 0.1651)
		(layer "F.Cu")
		(net "M_A_DQS_DN<1>")
	)
	(segment
		(start 214.114888 -36.977066)
		(end 213.378542 -36.977066)
		(width 0.1651)
		(layer "F.Cu")
		(net "M_A_DQS_DN<1>")
	)
	(segment
		(start 234.229402 -56.679338)
		(end 233.595418 -56.679338)
		(width 0.0889)
		(layer "F.Cu")
		(net "M_A_DQS_DN<1>")
	)
	(segment
		(start 209.999834 -18.94967)
		(end 209.6008 -18.550636)
		(width 0.1651)
		(layer "F.Cu")
		(net "M_A_DQS_DN<1>")
	)
	(segment
		(start 210.000342 -20.023582)
		(end 209.999834 -20.023582)
		(width 0.1651)
		(layer "F.Cu")
		(net "M_A_DQS_DN<1>")
	)
	(segment
		(start 209.594196 -27.015694)
		(end 209.594196 -24.586946)
		(width 0.1651)
		(layer "F.Cu")
		(net "M_A_DQS_DN<1>")
	)
	(segment
		(start 209.932016 -24.249126)
		(end 209.932016 -22.684486)
		(width 0.1651)
		(layer "F.Cu")
		(net "M_A_DQS_DN<1>")
	)
	(segment
		(start 213.378542 -36.977066)
		(end 213.0425 -36.641024)
		(width 0.1651)
		(layer "F.Cu")
		(net "M_A_DQS_DN<1>")
	)
	(segment
		(start 209.6008 -18.152872)
		(end 209.948272 -17.8054)
		(width 0.1651)
		(layer "F.Cu")
		(net "M_A_DQS_DN<1>")
	)
	(segment
		(start 213.0425 -35.450018)
		(end 213.378542 -35.113976)
		(width 0.1651)
		(layer "F.Cu")
		(net "M_A_DQS_DN<1>")
	)
	(segment
		(start 232.419906 -56.18099)
		(end 232.34523 -56.106314)
		(width 0.0889)
		(layer "F.Cu")
		(net "M_A_DQS_DN<1>")
	)
	(segment
		(start 213.0425 -36.641024)
		(end 213.0425 -35.450018)
		(width 0.1651)
		(layer "F.Cu")
		(net "M_A_DQS_DN<1>")
	)
	(segment
		(start 213.0425 -34.104834)
		(end 213.0425 -30.463998)
		(width 0.1651)
		(layer "F.Cu")
		(net "M_A_DQS_DN<1>")
	)
	(segment
		(start 209.948272 -17.8054)
		(end 210.1723 -17.8054)
		(width 0.1651)
		(layer "F.Cu")
		(net "M_A_DQS_DN<1>")
	)
	(segment
		(start 213.378542 -34.440876)
		(end 213.0425 -34.104834)
		(width 0.1651)
		(layer "F.Cu")
		(net "M_A_DQS_DN<1>")
	)
	(segment
		(start 213.899496 -34.440876)
		(end 213.378542 -34.440876)
		(width 0.1651)
		(layer "F.Cu")
		(net "M_A_DQS_DN<1>")
	)
	(segment
		(start 213.378542 -35.113976)
		(end 213.899496 -35.113976)
		(width 0.1651)
		(layer "F.Cu")
		(net "M_A_DQS_DN<1>")
	)
	(segment
		(start 232.34523 -56.106314)
		(end 231.883458 -56.106314)
		(width 0.0889)
		(layer "F.Cu")
		(net "M_A_DQS_DN<1>")
	)
	(segment
		(start 213.0425 -38.97122)
		(end 213.0425 -37.986208)
		(width 0.1651)
		(layer "F.Cu")
		(net "M_A_DQS_DN<1>")
	)
	(segment
		(start 214.241888 -37.523166)
		(end 214.241888 -37.104066)
		(width 0.1651)
		(layer "F.Cu")
		(net "M_A_DQS_DN<1>")
	)
	(segment
		(start 214.241888 -37.104066)
		(end 214.114888 -36.977066)
		(width 0.1651)
		(layer "F.Cu")
		(net "M_A_DQS_DN<1>")
	)
	(segment
		(start 214.026496 -34.567876)
		(end 213.899496 -34.440876)
		(width 0.1651)
		(layer "F.Cu")
		(net "M_A_DQS_DN<1>")
	)
	(segment
		(start 213.0425 -30.463998)
		(end 209.594196 -27.015694)
		(width 0.1651)
		(layer "F.Cu")
		(net "M_A_DQS_DN<1>")
	)
	(segment
		(start 209.6008 -18.550636)
		(end 209.6008 -18.152872)
		(width 0.1651)
		(layer "F.Cu")
		(net "M_A_DQS_DN<1>")
	)
	(segment
		(start 230.222044 -56.150764)
		(end 213.0425 -38.97122)
		(width 0.1651)
		(layer "F.Cu")
		(net "M_A_DQS_DN<1>")
	)
	(segment
		(start 210.1723 -17.8054)
		(end 210.387946 -18.021046)
		(width 0.1651)
		(layer "F.Cu")
		(net "M_A_DQS_DN<1>")
	)
	(segment
		(start 232.767124 -56.18099)
		(end 232.419906 -56.18099)
		(width 0.0889)
		(layer "F.Cu")
		(net "M_A_DQS_DN<1>")
	)
	(segment
		(start 213.899496 -35.113976)
		(end 214.026496 -34.986976)
		(width 0.1651)
		(layer "F.Cu")
		(net "M_A_DQS_DN<1>")
	)
	(segment
		(start 209.594196 -24.586946)
		(end 209.932016 -24.249126)
		(width 0.1651)
		(layer "F.Cu")
		(net "M_A_DQS_DN<1>")
	)
	(segment
		(start 214.026496 -34.986976)
		(end 214.026496 -34.567876)
		(width 0.1651)
		(layer "F.Cu")
		(net "M_A_DQS_DN<1>")
	)
	(via
		(at 210.387946 -18.021046)
		(size 0.508)
		(drill 0.254)
		(layers "F.Cu" "B.Cu")
		(net "M_A_DQS_DN<1>")
	)
	(via
		(at 210.387946 -22.228556)
		(size 0.508)
		(drill 0.254)
		(layers "F.Cu" "B.Cu")
		(net "M_A_DQS_DN<1>")
	)
	(arc
		(start 233.096308 -56.380888)
		(mid 232.957315 -56.238808)
		(end 232.767124 -56.18099)
		(width 0.0889)
		(layer "F.Cu")
		(net "M_A_DQS_DN<1>")
	)
	(arc
		(start 233.595418 -56.679338)
		(mid 233.307098 -56.59494)
		(end 233.096308 -56.380888)
		(width 0.0889)
		(layer "F.Cu")
		(net "M_A_DQS_DN<1>")
	)
	(arc
		(start 234.466638 -56.58104)
		(mid 234.357793 -56.653768)
		(end 234.229402 -56.679338)
		(width 0.0889)
		(layer "F.Cu")
		(net "M_A_DQS_DN<1>")
	)
	(segment
		(start 209.617818 -22.098)
		(end 209.973418 -22.4536)
		(width 0.1651)
		(layer "B.Cu")
		(net "M_A_DQS_DN<1>")
	)
	(segment
		(start 209.617818 -21.767546)
		(end 209.617818 -22.098)
		(width 0.1651)
		(layer "B.Cu")
		(net "M_A_DQS_DN<1>")
	)
	(segment
		(start 209.973418 -22.4536)
		(end 210.162902 -22.4536)
		(width 0.1651)
		(layer "B.Cu")
		(net "M_A_DQS_DN<1>")
	)
	(segment
		(start 209.871818 -21.513546)
		(end 209.617818 -21.767546)
		(width 0.1651)
		(layer "B.Cu")
		(net "M_A_DQS_DN<1>")
	)
	(segment
		(start 210.162902 -22.4536)
		(end 210.387946 -22.228556)
		(width 0.1651)
		(layer "B.Cu")
		(net "M_A_DQS_DN<1>")
	)
	(segment
		(start 210.000342 -20.224242)
		(end 209.999834 -20.224242)
		(width 0.1651)
		(layer "B.Cu")
		(net "M_A_DQS_DN<1>")
	)
	(segment
		(start 209.999834 -21.13153)
		(end 209.871818 -21.259546)
		(width 0.1651)
		(layer "B.Cu")
		(net "M_A_DQS_DN<1>")
	)
	(segment
		(start 209.999834 -20.224242)
		(end 209.999834 -21.13153)
		(width 0.1651)
		(layer "B.Cu")
		(net "M_A_DQS_DN<1>")
	)
	(segment
		(start 209.871818 -21.259546)
		(end 209.871818 -21.513546)
		(width 0.1651)
		(layer "B.Cu")
		(net "M_A_DQS_DN<1>")
	)
	(segment
		(start 210.619594 -21.082)
		(end 210.441794 -20.9042)
		(width 0.14224)
		(layer "In2.Cu")
		(net "M_A_DQS_DN<1>")
	)
	(segment
		(start 210.929474 -19.940778)
		(end 210.724496 -19.7358)
		(width 0.14224)
		(layer "In2.Cu")
		(net "M_A_DQS_DN<1>")
	)
	(segment
		(start 210.39455 -19.278854)
		(end 210.547204 -19.1262)
		(width 0.14224)
		(layer "In2.Cu")
		(net "M_A_DQS_DN<1>")
	)
	(segment
		(start 210.441794 -20.6502)
		(end 210.619594 -20.4724)
		(width 0.14224)
		(layer "In2.Cu")
		(net "M_A_DQS_DN<1>")
	)
	(segment
		(start 210.547204 -19.7358)
		(end 210.39455 -19.583146)
		(width 0.14224)
		(layer "In2.Cu")
		(net "M_A_DQS_DN<1>")
	)
	(segment
		(start 210.39455 -19.583146)
		(end 210.39455 -19.278854)
		(width 0.14224)
		(layer "In2.Cu")
		(net "M_A_DQS_DN<1>")
	)
	(segment
		(start 210.547204 -19.1262)
		(end 210.749896 -19.1262)
		(width 0.14224)
		(layer "In2.Cu")
		(net "M_A_DQS_DN<1>")
	)
	(segment
		(start 210.929474 -21.261324)
		(end 210.75015 -21.082)
		(width 0.14224)
		(layer "In2.Cu")
		(net "M_A_DQS_DN<1>")
	)
	(segment
		(start 210.619594 -20.4724)
		(end 210.746594 -20.4724)
		(width 0.14224)
		(layer "In2.Cu")
		(net "M_A_DQS_DN<1>")
	)
	(segment
		(start 210.746594 -20.4724)
		(end 210.929474 -20.28952)
		(width 0.14224)
		(layer "In2.Cu")
		(net "M_A_DQS_DN<1>")
	)
	(segment
		(start 210.749896 -19.1262)
		(end 210.929474 -18.946622)
		(width 0.14224)
		(layer "In2.Cu")
		(net "M_A_DQS_DN<1>")
	)
	(segment
		(start 210.929474 -18.946622)
		(end 210.929474 -18.280888)
		(width 0.14224)
		(layer "In2.Cu")
		(net "M_A_DQS_DN<1>")
	)
	(segment
		(start 210.929474 -20.28952)
		(end 210.929474 -19.940778)
		(width 0.14224)
		(layer "In2.Cu")
		(net "M_A_DQS_DN<1>")
	)
	(segment
		(start 210.929474 -21.966174)
		(end 210.929474 -21.261324)
		(width 0.14224)
		(layer "In2.Cu")
		(net "M_A_DQS_DN<1>")
	)
	(segment
		(start 210.441794 -20.9042)
		(end 210.441794 -20.6502)
		(width 0.14224)
		(layer "In2.Cu")
		(net "M_A_DQS_DN<1>")
	)
	(segment
		(start 210.75015 -21.082)
		(end 210.619594 -21.082)
		(width 0.14224)
		(layer "In2.Cu")
		(net "M_A_DQS_DN<1>")
	)
	(segment
		(start 210.929474 -18.280888)
		(end 210.669632 -18.021046)
		(width 0.14224)
		(layer "In2.Cu")
		(net "M_A_DQS_DN<1>")
	)
	(segment
		(start 210.724496 -19.7358)
		(end 210.547204 -19.7358)
		(width 0.14224)
		(layer "In2.Cu")
		(net "M_A_DQS_DN<1>")
	)
	(segment
		(start 210.387946 -22.228556)
		(end 210.387946 -22.22881)
		(width 0.14224)
		(layer "In2.Cu")
		(net "M_A_DQS_DN<1>")
	)
	(segment
		(start 210.666838 -22.22881)
		(end 210.929474 -21.966174)
		(width 0.14224)
		(layer "In2.Cu")
		(net "M_A_DQS_DN<1>")
	)
	(segment
		(start 210.669632 -18.021046)
		(end 210.387946 -18.021046)
		(width 0.14224)
		(layer "In2.Cu")
		(net "M_A_DQS_DN<1>")
	)
	(segment
		(start 210.387946 -22.22881)
		(end 210.666838 -22.22881)
		(width 0.14224)
		(layer "In2.Cu")
		(net "M_A_DQS_DN<1>")
	)
	(segment
		(start 237.565692 -17.60093)
		(end 237.357412 -17.60093)
		(width 0.1651)
		(layer "F.Cu")
		(net "M_A_DQS_DN<17>")
	)
	(segment
		(start 238.049816 -16.077184)
		(end 237.631732 -16.495268)
		(width 0.1651)
		(layer "F.Cu")
		(net "M_A_DQS_DN<17>")
	)
	(segment
		(start 237.631732 -16.9164)
		(end 237.81766 -17.102328)
		(width 0.1651)
		(layer "F.Cu")
		(net "M_A_DQS_DN<17>")
	)
	(segment
		(start 237.631732 -16.495268)
		(end 237.631732 -16.9164)
		(width 0.1651)
		(layer "F.Cu")
		(net "M_A_DQS_DN<17>")
	)
	(segment
		(start 237.357412 -17.60093)
		(end 237.168182 -17.4117)
		(width 0.1651)
		(layer "F.Cu")
		(net "M_A_DQS_DN<17>")
	)
	(segment
		(start 249.061224 -60.047886)
		(end 248.489724 -60.047886)
		(width 0.1016)
		(layer "F.Cu")
		(net "M_A_DQS_DN<17>")
	)
	(segment
		(start 238.049816 -15.423642)
		(end 238.049816 -16.077184)
		(width 0.1651)
		(layer "F.Cu")
		(net "M_A_DQS_DN<17>")
	)
	(segment
		(start 237.81766 -17.102328)
		(end 237.81766 -17.348962)
		(width 0.1651)
		(layer "F.Cu")
		(net "M_A_DQS_DN<17>")
	)
	(segment
		(start 237.168182 -17.4117)
		(end 237.149132 -17.4117)
		(width 0.1651)
		(layer "F.Cu")
		(net "M_A_DQS_DN<17>")
	)
	(segment
		(start 238.050324 -15.423642)
		(end 238.049816 -15.423642)
		(width 0.1651)
		(layer "F.Cu")
		(net "M_A_DQS_DN<17>")
	)
	(segment
		(start 237.81766 -17.348962)
		(end 237.565692 -17.60093)
		(width 0.1651)
		(layer "F.Cu")
		(net "M_A_DQS_DN<17>")
	)
	(via
		(at 237.149132 -17.4117)
		(size 0.508)
		(drill 0.254)
		(layers "F.Cu" "B.Cu")
		(net "M_A_DQS_DN<17>")
	)
	(via
		(at 237.142528 -22.8346)
		(size 0.508)
		(drill 0.254)
		(layers "F.Cu" "B.Cu")
		(net "M_A_DQS_DN<17>")
	)
	(via
		(at 248.489724 -60.047886)
		(size 0.508)
		(drill 0.254)
		(layers "F.Cu" "B.Cu")
		(net "M_A_DQS_DN<17>")
	)
	(segment
		(start 237.337092 -22.640036)
		(end 237.564168 -22.640036)
		(width 0.1651)
		(layer "B.Cu")
		(net "M_A_DQS_DN<17>")
	)
	(segment
		(start 237.564168 -22.640036)
		(end 237.784132 -22.86)
		(width 0.1651)
		(layer "B.Cu")
		(net "M_A_DQS_DN<17>")
	)
	(segment
		(start 237.784132 -23.1902)
		(end 237.606332 -23.368)
		(width 0.1651)
		(layer "B.Cu")
		(net "M_A_DQS_DN<17>")
	)
	(segment
		(start 238.05007 -24.167592)
		(end 238.05007 -24.823928)
		(width 0.1651)
		(layer "B.Cu")
		(net "M_A_DQS_DN<17>")
	)
	(segment
		(start 237.784132 -22.86)
		(end 237.784132 -23.1902)
		(width 0.1651)
		(layer "B.Cu")
		(net "M_A_DQS_DN<17>")
	)
	(segment
		(start 238.05007 -24.823928)
		(end 238.050324 -24.824182)
		(width 0.1651)
		(layer "B.Cu")
		(net "M_A_DQS_DN<17>")
	)
	(segment
		(start 237.142528 -22.8346)
		(end 237.337092 -22.640036)
		(width 0.1651)
		(layer "B.Cu")
		(net "M_A_DQS_DN<17>")
	)
	(segment
		(start 237.606332 -23.723854)
		(end 238.05007 -24.167592)
		(width 0.1651)
		(layer "B.Cu")
		(net "M_A_DQS_DN<17>")
	)
	(segment
		(start 237.606332 -23.368)
		(end 237.606332 -23.723854)
		(width 0.1651)
		(layer "B.Cu")
		(net "M_A_DQS_DN<17>")
	)
	(segment
		(start 242.900962 -44.773088)
		(end 243.229892 -45.102018)
		(width 0.14224)
		(layer "In2.Cu")
		(net "M_A_DQS_DN<17>")
	)
	(segment
		(start 245.1608 -48.002698)
		(end 245.12143 -48.042068)
		(width 0.0889)
		(layer "In2.Cu")
		(net "M_A_DQS_DN<17>")
	)
	(segment
		(start 247.62079 -58.96229)
		(end 247.649492 -58.96229)
		(width 0.0889)
		(layer "In2.Cu")
		(net "M_A_DQS_DN<17>")
	)
	(segment
		(start 239.552988 -41.568624)
		(end 239.696498 -41.568624)
		(width 0.14224)
		(layer "In2.Cu")
		(net "M_A_DQS_DN<17>")
	)
	(segment
		(start 236.940852 -24.787352)
		(end 237.910116 -25.756616)
		(width 0.14224)
		(layer "In2.Cu")
		(net "M_A_DQS_DN<17>")
	)
	(segment
		(start 245.1608 -47.9806)
		(end 245.1608 -48.002698)
		(width 0.0889)
		(layer "In2.Cu")
		(net "M_A_DQS_DN<17>")
	)
	(segment
		(start 238.364776 -35.539172)
		(end 238.0742 -35.829748)
		(width 0.14224)
		(layer "In2.Cu")
		(net "M_A_DQS_DN<17>")
	)
	(segment
		(start 245.1608 -47.176436)
		(end 245.1608 -47.9806)
		(width 0.14224)
		(layer "In2.Cu")
		(net "M_A_DQS_DN<17>")
	)
	(segment
		(start 238.270288 -30.454854)
		(end 238.143288 -30.581854)
		(width 0.14224)
		(layer "In2.Cu")
		(net "M_A_DQS_DN<17>")
	)
	(segment
		(start 238.59744 -39.640256)
		(end 238.49584 -39.741856)
		(width 0.14224)
		(layer "In2.Cu")
		(net "M_A_DQS_DN<17>")
	)
	(segment
		(start 242.757452 -44.773088)
		(end 242.900962 -44.773088)
		(width 0.14224)
		(layer "In2.Cu")
		(net "M_A_DQS_DN<17>")
	)
	(segment
		(start 237.142528 -22.8346)
		(end 237.580932 -23.273004)
		(width 0.14224)
		(layer "In2.Cu")
		(net "M_A_DQS_DN<17>")
	)
	(segment
		(start 246.457724 -55.1942)
		(end 246.509286 -55.245762)
		(width 0.0889)
		(layer "In2.Cu")
		(net "M_A_DQS_DN<17>")
	)
	(segment
		(start 238.831882 -35.539172)
		(end 238.364776 -35.539172)
		(width 0.14224)
		(layer "In2.Cu")
		(net "M_A_DQS_DN<17>")
	)
	(segment
		(start 239.210088 -36.994338)
		(end 239.210088 -37.853366)
		(width 0.14224)
		(layer "In2.Cu")
		(net "M_A_DQS_DN<17>")
	)
	(segment
		(start 238.270288 -31.216854)
		(end 238.143288 -31.343854)
		(width 0.14224)
		(layer "In2.Cu")
		(net "M_A_DQS_DN<17>")
	)
	(segment
		(start 238.0742 -36.325556)
		(end 238.364776 -36.616132)
		(width 0.14224)
		(layer "In2.Cu")
		(net "M_A_DQS_DN<17>")
	)
	(segment
		(start 246.457724 -52.885848)
		(end 246.457724 -55.1942)
		(width 0.0889)
		(layer "In2.Cu")
		(net "M_A_DQS_DN<17>")
	)
	(segment
		(start 240.025428 -41.897554)
		(end 240.025428 -42.041064)
		(width 0.14224)
		(layer "In2.Cu")
		(net "M_A_DQS_DN<17>")
	)
	(segment
		(start 243.229892 -45.102018)
		(end 243.229892 -45.245528)
		(width 0.14224)
		(layer "In2.Cu")
		(net "M_A_DQS_DN<17>")
	)
	(segment
		(start 246.758206 -58.46699)
		(end 246.794782 -58.46699)
		(width 0.0889)
		(layer "In2.Cu")
		(net "M_A_DQS_DN<17>")
	)
	(segment
		(start 238.143288 -29.057854)
		(end 238.143288 -29.311854)
		(width 0.14224)
		(layer "In2.Cu")
		(net "M_A_DQS_DN<17>")
	)
	(segment
		(start 238.59744 -39.175436)
		(end 238.59744 -39.640256)
		(width 0.14224)
		(layer "In2.Cu")
		(net "M_A_DQS_DN<17>")
	)
	(segment
		(start 237.580932 -23.876)
		(end 237.453932 -24.003)
		(width 0.14224)
		(layer "In2.Cu")
		(net "M_A_DQS_DN<17>")
	)
	(segment
		(start 240.497614 -42.36974)
		(end 240.826544 -42.69867)
		(width 0.14224)
		(layer "In2.Cu")
		(net "M_A_DQS_DN<17>")
	)
	(segment
		(start 238.49584 -39.073836)
		(end 238.59744 -39.175436)
		(width 0.14224)
		(layer "In2.Cu")
		(net "M_A_DQS_DN<17>")
	)
	(segment
		(start 246.432578 -56.864504)
		(end 246.425974 -56.876188)
		(width 0.0889)
		(layer "In2.Cu")
		(net "M_A_DQS_DN<17>")
	)
	(segment
		(start 236.940852 -24.13)
		(end 236.940852 -24.787352)
		(width 0.14224)
		(layer "In2.Cu")
		(net "M_A_DQS_DN<17>")
	)
	(segment
		(start 237.580932 -23.273004)
		(end 237.580932 -23.876)
		(width 0.14224)
		(layer "In2.Cu")
		(net "M_A_DQS_DN<17>")
	)
	(segment
		(start 238.270288 -29.692854)
		(end 238.143288 -29.819854)
		(width 0.14224)
		(layer "In2.Cu")
		(net "M_A_DQS_DN<17>")
	)
	(segment
		(start 241.29873 -43.170856)
		(end 241.62766 -43.499786)
		(width 0.14224)
		(layer "In2.Cu")
		(net "M_A_DQS_DN<17>")
	)
	(segment
		(start 238.270288 -29.438854)
		(end 238.270288 -29.692854)
		(width 0.14224)
		(layer "In2.Cu")
		(net "M_A_DQS_DN<17>")
	)
	(segment
		(start 240.826544 -42.84218)
		(end 241.15522 -43.170856)
		(width 0.14224)
		(layer "In2.Cu")
		(net "M_A_DQS_DN<17>")
	)
	(segment
		(start 237.344712 -17.60728)
		(end 237.59414 -17.60728)
		(width 0.14224)
		(layer "In2.Cu")
		(net "M_A_DQS_DN<17>")
	)
	(segment
		(start 240.354104 -42.36974)
		(end 240.497614 -42.36974)
		(width 0.14224)
		(layer "In2.Cu")
		(net "M_A_DQS_DN<17>")
	)
	(segment
		(start 248.214388 -59.403742)
		(end 248.489724 -60.047886)
		(width 0.0889)
		(layer "In2.Cu")
		(net "M_A_DQS_DN<17>")
	)
	(segment
		(start 238.143288 -30.073854)
		(end 238.270288 -30.200854)
		(width 0.14224)
		(layer "In2.Cu")
		(net "M_A_DQS_DN<17>")
	)
	(segment
		(start 240.025428 -42.041064)
		(end 240.354104 -42.36974)
		(width 0.14224)
		(layer "In2.Cu")
		(net "M_A_DQS_DN<17>")
	)
	(segment
		(start 244.832124 -46.84776)
		(end 245.1608 -47.176436)
		(width 0.14224)
		(layer "In2.Cu")
		(net "M_A_DQS_DN<17>")
	)
	(segment
		(start 237.453932 -24.003)
		(end 237.067852 -24.003)
		(width 0.14224)
		(layer "In2.Cu")
		(net "M_A_DQS_DN<17>")
	)
	(segment
		(start 243.702078 -45.574204)
		(end 244.031008 -45.903134)
		(width 0.14224)
		(layer "In2.Cu")
		(net "M_A_DQS_DN<17>")
	)
	(segment
		(start 238.143288 -33.747456)
		(end 238.374936 -33.979104)
		(width 0.14224)
		(layer "In2.Cu")
		(net "M_A_DQS_DN<17>")
	)
	(segment
		(start 238.374936 -33.979104)
		(end 238.847376 -33.979104)
		(width 0.14224)
		(layer "In2.Cu")
		(net "M_A_DQS_DN<17>")
	)
	(segment
		(start 239.696498 -41.568624)
		(end 240.025428 -41.897554)
		(width 0.14224)
		(layer "In2.Cu")
		(net "M_A_DQS_DN<17>")
	)
	(segment
		(start 242.428776 -44.444412)
		(end 242.757452 -44.773088)
		(width 0.14224)
		(layer "In2.Cu")
		(net "M_A_DQS_DN<17>")
	)
	(segment
		(start 242.428776 -44.300902)
		(end 242.428776 -44.444412)
		(width 0.14224)
		(layer "In2.Cu")
		(net "M_A_DQS_DN<17>")
	)
	(segment
		(start 237.149132 -17.4117)
		(end 237.344712 -17.60728)
		(width 0.14224)
		(layer "In2.Cu")
		(net "M_A_DQS_DN<17>")
	)
	(segment
		(start 238.143288 -30.835854)
		(end 238.270288 -30.962854)
		(width 0.14224)
		(layer "In2.Cu")
		(net "M_A_DQS_DN<17>")
	)
	(segment
		(start 237.067852 -24.003)
		(end 236.940852 -24.13)
		(width 0.14224)
		(layer "In2.Cu")
		(net "M_A_DQS_DN<17>")
	)
	(segment
		(start 246.509286 -55.245762)
		(end 246.509286 -55.738522)
		(width 0.0889)
		(layer "In2.Cu")
		(net "M_A_DQS_DN<17>")
	)
	(segment
		(start 247.072912 -51.462432)
		(end 247.072912 -52.27066)
		(width 0.0889)
		(layer "In2.Cu")
		(net "M_A_DQS_DN<17>")
	)
	(segment
		(start 238.831882 -36.616132)
		(end 239.210088 -36.994338)
		(width 0.14224)
		(layer "In2.Cu")
		(net "M_A_DQS_DN<17>")
	)
	(segment
		(start 237.910116 -25.967944)
		(end 238.067596 -26.125424)
		(width 0.14224)
		(layer "In2.Cu")
		(net "M_A_DQS_DN<17>")
	)
	(segment
		(start 241.62766 -43.643296)
		(end 241.956336 -43.971972)
		(width 0.14224)
		(layer "In2.Cu")
		(net "M_A_DQS_DN<17>")
	)
	(segment
		(start 244.359684 -46.37532)
		(end 244.503194 -46.37532)
		(width 0.14224)
		(layer "In2.Cu")
		(net "M_A_DQS_DN<17>")
	)
	(segment
		(start 242.099846 -43.971972)
		(end 242.428776 -44.300902)
		(width 0.14224)
		(layer "In2.Cu")
		(net "M_A_DQS_DN<17>")
	)
	(segment
		(start 239.210088 -35.160966)
		(end 238.831882 -35.539172)
		(width 0.14224)
		(layer "In2.Cu")
		(net "M_A_DQS_DN<17>")
	)
	(segment
		(start 239.210088 -37.853366)
		(end 238.831882 -38.231572)
		(width 0.14224)
		(layer "In2.Cu")
		(net "M_A_DQS_DN<17>")
	)
	(segment
		(start 244.031008 -46.046644)
		(end 244.359684 -46.37532)
		(width 0.14224)
		(layer "In2.Cu")
		(net "M_A_DQS_DN<17>")
	)
	(segment
		(start 238.661956 -38.231572)
		(end 238.49584 -38.397688)
		(width 0.14224)
		(layer "In2.Cu")
		(net "M_A_DQS_DN<17>")
	)
	(segment
		(start 240.826544 -42.69867)
		(end 240.826544 -42.84218)
		(width 0.14224)
		(layer "In2.Cu")
		(net "M_A_DQS_DN<17>")
	)
	(segment
		(start 238.847376 -33.979104)
		(end 239.210088 -34.341816)
		(width 0.14224)
		(layer "In2.Cu")
		(net "M_A_DQS_DN<17>")
	)
	(segment
		(start 241.15522 -43.170856)
		(end 241.29873 -43.170856)
		(width 0.14224)
		(layer "In2.Cu")
		(net "M_A_DQS_DN<17>")
	)
	(segment
		(start 238.067596 -26.125424)
		(end 238.067596 -26.379424)
		(width 0.14224)
		(layer "In2.Cu")
		(net "M_A_DQS_DN<17>")
	)
	(segment
		(start 237.910116 -26.536904)
		(end 237.910116 -28.824682)
		(width 0.14224)
		(layer "In2.Cu")
		(net "M_A_DQS_DN<17>")
	)
	(segment
		(start 238.49584 -38.397688)
		(end 238.49584 -39.073836)
		(width 0.14224)
		(layer "In2.Cu")
		(net "M_A_DQS_DN<17>")
	)
	(segment
		(start 241.956336 -43.971972)
		(end 242.099846 -43.971972)
		(width 0.14224)
		(layer "In2.Cu")
		(net "M_A_DQS_DN<17>")
	)
	(segment
		(start 247.072912 -52.27066)
		(end 246.457724 -52.885848)
		(width 0.0889)
		(layer "In2.Cu")
		(net "M_A_DQS_DN<17>")
	)
	(segment
		(start 238.244888 -32.716216)
		(end 238.244888 -33.181036)
		(width 0.14224)
		(layer "In2.Cu")
		(net "M_A_DQS_DN<17>")
	)
	(segment
		(start 241.62766 -43.499786)
		(end 241.62766 -43.643296)
		(width 0.14224)
		(layer "In2.Cu")
		(net "M_A_DQS_DN<17>")
	)
	(segment
		(start 244.031008 -45.903134)
		(end 244.031008 -46.046644)
		(width 0.14224)
		(layer "In2.Cu")
		(net "M_A_DQS_DN<17>")
	)
	(segment
		(start 238.143288 -32.614616)
		(end 238.244888 -32.716216)
		(width 0.14224)
		(layer "In2.Cu")
		(net "M_A_DQS_DN<17>")
	)
	(segment
		(start 243.558568 -45.574204)
		(end 243.702078 -45.574204)
		(width 0.14224)
		(layer "In2.Cu")
		(net "M_A_DQS_DN<17>")
	)
	(segment
		(start 245.12143 -48.042068)
		(end 245.12143 -49.390554)
		(width 0.0889)
		(layer "In2.Cu")
		(net "M_A_DQS_DN<17>")
	)
	(segment
		(start 238.364776 -36.616132)
		(end 238.831882 -36.616132)
		(width 0.14224)
		(layer "In2.Cu")
		(net "M_A_DQS_DN<17>")
	)
	(segment
		(start 245.12143 -49.390554)
		(end 246.906796 -51.17592)
		(width 0.0889)
		(layer "In2.Cu")
		(net "M_A_DQS_DN<17>")
	)
	(segment
		(start 243.229892 -45.245528)
		(end 243.558568 -45.574204)
		(width 0.14224)
		(layer "In2.Cu")
		(net "M_A_DQS_DN<17>")
	)
	(segment
		(start 238.49584 -39.741856)
		(end 238.49584 -40.511476)
		(width 0.14224)
		(layer "In2.Cu")
		(net "M_A_DQS_DN<17>")
	)
	(segment
		(start 239.210088 -34.341816)
		(end 239.210088 -35.160966)
		(width 0.14224)
		(layer "In2.Cu")
		(net "M_A_DQS_DN<17>")
	)
	(segment
		(start 246.509286 -55.738522)
		(end 246.420132 -55.89524)
		(width 0.0889)
		(layer "In2.Cu")
		(net "M_A_DQS_DN<17>")
	)
	(segment
		(start 238.143288 -29.311854)
		(end 238.270288 -29.438854)
		(width 0.14224)
		(layer "In2.Cu")
		(net "M_A_DQS_DN<17>")
	)
	(segment
		(start 238.270288 -30.200854)
		(end 238.270288 -30.454854)
		(width 0.14224)
		(layer "In2.Cu")
		(net "M_A_DQS_DN<17>")
	)
	(segment
		(start 238.49584 -40.511476)
		(end 239.552988 -41.568624)
		(width 0.14224)
		(layer "In2.Cu")
		(net "M_A_DQS_DN<17>")
	)
	(segment
		(start 244.503194 -46.37532)
		(end 244.832124 -46.70425)
		(width 0.14224)
		(layer "In2.Cu")
		(net "M_A_DQS_DN<17>")
	)
	(segment
		(start 246.432578 -57.855104)
		(end 246.425974 -57.866788)
		(width 0.0889)
		(layer "In2.Cu")
		(net "M_A_DQS_DN<17>")
	)
	(segment
		(start 238.244888 -33.181036)
		(end 238.143288 -33.282636)
		(width 0.14224)
		(layer "In2.Cu")
		(net "M_A_DQS_DN<17>")
	)
	(segment
		(start 246.906796 -51.17592)
		(end 247.072912 -51.462432)
		(width 0.0889)
		(layer "In2.Cu")
		(net "M_A_DQS_DN<17>")
	)
	(segment
		(start 237.59414 -17.60728)
		(end 237.931452 -17.944592)
		(width 0.14224)
		(layer "In2.Cu")
		(net "M_A_DQS_DN<17>")
	)
	(segment
		(start 244.832124 -46.70425)
		(end 244.832124 -46.84776)
		(width 0.14224)
		(layer "In2.Cu")
		(net "M_A_DQS_DN<17>")
	)
	(segment
		(start 237.910116 -25.756616)
		(end 237.910116 -25.967944)
		(width 0.14224)
		(layer "In2.Cu")
		(net "M_A_DQS_DN<17>")
	)
	(segment
		(start 238.143288 -31.343854)
		(end 238.143288 -32.614616)
		(width 0.14224)
		(layer "In2.Cu")
		(net "M_A_DQS_DN<17>")
	)
	(segment
		(start 238.270288 -30.962854)
		(end 238.270288 -31.216854)
		(width 0.14224)
		(layer "In2.Cu")
		(net "M_A_DQS_DN<17>")
	)
	(segment
		(start 237.931452 -17.944592)
		(end 237.931452 -22.045676)
		(width 0.14224)
		(layer "In2.Cu")
		(net "M_A_DQS_DN<17>")
	)
	(segment
		(start 237.931452 -22.045676)
		(end 237.142528 -22.8346)
		(width 0.14224)
		(layer "In2.Cu")
		(net "M_A_DQS_DN<17>")
	)
	(segment
		(start 238.067596 -26.379424)
		(end 237.910116 -26.536904)
		(width 0.14224)
		(layer "In2.Cu")
		(net "M_A_DQS_DN<17>")
	)
	(segment
		(start 238.143288 -30.581854)
		(end 238.143288 -30.835854)
		(width 0.14224)
		(layer "In2.Cu")
		(net "M_A_DQS_DN<17>")
	)
	(segment
		(start 237.910116 -28.824682)
		(end 238.143288 -29.057854)
		(width 0.14224)
		(layer "In2.Cu")
		(net "M_A_DQS_DN<17>")
	)
	(segment
		(start 238.0742 -35.829748)
		(end 238.0742 -36.325556)
		(width 0.14224)
		(layer "In2.Cu")
		(net "M_A_DQS_DN<17>")
	)
	(segment
		(start 238.143288 -29.819854)
		(end 238.143288 -30.073854)
		(width 0.14224)
		(layer "In2.Cu")
		(net "M_A_DQS_DN<17>")
	)
	(segment
		(start 238.143288 -33.282636)
		(end 238.143288 -33.747456)
		(width 0.14224)
		(layer "In2.Cu")
		(net "M_A_DQS_DN<17>")
	)
	(segment
		(start 238.831882 -38.231572)
		(end 238.661956 -38.231572)
		(width 0.14224)
		(layer "In2.Cu")
		(net "M_A_DQS_DN<17>")
	)
	(segment
		(start 246.425974 -56.876188)
		(end 246.420132 -56.88584)
		(width 0.0889)
		(layer "In2.Cu")
		(net "M_A_DQS_DN<17>")
	)
	(arc
		(start 247.649492 -58.96229)
		(mid 247.934539 -59.045818)
		(end 248.143014 -59.257438)
		(width 0.0889)
		(layer "In2.Cu")
		(net "M_A_DQS_DN<17>")
	)
	(arc
		(start 246.425974 -57.866788)
		(mid 246.422424 -58.260813)
		(end 246.758206 -58.46699)
		(width 0.0889)
		(layer "In2.Cu")
		(net "M_A_DQS_DN<17>")
	)
	(arc
		(start 246.420132 -56.88584)
		(mid 246.372241 -57.081803)
		(end 246.425974 -57.276238)
		(width 0.0889)
		(layer "In2.Cu")
		(net "M_A_DQS_DN<17>")
	)
	(arc
		(start 246.420132 -55.89524)
		(mid 246.372241 -56.091203)
		(end 246.425974 -56.285638)
		(width 0.0889)
		(layer "In2.Cu")
		(net "M_A_DQS_DN<17>")
	)
	(arc
		(start 246.794782 -58.46699)
		(mid 247.077686 -58.551409)
		(end 247.284494 -58.762138)
		(width 0.0889)
		(layer "In2.Cu")
		(net "M_A_DQS_DN<17>")
	)
	(arc
		(start 247.284494 -58.762138)
		(mid 247.426537 -58.90605)
		(end 247.62079 -58.96229)
		(width 0.0889)
		(layer "In2.Cu")
		(net "M_A_DQS_DN<17>")
	)
	(arc
		(start 246.425974 -57.276238)
		(mid 246.505066 -57.564818)
		(end 246.432578 -57.855104)
		(width 0.0889)
		(layer "In2.Cu")
		(net "M_A_DQS_DN<17>")
	)
	(arc
		(start 246.425974 -56.285638)
		(mid 246.505066 -56.574218)
		(end 246.432578 -56.864504)
		(width 0.0889)
		(layer "In2.Cu")
		(net "M_A_DQS_DN<17>")
	)
	(arc
		(start 248.143014 -59.257438)
		(mid 248.181257 -59.329343)
		(end 248.214388 -59.403742)
		(width 0.0889)
		(layer "In2.Cu")
		(net "M_A_DQS_DN<17>")
	)
	(segment
		(start 311.5818 -16.9164)
		(end 311.5818 -16.495268)
		(width 0.1651)
		(layer "F.Cu")
		(net "M_A_DQS_DN<16>")
	)
	(segment
		(start 311.51576 -17.60093)
		(end 311.767728 -17.348962)
		(width 0.1651)
		(layer "F.Cu")
		(net "M_A_DQS_DN<16>")
	)
	(segment
		(start 311.0992 -17.4117)
		(end 311.11825 -17.4117)
		(width 0.1651)
		(layer "F.Cu")
		(net "M_A_DQS_DN<16>")
	)
	(segment
		(start 311.30748 -17.60093)
		(end 311.51576 -17.60093)
		(width 0.1651)
		(layer "F.Cu")
		(net "M_A_DQS_DN<16>")
	)
	(segment
		(start 311.11825 -17.4117)
		(end 311.30748 -17.60093)
		(width 0.1651)
		(layer "F.Cu")
		(net "M_A_DQS_DN<16>")
	)
	(segment
		(start 311.5818 -16.495268)
		(end 311.999884 -16.077184)
		(width 0.1651)
		(layer "F.Cu")
		(net "M_A_DQS_DN<16>")
	)
	(segment
		(start 311.767728 -17.102328)
		(end 311.5818 -16.9164)
		(width 0.1651)
		(layer "F.Cu")
		(net "M_A_DQS_DN<16>")
	)
	(segment
		(start 287.50514 -55.409338)
		(end 286.93364 -55.409338)
		(width 0.1016)
		(layer "F.Cu")
		(net "M_A_DQS_DN<16>")
	)
	(segment
		(start 311.999884 -16.077184)
		(end 311.999884 -15.423642)
		(width 0.1651)
		(layer "F.Cu")
		(net "M_A_DQS_DN<16>")
	)
	(segment
		(start 311.999884 -15.423642)
		(end 312.000392 -15.423642)
		(width 0.1651)
		(layer "F.Cu")
		(net "M_A_DQS_DN<16>")
	)
	(segment
		(start 311.767728 -17.348962)
		(end 311.767728 -17.102328)
		(width 0.1651)
		(layer "F.Cu")
		(net "M_A_DQS_DN<16>")
	)
	(via
		(at 311.0992 -17.4117)
		(size 0.508)
		(drill 0.254)
		(layers "F.Cu" "B.Cu")
		(net "M_A_DQS_DN<16>")
	)
	(via
		(at 311.092596 -22.8346)
		(size 0.508)
		(drill 0.254)
		(layers "F.Cu" "B.Cu")
		(net "M_A_DQS_DN<16>")
	)
	(via
		(at 286.93364 -55.409338)
		(size 0.508)
		(drill 0.254)
		(layers "F.Cu" "B.Cu")
		(net "M_A_DQS_DN<16>")
	)
	(segment
		(start 311.5564 -23.368)
		(end 311.5564 -23.723854)
		(width 0.1651)
		(layer "B.Cu")
		(net "M_A_DQS_DN<16>")
	)
	(segment
		(start 311.7342 -23.1902)
		(end 311.5564 -23.368)
		(width 0.1651)
		(layer "B.Cu")
		(net "M_A_DQS_DN<16>")
	)
	(segment
		(start 311.7342 -22.86)
		(end 311.7342 -23.1902)
		(width 0.1651)
		(layer "B.Cu")
		(net "M_A_DQS_DN<16>")
	)
	(segment
		(start 311.5564 -23.723854)
		(end 312.000138 -24.167592)
		(width 0.1651)
		(layer "B.Cu")
		(net "M_A_DQS_DN<16>")
	)
	(segment
		(start 311.28716 -22.640036)
		(end 311.514236 -22.640036)
		(width 0.1651)
		(layer "B.Cu")
		(net "M_A_DQS_DN<16>")
	)
	(segment
		(start 312.000138 -24.823928)
		(end 312.000392 -24.824182)
		(width 0.1651)
		(layer "B.Cu")
		(net "M_A_DQS_DN<16>")
	)
	(segment
		(start 312.000138 -24.167592)
		(end 312.000138 -24.823928)
		(width 0.1651)
		(layer "B.Cu")
		(net "M_A_DQS_DN<16>")
	)
	(segment
		(start 311.092596 -22.8346)
		(end 311.28716 -22.640036)
		(width 0.1651)
		(layer "B.Cu")
		(net "M_A_DQS_DN<16>")
	)
	(segment
		(start 311.514236 -22.640036)
		(end 311.7342 -22.86)
		(width 0.1651)
		(layer "B.Cu")
		(net "M_A_DQS_DN<16>")
	)
	(segment
		(start 287.44545 -52.732432)
		(end 287.58515 -52.490624)
		(width 0.0889)
		(layer "In2.Cu")
		(net "M_A_DQS_DN<16>")
	)
	(segment
		(start 311.0992 -23.9776)
		(end 311.277 -23.9776)
		(width 0.14224)
		(layer "In2.Cu")
		(net "M_A_DQS_DN<16>")
	)
	(segment
		(start 291.102542 -49.029112)
		(end 291.28212 -48.849534)
		(width 0.14224)
		(layer "In2.Cu")
		(net "M_A_DQS_DN<16>")
	)
	(segment
		(start 288.93262 -51.143154)
		(end 288.9885 -51.143154)
		(width 0.0889)
		(layer "In2.Cu")
		(net "M_A_DQS_DN<16>")
	)
	(segment
		(start 299.064934 -44.03344)
		(end 301.86376 -44.03344)
		(width 0.14224)
		(layer "In2.Cu")
		(net "M_A_DQS_DN<16>")
	)
	(segment
		(start 298.909994 -44.95038)
		(end 298.909994 -44.18838)
		(width 0.14224)
		(layer "In2.Cu")
		(net "M_A_DQS_DN<16>")
	)
	(segment
		(start 295.303956 -45.615098)
		(end 295.483534 -45.43552)
		(width 0.14224)
		(layer "In2.Cu")
		(net "M_A_DQS_DN<16>")
	)
	(segment
		(start 311.277 -23.9776)
		(end 311.531 -23.7236)
		(width 0.14224)
		(layer "In2.Cu")
		(net "M_A_DQS_DN<16>")
	)
	(segment
		(start 310.971946 -37.668454)
		(end 311.67324 -36.96716)
		(width 0.14224)
		(layer "In2.Cu")
		(net "M_A_DQS_DN<16>")
	)
	(segment
		(start 311.531 -23.273004)
		(end 311.092596 -22.8346)
		(width 0.14224)
		(layer "In2.Cu")
		(net "M_A_DQS_DN<16>")
	)
	(segment
		(start 286.627824 -55.230014)
		(end 286.605472 -55.177944)
		(width 0.0889)
		(layer "In2.Cu")
		(net "M_A_DQS_DN<16>")
	)
	(segment
		(start 301.86376 -44.03344)
		(end 308.228746 -37.668454)
		(width 0.14224)
		(layer "In2.Cu")
		(net "M_A_DQS_DN<16>")
	)
	(segment
		(start 290.387278 -49.90592)
		(end 290.56711 -49.726088)
		(width 0.14224)
		(layer "In2.Cu")
		(net "M_A_DQS_DN<16>")
	)
	(segment
		(start 292.33622 -47.795434)
		(end 292.497764 -47.795434)
		(width 0.14224)
		(layer "In2.Cu")
		(net "M_A_DQS_DN<16>")
	)
	(segment
		(start 291.28212 -48.849534)
		(end 291.443664 -48.849534)
		(width 0.14224)
		(layer "In2.Cu")
		(net "M_A_DQS_DN<16>")
	)
	(segment
		(start 311.88152 -17.944592)
		(end 311.544208 -17.60728)
		(width 0.14224)
		(layer "In2.Cu")
		(net "M_A_DQS_DN<16>")
	)
	(segment
		(start 294.96258 -45.956474)
		(end 295.124124 -45.956474)
		(width 0.14224)
		(layer "In2.Cu")
		(net "M_A_DQS_DN<16>")
	)
	(segment
		(start 289.70478 -50.426874)
		(end 289.866324 -50.426874)
		(width 0.14224)
		(layer "In2.Cu")
		(net "M_A_DQS_DN<16>")
	)
	(segment
		(start 289.34537 -50.947828)
		(end 289.525202 -50.767996)
		(width 0.14224)
		(layer "In2.Cu")
		(net "M_A_DQS_DN<16>")
	)
	(segment
		(start 291.102542 -49.19091)
		(end 291.102542 -49.029112)
		(width 0.14224)
		(layer "In2.Cu")
		(net "M_A_DQS_DN<16>")
	)
	(segment
		(start 288.9885 -51.143154)
		(end 289.004248 -51.127406)
		(width 0.0889)
		(layer "In2.Cu")
		(net "M_A_DQS_DN<16>")
	)
	(segment
		(start 293.19855 -46.933104)
		(end 293.474394 -46.657006)
		(width 0.14224)
		(layer "In2.Cu")
		(net "M_A_DQS_DN<16>")
	)
	(segment
		(start 311.78754 -25.32634)
		(end 310.96204 -24.50084)
		(width 0.14224)
		(layer "In2.Cu")
		(net "M_A_DQS_DN<16>")
	)
	(segment
		(start 296.345864 -44.734734)
		(end 296.345864 -44.57319)
		(width 0.14224)
		(layer "In2.Cu")
		(net "M_A_DQS_DN<16>")
	)
	(segment
		(start 296.166032 -44.914566)
		(end 296.345864 -44.734734)
		(width 0.14224)
		(layer "In2.Cu")
		(net "M_A_DQS_DN<16>")
	)
	(segment
		(start 293.19855 -47.094648)
		(end 293.19855 -46.933104)
		(width 0.14224)
		(layer "In2.Cu")
		(net "M_A_DQS_DN<16>")
	)
	(segment
		(start 294.783002 -46.136052)
		(end 294.96258 -45.956474)
		(width 0.14224)
		(layer "In2.Cu")
		(net "M_A_DQS_DN<16>")
	)
	(segment
		(start 291.97681 -48.316642)
		(end 292.156642 -48.13681)
		(width 0.14224)
		(layer "In2.Cu")
		(net "M_A_DQS_DN<16>")
	)
	(segment
		(start 290.760912 -49.370742)
		(end 290.92271 -49.370742)
		(width 0.14224)
		(layer "In2.Cu")
		(net "M_A_DQS_DN<16>")
	)
	(segment
		(start 295.483534 -45.43552)
		(end 295.645078 -45.43552)
		(width 0.14224)
		(layer "In2.Cu")
		(net "M_A_DQS_DN<16>")
	)
	(segment
		(start 292.85692 -47.27448)
		(end 293.018718 -47.27448)
		(width 0.14224)
		(layer "In2.Cu")
		(net "M_A_DQS_DN<16>")
	)
	(segment
		(start 287.58515 -52.490624)
		(end 288.93262 -51.143154)
		(width 0.0889)
		(layer "In2.Cu")
		(net "M_A_DQS_DN<16>")
	)
	(segment
		(start 311.67324 -26.4541)
		(end 311.78754 -26.3398)
		(width 0.14224)
		(layer "In2.Cu")
		(net "M_A_DQS_DN<16>")
	)
	(segment
		(start 295.82491 -45.094144)
		(end 296.004488 -44.914566)
		(width 0.14224)
		(layer "In2.Cu")
		(net "M_A_DQS_DN<16>")
	)
	(segment
		(start 311.544208 -17.60728)
		(end 311.29478 -17.60728)
		(width 0.14224)
		(layer "In2.Cu")
		(net "M_A_DQS_DN<16>")
	)
	(segment
		(start 311.531 -23.7236)
		(end 311.531 -23.273004)
		(width 0.14224)
		(layer "In2.Cu")
		(net "M_A_DQS_DN<16>")
	)
	(segment
		(start 297.553634 -44.03344)
		(end 297.708574 -44.18838)
		(width 0.14224)
		(layer "In2.Cu")
		(net "M_A_DQS_DN<16>")
	)
	(segment
		(start 292.156642 -47.975012)
		(end 292.33622 -47.795434)
		(width 0.14224)
		(layer "In2.Cu")
		(net "M_A_DQS_DN<16>")
	)
	(segment
		(start 287.44545 -53.132482)
		(end 287.440624 -53.123846)
		(width 0.0889)
		(layer "In2.Cu")
		(net "M_A_DQS_DN<16>")
	)
	(segment
		(start 289.183826 -50.947828)
		(end 289.34537 -50.947828)
		(width 0.14224)
		(layer "In2.Cu")
		(net "M_A_DQS_DN<16>")
	)
	(segment
		(start 295.82491 -45.255688)
		(end 295.82491 -45.094144)
		(width 0.14224)
		(layer "In2.Cu")
		(net "M_A_DQS_DN<16>")
	)
	(segment
		(start 310.96204 -24.50084)
		(end 310.96204 -24.11476)
		(width 0.14224)
		(layer "In2.Cu")
		(net "M_A_DQS_DN<16>")
	)
	(segment
		(start 296.004488 -44.914566)
		(end 296.166032 -44.914566)
		(width 0.14224)
		(layer "In2.Cu")
		(net "M_A_DQS_DN<16>")
	)
	(segment
		(start 294.441626 -46.477428)
		(end 294.60317 -46.477428)
		(width 0.14224)
		(layer "In2.Cu")
		(net "M_A_DQS_DN<16>")
	)
	(segment
		(start 286.59328 -54.629304)
		(end 286.58693 -54.618636)
		(width 0.0889)
		(layer "In2.Cu")
		(net "M_A_DQS_DN<16>")
	)
	(segment
		(start 296.345864 -44.57319)
		(end 296.885614 -44.03344)
		(width 0.14224)
		(layer "In2.Cu")
		(net "M_A_DQS_DN<16>")
	)
	(segment
		(start 298.909994 -44.18838)
		(end 299.064934 -44.03344)
		(width 0.14224)
		(layer "In2.Cu")
		(net "M_A_DQS_DN<16>")
	)
	(segment
		(start 286.93364 -55.409338)
		(end 286.627824 -55.230014)
		(width 0.0889)
		(layer "In2.Cu")
		(net "M_A_DQS_DN<16>")
	)
	(segment
		(start 292.156642 -48.13681)
		(end 292.156642 -47.975012)
		(width 0.14224)
		(layer "In2.Cu")
		(net "M_A_DQS_DN<16>")
	)
	(segment
		(start 296.885614 -44.03344)
		(end 297.553634 -44.03344)
		(width 0.14224)
		(layer "In2.Cu")
		(net "M_A_DQS_DN<16>")
	)
	(segment
		(start 290.046156 -50.085498)
		(end 290.225734 -49.90592)
		(width 0.14224)
		(layer "In2.Cu")
		(net "M_A_DQS_DN<16>")
	)
	(segment
		(start 293.018718 -47.27448)
		(end 293.19855 -47.094648)
		(width 0.14224)
		(layer "In2.Cu")
		(net "M_A_DQS_DN<16>")
	)
	(segment
		(start 289.866324 -50.426874)
		(end 290.046156 -50.247042)
		(width 0.14224)
		(layer "In2.Cu")
		(net "M_A_DQS_DN<16>")
	)
	(segment
		(start 308.228746 -37.668454)
		(end 310.971946 -37.668454)
		(width 0.14224)
		(layer "In2.Cu")
		(net "M_A_DQS_DN<16>")
	)
	(segment
		(start 293.474394 -46.657006)
		(end 294.262048 -46.657006)
		(width 0.14224)
		(layer "In2.Cu")
		(net "M_A_DQS_DN<16>")
	)
	(segment
		(start 290.046156 -50.247042)
		(end 290.046156 -50.085498)
		(width 0.14224)
		(layer "In2.Cu")
		(net "M_A_DQS_DN<16>")
	)
	(segment
		(start 290.56711 -49.564544)
		(end 290.760912 -49.370742)
		(width 0.14224)
		(layer "In2.Cu")
		(net "M_A_DQS_DN<16>")
	)
	(segment
		(start 311.78754 -26.3398)
		(end 311.78754 -25.32634)
		(width 0.14224)
		(layer "In2.Cu")
		(net "M_A_DQS_DN<16>")
	)
	(segment
		(start 289.525202 -50.767996)
		(end 289.525202 -50.606452)
		(width 0.14224)
		(layer "In2.Cu")
		(net "M_A_DQS_DN<16>")
	)
	(segment
		(start 294.60317 -46.477428)
		(end 294.783002 -46.297596)
		(width 0.14224)
		(layer "In2.Cu")
		(net "M_A_DQS_DN<16>")
	)
	(segment
		(start 295.124124 -45.956474)
		(end 295.303956 -45.776642)
		(width 0.14224)
		(layer "In2.Cu")
		(net "M_A_DQS_DN<16>")
	)
	(segment
		(start 292.677596 -47.615602)
		(end 292.677596 -47.454058)
		(width 0.14224)
		(layer "In2.Cu")
		(net "M_A_DQS_DN<16>")
	)
	(segment
		(start 311.29478 -17.60728)
		(end 311.0992 -17.4117)
		(width 0.14224)
		(layer "In2.Cu")
		(net "M_A_DQS_DN<16>")
	)
	(segment
		(start 310.96204 -24.11476)
		(end 311.0992 -23.9776)
		(width 0.14224)
		(layer "In2.Cu")
		(net "M_A_DQS_DN<16>")
	)
	(segment
		(start 295.645078 -45.43552)
		(end 295.82491 -45.255688)
		(width 0.14224)
		(layer "In2.Cu")
		(net "M_A_DQS_DN<16>")
	)
	(segment
		(start 291.443664 -48.849534)
		(end 291.623496 -48.669702)
		(width 0.14224)
		(layer "In2.Cu")
		(net "M_A_DQS_DN<16>")
	)
	(segment
		(start 290.92271 -49.370742)
		(end 291.102542 -49.19091)
		(width 0.14224)
		(layer "In2.Cu")
		(net "M_A_DQS_DN<16>")
	)
	(segment
		(start 286.605472 -55.177944)
		(end 286.62249 -55.136542)
		(width 0.0889)
		(layer "In2.Cu")
		(net "M_A_DQS_DN<16>")
	)
	(segment
		(start 292.677596 -47.454058)
		(end 292.85692 -47.27448)
		(width 0.14224)
		(layer "In2.Cu")
		(net "M_A_DQS_DN<16>")
	)
	(segment
		(start 291.623496 -48.669702)
		(end 291.623496 -48.508158)
		(width 0.14224)
		(layer "In2.Cu")
		(net "M_A_DQS_DN<16>")
	)
	(segment
		(start 297.708574 -44.18838)
		(end 297.708574 -44.95038)
		(width 0.14224)
		(layer "In2.Cu")
		(net "M_A_DQS_DN<16>")
	)
	(segment
		(start 298.020994 -45.2628)
		(end 298.597574 -45.2628)
		(width 0.14224)
		(layer "In2.Cu")
		(net "M_A_DQS_DN<16>")
	)
	(segment
		(start 311.88152 -22.045676)
		(end 311.88152 -17.944592)
		(width 0.14224)
		(layer "In2.Cu")
		(net "M_A_DQS_DN<16>")
	)
	(segment
		(start 294.783002 -46.297596)
		(end 294.783002 -46.136052)
		(width 0.14224)
		(layer "In2.Cu")
		(net "M_A_DQS_DN<16>")
	)
	(segment
		(start 295.303956 -45.776642)
		(end 295.303956 -45.615098)
		(width 0.14224)
		(layer "In2.Cu")
		(net "M_A_DQS_DN<16>")
	)
	(segment
		(start 298.597574 -45.2628)
		(end 298.909994 -44.95038)
		(width 0.14224)
		(layer "In2.Cu")
		(net "M_A_DQS_DN<16>")
	)
	(segment
		(start 294.262048 -46.657006)
		(end 294.441626 -46.477428)
		(width 0.14224)
		(layer "In2.Cu")
		(net "M_A_DQS_DN<16>")
	)
	(segment
		(start 311.092596 -22.8346)
		(end 311.88152 -22.045676)
		(width 0.14224)
		(layer "In2.Cu")
		(net "M_A_DQS_DN<16>")
	)
	(segment
		(start 289.004248 -51.127406)
		(end 289.183826 -50.947828)
		(width 0.14224)
		(layer "In2.Cu")
		(net "M_A_DQS_DN<16>")
	)
	(segment
		(start 297.708574 -44.95038)
		(end 298.020994 -45.2628)
		(width 0.14224)
		(layer "In2.Cu")
		(net "M_A_DQS_DN<16>")
	)
	(segment
		(start 291.623496 -48.508158)
		(end 291.815012 -48.316642)
		(width 0.14224)
		(layer "In2.Cu")
		(net "M_A_DQS_DN<16>")
	)
	(segment
		(start 286.918654 -54.018688)
		(end 286.946594 -54.018688)
		(width 0.0889)
		(layer "In2.Cu")
		(net "M_A_DQS_DN<16>")
	)
	(segment
		(start 292.497764 -47.795434)
		(end 292.677596 -47.615602)
		(width 0.14224)
		(layer "In2.Cu")
		(net "M_A_DQS_DN<16>")
	)
	(segment
		(start 290.56711 -49.726088)
		(end 290.56711 -49.564544)
		(width 0.14224)
		(layer "In2.Cu")
		(net "M_A_DQS_DN<16>")
	)
	(segment
		(start 291.815012 -48.316642)
		(end 291.97681 -48.316642)
		(width 0.14224)
		(layer "In2.Cu")
		(net "M_A_DQS_DN<16>")
	)
	(segment
		(start 289.525202 -50.606452)
		(end 289.70478 -50.426874)
		(width 0.14224)
		(layer "In2.Cu")
		(net "M_A_DQS_DN<16>")
	)
	(segment
		(start 311.67324 -36.96716)
		(end 311.67324 -26.4541)
		(width 0.14224)
		(layer "In2.Cu")
		(net "M_A_DQS_DN<16>")
	)
	(segment
		(start 290.225734 -49.90592)
		(end 290.387278 -49.90592)
		(width 0.14224)
		(layer "In2.Cu")
		(net "M_A_DQS_DN<16>")
	)
	(segment
		(start 286.58693 -54.618636)
		(end 286.582104 -54.61)
		(width 0.0889)
		(layer "In2.Cu")
		(net "M_A_DQS_DN<16>")
	)
	(arc
		(start 286.582104 -54.61)
		(mid 286.585851 -54.220744)
		(end 286.918654 -54.018688)
		(width 0.0889)
		(layer "In2.Cu")
		(net "M_A_DQS_DN<16>")
	)
	(arc
		(start 287.440624 -53.123846)
		(mid 287.391869 -52.927494)
		(end 287.44545 -52.732432)
		(width 0.0889)
		(layer "In2.Cu")
		(net "M_A_DQS_DN<16>")
	)
	(arc
		(start 286.946594 -54.018688)
		(mid 287.448603 -53.717764)
		(end 287.44545 -53.132482)
		(width 0.0889)
		(layer "In2.Cu")
		(net "M_A_DQS_DN<16>")
	)
	(arc
		(start 286.62249 -55.136542)
		(mid 286.665203 -54.879615)
		(end 286.59328 -54.629304)
		(width 0.0889)
		(layer "In2.Cu")
		(net "M_A_DQS_DN<16>")
	)
	(segment
		(start 302.64989 -16.077184)
		(end 302.64989 -15.423642)
		(width 0.1651)
		(layer "F.Cu")
		(net "M_A_DQS_DN<15>")
	)
	(segment
		(start 302.417734 -17.102328)
		(end 302.231806 -16.9164)
		(width 0.1651)
		(layer "F.Cu")
		(net "M_A_DQS_DN<15>")
	)
	(segment
		(start 302.165766 -17.60093)
		(end 302.417734 -17.348962)
		(width 0.1651)
		(layer "F.Cu")
		(net "M_A_DQS_DN<15>")
	)
	(segment
		(start 302.417734 -17.348962)
		(end 302.417734 -17.102328)
		(width 0.1651)
		(layer "F.Cu")
		(net "M_A_DQS_DN<15>")
	)
	(segment
		(start 282.354274 -55.409338)
		(end 281.782774 -55.409338)
		(width 0.1016)
		(layer "F.Cu")
		(net "M_A_DQS_DN<15>")
	)
	(segment
		(start 302.231806 -16.9164)
		(end 302.231806 -16.495268)
		(width 0.1651)
		(layer "F.Cu")
		(net "M_A_DQS_DN<15>")
	)
	(segment
		(start 302.64989 -15.423642)
		(end 302.650398 -15.423642)
		(width 0.1651)
		(layer "F.Cu")
		(net "M_A_DQS_DN<15>")
	)
	(segment
		(start 302.231806 -16.495268)
		(end 302.64989 -16.077184)
		(width 0.1651)
		(layer "F.Cu")
		(net "M_A_DQS_DN<15>")
	)
	(segment
		(start 301.749206 -17.4117)
		(end 301.768256 -17.4117)
		(width 0.1651)
		(layer "F.Cu")
		(net "M_A_DQS_DN<15>")
	)
	(segment
		(start 301.768256 -17.4117)
		(end 301.957486 -17.60093)
		(width 0.1651)
		(layer "F.Cu")
		(net "M_A_DQS_DN<15>")
	)
	(segment
		(start 301.957486 -17.60093)
		(end 302.165766 -17.60093)
		(width 0.1651)
		(layer "F.Cu")
		(net "M_A_DQS_DN<15>")
	)
	(via
		(at 281.782774 -55.409338)
		(size 0.508)
		(drill 0.254)
		(layers "F.Cu" "B.Cu")
		(net "M_A_DQS_DN<15>")
	)
	(via
		(at 301.742602 -22.8346)
		(size 0.508)
		(drill 0.254)
		(layers "F.Cu" "B.Cu")
		(net "M_A_DQS_DN<15>")
	)
	(via
		(at 301.749206 -17.4117)
		(size 0.508)
		(drill 0.254)
		(layers "F.Cu" "B.Cu")
		(net "M_A_DQS_DN<15>")
	)
	(segment
		(start 302.206406 -23.723854)
		(end 302.650144 -24.167592)
		(width 0.1651)
		(layer "B.Cu")
		(net "M_A_DQS_DN<15>")
	)
	(segment
		(start 301.937166 -22.640036)
		(end 302.164242 -22.640036)
		(width 0.1651)
		(layer "B.Cu")
		(net "M_A_DQS_DN<15>")
	)
	(segment
		(start 302.650144 -24.167592)
		(end 302.650144 -24.823928)
		(width 0.1651)
		(layer "B.Cu")
		(net "M_A_DQS_DN<15>")
	)
	(segment
		(start 302.650144 -24.823928)
		(end 302.650398 -24.824182)
		(width 0.1651)
		(layer "B.Cu")
		(net "M_A_DQS_DN<15>")
	)
	(segment
		(start 302.384206 -23.1902)
		(end 302.206406 -23.368)
		(width 0.1651)
		(layer "B.Cu")
		(net "M_A_DQS_DN<15>")
	)
	(segment
		(start 301.742602 -22.8346)
		(end 301.937166 -22.640036)
		(width 0.1651)
		(layer "B.Cu")
		(net "M_A_DQS_DN<15>")
	)
	(segment
		(start 302.164242 -22.640036)
		(end 302.384206 -22.86)
		(width 0.1651)
		(layer "B.Cu")
		(net "M_A_DQS_DN<15>")
	)
	(segment
		(start 302.206406 -23.368)
		(end 302.206406 -23.723854)
		(width 0.1651)
		(layer "B.Cu")
		(net "M_A_DQS_DN<15>")
	)
	(segment
		(start 302.384206 -22.86)
		(end 302.384206 -23.1902)
		(width 0.1651)
		(layer "B.Cu")
		(net "M_A_DQS_DN<15>")
	)
	(segment
		(start 298.020994 -35.30346)
		(end 298.020994 -34.860992)
		(width 0.14224)
		(layer "In2.Cu")
		(net "M_A_DQS_DN<15>")
	)
	(segment
		(start 281.57424 -44.7548)
		(end 281.57424 -44.5008)
		(width 0.14224)
		(layer "In2.Cu")
		(net "M_A_DQS_DN<15>")
	)
	(segment
		(start 281.639518 -43.353482)
		(end 281.801062 -43.353482)
		(width 0.14224)
		(layer "In2.Cu")
		(net "M_A_DQS_DN<15>")
	)
	(segment
		(start 301.819564 -31.50489)
		(end 302.527716 -30.796738)
		(width 0.14224)
		(layer "In2.Cu")
		(net "M_A_DQS_DN<15>")
	)
	(segment
		(start 288.96056 -36.03244)
		(end 297.292014 -36.03244)
		(width 0.14224)
		(layer "In2.Cu")
		(net "M_A_DQS_DN<15>")
	)
	(segment
		(start 281.57424 -45.3136)
		(end 281.45994 -45.1993)
		(width 0.14224)
		(layer "In2.Cu")
		(net "M_A_DQS_DN<15>")
	)
	(segment
		(start 283.596842 -41.396158)
		(end 283.852112 -41.140888)
		(width 0.14224)
		(layer "In2.Cu")
		(net "M_A_DQS_DN<15>")
	)
	(segment
		(start 301.977806 -24.003)
		(end 302.181006 -23.7998)
		(width 0.14224)
		(layer "In2.Cu")
		(net "M_A_DQS_DN<15>")
	)
	(segment
		(start 282.529788 -42.463212)
		(end 282.734512 -42.258488)
		(width 0.14224)
		(layer "In2.Cu")
		(net "M_A_DQS_DN<15>")
	)
	(segment
		(start 281.45994 -44.3865)
		(end 281.45994 -43.53306)
		(width 0.14224)
		(layer "In2.Cu")
		(net "M_A_DQS_DN<15>")
	)
	(segment
		(start 302.685196 -26.282142)
		(end 302.685196 -26.028142)
		(width 0.14224)
		(layer "In2.Cu")
		(net "M_A_DQS_DN<15>")
	)
	(segment
		(start 281.627072 -55.085996)
		(end 281.514042 -54.749446)
		(width 0.0889)
		(layer "In2.Cu")
		(net "M_A_DQS_DN<15>")
	)
	(segment
		(start 298.490386 -34.3916)
		(end 298.932854 -34.3916)
		(width 0.14224)
		(layer "In2.Cu")
		(net "M_A_DQS_DN<15>")
	)
	(segment
		(start 302.181006 -23.273004)
		(end 301.742602 -22.8346)
		(width 0.14224)
		(layer "In2.Cu")
		(net "M_A_DQS_DN<15>")
	)
	(segment
		(start 281.45994 -48.190404)
		(end 281.45994 -47.936404)
		(width 0.14224)
		(layer "In2.Cu")
		(net "M_A_DQS_DN<15>")
	)
	(segment
		(start 283.41701 -41.737534)
		(end 283.596842 -41.557702)
		(width 0.14224)
		(layer "In2.Cu")
		(net "M_A_DQS_DN<15>")
	)
	(segment
		(start 299.130212 -33.152842)
		(end 299.420788 -32.862266)
		(width 0.14224)
		(layer "In2.Cu")
		(net "M_A_DQS_DN<15>")
	)
	(segment
		(start 284.193488 -40.961056)
		(end 284.193488 -40.799512)
		(width 0.14224)
		(layer "In2.Cu")
		(net "M_A_DQS_DN<15>")
	)
	(segment
		(start 281.57424 -47.822104)
		(end 281.57424 -47.568104)
		(width 0.14224)
		(layer "In2.Cu")
		(net "M_A_DQS_DN<15>")
	)
	(segment
		(start 298.114212 -34.194242)
		(end 298.293028 -34.194242)
		(width 0.14224)
		(layer "In2.Cu")
		(net "M_A_DQS_DN<15>")
	)
	(segment
		(start 284.803088 -40.351456)
		(end 284.803088 -40.189912)
		(width 0.14224)
		(layer "In2.Cu")
		(net "M_A_DQS_DN<15>")
	)
	(segment
		(start 302.527716 -30.796738)
		(end 302.527716 -30.07868)
		(width 0.14224)
		(layer "In2.Cu")
		(net "M_A_DQS_DN<15>")
	)
	(segment
		(start 281.57424 -45.5676)
		(end 281.57424 -45.3136)
		(width 0.14224)
		(layer "In2.Cu")
		(net "M_A_DQS_DN<15>")
	)
	(segment
		(start 281.782774 -55.409338)
		(end 281.627072 -55.085996)
		(width 0.0889)
		(layer "In2.Cu")
		(net "M_A_DQS_DN<15>")
	)
	(segment
		(start 281.45994 -43.53306)
		(end 281.639518 -43.353482)
		(width 0.14224)
		(layer "In2.Cu")
		(net "M_A_DQS_DN<15>")
	)
	(segment
		(start 281.45994 -46.6725)
		(end 281.45994 -46.4185)
		(width 0.14224)
		(layer "In2.Cu")
		(net "M_A_DQS_DN<15>")
	)
	(segment
		(start 301.540926 -24.18588)
		(end 301.723806 -24.003)
		(width 0.14224)
		(layer "In2.Cu")
		(net "M_A_DQS_DN<15>")
	)
	(segment
		(start 282.734512 -42.258488)
		(end 282.896056 -42.258488)
		(width 0.14224)
		(layer "In2.Cu")
		(net "M_A_DQS_DN<15>")
	)
	(segment
		(start 281.42057 -50.37963)
		(end 281.42057 -48.251872)
		(width 0.0889)
		(layer "In2.Cu")
		(net "M_A_DQS_DN<15>")
	)
	(segment
		(start 301.540926 -24.672544)
		(end 301.540926 -24.18588)
		(width 0.14224)
		(layer "In2.Cu")
		(net "M_A_DQS_DN<15>")
	)
	(segment
		(start 281.45994 -45.6819)
		(end 281.57424 -45.5676)
		(width 0.14224)
		(layer "In2.Cu")
		(net "M_A_DQS_DN<15>")
	)
	(segment
		(start 281.57424 -47.568104)
		(end 281.45994 -47.453804)
		(width 0.14224)
		(layer "In2.Cu")
		(net "M_A_DQS_DN<15>")
	)
	(segment
		(start 281.45994 -46.4185)
		(end 281.57424 -46.3042)
		(width 0.14224)
		(layer "In2.Cu")
		(net "M_A_DQS_DN<15>")
	)
	(segment
		(start 300.659546 -32.22244)
		(end 300.411388 -31.974282)
		(width 0.14224)
		(layer "In2.Cu")
		(net "M_A_DQS_DN<15>")
	)
	(segment
		(start 284.193488 -40.799512)
		(end 284.461712 -40.531288)
		(width 0.14224)
		(layer "In2.Cu")
		(net "M_A_DQS_DN<15>")
	)
	(segment
		(start 284.461712 -40.531288)
		(end 284.623256 -40.531288)
		(width 0.14224)
		(layer "In2.Cu")
		(net "M_A_DQS_DN<15>")
	)
	(segment
		(start 282.188412 -42.804588)
		(end 282.349956 -42.804588)
		(width 0.14224)
		(layer "In2.Cu")
		(net "M_A_DQS_DN<15>")
	)
	(segment
		(start 297.292014 -36.03244)
		(end 298.020994 -35.30346)
		(width 0.14224)
		(layer "In2.Cu")
		(net "M_A_DQS_DN<15>")
	)
	(segment
		(start 282.896056 -42.258488)
		(end 283.075888 -42.078656)
		(width 0.14224)
		(layer "In2.Cu")
		(net "M_A_DQS_DN<15>")
	)
	(segment
		(start 281.42057 -48.251872)
		(end 281.45994 -48.212502)
		(width 0.0889)
		(layer "In2.Cu")
		(net "M_A_DQS_DN<15>")
	)
	(segment
		(start 281.57424 -46.0502)
		(end 281.45994 -45.9359)
		(width 0.14224)
		(layer "In2.Cu")
		(net "M_A_DQS_DN<15>")
	)
	(segment
		(start 302.527716 -26.439622)
		(end 302.685196 -26.282142)
		(width 0.14224)
		(layer "In2.Cu")
		(net "M_A_DQS_DN<15>")
	)
	(segment
		(start 302.026828 -22.550628)
		(end 302.411638 -22.165564)
		(width 0.14224)
		(layer "In2.Cu")
		(net "M_A_DQS_DN<15>")
	)
	(segment
		(start 281.519884 -54.073044)
		(end 281.519884 -51.744372)
		(width 0.0889)
		(layer "In2.Cu")
		(net "M_A_DQS_DN<15>")
	)
	(segment
		(start 302.411638 -22.165564)
		(end 302.531526 -22.045676)
		(width 0.14224)
		(layer "In2.Cu")
		(net "M_A_DQS_DN<15>")
	)
	(segment
		(start 281.433016 -54.61381)
		(end 281.430984 -54.610254)
		(width 0.0889)
		(layer "In2.Cu")
		(net "M_A_DQS_DN<15>")
	)
	(segment
		(start 302.527716 -29.50972)
		(end 302.527716 -26.439622)
		(width 0.14224)
		(layer "In2.Cu")
		(net "M_A_DQS_DN<15>")
	)
	(segment
		(start 297.823636 -34.484818)
		(end 298.114212 -34.194242)
		(width 0.14224)
		(layer "In2.Cu")
		(net "M_A_DQS_DN<15>")
	)
	(segment
		(start 299.34027 -33.541716)
		(end 299.130212 -33.331658)
		(width 0.14224)
		(layer "In2.Cu")
		(net "M_A_DQS_DN<15>")
	)
	(segment
		(start 283.075888 -41.917112)
		(end 283.255466 -41.737534)
		(width 0.14224)
		(layer "In2.Cu")
		(net "M_A_DQS_DN<15>")
	)
	(segment
		(start 283.255466 -41.737534)
		(end 283.41701 -41.737534)
		(width 0.14224)
		(layer "In2.Cu")
		(net "M_A_DQS_DN<15>")
	)
	(segment
		(start 298.293028 -34.194242)
		(end 298.490386 -34.3916)
		(width 0.14224)
		(layer "In2.Cu")
		(net "M_A_DQS_DN<15>")
	)
	(segment
		(start 301.944786 -17.60728)
		(end 301.749206 -17.4117)
		(width 0.14224)
		(layer "In2.Cu")
		(net "M_A_DQS_DN<15>")
	)
	(segment
		(start 281.57424 -44.5008)
		(end 281.45994 -44.3865)
		(width 0.14224)
		(layer "In2.Cu")
		(net "M_A_DQS_DN<15>")
	)
	(segment
		(start 281.980894 -43.012106)
		(end 282.188412 -42.804588)
		(width 0.14224)
		(layer "In2.Cu")
		(net "M_A_DQS_DN<15>")
	)
	(segment
		(start 281.514042 -54.749446)
		(end 281.433016 -54.61381)
		(width 0.0889)
		(layer "In2.Cu")
		(net "M_A_DQS_DN<15>")
	)
	(segment
		(start 302.194214 -17.60728)
		(end 301.944786 -17.60728)
		(width 0.14224)
		(layer "In2.Cu")
		(net "M_A_DQS_DN<15>")
	)
	(segment
		(start 283.596842 -41.557702)
		(end 283.596842 -41.396158)
		(width 0.14224)
		(layer "In2.Cu")
		(net "M_A_DQS_DN<15>")
	)
	(segment
		(start 282.349956 -42.804588)
		(end 282.529788 -42.624756)
		(width 0.14224)
		(layer "In2.Cu")
		(net "M_A_DQS_DN<15>")
	)
	(segment
		(start 302.685196 -26.028142)
		(end 302.527716 -25.870662)
		(width 0.14224)
		(layer "In2.Cu")
		(net "M_A_DQS_DN<15>")
	)
	(segment
		(start 300.659546 -32.664908)
		(end 300.659546 -32.22244)
		(width 0.14224)
		(layer "In2.Cu")
		(net "M_A_DQS_DN<15>")
	)
	(segment
		(start 281.57424 -46.3042)
		(end 281.57424 -46.0502)
		(width 0.14224)
		(layer "In2.Cu")
		(net "M_A_DQS_DN<15>")
	)
	(segment
		(start 301.742602 -22.8346)
		(end 302.026828 -22.550628)
		(width 0.14224)
		(layer "In2.Cu")
		(net "M_A_DQS_DN<15>")
	)
	(segment
		(start 302.527716 -30.07868)
		(end 302.685196 -29.9212)
		(width 0.14224)
		(layer "In2.Cu")
		(net "M_A_DQS_DN<15>")
	)
	(segment
		(start 298.020994 -34.860992)
		(end 297.823636 -34.663634)
		(width 0.14224)
		(layer "In2.Cu")
		(net "M_A_DQS_DN<15>")
	)
	(segment
		(start 283.075888 -42.078656)
		(end 283.075888 -41.917112)
		(width 0.14224)
		(layer "In2.Cu")
		(net "M_A_DQS_DN<15>")
	)
	(segment
		(start 284.013656 -41.140888)
		(end 284.193488 -40.961056)
		(width 0.14224)
		(layer "In2.Cu")
		(net "M_A_DQS_DN<15>")
	)
	(segment
		(start 302.531526 -17.944592)
		(end 302.194214 -17.60728)
		(width 0.14224)
		(layer "In2.Cu")
		(net "M_A_DQS_DN<15>")
	)
	(segment
		(start 300.25213 -33.072324)
		(end 300.659546 -32.664908)
		(width 0.14224)
		(layer "In2.Cu")
		(net "M_A_DQS_DN<15>")
	)
	(segment
		(start 281.57424 -46.7868)
		(end 281.45994 -46.6725)
		(width 0.14224)
		(layer "In2.Cu")
		(net "M_A_DQS_DN<15>")
	)
	(segment
		(start 281.45994 -47.1551)
		(end 281.57424 -47.0408)
		(width 0.14224)
		(layer "In2.Cu")
		(net "M_A_DQS_DN<15>")
	)
	(segment
		(start 302.685196 -29.6672)
		(end 302.527716 -29.50972)
		(width 0.14224)
		(layer "In2.Cu")
		(net "M_A_DQS_DN<15>")
	)
	(segment
		(start 300.411388 -31.974282)
		(end 300.411388 -31.795466)
		(width 0.14224)
		(layer "In2.Cu")
		(net "M_A_DQS_DN<15>")
	)
	(segment
		(start 297.823636 -34.663634)
		(end 297.823636 -34.484818)
		(width 0.14224)
		(layer "In2.Cu")
		(net "M_A_DQS_DN<15>")
	)
	(segment
		(start 281.57424 -47.0408)
		(end 281.57424 -46.7868)
		(width 0.14224)
		(layer "In2.Cu")
		(net "M_A_DQS_DN<15>")
	)
	(segment
		(start 281.076908 -51.301396)
		(end 281.076908 -50.723292)
		(width 0.0889)
		(layer "In2.Cu")
		(net "M_A_DQS_DN<15>")
	)
	(segment
		(start 302.527716 -25.659334)
		(end 301.540926 -24.672544)
		(width 0.14224)
		(layer "In2.Cu")
		(net "M_A_DQS_DN<15>")
	)
	(segment
		(start 281.45994 -45.1993)
		(end 281.45994 -44.8691)
		(width 0.14224)
		(layer "In2.Cu")
		(net "M_A_DQS_DN<15>")
	)
	(segment
		(start 299.130212 -33.331658)
		(end 299.130212 -33.152842)
		(width 0.14224)
		(layer "In2.Cu")
		(net "M_A_DQS_DN<15>")
	)
	(segment
		(start 282.529788 -42.624756)
		(end 282.529788 -42.463212)
		(width 0.14224)
		(layer "In2.Cu")
		(net "M_A_DQS_DN<15>")
	)
	(segment
		(start 281.801062 -43.353482)
		(end 281.980894 -43.17365)
		(width 0.14224)
		(layer "In2.Cu")
		(net "M_A_DQS_DN<15>")
	)
	(segment
		(start 281.45994 -44.8691)
		(end 281.57424 -44.7548)
		(width 0.14224)
		(layer "In2.Cu")
		(net "M_A_DQS_DN<15>")
	)
	(segment
		(start 298.932854 -34.3916)
		(end 299.34027 -33.984184)
		(width 0.14224)
		(layer "In2.Cu")
		(net "M_A_DQS_DN<15>")
	)
	(segment
		(start 281.076908 -50.723292)
		(end 281.42057 -50.37963)
		(width 0.0889)
		(layer "In2.Cu")
		(net "M_A_DQS_DN<15>")
	)
	(segment
		(start 281.45994 -47.453804)
		(end 281.45994 -47.1551)
		(width 0.14224)
		(layer "In2.Cu")
		(net "M_A_DQS_DN<15>")
	)
	(segment
		(start 284.803088 -40.189912)
		(end 288.96056 -36.03244)
		(width 0.14224)
		(layer "In2.Cu")
		(net "M_A_DQS_DN<15>")
	)
	(segment
		(start 300.411388 -31.795466)
		(end 300.701964 -31.50489)
		(width 0.14224)
		(layer "In2.Cu")
		(net "M_A_DQS_DN<15>")
	)
	(segment
		(start 281.519884 -51.744372)
		(end 281.076908 -51.301396)
		(width 0.0889)
		(layer "In2.Cu")
		(net "M_A_DQS_DN<15>")
	)
	(segment
		(start 302.527716 -25.870662)
		(end 302.527716 -25.659334)
		(width 0.14224)
		(layer "In2.Cu")
		(net "M_A_DQS_DN<15>")
	)
	(segment
		(start 302.181006 -23.7998)
		(end 302.181006 -23.273004)
		(width 0.14224)
		(layer "In2.Cu")
		(net "M_A_DQS_DN<15>")
	)
	(segment
		(start 299.420788 -32.862266)
		(end 299.599604 -32.862266)
		(width 0.14224)
		(layer "In2.Cu")
		(net "M_A_DQS_DN<15>")
	)
	(segment
		(start 283.852112 -41.140888)
		(end 284.013656 -41.140888)
		(width 0.14224)
		(layer "In2.Cu")
		(net "M_A_DQS_DN<15>")
	)
	(segment
		(start 302.685196 -29.9212)
		(end 302.685196 -29.6672)
		(width 0.14224)
		(layer "In2.Cu")
		(net "M_A_DQS_DN<15>")
	)
	(segment
		(start 300.701964 -31.50489)
		(end 301.819564 -31.50489)
		(width 0.14224)
		(layer "In2.Cu")
		(net "M_A_DQS_DN<15>")
	)
	(segment
		(start 281.980894 -43.17365)
		(end 281.980894 -43.012106)
		(width 0.14224)
		(layer "In2.Cu")
		(net "M_A_DQS_DN<15>")
	)
	(segment
		(start 281.45994 -47.936404)
		(end 281.57424 -47.822104)
		(width 0.14224)
		(layer "In2.Cu")
		(net "M_A_DQS_DN<15>")
	)
	(segment
		(start 281.436064 -54.21884)
		(end 281.519884 -54.073044)
		(width 0.0889)
		(layer "In2.Cu")
		(net "M_A_DQS_DN<15>")
	)
	(segment
		(start 302.531526 -22.045676)
		(end 302.531526 -17.944592)
		(width 0.14224)
		(layer "In2.Cu")
		(net "M_A_DQS_DN<15>")
	)
	(segment
		(start 281.45994 -48.212502)
		(end 281.45994 -48.190404)
		(width 0.0889)
		(layer "In2.Cu")
		(net "M_A_DQS_DN<15>")
	)
	(segment
		(start 281.45994 -45.9359)
		(end 281.45994 -45.6819)
		(width 0.14224)
		(layer "In2.Cu")
		(net "M_A_DQS_DN<15>")
	)
	(segment
		(start 299.34027 -33.984184)
		(end 299.34027 -33.541716)
		(width 0.14224)
		(layer "In2.Cu")
		(net "M_A_DQS_DN<15>")
	)
	(segment
		(start 301.723806 -24.003)
		(end 301.977806 -24.003)
		(width 0.14224)
		(layer "In2.Cu")
		(net "M_A_DQS_DN<15>")
	)
	(segment
		(start 299.809662 -33.072324)
		(end 300.25213 -33.072324)
		(width 0.14224)
		(layer "In2.Cu")
		(net "M_A_DQS_DN<15>")
	)
	(segment
		(start 299.599604 -32.862266)
		(end 299.809662 -33.072324)
		(width 0.14224)
		(layer "In2.Cu")
		(net "M_A_DQS_DN<15>")
	)
	(segment
		(start 284.623256 -40.531288)
		(end 284.803088 -40.351456)
		(width 0.14224)
		(layer "In2.Cu")
		(net "M_A_DQS_DN<15>")
	)
	(arc
		(start 281.430984 -54.610254)
		(mid 281.382385 -54.413872)
		(end 281.436064 -54.21884)
		(width 0.0889)
		(layer "In2.Cu")
		(net "M_A_DQS_DN<15>")
	)
	(segment
		(start 293.299896 -15.423642)
		(end 293.299896 -16.077184)
		(width 0.1651)
		(layer "F.Cu")
		(net "M_A_DQS_DN<14>")
	)
	(segment
		(start 293.06774 -17.102328)
		(end 293.06774 -17.348962)
		(width 0.1651)
		(layer "F.Cu")
		(net "M_A_DQS_DN<14>")
	)
	(segment
		(start 292.881812 -16.495268)
		(end 292.881812 -16.9164)
		(width 0.1651)
		(layer "F.Cu")
		(net "M_A_DQS_DN<14>")
	)
	(segment
		(start 293.299896 -16.077184)
		(end 292.881812 -16.495268)
		(width 0.1651)
		(layer "F.Cu")
		(net "M_A_DQS_DN<14>")
	)
	(segment
		(start 293.300404 -15.423642)
		(end 293.299896 -15.423642)
		(width 0.1651)
		(layer "F.Cu")
		(net "M_A_DQS_DN<14>")
	)
	(segment
		(start 293.06774 -17.348962)
		(end 292.815772 -17.60093)
		(width 0.1651)
		(layer "F.Cu")
		(net "M_A_DQS_DN<14>")
	)
	(segment
		(start 277.203154 -55.409338)
		(end 276.631654 -55.409338)
		(width 0.1016)
		(layer "F.Cu")
		(net "M_A_DQS_DN<14>")
	)
	(segment
		(start 292.607492 -17.60093)
		(end 292.418262 -17.4117)
		(width 0.1651)
		(layer "F.Cu")
		(net "M_A_DQS_DN<14>")
	)
	(segment
		(start 292.418262 -17.4117)
		(end 292.399212 -17.4117)
		(width 0.1651)
		(layer "F.Cu")
		(net "M_A_DQS_DN<14>")
	)
	(segment
		(start 292.881812 -16.9164)
		(end 293.06774 -17.102328)
		(width 0.1651)
		(layer "F.Cu")
		(net "M_A_DQS_DN<14>")
	)
	(segment
		(start 292.815772 -17.60093)
		(end 292.607492 -17.60093)
		(width 0.1651)
		(layer "F.Cu")
		(net "M_A_DQS_DN<14>")
	)
	(via
		(at 292.399212 -17.4117)
		(size 0.508)
		(drill 0.254)
		(layers "F.Cu" "B.Cu")
		(net "M_A_DQS_DN<14>")
	)
	(via
		(at 276.631654 -55.409338)
		(size 0.508)
		(drill 0.254)
		(layers "F.Cu" "B.Cu")
		(net "M_A_DQS_DN<14>")
	)
	(via
		(at 292.392608 -22.8346)
		(size 0.508)
		(drill 0.254)
		(layers "F.Cu" "B.Cu")
		(net "M_A_DQS_DN<14>")
	)
	(segment
		(start 293.30015 -24.823928)
		(end 293.300404 -24.824182)
		(width 0.1651)
		(layer "B.Cu")
		(net "M_A_DQS_DN<14>")
	)
	(segment
		(start 292.587172 -22.640036)
		(end 292.814248 -22.640036)
		(width 0.1651)
		(layer "B.Cu")
		(net "M_A_DQS_DN<14>")
	)
	(segment
		(start 292.814248 -22.640036)
		(end 293.034212 -22.86)
		(width 0.1651)
		(layer "B.Cu")
		(net "M_A_DQS_DN<14>")
	)
	(segment
		(start 292.392608 -22.8346)
		(end 292.587172 -22.640036)
		(width 0.1651)
		(layer "B.Cu")
		(net "M_A_DQS_DN<14>")
	)
	(segment
		(start 293.30015 -24.167592)
		(end 293.30015 -24.823928)
		(width 0.1651)
		(layer "B.Cu")
		(net "M_A_DQS_DN<14>")
	)
	(segment
		(start 293.034212 -23.1902)
		(end 292.856412 -23.368)
		(width 0.1651)
		(layer "B.Cu")
		(net "M_A_DQS_DN<14>")
	)
	(segment
		(start 293.034212 -22.86)
		(end 293.034212 -23.1902)
		(width 0.1651)
		(layer "B.Cu")
		(net "M_A_DQS_DN<14>")
	)
	(segment
		(start 292.856412 -23.723854)
		(end 293.30015 -24.167592)
		(width 0.1651)
		(layer "B.Cu")
		(net "M_A_DQS_DN<14>")
	)
	(segment
		(start 292.856412 -23.368)
		(end 292.856412 -23.723854)
		(width 0.1651)
		(layer "B.Cu")
		(net "M_A_DQS_DN<14>")
	)
	(segment
		(start 276.362922 -54.749446)
		(end 276.281896 -54.61381)
		(width 0.0889)
		(layer "In2.Cu")
		(net "M_A_DQS_DN<14>")
	)
	(segment
		(start 292.262052 -24.003)
		(end 292.49116 -24.003)
		(width 0.14224)
		(layer "In2.Cu")
		(net "M_A_DQS_DN<14>")
	)
	(segment
		(start 274.1422 -45.0215)
		(end 274.1422 -44.7675)
		(width 0.14224)
		(layer "In2.Cu")
		(net "M_A_DQS_DN<14>")
	)
	(segment
		(start 293.181532 -22.045676)
		(end 293.181532 -17.944592)
		(width 0.14224)
		(layer "In2.Cu")
		(net "M_A_DQS_DN<14>")
	)
	(segment
		(start 274.1422 -40.3479)
		(end 274.2565 -40.2336)
		(width 0.14224)
		(layer "In2.Cu")
		(net "M_A_DQS_DN<14>")
	)
	(segment
		(start 287.711642 -27.096212)
		(end 288.808414 -25.99944)
		(width 0.14224)
		(layer "In2.Cu")
		(net "M_A_DQS_DN<14>")
	)
	(segment
		(start 274.2565 -43.9166)
		(end 274.2565 -43.6626)
		(width 0.14224)
		(layer "In2.Cu")
		(net "M_A_DQS_DN<14>")
	)
	(segment
		(start 292.274752 -24.7269)
		(end 292.274752 -24.4729)
		(width 0.14224)
		(layer "In2.Cu")
		(net "M_A_DQS_DN<14>")
	)
	(segment
		(start 274.33651 -47.062898)
		(end 274.33651 -46.7106)
		(width 0.14224)
		(layer "In2.Cu")
		(net "M_A_DQS_DN<14>")
	)
	(segment
		(start 276.850602 -34.604198)
		(end 277.259034 -34.195766)
		(width 0.14224)
		(layer "In2.Cu")
		(net "M_A_DQS_DN<14>")
	)
	(segment
		(start 274.1422 -45.5041)
		(end 274.2565 -45.3898)
		(width 0.14224)
		(layer "In2.Cu")
		(net "M_A_DQS_DN<14>")
	)
	(segment
		(start 276.279864 -54.610254)
		(end 276.280118 -54.61)
		(width 0.0889)
		(layer "In2.Cu")
		(net "M_A_DQS_DN<14>")
	)
	(segment
		(start 287.370012 -27.437842)
		(end 287.53181 -27.437842)
		(width 0.14224)
		(layer "In2.Cu")
		(net "M_A_DQS_DN<14>")
	)
	(segment
		(start 292.831012 -23.663148)
		(end 292.831012 -23.273004)
		(width 0.14224)
		(layer "In2.Cu")
		(net "M_A_DQS_DN<14>")
	)
	(segment
		(start 274.1422 -46.51629)
		(end 274.1422 -46.2407)
		(width 0.14224)
		(layer "In2.Cu")
		(net "M_A_DQS_DN<14>")
	)
	(segment
		(start 274.629372 -35.682428)
		(end 274.84832 -35.682428)
		(width 0.14224)
		(layer "In2.Cu")
		(net "M_A_DQS_DN<14>")
	)
	(segment
		(start 274.2565 -42.926)
		(end 274.1422 -42.8117)
		(width 0.14224)
		(layer "In2.Cu")
		(net "M_A_DQS_DN<14>")
	)
	(segment
		(start 276.408642 -34.604198)
		(end 276.850602 -34.604198)
		(width 0.14224)
		(layer "In2.Cu")
		(net "M_A_DQS_DN<14>")
	)
	(segment
		(start 274.1422 -41.085008)
		(end 274.2565 -40.970708)
		(width 0.14224)
		(layer "In2.Cu")
		(net "M_A_DQS_DN<14>")
	)
	(segment
		(start 291.467032 -25.99944)
		(end 292.160452 -25.30602)
		(width 0.14224)
		(layer "In2.Cu")
		(net "M_A_DQS_DN<14>")
	)
	(segment
		(start 292.160452 -24.8412)
		(end 292.274752 -24.7269)
		(width 0.14224)
		(layer "In2.Cu")
		(net "M_A_DQS_DN<14>")
	)
	(segment
		(start 292.160452 -24.1046)
		(end 292.262052 -24.003)
		(width 0.14224)
		(layer "In2.Cu")
		(net "M_A_DQS_DN<14>")
	)
	(segment
		(start 275.698712 -34.832036)
		(end 275.698712 -34.613088)
		(width 0.14224)
		(layer "In2.Cu")
		(net "M_A_DQS_DN<14>")
	)
	(segment
		(start 274.1422 -46.2407)
		(end 274.2565 -46.1264)
		(width 0.14224)
		(layer "In2.Cu")
		(net "M_A_DQS_DN<14>")
	)
	(segment
		(start 292.160452 -24.3586)
		(end 292.160452 -24.1046)
		(width 0.14224)
		(layer "In2.Cu")
		(net "M_A_DQS_DN<14>")
	)
	(segment
		(start 276.281896 -54.61381)
		(end 276.279864 -54.610254)
		(width 0.0889)
		(layer "In2.Cu")
		(net "M_A_DQS_DN<14>")
	)
	(segment
		(start 278.861266 -32.024574)
		(end 278.68372 -31.847028)
		(width 0.14224)
		(layer "In2.Cu")
		(net "M_A_DQS_DN<14>")
	)
	(segment
		(start 274.1422 -41.3385)
		(end 274.1422 -41.085008)
		(width 0.14224)
		(layer "In2.Cu")
		(net "M_A_DQS_DN<14>")
	)
	(segment
		(start 277.017988 -33.293812)
		(end 277.61438 -32.69742)
		(width 0.14224)
		(layer "In2.Cu")
		(net "M_A_DQS_DN<14>")
	)
	(segment
		(start 275.939758 -35.073082)
		(end 275.698712 -34.832036)
		(width 0.14224)
		(layer "In2.Cu")
		(net "M_A_DQS_DN<14>")
	)
	(segment
		(start 292.594792 -17.60728)
		(end 292.399212 -17.4117)
		(width 0.14224)
		(layer "In2.Cu")
		(net "M_A_DQS_DN<14>")
	)
	(segment
		(start 278.861266 -32.466534)
		(end 278.861266 -32.024574)
		(width 0.14224)
		(layer "In2.Cu")
		(net "M_A_DQS_DN<14>")
	)
	(segment
		(start 276.284944 -53.628036)
		(end 276.095206 -53.299106)
		(width 0.0889)
		(layer "In2.Cu")
		(net "M_A_DQS_DN<14>")
	)
	(segment
		(start 278.933656 -31.378144)
		(end 279.152604 -31.378144)
		(width 0.14224)
		(layer "In2.Cu")
		(net "M_A_DQS_DN<14>")
	)
	(segment
		(start 274.1422 -42.5577)
		(end 274.2565 -42.4434)
		(width 0.14224)
		(layer "In2.Cu")
		(net "M_A_DQS_DN<14>")
	)
	(segment
		(start 274.2565 -40.7162)
		(end 274.1422 -40.6019)
		(width 0.14224)
		(layer "In2.Cu")
		(net "M_A_DQS_DN<14>")
	)
	(segment
		(start 278.68372 -31.847028)
		(end 278.68372 -31.62808)
		(width 0.14224)
		(layer "In2.Cu")
		(net "M_A_DQS_DN<14>")
	)
	(segment
		(start 292.49116 -24.003)
		(end 292.831012 -23.663148)
		(width 0.14224)
		(layer "In2.Cu")
		(net "M_A_DQS_DN<14>")
	)
	(segment
		(start 274.1422 -44.0309)
		(end 274.2565 -43.9166)
		(width 0.14224)
		(layer "In2.Cu")
		(net "M_A_DQS_DN<14>")
	)
	(segment
		(start 274.84832 -35.682428)
		(end 275.089366 -35.923474)
		(width 0.14224)
		(layer "In2.Cu")
		(net "M_A_DQS_DN<14>")
	)
	(segment
		(start 275.948648 -34.363152)
		(end 276.167596 -34.363152)
		(width 0.14224)
		(layer "In2.Cu")
		(net "M_A_DQS_DN<14>")
	)
	(segment
		(start 286.954214 -27.85364)
		(end 287.370012 -27.437842)
		(width 0.14224)
		(layer "In2.Cu")
		(net "M_A_DQS_DN<14>")
	)
	(segment
		(start 274.2565 -44.6532)
		(end 274.2565 -44.3992)
		(width 0.14224)
		(layer "In2.Cu")
		(net "M_A_DQS_DN<14>")
	)
	(segment
		(start 274.2565 -39.3954)
		(end 274.2565 -39.1414)
		(width 0.14224)
		(layer "In2.Cu")
		(net "M_A_DQS_DN<14>")
	)
	(segment
		(start 280.002996 -30.527752)
		(end 280.002996 -30.308804)
		(width 0.14224)
		(layer "In2.Cu")
		(net "M_A_DQS_DN<14>")
	)
	(segment
		(start 275.531326 -35.923474)
		(end 275.939758 -35.515042)
		(width 0.14224)
		(layer "In2.Cu")
		(net "M_A_DQS_DN<14>")
	)
	(segment
		(start 274.2565 -45.8724)
		(end 274.1422 -45.7581)
		(width 0.14224)
		(layer "In2.Cu")
		(net "M_A_DQS_DN<14>")
	)
	(segment
		(start 285.43504 -28.1178)
		(end 285.6992 -27.85364)
		(width 0.14224)
		(layer "In2.Cu")
		(net "M_A_DQS_DN<14>")
	)
	(segment
		(start 278.68372 -31.62808)
		(end 278.933656 -31.378144)
		(width 0.14224)
		(layer "In2.Cu")
		(net "M_A_DQS_DN<14>")
	)
	(segment
		(start 277.833328 -32.69742)
		(end 278.010874 -32.874966)
		(width 0.14224)
		(layer "In2.Cu")
		(net "M_A_DQS_DN<14>")
	)
	(segment
		(start 283.65196 -28.1178)
		(end 285.43504 -28.1178)
		(width 0.14224)
		(layer "In2.Cu")
		(net "M_A_DQS_DN<14>")
	)
	(segment
		(start 274.2565 -39.1414)
		(end 274.1422 -39.0271)
		(width 0.14224)
		(layer "In2.Cu")
		(net "M_A_DQS_DN<14>")
	)
	(segment
		(start 274.2565 -41.7068)
		(end 274.2565 -41.4528)
		(width 0.14224)
		(layer "In2.Cu")
		(net "M_A_DQS_DN<14>")
	)
	(segment
		(start 274.33651 -46.7106)
		(end 274.1422 -46.51629)
		(width 0.14224)
		(layer "In2.Cu")
		(net "M_A_DQS_DN<14>")
	)
	(segment
		(start 292.831012 -23.273004)
		(end 292.392608 -22.8346)
		(width 0.14224)
		(layer "In2.Cu")
		(net "M_A_DQS_DN<14>")
	)
	(segment
		(start 274.2565 -44.3992)
		(end 274.1422 -44.2849)
		(width 0.14224)
		(layer "In2.Cu")
		(net "M_A_DQS_DN<14>")
	)
	(segment
		(start 292.392608 -22.8346)
		(end 293.181532 -22.045676)
		(width 0.14224)
		(layer "In2.Cu")
		(net "M_A_DQS_DN<14>")
	)
	(segment
		(start 292.160452 -25.30602)
		(end 292.160452 -24.8412)
		(width 0.14224)
		(layer "In2.Cu")
		(net "M_A_DQS_DN<14>")
	)
	(segment
		(start 278.452834 -32.874966)
		(end 278.861266 -32.466534)
		(width 0.14224)
		(layer "In2.Cu")
		(net "M_A_DQS_DN<14>")
	)
	(segment
		(start 275.089366 -35.923474)
		(end 275.531326 -35.923474)
		(width 0.14224)
		(layer "In2.Cu")
		(net "M_A_DQS_DN<14>")
	)
	(segment
		(start 277.259034 -34.195766)
		(end 277.259034 -33.753806)
		(width 0.14224)
		(layer "In2.Cu")
		(net "M_A_DQS_DN<14>")
	)
	(segment
		(start 274.1422 -44.7675)
		(end 274.2565 -44.6532)
		(width 0.14224)
		(layer "In2.Cu")
		(net "M_A_DQS_DN<14>")
	)
	(segment
		(start 274.1422 -36.1696)
		(end 274.629372 -35.682428)
		(width 0.14224)
		(layer "In2.Cu")
		(net "M_A_DQS_DN<14>")
	)
	(segment
		(start 274.1422 -40.6019)
		(end 274.1422 -40.3479)
		(width 0.14224)
		(layer "In2.Cu")
		(net "M_A_DQS_DN<14>")
	)
	(segment
		(start 277.259034 -33.753806)
		(end 277.017988 -33.51276)
		(width 0.14224)
		(layer "In2.Cu")
		(net "M_A_DQS_DN<14>")
	)
	(segment
		(start 288.808414 -25.99944)
		(end 289.4457 -25.99944)
		(width 0.14224)
		(layer "In2.Cu")
		(net "M_A_DQS_DN<14>")
	)
	(segment
		(start 292.84422 -17.60728)
		(end 292.594792 -17.60728)
		(width 0.14224)
		(layer "In2.Cu")
		(net "M_A_DQS_DN<14>")
	)
	(segment
		(start 293.181532 -17.944592)
		(end 292.84422 -17.60728)
		(width 0.14224)
		(layer "In2.Cu")
		(net "M_A_DQS_DN<14>")
	)
	(segment
		(start 274.1422 -39.8653)
		(end 274.1422 -39.5097)
		(width 0.14224)
		(layer "In2.Cu")
		(net "M_A_DQS_DN<14>")
	)
	(segment
		(start 280.180542 -30.705298)
		(end 280.002996 -30.527752)
		(width 0.14224)
		(layer "In2.Cu")
		(net "M_A_DQS_DN<14>")
	)
	(segment
		(start 274.2565 -45.1358)
		(end 274.1422 -45.0215)
		(width 0.14224)
		(layer "In2.Cu")
		(net "M_A_DQS_DN<14>")
	)
	(segment
		(start 276.095206 -53.299106)
		(end 276.095206 -52.977542)
		(width 0.0889)
		(layer "In2.Cu")
		(net "M_A_DQS_DN<14>")
	)
	(segment
		(start 274.1422 -38.7477)
		(end 274.2565 -38.6334)
		(width 0.14224)
		(layer "In2.Cu")
		(net "M_A_DQS_DN<14>")
	)
	(segment
		(start 274.1422 -43.2943)
		(end 274.2565 -43.18)
		(width 0.14224)
		(layer "In2.Cu")
		(net "M_A_DQS_DN<14>")
	)
	(segment
		(start 275.355558 -51.135026)
		(end 274.29714 -50.076608)
		(width 0.0889)
		(layer "In2.Cu")
		(net "M_A_DQS_DN<14>")
	)
	(segment
		(start 280.002996 -30.308804)
		(end 282.45816 -27.85364)
		(width 0.14224)
		(layer "In2.Cu")
		(net "M_A_DQS_DN<14>")
	)
	(segment
		(start 274.2565 -40.970708)
		(end 274.2565 -40.7162)
		(width 0.14224)
		(layer "In2.Cu")
		(net "M_A_DQS_DN<14>")
	)
	(segment
		(start 277.61438 -32.69742)
		(end 277.833328 -32.69742)
		(width 0.14224)
		(layer "In2.Cu")
		(net "M_A_DQS_DN<14>")
	)
	(segment
		(start 276.095206 -52.977542)
		(end 275.355558 -52.237894)
		(width 0.0889)
		(layer "In2.Cu")
		(net "M_A_DQS_DN<14>")
	)
	(segment
		(start 274.2565 -38.6334)
		(end 274.2565 -38.3794)
		(width 0.14224)
		(layer "In2.Cu")
		(net "M_A_DQS_DN<14>")
	)
	(segment
		(start 275.939758 -35.515042)
		(end 275.939758 -35.073082)
		(width 0.14224)
		(layer "In2.Cu")
		(net "M_A_DQS_DN<14>")
	)
	(segment
		(start 283.3878 -27.85364)
		(end 283.65196 -28.1178)
		(width 0.14224)
		(layer "In2.Cu")
		(net "M_A_DQS_DN<14>")
	)
	(segment
		(start 279.77211 -31.55569)
		(end 280.180542 -31.147258)
		(width 0.14224)
		(layer "In2.Cu")
		(net "M_A_DQS_DN<14>")
	)
	(segment
		(start 278.010874 -32.874966)
		(end 278.452834 -32.874966)
		(width 0.14224)
		(layer "In2.Cu")
		(net "M_A_DQS_DN<14>")
	)
	(segment
		(start 274.2565 -42.1894)
		(end 274.1422 -42.0751)
		(width 0.14224)
		(layer "In2.Cu")
		(net "M_A_DQS_DN<14>")
	)
	(segment
		(start 289.4457 -25.99944)
		(end 289.56 -26.11374)
		(width 0.14224)
		(layer "In2.Cu")
		(net "M_A_DQS_DN<14>")
	)
	(segment
		(start 274.1422 -42.0751)
		(end 274.1422 -41.8211)
		(width 0.14224)
		(layer "In2.Cu")
		(net "M_A_DQS_DN<14>")
	)
	(segment
		(start 274.2565 -46.1264)
		(end 274.2565 -45.8724)
		(width 0.14224)
		(layer "In2.Cu")
		(net "M_A_DQS_DN<14>")
	)
	(segment
		(start 276.631654 -55.409338)
		(end 276.475952 -55.085996)
		(width 0.0889)
		(layer "In2.Cu")
		(net "M_A_DQS_DN<14>")
	)
	(segment
		(start 274.1422 -45.7581)
		(end 274.1422 -45.5041)
		(width 0.14224)
		(layer "In2.Cu")
		(net "M_A_DQS_DN<14>")
	)
	(segment
		(start 274.1422 -39.0271)
		(end 274.1422 -38.7477)
		(width 0.14224)
		(layer "In2.Cu")
		(net "M_A_DQS_DN<14>")
	)
	(segment
		(start 274.2565 -43.18)
		(end 274.2565 -42.926)
		(width 0.14224)
		(layer "In2.Cu")
		(net "M_A_DQS_DN<14>")
	)
	(segment
		(start 287.53181 -27.437842)
		(end 287.711642 -27.25801)
		(width 0.14224)
		(layer "In2.Cu")
		(net "M_A_DQS_DN<14>")
	)
	(segment
		(start 274.29714 -47.102268)
		(end 274.33651 -47.062898)
		(width 0.0889)
		(layer "In2.Cu")
		(net "M_A_DQS_DN<14>")
	)
	(segment
		(start 276.167596 -34.363152)
		(end 276.408642 -34.604198)
		(width 0.14224)
		(layer "In2.Cu")
		(net "M_A_DQS_DN<14>")
	)
	(segment
		(start 274.2565 -41.4528)
		(end 274.1422 -41.3385)
		(width 0.14224)
		(layer "In2.Cu")
		(net "M_A_DQS_DN<14>")
	)
	(segment
		(start 276.475952 -55.085996)
		(end 276.362922 -54.749446)
		(width 0.0889)
		(layer "In2.Cu")
		(net "M_A_DQS_DN<14>")
	)
	(segment
		(start 277.017988 -33.51276)
		(end 277.017988 -33.293812)
		(width 0.14224)
		(layer "In2.Cu")
		(net "M_A_DQS_DN<14>")
	)
	(segment
		(start 274.2565 -38.3794)
		(end 274.1422 -38.2651)
		(width 0.14224)
		(layer "In2.Cu")
		(net "M_A_DQS_DN<14>")
	)
	(segment
		(start 274.2565 -39.9796)
		(end 274.1422 -39.8653)
		(width 0.14224)
		(layer "In2.Cu")
		(net "M_A_DQS_DN<14>")
	)
	(segment
		(start 289.56 -26.11374)
		(end 289.814 -26.11374)
		(width 0.14224)
		(layer "In2.Cu")
		(net "M_A_DQS_DN<14>")
	)
	(segment
		(start 274.2565 -43.6626)
		(end 274.1422 -43.5483)
		(width 0.14224)
		(layer "In2.Cu")
		(net "M_A_DQS_DN<14>")
	)
	(segment
		(start 274.2565 -40.2336)
		(end 274.2565 -39.9796)
		(width 0.14224)
		(layer "In2.Cu")
		(net "M_A_DQS_DN<14>")
	)
	(segment
		(start 274.29714 -50.076608)
		(end 274.29714 -47.102268)
		(width 0.0889)
		(layer "In2.Cu")
		(net "M_A_DQS_DN<14>")
	)
	(segment
		(start 274.2565 -42.4434)
		(end 274.2565 -42.1894)
		(width 0.14224)
		(layer "In2.Cu")
		(net "M_A_DQS_DN<14>")
	)
	(segment
		(start 282.45816 -27.85364)
		(end 283.3878 -27.85364)
		(width 0.14224)
		(layer "In2.Cu")
		(net "M_A_DQS_DN<14>")
	)
	(segment
		(start 274.1422 -42.8117)
		(end 274.1422 -42.5577)
		(width 0.14224)
		(layer "In2.Cu")
		(net "M_A_DQS_DN<14>")
	)
	(segment
		(start 274.1422 -38.2651)
		(end 274.1422 -36.1696)
		(width 0.14224)
		(layer "In2.Cu")
		(net "M_A_DQS_DN<14>")
	)
	(segment
		(start 279.33015 -31.55569)
		(end 279.77211 -31.55569)
		(width 0.14224)
		(layer "In2.Cu")
		(net "M_A_DQS_DN<14>")
	)
	(segment
		(start 274.2565 -45.3898)
		(end 274.2565 -45.1358)
		(width 0.14224)
		(layer "In2.Cu")
		(net "M_A_DQS_DN<14>")
	)
	(segment
		(start 289.814 -26.11374)
		(end 289.9283 -25.99944)
		(width 0.14224)
		(layer "In2.Cu")
		(net "M_A_DQS_DN<14>")
	)
	(segment
		(start 274.1422 -39.5097)
		(end 274.2565 -39.3954)
		(width 0.14224)
		(layer "In2.Cu")
		(net "M_A_DQS_DN<14>")
	)
	(segment
		(start 280.180542 -31.147258)
		(end 280.180542 -30.705298)
		(width 0.14224)
		(layer "In2.Cu")
		(net "M_A_DQS_DN<14>")
	)
	(segment
		(start 274.1422 -44.2849)
		(end 274.1422 -44.0309)
		(width 0.14224)
		(layer "In2.Cu")
		(net "M_A_DQS_DN<14>")
	)
	(segment
		(start 279.152604 -31.378144)
		(end 279.33015 -31.55569)
		(width 0.14224)
		(layer "In2.Cu")
		(net "M_A_DQS_DN<14>")
	)
	(segment
		(start 287.711642 -27.25801)
		(end 287.711642 -27.096212)
		(width 0.14224)
		(layer "In2.Cu")
		(net "M_A_DQS_DN<14>")
	)
	(segment
		(start 274.1422 -43.5483)
		(end 274.1422 -43.2943)
		(width 0.14224)
		(layer "In2.Cu")
		(net "M_A_DQS_DN<14>")
	)
	(segment
		(start 292.274752 -24.4729)
		(end 292.160452 -24.3586)
		(width 0.14224)
		(layer "In2.Cu")
		(net "M_A_DQS_DN<14>")
	)
	(segment
		(start 275.355558 -52.237894)
		(end 275.355558 -51.135026)
		(width 0.0889)
		(layer "In2.Cu")
		(net "M_A_DQS_DN<14>")
	)
	(segment
		(start 275.698712 -34.613088)
		(end 275.948648 -34.363152)
		(width 0.14224)
		(layer "In2.Cu")
		(net "M_A_DQS_DN<14>")
	)
	(segment
		(start 289.9283 -25.99944)
		(end 291.467032 -25.99944)
		(width 0.14224)
		(layer "In2.Cu")
		(net "M_A_DQS_DN<14>")
	)
	(segment
		(start 274.1422 -41.8211)
		(end 274.2565 -41.7068)
		(width 0.14224)
		(layer "In2.Cu")
		(net "M_A_DQS_DN<14>")
	)
	(segment
		(start 285.6992 -27.85364)
		(end 286.954214 -27.85364)
		(width 0.14224)
		(layer "In2.Cu")
		(net "M_A_DQS_DN<14>")
	)
	(arc
		(start 276.284944 -54.21884)
		(mid 276.364007 -53.923438)
		(end 276.284944 -53.628036)
		(width 0.0889)
		(layer "In2.Cu")
		(net "M_A_DQS_DN<14>")
	)
	(arc
		(start 276.280118 -54.61)
		(mid 276.231486 -54.413792)
		(end 276.284944 -54.21884)
		(width 0.0889)
		(layer "In2.Cu")
		(net "M_A_DQS_DN<14>")
	)
	(segment
		(start 278.719788 -32.571182)
		(end 278.719788 -32.82315)
		(width 0.1651)
		(layer "F.Cu")
		(net "M_A_DQS_DN<13>")
	)
	(segment
		(start 281.10053 -30.615128)
		(end 281.01417 -30.528768)
		(width 0.1651)
		(layer "F.Cu")
		(net "M_A_DQS_DN<13>")
	)
	(segment
		(start 281.01417 -30.528768)
		(end 280.762202 -30.528768)
		(width 0.1651)
		(layer "F.Cu")
		(net "M_A_DQS_DN<13>")
	)
	(segment
		(start 277.052278 -34.238692)
		(end 277.052278 -34.49066)
		(width 0.1651)
		(layer "F.Cu")
		(net "M_A_DQS_DN<13>")
	)
	(segment
		(start 277.138638 -35.071304)
		(end 276.592284 -35.617658)
		(width 0.1651)
		(layer "F.Cu")
		(net "M_A_DQS_DN<13>")
	)
	(segment
		(start 273.501104 -49.902618)
		(end 273.501104 -50.2666)
		(width 0.0889)
		(layer "F.Cu")
		(net "M_A_DQS_DN<13>")
	)
	(segment
		(start 276.592284 -35.617658)
		(end 275.744686 -35.617658)
		(width 0.1651)
		(layer "F.Cu")
		(net "M_A_DQS_DN<13>")
	)
	(segment
		(start 274.828508 -36.713668)
		(end 274.648676 -36.713668)
		(width 0.1651)
		(layer "F.Cu")
		(net "M_A_DQS_DN<13>")
	)
	(segment
		(start 277.76551 -33.950148)
		(end 277.67915 -33.863788)
		(width 0.1651)
		(layer "F.Cu")
		(net "M_A_DQS_DN<13>")
	)
	(segment
		(start 274.210526 -37.331396)
		(end 274.030948 -37.331396)
		(width 0.1651)
		(layer "F.Cu")
		(net "M_A_DQS_DN<13>")
	)
	(segment
		(start 283.492194 -23.695406)
		(end 283.0322 -24.1554)
		(width 0.1651)
		(layer "F.Cu")
		(net "M_A_DQS_DN<13>")
	)
	(segment
		(start 273.392138 -51.148742)
		(end 273.392138 -51.527456)
		(width 0.0889)
		(layer "F.Cu")
		(net "M_A_DQS_DN<13>")
	)
	(segment
		(start 283.257244 -17.60093)
		(end 283.068014 -17.4117)
		(width 0.1651)
		(layer "F.Cu")
		(net "M_A_DQS_DN<13>")
	)
	(segment
		(start 283.0322 -24.1554)
		(end 282.810712 -24.1554)
		(width 0.1651)
		(layer "F.Cu")
		(net "M_A_DQS_DN<13>")
	)
	(segment
		(start 277.67915 -33.863788)
		(end 277.427182 -33.863788)
		(width 0.1651)
		(layer "F.Cu")
		(net "M_A_DQS_DN<13>")
	)
	(segment
		(start 273.520154 -40.350694)
		(end 273.520154 -40.4114)
		(width 0.1016)
		(layer "F.Cu")
		(net "M_A_DQS_DN<13>")
	)
	(segment
		(start 273.520154 -37.84219)
		(end 273.520154 -40.350694)
		(width 0.1651)
		(layer "F.Cu")
		(net "M_A_DQS_DN<13>")
	)
	(segment
		(start 282.2067 -28.282646)
		(end 282.2067 -30.003242)
		(width 0.1651)
		(layer "F.Cu")
		(net "M_A_DQS_DN<13>")
	)
	(segment
		(start 283.327094 -22.8346)
		(end 283.492194 -22.9997)
		(width 0.1651)
		(layer "F.Cu")
		(net "M_A_DQS_DN<13>")
	)
	(segment
		(start 275.008086 -36.354258)
		(end 275.008086 -36.53409)
		(width 0.1651)
		(layer "F.Cu")
		(net "M_A_DQS_DN<13>")
	)
	(segment
		(start 274.648676 -36.713668)
		(end 274.390358 -36.971986)
		(width 0.1651)
		(layer "F.Cu")
		(net "M_A_DQS_DN<13>")
	)
	(segment
		(start 282.810712 -24.1554)
		(end 282.6766 -24.289512)
		(width 0.1651)
		(layer "F.Cu")
		(net "M_A_DQS_DN<13>")
	)
	(segment
		(start 283.717492 -17.102328)
		(end 283.717492 -17.348962)
		(width 0.1651)
		(layer "F.Cu")
		(net "M_A_DQS_DN<13>")
	)
	(segment
		(start 277.427182 -33.863788)
		(end 277.052278 -34.238692)
		(width 0.1651)
		(layer "F.Cu")
		(net "M_A_DQS_DN<13>")
	)
	(segment
		(start 274.030948 -37.331396)
		(end 273.520154 -37.84219)
		(width 0.1651)
		(layer "F.Cu")
		(net "M_A_DQS_DN<13>")
	)
	(segment
		(start 283.068014 -17.4117)
		(end 283.048964 -17.4117)
		(width 0.1651)
		(layer "F.Cu")
		(net "M_A_DQS_DN<13>")
	)
	(segment
		(start 280.387298 -30.903672)
		(end 280.387298 -31.15564)
		(width 0.1651)
		(layer "F.Cu")
		(net "M_A_DQS_DN<13>")
	)
	(segment
		(start 277.052278 -34.49066)
		(end 277.138638 -34.57702)
		(width 0.1651)
		(layer "F.Cu")
		(net "M_A_DQS_DN<13>")
	)
	(segment
		(start 278.719788 -32.82315)
		(end 278.806148 -32.90951)
		(width 0.1651)
		(layer "F.Cu")
		(net "M_A_DQS_DN<13>")
	)
	(segment
		(start 279.094692 -32.196278)
		(end 278.719788 -32.571182)
		(width 0.1651)
		(layer "F.Cu")
		(net "M_A_DQS_DN<13>")
	)
	(segment
		(start 278.806148 -32.90951)
		(end 278.806148 -33.403794)
		(width 0.1651)
		(layer "F.Cu")
		(net "M_A_DQS_DN<13>")
	)
	(segment
		(start 278.806148 -33.403794)
		(end 278.259794 -33.950148)
		(width 0.1651)
		(layer "F.Cu")
		(net "M_A_DQS_DN<13>")
	)
	(segment
		(start 273.769328 -51.778408)
		(end 273.769328 -51.446938)
		(width 0.0889)
		(layer "F.Cu")
		(net "M_A_DQS_DN<13>")
	)
	(segment
		(start 274.390358 -37.151564)
		(end 274.210526 -37.331396)
		(width 0.1651)
		(layer "F.Cu")
		(net "M_A_DQS_DN<13>")
	)
	(segment
		(start 282.0035 -27.553158)
		(end 282.0035 -28.079446)
		(width 0.1651)
		(layer "F.Cu")
		(net "M_A_DQS_DN<13>")
	)
	(segment
		(start 283.04236 -22.8346)
		(end 283.327094 -22.8346)
		(width 0.1651)
		(layer "F.Cu")
		(net "M_A_DQS_DN<13>")
	)
	(segment
		(start 273.501104 -50.2666)
		(end 273.602704 -50.3682)
		(width 0.0889)
		(layer "F.Cu")
		(net "M_A_DQS_DN<13>")
	)
	(segment
		(start 279.34666 -32.196278)
		(end 279.094692 -32.196278)
		(width 0.1651)
		(layer "F.Cu")
		(net "M_A_DQS_DN<13>")
	)
	(segment
		(start 273.602704 -50.3682)
		(end 273.602704 -50.5206)
		(width 0.0889)
		(layer "F.Cu")
		(net "M_A_DQS_DN<13>")
	)
	(segment
		(start 280.473658 -31.242)
		(end 280.473658 -31.736284)
		(width 0.1651)
		(layer "F.Cu")
		(net "M_A_DQS_DN<13>")
	)
	(segment
		(start 280.762202 -30.528768)
		(end 280.387298 -30.903672)
		(width 0.1651)
		(layer "F.Cu")
		(net "M_A_DQS_DN<13>")
	)
	(segment
		(start 282.2067 -30.003242)
		(end 281.594814 -30.615128)
		(width 0.1651)
		(layer "F.Cu")
		(net "M_A_DQS_DN<13>")
	)
	(segment
		(start 279.927304 -32.282638)
		(end 279.43302 -32.282638)
		(width 0.1651)
		(layer "F.Cu")
		(net "M_A_DQS_DN<13>")
	)
	(segment
		(start 273.591274 -40.48252)
		(end 273.591274 -49.812448)
		(width 0.1016)
		(layer "F.Cu")
		(net "M_A_DQS_DN<13>")
	)
	(segment
		(start 283.531564 -16.9164)
		(end 283.717492 -17.102328)
		(width 0.1651)
		(layer "F.Cu")
		(net "M_A_DQS_DN<13>")
	)
	(segment
		(start 273.602704 -50.5206)
		(end 273.501104 -50.6222)
		(width 0.0889)
		(layer "F.Cu")
		(net "M_A_DQS_DN<13>")
	)
	(segment
		(start 273.501104 -50.6222)
		(end 273.501104 -50.95875)
		(width 0.0889)
		(layer "F.Cu")
		(net "M_A_DQS_DN<13>")
	)
	(segment
		(start 283.949902 -15.423642)
		(end 283.949902 -16.07693)
		(width 0.1651)
		(layer "F.Cu")
		(net "M_A_DQS_DN<13>")
	)
	(segment
		(start 273.501104 -50.95875)
		(end 273.392138 -51.148742)
		(width 0.0889)
		(layer "F.Cu")
		(net "M_A_DQS_DN<13>")
	)
	(segment
		(start 278.259794 -33.950148)
		(end 277.76551 -33.950148)
		(width 0.1651)
		(layer "F.Cu")
		(net "M_A_DQS_DN<13>")
	)
	(segment
		(start 282.0035 -28.079446)
		(end 282.2067 -28.282646)
		(width 0.1651)
		(layer "F.Cu")
		(net "M_A_DQS_DN<13>")
	)
	(segment
		(start 283.717492 -17.348962)
		(end 283.465524 -17.60093)
		(width 0.1651)
		(layer "F.Cu")
		(net "M_A_DQS_DN<13>")
	)
	(segment
		(start 277.138638 -34.57702)
		(end 277.138638 -35.071304)
		(width 0.1651)
		(layer "F.Cu")
		(net "M_A_DQS_DN<13>")
	)
	(segment
		(start 274.390358 -36.971986)
		(end 274.390358 -37.151564)
		(width 0.1651)
		(layer "F.Cu")
		(net "M_A_DQS_DN<13>")
	)
	(segment
		(start 283.465524 -17.60093)
		(end 283.257244 -17.60093)
		(width 0.1651)
		(layer "F.Cu")
		(net "M_A_DQS_DN<13>")
	)
	(segment
		(start 283.531564 -16.495268)
		(end 283.531564 -16.9164)
		(width 0.1651)
		(layer "F.Cu")
		(net "M_A_DQS_DN<13>")
	)
	(segment
		(start 273.591274 -49.812448)
		(end 273.501104 -49.902618)
		(width 0.0889)
		(layer "F.Cu")
		(net "M_A_DQS_DN<13>")
	)
	(segment
		(start 283.492194 -22.9997)
		(end 283.492194 -23.695406)
		(width 0.1651)
		(layer "F.Cu")
		(net "M_A_DQS_DN<13>")
	)
	(segment
		(start 283.949902 -16.07693)
		(end 283.531564 -16.495268)
		(width 0.1651)
		(layer "F.Cu")
		(net "M_A_DQS_DN<13>")
	)
	(segment
		(start 282.6766 -24.289512)
		(end 282.6766 -26.880058)
		(width 0.1651)
		(layer "F.Cu")
		(net "M_A_DQS_DN<13>")
	)
	(segment
		(start 280.387298 -31.15564)
		(end 280.473658 -31.242)
		(width 0.1651)
		(layer "F.Cu")
		(net "M_A_DQS_DN<13>")
	)
	(segment
		(start 280.473658 -31.736284)
		(end 279.927304 -32.282638)
		(width 0.1651)
		(layer "F.Cu")
		(net "M_A_DQS_DN<13>")
	)
	(segment
		(start 281.594814 -30.615128)
		(end 281.10053 -30.615128)
		(width 0.1651)
		(layer "F.Cu")
		(net "M_A_DQS_DN<13>")
	)
	(segment
		(start 275.008086 -36.53409)
		(end 274.828508 -36.713668)
		(width 0.1651)
		(layer "F.Cu")
		(net "M_A_DQS_DN<13>")
	)
	(segment
		(start 283.95041 -15.423642)
		(end 283.949902 -15.423642)
		(width 0.1651)
		(layer "F.Cu")
		(net "M_A_DQS_DN<13>")
	)
	(segment
		(start 279.43302 -32.282638)
		(end 279.34666 -32.196278)
		(width 0.1651)
		(layer "F.Cu")
		(net "M_A_DQS_DN<13>")
	)
	(segment
		(start 275.744686 -35.617658)
		(end 275.008086 -36.354258)
		(width 0.1651)
		(layer "F.Cu")
		(net "M_A_DQS_DN<13>")
	)
	(segment
		(start 273.706082 -51.841654)
		(end 273.769328 -51.778408)
		(width 0.0889)
		(layer "F.Cu")
		(net "M_A_DQS_DN<13>")
	)
	(segment
		(start 282.6766 -26.880058)
		(end 282.0035 -27.553158)
		(width 0.1651)
		(layer "F.Cu")
		(net "M_A_DQS_DN<13>")
	)
	(segment
		(start 273.520154 -40.4114)
		(end 273.591274 -40.48252)
		(width 0.1016)
		(layer "F.Cu")
		(net "M_A_DQS_DN<13>")
	)
	(via
		(at 283.04236 -22.8346)
		(size 0.508)
		(drill 0.254)
		(layers "F.Cu" "B.Cu")
		(net "M_A_DQS_DN<13>")
	)
	(via
		(at 283.048964 -17.4117)
		(size 0.508)
		(drill 0.254)
		(layers "F.Cu" "B.Cu")
		(net "M_A_DQS_DN<13>")
	)
	(arc
		(start 273.42846 -51.65598)
		(mid 273.546973 -51.779177)
		(end 273.706082 -51.841654)
		(width 0.0889)
		(layer "F.Cu")
		(net "M_A_DQS_DN<13>")
	)
	(arc
		(start 273.392138 -51.527456)
		(mid 273.401399 -51.594231)
		(end 273.42846 -51.65598)
		(width 0.0889)
		(layer "F.Cu")
		(net "M_A_DQS_DN<13>")
	)
	(segment
		(start 283.506164 -23.368)
		(end 283.683964 -23.1902)
		(width 0.1651)
		(layer "B.Cu")
		(net "M_A_DQS_DN<13>")
	)
	(segment
		(start 283.949902 -24.824182)
		(end 283.949902 -24.167592)
		(width 0.1651)
		(layer "B.Cu")
		(net "M_A_DQS_DN<13>")
	)
	(segment
		(start 283.683964 -23.1902)
		(end 283.683964 -22.86)
		(width 0.1651)
		(layer "B.Cu")
		(net "M_A_DQS_DN<13>")
	)
	(segment
		(start 283.95041 -24.824182)
		(end 283.949902 -24.824182)
		(width 0.1651)
		(layer "B.Cu")
		(net "M_A_DQS_DN<13>")
	)
	(segment
		(start 283.506164 -23.723854)
		(end 283.506164 -23.368)
		(width 0.1651)
		(layer "B.Cu")
		(net "M_A_DQS_DN<13>")
	)
	(segment
		(start 283.683964 -22.86)
		(end 283.464 -22.640036)
		(width 0.1651)
		(layer "B.Cu")
		(net "M_A_DQS_DN<13>")
	)
	(segment
		(start 283.236924 -22.640036)
		(end 283.04236 -22.8346)
		(width 0.1651)
		(layer "B.Cu")
		(net "M_A_DQS_DN<13>")
	)
	(segment
		(start 283.949902 -24.167592)
		(end 283.506164 -23.723854)
		(width 0.1651)
		(layer "B.Cu")
		(net "M_A_DQS_DN<13>")
	)
	(segment
		(start 283.464 -22.640036)
		(end 283.236924 -22.640036)
		(width 0.1651)
		(layer "B.Cu")
		(net "M_A_DQS_DN<13>")
	)
	(segment
		(start 283.831284 -22.045676)
		(end 283.831284 -17.944592)
		(width 0.14224)
		(layer "In2.Cu")
		(net "M_A_DQS_DN<13>")
	)
	(segment
		(start 283.493972 -17.60728)
		(end 283.244544 -17.60728)
		(width 0.14224)
		(layer "In2.Cu")
		(net "M_A_DQS_DN<13>")
	)
	(segment
		(start 283.244544 -17.60728)
		(end 283.048964 -17.4117)
		(width 0.14224)
		(layer "In2.Cu")
		(net "M_A_DQS_DN<13>")
	)
	(segment
		(start 283.04236 -22.8346)
		(end 283.831284 -22.045676)
		(width 0.14224)
		(layer "In2.Cu")
		(net "M_A_DQS_DN<13>")
	)
	(segment
		(start 283.831284 -17.944592)
		(end 283.493972 -17.60728)
		(width 0.14224)
		(layer "In2.Cu")
		(net "M_A_DQS_DN<13>")
	)
	(segment
		(start 228.70033 -15.423642)
		(end 228.699822 -15.423642)
		(width 0.1651)
		(layer "F.Cu")
		(net "M_A_DQS_DN<12>")
	)
	(segment
		(start 228.467666 -17.102328)
		(end 228.467666 -17.348962)
		(width 0.1651)
		(layer "F.Cu")
		(net "M_A_DQS_DN<12>")
	)
	(segment
		(start 228.007418 -17.60093)
		(end 227.818188 -17.4117)
		(width 0.1651)
		(layer "F.Cu")
		(net "M_A_DQS_DN<12>")
	)
	(segment
		(start 228.281738 -16.495268)
		(end 228.281738 -16.9164)
		(width 0.1651)
		(layer "F.Cu")
		(net "M_A_DQS_DN<12>")
	)
	(segment
		(start 242.193318 -54.104286)
		(end 241.621818 -54.104286)
		(width 0.1016)
		(layer "F.Cu")
		(net "M_A_DQS_DN<12>")
	)
	(segment
		(start 228.215698 -17.60093)
		(end 228.007418 -17.60093)
		(width 0.1651)
		(layer "F.Cu")
		(net "M_A_DQS_DN<12>")
	)
	(segment
		(start 228.281738 -16.9164)
		(end 228.467666 -17.102328)
		(width 0.1651)
		(layer "F.Cu")
		(net "M_A_DQS_DN<12>")
	)
	(segment
		(start 228.699822 -15.423642)
		(end 228.699822 -16.077184)
		(width 0.1651)
		(layer "F.Cu")
		(net "M_A_DQS_DN<12>")
	)
	(segment
		(start 228.699822 -16.077184)
		(end 228.281738 -16.495268)
		(width 0.1651)
		(layer "F.Cu")
		(net "M_A_DQS_DN<12>")
	)
	(segment
		(start 228.467666 -17.348962)
		(end 228.215698 -17.60093)
		(width 0.1651)
		(layer "F.Cu")
		(net "M_A_DQS_DN<12>")
	)
	(segment
		(start 227.818188 -17.4117)
		(end 227.799138 -17.4117)
		(width 0.1651)
		(layer "F.Cu")
		(net "M_A_DQS_DN<12>")
	)
	(via
		(at 227.792534 -22.8346)
		(size 0.508)
		(drill 0.254)
		(layers "F.Cu" "B.Cu")
		(net "M_A_DQS_DN<12>")
	)
	(via
		(at 241.621818 -54.104286)
		(size 0.508)
		(drill 0.254)
		(layers "F.Cu" "B.Cu")
		(net "M_A_DQS_DN<12>")
	)
	(via
		(at 227.799138 -17.4117)
		(size 0.508)
		(drill 0.254)
		(layers "F.Cu" "B.Cu")
		(net "M_A_DQS_DN<12>")
	)
	(segment
		(start 228.434138 -22.86)
		(end 228.434138 -23.1902)
		(width 0.1651)
		(layer "B.Cu")
		(net "M_A_DQS_DN<12>")
	)
	(segment
		(start 228.700076 -24.167592)
		(end 228.700076 -24.823928)
		(width 0.1651)
		(layer "B.Cu")
		(net "M_A_DQS_DN<12>")
	)
	(segment
		(start 227.987098 -22.640036)
		(end 228.214174 -22.640036)
		(width 0.1651)
		(layer "B.Cu")
		(net "M_A_DQS_DN<12>")
	)
	(segment
		(start 227.792534 -22.8346)
		(end 227.987098 -22.640036)
		(width 0.1651)
		(layer "B.Cu")
		(net "M_A_DQS_DN<12>")
	)
	(segment
		(start 228.256338 -23.368)
		(end 228.256338 -23.723854)
		(width 0.1651)
		(layer "B.Cu")
		(net "M_A_DQS_DN<12>")
	)
	(segment
		(start 228.700076 -24.823928)
		(end 228.70033 -24.824182)
		(width 0.1651)
		(layer "B.Cu")
		(net "M_A_DQS_DN<12>")
	)
	(segment
		(start 228.256338 -23.723854)
		(end 228.700076 -24.167592)
		(width 0.1651)
		(layer "B.Cu")
		(net "M_A_DQS_DN<12>")
	)
	(segment
		(start 228.214174 -22.640036)
		(end 228.434138 -22.86)
		(width 0.1651)
		(layer "B.Cu")
		(net "M_A_DQS_DN<12>")
	)
	(segment
		(start 228.434138 -23.1902)
		(end 228.256338 -23.368)
		(width 0.1651)
		(layer "B.Cu")
		(net "M_A_DQS_DN<12>")
	)
	(segment
		(start 237.318042 -51.03749)
		(end 237.350808 -51.03749)
		(width 0.0889)
		(layer "In2.Cu")
		(net "M_A_DQS_DN<12>")
	)
	(segment
		(start 228.897688 -41.826688)
		(end 231.617012 -44.546012)
		(width 0.14224)
		(layer "In2.Cu")
		(net "M_A_DQS_DN<12>")
	)
	(segment
		(start 236.340904 -49.353724)
		(end 236.927644 -49.940464)
		(width 0.0889)
		(layer "In2.Cu")
		(net "M_A_DQS_DN<12>")
	)
	(segment
		(start 235.025438 -47.76343)
		(end 235.025438 -47.954438)
		(width 0.14224)
		(layer "In2.Cu")
		(net "M_A_DQS_DN<12>")
	)
	(segment
		(start 228.720396 -29.5275)
		(end 228.720396 -29.9212)
		(width 0.14224)
		(layer "In2.Cu")
		(net "M_A_DQS_DN<12>")
	)
	(segment
		(start 235.40847 -48.146462)
		(end 235.558838 -48.29683)
		(width 0.14224)
		(layer "In2.Cu")
		(net "M_A_DQS_DN<12>")
	)
	(segment
		(start 235.558838 -48.29683)
		(end 235.558838 -48.487838)
		(width 0.14224)
		(layer "In2.Cu")
		(net "M_A_DQS_DN<12>")
	)
	(segment
		(start 236.340904 -49.264824)
		(end 236.340904 -49.353724)
		(width 0.0889)
		(layer "In2.Cu")
		(net "M_A_DQS_DN<12>")
	)
	(segment
		(start 228.562916 -31.79572)
		(end 228.720396 -31.9532)
		(width 0.14224)
		(layer "In2.Cu")
		(net "M_A_DQS_DN<12>")
	)
	(segment
		(start 231.617012 -44.546012)
		(end 231.756712 -44.546012)
		(width 0.14224)
		(layer "In2.Cu")
		(net "M_A_DQS_DN<12>")
	)
	(segment
		(start 228.230938 -23.273004)
		(end 228.230938 -23.736808)
		(width 0.14224)
		(layer "In2.Cu")
		(net "M_A_DQS_DN<12>")
	)
	(segment
		(start 236.927644 -50.742088)
		(end 236.982508 -50.837338)
		(width 0.0889)
		(layer "In2.Cu")
		(net "M_A_DQS_DN<12>")
	)
	(segment
		(start 233.678222 -46.607222)
		(end 233.86923 -46.607222)
		(width 0.14224)
		(layer "In2.Cu")
		(net "M_A_DQS_DN<12>")
	)
	(segment
		(start 228.519482 -39.702232)
		(end 228.052376 -39.702232)
		(width 0.14224)
		(layer "In2.Cu")
		(net "M_A_DQS_DN<12>")
	)
	(segment
		(start 231.958388 -44.747688)
		(end 231.958388 -44.887388)
		(width 0.14224)
		(layer "In2.Cu")
		(net "M_A_DQS_DN<12>")
	)
	(segment
		(start 227.590858 -24.609552)
		(end 228.562916 -25.58161)
		(width 0.14224)
		(layer "In2.Cu")
		(net "M_A_DQS_DN<12>")
	)
	(segment
		(start 228.052376 -39.702232)
		(end 227.830888 -39.92372)
		(width 0.14224)
		(layer "In2.Cu")
		(net "M_A_DQS_DN<12>")
	)
	(segment
		(start 228.643688 -33.76676)
		(end 228.643688 -36.657026)
		(width 0.14224)
		(layer "In2.Cu")
		(net "M_A_DQS_DN<12>")
	)
	(segment
		(start 227.773738 -24.003)
		(end 227.590858 -24.18588)
		(width 0.14224)
		(layer "In2.Cu")
		(net "M_A_DQS_DN<12>")
	)
	(segment
		(start 228.720396 -30.6832)
		(end 228.562916 -30.84068)
		(width 0.14224)
		(layer "In2.Cu")
		(net "M_A_DQS_DN<12>")
	)
	(segment
		(start 234.019598 -46.75759)
		(end 234.019598 -46.948598)
		(width 0.14224)
		(layer "In2.Cu")
		(net "M_A_DQS_DN<12>")
	)
	(segment
		(start 234.181142 -47.110142)
		(end 234.37215 -47.110142)
		(width 0.14224)
		(layer "In2.Cu")
		(net "M_A_DQS_DN<12>")
	)
	(segment
		(start 227.964746 -24.003)
		(end 227.773738 -24.003)
		(width 0.14224)
		(layer "In2.Cu")
		(net "M_A_DQS_DN<12>")
	)
	(segment
		(start 228.581458 -17.944592)
		(end 228.581458 -22.045676)
		(width 0.14224)
		(layer "In2.Cu")
		(net "M_A_DQS_DN<12>")
	)
	(segment
		(start 228.562916 -31.60268)
		(end 228.562916 -31.79572)
		(width 0.14224)
		(layer "In2.Cu")
		(net "M_A_DQS_DN<12>")
	)
	(segment
		(start 233.86923 -46.607222)
		(end 234.019598 -46.75759)
		(width 0.14224)
		(layer "In2.Cu")
		(net "M_A_DQS_DN<12>")
	)
	(segment
		(start 228.897688 -39.324026)
		(end 228.519482 -39.702232)
		(width 0.14224)
		(layer "In2.Cu")
		(net "M_A_DQS_DN<12>")
	)
	(segment
		(start 227.792534 -22.8346)
		(end 228.230938 -23.273004)
		(width 0.14224)
		(layer "In2.Cu")
		(net "M_A_DQS_DN<12>")
	)
	(segment
		(start 228.562916 -29.37002)
		(end 228.720396 -29.5275)
		(width 0.14224)
		(layer "In2.Cu")
		(net "M_A_DQS_DN<12>")
	)
	(segment
		(start 236.335824 -49.264824)
		(end 236.340904 -49.264824)
		(width 0.14224)
		(layer "In2.Cu")
		(net "M_A_DQS_DN<12>")
	)
	(segment
		(start 228.562916 -30.07868)
		(end 228.562916 -30.27172)
		(width 0.14224)
		(layer "In2.Cu")
		(net "M_A_DQS_DN<12>")
	)
	(segment
		(start 234.522518 -47.451518)
		(end 234.684062 -47.613062)
		(width 0.14224)
		(layer "In2.Cu")
		(net "M_A_DQS_DN<12>")
	)
	(segment
		(start 228.720396 -31.9532)
		(end 228.720396 -32.2072)
		(width 0.14224)
		(layer "In2.Cu")
		(net "M_A_DQS_DN<12>")
	)
	(segment
		(start 236.927644 -49.940464)
		(end 236.927644 -50.742088)
		(width 0.0889)
		(layer "In2.Cu")
		(net "M_A_DQS_DN<12>")
	)
	(segment
		(start 232.264712 -45.079412)
		(end 232.491788 -45.306488)
		(width 0.14224)
		(layer "In2.Cu")
		(net "M_A_DQS_DN<12>")
	)
	(segment
		(start 227.830888 -40.557704)
		(end 228.052376 -40.779192)
		(width 0.14224)
		(layer "In2.Cu")
		(net "M_A_DQS_DN<12>")
	)
	(segment
		(start 232.663492 -45.592492)
		(end 232.8545 -45.592492)
		(width 0.14224)
		(layer "In2.Cu")
		(net "M_A_DQS_DN<12>")
	)
	(segment
		(start 239.886744 -52.523136)
		(end 239.926368 -52.523136)
		(width 0.0889)
		(layer "In2.Cu")
		(net "M_A_DQS_DN<12>")
	)
	(segment
		(start 228.562916 -25.58161)
		(end 228.562916 -29.37002)
		(width 0.14224)
		(layer "In2.Cu")
		(net "M_A_DQS_DN<12>")
	)
	(segment
		(start 228.720396 -31.1912)
		(end 228.720396 -31.4452)
		(width 0.14224)
		(layer "In2.Cu")
		(net "M_A_DQS_DN<12>")
	)
	(segment
		(start 228.720396 -31.4452)
		(end 228.562916 -31.60268)
		(width 0.14224)
		(layer "In2.Cu")
		(net "M_A_DQS_DN<12>")
	)
	(segment
		(start 228.643688 -36.657026)
		(end 228.290882 -37.009832)
		(width 0.14224)
		(layer "In2.Cu")
		(net "M_A_DQS_DN<12>")
	)
	(segment
		(start 228.562916 -33.685988)
		(end 228.643688 -33.76676)
		(width 0.14224)
		(layer "In2.Cu")
		(net "M_A_DQS_DN<12>")
	)
	(segment
		(start 240.752122 -53.018436)
		(end 240.776252 -53.018436)
		(width 0.0889)
		(layer "In2.Cu")
		(net "M_A_DQS_DN<12>")
	)
	(segment
		(start 233.004868 -45.74286)
		(end 233.004868 -45.933868)
		(width 0.14224)
		(layer "In2.Cu")
		(net "M_A_DQS_DN<12>")
	)
	(segment
		(start 235.025438 -47.954438)
		(end 235.217462 -48.146462)
		(width 0.14224)
		(layer "In2.Cu")
		(net "M_A_DQS_DN<12>")
	)
	(segment
		(start 231.756712 -44.546012)
		(end 231.958388 -44.747688)
		(width 0.14224)
		(layer "In2.Cu")
		(net "M_A_DQS_DN<12>")
	)
	(segment
		(start 231.958388 -44.887388)
		(end 232.150412 -45.079412)
		(width 0.14224)
		(layer "In2.Cu")
		(net "M_A_DQS_DN<12>")
	)
	(segment
		(start 228.562916 -30.27172)
		(end 228.720396 -30.4292)
		(width 0.14224)
		(layer "In2.Cu")
		(net "M_A_DQS_DN<12>")
	)
	(segment
		(start 228.052376 -38.086792)
		(end 228.519482 -38.086792)
		(width 0.14224)
		(layer "In2.Cu")
		(net "M_A_DQS_DN<12>")
	)
	(segment
		(start 228.519482 -40.779192)
		(end 228.897688 -41.157398)
		(width 0.14224)
		(layer "In2.Cu")
		(net "M_A_DQS_DN<12>")
	)
	(segment
		(start 228.720396 -29.9212)
		(end 228.562916 -30.07868)
		(width 0.14224)
		(layer "In2.Cu")
		(net "M_A_DQS_DN<12>")
	)
	(segment
		(start 228.052376 -37.009832)
		(end 227.830888 -37.23132)
		(width 0.14224)
		(layer "In2.Cu")
		(net "M_A_DQS_DN<12>")
	)
	(segment
		(start 228.897688 -38.464998)
		(end 228.897688 -39.324026)
		(width 0.14224)
		(layer "In2.Cu")
		(net "M_A_DQS_DN<12>")
	)
	(segment
		(start 228.244146 -17.60728)
		(end 228.581458 -17.944592)
		(width 0.14224)
		(layer "In2.Cu")
		(net "M_A_DQS_DN<12>")
	)
	(segment
		(start 234.37215 -47.110142)
		(end 234.522518 -47.26051)
		(width 0.14224)
		(layer "In2.Cu")
		(net "M_A_DQS_DN<12>")
	)
	(segment
		(start 232.491788 -45.306488)
		(end 232.491788 -45.420788)
		(width 0.14224)
		(layer "In2.Cu")
		(net "M_A_DQS_DN<12>")
	)
	(segment
		(start 228.720396 -32.2072)
		(end 228.562916 -32.36468)
		(width 0.14224)
		(layer "In2.Cu")
		(net "M_A_DQS_DN<12>")
	)
	(segment
		(start 227.830888 -37.23132)
		(end 227.830888 -37.865304)
		(width 0.14224)
		(layer "In2.Cu")
		(net "M_A_DQS_DN<12>")
	)
	(segment
		(start 234.684062 -47.613062)
		(end 234.87507 -47.613062)
		(width 0.14224)
		(layer "In2.Cu")
		(net "M_A_DQS_DN<12>")
	)
	(segment
		(start 238.172752 -51.532536)
		(end 238.200692 -51.532536)
		(width 0.0889)
		(layer "In2.Cu")
		(net "M_A_DQS_DN<12>")
	)
	(segment
		(start 227.830888 -37.865304)
		(end 228.052376 -38.086792)
		(width 0.14224)
		(layer "In2.Cu")
		(net "M_A_DQS_DN<12>")
	)
	(segment
		(start 234.522518 -47.26051)
		(end 234.522518 -47.451518)
		(width 0.14224)
		(layer "In2.Cu")
		(net "M_A_DQS_DN<12>")
	)
	(segment
		(start 227.994718 -17.60728)
		(end 228.244146 -17.60728)
		(width 0.14224)
		(layer "In2.Cu")
		(net "M_A_DQS_DN<12>")
	)
	(segment
		(start 233.166412 -46.095412)
		(end 233.35742 -46.095412)
		(width 0.14224)
		(layer "In2.Cu")
		(net "M_A_DQS_DN<12>")
	)
	(segment
		(start 228.052376 -40.779192)
		(end 228.519482 -40.779192)
		(width 0.14224)
		(layer "In2.Cu")
		(net "M_A_DQS_DN<12>")
	)
	(segment
		(start 227.799138 -17.4117)
		(end 227.994718 -17.60728)
		(width 0.14224)
		(layer "In2.Cu")
		(net "M_A_DQS_DN<12>")
	)
	(segment
		(start 228.897688 -41.157398)
		(end 228.897688 -41.826688)
		(width 0.14224)
		(layer "In2.Cu")
		(net "M_A_DQS_DN<12>")
	)
	(segment
		(start 232.491788 -45.420788)
		(end 232.663492 -45.592492)
		(width 0.14224)
		(layer "In2.Cu")
		(net "M_A_DQS_DN<12>")
	)
	(segment
		(start 236.17428 -48.912272)
		(end 236.17428 -49.10328)
		(width 0.14224)
		(layer "In2.Cu")
		(net "M_A_DQS_DN<12>")
	)
	(segment
		(start 235.832904 -48.761904)
		(end 236.023912 -48.761904)
		(width 0.14224)
		(layer "In2.Cu")
		(net "M_A_DQS_DN<12>")
	)
	(segment
		(start 234.019598 -46.948598)
		(end 234.181142 -47.110142)
		(width 0.14224)
		(layer "In2.Cu")
		(net "M_A_DQS_DN<12>")
	)
	(segment
		(start 232.150412 -45.079412)
		(end 232.264712 -45.079412)
		(width 0.14224)
		(layer "In2.Cu")
		(net "M_A_DQS_DN<12>")
	)
	(segment
		(start 234.87507 -47.613062)
		(end 235.025438 -47.76343)
		(width 0.14224)
		(layer "In2.Cu")
		(net "M_A_DQS_DN<12>")
	)
	(segment
		(start 235.558838 -48.487838)
		(end 235.832904 -48.761904)
		(width 0.14224)
		(layer "In2.Cu")
		(net "M_A_DQS_DN<12>")
	)
	(segment
		(start 239.028224 -52.027836)
		(end 239.064038 -52.027836)
		(width 0.0889)
		(layer "In2.Cu")
		(net "M_A_DQS_DN<12>")
	)
	(segment
		(start 228.290882 -37.009832)
		(end 228.052376 -37.009832)
		(width 0.14224)
		(layer "In2.Cu")
		(net "M_A_DQS_DN<12>")
	)
	(segment
		(start 228.562916 -30.84068)
		(end 228.562916 -31.03372)
		(width 0.14224)
		(layer "In2.Cu")
		(net "M_A_DQS_DN<12>")
	)
	(segment
		(start 228.720396 -30.4292)
		(end 228.720396 -30.6832)
		(width 0.14224)
		(layer "In2.Cu")
		(net "M_A_DQS_DN<12>")
	)
	(segment
		(start 233.004868 -45.933868)
		(end 233.166412 -46.095412)
		(width 0.14224)
		(layer "In2.Cu")
		(net "M_A_DQS_DN<12>")
	)
	(segment
		(start 228.562916 -31.03372)
		(end 228.720396 -31.1912)
		(width 0.14224)
		(layer "In2.Cu")
		(net "M_A_DQS_DN<12>")
	)
	(segment
		(start 233.507788 -46.436788)
		(end 233.678222 -46.607222)
		(width 0.14224)
		(layer "In2.Cu")
		(net "M_A_DQS_DN<12>")
	)
	(segment
		(start 236.023912 -48.761904)
		(end 236.17428 -48.912272)
		(width 0.14224)
		(layer "In2.Cu")
		(net "M_A_DQS_DN<12>")
	)
	(segment
		(start 227.830888 -39.92372)
		(end 227.830888 -40.557704)
		(width 0.14224)
		(layer "In2.Cu")
		(net "M_A_DQS_DN<12>")
	)
	(segment
		(start 235.217462 -48.146462)
		(end 235.40847 -48.146462)
		(width 0.14224)
		(layer "In2.Cu")
		(net "M_A_DQS_DN<12>")
	)
	(segment
		(start 227.590858 -24.18588)
		(end 227.590858 -24.609552)
		(width 0.14224)
		(layer "In2.Cu")
		(net "M_A_DQS_DN<12>")
	)
	(segment
		(start 232.8545 -45.592492)
		(end 233.004868 -45.74286)
		(width 0.14224)
		(layer "In2.Cu")
		(net "M_A_DQS_DN<12>")
	)
	(segment
		(start 241.440716 -53.524912)
		(end 241.621818 -54.104286)
		(width 0.0889)
		(layer "In2.Cu")
		(net "M_A_DQS_DN<12>")
	)
	(segment
		(start 233.507788 -46.24578)
		(end 233.507788 -46.436788)
		(width 0.14224)
		(layer "In2.Cu")
		(net "M_A_DQS_DN<12>")
	)
	(segment
		(start 228.581458 -22.045676)
		(end 227.792534 -22.8346)
		(width 0.14224)
		(layer "In2.Cu")
		(net "M_A_DQS_DN<12>")
	)
	(segment
		(start 233.35742 -46.095412)
		(end 233.507788 -46.24578)
		(width 0.14224)
		(layer "In2.Cu")
		(net "M_A_DQS_DN<12>")
	)
	(segment
		(start 236.17428 -49.10328)
		(end 236.335824 -49.264824)
		(width 0.14224)
		(layer "In2.Cu")
		(net "M_A_DQS_DN<12>")
	)
	(segment
		(start 228.562916 -32.36468)
		(end 228.562916 -33.685988)
		(width 0.14224)
		(layer "In2.Cu")
		(net "M_A_DQS_DN<12>")
	)
	(segment
		(start 228.230938 -23.736808)
		(end 227.964746 -24.003)
		(width 0.14224)
		(layer "In2.Cu")
		(net "M_A_DQS_DN<12>")
	)
	(segment
		(start 228.519482 -38.086792)
		(end 228.897688 -38.464998)
		(width 0.14224)
		(layer "In2.Cu")
		(net "M_A_DQS_DN<12>")
	)
	(arc
		(start 240.776252 -53.018436)
		(mid 241.064397 -53.100755)
		(end 241.275108 -53.313838)
		(width 0.0889)
		(layer "In2.Cu")
		(net "M_A_DQS_DN<12>")
	)
	(arc
		(start 236.982508 -50.837338)
		(mid 237.124191 -50.981142)
		(end 237.318042 -51.03749)
		(width 0.0889)
		(layer "In2.Cu")
		(net "M_A_DQS_DN<12>")
	)
	(arc
		(start 238.200692 -51.532536)
		(mid 238.488837 -51.614855)
		(end 238.699548 -51.827938)
		(width 0.0889)
		(layer "In2.Cu")
		(net "M_A_DQS_DN<12>")
	)
	(arc
		(start 237.841028 -51.332638)
		(mid 237.981107 -51.475374)
		(end 238.172752 -51.532536)
		(width 0.0889)
		(layer "In2.Cu")
		(net "M_A_DQS_DN<12>")
	)
	(arc
		(start 240.416588 -52.818284)
		(mid 240.558271 -52.962088)
		(end 240.752122 -53.018436)
		(width 0.0889)
		(layer "In2.Cu")
		(net "M_A_DQS_DN<12>")
	)
	(arc
		(start 237.350808 -51.03749)
		(mid 237.634025 -51.121771)
		(end 237.841028 -51.332638)
		(width 0.0889)
		(layer "In2.Cu")
		(net "M_A_DQS_DN<12>")
	)
	(arc
		(start 239.926368 -52.523136)
		(mid 240.209585 -52.607417)
		(end 240.416588 -52.818284)
		(width 0.0889)
		(layer "In2.Cu")
		(net "M_A_DQS_DN<12>")
	)
	(arc
		(start 239.558068 -52.323238)
		(mid 239.696812 -52.465271)
		(end 239.886744 -52.523136)
		(width 0.0889)
		(layer "In2.Cu")
		(net "M_A_DQS_DN<12>")
	)
	(arc
		(start 241.275108 -53.313838)
		(mid 241.350437 -53.425238)
		(end 241.440716 -53.524912)
		(width 0.0889)
		(layer "In2.Cu")
		(net "M_A_DQS_DN<12>")
	)
	(arc
		(start 238.699548 -51.827938)
		(mid 238.838292 -51.969971)
		(end 239.028224 -52.027836)
		(width 0.0889)
		(layer "In2.Cu")
		(net "M_A_DQS_DN<12>")
	)
	(arc
		(start 239.064038 -52.027836)
		(mid 239.349462 -52.111303)
		(end 239.558068 -52.323238)
		(width 0.0889)
		(layer "In2.Cu")
		(net "M_A_DQS_DN<12>")
	)
	(segment
		(start 219.349828 -15.423642)
		(end 219.349828 -16.077184)
		(width 0.1651)
		(layer "F.Cu")
		(net "M_A_DQS_DN<11>")
	)
	(segment
		(start 219.349828 -16.077184)
		(end 218.931744 -16.495268)
		(width 0.1651)
		(layer "F.Cu")
		(net "M_A_DQS_DN<11>")
	)
	(segment
		(start 218.865704 -17.60093)
		(end 218.657424 -17.60093)
		(width 0.1651)
		(layer "F.Cu")
		(net "M_A_DQS_DN<11>")
	)
	(segment
		(start 218.657424 -17.60093)
		(end 218.468194 -17.4117)
		(width 0.1651)
		(layer "F.Cu")
		(net "M_A_DQS_DN<11>")
	)
	(segment
		(start 219.350336 -15.423642)
		(end 219.349828 -15.423642)
		(width 0.1651)
		(layer "F.Cu")
		(net "M_A_DQS_DN<11>")
	)
	(segment
		(start 218.931744 -16.9164)
		(end 219.117672 -17.102328)
		(width 0.1651)
		(layer "F.Cu")
		(net "M_A_DQS_DN<11>")
	)
	(segment
		(start 219.117672 -17.102328)
		(end 219.117672 -17.348962)
		(width 0.1651)
		(layer "F.Cu")
		(net "M_A_DQS_DN<11>")
	)
	(segment
		(start 236.183678 -57.57164)
		(end 235.612178 -57.57164)
		(width 0.1016)
		(layer "F.Cu")
		(net "M_A_DQS_DN<11>")
	)
	(segment
		(start 218.931744 -16.495268)
		(end 218.931744 -16.9164)
		(width 0.1651)
		(layer "F.Cu")
		(net "M_A_DQS_DN<11>")
	)
	(segment
		(start 219.117672 -17.348962)
		(end 218.865704 -17.60093)
		(width 0.1651)
		(layer "F.Cu")
		(net "M_A_DQS_DN<11>")
	)
	(segment
		(start 218.468194 -17.4117)
		(end 218.449144 -17.4117)
		(width 0.1651)
		(layer "F.Cu")
		(net "M_A_DQS_DN<11>")
	)
	(via
		(at 218.44254 -22.8346)
		(size 0.508)
		(drill 0.254)
		(layers "F.Cu" "B.Cu")
		(net "M_A_DQS_DN<11>")
	)
	(via
		(at 235.612178 -57.57164)
		(size 0.508)
		(drill 0.254)
		(layers "F.Cu" "B.Cu")
		(net "M_A_DQS_DN<11>")
	)
	(via
		(at 218.449144 -17.4117)
		(size 0.508)
		(drill 0.254)
		(layers "F.Cu" "B.Cu")
		(net "M_A_DQS_DN<11>")
	)
	(segment
		(start 219.350082 -24.823928)
		(end 219.350082 -24.167592)
		(width 0.1651)
		(layer "B.Cu")
		(net "M_A_DQS_DN<11>")
	)
	(segment
		(start 218.637104 -22.640036)
		(end 218.44254 -22.8346)
		(width 0.1651)
		(layer "B.Cu")
		(net "M_A_DQS_DN<11>")
	)
	(segment
		(start 219.084144 -23.1902)
		(end 219.084144 -22.86)
		(width 0.1651)
		(layer "B.Cu")
		(net "M_A_DQS_DN<11>")
	)
	(segment
		(start 218.906344 -23.368)
		(end 219.084144 -23.1902)
		(width 0.1651)
		(layer "B.Cu")
		(net "M_A_DQS_DN<11>")
	)
	(segment
		(start 219.084144 -22.86)
		(end 218.86418 -22.640036)
		(width 0.1651)
		(layer "B.Cu")
		(net "M_A_DQS_DN<11>")
	)
	(segment
		(start 218.86418 -22.640036)
		(end 218.637104 -22.640036)
		(width 0.1651)
		(layer "B.Cu")
		(net "M_A_DQS_DN<11>")
	)
	(segment
		(start 218.906344 -23.723854)
		(end 218.906344 -23.368)
		(width 0.1651)
		(layer "B.Cu")
		(net "M_A_DQS_DN<11>")
	)
	(segment
		(start 219.350082 -24.167592)
		(end 218.906344 -23.723854)
		(width 0.1651)
		(layer "B.Cu")
		(net "M_A_DQS_DN<11>")
	)
	(segment
		(start 219.350336 -24.824182)
		(end 219.350082 -24.823928)
		(width 0.1651)
		(layer "B.Cu")
		(net "M_A_DQS_DN<11>")
	)
	(segment
		(start 229.282244 -54.108858)
		(end 229.444042 -54.270656)
		(width 0.14224)
		(layer "In2.Cu")
		(net "M_A_DQS_DN<11>")
	)
	(segment
		(start 227.559362 -52.565808)
		(end 227.739194 -52.565808)
		(width 0.14224)
		(layer "In2.Cu")
		(net "M_A_DQS_DN<11>")
	)
	(segment
		(start 229.444042 -54.450488)
		(end 229.620064 -54.62651)
		(width 0.14224)
		(layer "In2.Cu")
		(net "M_A_DQS_DN<11>")
	)
	(segment
		(start 217.975688 -25.213056)
		(end 217.975688 -25.406096)
		(width 0.14224)
		(layer "In2.Cu")
		(net "M_A_DQS_DN<11>")
	)
	(segment
		(start 218.6305 -38.304216)
		(end 218.6305 -39.181024)
		(width 0.14224)
		(layer "In2.Cu")
		(net "M_A_DQS_DN<11>")
	)
	(segment
		(start 227.342192 -52.348638)
		(end 227.559362 -52.565808)
		(width 0.14224)
		(layer "In2.Cu")
		(net "M_A_DQS_DN<11>")
	)
	(segment
		(start 218.458288 -43.464734)
		(end 223.260412 -48.266858)
		(width 0.14224)
		(layer "In2.Cu")
		(net "M_A_DQS_DN<11>")
	)
	(segment
		(start 229.620064 -54.62651)
		(end 229.799896 -54.62651)
		(width 0.14224)
		(layer "In2.Cu")
		(net "M_A_DQS_DN<11>")
	)
	(segment
		(start 224.129092 -49.135538)
		(end 224.306892 -49.313338)
		(width 0.14224)
		(layer "In2.Cu")
		(net "M_A_DQS_DN<11>")
	)
	(segment
		(start 226.789742 -51.796188)
		(end 227.000562 -52.007008)
		(width 0.14224)
		(layer "In2.Cu")
		(net "M_A_DQS_DN<11>")
	)
	(segment
		(start 217.975688 -25.975056)
		(end 217.975688 -26.168096)
		(width 0.14224)
		(layer "In2.Cu")
		(net "M_A_DQS_DN<11>")
	)
	(segment
		(start 228.437948 -53.264562)
		(end 228.437948 -53.444394)
		(width 0.14224)
		(layer "In2.Cu")
		(net "M_A_DQS_DN<11>")
	)
	(segment
		(start 218.6305 -39.181024)
		(end 218.252294 -39.55923)
		(width 0.14224)
		(layer "In2.Cu")
		(net "M_A_DQS_DN<11>")
	)
	(segment
		(start 218.458288 -43.071288)
		(end 218.458288 -43.464734)
		(width 0.14224)
		(layer "In2.Cu")
		(net "M_A_DQS_DN<11>")
	)
	(segment
		(start 230.302816 -55.12943)
		(end 230.46436 -55.290974)
		(width 0.14224)
		(layer "In2.Cu")
		(net "M_A_DQS_DN<11>")
	)
	(segment
		(start 218.270074 -37.94379)
		(end 218.6305 -38.304216)
		(width 0.14224)
		(layer "In2.Cu")
		(net "M_A_DQS_DN<11>")
	)
	(segment
		(start 217.975688 -32.9692)
		(end 217.620088 -33.3248)
		(width 0.14224)
		(layer "In2.Cu")
		(net "M_A_DQS_DN<11>")
	)
	(segment
		(start 226.789742 -51.616356)
		(end 226.789742 -51.796188)
		(width 0.14224)
		(layer "In2.Cu")
		(net "M_A_DQS_DN<11>")
	)
	(segment
		(start 217.620088 -33.3248)
		(end 217.620088 -37.74567)
		(width 0.14224)
		(layer "In2.Cu")
		(net "M_A_DQS_DN<11>")
	)
	(segment
		(start 223.387412 -48.266858)
		(end 223.602042 -48.481488)
		(width 0.14224)
		(layer "In2.Cu")
		(net "M_A_DQS_DN<11>")
	)
	(segment
		(start 226.173792 -51.180238)
		(end 226.448112 -51.454558)
		(width 0.14224)
		(layer "In2.Cu")
		(net "M_A_DQS_DN<11>")
	)
	(segment
		(start 218.644724 -17.60728)
		(end 218.894152 -17.60728)
		(width 0.14224)
		(layer "In2.Cu")
		(net "M_A_DQS_DN<11>")
	)
	(segment
		(start 227.900992 -52.727606)
		(end 227.900992 -52.907438)
		(width 0.14224)
		(layer "In2.Cu")
		(net "M_A_DQS_DN<11>")
	)
	(segment
		(start 230.625904 -55.63235)
		(end 230.641652 -55.648098)
		(width 0.0889)
		(layer "In2.Cu")
		(net "M_A_DQS_DN<11>")
	)
	(segment
		(start 225.665792 -50.672238)
		(end 225.832162 -50.838608)
		(width 0.14224)
		(layer "In2.Cu")
		(net "M_A_DQS_DN<11>")
	)
	(segment
		(start 229.102412 -54.108858)
		(end 229.282244 -54.108858)
		(width 0.14224)
		(layer "In2.Cu")
		(net "M_A_DQS_DN<11>")
	)
	(segment
		(start 229.96144 -54.788054)
		(end 229.96144 -54.967886)
		(width 0.14224)
		(layer "In2.Cu")
		(net "M_A_DQS_DN<11>")
	)
	(segment
		(start 217.85072 -42.46372)
		(end 218.458288 -43.071288)
		(width 0.14224)
		(layer "In2.Cu")
		(net "M_A_DQS_DN<11>")
	)
	(segment
		(start 229.444042 -54.270656)
		(end 229.444042 -54.450488)
		(width 0.14224)
		(layer "In2.Cu")
		(net "M_A_DQS_DN<11>")
	)
	(segment
		(start 231.144318 -56.206898)
		(end 231.917748 -56.98109)
		(width 0.0889)
		(layer "In2.Cu")
		(net "M_A_DQS_DN<11>")
	)
	(segment
		(start 229.799896 -54.62651)
		(end 229.96144 -54.788054)
		(width 0.14224)
		(layer "In2.Cu")
		(net "M_A_DQS_DN<11>")
	)
	(segment
		(start 230.46436 -55.470806)
		(end 230.625904 -55.63235)
		(width 0.14224)
		(layer "In2.Cu")
		(net "M_A_DQS_DN<11>")
	)
	(segment
		(start 218.133168 -25.817576)
		(end 217.975688 -25.975056)
		(width 0.14224)
		(layer "In2.Cu")
		(net "M_A_DQS_DN<11>")
	)
	(segment
		(start 225.151442 -50.157888)
		(end 225.324162 -50.330608)
		(width 0.14224)
		(layer "In2.Cu")
		(net "M_A_DQS_DN<11>")
	)
	(segment
		(start 227.342192 -52.168806)
		(end 227.342192 -52.348638)
		(width 0.14224)
		(layer "In2.Cu")
		(net "M_A_DQS_DN<11>")
	)
	(segment
		(start 218.880944 -23.7998)
		(end 218.677744 -24.003)
		(width 0.14224)
		(layer "In2.Cu")
		(net "M_A_DQS_DN<11>")
	)
	(segment
		(start 225.324162 -50.330608)
		(end 225.503994 -50.330608)
		(width 0.14224)
		(layer "In2.Cu")
		(net "M_A_DQS_DN<11>")
	)
	(segment
		(start 219.231464 -22.045676)
		(end 218.44254 -22.8346)
		(width 0.14224)
		(layer "In2.Cu")
		(net "M_A_DQS_DN<11>")
	)
	(segment
		(start 218.07932 -40.63619)
		(end 218.458288 -41.015158)
		(width 0.14224)
		(layer "In2.Cu")
		(net "M_A_DQS_DN<11>")
	)
	(segment
		(start 217.620088 -37.74567)
		(end 217.818208 -37.94379)
		(width 0.14224)
		(layer "In2.Cu")
		(net "M_A_DQS_DN<11>")
	)
	(segment
		(start 218.44254 -22.8346)
		(end 218.880944 -23.273004)
		(width 0.14224)
		(layer "In2.Cu")
		(net "M_A_DQS_DN<11>")
	)
	(segment
		(start 235.472732 -57.711086)
		(end 235.612178 -57.57164)
		(width 0.0889)
		(layer "In2.Cu")
		(net "M_A_DQS_DN<11>")
	)
	(segment
		(start 225.832162 -50.838608)
		(end 226.011994 -50.838608)
		(width 0.14224)
		(layer "In2.Cu")
		(net "M_A_DQS_DN<11>")
	)
	(segment
		(start 223.602042 -48.608488)
		(end 223.787462 -48.793908)
		(width 0.14224)
		(layer "In2.Cu")
		(net "M_A_DQS_DN<11>")
	)
	(segment
		(start 228.940868 -53.767482)
		(end 228.940868 -53.947314)
		(width 0.14224)
		(layer "In2.Cu")
		(net "M_A_DQS_DN<11>")
	)
	(segment
		(start 230.802942 -55.865268)
		(end 230.982774 -55.865268)
		(width 0.0889)
		(layer "In2.Cu")
		(net "M_A_DQS_DN<11>")
	)
	(segment
		(start 225.503994 -50.330608)
		(end 225.665792 -50.492406)
		(width 0.14224)
		(layer "In2.Cu")
		(net "M_A_DQS_DN<11>")
	)
	(segment
		(start 223.787462 -48.793908)
		(end 223.926654 -48.793908)
		(width 0.14224)
		(layer "In2.Cu")
		(net "M_A_DQS_DN<11>")
	)
	(segment
		(start 218.133168 -27.341576)
		(end 217.975688 -27.499056)
		(width 0.14224)
		(layer "In2.Cu")
		(net "M_A_DQS_DN<11>")
	)
	(segment
		(start 218.458288 -41.637712)
		(end 217.85072 -42.24528)
		(width 0.14224)
		(layer "In2.Cu")
		(net "M_A_DQS_DN<11>")
	)
	(segment
		(start 217.4748 -39.737538)
		(end 217.4748 -40.414702)
		(width 0.14224)
		(layer "In2.Cu")
		(net "M_A_DQS_DN<11>")
	)
	(segment
		(start 223.260412 -48.266858)
		(end 223.387412 -48.266858)
		(width 0.14224)
		(layer "In2.Cu")
		(net "M_A_DQS_DN<11>")
	)
	(segment
		(start 217.975688 -25.406096)
		(end 218.133168 -25.563576)
		(width 0.14224)
		(layer "In2.Cu")
		(net "M_A_DQS_DN<11>")
	)
	(segment
		(start 217.653108 -39.55923)
		(end 217.4748 -39.737538)
		(width 0.14224)
		(layer "In2.Cu")
		(net "M_A_DQS_DN<11>")
	)
	(segment
		(start 228.940868 -53.947314)
		(end 229.102412 -54.108858)
		(width 0.14224)
		(layer "In2.Cu")
		(net "M_A_DQS_DN<11>")
	)
	(segment
		(start 224.306892 -49.313338)
		(end 224.486724 -49.313338)
		(width 0.14224)
		(layer "In2.Cu")
		(net "M_A_DQS_DN<11>")
	)
	(segment
		(start 224.486724 -49.313338)
		(end 224.648268 -49.474882)
		(width 0.14224)
		(layer "In2.Cu")
		(net "M_A_DQS_DN<11>")
	)
	(segment
		(start 226.448112 -51.454558)
		(end 226.627944 -51.454558)
		(width 0.14224)
		(layer "In2.Cu")
		(net "M_A_DQS_DN<11>")
	)
	(segment
		(start 230.641652 -55.703978)
		(end 230.802942 -55.865268)
		(width 0.0889)
		(layer "In2.Cu")
		(net "M_A_DQS_DN<11>")
	)
	(segment
		(start 217.975688 -24.644096)
		(end 218.133168 -24.801576)
		(width 0.14224)
		(layer "In2.Cu")
		(net "M_A_DQS_DN<11>")
	)
	(segment
		(start 217.975688 -24.408384)
		(end 217.975688 -24.644096)
		(width 0.14224)
		(layer "In2.Cu")
		(net "M_A_DQS_DN<11>")
	)
	(segment
		(start 223.602042 -48.481488)
		(end 223.602042 -48.608488)
		(width 0.14224)
		(layer "In2.Cu")
		(net "M_A_DQS_DN<11>")
	)
	(segment
		(start 217.975688 -27.499056)
		(end 217.975688 -32.9692)
		(width 0.14224)
		(layer "In2.Cu")
		(net "M_A_DQS_DN<11>")
	)
	(segment
		(start 235.05541 -57.55894)
		(end 235.055664 -57.558686)
		(width 0.0889)
		(layer "In2.Cu")
		(net "M_A_DQS_DN<11>")
	)
	(segment
		(start 230.122984 -55.12943)
		(end 230.302816 -55.12943)
		(width 0.14224)
		(layer "In2.Cu")
		(net "M_A_DQS_DN<11>")
	)
	(segment
		(start 224.648268 -49.474882)
		(end 224.648268 -49.654714)
		(width 0.14224)
		(layer "In2.Cu")
		(net "M_A_DQS_DN<11>")
	)
	(segment
		(start 217.4748 -40.414702)
		(end 217.696288 -40.63619)
		(width 0.14224)
		(layer "In2.Cu")
		(net "M_A_DQS_DN<11>")
	)
	(segment
		(start 218.677744 -24.003)
		(end 218.381072 -24.003)
		(width 0.14224)
		(layer "In2.Cu")
		(net "M_A_DQS_DN<11>")
	)
	(segment
		(start 228.779324 -53.605938)
		(end 228.940868 -53.767482)
		(width 0.14224)
		(layer "In2.Cu")
		(net "M_A_DQS_DN<11>")
	)
	(segment
		(start 218.894152 -17.60728)
		(end 219.231464 -17.944592)
		(width 0.14224)
		(layer "In2.Cu")
		(net "M_A_DQS_DN<11>")
	)
	(segment
		(start 225.665792 -50.492406)
		(end 225.665792 -50.672238)
		(width 0.14224)
		(layer "In2.Cu")
		(net "M_A_DQS_DN<11>")
	)
	(segment
		(start 228.096572 -53.103018)
		(end 228.276404 -53.103018)
		(width 0.14224)
		(layer "In2.Cu")
		(net "M_A_DQS_DN<11>")
	)
	(segment
		(start 230.46436 -55.290974)
		(end 230.46436 -55.470806)
		(width 0.14224)
		(layer "In2.Cu")
		(net "M_A_DQS_DN<11>")
	)
	(segment
		(start 230.641652 -55.648098)
		(end 230.641652 -55.703978)
		(width 0.0889)
		(layer "In2.Cu")
		(net "M_A_DQS_DN<11>")
	)
	(segment
		(start 227.000562 -52.007008)
		(end 227.180394 -52.007008)
		(width 0.14224)
		(layer "In2.Cu")
		(net "M_A_DQS_DN<11>")
	)
	(segment
		(start 224.129092 -48.996346)
		(end 224.129092 -49.135538)
		(width 0.14224)
		(layer "In2.Cu")
		(net "M_A_DQS_DN<11>")
	)
	(segment
		(start 218.133168 -26.579576)
		(end 217.975688 -26.737056)
		(width 0.14224)
		(layer "In2.Cu")
		(net "M_A_DQS_DN<11>")
	)
	(segment
		(start 228.437948 -53.444394)
		(end 228.599492 -53.605938)
		(width 0.14224)
		(layer "In2.Cu")
		(net "M_A_DQS_DN<11>")
	)
	(segment
		(start 218.449144 -17.4117)
		(end 218.644724 -17.60728)
		(width 0.14224)
		(layer "In2.Cu")
		(net "M_A_DQS_DN<11>")
	)
	(segment
		(start 224.989644 -49.816258)
		(end 225.151442 -49.978056)
		(width 0.14224)
		(layer "In2.Cu")
		(net "M_A_DQS_DN<11>")
	)
	(segment
		(start 227.900992 -52.907438)
		(end 228.096572 -53.103018)
		(width 0.14224)
		(layer "In2.Cu")
		(net "M_A_DQS_DN<11>")
	)
	(segment
		(start 228.276404 -53.103018)
		(end 228.437948 -53.264562)
		(width 0.14224)
		(layer "In2.Cu")
		(net "M_A_DQS_DN<11>")
	)
	(segment
		(start 217.696288 -40.63619)
		(end 218.07932 -40.63619)
		(width 0.14224)
		(layer "In2.Cu")
		(net "M_A_DQS_DN<11>")
	)
	(segment
		(start 225.151442 -49.978056)
		(end 225.151442 -50.157888)
		(width 0.14224)
		(layer "In2.Cu")
		(net "M_A_DQS_DN<11>")
	)
	(segment
		(start 233.781346 -57.476136)
		(end 234.766612 -57.476136)
		(width 0.0889)
		(layer "In2.Cu")
		(net "M_A_DQS_DN<11>")
	)
	(segment
		(start 217.975688 -26.737056)
		(end 217.975688 -26.930096)
		(width 0.14224)
		(layer "In2.Cu")
		(net "M_A_DQS_DN<11>")
	)
	(segment
		(start 217.818208 -37.94379)
		(end 218.270074 -37.94379)
		(width 0.14224)
		(layer "In2.Cu")
		(net "M_A_DQS_DN<11>")
	)
	(segment
		(start 229.96144 -54.967886)
		(end 230.122984 -55.12943)
		(width 0.14224)
		(layer "In2.Cu")
		(net "M_A_DQS_DN<11>")
	)
	(segment
		(start 227.739194 -52.565808)
		(end 227.900992 -52.727606)
		(width 0.14224)
		(layer "In2.Cu")
		(net "M_A_DQS_DN<11>")
	)
	(segment
		(start 226.627944 -51.454558)
		(end 226.789742 -51.616356)
		(width 0.14224)
		(layer "In2.Cu")
		(net "M_A_DQS_DN<11>")
	)
	(segment
		(start 218.133168 -26.325576)
		(end 218.133168 -26.579576)
		(width 0.14224)
		(layer "In2.Cu")
		(net "M_A_DQS_DN<11>")
	)
	(segment
		(start 226.011994 -50.838608)
		(end 226.173792 -51.000406)
		(width 0.14224)
		(layer "In2.Cu")
		(net "M_A_DQS_DN<11>")
	)
	(segment
		(start 218.880944 -23.273004)
		(end 218.880944 -23.7998)
		(width 0.14224)
		(layer "In2.Cu")
		(net "M_A_DQS_DN<11>")
	)
	(segment
		(start 218.381072 -24.003)
		(end 217.975688 -24.408384)
		(width 0.14224)
		(layer "In2.Cu")
		(net "M_A_DQS_DN<11>")
	)
	(segment
		(start 223.926654 -48.793908)
		(end 224.129092 -48.996346)
		(width 0.14224)
		(layer "In2.Cu")
		(net "M_A_DQS_DN<11>")
	)
	(segment
		(start 218.133168 -27.087576)
		(end 218.133168 -27.341576)
		(width 0.14224)
		(layer "In2.Cu")
		(net "M_A_DQS_DN<11>")
	)
	(segment
		(start 218.133168 -24.801576)
		(end 218.133168 -25.055576)
		(width 0.14224)
		(layer "In2.Cu")
		(net "M_A_DQS_DN<11>")
	)
	(segment
		(start 217.975688 -26.930096)
		(end 218.133168 -27.087576)
		(width 0.14224)
		(layer "In2.Cu")
		(net "M_A_DQS_DN<11>")
	)
	(segment
		(start 230.982774 -55.865268)
		(end 231.144318 -56.027066)
		(width 0.0889)
		(layer "In2.Cu")
		(net "M_A_DQS_DN<11>")
	)
	(segment
		(start 218.458288 -41.015158)
		(end 218.458288 -41.637712)
		(width 0.14224)
		(layer "In2.Cu")
		(net "M_A_DQS_DN<11>")
	)
	(segment
		(start 218.133168 -25.563576)
		(end 218.133168 -25.817576)
		(width 0.14224)
		(layer "In2.Cu")
		(net "M_A_DQS_DN<11>")
	)
	(segment
		(start 217.85072 -42.24528)
		(end 217.85072 -42.46372)
		(width 0.14224)
		(layer "In2.Cu")
		(net "M_A_DQS_DN<11>")
	)
	(segment
		(start 226.173792 -51.000406)
		(end 226.173792 -51.180238)
		(width 0.14224)
		(layer "In2.Cu")
		(net "M_A_DQS_DN<11>")
	)
	(segment
		(start 218.133168 -25.055576)
		(end 217.975688 -25.213056)
		(width 0.14224)
		(layer "In2.Cu")
		(net "M_A_DQS_DN<11>")
	)
	(segment
		(start 224.809812 -49.816258)
		(end 224.989644 -49.816258)
		(width 0.14224)
		(layer "In2.Cu")
		(net "M_A_DQS_DN<11>")
	)
	(segment
		(start 219.231464 -17.944592)
		(end 219.231464 -22.045676)
		(width 0.14224)
		(layer "In2.Cu")
		(net "M_A_DQS_DN<11>")
	)
	(segment
		(start 218.252294 -39.55923)
		(end 217.653108 -39.55923)
		(width 0.14224)
		(layer "In2.Cu")
		(net "M_A_DQS_DN<11>")
	)
	(segment
		(start 228.599492 -53.605938)
		(end 228.779324 -53.605938)
		(width 0.14224)
		(layer "In2.Cu")
		(net "M_A_DQS_DN<11>")
	)
	(segment
		(start 224.648268 -49.654714)
		(end 224.809812 -49.816258)
		(width 0.14224)
		(layer "In2.Cu")
		(net "M_A_DQS_DN<11>")
	)
	(segment
		(start 233.2863 -56.98109)
		(end 233.781346 -57.476136)
		(width 0.0889)
		(layer "In2.Cu")
		(net "M_A_DQS_DN<11>")
	)
	(segment
		(start 231.917748 -56.98109)
		(end 233.2863 -56.98109)
		(width 0.0889)
		(layer "In2.Cu")
		(net "M_A_DQS_DN<11>")
	)
	(segment
		(start 231.144318 -56.027066)
		(end 231.144318 -56.206898)
		(width 0.0889)
		(layer "In2.Cu")
		(net "M_A_DQS_DN<11>")
	)
	(segment
		(start 235.472224 -57.711086)
		(end 235.472732 -57.711086)
		(width 0.0889)
		(layer "In2.Cu")
		(net "M_A_DQS_DN<11>")
	)
	(segment
		(start 227.180394 -52.007008)
		(end 227.342192 -52.168806)
		(width 0.14224)
		(layer "In2.Cu")
		(net "M_A_DQS_DN<11>")
	)
	(segment
		(start 217.975688 -26.168096)
		(end 218.133168 -26.325576)
		(width 0.14224)
		(layer "In2.Cu")
		(net "M_A_DQS_DN<11>")
	)
	(arc
		(start 234.766612 -57.476136)
		(mid 234.916353 -57.498898)
		(end 235.05541 -57.55894)
		(width 0.0889)
		(layer "In2.Cu")
		(net "M_A_DQS_DN<11>")
	)
	(arc
		(start 235.055664 -57.558686)
		(mid 235.079803 -57.573977)
		(end 235.103162 -57.590436)
		(width 0.0889)
		(layer "In2.Cu")
		(net "M_A_DQS_DN<11>")
	)
	(arc
		(start 235.103162 -57.590436)
		(mid 235.278077 -57.680188)
		(end 235.472224 -57.711086)
		(width 0.0889)
		(layer "In2.Cu")
		(net "M_A_DQS_DN<11>")
	)
	(segment
		(start 208.722468 -24.932132)
		(end 208.85785 -24.79675)
		(width 0.1651)
		(layer "F.Cu")
		(net "M_A_DQS_DN<10>")
	)
	(segment
		(start 212.248496 -31.070296)
		(end 209.347816 -28.169616)
		(width 0.1651)
		(layer "F.Cu")
		(net "M_A_DQS_DN<10>")
	)
	(segment
		(start 208.722468 -27.544268)
		(end 208.722468 -27.218132)
		(width 0.1651)
		(layer "F.Cu")
		(net "M_A_DQS_DN<10>")
	)
	(segment
		(start 208.85785 -25.55875)
		(end 208.85785 -25.321514)
		(width 0.1651)
		(layer "F.Cu")
		(net "M_A_DQS_DN<10>")
	)
	(segment
		(start 232.771188 -56.98109)
		(end 231.727756 -56.98109)
		(width 0.0889)
		(layer "F.Cu")
		(net "M_A_DQS_DN<10>")
	)
	(segment
		(start 209.58175 -16.9164)
		(end 209.767678 -17.102328)
		(width 0.1651)
		(layer "F.Cu")
		(net "M_A_DQS_DN<10>")
	)
	(segment
		(start 208.85785 -27.08275)
		(end 208.85785 -26.845514)
		(width 0.1651)
		(layer "F.Cu")
		(net "M_A_DQS_DN<10>")
	)
	(segment
		(start 211.322158 -32.70885)
		(end 211.912454 -32.70885)
		(width 0.1651)
		(layer "F.Cu")
		(net "M_A_DQS_DN<10>")
	)
	(segment
		(start 208.722468 -26.710132)
		(end 208.722468 -26.456132)
		(width 0.1651)
		(layer "F.Cu")
		(net "M_A_DQS_DN<10>")
	)
	(segment
		(start 234.466638 -57.57164)
		(end 234.140502 -57.57164)
		(width 0.0889)
		(layer "F.Cu")
		(net "M_A_DQS_DN<10>")
	)
	(segment
		(start 211.912454 -32.70885)
		(end 212.248496 -32.372808)
		(width 0.1651)
		(layer "F.Cu")
		(net "M_A_DQS_DN<10>")
	)
	(segment
		(start 209.296 -23.9776)
		(end 209.54238 -23.73122)
		(width 0.1651)
		(layer "F.Cu")
		(net "M_A_DQS_DN<10>")
	)
	(segment
		(start 209.270854 -22.8346)
		(end 209.092546 -22.8346)
		(width 0.1651)
		(layer "F.Cu")
		(net "M_A_DQS_DN<10>")
	)
	(segment
		(start 212.248496 -39.169848)
		(end 212.248496 -33.717992)
		(width 0.1651)
		(layer "F.Cu")
		(net "M_A_DQS_DN<10>")
	)
	(segment
		(start 209.58175 -16.495268)
		(end 209.58175 -16.9164)
		(width 0.1651)
		(layer "F.Cu")
		(net "M_A_DQS_DN<10>")
	)
	(segment
		(start 209.999834 -16.077184)
		(end 209.58175 -16.495268)
		(width 0.1651)
		(layer "F.Cu")
		(net "M_A_DQS_DN<10>")
	)
	(segment
		(start 208.915 -23.9776)
		(end 209.296 -23.9776)
		(width 0.1651)
		(layer "F.Cu")
		(net "M_A_DQS_DN<10>")
	)
	(segment
		(start 208.988406 -27.810206)
		(end 208.722468 -27.544268)
		(width 0.1651)
		(layer "F.Cu")
		(net "M_A_DQS_DN<10>")
	)
	(segment
		(start 231.727756 -56.98109)
		(end 231.67848 -56.931814)
		(width 0.0889)
		(layer "F.Cu")
		(net "M_A_DQS_DN<10>")
	)
	(segment
		(start 211.322158 -33.38195)
		(end 211.157058 -33.21685)
		(width 0.1651)
		(layer "F.Cu")
		(net "M_A_DQS_DN<10>")
	)
	(segment
		(start 211.912454 -33.38195)
		(end 211.322158 -33.38195)
		(width 0.1651)
		(layer "F.Cu")
		(net "M_A_DQS_DN<10>")
	)
	(segment
		(start 208.85785 -26.083514)
		(end 208.722468 -25.948132)
		(width 0.1651)
		(layer "F.Cu")
		(net "M_A_DQS_DN<10>")
	)
	(segment
		(start 212.248496 -32.372808)
		(end 212.248496 -31.070296)
		(width 0.1651)
		(layer "F.Cu")
		(net "M_A_DQS_DN<10>")
	)
	(segment
		(start 209.30743 -17.60093)
		(end 209.1182 -17.4117)
		(width 0.1651)
		(layer "F.Cu")
		(net "M_A_DQS_DN<10>")
	)
	(segment
		(start 208.722468 -25.694132)
		(end 208.85785 -25.55875)
		(width 0.1651)
		(layer "F.Cu")
		(net "M_A_DQS_DN<10>")
	)
	(segment
		(start 209.54238 -23.73122)
		(end 209.54238 -23.106126)
		(width 0.1651)
		(layer "F.Cu")
		(net "M_A_DQS_DN<10>")
	)
	(segment
		(start 208.722468 -27.218132)
		(end 208.85785 -27.08275)
		(width 0.1651)
		(layer "F.Cu")
		(net "M_A_DQS_DN<10>")
	)
	(segment
		(start 231.67848 -56.931814)
		(end 230.010462 -56.931814)
		(width 0.1651)
		(layer "F.Cu")
		(net "M_A_DQS_DN<10>")
	)
	(segment
		(start 208.85785 -25.321514)
		(end 208.722468 -25.186132)
		(width 0.1651)
		(layer "F.Cu")
		(net "M_A_DQS_DN<10>")
	)
	(segment
		(start 208.85785 -24.79675)
		(end 208.85785 -24.559514)
		(width 0.1651)
		(layer "F.Cu")
		(net "M_A_DQS_DN<10>")
	)
	(segment
		(start 208.722468 -25.186132)
		(end 208.722468 -24.932132)
		(width 0.1651)
		(layer "F.Cu")
		(net "M_A_DQS_DN<10>")
	)
	(segment
		(start 208.85785 -24.559514)
		(end 208.722468 -24.424132)
		(width 0.1651)
		(layer "F.Cu")
		(net "M_A_DQS_DN<10>")
	)
	(segment
		(start 208.722468 -25.948132)
		(end 208.722468 -25.694132)
		(width 0.1651)
		(layer "F.Cu")
		(net "M_A_DQS_DN<10>")
	)
	(segment
		(start 211.157058 -33.21685)
		(end 211.157058 -32.87395)
		(width 0.1651)
		(layer "F.Cu")
		(net "M_A_DQS_DN<10>")
	)
	(segment
		(start 208.722468 -24.424132)
		(end 208.722468 -24.170132)
		(width 0.1651)
		(layer "F.Cu")
		(net "M_A_DQS_DN<10>")
	)
	(segment
		(start 230.010462 -56.931814)
		(end 212.248496 -39.169848)
		(width 0.1651)
		(layer "F.Cu")
		(net "M_A_DQS_DN<10>")
	)
	(segment
		(start 208.722468 -26.456132)
		(end 208.85785 -26.32075)
		(width 0.1651)
		(layer "F.Cu")
		(net "M_A_DQS_DN<10>")
	)
	(segment
		(start 209.347816 -28.169616)
		(end 209.347816 -27.989784)
		(width 0.1651)
		(layer "F.Cu")
		(net "M_A_DQS_DN<10>")
	)
	(segment
		(start 209.999834 -15.423642)
		(end 209.999834 -16.077184)
		(width 0.1651)
		(layer "F.Cu")
		(net "M_A_DQS_DN<10>")
	)
	(segment
		(start 209.1182 -17.4117)
		(end 209.09915 -17.4117)
		(width 0.1651)
		(layer "F.Cu")
		(net "M_A_DQS_DN<10>")
	)
	(segment
		(start 208.722468 -24.170132)
		(end 208.915 -23.9776)
		(width 0.1651)
		(layer "F.Cu")
		(net "M_A_DQS_DN<10>")
	)
	(segment
		(start 208.85785 -26.32075)
		(end 208.85785 -26.083514)
		(width 0.1651)
		(layer "F.Cu")
		(net "M_A_DQS_DN<10>")
	)
	(segment
		(start 209.51571 -17.60093)
		(end 209.30743 -17.60093)
		(width 0.1651)
		(layer "F.Cu")
		(net "M_A_DQS_DN<10>")
	)
	(segment
		(start 211.157058 -32.87395)
		(end 211.322158 -32.70885)
		(width 0.1651)
		(layer "F.Cu")
		(net "M_A_DQS_DN<10>")
	)
	(segment
		(start 209.767678 -17.348962)
		(end 209.51571 -17.60093)
		(width 0.1651)
		(layer "F.Cu")
		(net "M_A_DQS_DN<10>")
	)
	(segment
		(start 209.167984 -27.810206)
		(end 208.988406 -27.810206)
		(width 0.1651)
		(layer "F.Cu")
		(net "M_A_DQS_DN<10>")
	)
	(segment
		(start 212.248496 -33.717992)
		(end 211.912454 -33.38195)
		(width 0.1651)
		(layer "F.Cu")
		(net "M_A_DQS_DN<10>")
	)
	(segment
		(start 209.54238 -23.106126)
		(end 209.270854 -22.8346)
		(width 0.1651)
		(layer "F.Cu")
		(net "M_A_DQS_DN<10>")
	)
	(segment
		(start 209.767678 -17.102328)
		(end 209.767678 -17.348962)
		(width 0.1651)
		(layer "F.Cu")
		(net "M_A_DQS_DN<10>")
	)
	(segment
		(start 208.85785 -26.845514)
		(end 208.722468 -26.710132)
		(width 0.1651)
		(layer "F.Cu")
		(net "M_A_DQS_DN<10>")
	)
	(segment
		(start 210.000342 -15.423642)
		(end 209.999834 -15.423642)
		(width 0.1651)
		(layer "F.Cu")
		(net "M_A_DQS_DN<10>")
	)
	(segment
		(start 233.71683 -57.47639)
		(end 233.597704 -57.47639)
		(width 0.0889)
		(layer "F.Cu")
		(net "M_A_DQS_DN<10>")
	)
	(segment
		(start 209.347816 -27.989784)
		(end 209.167984 -27.810206)
		(width 0.1651)
		(layer "F.Cu")
		(net "M_A_DQS_DN<10>")
	)
	(via
		(at 209.09915 -17.4117)
		(size 0.508)
		(drill 0.254)
		(layers "F.Cu" "B.Cu")
		(net "M_A_DQS_DN<10>")
	)
	(via
		(at 209.092546 -22.8346)
		(size 0.508)
		(drill 0.254)
		(layers "F.Cu" "B.Cu")
		(net "M_A_DQS_DN<10>")
	)
	(arc
		(start 233.597704 -57.47639)
		(mid 233.403398 -57.420239)
		(end 233.261408 -57.276238)
		(width 0.0889)
		(layer "F.Cu")
		(net "M_A_DQS_DN<10>")
	)
	(arc
		(start 234.140502 -57.57164)
		(mid 234.009031 -57.557051)
		(end 233.883962 -57.513982)
		(width 0.0889)
		(layer "F.Cu")
		(net "M_A_DQS_DN<10>")
	)
	(arc
		(start 233.883962 -57.513982)
		(mid 233.80248 -57.485927)
		(end 233.71683 -57.47639)
		(width 0.0889)
		(layer "F.Cu")
		(net "M_A_DQS_DN<10>")
	)
	(arc
		(start 233.261408 -57.276238)
		(mid 233.054404 -57.065374)
		(end 232.771188 -56.98109)
		(width 0.0889)
		(layer "F.Cu")
		(net "M_A_DQS_DN<10>")
	)
	(segment
		(start 210.000088 -24.167592)
		(end 210.000088 -24.823928)
		(width 0.1651)
		(layer "B.Cu")
		(net "M_A_DQS_DN<10>")
	)
	(segment
		(start 210.000088 -24.823928)
		(end 210.000342 -24.824182)
		(width 0.1651)
		(layer "B.Cu")
		(net "M_A_DQS_DN<10>")
	)
	(segment
		(start 209.55635 -23.368)
		(end 209.55635 -23.723854)
		(width 0.1651)
		(layer "B.Cu")
		(net "M_A_DQS_DN<10>")
	)
	(segment
		(start 209.514186 -22.640036)
		(end 209.73415 -22.86)
		(width 0.1651)
		(layer "B.Cu")
		(net "M_A_DQS_DN<10>")
	)
	(segment
		(start 209.28711 -22.640036)
		(end 209.514186 -22.640036)
		(width 0.1651)
		(layer "B.Cu")
		(net "M_A_DQS_DN<10>")
	)
	(segment
		(start 209.73415 -22.86)
		(end 209.73415 -23.1902)
		(width 0.1651)
		(layer "B.Cu")
		(net "M_A_DQS_DN<10>")
	)
	(segment
		(start 209.55635 -23.723854)
		(end 210.000088 -24.167592)
		(width 0.1651)
		(layer "B.Cu")
		(net "M_A_DQS_DN<10>")
	)
	(segment
		(start 209.73415 -23.1902)
		(end 209.55635 -23.368)
		(width 0.1651)
		(layer "B.Cu")
		(net "M_A_DQS_DN<10>")
	)
	(segment
		(start 209.092546 -22.8346)
		(end 209.28711 -22.640036)
		(width 0.1651)
		(layer "B.Cu")
		(net "M_A_DQS_DN<10>")
	)
	(segment
		(start 209.544158 -17.60728)
		(end 209.29473 -17.60728)
		(width 0.14224)
		(layer "In2.Cu")
		(net "M_A_DQS_DN<10>")
	)
	(segment
		(start 209.29473 -17.60728)
		(end 209.09915 -17.4117)
		(width 0.14224)
		(layer "In2.Cu")
		(net "M_A_DQS_DN<10>")
	)
	(segment
		(start 209.88147 -22.045676)
		(end 209.88147 -17.944592)
		(width 0.14224)
		(layer "In2.Cu")
		(net "M_A_DQS_DN<10>")
	)
	(segment
		(start 209.88147 -17.944592)
		(end 209.544158 -17.60728)
		(width 0.14224)
		(layer "In2.Cu")
		(net "M_A_DQS_DN<10>")
	)
	(segment
		(start 209.092546 -22.8346)
		(end 209.88147 -22.045676)
		(width 0.14224)
		(layer "In2.Cu")
		(net "M_A_DQS_DN<10>")
	)
	(segment
		(start 200.650348 -20.023582)
		(end 200.64984 -20.023582)
		(width 0.1651)
		(layer "F.Cu")
		(net "M_A_DQS_DN<0>")
	)
	(segment
		(start 200.64984 -18.94967)
		(end 200.267824 -18.567654)
		(width 0.1651)
		(layer "F.Cu")
		(net "M_A_DQS_DN<0>")
	)
	(segment
		(start 200.267824 -18.135854)
		(end 200.598278 -17.8054)
		(width 0.1651)
		(layer "F.Cu")
		(net "M_A_DQS_DN<0>")
	)
	(segment
		(start 200.822306 -17.8054)
		(end 201.037952 -18.021046)
		(width 0.1651)
		(layer "F.Cu")
		(net "M_A_DQS_DN<0>")
	)
	(segment
		(start 234.466638 -63.51524)
		(end 233.895138 -63.51524)
		(width 0.1016)
		(layer "F.Cu")
		(net "M_A_DQS_DN<0>")
	)
	(segment
		(start 200.64984 -20.023582)
		(end 200.64984 -18.94967)
		(width 0.1651)
		(layer "F.Cu")
		(net "M_A_DQS_DN<0>")
	)
	(segment
		(start 200.267824 -18.567654)
		(end 200.267824 -18.135854)
		(width 0.1651)
		(layer "F.Cu")
		(net "M_A_DQS_DN<0>")
	)
	(segment
		(start 200.598278 -17.8054)
		(end 200.822306 -17.8054)
		(width 0.1651)
		(layer "F.Cu")
		(net "M_A_DQS_DN<0>")
	)
	(via
		(at 201.037952 -22.228556)
		(size 0.508)
		(drill 0.254)
		(layers "F.Cu" "B.Cu")
		(net "M_A_DQS_DN<0>")
	)
	(via
		(at 233.895138 -63.51524)
		(size 0.508)
		(drill 0.254)
		(layers "F.Cu" "B.Cu")
		(net "M_A_DQS_DN<0>")
	)
	(via
		(at 201.037952 -18.021046)
		(size 0.508)
		(drill 0.254)
		(layers "F.Cu" "B.Cu")
		(net "M_A_DQS_DN<0>")
	)
	(segment
		(start 200.650348 -20.224242)
		(end 200.64984 -20.224242)
		(width 0.1651)
		(layer "B.Cu")
		(net "M_A_DQS_DN<0>")
	)
	(segment
		(start 200.521824 -21.259546)
		(end 200.521824 -21.513546)
		(width 0.1651)
		(layer "B.Cu")
		(net "M_A_DQS_DN<0>")
	)
	(segment
		(start 200.812908 -22.4536)
		(end 201.037952 -22.228556)
		(width 0.1651)
		(layer "B.Cu")
		(net "M_A_DQS_DN<0>")
	)
	(segment
		(start 200.267824 -22.098)
		(end 200.623424 -22.4536)
		(width 0.1651)
		(layer "B.Cu")
		(net "M_A_DQS_DN<0>")
	)
	(segment
		(start 200.521824 -21.513546)
		(end 200.267824 -21.767546)
		(width 0.1651)
		(layer "B.Cu")
		(net "M_A_DQS_DN<0>")
	)
	(segment
		(start 200.64984 -21.13153)
		(end 200.521824 -21.259546)
		(width 0.1651)
		(layer "B.Cu")
		(net "M_A_DQS_DN<0>")
	)
	(segment
		(start 200.267824 -21.767546)
		(end 200.267824 -22.098)
		(width 0.1651)
		(layer "B.Cu")
		(net "M_A_DQS_DN<0>")
	)
	(segment
		(start 200.623424 -22.4536)
		(end 200.812908 -22.4536)
		(width 0.1651)
		(layer "B.Cu")
		(net "M_A_DQS_DN<0>")
	)
	(segment
		(start 200.64984 -20.224242)
		(end 200.64984 -21.13153)
		(width 0.1651)
		(layer "B.Cu")
		(net "M_A_DQS_DN<0>")
	)
	(segment
		(start 201.037952 -22.228556)
		(end 201.037952 -22.22881)
		(width 0.14224)
		(layer "In2.Cu")
		(net "M_A_DQS_DN<0>")
	)
	(segment
		(start 201.400156 -21.082)
		(end 201.2696 -21.082)
		(width 0.14224)
		(layer "In2.Cu")
		(net "M_A_DQS_DN<0>")
	)
	(segment
		(start 232.783126 -63.610236)
		(end 232.28808 -63.11519)
		(width 0.0889)
		(layer "In2.Cu")
		(net "M_A_DQS_DN<0>")
	)
	(segment
		(start 201.0918 -20.6502)
		(end 201.2696 -20.4724)
		(width 0.14224)
		(layer "In2.Cu")
		(net "M_A_DQS_DN<0>")
	)
	(segment
		(start 201.044556 -19.278854)
		(end 201.19721 -19.1262)
		(width 0.14224)
		(layer "In2.Cu")
		(net "M_A_DQS_DN<0>")
	)
	(segment
		(start 200.967848 -25.141682)
		(end 200.592436 -24.76627)
		(width 0.14224)
		(layer "In2.Cu")
		(net "M_A_DQS_DN<0>")
	)
	(segment
		(start 203.787248 -35.257232)
		(end 203.21016 -34.680144)
		(width 0.14224)
		(layer "In2.Cu")
		(net "M_A_DQS_DN<0>")
	)
	(segment
		(start 231.22255 -63.806324)
		(end 231.049068 -63.806324)
		(width 0.0889)
		(layer "In2.Cu")
		(net "M_A_DQS_DN<0>")
	)
	(segment
		(start 201.57948 -21.261324)
		(end 201.400156 -21.082)
		(width 0.14224)
		(layer "In2.Cu")
		(net "M_A_DQS_DN<0>")
	)
	(segment
		(start 201.2696 -20.4724)
		(end 201.3966 -20.4724)
		(width 0.14224)
		(layer "In2.Cu")
		(net "M_A_DQS_DN<0>")
	)
	(segment
		(start 201.374502 -19.7358)
		(end 201.19721 -19.7358)
		(width 0.14224)
		(layer "In2.Cu")
		(net "M_A_DQS_DN<0>")
	)
	(segment
		(start 203.69276 -37.7444)
		(end 203.378054 -37.7444)
		(width 0.14224)
		(layer "In2.Cu")
		(net "M_A_DQS_DN<0>")
	)
	(segment
		(start 203.378054 -37.7444)
		(end 202.949048 -37.315394)
		(width 0.14224)
		(layer "In2.Cu")
		(net "M_A_DQS_DN<0>")
	)
	(segment
		(start 201.044556 -19.583146)
		(end 201.044556 -19.278854)
		(width 0.14224)
		(layer "In2.Cu")
		(net "M_A_DQS_DN<0>")
	)
	(segment
		(start 228.970586 -63.854076)
		(end 203.914248 -38.797738)
		(width 0.14224)
		(layer "In2.Cu")
		(net "M_A_DQS_DN<0>")
	)
	(segment
		(start 231.913684 -63.11519)
		(end 231.22255 -63.806324)
		(width 0.0889)
		(layer "In2.Cu")
		(net "M_A_DQS_DN<0>")
	)
	(segment
		(start 231.001316 -63.854076)
		(end 228.970586 -63.854076)
		(width 0.14224)
		(layer "In2.Cu")
		(net "M_A_DQS_DN<0>")
	)
	(segment
		(start 202.949048 -37.315394)
		(end 202.949048 -36.551616)
		(width 0.14224)
		(layer "In2.Cu")
		(net "M_A_DQS_DN<0>")
	)
	(segment
		(start 201.0918 -20.9042)
		(end 201.0918 -20.6502)
		(width 0.14224)
		(layer "In2.Cu")
		(net "M_A_DQS_DN<0>")
	)
	(segment
		(start 201.3966 -20.4724)
		(end 201.57948 -20.28952)
		(width 0.14224)
		(layer "In2.Cu")
		(net "M_A_DQS_DN<0>")
	)
	(segment
		(start 200.592436 -24.76627)
		(end 200.592436 -22.674072)
		(width 0.14224)
		(layer "In2.Cu")
		(net "M_A_DQS_DN<0>")
	)
	(segment
		(start 201.19721 -19.1262)
		(end 201.399902 -19.1262)
		(width 0.14224)
		(layer "In2.Cu")
		(net "M_A_DQS_DN<0>")
	)
	(segment
		(start 232.28808 -63.11519)
		(end 231.913684 -63.11519)
		(width 0.0889)
		(layer "In2.Cu")
		(net "M_A_DQS_DN<0>")
	)
	(segment
		(start 231.049068 -63.806324)
		(end 231.001316 -63.854076)
		(width 0.0889)
		(layer "In2.Cu")
		(net "M_A_DQS_DN<0>")
	)
	(segment
		(start 202.949048 -36.551616)
		(end 203.787248 -35.713416)
		(width 0.14224)
		(layer "In2.Cu")
		(net "M_A_DQS_DN<0>")
	)
	(segment
		(start 201.57948 -20.28952)
		(end 201.57948 -19.940778)
		(width 0.14224)
		(layer "In2.Cu")
		(net "M_A_DQS_DN<0>")
	)
	(segment
		(start 201.57948 -18.280888)
		(end 201.319638 -18.021046)
		(width 0.14224)
		(layer "In2.Cu")
		(net "M_A_DQS_DN<0>")
	)
	(segment
		(start 201.399902 -19.1262)
		(end 201.57948 -18.946622)
		(width 0.14224)
		(layer "In2.Cu")
		(net "M_A_DQS_DN<0>")
	)
	(segment
		(start 201.3712 -34.680144)
		(end 200.967848 -34.276792)
		(width 0.14224)
		(layer "In2.Cu")
		(net "M_A_DQS_DN<0>")
	)
	(segment
		(start 201.57948 -21.966174)
		(end 201.57948 -21.261324)
		(width 0.14224)
		(layer "In2.Cu")
		(net "M_A_DQS_DN<0>")
	)
	(segment
		(start 201.57948 -19.940778)
		(end 201.374502 -19.7358)
		(width 0.14224)
		(layer "In2.Cu")
		(net "M_A_DQS_DN<0>")
	)
	(segment
		(start 203.914248 -37.965888)
		(end 203.69276 -37.7444)
		(width 0.14224)
		(layer "In2.Cu")
		(net "M_A_DQS_DN<0>")
	)
	(segment
		(start 201.2696 -21.082)
		(end 201.0918 -20.9042)
		(width 0.14224)
		(layer "In2.Cu")
		(net "M_A_DQS_DN<0>")
	)
	(segment
		(start 201.316844 -22.22881)
		(end 201.57948 -21.966174)
		(width 0.14224)
		(layer "In2.Cu")
		(net "M_A_DQS_DN<0>")
	)
	(segment
		(start 201.037952 -22.22881)
		(end 201.316844 -22.22881)
		(width 0.14224)
		(layer "In2.Cu")
		(net "M_A_DQS_DN<0>")
	)
	(segment
		(start 201.57948 -18.946622)
		(end 201.57948 -18.280888)
		(width 0.14224)
		(layer "In2.Cu")
		(net "M_A_DQS_DN<0>")
	)
	(segment
		(start 201.319638 -18.021046)
		(end 201.037952 -18.021046)
		(width 0.14224)
		(layer "In2.Cu")
		(net "M_A_DQS_DN<0>")
	)
	(segment
		(start 233.172508 -63.610236)
		(end 232.783126 -63.610236)
		(width 0.0889)
		(layer "In2.Cu")
		(net "M_A_DQS_DN<0>")
	)
	(segment
		(start 203.21016 -34.680144)
		(end 201.3712 -34.680144)
		(width 0.14224)
		(layer "In2.Cu")
		(net "M_A_DQS_DN<0>")
	)
	(segment
		(start 200.592436 -22.674072)
		(end 201.037952 -22.228556)
		(width 0.14224)
		(layer "In2.Cu")
		(net "M_A_DQS_DN<0>")
	)
	(segment
		(start 201.19721 -19.7358)
		(end 201.044556 -19.583146)
		(width 0.14224)
		(layer "In2.Cu")
		(net "M_A_DQS_DN<0>")
	)
	(segment
		(start 200.967848 -34.276792)
		(end 200.967848 -25.141682)
		(width 0.14224)
		(layer "In2.Cu")
		(net "M_A_DQS_DN<0>")
	)
	(segment
		(start 203.787248 -35.713416)
		(end 203.787248 -35.257232)
		(width 0.14224)
		(layer "In2.Cu")
		(net "M_A_DQS_DN<0>")
	)
	(segment
		(start 203.914248 -38.797738)
		(end 203.914248 -37.965888)
		(width 0.14224)
		(layer "In2.Cu")
		(net "M_A_DQS_DN<0>")
	)
	(segment
		(start 233.895138 -63.51524)
		(end 233.688382 -63.51524)
		(width 0.0889)
		(layer "In2.Cu")
		(net "M_A_DQS_DN<0>")
	)
	(arc
		(start 233.688382 -63.51524)
		(mid 233.497001 -63.53272)
		(end 233.311954 -63.584582)
		(width 0.0889)
		(layer "In2.Cu")
		(net "M_A_DQS_DN<0>")
	)
	(arc
		(start 233.311954 -63.584582)
		(mid 233.243404 -63.603781)
		(end 233.172508 -63.610236)
		(width 0.0889)
		(layer "In2.Cu")
		(net "M_A_DQS_DN<0>")
	)
	(segment
		(start 211.315554 -34.922714)
		(end 210.095338 -33.702498)
		(width 0.1651)
		(layer "F.Cu")
		(net "M_A_DQ<9>")
	)
	(segment
		(start 232.828846 -57.971436)
		(end 231.843326 -57.971436)
		(width 0.0889)
		(layer "F.Cu")
		(net "M_A_DQ<9>")
	)
	(segment
		(start 207.917796 -23.386796)
		(end 207.612996 -23.081996)
		(width 0.1651)
		(layer "F.Cu")
		(net "M_A_DQ<9>")
	)
	(segment
		(start 210.095338 -33.702498)
		(end 210.095338 -32.13227)
		(width 0.1651)
		(layer "F.Cu")
		(net "M_A_DQ<9>")
	)
	(segment
		(start 231.843326 -57.971436)
		(end 231.747314 -57.875424)
		(width 0.0889)
		(layer "F.Cu")
		(net "M_A_DQ<9>")
	)
	(segment
		(start 211.315554 -39.611808)
		(end 211.315554 -34.922714)
		(width 0.1651)
		(layer "F.Cu")
		(net "M_A_DQ<9>")
	)
	(segment
		(start 231.747314 -57.875424)
		(end 229.57917 -57.875424)
		(width 0.1651)
		(layer "F.Cu")
		(net "M_A_DQ<9>")
	)
	(segment
		(start 210.3628 -31.864808)
		(end 210.3628 -31.396432)
		(width 0.1651)
		(layer "F.Cu")
		(net "M_A_DQ<9>")
	)
	(segment
		(start 229.57917 -57.875424)
		(end 211.315554 -39.611808)
		(width 0.1651)
		(layer "F.Cu")
		(net "M_A_DQ<9>")
	)
	(segment
		(start 207.450436 -15.423642)
		(end 207.449928 -15.423642)
		(width 0.1651)
		(layer "F.Cu")
		(net "M_A_DQ<9>")
	)
	(segment
		(start 210.095338 -31.12897)
		(end 210.095338 -30.448504)
		(width 0.1651)
		(layer "F.Cu")
		(net "M_A_DQ<9>")
	)
	(segment
		(start 207.612996 -22.788372)
		(end 208.122012 -22.279356)
		(width 0.1651)
		(layer "F.Cu")
		(net "M_A_DQ<9>")
	)
	(segment
		(start 207.612996 -23.081996)
		(end 207.612996 -22.788372)
		(width 0.1651)
		(layer "F.Cu")
		(net "M_A_DQ<9>")
	)
	(segment
		(start 233.419396 -58.561986)
		(end 232.828846 -57.971436)
		(width 0.0889)
		(layer "F.Cu")
		(net "M_A_DQ<9>")
	)
	(segment
		(start 234.466638 -58.561986)
		(end 233.419396 -58.561986)
		(width 0.0889)
		(layer "F.Cu")
		(net "M_A_DQ<9>")
	)
	(segment
		(start 207.449928 -15.423642)
		(end 207.449928 -16.687546)
		(width 0.1651)
		(layer "F.Cu")
		(net "M_A_DQ<9>")
	)
	(segment
		(start 207.75041 -23.935182)
		(end 207.917796 -23.767796)
		(width 0.1651)
		(layer "F.Cu")
		(net "M_A_DQ<9>")
	)
	(segment
		(start 207.75041 -28.103576)
		(end 207.75041 -23.935182)
		(width 0.1651)
		(layer "F.Cu")
		(net "M_A_DQ<9>")
	)
	(segment
		(start 207.917796 -23.767796)
		(end 207.917796 -23.386796)
		(width 0.1651)
		(layer "F.Cu")
		(net "M_A_DQ<9>")
	)
	(segment
		(start 210.095338 -30.448504)
		(end 207.75041 -28.103576)
		(width 0.1651)
		(layer "F.Cu")
		(net "M_A_DQ<9>")
	)
	(segment
		(start 210.095338 -32.13227)
		(end 210.3628 -31.864808)
		(width 0.1651)
		(layer "F.Cu")
		(net "M_A_DQ<9>")
	)
	(segment
		(start 210.3628 -31.396432)
		(end 210.095338 -31.12897)
		(width 0.1651)
		(layer "F.Cu")
		(net "M_A_DQ<9>")
	)
	(via
		(at 208.122012 -22.279356)
		(size 0.508)
		(drill 0.254)
		(layers "F.Cu" "B.Cu")
		(net "M_A_DQ<9>")
	)
	(via
		(at 207.449928 -16.687546)
		(size 0.508)
		(drill 0.254)
		(layers "F.Cu" "B.Cu")
		(net "M_A_DQ<9>")
	)
	(segment
		(start 208.30032 -20.224242)
		(end 208.299812 -20.224242)
		(width 0.1651)
		(layer "B.Cu")
		(net "M_A_DQ<9>")
	)
	(segment
		(start 208.122012 -21.776182)
		(end 208.122012 -22.279356)
		(width 0.1651)
		(layer "B.Cu")
		(net "M_A_DQ<9>")
	)
	(segment
		(start 208.299812 -21.598382)
		(end 208.122012 -21.776182)
		(width 0.1651)
		(layer "B.Cu")
		(net "M_A_DQ<9>")
	)
	(segment
		(start 208.299812 -20.224242)
		(end 208.299812 -21.598382)
		(width 0.1651)
		(layer "B.Cu")
		(net "M_A_DQ<9>")
	)
	(segment
		(start 207.449928 -17.226534)
		(end 207.449928 -16.687546)
		(width 0.14224)
		(layer "In2.Cu")
		(net "M_A_DQ<9>")
	)
	(segment
		(start 208.282794 -17.7038)
		(end 207.927194 -17.7038)
		(width 0.14224)
		(layer "In2.Cu")
		(net "M_A_DQ<9>")
	)
	(segment
		(start 208.122012 -22.279356)
		(end 208.496154 -21.905214)
		(width 0.14224)
		(layer "In2.Cu")
		(net "M_A_DQ<9>")
	)
	(segment
		(start 208.496154 -18.571464)
		(end 208.652618 -18.415)
		(width 0.14224)
		(layer "In2.Cu")
		(net "M_A_DQ<9>")
	)
	(segment
		(start 208.652618 -18.073624)
		(end 208.282794 -17.7038)
		(width 0.14224)
		(layer "In2.Cu")
		(net "M_A_DQ<9>")
	)
	(segment
		(start 208.496154 -21.905214)
		(end 208.496154 -18.571464)
		(width 0.14224)
		(layer "In2.Cu")
		(net "M_A_DQ<9>")
	)
	(segment
		(start 208.652618 -18.415)
		(end 208.652618 -18.073624)
		(width 0.14224)
		(layer "In2.Cu")
		(net "M_A_DQ<9>")
	)
	(segment
		(start 207.927194 -17.7038)
		(end 207.449928 -17.226534)
		(width 0.14224)
		(layer "In2.Cu")
		(net "M_A_DQ<9>")
	)
	(segment
		(start 211.42198 -40.672766)
		(end 229.3112 -58.561986)
		(width 0.1651)
		(layer "F.Cu")
		(net "M_A_DQ<8>")
	)
	(segment
		(start 209.804 -37.484304)
		(end 209.804 -37.827204)
		(width 0.1651)
		(layer "F.Cu")
		(net "M_A_DQ<8>")
	)
	(segment
		(start 210.621626 -35.807904)
		(end 210.456526 -35.973004)
		(width 0.1651)
		(layer "F.Cu")
		(net "M_A_DQ<8>")
	)
	(segment
		(start 210.621626 -38.157404)
		(end 210.621626 -39.872412)
		(width 0.1651)
		(layer "F.Cu")
		(net "M_A_DQ<8>")
	)
	(segment
		(start 209.530696 -35.973004)
		(end 209.365596 -36.138104)
		(width 0.1651)
		(layer "F.Cu")
		(net "M_A_DQ<8>")
	)
	(segment
		(start 231.8004 -58.561986)
		(end 232.749598 -58.561986)
		(width 0.0889)
		(layer "F.Cu")
		(net "M_A_DQ<8>")
	)
	(segment
		(start 209.365596 -36.138104)
		(end 209.365596 -36.481004)
		(width 0.1651)
		(layer "F.Cu")
		(net "M_A_DQ<8>")
	)
	(segment
		(start 210.621626 -37.154104)
		(end 210.456526 -37.319204)
		(width 0.1651)
		(layer "F.Cu")
		(net "M_A_DQ<8>")
	)
	(segment
		(start 209.530696 -36.646104)
		(end 210.456526 -36.646104)
		(width 0.1651)
		(layer "F.Cu")
		(net "M_A_DQ<8>")
	)
	(segment
		(start 208.30032 -20.023582)
		(end 208.299812 -20.023582)
		(width 0.1651)
		(layer "F.Cu")
		(net "M_A_DQ<8>")
	)
	(segment
		(start 210.621626 -35.210242)
		(end 210.621626 -35.807904)
		(width 0.1651)
		(layer "F.Cu")
		(net "M_A_DQ<8>")
	)
	(segment
		(start 209.9691 -37.319204)
		(end 209.804 -37.484304)
		(width 0.1651)
		(layer "F.Cu")
		(net "M_A_DQ<8>")
	)
	(segment
		(start 210.456526 -37.319204)
		(end 209.9691 -37.319204)
		(width 0.1651)
		(layer "F.Cu")
		(net "M_A_DQ<8>")
	)
	(segment
		(start 210.621626 -36.811204)
		(end 210.621626 -37.154104)
		(width 0.1651)
		(layer "F.Cu")
		(net "M_A_DQ<8>")
	)
	(segment
		(start 229.3112 -58.561986)
		(end 231.8004 -58.561986)
		(width 0.1651)
		(layer "F.Cu")
		(net "M_A_DQ<8>")
	)
	(segment
		(start 209.37728 -33.965896)
		(end 210.621626 -35.210242)
		(width 0.1651)
		(layer "F.Cu")
		(net "M_A_DQ<8>")
	)
	(segment
		(start 209.9691 -37.992304)
		(end 210.456526 -37.992304)
		(width 0.1651)
		(layer "F.Cu")
		(net "M_A_DQ<8>")
	)
	(segment
		(start 208.21904 -19.177)
		(end 208.122012 -18.161)
		(width 0.1651)
		(layer "F.Cu")
		(net "M_A_DQ<8>")
	)
	(segment
		(start 207.058768 -28.368752)
		(end 209.37728 -30.687264)
		(width 0.1651)
		(layer "F.Cu")
		(net "M_A_DQ<8>")
	)
	(segment
		(start 207.058768 -23.951438)
		(end 207.058768 -28.368752)
		(width 0.1651)
		(layer "F.Cu")
		(net "M_A_DQ<8>")
	)
	(segment
		(start 208.299812 -20.023582)
		(end 208.21904 -19.177)
		(width 0.1651)
		(layer "F.Cu")
		(net "M_A_DQ<8>")
	)
	(segment
		(start 209.37728 -30.687264)
		(end 209.37728 -33.965896)
		(width 0.1651)
		(layer "F.Cu")
		(net "M_A_DQ<8>")
	)
	(segment
		(start 210.456526 -37.992304)
		(end 210.621626 -38.157404)
		(width 0.1651)
		(layer "F.Cu")
		(net "M_A_DQ<8>")
	)
	(segment
		(start 209.365596 -36.481004)
		(end 209.530696 -36.646104)
		(width 0.1651)
		(layer "F.Cu")
		(net "M_A_DQ<8>")
	)
	(segment
		(start 210.621626 -39.872412)
		(end 211.42198 -40.672766)
		(width 0.1651)
		(layer "F.Cu")
		(net "M_A_DQ<8>")
	)
	(segment
		(start 207.449928 -23.560278)
		(end 207.058768 -23.951438)
		(width 0.1651)
		(layer "F.Cu")
		(net "M_A_DQ<8>")
	)
	(segment
		(start 210.456526 -36.646104)
		(end 210.621626 -36.811204)
		(width 0.1651)
		(layer "F.Cu")
		(net "M_A_DQ<8>")
	)
	(segment
		(start 209.804 -37.827204)
		(end 209.9691 -37.992304)
		(width 0.1651)
		(layer "F.Cu")
		(net "M_A_DQ<8>")
	)
	(segment
		(start 210.456526 -35.973004)
		(end 209.530696 -35.973004)
		(width 0.1651)
		(layer "F.Cu")
		(net "M_A_DQ<8>")
	)
	(via
		(at 208.122012 -18.161)
		(size 0.508)
		(drill 0.254)
		(layers "F.Cu" "B.Cu")
		(net "M_A_DQ<8>")
	)
	(via
		(at 207.449928 -23.560278)
		(size 0.508)
		(drill 0.254)
		(layers "F.Cu" "B.Cu")
		(net "M_A_DQ<8>")
	)
	(via
		(at 211.42198 -40.672766)
		(size 0.508)
		(drill 0.254)
		(layers "F.Cu" "B.Cu")
		(net "M_A_DQ<8>")
	)
	(segment
		(start 207.449928 -24.824182)
		(end 207.449928 -23.560278)
		(width 0.1651)
		(layer "B.Cu")
		(net "M_A_DQ<8>")
	)
	(segment
		(start 207.450436 -24.824182)
		(end 207.449928 -24.824182)
		(width 0.1651)
		(layer "B.Cu")
		(net "M_A_DQ<8>")
	)
	(segment
		(start 207.165194 -23.275544)
		(end 207.165194 -22.5298)
		(width 0.14224)
		(layer "In2.Cu")
		(net "M_A_DQ<8>")
	)
	(segment
		(start 207.901794 -21.7932)
		(end 207.901794 -21.293328)
		(width 0.14224)
		(layer "In2.Cu")
		(net "M_A_DQ<8>")
	)
	(segment
		(start 207.449928 -23.560278)
		(end 207.165194 -23.275544)
		(width 0.14224)
		(layer "In2.Cu")
		(net "M_A_DQ<8>")
	)
	(segment
		(start 207.901794 -18.965672)
		(end 207.901794 -18.381218)
		(width 0.14224)
		(layer "In2.Cu")
		(net "M_A_DQ<8>")
	)
	(segment
		(start 207.487012 -19.380454)
		(end 207.901794 -18.965672)
		(width 0.14224)
		(layer "In2.Cu")
		(net "M_A_DQ<8>")
	)
	(segment
		(start 207.901794 -21.293328)
		(end 207.512412 -20.903946)
		(width 0.14224)
		(layer "In2.Cu")
		(net "M_A_DQ<8>")
	)
	(segment
		(start 207.829912 -20.0533)
		(end 207.487012 -19.7104)
		(width 0.14224)
		(layer "In2.Cu")
		(net "M_A_DQ<8>")
	)
	(segment
		(start 207.829912 -20.2819)
		(end 207.829912 -20.0533)
		(width 0.14224)
		(layer "In2.Cu")
		(net "M_A_DQ<8>")
	)
	(segment
		(start 207.512412 -20.903946)
		(end 207.512412 -20.5994)
		(width 0.14224)
		(layer "In2.Cu")
		(net "M_A_DQ<8>")
	)
	(segment
		(start 207.165194 -22.5298)
		(end 207.901794 -21.7932)
		(width 0.14224)
		(layer "In2.Cu")
		(net "M_A_DQ<8>")
	)
	(segment
		(start 207.487012 -19.7104)
		(end 207.487012 -19.380454)
		(width 0.14224)
		(layer "In2.Cu")
		(net "M_A_DQ<8>")
	)
	(segment
		(start 207.901794 -18.381218)
		(end 208.122012 -18.161)
		(width 0.14224)
		(layer "In2.Cu")
		(net "M_A_DQ<8>")
	)
	(segment
		(start 207.512412 -20.5994)
		(end 207.829912 -20.2819)
		(width 0.14224)
		(layer "In2.Cu")
		(net "M_A_DQ<8>")
	)
	(segment
		(start 202.349862 -15.423642)
		(end 202.349862 -16.687546)
		(width 0.1651)
		(layer "F.Cu")
		(net "M_A_DQ<7>")
	)
	(segment
		(start 234.466638 -62.52464)
		(end 233.895138 -62.52464)
		(width 0.1016)
		(layer "F.Cu")
		(net "M_A_DQ<7>")
	)
	(segment
		(start 202.35037 -15.423642)
		(end 202.349862 -15.423642)
		(width 0.1651)
		(layer "F.Cu")
		(net "M_A_DQ<7>")
	)
	(via
		(at 233.895138 -62.52464)
		(size 0.508)
		(drill 0.254)
		(layers "F.Cu" "B.Cu")
		(net "M_A_DQ<7>")
	)
	(via
		(at 203.199746 -22.279356)
		(size 0.508)
		(drill 0.254)
		(layers "F.Cu" "B.Cu")
		(net "M_A_DQ<7>")
	)
	(via
		(at 202.349862 -16.687546)
		(size 0.508)
		(drill 0.254)
		(layers "F.Cu" "B.Cu")
		(net "M_A_DQ<7>")
	)
	(segment
		(start 203.200508 -22.278594)
		(end 203.199746 -22.279356)
		(width 0.1651)
		(layer "B.Cu")
		(net "M_A_DQ<7>")
	)
	(segment
		(start 203.200508 -20.224242)
		(end 203.200508 -22.278594)
		(width 0.1651)
		(layer "B.Cu")
		(net "M_A_DQ<7>")
	)
	(segment
		(start 202.984862 -23.397718)
		(end 202.740768 -23.153624)
		(width 0.14224)
		(layer "In2.Cu")
		(net "M_A_DQ<7>")
	)
	(segment
		(start 202.984862 -28.4734)
		(end 202.984862 -23.397718)
		(width 0.14224)
		(layer "In2.Cu")
		(net "M_A_DQ<7>")
	)
	(segment
		(start 205.636368 -38.265862)
		(end 205.636368 -33.170368)
		(width 0.14224)
		(layer "In2.Cu")
		(net "M_A_DQ<7>")
	)
	(segment
		(start 231.03586 -62.270386)
		(end 230.632 -62.270386)
		(width 0.0889)
		(layer "In2.Cu")
		(net "M_A_DQ<7>")
	)
	(segment
		(start 232.356914 -62.041024)
		(end 231.265222 -62.041024)
		(width 0.0889)
		(layer "In2.Cu")
		(net "M_A_DQ<7>")
	)
	(segment
		(start 202.740768 -22.738334)
		(end 203.199746 -22.279356)
		(width 0.14224)
		(layer "In2.Cu")
		(net "M_A_DQ<7>")
	)
	(segment
		(start 203.492862 -28.6766)
		(end 203.188062 -28.6766)
		(width 0.14224)
		(layer "In2.Cu")
		(net "M_A_DQ<7>")
	)
	(segment
		(start 202.9968 -17.653)
		(end 202.6666 -17.3228)
		(width 0.14224)
		(layer "In2.Cu")
		(net "M_A_DQ<7>")
	)
	(segment
		(start 203.696062 -28.4734)
		(end 203.492862 -28.6766)
		(width 0.14224)
		(layer "In2.Cu")
		(net "M_A_DQ<7>")
	)
	(segment
		(start 203.2508 -17.653)
		(end 202.9968 -17.653)
		(width 0.14224)
		(layer "In2.Cu")
		(net "M_A_DQ<7>")
	)
	(segment
		(start 202.6666 -17.004284)
		(end 202.349862 -16.687546)
		(width 0.14224)
		(layer "In2.Cu")
		(net "M_A_DQ<7>")
	)
	(segment
		(start 203.899262 -25.4254)
		(end 203.696062 -25.6286)
		(width 0.14224)
		(layer "In2.Cu")
		(net "M_A_DQ<7>")
	)
	(segment
		(start 204.493368 -32.027368)
		(end 204.493368 -25.714706)
		(width 0.14224)
		(layer "In2.Cu")
		(net "M_A_DQ<7>")
	)
	(segment
		(start 203.552552 -21.92655)
		(end 203.552552 -18.621248)
		(width 0.14224)
		(layer "In2.Cu")
		(net "M_A_DQ<7>")
	)
	(segment
		(start 205.636368 -33.170368)
		(end 204.493368 -32.027368)
		(width 0.14224)
		(layer "In2.Cu")
		(net "M_A_DQ<7>")
	)
	(segment
		(start 204.204062 -25.4254)
		(end 203.899262 -25.4254)
		(width 0.14224)
		(layer "In2.Cu")
		(net "M_A_DQ<7>")
	)
	(segment
		(start 204.493368 -25.714706)
		(end 204.204062 -25.4254)
		(width 0.14224)
		(layer "In2.Cu")
		(net "M_A_DQ<7>")
	)
	(segment
		(start 203.696062 -25.6286)
		(end 203.696062 -28.4734)
		(width 0.14224)
		(layer "In2.Cu")
		(net "M_A_DQ<7>")
	)
	(segment
		(start 202.740768 -23.153624)
		(end 202.740768 -22.738334)
		(width 0.14224)
		(layer "In2.Cu")
		(net "M_A_DQ<7>")
	)
	(segment
		(start 203.188062 -28.6766)
		(end 202.984862 -28.4734)
		(width 0.14224)
		(layer "In2.Cu")
		(net "M_A_DQ<7>")
	)
	(segment
		(start 231.265222 -62.041024)
		(end 231.03586 -62.270386)
		(width 0.0889)
		(layer "In2.Cu")
		(net "M_A_DQ<7>")
	)
	(segment
		(start 203.708 -18.1102)
		(end 203.2508 -17.653)
		(width 0.14224)
		(layer "In2.Cu")
		(net "M_A_DQ<7>")
	)
	(segment
		(start 202.6666 -17.3228)
		(end 202.6666 -17.004284)
		(width 0.14224)
		(layer "In2.Cu")
		(net "M_A_DQ<7>")
	)
	(segment
		(start 203.708 -18.4658)
		(end 203.708 -18.1102)
		(width 0.14224)
		(layer "In2.Cu")
		(net "M_A_DQ<7>")
	)
	(segment
		(start 230.632 -62.270386)
		(end 229.640892 -62.270386)
		(width 0.14224)
		(layer "In2.Cu")
		(net "M_A_DQ<7>")
	)
	(segment
		(start 233.895138 -62.52464)
		(end 232.84053 -62.52464)
		(width 0.0889)
		(layer "In2.Cu")
		(net "M_A_DQ<7>")
	)
	(segment
		(start 232.84053 -62.52464)
		(end 232.356914 -62.041024)
		(width 0.0889)
		(layer "In2.Cu")
		(net "M_A_DQ<7>")
	)
	(segment
		(start 229.640892 -62.270386)
		(end 205.636368 -38.265862)
		(width 0.14224)
		(layer "In2.Cu")
		(net "M_A_DQ<7>")
	)
	(segment
		(start 203.552552 -18.621248)
		(end 203.708 -18.4658)
		(width 0.14224)
		(layer "In2.Cu")
		(net "M_A_DQ<7>")
	)
	(segment
		(start 203.199746 -22.279356)
		(end 203.552552 -21.92655)
		(width 0.14224)
		(layer "In2.Cu")
		(net "M_A_DQ<7>")
	)
	(segment
		(start 203.2 -19.05)
		(end 203.33208 -18.91792)
		(width 0.1651)
		(layer "F.Cu")
		(net "M_A_DQ<6>")
	)
	(segment
		(start 203.33208 -18.69948)
		(end 203.2 -18.5674)
		(width 0.1651)
		(layer "F.Cu")
		(net "M_A_DQ<6>")
	)
	(segment
		(start 232.749598 -62.52464)
		(end 232.101898 -62.52464)
		(width 0.1016)
		(layer "F.Cu")
		(net "M_A_DQ<6>")
	)
	(segment
		(start 203.2 -18.5674)
		(end 203.2 -18.262854)
		(width 0.1651)
		(layer "F.Cu")
		(net "M_A_DQ<6>")
	)
	(segment
		(start 203.2 -18.262854)
		(end 203.199746 -18.2626)
		(width 0.1651)
		(layer "F.Cu")
		(net "M_A_DQ<6>")
	)
	(segment
		(start 203.33208 -18.91792)
		(end 203.33208 -18.69948)
		(width 0.1651)
		(layer "F.Cu")
		(net "M_A_DQ<6>")
	)
	(segment
		(start 203.200508 -20.023582)
		(end 203.2 -20.023582)
		(width 0.1651)
		(layer "F.Cu")
		(net "M_A_DQ<6>")
	)
	(segment
		(start 203.2 -20.023582)
		(end 203.2 -19.05)
		(width 0.1651)
		(layer "F.Cu")
		(net "M_A_DQ<6>")
	)
	(via
		(at 203.199746 -18.2626)
		(size 0.508)
		(drill 0.254)
		(layers "F.Cu" "B.Cu")
		(net "M_A_DQ<6>")
	)
	(via
		(at 232.101898 -62.52464)
		(size 0.508)
		(drill 0.254)
		(layers "F.Cu" "B.Cu")
		(net "M_A_DQ<6>")
	)
	(via
		(at 202.349862 -23.560278)
		(size 0.508)
		(drill 0.254)
		(layers "F.Cu" "B.Cu")
		(net "M_A_DQ<6>")
	)
	(segment
		(start 202.35037 -24.824182)
		(end 202.349862 -24.824182)
		(width 0.1651)
		(layer "B.Cu")
		(net "M_A_DQ<6>")
	)
	(segment
		(start 202.349862 -24.824182)
		(end 202.349862 -23.560278)
		(width 0.1651)
		(layer "B.Cu")
		(net "M_A_DQ<6>")
	)
	(segment
		(start 230.632 -62.905386)
		(end 231.086406 -62.905386)
		(width 0.0889)
		(layer "In2.Cu")
		(net "M_A_DQ<6>")
	)
	(segment
		(start 202.461368 -19.278854)
		(end 202.461368 -19.589496)
		(width 0.14224)
		(layer "In2.Cu")
		(net "M_A_DQ<6>")
	)
	(segment
		(start 202.886818 -21.405596)
		(end 202.886818 -21.757386)
		(width 0.14224)
		(layer "In2.Cu")
		(net "M_A_DQ<6>")
	)
	(segment
		(start 202.82535 -18.636996)
		(end 202.82535 -18.914872)
		(width 0.14224)
		(layer "In2.Cu")
		(net "M_A_DQ<6>")
	)
	(segment
		(start 231.467152 -62.52464)
		(end 232.101898 -62.52464)
		(width 0.0889)
		(layer "In2.Cu")
		(net "M_A_DQ<6>")
	)
	(segment
		(start 203.199746 -18.2626)
		(end 202.82535 -18.636996)
		(width 0.14224)
		(layer "In2.Cu")
		(net "M_A_DQ<6>")
	)
	(segment
		(start 203.772262 -32.246062)
		(end 204.925168 -33.398968)
		(width 0.14224)
		(layer "In2.Cu")
		(net "M_A_DQ<6>")
	)
	(segment
		(start 203.061062 -33.3756)
		(end 203.061062 -29.5656)
		(width 0.14224)
		(layer "In2.Cu")
		(net "M_A_DQ<6>")
	)
	(segment
		(start 204.925168 -33.398968)
		(end 204.925168 -35.968432)
		(width 0.14224)
		(layer "In2.Cu")
		(net "M_A_DQ<6>")
	)
	(segment
		(start 231.086406 -62.905386)
		(end 231.467152 -62.52464)
		(width 0.0889)
		(layer "In2.Cu")
		(net "M_A_DQ<6>")
	)
	(segment
		(start 203.569062 -29.3624)
		(end 203.772262 -29.5656)
		(width 0.14224)
		(layer "In2.Cu")
		(net "M_A_DQ<6>")
	)
	(segment
		(start 204.3176 -37.0078)
		(end 204.925168 -37.615368)
		(width 0.14224)
		(layer "In2.Cu")
		(net "M_A_DQ<6>")
	)
	(segment
		(start 202.11415 -22.530054)
		(end 202.11415 -23.324566)
		(width 0.14224)
		(layer "In2.Cu")
		(net "M_A_DQ<6>")
	)
	(segment
		(start 204.925168 -35.968432)
		(end 204.3176 -36.576)
		(width 0.14224)
		(layer "In2.Cu")
		(net "M_A_DQ<6>")
	)
	(segment
		(start 202.461368 -19.589496)
		(end 202.842368 -19.970496)
		(width 0.14224)
		(layer "In2.Cu")
		(net "M_A_DQ<6>")
	)
	(segment
		(start 204.3176 -36.576)
		(end 204.3176 -37.0078)
		(width 0.14224)
		(layer "In2.Cu")
		(net "M_A_DQ<6>")
	)
	(segment
		(start 202.857862 -33.5788)
		(end 203.061062 -33.3756)
		(width 0.14224)
		(layer "In2.Cu")
		(net "M_A_DQ<6>")
	)
	(segment
		(start 202.886818 -21.757386)
		(end 202.11415 -22.530054)
		(width 0.14224)
		(layer "In2.Cu")
		(net "M_A_DQ<6>")
	)
	(segment
		(start 202.349862 -23.560278)
		(end 202.349862 -33.3756)
		(width 0.14224)
		(layer "In2.Cu")
		(net "M_A_DQ<6>")
	)
	(segment
		(start 204.925168 -38.452806)
		(end 229.377748 -62.905386)
		(width 0.14224)
		(layer "In2.Cu")
		(net "M_A_DQ<6>")
	)
	(segment
		(start 202.11415 -23.324566)
		(end 202.349862 -23.560278)
		(width 0.14224)
		(layer "In2.Cu")
		(net "M_A_DQ<6>")
	)
	(segment
		(start 203.772262 -29.5656)
		(end 203.772262 -32.246062)
		(width 0.14224)
		(layer "In2.Cu")
		(net "M_A_DQ<6>")
	)
	(segment
		(start 203.264262 -29.3624)
		(end 203.569062 -29.3624)
		(width 0.14224)
		(layer "In2.Cu")
		(net "M_A_DQ<6>")
	)
	(segment
		(start 229.377748 -62.905386)
		(end 230.632 -62.905386)
		(width 0.14224)
		(layer "In2.Cu")
		(net "M_A_DQ<6>")
	)
	(segment
		(start 202.842368 -19.970496)
		(end 202.842368 -20.313904)
		(width 0.14224)
		(layer "In2.Cu")
		(net "M_A_DQ<6>")
	)
	(segment
		(start 202.461368 -20.694904)
		(end 202.461368 -20.980146)
		(width 0.14224)
		(layer "In2.Cu")
		(net "M_A_DQ<6>")
	)
	(segment
		(start 204.925168 -37.615368)
		(end 204.925168 -38.452806)
		(width 0.14224)
		(layer "In2.Cu")
		(net "M_A_DQ<6>")
	)
	(segment
		(start 202.461368 -20.980146)
		(end 202.886818 -21.405596)
		(width 0.14224)
		(layer "In2.Cu")
		(net "M_A_DQ<6>")
	)
	(segment
		(start 202.553062 -33.5788)
		(end 202.857862 -33.5788)
		(width 0.14224)
		(layer "In2.Cu")
		(net "M_A_DQ<6>")
	)
	(segment
		(start 202.349862 -33.3756)
		(end 202.553062 -33.5788)
		(width 0.14224)
		(layer "In2.Cu")
		(net "M_A_DQ<6>")
	)
	(segment
		(start 202.842368 -20.313904)
		(end 202.461368 -20.694904)
		(width 0.14224)
		(layer "In2.Cu")
		(net "M_A_DQ<6>")
	)
	(segment
		(start 202.82535 -18.914872)
		(end 202.461368 -19.278854)
		(width 0.14224)
		(layer "In2.Cu")
		(net "M_A_DQ<6>")
	)
	(segment
		(start 203.061062 -29.5656)
		(end 203.264262 -29.3624)
		(width 0.14224)
		(layer "In2.Cu")
		(net "M_A_DQ<6>")
	)
	(segment
		(start 313.700414 -15.423642)
		(end 313.700414 -16.687038)
		(width 0.1651)
		(layer "F.Cu")
		(net "M_A_DQ<63>")
	)
	(segment
		(start 313.700414 -16.687038)
		(end 313.699906 -16.687546)
		(width 0.1651)
		(layer "F.Cu")
		(net "M_A_DQ<63>")
	)
	(segment
		(start 287.79216 -55.904384)
		(end 288.36366 -55.904384)
		(width 0.1651)
		(layer "F.Cu")
		(net "M_A_DQ<63>")
	)
	(via
		(at 287.79216 -55.904384)
		(size 0.508)
		(drill 0.254)
		(layers "F.Cu" "B.Cu")
		(net "M_A_DQ<63>")
	)
	(via
		(at 314.54979 -22.279356)
		(size 0.508)
		(drill 0.254)
		(layers "F.Cu" "B.Cu")
		(net "M_A_DQ<63>")
	)
	(via
		(at 313.699906 -16.687546)
		(size 0.508)
		(drill 0.254)
		(layers "F.Cu" "B.Cu")
		(net "M_A_DQ<63>")
	)
	(segment
		(start 314.550298 -22.278848)
		(end 314.54979 -22.279356)
		(width 0.1651)
		(layer "B.Cu")
		(net "M_A_DQ<63>")
	)
	(segment
		(start 314.550298 -20.224242)
		(end 314.550298 -22.278848)
		(width 0.1651)
		(layer "B.Cu")
		(net "M_A_DQ<63>")
	)
	(segment
		(start 313.9186 -34.34842)
		(end 313.9186 -38.061392)
		(width 0.14224)
		(layer "In2.Cu")
		(net "M_A_DQ<63>")
	)
	(segment
		(start 314.1218 -34.14522)
		(end 313.9186 -34.34842)
		(width 0.14224)
		(layer "In2.Cu")
		(net "M_A_DQ<63>")
	)
	(segment
		(start 313.9186 -32.72282)
		(end 313.9186 -33.12922)
		(width 0.14224)
		(layer "In2.Cu")
		(net "M_A_DQ<63>")
	)
	(segment
		(start 288.651188 -55.99938)
		(end 288.65068 -55.999888)
		(width 0.0889)
		(layer "In2.Cu")
		(net "M_A_DQ<63>")
	)
	(segment
		(start 314.551568 -32.51962)
		(end 314.1218 -32.51962)
		(width 0.14224)
		(layer "In2.Cu")
		(net "M_A_DQ<63>")
	)
	(segment
		(start 291.338 -51.7906)
		(end 291.106352 -51.7906)
		(width 0.0889)
		(layer "In2.Cu")
		(net "M_A_DQ<63>")
	)
	(segment
		(start 308.908704 -40.493696)
		(end 302.133 -47.2694)
		(width 0.14224)
		(layer "In2.Cu")
		(net "M_A_DQ<63>")
	)
	(segment
		(start 313.9186 -33.12922)
		(end 314.1218 -33.33242)
		(width 0.14224)
		(layer "In2.Cu")
		(net "M_A_DQ<63>")
	)
	(segment
		(start 314.600844 -17.653)
		(end 315.058044 -18.1102)
		(width 0.14224)
		(layer "In2.Cu")
		(net "M_A_DQ<63>")
	)
	(segment
		(start 315.058044 -18.1102)
		(end 315.058044 -18.4658)
		(width 0.14224)
		(layer "In2.Cu")
		(net "M_A_DQ<63>")
	)
	(segment
		(start 313.699906 -17.006062)
		(end 314.346844 -17.653)
		(width 0.14224)
		(layer "In2.Cu")
		(net "M_A_DQ<63>")
	)
	(segment
		(start 289.254184 -53.642768)
		(end 289.254184 -55.646574)
		(width 0.0889)
		(layer "In2.Cu")
		(net "M_A_DQ<63>")
	)
	(segment
		(start 314.1218 -32.51962)
		(end 313.9186 -32.72282)
		(width 0.14224)
		(layer "In2.Cu")
		(net "M_A_DQ<63>")
	)
	(segment
		(start 287.79216 -55.56631)
		(end 287.79216 -55.904384)
		(width 0.0889)
		(layer "In2.Cu")
		(net "M_A_DQ<63>")
	)
	(segment
		(start 314.064396 -22.76475)
		(end 314.064396 -23.1267)
		(width 0.14224)
		(layer "In2.Cu")
		(net "M_A_DQ<63>")
	)
	(segment
		(start 314.346844 -17.653)
		(end 314.600844 -17.653)
		(width 0.14224)
		(layer "In2.Cu")
		(net "M_A_DQ<63>")
	)
	(segment
		(start 314.1218 -33.33242)
		(end 314.551568 -33.33242)
		(width 0.14224)
		(layer "In2.Cu")
		(net "M_A_DQ<63>")
	)
	(segment
		(start 314.902596 -21.92655)
		(end 314.54979 -22.279356)
		(width 0.14224)
		(layer "In2.Cu")
		(net "M_A_DQ<63>")
	)
	(segment
		(start 314.551568 -34.14522)
		(end 314.1218 -34.14522)
		(width 0.14224)
		(layer "In2.Cu")
		(net "M_A_DQ<63>")
	)
	(segment
		(start 313.9186 -38.061392)
		(end 311.486296 -40.493696)
		(width 0.14224)
		(layer "In2.Cu")
		(net "M_A_DQ<63>")
	)
	(segment
		(start 311.486296 -40.493696)
		(end 308.908704 -40.493696)
		(width 0.14224)
		(layer "In2.Cu")
		(net "M_A_DQ<63>")
	)
	(segment
		(start 315.058044 -18.4658)
		(end 314.902596 -18.621248)
		(width 0.14224)
		(layer "In2.Cu")
		(net "M_A_DQ<63>")
	)
	(segment
		(start 314.064396 -23.1267)
		(end 314.754768 -23.817072)
		(width 0.14224)
		(layer "In2.Cu")
		(net "M_A_DQ<63>")
	)
	(segment
		(start 291.106352 -51.7906)
		(end 289.254184 -53.642768)
		(width 0.0889)
		(layer "In2.Cu")
		(net "M_A_DQ<63>")
	)
	(segment
		(start 314.754768 -23.817072)
		(end 314.754768 -32.31642)
		(width 0.14224)
		(layer "In2.Cu")
		(net "M_A_DQ<63>")
	)
	(segment
		(start 294.559736 -48.568864)
		(end 291.338 -51.7906)
		(width 0.14224)
		(layer "In2.Cu")
		(net "M_A_DQ<63>")
	)
	(segment
		(start 288.901378 -55.99938)
		(end 288.651188 -55.99938)
		(width 0.0889)
		(layer "In2.Cu")
		(net "M_A_DQ<63>")
	)
	(segment
		(start 302.133 -47.2694)
		(end 297.4848 -47.2694)
		(width 0.14224)
		(layer "In2.Cu")
		(net "M_A_DQ<63>")
	)
	(segment
		(start 289.254184 -55.646574)
		(end 288.901378 -55.99938)
		(width 0.0889)
		(layer "In2.Cu")
		(net "M_A_DQ<63>")
	)
	(segment
		(start 313.699906 -16.687546)
		(end 313.699906 -17.006062)
		(width 0.14224)
		(layer "In2.Cu")
		(net "M_A_DQ<63>")
	)
	(segment
		(start 314.754768 -32.31642)
		(end 314.551568 -32.51962)
		(width 0.14224)
		(layer "In2.Cu")
		(net "M_A_DQ<63>")
	)
	(segment
		(start 296.185336 -48.568864)
		(end 294.559736 -48.568864)
		(width 0.14224)
		(layer "In2.Cu")
		(net "M_A_DQ<63>")
	)
	(segment
		(start 314.902596 -18.621248)
		(end 314.902596 -21.92655)
		(width 0.14224)
		(layer "In2.Cu")
		(net "M_A_DQ<63>")
	)
	(segment
		(start 297.4848 -47.2694)
		(end 296.185336 -48.568864)
		(width 0.14224)
		(layer "In2.Cu")
		(net "M_A_DQ<63>")
	)
	(segment
		(start 314.706 -33.990788)
		(end 314.551568 -34.14522)
		(width 0.14224)
		(layer "In2.Cu")
		(net "M_A_DQ<63>")
	)
	(segment
		(start 314.551568 -33.33242)
		(end 314.706 -33.486852)
		(width 0.14224)
		(layer "In2.Cu")
		(net "M_A_DQ<63>")
	)
	(segment
		(start 314.54979 -22.279356)
		(end 314.064396 -22.76475)
		(width 0.14224)
		(layer "In2.Cu")
		(net "M_A_DQ<63>")
	)
	(segment
		(start 287.850072 -55.508398)
		(end 287.79216 -55.56631)
		(width 0.0889)
		(layer "In2.Cu")
		(net "M_A_DQ<63>")
	)
	(segment
		(start 288.65068 -55.999888)
		(end 288.6329 -55.999888)
		(width 0.0889)
		(layer "In2.Cu")
		(net "M_A_DQ<63>")
	)
	(segment
		(start 314.706 -33.486852)
		(end 314.706 -33.990788)
		(width 0.14224)
		(layer "In2.Cu")
		(net "M_A_DQ<63>")
	)
	(arc
		(start 288.6329 -55.999888)
		(mid 288.347476 -55.916421)
		(end 288.13887 -55.704486)
		(width 0.0889)
		(layer "In2.Cu")
		(net "M_A_DQ<63>")
	)
	(arc
		(start 288.13887 -55.704486)
		(mid 288.117446 -55.671359)
		(end 288.092896 -55.640478)
		(width 0.0889)
		(layer "In2.Cu")
		(net "M_A_DQ<63>")
	)
	(arc
		(start 288.092896 -55.640478)
		(mid 287.983237 -55.552847)
		(end 287.850072 -55.508398)
		(width 0.0889)
		(layer "In2.Cu")
		(net "M_A_DQ<63>")
	)
	(segment
		(start 314.682124 -18.69948)
		(end 314.682124 -18.91792)
		(width 0.1651)
		(layer "F.Cu")
		(net "M_A_DQ<62>")
	)
	(segment
		(start 314.550044 -18.5674)
		(end 314.682124 -18.69948)
		(width 0.1651)
		(layer "F.Cu")
		(net "M_A_DQ<62>")
	)
	(segment
		(start 314.550044 -20.023328)
		(end 314.550298 -20.023582)
		(width 0.1651)
		(layer "F.Cu")
		(net "M_A_DQ<62>")
	)
	(segment
		(start 314.550044 -18.262854)
		(end 314.550044 -18.5674)
		(width 0.1651)
		(layer "F.Cu")
		(net "M_A_DQ<62>")
	)
	(segment
		(start 314.550044 -19.05)
		(end 314.550044 -20.023328)
		(width 0.1651)
		(layer "F.Cu")
		(net "M_A_DQ<62>")
	)
	(segment
		(start 314.682124 -18.91792)
		(end 314.550044 -19.05)
		(width 0.1651)
		(layer "F.Cu")
		(net "M_A_DQ<62>")
	)
	(segment
		(start 287.79216 -54.913784)
		(end 288.36366 -54.913784)
		(width 0.1651)
		(layer "F.Cu")
		(net "M_A_DQ<62>")
	)
	(segment
		(start 314.54979 -18.2626)
		(end 314.550044 -18.262854)
		(width 0.1651)
		(layer "F.Cu")
		(net "M_A_DQ<62>")
	)
	(via
		(at 287.79216 -54.913784)
		(size 0.508)
		(drill 0.254)
		(layers "F.Cu" "B.Cu")
		(net "M_A_DQ<62>")
	)
	(via
		(at 314.54979 -18.2626)
		(size 0.508)
		(drill 0.254)
		(layers "F.Cu" "B.Cu")
		(net "M_A_DQ<62>")
	)
	(via
		(at 313.699906 -23.560278)
		(size 0.508)
		(drill 0.254)
		(layers "F.Cu" "B.Cu")
		(net "M_A_DQ<62>")
	)
	(segment
		(start 313.699906 -24.824182)
		(end 313.699906 -23.560278)
		(width 0.1651)
		(layer "B.Cu")
		(net "M_A_DQ<62>")
	)
	(segment
		(start 313.700414 -24.824182)
		(end 313.699906 -24.824182)
		(width 0.1651)
		(layer "B.Cu")
		(net "M_A_DQ<62>")
	)
	(segment
		(start 313.464194 -23.324566)
		(end 313.464194 -22.530054)
		(width 0.14224)
		(layer "In2.Cu")
		(net "M_A_DQ<62>")
	)
	(segment
		(start 313.811412 -19.589496)
		(end 313.811412 -19.278854)
		(width 0.14224)
		(layer "In2.Cu")
		(net "M_A_DQ<62>")
	)
	(segment
		(start 313.459368 -26.202386)
		(end 313.459368 -25.618186)
		(width 0.14224)
		(layer "In2.Cu")
		(net "M_A_DQ<62>")
	)
	(segment
		(start 295.6814 -47.9044)
		(end 296.9514 -46.6344)
		(width 0.14224)
		(layer "In2.Cu")
		(net "M_A_DQ<62>")
	)
	(segment
		(start 294.513 -47.9044)
		(end 295.6814 -47.9044)
		(width 0.14224)
		(layer "In2.Cu")
		(net "M_A_DQ<62>")
	)
	(segment
		(start 313.8932 -28.668218)
		(end 314.0964 -28.465018)
		(width 0.14224)
		(layer "In2.Cu")
		(net "M_A_DQ<62>")
	)
	(segment
		(start 313.2836 -27.243786)
		(end 313.4868 -27.040586)
		(width 0.14224)
		(layer "In2.Cu")
		(net "M_A_DQ<62>")
	)
	(segment
		(start 313.459368 -24.398986)
		(end 313.459368 -24.081232)
		(width 0.14224)
		(layer "In2.Cu")
		(net "M_A_DQ<62>")
	)
	(segment
		(start 314.0964 -29.684218)
		(end 313.8932 -29.481018)
		(width 0.14224)
		(layer "In2.Cu")
		(net "M_A_DQ<62>")
	)
	(segment
		(start 313.891168 -27.040586)
		(end 314.094368 -26.837386)
		(width 0.14224)
		(layer "In2.Cu")
		(net "M_A_DQ<62>")
	)
	(segment
		(start 313.4868 -27.040586)
		(end 313.891168 -27.040586)
		(width 0.14224)
		(layer "In2.Cu")
		(net "M_A_DQ<62>")
	)
	(segment
		(start 313.4868 -27.855418)
		(end 313.2836 -27.652218)
		(width 0.14224)
		(layer "In2.Cu")
		(net "M_A_DQ<62>")
	)
	(segment
		(start 313.2836 -30.497018)
		(end 313.4868 -30.293818)
		(width 0.14224)
		(layer "In2.Cu")
		(net "M_A_DQ<62>")
	)
	(segment
		(start 314.094368 -26.837386)
		(end 314.094368 -26.608786)
		(width 0.14224)
		(layer "In2.Cu")
		(net "M_A_DQ<62>")
	)
	(segment
		(start 289.063684 -53.563774)
		(end 290.8808 -51.746658)
		(width 0.0889)
		(layer "In2.Cu")
		(net "M_A_DQ<62>")
	)
	(segment
		(start 313.4868 -28.668218)
		(end 313.8932 -28.668218)
		(width 0.14224)
		(layer "In2.Cu")
		(net "M_A_DQ<62>")
	)
	(segment
		(start 314.0964 -30.090618)
		(end 314.0964 -29.684218)
		(width 0.14224)
		(layer "In2.Cu")
		(net "M_A_DQ<62>")
	)
	(segment
		(start 314.094368 -24.805386)
		(end 313.891168 -24.602186)
		(width 0.14224)
		(layer "In2.Cu")
		(net "M_A_DQ<62>")
	)
	(segment
		(start 313.2836 -27.652218)
		(end 313.2836 -27.243786)
		(width 0.14224)
		(layer "In2.Cu")
		(net "M_A_DQ<62>")
	)
	(segment
		(start 287.79216 -55.251858)
		(end 287.857438 -55.317136)
		(width 0.0889)
		(layer "In2.Cu")
		(net "M_A_DQ<62>")
	)
	(segment
		(start 311.436004 -39.515796)
		(end 313.2836 -37.6682)
		(width 0.14224)
		(layer "In2.Cu")
		(net "M_A_DQ<62>")
	)
	(segment
		(start 313.662568 -24.602186)
		(end 313.459368 -24.398986)
		(width 0.14224)
		(layer "In2.Cu")
		(net "M_A_DQ<62>")
	)
	(segment
		(start 314.175394 -18.914872)
		(end 314.175394 -18.636996)
		(width 0.14224)
		(layer "In2.Cu")
		(net "M_A_DQ<62>")
	)
	(segment
		(start 290.8808 -51.5366)
		(end 294.513 -47.9044)
		(width 0.14224)
		(layer "In2.Cu")
		(net "M_A_DQ<62>")
	)
	(segment
		(start 313.2836 -29.277818)
		(end 313.2836 -28.871418)
		(width 0.14224)
		(layer "In2.Cu")
		(net "M_A_DQ<62>")
	)
	(segment
		(start 314.175394 -18.636996)
		(end 314.54979 -18.2626)
		(width 0.14224)
		(layer "In2.Cu")
		(net "M_A_DQ<62>")
	)
	(segment
		(start 301.7774 -46.6344)
		(end 308.896004 -39.515796)
		(width 0.14224)
		(layer "In2.Cu")
		(net "M_A_DQ<62>")
	)
	(segment
		(start 290.8808 -51.746658)
		(end 290.8808 -51.5366)
		(width 0.0889)
		(layer "In2.Cu")
		(net "M_A_DQ<62>")
	)
	(segment
		(start 287.79216 -54.913784)
		(end 287.79216 -55.251858)
		(width 0.0889)
		(layer "In2.Cu")
		(net "M_A_DQ<62>")
	)
	(segment
		(start 313.699906 -23.840694)
		(end 313.699906 -23.560278)
		(width 0.14224)
		(layer "In2.Cu")
		(net "M_A_DQ<62>")
	)
	(segment
		(start 296.9514 -46.6344)
		(end 301.7774 -46.6344)
		(width 0.14224)
		(layer "In2.Cu")
		(net "M_A_DQ<62>")
	)
	(segment
		(start 313.4868 -29.481018)
		(end 313.2836 -29.277818)
		(width 0.14224)
		(layer "In2.Cu")
		(net "M_A_DQ<62>")
	)
	(segment
		(start 289.063684 -55.567834)
		(end 289.063684 -53.563774)
		(width 0.0889)
		(layer "In2.Cu")
		(net "M_A_DQ<62>")
	)
	(segment
		(start 308.896004 -39.515796)
		(end 311.436004 -39.515796)
		(width 0.14224)
		(layer "In2.Cu")
		(net "M_A_DQ<62>")
	)
	(segment
		(start 313.464194 -22.530054)
		(end 314.236862 -21.757386)
		(width 0.14224)
		(layer "In2.Cu")
		(net "M_A_DQ<62>")
	)
	(segment
		(start 314.094368 -26.608786)
		(end 313.916568 -26.430986)
		(width 0.14224)
		(layer "In2.Cu")
		(net "M_A_DQ<62>")
	)
	(segment
		(start 313.4868 -30.293818)
		(end 313.8932 -30.293818)
		(width 0.14224)
		(layer "In2.Cu")
		(net "M_A_DQ<62>")
	)
	(segment
		(start 313.699906 -23.560278)
		(end 313.464194 -23.324566)
		(width 0.14224)
		(layer "In2.Cu")
		(net "M_A_DQ<62>")
	)
	(segment
		(start 313.811412 -20.980146)
		(end 313.811412 -20.694904)
		(width 0.14224)
		(layer "In2.Cu")
		(net "M_A_DQ<62>")
	)
	(segment
		(start 313.811412 -19.278854)
		(end 314.175394 -18.914872)
		(width 0.14224)
		(layer "In2.Cu")
		(net "M_A_DQ<62>")
	)
	(segment
		(start 314.0964 -28.058618)
		(end 313.8932 -27.855418)
		(width 0.14224)
		(layer "In2.Cu")
		(net "M_A_DQ<62>")
	)
	(segment
		(start 313.916568 -26.430986)
		(end 313.687968 -26.430986)
		(width 0.14224)
		(layer "In2.Cu")
		(net "M_A_DQ<62>")
	)
	(segment
		(start 314.236862 -21.405596)
		(end 313.811412 -20.980146)
		(width 0.14224)
		(layer "In2.Cu")
		(net "M_A_DQ<62>")
	)
	(segment
		(start 314.094368 -25.1968)
		(end 314.094368 -24.805386)
		(width 0.14224)
		(layer "In2.Cu")
		(net "M_A_DQ<62>")
	)
	(segment
		(start 313.891168 -25.4)
		(end 314.094368 -25.1968)
		(width 0.14224)
		(layer "In2.Cu")
		(net "M_A_DQ<62>")
	)
	(segment
		(start 313.687968 -26.430986)
		(end 313.459368 -26.202386)
		(width 0.14224)
		(layer "In2.Cu")
		(net "M_A_DQ<62>")
	)
	(segment
		(start 314.192412 -20.313904)
		(end 314.192412 -19.970496)
		(width 0.14224)
		(layer "In2.Cu")
		(net "M_A_DQ<62>")
	)
	(segment
		(start 313.811412 -20.694904)
		(end 314.192412 -20.313904)
		(width 0.14224)
		(layer "In2.Cu")
		(net "M_A_DQ<62>")
	)
	(segment
		(start 313.8932 -30.293818)
		(end 314.0964 -30.090618)
		(width 0.14224)
		(layer "In2.Cu")
		(net "M_A_DQ<62>")
	)
	(segment
		(start 313.8932 -29.481018)
		(end 313.4868 -29.481018)
		(width 0.14224)
		(layer "In2.Cu")
		(net "M_A_DQ<62>")
	)
	(segment
		(start 313.677554 -25.4)
		(end 313.891168 -25.4)
		(width 0.14224)
		(layer "In2.Cu")
		(net "M_A_DQ<62>")
	)
	(segment
		(start 288.82213 -55.809388)
		(end 289.063684 -55.567834)
		(width 0.0889)
		(layer "In2.Cu")
		(net "M_A_DQ<62>")
	)
	(segment
		(start 314.236862 -21.757386)
		(end 314.236862 -21.405596)
		(width 0.14224)
		(layer "In2.Cu")
		(net "M_A_DQ<62>")
	)
	(segment
		(start 313.459368 -24.081232)
		(end 313.699906 -23.840694)
		(width 0.14224)
		(layer "In2.Cu")
		(net "M_A_DQ<62>")
	)
	(segment
		(start 313.891168 -24.602186)
		(end 313.662568 -24.602186)
		(width 0.14224)
		(layer "In2.Cu")
		(net "M_A_DQ<62>")
	)
	(segment
		(start 288.639504 -55.809388)
		(end 288.82213 -55.809388)
		(width 0.0889)
		(layer "In2.Cu")
		(net "M_A_DQ<62>")
	)
	(segment
		(start 313.459368 -25.618186)
		(end 313.677554 -25.4)
		(width 0.14224)
		(layer "In2.Cu")
		(net "M_A_DQ<62>")
	)
	(segment
		(start 313.2836 -28.871418)
		(end 313.4868 -28.668218)
		(width 0.14224)
		(layer "In2.Cu")
		(net "M_A_DQ<62>")
	)
	(segment
		(start 313.8932 -27.855418)
		(end 313.4868 -27.855418)
		(width 0.14224)
		(layer "In2.Cu")
		(net "M_A_DQ<62>")
	)
	(segment
		(start 313.2836 -37.6682)
		(end 313.2836 -30.497018)
		(width 0.14224)
		(layer "In2.Cu")
		(net "M_A_DQ<62>")
	)
	(segment
		(start 314.192412 -19.970496)
		(end 313.811412 -19.589496)
		(width 0.14224)
		(layer "In2.Cu")
		(net "M_A_DQ<62>")
	)
	(segment
		(start 314.0964 -28.465018)
		(end 314.0964 -28.058618)
		(width 0.14224)
		(layer "In2.Cu")
		(net "M_A_DQ<62>")
	)
	(arc
		(start 287.857438 -55.317136)
		(mid 288.115575 -55.40989)
		(end 288.30397 -55.609236)
		(width 0.0889)
		(layer "In2.Cu")
		(net "M_A_DQ<62>")
	)
	(arc
		(start 288.30397 -55.609236)
		(mid 288.445653 -55.75304)
		(end 288.639504 -55.809388)
		(width 0.0889)
		(layer "In2.Cu")
		(net "M_A_DQ<62>")
	)
	(segment
		(start 285.2166 -57.390538)
		(end 285.7881 -57.390538)
		(width 0.1016)
		(layer "F.Cu")
		(net "M_A_DQ<61>")
	)
	(segment
		(start 307.750464 -15.423642)
		(end 307.749956 -15.423642)
		(width 0.1651)
		(layer "F.Cu")
		(net "M_A_DQ<61>")
	)
	(segment
		(start 307.749956 -15.423642)
		(end 307.749956 -16.687546)
		(width 0.1651)
		(layer "F.Cu")
		(net "M_A_DQ<61>")
	)
	(via
		(at 307.749956 -16.687546)
		(size 0.508)
		(drill 0.254)
		(layers "F.Cu" "B.Cu")
		(net "M_A_DQ<61>")
	)
	(via
		(at 285.2166 -57.390538)
		(size 0.508)
		(drill 0.254)
		(layers "F.Cu" "B.Cu")
		(net "M_A_DQ<61>")
	)
	(via
		(at 308.577996 -22.192996)
		(size 0.508)
		(drill 0.254)
		(layers "F.Cu" "B.Cu")
		(net "M_A_DQ<61>")
	)
	(segment
		(start 308.600348 -20.224242)
		(end 308.59984 -20.224242)
		(width 0.1651)
		(layer "B.Cu")
		(net "M_A_DQ<61>")
	)
	(segment
		(start 308.59984 -20.224242)
		(end 308.59984 -22.171152)
		(width 0.1651)
		(layer "B.Cu")
		(net "M_A_DQ<61>")
	)
	(segment
		(start 308.59984 -22.171152)
		(end 308.577996 -22.192996)
		(width 0.1651)
		(layer "B.Cu")
		(net "M_A_DQ<61>")
	)
	(segment
		(start 293.046404 -44.951396)
		(end 296.926 -41.0718)
		(width 0.14224)
		(layer "In2.Cu")
		(net "M_A_DQ<61>")
	)
	(segment
		(start 308.38394 -30.506924)
		(end 308.880256 -30.506924)
		(width 0.14224)
		(layer "In2.Cu")
		(net "M_A_DQ<61>")
	)
	(segment
		(start 284.911038 -55.68061)
		(end 284.865064 -55.6006)
		(width 0.0889)
		(layer "In2.Cu")
		(net "M_A_DQ<61>")
	)
	(segment
		(start 308.880256 -32.495744)
		(end 308.4068 -32.495744)
		(width 0.14224)
		(layer "In2.Cu")
		(net "M_A_DQ<61>")
	)
	(segment
		(start 308.880256 -31.832804)
		(end 309.035196 -31.677864)
		(width 0.14224)
		(layer "In2.Cu")
		(net "M_A_DQ<61>")
	)
	(segment
		(start 309.035196 -33.179004)
		(end 309.035196 -32.650684)
		(width 0.14224)
		(layer "In2.Cu")
		(net "M_A_DQ<61>")
	)
	(segment
		(start 287.02 -49.860454)
		(end 287.2232 -49.860454)
		(width 0.0889)
		(layer "In2.Cu")
		(net "M_A_DQ<61>")
	)
	(segment
		(start 308.38394 -31.169864)
		(end 308.229 -31.014924)
		(width 0.14224)
		(layer "In2.Cu")
		(net "M_A_DQ<61>")
	)
	(segment
		(start 285.2166 -57.390538)
		(end 285.546038 -56.629554)
		(width 0.0889)
		(layer "In2.Cu")
		(net "M_A_DQ<61>")
	)
	(segment
		(start 308.229 -31.014924)
		(end 308.229 -30.661864)
		(width 0.14224)
		(layer "In2.Cu")
		(net "M_A_DQ<61>")
	)
	(segment
		(start 309.035196 -31.677864)
		(end 309.035196 -31.324804)
		(width 0.14224)
		(layer "In2.Cu")
		(net "M_A_DQ<61>")
	)
	(segment
		(start 309.031894 -18.4658)
		(end 309.031894 -18.053304)
		(width 0.14224)
		(layer "In2.Cu")
		(net "M_A_DQ<61>")
	)
	(segment
		(start 288.779458 -44.951396)
		(end 293.046404 -44.951396)
		(width 0.14224)
		(layer "In2.Cu")
		(net "M_A_DQ<61>")
	)
	(segment
		(start 287.2232 -49.860454)
		(end 288.417 -48.666654)
		(width 0.14224)
		(layer "In2.Cu")
		(net "M_A_DQ<61>")
	)
	(segment
		(start 308.229 -30.661864)
		(end 308.38394 -30.506924)
		(width 0.14224)
		(layer "In2.Cu")
		(net "M_A_DQ<61>")
	)
	(segment
		(start 284.86989 -54.218586)
		(end 284.9499 -54.092602)
		(width 0.0889)
		(layer "In2.Cu")
		(net "M_A_DQ<61>")
	)
	(segment
		(start 296.926 -41.0718)
		(end 301.1424 -41.0718)
		(width 0.14224)
		(layer "In2.Cu")
		(net "M_A_DQ<61>")
	)
	(segment
		(start 288.417 -45.313854)
		(end 288.779458 -44.951396)
		(width 0.14224)
		(layer "In2.Cu")
		(net "M_A_DQ<61>")
	)
	(segment
		(start 285.379922 -56.034432)
		(end 285.172658 -55.950612)
		(width 0.0889)
		(layer "In2.Cu")
		(net "M_A_DQ<61>")
	)
	(segment
		(start 286.766 -50.8508)
		(end 286.766 -50.114454)
		(width 0.0889)
		(layer "In2.Cu")
		(net "M_A_DQ<61>")
	)
	(segment
		(start 309.035196 -25.46985)
		(end 308.679596 -25.11425)
		(width 0.14224)
		(layer "In2.Cu")
		(net "M_A_DQ<61>")
	)
	(segment
		(start 308.2798 -32.368744)
		(end 308.2798 -31.959804)
		(width 0.14224)
		(layer "In2.Cu")
		(net "M_A_DQ<61>")
	)
	(segment
		(start 308.880256 -30.506924)
		(end 309.035196 -30.351984)
		(width 0.14224)
		(layer "In2.Cu")
		(net "M_A_DQ<61>")
	)
	(segment
		(start 309.035196 -32.650684)
		(end 308.880256 -32.495744)
		(width 0.14224)
		(layer "In2.Cu")
		(net "M_A_DQ<61>")
	)
	(segment
		(start 309.035196 -30.351984)
		(end 309.035196 -25.46985)
		(width 0.14224)
		(layer "In2.Cu")
		(net "M_A_DQ<61>")
	)
	(segment
		(start 308.52364 -22.247352)
		(end 308.577996 -22.192996)
		(width 0.14224)
		(layer "In2.Cu")
		(net "M_A_DQ<61>")
	)
	(segment
		(start 308.835044 -18.66265)
		(end 309.031894 -18.4658)
		(width 0.14224)
		(layer "In2.Cu")
		(net "M_A_DQ<61>")
	)
	(segment
		(start 308.320694 -17.653)
		(end 307.749956 -17.082262)
		(width 0.14224)
		(layer "In2.Cu")
		(net "M_A_DQ<61>")
	)
	(segment
		(start 308.61 -22.192996)
		(end 308.835044 -21.967952)
		(width 0.14224)
		(layer "In2.Cu")
		(net "M_A_DQ<61>")
	)
	(segment
		(start 284.9499 -53.458618)
		(end 285.805626 -52.602892)
		(width 0.0889)
		(layer "In2.Cu")
		(net "M_A_DQ<61>")
	)
	(segment
		(start 308.4068 -31.832804)
		(end 308.880256 -31.832804)
		(width 0.14224)
		(layer "In2.Cu")
		(net "M_A_DQ<61>")
	)
	(segment
		(start 285.805626 -52.602892)
		(end 285.805626 -51.811174)
		(width 0.0889)
		(layer "In2.Cu")
		(net "M_A_DQ<61>")
	)
	(segment
		(start 301.1424 -41.0718)
		(end 309.035196 -33.179004)
		(width 0.14224)
		(layer "In2.Cu")
		(net "M_A_DQ<61>")
	)
	(segment
		(start 284.87624 -54.629304)
		(end 284.86989 -54.618636)
		(width 0.0889)
		(layer "In2.Cu")
		(net "M_A_DQ<61>")
	)
	(segment
		(start 308.4068 -32.495744)
		(end 308.2798 -32.368744)
		(width 0.14224)
		(layer "In2.Cu")
		(net "M_A_DQ<61>")
	)
	(segment
		(start 308.679596 -23.68804)
		(end 308.52364 -23.532084)
		(width 0.14224)
		(layer "In2.Cu")
		(net "M_A_DQ<61>")
	)
	(segment
		(start 307.749956 -17.082262)
		(end 307.749956 -16.687546)
		(width 0.14224)
		(layer "In2.Cu")
		(net "M_A_DQ<61>")
	)
	(segment
		(start 288.417 -48.666654)
		(end 288.417 -45.313854)
		(width 0.14224)
		(layer "In2.Cu")
		(net "M_A_DQ<61>")
	)
	(segment
		(start 285.172658 -55.950612)
		(end 285.016448 -55.809896)
		(width 0.0889)
		(layer "In2.Cu")
		(net "M_A_DQ<61>")
	)
	(segment
		(start 286.766 -50.114454)
		(end 287.02 -49.860454)
		(width 0.0889)
		(layer "In2.Cu")
		(net "M_A_DQ<61>")
	)
	(segment
		(start 285.805626 -51.811174)
		(end 286.766 -50.8508)
		(width 0.0889)
		(layer "In2.Cu")
		(net "M_A_DQ<61>")
	)
	(segment
		(start 284.86989 -54.618636)
		(end 284.865064 -54.61)
		(width 0.0889)
		(layer "In2.Cu")
		(net "M_A_DQ<61>")
	)
	(segment
		(start 308.63159 -17.653)
		(end 308.320694 -17.653)
		(width 0.14224)
		(layer "In2.Cu")
		(net "M_A_DQ<61>")
	)
	(segment
		(start 308.2798 -31.959804)
		(end 308.4068 -31.832804)
		(width 0.14224)
		(layer "In2.Cu")
		(net "M_A_DQ<61>")
	)
	(segment
		(start 308.679596 -25.11425)
		(end 308.679596 -23.68804)
		(width 0.14224)
		(layer "In2.Cu")
		(net "M_A_DQ<61>")
	)
	(segment
		(start 308.880256 -31.169864)
		(end 308.38394 -31.169864)
		(width 0.14224)
		(layer "In2.Cu")
		(net "M_A_DQ<61>")
	)
	(segment
		(start 285.016448 -55.809896)
		(end 284.911038 -55.68061)
		(width 0.0889)
		(layer "In2.Cu")
		(net "M_A_DQ<61>")
	)
	(segment
		(start 308.835044 -21.967952)
		(end 308.835044 -18.66265)
		(width 0.14224)
		(layer "In2.Cu")
		(net "M_A_DQ<61>")
	)
	(segment
		(start 308.577996 -22.192996)
		(end 308.61 -22.192996)
		(width 0.14224)
		(layer "In2.Cu")
		(net "M_A_DQ<61>")
	)
	(segment
		(start 309.031894 -18.053304)
		(end 308.63159 -17.653)
		(width 0.14224)
		(layer "In2.Cu")
		(net "M_A_DQ<61>")
	)
	(segment
		(start 284.9499 -54.092602)
		(end 284.9499 -53.458618)
		(width 0.0889)
		(layer "In2.Cu")
		(net "M_A_DQ<61>")
	)
	(segment
		(start 309.035196 -31.324804)
		(end 308.880256 -31.169864)
		(width 0.14224)
		(layer "In2.Cu")
		(net "M_A_DQ<61>")
	)
	(segment
		(start 308.52364 -23.532084)
		(end 308.52364 -22.247352)
		(width 0.14224)
		(layer "In2.Cu")
		(net "M_A_DQ<61>")
	)
	(segment
		(start 285.546038 -56.629554)
		(end 285.568136 -56.5912)
		(width 0.0889)
		(layer "In2.Cu")
		(net "M_A_DQ<61>")
	)
	(arc
		(start 284.86989 -55.209186)
		(mid 284.949112 -54.920068)
		(end 284.87624 -54.629304)
		(width 0.0889)
		(layer "In2.Cu")
		(net "M_A_DQ<61>")
	)
	(arc
		(start 284.865064 -55.6006)
		(mid 284.816309 -55.404248)
		(end 284.86989 -55.209186)
		(width 0.0889)
		(layer "In2.Cu")
		(net "M_A_DQ<61>")
	)
	(arc
		(start 284.865064 -54.61)
		(mid 284.816309 -54.413648)
		(end 284.86989 -54.218586)
		(width 0.0889)
		(layer "In2.Cu")
		(net "M_A_DQ<61>")
	)
	(arc
		(start 285.568136 -56.5912)
		(mid 285.595702 -56.271717)
		(end 285.379922 -56.034432)
		(width 0.0889)
		(layer "In2.Cu")
		(net "M_A_DQ<61>")
	)
	(segment
		(start 308.59984 -18.692368)
		(end 308.501796 -18.161)
		(width 0.1651)
		(layer "F.Cu")
		(net "M_A_DQ<60>")
	)
	(segment
		(start 308.600348 -20.023582)
		(end 308.59984 -20.023582)
		(width 0.1651)
		(layer "F.Cu")
		(net "M_A_DQ<60>")
	)
	(segment
		(start 285.2166 -56.399938)
		(end 285.7881 -56.399938)
		(width 0.1016)
		(layer "F.Cu")
		(net "M_A_DQ<60>")
	)
	(segment
		(start 308.59984 -20.023582)
		(end 308.59984 -18.692368)
		(width 0.1651)
		(layer "F.Cu")
		(net "M_A_DQ<60>")
	)
	(via
		(at 307.749956 -23.560278)
		(size 0.508)
		(drill 0.254)
		(layers "F.Cu" "B.Cu")
		(net "M_A_DQ<60>")
	)
	(via
		(at 285.2166 -56.399938)
		(size 0.508)
		(drill 0.254)
		(layers "F.Cu" "B.Cu")
		(net "M_A_DQ<60>")
	)
	(via
		(at 308.501796 -18.161)
		(size 0.508)
		(drill 0.254)
		(layers "F.Cu" "B.Cu")
		(net "M_A_DQ<60>")
	)
	(segment
		(start 307.749956 -24.824182)
		(end 307.749956 -23.560278)
		(width 0.1651)
		(layer "B.Cu")
		(net "M_A_DQ<60>")
	)
	(segment
		(start 307.750464 -24.824182)
		(end 307.749956 -24.824182)
		(width 0.1651)
		(layer "B.Cu")
		(net "M_A_DQ<60>")
	)
	(segment
		(start 300.99 -40.259)
		(end 307.467 -33.782)
		(width 0.14224)
		(layer "In2.Cu")
		(net "M_A_DQ<60>")
	)
	(segment
		(start 308.225444 -21.344128)
		(end 307.874162 -20.992846)
		(width 0.14224)
		(layer "In2.Cu")
		(net "M_A_DQ<60>")
	)
	(segment
		(start 284.805374 -56.346344)
		(end 284.805374 -55.923434)
		(width 0.0889)
		(layer "In2.Cu")
		(net "M_A_DQ<60>")
	)
	(segment
		(start 307.874162 -20.992846)
		(end 307.874162 -20.6375)
		(width 0.14224)
		(layer "In2.Cu")
		(net "M_A_DQ<60>")
	)
	(segment
		(start 287.909 -47.890938)
		(end 287.75406 -47.735998)
		(width 0.14224)
		(layer "In2.Cu")
		(net "M_A_DQ<60>")
	)
	(segment
		(start 308.242462 -19.9644)
		(end 307.861462 -19.5834)
		(width 0.14224)
		(layer "In2.Cu")
		(net "M_A_DQ<60>")
	)
	(segment
		(start 308.044596 -23.854918)
		(end 307.749956 -23.560278)
		(width 0.14224)
		(layer "In2.Cu")
		(net "M_A_DQ<60>")
	)
	(segment
		(start 285.2166 -56.399938)
		(end 284.858968 -56.399938)
		(width 0.0889)
		(layer "In2.Cu")
		(net "M_A_DQ<60>")
	)
	(segment
		(start 307.749956 -23.560278)
		(end 307.514244 -23.324566)
		(width 0.14224)
		(layer "In2.Cu")
		(net "M_A_DQ<60>")
	)
	(segment
		(start 308.225444 -21.818854)
		(end 308.225444 -21.344128)
		(width 0.14224)
		(layer "In2.Cu")
		(net "M_A_DQ<60>")
	)
	(segment
		(start 286.2326 -47.227998)
		(end 286.38754 -47.073058)
		(width 0.14224)
		(layer "In2.Cu")
		(net "M_A_DQ<60>")
	)
	(segment
		(start 307.514244 -22.530054)
		(end 308.225444 -21.818854)
		(width 0.14224)
		(layer "In2.Cu")
		(net "M_A_DQ<60>")
	)
	(segment
		(start 285.615126 -51.731672)
		(end 286.563562 -50.783236)
		(width 0.0889)
		(layer "In2.Cu")
		(net "M_A_DQ<60>")
	)
	(segment
		(start 307.874162 -20.6375)
		(end 308.242462 -20.2692)
		(width 0.14224)
		(layer "In2.Cu")
		(net "M_A_DQ<60>")
	)
	(segment
		(start 286.563562 -49.911)
		(end 286.8422 -49.632362)
		(width 0.0889)
		(layer "In2.Cu")
		(net "M_A_DQ<60>")
	)
	(segment
		(start 286.8422 -45.237654)
		(end 287.680654 -44.3992)
		(width 0.14224)
		(layer "In2.Cu")
		(net "M_A_DQ<60>")
	)
	(segment
		(start 284.70479 -54.713886)
		(end 284.69844 -54.703218)
		(width 0.0889)
		(layer "In2.Cu")
		(net "M_A_DQ<60>")
	)
	(segment
		(start 308.044596 -25.342342)
		(end 308.044596 -23.854918)
		(width 0.14224)
		(layer "In2.Cu")
		(net "M_A_DQ<60>")
	)
	(segment
		(start 308.242462 -20.2692)
		(end 308.242462 -19.9644)
		(width 0.14224)
		(layer "In2.Cu")
		(net "M_A_DQ<60>")
	)
	(segment
		(start 286.99714 -48.398938)
		(end 287.75406 -48.398938)
		(width 0.14224)
		(layer "In2.Cu")
		(net "M_A_DQ<60>")
	)
	(segment
		(start 307.861462 -19.278854)
		(end 308.225444 -18.914872)
		(width 0.14224)
		(layer "In2.Cu")
		(net "M_A_DQ<60>")
	)
	(segment
		(start 286.99714 -46.410118)
		(end 286.8422 -46.255178)
		(width 0.14224)
		(layer "In2.Cu")
		(net "M_A_DQ<60>")
	)
	(segment
		(start 287.70326 -46.410118)
		(end 286.99714 -46.410118)
		(width 0.14224)
		(layer "In2.Cu")
		(net "M_A_DQ<60>")
	)
	(segment
		(start 296.900854 -40.259)
		(end 300.99 -40.259)
		(width 0.14224)
		(layer "In2.Cu")
		(net "M_A_DQ<60>")
	)
	(segment
		(start 287.909 -48.243998)
		(end 287.909 -47.890938)
		(width 0.14224)
		(layer "In2.Cu")
		(net "M_A_DQ<60>")
	)
	(segment
		(start 285.615126 -52.523898)
		(end 285.615126 -51.731672)
		(width 0.0889)
		(layer "In2.Cu")
		(net "M_A_DQ<60>")
	)
	(segment
		(start 307.861462 -19.5834)
		(end 307.861462 -19.278854)
		(width 0.14224)
		(layer "In2.Cu")
		(net "M_A_DQ<60>")
	)
	(segment
		(start 286.8422 -49.403254)
		(end 286.8422 -48.553878)
		(width 0.14224)
		(layer "In2.Cu")
		(net "M_A_DQ<60>")
	)
	(segment
		(start 286.8422 -48.553878)
		(end 286.99714 -48.398938)
		(width 0.14224)
		(layer "In2.Cu")
		(net "M_A_DQ<60>")
	)
	(segment
		(start 286.38754 -47.073058)
		(end 287.70326 -47.073058)
		(width 0.14224)
		(layer "In2.Cu")
		(net "M_A_DQ<60>")
	)
	(segment
		(start 286.563562 -50.783236)
		(end 286.563562 -49.911)
		(width 0.0889)
		(layer "In2.Cu")
		(net "M_A_DQ<60>")
	)
	(segment
		(start 287.680654 -44.3992)
		(end 292.760654 -44.3992)
		(width 0.14224)
		(layer "In2.Cu")
		(net "M_A_DQ<60>")
	)
	(segment
		(start 307.467 -30.0736)
		(end 308.400196 -29.140404)
		(width 0.14224)
		(layer "In2.Cu")
		(net "M_A_DQ<60>")
	)
	(segment
		(start 308.400196 -29.140404)
		(end 308.400196 -25.697942)
		(width 0.14224)
		(layer "In2.Cu")
		(net "M_A_DQ<60>")
	)
	(segment
		(start 287.75406 -48.398938)
		(end 287.909 -48.243998)
		(width 0.14224)
		(layer "In2.Cu")
		(net "M_A_DQ<60>")
	)
	(segment
		(start 284.7594 -53.379624)
		(end 285.615126 -52.523898)
		(width 0.0889)
		(layer "In2.Cu")
		(net "M_A_DQ<60>")
	)
	(segment
		(start 284.70479 -54.123336)
		(end 284.7594 -54.028848)
		(width 0.0889)
		(layer "In2.Cu")
		(net "M_A_DQ<60>")
	)
	(segment
		(start 287.75406 -47.735998)
		(end 286.38754 -47.735998)
		(width 0.14224)
		(layer "In2.Cu")
		(net "M_A_DQ<60>")
	)
	(segment
		(start 284.784292 -55.84444)
		(end 284.70479 -55.704486)
		(width 0.0889)
		(layer "In2.Cu")
		(net "M_A_DQ<60>")
	)
	(segment
		(start 287.8582 -46.918118)
		(end 287.8582 -46.565058)
		(width 0.14224)
		(layer "In2.Cu")
		(net "M_A_DQ<60>")
	)
	(segment
		(start 287.8582 -46.565058)
		(end 287.70326 -46.410118)
		(width 0.14224)
		(layer "In2.Cu")
		(net "M_A_DQ<60>")
	)
	(segment
		(start 284.70479 -55.704486)
		(end 284.69844 -55.693818)
		(width 0.0889)
		(layer "In2.Cu")
		(net "M_A_DQ<60>")
	)
	(segment
		(start 292.760654 -44.3992)
		(end 296.900854 -40.259)
		(width 0.14224)
		(layer "In2.Cu")
		(net "M_A_DQ<60>")
	)
	(segment
		(start 286.2326 -47.581058)
		(end 286.2326 -47.227998)
		(width 0.14224)
		(layer "In2.Cu")
		(net "M_A_DQ<60>")
	)
	(segment
		(start 284.7594 -54.028848)
		(end 284.7594 -53.379624)
		(width 0.0889)
		(layer "In2.Cu")
		(net "M_A_DQ<60>")
	)
	(segment
		(start 287.70326 -47.073058)
		(end 287.8582 -46.918118)
		(width 0.14224)
		(layer "In2.Cu")
		(net "M_A_DQ<60>")
	)
	(segment
		(start 284.709616 -54.722522)
		(end 284.70479 -54.713886)
		(width 0.0889)
		(layer "In2.Cu")
		(net "M_A_DQ<60>")
	)
	(segment
		(start 308.400196 -25.697942)
		(end 308.044596 -25.342342)
		(width 0.14224)
		(layer "In2.Cu")
		(net "M_A_DQ<60>")
	)
	(segment
		(start 307.467 -33.782)
		(end 307.467 -30.0736)
		(width 0.14224)
		(layer "In2.Cu")
		(net "M_A_DQ<60>")
	)
	(segment
		(start 284.858968 -56.399938)
		(end 284.805374 -56.346344)
		(width 0.0889)
		(layer "In2.Cu")
		(net "M_A_DQ<60>")
	)
	(segment
		(start 308.225444 -18.914872)
		(end 308.225444 -18.437352)
		(width 0.14224)
		(layer "In2.Cu")
		(net "M_A_DQ<60>")
	)
	(segment
		(start 286.8422 -49.632362)
		(end 286.8422 -49.403254)
		(width 0.0889)
		(layer "In2.Cu")
		(net "M_A_DQ<60>")
	)
	(segment
		(start 286.8422 -46.255178)
		(end 286.8422 -45.237654)
		(width 0.14224)
		(layer "In2.Cu")
		(net "M_A_DQ<60>")
	)
	(segment
		(start 286.38754 -47.735998)
		(end 286.2326 -47.581058)
		(width 0.14224)
		(layer "In2.Cu")
		(net "M_A_DQ<60>")
	)
	(segment
		(start 307.514244 -23.324566)
		(end 307.514244 -22.530054)
		(width 0.14224)
		(layer "In2.Cu")
		(net "M_A_DQ<60>")
	)
	(segment
		(start 308.225444 -18.437352)
		(end 308.501796 -18.161)
		(width 0.14224)
		(layer "In2.Cu")
		(net "M_A_DQ<60>")
	)
	(arc
		(start 284.70479 -55.113936)
		(mid 284.75826 -54.918873)
		(end 284.709616 -54.722522)
		(width 0.0889)
		(layer "In2.Cu")
		(net "M_A_DQ<60>")
	)
	(arc
		(start 284.69844 -55.693818)
		(mid 284.625642 -55.403055)
		(end 284.70479 -55.113936)
		(width 0.0889)
		(layer "In2.Cu")
		(net "M_A_DQ<60>")
	)
	(arc
		(start 284.805374 -55.923434)
		(mid 284.799923 -55.882577)
		(end 284.784292 -55.84444)
		(width 0.0889)
		(layer "In2.Cu")
		(net "M_A_DQ<60>")
	)
	(arc
		(start 284.69844 -54.703218)
		(mid 284.625642 -54.412455)
		(end 284.70479 -54.123336)
		(width 0.0889)
		(layer "In2.Cu")
		(net "M_A_DQ<60>")
	)
	(segment
		(start 196.399912 -15.423642)
		(end 196.399912 -16.687546)
		(width 0.1651)
		(layer "F.Cu")
		(net "M_A_DQ<5>")
	)
	(segment
		(start 234.466638 -66.48704)
		(end 233.895138 -66.48704)
		(width 0.1651)
		(layer "F.Cu")
		(net "M_A_DQ<5>")
	)
	(segment
		(start 196.40042 -15.423642)
		(end 196.399912 -15.423642)
		(width 0.1651)
		(layer "F.Cu")
		(net "M_A_DQ<5>")
	)
	(via
		(at 233.895138 -66.48704)
		(size 0.508)
		(drill 0.254)
		(layers "F.Cu" "B.Cu")
		(net "M_A_DQ<5>")
	)
	(via
		(at 197.173596 -22.279356)
		(size 0.508)
		(drill 0.254)
		(layers "F.Cu" "B.Cu")
		(net "M_A_DQ<5>")
	)
	(via
		(at 196.399912 -16.687546)
		(size 0.508)
		(drill 0.254)
		(layers "F.Cu" "B.Cu")
		(net "M_A_DQ<5>")
	)
	(segment
		(start 197.250304 -20.224242)
		(end 197.249796 -20.224242)
		(width 0.1651)
		(layer "B.Cu")
		(net "M_A_DQ<5>")
	)
	(segment
		(start 197.249796 -20.224242)
		(end 197.249796 -22.203156)
		(width 0.1651)
		(layer "B.Cu")
		(net "M_A_DQ<5>")
	)
	(segment
		(start 197.249796 -22.203156)
		(end 197.173596 -22.279356)
		(width 0.1651)
		(layer "B.Cu")
		(net "M_A_DQ<5>")
	)
	(segment
		(start 196.857112 -31.935166)
		(end 196.857112 -23.289768)
		(width 0.14224)
		(layer "In2.Cu")
		(net "M_A_DQ<5>")
	)
	(segment
		(start 231.93883 -66.003424)
		(end 231.175052 -66.767202)
		(width 0.0889)
		(layer "In2.Cu")
		(net "M_A_DQ<5>")
	)
	(segment
		(start 233.895138 -66.48704)
		(end 232.859834 -66.48704)
		(width 0.0889)
		(layer "In2.Cu")
		(net "M_A_DQ<5>")
	)
	(segment
		(start 197.485 -21.967952)
		(end 197.485 -18.66265)
		(width 0.14224)
		(layer "In2.Cu")
		(net "M_A_DQ<5>")
	)
	(segment
		(start 197.281546 -17.653)
		(end 196.97065 -17.653)
		(width 0.14224)
		(layer "In2.Cu")
		(net "M_A_DQ<5>")
	)
	(segment
		(start 197.68185 -18.4658)
		(end 197.68185 -18.053304)
		(width 0.14224)
		(layer "In2.Cu")
		(net "M_A_DQ<5>")
	)
	(segment
		(start 231.175052 -66.767202)
		(end 230.505 -66.767202)
		(width 0.0889)
		(layer "In2.Cu")
		(net "M_A_DQ<5>")
	)
	(segment
		(start 232.859834 -66.48704)
		(end 232.376218 -66.003424)
		(width 0.0889)
		(layer "In2.Cu")
		(net "M_A_DQ<5>")
	)
	(segment
		(start 232.376218 -66.003424)
		(end 231.93883 -66.003424)
		(width 0.0889)
		(layer "In2.Cu")
		(net "M_A_DQ<5>")
	)
	(segment
		(start 197.68185 -18.053304)
		(end 197.281546 -17.653)
		(width 0.14224)
		(layer "In2.Cu")
		(net "M_A_DQ<5>")
	)
	(segment
		(start 196.399912 -17.082262)
		(end 196.399912 -16.687546)
		(width 0.14224)
		(layer "In2.Cu")
		(net "M_A_DQ<5>")
	)
	(segment
		(start 196.695568 -23.128224)
		(end 196.695568 -22.757384)
		(width 0.14224)
		(layer "In2.Cu")
		(net "M_A_DQ<5>")
	)
	(segment
		(start 197.863968 -32.942022)
		(end 196.857112 -31.935166)
		(width 0.14224)
		(layer "In2.Cu")
		(net "M_A_DQ<5>")
	)
	(segment
		(start 197.485 -18.66265)
		(end 197.68185 -18.4658)
		(width 0.14224)
		(layer "In2.Cu")
		(net "M_A_DQ<5>")
	)
	(segment
		(start 197.863968 -36.854384)
		(end 197.863968 -32.942022)
		(width 0.14224)
		(layer "In2.Cu")
		(net "M_A_DQ<5>")
	)
	(segment
		(start 227.776786 -66.767202)
		(end 197.863968 -36.854384)
		(width 0.14224)
		(layer "In2.Cu")
		(net "M_A_DQ<5>")
	)
	(segment
		(start 230.505 -66.767202)
		(end 227.776786 -66.767202)
		(width 0.14224)
		(layer "In2.Cu")
		(net "M_A_DQ<5>")
	)
	(segment
		(start 196.695568 -22.757384)
		(end 197.173596 -22.279356)
		(width 0.14224)
		(layer "In2.Cu")
		(net "M_A_DQ<5>")
	)
	(segment
		(start 196.857112 -23.289768)
		(end 196.695568 -23.128224)
		(width 0.14224)
		(layer "In2.Cu")
		(net "M_A_DQ<5>")
	)
	(segment
		(start 197.173596 -22.279356)
		(end 197.485 -21.967952)
		(width 0.14224)
		(layer "In2.Cu")
		(net "M_A_DQ<5>")
	)
	(segment
		(start 196.97065 -17.653)
		(end 196.399912 -17.082262)
		(width 0.14224)
		(layer "In2.Cu")
		(net "M_A_DQ<5>")
	)
	(segment
		(start 287.79216 -58.876438)
		(end 288.36366 -58.876438)
		(width 0.1016)
		(layer "F.Cu")
		(net "M_A_DQ<59>")
	)
	(segment
		(start 315.400436 -15.423642)
		(end 315.400436 -16.687038)
		(width 0.1651)
		(layer "F.Cu")
		(net "M_A_DQ<59>")
	)
	(segment
		(start 315.400436 -16.687038)
		(end 315.399928 -16.687546)
		(width 0.1651)
		(layer "F.Cu")
		(net "M_A_DQ<59>")
	)
	(via
		(at 316.249812 -22.279356)
		(size 0.508)
		(drill 0.254)
		(layers "F.Cu" "B.Cu")
		(net "M_A_DQ<59>")
	)
	(via
		(at 287.79216 -58.876438)
		(size 0.508)
		(drill 0.254)
		(layers "F.Cu" "B.Cu")
		(net "M_A_DQ<59>")
	)
	(via
		(at 315.399928 -16.687546)
		(size 0.508)
		(drill 0.254)
		(layers "F.Cu" "B.Cu")
		(net "M_A_DQ<59>")
	)
	(segment
		(start 316.25032 -22.278848)
		(end 316.249812 -22.279356)
		(width 0.1651)
		(layer "B.Cu")
		(net "M_A_DQ<59>")
	)
	(segment
		(start 316.25032 -20.224242)
		(end 316.25032 -22.278848)
		(width 0.1651)
		(layer "B.Cu")
		(net "M_A_DQ<59>")
	)
	(segment
		(start 288.299144 -57.5818)
		(end 288.30397 -57.590436)
		(width 0.0889)
		(layer "In2.Cu")
		(net "M_A_DQ<59>")
	)
	(segment
		(start 291.428424 -52.5526)
		(end 290.021264 -53.95976)
		(width 0.0889)
		(layer "In2.Cu")
		(net "M_A_DQ<59>")
	)
	(segment
		(start 316.0522 -23.4188)
		(end 316.0522 -37.807392)
		(width 0.14224)
		(layer "In2.Cu")
		(net "M_A_DQ<59>")
	)
	(segment
		(start 287.857438 -58.473086)
		(end 287.79216 -58.538364)
		(width 0.0889)
		(layer "In2.Cu")
		(net "M_A_DQ<59>")
	)
	(segment
		(start 316.249812 -22.279356)
		(end 315.7982 -22.730968)
		(width 0.14224)
		(layer "In2.Cu")
		(net "M_A_DQ<59>")
	)
	(segment
		(start 302.1838 -49.149)
		(end 293.492936 -51.642264)
		(width 0.14224)
		(layer "In2.Cu")
		(net "M_A_DQ<59>")
	)
	(segment
		(start 316.0522 -37.807392)
		(end 311.359296 -42.500296)
		(width 0.14224)
		(layer "In2.Cu")
		(net "M_A_DQ<59>")
	)
	(segment
		(start 315.399928 -16.687546)
		(end 315.399928 -17.006062)
		(width 0.14224)
		(layer "In2.Cu")
		(net "M_A_DQ<59>")
	)
	(segment
		(start 308.832504 -42.500296)
		(end 302.1838 -49.149)
		(width 0.14224)
		(layer "In2.Cu")
		(net "M_A_DQ<59>")
	)
	(segment
		(start 290.021264 -56.264048)
		(end 289.294824 -56.990488)
		(width 0.0889)
		(layer "In2.Cu")
		(net "M_A_DQ<59>")
	)
	(segment
		(start 315.7982 -23.1648)
		(end 316.0522 -23.4188)
		(width 0.14224)
		(layer "In2.Cu")
		(net "M_A_DQ<59>")
	)
	(segment
		(start 316.046866 -17.653)
		(end 316.300866 -17.653)
		(width 0.14224)
		(layer "In2.Cu")
		(net "M_A_DQ<59>")
	)
	(segment
		(start 316.602618 -21.92655)
		(end 316.249812 -22.279356)
		(width 0.14224)
		(layer "In2.Cu")
		(net "M_A_DQ<59>")
	)
	(segment
		(start 316.758066 -18.1102)
		(end 316.758066 -18.4658)
		(width 0.14224)
		(layer "In2.Cu")
		(net "M_A_DQ<59>")
	)
	(segment
		(start 292.5826 -52.5526)
		(end 291.428424 -52.5526)
		(width 0.0889)
		(layer "In2.Cu")
		(net "M_A_DQ<59>")
	)
	(segment
		(start 315.399928 -17.006062)
		(end 316.046866 -17.653)
		(width 0.14224)
		(layer "In2.Cu")
		(net "M_A_DQ<59>")
	)
	(segment
		(start 316.300866 -17.653)
		(end 316.758066 -18.1102)
		(width 0.14224)
		(layer "In2.Cu")
		(net "M_A_DQ<59>")
	)
	(segment
		(start 290.021264 -53.95976)
		(end 290.021264 -56.264048)
		(width 0.0889)
		(layer "In2.Cu")
		(net "M_A_DQ<59>")
	)
	(segment
		(start 288.30397 -57.590436)
		(end 288.31032 -57.601104)
		(width 0.0889)
		(layer "In2.Cu")
		(net "M_A_DQ<59>")
	)
	(segment
		(start 293.492936 -51.642264)
		(end 292.5826 -52.5526)
		(width 0.14224)
		(layer "In2.Cu")
		(net "M_A_DQ<59>")
	)
	(segment
		(start 287.79216 -58.538364)
		(end 287.79216 -58.876438)
		(width 0.0889)
		(layer "In2.Cu")
		(net "M_A_DQ<59>")
	)
	(segment
		(start 311.359296 -42.500296)
		(end 308.832504 -42.500296)
		(width 0.14224)
		(layer "In2.Cu")
		(net "M_A_DQ<59>")
	)
	(segment
		(start 289.294824 -56.990488)
		(end 288.635694 -56.990488)
		(width 0.0889)
		(layer "In2.Cu")
		(net "M_A_DQ<59>")
	)
	(segment
		(start 315.7982 -22.730968)
		(end 315.7982 -23.1648)
		(width 0.14224)
		(layer "In2.Cu")
		(net "M_A_DQ<59>")
	)
	(segment
		(start 316.602618 -18.621248)
		(end 316.602618 -21.92655)
		(width 0.14224)
		(layer "In2.Cu")
		(net "M_A_DQ<59>")
	)
	(segment
		(start 316.758066 -18.4658)
		(end 316.602618 -18.621248)
		(width 0.14224)
		(layer "In2.Cu")
		(net "M_A_DQ<59>")
	)
	(arc
		(start 288.31032 -57.601104)
		(mid 288.383118 -57.891867)
		(end 288.30397 -58.180986)
		(width 0.0889)
		(layer "In2.Cu")
		(net "M_A_DQ<59>")
	)
	(arc
		(start 288.635694 -56.990488)
		(mid 288.302776 -57.192479)
		(end 288.299144 -57.5818)
		(width 0.0889)
		(layer "In2.Cu")
		(net "M_A_DQ<59>")
	)
	(arc
		(start 288.30397 -58.180986)
		(mid 288.115547 -58.38029)
		(end 287.857438 -58.473086)
		(width 0.0889)
		(layer "In2.Cu")
		(net "M_A_DQ<59>")
	)
	(segment
		(start 287.79216 -57.885584)
		(end 288.36366 -57.885584)
		(width 0.1651)
		(layer "F.Cu")
		(net "M_A_DQ<58>")
	)
	(segment
		(start 316.381384 -18.67154)
		(end 316.249812 -18.539968)
		(width 0.1651)
		(layer "F.Cu")
		(net "M_A_DQ<58>")
	)
	(segment
		(start 316.25032 -19.02714)
		(end 316.249812 -19.026632)
		(width 0.1651)
		(layer "F.Cu")
		(net "M_A_DQ<58>")
	)
	(segment
		(start 316.381384 -18.89506)
		(end 316.381384 -18.67154)
		(width 0.1651)
		(layer "F.Cu")
		(net "M_A_DQ<58>")
	)
	(segment
		(start 316.249812 -19.026632)
		(end 316.381384 -18.89506)
		(width 0.1651)
		(layer "F.Cu")
		(net "M_A_DQ<58>")
	)
	(segment
		(start 316.249812 -18.539968)
		(end 316.249812 -18.2626)
		(width 0.1651)
		(layer "F.Cu")
		(net "M_A_DQ<58>")
	)
	(segment
		(start 316.25032 -20.023582)
		(end 316.25032 -19.02714)
		(width 0.1651)
		(layer "F.Cu")
		(net "M_A_DQ<58>")
	)
	(via
		(at 316.249812 -18.2626)
		(size 0.508)
		(drill 0.254)
		(layers "F.Cu" "B.Cu")
		(net "M_A_DQ<58>")
	)
	(via
		(at 315.399928 -23.560278)
		(size 0.508)
		(drill 0.254)
		(layers "F.Cu" "B.Cu")
		(net "M_A_DQ<58>")
	)
	(via
		(at 287.79216 -57.885584)
		(size 0.508)
		(drill 0.254)
		(layers "F.Cu" "B.Cu")
		(net "M_A_DQ<58>")
	)
	(segment
		(start 315.400436 -23.560786)
		(end 315.399928 -23.560278)
		(width 0.1651)
		(layer "B.Cu")
		(net "M_A_DQ<58>")
	)
	(segment
		(start 315.400436 -24.824182)
		(end 315.400436 -23.560786)
		(width 0.1651)
		(layer "B.Cu")
		(net "M_A_DQ<58>")
	)
	(segment
		(start 315.506862 -19.310604)
		(end 315.851794 -18.965672)
		(width 0.14224)
		(layer "In2.Cu")
		(net "M_A_DQ<58>")
	)
	(segment
		(start 315.851794 -18.660618)
		(end 316.249812 -18.2626)
		(width 0.14224)
		(layer "In2.Cu")
		(net "M_A_DQ<58>")
	)
	(segment
		(start 289.21583 -56.799988)
		(end 289.830764 -56.185054)
		(width 0.0889)
		(layer "In2.Cu")
		(net "M_A_DQ<58>")
	)
	(segment
		(start 299.47235 -48.70196)
		(end 299.47235 -47.97044)
		(width 0.14224)
		(layer "In2.Cu")
		(net "M_A_DQ<58>")
	)
	(segment
		(start 315.851794 -18.965672)
		(end 315.851794 -18.660618)
		(width 0.14224)
		(layer "In2.Cu")
		(net "M_A_DQ<58>")
	)
	(segment
		(start 292.074346 -52.3494)
		(end 292.27907 -52.144676)
		(width 0.0889)
		(layer "In2.Cu")
		(net "M_A_DQ<58>")
	)
	(segment
		(start 294.981376 -49.44237)
		(end 296.403776 -49.44237)
		(width 0.14224)
		(layer "In2.Cu")
		(net "M_A_DQ<58>")
	)
	(segment
		(start 311.575196 -41.369996)
		(end 315.399928 -37.545264)
		(width 0.14224)
		(layer "In2.Cu")
		(net "M_A_DQ<58>")
	)
	(segment
		(start 298.82211 -48.70196)
		(end 298.96435 -48.8442)
		(width 0.14224)
		(layer "In2.Cu")
		(net "M_A_DQ<58>")
	)
	(segment
		(start 289.830764 -53.880512)
		(end 291.361876 -52.3494)
		(width 0.0889)
		(layer "In2.Cu")
		(net "M_A_DQ<58>")
	)
	(segment
		(start 298.017946 -47.8282)
		(end 298.67987 -47.8282)
		(width 0.14224)
		(layer "In2.Cu")
		(net "M_A_DQ<58>")
	)
	(segment
		(start 315.811662 -19.964146)
		(end 315.506862 -19.659346)
		(width 0.14224)
		(layer "In2.Cu")
		(net "M_A_DQ<58>")
	)
	(segment
		(start 315.115194 -23.275544)
		(end 315.115194 -22.5298)
		(width 0.14224)
		(layer "In2.Cu")
		(net "M_A_DQ<58>")
	)
	(segment
		(start 298.82211 -47.97044)
		(end 298.82211 -48.70196)
		(width 0.14224)
		(layer "In2.Cu")
		(net "M_A_DQ<58>")
	)
	(segment
		(start 315.964062 -21.680932)
		(end 315.964062 -21.4122)
		(width 0.14224)
		(layer "In2.Cu")
		(net "M_A_DQ<58>")
	)
	(segment
		(start 315.506862 -20.55495)
		(end 315.811662 -20.25015)
		(width 0.14224)
		(layer "In2.Cu")
		(net "M_A_DQ<58>")
	)
	(segment
		(start 315.506862 -19.659346)
		(end 315.506862 -19.310604)
		(width 0.14224)
		(layer "In2.Cu")
		(net "M_A_DQ<58>")
	)
	(segment
		(start 291.361876 -52.3494)
		(end 292.074346 -52.3494)
		(width 0.0889)
		(layer "In2.Cu")
		(net "M_A_DQ<58>")
	)
	(segment
		(start 298.96435 -48.8442)
		(end 299.33011 -48.8442)
		(width 0.14224)
		(layer "In2.Cu")
		(net "M_A_DQ<58>")
	)
	(segment
		(start 315.399928 -37.545264)
		(end 315.399928 -23.560278)
		(width 0.14224)
		(layer "In2.Cu")
		(net "M_A_DQ<58>")
	)
	(segment
		(start 287.79216 -57.885584)
		(end 288.063686 -57.322466)
		(width 0.0889)
		(layer "In2.Cu")
		(net "M_A_DQ<58>")
	)
	(segment
		(start 288.62909 -56.799988)
		(end 289.21583 -56.799988)
		(width 0.0889)
		(layer "In2.Cu")
		(net "M_A_DQ<58>")
	)
	(segment
		(start 315.964062 -21.4122)
		(end 315.506862 -20.955)
		(width 0.14224)
		(layer "In2.Cu")
		(net "M_A_DQ<58>")
	)
	(segment
		(start 299.61459 -47.8282)
		(end 302.4124 -47.8282)
		(width 0.14224)
		(layer "In2.Cu")
		(net "M_A_DQ<58>")
	)
	(segment
		(start 315.399928 -23.560278)
		(end 315.115194 -23.275544)
		(width 0.14224)
		(layer "In2.Cu")
		(net "M_A_DQ<58>")
	)
	(segment
		(start 315.506862 -20.955)
		(end 315.506862 -20.55495)
		(width 0.14224)
		(layer "In2.Cu")
		(net "M_A_DQ<58>")
	)
	(segment
		(start 298.67987 -47.8282)
		(end 298.82211 -47.97044)
		(width 0.14224)
		(layer "In2.Cu")
		(net "M_A_DQ<58>")
	)
	(segment
		(start 289.830764 -56.185054)
		(end 289.830764 -53.880512)
		(width 0.0889)
		(layer "In2.Cu")
		(net "M_A_DQ<58>")
	)
	(segment
		(start 299.47235 -47.97044)
		(end 299.61459 -47.8282)
		(width 0.14224)
		(layer "In2.Cu")
		(net "M_A_DQ<58>")
	)
	(segment
		(start 292.27907 -52.144676)
		(end 294.981376 -49.44237)
		(width 0.14224)
		(layer "In2.Cu")
		(net "M_A_DQ<58>")
	)
	(segment
		(start 315.115194 -22.5298)
		(end 315.964062 -21.680932)
		(width 0.14224)
		(layer "In2.Cu")
		(net "M_A_DQ<58>")
	)
	(segment
		(start 296.403776 -49.44237)
		(end 298.017946 -47.8282)
		(width 0.14224)
		(layer "In2.Cu")
		(net "M_A_DQ<58>")
	)
	(segment
		(start 302.4124 -47.8282)
		(end 308.870604 -41.369996)
		(width 0.14224)
		(layer "In2.Cu")
		(net "M_A_DQ<58>")
	)
	(segment
		(start 315.811662 -20.25015)
		(end 315.811662 -19.964146)
		(width 0.14224)
		(layer "In2.Cu")
		(net "M_A_DQ<58>")
	)
	(segment
		(start 308.870604 -41.369996)
		(end 311.575196 -41.369996)
		(width 0.14224)
		(layer "In2.Cu")
		(net "M_A_DQ<58>")
	)
	(segment
		(start 299.33011 -48.8442)
		(end 299.47235 -48.70196)
		(width 0.14224)
		(layer "In2.Cu")
		(net "M_A_DQ<58>")
	)
	(arc
		(start 288.063686 -57.322466)
		(mid 288.249638 -56.956532)
		(end 288.62909 -56.799988)
		(width 0.0889)
		(layer "In2.Cu")
		(net "M_A_DQ<58>")
	)
	(segment
		(start 309.450486 -15.423642)
		(end 309.449978 -15.423642)
		(width 0.1651)
		(layer "F.Cu")
		(net "M_A_DQ<57>")
	)
	(segment
		(start 309.449978 -15.423642)
		(end 309.449978 -16.687546)
		(width 0.1651)
		(layer "F.Cu")
		(net "M_A_DQ<57>")
	)
	(segment
		(start 286.64662 -57.885584)
		(end 286.07512 -57.885584)
		(width 0.1016)
		(layer "F.Cu")
		(net "M_A_DQ<57>")
	)
	(via
		(at 310.122062 -22.279356)
		(size 0.508)
		(drill 0.254)
		(layers "F.Cu" "B.Cu")
		(net "M_A_DQ<57>")
	)
	(via
		(at 309.449978 -16.687546)
		(size 0.508)
		(drill 0.254)
		(layers "F.Cu" "B.Cu")
		(net "M_A_DQ<57>")
	)
	(via
		(at 286.07512 -57.885584)
		(size 0.508)
		(drill 0.254)
		(layers "F.Cu" "B.Cu")
		(net "M_A_DQ<57>")
	)
	(segment
		(start 310.122062 -21.776182)
		(end 310.122062 -22.279356)
		(width 0.1651)
		(layer "B.Cu")
		(net "M_A_DQ<57>")
	)
	(segment
		(start 310.299862 -21.598382)
		(end 310.122062 -21.776182)
		(width 0.1651)
		(layer "B.Cu")
		(net "M_A_DQ<57>")
	)
	(segment
		(start 310.299862 -20.224242)
		(end 310.299862 -21.598382)
		(width 0.1651)
		(layer "B.Cu")
		(net "M_A_DQ<57>")
	)
	(segment
		(start 310.30037 -20.224242)
		(end 310.299862 -20.224242)
		(width 0.1651)
		(layer "B.Cu")
		(net "M_A_DQ<57>")
	)
	(segment
		(start 285.6611 -53.99278)
		(end 285.6611 -53.75275)
		(width 0.0889)
		(layer "In2.Cu")
		(net "M_A_DQ<57>")
	)
	(segment
		(start 301.2948 -43.0276)
		(end 308.4322 -35.8902)
		(width 0.14224)
		(layer "In2.Cu")
		(net "M_A_DQ<57>")
	)
	(segment
		(start 308.4322 -35.8902)
		(end 309.931054 -35.8902)
		(width 0.14224)
		(layer "In2.Cu")
		(net "M_A_DQ<57>")
	)
	(segment
		(start 288.1884 -50.5206)
		(end 292.800024 -45.908976)
		(width 0.14224)
		(layer "In2.Cu")
		(net "M_A_DQ<57>")
	)
	(segment
		(start 285.913576 -55.343806)
		(end 285.775146 -55.194962)
		(width 0.0889)
		(layer "In2.Cu")
		(net "M_A_DQ<57>")
	)
	(segment
		(start 299.591222 -42.3926)
		(end 299.746162 -42.54754)
		(width 0.14224)
		(layer "In2.Cu")
		(net "M_A_DQ<57>")
	)
	(segment
		(start 310.496204 -21.905214)
		(end 310.496204 -18.571464)
		(width 0.14224)
		(layer "In2.Cu")
		(net "M_A_DQ<57>")
	)
	(segment
		(start 309.619396 -22.782022)
		(end 310.122062 -22.279356)
		(width 0.14224)
		(layer "In2.Cu")
		(net "M_A_DQ<57>")
	)
	(segment
		(start 292.800024 -45.908976)
		(end 293.841678 -45.908976)
		(width 0.14224)
		(layer "In2.Cu")
		(net "M_A_DQ<57>")
	)
	(segment
		(start 285.6611 -53.75275)
		(end 286.530542 -52.883308)
		(width 0.0889)
		(layer "In2.Cu")
		(net "M_A_DQ<57>")
	)
	(segment
		(start 286.530542 -52.194206)
		(end 288.1884 -50.536348)
		(width 0.0889)
		(layer "In2.Cu")
		(net "M_A_DQ<57>")
	)
	(segment
		(start 285.72841 -54.713886)
		(end 285.73476 -54.703218)
		(width 0.0889)
		(layer "In2.Cu")
		(net "M_A_DQ<57>")
	)
	(segment
		(start 298.420282 -42.87266)
		(end 298.575222 -43.0276)
		(width 0.14224)
		(layer "In2.Cu")
		(net "M_A_DQ<57>")
	)
	(segment
		(start 310.652668 -18.073624)
		(end 310.282844 -17.7038)
		(width 0.14224)
		(layer "In2.Cu")
		(net "M_A_DQ<57>")
	)
	(segment
		(start 286.07512 -57.885584)
		(end 286.405066 -57.123838)
		(width 0.0889)
		(layer "In2.Cu")
		(net "M_A_DQ<57>")
	)
	(segment
		(start 286.42183 -56.695086)
		(end 286.41548 -56.684418)
		(width 0.0889)
		(layer "In2.Cu")
		(net "M_A_DQ<57>")
	)
	(segment
		(start 298.928282 -43.0276)
		(end 299.083222 -42.87266)
		(width 0.14224)
		(layer "In2.Cu")
		(net "M_A_DQ<57>")
	)
	(segment
		(start 310.122062 -22.279356)
		(end 310.496204 -21.905214)
		(width 0.14224)
		(layer "In2.Cu")
		(net "M_A_DQ<57>")
	)
	(segment
		(start 310.282844 -17.7038)
		(end 309.927244 -17.7038)
		(width 0.14224)
		(layer "In2.Cu")
		(net "M_A_DQ<57>")
	)
	(segment
		(start 296.723054 -43.0276)
		(end 297.602402 -43.0276)
		(width 0.14224)
		(layer "In2.Cu")
		(net "M_A_DQ<57>")
	)
	(segment
		(start 309.974996 -24.749506)
		(end 309.974996 -23.437596)
		(width 0.14224)
		(layer "In2.Cu")
		(net "M_A_DQ<57>")
	)
	(segment
		(start 309.931054 -35.8902)
		(end 310.6928 -35.128454)
		(width 0.14224)
		(layer "In2.Cu")
		(net "M_A_DQ<57>")
	)
	(segment
		(start 286.405066 -57.123838)
		(end 286.42183 -57.095136)
		(width 0.0889)
		(layer "In2.Cu")
		(net "M_A_DQ<57>")
	)
	(segment
		(start 286.220662 -55.531512)
		(end 286.096964 -55.479442)
		(width 0.0889)
		(layer "In2.Cu")
		(net "M_A_DQ<57>")
	)
	(segment
		(start 309.927244 -17.7038)
		(end 309.449978 -17.226534)
		(width 0.14224)
		(layer "In2.Cu")
		(net "M_A_DQ<57>")
	)
	(segment
		(start 286.530542 -52.883308)
		(end 286.530542 -52.194206)
		(width 0.0889)
		(layer "In2.Cu")
		(net "M_A_DQ<57>")
	)
	(segment
		(start 310.496204 -18.571464)
		(end 310.652668 -18.415)
		(width 0.14224)
		(layer "In2.Cu")
		(net "M_A_DQ<57>")
	)
	(segment
		(start 299.746162 -42.54754)
		(end 299.746162 -42.87266)
		(width 0.14224)
		(layer "In2.Cu")
		(net "M_A_DQ<57>")
	)
	(segment
		(start 285.775146 -55.194962)
		(end 285.72841 -55.113936)
		(width 0.0889)
		(layer "In2.Cu")
		(net "M_A_DQ<57>")
	)
	(segment
		(start 293.841678 -45.908976)
		(end 296.723054 -43.0276)
		(width 0.14224)
		(layer "In2.Cu")
		(net "M_A_DQ<57>")
	)
	(segment
		(start 298.265342 -42.3926)
		(end 298.420282 -42.54754)
		(width 0.14224)
		(layer "In2.Cu")
		(net "M_A_DQ<57>")
	)
	(segment
		(start 299.746162 -42.87266)
		(end 299.901102 -43.0276)
		(width 0.14224)
		(layer "In2.Cu")
		(net "M_A_DQ<57>")
	)
	(segment
		(start 299.083222 -42.54754)
		(end 299.238162 -42.3926)
		(width 0.14224)
		(layer "In2.Cu")
		(net "M_A_DQ<57>")
	)
	(segment
		(start 297.602402 -43.0276)
		(end 297.757342 -42.87266)
		(width 0.14224)
		(layer "In2.Cu")
		(net "M_A_DQ<57>")
	)
	(segment
		(start 286.426656 -56.703722)
		(end 286.42183 -56.695086)
		(width 0.0889)
		(layer "In2.Cu")
		(net "M_A_DQ<57>")
	)
	(segment
		(start 299.238162 -42.3926)
		(end 299.591222 -42.3926)
		(width 0.14224)
		(layer "In2.Cu")
		(net "M_A_DQ<57>")
	)
	(segment
		(start 298.420282 -42.54754)
		(end 298.420282 -42.87266)
		(width 0.14224)
		(layer "In2.Cu")
		(net "M_A_DQ<57>")
	)
	(segment
		(start 309.449978 -17.226534)
		(end 309.449978 -16.687546)
		(width 0.14224)
		(layer "In2.Cu")
		(net "M_A_DQ<57>")
	)
	(segment
		(start 299.901102 -43.0276)
		(end 301.2948 -43.0276)
		(width 0.14224)
		(layer "In2.Cu")
		(net "M_A_DQ<57>")
	)
	(segment
		(start 310.6928 -25.46731)
		(end 309.974996 -24.749506)
		(width 0.14224)
		(layer "In2.Cu")
		(net "M_A_DQ<57>")
	)
	(segment
		(start 310.6928 -35.128454)
		(end 310.6928 -25.46731)
		(width 0.14224)
		(layer "In2.Cu")
		(net "M_A_DQ<57>")
	)
	(segment
		(start 297.757342 -42.87266)
		(end 297.757342 -42.54754)
		(width 0.14224)
		(layer "In2.Cu")
		(net "M_A_DQ<57>")
	)
	(segment
		(start 288.1884 -50.536348)
		(end 288.1884 -50.5206)
		(width 0.14224)
		(layer "In2.Cu")
		(net "M_A_DQ<57>")
	)
	(segment
		(start 285.723584 -54.722522)
		(end 285.72841 -54.713886)
		(width 0.0889)
		(layer "In2.Cu")
		(net "M_A_DQ<57>")
	)
	(segment
		(start 297.912282 -42.3926)
		(end 298.265342 -42.3926)
		(width 0.14224)
		(layer "In2.Cu")
		(net "M_A_DQ<57>")
	)
	(segment
		(start 297.757342 -42.54754)
		(end 297.912282 -42.3926)
		(width 0.14224)
		(layer "In2.Cu")
		(net "M_A_DQ<57>")
	)
	(segment
		(start 309.974996 -23.437596)
		(end 309.619396 -23.081996)
		(width 0.14224)
		(layer "In2.Cu")
		(net "M_A_DQ<57>")
	)
	(segment
		(start 298.575222 -43.0276)
		(end 298.928282 -43.0276)
		(width 0.14224)
		(layer "In2.Cu")
		(net "M_A_DQ<57>")
	)
	(segment
		(start 299.083222 -42.87266)
		(end 299.083222 -42.54754)
		(width 0.14224)
		(layer "In2.Cu")
		(net "M_A_DQ<57>")
	)
	(segment
		(start 285.72841 -54.123336)
		(end 285.6611 -53.99278)
		(width 0.0889)
		(layer "In2.Cu")
		(net "M_A_DQ<57>")
	)
	(segment
		(start 309.619396 -23.081996)
		(end 309.619396 -22.782022)
		(width 0.14224)
		(layer "In2.Cu")
		(net "M_A_DQ<57>")
	)
	(segment
		(start 310.652668 -18.415)
		(end 310.652668 -18.073624)
		(width 0.14224)
		(layer "In2.Cu")
		(net "M_A_DQ<57>")
	)
	(segment
		(start 286.096964 -55.479442)
		(end 285.913576 -55.343806)
		(width 0.0889)
		(layer "In2.Cu")
		(net "M_A_DQ<57>")
	)
	(arc
		(start 286.41548 -56.684418)
		(mid 286.342682 -56.393655)
		(end 286.42183 -56.104536)
		(width 0.0889)
		(layer "In2.Cu")
		(net "M_A_DQ<57>")
	)
	(arc
		(start 285.72841 -55.113936)
		(mid 285.67494 -54.918873)
		(end 285.723584 -54.722522)
		(width 0.0889)
		(layer "In2.Cu")
		(net "M_A_DQ<57>")
	)
	(arc
		(start 285.73476 -54.703218)
		(mid 285.807558 -54.412455)
		(end 285.72841 -54.123336)
		(width 0.0889)
		(layer "In2.Cu")
		(net "M_A_DQ<57>")
	)
	(arc
		(start 286.42183 -56.104536)
		(mid 286.452864 -55.771802)
		(end 286.220662 -55.531512)
		(width 0.0889)
		(layer "In2.Cu")
		(net "M_A_DQ<57>")
	)
	(arc
		(start 286.42183 -57.095136)
		(mid 286.4753 -56.900073)
		(end 286.426656 -56.703722)
		(width 0.0889)
		(layer "In2.Cu")
		(net "M_A_DQ<57>")
	)
	(segment
		(start 310.30037 -20.023582)
		(end 310.299862 -20.023582)
		(width 0.1651)
		(layer "F.Cu")
		(net "M_A_DQ<56>")
	)
	(segment
		(start 286.64662 -55.904384)
		(end 286.07512 -55.904384)
		(width 0.1016)
		(layer "F.Cu")
		(net "M_A_DQ<56>")
	)
	(segment
		(start 310.21909 -19.177)
		(end 310.122062 -18.161)
		(width 0.1651)
		(layer "F.Cu")
		(net "M_A_DQ<56>")
	)
	(segment
		(start 310.299862 -20.023582)
		(end 310.21909 -19.177)
		(width 0.1651)
		(layer "F.Cu")
		(net "M_A_DQ<56>")
	)
	(via
		(at 309.449978 -23.560278)
		(size 0.508)
		(drill 0.254)
		(layers "F.Cu" "B.Cu")
		(net "M_A_DQ<56>")
	)
	(via
		(at 310.122062 -18.161)
		(size 0.508)
		(drill 0.254)
		(layers "F.Cu" "B.Cu")
		(net "M_A_DQ<56>")
	)
	(via
		(at 286.07512 -55.904384)
		(size 0.508)
		(drill 0.254)
		(layers "F.Cu" "B.Cu")
		(net "M_A_DQ<56>")
	)
	(segment
		(start 309.450486 -24.824182)
		(end 309.449978 -24.824182)
		(width 0.1651)
		(layer "B.Cu")
		(net "M_A_DQ<56>")
	)
	(segment
		(start 309.449978 -24.824182)
		(end 309.449978 -23.560278)
		(width 0.1651)
		(layer "B.Cu")
		(net "M_A_DQ<56>")
	)
	(segment
		(start 309.487062 -19.7104)
		(end 309.487062 -19.380454)
		(width 0.14224)
		(layer "In2.Cu")
		(net "M_A_DQ<56>")
	)
	(segment
		(start 309.512462 -20.5994)
		(end 309.829962 -20.2819)
		(width 0.14224)
		(layer "In2.Cu")
		(net "M_A_DQ<56>")
	)
	(segment
		(start 285.625032 -55.317644)
		(end 285.56331 -55.209186)
		(width 0.0889)
		(layer "In2.Cu")
		(net "M_A_DQ<56>")
	)
	(segment
		(start 310.0578 -30.193488)
		(end 309.670196 -29.805884)
		(width 0.14224)
		(layer "In2.Cu")
		(net "M_A_DQ<56>")
	)
	(segment
		(start 289.16884 -46.817534)
		(end 289.69716 -46.817534)
		(width 0.14224)
		(layer "In2.Cu")
		(net "M_A_DQ<56>")
	)
	(segment
		(start 286.07512 -55.904384)
		(end 286.059626 -55.902098)
		(width 0.0889)
		(layer "In2.Cu")
		(net "M_A_DQ<56>")
	)
	(segment
		(start 289.0266 -48.382936)
		(end 289.18154 -48.227996)
		(width 0.14224)
		(layer "In2.Cu")
		(net "M_A_DQ<56>")
	)
	(segment
		(start 310.0578 -30.517084)
		(end 310.0578 -30.193488)
		(width 0.14224)
		(layer "In2.Cu")
		(net "M_A_DQ<56>")
	)
	(segment
		(start 289.58286 -48.227996)
		(end 289.7378 -48.073056)
		(width 0.14224)
		(layer "In2.Cu")
		(net "M_A_DQ<56>")
	)
	(segment
		(start 309.512462 -20.903946)
		(end 309.512462 -20.5994)
		(width 0.14224)
		(layer "In2.Cu")
		(net "M_A_DQ<56>")
	)
	(segment
		(start 310.0578 -27.348688)
		(end 309.670196 -26.961084)
		(width 0.14224)
		(layer "In2.Cu")
		(net "M_A_DQ<56>")
	)
	(segment
		(start 310.0578 -29.094684)
		(end 310.0578 -28.771088)
		(width 0.14224)
		(layer "In2.Cu")
		(net "M_A_DQ<56>")
	)
	(segment
		(start 289.0266 -48.971454)
		(end 289.0266 -48.382936)
		(width 0.14224)
		(layer "In2.Cu")
		(net "M_A_DQ<56>")
	)
	(segment
		(start 309.217568 -24.864314)
		(end 309.217568 -23.792688)
		(width 0.14224)
		(layer "In2.Cu")
		(net "M_A_DQ<56>")
	)
	(segment
		(start 289.0266 -47.410116)
		(end 289.0266 -46.959774)
		(width 0.14224)
		(layer "In2.Cu")
		(net "M_A_DQ<56>")
	)
	(segment
		(start 289.69716 -46.167294)
		(end 289.16884 -46.167294)
		(width 0.14224)
		(layer "In2.Cu")
		(net "M_A_DQ<56>")
	)
	(segment
		(start 309.829962 -20.2819)
		(end 309.829962 -20.0533)
		(width 0.14224)
		(layer "In2.Cu")
		(net "M_A_DQ<56>")
	)
	(segment
		(start 289.367214 -45.430186)
		(end 293.431468 -45.430186)
		(width 0.14224)
		(layer "In2.Cu")
		(net "M_A_DQ<56>")
	)
	(segment
		(start 289.7378 -47.719996)
		(end 289.58286 -47.565056)
		(width 0.14224)
		(layer "In2.Cu")
		(net "M_A_DQ<56>")
	)
	(segment
		(start 310.0578 -25.926288)
		(end 309.670196 -25.538684)
		(width 0.14224)
		(layer "In2.Cu")
		(net "M_A_DQ<56>")
	)
	(segment
		(start 309.829962 -20.0533)
		(end 309.487062 -19.7104)
		(width 0.14224)
		(layer "In2.Cu")
		(net "M_A_DQ<56>")
	)
	(segment
		(start 285.55696 -54.629304)
		(end 285.56331 -54.618636)
		(width 0.0889)
		(layer "In2.Cu")
		(net "M_A_DQ<56>")
	)
	(segment
		(start 285.4706 -54.039008)
		(end 285.4706 -53.673502)
		(width 0.0889)
		(layer "In2.Cu")
		(net "M_A_DQ<56>")
	)
	(segment
		(start 286.340042 -52.80406)
		(end 286.340042 -52.114196)
		(width 0.0889)
		(layer "In2.Cu")
		(net "M_A_DQ<56>")
	)
	(segment
		(start 309.165244 -23.275544)
		(end 309.165244 -22.5298)
		(width 0.14224)
		(layer "In2.Cu")
		(net "M_A_DQ<56>")
	)
	(segment
		(start 289.18154 -47.565056)
		(end 289.0266 -47.410116)
		(width 0.14224)
		(layer "In2.Cu")
		(net "M_A_DQ<56>")
	)
	(segment
		(start 309.670196 -30.904688)
		(end 310.0578 -30.517084)
		(width 0.14224)
		(layer "In2.Cu")
		(net "M_A_DQ<56>")
	)
	(segment
		(start 309.670196 -32.327088)
		(end 310.0578 -31.939484)
		(width 0.14224)
		(layer "In2.Cu")
		(net "M_A_DQ<56>")
	)
	(segment
		(start 310.0578 -26.249884)
		(end 310.0578 -25.926288)
		(width 0.14224)
		(layer "In2.Cu")
		(net "M_A_DQ<56>")
	)
	(segment
		(start 309.901844 -18.381218)
		(end 310.122062 -18.161)
		(width 0.14224)
		(layer "In2.Cu")
		(net "M_A_DQ<56>")
	)
	(segment
		(start 309.217568 -23.792688)
		(end 309.449978 -23.560278)
		(width 0.14224)
		(layer "In2.Cu")
		(net "M_A_DQ<56>")
	)
	(segment
		(start 310.0578 -34.460688)
		(end 309.670196 -34.073084)
		(width 0.14224)
		(layer "In2.Cu")
		(net "M_A_DQ<56>")
	)
	(segment
		(start 309.670196 -25.538684)
		(end 309.670196 -25.316942)
		(width 0.14224)
		(layer "In2.Cu")
		(net "M_A_DQ<56>")
	)
	(segment
		(start 297.129454 -41.7322)
		(end 301.371254 -41.7322)
		(width 0.14224)
		(layer "In2.Cu")
		(net "M_A_DQ<56>")
	)
	(segment
		(start 309.901844 -18.965672)
		(end 309.901844 -18.381218)
		(width 0.14224)
		(layer "In2.Cu")
		(net "M_A_DQ<56>")
	)
	(segment
		(start 289.0266 -46.025054)
		(end 289.0266 -45.7708)
		(width 0.14224)
		(layer "In2.Cu")
		(net "M_A_DQ<56>")
	)
	(segment
		(start 293.431468 -45.430186)
		(end 297.129454 -41.7322)
		(width 0.14224)
		(layer "In2.Cu")
		(net "M_A_DQ<56>")
	)
	(segment
		(start 309.670196 -34.073084)
		(end 309.670196 -33.749488)
		(width 0.14224)
		(layer "In2.Cu")
		(net "M_A_DQ<56>")
	)
	(segment
		(start 309.449978 -23.560278)
		(end 309.165244 -23.275544)
		(width 0.14224)
		(layer "In2.Cu")
		(net "M_A_DQ<56>")
	)
	(segment
		(start 309.165244 -22.5298)
		(end 309.901844 -21.7932)
		(width 0.14224)
		(layer "In2.Cu")
		(net "M_A_DQ<56>")
	)
	(segment
		(start 310.0578 -28.771088)
		(end 309.670196 -28.383484)
		(width 0.14224)
		(layer "In2.Cu")
		(net "M_A_DQ<56>")
	)
	(segment
		(start 309.901844 -21.7932)
		(end 309.901844 -21.293328)
		(width 0.14224)
		(layer "In2.Cu")
		(net "M_A_DQ<56>")
	)
	(segment
		(start 309.670196 -25.316942)
		(end 309.217568 -24.864314)
		(width 0.14224)
		(layer "In2.Cu")
		(net "M_A_DQ<56>")
	)
	(segment
		(start 309.901844 -21.293328)
		(end 309.512462 -20.903946)
		(width 0.14224)
		(layer "In2.Cu")
		(net "M_A_DQ<56>")
	)
	(segment
		(start 301.371254 -41.7322)
		(end 307.931566 -35.171888)
		(width 0.14224)
		(layer "In2.Cu")
		(net "M_A_DQ<56>")
	)
	(segment
		(start 287.782 -50.216054)
		(end 289.0266 -48.971454)
		(width 0.14224)
		(layer "In2.Cu")
		(net "M_A_DQ<56>")
	)
	(segment
		(start 309.670196 -26.961084)
		(end 309.670196 -26.637488)
		(width 0.14224)
		(layer "In2.Cu")
		(net "M_A_DQ<56>")
	)
	(segment
		(start 309.670196 -35.171888)
		(end 310.0578 -34.784284)
		(width 0.14224)
		(layer "In2.Cu")
		(net "M_A_DQ<56>")
	)
	(segment
		(start 310.0578 -33.361884)
		(end 310.0578 -33.038288)
		(width 0.14224)
		(layer "In2.Cu")
		(net "M_A_DQ<56>")
	)
	(segment
		(start 310.0578 -34.784284)
		(end 310.0578 -34.460688)
		(width 0.14224)
		(layer "In2.Cu")
		(net "M_A_DQ<56>")
	)
	(segment
		(start 310.0578 -33.038288)
		(end 309.670196 -32.650684)
		(width 0.14224)
		(layer "In2.Cu")
		(net "M_A_DQ<56>")
	)
	(segment
		(start 309.670196 -33.749488)
		(end 310.0578 -33.361884)
		(width 0.14224)
		(layer "In2.Cu")
		(net "M_A_DQ<56>")
	)
	(segment
		(start 309.487062 -19.380454)
		(end 309.901844 -18.965672)
		(width 0.14224)
		(layer "In2.Cu")
		(net "M_A_DQ<56>")
	)
	(segment
		(start 289.18154 -48.227996)
		(end 289.58286 -48.227996)
		(width 0.14224)
		(layer "In2.Cu")
		(net "M_A_DQ<56>")
	)
	(segment
		(start 287.782 -50.672238)
		(end 287.782 -50.216054)
		(width 0.0889)
		(layer "In2.Cu")
		(net "M_A_DQ<56>")
	)
	(segment
		(start 286.340042 -52.114196)
		(end 287.782 -50.672238)
		(width 0.0889)
		(layer "In2.Cu")
		(net "M_A_DQ<56>")
	)
	(segment
		(start 309.670196 -28.059888)
		(end 310.0578 -27.672284)
		(width 0.14224)
		(layer "In2.Cu")
		(net "M_A_DQ<56>")
	)
	(segment
		(start 289.0266 -45.7708)
		(end 289.367214 -45.430186)
		(width 0.14224)
		(layer "In2.Cu")
		(net "M_A_DQ<56>")
	)
	(segment
		(start 310.0578 -31.939484)
		(end 310.0578 -31.615888)
		(width 0.14224)
		(layer "In2.Cu")
		(net "M_A_DQ<56>")
	)
	(segment
		(start 307.931566 -35.171888)
		(end 309.670196 -35.171888)
		(width 0.14224)
		(layer "In2.Cu")
		(net "M_A_DQ<56>")
	)
	(segment
		(start 309.670196 -32.650684)
		(end 309.670196 -32.327088)
		(width 0.14224)
		(layer "In2.Cu")
		(net "M_A_DQ<56>")
	)
	(segment
		(start 289.16884 -46.167294)
		(end 289.0266 -46.025054)
		(width 0.14224)
		(layer "In2.Cu")
		(net "M_A_DQ<56>")
	)
	(segment
		(start 310.0578 -31.615888)
		(end 309.670196 -31.228284)
		(width 0.14224)
		(layer "In2.Cu")
		(net "M_A_DQ<56>")
	)
	(segment
		(start 285.56331 -54.218586)
		(end 285.4706 -54.039008)
		(width 0.0889)
		(layer "In2.Cu")
		(net "M_A_DQ<56>")
	)
	(segment
		(start 285.56331 -54.618636)
		(end 285.568136 -54.61)
		(width 0.0889)
		(layer "In2.Cu")
		(net "M_A_DQ<56>")
	)
	(segment
		(start 289.69716 -46.817534)
		(end 289.8394 -46.675294)
		(width 0.14224)
		(layer "In2.Cu")
		(net "M_A_DQ<56>")
	)
	(segment
		(start 309.670196 -28.383484)
		(end 309.670196 -28.059888)
		(width 0.14224)
		(layer "In2.Cu")
		(net "M_A_DQ<56>")
	)
	(segment
		(start 309.670196 -26.637488)
		(end 310.0578 -26.249884)
		(width 0.14224)
		(layer "In2.Cu")
		(net "M_A_DQ<56>")
	)
	(segment
		(start 285.4706 -53.673502)
		(end 286.340042 -52.80406)
		(width 0.0889)
		(layer "In2.Cu")
		(net "M_A_DQ<56>")
	)
	(segment
		(start 289.8394 -46.309534)
		(end 289.69716 -46.167294)
		(width 0.14224)
		(layer "In2.Cu")
		(net "M_A_DQ<56>")
	)
	(segment
		(start 289.8394 -46.675294)
		(end 289.8394 -46.309534)
		(width 0.14224)
		(layer "In2.Cu")
		(net "M_A_DQ<56>")
	)
	(segment
		(start 309.670196 -29.482288)
		(end 310.0578 -29.094684)
		(width 0.14224)
		(layer "In2.Cu")
		(net "M_A_DQ<56>")
	)
	(segment
		(start 309.670196 -29.805884)
		(end 309.670196 -29.482288)
		(width 0.14224)
		(layer "In2.Cu")
		(net "M_A_DQ<56>")
	)
	(segment
		(start 310.0578 -27.672284)
		(end 310.0578 -27.348688)
		(width 0.14224)
		(layer "In2.Cu")
		(net "M_A_DQ<56>")
	)
	(segment
		(start 309.670196 -31.228284)
		(end 309.670196 -30.904688)
		(width 0.14224)
		(layer "In2.Cu")
		(net "M_A_DQ<56>")
	)
	(segment
		(start 289.7378 -48.073056)
		(end 289.7378 -47.719996)
		(width 0.14224)
		(layer "In2.Cu")
		(net "M_A_DQ<56>")
	)
	(segment
		(start 289.58286 -47.565056)
		(end 289.18154 -47.565056)
		(width 0.14224)
		(layer "In2.Cu")
		(net "M_A_DQ<56>")
	)
	(segment
		(start 289.0266 -46.959774)
		(end 289.16884 -46.817534)
		(width 0.14224)
		(layer "In2.Cu")
		(net "M_A_DQ<56>")
	)
	(segment
		(start 286.059626 -55.902098)
		(end 285.625032 -55.317644)
		(width 0.0889)
		(layer "In2.Cu")
		(net "M_A_DQ<56>")
	)
	(arc
		(start 285.56331 -55.209186)
		(mid 285.484088 -54.920068)
		(end 285.55696 -54.629304)
		(width 0.0889)
		(layer "In2.Cu")
		(net "M_A_DQ<56>")
	)
	(arc
		(start 285.568136 -54.61)
		(mid 285.616891 -54.413648)
		(end 285.56331 -54.218586)
		(width 0.0889)
		(layer "In2.Cu")
		(net "M_A_DQ<56>")
	)
	(segment
		(start 304.349912 -15.423642)
		(end 304.349912 -16.687546)
		(width 0.1651)
		(layer "F.Cu")
		(net "M_A_DQ<55>")
	)
	(segment
		(start 283.212794 -57.885584)
		(end 282.641294 -57.885584)
		(width 0.1016)
		(layer "F.Cu")
		(net "M_A_DQ<55>")
	)
	(segment
		(start 304.35042 -15.423642)
		(end 304.349912 -15.423642)
		(width 0.1651)
		(layer "F.Cu")
		(net "M_A_DQ<55>")
	)
	(via
		(at 282.641294 -57.885584)
		(size 0.508)
		(drill 0.254)
		(layers "F.Cu" "B.Cu")
		(net "M_A_DQ<55>")
	)
	(via
		(at 305.199796 -22.279356)
		(size 0.508)
		(drill 0.254)
		(layers "F.Cu" "B.Cu")
		(net "M_A_DQ<55>")
	)
	(via
		(at 304.349912 -16.687546)
		(size 0.508)
		(drill 0.254)
		(layers "F.Cu" "B.Cu")
		(net "M_A_DQ<55>")
	)
	(segment
		(start 305.200304 -20.224242)
		(end 305.199796 -20.224242)
		(width 0.1651)
		(layer "B.Cu")
		(net "M_A_DQ<55>")
	)
	(segment
		(start 305.199796 -20.224242)
		(end 305.199796 -22.279356)
		(width 0.1651)
		(layer "B.Cu")
		(net "M_A_DQ<55>")
	)
	(segment
		(start 283.099764 -53.368702)
		(end 283.099764 -51.662838)
		(width 0.0889)
		(layer "In2.Cu")
		(net "M_A_DQ<55>")
	)
	(segment
		(start 283.767022 -48.658526)
		(end 284.014164 -48.411384)
		(width 0.0889)
		(layer "In2.Cu")
		(net "M_A_DQ<55>")
	)
	(segment
		(start 305.054 -24.546052)
		(end 304.8508 -24.342852)
		(width 0.14224)
		(layer "In2.Cu")
		(net "M_A_DQ<55>")
	)
	(segment
		(start 305.656996 -28.238196)
		(end 305.656996 -26.790396)
		(width 0.14224)
		(layer "In2.Cu")
		(net "M_A_DQ<55>")
	)
	(segment
		(start 282.641294 -57.885584)
		(end 282.988004 -57.095136)
		(width 0.0889)
		(layer "In2.Cu")
		(net "M_A_DQ<55>")
	)
	(segment
		(start 304.8508 -23.3934)
		(end 304.7238 -23.2664)
		(width 0.14224)
		(layer "In2.Cu")
		(net "M_A_DQ<55>")
	)
	(segment
		(start 305.199796 -22.279356)
		(end 305.552602 -21.92655)
		(width 0.14224)
		(layer "In2.Cu")
		(net "M_A_DQ<55>")
	)
	(segment
		(start 305.656996 -26.790396)
		(end 305.529996 -26.663396)
		(width 0.14224)
		(layer "In2.Cu")
		(net "M_A_DQ<55>")
	)
	(segment
		(start 305.529996 -24.749252)
		(end 305.326796 -24.546052)
		(width 0.14224)
		(layer "In2.Cu")
		(net "M_A_DQ<55>")
	)
	(segment
		(start 305.552602 -21.92655)
		(end 305.552602 -18.621248)
		(width 0.14224)
		(layer "In2.Cu")
		(net "M_A_DQ<55>")
	)
	(segment
		(start 304.8508 -24.342852)
		(end 304.8508 -23.3934)
		(width 0.14224)
		(layer "In2.Cu")
		(net "M_A_DQ<55>")
	)
	(segment
		(start 305.555396 -28.339796)
		(end 305.656996 -28.238196)
		(width 0.14224)
		(layer "In2.Cu")
		(net "M_A_DQ<55>")
	)
	(segment
		(start 305.70805 -18.4658)
		(end 305.70805 -18.1102)
		(width 0.14224)
		(layer "In2.Cu")
		(net "M_A_DQ<55>")
	)
	(segment
		(start 305.529996 -26.663396)
		(end 305.529996 -24.749252)
		(width 0.14224)
		(layer "In2.Cu")
		(net "M_A_DQ<55>")
	)
	(segment
		(start 283.099764 -51.662838)
		(end 283.767022 -50.99558)
		(width 0.0889)
		(layer "In2.Cu")
		(net "M_A_DQ<55>")
	)
	(segment
		(start 283.767022 -50.99558)
		(end 283.767022 -48.658526)
		(width 0.0889)
		(layer "In2.Cu")
		(net "M_A_DQ<55>")
	)
	(segment
		(start 304.7238 -23.2664)
		(end 304.7238 -22.755352)
		(width 0.14224)
		(layer "In2.Cu")
		(net "M_A_DQ<55>")
	)
	(segment
		(start 305.250596 -29.165804)
		(end 305.555396 -28.861004)
		(width 0.14224)
		(layer "In2.Cu")
		(net "M_A_DQ<55>")
	)
	(segment
		(start 283.232352 -54.913784)
		(end 283.232352 -53.50129)
		(width 0.0889)
		(layer "In2.Cu")
		(net "M_A_DQ<55>")
	)
	(segment
		(start 305.250596 -31.883604)
		(end 305.250596 -29.165804)
		(width 0.14224)
		(layer "In2.Cu")
		(net "M_A_DQ<55>")
	)
	(segment
		(start 305.70805 -18.1102)
		(end 305.25085 -17.653)
		(width 0.14224)
		(layer "In2.Cu")
		(net "M_A_DQ<55>")
	)
	(segment
		(start 305.552602 -18.621248)
		(end 305.70805 -18.4658)
		(width 0.14224)
		(layer "In2.Cu")
		(net "M_A_DQ<55>")
	)
	(segment
		(start 305.25085 -17.653)
		(end 304.99685 -17.653)
		(width 0.14224)
		(layer "In2.Cu")
		(net "M_A_DQ<55>")
	)
	(segment
		(start 305.326796 -24.546052)
		(end 305.054 -24.546052)
		(width 0.14224)
		(layer "In2.Cu")
		(net "M_A_DQ<55>")
	)
	(segment
		(start 290.0426 -38.0746)
		(end 299.0596 -38.0746)
		(width 0.14224)
		(layer "In2.Cu")
		(net "M_A_DQ<55>")
	)
	(segment
		(start 283.232352 -53.50129)
		(end 283.099764 -53.368702)
		(width 0.0889)
		(layer "In2.Cu")
		(net "M_A_DQ<55>")
	)
	(segment
		(start 305.555396 -28.861004)
		(end 305.555396 -28.339796)
		(width 0.14224)
		(layer "In2.Cu")
		(net "M_A_DQ<55>")
	)
	(segment
		(start 304.349912 -17.006062)
		(end 304.349912 -16.687546)
		(width 0.14224)
		(layer "In2.Cu")
		(net "M_A_DQ<55>")
	)
	(segment
		(start 284.014164 -48.411384)
		(end 284.014164 -44.103036)
		(width 0.14224)
		(layer "In2.Cu")
		(net "M_A_DQ<55>")
	)
	(segment
		(start 304.7238 -22.755352)
		(end 305.199796 -22.279356)
		(width 0.14224)
		(layer "In2.Cu")
		(net "M_A_DQ<55>")
	)
	(segment
		(start 284.014164 -44.103036)
		(end 290.0426 -38.0746)
		(width 0.14224)
		(layer "In2.Cu")
		(net "M_A_DQ<55>")
	)
	(segment
		(start 304.99685 -17.653)
		(end 304.349912 -17.006062)
		(width 0.14224)
		(layer "In2.Cu")
		(net "M_A_DQ<55>")
	)
	(segment
		(start 299.0596 -38.0746)
		(end 305.250596 -31.883604)
		(width 0.14224)
		(layer "In2.Cu")
		(net "M_A_DQ<55>")
	)
	(arc
		(start 283.1719 -55.173626)
		(mid 283.216923 -55.047148)
		(end 283.232352 -54.913784)
		(width 0.0889)
		(layer "In2.Cu")
		(net "M_A_DQ<55>")
	)
	(arc
		(start 283.153104 -55.20944)
		(mid 283.162857 -55.191719)
		(end 283.1719 -55.173626)
		(width 0.0889)
		(layer "In2.Cu")
		(net "M_A_DQ<55>")
	)
	(arc
		(start 283.035502 -56.826658)
		(mid 283.040833 -56.503312)
		(end 283.153104 -56.20004)
		(width 0.0889)
		(layer "In2.Cu")
		(net "M_A_DQ<55>")
	)
	(arc
		(start 283.153104 -56.20004)
		(mid 283.232235 -55.904638)
		(end 283.153104 -55.609236)
		(width 0.0889)
		(layer "In2.Cu")
		(net "M_A_DQ<55>")
	)
	(arc
		(start 283.153104 -55.609236)
		(mid 283.099605 -55.409338)
		(end 283.153104 -55.20944)
		(width 0.0889)
		(layer "In2.Cu")
		(net "M_A_DQ<55>")
	)
	(arc
		(start 282.988004 -57.095136)
		(mid 283.035364 -56.965067)
		(end 283.035502 -56.826658)
		(width 0.0889)
		(layer "In2.Cu")
		(net "M_A_DQ<55>")
	)
	(segment
		(start 283.212794 -55.904384)
		(end 282.641294 -55.904384)
		(width 0.1016)
		(layer "F.Cu")
		(net "M_A_DQ<54>")
	)
	(segment
		(start 305.20005 -20.023328)
		(end 305.200304 -20.023582)
		(width 0.1651)
		(layer "F.Cu")
		(net "M_A_DQ<54>")
	)
	(segment
		(start 305.20005 -18.262854)
		(end 305.20005 -18.5674)
		(width 0.1651)
		(layer "F.Cu")
		(net "M_A_DQ<54>")
	)
	(segment
		(start 305.199796 -18.2626)
		(end 305.20005 -18.262854)
		(width 0.1651)
		(layer "F.Cu")
		(net "M_A_DQ<54>")
	)
	(segment
		(start 305.20005 -19.05)
		(end 305.20005 -20.023328)
		(width 0.1651)
		(layer "F.Cu")
		(net "M_A_DQ<54>")
	)
	(segment
		(start 305.33213 -18.91792)
		(end 305.20005 -19.05)
		(width 0.1651)
		(layer "F.Cu")
		(net "M_A_DQ<54>")
	)
	(segment
		(start 305.33213 -18.69948)
		(end 305.33213 -18.91792)
		(width 0.1651)
		(layer "F.Cu")
		(net "M_A_DQ<54>")
	)
	(segment
		(start 305.20005 -18.5674)
		(end 305.33213 -18.69948)
		(width 0.1651)
		(layer "F.Cu")
		(net "M_A_DQ<54>")
	)
	(via
		(at 305.199796 -18.2626)
		(size 0.508)
		(drill 0.254)
		(layers "F.Cu" "B.Cu")
		(net "M_A_DQ<54>")
	)
	(via
		(at 304.349912 -23.560278)
		(size 0.508)
		(drill 0.254)
		(layers "F.Cu" "B.Cu")
		(net "M_A_DQ<54>")
	)
	(via
		(at 282.641294 -55.904384)
		(size 0.508)
		(drill 0.254)
		(layers "F.Cu" "B.Cu")
		(net "M_A_DQ<54>")
	)
	(segment
		(start 304.349912 -24.824182)
		(end 304.349912 -23.560278)
		(width 0.1651)
		(layer "B.Cu")
		(net "M_A_DQ<54>")
	)
	(segment
		(start 304.35042 -24.824182)
		(end 304.349912 -24.824182)
		(width 0.1651)
		(layer "B.Cu")
		(net "M_A_DQ<54>")
	)
	(segment
		(start 304.461418 -20.980146)
		(end 304.461418 -20.694904)
		(width 0.14224)
		(layer "In2.Cu")
		(net "M_A_DQ<54>")
	)
	(segment
		(start 283.366464 -48.411384)
		(end 283.366464 -44.064936)
		(width 0.14224)
		(layer "In2.Cu")
		(net "M_A_DQ<54>")
	)
	(segment
		(start 304.461418 -20.694904)
		(end 304.842418 -20.313904)
		(width 0.14224)
		(layer "In2.Cu")
		(net "M_A_DQ<54>")
	)
	(segment
		(start 304.88636 -28.7782)
		(end 304.88636 -28.40736)
		(width 0.14224)
		(layer "In2.Cu")
		(net "M_A_DQ<54>")
	)
	(segment
		(start 304.807112 -25.280366)
		(end 303.862232 -24.335486)
		(width 0.14224)
		(layer "In2.Cu")
		(net "M_A_DQ<54>")
	)
	(segment
		(start 300.990762 -34.390584)
		(end 301.240698 -34.140648)
		(width 0.14224)
		(layer "In2.Cu")
		(net "M_A_DQ<54>")
	)
	(segment
		(start 282.641294 -55.904384)
		(end 282.955746 -55.178452)
		(width 0.0889)
		(layer "In2.Cu")
		(net "M_A_DQ<54>")
	)
	(segment
		(start 282.90901 -51.576224)
		(end 283.576522 -50.908712)
		(width 0.0889)
		(layer "In2.Cu")
		(net "M_A_DQ<54>")
	)
	(segment
		(start 304.1142 -23.324566)
		(end 304.1142 -22.530054)
		(width 0.14224)
		(layer "In2.Cu")
		(net "M_A_DQ<54>")
	)
	(segment
		(start 303.862232 -24.047958)
		(end 304.302668 -23.607268)
		(width 0.14224)
		(layer "In2.Cu")
		(net "M_A_DQ<54>")
	)
	(segment
		(start 304.302668 -23.607268)
		(end 304.349912 -23.560278)
		(width 0.14224)
		(layer "In2.Cu")
		(net "M_A_DQ<54>")
	)
	(segment
		(start 304.8254 -18.636996)
		(end 305.199796 -18.2626)
		(width 0.14224)
		(layer "In2.Cu")
		(net "M_A_DQ<54>")
	)
	(segment
		(start 304.742596 -26.866596)
		(end 304.807112 -26.80208)
		(width 0.14224)
		(layer "In2.Cu")
		(net "M_A_DQ<54>")
	)
	(segment
		(start 303.862232 -24.335486)
		(end 303.862232 -24.047958)
		(width 0.14224)
		(layer "In2.Cu")
		(net "M_A_DQ<54>")
	)
	(segment
		(start 299.834808 -36.267136)
		(end 300.053756 -36.267136)
		(width 0.14224)
		(layer "In2.Cu")
		(net "M_A_DQ<54>")
	)
	(segment
		(start 302.028352 -34.140648)
		(end 302.4632 -33.7058)
		(width 0.14224)
		(layer "In2.Cu")
		(net "M_A_DQ<54>")
	)
	(segment
		(start 301.240698 -34.140648)
		(end 302.028352 -34.140648)
		(width 0.14224)
		(layer "In2.Cu")
		(net "M_A_DQ<54>")
	)
	(segment
		(start 299.115226 -36.26612)
		(end 299.365162 -36.016184)
		(width 0.14224)
		(layer "In2.Cu")
		(net "M_A_DQ<54>")
	)
	(segment
		(start 298.427394 -36.953952)
		(end 298.646342 -36.953952)
		(width 0.14224)
		(layer "In2.Cu")
		(net "M_A_DQ<54>")
	)
	(segment
		(start 300.76902 -35.325558)
		(end 300.970442 -35.325558)
		(width 0.14224)
		(layer "In2.Cu")
		(net "M_A_DQ<54>")
	)
	(segment
		(start 304.842418 -19.970496)
		(end 304.461418 -19.589496)
		(width 0.14224)
		(layer "In2.Cu")
		(net "M_A_DQ<54>")
	)
	(segment
		(start 301.237904 -35.058096)
		(end 301.237904 -34.856674)
		(width 0.14224)
		(layer "In2.Cu")
		(net "M_A_DQ<54>")
	)
	(segment
		(start 300.521878 -35.078416)
		(end 300.76902 -35.325558)
		(width 0.14224)
		(layer "In2.Cu")
		(net "M_A_DQ<54>")
	)
	(segment
		(start 304.615596 -30.76575)
		(end 304.615596 -29.048964)
		(width 0.14224)
		(layer "In2.Cu")
		(net "M_A_DQ<54>")
	)
	(segment
		(start 289.8648 -37.5666)
		(end 297.814746 -37.5666)
		(width 0.14224)
		(layer "In2.Cu")
		(net "M_A_DQ<54>")
	)
	(segment
		(start 300.30293 -35.078416)
		(end 300.521878 -35.078416)
		(width 0.14224)
		(layer "In2.Cu")
		(net "M_A_DQ<54>")
	)
	(segment
		(start 297.814746 -37.5666)
		(end 298.427394 -36.953952)
		(width 0.14224)
		(layer "In2.Cu")
		(net "M_A_DQ<54>")
	)
	(segment
		(start 283.041598 -53.603652)
		(end 282.90901 -53.471064)
		(width 0.0889)
		(layer "In2.Cu")
		(net "M_A_DQ<54>")
	)
	(segment
		(start 298.646342 -36.953952)
		(end 298.89704 -37.204904)
		(width 0.14224)
		(layer "In2.Cu")
		(net "M_A_DQ<54>")
	)
	(segment
		(start 304.8254 -18.914872)
		(end 304.8254 -18.636996)
		(width 0.14224)
		(layer "In2.Cu")
		(net "M_A_DQ<54>")
	)
	(segment
		(start 302.4632 -32.918146)
		(end 304.615596 -30.76575)
		(width 0.14224)
		(layer "In2.Cu")
		(net "M_A_DQ<54>")
	)
	(segment
		(start 283.576522 -48.621442)
		(end 283.366464 -48.411384)
		(width 0.0889)
		(layer "In2.Cu")
		(net "M_A_DQ<54>")
	)
	(segment
		(start 304.461418 -19.589496)
		(end 304.461418 -19.278854)
		(width 0.14224)
		(layer "In2.Cu")
		(net "M_A_DQ<54>")
	)
	(segment
		(start 304.886868 -21.405596)
		(end 304.461418 -20.980146)
		(width 0.14224)
		(layer "In2.Cu")
		(net "M_A_DQ<54>")
	)
	(segment
		(start 301.237904 -34.856674)
		(end 300.990762 -34.609532)
		(width 0.14224)
		(layer "In2.Cu")
		(net "M_A_DQ<54>")
	)
	(segment
		(start 304.886868 -21.757386)
		(end 304.886868 -21.405596)
		(width 0.14224)
		(layer "In2.Cu")
		(net "M_A_DQ<54>")
	)
	(segment
		(start 300.303692 -36.0172)
		(end 300.303692 -35.798252)
		(width 0.14224)
		(layer "In2.Cu")
		(net "M_A_DQ<54>")
	)
	(segment
		(start 304.461418 -19.278854)
		(end 304.8254 -18.914872)
		(width 0.14224)
		(layer "In2.Cu")
		(net "M_A_DQ<54>")
	)
	(segment
		(start 304.742596 -28.263596)
		(end 304.742596 -26.866596)
		(width 0.14224)
		(layer "In2.Cu")
		(net "M_A_DQ<54>")
	)
	(segment
		(start 300.990762 -34.609532)
		(end 300.990762 -34.390584)
		(width 0.14224)
		(layer "In2.Cu")
		(net "M_A_DQ<54>")
	)
	(segment
		(start 299.115226 -36.485068)
		(end 299.115226 -36.26612)
		(width 0.14224)
		(layer "In2.Cu")
		(net "M_A_DQ<54>")
	)
	(segment
		(start 299.115988 -37.204904)
		(end 299.365924 -36.954968)
		(width 0.14224)
		(layer "In2.Cu")
		(net "M_A_DQ<54>")
	)
	(segment
		(start 300.053756 -36.267136)
		(end 300.303692 -36.0172)
		(width 0.14224)
		(layer "In2.Cu")
		(net "M_A_DQ<54>")
	)
	(segment
		(start 299.365924 -36.954968)
		(end 299.365924 -36.73602)
		(width 0.14224)
		(layer "In2.Cu")
		(net "M_A_DQ<54>")
	)
	(segment
		(start 299.58411 -36.016184)
		(end 299.834808 -36.267136)
		(width 0.14224)
		(layer "In2.Cu")
		(net "M_A_DQ<54>")
	)
	(segment
		(start 298.89704 -37.204904)
		(end 299.115988 -37.204904)
		(width 0.14224)
		(layer "In2.Cu")
		(net "M_A_DQ<54>")
	)
	(segment
		(start 304.1142 -22.530054)
		(end 304.886868 -21.757386)
		(width 0.14224)
		(layer "In2.Cu")
		(net "M_A_DQ<54>")
	)
	(segment
		(start 304.807112 -26.80208)
		(end 304.807112 -25.280366)
		(width 0.14224)
		(layer "In2.Cu")
		(net "M_A_DQ<54>")
	)
	(segment
		(start 304.615596 -29.048964)
		(end 304.88636 -28.7782)
		(width 0.14224)
		(layer "In2.Cu")
		(net "M_A_DQ<54>")
	)
	(segment
		(start 283.366464 -44.064936)
		(end 289.8648 -37.5666)
		(width 0.14224)
		(layer "In2.Cu")
		(net "M_A_DQ<54>")
	)
	(segment
		(start 283.576522 -50.908712)
		(end 283.576522 -48.621442)
		(width 0.0889)
		(layer "In2.Cu")
		(net "M_A_DQ<54>")
	)
	(segment
		(start 282.90901 -53.471064)
		(end 282.90901 -51.576224)
		(width 0.0889)
		(layer "In2.Cu")
		(net "M_A_DQ<54>")
	)
	(segment
		(start 304.88636 -28.40736)
		(end 304.742596 -28.263596)
		(width 0.14224)
		(layer "In2.Cu")
		(net "M_A_DQ<54>")
	)
	(segment
		(start 300.052994 -35.328352)
		(end 300.30293 -35.078416)
		(width 0.14224)
		(layer "In2.Cu")
		(net "M_A_DQ<54>")
	)
	(segment
		(start 302.4632 -33.7058)
		(end 302.4632 -32.918146)
		(width 0.14224)
		(layer "In2.Cu")
		(net "M_A_DQ<54>")
	)
	(segment
		(start 300.970442 -35.325558)
		(end 301.237904 -35.058096)
		(width 0.14224)
		(layer "In2.Cu")
		(net "M_A_DQ<54>")
	)
	(segment
		(start 299.365924 -36.73602)
		(end 299.115226 -36.485068)
		(width 0.14224)
		(layer "In2.Cu")
		(net "M_A_DQ<54>")
	)
	(segment
		(start 304.349912 -23.560278)
		(end 304.1142 -23.324566)
		(width 0.14224)
		(layer "In2.Cu")
		(net "M_A_DQ<54>")
	)
	(segment
		(start 300.303692 -35.798252)
		(end 300.052994 -35.5473)
		(width 0.14224)
		(layer "In2.Cu")
		(net "M_A_DQ<54>")
	)
	(segment
		(start 283.041598 -54.913784)
		(end 283.041598 -53.603652)
		(width 0.0889)
		(layer "In2.Cu")
		(net "M_A_DQ<54>")
	)
	(segment
		(start 304.842418 -20.313904)
		(end 304.842418 -19.970496)
		(width 0.14224)
		(layer "In2.Cu")
		(net "M_A_DQ<54>")
	)
	(segment
		(start 300.052994 -35.5473)
		(end 300.052994 -35.328352)
		(width 0.14224)
		(layer "In2.Cu")
		(net "M_A_DQ<54>")
	)
	(segment
		(start 299.365162 -36.016184)
		(end 299.58411 -36.016184)
		(width 0.14224)
		(layer "In2.Cu")
		(net "M_A_DQ<54>")
	)
	(arc
		(start 282.988004 -55.113936)
		(mid 283.027991 -55.01739)
		(end 283.041598 -54.913784)
		(width 0.0889)
		(layer "In2.Cu")
		(net "M_A_DQ<54>")
	)
	(arc
		(start 282.955746 -55.178452)
		(mid 282.970893 -55.145703)
		(end 282.988004 -55.113936)
		(width 0.0889)
		(layer "In2.Cu")
		(net "M_A_DQ<54>")
	)
	(segment
		(start 298.399962 -15.423642)
		(end 298.399962 -16.687546)
		(width 0.1651)
		(layer "F.Cu")
		(net "M_A_DQ<53>")
	)
	(segment
		(start 298.40047 -15.423642)
		(end 298.399962 -15.423642)
		(width 0.1651)
		(layer "F.Cu")
		(net "M_A_DQ<53>")
	)
	(segment
		(start 280.637234 -57.390538)
		(end 280.065734 -57.390538)
		(width 0.1016)
		(layer "F.Cu")
		(net "M_A_DQ<53>")
	)
	(via
		(at 280.065734 -57.390538)
		(size 0.508)
		(drill 0.254)
		(layers "F.Cu" "B.Cu")
		(net "M_A_DQ<53>")
	)
	(via
		(at 299.173646 -22.279356)
		(size 0.508)
		(drill 0.254)
		(layers "F.Cu" "B.Cu")
		(net "M_A_DQ<53>")
	)
	(via
		(at 298.399962 -16.687546)
		(size 0.508)
		(drill 0.254)
		(layers "F.Cu" "B.Cu")
		(net "M_A_DQ<53>")
	)
	(segment
		(start 299.249846 -22.203156)
		(end 299.173646 -22.279356)
		(width 0.1651)
		(layer "B.Cu")
		(net "M_A_DQ<53>")
	)
	(segment
		(start 299.249846 -20.224242)
		(end 299.249846 -22.203156)
		(width 0.1651)
		(layer "B.Cu")
		(net "M_A_DQ<53>")
	)
	(segment
		(start 299.250354 -20.224242)
		(end 299.249846 -20.224242)
		(width 0.1651)
		(layer "B.Cu")
		(net "M_A_DQ<53>")
	)
	(segment
		(start 279.022556 -49.351692)
		(end 279.241504 -49.132744)
		(width 0.0889)
		(layer "In2.Cu")
		(net "M_A_DQ<53>")
	)
	(segment
		(start 279.434036 -50.946558)
		(end 279.434036 -50.012854)
		(width 0.0889)
		(layer "In2.Cu")
		(net "M_A_DQ<53>")
	)
	(segment
		(start 299.637196 -28.83535)
		(end 299.637196 -26.841196)
		(width 0.14224)
		(layer "In2.Cu")
		(net "M_A_DQ<53>")
	)
	(segment
		(start 299.281596 -17.653)
		(end 298.9707 -17.653)
		(width 0.14224)
		(layer "In2.Cu")
		(net "M_A_DQ<53>")
	)
	(segment
		(start 279.241504 -49.132744)
		(end 279.1968 -49.08804)
		(width 0.14224)
		(layer "In2.Cu")
		(net "M_A_DQ<53>")
	)
	(segment
		(start 299.286168 -25.315672)
		(end 299.082968 -25.112472)
		(width 0.14224)
		(layer "In2.Cu")
		(net "M_A_DQ<53>")
	)
	(segment
		(start 299.383196 -25.315672)
		(end 299.286168 -25.315672)
		(width 0.14224)
		(layer "In2.Cu")
		(net "M_A_DQ<53>")
	)
	(segment
		(start 279.022556 -49.601374)
		(end 279.022556 -49.351692)
		(width 0.0889)
		(layer "In2.Cu")
		(net "M_A_DQ<53>")
	)
	(segment
		(start 280.021792 -55.950612)
		(end 279.865582 -55.809896)
		(width 0.0889)
		(layer "In2.Cu")
		(net "M_A_DQ<53>")
	)
	(segment
		(start 280.229056 -56.034432)
		(end 280.021792 -55.950612)
		(width 0.0889)
		(layer "In2.Cu")
		(net "M_A_DQ<53>")
	)
	(segment
		(start 298.399962 -17.082262)
		(end 298.399962 -16.687546)
		(width 0.14224)
		(layer "In2.Cu")
		(net "M_A_DQ<53>")
	)
	(segment
		(start 279.719024 -54.218586)
		(end 279.80894 -54.076854)
		(width 0.0889)
		(layer "In2.Cu")
		(net "M_A_DQ<53>")
	)
	(segment
		(start 299.082968 -25.112472)
		(end 299.082968 -24.706072)
		(width 0.14224)
		(layer "In2.Cu")
		(net "M_A_DQ<53>")
	)
	(segment
		(start 285.1277 -36.461954)
		(end 287.934654 -33.655)
		(width 0.14224)
		(layer "In2.Cu")
		(net "M_A_DQ<53>")
	)
	(segment
		(start 280.065734 -57.390538)
		(end 280.395172 -56.629554)
		(width 0.0889)
		(layer "In2.Cu")
		(net "M_A_DQ<53>")
	)
	(segment
		(start 279.865582 -55.809896)
		(end 279.760172 -55.68061)
		(width 0.0889)
		(layer "In2.Cu")
		(net "M_A_DQ<53>")
	)
	(segment
		(start 284.2133 -36.461954)
		(end 285.1277 -36.461954)
		(width 0.14224)
		(layer "In2.Cu")
		(net "M_A_DQ<53>")
	)
	(segment
		(start 279.80894 -51.992276)
		(end 279.629616 -51.812952)
		(width 0.0889)
		(layer "In2.Cu")
		(net "M_A_DQ<53>")
	)
	(segment
		(start 279.629616 -51.142138)
		(end 279.434036 -50.946558)
		(width 0.0889)
		(layer "In2.Cu")
		(net "M_A_DQ<53>")
	)
	(segment
		(start 287.934654 -33.655)
		(end 294.817546 -33.655)
		(width 0.14224)
		(layer "In2.Cu")
		(net "M_A_DQ<53>")
	)
	(segment
		(start 280.395172 -56.629554)
		(end 280.41727 -56.5912)
		(width 0.0889)
		(layer "In2.Cu")
		(net "M_A_DQ<53>")
	)
	(segment
		(start 299.6819 -18.053304)
		(end 299.281596 -17.653)
		(width 0.14224)
		(layer "In2.Cu")
		(net "M_A_DQ<53>")
	)
	(segment
		(start 279.1968 -41.478454)
		(end 284.2133 -36.461954)
		(width 0.14224)
		(layer "In2.Cu")
		(net "M_A_DQ<53>")
	)
	(segment
		(start 299.173646 -22.279356)
		(end 299.48505 -21.967952)
		(width 0.14224)
		(layer "In2.Cu")
		(net "M_A_DQ<53>")
	)
	(segment
		(start 299.6819 -18.4658)
		(end 299.6819 -18.053304)
		(width 0.14224)
		(layer "In2.Cu")
		(net "M_A_DQ<53>")
	)
	(segment
		(start 299.383196 -24.502872)
		(end 299.586396 -24.299672)
		(width 0.14224)
		(layer "In2.Cu")
		(net "M_A_DQ<53>")
	)
	(segment
		(start 299.586396 -26.790396)
		(end 299.586396 -25.518872)
		(width 0.14224)
		(layer "In2.Cu")
		(net "M_A_DQ<53>")
	)
	(segment
		(start 279.725374 -54.629304)
		(end 279.719024 -54.618636)
		(width 0.0889)
		(layer "In2.Cu")
		(net "M_A_DQ<53>")
	)
	(segment
		(start 298.671996 -23.107396)
		(end 298.671996 -22.781006)
		(width 0.14224)
		(layer "In2.Cu")
		(net "M_A_DQ<53>")
	)
	(segment
		(start 298.9707 -17.653)
		(end 298.399962 -17.082262)
		(width 0.14224)
		(layer "In2.Cu")
		(net "M_A_DQ<53>")
	)
	(segment
		(start 294.817546 -33.655)
		(end 299.637196 -28.83535)
		(width 0.14224)
		(layer "In2.Cu")
		(net "M_A_DQ<53>")
	)
	(segment
		(start 298.671996 -22.781006)
		(end 299.173646 -22.279356)
		(width 0.14224)
		(layer "In2.Cu")
		(net "M_A_DQ<53>")
	)
	(segment
		(start 299.637196 -26.841196)
		(end 299.586396 -26.790396)
		(width 0.14224)
		(layer "In2.Cu")
		(net "M_A_DQ<53>")
	)
	(segment
		(start 279.629616 -51.812952)
		(end 279.629616 -51.142138)
		(width 0.0889)
		(layer "In2.Cu")
		(net "M_A_DQ<53>")
	)
	(segment
		(start 299.586396 -25.518872)
		(end 299.383196 -25.315672)
		(width 0.14224)
		(layer "In2.Cu")
		(net "M_A_DQ<53>")
	)
	(segment
		(start 279.1968 -49.08804)
		(end 279.1968 -41.478454)
		(width 0.14224)
		(layer "In2.Cu")
		(net "M_A_DQ<53>")
	)
	(segment
		(start 298.983146 -23.418546)
		(end 298.671996 -23.107396)
		(width 0.14224)
		(layer "In2.Cu")
		(net "M_A_DQ<53>")
	)
	(segment
		(start 299.586396 -24.059896)
		(end 299.391324 -23.864824)
		(width 0.14224)
		(layer "In2.Cu")
		(net "M_A_DQ<53>")
	)
	(segment
		(start 298.983146 -23.714202)
		(end 298.983146 -23.418546)
		(width 0.14224)
		(layer "In2.Cu")
		(net "M_A_DQ<53>")
	)
	(segment
		(start 279.80894 -54.076854)
		(end 279.80894 -51.992276)
		(width 0.0889)
		(layer "In2.Cu")
		(net "M_A_DQ<53>")
	)
	(segment
		(start 299.133768 -23.864824)
		(end 298.983146 -23.714202)
		(width 0.14224)
		(layer "In2.Cu")
		(net "M_A_DQ<53>")
	)
	(segment
		(start 299.391324 -23.864824)
		(end 299.133768 -23.864824)
		(width 0.14224)
		(layer "In2.Cu")
		(net "M_A_DQ<53>")
	)
	(segment
		(start 279.434036 -50.012854)
		(end 279.022556 -49.601374)
		(width 0.0889)
		(layer "In2.Cu")
		(net "M_A_DQ<53>")
	)
	(segment
		(start 299.082968 -24.706072)
		(end 299.286168 -24.502872)
		(width 0.14224)
		(layer "In2.Cu")
		(net "M_A_DQ<53>")
	)
	(segment
		(start 299.586396 -24.299672)
		(end 299.586396 -24.059896)
		(width 0.14224)
		(layer "In2.Cu")
		(net "M_A_DQ<53>")
	)
	(segment
		(start 299.48505 -18.66265)
		(end 299.6819 -18.4658)
		(width 0.14224)
		(layer "In2.Cu")
		(net "M_A_DQ<53>")
	)
	(segment
		(start 299.48505 -21.967952)
		(end 299.48505 -18.66265)
		(width 0.14224)
		(layer "In2.Cu")
		(net "M_A_DQ<53>")
	)
	(segment
		(start 279.760172 -55.68061)
		(end 279.714198 -55.6006)
		(width 0.0889)
		(layer "In2.Cu")
		(net "M_A_DQ<53>")
	)
	(segment
		(start 279.719024 -54.618636)
		(end 279.714198 -54.61)
		(width 0.0889)
		(layer "In2.Cu")
		(net "M_A_DQ<53>")
	)
	(segment
		(start 299.286168 -24.502872)
		(end 299.383196 -24.502872)
		(width 0.14224)
		(layer "In2.Cu")
		(net "M_A_DQ<53>")
	)
	(arc
		(start 279.719024 -55.209186)
		(mid 279.798246 -54.920068)
		(end 279.725374 -54.629304)
		(width 0.0889)
		(layer "In2.Cu")
		(net "M_A_DQ<53>")
	)
	(arc
		(start 279.714198 -54.61)
		(mid 279.665443 -54.413648)
		(end 279.719024 -54.218586)
		(width 0.0889)
		(layer "In2.Cu")
		(net "M_A_DQ<53>")
	)
	(arc
		(start 279.714198 -55.6006)
		(mid 279.665443 -55.404248)
		(end 279.719024 -55.209186)
		(width 0.0889)
		(layer "In2.Cu")
		(net "M_A_DQ<53>")
	)
	(arc
		(start 280.41727 -56.5912)
		(mid 280.444836 -56.271717)
		(end 280.229056 -56.034432)
		(width 0.0889)
		(layer "In2.Cu")
		(net "M_A_DQ<53>")
	)
	(segment
		(start 299.250354 -20.023582)
		(end 299.249846 -20.023582)
		(width 0.1651)
		(layer "F.Cu")
		(net "M_A_DQ<52>")
	)
	(segment
		(start 299.249846 -20.023582)
		(end 299.249846 -18.692368)
		(width 0.1651)
		(layer "F.Cu")
		(net "M_A_DQ<52>")
	)
	(segment
		(start 299.249846 -18.692368)
		(end 299.151802 -18.161)
		(width 0.1651)
		(layer "F.Cu")
		(net "M_A_DQ<52>")
	)
	(segment
		(start 280.637234 -56.399938)
		(end 280.065734 -56.399938)
		(width 0.1016)
		(layer "F.Cu")
		(net "M_A_DQ<52>")
	)
	(via
		(at 280.065734 -56.399938)
		(size 0.508)
		(drill 0.254)
		(layers "F.Cu" "B.Cu")
		(net "M_A_DQ<52>")
	)
	(via
		(at 299.151802 -18.161)
		(size 0.508)
		(drill 0.254)
		(layers "F.Cu" "B.Cu")
		(net "M_A_DQ<52>")
	)
	(via
		(at 298.399962 -23.560278)
		(size 0.508)
		(drill 0.254)
		(layers "F.Cu" "B.Cu")
		(net "M_A_DQ<52>")
	)
	(segment
		(start 298.399962 -24.824182)
		(end 298.399962 -23.560278)
		(width 0.1651)
		(layer "B.Cu")
		(net "M_A_DQ<52>")
	)
	(segment
		(start 298.40047 -24.824182)
		(end 298.399962 -24.824182)
		(width 0.1651)
		(layer "B.Cu")
		(net "M_A_DQ<52>")
	)
	(segment
		(start 298.925996 -26.222452)
		(end 298.549568 -25.846024)
		(width 0.14224)
		(layer "In2.Cu")
		(net "M_A_DQ<52>")
	)
	(segment
		(start 298.892468 -19.9644)
		(end 298.511468 -19.5834)
		(width 0.14224)
		(layer "In2.Cu")
		(net "M_A_DQ<52>")
	)
	(segment
		(start 279.553924 -55.704486)
		(end 279.547574 -55.693818)
		(width 0.0889)
		(layer "In2.Cu")
		(net "M_A_DQ<52>")
	)
	(segment
		(start 279.633426 -55.84444)
		(end 279.553924 -55.704486)
		(width 0.0889)
		(layer "In2.Cu")
		(net "M_A_DQ<52>")
	)
	(segment
		(start 279.439116 -51.221386)
		(end 279.243536 -51.025806)
		(width 0.0889)
		(layer "In2.Cu")
		(net "M_A_DQ<52>")
	)
	(segment
		(start 278.0538 -45.077634)
		(end 278.20874 -44.922694)
		(width 0.14224)
		(layer "In2.Cu")
		(net "M_A_DQ<52>")
	)
	(segment
		(start 278.54656 -43.313604)
		(end 278.6888 -43.171364)
		(width 0.14224)
		(layer "In2.Cu")
		(net "M_A_DQ<52>")
	)
	(segment
		(start 278.0538 -48.59274)
		(end 278.0538 -47.729394)
		(width 0.14224)
		(layer "In2.Cu")
		(net "M_A_DQ<52>")
	)
	(segment
		(start 278.6888 -47.066454)
		(end 278.53386 -46.911514)
		(width 0.14224)
		(layer "In2.Cu")
		(net "M_A_DQ<52>")
	)
	(segment
		(start 298.511468 -19.278854)
		(end 298.87545 -18.914872)
		(width 0.14224)
		(layer "In2.Cu")
		(net "M_A_DQ<52>")
	)
	(segment
		(start 298.87545 -18.437352)
		(end 299.151802 -18.161)
		(width 0.14224)
		(layer "In2.Cu")
		(net "M_A_DQ<52>")
	)
	(segment
		(start 299.002196 -28.441396)
		(end 298.697396 -28.136596)
		(width 0.14224)
		(layer "In2.Cu")
		(net "M_A_DQ<52>")
	)
	(segment
		(start 278.6888 -43.171364)
		(end 278.6888 -41.224454)
		(width 0.14224)
		(layer "In2.Cu")
		(net "M_A_DQ<52>")
	)
	(segment
		(start 278.0538 -46.403514)
		(end 278.20874 -46.248574)
		(width 0.14224)
		(layer "In2.Cu")
		(net "M_A_DQ<52>")
	)
	(segment
		(start 278.6888 -45.740574)
		(end 278.53386 -45.585634)
		(width 0.14224)
		(layer "In2.Cu")
		(net "M_A_DQ<52>")
	)
	(segment
		(start 294.894 -32.7914)
		(end 299.002196 -28.683204)
		(width 0.14224)
		(layer "In2.Cu")
		(net "M_A_DQ<52>")
	)
	(segment
		(start 278.53386 -47.574454)
		(end 278.6888 -47.419514)
		(width 0.14224)
		(layer "In2.Cu")
		(net "M_A_DQ<52>")
	)
	(segment
		(start 299.002196 -28.683204)
		(end 299.002196 -28.441396)
		(width 0.14224)
		(layer "In2.Cu")
		(net "M_A_DQ<52>")
	)
	(segment
		(start 298.399962 -23.560278)
		(end 298.16425 -23.324566)
		(width 0.14224)
		(layer "In2.Cu")
		(net "M_A_DQ<52>")
	)
	(segment
		(start 298.549568 -24.042624)
		(end 298.399962 -23.893018)
		(width 0.14224)
		(layer "In2.Cu")
		(net "M_A_DQ<52>")
	)
	(segment
		(start 279.61844 -52.07127)
		(end 279.439116 -51.891946)
		(width 0.0889)
		(layer "In2.Cu")
		(net "M_A_DQ<52>")
	)
	(segment
		(start 278.17064 -43.313604)
		(end 278.54656 -43.313604)
		(width 0.14224)
		(layer "In2.Cu")
		(net "M_A_DQ<52>")
	)
	(segment
		(start 278.6888 -44.767754)
		(end 278.6888 -44.106084)
		(width 0.14224)
		(layer "In2.Cu")
		(net "M_A_DQ<52>")
	)
	(segment
		(start 298.925996 -26.764996)
		(end 298.925996 -26.222452)
		(width 0.14224)
		(layer "In2.Cu")
		(net "M_A_DQ<52>")
	)
	(segment
		(start 278.593804 -49.132744)
		(end 278.0538 -48.59274)
		(width 0.14224)
		(layer "In2.Cu")
		(net "M_A_DQ<52>")
	)
	(segment
		(start 298.524168 -20.992846)
		(end 298.524168 -20.6375)
		(width 0.14224)
		(layer "In2.Cu")
		(net "M_A_DQ<52>")
	)
	(segment
		(start 278.6888 -44.106084)
		(end 278.54656 -43.963844)
		(width 0.14224)
		(layer "In2.Cu")
		(net "M_A_DQ<52>")
	)
	(segment
		(start 278.17064 -43.963844)
		(end 278.0284 -43.821604)
		(width 0.14224)
		(layer "In2.Cu")
		(net "M_A_DQ<52>")
	)
	(segment
		(start 279.243536 -50.092102)
		(end 278.832056 -49.680622)
		(width 0.0889)
		(layer "In2.Cu")
		(net "M_A_DQ<52>")
	)
	(segment
		(start 278.53386 -45.585634)
		(end 278.20874 -45.585634)
		(width 0.14224)
		(layer "In2.Cu")
		(net "M_A_DQ<52>")
	)
	(segment
		(start 279.439116 -51.891946)
		(end 279.439116 -51.221386)
		(width 0.0889)
		(layer "In2.Cu")
		(net "M_A_DQ<52>")
	)
	(segment
		(start 278.6888 -41.224454)
		(end 287.121854 -32.7914)
		(width 0.14224)
		(layer "In2.Cu")
		(net "M_A_DQ<52>")
	)
	(segment
		(start 280.044144 -56.396636)
		(end 279.633426 -55.84444)
		(width 0.0889)
		(layer "In2.Cu")
		(net "M_A_DQ<52>")
	)
	(segment
		(start 278.20874 -47.574454)
		(end 278.53386 -47.574454)
		(width 0.14224)
		(layer "In2.Cu")
		(net "M_A_DQ<52>")
	)
	(segment
		(start 287.121854 -32.7914)
		(end 294.894 -32.7914)
		(width 0.14224)
		(layer "In2.Cu")
		(net "M_A_DQ<52>")
	)
	(segment
		(start 298.87545 -18.914872)
		(end 298.87545 -18.437352)
		(width 0.14224)
		(layer "In2.Cu")
		(net "M_A_DQ<52>")
	)
	(segment
		(start 298.524168 -20.6375)
		(end 298.892468 -20.2692)
		(width 0.14224)
		(layer "In2.Cu")
		(net "M_A_DQ<52>")
	)
	(segment
		(start 278.53386 -44.922694)
		(end 278.6888 -44.767754)
		(width 0.14224)
		(layer "In2.Cu")
		(net "M_A_DQ<52>")
	)
	(segment
		(start 278.53386 -46.248574)
		(end 278.6888 -46.093634)
		(width 0.14224)
		(layer "In2.Cu")
		(net "M_A_DQ<52>")
	)
	(segment
		(start 298.697396 -28.136596)
		(end 298.697396 -26.993596)
		(width 0.14224)
		(layer "In2.Cu")
		(net "M_A_DQ<52>")
	)
	(segment
		(start 298.16425 -22.530054)
		(end 298.87545 -21.818854)
		(width 0.14224)
		(layer "In2.Cu")
		(net "M_A_DQ<52>")
	)
	(segment
		(start 278.53386 -46.911514)
		(end 278.20874 -46.911514)
		(width 0.14224)
		(layer "In2.Cu")
		(net "M_A_DQ<52>")
	)
	(segment
		(start 278.54656 -43.963844)
		(end 278.17064 -43.963844)
		(width 0.14224)
		(layer "In2.Cu")
		(net "M_A_DQ<52>")
	)
	(segment
		(start 279.243536 -51.025806)
		(end 279.243536 -50.092102)
		(width 0.0889)
		(layer "In2.Cu")
		(net "M_A_DQ<52>")
	)
	(segment
		(start 278.6888 -46.093634)
		(end 278.6888 -45.740574)
		(width 0.14224)
		(layer "In2.Cu")
		(net "M_A_DQ<52>")
	)
	(segment
		(start 298.892468 -20.2692)
		(end 298.892468 -19.9644)
		(width 0.14224)
		(layer "In2.Cu")
		(net "M_A_DQ<52>")
	)
	(segment
		(start 278.832056 -49.370996)
		(end 278.593804 -49.132744)
		(width 0.0889)
		(layer "In2.Cu")
		(net "M_A_DQ<52>")
	)
	(segment
		(start 278.832056 -49.680622)
		(end 278.832056 -49.370996)
		(width 0.0889)
		(layer "In2.Cu")
		(net "M_A_DQ<52>")
	)
	(segment
		(start 279.553924 -54.123336)
		(end 279.61844 -54.011576)
		(width 0.0889)
		(layer "In2.Cu")
		(net "M_A_DQ<52>")
	)
	(segment
		(start 278.20874 -46.248574)
		(end 278.53386 -46.248574)
		(width 0.14224)
		(layer "In2.Cu")
		(net "M_A_DQ<52>")
	)
	(segment
		(start 298.16425 -23.324566)
		(end 298.16425 -22.530054)
		(width 0.14224)
		(layer "In2.Cu")
		(net "M_A_DQ<52>")
	)
	(segment
		(start 298.549568 -25.846024)
		(end 298.549568 -24.042624)
		(width 0.14224)
		(layer "In2.Cu")
		(net "M_A_DQ<52>")
	)
	(segment
		(start 278.0538 -47.729394)
		(end 278.20874 -47.574454)
		(width 0.14224)
		(layer "In2.Cu")
		(net "M_A_DQ<52>")
	)
	(segment
		(start 298.87545 -21.344128)
		(end 298.524168 -20.992846)
		(width 0.14224)
		(layer "In2.Cu")
		(net "M_A_DQ<52>")
	)
	(segment
		(start 278.20874 -45.585634)
		(end 278.0538 -45.430694)
		(width 0.14224)
		(layer "In2.Cu")
		(net "M_A_DQ<52>")
	)
	(segment
		(start 278.0284 -43.821604)
		(end 278.0284 -43.455844)
		(width 0.14224)
		(layer "In2.Cu")
		(net "M_A_DQ<52>")
	)
	(segment
		(start 279.61844 -54.011576)
		(end 279.61844 -52.07127)
		(width 0.0889)
		(layer "In2.Cu")
		(net "M_A_DQ<52>")
	)
	(segment
		(start 298.511468 -19.5834)
		(end 298.511468 -19.278854)
		(width 0.14224)
		(layer "In2.Cu")
		(net "M_A_DQ<52>")
	)
	(segment
		(start 298.697396 -26.993596)
		(end 298.925996 -26.764996)
		(width 0.14224)
		(layer "In2.Cu")
		(net "M_A_DQ<52>")
	)
	(segment
		(start 279.553924 -54.713886)
		(end 279.547574 -54.703218)
		(width 0.0889)
		(layer "In2.Cu")
		(net "M_A_DQ<52>")
	)
	(segment
		(start 278.0538 -45.430694)
		(end 278.0538 -45.077634)
		(width 0.14224)
		(layer "In2.Cu")
		(net "M_A_DQ<52>")
	)
	(segment
		(start 278.6888 -47.419514)
		(end 278.6888 -47.066454)
		(width 0.14224)
		(layer "In2.Cu")
		(net "M_A_DQ<52>")
	)
	(segment
		(start 298.87545 -21.818854)
		(end 298.87545 -21.344128)
		(width 0.14224)
		(layer "In2.Cu")
		(net "M_A_DQ<52>")
	)
	(segment
		(start 298.399962 -23.893018)
		(end 298.399962 -23.560278)
		(width 0.14224)
		(layer "In2.Cu")
		(net "M_A_DQ<52>")
	)
	(segment
		(start 278.20874 -44.922694)
		(end 278.53386 -44.922694)
		(width 0.14224)
		(layer "In2.Cu")
		(net "M_A_DQ<52>")
	)
	(segment
		(start 278.20874 -46.911514)
		(end 278.0538 -46.756574)
		(width 0.14224)
		(layer "In2.Cu")
		(net "M_A_DQ<52>")
	)
	(segment
		(start 278.0538 -46.756574)
		(end 278.0538 -46.403514)
		(width 0.14224)
		(layer "In2.Cu")
		(net "M_A_DQ<52>")
	)
	(segment
		(start 279.55875 -54.722522)
		(end 279.553924 -54.713886)
		(width 0.0889)
		(layer "In2.Cu")
		(net "M_A_DQ<52>")
	)
	(segment
		(start 278.0284 -43.455844)
		(end 278.17064 -43.313604)
		(width 0.14224)
		(layer "In2.Cu")
		(net "M_A_DQ<52>")
	)
	(segment
		(start 280.065734 -56.399938)
		(end 280.044144 -56.396636)
		(width 0.0889)
		(layer "In2.Cu")
		(net "M_A_DQ<52>")
	)
	(arc
		(start 279.547574 -55.693818)
		(mid 279.474776 -55.403055)
		(end 279.553924 -55.113936)
		(width 0.0889)
		(layer "In2.Cu")
		(net "M_A_DQ<52>")
	)
	(arc
		(start 279.547574 -54.703218)
		(mid 279.474776 -54.412455)
		(end 279.553924 -54.123336)
		(width 0.0889)
		(layer "In2.Cu")
		(net "M_A_DQ<52>")
	)
	(arc
		(start 279.553924 -55.113936)
		(mid 279.607394 -54.918873)
		(end 279.55875 -54.722522)
		(width 0.0889)
		(layer "In2.Cu")
		(net "M_A_DQ<52>")
	)
	(segment
		(start 306.050442 -15.423642)
		(end 306.049934 -15.423642)
		(width 0.1651)
		(layer "F.Cu")
		(net "M_A_DQ<51>")
	)
	(segment
		(start 306.049934 -15.423642)
		(end 306.049934 -16.687546)
		(width 0.1651)
		(layer "F.Cu")
		(net "M_A_DQ<51>")
	)
	(segment
		(start 284.071314 -57.390538)
		(end 283.499814 -57.390538)
		(width 0.1016)
		(layer "F.Cu")
		(net "M_A_DQ<51>")
	)
	(via
		(at 283.499814 -57.390538)
		(size 0.508)
		(drill 0.254)
		(layers "F.Cu" "B.Cu")
		(net "M_A_DQ<51>")
	)
	(via
		(at 306.899818 -22.279356)
		(size 0.508)
		(drill 0.254)
		(layers "F.Cu" "B.Cu")
		(net "M_A_DQ<51>")
	)
	(via
		(at 306.049934 -16.687546)
		(size 0.508)
		(drill 0.254)
		(layers "F.Cu" "B.Cu")
		(net "M_A_DQ<51>")
	)
	(segment
		(start 306.899818 -20.224242)
		(end 306.899818 -22.279356)
		(width 0.1651)
		(layer "B.Cu")
		(net "M_A_DQ<51>")
	)
	(segment
		(start 306.900326 -20.224242)
		(end 306.899818 -20.224242)
		(width 0.1651)
		(layer "B.Cu")
		(net "M_A_DQ<51>")
	)
	(segment
		(start 284.534102 -51.313588)
		(end 284.534102 -50.240184)
		(width 0.0889)
		(layer "In2.Cu")
		(net "M_A_DQ<51>")
	)
	(segment
		(start 300.7614 -39.1668)
		(end 306.575968 -33.352232)
		(width 0.14224)
		(layer "In2.Cu")
		(net "M_A_DQ<51>")
	)
	(segment
		(start 284.534102 -50.240184)
		(end 285.042864 -49.731422)
		(width 0.0889)
		(layer "In2.Cu")
		(net "M_A_DQ<51>")
	)
	(segment
		(start 307.384196 -28.965144)
		(end 307.384196 -24.216106)
		(width 0.14224)
		(layer "In2.Cu")
		(net "M_A_DQ<51>")
	)
	(segment
		(start 284.011624 -55.113936)
		(end 283.947108 -55.002176)
		(width 0.0889)
		(layer "In2.Cu")
		(net "M_A_DQ<51>")
	)
	(segment
		(start 307.408072 -18.4658)
		(end 307.408072 -18.1102)
		(width 0.14224)
		(layer "In2.Cu")
		(net "M_A_DQ<51>")
	)
	(segment
		(start 307.252624 -21.92655)
		(end 307.252624 -18.621248)
		(width 0.14224)
		(layer "In2.Cu")
		(net "M_A_DQ<51>")
	)
	(segment
		(start 285.042864 -49.731422)
		(end 285.042864 -49.440084)
		(width 0.0889)
		(layer "In2.Cu")
		(net "M_A_DQ<51>")
	)
	(segment
		(start 306.575968 -29.773372)
		(end 307.384196 -28.965144)
		(width 0.14224)
		(layer "In2.Cu")
		(net "M_A_DQ<51>")
	)
	(segment
		(start 284.113224 -53.525928)
		(end 284.113224 -51.734466)
		(width 0.0889)
		(layer "In2.Cu")
		(net "M_A_DQ<51>")
	)
	(segment
		(start 306.451 -23.28291)
		(end 306.451 -22.728174)
		(width 0.14224)
		(layer "In2.Cu")
		(net "M_A_DQ<51>")
	)
	(segment
		(start 283.947108 -55.002176)
		(end 283.947108 -53.692044)
		(width 0.0889)
		(layer "In2.Cu")
		(net "M_A_DQ<51>")
	)
	(segment
		(start 283.499814 -57.390538)
		(end 283.932122 -56.802782)
		(width 0.0889)
		(layer "In2.Cu")
		(net "M_A_DQ<51>")
	)
	(segment
		(start 283.947108 -53.692044)
		(end 284.113224 -53.525928)
		(width 0.0889)
		(layer "In2.Cu")
		(net "M_A_DQ<51>")
	)
	(segment
		(start 284.113224 -51.734466)
		(end 284.534102 -51.313588)
		(width 0.0889)
		(layer "In2.Cu")
		(net "M_A_DQ<51>")
	)
	(segment
		(start 306.575968 -33.352232)
		(end 306.575968 -29.773372)
		(width 0.14224)
		(layer "In2.Cu")
		(net "M_A_DQ<51>")
	)
	(segment
		(start 284.011624 -55.704486)
		(end 284.017974 -55.693818)
		(width 0.0889)
		(layer "In2.Cu")
		(net "M_A_DQ<51>")
	)
	(segment
		(start 285.309564 -49.173384)
		(end 285.309564 -44.483782)
		(width 0.14224)
		(layer "In2.Cu")
		(net "M_A_DQ<51>")
	)
	(segment
		(start 285.309564 -44.483782)
		(end 290.626546 -39.1668)
		(width 0.14224)
		(layer "In2.Cu")
		(net "M_A_DQ<51>")
	)
	(segment
		(start 285.042864 -49.440084)
		(end 285.309564 -49.173384)
		(width 0.0889)
		(layer "In2.Cu")
		(net "M_A_DQ<51>")
	)
	(segment
		(start 306.950872 -17.653)
		(end 306.696872 -17.653)
		(width 0.14224)
		(layer "In2.Cu")
		(net "M_A_DQ<51>")
	)
	(segment
		(start 307.384196 -24.216106)
		(end 306.451 -23.28291)
		(width 0.14224)
		(layer "In2.Cu")
		(net "M_A_DQ<51>")
	)
	(segment
		(start 306.049934 -17.006062)
		(end 306.049934 -16.687546)
		(width 0.14224)
		(layer "In2.Cu")
		(net "M_A_DQ<51>")
	)
	(segment
		(start 306.899818 -22.279356)
		(end 307.252624 -21.92655)
		(width 0.14224)
		(layer "In2.Cu")
		(net "M_A_DQ<51>")
	)
	(segment
		(start 284.006798 -55.713122)
		(end 284.011624 -55.704486)
		(width 0.0889)
		(layer "In2.Cu")
		(net "M_A_DQ<51>")
	)
	(segment
		(start 306.696872 -17.653)
		(end 306.049934 -17.006062)
		(width 0.14224)
		(layer "In2.Cu")
		(net "M_A_DQ<51>")
	)
	(segment
		(start 307.408072 -18.1102)
		(end 306.950872 -17.653)
		(width 0.14224)
		(layer "In2.Cu")
		(net "M_A_DQ<51>")
	)
	(segment
		(start 306.451 -22.728174)
		(end 306.899818 -22.279356)
		(width 0.14224)
		(layer "In2.Cu")
		(net "M_A_DQ<51>")
	)
	(segment
		(start 307.252624 -18.621248)
		(end 307.408072 -18.4658)
		(width 0.14224)
		(layer "In2.Cu")
		(net "M_A_DQ<51>")
	)
	(segment
		(start 290.626546 -39.1668)
		(end 300.7614 -39.1668)
		(width 0.14224)
		(layer "In2.Cu")
		(net "M_A_DQ<51>")
	)
	(arc
		(start 284.011624 -56.104536)
		(mid 283.958154 -55.909473)
		(end 284.006798 -55.713122)
		(width 0.0889)
		(layer "In2.Cu")
		(net "M_A_DQ<51>")
	)
	(arc
		(start 284.017974 -55.693818)
		(mid 284.090772 -55.403055)
		(end 284.011624 -55.113936)
		(width 0.0889)
		(layer "In2.Cu")
		(net "M_A_DQ<51>")
	)
	(arc
		(start 283.932122 -56.802782)
		(mid 284.086932 -56.466765)
		(end 284.011624 -56.104536)
		(width 0.0889)
		(layer "In2.Cu")
		(net "M_A_DQ<51>")
	)
	(segment
		(start 284.071314 -56.399938)
		(end 283.499814 -56.399938)
		(width 0.1016)
		(layer "F.Cu")
		(net "M_A_DQ<50>")
	)
	(segment
		(start 307.03139 -18.67154)
		(end 306.899818 -18.539968)
		(width 0.1651)
		(layer "F.Cu")
		(net "M_A_DQ<50>")
	)
	(segment
		(start 306.899818 -20.023582)
		(end 306.899818 -19.026632)
		(width 0.1651)
		(layer "F.Cu")
		(net "M_A_DQ<50>")
	)
	(segment
		(start 306.899818 -18.539968)
		(end 306.899818 -18.2626)
		(width 0.1651)
		(layer "F.Cu")
		(net "M_A_DQ<50>")
	)
	(segment
		(start 307.03139 -18.89506)
		(end 307.03139 -18.67154)
		(width 0.1651)
		(layer "F.Cu")
		(net "M_A_DQ<50>")
	)
	(segment
		(start 306.899818 -19.026632)
		(end 307.03139 -18.89506)
		(width 0.1651)
		(layer "F.Cu")
		(net "M_A_DQ<50>")
	)
	(segment
		(start 306.900326 -20.023582)
		(end 306.899818 -20.023582)
		(width 0.1651)
		(layer "F.Cu")
		(net "M_A_DQ<50>")
	)
	(via
		(at 306.049934 -23.560278)
		(size 0.508)
		(drill 0.254)
		(layers "F.Cu" "B.Cu")
		(net "M_A_DQ<50>")
	)
	(via
		(at 306.899818 -18.2626)
		(size 0.508)
		(drill 0.254)
		(layers "F.Cu" "B.Cu")
		(net "M_A_DQ<50>")
	)
	(via
		(at 283.499814 -56.399938)
		(size 0.508)
		(drill 0.254)
		(layers "F.Cu" "B.Cu")
		(net "M_A_DQ<50>")
	)
	(segment
		(start 306.050442 -24.824182)
		(end 306.049934 -24.824182)
		(width 0.1651)
		(layer "B.Cu")
		(net "M_A_DQ<50>")
	)
	(segment
		(start 306.049934 -24.824182)
		(end 306.049934 -23.560278)
		(width 0.1651)
		(layer "B.Cu")
		(net "M_A_DQ<50>")
	)
	(segment
		(start 283.846524 -55.209186)
		(end 283.756608 -55.05323)
		(width 0.0889)
		(layer "In2.Cu")
		(net "M_A_DQ<50>")
	)
	(segment
		(start 306.520596 -28.898596)
		(end 306.520596 -28.288996)
		(width 0.14224)
		(layer "In2.Cu")
		(net "M_A_DQ<50>")
	)
	(segment
		(start 306.520596 -28.288996)
		(end 306.393596 -28.161996)
		(width 0.14224)
		(layer "In2.Cu")
		(net "M_A_DQ<50>")
	)
	(segment
		(start 283.922724 -51.655218)
		(end 284.343602 -51.23434)
		(width 0.0889)
		(layer "In2.Cu")
		(net "M_A_DQ<50>")
	)
	(segment
		(start 284.852364 -49.363884)
		(end 284.661864 -49.173384)
		(width 0.0889)
		(layer "In2.Cu")
		(net "M_A_DQ<50>")
	)
	(segment
		(start 305.337464 -33.650428)
		(end 305.5874 -33.400492)
		(width 0.14224)
		(layer "In2.Cu")
		(net "M_A_DQ<50>")
	)
	(segment
		(start 284.661864 -44.267882)
		(end 290.321746 -38.608)
		(width 0.14224)
		(layer "In2.Cu")
		(net "M_A_DQ<50>")
	)
	(segment
		(start 283.840174 -55.619904)
		(end 283.846524 -55.609236)
		(width 0.0889)
		(layer "In2.Cu")
		(net "M_A_DQ<50>")
	)
	(segment
		(start 306.156868 -20.55495)
		(end 306.461668 -20.25015)
		(width 0.14224)
		(layer "In2.Cu")
		(net "M_A_DQ<50>")
	)
	(segment
		(start 305.7652 -23.275544)
		(end 305.7652 -22.5298)
		(width 0.14224)
		(layer "In2.Cu")
		(net "M_A_DQ<50>")
	)
	(segment
		(start 306.5018 -18.660618)
		(end 306.899818 -18.2626)
		(width 0.14224)
		(layer "In2.Cu")
		(net "M_A_DQ<50>")
	)
	(segment
		(start 306.461668 -20.25015)
		(end 306.461668 -19.964146)
		(width 0.14224)
		(layer "In2.Cu")
		(net "M_A_DQ<50>")
	)
	(segment
		(start 306.156868 -20.955)
		(end 306.156868 -20.55495)
		(width 0.14224)
		(layer "In2.Cu")
		(net "M_A_DQ<50>")
	)
	(segment
		(start 300.242224 -38.608)
		(end 304.589688 -34.260536)
		(width 0.14224)
		(layer "In2.Cu")
		(net "M_A_DQ<50>")
	)
	(segment
		(start 305.324002 -32.698944)
		(end 305.885596 -32.13735)
		(width 0.14224)
		(layer "In2.Cu")
		(net "M_A_DQ<50>")
	)
	(segment
		(start 306.093368 -25.668224)
		(end 306.093368 -25.363424)
		(width 0.14224)
		(layer "In2.Cu")
		(net "M_A_DQ<50>")
	)
	(segment
		(start 306.5018 -18.965672)
		(end 306.5018 -18.660618)
		(width 0.14224)
		(layer "In2.Cu")
		(net "M_A_DQ<50>")
	)
	(segment
		(start 306.156868 -19.659346)
		(end 306.156868 -19.310604)
		(width 0.14224)
		(layer "In2.Cu")
		(net "M_A_DQ<50>")
	)
	(segment
		(start 306.245768 -25.211024)
		(end 306.601368 -25.211024)
		(width 0.14224)
		(layer "In2.Cu")
		(net "M_A_DQ<50>")
	)
	(segment
		(start 283.499814 -56.399938)
		(end 283.801312 -55.706518)
		(width 0.0889)
		(layer "In2.Cu")
		(net "M_A_DQ<50>")
	)
	(segment
		(start 306.093368 -25.363424)
		(end 306.245768 -25.211024)
		(width 0.14224)
		(layer "In2.Cu")
		(net "M_A_DQ<50>")
	)
	(segment
		(start 306.614068 -21.4122)
		(end 306.156868 -20.955)
		(width 0.14224)
		(layer "In2.Cu")
		(net "M_A_DQ<50>")
	)
	(segment
		(start 306.156868 -19.310604)
		(end 306.5018 -18.965672)
		(width 0.14224)
		(layer "In2.Cu")
		(net "M_A_DQ<50>")
	)
	(segment
		(start 306.525168 -24.499824)
		(end 306.160424 -24.499824)
		(width 0.14224)
		(layer "In2.Cu")
		(net "M_A_DQ<50>")
	)
	(segment
		(start 290.321746 -38.608)
		(end 300.242224 -38.608)
		(width 0.14224)
		(layer "In2.Cu")
		(net "M_A_DQ<50>")
	)
	(segment
		(start 306.049934 -23.560278)
		(end 305.7652 -23.275544)
		(width 0.14224)
		(layer "In2.Cu")
		(net "M_A_DQ<50>")
	)
	(segment
		(start 306.804568 -24.779224)
		(end 306.525168 -24.499824)
		(width 0.14224)
		(layer "In2.Cu")
		(net "M_A_DQ<50>")
	)
	(segment
		(start 305.5874 -33.181544)
		(end 305.324002 -32.917892)
		(width 0.14224)
		(layer "In2.Cu")
		(net "M_A_DQ<50>")
	)
	(segment
		(start 304.589688 -33.915858)
		(end 304.88636 -33.619186)
		(width 0.14224)
		(layer "In2.Cu")
		(net "M_A_DQ<50>")
	)
	(segment
		(start 305.11877 -33.650428)
		(end 305.337464 -33.650428)
		(width 0.14224)
		(layer "In2.Cu")
		(net "M_A_DQ<50>")
	)
	(segment
		(start 306.601368 -25.211024)
		(end 306.804568 -25.007824)
		(width 0.14224)
		(layer "In2.Cu")
		(net "M_A_DQ<50>")
	)
	(segment
		(start 304.589688 -34.260536)
		(end 304.589688 -33.915858)
		(width 0.14224)
		(layer "In2.Cu")
		(net "M_A_DQ<50>")
	)
	(segment
		(start 306.614068 -21.680932)
		(end 306.614068 -21.4122)
		(width 0.14224)
		(layer "In2.Cu")
		(net "M_A_DQ<50>")
	)
	(segment
		(start 304.88636 -33.619186)
		(end 305.087528 -33.619186)
		(width 0.14224)
		(layer "In2.Cu")
		(net "M_A_DQ<50>")
	)
	(segment
		(start 306.296568 -25.871424)
		(end 306.093368 -25.668224)
		(width 0.14224)
		(layer "In2.Cu")
		(net "M_A_DQ<50>")
	)
	(segment
		(start 306.049934 -24.389334)
		(end 306.049934 -23.560278)
		(width 0.14224)
		(layer "In2.Cu")
		(net "M_A_DQ<50>")
	)
	(segment
		(start 283.756608 -53.61305)
		(end 283.922724 -53.446934)
		(width 0.0889)
		(layer "In2.Cu")
		(net "M_A_DQ<50>")
	)
	(segment
		(start 284.852364 -49.652174)
		(end 284.852364 -49.363884)
		(width 0.0889)
		(layer "In2.Cu")
		(net "M_A_DQ<50>")
	)
	(segment
		(start 284.661864 -49.173384)
		(end 284.661864 -44.267882)
		(width 0.14224)
		(layer "In2.Cu")
		(net "M_A_DQ<50>")
	)
	(segment
		(start 284.343602 -50.160936)
		(end 284.852364 -49.652174)
		(width 0.0889)
		(layer "In2.Cu")
		(net "M_A_DQ<50>")
	)
	(segment
		(start 283.756608 -55.05323)
		(end 283.756608 -53.61305)
		(width 0.0889)
		(layer "In2.Cu")
		(net "M_A_DQ<50>")
	)
	(segment
		(start 284.343602 -51.23434)
		(end 284.343602 -50.160936)
		(width 0.0889)
		(layer "In2.Cu")
		(net "M_A_DQ<50>")
	)
	(segment
		(start 306.461668 -19.964146)
		(end 306.156868 -19.659346)
		(width 0.14224)
		(layer "In2.Cu")
		(net "M_A_DQ<50>")
	)
	(segment
		(start 305.7652 -22.5298)
		(end 306.614068 -21.680932)
		(width 0.14224)
		(layer "In2.Cu")
		(net "M_A_DQ<50>")
	)
	(segment
		(start 305.5874 -33.400492)
		(end 305.5874 -33.181544)
		(width 0.14224)
		(layer "In2.Cu")
		(net "M_A_DQ<50>")
	)
	(segment
		(start 306.804568 -26.557224)
		(end 306.804568 -26.049224)
		(width 0.14224)
		(layer "In2.Cu")
		(net "M_A_DQ<50>")
	)
	(segment
		(start 306.393596 -26.968196)
		(end 306.804568 -26.557224)
		(width 0.14224)
		(layer "In2.Cu")
		(net "M_A_DQ<50>")
	)
	(segment
		(start 306.160424 -24.499824)
		(end 306.049934 -24.389334)
		(width 0.14224)
		(layer "In2.Cu")
		(net "M_A_DQ<50>")
	)
	(segment
		(start 305.885596 -32.13735)
		(end 305.885596 -29.533596)
		(width 0.14224)
		(layer "In2.Cu")
		(net "M_A_DQ<50>")
	)
	(segment
		(start 305.885596 -29.533596)
		(end 306.520596 -28.898596)
		(width 0.14224)
		(layer "In2.Cu")
		(net "M_A_DQ<50>")
	)
	(segment
		(start 306.804568 -26.049224)
		(end 306.626768 -25.871424)
		(width 0.14224)
		(layer "In2.Cu")
		(net "M_A_DQ<50>")
	)
	(segment
		(start 283.846524 -55.609236)
		(end 283.85135 -55.6006)
		(width 0.0889)
		(layer "In2.Cu")
		(net "M_A_DQ<50>")
	)
	(segment
		(start 306.626768 -25.871424)
		(end 306.296568 -25.871424)
		(width 0.14224)
		(layer "In2.Cu")
		(net "M_A_DQ<50>")
	)
	(segment
		(start 305.087528 -33.619186)
		(end 305.11877 -33.650428)
		(width 0.14224)
		(layer "In2.Cu")
		(net "M_A_DQ<50>")
	)
	(segment
		(start 305.324002 -32.917892)
		(end 305.324002 -32.698944)
		(width 0.14224)
		(layer "In2.Cu")
		(net "M_A_DQ<50>")
	)
	(segment
		(start 283.922724 -53.446934)
		(end 283.922724 -51.655218)
		(width 0.0889)
		(layer "In2.Cu")
		(net "M_A_DQ<50>")
	)
	(segment
		(start 306.393596 -28.161996)
		(end 306.393596 -26.968196)
		(width 0.14224)
		(layer "In2.Cu")
		(net "M_A_DQ<50>")
	)
	(segment
		(start 306.804568 -25.007824)
		(end 306.804568 -24.779224)
		(width 0.14224)
		(layer "In2.Cu")
		(net "M_A_DQ<50>")
	)
	(arc
		(start 283.85135 -55.6006)
		(mid 283.900105 -55.404248)
		(end 283.846524 -55.209186)
		(width 0.0889)
		(layer "In2.Cu")
		(net "M_A_DQ<50>")
	)
	(arc
		(start 283.801312 -55.706518)
		(mid 283.818999 -55.662428)
		(end 283.840174 -55.619904)
		(width 0.0889)
		(layer "In2.Cu")
		(net "M_A_DQ<50>")
	)
	(segment
		(start 197.250304 -20.023582)
		(end 197.249796 -20.023582)
		(width 0.1651)
		(layer "F.Cu")
		(net "M_A_DQ<4>")
	)
	(segment
		(start 197.249796 -20.023582)
		(end 197.249796 -18.692368)
		(width 0.1651)
		(layer "F.Cu")
		(net "M_A_DQ<4>")
	)
	(segment
		(start 232.749598 -66.48704)
		(end 232.101898 -66.48704)
		(width 0.1016)
		(layer "F.Cu")
		(net "M_A_DQ<4>")
	)
	(segment
		(start 197.249796 -18.692368)
		(end 197.151752 -18.161)
		(width 0.1651)
		(layer "F.Cu")
		(net "M_A_DQ<4>")
	)
	(via
		(at 196.399912 -23.560278)
		(size 0.508)
		(drill 0.254)
		(layers "F.Cu" "B.Cu")
		(net "M_A_DQ<4>")
	)
	(via
		(at 232.101898 -66.48704)
		(size 0.508)
		(drill 0.254)
		(layers "F.Cu" "B.Cu")
		(net "M_A_DQ<4>")
	)
	(via
		(at 197.151752 -18.161)
		(size 0.508)
		(drill 0.254)
		(layers "F.Cu" "B.Cu")
		(net "M_A_DQ<4>")
	)
	(segment
		(start 196.399912 -24.824182)
		(end 196.399912 -23.560278)
		(width 0.1651)
		(layer "B.Cu")
		(net "M_A_DQ<4>")
	)
	(segment
		(start 196.40042 -24.824182)
		(end 196.399912 -24.824182)
		(width 0.1651)
		(layer "B.Cu")
		(net "M_A_DQ<4>")
	)
	(segment
		(start 196.892418 -19.9644)
		(end 196.511418 -19.5834)
		(width 0.14224)
		(layer "In2.Cu")
		(net "M_A_DQ<4>")
	)
	(segment
		(start 196.511418 -19.5834)
		(end 196.511418 -19.278854)
		(width 0.14224)
		(layer "In2.Cu")
		(net "M_A_DQ<4>")
	)
	(segment
		(start 196.399912 -23.560278)
		(end 196.1642 -23.324566)
		(width 0.14224)
		(layer "In2.Cu")
		(net "M_A_DQ<4>")
	)
	(segment
		(start 196.8754 -18.914872)
		(end 196.8754 -18.437352)
		(width 0.14224)
		(layer "In2.Cu")
		(net "M_A_DQ<4>")
	)
	(segment
		(start 196.511418 -19.278854)
		(end 196.8754 -18.914872)
		(width 0.14224)
		(layer "In2.Cu")
		(net "M_A_DQ<4>")
	)
	(segment
		(start 196.8754 -18.437352)
		(end 197.151752 -18.161)
		(width 0.14224)
		(layer "In2.Cu")
		(net "M_A_DQ<4>")
	)
	(segment
		(start 196.348096 -33.488376)
		(end 196.205856 -33.346136)
		(width 0.14224)
		(layer "In2.Cu")
		(net "M_A_DQ<4>")
	)
	(segment
		(start 231.186736 -67.402202)
		(end 230.505 -67.402202)
		(width 0.0889)
		(layer "In2.Cu")
		(net "M_A_DQ<4>")
	)
	(segment
		(start 196.1642 -22.530054)
		(end 196.8754 -21.818854)
		(width 0.14224)
		(layer "In2.Cu")
		(net "M_A_DQ<4>")
	)
	(segment
		(start 196.892418 -20.2692)
		(end 196.892418 -19.9644)
		(width 0.14224)
		(layer "In2.Cu")
		(net "M_A_DQ<4>")
	)
	(segment
		(start 196.8754 -21.344128)
		(end 196.524118 -20.992846)
		(width 0.14224)
		(layer "In2.Cu")
		(net "M_A_DQ<4>")
	)
	(segment
		(start 196.205856 -36.094416)
		(end 196.205856 -34.280856)
		(width 0.14224)
		(layer "In2.Cu")
		(net "M_A_DQ<4>")
	)
	(segment
		(start 196.78396 -33.488376)
		(end 196.348096 -33.488376)
		(width 0.14224)
		(layer "In2.Cu")
		(net "M_A_DQ<4>")
	)
	(segment
		(start 196.205856 -23.754334)
		(end 196.399912 -23.560278)
		(width 0.14224)
		(layer "In2.Cu")
		(net "M_A_DQ<4>")
	)
	(segment
		(start 196.205856 -34.280856)
		(end 196.348096 -34.138616)
		(width 0.14224)
		(layer "In2.Cu")
		(net "M_A_DQ<4>")
	)
	(segment
		(start 196.524118 -20.6375)
		(end 196.892418 -20.2692)
		(width 0.14224)
		(layer "In2.Cu")
		(net "M_A_DQ<4>")
	)
	(segment
		(start 227.513642 -67.402202)
		(end 196.205856 -36.094416)
		(width 0.14224)
		(layer "In2.Cu")
		(net "M_A_DQ<4>")
	)
	(segment
		(start 196.78396 -34.138616)
		(end 196.9262 -33.996376)
		(width 0.14224)
		(layer "In2.Cu")
		(net "M_A_DQ<4>")
	)
	(segment
		(start 196.9262 -33.630616)
		(end 196.78396 -33.488376)
		(width 0.14224)
		(layer "In2.Cu")
		(net "M_A_DQ<4>")
	)
	(segment
		(start 196.1642 -23.324566)
		(end 196.1642 -22.530054)
		(width 0.14224)
		(layer "In2.Cu")
		(net "M_A_DQ<4>")
	)
	(segment
		(start 196.8754 -21.818854)
		(end 196.8754 -21.344128)
		(width 0.14224)
		(layer "In2.Cu")
		(net "M_A_DQ<4>")
	)
	(segment
		(start 230.505 -67.402202)
		(end 227.513642 -67.402202)
		(width 0.14224)
		(layer "In2.Cu")
		(net "M_A_DQ<4>")
	)
	(segment
		(start 196.524118 -20.992846)
		(end 196.524118 -20.6375)
		(width 0.14224)
		(layer "In2.Cu")
		(net "M_A_DQ<4>")
	)
	(segment
		(start 196.9262 -33.996376)
		(end 196.9262 -33.630616)
		(width 0.14224)
		(layer "In2.Cu")
		(net "M_A_DQ<4>")
	)
	(segment
		(start 196.205856 -33.346136)
		(end 196.205856 -23.754334)
		(width 0.14224)
		(layer "In2.Cu")
		(net "M_A_DQ<4>")
	)
	(segment
		(start 196.348096 -34.138616)
		(end 196.78396 -34.138616)
		(width 0.14224)
		(layer "In2.Cu")
		(net "M_A_DQ<4>")
	)
	(segment
		(start 232.101898 -66.48704)
		(end 231.186736 -67.402202)
		(width 0.0889)
		(layer "In2.Cu")
		(net "M_A_DQ<4>")
	)
	(segment
		(start 281.495754 -57.885584)
		(end 280.924254 -57.885584)
		(width 0.1016)
		(layer "F.Cu")
		(net "M_A_DQ<49>")
	)
	(segment
		(start 300.099984 -15.423642)
		(end 300.099984 -16.687546)
		(width 0.1651)
		(layer "F.Cu")
		(net "M_A_DQ<49>")
	)
	(segment
		(start 300.100492 -15.423642)
		(end 300.099984 -15.423642)
		(width 0.1651)
		(layer "F.Cu")
		(net "M_A_DQ<49>")
	)
	(via
		(at 280.924254 -57.885584)
		(size 0.508)
		(drill 0.254)
		(layers "F.Cu" "B.Cu")
		(net "M_A_DQ<49>")
	)
	(via
		(at 300.099984 -16.687546)
		(size 0.508)
		(drill 0.254)
		(layers "F.Cu" "B.Cu")
		(net "M_A_DQ<49>")
	)
	(via
		(at 300.772068 -22.279356)
		(size 0.508)
		(drill 0.254)
		(layers "F.Cu" "B.Cu")
		(net "M_A_DQ<49>")
	)
	(segment
		(start 300.950376 -20.224242)
		(end 300.949868 -20.224242)
		(width 0.1651)
		(layer "B.Cu")
		(net "M_A_DQ<49>")
	)
	(segment
		(start 300.772068 -21.776182)
		(end 300.772068 -22.279356)
		(width 0.1651)
		(layer "B.Cu")
		(net "M_A_DQ<49>")
	)
	(segment
		(start 300.949868 -21.598382)
		(end 300.772068 -21.776182)
		(width 0.1651)
		(layer "B.Cu")
		(net "M_A_DQ<49>")
	)
	(segment
		(start 300.949868 -20.224242)
		(end 300.949868 -21.598382)
		(width 0.1651)
		(layer "B.Cu")
		(net "M_A_DQ<49>")
	)
	(segment
		(start 294.9448 -35.0266)
		(end 295.4528 -35.0266)
		(width 0.14224)
		(layer "In2.Cu")
		(net "M_A_DQ<49>")
	)
	(segment
		(start 280.594308 -57.123838)
		(end 280.577544 -57.095136)
		(width 0.0889)
		(layer "In2.Cu")
		(net "M_A_DQ<49>")
	)
	(segment
		(start 300.653196 -23.488396)
		(end 300.272196 -23.107396)
		(width 0.14224)
		(layer "In2.Cu")
		(net "M_A_DQ<49>")
	)
	(segment
		(start 281.208988 -55.597298)
		(end 280.713434 -55.254144)
		(width 0.0889)
		(layer "In2.Cu")
		(net "M_A_DQ<49>")
	)
	(segment
		(start 301.302674 -18.073624)
		(end 300.93285 -17.7038)
		(width 0.14224)
		(layer "In2.Cu")
		(net "M_A_DQ<49>")
	)
	(segment
		(start 281.2288 -56.177688)
		(end 281.270964 -56.104536)
		(width 0.0889)
		(layer "In2.Cu")
		(net "M_A_DQ<49>")
	)
	(segment
		(start 300.272196 -22.779228)
		(end 300.772068 -22.279356)
		(width 0.14224)
		(layer "In2.Cu")
		(net "M_A_DQ<49>")
	)
	(segment
		(start 292.9382 -35.0266)
		(end 293.243 -34.7218)
		(width 0.14224)
		(layer "In2.Cu")
		(net "M_A_DQ<49>")
	)
	(segment
		(start 300.57725 -17.7038)
		(end 300.099984 -17.226534)
		(width 0.14224)
		(layer "In2.Cu")
		(net "M_A_DQ<49>")
	)
	(segment
		(start 301.14621 -21.905214)
		(end 301.14621 -18.571464)
		(width 0.14224)
		(layer "In2.Cu")
		(net "M_A_DQ<49>")
	)
	(segment
		(start 300.099984 -17.226534)
		(end 300.099984 -16.687546)
		(width 0.14224)
		(layer "In2.Cu")
		(net "M_A_DQ<49>")
	)
	(segment
		(start 280.203402 -50.013616)
		(end 280.277824 -49.939194)
		(width 0.0889)
		(layer "In2.Cu")
		(net "M_A_DQ<49>")
	)
	(segment
		(start 301.262796 -26.095452)
		(end 300.653196 -25.485852)
		(width 0.14224)
		(layer "In2.Cu")
		(net "M_A_DQ<49>")
	)
	(segment
		(start 280.277824 -48.248824)
		(end 280.536904 -47.989744)
		(width 0.0889)
		(layer "In2.Cu")
		(net "M_A_DQ<49>")
	)
	(segment
		(start 281.044904 -56.330596)
		(end 281.2288 -56.177688)
		(width 0.0889)
		(layer "In2.Cu")
		(net "M_A_DQ<49>")
	)
	(segment
		(start 301.262796 -29.216604)
		(end 301.262796 -26.095452)
		(width 0.14224)
		(layer "In2.Cu")
		(net "M_A_DQ<49>")
	)
	(segment
		(start 280.52395 -53.74005)
		(end 280.57602 -53.68798)
		(width 0.0889)
		(layer "In2.Cu")
		(net "M_A_DQ<49>")
	)
	(segment
		(start 295.4528 -35.0266)
		(end 301.262796 -29.216604)
		(width 0.14224)
		(layer "In2.Cu")
		(net "M_A_DQ<49>")
	)
	(segment
		(start 280.577544 -54.713886)
		(end 280.583894 -54.703218)
		(width 0.0889)
		(layer "In2.Cu")
		(net "M_A_DQ<49>")
	)
	(segment
		(start 280.277824 -49.939194)
		(end 280.277824 -48.248824)
		(width 0.0889)
		(layer "In2.Cu")
		(net "M_A_DQ<49>")
	)
	(segment
		(start 280.924254 -57.885584)
		(end 280.594308 -57.123838)
		(width 0.0889)
		(layer "In2.Cu")
		(net "M_A_DQ<49>")
	)
	(segment
		(start 280.52395 -53.923184)
		(end 280.52395 -53.74005)
		(width 0.0889)
		(layer "In2.Cu")
		(net "M_A_DQ<49>")
	)
	(segment
		(start 280.353008 -50.842418)
		(end 280.203402 -50.692812)
		(width 0.0889)
		(layer "In2.Cu")
		(net "M_A_DQ<49>")
	)
	(segment
		(start 280.57602 -51.735482)
		(end 280.353008 -51.51247)
		(width 0.0889)
		(layer "In2.Cu")
		(net "M_A_DQ<49>")
	)
	(segment
		(start 294.64 -34.7218)
		(end 294.9448 -35.0266)
		(width 0.14224)
		(layer "In2.Cu")
		(net "M_A_DQ<49>")
	)
	(segment
		(start 280.688034 -56.571896)
		(end 281.044904 -56.330596)
		(width 0.0889)
		(layer "In2.Cu")
		(net "M_A_DQ<49>")
	)
	(segment
		(start 280.203402 -50.692812)
		(end 280.203402 -50.013616)
		(width 0.0889)
		(layer "In2.Cu")
		(net "M_A_DQ<49>")
	)
	(segment
		(start 301.14621 -18.571464)
		(end 301.302674 -18.415)
		(width 0.14224)
		(layer "In2.Cu")
		(net "M_A_DQ<49>")
	)
	(segment
		(start 288.3916 -35.0266)
		(end 292.9382 -35.0266)
		(width 0.14224)
		(layer "In2.Cu")
		(net "M_A_DQ<49>")
	)
	(segment
		(start 280.57602 -53.68798)
		(end 280.57602 -51.735482)
		(width 0.0889)
		(layer "In2.Cu")
		(net "M_A_DQ<49>")
	)
	(segment
		(start 300.93285 -17.7038)
		(end 300.57725 -17.7038)
		(width 0.14224)
		(layer "In2.Cu")
		(net "M_A_DQ<49>")
	)
	(segment
		(start 280.536904 -47.989744)
		(end 280.536904 -42.881296)
		(width 0.14224)
		(layer "In2.Cu")
		(net "M_A_DQ<49>")
	)
	(segment
		(start 300.272196 -23.107396)
		(end 300.272196 -22.779228)
		(width 0.14224)
		(layer "In2.Cu")
		(net "M_A_DQ<49>")
	)
	(segment
		(start 280.353008 -51.51247)
		(end 280.353008 -50.842418)
		(width 0.0889)
		(layer "In2.Cu")
		(net "M_A_DQ<49>")
	)
	(segment
		(start 300.653196 -25.485852)
		(end 300.653196 -23.488396)
		(width 0.14224)
		(layer "In2.Cu")
		(net "M_A_DQ<49>")
	)
	(segment
		(start 280.536904 -42.881296)
		(end 288.3916 -35.0266)
		(width 0.14224)
		(layer "In2.Cu")
		(net "M_A_DQ<49>")
	)
	(segment
		(start 300.772068 -22.279356)
		(end 301.14621 -21.905214)
		(width 0.14224)
		(layer "In2.Cu")
		(net "M_A_DQ<49>")
	)
	(segment
		(start 281.27579 -55.713122)
		(end 281.208988 -55.597298)
		(width 0.0889)
		(layer "In2.Cu")
		(net "M_A_DQ<49>")
	)
	(segment
		(start 293.243 -34.7218)
		(end 294.64 -34.7218)
		(width 0.14224)
		(layer "In2.Cu")
		(net "M_A_DQ<49>")
	)
	(segment
		(start 280.572718 -54.722522)
		(end 280.577544 -54.713886)
		(width 0.0889)
		(layer "In2.Cu")
		(net "M_A_DQ<49>")
	)
	(segment
		(start 301.302674 -18.415)
		(end 301.302674 -18.073624)
		(width 0.14224)
		(layer "In2.Cu")
		(net "M_A_DQ<49>")
	)
	(arc
		(start 280.577544 -57.095136)
		(mid 280.532544 -56.812328)
		(end 280.688034 -56.571896)
		(width 0.0889)
		(layer "In2.Cu")
		(net "M_A_DQ<49>")
	)
	(arc
		(start 280.713434 -55.254144)
		(mid 280.537242 -55.016313)
		(end 280.572718 -54.722522)
		(width 0.0889)
		(layer "In2.Cu")
		(net "M_A_DQ<49>")
	)
	(arc
		(start 280.577544 -54.123336)
		(mid 280.537557 -54.02679)
		(end 280.52395 -53.923184)
		(width 0.0889)
		(layer "In2.Cu")
		(net "M_A_DQ<49>")
	)
	(arc
		(start 280.583894 -54.703218)
		(mid 280.656692 -54.412455)
		(end 280.577544 -54.123336)
		(width 0.0889)
		(layer "In2.Cu")
		(net "M_A_DQ<49>")
	)
	(arc
		(start 281.270964 -56.104536)
		(mid 281.324434 -55.909473)
		(end 281.27579 -55.713122)
		(width 0.0889)
		(layer "In2.Cu")
		(net "M_A_DQ<49>")
	)
	(segment
		(start 281.495754 -55.904384)
		(end 280.924254 -55.904384)
		(width 0.1016)
		(layer "F.Cu")
		(net "M_A_DQ<48>")
	)
	(segment
		(start 300.949868 -20.023582)
		(end 300.869096 -19.177)
		(width 0.1651)
		(layer "F.Cu")
		(net "M_A_DQ<48>")
	)
	(segment
		(start 300.869096 -19.177)
		(end 300.772068 -18.161)
		(width 0.1651)
		(layer "F.Cu")
		(net "M_A_DQ<48>")
	)
	(segment
		(start 300.950376 -20.023582)
		(end 300.949868 -20.023582)
		(width 0.1651)
		(layer "F.Cu")
		(net "M_A_DQ<48>")
	)
	(via
		(at 300.772068 -18.161)
		(size 0.508)
		(drill 0.254)
		(layers "F.Cu" "B.Cu")
		(net "M_A_DQ<48>")
	)
	(via
		(at 280.924254 -55.904384)
		(size 0.508)
		(drill 0.254)
		(layers "F.Cu" "B.Cu")
		(net "M_A_DQ<48>")
	)
	(via
		(at 300.099984 -23.560278)
		(size 0.508)
		(drill 0.254)
		(layers "F.Cu" "B.Cu")
		(net "M_A_DQ<48>")
	)
	(segment
		(start 300.099984 -24.824182)
		(end 300.099984 -23.560278)
		(width 0.1651)
		(layer "B.Cu")
		(net "M_A_DQ<48>")
	)
	(segment
		(start 300.100492 -24.824182)
		(end 300.099984 -24.824182)
		(width 0.1651)
		(layer "B.Cu")
		(net "M_A_DQ<48>")
	)
	(segment
		(start 279.889204 -47.989744)
		(end 279.889204 -41.54805)
		(width 0.14224)
		(layer "In2.Cu")
		(net "M_A_DQ<48>")
	)
	(segment
		(start 280.012902 -49.934368)
		(end 280.087324 -49.859946)
		(width 0.0889)
		(layer "In2.Cu")
		(net "M_A_DQ<48>")
	)
	(segment
		(start 299.81525 -22.5298)
		(end 300.55185 -21.7932)
		(width 0.14224)
		(layer "In2.Cu")
		(net "M_A_DQ<48>")
	)
	(segment
		(start 300.55185 -21.293328)
		(end 300.162468 -20.903946)
		(width 0.14224)
		(layer "In2.Cu")
		(net "M_A_DQ<48>")
	)
	(segment
		(start 280.162508 -51.591464)
		(end 280.162508 -50.921666)
		(width 0.0889)
		(layer "In2.Cu")
		(net "M_A_DQ<48>")
	)
	(segment
		(start 284.032452 -37.430202)
		(end 284.233874 -37.430202)
		(width 0.14224)
		(layer "In2.Cu")
		(net "M_A_DQ<48>")
	)
	(segment
		(start 280.012902 -50.77206)
		(end 280.012902 -49.934368)
		(width 0.0889)
		(layer "In2.Cu")
		(net "M_A_DQ<48>")
	)
	(segment
		(start 300.5836 -29.0322)
		(end 300.5836 -28.3718)
		(width 0.14224)
		(layer "In2.Cu")
		(net "M_A_DQ<48>")
	)
	(segment
		(start 281.18562 -41.165272)
		(end 281.18562 -40.946324)
		(width 0.14224)
		(layer "In2.Cu")
		(net "M_A_DQ<48>")
	)
	(segment
		(start 282.592272 -39.539672)
		(end 282.81122 -39.539672)
		(width 0.14224)
		(layer "In2.Cu")
		(net "M_A_DQ<48>")
	)
	(segment
		(start 283.53004 -38.601904)
		(end 283.748988 -38.601904)
		(width 0.14224)
		(layer "In2.Cu")
		(net "M_A_DQ<48>")
	)
	(segment
		(start 279.889204 -41.54805)
		(end 280.260044 -41.17721)
		(width 0.14224)
		(layer "In2.Cu")
		(net "M_A_DQ<48>")
	)
	(segment
		(start 281.41676 -40.239442)
		(end 281.654504 -40.47744)
		(width 0.14224)
		(layer "In2.Cu")
		(net "M_A_DQ<48>")
	)
	(segment
		(start 280.406094 -54.629304)
		(end 280.412444 -54.618636)
		(width 0.0889)
		(layer "In2.Cu")
		(net "M_A_DQ<48>")
	)
	(segment
		(start 283.061156 -39.070788)
		(end 282.823412 -38.83279)
		(width 0.14224)
		(layer "In2.Cu")
		(net "M_A_DQ<48>")
	)
	(segment
		(start 282.13558 -39.301674)
		(end 282.354528 -39.301674)
		(width 0.14224)
		(layer "In2.Cu")
		(net "M_A_DQ<48>")
	)
	(segment
		(start 300.55185 -21.7932)
		(end 300.55185 -21.293328)
		(width 0.14224)
		(layer "In2.Cu")
		(net "M_A_DQ<48>")
	)
	(segment
		(start 281.18562 -40.946324)
		(end 280.947876 -40.708326)
		(width 0.14224)
		(layer "In2.Cu")
		(net "M_A_DQ<48>")
	)
	(segment
		(start 280.935684 -41.415208)
		(end 281.18562 -41.165272)
		(width 0.14224)
		(layer "In2.Cu")
		(net "M_A_DQ<48>")
	)
	(segment
		(start 283.292296 -38.363906)
		(end 283.53004 -38.601904)
		(width 0.14224)
		(layer "In2.Cu")
		(net "M_A_DQ<48>")
	)
	(segment
		(start 283.073348 -38.363906)
		(end 283.292296 -38.363906)
		(width 0.14224)
		(layer "In2.Cu")
		(net "M_A_DQ<48>")
	)
	(segment
		(start 300.526196 -26.222452)
		(end 300.099984 -25.79624)
		(width 0.14224)
		(layer "In2.Cu")
		(net "M_A_DQ<48>")
	)
	(segment
		(start 283.998924 -38.13302)
		(end 283.76499 -37.899086)
		(width 0.14224)
		(layer "In2.Cu")
		(net "M_A_DQ<48>")
	)
	(segment
		(start 300.526196 -26.688796)
		(end 300.526196 -26.222452)
		(width 0.14224)
		(layer "In2.Cu")
		(net "M_A_DQ<48>")
	)
	(segment
		(start 300.272196 -28.060396)
		(end 300.272196 -26.942796)
		(width 0.14224)
		(layer "In2.Cu")
		(net "M_A_DQ<48>")
	)
	(segment
		(start 280.260044 -41.17721)
		(end 280.478992 -41.17721)
		(width 0.14224)
		(layer "In2.Cu")
		(net "M_A_DQ<48>")
	)
	(segment
		(start 283.76499 -37.899086)
		(end 283.76499 -37.697664)
		(width 0.14224)
		(layer "In2.Cu")
		(net "M_A_DQ<48>")
	)
	(segment
		(start 284.686756 -37.664136)
		(end 288.162492 -34.1884)
		(width 0.14224)
		(layer "In2.Cu")
		(net "M_A_DQ<48>")
	)
	(segment
		(start 280.478992 -41.17721)
		(end 280.716736 -41.415208)
		(width 0.14224)
		(layer "In2.Cu")
		(net "M_A_DQ<48>")
	)
	(segment
		(start 300.55185 -18.381218)
		(end 300.772068 -18.161)
		(width 0.14224)
		(layer "In2.Cu")
		(net "M_A_DQ<48>")
	)
	(segment
		(start 280.162508 -50.921666)
		(end 280.012902 -50.77206)
		(width 0.0889)
		(layer "In2.Cu")
		(net "M_A_DQ<48>")
	)
	(segment
		(start 283.061156 -39.289736)
		(end 283.061156 -39.070788)
		(width 0.14224)
		(layer "In2.Cu")
		(net "M_A_DQ<48>")
	)
	(segment
		(start 280.087324 -48.187864)
		(end 279.889204 -47.989744)
		(width 0.0889)
		(layer "In2.Cu")
		(net "M_A_DQ<48>")
	)
	(segment
		(start 282.354528 -39.301674)
		(end 282.592272 -39.539672)
		(width 0.14224)
		(layer "In2.Cu")
		(net "M_A_DQ<48>")
	)
	(segment
		(start 280.716736 -41.415208)
		(end 280.935684 -41.415208)
		(width 0.14224)
		(layer "In2.Cu")
		(net "M_A_DQ<48>")
	)
	(segment
		(start 288.162492 -34.1884)
		(end 295.4274 -34.1884)
		(width 0.14224)
		(layer "In2.Cu")
		(net "M_A_DQ<48>")
	)
	(segment
		(start 300.137068 -19.380454)
		(end 300.55185 -18.965672)
		(width 0.14224)
		(layer "In2.Cu")
		(net "M_A_DQ<48>")
	)
	(segment
		(start 281.873452 -40.47744)
		(end 282.123388 -40.227504)
		(width 0.14224)
		(layer "In2.Cu")
		(net "M_A_DQ<48>")
	)
	(segment
		(start 300.137068 -19.7104)
		(end 300.137068 -19.380454)
		(width 0.14224)
		(layer "In2.Cu")
		(net "M_A_DQ<48>")
	)
	(segment
		(start 280.087324 -49.859946)
		(end 280.087324 -48.187864)
		(width 0.0889)
		(layer "In2.Cu")
		(net "M_A_DQ<48>")
	)
	(segment
		(start 281.654504 -40.47744)
		(end 281.873452 -40.47744)
		(width 0.14224)
		(layer "In2.Cu")
		(net "M_A_DQ<48>")
	)
	(segment
		(start 283.998924 -38.351968)
		(end 283.998924 -38.13302)
		(width 0.14224)
		(layer "In2.Cu")
		(net "M_A_DQ<48>")
	)
	(segment
		(start 280.38552 -51.814476)
		(end 280.162508 -51.591464)
		(width 0.0889)
		(layer "In2.Cu")
		(net "M_A_DQ<48>")
	)
	(segment
		(start 283.748988 -38.601904)
		(end 283.998924 -38.351968)
		(width 0.14224)
		(layer "In2.Cu")
		(net "M_A_DQ<48>")
	)
	(segment
		(start 281.885644 -39.55161)
		(end 282.13558 -39.301674)
		(width 0.14224)
		(layer "In2.Cu")
		(net "M_A_DQ<48>")
	)
	(segment
		(start 295.4274 -34.1884)
		(end 300.5836 -29.0322)
		(width 0.14224)
		(layer "In2.Cu")
		(net "M_A_DQ<48>")
	)
	(segment
		(start 280.333196 -53.660802)
		(end 280.38552 -53.608478)
		(width 0.0889)
		(layer "In2.Cu")
		(net "M_A_DQ<48>")
	)
	(segment
		(start 300.162468 -20.5994)
		(end 300.479968 -20.2819)
		(width 0.14224)
		(layer "In2.Cu")
		(net "M_A_DQ<48>")
	)
	(segment
		(start 280.924254 -55.904384)
		(end 280.429208 -55.23865)
		(width 0.0889)
		(layer "In2.Cu")
		(net "M_A_DQ<48>")
	)
	(segment
		(start 300.55185 -18.965672)
		(end 300.55185 -18.381218)
		(width 0.14224)
		(layer "In2.Cu")
		(net "M_A_DQ<48>")
	)
	(segment
		(start 281.197812 -40.239442)
		(end 281.41676 -40.239442)
		(width 0.14224)
		(layer "In2.Cu")
		(net "M_A_DQ<48>")
	)
	(segment
		(start 282.123388 -40.008556)
		(end 281.885644 -39.770558)
		(width 0.14224)
		(layer "In2.Cu")
		(net "M_A_DQ<48>")
	)
	(segment
		(start 300.5836 -28.3718)
		(end 300.272196 -28.060396)
		(width 0.14224)
		(layer "In2.Cu")
		(net "M_A_DQ<48>")
	)
	(segment
		(start 282.81122 -39.539672)
		(end 283.061156 -39.289736)
		(width 0.14224)
		(layer "In2.Cu")
		(net "M_A_DQ<48>")
	)
	(segment
		(start 280.38552 -53.608478)
		(end 280.38552 -51.814476)
		(width 0.0889)
		(layer "In2.Cu")
		(net "M_A_DQ<48>")
	)
	(segment
		(start 300.479968 -20.0533)
		(end 300.137068 -19.7104)
		(width 0.14224)
		(layer "In2.Cu")
		(net "M_A_DQ<48>")
	)
	(segment
		(start 299.81525 -23.275544)
		(end 299.81525 -22.5298)
		(width 0.14224)
		(layer "In2.Cu")
		(net "M_A_DQ<48>")
	)
	(segment
		(start 300.272196 -26.942796)
		(end 300.526196 -26.688796)
		(width 0.14224)
		(layer "In2.Cu")
		(net "M_A_DQ<48>")
	)
	(segment
		(start 283.76499 -37.697664)
		(end 284.032452 -37.430202)
		(width 0.14224)
		(layer "In2.Cu")
		(net "M_A_DQ<48>")
	)
	(segment
		(start 280.947876 -40.708326)
		(end 280.947876 -40.489378)
		(width 0.14224)
		(layer "In2.Cu")
		(net "M_A_DQ<48>")
	)
	(segment
		(start 300.479968 -20.2819)
		(end 300.479968 -20.0533)
		(width 0.14224)
		(layer "In2.Cu")
		(net "M_A_DQ<48>")
	)
	(segment
		(start 300.099984 -25.79624)
		(end 300.099984 -23.560278)
		(width 0.14224)
		(layer "In2.Cu")
		(net "M_A_DQ<48>")
	)
	(segment
		(start 280.333196 -53.923184)
		(end 280.333196 -53.660802)
		(width 0.0889)
		(layer "In2.Cu")
		(net "M_A_DQ<48>")
	)
	(segment
		(start 282.823412 -38.613842)
		(end 283.073348 -38.363906)
		(width 0.14224)
		(layer "In2.Cu")
		(net "M_A_DQ<48>")
	)
	(segment
		(start 282.823412 -38.83279)
		(end 282.823412 -38.613842)
		(width 0.14224)
		(layer "In2.Cu")
		(net "M_A_DQ<48>")
	)
	(segment
		(start 300.162468 -20.903946)
		(end 300.162468 -20.5994)
		(width 0.14224)
		(layer "In2.Cu")
		(net "M_A_DQ<48>")
	)
	(segment
		(start 280.947876 -40.489378)
		(end 281.197812 -40.239442)
		(width 0.14224)
		(layer "In2.Cu")
		(net "M_A_DQ<48>")
	)
	(segment
		(start 281.885644 -39.770558)
		(end 281.885644 -39.55161)
		(width 0.14224)
		(layer "In2.Cu")
		(net "M_A_DQ<48>")
	)
	(segment
		(start 284.233874 -37.430202)
		(end 284.467808 -37.664136)
		(width 0.14224)
		(layer "In2.Cu")
		(net "M_A_DQ<48>")
	)
	(segment
		(start 280.412444 -54.618636)
		(end 280.41727 -54.61)
		(width 0.0889)
		(layer "In2.Cu")
		(net "M_A_DQ<48>")
	)
	(segment
		(start 280.429208 -55.23865)
		(end 280.412444 -55.209186)
		(width 0.0889)
		(layer "In2.Cu")
		(net "M_A_DQ<48>")
	)
	(segment
		(start 300.099984 -23.560278)
		(end 299.81525 -23.275544)
		(width 0.14224)
		(layer "In2.Cu")
		(net "M_A_DQ<48>")
	)
	(segment
		(start 282.123388 -40.227504)
		(end 282.123388 -40.008556)
		(width 0.14224)
		(layer "In2.Cu")
		(net "M_A_DQ<48>")
	)
	(segment
		(start 284.467808 -37.664136)
		(end 284.686756 -37.664136)
		(width 0.14224)
		(layer "In2.Cu")
		(net "M_A_DQ<48>")
	)
	(arc
		(start 280.412444 -54.218586)
		(mid 280.353377 -54.0761)
		(end 280.333196 -53.923184)
		(width 0.0889)
		(layer "In2.Cu")
		(net "M_A_DQ<48>")
	)
	(arc
		(start 280.41727 -54.61)
		(mid 280.466025 -54.413648)
		(end 280.412444 -54.218586)
		(width 0.0889)
		(layer "In2.Cu")
		(net "M_A_DQ<48>")
	)
	(arc
		(start 280.412444 -55.209186)
		(mid 280.333222 -54.920068)
		(end 280.406094 -54.629304)
		(width 0.0889)
		(layer "In2.Cu")
		(net "M_A_DQ<48>")
	)
	(segment
		(start 278.061674 -57.885584)
		(end 277.490174 -57.885584)
		(width 0.1016)
		(layer "F.Cu")
		(net "M_A_DQ<47>")
	)
	(segment
		(start 295.000426 -15.423642)
		(end 294.999918 -15.423642)
		(width 0.1651)
		(layer "F.Cu")
		(net "M_A_DQ<47>")
	)
	(segment
		(start 294.999918 -15.423642)
		(end 294.999918 -16.687546)
		(width 0.1651)
		(layer "F.Cu")
		(net "M_A_DQ<47>")
	)
	(via
		(at 277.490174 -57.885584)
		(size 0.508)
		(drill 0.254)
		(layers "F.Cu" "B.Cu")
		(net "M_A_DQ<47>")
	)
	(via
		(at 294.999918 -16.687546)
		(size 0.508)
		(drill 0.254)
		(layers "F.Cu" "B.Cu")
		(net "M_A_DQ<47>")
	)
	(via
		(at 295.849802 -22.279356)
		(size 0.508)
		(drill 0.254)
		(layers "F.Cu" "B.Cu")
		(net "M_A_DQ<47>")
	)
	(segment
		(start 295.85031 -20.224242)
		(end 295.849802 -20.224242)
		(width 0.1651)
		(layer "B.Cu")
		(net "M_A_DQ<47>")
	)
	(segment
		(start 295.849802 -20.224242)
		(end 295.849802 -22.279356)
		(width 0.1651)
		(layer "B.Cu")
		(net "M_A_DQ<47>")
	)
	(segment
		(start 296.358056 -18.4658)
		(end 296.358056 -18.1102)
		(width 0.14224)
		(layer "In2.Cu")
		(net "M_A_DQ<47>")
	)
	(segment
		(start 295.7322 -23.5458)
		(end 295.3766 -23.1902)
		(width 0.14224)
		(layer "In2.Cu")
		(net "M_A_DQ<47>")
	)
	(segment
		(start 277.923498 -57.536842)
		(end 277.803356 -57.4167)
		(width 0.0889)
		(layer "In2.Cu")
		(net "M_A_DQ<47>")
	)
	(segment
		(start 293.5986 -30.6578)
		(end 295.519348 -28.737052)
		(width 0.14224)
		(layer "In2.Cu")
		(net "M_A_DQ<47>")
	)
	(segment
		(start 295.519348 -28.737052)
		(end 295.519348 -28.260548)
		(width 0.14224)
		(layer "In2.Cu")
		(net "M_A_DQ<47>")
	)
	(segment
		(start 295.646856 -17.653)
		(end 294.999918 -17.006062)
		(width 0.14224)
		(layer "In2.Cu")
		(net "M_A_DQ<47>")
	)
	(segment
		(start 278.080978 -52.907692)
		(end 276.803104 -51.629818)
		(width 0.0889)
		(layer "In2.Cu")
		(net "M_A_DQ<47>")
	)
	(segment
		(start 277.860506 -57.885584)
		(end 277.923498 -57.822592)
		(width 0.0889)
		(layer "In2.Cu")
		(net "M_A_DQ<47>")
	)
	(segment
		(start 277.923498 -57.822592)
		(end 277.923498 -57.536842)
		(width 0.0889)
		(layer "In2.Cu")
		(net "M_A_DQ<47>")
	)
	(segment
		(start 295.3766 -22.752558)
		(end 295.849802 -22.279356)
		(width 0.14224)
		(layer "In2.Cu")
		(net "M_A_DQ<47>")
	)
	(segment
		(start 295.247568 -27.039316)
		(end 295.7322 -26.554684)
		(width 0.14224)
		(layer "In2.Cu")
		(net "M_A_DQ<47>")
	)
	(segment
		(start 296.202608 -21.92655)
		(end 296.202608 -18.621248)
		(width 0.14224)
		(layer "In2.Cu")
		(net "M_A_DQ<47>")
	)
	(segment
		(start 295.7322 -26.554684)
		(end 295.7322 -23.5458)
		(width 0.14224)
		(layer "In2.Cu")
		(net "M_A_DQ<47>")
	)
	(segment
		(start 295.3766 -23.1902)
		(end 295.3766 -22.752558)
		(width 0.14224)
		(layer "In2.Cu")
		(net "M_A_DQ<47>")
	)
	(segment
		(start 296.358056 -18.1102)
		(end 295.900856 -17.653)
		(width 0.14224)
		(layer "In2.Cu")
		(net "M_A_DQ<47>")
	)
	(segment
		(start 276.3012 -39.4462)
		(end 285.0896 -30.6578)
		(width 0.14224)
		(layer "In2.Cu")
		(net "M_A_DQ<47>")
	)
	(segment
		(start 275.873972 -47.722028)
		(end 276.3012 -47.2948)
		(width 0.0889)
		(layer "In2.Cu")
		(net "M_A_DQ<47>")
	)
	(segment
		(start 295.519348 -28.260548)
		(end 295.247568 -27.988768)
		(width 0.14224)
		(layer "In2.Cu")
		(net "M_A_DQ<47>")
	)
	(segment
		(start 296.202608 -18.621248)
		(end 296.358056 -18.4658)
		(width 0.14224)
		(layer "In2.Cu")
		(net "M_A_DQ<47>")
	)
	(segment
		(start 295.900856 -17.653)
		(end 295.646856 -17.653)
		(width 0.14224)
		(layer "In2.Cu")
		(net "M_A_DQ<47>")
	)
	(segment
		(start 277.490174 -57.885584)
		(end 277.860506 -57.885584)
		(width 0.0889)
		(layer "In2.Cu")
		(net "M_A_DQ<47>")
	)
	(segment
		(start 276.803104 -51.629818)
		(end 276.803104 -49.920398)
		(width 0.0889)
		(layer "In2.Cu")
		(net "M_A_DQ<47>")
	)
	(segment
		(start 275.873972 -48.991266)
		(end 275.873972 -47.722028)
		(width 0.0889)
		(layer "In2.Cu")
		(net "M_A_DQ<47>")
	)
	(segment
		(start 276.803104 -49.920398)
		(end 275.873972 -48.991266)
		(width 0.0889)
		(layer "In2.Cu")
		(net "M_A_DQ<47>")
	)
	(segment
		(start 295.247568 -27.988768)
		(end 295.247568 -27.039316)
		(width 0.14224)
		(layer "In2.Cu")
		(net "M_A_DQ<47>")
	)
	(segment
		(start 278.080978 -54.925214)
		(end 278.080978 -52.907692)
		(width 0.0889)
		(layer "In2.Cu")
		(net "M_A_DQ<47>")
	)
	(segment
		(start 295.849802 -22.279356)
		(end 296.202608 -21.92655)
		(width 0.14224)
		(layer "In2.Cu")
		(net "M_A_DQ<47>")
	)
	(segment
		(start 285.0896 -30.6578)
		(end 293.5986 -30.6578)
		(width 0.14224)
		(layer "In2.Cu")
		(net "M_A_DQ<47>")
	)
	(segment
		(start 276.3012 -47.2948)
		(end 276.3012 -39.4462)
		(width 0.14224)
		(layer "In2.Cu")
		(net "M_A_DQ<47>")
	)
	(segment
		(start 294.999918 -17.006062)
		(end 294.999918 -16.687546)
		(width 0.14224)
		(layer "In2.Cu")
		(net "M_A_DQ<47>")
	)
	(arc
		(start 278.001984 -55.20944)
		(mid 278.059518 -55.072338)
		(end 278.080978 -54.925214)
		(width 0.0889)
		(layer "In2.Cu")
		(net "M_A_DQ<47>")
	)
	(arc
		(start 278.001984 -56.20004)
		(mid 278.081115 -55.904638)
		(end 278.001984 -55.609236)
		(width 0.0889)
		(layer "In2.Cu")
		(net "M_A_DQ<47>")
	)
	(arc
		(start 277.803356 -57.4167)
		(mid 277.785912 -57.252348)
		(end 277.836884 -57.095136)
		(width 0.0889)
		(layer "In2.Cu")
		(net "M_A_DQ<47>")
	)
	(arc
		(start 277.884382 -56.826658)
		(mid 277.889713 -56.503312)
		(end 278.001984 -56.20004)
		(width 0.0889)
		(layer "In2.Cu")
		(net "M_A_DQ<47>")
	)
	(arc
		(start 278.001984 -55.609236)
		(mid 277.948485 -55.409338)
		(end 278.001984 -55.20944)
		(width 0.0889)
		(layer "In2.Cu")
		(net "M_A_DQ<47>")
	)
	(arc
		(start 277.836884 -57.095136)
		(mid 277.884244 -56.965067)
		(end 277.884382 -56.826658)
		(width 0.0889)
		(layer "In2.Cu")
		(net "M_A_DQ<47>")
	)
	(segment
		(start 295.850056 -19.05)
		(end 295.850056 -20.023328)
		(width 0.1651)
		(layer "F.Cu")
		(net "M_A_DQ<46>")
	)
	(segment
		(start 295.850056 -18.5674)
		(end 295.982136 -18.69948)
		(width 0.1651)
		(layer "F.Cu")
		(net "M_A_DQ<46>")
	)
	(segment
		(start 295.982136 -18.69948)
		(end 295.982136 -18.91792)
		(width 0.1651)
		(layer "F.Cu")
		(net "M_A_DQ<46>")
	)
	(segment
		(start 278.061674 -55.904384)
		(end 277.490174 -55.904384)
		(width 0.1016)
		(layer "F.Cu")
		(net "M_A_DQ<46>")
	)
	(segment
		(start 295.849802 -18.2626)
		(end 295.850056 -18.262854)
		(width 0.1651)
		(layer "F.Cu")
		(net "M_A_DQ<46>")
	)
	(segment
		(start 295.850056 -20.023328)
		(end 295.85031 -20.023582)
		(width 0.1651)
		(layer "F.Cu")
		(net "M_A_DQ<46>")
	)
	(segment
		(start 295.982136 -18.91792)
		(end 295.850056 -19.05)
		(width 0.1651)
		(layer "F.Cu")
		(net "M_A_DQ<46>")
	)
	(segment
		(start 295.850056 -18.262854)
		(end 295.850056 -18.5674)
		(width 0.1651)
		(layer "F.Cu")
		(net "M_A_DQ<46>")
	)
	(via
		(at 277.490174 -55.904384)
		(size 0.508)
		(drill 0.254)
		(layers "F.Cu" "B.Cu")
		(net "M_A_DQ<46>")
	)
	(via
		(at 295.849802 -18.2626)
		(size 0.508)
		(drill 0.254)
		(layers "F.Cu" "B.Cu")
		(net "M_A_DQ<46>")
	)
	(via
		(at 294.999918 -23.560278)
		(size 0.508)
		(drill 0.254)
		(layers "F.Cu" "B.Cu")
		(net "M_A_DQ<46>")
	)
	(segment
		(start 295.000426 -24.824182)
		(end 294.999918 -24.824182)
		(width 0.1651)
		(layer "B.Cu")
		(net "M_A_DQ<46>")
	)
	(segment
		(start 294.999918 -24.824182)
		(end 294.999918 -23.560278)
		(width 0.1651)
		(layer "B.Cu")
		(net "M_A_DQ<46>")
	)
	(segment
		(start 294.999918 -23.561294)
		(end 294.999918 -23.560278)
		(width 0.14224)
		(layer "In2.Cu")
		(net "M_A_DQ<46>")
	)
	(segment
		(start 294.764206 -22.530054)
		(end 295.536874 -21.757386)
		(width 0.14224)
		(layer "In2.Cu")
		(net "M_A_DQ<46>")
	)
	(segment
		(start 294.999918 -23.560278)
		(end 294.764206 -23.324566)
		(width 0.14224)
		(layer "In2.Cu")
		(net "M_A_DQ<46>")
	)
	(segment
		(start 295.492424 -19.970496)
		(end 295.111424 -19.589496)
		(width 0.14224)
		(layer "In2.Cu")
		(net "M_A_DQ<46>")
	)
	(segment
		(start 295.111424 -20.694904)
		(end 295.492424 -20.313904)
		(width 0.14224)
		(layer "In2.Cu")
		(net "M_A_DQ<46>")
	)
	(segment
		(start 294.513 -27.774138)
		(end 294.7162 -27.570938)
		(width 0.14224)
		(layer "In2.Cu")
		(net "M_A_DQ<46>")
	)
	(segment
		(start 277.890478 -52.987956)
		(end 276.612604 -51.710082)
		(width 0.0889)
		(layer "In2.Cu")
		(net "M_A_DQ<46>")
	)
	(segment
		(start 294.767 -26.1366)
		(end 295.148 -25.7556)
		(width 0.14224)
		(layer "In2.Cu")
		(net "M_A_DQ<46>")
	)
	(segment
		(start 294.235632 -25.134824)
		(end 294.235632 -24.728424)
		(width 0.14224)
		(layer "In2.Cu")
		(net "M_A_DQ<46>")
	)
	(segment
		(start 276.196806 -37.56914)
		(end 276.65426 -37.56914)
		(width 0.14224)
		(layer "In2.Cu")
		(net "M_A_DQ<46>")
	)
	(segment
		(start 275.683472 -49.07026)
		(end 275.683472 -47.353728)
		(width 0.0889)
		(layer "In2.Cu")
		(net "M_A_DQ<46>")
	)
	(segment
		(start 277.3934 -36.372546)
		(end 283.717746 -30.0482)
		(width 0.14224)
		(layer "In2.Cu")
		(net "M_A_DQ<46>")
	)
	(segment
		(start 295.111424 -19.589496)
		(end 295.111424 -19.278854)
		(width 0.14224)
		(layer "In2.Cu")
		(net "M_A_DQ<46>")
	)
	(segment
		(start 294.513 -26.961338)
		(end 294.3606 -26.961338)
		(width 0.14224)
		(layer "In2.Cu")
		(net "M_A_DQ<46>")
	)
	(segment
		(start 277.490174 -55.904384)
		(end 277.798784 -55.193184)
		(width 0.0889)
		(layer "In2.Cu")
		(net "M_A_DQ<46>")
	)
	(segment
		(start 294.1828 -26.783538)
		(end 294.1828 -26.2636)
		(width 0.14224)
		(layer "In2.Cu")
		(net "M_A_DQ<46>")
	)
	(segment
		(start 294.513 -28.575)
		(end 294.1828 -28.2448)
		(width 0.14224)
		(layer "In2.Cu")
		(net "M_A_DQ<46>")
	)
	(segment
		(start 277.3934 -36.83)
		(end 277.3934 -36.372546)
		(width 0.14224)
		(layer "In2.Cu")
		(net "M_A_DQ<46>")
	)
	(segment
		(start 295.1734 -23.734776)
		(end 294.999918 -23.561294)
		(width 0.14224)
		(layer "In2.Cu")
		(net "M_A_DQ<46>")
	)
	(segment
		(start 295.03243 -24.525224)
		(end 295.1734 -24.384254)
		(width 0.14224)
		(layer "In2.Cu")
		(net "M_A_DQ<46>")
	)
	(segment
		(start 294.3098 -26.1366)
		(end 294.767 -26.1366)
		(width 0.14224)
		(layer "In2.Cu")
		(net "M_A_DQ<46>")
	)
	(segment
		(start 295.475406 -18.636996)
		(end 295.849802 -18.2626)
		(width 0.14224)
		(layer "In2.Cu")
		(net "M_A_DQ<46>")
	)
	(segment
		(start 294.1828 -28.2448)
		(end 294.1828 -27.951938)
		(width 0.14224)
		(layer "In2.Cu")
		(net "M_A_DQ<46>")
	)
	(segment
		(start 294.984424 -25.363424)
		(end 294.464232 -25.363424)
		(width 0.14224)
		(layer "In2.Cu")
		(net "M_A_DQ<46>")
	)
	(segment
		(start 277.890478 -54.913784)
		(end 277.890478 -52.987956)
		(width 0.0889)
		(layer "In2.Cu")
		(net "M_A_DQ<46>")
	)
	(segment
		(start 294.3606 -27.774138)
		(end 294.513 -27.774138)
		(width 0.14224)
		(layer "In2.Cu")
		(net "M_A_DQ<46>")
	)
	(segment
		(start 275.8186 -47.2186)
		(end 275.8186 -37.947346)
		(width 0.14224)
		(layer "In2.Cu")
		(net "M_A_DQ<46>")
	)
	(segment
		(start 295.111424 -19.278854)
		(end 295.475406 -18.914872)
		(width 0.14224)
		(layer "In2.Cu")
		(net "M_A_DQ<46>")
	)
	(segment
		(start 275.683472 -47.353728)
		(end 275.8186 -47.2186)
		(width 0.0889)
		(layer "In2.Cu")
		(net "M_A_DQ<46>")
	)
	(segment
		(start 294.513 -28.845256)
		(end 294.513 -28.575)
		(width 0.14224)
		(layer "In2.Cu")
		(net "M_A_DQ<46>")
	)
	(segment
		(start 295.148 -25.527)
		(end 294.984424 -25.363424)
		(width 0.14224)
		(layer "In2.Cu")
		(net "M_A_DQ<46>")
	)
	(segment
		(start 294.3606 -26.961338)
		(end 294.1828 -26.783538)
		(width 0.14224)
		(layer "In2.Cu")
		(net "M_A_DQ<46>")
	)
	(segment
		(start 295.475406 -18.914872)
		(end 295.475406 -18.636996)
		(width 0.14224)
		(layer "In2.Cu")
		(net "M_A_DQ<46>")
	)
	(segment
		(start 294.764206 -23.324566)
		(end 294.764206 -22.530054)
		(width 0.14224)
		(layer "In2.Cu")
		(net "M_A_DQ<46>")
	)
	(segment
		(start 276.612604 -51.710082)
		(end 276.612604 -49.999392)
		(width 0.0889)
		(layer "In2.Cu")
		(net "M_A_DQ<46>")
	)
	(segment
		(start 294.7162 -27.164538)
		(end 294.513 -26.961338)
		(width 0.14224)
		(layer "In2.Cu")
		(net "M_A_DQ<46>")
	)
	(segment
		(start 295.148 -25.7556)
		(end 295.148 -25.527)
		(width 0.14224)
		(layer "In2.Cu")
		(net "M_A_DQ<46>")
	)
	(segment
		(start 295.492424 -20.313904)
		(end 295.492424 -19.970496)
		(width 0.14224)
		(layer "In2.Cu")
		(net "M_A_DQ<46>")
	)
	(segment
		(start 295.536874 -21.405596)
		(end 295.111424 -20.980146)
		(width 0.14224)
		(layer "In2.Cu")
		(net "M_A_DQ<46>")
	)
	(segment
		(start 294.1828 -26.2636)
		(end 294.3098 -26.1366)
		(width 0.14224)
		(layer "In2.Cu")
		(net "M_A_DQ<46>")
	)
	(segment
		(start 295.1734 -24.384254)
		(end 295.1734 -23.734776)
		(width 0.14224)
		(layer "In2.Cu")
		(net "M_A_DQ<46>")
	)
	(segment
		(start 294.7162 -27.570938)
		(end 294.7162 -27.164538)
		(width 0.14224)
		(layer "In2.Cu")
		(net "M_A_DQ<46>")
	)
	(segment
		(start 295.111424 -20.980146)
		(end 295.111424 -20.694904)
		(width 0.14224)
		(layer "In2.Cu")
		(net "M_A_DQ<46>")
	)
	(segment
		(start 276.612604 -49.999392)
		(end 275.683472 -49.07026)
		(width 0.0889)
		(layer "In2.Cu")
		(net "M_A_DQ<46>")
	)
	(segment
		(start 295.536874 -21.757386)
		(end 295.536874 -21.405596)
		(width 0.14224)
		(layer "In2.Cu")
		(net "M_A_DQ<46>")
	)
	(segment
		(start 276.65426 -37.56914)
		(end 277.3934 -36.83)
		(width 0.14224)
		(layer "In2.Cu")
		(net "M_A_DQ<46>")
	)
	(segment
		(start 293.310056 -30.0482)
		(end 294.513 -28.845256)
		(width 0.14224)
		(layer "In2.Cu")
		(net "M_A_DQ<46>")
	)
	(segment
		(start 294.464232 -25.363424)
		(end 294.235632 -25.134824)
		(width 0.14224)
		(layer "In2.Cu")
		(net "M_A_DQ<46>")
	)
	(segment
		(start 294.235632 -24.728424)
		(end 294.438832 -24.525224)
		(width 0.14224)
		(layer "In2.Cu")
		(net "M_A_DQ<46>")
	)
	(segment
		(start 275.8186 -37.947346)
		(end 276.196806 -37.56914)
		(width 0.14224)
		(layer "In2.Cu")
		(net "M_A_DQ<46>")
	)
	(segment
		(start 294.1828 -27.951938)
		(end 294.3606 -27.774138)
		(width 0.14224)
		(layer "In2.Cu")
		(net "M_A_DQ<46>")
	)
	(segment
		(start 294.438832 -24.525224)
		(end 295.03243 -24.525224)
		(width 0.14224)
		(layer "In2.Cu")
		(net "M_A_DQ<46>")
	)
	(segment
		(start 283.717746 -30.0482)
		(end 293.310056 -30.0482)
		(width 0.14224)
		(layer "In2.Cu")
		(net "M_A_DQ<46>")
	)
	(arc
		(start 277.798784 -55.193184)
		(mid 277.816354 -55.152848)
		(end 277.836884 -55.113936)
		(width 0.0889)
		(layer "In2.Cu")
		(net "M_A_DQ<46>")
	)
	(arc
		(start 277.836884 -55.113936)
		(mid 277.876871 -55.01739)
		(end 277.890478 -54.913784)
		(width 0.0889)
		(layer "In2.Cu")
		(net "M_A_DQ<46>")
	)
	(segment
		(start 275.486114 -57.390538)
		(end 274.914614 -57.390538)
		(width 0.1016)
		(layer "F.Cu")
		(net "M_A_DQ<45>")
	)
	(segment
		(start 289.050476 -15.423642)
		(end 289.049968 -15.423642)
		(width 0.1651)
		(layer "F.Cu")
		(net "M_A_DQ<45>")
	)
	(segment
		(start 289.049968 -15.423642)
		(end 289.049968 -16.687546)
		(width 0.1651)
		(layer "F.Cu")
		(net "M_A_DQ<45>")
	)
	(via
		(at 289.823652 -22.279356)
		(size 0.508)
		(drill 0.254)
		(layers "F.Cu" "B.Cu")
		(net "M_A_DQ<45>")
	)
	(via
		(at 289.049968 -16.687546)
		(size 0.508)
		(drill 0.254)
		(layers "F.Cu" "B.Cu")
		(net "M_A_DQ<45>")
	)
	(via
		(at 274.914614 -57.390538)
		(size 0.508)
		(drill 0.254)
		(layers "F.Cu" "B.Cu")
		(net "M_A_DQ<45>")
	)
	(segment
		(start 289.899852 -20.224242)
		(end 289.899852 -22.203156)
		(width 0.1651)
		(layer "B.Cu")
		(net "M_A_DQ<45>")
	)
	(segment
		(start 289.90036 -20.224242)
		(end 289.899852 -20.224242)
		(width 0.1651)
		(layer "B.Cu")
		(net "M_A_DQ<45>")
	)
	(segment
		(start 289.899852 -22.203156)
		(end 289.823652 -22.279356)
		(width 0.1651)
		(layer "B.Cu")
		(net "M_A_DQ<45>")
	)
	(segment
		(start 289.049968 -17.082262)
		(end 289.049968 -16.687546)
		(width 0.14224)
		(layer "In2.Cu")
		(net "M_A_DQ<45>")
	)
	(segment
		(start 273.907758 -51.734974)
		(end 272.766536 -50.593752)
		(width 0.0889)
		(layer "In2.Cu")
		(net "M_A_DQ<45>")
	)
	(segment
		(start 288.190178 -24.047196)
		(end 289.756596 -24.047196)
		(width 0.14224)
		(layer "In2.Cu")
		(net "M_A_DQ<45>")
	)
	(segment
		(start 287.259522 -24.474678)
		(end 287.762696 -24.474678)
		(width 0.14224)
		(layer "In2.Cu")
		(net "M_A_DQ<45>")
	)
	(segment
		(start 281.888946 -25.146)
		(end 282.501086 -25.146)
		(width 0.14224)
		(layer "In2.Cu")
		(net "M_A_DQ<45>")
	)
	(segment
		(start 290.135056 -21.967952)
		(end 290.135056 -18.66265)
		(width 0.14224)
		(layer "In2.Cu")
		(net "M_A_DQ<45>")
	)
	(segment
		(start 284.682946 -24.9174)
		(end 285.089346 -25.3238)
		(width 0.14224)
		(layer "In2.Cu")
		(net "M_A_DQ<45>")
	)
	(segment
		(start 283.921454 -25.3238)
		(end 284.327854 -24.9174)
		(width 0.14224)
		(layer "In2.Cu")
		(net "M_A_DQ<45>")
	)
	(segment
		(start 290.331906 -18.053304)
		(end 289.931602 -17.653)
		(width 0.14224)
		(layer "In2.Cu")
		(net "M_A_DQ<45>")
	)
	(segment
		(start 285.547054 -25.3238)
		(end 285.953454 -24.9174)
		(width 0.14224)
		(layer "In2.Cu")
		(net "M_A_DQ<45>")
	)
	(segment
		(start 289.756596 -24.047196)
		(end 289.883596 -23.920196)
		(width 0.14224)
		(layer "In2.Cu")
		(net "M_A_DQ<45>")
	)
	(segment
		(start 289.823652 -22.279356)
		(end 290.135056 -21.967952)
		(width 0.14224)
		(layer "In2.Cu")
		(net "M_A_DQ<45>")
	)
	(segment
		(start 286.8168 -24.9174)
		(end 287.259522 -24.474678)
		(width 0.14224)
		(layer "In2.Cu")
		(net "M_A_DQ<45>")
	)
	(segment
		(start 272.1102 -46.9138)
		(end 272.1102 -33.4518)
		(width 0.14224)
		(layer "In2.Cu")
		(net "M_A_DQ<45>")
	)
	(segment
		(start 274.656804 -53.594)
		(end 273.907758 -52.844954)
		(width 0.0889)
		(layer "In2.Cu")
		(net "M_A_DQ<45>")
	)
	(segment
		(start 290.331906 -18.4658)
		(end 290.331906 -18.053304)
		(width 0.14224)
		(layer "In2.Cu")
		(net "M_A_DQ<45>")
	)
	(segment
		(start 274.568158 -54.218586)
		(end 274.656804 -54.065932)
		(width 0.0889)
		(layer "In2.Cu")
		(net "M_A_DQ<45>")
	)
	(segment
		(start 273.907758 -52.844954)
		(end 273.907758 -51.734974)
		(width 0.0889)
		(layer "In2.Cu")
		(net "M_A_DQ<45>")
	)
	(segment
		(start 274.656804 -54.065932)
		(end 274.656804 -53.594)
		(width 0.0889)
		(layer "In2.Cu")
		(net "M_A_DQ<45>")
	)
	(segment
		(start 283.565346 -25.3238)
		(end 283.921454 -25.3238)
		(width 0.14224)
		(layer "In2.Cu")
		(net "M_A_DQ<45>")
	)
	(segment
		(start 274.577048 -54.633876)
		(end 274.568158 -54.618636)
		(width 0.0889)
		(layer "In2.Cu")
		(net "M_A_DQ<45>")
	)
	(segment
		(start 272.766536 -47.570136)
		(end 272.1102 -46.9138)
		(width 0.0889)
		(layer "In2.Cu")
		(net "M_A_DQ<45>")
	)
	(segment
		(start 289.353752 -22.749256)
		(end 289.823652 -22.279356)
		(width 0.14224)
		(layer "In2.Cu")
		(net "M_A_DQ<45>")
	)
	(segment
		(start 272.1102 -33.4518)
		(end 280.6446 -24.9174)
		(width 0.14224)
		(layer "In2.Cu")
		(net "M_A_DQ<45>")
	)
	(segment
		(start 285.089346 -25.3238)
		(end 285.547054 -25.3238)
		(width 0.14224)
		(layer "In2.Cu")
		(net "M_A_DQ<45>")
	)
	(segment
		(start 280.6446 -24.9174)
		(end 281.660346 -24.9174)
		(width 0.14224)
		(layer "In2.Cu")
		(net "M_A_DQ<45>")
	)
	(segment
		(start 282.729686 -24.9174)
		(end 283.158946 -24.9174)
		(width 0.14224)
		(layer "In2.Cu")
		(net "M_A_DQ<45>")
	)
	(segment
		(start 285.953454 -24.9174)
		(end 286.8168 -24.9174)
		(width 0.14224)
		(layer "In2.Cu")
		(net "M_A_DQ<45>")
	)
	(segment
		(start 283.158946 -24.9174)
		(end 283.565346 -25.3238)
		(width 0.14224)
		(layer "In2.Cu")
		(net "M_A_DQ<45>")
	)
	(segment
		(start 282.501086 -25.146)
		(end 282.729686 -24.9174)
		(width 0.14224)
		(layer "In2.Cu")
		(net "M_A_DQ<45>")
	)
	(segment
		(start 284.327854 -24.9174)
		(end 284.682946 -24.9174)
		(width 0.14224)
		(layer "In2.Cu")
		(net "M_A_DQ<45>")
	)
	(segment
		(start 289.883596 -23.920196)
		(end 289.883596 -23.704296)
		(width 0.14224)
		(layer "In2.Cu")
		(net "M_A_DQ<45>")
	)
	(segment
		(start 274.914614 -57.390538)
		(end 275.244052 -56.629554)
		(width 0.0889)
		(layer "In2.Cu")
		(net "M_A_DQ<45>")
	)
	(segment
		(start 290.135056 -18.66265)
		(end 290.331906 -18.4658)
		(width 0.14224)
		(layer "In2.Cu")
		(net "M_A_DQ<45>")
	)
	(segment
		(start 289.883596 -23.704296)
		(end 289.353752 -23.174452)
		(width 0.14224)
		(layer "In2.Cu")
		(net "M_A_DQ<45>")
	)
	(segment
		(start 287.762696 -24.474678)
		(end 288.190178 -24.047196)
		(width 0.14224)
		(layer "In2.Cu")
		(net "M_A_DQ<45>")
	)
	(segment
		(start 272.766536 -50.593752)
		(end 272.766536 -47.570136)
		(width 0.0889)
		(layer "In2.Cu")
		(net "M_A_DQ<45>")
	)
	(segment
		(start 275.261324 -56.199786)
		(end 275.232876 -56.150256)
		(width 0.0889)
		(layer "In2.Cu")
		(net "M_A_DQ<45>")
	)
	(segment
		(start 281.660346 -24.9174)
		(end 281.888946 -25.146)
		(width 0.14224)
		(layer "In2.Cu")
		(net "M_A_DQ<45>")
	)
	(segment
		(start 289.620706 -17.653)
		(end 289.049968 -17.082262)
		(width 0.14224)
		(layer "In2.Cu")
		(net "M_A_DQ<45>")
	)
	(segment
		(start 274.568158 -54.618636)
		(end 274.563332 -54.61)
		(width 0.0889)
		(layer "In2.Cu")
		(net "M_A_DQ<45>")
	)
	(segment
		(start 289.931602 -17.653)
		(end 289.620706 -17.653)
		(width 0.14224)
		(layer "In2.Cu")
		(net "M_A_DQ<45>")
	)
	(segment
		(start 289.353752 -23.174452)
		(end 289.353752 -22.749256)
		(width 0.14224)
		(layer "In2.Cu")
		(net "M_A_DQ<45>")
	)
	(segment
		(start 275.244052 -56.629554)
		(end 275.26615 -56.5912)
		(width 0.0889)
		(layer "In2.Cu")
		(net "M_A_DQ<45>")
	)
	(arc
		(start 274.543012 -55.556912)
		(mid 274.515726 -55.380284)
		(end 274.568158 -55.20944)
		(width 0.0889)
		(layer "In2.Cu")
		(net "M_A_DQ<45>")
	)
	(arc
		(start 275.232876 -56.150256)
		(mid 275.064238 -55.925683)
		(end 274.814792 -55.796688)
		(width 0.0889)
		(layer "In2.Cu")
		(net "M_A_DQ<45>")
	)
	(arc
		(start 275.26615 -56.5912)
		(mid 275.314905 -56.394848)
		(end 275.261324 -56.199786)
		(width 0.0889)
		(layer "In2.Cu")
		(net "M_A_DQ<45>")
	)
	(arc
		(start 274.814792 -55.796688)
		(mid 274.696269 -55.744405)
		(end 274.60067 -55.656988)
		(width 0.0889)
		(layer "In2.Cu")
		(net "M_A_DQ<45>")
	)
	(arc
		(start 274.568158 -55.20944)
		(mid 274.647347 -54.922825)
		(end 274.577048 -54.633876)
		(width 0.0889)
		(layer "In2.Cu")
		(net "M_A_DQ<45>")
	)
	(arc
		(start 274.563332 -54.61)
		(mid 274.514546 -54.413648)
		(end 274.568158 -54.218586)
		(width 0.0889)
		(layer "In2.Cu")
		(net "M_A_DQ<45>")
	)
	(arc
		(start 274.60067 -55.656988)
		(mid 274.568232 -55.609029)
		(end 274.543012 -55.556912)
		(width 0.0889)
		(layer "In2.Cu")
		(net "M_A_DQ<45>")
	)
	(segment
		(start 289.90036 -20.023582)
		(end 289.899852 -20.023582)
		(width 0.1651)
		(layer "F.Cu")
		(net "M_A_DQ<44>")
	)
	(segment
		(start 289.899852 -18.692368)
		(end 289.801808 -18.161)
		(width 0.1651)
		(layer "F.Cu")
		(net "M_A_DQ<44>")
	)
	(segment
		(start 275.486114 -56.399938)
		(end 274.914614 -56.399938)
		(width 0.1016)
		(layer "F.Cu")
		(net "M_A_DQ<44>")
	)
	(segment
		(start 289.899852 -20.023582)
		(end 289.899852 -18.692368)
		(width 0.1651)
		(layer "F.Cu")
		(net "M_A_DQ<44>")
	)
	(via
		(at 289.049968 -23.560278)
		(size 0.508)
		(drill 0.254)
		(layers "F.Cu" "B.Cu")
		(net "M_A_DQ<44>")
	)
	(via
		(at 289.801808 -18.161)
		(size 0.508)
		(drill 0.254)
		(layers "F.Cu" "B.Cu")
		(net "M_A_DQ<44>")
	)
	(via
		(at 274.914614 -56.399938)
		(size 0.508)
		(drill 0.254)
		(layers "F.Cu" "B.Cu")
		(net "M_A_DQ<44>")
	)
	(segment
		(start 289.049968 -24.824182)
		(end 289.049968 -23.560278)
		(width 0.1651)
		(layer "B.Cu")
		(net "M_A_DQ<44>")
	)
	(segment
		(start 289.050476 -24.824182)
		(end 289.049968 -24.824182)
		(width 0.1651)
		(layer "B.Cu")
		(net "M_A_DQ<44>")
	)
	(segment
		(start 270.9672 -40.445944)
		(end 271.12214 -40.291004)
		(width 0.14224)
		(layer "In2.Cu")
		(net "M_A_DQ<44>")
	)
	(segment
		(start 289.161474 -19.5834)
		(end 289.161474 -19.278854)
		(width 0.14224)
		(layer "In2.Cu")
		(net "M_A_DQ<44>")
	)
	(segment
		(start 271.12214 -40.291004)
		(end 271.42186 -40.291004)
		(width 0.14224)
		(layer "In2.Cu")
		(net "M_A_DQ<44>")
	)
	(segment
		(start 271.42186 -44.268644)
		(end 271.5768 -44.113704)
		(width 0.14224)
		(layer "In2.Cu")
		(net "M_A_DQ<44>")
	)
	(segment
		(start 271.12214 -44.931584)
		(end 270.9672 -44.776644)
		(width 0.14224)
		(layer "In2.Cu")
		(net "M_A_DQ<44>")
	)
	(segment
		(start 271.5768 -47.12589)
		(end 271.5768 -45.086524)
		(width 0.14224)
		(layer "In2.Cu")
		(net "M_A_DQ<44>")
	)
	(segment
		(start 287.573212 -24.017478)
		(end 288.026094 -23.564596)
		(width 0.14224)
		(layer "In2.Cu")
		(net "M_A_DQ<44>")
	)
	(segment
		(start 271.12214 -41.616884)
		(end 271.42186 -41.616884)
		(width 0.14224)
		(layer "In2.Cu")
		(net "M_A_DQ<44>")
	)
	(segment
		(start 271.12214 -42.279824)
		(end 270.9672 -42.124884)
		(width 0.14224)
		(layer "In2.Cu")
		(net "M_A_DQ<44>")
	)
	(segment
		(start 270.9672 -41.771824)
		(end 271.12214 -41.616884)
		(width 0.14224)
		(layer "In2.Cu")
		(net "M_A_DQ<44>")
	)
	(segment
		(start 270.9672 -43.097704)
		(end 271.12214 -42.942764)
		(width 0.14224)
		(layer "In2.Cu")
		(net "M_A_DQ<44>")
	)
	(segment
		(start 289.542474 -20.2692)
		(end 289.542474 -19.9644)
		(width 0.14224)
		(layer "In2.Cu")
		(net "M_A_DQ<44>")
	)
	(segment
		(start 289.174174 -20.6375)
		(end 289.542474 -20.2692)
		(width 0.14224)
		(layer "In2.Cu")
		(net "M_A_DQ<44>")
	)
	(segment
		(start 270.9672 -43.450764)
		(end 270.9672 -43.097704)
		(width 0.14224)
		(layer "In2.Cu")
		(net "M_A_DQ<44>")
	)
	(segment
		(start 274.402804 -54.713886)
		(end 274.392136 -54.695344)
		(width 0.0889)
		(layer "In2.Cu")
		(net "M_A_DQ<44>")
	)
	(segment
		(start 271.5768 -42.787824)
		(end 271.5768 -42.434764)
		(width 0.14224)
		(layer "In2.Cu")
		(net "M_A_DQ<44>")
	)
	(segment
		(start 271.12214 -39.628064)
		(end 270.9672 -39.473124)
		(width 0.14224)
		(layer "In2.Cu")
		(net "M_A_DQ<44>")
	)
	(segment
		(start 271.5768 -41.108884)
		(end 271.42186 -40.953944)
		(width 0.14224)
		(layer "In2.Cu")
		(net "M_A_DQ<44>")
	)
	(segment
		(start 288.026094 -23.564596)
		(end 289.04565 -23.564596)
		(width 0.14224)
		(layer "In2.Cu")
		(net "M_A_DQ<44>")
	)
	(segment
		(start 271.5768 -40.136064)
		(end 271.5768 -39.783004)
		(width 0.14224)
		(layer "In2.Cu")
		(net "M_A_DQ<44>")
	)
	(segment
		(start 270.9672 -40.799004)
		(end 270.9672 -40.445944)
		(width 0.14224)
		(layer "In2.Cu")
		(net "M_A_DQ<44>")
	)
	(segment
		(start 274.914614 -56.399938)
		(end 274.41906 -55.733188)
		(width 0.0889)
		(layer "In2.Cu")
		(net "M_A_DQ<44>")
	)
	(segment
		(start 273.717258 -51.813968)
		(end 272.576036 -50.672746)
		(width 0.0889)
		(layer "In2.Cu")
		(net "M_A_DQ<44>")
	)
	(segment
		(start 271.42186 -44.931584)
		(end 271.12214 -44.931584)
		(width 0.14224)
		(layer "In2.Cu")
		(net "M_A_DQ<44>")
	)
	(segment
		(start 271.42186 -40.291004)
		(end 271.5768 -40.136064)
		(width 0.14224)
		(layer "In2.Cu")
		(net "M_A_DQ<44>")
	)
	(segment
		(start 274.402804 -54.122828)
		(end 274.466304 -54.013608)
		(width 0.0889)
		(layer "In2.Cu")
		(net "M_A_DQ<44>")
	)
	(segment
		(start 271.5768 -43.760644)
		(end 271.42186 -43.605704)
		(width 0.14224)
		(layer "In2.Cu")
		(net "M_A_DQ<44>")
	)
	(segment
		(start 270.9672 -33.857946)
		(end 280.491946 -24.3332)
		(width 0.14224)
		(layer "In2.Cu")
		(net "M_A_DQ<44>")
	)
	(segment
		(start 271.5768 -41.461944)
		(end 271.5768 -41.108884)
		(width 0.14224)
		(layer "In2.Cu")
		(net "M_A_DQ<44>")
	)
	(segment
		(start 273.717258 -52.923948)
		(end 273.717258 -51.813968)
		(width 0.0889)
		(layer "In2.Cu")
		(net "M_A_DQ<44>")
	)
	(segment
		(start 270.9672 -44.776644)
		(end 270.9672 -44.423584)
		(width 0.14224)
		(layer "In2.Cu")
		(net "M_A_DQ<44>")
	)
	(segment
		(start 271.42186 -41.616884)
		(end 271.5768 -41.461944)
		(width 0.14224)
		(layer "In2.Cu")
		(net "M_A_DQ<44>")
	)
	(segment
		(start 289.542474 -19.9644)
		(end 289.161474 -19.5834)
		(width 0.14224)
		(layer "In2.Cu")
		(net "M_A_DQ<44>")
	)
	(segment
		(start 271.5768 -45.086524)
		(end 271.42186 -44.931584)
		(width 0.14224)
		(layer "In2.Cu")
		(net "M_A_DQ<44>")
	)
	(segment
		(start 270.9672 -44.423584)
		(end 271.12214 -44.268644)
		(width 0.14224)
		(layer "In2.Cu")
		(net "M_A_DQ<44>")
	)
	(segment
		(start 272.576036 -48.125126)
		(end 271.5768 -47.12589)
		(width 0.0889)
		(layer "In2.Cu")
		(net "M_A_DQ<44>")
	)
	(segment
		(start 280.491946 -24.3332)
		(end 286.502856 -24.3332)
		(width 0.14224)
		(layer "In2.Cu")
		(net "M_A_DQ<44>")
	)
	(segment
		(start 270.9672 -39.473124)
		(end 270.9672 -33.857946)
		(width 0.14224)
		(layer "In2.Cu")
		(net "M_A_DQ<44>")
	)
	(segment
		(start 289.525456 -21.344128)
		(end 289.174174 -20.992846)
		(width 0.14224)
		(layer "In2.Cu")
		(net "M_A_DQ<44>")
	)
	(segment
		(start 271.42186 -42.279824)
		(end 271.12214 -42.279824)
		(width 0.14224)
		(layer "In2.Cu")
		(net "M_A_DQ<44>")
	)
	(segment
		(start 289.525456 -18.914872)
		(end 289.525456 -18.437352)
		(width 0.14224)
		(layer "In2.Cu")
		(net "M_A_DQ<44>")
	)
	(segment
		(start 274.466304 -54.013608)
		(end 274.466304 -53.672994)
		(width 0.0889)
		(layer "In2.Cu")
		(net "M_A_DQ<44>")
	)
	(segment
		(start 289.525456 -21.818854)
		(end 289.525456 -21.344128)
		(width 0.14224)
		(layer "In2.Cu")
		(net "M_A_DQ<44>")
	)
	(segment
		(start 288.814256 -23.324566)
		(end 288.814256 -22.530054)
		(width 0.14224)
		(layer "In2.Cu")
		(net "M_A_DQ<44>")
	)
	(segment
		(start 289.174174 -20.992846)
		(end 289.174174 -20.6375)
		(width 0.14224)
		(layer "In2.Cu")
		(net "M_A_DQ<44>")
	)
	(segment
		(start 271.5768 -44.113704)
		(end 271.5768 -43.760644)
		(width 0.14224)
		(layer "In2.Cu")
		(net "M_A_DQ<44>")
	)
	(segment
		(start 271.12214 -43.605704)
		(end 270.9672 -43.450764)
		(width 0.14224)
		(layer "In2.Cu")
		(net "M_A_DQ<44>")
	)
	(segment
		(start 271.42186 -40.953944)
		(end 271.12214 -40.953944)
		(width 0.14224)
		(layer "In2.Cu")
		(net "M_A_DQ<44>")
	)
	(segment
		(start 274.41906 -55.733188)
		(end 274.402804 -55.704486)
		(width 0.0889)
		(layer "In2.Cu")
		(net "M_A_DQ<44>")
	)
	(segment
		(start 289.04565 -23.564596)
		(end 289.049968 -23.560278)
		(width 0.14224)
		(layer "In2.Cu")
		(net "M_A_DQ<44>")
	)
	(segment
		(start 271.42186 -43.605704)
		(end 271.12214 -43.605704)
		(width 0.14224)
		(layer "In2.Cu")
		(net "M_A_DQ<44>")
	)
	(segment
		(start 270.9672 -42.124884)
		(end 270.9672 -41.771824)
		(width 0.14224)
		(layer "In2.Cu")
		(net "M_A_DQ<44>")
	)
	(segment
		(start 289.049968 -23.560278)
		(end 288.814256 -23.324566)
		(width 0.14224)
		(layer "In2.Cu")
		(net "M_A_DQ<44>")
	)
	(segment
		(start 271.12214 -44.268644)
		(end 271.42186 -44.268644)
		(width 0.14224)
		(layer "In2.Cu")
		(net "M_A_DQ<44>")
	)
	(segment
		(start 271.5768 -42.434764)
		(end 271.42186 -42.279824)
		(width 0.14224)
		(layer "In2.Cu")
		(net "M_A_DQ<44>")
	)
	(segment
		(start 286.818578 -24.017478)
		(end 287.573212 -24.017478)
		(width 0.14224)
		(layer "In2.Cu")
		(net "M_A_DQ<44>")
	)
	(segment
		(start 288.814256 -22.530054)
		(end 289.525456 -21.818854)
		(width 0.14224)
		(layer "In2.Cu")
		(net "M_A_DQ<44>")
	)
	(segment
		(start 271.12214 -42.942764)
		(end 271.42186 -42.942764)
		(width 0.14224)
		(layer "In2.Cu")
		(net "M_A_DQ<44>")
	)
	(segment
		(start 271.5768 -39.783004)
		(end 271.42186 -39.628064)
		(width 0.14224)
		(layer "In2.Cu")
		(net "M_A_DQ<44>")
	)
	(segment
		(start 286.502856 -24.3332)
		(end 286.818578 -24.017478)
		(width 0.14224)
		(layer "In2.Cu")
		(net "M_A_DQ<44>")
	)
	(segment
		(start 274.466304 -53.672994)
		(end 273.717258 -52.923948)
		(width 0.0889)
		(layer "In2.Cu")
		(net "M_A_DQ<44>")
	)
	(segment
		(start 271.42186 -39.628064)
		(end 271.12214 -39.628064)
		(width 0.14224)
		(layer "In2.Cu")
		(net "M_A_DQ<44>")
	)
	(segment
		(start 271.12214 -40.953944)
		(end 270.9672 -40.799004)
		(width 0.14224)
		(layer "In2.Cu")
		(net "M_A_DQ<44>")
	)
	(segment
		(start 272.576036 -50.672746)
		(end 272.576036 -48.125126)
		(width 0.0889)
		(layer "In2.Cu")
		(net "M_A_DQ<44>")
	)
	(segment
		(start 271.42186 -42.942764)
		(end 271.5768 -42.787824)
		(width 0.14224)
		(layer "In2.Cu")
		(net "M_A_DQ<44>")
	)
	(segment
		(start 289.525456 -18.437352)
		(end 289.801808 -18.161)
		(width 0.14224)
		(layer "In2.Cu")
		(net "M_A_DQ<44>")
	)
	(segment
		(start 289.161474 -19.278854)
		(end 289.525456 -18.914872)
		(width 0.14224)
		(layer "In2.Cu")
		(net "M_A_DQ<44>")
	)
	(arc
		(start 274.392136 -54.695344)
		(mid 274.323537 -54.40771)
		(end 274.402804 -54.122828)
		(width 0.0889)
		(layer "In2.Cu")
		(net "M_A_DQ<44>")
	)
	(arc
		(start 274.373086 -55.646574)
		(mid 274.324424 -55.376596)
		(end 274.402804 -55.113682)
		(width 0.0889)
		(layer "In2.Cu")
		(net "M_A_DQ<44>")
	)
	(arc
		(start 274.402804 -55.113682)
		(mid 274.456337 -54.913784)
		(end 274.402804 -54.713886)
		(width 0.0889)
		(layer "In2.Cu")
		(net "M_A_DQ<44>")
	)
	(arc
		(start 274.402804 -55.704486)
		(mid 274.38706 -55.675984)
		(end 274.373086 -55.646574)
		(width 0.0889)
		(layer "In2.Cu")
		(net "M_A_DQ<44>")
	)
	(segment
		(start 296.69994 -15.423642)
		(end 296.69994 -16.687546)
		(width 0.1651)
		(layer "F.Cu")
		(net "M_A_DQ<43>")
	)
	(segment
		(start 278.920194 -57.390538)
		(end 278.348694 -57.390538)
		(width 0.1016)
		(layer "F.Cu")
		(net "M_A_DQ<43>")
	)
	(segment
		(start 296.700448 -15.423642)
		(end 296.69994 -15.423642)
		(width 0.1651)
		(layer "F.Cu")
		(net "M_A_DQ<43>")
	)
	(via
		(at 297.549824 -22.279356)
		(size 0.508)
		(drill 0.254)
		(layers "F.Cu" "B.Cu")
		(net "M_A_DQ<43>")
	)
	(via
		(at 296.69994 -16.687546)
		(size 0.508)
		(drill 0.254)
		(layers "F.Cu" "B.Cu")
		(net "M_A_DQ<43>")
	)
	(via
		(at 278.348694 -57.390538)
		(size 0.508)
		(drill 0.254)
		(layers "F.Cu" "B.Cu")
		(net "M_A_DQ<43>")
	)
	(segment
		(start 297.549824 -20.224242)
		(end 297.549824 -22.279356)
		(width 0.1651)
		(layer "B.Cu")
		(net "M_A_DQ<43>")
	)
	(segment
		(start 297.550332 -20.224242)
		(end 297.549824 -20.224242)
		(width 0.1651)
		(layer "B.Cu")
		(net "M_A_DQ<43>")
	)
	(segment
		(start 297.020996 -22.808184)
		(end 297.549824 -22.279356)
		(width 0.14224)
		(layer "In2.Cu")
		(net "M_A_DQ<43>")
	)
	(segment
		(start 277.2664 -40.5892)
		(end 285.8516 -32.004)
		(width 0.14224)
		(layer "In2.Cu")
		(net "M_A_DQ<43>")
	)
	(segment
		(start 278.860504 -56.695086)
		(end 278.866854 -56.684418)
		(width 0.0889)
		(layer "In2.Cu")
		(net "M_A_DQ<43>")
	)
	(segment
		(start 278.855678 -55.713122)
		(end 278.860504 -55.704486)
		(width 0.0889)
		(layer "In2.Cu")
		(net "M_A_DQ<43>")
	)
	(segment
		(start 277.2664 -47.522638)
		(end 277.2664 -40.5892)
		(width 0.14224)
		(layer "In2.Cu")
		(net "M_A_DQ<43>")
	)
	(segment
		(start 297.549824 -22.279356)
		(end 297.90263 -21.92655)
		(width 0.14224)
		(layer "In2.Cu")
		(net "M_A_DQ<43>")
	)
	(segment
		(start 296.69994 -17.006062)
		(end 296.69994 -16.687546)
		(width 0.14224)
		(layer "In2.Cu")
		(net "M_A_DQ<43>")
	)
	(segment
		(start 278.860504 -55.113936)
		(end 278.807164 -55.018686)
		(width 0.0889)
		(layer "In2.Cu")
		(net "M_A_DQ<43>")
	)
	(segment
		(start 278.348694 -57.390538)
		(end 278.348694 -57.052464)
		(width 0.0889)
		(layer "In2.Cu")
		(net "M_A_DQ<43>")
	)
	(segment
		(start 278.807164 -53.002942)
		(end 278.939244 -52.870862)
		(width 0.0889)
		(layer "In2.Cu")
		(net "M_A_DQ<43>")
	)
	(segment
		(start 285.8516 -32.004)
		(end 294.049196 -32.004)
		(width 0.14224)
		(layer "In2.Cu")
		(net "M_A_DQ<43>")
	)
	(segment
		(start 298.058078 -18.4658)
		(end 298.058078 -18.1102)
		(width 0.14224)
		(layer "In2.Cu")
		(net "M_A_DQ<43>")
	)
	(segment
		(start 276.701504 -48.087534)
		(end 277.2664 -47.522638)
		(width 0.0889)
		(layer "In2.Cu")
		(net "M_A_DQ<43>")
	)
	(segment
		(start 278.860504 -55.704486)
		(end 278.866854 -55.693818)
		(width 0.0889)
		(layer "In2.Cu")
		(net "M_A_DQ<43>")
	)
	(segment
		(start 276.701504 -48.794924)
		(end 276.701504 -48.087534)
		(width 0.0889)
		(layer "In2.Cu")
		(net "M_A_DQ<43>")
	)
	(segment
		(start 277.95601 -50.04943)
		(end 276.701504 -48.794924)
		(width 0.0889)
		(layer "In2.Cu")
		(net "M_A_DQ<43>")
	)
	(segment
		(start 297.600878 -17.653)
		(end 297.346878 -17.653)
		(width 0.14224)
		(layer "In2.Cu")
		(net "M_A_DQ<43>")
	)
	(segment
		(start 297.346878 -17.653)
		(end 296.69994 -17.006062)
		(width 0.14224)
		(layer "In2.Cu")
		(net "M_A_DQ<43>")
	)
	(segment
		(start 278.939244 -52.870862)
		(end 278.939244 -52.180998)
		(width 0.0889)
		(layer "In2.Cu")
		(net "M_A_DQ<43>")
	)
	(segment
		(start 277.95601 -51.197764)
		(end 277.95601 -50.04943)
		(width 0.0889)
		(layer "In2.Cu")
		(net "M_A_DQ<43>")
	)
	(segment
		(start 297.020996 -23.183596)
		(end 297.020996 -22.808184)
		(width 0.14224)
		(layer "In2.Cu")
		(net "M_A_DQ<43>")
	)
	(segment
		(start 297.90263 -18.621248)
		(end 298.058078 -18.4658)
		(width 0.14224)
		(layer "In2.Cu")
		(net "M_A_DQ<43>")
	)
	(segment
		(start 297.808396 -23.970996)
		(end 297.020996 -23.183596)
		(width 0.14224)
		(layer "In2.Cu")
		(net "M_A_DQ<43>")
	)
	(segment
		(start 278.348694 -57.052464)
		(end 278.413972 -56.987186)
		(width 0.0889)
		(layer "In2.Cu")
		(net "M_A_DQ<43>")
	)
	(segment
		(start 278.807164 -55.018686)
		(end 278.807164 -53.002942)
		(width 0.0889)
		(layer "In2.Cu")
		(net "M_A_DQ<43>")
	)
	(segment
		(start 297.8404 -26.7462)
		(end 297.808396 -26.714196)
		(width 0.14224)
		(layer "In2.Cu")
		(net "M_A_DQ<43>")
	)
	(segment
		(start 298.058078 -18.1102)
		(end 297.600878 -17.653)
		(width 0.14224)
		(layer "In2.Cu")
		(net "M_A_DQ<43>")
	)
	(segment
		(start 297.90263 -21.92655)
		(end 297.90263 -18.621248)
		(width 0.14224)
		(layer "In2.Cu")
		(net "M_A_DQ<43>")
	)
	(segment
		(start 294.049196 -32.004)
		(end 297.8404 -28.212796)
		(width 0.14224)
		(layer "In2.Cu")
		(net "M_A_DQ<43>")
	)
	(segment
		(start 297.808396 -26.714196)
		(end 297.808396 -23.970996)
		(width 0.14224)
		(layer "In2.Cu")
		(net "M_A_DQ<43>")
	)
	(segment
		(start 297.8404 -28.212796)
		(end 297.8404 -26.7462)
		(width 0.14224)
		(layer "In2.Cu")
		(net "M_A_DQ<43>")
	)
	(segment
		(start 278.939244 -52.180998)
		(end 277.95601 -51.197764)
		(width 0.0889)
		(layer "In2.Cu")
		(net "M_A_DQ<43>")
	)
	(arc
		(start 278.860504 -56.104536)
		(mid 278.807034 -55.909473)
		(end 278.855678 -55.713122)
		(width 0.0889)
		(layer "In2.Cu")
		(net "M_A_DQ<43>")
	)
	(arc
		(start 278.866854 -55.693818)
		(mid 278.939652 -55.403055)
		(end 278.860504 -55.113936)
		(width 0.0889)
		(layer "In2.Cu")
		(net "M_A_DQ<43>")
	)
	(arc
		(start 278.866854 -56.684418)
		(mid 278.939652 -56.393655)
		(end 278.860504 -56.104536)
		(width 0.0889)
		(layer "In2.Cu")
		(net "M_A_DQ<43>")
	)
	(arc
		(start 278.413972 -56.987186)
		(mid 278.672109 -56.894432)
		(end 278.860504 -56.695086)
		(width 0.0889)
		(layer "In2.Cu")
		(net "M_A_DQ<43>")
	)
	(segment
		(start 297.549824 -20.023582)
		(end 297.549824 -19.026632)
		(width 0.1651)
		(layer "F.Cu")
		(net "M_A_DQ<42>")
	)
	(segment
		(start 297.549824 -19.026632)
		(end 297.681396 -18.89506)
		(width 0.1651)
		(layer "F.Cu")
		(net "M_A_DQ<42>")
	)
	(segment
		(start 278.920194 -56.399938)
		(end 278.348694 -56.399938)
		(width 0.1016)
		(layer "F.Cu")
		(net "M_A_DQ<42>")
	)
	(segment
		(start 297.681396 -18.67154)
		(end 297.549824 -18.539968)
		(width 0.1651)
		(layer "F.Cu")
		(net "M_A_DQ<42>")
	)
	(segment
		(start 297.681396 -18.89506)
		(end 297.681396 -18.67154)
		(width 0.1651)
		(layer "F.Cu")
		(net "M_A_DQ<42>")
	)
	(segment
		(start 297.550332 -20.023582)
		(end 297.549824 -20.023582)
		(width 0.1651)
		(layer "F.Cu")
		(net "M_A_DQ<42>")
	)
	(segment
		(start 297.549824 -18.539968)
		(end 297.549824 -18.2626)
		(width 0.1651)
		(layer "F.Cu")
		(net "M_A_DQ<42>")
	)
	(via
		(at 278.348694 -56.399938)
		(size 0.508)
		(drill 0.254)
		(layers "F.Cu" "B.Cu")
		(net "M_A_DQ<42>")
	)
	(via
		(at 296.69994 -23.560278)
		(size 0.508)
		(drill 0.254)
		(layers "F.Cu" "B.Cu")
		(net "M_A_DQ<42>")
	)
	(via
		(at 297.549824 -18.2626)
		(size 0.508)
		(drill 0.254)
		(layers "F.Cu" "B.Cu")
		(net "M_A_DQ<42>")
	)
	(segment
		(start 296.69994 -24.824182)
		(end 296.69994 -23.560278)
		(width 0.1651)
		(layer "B.Cu")
		(net "M_A_DQ<42>")
	)
	(segment
		(start 296.700448 -24.824182)
		(end 296.69994 -24.824182)
		(width 0.1651)
		(layer "B.Cu")
		(net "M_A_DQ<42>")
	)
	(segment
		(start 296.415206 -22.5298)
		(end 297.264074 -21.680932)
		(width 0.14224)
		(layer "In2.Cu")
		(net "M_A_DQ<42>")
	)
	(segment
		(start 278.616664 -55.072788)
		(end 278.616664 -52.923694)
		(width 0.0889)
		(layer "In2.Cu")
		(net "M_A_DQ<42>")
	)
	(segment
		(start 296.9006 -26.9748)
		(end 297.173396 -26.702004)
		(width 0.14224)
		(layer "In2.Cu")
		(net "M_A_DQ<42>")
	)
	(segment
		(start 296.806874 -20.55495)
		(end 297.111674 -20.25015)
		(width 0.14224)
		(layer "In2.Cu")
		(net "M_A_DQ<42>")
	)
	(segment
		(start 297.0022 -24.4348)
		(end 296.545 -24.4348)
		(width 0.14224)
		(layer "In2.Cu")
		(net "M_A_DQ<42>")
	)
	(segment
		(start 297.173396 -26.702004)
		(end 297.173396 -24.605996)
		(width 0.14224)
		(layer "In2.Cu")
		(net "M_A_DQ<42>")
	)
	(segment
		(start 296.19575 -28.959048)
		(end 296.19575 -28.301442)
		(width 0.14224)
		(layer "In2.Cu")
		(net "M_A_DQ<42>")
	)
	(segment
		(start 296.806874 -19.659346)
		(end 296.806874 -19.310604)
		(width 0.14224)
		(layer "In2.Cu")
		(net "M_A_DQ<42>")
	)
	(segment
		(start 278.748744 -52.260754)
		(end 277.76551 -51.27752)
		(width 0.0889)
		(layer "In2.Cu")
		(net "M_A_DQ<42>")
	)
	(segment
		(start 278.695404 -55.209186)
		(end 278.616664 -55.072788)
		(width 0.0889)
		(layer "In2.Cu")
		(net "M_A_DQ<42>")
	)
	(segment
		(start 296.806874 -20.955)
		(end 296.806874 -20.55495)
		(width 0.14224)
		(layer "In2.Cu")
		(net "M_A_DQ<42>")
	)
	(segment
		(start 278.348694 -56.738012)
		(end 278.406606 -56.795924)
		(width 0.0889)
		(layer "In2.Cu")
		(net "M_A_DQ<42>")
	)
	(segment
		(start 278.348694 -56.399938)
		(end 278.348694 -56.738012)
		(width 0.0889)
		(layer "In2.Cu")
		(net "M_A_DQ<42>")
	)
	(segment
		(start 297.173396 -24.605996)
		(end 297.0022 -24.4348)
		(width 0.14224)
		(layer "In2.Cu")
		(net "M_A_DQ<42>")
	)
	(segment
		(start 296.69994 -23.560278)
		(end 296.415206 -23.275544)
		(width 0.14224)
		(layer "In2.Cu")
		(net "M_A_DQ<42>")
	)
	(segment
		(start 285.496 -31.2928)
		(end 293.861998 -31.2928)
		(width 0.14224)
		(layer "In2.Cu")
		(net "M_A_DQ<42>")
	)
	(segment
		(start 276.511004 -47.669196)
		(end 276.7838 -47.3964)
		(width 0.0889)
		(layer "In2.Cu")
		(net "M_A_DQ<42>")
	)
	(segment
		(start 296.806874 -19.310604)
		(end 297.151806 -18.965672)
		(width 0.14224)
		(layer "In2.Cu")
		(net "M_A_DQ<42>")
	)
	(segment
		(start 278.616664 -52.923694)
		(end 278.748744 -52.791614)
		(width 0.0889)
		(layer "In2.Cu")
		(net "M_A_DQ<42>")
	)
	(segment
		(start 276.7838 -40.005)
		(end 285.496 -31.2928)
		(width 0.14224)
		(layer "In2.Cu")
		(net "M_A_DQ<42>")
	)
	(segment
		(start 296.3926 -23.867618)
		(end 296.69994 -23.560278)
		(width 0.14224)
		(layer "In2.Cu")
		(net "M_A_DQ<42>")
	)
	(segment
		(start 297.111674 -19.964146)
		(end 296.806874 -19.659346)
		(width 0.14224)
		(layer "In2.Cu")
		(net "M_A_DQ<42>")
	)
	(segment
		(start 293.861998 -31.2928)
		(end 296.19575 -28.959048)
		(width 0.14224)
		(layer "In2.Cu")
		(net "M_A_DQ<42>")
	)
	(segment
		(start 296.3926 -28.104592)
		(end 296.3926 -27.326336)
		(width 0.14224)
		(layer "In2.Cu")
		(net "M_A_DQ<42>")
	)
	(segment
		(start 296.744136 -26.9748)
		(end 296.9006 -26.9748)
		(width 0.14224)
		(layer "In2.Cu")
		(net "M_A_DQ<42>")
	)
	(segment
		(start 297.264074 -21.680932)
		(end 297.264074 -21.4122)
		(width 0.14224)
		(layer "In2.Cu")
		(net "M_A_DQ<42>")
	)
	(segment
		(start 297.111674 -20.25015)
		(end 297.111674 -19.964146)
		(width 0.14224)
		(layer "In2.Cu")
		(net "M_A_DQ<42>")
	)
	(segment
		(start 278.748744 -52.791614)
		(end 278.748744 -52.260754)
		(width 0.0889)
		(layer "In2.Cu")
		(net "M_A_DQ<42>")
	)
	(segment
		(start 277.76551 -51.27752)
		(end 277.76551 -50.128424)
		(width 0.0889)
		(layer "In2.Cu")
		(net "M_A_DQ<42>")
	)
	(segment
		(start 276.511004 -48.873918)
		(end 276.511004 -47.669196)
		(width 0.0889)
		(layer "In2.Cu")
		(net "M_A_DQ<42>")
	)
	(segment
		(start 297.151806 -18.965672)
		(end 297.151806 -18.660618)
		(width 0.14224)
		(layer "In2.Cu")
		(net "M_A_DQ<42>")
	)
	(segment
		(start 296.3926 -27.326336)
		(end 296.744136 -26.9748)
		(width 0.14224)
		(layer "In2.Cu")
		(net "M_A_DQ<42>")
	)
	(segment
		(start 297.264074 -21.4122)
		(end 296.806874 -20.955)
		(width 0.14224)
		(layer "In2.Cu")
		(net "M_A_DQ<42>")
	)
	(segment
		(start 296.19575 -28.301442)
		(end 296.3926 -28.104592)
		(width 0.14224)
		(layer "In2.Cu")
		(net "M_A_DQ<42>")
	)
	(segment
		(start 297.151806 -18.660618)
		(end 297.549824 -18.2626)
		(width 0.14224)
		(layer "In2.Cu")
		(net "M_A_DQ<42>")
	)
	(segment
		(start 296.545 -24.4348)
		(end 296.3926 -24.2824)
		(width 0.14224)
		(layer "In2.Cu")
		(net "M_A_DQ<42>")
	)
	(segment
		(start 276.7838 -47.3964)
		(end 276.7838 -40.005)
		(width 0.14224)
		(layer "In2.Cu")
		(net "M_A_DQ<42>")
	)
	(segment
		(start 296.415206 -23.275544)
		(end 296.415206 -22.5298)
		(width 0.14224)
		(layer "In2.Cu")
		(net "M_A_DQ<42>")
	)
	(segment
		(start 296.3926 -24.2824)
		(end 296.3926 -23.867618)
		(width 0.14224)
		(layer "In2.Cu")
		(net "M_A_DQ<42>")
	)
	(segment
		(start 277.76551 -50.128424)
		(end 276.511004 -48.873918)
		(width 0.0889)
		(layer "In2.Cu")
		(net "M_A_DQ<42>")
	)
	(arc
		(start 278.689054 -55.619904)
		(mid 278.694531 -55.610188)
		(end 278.70023 -55.6006)
		(width 0.0889)
		(layer "In2.Cu")
		(net "M_A_DQ<42>")
	)
	(arc
		(start 278.695404 -56.199786)
		(mid 278.616182 -55.910668)
		(end 278.689054 -55.619904)
		(width 0.0889)
		(layer "In2.Cu")
		(net "M_A_DQ<42>")
	)
	(arc
		(start 278.406606 -56.795924)
		(mid 278.708875 -56.574375)
		(end 278.695404 -56.199786)
		(width 0.0889)
		(layer "In2.Cu")
		(net "M_A_DQ<42>")
	)
	(arc
		(start 278.70023 -55.6006)
		(mid 278.748985 -55.404248)
		(end 278.695404 -55.209186)
		(width 0.0889)
		(layer "In2.Cu")
		(net "M_A_DQ<42>")
	)
	(segment
		(start 290.750498 -15.423642)
		(end 290.74999 -15.423642)
		(width 0.1651)
		(layer "F.Cu")
		(net "M_A_DQ<41>")
	)
	(segment
		(start 275.773134 -57.885584)
		(end 276.344634 -57.885584)
		(width 0.1016)
		(layer "F.Cu")
		(net "M_A_DQ<41>")
	)
	(segment
		(start 290.74999 -15.423642)
		(end 290.74999 -16.687546)
		(width 0.1651)
		(layer "F.Cu")
		(net "M_A_DQ<41>")
	)
	(via
		(at 291.422074 -22.279356)
		(size 0.508)
		(drill 0.254)
		(layers "F.Cu" "B.Cu")
		(net "M_A_DQ<41>")
	)
	(via
		(at 275.773134 -57.885584)
		(size 0.508)
		(drill 0.254)
		(layers "F.Cu" "B.Cu")
		(net "M_A_DQ<41>")
	)
	(via
		(at 290.74999 -16.687546)
		(size 0.508)
		(drill 0.254)
		(layers "F.Cu" "B.Cu")
		(net "M_A_DQ<41>")
	)
	(segment
		(start 291.599874 -20.224242)
		(end 291.599874 -21.598382)
		(width 0.1651)
		(layer "B.Cu")
		(net "M_A_DQ<41>")
	)
	(segment
		(start 291.422074 -21.776182)
		(end 291.422074 -22.279356)
		(width 0.1651)
		(layer "B.Cu")
		(net "M_A_DQ<41>")
	)
	(segment
		(start 291.599874 -21.598382)
		(end 291.422074 -21.776182)
		(width 0.1651)
		(layer "B.Cu")
		(net "M_A_DQ<41>")
	)
	(segment
		(start 291.600382 -20.224242)
		(end 291.599874 -20.224242)
		(width 0.1651)
		(layer "B.Cu")
		(net "M_A_DQ<41>")
	)
	(segment
		(start 279.568656 -29.549344)
		(end 279.568656 -29.244544)
		(width 0.14224)
		(layer "In2.Cu")
		(net "M_A_DQ<41>")
	)
	(segment
		(start 281.444192 -27.673808)
		(end 281.444192 -27.45486)
		(width 0.14224)
		(layer "In2.Cu")
		(net "M_A_DQ<41>")
	)
	(segment
		(start 274.631658 -52.545234)
		(end 274.631658 -51.435)
		(width 0.0889)
		(layer "In2.Cu")
		(net "M_A_DQ<41>")
	)
	(segment
		(start 291.255196 -23.412196)
		(end 290.937696 -23.094696)
		(width 0.14224)
		(layer "In2.Cu")
		(net "M_A_DQ<41>")
	)
	(segment
		(start 273.3548 -35.7632)
		(end 279.568656 -29.549344)
		(width 0.14224)
		(layer "In2.Cu")
		(net "M_A_DQ<41>")
	)
	(segment
		(start 291.227256 -17.7038)
		(end 290.74999 -17.226534)
		(width 0.14224)
		(layer "In2.Cu")
		(net "M_A_DQ<41>")
	)
	(segment
		(start 290.937696 -22.763734)
		(end 291.422074 -22.279356)
		(width 0.14224)
		(layer "In2.Cu")
		(net "M_A_DQ<41>")
	)
	(segment
		(start 290.74999 -17.226534)
		(end 290.74999 -16.687546)
		(width 0.14224)
		(layer "In2.Cu")
		(net "M_A_DQ<41>")
	)
	(segment
		(start 282.4734 -26.6446)
		(end 286.886142 -26.6446)
		(width 0.14224)
		(layer "In2.Cu")
		(net "M_A_DQ<41>")
	)
	(segment
		(start 291.255196 -24.644604)
		(end 291.255196 -23.412196)
		(width 0.14224)
		(layer "In2.Cu")
		(net "M_A_DQ<41>")
	)
	(segment
		(start 275.337016 -53.969412)
		(end 275.337016 -53.250592)
		(width 0.0889)
		(layer "In2.Cu")
		(net "M_A_DQ<41>")
	)
	(segment
		(start 291.796216 -21.905214)
		(end 291.796216 -18.571464)
		(width 0.14224)
		(layer "In2.Cu")
		(net "M_A_DQ<41>")
	)
	(segment
		(start 281.09164 -26.88336)
		(end 281.341576 -26.633424)
		(width 0.14224)
		(layer "In2.Cu")
		(net "M_A_DQ<41>")
	)
	(segment
		(start 281.09164 -27.102308)
		(end 281.09164 -26.88336)
		(width 0.14224)
		(layer "In2.Cu")
		(net "M_A_DQ<41>")
	)
	(segment
		(start 288.562542 -24.9682)
		(end 290.9316 -24.9682)
		(width 0.14224)
		(layer "In2.Cu")
		(net "M_A_DQ<41>")
	)
	(segment
		(start 273.515836 -47.150782)
		(end 273.3548 -46.989746)
		(width 0.0889)
		(layer "In2.Cu")
		(net "M_A_DQ<41>")
	)
	(segment
		(start 291.796216 -18.571464)
		(end 291.95268 -18.415)
		(width 0.14224)
		(layer "In2.Cu")
		(net "M_A_DQ<41>")
	)
	(segment
		(start 291.422074 -22.279356)
		(end 291.796216 -21.905214)
		(width 0.14224)
		(layer "In2.Cu")
		(net "M_A_DQ<41>")
	)
	(segment
		(start 282.132024 -26.985976)
		(end 282.4734 -26.6446)
		(width 0.14224)
		(layer "In2.Cu")
		(net "M_A_DQ<41>")
	)
	(segment
		(start 273.3548 -46.989746)
		(end 273.3548 -35.7632)
		(width 0.14224)
		(layer "In2.Cu")
		(net "M_A_DQ<41>")
	)
	(segment
		(start 286.886142 -26.6446)
		(end 288.562542 -24.9682)
		(width 0.14224)
		(layer "In2.Cu")
		(net "M_A_DQ<41>")
	)
	(segment
		(start 281.560524 -26.633424)
		(end 281.913076 -26.985976)
		(width 0.14224)
		(layer "In2.Cu")
		(net "M_A_DQ<41>")
	)
	(segment
		(start 275.425916 -54.12359)
		(end 275.337016 -53.969412)
		(width 0.0889)
		(layer "In2.Cu")
		(net "M_A_DQ<41>")
	)
	(segment
		(start 281.341576 -26.633424)
		(end 281.560524 -26.633424)
		(width 0.14224)
		(layer "In2.Cu")
		(net "M_A_DQ<41>")
	)
	(segment
		(start 279.568656 -29.244544)
		(end 279.951688 -28.861512)
		(width 0.14224)
		(layer "In2.Cu")
		(net "M_A_DQ<41>")
	)
	(segment
		(start 279.951688 -28.861512)
		(end 280.256488 -28.861512)
		(width 0.14224)
		(layer "In2.Cu")
		(net "M_A_DQ<41>")
	)
	(segment
		(start 281.444192 -27.45486)
		(end 281.09164 -27.102308)
		(width 0.14224)
		(layer "In2.Cu")
		(net "M_A_DQ<41>")
	)
	(segment
		(start 291.95268 -18.415)
		(end 291.95268 -18.073624)
		(width 0.14224)
		(layer "In2.Cu")
		(net "M_A_DQ<41>")
	)
	(segment
		(start 290.937696 -23.094696)
		(end 290.937696 -22.763734)
		(width 0.14224)
		(layer "In2.Cu")
		(net "M_A_DQ<41>")
	)
	(segment
		(start 275.773134 -57.885584)
		(end 275.426424 -57.095136)
		(width 0.0889)
		(layer "In2.Cu")
		(net "M_A_DQ<41>")
	)
	(segment
		(start 275.337016 -53.250592)
		(end 274.631658 -52.545234)
		(width 0.0889)
		(layer "In2.Cu")
		(net "M_A_DQ<41>")
	)
	(segment
		(start 290.9316 -24.9682)
		(end 291.255196 -24.644604)
		(width 0.14224)
		(layer "In2.Cu")
		(net "M_A_DQ<41>")
	)
	(segment
		(start 281.913076 -26.985976)
		(end 282.132024 -26.985976)
		(width 0.14224)
		(layer "In2.Cu")
		(net "M_A_DQ<41>")
	)
	(segment
		(start 275.426424 -54.123336)
		(end 275.425916 -54.12359)
		(width 0.0889)
		(layer "In2.Cu")
		(net "M_A_DQ<41>")
	)
	(segment
		(start 291.95268 -18.073624)
		(end 291.582856 -17.7038)
		(width 0.14224)
		(layer "In2.Cu")
		(net "M_A_DQ<41>")
	)
	(segment
		(start 280.256488 -28.861512)
		(end 281.444192 -27.673808)
		(width 0.14224)
		(layer "In2.Cu")
		(net "M_A_DQ<41>")
	)
	(segment
		(start 274.631658 -51.435)
		(end 273.515836 -50.319178)
		(width 0.0889)
		(layer "In2.Cu")
		(net "M_A_DQ<41>")
	)
	(segment
		(start 291.582856 -17.7038)
		(end 291.227256 -17.7038)
		(width 0.14224)
		(layer "In2.Cu")
		(net "M_A_DQ<41>")
	)
	(segment
		(start 273.515836 -50.319178)
		(end 273.515836 -47.150782)
		(width 0.0889)
		(layer "In2.Cu")
		(net "M_A_DQ<41>")
	)
	(arc
		(start 275.619718 -56.525668)
		(mid 275.881959 -56.370369)
		(end 276.090634 -56.148224)
		(width 0.0889)
		(layer "In2.Cu")
		(net "M_A_DQ<41>")
	)
	(arc
		(start 275.426424 -54.71414)
		(mid 275.505487 -54.418738)
		(end 275.426424 -54.123336)
		(width 0.0889)
		(layer "In2.Cu")
		(net "M_A_DQ<41>")
	)
	(arc
		(start 275.426424 -57.095136)
		(mid 275.394153 -56.766629)
		(end 275.619718 -56.525668)
		(width 0.0889)
		(layer "In2.Cu")
		(net "M_A_DQ<41>")
	)
	(arc
		(start 276.090634 -56.148224)
		(mid 276.158629 -55.79724)
		(end 275.91893 -55.53202)
		(width 0.0889)
		(layer "In2.Cu")
		(net "M_A_DQ<41>")
	)
	(arc
		(start 275.426424 -55.113936)
		(mid 275.372925 -54.914038)
		(end 275.426424 -54.71414)
		(width 0.0889)
		(layer "In2.Cu")
		(net "M_A_DQ<41>")
	)
	(arc
		(start 275.91893 -55.53202)
		(mid 275.636347 -55.365767)
		(end 275.426424 -55.113936)
		(width 0.0889)
		(layer "In2.Cu")
		(net "M_A_DQ<41>")
	)
	(segment
		(start 291.519102 -19.177)
		(end 291.422074 -18.161)
		(width 0.1651)
		(layer "F.Cu")
		(net "M_A_DQ<40>")
	)
	(segment
		(start 291.600382 -20.023582)
		(end 291.599874 -20.023582)
		(width 0.1651)
		(layer "F.Cu")
		(net "M_A_DQ<40>")
	)
	(segment
		(start 276.344634 -55.904384)
		(end 275.773134 -55.904384)
		(width 0.1016)
		(layer "F.Cu")
		(net "M_A_DQ<40>")
	)
	(segment
		(start 291.599874 -20.023582)
		(end 291.519102 -19.177)
		(width 0.1651)
		(layer "F.Cu")
		(net "M_A_DQ<40>")
	)
	(via
		(at 275.773134 -55.904384)
		(size 0.508)
		(drill 0.254)
		(layers "F.Cu" "B.Cu")
		(net "M_A_DQ<40>")
	)
	(via
		(at 291.422074 -18.161)
		(size 0.508)
		(drill 0.254)
		(layers "F.Cu" "B.Cu")
		(net "M_A_DQ<40>")
	)
	(via
		(at 290.74999 -23.560278)
		(size 0.508)
		(drill 0.254)
		(layers "F.Cu" "B.Cu")
		(net "M_A_DQ<40>")
	)
	(segment
		(start 290.750498 -24.824182)
		(end 290.74999 -24.824182)
		(width 0.1651)
		(layer "B.Cu")
		(net "M_A_DQ<40>")
	)
	(segment
		(start 290.74999 -24.824182)
		(end 290.74999 -23.560278)
		(width 0.1651)
		(layer "B.Cu")
		(net "M_A_DQ<40>")
	)
	(segment
		(start 273.242024 -47.991014)
		(end 273.242024 -47.436024)
		(width 0.0889)
		(layer "In2.Cu")
		(net "M_A_DQ<40>")
	)
	(segment
		(start 276.013418 -31.504382)
		(end 276.263354 -31.254446)
		(width 0.14224)
		(layer "In2.Cu")
		(net "M_A_DQ<40>")
	)
	(segment
		(start 277.201122 -30.09773)
		(end 276.83587 -29.732478)
		(width 0.14224)
		(layer "In2.Cu")
		(net "M_A_DQ<40>")
	)
	(segment
		(start 280.5176 -25.8318)
		(end 286.800544 -25.8318)
		(width 0.14224)
		(layer "In2.Cu")
		(net "M_A_DQ<40>")
	)
	(segment
		(start 274.856702 -32.44215)
		(end 275.07565 -32.44215)
		(width 0.14224)
		(layer "In2.Cu")
		(net "M_A_DQ<40>")
	)
	(segment
		(start 290.812474 -20.5994)
		(end 291.129974 -20.2819)
		(width 0.14224)
		(layer "In2.Cu")
		(net "M_A_DQ<40>")
	)
	(segment
		(start 291.129974 -20.0533)
		(end 290.787074 -19.7104)
		(width 0.14224)
		(layer "In2.Cu")
		(net "M_A_DQ<40>")
	)
	(segment
		(start 290.787074 -19.7104)
		(end 290.787074 -19.380454)
		(width 0.14224)
		(layer "In2.Cu")
		(net "M_A_DQ<40>")
	)
	(segment
		(start 275.898102 -30.670246)
		(end 275.898102 -30.451298)
		(width 0.14224)
		(layer "In2.Cu")
		(net "M_A_DQ<40>")
	)
	(segment
		(start 275.21027 -31.13913)
		(end 275.429218 -31.13913)
		(width 0.14224)
		(layer "In2.Cu")
		(net "M_A_DQ<40>")
	)
	(segment
		(start 274.49145 -32.076898)
		(end 274.856702 -32.44215)
		(width 0.14224)
		(layer "In2.Cu")
		(net "M_A_DQ<40>")
	)
	(segment
		(start 274.960334 -31.389066)
		(end 275.21027 -31.13913)
		(width 0.14224)
		(layer "In2.Cu")
		(net "M_A_DQ<40>")
	)
	(segment
		(start 275.325586 -31.973266)
		(end 274.960334 -31.608014)
		(width 0.14224)
		(layer "In2.Cu")
		(net "M_A_DQ<40>")
	)
	(segment
		(start 272.8722 -47.0662)
		(end 272.8722 -33.4772)
		(width 0.14224)
		(layer "In2.Cu")
		(net "M_A_DQ<40>")
	)
	(segment
		(start 276.148038 -30.201362)
		(end 276.366986 -30.201362)
		(width 0.14224)
		(layer "In2.Cu")
		(net "M_A_DQ<40>")
	)
	(segment
		(start 290.74999 -24.26081)
		(end 290.74999 -23.560278)
		(width 0.14224)
		(layer "In2.Cu")
		(net "M_A_DQ<40>")
	)
	(segment
		(start 274.960334 -31.608014)
		(end 274.960334 -31.389066)
		(width 0.14224)
		(layer "In2.Cu")
		(net "M_A_DQ<40>")
	)
	(segment
		(start 276.83587 -29.51353)
		(end 280.5176 -25.8318)
		(width 0.14224)
		(layer "In2.Cu")
		(net "M_A_DQ<40>")
	)
	(segment
		(start 276.83587 -29.732478)
		(end 276.83587 -29.51353)
		(width 0.14224)
		(layer "In2.Cu")
		(net "M_A_DQ<40>")
	)
	(segment
		(start 290.74999 -23.560278)
		(end 290.465256 -23.275544)
		(width 0.14224)
		(layer "In2.Cu")
		(net "M_A_DQ<40>")
	)
	(segment
		(start 288.379662 -24.504396)
		(end 290.506404 -24.504396)
		(width 0.14224)
		(layer "In2.Cu")
		(net "M_A_DQ<40>")
	)
	(segment
		(start 275.773134 -55.904384)
		(end 275.73097 -55.85968)
		(width 0.0889)
		(layer "In2.Cu")
		(net "M_A_DQ<40>")
	)
	(segment
		(start 276.732238 -30.566614)
		(end 276.951186 -30.566614)
		(width 0.14224)
		(layer "In2.Cu")
		(net "M_A_DQ<40>")
	)
	(segment
		(start 273.242024 -47.436024)
		(end 272.8722 -47.0662)
		(width 0.0889)
		(layer "In2.Cu")
		(net "M_A_DQ<40>")
	)
	(segment
		(start 276.263354 -31.254446)
		(end 276.263354 -31.035498)
		(width 0.14224)
		(layer "In2.Cu")
		(net "M_A_DQ<40>")
	)
	(segment
		(start 275.79447 -31.504382)
		(end 276.013418 -31.504382)
		(width 0.14224)
		(layer "In2.Cu")
		(net "M_A_DQ<40>")
	)
	(segment
		(start 290.787074 -19.380454)
		(end 291.201856 -18.965672)
		(width 0.14224)
		(layer "In2.Cu")
		(net "M_A_DQ<40>")
	)
	(segment
		(start 290.465256 -23.275544)
		(end 290.465256 -22.5298)
		(width 0.14224)
		(layer "In2.Cu")
		(net "M_A_DQ<40>")
	)
	(segment
		(start 291.201856 -21.7932)
		(end 291.201856 -21.293328)
		(width 0.14224)
		(layer "In2.Cu")
		(net "M_A_DQ<40>")
	)
	(segment
		(start 291.201856 -18.381218)
		(end 291.422074 -18.161)
		(width 0.14224)
		(layer "In2.Cu")
		(net "M_A_DQ<40>")
	)
	(segment
		(start 275.429218 -31.13913)
		(end 275.79447 -31.504382)
		(width 0.14224)
		(layer "In2.Cu")
		(net "M_A_DQ<40>")
	)
	(segment
		(start 276.951186 -30.566614)
		(end 277.201122 -30.316678)
		(width 0.14224)
		(layer "In2.Cu")
		(net "M_A_DQ<40>")
	)
	(segment
		(start 277.201122 -30.316678)
		(end 277.201122 -30.09773)
		(width 0.14224)
		(layer "In2.Cu")
		(net "M_A_DQ<40>")
	)
	(segment
		(start 276.366986 -30.201362)
		(end 276.732238 -30.566614)
		(width 0.14224)
		(layer "In2.Cu")
		(net "M_A_DQ<40>")
	)
	(segment
		(start 275.07565 -32.44215)
		(end 275.325586 -32.192214)
		(width 0.14224)
		(layer "In2.Cu")
		(net "M_A_DQ<40>")
	)
	(segment
		(start 287.95218 -24.931878)
		(end 288.379662 -24.504396)
		(width 0.14224)
		(layer "In2.Cu")
		(net "M_A_DQ<40>")
	)
	(segment
		(start 275.146516 -54.019704)
		(end 275.146516 -53.329586)
		(width 0.0889)
		(layer "In2.Cu")
		(net "M_A_DQ<40>")
	)
	(segment
		(start 286.800544 -25.8318)
		(end 287.700466 -24.931878)
		(width 0.14224)
		(layer "In2.Cu")
		(net "M_A_DQ<40>")
	)
	(segment
		(start 290.506404 -24.504396)
		(end 290.74999 -24.26081)
		(width 0.14224)
		(layer "In2.Cu")
		(net "M_A_DQ<40>")
	)
	(segment
		(start 275.325586 -32.192214)
		(end 275.325586 -31.973266)
		(width 0.14224)
		(layer "In2.Cu")
		(net "M_A_DQ<40>")
	)
	(segment
		(start 287.700466 -24.931878)
		(end 287.95218 -24.931878)
		(width 0.14224)
		(layer "In2.Cu")
		(net "M_A_DQ<40>")
	)
	(segment
		(start 272.8722 -33.4772)
		(end 274.272502 -32.076898)
		(width 0.14224)
		(layer "In2.Cu")
		(net "M_A_DQ<40>")
	)
	(segment
		(start 290.812474 -20.903946)
		(end 290.812474 -20.5994)
		(width 0.14224)
		(layer "In2.Cu")
		(net "M_A_DQ<40>")
	)
	(segment
		(start 273.325336 -48.074326)
		(end 273.242024 -47.991014)
		(width 0.0889)
		(layer "In2.Cu")
		(net "M_A_DQ<40>")
	)
	(segment
		(start 276.263354 -31.035498)
		(end 275.898102 -30.670246)
		(width 0.14224)
		(layer "In2.Cu")
		(net "M_A_DQ<40>")
	)
	(segment
		(start 291.201856 -21.293328)
		(end 290.812474 -20.903946)
		(width 0.14224)
		(layer "In2.Cu")
		(net "M_A_DQ<40>")
	)
	(segment
		(start 273.325336 -50.398172)
		(end 273.325336 -48.074326)
		(width 0.0889)
		(layer "In2.Cu")
		(net "M_A_DQ<40>")
	)
	(segment
		(start 274.272502 -32.076898)
		(end 274.49145 -32.076898)
		(width 0.14224)
		(layer "In2.Cu")
		(net "M_A_DQ<40>")
	)
	(segment
		(start 275.265388 -55.216552)
		(end 275.261324 -55.20944)
		(width 0.0889)
		(layer "In2.Cu")
		(net "M_A_DQ<40>")
	)
	(segment
		(start 274.441158 -51.513994)
		(end 273.325336 -50.398172)
		(width 0.0889)
		(layer "In2.Cu")
		(net "M_A_DQ<40>")
	)
	(segment
		(start 291.201856 -18.965672)
		(end 291.201856 -18.381218)
		(width 0.14224)
		(layer "In2.Cu")
		(net "M_A_DQ<40>")
	)
	(segment
		(start 274.441158 -52.624228)
		(end 274.441158 -51.513994)
		(width 0.0889)
		(layer "In2.Cu")
		(net "M_A_DQ<40>")
	)
	(segment
		(start 290.465256 -22.5298)
		(end 291.201856 -21.7932)
		(width 0.14224)
		(layer "In2.Cu")
		(net "M_A_DQ<40>")
	)
	(segment
		(start 275.261324 -54.218586)
		(end 275.146516 -54.019704)
		(width 0.0889)
		(layer "In2.Cu")
		(net "M_A_DQ<40>")
	)
	(segment
		(start 291.129974 -20.2819)
		(end 291.129974 -20.0533)
		(width 0.14224)
		(layer "In2.Cu")
		(net "M_A_DQ<40>")
	)
	(segment
		(start 275.146516 -53.329586)
		(end 274.441158 -52.624228)
		(width 0.0889)
		(layer "In2.Cu")
		(net "M_A_DQ<40>")
	)
	(segment
		(start 275.898102 -30.451298)
		(end 276.148038 -30.201362)
		(width 0.14224)
		(layer "In2.Cu")
		(net "M_A_DQ<40>")
	)
	(arc
		(start 275.261324 -54.618636)
		(mid 275.314857 -54.418628)
		(end 275.261324 -54.218586)
		(width 0.0889)
		(layer "In2.Cu")
		(net "M_A_DQ<40>")
	)
	(arc
		(start 275.73097 -55.85968)
		(mid 275.481603 -55.550116)
		(end 275.265388 -55.216552)
		(width 0.0889)
		(layer "In2.Cu")
		(net "M_A_DQ<40>")
	)
	(arc
		(start 275.261324 -55.20944)
		(mid 275.182193 -54.914038)
		(end 275.261324 -54.618636)
		(width 0.0889)
		(layer "In2.Cu")
		(net "M_A_DQ<40>")
	)
	(segment
		(start 234.466638 -61.53404)
		(end 233.895138 -61.53404)
		(width 0.1016)
		(layer "F.Cu")
		(net "M_A_DQ<3>")
	)
	(segment
		(start 204.050392 -15.423642)
		(end 204.049884 -15.423642)
		(width 0.1651)
		(layer "F.Cu")
		(net "M_A_DQ<3>")
	)
	(segment
		(start 204.049884 -15.423642)
		(end 204.049884 -16.687546)
		(width 0.1651)
		(layer "F.Cu")
		(net "M_A_DQ<3>")
	)
	(via
		(at 233.895138 -61.53404)
		(size 0.508)
		(drill 0.254)
		(layers "F.Cu" "B.Cu")
		(net "M_A_DQ<3>")
	)
	(via
		(at 204.049884 -16.687546)
		(size 0.508)
		(drill 0.254)
		(layers "F.Cu" "B.Cu")
		(net "M_A_DQ<3>")
	)
	(via
		(at 204.899768 -22.279356)
		(size 0.508)
		(drill 0.254)
		(layers "F.Cu" "B.Cu")
		(net "M_A_DQ<3>")
	)
	(segment
		(start 204.900276 -20.224242)
		(end 204.899768 -20.224242)
		(width 0.1651)
		(layer "B.Cu")
		(net "M_A_DQ<3>")
	)
	(segment
		(start 204.899768 -20.224242)
		(end 204.899768 -22.279356)
		(width 0.1651)
		(layer "B.Cu")
		(net "M_A_DQ<3>")
	)
	(segment
		(start 207.338168 -37.809424)
		(end 207.541368 -38.012624)
		(width 0.14224)
		(layer "In2.Cu")
		(net "M_A_DQ<3>")
	)
	(segment
		(start 204.696822 -17.653)
		(end 204.366622 -17.3228)
		(width 0.14224)
		(layer "In2.Cu")
		(net "M_A_DQ<3>")
	)
	(segment
		(start 208.049368 -33.948624)
		(end 208.252568 -33.745424)
		(width 0.14224)
		(layer "In2.Cu")
		(net "M_A_DQ<3>")
	)
	(segment
		(start 205.408022 -18.1102)
		(end 204.950822 -17.653)
		(width 0.14224)
		(layer "In2.Cu")
		(net "M_A_DQ<3>")
	)
	(segment
		(start 207.541368 -38.012624)
		(end 207.846168 -38.012624)
		(width 0.14224)
		(layer "In2.Cu")
		(net "M_A_DQ<3>")
	)
	(segment
		(start 204.899768 -22.279356)
		(end 204.4192 -22.759924)
		(width 0.14224)
		(layer "In2.Cu")
		(net "M_A_DQ<3>")
	)
	(segment
		(start 204.899768 -22.279356)
		(end 205.252574 -21.92655)
		(width 0.14224)
		(layer "In2.Cu")
		(net "M_A_DQ<3>")
	)
	(segment
		(start 204.950822 -17.653)
		(end 204.696822 -17.653)
		(width 0.14224)
		(layer "In2.Cu")
		(net "M_A_DQ<3>")
	)
	(segment
		(start 204.366622 -17.004284)
		(end 204.049884 -16.687546)
		(width 0.14224)
		(layer "In2.Cu")
		(net "M_A_DQ<3>")
	)
	(segment
		(start 205.5876 -24.3586)
		(end 206.6036 -24.3586)
		(width 0.14224)
		(layer "In2.Cu")
		(net "M_A_DQ<3>")
	)
	(segment
		(start 208.049368 -37.809424)
		(end 208.049368 -33.948624)
		(width 0.14224)
		(layer "In2.Cu")
		(net "M_A_DQ<3>")
	)
	(segment
		(start 208.760568 -33.948624)
		(end 208.760568 -39.593774)
		(width 0.14224)
		(layer "In2.Cu")
		(net "M_A_DQ<3>")
	)
	(segment
		(start 208.252568 -33.745424)
		(end 208.557368 -33.745424)
		(width 0.14224)
		(layer "In2.Cu")
		(net "M_A_DQ<3>")
	)
	(segment
		(start 204.4192 -23.1902)
		(end 205.5876 -24.3586)
		(width 0.14224)
		(layer "In2.Cu")
		(net "M_A_DQ<3>")
	)
	(segment
		(start 204.4192 -22.759924)
		(end 204.4192 -23.1902)
		(width 0.14224)
		(layer "In2.Cu")
		(net "M_A_DQ<3>")
	)
	(segment
		(start 230.505 -61.000386)
		(end 232.30078 -61.000386)
		(width 0.0889)
		(layer "In2.Cu")
		(net "M_A_DQ<3>")
	)
	(segment
		(start 208.557368 -33.745424)
		(end 208.760568 -33.948624)
		(width 0.14224)
		(layer "In2.Cu")
		(net "M_A_DQ<3>")
	)
	(segment
		(start 205.408022 -18.4658)
		(end 205.408022 -18.1102)
		(width 0.14224)
		(layer "In2.Cu")
		(net "M_A_DQ<3>")
	)
	(segment
		(start 232.30078 -61.000386)
		(end 232.834434 -61.53404)
		(width 0.0889)
		(layer "In2.Cu")
		(net "M_A_DQ<3>")
	)
	(segment
		(start 204.366622 -17.3228)
		(end 204.366622 -17.004284)
		(width 0.14224)
		(layer "In2.Cu")
		(net "M_A_DQ<3>")
	)
	(segment
		(start 206.6036 -24.3586)
		(end 207.338168 -25.093168)
		(width 0.14224)
		(layer "In2.Cu")
		(net "M_A_DQ<3>")
	)
	(segment
		(start 205.252574 -21.92655)
		(end 205.252574 -18.621248)
		(width 0.14224)
		(layer "In2.Cu")
		(net "M_A_DQ<3>")
	)
	(segment
		(start 207.846168 -38.012624)
		(end 208.049368 -37.809424)
		(width 0.14224)
		(layer "In2.Cu")
		(net "M_A_DQ<3>")
	)
	(segment
		(start 208.760568 -39.593774)
		(end 230.16718 -61.000386)
		(width 0.14224)
		(layer "In2.Cu")
		(net "M_A_DQ<3>")
	)
	(segment
		(start 232.834434 -61.53404)
		(end 233.895138 -61.53404)
		(width 0.0889)
		(layer "In2.Cu")
		(net "M_A_DQ<3>")
	)
	(segment
		(start 207.338168 -25.093168)
		(end 207.338168 -37.809424)
		(width 0.14224)
		(layer "In2.Cu")
		(net "M_A_DQ<3>")
	)
	(segment
		(start 205.252574 -18.621248)
		(end 205.408022 -18.4658)
		(width 0.14224)
		(layer "In2.Cu")
		(net "M_A_DQ<3>")
	)
	(segment
		(start 230.16718 -61.000386)
		(end 230.505 -61.000386)
		(width 0.14224)
		(layer "In2.Cu")
		(net "M_A_DQ<3>")
	)
	(segment
		(start 275.166074 -41.521126)
		(end 275.731732 -40.955468)
		(width 0.1016)
		(layer "F.Cu")
		(net "M_A_DQ<39>")
	)
	(segment
		(start 286.6898 -23.9014)
		(end 285.9532 -23.1648)
		(width 0.1651)
		(layer "F.Cu")
		(net "M_A_DQ<39>")
	)
	(segment
		(start 285.9532 -23.1648)
		(end 285.9532 -22.444456)
		(width 0.1651)
		(layer "F.Cu")
		(net "M_A_DQ<39>")
	)
	(segment
		(start 275.166074 -49.812448)
		(end 275.166074 -41.521126)
		(width 0.1016)
		(layer "F.Cu")
		(net "M_A_DQ<39>")
	)
	(segment
		(start 286.6898 -26.667968)
		(end 286.6898 -23.9014)
		(width 0.1651)
		(layer "F.Cu")
		(net "M_A_DQ<39>")
	)
	(segment
		(start 286.1183 -22.279356)
		(end 286.499808 -22.279356)
		(width 0.1651)
		(layer "F.Cu")
		(net "M_A_DQ<39>")
	)
	(segment
		(start 275.731732 -40.4114)
		(end 275.731732 -39.680896)
		(width 0.1651)
		(layer "F.Cu")
		(net "M_A_DQ<39>")
	)
	(segment
		(start 275.008848 -53.542184)
		(end 275.008848 -50.26279)
		(width 0.0889)
		(layer "F.Cu")
		(net "M_A_DQ<39>")
	)
	(segment
		(start 285.479236 -27.878532)
		(end 286.6898 -26.667968)
		(width 0.1651)
		(layer "F.Cu")
		(net "M_A_DQ<39>")
	)
	(segment
		(start 275.731732 -39.680896)
		(end 285.479236 -29.933392)
		(width 0.1651)
		(layer "F.Cu")
		(net "M_A_DQ<39>")
	)
	(segment
		(start 285.649924 -15.423642)
		(end 285.649924 -16.687546)
		(width 0.1651)
		(layer "F.Cu")
		(net "M_A_DQ<39>")
	)
	(segment
		(start 285.479236 -29.933392)
		(end 285.479236 -28.575)
		(width 0.1651)
		(layer "F.Cu")
		(net "M_A_DQ<39>")
	)
	(segment
		(start 274.627848 -53.923184)
		(end 275.008848 -53.542184)
		(width 0.0889)
		(layer "F.Cu")
		(net "M_A_DQ<39>")
	)
	(segment
		(start 275.731732 -40.955468)
		(end 275.731732 -40.4114)
		(width 0.1016)
		(layer "F.Cu")
		(net "M_A_DQ<39>")
	)
	(segment
		(start 285.650432 -15.423642)
		(end 285.649924 -15.423642)
		(width 0.1651)
		(layer "F.Cu")
		(net "M_A_DQ<39>")
	)
	(segment
		(start 275.008848 -50.26279)
		(end 275.166074 -50.105564)
		(width 0.0889)
		(layer "F.Cu")
		(net "M_A_DQ<39>")
	)
	(segment
		(start 285.479236 -28.575)
		(end 285.479236 -27.878532)
		(width 0.1651)
		(layer "F.Cu")
		(net "M_A_DQ<39>")
	)
	(segment
		(start 285.9532 -22.444456)
		(end 286.1183 -22.279356)
		(width 0.1651)
		(layer "F.Cu")
		(net "M_A_DQ<39>")
	)
	(segment
		(start 275.166074 -50.105564)
		(end 275.166074 -49.812448)
		(width 0.0889)
		(layer "F.Cu")
		(net "M_A_DQ<39>")
	)
	(via
		(at 286.499808 -22.279356)
		(size 0.508)
		(drill 0.254)
		(layers "F.Cu" "B.Cu")
		(net "M_A_DQ<39>")
	)
	(via
		(at 285.649924 -16.687546)
		(size 0.508)
		(drill 0.254)
		(layers "F.Cu" "B.Cu")
		(net "M_A_DQ<39>")
	)
	(via
		(at 285.479236 -28.575)
		(size 0.508)
		(drill 0.254)
		(layers "F.Cu" "B.Cu")
		(net "M_A_DQ<39>")
	)
	(segment
		(start 286.500316 -20.224242)
		(end 286.499808 -20.224242)
		(width 0.1651)
		(layer "B.Cu")
		(net "M_A_DQ<39>")
	)
	(segment
		(start 286.499808 -20.224242)
		(end 286.499808 -22.279356)
		(width 0.1651)
		(layer "B.Cu")
		(net "M_A_DQ<39>")
	)
	(segment
		(start 286.852614 -18.621248)
		(end 287.008062 -18.4658)
		(width 0.14224)
		(layer "In2.Cu")
		(net "M_A_DQ<39>")
	)
	(segment
		(start 287.008062 -18.1102)
		(end 286.550862 -17.653)
		(width 0.14224)
		(layer "In2.Cu")
		(net "M_A_DQ<39>")
	)
	(segment
		(start 287.008062 -18.4658)
		(end 287.008062 -18.1102)
		(width 0.14224)
		(layer "In2.Cu")
		(net "M_A_DQ<39>")
	)
	(segment
		(start 286.852614 -21.92655)
		(end 286.852614 -18.621248)
		(width 0.14224)
		(layer "In2.Cu")
		(net "M_A_DQ<39>")
	)
	(segment
		(start 286.296862 -17.653)
		(end 285.649924 -17.006062)
		(width 0.14224)
		(layer "In2.Cu")
		(net "M_A_DQ<39>")
	)
	(segment
		(start 286.550862 -17.653)
		(end 286.296862 -17.653)
		(width 0.14224)
		(layer "In2.Cu")
		(net "M_A_DQ<39>")
	)
	(segment
		(start 285.649924 -17.006062)
		(end 285.649924 -16.687546)
		(width 0.14224)
		(layer "In2.Cu")
		(net "M_A_DQ<39>")
	)
	(segment
		(start 286.499808 -22.279356)
		(end 286.852614 -21.92655)
		(width 0.14224)
		(layer "In2.Cu")
		(net "M_A_DQ<39>")
	)
	(segment
		(start 285.9786 -24.511254)
		(end 285.9786 -24.282146)
		(width 0.1651)
		(layer "F.Cu")
		(net "M_A_DQ<38>")
	)
	(segment
		(start 285.8643 -25.5016)
		(end 284.4927 -25.5016)
		(width 0.1651)
		(layer "F.Cu")
		(net "M_A_DQ<38>")
	)
	(segment
		(start 284.4038 -26.340054)
		(end 284.531054 -26.2128)
		(width 0.1651)
		(layer "F.Cu")
		(net "M_A_DQ<38>")
	)
	(segment
		(start 284.5562 -24.638)
		(end 285.851854 -24.638)
		(width 0.1651)
		(layer "F.Cu")
		(net "M_A_DQ<38>")
	)
	(segment
		(start 274.772374 -41.330372)
		(end 275.091906 -41.01084)
		(width 0.1016)
		(layer "F.Cu")
		(net "M_A_DQ<38>")
	)
	(segment
		(start 285.8643 -26.2128)
		(end 286.0294 -26.0477)
		(width 0.1651)
		(layer "F.Cu")
		(net "M_A_DQ<38>")
	)
	(segment
		(start 285.9786 -24.282146)
		(end 285.649924 -23.95347)
		(width 0.1651)
		(layer "F.Cu")
		(net "M_A_DQ<38>")
	)
	(segment
		(start 286.499808 -18.2626)
		(end 286.500062 -18.262854)
		(width 0.1651)
		(layer "F.Cu")
		(net "M_A_DQ<38>")
	)
	(segment
		(start 274.818348 -50.233326)
		(end 274.772374 -50.187352)
		(width 0.0889)
		(layer "F.Cu")
		(net "M_A_DQ<38>")
	)
	(segment
		(start 286.500062 -19.05)
		(end 286.500062 -20.023328)
		(width 0.1651)
		(layer "F.Cu")
		(net "M_A_DQ<38>")
	)
	(segment
		(start 286.500062 -20.023328)
		(end 286.500316 -20.023582)
		(width 0.1651)
		(layer "F.Cu")
		(net "M_A_DQ<38>")
	)
	(segment
		(start 274.818348 -51.751484)
		(end 274.818348 -50.233326)
		(width 0.0889)
		(layer "F.Cu")
		(net "M_A_DQ<38>")
	)
	(segment
		(start 275.091906 -41.01084)
		(end 275.091906 -40.4114)
		(width 0.1016)
		(layer "F.Cu")
		(net "M_A_DQ<38>")
	)
	(segment
		(start 285.851854 -24.638)
		(end 285.9786 -24.511254)
		(width 0.1651)
		(layer "F.Cu")
		(net "M_A_DQ<38>")
	)
	(segment
		(start 275.091906 -40.4114)
		(end 275.091906 -39.415466)
		(width 0.1651)
		(layer "F.Cu")
		(net "M_A_DQ<38>")
	)
	(segment
		(start 274.772374 -49.812448)
		(end 274.772374 -41.330372)
		(width 0.1016)
		(layer "F.Cu")
		(net "M_A_DQ<38>")
	)
	(segment
		(start 286.632142 -18.69948)
		(end 286.632142 -18.91792)
		(width 0.1651)
		(layer "F.Cu")
		(net "M_A_DQ<38>")
	)
	(segment
		(start 274.772374 -50.187352)
		(end 274.772374 -49.812448)
		(width 0.0889)
		(layer "F.Cu")
		(net "M_A_DQ<38>")
	)
	(segment
		(start 284.4038 -29.588968)
		(end 284.4038 -26.340054)
		(width 0.1651)
		(layer "F.Cu")
		(net "M_A_DQ<38>")
	)
	(segment
		(start 275.091906 -39.415466)
		(end 284.4038 -30.103572)
		(width 0.1651)
		(layer "F.Cu")
		(net "M_A_DQ<38>")
	)
	(segment
		(start 284.531054 -26.2128)
		(end 285.8643 -26.2128)
		(width 0.1651)
		(layer "F.Cu")
		(net "M_A_DQ<38>")
	)
	(segment
		(start 286.500062 -18.262854)
		(end 286.500062 -18.5674)
		(width 0.1651)
		(layer "F.Cu")
		(net "M_A_DQ<38>")
	)
	(segment
		(start 284.353 -25.3619)
		(end 284.353 -24.8412)
		(width 0.1651)
		(layer "F.Cu")
		(net "M_A_DQ<38>")
	)
	(segment
		(start 284.353 -24.8412)
		(end 284.5562 -24.638)
		(width 0.1651)
		(layer "F.Cu")
		(net "M_A_DQ<38>")
	)
	(segment
		(start 286.0294 -26.0477)
		(end 286.0294 -25.6667)
		(width 0.1651)
		(layer "F.Cu")
		(net "M_A_DQ<38>")
	)
	(segment
		(start 274.627848 -51.941984)
		(end 274.818348 -51.751484)
		(width 0.0889)
		(layer "F.Cu")
		(net "M_A_DQ<38>")
	)
	(segment
		(start 286.0294 -25.6667)
		(end 285.8643 -25.5016)
		(width 0.1651)
		(layer "F.Cu")
		(net "M_A_DQ<38>")
	)
	(segment
		(start 286.632142 -18.91792)
		(end 286.500062 -19.05)
		(width 0.1651)
		(layer "F.Cu")
		(net "M_A_DQ<38>")
	)
	(segment
		(start 284.4927 -25.5016)
		(end 284.353 -25.3619)
		(width 0.1651)
		(layer "F.Cu")
		(net "M_A_DQ<38>")
	)
	(segment
		(start 286.500062 -18.5674)
		(end 286.632142 -18.69948)
		(width 0.1651)
		(layer "F.Cu")
		(net "M_A_DQ<38>")
	)
	(segment
		(start 285.649924 -23.95347)
		(end 285.649924 -23.560278)
		(width 0.1651)
		(layer "F.Cu")
		(net "M_A_DQ<38>")
	)
	(segment
		(start 284.4038 -30.103572)
		(end 284.4038 -29.588968)
		(width 0.1651)
		(layer "F.Cu")
		(net "M_A_DQ<38>")
	)
	(via
		(at 284.4038 -29.588968)
		(size 0.508)
		(drill 0.254)
		(layers "F.Cu" "B.Cu")
		(net "M_A_DQ<38>")
	)
	(via
		(at 286.499808 -18.2626)
		(size 0.508)
		(drill 0.254)
		(layers "F.Cu" "B.Cu")
		(net "M_A_DQ<38>")
	)
	(via
		(at 285.649924 -23.560278)
		(size 0.508)
		(drill 0.254)
		(layers "F.Cu" "B.Cu")
		(net "M_A_DQ<38>")
	)
	(segment
		(start 285.649924 -24.824182)
		(end 285.649924 -23.560278)
		(width 0.1651)
		(layer "B.Cu")
		(net "M_A_DQ<38>")
	)
	(segment
		(start 285.650432 -24.824182)
		(end 285.649924 -24.824182)
		(width 0.1651)
		(layer "B.Cu")
		(net "M_A_DQ<38>")
	)
	(segment
		(start 286.125412 -18.636996)
		(end 286.499808 -18.2626)
		(width 0.14224)
		(layer "In2.Cu")
		(net "M_A_DQ<38>")
	)
	(segment
		(start 286.14243 -20.313904)
		(end 286.14243 -19.970496)
		(width 0.14224)
		(layer "In2.Cu")
		(net "M_A_DQ<38>")
	)
	(segment
		(start 286.18688 -21.405596)
		(end 285.76143 -20.980146)
		(width 0.14224)
		(layer "In2.Cu")
		(net "M_A_DQ<38>")
	)
	(segment
		(start 286.14243 -19.970496)
		(end 285.76143 -19.589496)
		(width 0.14224)
		(layer "In2.Cu")
		(net "M_A_DQ<38>")
	)
	(segment
		(start 285.76143 -19.589496)
		(end 285.76143 -19.278854)
		(width 0.14224)
		(layer "In2.Cu")
		(net "M_A_DQ<38>")
	)
	(segment
		(start 285.76143 -20.980146)
		(end 285.76143 -20.694904)
		(width 0.14224)
		(layer "In2.Cu")
		(net "M_A_DQ<38>")
	)
	(segment
		(start 285.414212 -23.324566)
		(end 285.414212 -22.530054)
		(width 0.14224)
		(layer "In2.Cu")
		(net "M_A_DQ<38>")
	)
	(segment
		(start 285.76143 -19.278854)
		(end 286.125412 -18.914872)
		(width 0.14224)
		(layer "In2.Cu")
		(net "M_A_DQ<38>")
	)
	(segment
		(start 285.76143 -20.694904)
		(end 286.14243 -20.313904)
		(width 0.14224)
		(layer "In2.Cu")
		(net "M_A_DQ<38>")
	)
	(segment
		(start 285.414212 -22.530054)
		(end 286.18688 -21.757386)
		(width 0.14224)
		(layer "In2.Cu")
		(net "M_A_DQ<38>")
	)
	(segment
		(start 286.125412 -18.914872)
		(end 286.125412 -18.636996)
		(width 0.14224)
		(layer "In2.Cu")
		(net "M_A_DQ<38>")
	)
	(segment
		(start 285.649924 -23.560278)
		(end 285.414212 -23.324566)
		(width 0.14224)
		(layer "In2.Cu")
		(net "M_A_DQ<38>")
	)
	(segment
		(start 286.18688 -21.757386)
		(end 286.18688 -21.405596)
		(width 0.14224)
		(layer "In2.Cu")
		(net "M_A_DQ<38>")
	)
	(segment
		(start 273.8882 -34.11347)
		(end 271.308576 -36.693094)
		(width 0.1651)
		(layer "F.Cu")
		(net "M_A_DQ<37>")
	)
	(segment
		(start 271.308576 -36.693094)
		(end 271.308576 -40.4114)
		(width 0.1651)
		(layer "F.Cu")
		(net "M_A_DQ<37>")
	)
	(segment
		(start 272.04162 -52.830984)
		(end 272.074386 -52.830984)
		(width 0.0889)
		(layer "F.Cu")
		(net "M_A_DQ<37>")
	)
	(segment
		(start 271.519904 -51.338734)
		(end 271.711166 -51.670458)
		(width 0.0889)
		(layer "F.Cu")
		(net "M_A_DQ<37>")
	)
	(segment
		(start 280.973784 -22.779482)
		(end 280.973784 -23.140416)
		(width 0.1651)
		(layer "F.Cu")
		(net "M_A_DQ<37>")
	)
	(segment
		(start 272.660364 -53.340508)
		(end 272.660364 -53.67274)
		(width 0.0889)
		(layer "F.Cu")
		(net "M_A_DQ<37>")
	)
	(segment
		(start 273.8882 -32.18053)
		(end 273.8882 -34.11347)
		(width 0.1651)
		(layer "F.Cu")
		(net "M_A_DQ<37>")
	)
	(segment
		(start 280.473658 -22.279356)
		(end 280.973784 -22.779482)
		(width 0.1651)
		(layer "F.Cu")
		(net "M_A_DQ<37>")
	)
	(segment
		(start 272.569686 -53.129434)
		(end 272.660364 -53.340508)
		(width 0.0889)
		(layer "F.Cu")
		(net "M_A_DQ<37>")
	)
	(segment
		(start 280.3525 -25.71623)
		(end 273.8882 -32.18053)
		(width 0.1651)
		(layer "F.Cu")
		(net "M_A_DQ<37>")
	)
	(segment
		(start 271.308576 -41.006776)
		(end 272.016474 -41.714674)
		(width 0.1016)
		(layer "F.Cu")
		(net "M_A_DQ<37>")
	)
	(segment
		(start 272.016474 -50.156872)
		(end 271.519904 -50.653442)
		(width 0.0889)
		(layer "F.Cu")
		(net "M_A_DQ<37>")
	)
	(segment
		(start 272.016474 -49.812448)
		(end 272.016474 -50.156872)
		(width 0.0889)
		(layer "F.Cu")
		(net "M_A_DQ<37>")
	)
	(segment
		(start 271.308576 -40.4114)
		(end 271.308576 -41.006776)
		(width 0.1016)
		(layer "F.Cu")
		(net "M_A_DQ<37>")
	)
	(segment
		(start 272.016474 -41.714674)
		(end 272.016474 -49.812448)
		(width 0.1016)
		(layer "F.Cu")
		(net "M_A_DQ<37>")
	)
	(segment
		(start 279.700482 -15.423642)
		(end 279.699974 -15.423642)
		(width 0.1651)
		(layer "F.Cu")
		(net "M_A_DQ<37>")
	)
	(segment
		(start 280.3525 -23.7617)
		(end 280.3525 -25.71623)
		(width 0.1651)
		(layer "F.Cu")
		(net "M_A_DQ<37>")
	)
	(segment
		(start 271.519904 -50.653442)
		(end 271.519904 -51.338734)
		(width 0.0889)
		(layer "F.Cu")
		(net "M_A_DQ<37>")
	)
	(segment
		(start 280.973784 -23.140416)
		(end 280.3525 -23.7617)
		(width 0.1651)
		(layer "F.Cu")
		(net "M_A_DQ<37>")
	)
	(segment
		(start 272.660364 -53.67274)
		(end 272.910808 -53.923184)
		(width 0.0889)
		(layer "F.Cu")
		(net "M_A_DQ<37>")
	)
	(segment
		(start 279.699974 -15.423642)
		(end 279.699974 -16.687546)
		(width 0.1651)
		(layer "F.Cu")
		(net "M_A_DQ<37>")
	)
	(via
		(at 280.473658 -22.279356)
		(size 0.508)
		(drill 0.254)
		(layers "F.Cu" "B.Cu")
		(net "M_A_DQ<37>")
	)
	(via
		(at 279.699974 -16.687546)
		(size 0.508)
		(drill 0.254)
		(layers "F.Cu" "B.Cu")
		(net "M_A_DQ<37>")
	)
	(arc
		(start 272.074386 -52.830984)
		(mid 272.360562 -52.916274)
		(end 272.569686 -53.129434)
		(width 0.0889)
		(layer "F.Cu")
		(net "M_A_DQ<37>")
	)
	(arc
		(start 271.711166 -52.240434)
		(mid 271.708592 -52.629605)
		(end 272.04162 -52.830984)
		(width 0.0889)
		(layer "F.Cu")
		(net "M_A_DQ<37>")
	)
	(arc
		(start 271.711166 -51.670458)
		(mid 271.787473 -51.955446)
		(end 271.711166 -52.240434)
		(width 0.0889)
		(layer "F.Cu")
		(net "M_A_DQ<37>")
	)
	(segment
		(start 280.549858 -22.203156)
		(end 280.473658 -22.279356)
		(width 0.1651)
		(layer "B.Cu")
		(net "M_A_DQ<37>")
	)
	(segment
		(start 280.549858 -20.224242)
		(end 280.549858 -22.203156)
		(width 0.1651)
		(layer "B.Cu")
		(net "M_A_DQ<37>")
	)
	(segment
		(start 280.550366 -20.224242)
		(end 280.549858 -20.224242)
		(width 0.1651)
		(layer "B.Cu")
		(net "M_A_DQ<37>")
	)
	(segment
		(start 279.699974 -17.082262)
		(end 279.699974 -16.687546)
		(width 0.14224)
		(layer "In2.Cu")
		(net "M_A_DQ<37>")
	)
	(segment
		(start 280.981912 -18.053304)
		(end 280.581608 -17.653)
		(width 0.14224)
		(layer "In2.Cu")
		(net "M_A_DQ<37>")
	)
	(segment
		(start 280.981912 -18.4658)
		(end 280.981912 -18.053304)
		(width 0.14224)
		(layer "In2.Cu")
		(net "M_A_DQ<37>")
	)
	(segment
		(start 280.785062 -18.66265)
		(end 280.981912 -18.4658)
		(width 0.14224)
		(layer "In2.Cu")
		(net "M_A_DQ<37>")
	)
	(segment
		(start 280.785062 -21.967952)
		(end 280.785062 -18.66265)
		(width 0.14224)
		(layer "In2.Cu")
		(net "M_A_DQ<37>")
	)
	(segment
		(start 280.473658 -22.279356)
		(end 280.785062 -21.967952)
		(width 0.14224)
		(layer "In2.Cu")
		(net "M_A_DQ<37>")
	)
	(segment
		(start 280.581608 -17.653)
		(end 280.270712 -17.653)
		(width 0.14224)
		(layer "In2.Cu")
		(net "M_A_DQ<37>")
	)
	(segment
		(start 280.270712 -17.653)
		(end 279.699974 -17.082262)
		(width 0.14224)
		(layer "In2.Cu")
		(net "M_A_DQ<37>")
	)
	(segment
		(start 272.025618 -33.874964)
		(end 272.20545 -33.874964)
		(width 0.1651)
		(layer "F.Cu")
		(net "M_A_DQ<36>")
	)
	(segment
		(start 270.66875 -40.4622)
		(end 270.66875 -40.976804)
		(width 0.1016)
		(layer "F.Cu")
		(net "M_A_DQ<36>")
	)
	(segment
		(start 279.687274 -25.426924)
		(end 271.722342 -33.391856)
		(width 0.1651)
		(layer "F.Cu")
		(net "M_A_DQ<36>")
	)
	(segment
		(start 271.57299 -52.793646)
		(end 272.052288 -53.427884)
		(width 0.0889)
		(layer "F.Cu")
		(net "M_A_DQ<36>")
	)
	(segment
		(start 271.622774 -49.799748)
		(end 271.610074 -49.812448)
		(width 0.1016)
		(layer "F.Cu")
		(net "M_A_DQ<36>")
	)
	(segment
		(start 280.549858 -20.023582)
		(end 280.549858 -18.692368)
		(width 0.1651)
		(layer "F.Cu")
		(net "M_A_DQ<36>")
	)
	(segment
		(start 271.722342 -33.391856)
		(end 271.722342 -33.571688)
		(width 0.1651)
		(layer "F.Cu")
		(net "M_A_DQ<36>")
	)
	(segment
		(start 271.31645 -51.393344)
		(end 271.53489 -51.772058)
		(width 0.0889)
		(layer "F.Cu")
		(net "M_A_DQ<36>")
	)
	(segment
		(start 272.82902 -33.485074)
		(end 273.078702 -33.734756)
		(width 0.1651)
		(layer "F.Cu")
		(net "M_A_DQ<36>")
	)
	(segment
		(start 272.20545 -33.874964)
		(end 272.59534 -33.485074)
		(width 0.1651)
		(layer "F.Cu")
		(net "M_A_DQ<36>")
	)
	(segment
		(start 271.722342 -33.571688)
		(end 272.025618 -33.874964)
		(width 0.1651)
		(layer "F.Cu")
		(net "M_A_DQ<36>")
	)
	(segment
		(start 271.31645 -50.399696)
		(end 271.31645 -51.393344)
		(width 0.0889)
		(layer "F.Cu")
		(net "M_A_DQ<36>")
	)
	(segment
		(start 272.59534 -33.485074)
		(end 272.82902 -33.485074)
		(width 0.1651)
		(layer "F.Cu")
		(net "M_A_DQ<36>")
	)
	(segment
		(start 273.078702 -33.968436)
		(end 270.66875 -36.378388)
		(width 0.1651)
		(layer "F.Cu")
		(net "M_A_DQ<36>")
	)
	(segment
		(start 273.078702 -33.734756)
		(end 273.078702 -33.968436)
		(width 0.1651)
		(layer "F.Cu")
		(net "M_A_DQ<36>")
	)
	(segment
		(start 270.66875 -36.378388)
		(end 270.66875 -40.4622)
		(width 0.1651)
		(layer "F.Cu")
		(net "M_A_DQ<36>")
	)
	(segment
		(start 279.699974 -23.560278)
		(end 279.687274 -23.572978)
		(width 0.1651)
		(layer "F.Cu")
		(net "M_A_DQ<36>")
	)
	(segment
		(start 271.610074 -49.812448)
		(end 271.610074 -50.106072)
		(width 0.0889)
		(layer "F.Cu")
		(net "M_A_DQ<36>")
	)
	(segment
		(start 271.610074 -50.106072)
		(end 271.31645 -50.399696)
		(width 0.0889)
		(layer "F.Cu")
		(net "M_A_DQ<36>")
	)
	(segment
		(start 280.550366 -20.023582)
		(end 280.549858 -20.023582)
		(width 0.1651)
		(layer "F.Cu")
		(net "M_A_DQ<36>")
	)
	(segment
		(start 271.622774 -41.930828)
		(end 271.622774 -49.799748)
		(width 0.1016)
		(layer "F.Cu")
		(net "M_A_DQ<36>")
	)
	(segment
		(start 280.549858 -18.692368)
		(end 280.451814 -18.161)
		(width 0.1651)
		(layer "F.Cu")
		(net "M_A_DQ<36>")
	)
	(segment
		(start 279.687274 -23.572978)
		(end 279.687274 -25.426924)
		(width 0.1651)
		(layer "F.Cu")
		(net "M_A_DQ<36>")
	)
	(segment
		(start 270.66875 -40.976804)
		(end 271.622774 -41.930828)
		(width 0.1016)
		(layer "F.Cu")
		(net "M_A_DQ<36>")
	)
	(via
		(at 280.451814 -18.161)
		(size 0.508)
		(drill 0.254)
		(layers "F.Cu" "B.Cu")
		(net "M_A_DQ<36>")
	)
	(via
		(at 279.699974 -23.560278)
		(size 0.508)
		(drill 0.254)
		(layers "F.Cu" "B.Cu")
		(net "M_A_DQ<36>")
	)
	(arc
		(start 271.53489 -52.138834)
		(mid 271.454983 -52.437284)
		(end 271.53489 -52.735734)
		(width 0.0889)
		(layer "F.Cu")
		(net "M_A_DQ<36>")
	)
	(arc
		(start 271.53489 -52.735734)
		(mid 271.553098 -52.765244)
		(end 271.57299 -52.793646)
		(width 0.0889)
		(layer "F.Cu")
		(net "M_A_DQ<36>")
	)
	(arc
		(start 271.53489 -51.772058)
		(mid 271.584013 -51.955446)
		(end 271.53489 -52.138834)
		(width 0.0889)
		(layer "F.Cu")
		(net "M_A_DQ<36>")
	)
	(segment
		(start 279.700482 -24.824182)
		(end 279.699974 -24.824182)
		(width 0.1651)
		(layer "B.Cu")
		(net "M_A_DQ<36>")
	)
	(segment
		(start 279.699974 -24.824182)
		(end 279.699974 -23.560278)
		(width 0.1651)
		(layer "B.Cu")
		(net "M_A_DQ<36>")
	)
	(segment
		(start 279.82418 -20.6375)
		(end 280.19248 -20.2692)
		(width 0.14224)
		(layer "In2.Cu")
		(net "M_A_DQ<36>")
	)
	(segment
		(start 280.19248 -20.2692)
		(end 280.19248 -19.9644)
		(width 0.14224)
		(layer "In2.Cu")
		(net "M_A_DQ<36>")
	)
	(segment
		(start 279.464262 -23.324566)
		(end 279.464262 -22.530054)
		(width 0.14224)
		(layer "In2.Cu")
		(net "M_A_DQ<36>")
	)
	(segment
		(start 279.82418 -20.992846)
		(end 279.82418 -20.6375)
		(width 0.14224)
		(layer "In2.Cu")
		(net "M_A_DQ<36>")
	)
	(segment
		(start 279.81148 -19.278854)
		(end 280.175462 -18.914872)
		(width 0.14224)
		(layer "In2.Cu")
		(net "M_A_DQ<36>")
	)
	(segment
		(start 280.19248 -19.9644)
		(end 279.81148 -19.5834)
		(width 0.14224)
		(layer "In2.Cu")
		(net "M_A_DQ<36>")
	)
	(segment
		(start 280.175462 -18.914872)
		(end 280.175462 -18.437352)
		(width 0.14224)
		(layer "In2.Cu")
		(net "M_A_DQ<36>")
	)
	(segment
		(start 280.175462 -18.437352)
		(end 280.451814 -18.161)
		(width 0.14224)
		(layer "In2.Cu")
		(net "M_A_DQ<36>")
	)
	(segment
		(start 279.81148 -19.5834)
		(end 279.81148 -19.278854)
		(width 0.14224)
		(layer "In2.Cu")
		(net "M_A_DQ<36>")
	)
	(segment
		(start 280.175462 -21.818854)
		(end 280.175462 -21.344128)
		(width 0.14224)
		(layer "In2.Cu")
		(net "M_A_DQ<36>")
	)
	(segment
		(start 279.464262 -22.530054)
		(end 280.175462 -21.818854)
		(width 0.14224)
		(layer "In2.Cu")
		(net "M_A_DQ<36>")
	)
	(segment
		(start 279.699974 -23.560278)
		(end 279.464262 -23.324566)
		(width 0.14224)
		(layer "In2.Cu")
		(net "M_A_DQ<36>")
	)
	(segment
		(start 280.175462 -21.344128)
		(end 279.82418 -20.992846)
		(width 0.14224)
		(layer "In2.Cu")
		(net "M_A_DQ<36>")
	)
	(segment
		(start 275.953474 -41.876726)
		(end 277.011384 -40.818816)
		(width 0.1016)
		(layer "F.Cu")
		(net "M_A_DQ<35>")
	)
	(segment
		(start 289.647884 -23.506684)
		(end 288.942526 -22.801326)
		(width 0.1651)
		(layer "F.Cu")
		(net "M_A_DQ<35>")
	)
	(segment
		(start 287.3756 -28.6766)
		(end 288.0614 -27.9908)
		(width 0.1651)
		(layer "F.Cu")
		(net "M_A_DQ<35>")
	)
	(segment
		(start 288.0614 -25.8318)
		(end 289.647884 -24.245316)
		(width 0.1651)
		(layer "F.Cu")
		(net "M_A_DQ<35>")
	)
	(segment
		(start 275.949918 -52.357274)
		(end 275.949918 -51.919886)
		(width 0.0889)
		(layer "F.Cu")
		(net "M_A_DQ<35>")
	)
	(segment
		(start 277.011384 -40.818816)
		(end 277.011384 -40.5384)
		(width 0.1016)
		(layer "F.Cu")
		(net "M_A_DQ<35>")
	)
	(segment
		(start 286.758888 -30.464252)
		(end 286.758888 -29.293312)
		(width 0.1651)
		(layer "F.Cu")
		(net "M_A_DQ<35>")
	)
	(segment
		(start 276.076918 -51.600862)
		(end 276.076918 -49.923192)
		(width 0.0889)
		(layer "F.Cu")
		(net "M_A_DQ<35>")
	)
	(segment
		(start 275.993098 -51.750722)
		(end 276.076918 -51.600862)
		(width 0.0889)
		(layer "F.Cu")
		(net "M_A_DQ<35>")
	)
	(segment
		(start 275.953474 -49.799748)
		(end 275.953474 -41.876726)
		(width 0.1016)
		(layer "F.Cu")
		(net "M_A_DQ<35>")
	)
	(segment
		(start 287.349946 -15.423642)
		(end 287.349946 -16.687546)
		(width 0.1651)
		(layer "F.Cu")
		(net "M_A_DQ<35>")
	)
	(segment
		(start 277.011384 -40.211756)
		(end 286.758888 -30.464252)
		(width 0.1651)
		(layer "F.Cu")
		(net "M_A_DQ<35>")
	)
	(segment
		(start 289.647884 -24.245316)
		(end 289.647884 -23.506684)
		(width 0.1651)
		(layer "F.Cu")
		(net "M_A_DQ<35>")
	)
	(segment
		(start 276.076918 -49.923192)
		(end 275.953474 -49.799748)
		(width 0.0889)
		(layer "F.Cu")
		(net "M_A_DQ<35>")
	)
	(segment
		(start 288.0614 -27.9908)
		(end 288.0614 -25.8318)
		(width 0.1651)
		(layer "F.Cu")
		(net "M_A_DQ<35>")
	)
	(segment
		(start 288.942526 -22.801326)
		(end 288.7218 -22.801326)
		(width 0.1651)
		(layer "F.Cu")
		(net "M_A_DQ<35>")
	)
	(segment
		(start 288.7218 -22.801326)
		(end 288.19983 -22.279356)
		(width 0.1651)
		(layer "F.Cu")
		(net "M_A_DQ<35>")
	)
	(segment
		(start 275.486114 -53.427884)
		(end 275.949918 -52.357274)
		(width 0.0889)
		(layer "F.Cu")
		(net "M_A_DQ<35>")
	)
	(segment
		(start 287.350454 -15.423642)
		(end 287.349946 -15.423642)
		(width 0.1651)
		(layer "F.Cu")
		(net "M_A_DQ<35>")
	)
	(segment
		(start 286.758888 -29.293312)
		(end 287.3756 -28.6766)
		(width 0.1651)
		(layer "F.Cu")
		(net "M_A_DQ<35>")
	)
	(segment
		(start 277.011384 -40.5384)
		(end 277.011384 -40.211756)
		(width 0.1651)
		(layer "F.Cu")
		(net "M_A_DQ<35>")
	)
	(via
		(at 288.19983 -22.279356)
		(size 0.508)
		(drill 0.254)
		(layers "F.Cu" "B.Cu")
		(net "M_A_DQ<35>")
	)
	(via
		(at 287.349946 -16.687546)
		(size 0.508)
		(drill 0.254)
		(layers "F.Cu" "B.Cu")
		(net "M_A_DQ<35>")
	)
	(via
		(at 287.3756 -28.6766)
		(size 0.508)
		(drill 0.254)
		(layers "F.Cu" "B.Cu")
		(net "M_A_DQ<35>")
	)
	(arc
		(start 275.949918 -51.919886)
		(mid 275.960873 -51.832587)
		(end 275.993098 -51.750722)
		(width 0.0889)
		(layer "F.Cu")
		(net "M_A_DQ<35>")
	)
	(segment
		(start 288.200338 -20.224242)
		(end 288.19983 -20.224242)
		(width 0.1651)
		(layer "B.Cu")
		(net "M_A_DQ<35>")
	)
	(segment
		(start 288.19983 -20.224242)
		(end 288.19983 -22.279356)
		(width 0.1651)
		(layer "B.Cu")
		(net "M_A_DQ<35>")
	)
	(segment
		(start 288.552636 -21.92655)
		(end 288.552636 -18.621248)
		(width 0.14224)
		(layer "In2.Cu")
		(net "M_A_DQ<35>")
	)
	(segment
		(start 288.708084 -18.4658)
		(end 288.708084 -18.1102)
		(width 0.14224)
		(layer "In2.Cu")
		(net "M_A_DQ<35>")
	)
	(segment
		(start 288.250884 -17.653)
		(end 287.996884 -17.653)
		(width 0.14224)
		(layer "In2.Cu")
		(net "M_A_DQ<35>")
	)
	(segment
		(start 288.19983 -22.279356)
		(end 288.552636 -21.92655)
		(width 0.14224)
		(layer "In2.Cu")
		(net "M_A_DQ<35>")
	)
	(segment
		(start 288.708084 -18.1102)
		(end 288.250884 -17.653)
		(width 0.14224)
		(layer "In2.Cu")
		(net "M_A_DQ<35>")
	)
	(segment
		(start 287.349946 -17.006062)
		(end 287.349946 -16.687546)
		(width 0.14224)
		(layer "In2.Cu")
		(net "M_A_DQ<35>")
	)
	(segment
		(start 287.996884 -17.653)
		(end 287.349946 -17.006062)
		(width 0.14224)
		(layer "In2.Cu")
		(net "M_A_DQ<35>")
	)
	(segment
		(start 288.552636 -18.621248)
		(end 288.708084 -18.4658)
		(width 0.14224)
		(layer "In2.Cu")
		(net "M_A_DQ<35>")
	)
	(segment
		(start 287.725866 -22.917658)
		(end 287.5026 -22.694392)
		(width 0.1651)
		(layer "F.Cu")
		(net "M_A_DQ<34>")
	)
	(segment
		(start 288.19983 -19.026632)
		(end 288.331402 -18.89506)
		(width 0.1651)
		(layer "F.Cu")
		(net "M_A_DQ<34>")
	)
	(segment
		(start 275.559774 -49.963324)
		(end 275.559774 -49.812448)
		(width 0.0889)
		(layer "F.Cu")
		(net "M_A_DQ<34>")
	)
	(segment
		(start 275.486114 -52.437538)
		(end 275.886418 -51.512978)
		(width 0.0889)
		(layer "F.Cu")
		(net "M_A_DQ<34>")
	)
	(segment
		(start 275.559774 -49.812448)
		(end 275.559774 -41.685972)
		(width 0.1016)
		(layer "F.Cu")
		(net "M_A_DQ<34>")
	)
	(segment
		(start 275.886418 -51.512978)
		(end 275.886418 -50.289968)
		(width 0.0889)
		(layer "F.Cu")
		(net "M_A_DQ<34>")
	)
	(segment
		(start 287.349946 -24.689054)
		(end 287.9852 -24.0538)
		(width 0.1651)
		(layer "F.Cu")
		(net "M_A_DQ<34>")
	)
	(segment
		(start 287.349946 -27.3939)
		(end 287.349946 -26.416)
		(width 0.1651)
		(layer "F.Cu")
		(net "M_A_DQ<34>")
	)
	(segment
		(start 288.200338 -20.023582)
		(end 288.19983 -20.023582)
		(width 0.1651)
		(layer "F.Cu")
		(net "M_A_DQ<34>")
	)
	(segment
		(start 287.349946 -26.416)
		(end 287.349946 -24.689054)
		(width 0.1651)
		(layer "F.Cu")
		(net "M_A_DQ<34>")
	)
	(segment
		(start 287.0708 -23.281132)
		(end 287.349946 -23.560278)
		(width 0.1651)
		(layer "F.Cu")
		(net "M_A_DQ<34>")
	)
	(segment
		(start 288.19983 -20.023582)
		(end 288.19983 -19.026632)
		(width 0.1651)
		(layer "F.Cu")
		(net "M_A_DQ<34>")
	)
	(segment
		(start 287.322768 -22.694392)
		(end 287.0708 -22.94636)
		(width 0.1651)
		(layer "F.Cu")
		(net "M_A_DQ<34>")
	)
	(segment
		(start 287.9852 -23.571454)
		(end 287.8074 -23.393654)
		(width 0.1651)
		(layer "F.Cu")
		(net "M_A_DQ<34>")
	)
	(segment
		(start 275.886418 -50.289968)
		(end 275.559774 -49.963324)
		(width 0.0889)
		(layer "F.Cu")
		(net "M_A_DQ<34>")
	)
	(segment
		(start 286.119062 -30.198822)
		(end 286.119062 -28.624784)
		(width 0.1651)
		(layer "F.Cu")
		(net "M_A_DQ<34>")
	)
	(segment
		(start 287.9852 -24.0538)
		(end 287.9852 -23.571454)
		(width 0.1651)
		(layer "F.Cu")
		(net "M_A_DQ<34>")
	)
	(segment
		(start 287.5026 -22.694392)
		(end 287.322768 -22.694392)
		(width 0.1651)
		(layer "F.Cu")
		(net "M_A_DQ<34>")
	)
	(segment
		(start 286.119062 -28.624784)
		(end 287.349946 -27.3939)
		(width 0.1651)
		(layer "F.Cu")
		(net "M_A_DQ<34>")
	)
	(segment
		(start 276.371558 -40.874188)
		(end 276.371558 -40.4622)
		(width 0.1016)
		(layer "F.Cu")
		(net "M_A_DQ<34>")
	)
	(segment
		(start 276.371558 -40.4622)
		(end 276.371558 -39.946326)
		(width 0.1651)
		(layer "F.Cu")
		(net "M_A_DQ<34>")
	)
	(segment
		(start 288.331402 -18.67154)
		(end 288.19983 -18.539968)
		(width 0.1651)
		(layer "F.Cu")
		(net "M_A_DQ<34>")
	)
	(segment
		(start 275.559774 -41.685972)
		(end 276.371558 -40.874188)
		(width 0.1016)
		(layer "F.Cu")
		(net "M_A_DQ<34>")
	)
	(segment
		(start 287.8074 -23.23846)
		(end 287.725866 -23.156926)
		(width 0.1651)
		(layer "F.Cu")
		(net "M_A_DQ<34>")
	)
	(segment
		(start 287.725866 -23.156926)
		(end 287.725866 -22.917658)
		(width 0.1651)
		(layer "F.Cu")
		(net "M_A_DQ<34>")
	)
	(segment
		(start 288.331402 -18.89506)
		(end 288.331402 -18.67154)
		(width 0.1651)
		(layer "F.Cu")
		(net "M_A_DQ<34>")
	)
	(segment
		(start 287.0708 -22.94636)
		(end 287.0708 -23.281132)
		(width 0.1651)
		(layer "F.Cu")
		(net "M_A_DQ<34>")
	)
	(segment
		(start 288.19983 -18.539968)
		(end 288.19983 -18.2626)
		(width 0.1651)
		(layer "F.Cu")
		(net "M_A_DQ<34>")
	)
	(segment
		(start 287.8074 -23.393654)
		(end 287.8074 -23.23846)
		(width 0.1651)
		(layer "F.Cu")
		(net "M_A_DQ<34>")
	)
	(segment
		(start 276.371558 -39.946326)
		(end 286.119062 -30.198822)
		(width 0.1651)
		(layer "F.Cu")
		(net "M_A_DQ<34>")
	)
	(via
		(at 288.19983 -18.2626)
		(size 0.508)
		(drill 0.254)
		(layers "F.Cu" "B.Cu")
		(net "M_A_DQ<34>")
	)
	(via
		(at 287.349946 -23.560278)
		(size 0.508)
		(drill 0.254)
		(layers "F.Cu" "B.Cu")
		(net "M_A_DQ<34>")
	)
	(via
		(at 287.349946 -26.416)
		(size 0.508)
		(drill 0.254)
		(layers "F.Cu" "B.Cu")
		(net "M_A_DQ<34>")
	)
	(segment
		(start 287.349946 -24.824182)
		(end 287.349946 -23.560278)
		(width 0.1651)
		(layer "B.Cu")
		(net "M_A_DQ<34>")
	)
	(segment
		(start 287.350454 -24.824182)
		(end 287.349946 -24.824182)
		(width 0.1651)
		(layer "B.Cu")
		(net "M_A_DQ<34>")
	)
	(segment
		(start 287.801812 -18.660618)
		(end 288.19983 -18.2626)
		(width 0.14224)
		(layer "In2.Cu")
		(net "M_A_DQ<34>")
	)
	(segment
		(start 287.45688 -19.659346)
		(end 287.45688 -19.310604)
		(width 0.14224)
		(layer "In2.Cu")
		(net "M_A_DQ<34>")
	)
	(segment
		(start 287.45688 -19.310604)
		(end 287.801812 -18.965672)
		(width 0.14224)
		(layer "In2.Cu")
		(net "M_A_DQ<34>")
	)
	(segment
		(start 287.76168 -20.25015)
		(end 287.76168 -19.964146)
		(width 0.14224)
		(layer "In2.Cu")
		(net "M_A_DQ<34>")
	)
	(segment
		(start 287.349946 -23.560278)
		(end 287.065212 -23.275544)
		(width 0.14224)
		(layer "In2.Cu")
		(net "M_A_DQ<34>")
	)
	(segment
		(start 287.76168 -19.964146)
		(end 287.45688 -19.659346)
		(width 0.14224)
		(layer "In2.Cu")
		(net "M_A_DQ<34>")
	)
	(segment
		(start 287.45688 -20.955)
		(end 287.45688 -20.55495)
		(width 0.14224)
		(layer "In2.Cu")
		(net "M_A_DQ<34>")
	)
	(segment
		(start 287.801812 -18.965672)
		(end 287.801812 -18.660618)
		(width 0.14224)
		(layer "In2.Cu")
		(net "M_A_DQ<34>")
	)
	(segment
		(start 287.91408 -21.4122)
		(end 287.45688 -20.955)
		(width 0.14224)
		(layer "In2.Cu")
		(net "M_A_DQ<34>")
	)
	(segment
		(start 287.065212 -23.275544)
		(end 287.065212 -22.5298)
		(width 0.14224)
		(layer "In2.Cu")
		(net "M_A_DQ<34>")
	)
	(segment
		(start 287.45688 -20.55495)
		(end 287.76168 -20.25015)
		(width 0.14224)
		(layer "In2.Cu")
		(net "M_A_DQ<34>")
	)
	(segment
		(start 287.065212 -22.5298)
		(end 287.91408 -21.680932)
		(width 0.14224)
		(layer "In2.Cu")
		(net "M_A_DQ<34>")
	)
	(segment
		(start 287.91408 -21.680932)
		(end 287.91408 -21.4122)
		(width 0.14224)
		(layer "In2.Cu")
		(net "M_A_DQ<34>")
	)
	(segment
		(start 281.6733 -24.097488)
		(end 281.6733 -26.30551)
		(width 0.1651)
		(layer "F.Cu")
		(net "M_A_DQ<33>")
	)
	(segment
		(start 281.400504 -15.423642)
		(end 281.399996 -15.423642)
		(width 0.1651)
		(layer "F.Cu")
		(net "M_A_DQ<33>")
	)
	(segment
		(start 272.797524 -49.818798)
		(end 272.797524 -51.8287)
		(width 0.0889)
		(layer "F.Cu")
		(net "M_A_DQ<33>")
	)
	(segment
		(start 280.149808 -29.761942)
		(end 272.588228 -37.323522)
		(width 0.1651)
		(layer "F.Cu")
		(net "M_A_DQ<33>")
	)
	(segment
		(start 281.931364 -23.448264)
		(end 281.931364 -23.839424)
		(width 0.1651)
		(layer "F.Cu")
		(net "M_A_DQ<33>")
	)
	(segment
		(start 272.588228 -40.991028)
		(end 272.803874 -41.206674)
		(width 0.1016)
		(layer "F.Cu")
		(net "M_A_DQ<33>")
	)
	(segment
		(start 281.6733 -26.30551)
		(end 279.805892 -28.172918)
		(width 0.1651)
		(layer "F.Cu")
		(net "M_A_DQ<33>")
	)
	(segment
		(start 282.07208 -22.279356)
		(end 281.563064 -22.788372)
		(width 0.1651)
		(layer "F.Cu")
		(net "M_A_DQ<33>")
	)
	(segment
		(start 279.094692 -29.850842)
		(end 279.6667 -29.278834)
		(width 0.1651)
		(layer "F.Cu")
		(net "M_A_DQ<33>")
	)
	(segment
		(start 279.90038 -29.278834)
		(end 280.149808 -29.528262)
		(width 0.1651)
		(layer "F.Cu")
		(net "M_A_DQ<33>")
	)
	(segment
		(start 272.797524 -51.8287)
		(end 272.910808 -51.941984)
		(width 0.0889)
		(layer "F.Cu")
		(net "M_A_DQ<33>")
	)
	(segment
		(start 279.6667 -29.278834)
		(end 279.90038 -29.278834)
		(width 0.1651)
		(layer "F.Cu")
		(net "M_A_DQ<33>")
	)
	(segment
		(start 279.805892 -28.172918)
		(end 278.611076 -29.367734)
		(width 0.1651)
		(layer "F.Cu")
		(net "M_A_DQ<33>")
	)
	(segment
		(start 278.846788 -29.850842)
		(end 279.094692 -29.850842)
		(width 0.1651)
		(layer "F.Cu")
		(net "M_A_DQ<33>")
	)
	(segment
		(start 272.803874 -49.812448)
		(end 272.797524 -49.818798)
		(width 0.0889)
		(layer "F.Cu")
		(net "M_A_DQ<33>")
	)
	(segment
		(start 281.563064 -23.079964)
		(end 281.931364 -23.448264)
		(width 0.1651)
		(layer "F.Cu")
		(net "M_A_DQ<33>")
	)
	(segment
		(start 281.563064 -22.788372)
		(end 281.563064 -23.079964)
		(width 0.1651)
		(layer "F.Cu")
		(net "M_A_DQ<33>")
	)
	(segment
		(start 272.588228 -37.323522)
		(end 272.588228 -40.3606)
		(width 0.1651)
		(layer "F.Cu")
		(net "M_A_DQ<33>")
	)
	(segment
		(start 278.611076 -29.61513)
		(end 278.846788 -29.850842)
		(width 0.1651)
		(layer "F.Cu")
		(net "M_A_DQ<33>")
	)
	(segment
		(start 281.399996 -15.423642)
		(end 281.399996 -16.687546)
		(width 0.1651)
		(layer "F.Cu")
		(net "M_A_DQ<33>")
	)
	(segment
		(start 280.149808 -29.528262)
		(end 280.149808 -29.761942)
		(width 0.1651)
		(layer "F.Cu")
		(net "M_A_DQ<33>")
	)
	(segment
		(start 281.931364 -23.839424)
		(end 281.6733 -24.097488)
		(width 0.1651)
		(layer "F.Cu")
		(net "M_A_DQ<33>")
	)
	(segment
		(start 278.611076 -29.367734)
		(end 278.611076 -29.61513)
		(width 0.1651)
		(layer "F.Cu")
		(net "M_A_DQ<33>")
	)
	(segment
		(start 272.588228 -40.3606)
		(end 272.588228 -40.991028)
		(width 0.1016)
		(layer "F.Cu")
		(net "M_A_DQ<33>")
	)
	(segment
		(start 272.803874 -41.206674)
		(end 272.803874 -49.812448)
		(width 0.1016)
		(layer "F.Cu")
		(net "M_A_DQ<33>")
	)
	(via
		(at 281.399996 -16.687546)
		(size 0.508)
		(drill 0.254)
		(layers "F.Cu" "B.Cu")
		(net "M_A_DQ<33>")
	)
	(via
		(at 282.07208 -22.279356)
		(size 0.508)
		(drill 0.254)
		(layers "F.Cu" "B.Cu")
		(net "M_A_DQ<33>")
	)
	(via
		(at 279.805892 -28.172918)
		(size 0.508)
		(drill 0.254)
		(layers "F.Cu" "B.Cu")
		(net "M_A_DQ<33>")
	)
	(segment
		(start 282.24988 -20.224242)
		(end 282.24988 -21.598382)
		(width 0.1651)
		(layer "B.Cu")
		(net "M_A_DQ<33>")
	)
	(segment
		(start 282.250388 -20.224242)
		(end 282.24988 -20.224242)
		(width 0.1651)
		(layer "B.Cu")
		(net "M_A_DQ<33>")
	)
	(segment
		(start 282.07208 -21.776182)
		(end 282.07208 -22.279356)
		(width 0.1651)
		(layer "B.Cu")
		(net "M_A_DQ<33>")
	)
	(segment
		(start 282.24988 -21.598382)
		(end 282.07208 -21.776182)
		(width 0.1651)
		(layer "B.Cu")
		(net "M_A_DQ<33>")
	)
	(segment
		(start 282.602686 -18.415)
		(end 282.602686 -18.073624)
		(width 0.14224)
		(layer "In2.Cu")
		(net "M_A_DQ<33>")
	)
	(segment
		(start 281.877262 -17.7038)
		(end 281.399996 -17.226534)
		(width 0.14224)
		(layer "In2.Cu")
		(net "M_A_DQ<33>")
	)
	(segment
		(start 282.602686 -18.073624)
		(end 282.232862 -17.7038)
		(width 0.14224)
		(layer "In2.Cu")
		(net "M_A_DQ<33>")
	)
	(segment
		(start 282.446222 -21.905214)
		(end 282.446222 -18.571464)
		(width 0.14224)
		(layer "In2.Cu")
		(net "M_A_DQ<33>")
	)
	(segment
		(start 282.07208 -22.279356)
		(end 282.446222 -21.905214)
		(width 0.14224)
		(layer "In2.Cu")
		(net "M_A_DQ<33>")
	)
	(segment
		(start 282.446222 -18.571464)
		(end 282.602686 -18.415)
		(width 0.14224)
		(layer "In2.Cu")
		(net "M_A_DQ<33>")
	)
	(segment
		(start 281.399996 -17.226534)
		(end 281.399996 -16.687546)
		(width 0.14224)
		(layer "In2.Cu")
		(net "M_A_DQ<33>")
	)
	(segment
		(start 282.232862 -17.7038)
		(end 281.877262 -17.7038)
		(width 0.14224)
		(layer "In2.Cu")
		(net "M_A_DQ<33>")
	)
	(segment
		(start 272.3896 -52.100226)
		(end 272.3896 -51.835558)
		(width 0.0889)
		(layer "F.Cu")
		(net "M_A_DQ<32>")
	)
	(segment
		(start 277.538942 -31.418022)
		(end 277.538942 -31.184342)
		(width 0.1651)
		(layer "F.Cu")
		(net "M_A_DQ<32>")
	)
	(segment
		(start 272.3896 -51.835558)
		(end 272.607024 -51.618134)
		(width 0.0889)
		(layer "F.Cu")
		(net "M_A_DQ<32>")
	)
	(segment
		(start 276.30628 -31.684468)
		(end 276.032722 -31.684468)
		(width 0.1651)
		(layer "F.Cu")
		(net "M_A_DQ<32>")
	)
	(segment
		(start 277.055834 -30.934914)
		(end 276.30628 -31.684468)
		(width 0.1651)
		(layer "F.Cu")
		(net "M_A_DQ<32>")
	)
	(segment
		(start 271.948402 -37.008562)
		(end 277.538942 -31.418022)
		(width 0.1651)
		(layer "F.Cu")
		(net "M_A_DQ<32>")
	)
	(segment
		(start 272.052288 -52.437538)
		(end 272.10004 -52.39004)
		(width 0.0889)
		(layer "F.Cu")
		(net "M_A_DQ<32>")
	)
	(segment
		(start 282.169108 -19.177)
		(end 282.07208 -18.161)
		(width 0.1651)
		(layer "F.Cu")
		(net "M_A_DQ<32>")
	)
	(segment
		(start 281.0129 -23.947374)
		(end 281.399996 -23.560278)
		(width 0.1651)
		(layer "F.Cu")
		(net "M_A_DQ<32>")
	)
	(segment
		(start 272.607024 -50.30597)
		(end 272.410174 -50.10912)
		(width 0.0889)
		(layer "F.Cu")
		(net "M_A_DQ<32>")
	)
	(segment
		(start 271.948402 -40.386)
		(end 271.948402 -37.008562)
		(width 0.1651)
		(layer "F.Cu")
		(net "M_A_DQ<32>")
	)
	(segment
		(start 280.448512 -26.575258)
		(end 281.0129 -26.01087)
		(width 0.1651)
		(layer "F.Cu")
		(net "M_A_DQ<32>")
	)
	(segment
		(start 282.24988 -20.023582)
		(end 282.169108 -19.177)
		(width 0.1651)
		(layer "F.Cu")
		(net "M_A_DQ<32>")
	)
	(segment
		(start 277.538942 -31.184342)
		(end 277.289514 -30.934914)
		(width 0.1651)
		(layer "F.Cu")
		(net "M_A_DQ<32>")
	)
	(segment
		(start 272.410174 -41.42232)
		(end 271.948402 -40.960548)
		(width 0.1016)
		(layer "F.Cu")
		(net "M_A_DQ<32>")
	)
	(segment
		(start 271.948402 -40.960548)
		(end 271.948402 -40.386)
		(width 0.1016)
		(layer "F.Cu")
		(net "M_A_DQ<32>")
	)
	(segment
		(start 275.822664 -31.201106)
		(end 280.448512 -26.575258)
		(width 0.1651)
		(layer "F.Cu")
		(net "M_A_DQ<32>")
	)
	(segment
		(start 272.410174 -50.10912)
		(end 272.410174 -41.42232)
		(width 0.1016)
		(layer "F.Cu")
		(net "M_A_DQ<32>")
	)
	(segment
		(start 282.250388 -20.023582)
		(end 282.24988 -20.023582)
		(width 0.1651)
		(layer "F.Cu")
		(net "M_A_DQ<32>")
	)
	(segment
		(start 276.032722 -31.684468)
		(end 275.822664 -31.47441)
		(width 0.1651)
		(layer "F.Cu")
		(net "M_A_DQ<32>")
	)
	(segment
		(start 272.607024 -51.618134)
		(end 272.607024 -50.30597)
		(width 0.0889)
		(layer "F.Cu")
		(net "M_A_DQ<32>")
	)
	(segment
		(start 277.289514 -30.934914)
		(end 277.055834 -30.934914)
		(width 0.1651)
		(layer "F.Cu")
		(net "M_A_DQ<32>")
	)
	(segment
		(start 281.0129 -26.01087)
		(end 281.0129 -23.947374)
		(width 0.1651)
		(layer "F.Cu")
		(net "M_A_DQ<32>")
	)
	(segment
		(start 275.822664 -31.47441)
		(end 275.822664 -31.201106)
		(width 0.1651)
		(layer "F.Cu")
		(net "M_A_DQ<32>")
	)
	(segment
		(start 272.10004 -52.39004)
		(end 272.3896 -52.100226)
		(width 0.0889)
		(layer "F.Cu")
		(net "M_A_DQ<32>")
	)
	(via
		(at 280.448512 -26.575258)
		(size 0.508)
		(drill 0.254)
		(layers "F.Cu" "B.Cu")
		(net "M_A_DQ<32>")
	)
	(via
		(at 281.399996 -23.560278)
		(size 0.508)
		(drill 0.254)
		(layers "F.Cu" "B.Cu")
		(net "M_A_DQ<32>")
	)
	(via
		(at 282.07208 -18.161)
		(size 0.508)
		(drill 0.254)
		(layers "F.Cu" "B.Cu")
		(net "M_A_DQ<32>")
	)
	(segment
		(start 281.400504 -24.824182)
		(end 281.399996 -24.824182)
		(width 0.1651)
		(layer "B.Cu")
		(net "M_A_DQ<32>")
	)
	(segment
		(start 281.399996 -24.824182)
		(end 281.399996 -23.560278)
		(width 0.1651)
		(layer "B.Cu")
		(net "M_A_DQ<32>")
	)
	(segment
		(start 281.43708 -19.7104)
		(end 281.43708 -19.380454)
		(width 0.14224)
		(layer "In2.Cu")
		(net "M_A_DQ<32>")
	)
	(segment
		(start 281.77998 -20.0533)
		(end 281.43708 -19.7104)
		(width 0.14224)
		(layer "In2.Cu")
		(net "M_A_DQ<32>")
	)
	(segment
		(start 281.46248 -20.5994)
		(end 281.77998 -20.2819)
		(width 0.14224)
		(layer "In2.Cu")
		(net "M_A_DQ<32>")
	)
	(segment
		(start 281.399996 -23.560278)
		(end 281.115262 -23.275544)
		(width 0.14224)
		(layer "In2.Cu")
		(net "M_A_DQ<32>")
	)
	(segment
		(start 281.851862 -18.965672)
		(end 281.851862 -18.381218)
		(width 0.14224)
		(layer "In2.Cu")
		(net "M_A_DQ<32>")
	)
	(segment
		(start 281.43708 -19.380454)
		(end 281.851862 -18.965672)
		(width 0.14224)
		(layer "In2.Cu")
		(net "M_A_DQ<32>")
	)
	(segment
		(start 281.115262 -22.5298)
		(end 281.851862 -21.7932)
		(width 0.14224)
		(layer "In2.Cu")
		(net "M_A_DQ<32>")
	)
	(segment
		(start 281.851862 -21.293328)
		(end 281.46248 -20.903946)
		(width 0.14224)
		(layer "In2.Cu")
		(net "M_A_DQ<32>")
	)
	(segment
		(start 281.851862 -18.381218)
		(end 282.07208 -18.161)
		(width 0.14224)
		(layer "In2.Cu")
		(net "M_A_DQ<32>")
	)
	(segment
		(start 281.851862 -21.7932)
		(end 281.851862 -21.293328)
		(width 0.14224)
		(layer "In2.Cu")
		(net "M_A_DQ<32>")
	)
	(segment
		(start 281.46248 -20.903946)
		(end 281.46248 -20.5994)
		(width 0.14224)
		(layer "In2.Cu")
		(net "M_A_DQ<32>")
	)
	(segment
		(start 281.115262 -23.275544)
		(end 281.115262 -22.5298)
		(width 0.14224)
		(layer "In2.Cu")
		(net "M_A_DQ<32>")
	)
	(segment
		(start 281.77998 -20.2819)
		(end 281.77998 -20.0533)
		(width 0.14224)
		(layer "In2.Cu")
		(net "M_A_DQ<32>")
	)
	(segment
		(start 230.399844 -15.423642)
		(end 230.399844 -16.687546)
		(width 0.1651)
		(layer "F.Cu")
		(net "M_A_DQ<31>")
	)
	(segment
		(start 230.400352 -15.423642)
		(end 230.399844 -15.423642)
		(width 0.1651)
		(layer "F.Cu")
		(net "M_A_DQ<31>")
	)
	(segment
		(start 243.051838 -56.58104)
		(end 242.480338 -56.58104)
		(width 0.1016)
		(layer "F.Cu")
		(net "M_A_DQ<31>")
	)
	(via
		(at 231.249728 -22.279356)
		(size 0.508)
		(drill 0.254)
		(layers "F.Cu" "B.Cu")
		(net "M_A_DQ<31>")
	)
	(via
		(at 230.399844 -16.687546)
		(size 0.508)
		(drill 0.254)
		(layers "F.Cu" "B.Cu")
		(net "M_A_DQ<31>")
	)
	(via
		(at 242.480338 -56.58104)
		(size 0.508)
		(drill 0.254)
		(layers "F.Cu" "B.Cu")
		(net "M_A_DQ<31>")
	)
	(segment
		(start 231.25049 -20.224242)
		(end 231.25049 -22.278594)
		(width 0.1651)
		(layer "B.Cu")
		(net "M_A_DQ<31>")
	)
	(segment
		(start 231.25049 -22.278594)
		(end 231.249728 -22.279356)
		(width 0.1651)
		(layer "B.Cu")
		(net "M_A_DQ<31>")
	)
	(segment
		(start 231.349296 -23.780496)
		(end 231.349296 -25.803352)
		(width 0.14224)
		(layer "In2.Cu")
		(net "M_A_DQ<31>")
	)
	(segment
		(start 231.602534 -21.92655)
		(end 231.249728 -22.279356)
		(width 0.14224)
		(layer "In2.Cu")
		(net "M_A_DQ<31>")
	)
	(segment
		(start 241.383566 -51.03749)
		(end 243.071396 -52.72532)
		(width 0.0889)
		(layer "In2.Cu")
		(net "M_A_DQ<31>")
	)
	(segment
		(start 231.73436 -28.145232)
		(end 231.590596 -28.288996)
		(width 0.14224)
		(layer "In2.Cu")
		(net "M_A_DQ<31>")
	)
	(segment
		(start 242.802918 -56.58104)
		(end 242.480338 -56.58104)
		(width 0.0889)
		(layer "In2.Cu")
		(net "M_A_DQ<31>")
	)
	(segment
		(start 231.602534 -18.621248)
		(end 231.602534 -21.92655)
		(width 0.14224)
		(layer "In2.Cu")
		(net "M_A_DQ<31>")
	)
	(segment
		(start 231.184196 -37.44976)
		(end 231.326436 -37.592)
		(width 0.14224)
		(layer "In2.Cu")
		(net "M_A_DQ<31>")
	)
	(segment
		(start 239.371124 -50.017934)
		(end 239.558068 -50.342038)
		(width 0.0889)
		(layer "In2.Cu")
		(net "M_A_DQ<31>")
	)
	(segment
		(start 230.716582 -17.3228)
		(end 231.046782 -17.653)
		(width 0.14224)
		(layer "In2.Cu")
		(net "M_A_DQ<31>")
	)
	(segment
		(start 231.300782 -17.653)
		(end 231.757982 -18.1102)
		(width 0.14224)
		(layer "In2.Cu")
		(net "M_A_DQ<31>")
	)
	(segment
		(start 231.046782 -17.653)
		(end 231.300782 -17.653)
		(width 0.14224)
		(layer "In2.Cu")
		(net "M_A_DQ<31>")
	)
	(segment
		(start 231.539796 -25.993852)
		(end 231.539796 -26.790396)
		(width 0.14224)
		(layer "In2.Cu")
		(net "M_A_DQ<31>")
	)
	(segment
		(start 239.184688 -48.767492)
		(end 239.242346 -48.767492)
		(width 0.14224)
		(layer "In2.Cu")
		(net "M_A_DQ<31>")
	)
	(segment
		(start 231.184196 -34.855404)
		(end 231.184196 -37.44976)
		(width 0.14224)
		(layer "In2.Cu")
		(net "M_A_DQ<31>")
	)
	(segment
		(start 243.071142 -52.725574)
		(end 243.071142 -53.60924)
		(width 0.0889)
		(layer "In2.Cu")
		(net "M_A_DQ<31>")
	)
	(segment
		(start 243.071396 -52.72532)
		(end 243.071142 -52.725574)
		(width 0.0889)
		(layer "In2.Cu")
		(net "M_A_DQ<31>")
	)
	(segment
		(start 230.790496 -23.221696)
		(end 231.349296 -23.780496)
		(width 0.14224)
		(layer "In2.Cu")
		(net "M_A_DQ<31>")
	)
	(segment
		(start 231.9782 -37.592)
		(end 233.2482 -38.862)
		(width 0.14224)
		(layer "In2.Cu")
		(net "M_A_DQ<31>")
	)
	(segment
		(start 231.757982 -18.1102)
		(end 231.757982 -18.4658)
		(width 0.14224)
		(layer "In2.Cu")
		(net "M_A_DQ<31>")
	)
	(segment
		(start 233.2482 -38.862)
		(end 233.2482 -42.831004)
		(width 0.14224)
		(layer "In2.Cu")
		(net "M_A_DQ<31>")
	)
	(segment
		(start 231.391968 -29.270452)
		(end 231.391968 -34.647632)
		(width 0.14224)
		(layer "In2.Cu")
		(net "M_A_DQ<31>")
	)
	(segment
		(start 242.858036 -55.721758)
		(end 242.858036 -56.525922)
		(width 0.0889)
		(layer "In2.Cu")
		(net "M_A_DQ<31>")
	)
	(segment
		(start 231.326436 -37.592)
		(end 231.9782 -37.592)
		(width 0.14224)
		(layer "In2.Cu")
		(net "M_A_DQ<31>")
	)
	(segment
		(start 231.391968 -34.647632)
		(end 231.184196 -34.855404)
		(width 0.14224)
		(layer "In2.Cu")
		(net "M_A_DQ<31>")
	)
	(segment
		(start 240.752122 -51.03749)
		(end 241.383566 -51.03749)
		(width 0.0889)
		(layer "In2.Cu")
		(net "M_A_DQ<31>")
	)
	(segment
		(start 230.716582 -17.004284)
		(end 230.716582 -17.3228)
		(width 0.14224)
		(layer "In2.Cu")
		(net "M_A_DQ<31>")
	)
	(segment
		(start 230.790496 -22.738588)
		(end 230.790496 -23.221696)
		(width 0.14224)
		(layer "In2.Cu")
		(net "M_A_DQ<31>")
	)
	(segment
		(start 233.2482 -42.831004)
		(end 239.184688 -48.767492)
		(width 0.14224)
		(layer "In2.Cu")
		(net "M_A_DQ<31>")
	)
	(segment
		(start 239.307624 -48.83277)
		(end 239.307624 -49.210214)
		(width 0.0889)
		(layer "In2.Cu")
		(net "M_A_DQ<31>")
	)
	(segment
		(start 239.307624 -49.210214)
		(end 239.371124 -49.273714)
		(width 0.0889)
		(layer "In2.Cu")
		(net "M_A_DQ<31>")
	)
	(segment
		(start 231.249728 -22.279356)
		(end 230.790496 -22.738588)
		(width 0.14224)
		(layer "In2.Cu")
		(net "M_A_DQ<31>")
	)
	(segment
		(start 239.889792 -50.541936)
		(end 239.922558 -50.541936)
		(width 0.0889)
		(layer "In2.Cu")
		(net "M_A_DQ<31>")
	)
	(segment
		(start 231.590596 -28.288996)
		(end 231.590596 -29.071824)
		(width 0.14224)
		(layer "In2.Cu")
		(net "M_A_DQ<31>")
	)
	(segment
		(start 231.757982 -18.4658)
		(end 231.602534 -18.621248)
		(width 0.14224)
		(layer "In2.Cu")
		(net "M_A_DQ<31>")
	)
	(segment
		(start 239.371124 -49.273714)
		(end 239.371124 -50.017934)
		(width 0.0889)
		(layer "In2.Cu")
		(net "M_A_DQ<31>")
	)
	(segment
		(start 242.858036 -56.525922)
		(end 242.802918 -56.58104)
		(width 0.0889)
		(layer "In2.Cu")
		(net "M_A_DQ<31>")
	)
	(segment
		(start 230.399844 -16.687546)
		(end 230.716582 -17.004284)
		(width 0.14224)
		(layer "In2.Cu")
		(net "M_A_DQ<31>")
	)
	(segment
		(start 231.349296 -25.803352)
		(end 231.539796 -25.993852)
		(width 0.14224)
		(layer "In2.Cu")
		(net "M_A_DQ<31>")
	)
	(segment
		(start 231.590596 -29.071824)
		(end 231.391968 -29.270452)
		(width 0.14224)
		(layer "In2.Cu")
		(net "M_A_DQ<31>")
	)
	(segment
		(start 231.539796 -26.790396)
		(end 231.73436 -26.98496)
		(width 0.14224)
		(layer "In2.Cu")
		(net "M_A_DQ<31>")
	)
	(segment
		(start 239.242346 -48.767492)
		(end 239.307624 -48.83277)
		(width 0.0889)
		(layer "In2.Cu")
		(net "M_A_DQ<31>")
	)
	(segment
		(start 231.73436 -26.98496)
		(end 231.73436 -28.145232)
		(width 0.14224)
		(layer "In2.Cu")
		(net "M_A_DQ<31>")
	)
	(arc
		(start 242.874292 -55.52186)
		(mid 242.878899 -55.622845)
		(end 242.858036 -55.721758)
		(width 0.0889)
		(layer "In2.Cu")
		(net "M_A_DQ<31>")
	)
	(arc
		(start 240.416588 -50.837338)
		(mid 240.558271 -50.981142)
		(end 240.752122 -51.03749)
		(width 0.0889)
		(layer "In2.Cu")
		(net "M_A_DQ<31>")
	)
	(arc
		(start 242.991894 -54.304438)
		(mid 243.071025 -54.59984)
		(end 242.991894 -54.895242)
		(width 0.0889)
		(layer "In2.Cu")
		(net "M_A_DQ<31>")
	)
	(arc
		(start 239.558068 -50.342038)
		(mid 239.698147 -50.484774)
		(end 239.889792 -50.541936)
		(width 0.0889)
		(layer "In2.Cu")
		(net "M_A_DQ<31>")
	)
	(arc
		(start 239.922558 -50.541936)
		(mid 240.207982 -50.625403)
		(end 240.416588 -50.837338)
		(width 0.0889)
		(layer "In2.Cu")
		(net "M_A_DQ<31>")
	)
	(arc
		(start 243.071142 -53.60924)
		(mid 243.050951 -53.762154)
		(end 242.991894 -53.904642)
		(width 0.0889)
		(layer "In2.Cu")
		(net "M_A_DQ<31>")
	)
	(arc
		(start 242.991894 -54.895242)
		(mid 242.879648 -55.198518)
		(end 242.874292 -55.52186)
		(width 0.0889)
		(layer "In2.Cu")
		(net "M_A_DQ<31>")
	)
	(arc
		(start 242.991894 -53.904642)
		(mid 242.938395 -54.10454)
		(end 242.991894 -54.304438)
		(width 0.0889)
		(layer "In2.Cu")
		(net "M_A_DQ<31>")
	)
	(segment
		(start 231.382062 -18.91792)
		(end 231.382062 -18.69948)
		(width 0.1651)
		(layer "F.Cu")
		(net "M_A_DQ<30>")
	)
	(segment
		(start 231.249982 -20.023582)
		(end 231.249982 -19.05)
		(width 0.1651)
		(layer "F.Cu")
		(net "M_A_DQ<30>")
	)
	(segment
		(start 231.249982 -19.05)
		(end 231.382062 -18.91792)
		(width 0.1651)
		(layer "F.Cu")
		(net "M_A_DQ<30>")
	)
	(segment
		(start 231.25049 -20.023582)
		(end 231.249982 -20.023582)
		(width 0.1651)
		(layer "F.Cu")
		(net "M_A_DQ<30>")
	)
	(segment
		(start 243.051838 -54.59984)
		(end 242.480338 -54.59984)
		(width 0.1016)
		(layer "F.Cu")
		(net "M_A_DQ<30>")
	)
	(segment
		(start 231.249982 -18.5674)
		(end 231.249982 -18.262854)
		(width 0.1651)
		(layer "F.Cu")
		(net "M_A_DQ<30>")
	)
	(segment
		(start 231.382062 -18.69948)
		(end 231.249982 -18.5674)
		(width 0.1651)
		(layer "F.Cu")
		(net "M_A_DQ<30>")
	)
	(segment
		(start 231.249982 -18.262854)
		(end 231.249728 -18.2626)
		(width 0.1651)
		(layer "F.Cu")
		(net "M_A_DQ<30>")
	)
	(via
		(at 242.480338 -54.59984)
		(size 0.508)
		(drill 0.254)
		(layers "F.Cu" "B.Cu")
		(net "M_A_DQ<30>")
	)
	(via
		(at 231.249728 -18.2626)
		(size 0.508)
		(drill 0.254)
		(layers "F.Cu" "B.Cu")
		(net "M_A_DQ<30>")
	)
	(via
		(at 230.399844 -23.560278)
		(size 0.508)
		(drill 0.254)
		(layers "F.Cu" "B.Cu")
		(net "M_A_DQ<30>")
	)
	(segment
		(start 230.399844 -24.824182)
		(end 230.399844 -23.560278)
		(width 0.1651)
		(layer "B.Cu")
		(net "M_A_DQ<30>")
	)
	(segment
		(start 230.400352 -24.824182)
		(end 230.399844 -24.824182)
		(width 0.1651)
		(layer "B.Cu")
		(net "M_A_DQ<30>")
	)
	(segment
		(start 231.09174 -40.518588)
		(end 230.9368 -40.363648)
		(width 0.14224)
		(layer "In2.Cu")
		(net "M_A_DQ<30>")
	)
	(segment
		(start 230.904796 -26.273252)
		(end 230.642668 -26.011124)
		(width 0.14224)
		(layer "In2.Cu")
		(net "M_A_DQ<30>")
	)
	(segment
		(start 231.62514 -41.844468)
		(end 231.4702 -41.689528)
		(width 0.14224)
		(layer "In2.Cu")
		(net "M_A_DQ<30>")
	)
	(segment
		(start 239.180624 -50.069242)
		(end 239.180624 -49.362614)
		(width 0.0889)
		(layer "In2.Cu")
		(net "M_A_DQ<30>")
	)
	(segment
		(start 230.642668 -26.011124)
		(end 230.642668 -24.191468)
		(width 0.14224)
		(layer "In2.Cu")
		(net "M_A_DQ<30>")
	)
	(segment
		(start 230.89235 -19.970496)
		(end 230.51135 -19.589496)
		(width 0.14224)
		(layer "In2.Cu")
		(net "M_A_DQ<30>")
	)
	(segment
		(start 230.756968 -28.914852)
		(end 230.930196 -28.741624)
		(width 0.14224)
		(layer "In2.Cu")
		(net "M_A_DQ<30>")
	)
	(segment
		(start 232.7021 -43.143678)
		(end 232.7021 -41.999408)
		(width 0.14224)
		(layer "In2.Cu")
		(net "M_A_DQ<30>")
	)
	(segment
		(start 230.904796 -26.714196)
		(end 230.904796 -26.273252)
		(width 0.14224)
		(layer "In2.Cu")
		(net "M_A_DQ<30>")
	)
	(segment
		(start 230.875332 -18.914872)
		(end 230.875332 -18.636996)
		(width 0.14224)
		(layer "In2.Cu")
		(net "M_A_DQ<30>")
	)
	(segment
		(start 230.930196 -28.741624)
		(end 230.930196 -28.365196)
		(width 0.14224)
		(layer "In2.Cu")
		(net "M_A_DQ<30>")
	)
	(segment
		(start 230.549196 -34.576004)
		(end 230.756968 -34.368232)
		(width 0.14224)
		(layer "In2.Cu")
		(net "M_A_DQ<30>")
	)
	(segment
		(start 231.09174 -39.855648)
		(end 231.68356 -39.855648)
		(width 0.14224)
		(layer "In2.Cu")
		(net "M_A_DQ<30>")
	)
	(segment
		(start 230.9368 -40.363648)
		(end 230.9368 -40.010588)
		(width 0.14224)
		(layer "In2.Cu")
		(net "M_A_DQ<30>")
	)
	(segment
		(start 241.304572 -51.22799)
		(end 240.745518 -51.22799)
		(width 0.0889)
		(layer "In2.Cu")
		(net "M_A_DQ<30>")
	)
	(segment
		(start 230.756968 -34.368232)
		(end 230.756968 -28.914852)
		(width 0.14224)
		(layer "In2.Cu")
		(net "M_A_DQ<30>")
	)
	(segment
		(start 230.930196 -28.365196)
		(end 230.701596 -28.136596)
		(width 0.14224)
		(layer "In2.Cu")
		(net "M_A_DQ<30>")
	)
	(segment
		(start 230.89235 -20.313904)
		(end 230.89235 -19.970496)
		(width 0.14224)
		(layer "In2.Cu")
		(net "M_A_DQ<30>")
	)
	(segment
		(start 231.8258 -39.713408)
		(end 231.8258 -39.19474)
		(width 0.14224)
		(layer "In2.Cu")
		(net "M_A_DQ<30>")
	)
	(segment
		(start 238.844836 -49.286414)
		(end 238.79683 -49.238408)
		(width 0.0889)
		(layer "In2.Cu")
		(net "M_A_DQ<30>")
	)
	(segment
		(start 232.7021 -40.673528)
		(end 232.54716 -40.518588)
		(width 0.14224)
		(layer "In2.Cu")
		(net "M_A_DQ<30>")
	)
	(segment
		(start 232.7021 -41.026588)
		(end 232.7021 -40.673528)
		(width 0.14224)
		(layer "In2.Cu")
		(net "M_A_DQ<30>")
	)
	(segment
		(start 239.915954 -50.732436)
		(end 239.883188 -50.732436)
		(width 0.0889)
		(layer "In2.Cu")
		(net "M_A_DQ<30>")
	)
	(segment
		(start 232.54716 -40.518588)
		(end 231.09174 -40.518588)
		(width 0.14224)
		(layer "In2.Cu")
		(net "M_A_DQ<30>")
	)
	(segment
		(start 230.399844 -23.560278)
		(end 230.164132 -23.324566)
		(width 0.14224)
		(layer "In2.Cu")
		(net "M_A_DQ<30>")
	)
	(segment
		(start 230.701596 -26.917396)
		(end 230.904796 -26.714196)
		(width 0.14224)
		(layer "In2.Cu")
		(net "M_A_DQ<30>")
	)
	(segment
		(start 230.875332 -18.636996)
		(end 231.249728 -18.2626)
		(width 0.14224)
		(layer "In2.Cu")
		(net "M_A_DQ<30>")
	)
	(segment
		(start 238.79683 -49.238408)
		(end 232.7021 -43.143678)
		(width 0.14224)
		(layer "In2.Cu")
		(net "M_A_DQ<30>")
	)
	(segment
		(start 230.704136 -39.0525)
		(end 230.549196 -38.89756)
		(width 0.14224)
		(layer "In2.Cu")
		(net "M_A_DQ<30>")
	)
	(segment
		(start 239.180624 -49.362614)
		(end 239.104424 -49.286414)
		(width 0.0889)
		(layer "In2.Cu")
		(net "M_A_DQ<30>")
	)
	(segment
		(start 242.880388 -53.60924)
		(end 242.880642 -53.124608)
		(width 0.0889)
		(layer "In2.Cu")
		(net "M_A_DQ<30>")
	)
	(segment
		(start 230.51135 -20.694904)
		(end 230.89235 -20.313904)
		(width 0.14224)
		(layer "In2.Cu")
		(net "M_A_DQ<30>")
	)
	(segment
		(start 230.9368 -40.010588)
		(end 231.09174 -39.855648)
		(width 0.14224)
		(layer "In2.Cu")
		(net "M_A_DQ<30>")
	)
	(segment
		(start 230.549196 -38.89756)
		(end 230.549196 -34.576004)
		(width 0.14224)
		(layer "In2.Cu")
		(net "M_A_DQ<30>")
	)
	(segment
		(start 230.51135 -19.589496)
		(end 230.51135 -19.278854)
		(width 0.14224)
		(layer "In2.Cu")
		(net "M_A_DQ<30>")
	)
	(segment
		(start 230.51135 -20.980146)
		(end 230.51135 -20.694904)
		(width 0.14224)
		(layer "In2.Cu")
		(net "M_A_DQ<30>")
	)
	(segment
		(start 231.62514 -41.181528)
		(end 232.54716 -41.181528)
		(width 0.14224)
		(layer "In2.Cu")
		(net "M_A_DQ<30>")
	)
	(segment
		(start 230.399844 -23.948644)
		(end 230.399844 -23.560278)
		(width 0.14224)
		(layer "In2.Cu")
		(net "M_A_DQ<30>")
	)
	(segment
		(start 242.880896 -53.124354)
		(end 242.880896 -52.804314)
		(width 0.0889)
		(layer "In2.Cu")
		(net "M_A_DQ<30>")
	)
	(segment
		(start 242.480338 -54.59984)
		(end 242.785646 -53.895752)
		(width 0.0889)
		(layer "In2.Cu")
		(net "M_A_DQ<30>")
	)
	(segment
		(start 230.164132 -22.530054)
		(end 230.9368 -21.757386)
		(width 0.14224)
		(layer "In2.Cu")
		(net "M_A_DQ<30>")
	)
	(segment
		(start 230.164132 -23.324566)
		(end 230.164132 -22.530054)
		(width 0.14224)
		(layer "In2.Cu")
		(net "M_A_DQ<30>")
	)
	(segment
		(start 231.8258 -39.19474)
		(end 231.68356 -39.0525)
		(width 0.14224)
		(layer "In2.Cu")
		(net "M_A_DQ<30>")
	)
	(segment
		(start 231.68356 -39.0525)
		(end 230.704136 -39.0525)
		(width 0.14224)
		(layer "In2.Cu")
		(net "M_A_DQ<30>")
	)
	(segment
		(start 231.68356 -39.855648)
		(end 231.8258 -39.713408)
		(width 0.14224)
		(layer "In2.Cu")
		(net "M_A_DQ<30>")
	)
	(segment
		(start 230.701596 -28.136596)
		(end 230.701596 -26.917396)
		(width 0.14224)
		(layer "In2.Cu")
		(net "M_A_DQ<30>")
	)
	(segment
		(start 231.4702 -41.689528)
		(end 231.4702 -41.336468)
		(width 0.14224)
		(layer "In2.Cu")
		(net "M_A_DQ<30>")
	)
	(segment
		(start 232.54716 -41.181528)
		(end 232.7021 -41.026588)
		(width 0.14224)
		(layer "In2.Cu")
		(net "M_A_DQ<30>")
	)
	(segment
		(start 230.642668 -24.191468)
		(end 230.399844 -23.948644)
		(width 0.14224)
		(layer "In2.Cu")
		(net "M_A_DQ<30>")
	)
	(segment
		(start 239.392968 -50.437288)
		(end 239.180624 -50.069242)
		(width 0.0889)
		(layer "In2.Cu")
		(net "M_A_DQ<30>")
	)
	(segment
		(start 232.7021 -41.999408)
		(end 232.54716 -41.844468)
		(width 0.14224)
		(layer "In2.Cu")
		(net "M_A_DQ<30>")
	)
	(segment
		(start 230.9368 -21.757386)
		(end 230.9368 -21.405596)
		(width 0.14224)
		(layer "In2.Cu")
		(net "M_A_DQ<30>")
	)
	(segment
		(start 239.104424 -49.286414)
		(end 238.844836 -49.286414)
		(width 0.0889)
		(layer "In2.Cu")
		(net "M_A_DQ<30>")
	)
	(segment
		(start 230.9368 -21.405596)
		(end 230.51135 -20.980146)
		(width 0.14224)
		(layer "In2.Cu")
		(net "M_A_DQ<30>")
	)
	(segment
		(start 230.51135 -19.278854)
		(end 230.875332 -18.914872)
		(width 0.14224)
		(layer "In2.Cu")
		(net "M_A_DQ<30>")
	)
	(segment
		(start 231.4702 -41.336468)
		(end 231.62514 -41.181528)
		(width 0.14224)
		(layer "In2.Cu")
		(net "M_A_DQ<30>")
	)
	(segment
		(start 242.880642 -53.124608)
		(end 242.880896 -53.124354)
		(width 0.0889)
		(layer "In2.Cu")
		(net "M_A_DQ<30>")
	)
	(segment
		(start 242.880896 -52.804314)
		(end 241.304572 -51.22799)
		(width 0.0889)
		(layer "In2.Cu")
		(net "M_A_DQ<30>")
	)
	(segment
		(start 232.54716 -41.844468)
		(end 231.62514 -41.844468)
		(width 0.14224)
		(layer "In2.Cu")
		(net "M_A_DQ<30>")
	)
	(arc
		(start 240.251488 -50.932588)
		(mid 240.109805 -50.788784)
		(end 239.915954 -50.732436)
		(width 0.0889)
		(layer "In2.Cu")
		(net "M_A_DQ<30>")
	)
	(arc
		(start 242.826794 -53.809138)
		(mid 242.866748 -53.712714)
		(end 242.880388 -53.60924)
		(width 0.0889)
		(layer "In2.Cu")
		(net "M_A_DQ<30>")
	)
	(arc
		(start 240.745518 -51.22799)
		(mid 240.460094 -51.144523)
		(end 240.251488 -50.932588)
		(width 0.0889)
		(layer "In2.Cu")
		(net "M_A_DQ<30>")
	)
	(arc
		(start 242.785646 -53.895752)
		(mid 242.804464 -53.851611)
		(end 242.826794 -53.809138)
		(width 0.0889)
		(layer "In2.Cu")
		(net "M_A_DQ<30>")
	)
	(arc
		(start 239.883188 -50.732436)
		(mid 239.599971 -50.648155)
		(end 239.392968 -50.437288)
		(width 0.0889)
		(layer "In2.Cu")
		(net "M_A_DQ<30>")
	)
	(segment
		(start 232.749598 -61.53404)
		(end 232.0798 -61.53404)
		(width 0.1016)
		(layer "F.Cu")
		(net "M_A_DQ<2>")
	)
	(segment
		(start 205.03134 -18.67154)
		(end 204.899768 -18.539968)
		(width 0.1651)
		(layer "F.Cu")
		(net "M_A_DQ<2>")
	)
	(segment
		(start 204.899768 -20.023582)
		(end 204.899768 -19.026632)
		(width 0.1651)
		(layer "F.Cu")
		(net "M_A_DQ<2>")
	)
	(segment
		(start 204.900276 -20.023582)
		(end 204.899768 -20.023582)
		(width 0.1651)
		(layer "F.Cu")
		(net "M_A_DQ<2>")
	)
	(segment
		(start 204.899768 -18.539968)
		(end 204.899768 -18.2626)
		(width 0.1651)
		(layer "F.Cu")
		(net "M_A_DQ<2>")
	)
	(segment
		(start 205.03134 -18.89506)
		(end 205.03134 -18.67154)
		(width 0.1651)
		(layer "F.Cu")
		(net "M_A_DQ<2>")
	)
	(segment
		(start 204.899768 -19.026632)
		(end 205.03134 -18.89506)
		(width 0.1651)
		(layer "F.Cu")
		(net "M_A_DQ<2>")
	)
	(via
		(at 232.0798 -61.53404)
		(size 0.508)
		(drill 0.254)
		(layers "F.Cu" "B.Cu")
		(net "M_A_DQ<2>")
	)
	(via
		(at 204.049884 -23.560278)
		(size 0.508)
		(drill 0.254)
		(layers "F.Cu" "B.Cu")
		(net "M_A_DQ<2>")
	)
	(via
		(at 204.899768 -18.2626)
		(size 0.508)
		(drill 0.254)
		(layers "F.Cu" "B.Cu")
		(net "M_A_DQ<2>")
	)
	(segment
		(start 204.050392 -24.824182)
		(end 204.049884 -24.824182)
		(width 0.1651)
		(layer "B.Cu")
		(net "M_A_DQ<2>")
	)
	(segment
		(start 204.049884 -24.824182)
		(end 204.049884 -23.560278)
		(width 0.1651)
		(layer "B.Cu")
		(net "M_A_DQ<2>")
	)
	(segment
		(start 206.042768 -26.0096)
		(end 205.839568 -26.2128)
		(width 0.14224)
		(layer "In2.Cu")
		(net "M_A_DQ<2>")
	)
	(segment
		(start 204.461618 -19.964146)
		(end 204.156818 -19.659346)
		(width 0.14224)
		(layer "In2.Cu")
		(net "M_A_DQ<2>")
	)
	(segment
		(start 204.481684 -23.992078)
		(end 204.049884 -23.560278)
		(width 0.14224)
		(layer "In2.Cu")
		(net "M_A_DQ<2>")
	)
	(segment
		(start 204.156818 -19.310604)
		(end 204.50175 -18.965672)
		(width 0.14224)
		(layer "In2.Cu")
		(net "M_A_DQ<2>")
	)
	(segment
		(start 232.0798 -61.53404)
		(end 231.060752 -61.53404)
		(width 0.0889)
		(layer "In2.Cu")
		(net "M_A_DQ<2>")
	)
	(segment
		(start 204.049884 -23.560278)
		(end 203.76515 -23.275544)
		(width 0.14224)
		(layer "In2.Cu")
		(net "M_A_DQ<2>")
	)
	(segment
		(start 204.156818 -20.55495)
		(end 204.461618 -20.25015)
		(width 0.14224)
		(layer "In2.Cu")
		(net "M_A_DQ<2>")
	)
	(segment
		(start 204.461618 -20.25015)
		(end 204.461618 -19.964146)
		(width 0.14224)
		(layer "In2.Cu")
		(net "M_A_DQ<2>")
	)
	(segment
		(start 230.632 -61.635386)
		(end 229.904036 -61.635386)
		(width 0.14224)
		(layer "In2.Cu")
		(net "M_A_DQ<2>")
	)
	(segment
		(start 206.347568 -26.0096)
		(end 206.042768 -26.0096)
		(width 0.14224)
		(layer "In2.Cu")
		(net "M_A_DQ<2>")
	)
	(segment
		(start 205.636368 -31.8262)
		(end 205.331568 -31.8262)
		(width 0.14224)
		(layer "In2.Cu")
		(net "M_A_DQ<2>")
	)
	(segment
		(start 205.128368 -25.118822)
		(end 204.481684 -24.472138)
		(width 0.14224)
		(layer "In2.Cu")
		(net "M_A_DQ<2>")
	)
	(segment
		(start 203.76515 -23.275544)
		(end 203.76515 -22.5298)
		(width 0.14224)
		(layer "In2.Cu")
		(net "M_A_DQ<2>")
	)
	(segment
		(start 205.839568 -26.2128)
		(end 205.839568 -31.623)
		(width 0.14224)
		(layer "In2.Cu")
		(net "M_A_DQ<2>")
	)
	(segment
		(start 231.060752 -61.53404)
		(end 230.959406 -61.635386)
		(width 0.0889)
		(layer "In2.Cu")
		(net "M_A_DQ<2>")
	)
	(segment
		(start 230.959406 -61.635386)
		(end 230.632 -61.635386)
		(width 0.0889)
		(layer "In2.Cu")
		(net "M_A_DQ<2>")
	)
	(segment
		(start 229.904036 -61.635386)
		(end 206.550768 -38.282118)
		(width 0.14224)
		(layer "In2.Cu")
		(net "M_A_DQ<2>")
	)
	(segment
		(start 204.614018 -21.4122)
		(end 204.156818 -20.955)
		(width 0.14224)
		(layer "In2.Cu")
		(net "M_A_DQ<2>")
	)
	(segment
		(start 204.50175 -18.965672)
		(end 204.50175 -18.660618)
		(width 0.14224)
		(layer "In2.Cu")
		(net "M_A_DQ<2>")
	)
	(segment
		(start 206.550768 -38.282118)
		(end 206.550768 -26.2128)
		(width 0.14224)
		(layer "In2.Cu")
		(net "M_A_DQ<2>")
	)
	(segment
		(start 204.614018 -21.680932)
		(end 204.614018 -21.4122)
		(width 0.14224)
		(layer "In2.Cu")
		(net "M_A_DQ<2>")
	)
	(segment
		(start 205.128368 -31.623)
		(end 205.128368 -25.118822)
		(width 0.14224)
		(layer "In2.Cu")
		(net "M_A_DQ<2>")
	)
	(segment
		(start 204.481684 -24.472138)
		(end 204.481684 -23.992078)
		(width 0.14224)
		(layer "In2.Cu")
		(net "M_A_DQ<2>")
	)
	(segment
		(start 206.550768 -26.2128)
		(end 206.347568 -26.0096)
		(width 0.14224)
		(layer "In2.Cu")
		(net "M_A_DQ<2>")
	)
	(segment
		(start 203.76515 -22.5298)
		(end 204.614018 -21.680932)
		(width 0.14224)
		(layer "In2.Cu")
		(net "M_A_DQ<2>")
	)
	(segment
		(start 204.50175 -18.660618)
		(end 204.899768 -18.2626)
		(width 0.14224)
		(layer "In2.Cu")
		(net "M_A_DQ<2>")
	)
	(segment
		(start 205.839568 -31.623)
		(end 205.636368 -31.8262)
		(width 0.14224)
		(layer "In2.Cu")
		(net "M_A_DQ<2>")
	)
	(segment
		(start 205.331568 -31.8262)
		(end 205.128368 -31.623)
		(width 0.14224)
		(layer "In2.Cu")
		(net "M_A_DQ<2>")
	)
	(segment
		(start 204.156818 -19.659346)
		(end 204.156818 -19.310604)
		(width 0.14224)
		(layer "In2.Cu")
		(net "M_A_DQ<2>")
	)
	(segment
		(start 204.156818 -20.955)
		(end 204.156818 -20.55495)
		(width 0.14224)
		(layer "In2.Cu")
		(net "M_A_DQ<2>")
	)
	(segment
		(start 224.450402 -15.423642)
		(end 224.449894 -15.423642)
		(width 0.1651)
		(layer "F.Cu")
		(net "M_A_DQ<29>")
	)
	(segment
		(start 240.476278 -56.085486)
		(end 239.904778 -56.085486)
		(width 0.1016)
		(layer "F.Cu")
		(net "M_A_DQ<29>")
	)
	(segment
		(start 224.449894 -15.423642)
		(end 224.449894 -16.687546)
		(width 0.1651)
		(layer "F.Cu")
		(net "M_A_DQ<29>")
	)
	(via
		(at 225.223578 -22.279356)
		(size 0.508)
		(drill 0.254)
		(layers "F.Cu" "B.Cu")
		(net "M_A_DQ<29>")
	)
	(via
		(at 224.449894 -16.687546)
		(size 0.508)
		(drill 0.254)
		(layers "F.Cu" "B.Cu")
		(net "M_A_DQ<29>")
	)
	(via
		(at 239.904778 -56.085486)
		(size 0.508)
		(drill 0.254)
		(layers "F.Cu" "B.Cu")
		(net "M_A_DQ<29>")
	)
	(segment
		(start 225.299778 -20.224242)
		(end 225.299778 -22.203156)
		(width 0.1651)
		(layer "B.Cu")
		(net "M_A_DQ<29>")
	)
	(segment
		(start 225.299778 -22.203156)
		(end 225.223578 -22.279356)
		(width 0.1651)
		(layer "B.Cu")
		(net "M_A_DQ<29>")
	)
	(segment
		(start 225.300286 -20.224242)
		(end 225.299778 -20.224242)
		(width 0.1651)
		(layer "B.Cu")
		(net "M_A_DQ<29>")
	)
	(segment
		(start 225.697796 -27.069796)
		(end 225.697796 -28.212796)
		(width 0.14224)
		(layer "In2.Cu")
		(net "M_A_DQ<29>")
	)
	(segment
		(start 234.298744 -51.143154)
		(end 234.406948 -51.332638)
		(width 0.0889)
		(layer "In2.Cu")
		(net "M_A_DQ<29>")
	)
	(segment
		(start 240.251488 -54.894988)
		(end 240.256314 -54.903624)
		(width 0.0889)
		(layer "In2.Cu")
		(net "M_A_DQ<29>")
	)
	(segment
		(start 224.707196 -23.132796)
		(end 225.596196 -24.021796)
		(width 0.14224)
		(layer "In2.Cu")
		(net "M_A_DQ<29>")
	)
	(segment
		(start 225.549968 -28.938474)
		(end 225.753168 -29.141674)
		(width 0.14224)
		(layer "In2.Cu")
		(net "M_A_DQ<29>")
	)
	(segment
		(start 237.318042 -53.018436)
		(end 237.342172 -53.018436)
		(width 0.0889)
		(layer "In2.Cu")
		(net "M_A_DQ<29>")
	)
	(segment
		(start 225.905568 -29.141674)
		(end 226.0346 -29.270706)
		(width 0.14224)
		(layer "In2.Cu")
		(net "M_A_DQ<29>")
	)
	(segment
		(start 225.549968 -42.69867)
		(end 227.123498 -44.2722)
		(width 0.14224)
		(layer "In2.Cu")
		(net "M_A_DQ<29>")
	)
	(segment
		(start 234.298744 -50.413158)
		(end 234.298744 -51.143154)
		(width 0.0889)
		(layer "In2.Cu")
		(net "M_A_DQ<29>")
	)
	(segment
		(start 234.738672 -51.532536)
		(end 234.766612 -51.532536)
		(width 0.0889)
		(layer "In2.Cu")
		(net "M_A_DQ<29>")
	)
	(segment
		(start 225.753168 -29.141674)
		(end 225.905568 -29.141674)
		(width 0.14224)
		(layer "In2.Cu")
		(net "M_A_DQ<29>")
	)
	(segment
		(start 239.889792 -54.504336)
		(end 239.904778 -54.504336)
		(width 0.0889)
		(layer "In2.Cu")
		(net "M_A_DQ<29>")
	)
	(segment
		(start 240.086896 -54.609492)
		(end 240.251488 -54.894988)
		(width 0.0889)
		(layer "In2.Cu")
		(net "M_A_DQ<29>")
	)
	(segment
		(start 227.123498 -44.2722)
		(end 228.157786 -44.2722)
		(width 0.14224)
		(layer "In2.Cu")
		(net "M_A_DQ<29>")
	)
	(segment
		(start 225.880168 -30.722824)
		(end 225.880168 -31.033974)
		(width 0.14224)
		(layer "In2.Cu")
		(net "M_A_DQ<29>")
	)
	(segment
		(start 239.035082 -54.00929)
		(end 239.067848 -54.00929)
		(width 0.0889)
		(layer "In2.Cu")
		(net "M_A_DQ<29>")
	)
	(segment
		(start 225.331528 -17.653)
		(end 225.731832 -18.053304)
		(width 0.14224)
		(layer "In2.Cu")
		(net "M_A_DQ<29>")
	)
	(segment
		(start 225.596196 -26.968196)
		(end 225.697796 -27.069796)
		(width 0.14224)
		(layer "In2.Cu")
		(net "M_A_DQ<29>")
	)
	(segment
		(start 225.549968 -31.364174)
		(end 225.549968 -42.69867)
		(width 0.14224)
		(layer "In2.Cu")
		(net "M_A_DQ<29>")
	)
	(segment
		(start 225.731832 -18.4658)
		(end 225.534982 -18.66265)
		(width 0.14224)
		(layer "In2.Cu")
		(net "M_A_DQ<29>")
	)
	(segment
		(start 225.854768 -29.954474)
		(end 225.753168 -29.954474)
		(width 0.14224)
		(layer "In2.Cu")
		(net "M_A_DQ<29>")
	)
	(segment
		(start 225.534982 -21.967952)
		(end 225.223578 -22.279356)
		(width 0.14224)
		(layer "In2.Cu")
		(net "M_A_DQ<29>")
	)
	(segment
		(start 224.449894 -16.687546)
		(end 224.449894 -17.082262)
		(width 0.14224)
		(layer "In2.Cu")
		(net "M_A_DQ<29>")
	)
	(segment
		(start 238.172752 -53.513736)
		(end 238.205518 -53.513736)
		(width 0.0889)
		(layer "In2.Cu")
		(net "M_A_DQ<29>")
	)
	(segment
		(start 240.234724 -55.32374)
		(end 239.904778 -56.085486)
		(width 0.0889)
		(layer "In2.Cu")
		(net "M_A_DQ<29>")
	)
	(segment
		(start 234.026202 -50.140616)
		(end 234.298744 -50.413158)
		(width 0.0889)
		(layer "In2.Cu")
		(net "M_A_DQ<29>")
	)
	(segment
		(start 225.753168 -29.954474)
		(end 225.549968 -30.157674)
		(width 0.14224)
		(layer "In2.Cu")
		(net "M_A_DQ<29>")
	)
	(segment
		(start 225.549968 -30.157674)
		(end 225.549968 -30.392624)
		(width 0.14224)
		(layer "In2.Cu")
		(net "M_A_DQ<29>")
	)
	(segment
		(start 225.17989 -22.279356)
		(end 224.707196 -22.75205)
		(width 0.14224)
		(layer "In2.Cu")
		(net "M_A_DQ<29>")
	)
	(segment
		(start 228.157786 -44.2722)
		(end 234.026202 -50.140616)
		(width 0.14224)
		(layer "In2.Cu")
		(net "M_A_DQ<29>")
	)
	(segment
		(start 225.534982 -18.66265)
		(end 225.534982 -21.967952)
		(width 0.14224)
		(layer "In2.Cu")
		(net "M_A_DQ<29>")
	)
	(segment
		(start 236.452664 -52.523136)
		(end 236.492288 -52.523136)
		(width 0.0889)
		(layer "In2.Cu")
		(net "M_A_DQ<29>")
	)
	(segment
		(start 240.251488 -55.295038)
		(end 240.234724 -55.32374)
		(width 0.0889)
		(layer "In2.Cu")
		(net "M_A_DQ<29>")
	)
	(segment
		(start 225.223578 -22.279356)
		(end 225.17989 -22.279356)
		(width 0.14224)
		(layer "In2.Cu")
		(net "M_A_DQ<29>")
	)
	(segment
		(start 224.449894 -17.082262)
		(end 225.020632 -17.653)
		(width 0.14224)
		(layer "In2.Cu")
		(net "M_A_DQ<29>")
	)
	(segment
		(start 224.707196 -22.75205)
		(end 224.707196 -23.132796)
		(width 0.14224)
		(layer "In2.Cu")
		(net "M_A_DQ<29>")
	)
	(segment
		(start 225.549968 -30.392624)
		(end 225.880168 -30.722824)
		(width 0.14224)
		(layer "In2.Cu")
		(net "M_A_DQ<29>")
	)
	(segment
		(start 225.697796 -28.212796)
		(end 225.549968 -28.360624)
		(width 0.14224)
		(layer "In2.Cu")
		(net "M_A_DQ<29>")
	)
	(segment
		(start 225.731832 -18.053304)
		(end 225.731832 -18.4658)
		(width 0.14224)
		(layer "In2.Cu")
		(net "M_A_DQ<29>")
	)
	(segment
		(start 225.880168 -31.033974)
		(end 225.549968 -31.364174)
		(width 0.14224)
		(layer "In2.Cu")
		(net "M_A_DQ<29>")
	)
	(segment
		(start 235.594144 -52.027836)
		(end 235.629958 -52.027836)
		(width 0.0889)
		(layer "In2.Cu")
		(net "M_A_DQ<29>")
	)
	(segment
		(start 225.020632 -17.653)
		(end 225.331528 -17.653)
		(width 0.14224)
		(layer "In2.Cu")
		(net "M_A_DQ<29>")
	)
	(segment
		(start 226.0346 -29.270706)
		(end 226.0346 -29.774642)
		(width 0.14224)
		(layer "In2.Cu")
		(net "M_A_DQ<29>")
	)
	(segment
		(start 226.0346 -29.774642)
		(end 225.854768 -29.954474)
		(width 0.14224)
		(layer "In2.Cu")
		(net "M_A_DQ<29>")
	)
	(segment
		(start 225.596196 -24.021796)
		(end 225.596196 -26.968196)
		(width 0.14224)
		(layer "In2.Cu")
		(net "M_A_DQ<29>")
	)
	(segment
		(start 225.549968 -28.360624)
		(end 225.549968 -28.938474)
		(width 0.14224)
		(layer "In2.Cu")
		(net "M_A_DQ<29>")
	)
	(arc
		(start 234.766612 -51.532536)
		(mid 235.054757 -51.614855)
		(end 235.265468 -51.827938)
		(width 0.0889)
		(layer "In2.Cu")
		(net "M_A_DQ<29>")
	)
	(arc
		(start 239.558068 -54.304438)
		(mid 239.698147 -54.447174)
		(end 239.889792 -54.504336)
		(width 0.0889)
		(layer "In2.Cu")
		(net "M_A_DQ<29>")
	)
	(arc
		(start 239.904778 -54.504336)
		(mid 240.00993 -54.53251)
		(end 240.086896 -54.609492)
		(width 0.0889)
		(layer "In2.Cu")
		(net "M_A_DQ<29>")
	)
	(arc
		(start 240.256314 -54.903624)
		(mid 240.305069 -55.099976)
		(end 240.251488 -55.295038)
		(width 0.0889)
		(layer "In2.Cu")
		(net "M_A_DQ<29>")
	)
	(arc
		(start 235.629958 -52.027836)
		(mid 235.915382 -52.111303)
		(end 236.123988 -52.323238)
		(width 0.0889)
		(layer "In2.Cu")
		(net "M_A_DQ<29>")
	)
	(arc
		(start 237.342172 -53.018436)
		(mid 237.630317 -53.100755)
		(end 237.841028 -53.313838)
		(width 0.0889)
		(layer "In2.Cu")
		(net "M_A_DQ<29>")
	)
	(arc
		(start 237.841028 -53.313838)
		(mid 237.981107 -53.456574)
		(end 238.172752 -53.513736)
		(width 0.0889)
		(layer "In2.Cu")
		(net "M_A_DQ<29>")
	)
	(arc
		(start 236.123988 -52.323238)
		(mid 236.262732 -52.465271)
		(end 236.452664 -52.523136)
		(width 0.0889)
		(layer "In2.Cu")
		(net "M_A_DQ<29>")
	)
	(arc
		(start 236.492288 -52.523136)
		(mid 236.775505 -52.607417)
		(end 236.982508 -52.818284)
		(width 0.0889)
		(layer "In2.Cu")
		(net "M_A_DQ<29>")
	)
	(arc
		(start 234.406948 -51.332638)
		(mid 234.547027 -51.475374)
		(end 234.738672 -51.532536)
		(width 0.0889)
		(layer "In2.Cu")
		(net "M_A_DQ<29>")
	)
	(arc
		(start 238.205518 -53.513736)
		(mid 238.490942 -53.597203)
		(end 238.699548 -53.809138)
		(width 0.0889)
		(layer "In2.Cu")
		(net "M_A_DQ<29>")
	)
	(arc
		(start 236.982508 -52.818284)
		(mid 237.124191 -52.962088)
		(end 237.318042 -53.018436)
		(width 0.0889)
		(layer "In2.Cu")
		(net "M_A_DQ<29>")
	)
	(arc
		(start 238.699548 -53.809138)
		(mid 238.841231 -53.952942)
		(end 239.035082 -54.00929)
		(width 0.0889)
		(layer "In2.Cu")
		(net "M_A_DQ<29>")
	)
	(arc
		(start 235.265468 -51.827938)
		(mid 235.404212 -51.969971)
		(end 235.594144 -52.027836)
		(width 0.0889)
		(layer "In2.Cu")
		(net "M_A_DQ<29>")
	)
	(arc
		(start 239.067848 -54.00929)
		(mid 239.351065 -54.093571)
		(end 239.558068 -54.304438)
		(width 0.0889)
		(layer "In2.Cu")
		(net "M_A_DQ<29>")
	)
	(segment
		(start 240.476278 -55.094886)
		(end 239.904778 -55.094886)
		(width 0.1016)
		(layer "F.Cu")
		(net "M_A_DQ<28>")
	)
	(segment
		(start 225.299778 -20.023582)
		(end 225.299778 -18.692368)
		(width 0.1651)
		(layer "F.Cu")
		(net "M_A_DQ<28>")
	)
	(segment
		(start 225.300286 -20.023582)
		(end 225.299778 -20.023582)
		(width 0.1651)
		(layer "F.Cu")
		(net "M_A_DQ<28>")
	)
	(segment
		(start 225.299778 -18.692368)
		(end 225.201734 -18.161)
		(width 0.1651)
		(layer "F.Cu")
		(net "M_A_DQ<28>")
	)
	(via
		(at 225.201734 -18.161)
		(size 0.508)
		(drill 0.254)
		(layers "F.Cu" "B.Cu")
		(net "M_A_DQ<28>")
	)
	(via
		(at 239.904778 -55.094886)
		(size 0.508)
		(drill 0.254)
		(layers "F.Cu" "B.Cu")
		(net "M_A_DQ<28>")
	)
	(via
		(at 224.449894 -23.560278)
		(size 0.508)
		(drill 0.254)
		(layers "F.Cu" "B.Cu")
		(net "M_A_DQ<28>")
	)
	(segment
		(start 224.449894 -24.824182)
		(end 224.449894 -23.560278)
		(width 0.1651)
		(layer "B.Cu")
		(net "M_A_DQ<28>")
	)
	(segment
		(start 224.450402 -24.824182)
		(end 224.449894 -24.824182)
		(width 0.1651)
		(layer "B.Cu")
		(net "M_A_DQ<28>")
	)
	(segment
		(start 237.316264 -53.20919)
		(end 237.344204 -53.20919)
		(width 0.0889)
		(layer "In2.Cu")
		(net "M_A_DQ<28>")
	)
	(segment
		(start 224.961196 -24.07158)
		(end 224.961196 -24.526748)
		(width 0.14224)
		(layer "In2.Cu")
		(net "M_A_DQ<28>")
	)
	(segment
		(start 224.910396 -31.703518)
		(end 224.910396 -32.056578)
		(width 0.14224)
		(layer "In2.Cu")
		(net "M_A_DQ<28>")
	)
	(segment
		(start 224.961196 -24.526748)
		(end 224.711768 -24.776176)
		(width 0.14224)
		(layer "In2.Cu")
		(net "M_A_DQ<28>")
	)
	(segment
		(start 224.755456 -30.885638)
		(end 224.47504 -30.885638)
		(width 0.14224)
		(layer "In2.Cu")
		(net "M_A_DQ<28>")
	)
	(segment
		(start 224.214182 -22.530054)
		(end 224.214182 -23.324566)
		(width 0.14224)
		(layer "In2.Cu")
		(net "M_A_DQ<28>")
	)
	(segment
		(start 236.452918 -52.71389)
		(end 236.488732 -52.71389)
		(width 0.0889)
		(layer "In2.Cu")
		(net "M_A_DQ<28>")
	)
	(segment
		(start 233.991404 -51.021234)
		(end 234.241848 -51.427888)
		(width 0.0889)
		(layer "In2.Cu")
		(net "M_A_DQ<28>")
	)
	(segment
		(start 239.028478 -54.19979)
		(end 239.061244 -54.19979)
		(width 0.0889)
		(layer "In2.Cu")
		(net "M_A_DQ<28>")
	)
	(segment
		(start 224.47504 -29.559758)
		(end 224.3201 -29.714698)
		(width 0.14224)
		(layer "In2.Cu")
		(net "M_A_DQ<28>")
	)
	(segment
		(start 224.755456 -32.874458)
		(end 224.910396 -33.029398)
		(width 0.14224)
		(layer "In2.Cu")
		(net "M_A_DQ<28>")
	)
	(segment
		(start 225.201734 -18.161)
		(end 224.925382 -18.437352)
		(width 0.14224)
		(layer "In2.Cu")
		(net "M_A_DQ<28>")
	)
	(segment
		(start 224.910396 -30.377638)
		(end 224.910396 -30.730698)
		(width 0.14224)
		(layer "In2.Cu")
		(net "M_A_DQ<28>")
	)
	(segment
		(start 224.961196 -25.588976)
		(end 224.961196 -26.663396)
		(width 0.14224)
		(layer "In2.Cu")
		(net "M_A_DQ<28>")
	)
	(segment
		(start 224.961196 -26.663396)
		(end 224.707196 -26.917396)
		(width 0.14224)
		(layer "In2.Cu")
		(net "M_A_DQ<28>")
	)
	(segment
		(start 224.449894 -23.560278)
		(end 224.961196 -24.07158)
		(width 0.14224)
		(layer "In2.Cu")
		(net "M_A_DQ<28>")
	)
	(segment
		(start 224.755456 -31.548578)
		(end 224.910396 -31.703518)
		(width 0.14224)
		(layer "In2.Cu")
		(net "M_A_DQ<28>")
	)
	(segment
		(start 224.711768 -24.776176)
		(end 224.711768 -25.339548)
		(width 0.14224)
		(layer "In2.Cu")
		(net "M_A_DQ<28>")
	)
	(segment
		(start 224.47504 -31.548578)
		(end 224.755456 -31.548578)
		(width 0.14224)
		(layer "In2.Cu")
		(net "M_A_DQ<28>")
	)
	(segment
		(start 224.3201 -31.393638)
		(end 224.47504 -31.548578)
		(width 0.14224)
		(layer "In2.Cu")
		(net "M_A_DQ<28>")
	)
	(segment
		(start 238.166148 -53.704236)
		(end 238.198914 -53.704236)
		(width 0.0889)
		(layer "In2.Cu")
		(net "M_A_DQ<28>")
	)
	(segment
		(start 234.740704 -51.72329)
		(end 234.764834 -51.72329)
		(width 0.0889)
		(layer "In2.Cu")
		(net "M_A_DQ<28>")
	)
	(segment
		(start 224.60204 -32.874458)
		(end 224.755456 -32.874458)
		(width 0.14224)
		(layer "In2.Cu")
		(net "M_A_DQ<28>")
	)
	(segment
		(start 224.910396 -28.314396)
		(end 224.910396 -29.404818)
		(width 0.14224)
		(layer "In2.Cu")
		(net "M_A_DQ<28>")
	)
	(segment
		(start 224.5741 -20.6375)
		(end 224.5741 -20.992846)
		(width 0.14224)
		(layer "In2.Cu")
		(net "M_A_DQ<28>")
	)
	(segment
		(start 224.910396 -33.029398)
		(end 224.910396 -42.957242)
		(width 0.14224)
		(layer "In2.Cu")
		(net "M_A_DQ<28>")
	)
	(segment
		(start 224.5614 -19.5834)
		(end 224.9424 -19.9644)
		(width 0.14224)
		(layer "In2.Cu")
		(net "M_A_DQ<28>")
	)
	(segment
		(start 224.47504 -30.885638)
		(end 224.3201 -31.040578)
		(width 0.14224)
		(layer "In2.Cu")
		(net "M_A_DQ<28>")
	)
	(segment
		(start 224.4598 -32.732218)
		(end 224.60204 -32.874458)
		(width 0.14224)
		(layer "In2.Cu")
		(net "M_A_DQ<28>")
	)
	(segment
		(start 235.590588 -52.21859)
		(end 235.630212 -52.21859)
		(width 0.0889)
		(layer "In2.Cu")
		(net "M_A_DQ<28>")
	)
	(segment
		(start 224.3201 -30.067758)
		(end 224.47504 -30.222698)
		(width 0.14224)
		(layer "In2.Cu")
		(net "M_A_DQ<28>")
	)
	(segment
		(start 224.755456 -29.559758)
		(end 224.47504 -29.559758)
		(width 0.14224)
		(layer "In2.Cu")
		(net "M_A_DQ<28>")
	)
	(segment
		(start 224.9424 -19.9644)
		(end 224.9424 -20.2692)
		(width 0.14224)
		(layer "In2.Cu")
		(net "M_A_DQ<28>")
	)
	(segment
		(start 224.910396 -29.404818)
		(end 224.755456 -29.559758)
		(width 0.14224)
		(layer "In2.Cu")
		(net "M_A_DQ<28>")
	)
	(segment
		(start 239.392968 -54.399688)
		(end 239.409732 -54.429152)
		(width 0.0889)
		(layer "In2.Cu")
		(net "M_A_DQ<28>")
	)
	(segment
		(start 224.910396 -42.957242)
		(end 227.114354 -45.1612)
		(width 0.14224)
		(layer "In2.Cu")
		(net "M_A_DQ<28>")
	)
	(segment
		(start 224.925382 -18.914872)
		(end 224.5614 -19.278854)
		(width 0.14224)
		(layer "In2.Cu")
		(net "M_A_DQ<28>")
	)
	(segment
		(start 224.707196 -28.111196)
		(end 224.910396 -28.314396)
		(width 0.14224)
		(layer "In2.Cu")
		(net "M_A_DQ<28>")
	)
	(segment
		(start 239.409732 -54.429152)
		(end 239.904778 -55.094886)
		(width 0.0889)
		(layer "In2.Cu")
		(net "M_A_DQ<28>")
	)
	(segment
		(start 224.60204 -32.211518)
		(end 224.4598 -32.353758)
		(width 0.14224)
		(layer "In2.Cu")
		(net "M_A_DQ<28>")
	)
	(segment
		(start 224.910396 -30.730698)
		(end 224.755456 -30.885638)
		(width 0.14224)
		(layer "In2.Cu")
		(net "M_A_DQ<28>")
	)
	(segment
		(start 224.5741 -20.992846)
		(end 224.925382 -21.344128)
		(width 0.14224)
		(layer "In2.Cu")
		(net "M_A_DQ<28>")
	)
	(segment
		(start 228.130608 -45.1612)
		(end 233.764074 -50.794666)
		(width 0.14224)
		(layer "In2.Cu")
		(net "M_A_DQ<28>")
	)
	(segment
		(start 224.3201 -31.040578)
		(end 224.3201 -31.393638)
		(width 0.14224)
		(layer "In2.Cu")
		(net "M_A_DQ<28>")
	)
	(segment
		(start 224.3201 -29.714698)
		(end 224.3201 -30.067758)
		(width 0.14224)
		(layer "In2.Cu")
		(net "M_A_DQ<28>")
	)
	(segment
		(start 224.214182 -23.324566)
		(end 224.449894 -23.560278)
		(width 0.14224)
		(layer "In2.Cu")
		(net "M_A_DQ<28>")
	)
	(segment
		(start 224.925382 -21.344128)
		(end 224.925382 -21.818854)
		(width 0.14224)
		(layer "In2.Cu")
		(net "M_A_DQ<28>")
	)
	(segment
		(start 233.764074 -50.794666)
		(end 233.946446 -50.977038)
		(width 0.0889)
		(layer "In2.Cu")
		(net "M_A_DQ<28>")
	)
	(segment
		(start 233.946446 -50.977038)
		(end 233.991404 -51.021234)
		(width 0.0889)
		(layer "In2.Cu")
		(net "M_A_DQ<28>")
	)
	(segment
		(start 224.755456 -32.211518)
		(end 224.60204 -32.211518)
		(width 0.14224)
		(layer "In2.Cu")
		(net "M_A_DQ<28>")
	)
	(segment
		(start 224.4598 -32.353758)
		(end 224.4598 -32.732218)
		(width 0.14224)
		(layer "In2.Cu")
		(net "M_A_DQ<28>")
	)
	(segment
		(start 224.910396 -32.056578)
		(end 224.755456 -32.211518)
		(width 0.14224)
		(layer "In2.Cu")
		(net "M_A_DQ<28>")
	)
	(segment
		(start 224.925382 -21.818854)
		(end 224.214182 -22.530054)
		(width 0.14224)
		(layer "In2.Cu")
		(net "M_A_DQ<28>")
	)
	(segment
		(start 224.5614 -19.278854)
		(end 224.5614 -19.5834)
		(width 0.14224)
		(layer "In2.Cu")
		(net "M_A_DQ<28>")
	)
	(segment
		(start 224.47504 -30.222698)
		(end 224.755456 -30.222698)
		(width 0.14224)
		(layer "In2.Cu")
		(net "M_A_DQ<28>")
	)
	(segment
		(start 224.755456 -30.222698)
		(end 224.910396 -30.377638)
		(width 0.14224)
		(layer "In2.Cu")
		(net "M_A_DQ<28>")
	)
	(segment
		(start 224.711768 -25.339548)
		(end 224.961196 -25.588976)
		(width 0.14224)
		(layer "In2.Cu")
		(net "M_A_DQ<28>")
	)
	(segment
		(start 227.114354 -45.1612)
		(end 228.130608 -45.1612)
		(width 0.14224)
		(layer "In2.Cu")
		(net "M_A_DQ<28>")
	)
	(segment
		(start 224.707196 -26.917396)
		(end 224.707196 -28.111196)
		(width 0.14224)
		(layer "In2.Cu")
		(net "M_A_DQ<28>")
	)
	(segment
		(start 224.9424 -20.2692)
		(end 224.5741 -20.6375)
		(width 0.14224)
		(layer "In2.Cu")
		(net "M_A_DQ<28>")
	)
	(segment
		(start 224.925382 -18.437352)
		(end 224.925382 -18.914872)
		(width 0.14224)
		(layer "In2.Cu")
		(net "M_A_DQ<28>")
	)
	(arc
		(start 235.630212 -52.21859)
		(mid 235.820141 -52.27646)
		(end 235.958888 -52.418488)
		(width 0.0889)
		(layer "In2.Cu")
		(net "M_A_DQ<28>")
	)
	(arc
		(start 238.198914 -53.704236)
		(mid 238.392764 -53.760586)
		(end 238.534448 -53.904388)
		(width 0.0889)
		(layer "In2.Cu")
		(net "M_A_DQ<28>")
	)
	(arc
		(start 237.675928 -53.409088)
		(mid 237.882932 -53.619952)
		(end 238.166148 -53.704236)
		(width 0.0889)
		(layer "In2.Cu")
		(net "M_A_DQ<28>")
	)
	(arc
		(start 236.488732 -52.71389)
		(mid 236.678661 -52.77176)
		(end 236.817408 -52.913788)
		(width 0.0889)
		(layer "In2.Cu")
		(net "M_A_DQ<28>")
	)
	(arc
		(start 237.344204 -53.20919)
		(mid 237.535846 -53.266356)
		(end 237.675928 -53.409088)
		(width 0.0889)
		(layer "In2.Cu")
		(net "M_A_DQ<28>")
	)
	(arc
		(start 234.241848 -51.427888)
		(mid 234.452561 -51.640967)
		(end 234.740704 -51.72329)
		(width 0.0889)
		(layer "In2.Cu")
		(net "M_A_DQ<28>")
	)
	(arc
		(start 238.534448 -53.904388)
		(mid 238.743056 -54.11632)
		(end 239.028478 -54.19979)
		(width 0.0889)
		(layer "In2.Cu")
		(net "M_A_DQ<28>")
	)
	(arc
		(start 235.958888 -52.418488)
		(mid 236.167496 -52.63042)
		(end 236.452918 -52.71389)
		(width 0.0889)
		(layer "In2.Cu")
		(net "M_A_DQ<28>")
	)
	(arc
		(start 235.100368 -51.923442)
		(mid 235.307372 -52.134306)
		(end 235.590588 -52.21859)
		(width 0.0889)
		(layer "In2.Cu")
		(net "M_A_DQ<28>")
	)
	(arc
		(start 236.817408 -52.913788)
		(mid 237.028121 -53.126867)
		(end 237.316264 -53.20919)
		(width 0.0889)
		(layer "In2.Cu")
		(net "M_A_DQ<28>")
	)
	(arc
		(start 234.764834 -51.72329)
		(mid 234.958684 -51.77964)
		(end 235.100368 -51.923442)
		(width 0.0889)
		(layer "In2.Cu")
		(net "M_A_DQ<28>")
	)
	(arc
		(start 239.061244 -54.19979)
		(mid 239.252886 -54.256956)
		(end 239.392968 -54.399688)
		(width 0.0889)
		(layer "In2.Cu")
		(net "M_A_DQ<28>")
	)
	(segment
		(start 232.099866 -15.423642)
		(end 232.099866 -16.687546)
		(width 0.1651)
		(layer "F.Cu")
		(net "M_A_DQ<27>")
	)
	(segment
		(start 232.100374 -15.423642)
		(end 232.099866 -15.423642)
		(width 0.1651)
		(layer "F.Cu")
		(net "M_A_DQ<27>")
	)
	(segment
		(start 243.910104 -56.085486)
		(end 243.338604 -56.085486)
		(width 0.1016)
		(layer "F.Cu")
		(net "M_A_DQ<27>")
	)
	(via
		(at 232.099866 -16.687546)
		(size 0.508)
		(drill 0.254)
		(layers "F.Cu" "B.Cu")
		(net "M_A_DQ<27>")
	)
	(via
		(at 232.94975 -22.279356)
		(size 0.508)
		(drill 0.254)
		(layers "F.Cu" "B.Cu")
		(net "M_A_DQ<27>")
	)
	(via
		(at 243.338604 -56.085486)
		(size 0.508)
		(drill 0.254)
		(layers "F.Cu" "B.Cu")
		(net "M_A_DQ<27>")
	)
	(segment
		(start 232.950512 -20.224242)
		(end 232.950512 -22.278594)
		(width 0.1651)
		(layer "B.Cu")
		(net "M_A_DQ<27>")
	)
	(segment
		(start 232.950512 -22.278594)
		(end 232.94975 -22.279356)
		(width 0.1651)
		(layer "B.Cu")
		(net "M_A_DQ<27>")
	)
	(segment
		(start 243.674392 -56.085486)
		(end 243.338604 -56.085486)
		(width 0.0889)
		(layer "In2.Cu")
		(net "M_A_DQ<27>")
	)
	(segment
		(start 232.661968 -31.77286)
		(end 232.816908 -31.9278)
		(width 0.14224)
		(layer "In2.Cu")
		(net "M_A_DQ<27>")
	)
	(segment
		(start 233.89336 -31.9278)
		(end 234.0356 -32.07004)
		(width 0.14224)
		(layer "In2.Cu")
		(net "M_A_DQ<27>")
	)
	(segment
		(start 232.97134 -32.696404)
		(end 232.8164 -32.851344)
		(width 0.14224)
		(layer "In2.Cu")
		(net "M_A_DQ<27>")
	)
	(segment
		(start 233.458004 -18.4658)
		(end 233.302556 -18.621248)
		(width 0.14224)
		(layer "In2.Cu")
		(net "M_A_DQ<27>")
	)
	(segment
		(start 233.458004 -18.1102)
		(end 233.458004 -18.4658)
		(width 0.14224)
		(layer "In2.Cu")
		(net "M_A_DQ<27>")
	)
	(segment
		(start 232.712768 -24.776938)
		(end 232.712768 -25.54097)
		(width 0.14224)
		(layer "In2.Cu")
		(net "M_A_DQ<27>")
	)
	(segment
		(start 233.266996 -23.996396)
		(end 233.266996 -24.22271)
		(width 0.14224)
		(layer "In2.Cu")
		(net "M_A_DQ<27>")
	)
	(segment
		(start 243.796312 -53.126894)
		(end 243.79682 -53.60924)
		(width 0.0889)
		(layer "In2.Cu")
		(net "M_A_DQ<27>")
	)
	(segment
		(start 233.89336 -32.696404)
		(end 232.97134 -32.696404)
		(width 0.14224)
		(layer "In2.Cu")
		(net "M_A_DQ<27>")
	)
	(segment
		(start 234.0356 -32.07004)
		(end 234.0356 -32.554164)
		(width 0.14224)
		(layer "In2.Cu")
		(net "M_A_DQ<27>")
	)
	(segment
		(start 233.266996 -26.803096)
		(end 233.444796 -26.980896)
		(width 0.14224)
		(layer "In2.Cu")
		(net "M_A_DQ<27>")
	)
	(segment
		(start 232.97134 -33.359344)
		(end 234.132628 -33.359344)
		(width 0.14224)
		(layer "In2.Cu")
		(net "M_A_DQ<27>")
	)
	(segment
		(start 243.850414 -53.808884)
		(end 243.856764 -53.819552)
		(width 0.0889)
		(layer "In2.Cu")
		(net "M_A_DQ<27>")
	)
	(segment
		(start 233.322368 -29.177996)
		(end 232.661968 -29.838396)
		(width 0.14224)
		(layer "In2.Cu")
		(net "M_A_DQ<27>")
	)
	(segment
		(start 232.661968 -29.838396)
		(end 232.661968 -31.77286)
		(width 0.14224)
		(layer "In2.Cu")
		(net "M_A_DQ<27>")
	)
	(segment
		(start 233.444796 -28.174696)
		(end 233.322368 -28.297124)
		(width 0.14224)
		(layer "In2.Cu")
		(net "M_A_DQ<27>")
	)
	(segment
		(start 240.120424 -47.813214)
		(end 240.120424 -48.092614)
		(width 0.0889)
		(layer "In2.Cu")
		(net "M_A_DQ<27>")
	)
	(segment
		(start 234.287568 -41.980358)
		(end 240.120424 -47.813214)
		(width 0.14224)
		(layer "In2.Cu")
		(net "M_A_DQ<27>")
	)
	(segment
		(start 243.740432 -54.596538)
		(end 243.740432 -56.019446)
		(width 0.0889)
		(layer "In2.Cu")
		(net "M_A_DQ<27>")
	)
	(segment
		(start 243.740432 -56.019446)
		(end 243.674392 -56.085486)
		(width 0.0889)
		(layer "In2.Cu")
		(net "M_A_DQ<27>")
	)
	(segment
		(start 233.266996 -24.22271)
		(end 232.712768 -24.776938)
		(width 0.14224)
		(layer "In2.Cu")
		(net "M_A_DQ<27>")
	)
	(segment
		(start 243.850414 -54.399434)
		(end 243.740432 -54.596538)
		(width 0.0889)
		(layer "In2.Cu")
		(net "M_A_DQ<27>")
	)
	(segment
		(start 234.287568 -33.514284)
		(end 234.287568 -41.980358)
		(width 0.14224)
		(layer "In2.Cu")
		(net "M_A_DQ<27>")
	)
	(segment
		(start 234.0356 -32.554164)
		(end 233.89336 -32.696404)
		(width 0.14224)
		(layer "In2.Cu")
		(net "M_A_DQ<27>")
	)
	(segment
		(start 240.120424 -48.092614)
		(end 240.349024 -48.321214)
		(width 0.0889)
		(layer "In2.Cu")
		(net "M_A_DQ<27>")
	)
	(segment
		(start 232.8164 -33.204404)
		(end 232.97134 -33.359344)
		(width 0.14224)
		(layer "In2.Cu")
		(net "M_A_DQ<27>")
	)
	(segment
		(start 232.816908 -31.9278)
		(end 233.89336 -31.9278)
		(width 0.14224)
		(layer "In2.Cu")
		(net "M_A_DQ<27>")
	)
	(segment
		(start 232.416604 -17.3228)
		(end 232.746804 -17.653)
		(width 0.14224)
		(layer "In2.Cu")
		(net "M_A_DQ<27>")
	)
	(segment
		(start 232.484168 -22.744938)
		(end 232.484168 -23.213568)
		(width 0.14224)
		(layer "In2.Cu")
		(net "M_A_DQ<27>")
	)
	(segment
		(start 240.349024 -49.13249)
		(end 241.238024 -50.02149)
		(width 0.0889)
		(layer "In2.Cu")
		(net "M_A_DQ<27>")
	)
	(segment
		(start 232.416604 -17.004284)
		(end 232.416604 -17.3228)
		(width 0.14224)
		(layer "In2.Cu")
		(net "M_A_DQ<27>")
	)
	(segment
		(start 232.746804 -17.653)
		(end 233.000804 -17.653)
		(width 0.14224)
		(layer "In2.Cu")
		(net "M_A_DQ<27>")
	)
	(segment
		(start 232.484168 -23.213568)
		(end 233.266996 -23.996396)
		(width 0.14224)
		(layer "In2.Cu")
		(net "M_A_DQ<27>")
	)
	(segment
		(start 232.8164 -32.851344)
		(end 232.8164 -33.204404)
		(width 0.14224)
		(layer "In2.Cu")
		(net "M_A_DQ<27>")
	)
	(segment
		(start 241.453924 -50.02149)
		(end 243.3828 -51.950366)
		(width 0.0889)
		(layer "In2.Cu")
		(net "M_A_DQ<27>")
	)
	(segment
		(start 233.302556 -18.621248)
		(end 233.302556 -21.92655)
		(width 0.14224)
		(layer "In2.Cu")
		(net "M_A_DQ<27>")
	)
	(segment
		(start 233.302556 -21.92655)
		(end 232.94975 -22.279356)
		(width 0.14224)
		(layer "In2.Cu")
		(net "M_A_DQ<27>")
	)
	(segment
		(start 240.349024 -48.321214)
		(end 240.349024 -49.13249)
		(width 0.0889)
		(layer "In2.Cu")
		(net "M_A_DQ<27>")
	)
	(segment
		(start 232.94975 -22.279356)
		(end 232.484168 -22.744938)
		(width 0.14224)
		(layer "In2.Cu")
		(net "M_A_DQ<27>")
	)
	(segment
		(start 243.3828 -51.950366)
		(end 243.796312 -52.363878)
		(width 0.0889)
		(layer "In2.Cu")
		(net "M_A_DQ<27>")
	)
	(segment
		(start 233.322368 -28.297124)
		(end 233.322368 -29.177996)
		(width 0.14224)
		(layer "In2.Cu")
		(net "M_A_DQ<27>")
	)
	(segment
		(start 233.000804 -17.653)
		(end 233.458004 -18.1102)
		(width 0.14224)
		(layer "In2.Cu")
		(net "M_A_DQ<27>")
	)
	(segment
		(start 233.444796 -26.980896)
		(end 233.444796 -28.174696)
		(width 0.14224)
		(layer "In2.Cu")
		(net "M_A_DQ<27>")
	)
	(segment
		(start 232.712768 -25.54097)
		(end 233.266996 -26.095198)
		(width 0.14224)
		(layer "In2.Cu")
		(net "M_A_DQ<27>")
	)
	(segment
		(start 241.238024 -50.02149)
		(end 241.453924 -50.02149)
		(width 0.0889)
		(layer "In2.Cu")
		(net "M_A_DQ<27>")
	)
	(segment
		(start 243.796312 -52.363878)
		(end 243.796312 -53.126894)
		(width 0.0889)
		(layer "In2.Cu")
		(net "M_A_DQ<27>")
	)
	(segment
		(start 234.132628 -33.359344)
		(end 234.287568 -33.514284)
		(width 0.14224)
		(layer "In2.Cu")
		(net "M_A_DQ<27>")
	)
	(segment
		(start 233.266996 -26.095198)
		(end 233.266996 -26.803096)
		(width 0.14224)
		(layer "In2.Cu")
		(net "M_A_DQ<27>")
	)
	(segment
		(start 232.099866 -16.687546)
		(end 232.416604 -17.004284)
		(width 0.14224)
		(layer "In2.Cu")
		(net "M_A_DQ<27>")
	)
	(arc
		(start 243.79682 -53.60924)
		(mid 243.810523 -53.712575)
		(end 243.850414 -53.808884)
		(width 0.0889)
		(layer "In2.Cu")
		(net "M_A_DQ<27>")
	)
	(arc
		(start 243.856764 -53.819552)
		(mid 243.929562 -54.110315)
		(end 243.850414 -54.399434)
		(width 0.0889)
		(layer "In2.Cu")
		(net "M_A_DQ<27>")
	)
	(segment
		(start 243.910104 -55.094886)
		(end 243.338604 -55.094886)
		(width 0.1016)
		(layer "F.Cu")
		(net "M_A_DQ<26>")
	)
	(segment
		(start 232.94975 -20.02282)
		(end 232.94975 -19.026632)
		(width 0.1651)
		(layer "F.Cu")
		(net "M_A_DQ<26>")
	)
	(segment
		(start 233.081322 -18.89506)
		(end 233.081322 -18.67154)
		(width 0.1651)
		(layer "F.Cu")
		(net "M_A_DQ<26>")
	)
	(segment
		(start 232.94975 -18.539968)
		(end 232.94975 -18.2626)
		(width 0.1651)
		(layer "F.Cu")
		(net "M_A_DQ<26>")
	)
	(segment
		(start 232.950512 -20.023582)
		(end 232.94975 -20.02282)
		(width 0.1651)
		(layer "F.Cu")
		(net "M_A_DQ<26>")
	)
	(segment
		(start 232.94975 -19.026632)
		(end 233.081322 -18.89506)
		(width 0.1651)
		(layer "F.Cu")
		(net "M_A_DQ<26>")
	)
	(segment
		(start 233.081322 -18.67154)
		(end 232.94975 -18.539968)
		(width 0.1651)
		(layer "F.Cu")
		(net "M_A_DQ<26>")
	)
	(via
		(at 232.94975 -18.2626)
		(size 0.508)
		(drill 0.254)
		(layers "F.Cu" "B.Cu")
		(net "M_A_DQ<26>")
	)
	(via
		(at 243.338604 -55.094886)
		(size 0.508)
		(drill 0.254)
		(layers "F.Cu" "B.Cu")
		(net "M_A_DQ<26>")
	)
	(via
		(at 232.099866 -23.560278)
		(size 0.508)
		(drill 0.254)
		(layers "F.Cu" "B.Cu")
		(net "M_A_DQ<26>")
	)
	(segment
		(start 232.100374 -24.824182)
		(end 232.099866 -24.824182)
		(width 0.1651)
		(layer "B.Cu")
		(net "M_A_DQ<26>")
	)
	(segment
		(start 232.099866 -24.824182)
		(end 232.099866 -23.560278)
		(width 0.1651)
		(layer "B.Cu")
		(net "M_A_DQ<26>")
	)
	(segment
		(start 232.77576 -35.07613)
		(end 232.918 -34.93389)
		(width 0.14224)
		(layer "In2.Cu")
		(net "M_A_DQ<26>")
	)
	(segment
		(start 232.918 -34.93389)
		(end 232.918 -34.344864)
		(width 0.14224)
		(layer "In2.Cu")
		(net "M_A_DQ<26>")
	)
	(segment
		(start 232.2068 -19.310604)
		(end 232.551732 -18.965672)
		(width 0.14224)
		(layer "In2.Cu")
		(net "M_A_DQ<26>")
	)
	(segment
		(start 233.7308 -37.21989)
		(end 233.57586 -37.06495)
		(width 0.14224)
		(layer "In2.Cu")
		(net "M_A_DQ<26>")
	)
	(segment
		(start 231.815132 -23.275544)
		(end 231.815132 -22.5298)
		(width 0.14224)
		(layer "In2.Cu")
		(net "M_A_DQ<26>")
	)
	(segment
		(start 232.1433 -35.58413)
		(end 232.1433 -35.23107)
		(width 0.14224)
		(layer "In2.Cu")
		(net "M_A_DQ<26>")
	)
	(segment
		(start 233.57586 -36.40201)
		(end 233.7308 -36.24707)
		(width 0.14224)
		(layer "In2.Cu")
		(net "M_A_DQ<26>")
	)
	(segment
		(start 232.1433 -36.91001)
		(end 232.1433 -36.55695)
		(width 0.14224)
		(layer "In2.Cu")
		(net "M_A_DQ<26>")
	)
	(segment
		(start 232.2068 -19.659346)
		(end 232.2068 -19.310604)
		(width 0.14224)
		(layer "In2.Cu")
		(net "M_A_DQ<26>")
	)
	(segment
		(start 243.605812 -52.442872)
		(end 241.37493 -50.21199)
		(width 0.0889)
		(layer "In2.Cu")
		(net "M_A_DQ<26>")
	)
	(segment
		(start 232.29824 -36.40201)
		(end 233.57586 -36.40201)
		(width 0.14224)
		(layer "In2.Cu")
		(net "M_A_DQ<26>")
	)
	(segment
		(start 232.454196 -26.917396)
		(end 232.631996 -26.739596)
		(width 0.14224)
		(layer "In2.Cu")
		(net "M_A_DQ<26>")
	)
	(segment
		(start 232.1433 -36.55695)
		(end 232.29824 -36.40201)
		(width 0.14224)
		(layer "In2.Cu")
		(net "M_A_DQ<26>")
	)
	(segment
		(start 239.636046 -48.245014)
		(end 233.7308 -42.339768)
		(width 0.14224)
		(layer "In2.Cu")
		(net "M_A_DQ<26>")
	)
	(segment
		(start 239.96777 -48.245014)
		(end 239.636046 -48.245014)
		(width 0.0889)
		(layer "In2.Cu")
		(net "M_A_DQ<26>")
	)
	(segment
		(start 232.026968 -33.923224)
		(end 232.026968 -29.575252)
		(width 0.14224)
		(layer "In2.Cu")
		(net "M_A_DQ<26>")
	)
	(segment
		(start 243.605812 -53.608224)
		(end 243.605812 -52.442872)
		(width 0.0889)
		(layer "In2.Cu")
		(net "M_A_DQ<26>")
	)
	(segment
		(start 233.7308 -36.24707)
		(end 233.7308 -35.89401)
		(width 0.14224)
		(layer "In2.Cu")
		(net "M_A_DQ<26>")
	)
	(segment
		(start 243.3828 -54.97068)
		(end 243.515896 -54.596538)
		(width 0.0889)
		(layer "In2.Cu")
		(net "M_A_DQ<26>")
	)
	(segment
		(start 232.551732 -18.660618)
		(end 232.94975 -18.2626)
		(width 0.14224)
		(layer "In2.Cu")
		(net "M_A_DQ<26>")
	)
	(segment
		(start 232.631996 -26.373328)
		(end 232.099866 -25.841198)
		(width 0.14224)
		(layer "In2.Cu")
		(net "M_A_DQ<26>")
	)
	(segment
		(start 232.1433 -35.23107)
		(end 232.29824 -35.07613)
		(width 0.14224)
		(layer "In2.Cu")
		(net "M_A_DQ<26>")
	)
	(segment
		(start 240.158524 -49.211484)
		(end 240.158524 -48.435768)
		(width 0.0889)
		(layer "In2.Cu")
		(net "M_A_DQ<26>")
	)
	(segment
		(start 243.338604 -55.094886)
		(end 243.3828 -54.97068)
		(width 0.0889)
		(layer "In2.Cu")
		(net "M_A_DQ<26>")
	)
	(segment
		(start 232.2068 -20.955)
		(end 232.2068 -20.55495)
		(width 0.14224)
		(layer "In2.Cu")
		(net "M_A_DQ<26>")
	)
	(segment
		(start 232.631996 -26.739596)
		(end 232.631996 -26.373328)
		(width 0.14224)
		(layer "In2.Cu")
		(net "M_A_DQ<26>")
	)
	(segment
		(start 243.685314 -53.904134)
		(end 243.678964 -53.893466)
		(width 0.0889)
		(layer "In2.Cu")
		(net "M_A_DQ<26>")
	)
	(segment
		(start 232.099866 -23.560278)
		(end 231.815132 -23.275544)
		(width 0.14224)
		(layer "In2.Cu")
		(net "M_A_DQ<26>")
	)
	(segment
		(start 232.606596 -28.314396)
		(end 232.454196 -28.161996)
		(width 0.14224)
		(layer "In2.Cu")
		(net "M_A_DQ<26>")
	)
	(segment
		(start 233.7308 -42.339768)
		(end 233.7308 -37.21989)
		(width 0.14224)
		(layer "In2.Cu")
		(net "M_A_DQ<26>")
	)
	(segment
		(start 232.306368 -34.202624)
		(end 232.026968 -33.923224)
		(width 0.14224)
		(layer "In2.Cu")
		(net "M_A_DQ<26>")
	)
	(segment
		(start 232.454196 -28.161996)
		(end 232.454196 -26.917396)
		(width 0.14224)
		(layer "In2.Cu")
		(net "M_A_DQ<26>")
	)
	(segment
		(start 240.158524 -48.435768)
		(end 239.96777 -48.245014)
		(width 0.0889)
		(layer "In2.Cu")
		(net "M_A_DQ<26>")
	)
	(segment
		(start 232.77576 -34.202624)
		(end 232.306368 -34.202624)
		(width 0.14224)
		(layer "In2.Cu")
		(net "M_A_DQ<26>")
	)
	(segment
		(start 233.57586 -35.73907)
		(end 232.29824 -35.73907)
		(width 0.14224)
		(layer "In2.Cu")
		(net "M_A_DQ<26>")
	)
	(segment
		(start 232.606596 -28.995624)
		(end 232.606596 -28.314396)
		(width 0.14224)
		(layer "In2.Cu")
		(net "M_A_DQ<26>")
	)
	(segment
		(start 232.664 -21.4122)
		(end 232.2068 -20.955)
		(width 0.14224)
		(layer "In2.Cu")
		(net "M_A_DQ<26>")
	)
	(segment
		(start 232.29824 -37.06495)
		(end 232.1433 -36.91001)
		(width 0.14224)
		(layer "In2.Cu")
		(net "M_A_DQ<26>")
	)
	(segment
		(start 232.29824 -35.07613)
		(end 232.77576 -35.07613)
		(width 0.14224)
		(layer "In2.Cu")
		(net "M_A_DQ<26>")
	)
	(segment
		(start 232.026968 -29.575252)
		(end 232.606596 -28.995624)
		(width 0.14224)
		(layer "In2.Cu")
		(net "M_A_DQ<26>")
	)
	(segment
		(start 232.5116 -19.964146)
		(end 232.2068 -19.659346)
		(width 0.14224)
		(layer "In2.Cu")
		(net "M_A_DQ<26>")
	)
	(segment
		(start 232.664 -21.680932)
		(end 232.664 -21.4122)
		(width 0.14224)
		(layer "In2.Cu")
		(net "M_A_DQ<26>")
	)
	(segment
		(start 233.57586 -37.06495)
		(end 232.29824 -37.06495)
		(width 0.14224)
		(layer "In2.Cu")
		(net "M_A_DQ<26>")
	)
	(segment
		(start 232.5116 -20.25015)
		(end 232.5116 -19.964146)
		(width 0.14224)
		(layer "In2.Cu")
		(net "M_A_DQ<26>")
	)
	(segment
		(start 232.918 -34.344864)
		(end 232.77576 -34.202624)
		(width 0.14224)
		(layer "In2.Cu")
		(net "M_A_DQ<26>")
	)
	(segment
		(start 243.515896 -54.596538)
		(end 243.685314 -54.30393)
		(width 0.0889)
		(layer "In2.Cu")
		(net "M_A_DQ<26>")
	)
	(segment
		(start 232.099866 -25.841198)
		(end 232.099866 -23.560278)
		(width 0.14224)
		(layer "In2.Cu")
		(net "M_A_DQ<26>")
	)
	(segment
		(start 241.15903 -50.21199)
		(end 240.158524 -49.211484)
		(width 0.0889)
		(layer "In2.Cu")
		(net "M_A_DQ<26>")
	)
	(segment
		(start 241.37493 -50.21199)
		(end 241.15903 -50.21199)
		(width 0.0889)
		(layer "In2.Cu")
		(net "M_A_DQ<26>")
	)
	(segment
		(start 232.2068 -20.55495)
		(end 232.5116 -20.25015)
		(width 0.14224)
		(layer "In2.Cu")
		(net "M_A_DQ<26>")
	)
	(segment
		(start 233.7308 -35.89401)
		(end 233.57586 -35.73907)
		(width 0.14224)
		(layer "In2.Cu")
		(net "M_A_DQ<26>")
	)
	(segment
		(start 231.815132 -22.5298)
		(end 232.664 -21.680932)
		(width 0.14224)
		(layer "In2.Cu")
		(net "M_A_DQ<26>")
	)
	(segment
		(start 232.551732 -18.965672)
		(end 232.551732 -18.660618)
		(width 0.14224)
		(layer "In2.Cu")
		(net "M_A_DQ<26>")
	)
	(segment
		(start 232.29824 -35.73907)
		(end 232.1433 -35.58413)
		(width 0.14224)
		(layer "In2.Cu")
		(net "M_A_DQ<26>")
	)
	(arc
		(start 243.685314 -54.30393)
		(mid 243.738813 -54.104032)
		(end 243.685314 -53.904134)
		(width 0.0889)
		(layer "In2.Cu")
		(net "M_A_DQ<26>")
	)
	(arc
		(start 243.678964 -53.893466)
		(mid 243.624427 -53.755454)
		(end 243.605812 -53.608224)
		(width 0.0889)
		(layer "In2.Cu")
		(net "M_A_DQ<26>")
	)
	(segment
		(start 226.149916 -15.423642)
		(end 226.149916 -16.687546)
		(width 0.1651)
		(layer "F.Cu")
		(net "M_A_DQ<25>")
	)
	(segment
		(start 241.334798 -56.58104)
		(end 240.763298 -56.58104)
		(width 0.1016)
		(layer "F.Cu")
		(net "M_A_DQ<25>")
	)
	(segment
		(start 226.150424 -15.423642)
		(end 226.149916 -15.423642)
		(width 0.1651)
		(layer "F.Cu")
		(net "M_A_DQ<25>")
	)
	(via
		(at 226.822 -22.279356)
		(size 0.508)
		(drill 0.254)
		(layers "F.Cu" "B.Cu")
		(net "M_A_DQ<25>")
	)
	(via
		(at 226.149916 -16.687546)
		(size 0.508)
		(drill 0.254)
		(layers "F.Cu" "B.Cu")
		(net "M_A_DQ<25>")
	)
	(via
		(at 240.763298 -56.58104)
		(size 0.508)
		(drill 0.254)
		(layers "F.Cu" "B.Cu")
		(net "M_A_DQ<25>")
	)
	(segment
		(start 226.9998 -20.224242)
		(end 226.9998 -21.598382)
		(width 0.1651)
		(layer "B.Cu")
		(net "M_A_DQ<25>")
	)
	(segment
		(start 226.822 -21.776182)
		(end 226.822 -22.279356)
		(width 0.1651)
		(layer "B.Cu")
		(net "M_A_DQ<25>")
	)
	(segment
		(start 227.000308 -20.224242)
		(end 226.9998 -20.224242)
		(width 0.1651)
		(layer "B.Cu")
		(net "M_A_DQ<25>")
	)
	(segment
		(start 226.9998 -21.598382)
		(end 226.822 -21.776182)
		(width 0.1651)
		(layer "B.Cu")
		(net "M_A_DQ<25>")
	)
	(segment
		(start 235.705396 -49.987454)
		(end 236.024928 -50.306986)
		(width 0.0889)
		(layer "In2.Cu")
		(net "M_A_DQ<25>")
	)
	(segment
		(start 227.628196 -29.279596)
		(end 227.628196 -36.111434)
		(width 0.14224)
		(layer "In2.Cu")
		(net "M_A_DQ<25>")
	)
	(segment
		(start 236.455712 -51.532536)
		(end 236.483652 -51.532536)
		(width 0.0889)
		(layer "In2.Cu")
		(net "M_A_DQ<25>")
	)
	(segment
		(start 226.822 -22.279356)
		(end 226.332796 -22.76856)
		(width 0.14224)
		(layer "In2.Cu")
		(net "M_A_DQ<25>")
	)
	(segment
		(start 226.982782 -17.7038)
		(end 227.352606 -18.073624)
		(width 0.14224)
		(layer "In2.Cu")
		(net "M_A_DQ<25>")
	)
	(segment
		(start 227.352606 -18.415)
		(end 227.196142 -18.571464)
		(width 0.14224)
		(layer "In2.Cu")
		(net "M_A_DQ<25>")
	)
	(segment
		(start 227.196142 -18.571464)
		(end 227.196142 -21.905214)
		(width 0.14224)
		(layer "In2.Cu")
		(net "M_A_DQ<25>")
	)
	(segment
		(start 227.352606 -18.073624)
		(end 227.352606 -18.415)
		(width 0.14224)
		(layer "In2.Cu")
		(net "M_A_DQ<25>")
	)
	(segment
		(start 226.627182 -17.7038)
		(end 226.982782 -17.7038)
		(width 0.14224)
		(layer "In2.Cu")
		(net "M_A_DQ<25>")
	)
	(segment
		(start 226.764596 -25.571196)
		(end 227.310696 -26.117296)
		(width 0.14224)
		(layer "In2.Cu")
		(net "M_A_DQ<25>")
	)
	(segment
		(start 226.149916 -17.226534)
		(end 226.627182 -17.7038)
		(width 0.14224)
		(layer "In2.Cu")
		(net "M_A_DQ<25>")
	)
	(segment
		(start 236.024928 -50.306986)
		(end 236.024928 -51.141884)
		(width 0.0889)
		(layer "In2.Cu")
		(net "M_A_DQ<25>")
	)
	(segment
		(start 227.310696 -26.117296)
		(end 227.310696 -28.962096)
		(width 0.14224)
		(layer "In2.Cu")
		(net "M_A_DQ<25>")
	)
	(segment
		(start 226.819968 -41.340532)
		(end 228.176836 -42.6974)
		(width 0.14224)
		(layer "In2.Cu")
		(net "M_A_DQ<25>")
	)
	(segment
		(start 226.332796 -22.76856)
		(end 226.332796 -23.107396)
		(width 0.14224)
		(layer "In2.Cu")
		(net "M_A_DQ<25>")
	)
	(segment
		(start 236.024928 -51.141884)
		(end 236.123988 -51.332638)
		(width 0.0889)
		(layer "In2.Cu")
		(net "M_A_DQ<25>")
	)
	(segment
		(start 240.411762 -55.781702)
		(end 240.43386 -55.820056)
		(width 0.0889)
		(layer "In2.Cu")
		(net "M_A_DQ<25>")
	)
	(segment
		(start 239.889792 -53.513736)
		(end 239.922558 -53.513736)
		(width 0.0889)
		(layer "In2.Cu")
		(net "M_A_DQ<25>")
	)
	(segment
		(start 227.196142 -21.905214)
		(end 226.822 -22.279356)
		(width 0.14224)
		(layer "In2.Cu")
		(net "M_A_DQ<25>")
	)
	(segment
		(start 226.764596 -23.539196)
		(end 226.764596 -25.571196)
		(width 0.14224)
		(layer "In2.Cu")
		(net "M_A_DQ<25>")
	)
	(segment
		(start 227.628196 -36.111434)
		(end 226.819968 -36.919662)
		(width 0.14224)
		(layer "In2.Cu")
		(net "M_A_DQ<25>")
	)
	(segment
		(start 226.819968 -36.919662)
		(end 226.819968 -41.340532)
		(width 0.14224)
		(layer "In2.Cu")
		(net "M_A_DQ<25>")
	)
	(segment
		(start 237.311184 -52.027836)
		(end 237.346998 -52.027836)
		(width 0.0889)
		(layer "In2.Cu")
		(net "M_A_DQ<25>")
	)
	(segment
		(start 226.149916 -16.687546)
		(end 226.149916 -17.226534)
		(width 0.14224)
		(layer "In2.Cu")
		(net "M_A_DQ<25>")
	)
	(segment
		(start 240.43386 -55.820056)
		(end 240.763298 -56.58104)
		(width 0.0889)
		(layer "In2.Cu")
		(net "M_A_DQ<25>")
	)
	(segment
		(start 228.415342 -42.6974)
		(end 235.705396 -49.987454)
		(width 0.14224)
		(layer "In2.Cu")
		(net "M_A_DQ<25>")
	)
	(segment
		(start 239.035082 -53.018436)
		(end 239.059212 -53.018436)
		(width 0.0889)
		(layer "In2.Cu")
		(net "M_A_DQ<25>")
	)
	(segment
		(start 238.169704 -52.523136)
		(end 238.209328 -52.523136)
		(width 0.0889)
		(layer "In2.Cu")
		(net "M_A_DQ<25>")
	)
	(segment
		(start 228.176836 -42.6974)
		(end 228.415342 -42.6974)
		(width 0.14224)
		(layer "In2.Cu")
		(net "M_A_DQ<25>")
	)
	(segment
		(start 226.332796 -23.107396)
		(end 226.764596 -23.539196)
		(width 0.14224)
		(layer "In2.Cu")
		(net "M_A_DQ<25>")
	)
	(segment
		(start 227.310696 -28.962096)
		(end 227.628196 -29.279596)
		(width 0.14224)
		(layer "In2.Cu")
		(net "M_A_DQ<25>")
	)
	(arc
		(start 238.209328 -52.523136)
		(mid 238.492545 -52.607417)
		(end 238.699548 -52.818284)
		(width 0.0889)
		(layer "In2.Cu")
		(net "M_A_DQ<25>")
	)
	(arc
		(start 239.558068 -53.313838)
		(mid 239.698147 -53.456574)
		(end 239.889792 -53.513736)
		(width 0.0889)
		(layer "In2.Cu")
		(net "M_A_DQ<25>")
	)
	(arc
		(start 236.123988 -51.332638)
		(mid 236.264067 -51.475374)
		(end 236.455712 -51.532536)
		(width 0.0889)
		(layer "In2.Cu")
		(net "M_A_DQ<25>")
	)
	(arc
		(start 239.059212 -53.018436)
		(mid 239.347357 -53.100755)
		(end 239.558068 -53.313838)
		(width 0.0889)
		(layer "In2.Cu")
		(net "M_A_DQ<25>")
	)
	(arc
		(start 237.346998 -52.027836)
		(mid 237.632422 -52.111303)
		(end 237.841028 -52.323238)
		(width 0.0889)
		(layer "In2.Cu")
		(net "M_A_DQ<25>")
	)
	(arc
		(start 241.110008 -54.399688)
		(mid 241.145984 -54.717398)
		(end 240.937796 -54.960012)
		(width 0.0889)
		(layer "In2.Cu")
		(net "M_A_DQ<25>")
	)
	(arc
		(start 239.922558 -53.513736)
		(mid 240.207982 -53.597203)
		(end 240.416588 -53.809138)
		(width 0.0889)
		(layer "In2.Cu")
		(net "M_A_DQ<25>")
	)
	(arc
		(start 236.483652 -51.532536)
		(mid 236.771797 -51.614855)
		(end 236.982508 -51.827938)
		(width 0.0889)
		(layer "In2.Cu")
		(net "M_A_DQ<25>")
	)
	(arc
		(start 236.982508 -51.827938)
		(mid 237.121252 -51.969971)
		(end 237.311184 -52.027836)
		(width 0.0889)
		(layer "In2.Cu")
		(net "M_A_DQ<25>")
	)
	(arc
		(start 240.416588 -53.809138)
		(mid 240.462315 -53.872941)
		(end 240.519712 -53.926486)
		(width 0.0889)
		(layer "In2.Cu")
		(net "M_A_DQ<25>")
	)
	(arc
		(start 240.478818 -55.309008)
		(mid 240.367096 -55.534257)
		(end 240.411762 -55.781702)
		(width 0.0889)
		(layer "In2.Cu")
		(net "M_A_DQ<25>")
	)
	(arc
		(start 240.519712 -53.926486)
		(mid 240.659411 -54.024931)
		(end 240.806224 -54.112414)
		(width 0.0889)
		(layer "In2.Cu")
		(net "M_A_DQ<25>")
	)
	(arc
		(start 237.841028 -52.323238)
		(mid 237.979772 -52.465271)
		(end 238.169704 -52.523136)
		(width 0.0889)
		(layer "In2.Cu")
		(net "M_A_DQ<25>")
	)
	(arc
		(start 240.937796 -54.960012)
		(mid 240.690898 -55.111613)
		(end 240.478818 -55.309008)
		(width 0.0889)
		(layer "In2.Cu")
		(net "M_A_DQ<25>")
	)
	(arc
		(start 240.806224 -54.112414)
		(mid 240.979052 -54.233907)
		(end 241.110008 -54.399688)
		(width 0.0889)
		(layer "In2.Cu")
		(net "M_A_DQ<25>")
	)
	(arc
		(start 238.699548 -52.818284)
		(mid 238.841231 -52.962088)
		(end 239.035082 -53.018436)
		(width 0.0889)
		(layer "In2.Cu")
		(net "M_A_DQ<25>")
	)
	(segment
		(start 227.000308 -20.023582)
		(end 226.9998 -20.023582)
		(width 0.1651)
		(layer "F.Cu")
		(net "M_A_DQ<24>")
	)
	(segment
		(start 226.919028 -19.177)
		(end 226.822 -18.161)
		(width 0.1651)
		(layer "F.Cu")
		(net "M_A_DQ<24>")
	)
	(segment
		(start 226.9998 -20.023582)
		(end 226.919028 -19.177)
		(width 0.1651)
		(layer "F.Cu")
		(net "M_A_DQ<24>")
	)
	(segment
		(start 241.334798 -54.59984)
		(end 240.763298 -54.59984)
		(width 0.1016)
		(layer "F.Cu")
		(net "M_A_DQ<24>")
	)
	(via
		(at 226.149916 -23.560278)
		(size 0.508)
		(drill 0.254)
		(layers "F.Cu" "B.Cu")
		(net "M_A_DQ<24>")
	)
	(via
		(at 240.763298 -54.59984)
		(size 0.508)
		(drill 0.254)
		(layers "F.Cu" "B.Cu")
		(net "M_A_DQ<24>")
	)
	(via
		(at 226.822 -18.161)
		(size 0.508)
		(drill 0.254)
		(layers "F.Cu" "B.Cu")
		(net "M_A_DQ<24>")
	)
	(segment
		(start 226.149916 -24.824182)
		(end 226.149916 -23.560278)
		(width 0.1651)
		(layer "B.Cu")
		(net "M_A_DQ<24>")
	)
	(segment
		(start 226.150424 -24.824182)
		(end 226.149916 -24.824182)
		(width 0.1651)
		(layer "B.Cu")
		(net "M_A_DQ<24>")
	)
	(segment
		(start 226.184968 -41.730422)
		(end 226.184968 -36.656518)
		(width 0.14224)
		(layer "In2.Cu")
		(net "M_A_DQ<24>")
	)
	(segment
		(start 226.2124 -20.903946)
		(end 226.2124 -20.5994)
		(width 0.14224)
		(layer "In2.Cu")
		(net "M_A_DQ<24>")
	)
	(segment
		(start 234.865926 -50.064162)
		(end 228.159564 -43.3578)
		(width 0.14224)
		(layer "In2.Cu")
		(net "M_A_DQ<24>")
	)
	(segment
		(start 226.187 -19.7104)
		(end 226.187 -19.380454)
		(width 0.14224)
		(layer "In2.Cu")
		(net "M_A_DQ<24>")
	)
	(segment
		(start 226.388168 -34.675318)
		(end 226.789996 -34.675318)
		(width 0.14224)
		(layer "In2.Cu")
		(net "M_A_DQ<24>")
	)
	(segment
		(start 226.184968 -36.656518)
		(end 226.695 -36.146486)
		(width 0.14224)
		(layer "In2.Cu")
		(net "M_A_DQ<24>")
	)
	(segment
		(start 226.601782 -18.381218)
		(end 226.822 -18.161)
		(width 0.14224)
		(layer "In2.Cu")
		(net "M_A_DQ<24>")
	)
	(segment
		(start 226.5299 -20.0533)
		(end 226.187 -19.7104)
		(width 0.14224)
		(layer "In2.Cu")
		(net "M_A_DQ<24>")
	)
	(segment
		(start 226.388168 -33.862518)
		(end 226.184968 -33.659318)
		(width 0.14224)
		(layer "In2.Cu")
		(net "M_A_DQ<24>")
	)
	(segment
		(start 226.388168 -33.049718)
		(end 226.789996 -33.049718)
		(width 0.14224)
		(layer "In2.Cu")
		(net "M_A_DQ<24>")
	)
	(segment
		(start 234.96524 -50.163476)
		(end 234.865926 -50.064162)
		(width 0.0889)
		(layer "In2.Cu")
		(net "M_A_DQ<24>")
	)
	(segment
		(start 226.55276 -35.488118)
		(end 226.388168 -35.488118)
		(width 0.14224)
		(layer "In2.Cu")
		(net "M_A_DQ<24>")
	)
	(segment
		(start 226.149916 -23.560278)
		(end 225.865182 -23.275544)
		(width 0.14224)
		(layer "In2.Cu")
		(net "M_A_DQ<24>")
	)
	(segment
		(start 240.763298 -54.59984)
		(end 240.268252 -53.933852)
		(width 0.0889)
		(layer "In2.Cu")
		(net "M_A_DQ<24>")
	)
	(segment
		(start 226.388168 -31.424118)
		(end 226.789996 -31.424118)
		(width 0.14224)
		(layer "In2.Cu")
		(net "M_A_DQ<24>")
	)
	(segment
		(start 226.184968 -35.284918)
		(end 226.184968 -34.878518)
		(width 0.14224)
		(layer "In2.Cu")
		(net "M_A_DQ<24>")
	)
	(segment
		(start 227.812346 -43.3578)
		(end 226.184968 -41.730422)
		(width 0.14224)
		(layer "In2.Cu")
		(net "M_A_DQ<24>")
	)
	(segment
		(start 226.6823 -28.4099)
		(end 226.332796 -28.060396)
		(width 0.14224)
		(layer "In2.Cu")
		(net "M_A_DQ<24>")
	)
	(segment
		(start 226.184968 -34.878518)
		(end 226.388168 -34.675318)
		(width 0.14224)
		(layer "In2.Cu")
		(net "M_A_DQ<24>")
	)
	(segment
		(start 225.865182 -22.5298)
		(end 226.601782 -21.7932)
		(width 0.14224)
		(layer "In2.Cu")
		(net "M_A_DQ<24>")
	)
	(segment
		(start 235.082334 -50.779426)
		(end 234.96524 -50.575464)
		(width 0.0889)
		(layer "In2.Cu")
		(net "M_A_DQ<24>")
	)
	(segment
		(start 240.268252 -53.933852)
		(end 240.251488 -53.904388)
		(width 0.0889)
		(layer "In2.Cu")
		(net "M_A_DQ<24>")
	)
	(segment
		(start 226.993196 -31.220918)
		(end 226.993196 -29.533596)
		(width 0.14224)
		(layer "In2.Cu")
		(net "M_A_DQ<24>")
	)
	(segment
		(start 239.915954 -53.704236)
		(end 239.883188 -53.704236)
		(width 0.0889)
		(layer "In2.Cu")
		(net "M_A_DQ<24>")
	)
	(segment
		(start 226.993196 -32.440118)
		(end 226.789996 -32.236918)
		(width 0.14224)
		(layer "In2.Cu")
		(net "M_A_DQ<24>")
	)
	(segment
		(start 226.149916 -25.836372)
		(end 226.149916 -23.560278)
		(width 0.14224)
		(layer "In2.Cu")
		(net "M_A_DQ<24>")
	)
	(segment
		(start 226.601782 -18.965672)
		(end 226.601782 -18.381218)
		(width 0.14224)
		(layer "In2.Cu")
		(net "M_A_DQ<24>")
	)
	(segment
		(start 228.159564 -43.3578)
		(end 227.812346 -43.3578)
		(width 0.14224)
		(layer "In2.Cu")
		(net "M_A_DQ<24>")
	)
	(segment
		(start 226.612196 -26.688796)
		(end 226.612196 -26.298652)
		(width 0.14224)
		(layer "In2.Cu")
		(net "M_A_DQ<24>")
	)
	(segment
		(start 226.789996 -31.424118)
		(end 226.993196 -31.220918)
		(width 0.14224)
		(layer "In2.Cu")
		(net "M_A_DQ<24>")
	)
	(segment
		(start 226.184968 -33.252918)
		(end 226.388168 -33.049718)
		(width 0.14224)
		(layer "In2.Cu")
		(net "M_A_DQ<24>")
	)
	(segment
		(start 226.993196 -32.846518)
		(end 226.993196 -32.440118)
		(width 0.14224)
		(layer "In2.Cu")
		(net "M_A_DQ<24>")
	)
	(segment
		(start 226.184968 -31.627318)
		(end 226.388168 -31.424118)
		(width 0.14224)
		(layer "In2.Cu")
		(net "M_A_DQ<24>")
	)
	(segment
		(start 236.481874 -51.72329)
		(end 236.457744 -51.72329)
		(width 0.0889)
		(layer "In2.Cu")
		(net "M_A_DQ<24>")
	)
	(segment
		(start 226.789996 -33.862518)
		(end 226.388168 -33.862518)
		(width 0.14224)
		(layer "In2.Cu")
		(net "M_A_DQ<24>")
	)
	(segment
		(start 226.789996 -32.236918)
		(end 226.388168 -32.236918)
		(width 0.14224)
		(layer "In2.Cu")
		(net "M_A_DQ<24>")
	)
	(segment
		(start 225.865182 -23.275544)
		(end 225.865182 -22.5298)
		(width 0.14224)
		(layer "In2.Cu")
		(net "M_A_DQ<24>")
	)
	(segment
		(start 234.96524 -50.575464)
		(end 234.96524 -50.163476)
		(width 0.0889)
		(layer "In2.Cu")
		(net "M_A_DQ<24>")
	)
	(segment
		(start 226.332796 -26.968196)
		(end 226.612196 -26.688796)
		(width 0.14224)
		(layer "In2.Cu")
		(net "M_A_DQ<24>")
	)
	(segment
		(start 226.184968 -32.033718)
		(end 226.184968 -31.627318)
		(width 0.14224)
		(layer "In2.Cu")
		(net "M_A_DQ<24>")
	)
	(segment
		(start 226.187 -19.380454)
		(end 226.601782 -18.965672)
		(width 0.14224)
		(layer "In2.Cu")
		(net "M_A_DQ<24>")
	)
	(segment
		(start 226.184968 -33.659318)
		(end 226.184968 -33.252918)
		(width 0.14224)
		(layer "In2.Cu")
		(net "M_A_DQ<24>")
	)
	(segment
		(start 226.388168 -35.488118)
		(end 226.184968 -35.284918)
		(width 0.14224)
		(layer "In2.Cu")
		(net "M_A_DQ<24>")
	)
	(segment
		(start 226.612196 -26.298652)
		(end 226.149916 -25.836372)
		(width 0.14224)
		(layer "In2.Cu")
		(net "M_A_DQ<24>")
	)
	(segment
		(start 226.2124 -20.5994)
		(end 226.5299 -20.2819)
		(width 0.14224)
		(layer "In2.Cu")
		(net "M_A_DQ<24>")
	)
	(segment
		(start 237.347252 -52.21859)
		(end 237.307628 -52.21859)
		(width 0.0889)
		(layer "In2.Cu")
		(net "M_A_DQ<24>")
	)
	(segment
		(start 226.332796 -28.060396)
		(end 226.332796 -26.968196)
		(width 0.14224)
		(layer "In2.Cu")
		(net "M_A_DQ<24>")
	)
	(segment
		(start 226.993196 -34.065718)
		(end 226.789996 -33.862518)
		(width 0.14224)
		(layer "In2.Cu")
		(net "M_A_DQ<24>")
	)
	(segment
		(start 226.695 -35.630358)
		(end 226.55276 -35.488118)
		(width 0.14224)
		(layer "In2.Cu")
		(net "M_A_DQ<24>")
	)
	(segment
		(start 226.993196 -34.472118)
		(end 226.993196 -34.065718)
		(width 0.14224)
		(layer "In2.Cu")
		(net "M_A_DQ<24>")
	)
	(segment
		(start 239.061244 -53.20919)
		(end 239.033304 -53.20919)
		(width 0.0889)
		(layer "In2.Cu")
		(net "M_A_DQ<24>")
	)
	(segment
		(start 226.601782 -21.7932)
		(end 226.601782 -21.293328)
		(width 0.14224)
		(layer "In2.Cu")
		(net "M_A_DQ<24>")
	)
	(segment
		(start 226.789996 -33.049718)
		(end 226.993196 -32.846518)
		(width 0.14224)
		(layer "In2.Cu")
		(net "M_A_DQ<24>")
	)
	(segment
		(start 226.6823 -29.2227)
		(end 226.6823 -28.4099)
		(width 0.14224)
		(layer "In2.Cu")
		(net "M_A_DQ<24>")
	)
	(segment
		(start 226.993196 -29.533596)
		(end 226.6823 -29.2227)
		(width 0.14224)
		(layer "In2.Cu")
		(net "M_A_DQ<24>")
	)
	(segment
		(start 226.601782 -21.293328)
		(end 226.2124 -20.903946)
		(width 0.14224)
		(layer "In2.Cu")
		(net "M_A_DQ<24>")
	)
	(segment
		(start 226.695 -36.146486)
		(end 226.695 -35.630358)
		(width 0.14224)
		(layer "In2.Cu")
		(net "M_A_DQ<24>")
	)
	(segment
		(start 226.388168 -32.236918)
		(end 226.184968 -32.033718)
		(width 0.14224)
		(layer "In2.Cu")
		(net "M_A_DQ<24>")
	)
	(segment
		(start 226.5299 -20.2819)
		(end 226.5299 -20.0533)
		(width 0.14224)
		(layer "In2.Cu")
		(net "M_A_DQ<24>")
	)
	(segment
		(start 238.205772 -52.71389)
		(end 238.169958 -52.71389)
		(width 0.0889)
		(layer "In2.Cu")
		(net "M_A_DQ<24>")
	)
	(segment
		(start 226.789996 -34.675318)
		(end 226.993196 -34.472118)
		(width 0.14224)
		(layer "In2.Cu")
		(net "M_A_DQ<24>")
	)
	(arc
		(start 237.675928 -52.418488)
		(mid 237.537184 -52.276455)
		(end 237.347252 -52.21859)
		(width 0.0889)
		(layer "In2.Cu")
		(net "M_A_DQ<24>")
	)
	(arc
		(start 235.958888 -51.427888)
		(mid 235.857253 -51.311485)
		(end 235.719112 -51.242214)
		(width 0.0889)
		(layer "In2.Cu")
		(net "M_A_DQ<24>")
	)
	(arc
		(start 238.534448 -52.913788)
		(mid 238.395704 -52.771755)
		(end 238.205772 -52.71389)
		(width 0.0889)
		(layer "In2.Cu")
		(net "M_A_DQ<24>")
	)
	(arc
		(start 237.307628 -52.21859)
		(mid 237.024411 -52.134309)
		(end 236.817408 -51.923442)
		(width 0.0889)
		(layer "In2.Cu")
		(net "M_A_DQ<24>")
	)
	(arc
		(start 239.033304 -53.20919)
		(mid 238.745159 -53.126871)
		(end 238.534448 -52.913788)
		(width 0.0889)
		(layer "In2.Cu")
		(net "M_A_DQ<24>")
	)
	(arc
		(start 238.169958 -52.71389)
		(mid 237.884534 -52.630423)
		(end 237.675928 -52.418488)
		(width 0.0889)
		(layer "In2.Cu")
		(net "M_A_DQ<24>")
	)
	(arc
		(start 236.457744 -51.72329)
		(mid 236.169599 -51.640971)
		(end 235.958888 -51.427888)
		(width 0.0889)
		(layer "In2.Cu")
		(net "M_A_DQ<24>")
	)
	(arc
		(start 240.251488 -53.904388)
		(mid 240.109805 -53.760584)
		(end 239.915954 -53.704236)
		(width 0.0889)
		(layer "In2.Cu")
		(net "M_A_DQ<24>")
	)
	(arc
		(start 239.392968 -53.409088)
		(mid 239.252889 -53.266352)
		(end 239.061244 -53.20919)
		(width 0.0889)
		(layer "In2.Cu")
		(net "M_A_DQ<24>")
	)
	(arc
		(start 235.719112 -51.242214)
		(mid 235.35884 -51.068446)
		(end 235.082334 -50.779426)
		(width 0.0889)
		(layer "In2.Cu")
		(net "M_A_DQ<24>")
	)
	(arc
		(start 236.817408 -51.923442)
		(mid 236.675725 -51.779638)
		(end 236.481874 -51.72329)
		(width 0.0889)
		(layer "In2.Cu")
		(net "M_A_DQ<24>")
	)
	(arc
		(start 239.883188 -53.704236)
		(mid 239.599971 -53.619955)
		(end 239.392968 -53.409088)
		(width 0.0889)
		(layer "In2.Cu")
		(net "M_A_DQ<24>")
	)
	(segment
		(start 237.900718 -55.59044)
		(end 237.329218 -55.59044)
		(width 0.1016)
		(layer "F.Cu")
		(net "M_A_DQ<23>")
	)
	(segment
		(start 221.04985 -15.423642)
		(end 221.04985 -16.687546)
		(width 0.1651)
		(layer "F.Cu")
		(net "M_A_DQ<23>")
	)
	(segment
		(start 221.050358 -15.423642)
		(end 221.04985 -15.423642)
		(width 0.1651)
		(layer "F.Cu")
		(net "M_A_DQ<23>")
	)
	(via
		(at 221.04985 -16.687546)
		(size 0.508)
		(drill 0.254)
		(layers "F.Cu" "B.Cu")
		(net "M_A_DQ<23>")
	)
	(via
		(at 237.329218 -55.59044)
		(size 0.508)
		(drill 0.254)
		(layers "F.Cu" "B.Cu")
		(net "M_A_DQ<23>")
	)
	(via
		(at 221.899734 -22.279356)
		(size 0.508)
		(drill 0.254)
		(layers "F.Cu" "B.Cu")
		(net "M_A_DQ<23>")
	)
	(segment
		(start 221.899734 -20.225004)
		(end 221.900496 -20.224242)
		(width 0.1651)
		(layer "B.Cu")
		(net "M_A_DQ<23>")
	)
	(segment
		(start 221.899734 -22.279356)
		(end 221.899734 -20.225004)
		(width 0.1651)
		(layer "B.Cu")
		(net "M_A_DQ<23>")
	)
	(segment
		(start 232.50017 -53.553614)
		(end 232.641648 -53.553614)
		(width 0.0889)
		(layer "In2.Cu")
		(net "M_A_DQ<23>")
	)
	(segment
		(start 220.962728 -38.184836)
		(end 221.267528 -38.184836)
		(width 0.14224)
		(layer "In2.Cu")
		(net "M_A_DQ<23>")
	)
	(segment
		(start 232.641648 -53.553614)
		(end 234.58297 -55.494936)
		(width 0.0889)
		(layer "In2.Cu")
		(net "M_A_DQ<23>")
	)
	(segment
		(start 231.840278 -52.893722)
		(end 232.243376 -53.29682)
		(width 0.14224)
		(layer "In2.Cu")
		(net "M_A_DQ<23>")
	)
	(segment
		(start 221.267528 -38.184836)
		(end 221.501462 -37.950902)
		(width 0.14224)
		(layer "In2.Cu")
		(net "M_A_DQ<23>")
	)
	(segment
		(start 221.366588 -17.004284)
		(end 221.366588 -17.3228)
		(width 0.14224)
		(layer "In2.Cu")
		(net "M_A_DQ<23>")
	)
	(segment
		(start 227.1268 -48.514)
		(end 228.4476 -48.514)
		(width 0.14224)
		(layer "In2.Cu")
		(net "M_A_DQ<23>")
	)
	(segment
		(start 221.638368 -24.132032)
		(end 220.774768 -24.995632)
		(width 0.14224)
		(layer "In2.Cu")
		(net "M_A_DQ<23>")
	)
	(segment
		(start 234.58297 -55.494936)
		(end 234.771438 -55.494936)
		(width 0.0889)
		(layer "In2.Cu")
		(net "M_A_DQ<23>")
	)
	(segment
		(start 221.696788 -17.653)
		(end 221.950788 -17.653)
		(width 0.14224)
		(layer "In2.Cu")
		(net "M_A_DQ<23>")
	)
	(segment
		(start 222.407988 -18.1102)
		(end 222.407988 -18.4658)
		(width 0.14224)
		(layer "In2.Cu")
		(net "M_A_DQ<23>")
	)
	(segment
		(start 221.501462 -34.5186)
		(end 221.704662 -34.3154)
		(width 0.14224)
		(layer "In2.Cu")
		(net "M_A_DQ<23>")
	)
	(segment
		(start 231.840278 -51.906678)
		(end 231.840278 -52.893722)
		(width 0.14224)
		(layer "In2.Cu")
		(net "M_A_DQ<23>")
	)
	(segment
		(start 221.704662 -34.3154)
		(end 222.009462 -34.3154)
		(width 0.14224)
		(layer "In2.Cu")
		(net "M_A_DQ<23>")
	)
	(segment
		(start 222.407988 -18.4658)
		(end 222.25254 -18.621248)
		(width 0.14224)
		(layer "In2.Cu")
		(net "M_A_DQ<23>")
	)
	(segment
		(start 221.950788 -17.653)
		(end 222.407988 -18.1102)
		(width 0.14224)
		(layer "In2.Cu")
		(net "M_A_DQ<23>")
	)
	(segment
		(start 232.243376 -53.29682)
		(end 232.50017 -53.553614)
		(width 0.0889)
		(layer "In2.Cu")
		(net "M_A_DQ<23>")
	)
	(segment
		(start 222.25254 -21.92655)
		(end 221.899734 -22.279356)
		(width 0.14224)
		(layer "In2.Cu")
		(net "M_A_DQ<23>")
	)
	(segment
		(start 235.601002 -55.99049)
		(end 235.633768 -55.99049)
		(width 0.0889)
		(layer "In2.Cu")
		(net "M_A_DQ<23>")
	)
	(segment
		(start 221.04985 -16.687546)
		(end 221.366588 -17.004284)
		(width 0.14224)
		(layer "In2.Cu")
		(net "M_A_DQ<23>")
	)
	(segment
		(start 222.25254 -18.621248)
		(end 222.25254 -21.92655)
		(width 0.14224)
		(layer "In2.Cu")
		(net "M_A_DQ<23>")
	)
	(segment
		(start 220.774768 -37.996876)
		(end 220.962728 -38.184836)
		(width 0.14224)
		(layer "In2.Cu")
		(net "M_A_DQ<23>")
	)
	(segment
		(start 236.006894 -55.866792)
		(end 236.377734 -55.59044)
		(width 0.0889)
		(layer "In2.Cu")
		(net "M_A_DQ<23>")
	)
	(segment
		(start 221.638368 -23.340568)
		(end 221.638368 -24.132032)
		(width 0.14224)
		(layer "In2.Cu")
		(net "M_A_DQ<23>")
	)
	(segment
		(start 220.774768 -24.995632)
		(end 220.774768 -37.996876)
		(width 0.14224)
		(layer "In2.Cu")
		(net "M_A_DQ<23>")
	)
	(segment
		(start 221.435168 -22.743922)
		(end 221.435168 -23.137368)
		(width 0.14224)
		(layer "In2.Cu")
		(net "M_A_DQ<23>")
	)
	(segment
		(start 221.366588 -17.3228)
		(end 221.696788 -17.653)
		(width 0.14224)
		(layer "In2.Cu")
		(net "M_A_DQ<23>")
	)
	(segment
		(start 221.435168 -23.137368)
		(end 221.638368 -23.340568)
		(width 0.14224)
		(layer "In2.Cu")
		(net "M_A_DQ<23>")
	)
	(segment
		(start 221.899734 -22.279356)
		(end 221.435168 -22.743922)
		(width 0.14224)
		(layer "In2.Cu")
		(net "M_A_DQ<23>")
	)
	(segment
		(start 228.4476 -48.514)
		(end 231.840278 -51.906678)
		(width 0.14224)
		(layer "In2.Cu")
		(net "M_A_DQ<23>")
	)
	(segment
		(start 221.501462 -37.950902)
		(end 221.501462 -34.5186)
		(width 0.14224)
		(layer "In2.Cu")
		(net "M_A_DQ<23>")
	)
	(segment
		(start 236.377734 -55.59044)
		(end 237.329218 -55.59044)
		(width 0.0889)
		(layer "In2.Cu")
		(net "M_A_DQ<23>")
	)
	(segment
		(start 222.212662 -43.599862)
		(end 227.1268 -48.514)
		(width 0.14224)
		(layer "In2.Cu")
		(net "M_A_DQ<23>")
	)
	(segment
		(start 222.212662 -34.5186)
		(end 222.212662 -43.599862)
		(width 0.14224)
		(layer "In2.Cu")
		(net "M_A_DQ<23>")
	)
	(segment
		(start 222.009462 -34.3154)
		(end 222.212662 -34.5186)
		(width 0.14224)
		(layer "In2.Cu")
		(net "M_A_DQ<23>")
	)
	(arc
		(start 234.771438 -55.494936)
		(mid 235.056862 -55.578403)
		(end 235.265468 -55.790338)
		(width 0.0889)
		(layer "In2.Cu")
		(net "M_A_DQ<23>")
	)
	(arc
		(start 235.633768 -55.99049)
		(mid 235.830315 -55.958759)
		(end 236.006894 -55.866792)
		(width 0.0889)
		(layer "In2.Cu")
		(net "M_A_DQ<23>")
	)
	(arc
		(start 235.265468 -55.790338)
		(mid 235.407151 -55.934142)
		(end 235.601002 -55.99049)
		(width 0.0889)
		(layer "In2.Cu")
		(net "M_A_DQ<23>")
	)
	(segment
		(start 221.900496 -20.023582)
		(end 221.899988 -20.023582)
		(width 0.1651)
		(layer "F.Cu")
		(net "M_A_DQ<22>")
	)
	(segment
		(start 222.032068 -18.91792)
		(end 222.032068 -18.69948)
		(width 0.1651)
		(layer "F.Cu")
		(net "M_A_DQ<22>")
	)
	(segment
		(start 221.899988 -20.023582)
		(end 221.899988 -19.05)
		(width 0.1651)
		(layer "F.Cu")
		(net "M_A_DQ<22>")
	)
	(segment
		(start 236.183678 -56.58104)
		(end 235.612178 -56.58104)
		(width 0.1016)
		(layer "F.Cu")
		(net "M_A_DQ<22>")
	)
	(segment
		(start 222.032068 -18.69948)
		(end 221.899988 -18.5674)
		(width 0.1651)
		(layer "F.Cu")
		(net "M_A_DQ<22>")
	)
	(segment
		(start 221.899988 -18.262854)
		(end 221.899734 -18.2626)
		(width 0.1651)
		(layer "F.Cu")
		(net "M_A_DQ<22>")
	)
	(segment
		(start 221.899988 -19.05)
		(end 222.032068 -18.91792)
		(width 0.1651)
		(layer "F.Cu")
		(net "M_A_DQ<22>")
	)
	(segment
		(start 221.899988 -18.5674)
		(end 221.899988 -18.262854)
		(width 0.1651)
		(layer "F.Cu")
		(net "M_A_DQ<22>")
	)
	(via
		(at 221.04985 -23.561294)
		(size 0.508)
		(drill 0.254)
		(layers "F.Cu" "B.Cu")
		(net "M_A_DQ<22>")
	)
	(via
		(at 235.612178 -56.58104)
		(size 0.508)
		(drill 0.254)
		(layers "F.Cu" "B.Cu")
		(net "M_A_DQ<22>")
	)
	(via
		(at 221.899734 -18.2626)
		(size 0.508)
		(drill 0.254)
		(layers "F.Cu" "B.Cu")
		(net "M_A_DQ<22>")
	)
	(segment
		(start 221.050358 -24.824182)
		(end 221.04985 -24.824182)
		(width 0.1651)
		(layer "B.Cu")
		(net "M_A_DQ<22>")
	)
	(segment
		(start 221.04985 -24.824182)
		(end 221.04985 -23.561294)
		(width 0.1651)
		(layer "B.Cu")
		(net "M_A_DQ<22>")
	)
	(segment
		(start 220.114368 -39.8907)
		(end 220.256608 -40.03294)
		(width 0.14224)
		(layer "In2.Cu")
		(net "M_A_DQ<22>")
	)
	(segment
		(start 227.848414 -50.454814)
		(end 228.6 -51.2064)
		(width 0.14224)
		(layer "In2.Cu")
		(net "M_A_DQ<22>")
	)
	(segment
		(start 232.562908 -53.743606)
		(end 234.504738 -55.685436)
		(width 0.0889)
		(layer "In2.Cu")
		(net "M_A_DQ<22>")
	)
	(segment
		(start 220.814138 -23.325582)
		(end 221.04985 -23.561294)
		(width 0.14224)
		(layer "In2.Cu")
		(net "M_A_DQ<22>")
	)
	(segment
		(start 221.525338 -18.914872)
		(end 221.161356 -19.278854)
		(width 0.14224)
		(layer "In2.Cu")
		(net "M_A_DQ<22>")
	)
	(segment
		(start 221.57436 -39.3827)
		(end 220.256608 -39.3827)
		(width 0.14224)
		(layer "In2.Cu")
		(net "M_A_DQ<22>")
	)
	(segment
		(start 221.899734 -18.2626)
		(end 221.525338 -18.636996)
		(width 0.14224)
		(layer "In2.Cu")
		(net "M_A_DQ<22>")
	)
	(segment
		(start 221.7166 -39.24046)
		(end 221.57436 -39.3827)
		(width 0.14224)
		(layer "In2.Cu")
		(net "M_A_DQ<22>")
	)
	(segment
		(start 227.848414 -50.253646)
		(end 227.848414 -50.454814)
		(width 0.14224)
		(layer "In2.Cu")
		(net "M_A_DQ<22>")
	)
	(segment
		(start 221.586806 -21.405596)
		(end 221.586806 -21.757386)
		(width 0.14224)
		(layer "In2.Cu")
		(net "M_A_DQ<22>")
	)
	(segment
		(start 235.594398 -56.18099)
		(end 235.627164 -56.18099)
		(width 0.0889)
		(layer "In2.Cu")
		(net "M_A_DQ<22>")
	)
	(segment
		(start 221.57436 -38.73246)
		(end 221.7166 -38.8747)
		(width 0.14224)
		(layer "In2.Cu")
		(net "M_A_DQ<22>")
	)
	(segment
		(start 234.504738 -55.685436)
		(end 234.764834 -55.685436)
		(width 0.0889)
		(layer "In2.Cu")
		(net "M_A_DQ<22>")
	)
	(segment
		(start 235.905294 -56.411876)
		(end 235.612178 -56.58104)
		(width 0.0889)
		(layer "In2.Cu")
		(net "M_A_DQ<22>")
	)
	(segment
		(start 221.161356 -19.589496)
		(end 221.542356 -19.970496)
		(width 0.14224)
		(layer "In2.Cu")
		(net "M_A_DQ<22>")
	)
	(segment
		(start 221.57436 -41.33342)
		(end 221.7166 -41.47566)
		(width 0.14224)
		(layer "In2.Cu")
		(net "M_A_DQ<22>")
	)
	(segment
		(start 221.542356 -19.970496)
		(end 221.542356 -20.313904)
		(width 0.14224)
		(layer "In2.Cu")
		(net "M_A_DQ<22>")
	)
	(segment
		(start 220.114368 -24.894032)
		(end 220.114368 -38.59022)
		(width 0.14224)
		(layer "In2.Cu")
		(net "M_A_DQ<22>")
	)
	(segment
		(start 221.57436 -40.68318)
		(end 220.256608 -40.68318)
		(width 0.14224)
		(layer "In2.Cu")
		(net "M_A_DQ<22>")
	)
	(segment
		(start 221.7166 -40.17518)
		(end 221.7166 -40.54094)
		(width 0.14224)
		(layer "In2.Cu")
		(net "M_A_DQ<22>")
	)
	(segment
		(start 220.256608 -40.68318)
		(end 220.114368 -40.82542)
		(width 0.14224)
		(layer "In2.Cu")
		(net "M_A_DQ<22>")
	)
	(segment
		(start 227.88372 -49.49952)
		(end 228.142546 -49.758346)
		(width 0.14224)
		(layer "In2.Cu")
		(net "M_A_DQ<22>")
	)
	(segment
		(start 221.7166 -41.47566)
		(end 221.7166 -41.84142)
		(width 0.14224)
		(layer "In2.Cu")
		(net "M_A_DQ<22>")
	)
	(segment
		(start 221.57436 -40.03294)
		(end 221.7166 -40.17518)
		(width 0.14224)
		(layer "In2.Cu")
		(net "M_A_DQ<22>")
	)
	(segment
		(start 220.114368 -38.59022)
		(end 220.256608 -38.73246)
		(width 0.14224)
		(layer "In2.Cu")
		(net "M_A_DQ<22>")
	)
	(segment
		(start 221.161356 -19.278854)
		(end 221.161356 -19.589496)
		(width 0.14224)
		(layer "In2.Cu")
		(net "M_A_DQ<22>")
	)
	(segment
		(start 227.187252 -49.793652)
		(end 227.38842 -49.793652)
		(width 0.14224)
		(layer "In2.Cu")
		(net "M_A_DQ<22>")
	)
	(segment
		(start 220.256608 -38.73246)
		(end 221.57436 -38.73246)
		(width 0.14224)
		(layer "In2.Cu")
		(net "M_A_DQ<22>")
	)
	(segment
		(start 221.7166 -41.84142)
		(end 221.57436 -41.98366)
		(width 0.14224)
		(layer "In2.Cu")
		(net "M_A_DQ<22>")
	)
	(segment
		(start 221.161356 -20.980146)
		(end 221.586806 -21.405596)
		(width 0.14224)
		(layer "In2.Cu")
		(net "M_A_DQ<22>")
	)
	(segment
		(start 228.6 -51.2064)
		(end 229.2096 -51.2064)
		(width 0.14224)
		(layer "In2.Cu")
		(net "M_A_DQ<22>")
	)
	(segment
		(start 220.114368 -39.52494)
		(end 220.114368 -39.8907)
		(width 0.14224)
		(layer "In2.Cu")
		(net "M_A_DQ<22>")
	)
	(segment
		(start 235.926376 -56.333136)
		(end 235.905294 -56.411876)
		(width 0.0889)
		(layer "In2.Cu")
		(net "M_A_DQ<22>")
	)
	(segment
		(start 228.142546 -49.758346)
		(end 228.142546 -49.959514)
		(width 0.14224)
		(layer "In2.Cu")
		(net "M_A_DQ<22>")
	)
	(segment
		(start 231.94772 -53.94452)
		(end 232.210864 -53.94452)
		(width 0.14224)
		(layer "In2.Cu")
		(net "M_A_DQ<22>")
	)
	(segment
		(start 220.256608 -41.33342)
		(end 221.57436 -41.33342)
		(width 0.14224)
		(layer "In2.Cu")
		(net "M_A_DQ<22>")
	)
	(segment
		(start 229.2096 -51.2064)
		(end 231.94772 -53.94452)
		(width 0.14224)
		(layer "In2.Cu")
		(net "M_A_DQ<22>")
	)
	(segment
		(start 220.256608 -39.3827)
		(end 220.114368 -39.52494)
		(width 0.14224)
		(layer "In2.Cu")
		(net "M_A_DQ<22>")
	)
	(segment
		(start 227.38842 -49.793652)
		(end 227.682552 -49.49952)
		(width 0.14224)
		(layer "In2.Cu")
		(net "M_A_DQ<22>")
	)
	(segment
		(start 228.142546 -49.959514)
		(end 227.848414 -50.253646)
		(width 0.14224)
		(layer "In2.Cu")
		(net "M_A_DQ<22>")
	)
	(segment
		(start 220.114368 -41.19118)
		(end 220.256608 -41.33342)
		(width 0.14224)
		(layer "In2.Cu")
		(net "M_A_DQ<22>")
	)
	(segment
		(start 232.210864 -53.94452)
		(end 232.411778 -53.743606)
		(width 0.0889)
		(layer "In2.Cu")
		(net "M_A_DQ<22>")
	)
	(segment
		(start 220.814138 -22.530054)
		(end 220.814138 -23.325582)
		(width 0.14224)
		(layer "In2.Cu")
		(net "M_A_DQ<22>")
	)
	(segment
		(start 220.114368 -42.720768)
		(end 227.187252 -49.793652)
		(width 0.14224)
		(layer "In2.Cu")
		(net "M_A_DQ<22>")
	)
	(segment
		(start 220.256608 -40.03294)
		(end 221.57436 -40.03294)
		(width 0.14224)
		(layer "In2.Cu")
		(net "M_A_DQ<22>")
	)
	(segment
		(start 220.256608 -41.98366)
		(end 220.114368 -42.1259)
		(width 0.14224)
		(layer "In2.Cu")
		(net "M_A_DQ<22>")
	)
	(segment
		(start 221.542356 -20.313904)
		(end 221.161356 -20.694904)
		(width 0.14224)
		(layer "In2.Cu")
		(net "M_A_DQ<22>")
	)
	(segment
		(start 221.161356 -20.694904)
		(end 221.161356 -20.980146)
		(width 0.14224)
		(layer "In2.Cu")
		(net "M_A_DQ<22>")
	)
	(segment
		(start 220.114368 -42.1259)
		(end 220.114368 -42.720768)
		(width 0.14224)
		(layer "In2.Cu")
		(net "M_A_DQ<22>")
	)
	(segment
		(start 221.04985 -23.95855)
		(end 220.114368 -24.894032)
		(width 0.14224)
		(layer "In2.Cu")
		(net "M_A_DQ<22>")
	)
	(segment
		(start 221.7166 -40.54094)
		(end 221.57436 -40.68318)
		(width 0.14224)
		(layer "In2.Cu")
		(net "M_A_DQ<22>")
	)
	(segment
		(start 221.586806 -21.757386)
		(end 220.814138 -22.530054)
		(width 0.14224)
		(layer "In2.Cu")
		(net "M_A_DQ<22>")
	)
	(segment
		(start 227.682552 -49.49952)
		(end 227.88372 -49.49952)
		(width 0.14224)
		(layer "In2.Cu")
		(net "M_A_DQ<22>")
	)
	(segment
		(start 220.114368 -40.82542)
		(end 220.114368 -41.19118)
		(width 0.14224)
		(layer "In2.Cu")
		(net "M_A_DQ<22>")
	)
	(segment
		(start 221.04985 -23.561294)
		(end 221.04985 -23.95855)
		(width 0.14224)
		(layer "In2.Cu")
		(net "M_A_DQ<22>")
	)
	(segment
		(start 221.525338 -18.636996)
		(end 221.525338 -18.914872)
		(width 0.14224)
		(layer "In2.Cu")
		(net "M_A_DQ<22>")
	)
	(segment
		(start 221.7166 -38.8747)
		(end 221.7166 -39.24046)
		(width 0.14224)
		(layer "In2.Cu")
		(net "M_A_DQ<22>")
	)
	(segment
		(start 221.57436 -41.98366)
		(end 220.256608 -41.98366)
		(width 0.14224)
		(layer "In2.Cu")
		(net "M_A_DQ<22>")
	)
	(segment
		(start 232.411778 -53.743606)
		(end 232.562908 -53.743606)
		(width 0.0889)
		(layer "In2.Cu")
		(net "M_A_DQ<22>")
	)
	(arc
		(start 235.100368 -55.885588)
		(mid 235.308976 -56.09752)
		(end 235.594398 -56.18099)
		(width 0.0889)
		(layer "In2.Cu")
		(net "M_A_DQ<22>")
	)
	(arc
		(start 235.627164 -56.18099)
		(mid 235.793458 -56.224224)
		(end 235.926376 -56.333136)
		(width 0.0889)
		(layer "In2.Cu")
		(net "M_A_DQ<22>")
	)
	(arc
		(start 234.764834 -55.685436)
		(mid 234.958684 -55.741786)
		(end 235.100368 -55.885588)
		(width 0.0889)
		(layer "In2.Cu")
		(net "M_A_DQ<22>")
	)
	(segment
		(start 215.0999 -15.423642)
		(end 215.0999 -16.687546)
		(width 0.1651)
		(layer "F.Cu")
		(net "M_A_DQ<21>")
	)
	(segment
		(start 215.100408 -15.423642)
		(end 215.0999 -15.423642)
		(width 0.1651)
		(layer "F.Cu")
		(net "M_A_DQ<21>")
	)
	(segment
		(start 238.759238 -58.06694)
		(end 238.187738 -58.06694)
		(width 0.1016)
		(layer "F.Cu")
		(net "M_A_DQ<21>")
	)
	(via
		(at 215.0999 -16.687546)
		(size 0.508)
		(drill 0.254)
		(layers "F.Cu" "B.Cu")
		(net "M_A_DQ<21>")
	)
	(via
		(at 215.873584 -22.279356)
		(size 0.508)
		(drill 0.254)
		(layers "F.Cu" "B.Cu")
		(net "M_A_DQ<21>")
	)
	(via
		(at 238.187738 -58.06694)
		(size 0.508)
		(drill 0.254)
		(layers "F.Cu" "B.Cu")
		(net "M_A_DQ<21>")
	)
	(segment
		(start 215.950292 -20.224242)
		(end 215.949784 -20.224242)
		(width 0.1651)
		(layer "B.Cu")
		(net "M_A_DQ<21>")
	)
	(segment
		(start 215.949784 -20.224242)
		(end 215.949784 -22.203156)
		(width 0.1651)
		(layer "B.Cu")
		(net "M_A_DQ<21>")
	)
	(segment
		(start 215.949784 -22.203156)
		(end 215.873584 -22.279356)
		(width 0.1651)
		(layer "B.Cu")
		(net "M_A_DQ<21>")
	)
	(segment
		(start 215.873584 -22.279356)
		(end 215.389968 -22.762972)
		(width 0.14224)
		(layer "In2.Cu")
		(net "M_A_DQ<21>")
	)
	(segment
		(start 231.268524 -58.522108)
		(end 231.347264 -58.522108)
		(width 0.0889)
		(layer "In2.Cu")
		(net "M_A_DQ<21>")
	)
	(segment
		(start 231.699308 -58.874152)
		(end 232.690162 -58.874152)
		(width 0.0889)
		(layer "In2.Cu")
		(net "M_A_DQ<21>")
	)
	(segment
		(start 216.381838 -18.4658)
		(end 216.184988 -18.66265)
		(width 0.14224)
		(layer "In2.Cu")
		(net "M_A_DQ<21>")
	)
	(segment
		(start 215.981534 -17.653)
		(end 216.381838 -18.053304)
		(width 0.14224)
		(layer "In2.Cu")
		(net "M_A_DQ<21>")
	)
	(segment
		(start 237.311184 -58.16219)
		(end 237.365794 -58.16219)
		(width 0.0889)
		(layer "In2.Cu")
		(net "M_A_DQ<21>")
	)
	(segment
		(start 236.866938 -59.114182)
		(end 236.935518 -58.443622)
		(width 0.0889)
		(layer "In2.Cu")
		(net "M_A_DQ<21>")
	)
	(segment
		(start 215.389968 -23.162768)
		(end 215.593168 -23.365968)
		(width 0.14224)
		(layer "In2.Cu")
		(net "M_A_DQ<21>")
	)
	(segment
		(start 215.4555 -43.764454)
		(end 230.213154 -58.522108)
		(width 0.14224)
		(layer "In2.Cu")
		(net "M_A_DQ<21>")
	)
	(segment
		(start 216.184988 -18.66265)
		(end 216.184988 -21.967952)
		(width 0.14224)
		(layer "In2.Cu")
		(net "M_A_DQ<21>")
	)
	(segment
		(start 215.593168 -24.333454)
		(end 215.4555 -24.471122)
		(width 0.14224)
		(layer "In2.Cu")
		(net "M_A_DQ<21>")
	)
	(segment
		(start 215.0999 -16.687546)
		(end 215.0999 -17.082262)
		(width 0.14224)
		(layer "In2.Cu")
		(net "M_A_DQ<21>")
	)
	(segment
		(start 237.365794 -58.16219)
		(end 238.187738 -58.06694)
		(width 0.0889)
		(layer "In2.Cu")
		(net "M_A_DQ<21>")
	)
	(segment
		(start 236.935518 -58.443622)
		(end 236.982508 -58.362088)
		(width 0.0889)
		(layer "In2.Cu")
		(net "M_A_DQ<21>")
	)
	(segment
		(start 232.690162 -58.874152)
		(end 233.273346 -59.457336)
		(width 0.0889)
		(layer "In2.Cu")
		(net "M_A_DQ<21>")
	)
	(segment
		(start 215.4555 -24.471122)
		(end 215.4555 -43.764454)
		(width 0.14224)
		(layer "In2.Cu")
		(net "M_A_DQ<21>")
	)
	(segment
		(start 215.0999 -17.082262)
		(end 215.670638 -17.653)
		(width 0.14224)
		(layer "In2.Cu")
		(net "M_A_DQ<21>")
	)
	(segment
		(start 216.184988 -21.967952)
		(end 215.873584 -22.279356)
		(width 0.14224)
		(layer "In2.Cu")
		(net "M_A_DQ<21>")
	)
	(segment
		(start 215.593168 -23.365968)
		(end 215.593168 -24.333454)
		(width 0.14224)
		(layer "In2.Cu")
		(net "M_A_DQ<21>")
	)
	(segment
		(start 216.381838 -18.053304)
		(end 216.381838 -18.4658)
		(width 0.14224)
		(layer "In2.Cu")
		(net "M_A_DQ<21>")
	)
	(segment
		(start 230.213154 -58.522108)
		(end 231.268524 -58.522108)
		(width 0.14224)
		(layer "In2.Cu")
		(net "M_A_DQ<21>")
	)
	(segment
		(start 233.273346 -59.457336)
		(end 234.771438 -59.457336)
		(width 0.0889)
		(layer "In2.Cu")
		(net "M_A_DQ<21>")
	)
	(segment
		(start 215.670638 -17.653)
		(end 215.981534 -17.653)
		(width 0.14224)
		(layer "In2.Cu")
		(net "M_A_DQ<21>")
	)
	(segment
		(start 215.389968 -22.762972)
		(end 215.389968 -23.162768)
		(width 0.14224)
		(layer "In2.Cu")
		(net "M_A_DQ<21>")
	)
	(segment
		(start 231.347264 -58.522108)
		(end 231.699308 -58.874152)
		(width 0.0889)
		(layer "In2.Cu")
		(net "M_A_DQ<21>")
	)
	(segment
		(start 236.452918 -59.457336)
		(end 236.485684 -59.457336)
		(width 0.0889)
		(layer "In2.Cu")
		(net "M_A_DQ<21>")
	)
	(arc
		(start 234.771438 -59.457336)
		(mid 235.056862 -59.540803)
		(end 235.265468 -59.752738)
		(width 0.0889)
		(layer "In2.Cu")
		(net "M_A_DQ<21>")
	)
	(arc
		(start 236.485684 -59.457336)
		(mid 236.677326 -59.40017)
		(end 236.817408 -59.257438)
		(width 0.0889)
		(layer "In2.Cu")
		(net "M_A_DQ<21>")
	)
	(arc
		(start 235.265468 -59.752738)
		(mid 235.416829 -59.902133)
		(end 235.623354 -59.95289)
		(width 0.0889)
		(layer "In2.Cu")
		(net "M_A_DQ<21>")
	)
	(arc
		(start 235.623354 -59.95289)
		(mid 235.817204 -59.89654)
		(end 235.958888 -59.752738)
		(width 0.0889)
		(layer "In2.Cu")
		(net "M_A_DQ<21>")
	)
	(arc
		(start 235.958888 -59.752738)
		(mid 236.167496 -59.540806)
		(end 236.452918 -59.457336)
		(width 0.0889)
		(layer "In2.Cu")
		(net "M_A_DQ<21>")
	)
	(arc
		(start 236.982508 -58.362088)
		(mid 237.121252 -58.220055)
		(end 237.311184 -58.16219)
		(width 0.0889)
		(layer "In2.Cu")
		(net "M_A_DQ<21>")
	)
	(arc
		(start 236.817408 -59.257438)
		(mid 236.849031 -59.188179)
		(end 236.866938 -59.114182)
		(width 0.0889)
		(layer "In2.Cu")
		(net "M_A_DQ<21>")
	)
	(segment
		(start 237.900718 -58.561986)
		(end 237.329218 -58.561986)
		(width 0.1016)
		(layer "F.Cu")
		(net "M_A_DQ<20>")
	)
	(segment
		(start 215.950292 -20.023582)
		(end 215.949784 -20.023582)
		(width 0.1651)
		(layer "F.Cu")
		(net "M_A_DQ<20>")
	)
	(segment
		(start 215.949784 -20.023582)
		(end 215.949784 -18.692368)
		(width 0.1651)
		(layer "F.Cu")
		(net "M_A_DQ<20>")
	)
	(segment
		(start 215.949784 -18.692368)
		(end 215.85174 -18.161)
		(width 0.1651)
		(layer "F.Cu")
		(net "M_A_DQ<20>")
	)
	(via
		(at 237.329218 -58.561986)
		(size 0.508)
		(drill 0.254)
		(layers "F.Cu" "B.Cu")
		(net "M_A_DQ<20>")
	)
	(via
		(at 215.85174 -18.161)
		(size 0.508)
		(drill 0.254)
		(layers "F.Cu" "B.Cu")
		(net "M_A_DQ<20>")
	)
	(via
		(at 215.0999 -23.560278)
		(size 0.508)
		(drill 0.254)
		(layers "F.Cu" "B.Cu")
		(net "M_A_DQ<20>")
	)
	(segment
		(start 215.0999 -24.824182)
		(end 215.0999 -23.560278)
		(width 0.1651)
		(layer "B.Cu")
		(net "M_A_DQ<20>")
	)
	(segment
		(start 215.100408 -24.824182)
		(end 215.0999 -24.824182)
		(width 0.1651)
		(layer "B.Cu")
		(net "M_A_DQ<20>")
	)
	(segment
		(start 215.592406 -20.2692)
		(end 215.592406 -19.9644)
		(width 0.14224)
		(layer "In2.Cu")
		(net "M_A_DQ<20>")
	)
	(segment
		(start 233.195114 -59.647836)
		(end 232.61193 -59.064652)
		(width 0.0889)
		(layer "In2.Cu")
		(net "M_A_DQ<20>")
	)
	(segment
		(start 231.305862 -59.169808)
		(end 229.845362 -59.169808)
		(width 0.14224)
		(layer "In2.Cu")
		(net "M_A_DQ<20>")
	)
	(segment
		(start 235.629958 -60.14339)
		(end 235.594398 -60.14339)
		(width 0.0889)
		(layer "In2.Cu")
		(net "M_A_DQ<20>")
	)
	(segment
		(start 237.329218 -58.561986)
		(end 237.018068 -59.27979)
		(width 0.0889)
		(layer "In2.Cu")
		(net "M_A_DQ<20>")
	)
	(segment
		(start 215.0999 -23.560278)
		(end 214.864188 -23.324566)
		(width 0.14224)
		(layer "In2.Cu")
		(net "M_A_DQ<20>")
	)
	(segment
		(start 215.224106 -20.6375)
		(end 215.592406 -20.2692)
		(width 0.14224)
		(layer "In2.Cu")
		(net "M_A_DQ<20>")
	)
	(segment
		(start 214.704168 -23.95601)
		(end 215.0999 -23.560278)
		(width 0.14224)
		(layer "In2.Cu")
		(net "M_A_DQ<20>")
	)
	(segment
		(start 215.211406 -19.278854)
		(end 215.575388 -18.914872)
		(width 0.14224)
		(layer "In2.Cu")
		(net "M_A_DQ<20>")
	)
	(segment
		(start 234.764834 -59.647836)
		(end 233.195114 -59.647836)
		(width 0.0889)
		(layer "In2.Cu")
		(net "M_A_DQ<20>")
	)
	(segment
		(start 215.575388 -21.344128)
		(end 215.224106 -20.992846)
		(width 0.14224)
		(layer "In2.Cu")
		(net "M_A_DQ<20>")
	)
	(segment
		(start 229.845362 -59.169808)
		(end 214.704168 -44.028614)
		(width 0.14224)
		(layer "In2.Cu")
		(net "M_A_DQ<20>")
	)
	(segment
		(start 215.211406 -19.5834)
		(end 215.211406 -19.278854)
		(width 0.14224)
		(layer "In2.Cu")
		(net "M_A_DQ<20>")
	)
	(segment
		(start 214.864188 -23.324566)
		(end 214.864188 -22.530054)
		(width 0.14224)
		(layer "In2.Cu")
		(net "M_A_DQ<20>")
	)
	(segment
		(start 214.864188 -22.530054)
		(end 215.575388 -21.818854)
		(width 0.14224)
		(layer "In2.Cu")
		(net "M_A_DQ<20>")
	)
	(segment
		(start 215.575388 -18.437352)
		(end 215.85174 -18.161)
		(width 0.14224)
		(layer "In2.Cu")
		(net "M_A_DQ<20>")
	)
	(segment
		(start 232.61193 -59.064652)
		(end 231.510332 -59.064652)
		(width 0.0889)
		(layer "In2.Cu")
		(net "M_A_DQ<20>")
	)
	(segment
		(start 236.492288 -59.647836)
		(end 236.459522 -59.647836)
		(width 0.0889)
		(layer "In2.Cu")
		(net "M_A_DQ<20>")
	)
	(segment
		(start 231.405176 -59.169808)
		(end 231.305862 -59.169808)
		(width 0.0889)
		(layer "In2.Cu")
		(net "M_A_DQ<20>")
	)
	(segment
		(start 214.704168 -44.028614)
		(end 214.704168 -23.95601)
		(width 0.14224)
		(layer "In2.Cu")
		(net "M_A_DQ<20>")
	)
	(segment
		(start 231.510332 -59.064652)
		(end 231.405176 -59.169808)
		(width 0.0889)
		(layer "In2.Cu")
		(net "M_A_DQ<20>")
	)
	(segment
		(start 215.592406 -19.9644)
		(end 215.211406 -19.5834)
		(width 0.14224)
		(layer "In2.Cu")
		(net "M_A_DQ<20>")
	)
	(segment
		(start 215.575388 -21.818854)
		(end 215.575388 -21.344128)
		(width 0.14224)
		(layer "In2.Cu")
		(net "M_A_DQ<20>")
	)
	(segment
		(start 215.224106 -20.992846)
		(end 215.224106 -20.6375)
		(width 0.14224)
		(layer "In2.Cu")
		(net "M_A_DQ<20>")
	)
	(segment
		(start 215.575388 -18.914872)
		(end 215.575388 -18.437352)
		(width 0.14224)
		(layer "In2.Cu")
		(net "M_A_DQ<20>")
	)
	(arc
		(start 235.100368 -59.847988)
		(mid 234.958685 -59.704184)
		(end 234.764834 -59.647836)
		(width 0.0889)
		(layer "In2.Cu")
		(net "M_A_DQ<20>")
	)
	(arc
		(start 236.459522 -59.647836)
		(mid 236.265672 -59.704186)
		(end 236.123988 -59.847988)
		(width 0.0889)
		(layer "In2.Cu")
		(net "M_A_DQ<20>")
	)
	(arc
		(start 236.123988 -59.847988)
		(mid 235.91538 -60.05992)
		(end 235.629958 -60.14339)
		(width 0.0889)
		(layer "In2.Cu")
		(net "M_A_DQ<20>")
	)
	(arc
		(start 236.982508 -59.352688)
		(mid 236.775504 -59.563552)
		(end 236.492288 -59.647836)
		(width 0.0889)
		(layer "In2.Cu")
		(net "M_A_DQ<20>")
	)
	(arc
		(start 235.594398 -60.14339)
		(mid 235.308974 -60.059923)
		(end 235.100368 -59.847988)
		(width 0.0889)
		(layer "In2.Cu")
		(net "M_A_DQ<20>")
	)
	(arc
		(start 237.018068 -59.27979)
		(mid 237.001541 -59.31685)
		(end 236.982508 -59.352688)
		(width 0.0889)
		(layer "In2.Cu")
		(net "M_A_DQ<20>")
	)
	(segment
		(start 234.466638 -65.49644)
		(end 233.895138 -65.49644)
		(width 0.1016)
		(layer "F.Cu")
		(net "M_A_DQ<1>")
	)
	(segment
		(start 198.100442 -15.423642)
		(end 198.099934 -15.423642)
		(width 0.1651)
		(layer "F.Cu")
		(net "M_A_DQ<1>")
	)
	(segment
		(start 198.099934 -15.423642)
		(end 198.099934 -16.687546)
		(width 0.1651)
		(layer "F.Cu")
		(net "M_A_DQ<1>")
	)
	(via
		(at 198.772018 -22.279356)
		(size 0.508)
		(drill 0.254)
		(layers "F.Cu" "B.Cu")
		(net "M_A_DQ<1>")
	)
	(via
		(at 198.099934 -16.687546)
		(size 0.508)
		(drill 0.254)
		(layers "F.Cu" "B.Cu")
		(net "M_A_DQ<1>")
	)
	(via
		(at 233.895138 -65.49644)
		(size 0.508)
		(drill 0.254)
		(layers "F.Cu" "B.Cu")
		(net "M_A_DQ<1>")
	)
	(segment
		(start 198.772018 -21.776182)
		(end 198.772018 -22.279356)
		(width 0.1651)
		(layer "B.Cu")
		(net "M_A_DQ<1>")
	)
	(segment
		(start 198.950326 -20.224242)
		(end 198.949818 -20.224242)
		(width 0.1651)
		(layer "B.Cu")
		(net "M_A_DQ<1>")
	)
	(segment
		(start 198.949818 -20.224242)
		(end 198.949818 -21.598382)
		(width 0.1651)
		(layer "B.Cu")
		(net "M_A_DQ<1>")
	)
	(segment
		(start 198.949818 -21.598382)
		(end 198.772018 -21.776182)
		(width 0.1651)
		(layer "B.Cu")
		(net "M_A_DQ<1>")
	)
	(segment
		(start 198.5772 -17.7038)
		(end 198.099934 -17.226534)
		(width 0.14224)
		(layer "In2.Cu")
		(net "M_A_DQ<1>")
	)
	(segment
		(start 198.244968 -26.256742)
		(end 198.829168 -26.256742)
		(width 0.14224)
		(layer "In2.Cu")
		(net "M_A_DQ<1>")
	)
	(segment
		(start 199.032368 -26.053542)
		(end 199.032368 -25.744424)
		(width 0.14224)
		(layer "In2.Cu")
		(net "M_A_DQ<1>")
	)
	(segment
		(start 230.632 -65.497202)
		(end 228.303074 -65.497202)
		(width 0.14224)
		(layer "In2.Cu")
		(net "M_A_DQ<1>")
	)
	(segment
		(start 199.133968 -27.272742)
		(end 198.829168 -26.967942)
		(width 0.14224)
		(layer "In2.Cu")
		(net "M_A_DQ<1>")
	)
	(segment
		(start 198.624952 -25.337008)
		(end 198.624952 -23.466552)
		(width 0.14224)
		(layer "In2.Cu")
		(net "M_A_DQ<1>")
	)
	(segment
		(start 232.840784 -65.49644)
		(end 232.358946 -65.014602)
		(width 0.0889)
		(layer "In2.Cu")
		(net "M_A_DQ<1>")
	)
	(segment
		(start 198.9328 -17.7038)
		(end 198.5772 -17.7038)
		(width 0.14224)
		(layer "In2.Cu")
		(net "M_A_DQ<1>")
	)
	(segment
		(start 232.358946 -65.014602)
		(end 231.746044 -65.014602)
		(width 0.0889)
		(layer "In2.Cu")
		(net "M_A_DQ<1>")
	)
	(segment
		(start 198.295768 -22.755606)
		(end 198.772018 -22.279356)
		(width 0.14224)
		(layer "In2.Cu")
		(net "M_A_DQ<1>")
	)
	(segment
		(start 199.302624 -18.073624)
		(end 198.9328 -17.7038)
		(width 0.14224)
		(layer "In2.Cu")
		(net "M_A_DQ<1>")
	)
	(segment
		(start 198.244968 -26.967942)
		(end 198.041768 -26.764742)
		(width 0.14224)
		(layer "In2.Cu")
		(net "M_A_DQ<1>")
	)
	(segment
		(start 198.772018 -22.279356)
		(end 199.14616 -21.905214)
		(width 0.14224)
		(layer "In2.Cu")
		(net "M_A_DQ<1>")
	)
	(segment
		(start 199.133968 -36.328096)
		(end 199.133968 -27.272742)
		(width 0.14224)
		(layer "In2.Cu")
		(net "M_A_DQ<1>")
	)
	(segment
		(start 228.303074 -65.497202)
		(end 199.133968 -36.328096)
		(width 0.14224)
		(layer "In2.Cu")
		(net "M_A_DQ<1>")
	)
	(segment
		(start 198.829168 -26.967942)
		(end 198.244968 -26.967942)
		(width 0.14224)
		(layer "In2.Cu")
		(net "M_A_DQ<1>")
	)
	(segment
		(start 198.041768 -26.459942)
		(end 198.244968 -26.256742)
		(width 0.14224)
		(layer "In2.Cu")
		(net "M_A_DQ<1>")
	)
	(segment
		(start 198.295768 -23.137368)
		(end 198.295768 -22.755606)
		(width 0.14224)
		(layer "In2.Cu")
		(net "M_A_DQ<1>")
	)
	(segment
		(start 199.14616 -21.905214)
		(end 199.14616 -18.571464)
		(width 0.14224)
		(layer "In2.Cu")
		(net "M_A_DQ<1>")
	)
	(segment
		(start 198.624952 -23.466552)
		(end 198.295768 -23.137368)
		(width 0.14224)
		(layer "In2.Cu")
		(net "M_A_DQ<1>")
	)
	(segment
		(start 198.829168 -26.256742)
		(end 199.032368 -26.053542)
		(width 0.14224)
		(layer "In2.Cu")
		(net "M_A_DQ<1>")
	)
	(segment
		(start 233.895138 -65.49644)
		(end 232.840784 -65.49644)
		(width 0.0889)
		(layer "In2.Cu")
		(net "M_A_DQ<1>")
	)
	(segment
		(start 198.041768 -26.764742)
		(end 198.041768 -26.459942)
		(width 0.14224)
		(layer "In2.Cu")
		(net "M_A_DQ<1>")
	)
	(segment
		(start 231.746044 -65.014602)
		(end 231.263444 -65.497202)
		(width 0.0889)
		(layer "In2.Cu")
		(net "M_A_DQ<1>")
	)
	(segment
		(start 231.263444 -65.497202)
		(end 230.632 -65.497202)
		(width 0.0889)
		(layer "In2.Cu")
		(net "M_A_DQ<1>")
	)
	(segment
		(start 199.032368 -25.744424)
		(end 198.624952 -25.337008)
		(width 0.14224)
		(layer "In2.Cu")
		(net "M_A_DQ<1>")
	)
	(segment
		(start 198.099934 -17.226534)
		(end 198.099934 -16.687546)
		(width 0.14224)
		(layer "In2.Cu")
		(net "M_A_DQ<1>")
	)
	(segment
		(start 199.302624 -18.415)
		(end 199.302624 -18.073624)
		(width 0.14224)
		(layer "In2.Cu")
		(net "M_A_DQ<1>")
	)
	(segment
		(start 199.14616 -18.571464)
		(end 199.302624 -18.415)
		(width 0.14224)
		(layer "In2.Cu")
		(net "M_A_DQ<1>")
	)
	(segment
		(start 222.75038 -15.423642)
		(end 222.749872 -15.423642)
		(width 0.1651)
		(layer "F.Cu")
		(net "M_A_DQ<19>")
	)
	(segment
		(start 237.042198 -55.094886)
		(end 236.470698 -55.094886)
		(width 0.1016)
		(layer "F.Cu")
		(net "M_A_DQ<19>")
	)
	(segment
		(start 222.749872 -15.423642)
		(end 222.749872 -16.687546)
		(width 0.1651)
		(layer "F.Cu")
		(net "M_A_DQ<19>")
	)
	(via
		(at 223.599756 -22.279356)
		(size 0.508)
		(drill 0.254)
		(layers "F.Cu" "B.Cu")
		(net "M_A_DQ<19>")
	)
	(via
		(at 222.749872 -16.687546)
		(size 0.508)
		(drill 0.254)
		(layers "F.Cu" "B.Cu")
		(net "M_A_DQ<19>")
	)
	(via
		(at 236.470698 -55.094886)
		(size 0.508)
		(drill 0.254)
		(layers "F.Cu" "B.Cu")
		(net "M_A_DQ<19>")
	)
	(segment
		(start 223.600518 -22.278594)
		(end 223.599756 -22.279356)
		(width 0.1651)
		(layer "B.Cu")
		(net "M_A_DQ<19>")
	)
	(segment
		(start 223.600518 -20.224242)
		(end 223.600518 -22.278594)
		(width 0.1651)
		(layer "B.Cu")
		(net "M_A_DQ<19>")
	)
	(segment
		(start 233.908092 -53.018436)
		(end 233.883962 -53.018436)
		(width 0.0889)
		(layer "In2.Cu")
		(net "M_A_DQ<19>")
	)
	(segment
		(start 223.482662 -42.685462)
		(end 223.482662 -42.022268)
		(width 0.14224)
		(layer "In2.Cu")
		(net "M_A_DQ<19>")
	)
	(segment
		(start 223.482662 -37.071808)
		(end 223.482662 -28.0416)
		(width 0.14224)
		(layer "In2.Cu")
		(net "M_A_DQ<19>")
	)
	(segment
		(start 223.06661 -17.3228)
		(end 223.06661 -17.004284)
		(width 0.14224)
		(layer "In2.Cu")
		(net "M_A_DQ<19>")
	)
	(segment
		(start 223.314768 -24.419306)
		(end 223.314768 -23.368)
		(width 0.14224)
		(layer "In2.Cu")
		(net "M_A_DQ<19>")
	)
	(segment
		(start 223.482662 -28.0416)
		(end 223.279462 -27.8384)
		(width 0.14224)
		(layer "In2.Cu")
		(net "M_A_DQ<19>")
	)
	(segment
		(start 236.470698 -55.094886)
		(end 236.177582 -55.26405)
		(width 0.0889)
		(layer "In2.Cu")
		(net "M_A_DQ<19>")
	)
	(segment
		(start 236.177582 -55.26405)
		(end 236.088174 -55.23992)
		(width 0.0889)
		(layer "In2.Cu")
		(net "M_A_DQ<19>")
	)
	(segment
		(start 223.06661 -17.004284)
		(end 222.749872 -16.687546)
		(width 0.14224)
		(layer "In2.Cu")
		(net "M_A_DQ<19>")
	)
	(segment
		(start 223.11614 -22.762972)
		(end 223.599756 -22.279356)
		(width 0.14224)
		(layer "In2.Cu")
		(net "M_A_DQ<19>")
	)
	(segment
		(start 233.428794 -52.58816)
		(end 233.428794 -51.842416)
		(width 0.0889)
		(layer "In2.Cu")
		(net "M_A_DQ<19>")
	)
	(segment
		(start 223.637602 -37.889688)
		(end 223.92386 -37.889688)
		(width 0.14224)
		(layer "In2.Cu")
		(net "M_A_DQ<19>")
	)
	(segment
		(start 223.482662 -39.723568)
		(end 223.482662 -39.370508)
		(width 0.14224)
		(layer "In2.Cu")
		(net "M_A_DQ<19>")
	)
	(segment
		(start 223.637602 -38.552628)
		(end 223.482662 -38.397688)
		(width 0.14224)
		(layer "In2.Cu")
		(net "M_A_DQ<19>")
	)
	(segment
		(start 227.966778 -46.3804)
		(end 227.1776 -46.3804)
		(width 0.14224)
		(layer "In2.Cu")
		(net "M_A_DQ<19>")
	)
	(segment
		(start 222.263462 -27.8384)
		(end 222.060262 -27.6352)
		(width 0.14224)
		(layer "In2.Cu")
		(net "M_A_DQ<19>")
	)
	(segment
		(start 233.428794 -51.842416)
		(end 233.22788 -51.641502)
		(width 0.0889)
		(layer "In2.Cu")
		(net "M_A_DQ<19>")
	)
	(segment
		(start 223.637602 -37.226748)
		(end 223.482662 -37.071808)
		(width 0.14224)
		(layer "In2.Cu")
		(net "M_A_DQ<19>")
	)
	(segment
		(start 222.818706 -25.105106)
		(end 223.076262 -25.362662)
		(width 0.14224)
		(layer "In2.Cu")
		(net "M_A_DQ<19>")
	)
	(segment
		(start 223.92386 -39.878508)
		(end 223.637602 -39.878508)
		(width 0.14224)
		(layer "In2.Cu")
		(net "M_A_DQ<19>")
	)
	(segment
		(start 223.92386 -41.867328)
		(end 224.0788 -41.712388)
		(width 0.14224)
		(layer "In2.Cu")
		(net "M_A_DQ<19>")
	)
	(segment
		(start 233.22788 -51.641502)
		(end 227.966778 -46.3804)
		(width 0.14224)
		(layer "In2.Cu")
		(net "M_A_DQ<19>")
	)
	(segment
		(start 223.482662 -42.022268)
		(end 223.637602 -41.867328)
		(width 0.14224)
		(layer "In2.Cu")
		(net "M_A_DQ<19>")
	)
	(segment
		(start 234.771438 -53.513736)
		(end 234.738672 -53.513736)
		(width 0.0889)
		(layer "In2.Cu")
		(net "M_A_DQ<19>")
	)
	(segment
		(start 223.39681 -17.653)
		(end 223.06661 -17.3228)
		(width 0.14224)
		(layer "In2.Cu")
		(net "M_A_DQ<19>")
	)
	(segment
		(start 223.279462 -27.8384)
		(end 222.263462 -27.8384)
		(width 0.14224)
		(layer "In2.Cu")
		(net "M_A_DQ<19>")
	)
	(segment
		(start 223.314768 -23.368)
		(end 223.11614 -23.169372)
		(width 0.14224)
		(layer "In2.Cu")
		(net "M_A_DQ<19>")
	)
	(segment
		(start 235.633768 -54.99989)
		(end 235.601002 -54.99989)
		(width 0.0889)
		(layer "In2.Cu")
		(net "M_A_DQ<19>")
	)
	(segment
		(start 223.482662 -40.696388)
		(end 223.637602 -40.541448)
		(width 0.14224)
		(layer "In2.Cu")
		(net "M_A_DQ<19>")
	)
	(segment
		(start 223.599756 -22.279356)
		(end 223.952562 -21.92655)
		(width 0.14224)
		(layer "In2.Cu")
		(net "M_A_DQ<19>")
	)
	(segment
		(start 224.0788 -37.381688)
		(end 223.92386 -37.226748)
		(width 0.14224)
		(layer "In2.Cu")
		(net "M_A_DQ<19>")
	)
	(segment
		(start 223.92386 -37.226748)
		(end 223.637602 -37.226748)
		(width 0.14224)
		(layer "In2.Cu")
		(net "M_A_DQ<19>")
	)
	(segment
		(start 223.637602 -40.541448)
		(end 223.92386 -40.541448)
		(width 0.14224)
		(layer "In2.Cu")
		(net "M_A_DQ<19>")
	)
	(segment
		(start 224.10801 -18.4658)
		(end 224.10801 -18.1102)
		(width 0.14224)
		(layer "In2.Cu")
		(net "M_A_DQ<19>")
	)
	(segment
		(start 224.0788 -39.060628)
		(end 224.0788 -38.707568)
		(width 0.14224)
		(layer "In2.Cu")
		(net "M_A_DQ<19>")
	)
	(segment
		(start 223.482662 -38.044628)
		(end 223.637602 -37.889688)
		(width 0.14224)
		(layer "In2.Cu")
		(net "M_A_DQ<19>")
	)
	(segment
		(start 223.482662 -38.397688)
		(end 223.482662 -38.044628)
		(width 0.14224)
		(layer "In2.Cu")
		(net "M_A_DQ<19>")
	)
	(segment
		(start 223.637602 -41.204388)
		(end 223.482662 -41.049448)
		(width 0.14224)
		(layer "In2.Cu")
		(net "M_A_DQ<19>")
	)
	(segment
		(start 222.060262 -25.308306)
		(end 222.263462 -25.105106)
		(width 0.14224)
		(layer "In2.Cu")
		(net "M_A_DQ<19>")
	)
	(segment
		(start 227.1776 -46.3804)
		(end 223.482662 -42.685462)
		(width 0.14224)
		(layer "In2.Cu")
		(net "M_A_DQ<19>")
	)
	(segment
		(start 223.92386 -41.204388)
		(end 223.637602 -41.204388)
		(width 0.14224)
		(layer "In2.Cu")
		(net "M_A_DQ<19>")
	)
	(segment
		(start 224.10801 -18.1102)
		(end 223.65081 -17.653)
		(width 0.14224)
		(layer "In2.Cu")
		(net "M_A_DQ<19>")
	)
	(segment
		(start 224.0788 -40.033448)
		(end 223.92386 -39.878508)
		(width 0.14224)
		(layer "In2.Cu")
		(net "M_A_DQ<19>")
	)
	(segment
		(start 223.11614 -23.169372)
		(end 223.11614 -22.762972)
		(width 0.14224)
		(layer "In2.Cu")
		(net "M_A_DQ<19>")
	)
	(segment
		(start 223.92386 -37.889688)
		(end 224.0788 -37.734748)
		(width 0.14224)
		(layer "In2.Cu")
		(net "M_A_DQ<19>")
	)
	(segment
		(start 222.060262 -27.6352)
		(end 222.060262 -25.308306)
		(width 0.14224)
		(layer "In2.Cu")
		(net "M_A_DQ<19>")
	)
	(segment
		(start 223.482662 -41.049448)
		(end 223.482662 -40.696388)
		(width 0.14224)
		(layer "In2.Cu")
		(net "M_A_DQ<19>")
	)
	(segment
		(start 223.952562 -18.621248)
		(end 224.10801 -18.4658)
		(width 0.14224)
		(layer "In2.Cu")
		(net "M_A_DQ<19>")
	)
	(segment
		(start 223.218502 -27.178)
		(end 223.645222 -27.178)
		(width 0.14224)
		(layer "In2.Cu")
		(net "M_A_DQ<19>")
	)
	(segment
		(start 223.482662 -39.370508)
		(end 223.637602 -39.215568)
		(width 0.14224)
		(layer "In2.Cu")
		(net "M_A_DQ<19>")
	)
	(segment
		(start 223.076262 -25.362662)
		(end 223.076262 -27.03576)
		(width 0.14224)
		(layer "In2.Cu")
		(net "M_A_DQ<19>")
	)
	(segment
		(start 222.263462 -25.105106)
		(end 222.818706 -25.105106)
		(width 0.14224)
		(layer "In2.Cu")
		(net "M_A_DQ<19>")
	)
	(segment
		(start 223.645222 -27.178)
		(end 223.787462 -27.03576)
		(width 0.14224)
		(layer "In2.Cu")
		(net "M_A_DQ<19>")
	)
	(segment
		(start 223.787462 -24.892)
		(end 223.314768 -24.419306)
		(width 0.14224)
		(layer "In2.Cu")
		(net "M_A_DQ<19>")
	)
	(segment
		(start 233.5022 -52.729384)
		(end 233.428794 -52.58816)
		(width 0.0889)
		(layer "In2.Cu")
		(net "M_A_DQ<19>")
	)
	(segment
		(start 223.92386 -39.215568)
		(end 224.0788 -39.060628)
		(width 0.14224)
		(layer "In2.Cu")
		(net "M_A_DQ<19>")
	)
	(segment
		(start 223.076262 -27.03576)
		(end 223.218502 -27.178)
		(width 0.14224)
		(layer "In2.Cu")
		(net "M_A_DQ<19>")
	)
	(segment
		(start 233.548428 -52.818284)
		(end 233.5022 -52.729384)
		(width 0.0889)
		(layer "In2.Cu")
		(net "M_A_DQ<19>")
	)
	(segment
		(start 223.92386 -40.541448)
		(end 224.0788 -40.386508)
		(width 0.14224)
		(layer "In2.Cu")
		(net "M_A_DQ<19>")
	)
	(segment
		(start 223.65081 -17.653)
		(end 223.39681 -17.653)
		(width 0.14224)
		(layer "In2.Cu")
		(net "M_A_DQ<19>")
	)
	(segment
		(start 224.0788 -38.707568)
		(end 223.92386 -38.552628)
		(width 0.14224)
		(layer "In2.Cu")
		(net "M_A_DQ<19>")
	)
	(segment
		(start 224.0788 -37.734748)
		(end 224.0788 -37.381688)
		(width 0.14224)
		(layer "In2.Cu")
		(net "M_A_DQ<19>")
	)
	(segment
		(start 223.637602 -39.878508)
		(end 223.482662 -39.723568)
		(width 0.14224)
		(layer "In2.Cu")
		(net "M_A_DQ<19>")
	)
	(segment
		(start 224.0788 -40.386508)
		(end 224.0788 -40.033448)
		(width 0.14224)
		(layer "In2.Cu")
		(net "M_A_DQ<19>")
	)
	(segment
		(start 223.92386 -38.552628)
		(end 223.637602 -38.552628)
		(width 0.14224)
		(layer "In2.Cu")
		(net "M_A_DQ<19>")
	)
	(segment
		(start 223.637602 -39.215568)
		(end 223.92386 -39.215568)
		(width 0.14224)
		(layer "In2.Cu")
		(net "M_A_DQ<19>")
	)
	(segment
		(start 223.637602 -41.867328)
		(end 223.92386 -41.867328)
		(width 0.14224)
		(layer "In2.Cu")
		(net "M_A_DQ<19>")
	)
	(segment
		(start 224.0788 -41.359328)
		(end 223.92386 -41.204388)
		(width 0.14224)
		(layer "In2.Cu")
		(net "M_A_DQ<19>")
	)
	(segment
		(start 224.0788 -41.712388)
		(end 224.0788 -41.359328)
		(width 0.14224)
		(layer "In2.Cu")
		(net "M_A_DQ<19>")
	)
	(segment
		(start 223.952562 -21.92655)
		(end 223.952562 -18.621248)
		(width 0.14224)
		(layer "In2.Cu")
		(net "M_A_DQ<19>")
	)
	(segment
		(start 223.787462 -27.03576)
		(end 223.787462 -24.892)
		(width 0.14224)
		(layer "In2.Cu")
		(net "M_A_DQ<19>")
	)
	(arc
		(start 233.883962 -53.018436)
		(mid 233.690112 -52.962086)
		(end 233.548428 -52.818284)
		(width 0.0889)
		(layer "In2.Cu")
		(net "M_A_DQ<19>")
	)
	(arc
		(start 234.738672 -53.513736)
		(mid 234.54703 -53.45657)
		(end 234.406948 -53.313838)
		(width 0.0889)
		(layer "In2.Cu")
		(net "M_A_DQ<19>")
	)
	(arc
		(start 234.406948 -53.313838)
		(mid 234.196235 -53.100759)
		(end 233.908092 -53.018436)
		(width 0.0889)
		(layer "In2.Cu")
		(net "M_A_DQ<19>")
	)
	(arc
		(start 236.088174 -55.23992)
		(mid 235.888429 -55.067926)
		(end 235.633768 -54.99989)
		(width 0.0889)
		(layer "In2.Cu")
		(net "M_A_DQ<19>")
	)
	(arc
		(start 235.265468 -54.399688)
		(mid 235.269797 -53.816516)
		(end 234.771438 -53.513736)
		(width 0.0889)
		(layer "In2.Cu")
		(net "M_A_DQ<19>")
	)
	(arc
		(start 235.601002 -54.99989)
		(mid 235.262833 -54.795092)
		(end 235.265468 -54.399688)
		(width 0.0889)
		(layer "In2.Cu")
		(net "M_A_DQ<19>")
	)
	(segment
		(start 223.600518 -20.023582)
		(end 223.600518 -18.263362)
		(width 0.1651)
		(layer "F.Cu")
		(net "M_A_DQ<18>")
	)
	(segment
		(start 223.600518 -18.263362)
		(end 223.599756 -18.2626)
		(width 0.1651)
		(layer "F.Cu")
		(net "M_A_DQ<18>")
	)
	(segment
		(start 236.183678 -55.59044)
		(end 235.612178 -55.59044)
		(width 0.1016)
		(layer "F.Cu")
		(net "M_A_DQ<18>")
	)
	(via
		(at 222.749872 -23.560278)
		(size 0.508)
		(drill 0.254)
		(layers "F.Cu" "B.Cu")
		(net "M_A_DQ<18>")
	)
	(via
		(at 235.612178 -55.59044)
		(size 0.508)
		(drill 0.254)
		(layers "F.Cu" "B.Cu")
		(net "M_A_DQ<18>")
	)
	(via
		(at 223.599756 -18.2626)
		(size 0.508)
		(drill 0.254)
		(layers "F.Cu" "B.Cu")
		(net "M_A_DQ<18>")
	)
	(segment
		(start 222.75038 -24.824182)
		(end 222.749872 -24.824182)
		(width 0.1651)
		(layer "B.Cu")
		(net "M_A_DQ<18>")
	)
	(segment
		(start 222.749872 -24.824182)
		(end 222.749872 -23.560278)
		(width 0.1651)
		(layer "B.Cu")
		(net "M_A_DQ<18>")
	)
	(segment
		(start 222.465138 -23.275544)
		(end 222.465138 -22.5298)
		(width 0.14224)
		(layer "In2.Cu")
		(net "M_A_DQ<18>")
	)
	(segment
		(start 221.933262 -33.8328)
		(end 221.628462 -33.8328)
		(width 0.14224)
		(layer "In2.Cu")
		(net "M_A_DQ<18>")
	)
	(segment
		(start 222.856806 -19.310604)
		(end 223.201738 -18.965672)
		(width 0.14224)
		(layer "In2.Cu")
		(net "M_A_DQ<18>")
	)
	(segment
		(start 223.314006 -21.4122)
		(end 222.856806 -20.955)
		(width 0.14224)
		(layer "In2.Cu")
		(net "M_A_DQ<18>")
	)
	(segment
		(start 222.856806 -19.659346)
		(end 222.856806 -19.310604)
		(width 0.14224)
		(layer "In2.Cu")
		(net "M_A_DQ<18>")
	)
	(segment
		(start 233.3498 -52.861718)
		(end 233.264456 -52.729384)
		(width 0.0889)
		(layer "In2.Cu")
		(net "M_A_DQ<18>")
	)
	(segment
		(start 232.932224 -52.262024)
		(end 228.0666 -47.3964)
		(width 0.14224)
		(layer "In2.Cu")
		(net "M_A_DQ<18>")
	)
	(segment
		(start 223.201738 -18.660618)
		(end 223.599756 -18.2626)
		(width 0.14224)
		(layer "In2.Cu")
		(net "M_A_DQ<18>")
	)
	(segment
		(start 223.161606 -20.25015)
		(end 223.161606 -19.964146)
		(width 0.14224)
		(layer "In2.Cu")
		(net "M_A_DQ<18>")
	)
	(segment
		(start 235.612178 -55.59044)
		(end 235.905294 -55.421276)
		(width 0.0889)
		(layer "In2.Cu")
		(net "M_A_DQ<18>")
	)
	(segment
		(start 222.749872 -23.82012)
		(end 222.749872 -23.560278)
		(width 0.14224)
		(layer "In2.Cu")
		(net "M_A_DQ<18>")
	)
	(segment
		(start 235.627164 -55.19039)
		(end 235.594398 -55.19039)
		(width 0.0889)
		(layer "In2.Cu")
		(net "M_A_DQ<18>")
	)
	(segment
		(start 222.856806 -20.955)
		(end 222.856806 -20.55495)
		(width 0.14224)
		(layer "In2.Cu")
		(net "M_A_DQ<18>")
	)
	(segment
		(start 223.201738 -18.965672)
		(end 223.201738 -18.660618)
		(width 0.14224)
		(layer "In2.Cu")
		(net "M_A_DQ<18>")
	)
	(segment
		(start 223.314006 -21.680932)
		(end 223.314006 -21.4122)
		(width 0.14224)
		(layer "In2.Cu")
		(net "M_A_DQ<18>")
	)
	(segment
		(start 227.2538 -47.3964)
		(end 222.847662 -42.990262)
		(width 0.14224)
		(layer "In2.Cu")
		(net "M_A_DQ<18>")
	)
	(segment
		(start 233.383328 -52.913788)
		(end 233.3498 -52.861718)
		(width 0.0889)
		(layer "In2.Cu")
		(net "M_A_DQ<18>")
	)
	(segment
		(start 223.161606 -19.964146)
		(end 222.856806 -19.659346)
		(width 0.14224)
		(layer "In2.Cu")
		(net "M_A_DQ<18>")
	)
	(segment
		(start 233.910124 -53.20919)
		(end 233.882184 -53.20919)
		(width 0.0889)
		(layer "In2.Cu")
		(net "M_A_DQ<18>")
	)
	(segment
		(start 222.847662 -28.6004)
		(end 222.644462 -28.3972)
		(width 0.14224)
		(layer "In2.Cu")
		(net "M_A_DQ<18>")
	)
	(segment
		(start 222.339662 -28.3972)
		(end 222.136462 -28.6004)
		(width 0.14224)
		(layer "In2.Cu")
		(net "M_A_DQ<18>")
	)
	(segment
		(start 233.264456 -52.729384)
		(end 232.932224 -52.262024)
		(width 0.0889)
		(layer "In2.Cu")
		(net "M_A_DQ<18>")
	)
	(segment
		(start 222.644462 -28.3972)
		(end 222.339662 -28.3972)
		(width 0.14224)
		(layer "In2.Cu")
		(net "M_A_DQ<18>")
	)
	(segment
		(start 221.628462 -33.8328)
		(end 221.409768 -33.614106)
		(width 0.14224)
		(layer "In2.Cu")
		(net "M_A_DQ<18>")
	)
	(segment
		(start 222.856806 -20.55495)
		(end 223.161606 -20.25015)
		(width 0.14224)
		(layer "In2.Cu")
		(net "M_A_DQ<18>")
	)
	(segment
		(start 222.136462 -28.6004)
		(end 222.136462 -33.6296)
		(width 0.14224)
		(layer "In2.Cu")
		(net "M_A_DQ<18>")
	)
	(segment
		(start 235.905294 -55.421276)
		(end 235.926376 -55.342536)
		(width 0.0889)
		(layer "In2.Cu")
		(net "M_A_DQ<18>")
	)
	(segment
		(start 234.764834 -53.704236)
		(end 234.732068 -53.704236)
		(width 0.0889)
		(layer "In2.Cu")
		(net "M_A_DQ<18>")
	)
	(segment
		(start 222.847662 -42.990262)
		(end 222.847662 -28.6004)
		(width 0.14224)
		(layer "In2.Cu")
		(net "M_A_DQ<18>")
	)
	(segment
		(start 222.136462 -33.6296)
		(end 221.933262 -33.8328)
		(width 0.14224)
		(layer "In2.Cu")
		(net "M_A_DQ<18>")
	)
	(segment
		(start 222.749872 -23.560278)
		(end 222.465138 -23.275544)
		(width 0.14224)
		(layer "In2.Cu")
		(net "M_A_DQ<18>")
	)
	(segment
		(start 222.465138 -22.5298)
		(end 223.314006 -21.680932)
		(width 0.14224)
		(layer "In2.Cu")
		(net "M_A_DQ<18>")
	)
	(segment
		(start 228.0666 -47.3964)
		(end 227.2538 -47.3964)
		(width 0.14224)
		(layer "In2.Cu")
		(net "M_A_DQ<18>")
	)
	(segment
		(start 221.409768 -25.160224)
		(end 222.749872 -23.82012)
		(width 0.14224)
		(layer "In2.Cu")
		(net "M_A_DQ<18>")
	)
	(segment
		(start 221.409768 -33.614106)
		(end 221.409768 -25.160224)
		(width 0.14224)
		(layer "In2.Cu")
		(net "M_A_DQ<18>")
	)
	(arc
		(start 234.241848 -53.409088)
		(mid 234.101769 -53.266352)
		(end 233.910124 -53.20919)
		(width 0.0889)
		(layer "In2.Cu")
		(net "M_A_DQ<18>")
	)
	(arc
		(start 235.100368 -54.304438)
		(mid 235.103116 -53.908971)
		(end 234.764834 -53.704236)
		(width 0.0889)
		(layer "In2.Cu")
		(net "M_A_DQ<18>")
	)
	(arc
		(start 233.882184 -53.20919)
		(mid 233.594039 -53.126871)
		(end 233.383328 -52.913788)
		(width 0.0889)
		(layer "In2.Cu")
		(net "M_A_DQ<18>")
	)
	(arc
		(start 235.594398 -55.19039)
		(mid 235.096147 -54.88755)
		(end 235.100368 -54.304438)
		(width 0.0889)
		(layer "In2.Cu")
		(net "M_A_DQ<18>")
	)
	(arc
		(start 235.926376 -55.342536)
		(mid 235.793495 -55.233553)
		(end 235.627164 -55.19039)
		(width 0.0889)
		(layer "In2.Cu")
		(net "M_A_DQ<18>")
	)
	(arc
		(start 234.732068 -53.704236)
		(mid 234.448851 -53.619955)
		(end 234.241848 -53.409088)
		(width 0.0889)
		(layer "In2.Cu")
		(net "M_A_DQ<18>")
	)
	(segment
		(start 216.799922 -15.423642)
		(end 216.799922 -16.687546)
		(width 0.1651)
		(layer "F.Cu")
		(net "M_A_DQ<17>")
	)
	(segment
		(start 238.759238 -57.076086)
		(end 238.187738 -57.076086)
		(width 0.1016)
		(layer "F.Cu")
		(net "M_A_DQ<17>")
	)
	(segment
		(start 216.80043 -15.423642)
		(end 216.799922 -15.423642)
		(width 0.1651)
		(layer "F.Cu")
		(net "M_A_DQ<17>")
	)
	(via
		(at 216.799922 -16.687546)
		(size 0.508)
		(drill 0.254)
		(layers "F.Cu" "B.Cu")
		(net "M_A_DQ<17>")
	)
	(via
		(at 217.472006 -22.279356)
		(size 0.508)
		(drill 0.254)
		(layers "F.Cu" "B.Cu")
		(net "M_A_DQ<17>")
	)
	(via
		(at 238.187738 -57.076086)
		(size 0.508)
		(drill 0.254)
		(layers "F.Cu" "B.Cu")
		(net "M_A_DQ<17>")
	)
	(segment
		(start 217.649806 -21.598382)
		(end 217.472006 -21.776182)
		(width 0.1651)
		(layer "B.Cu")
		(net "M_A_DQ<17>")
	)
	(segment
		(start 217.472006 -21.776182)
		(end 217.472006 -22.279356)
		(width 0.1651)
		(layer "B.Cu")
		(net "M_A_DQ<17>")
	)
	(segment
		(start 217.649806 -20.224242)
		(end 217.649806 -21.598382)
		(width 0.1651)
		(layer "B.Cu")
		(net "M_A_DQ<17>")
	)
	(segment
		(start 217.650314 -20.224242)
		(end 217.649806 -20.224242)
		(width 0.1651)
		(layer "B.Cu")
		(net "M_A_DQ<17>")
	)
	(segment
		(start 236.880146 -57.768744)
		(end 237.122716 -57.91454)
		(width 0.0889)
		(layer "In2.Cu")
		(net "M_A_DQ<17>")
	)
	(segment
		(start 231.093518 -57.226708)
		(end 231.928924 -58.062114)
		(width 0.0889)
		(layer "In2.Cu")
		(net "M_A_DQ<17>")
	)
	(segment
		(start 217.290396 -23.818596)
		(end 217.015568 -24.093424)
		(width 0.14224)
		(layer "In2.Cu")
		(net "M_A_DQ<17>")
	)
	(segment
		(start 217.290396 -23.412196)
		(end 217.290396 -23.818596)
		(width 0.14224)
		(layer "In2.Cu")
		(net "M_A_DQ<17>")
	)
	(segment
		(start 235.205016 -58.16219)
		(end 235.633768 -58.16219)
		(width 0.0889)
		(layer "In2.Cu")
		(net "M_A_DQ<17>")
	)
	(segment
		(start 230.3018 -56.388)
		(end 230.3018 -56.9722)
		(width 0.14224)
		(layer "In2.Cu")
		(net "M_A_DQ<17>")
	)
	(segment
		(start 217.846148 -21.905214)
		(end 217.472006 -22.279356)
		(width 0.14224)
		(layer "In2.Cu")
		(net "M_A_DQ<17>")
	)
	(segment
		(start 216.659968 -42.746168)
		(end 230.3018 -56.388)
		(width 0.14224)
		(layer "In2.Cu")
		(net "M_A_DQ<17>")
	)
	(segment
		(start 237.675928 -57.771538)
		(end 237.692438 -57.742836)
		(width 0.0889)
		(layer "In2.Cu")
		(net "M_A_DQ<17>")
	)
	(segment
		(start 218.002612 -18.073624)
		(end 218.002612 -18.415)
		(width 0.14224)
		(layer "In2.Cu")
		(net "M_A_DQ<17>")
	)
	(segment
		(start 216.990168 -22.761194)
		(end 216.990168 -23.111968)
		(width 0.14224)
		(layer "In2.Cu")
		(net "M_A_DQ<17>")
	)
	(segment
		(start 216.799922 -16.687546)
		(end 216.799922 -17.226534)
		(width 0.14224)
		(layer "In2.Cu")
		(net "M_A_DQ<17>")
	)
	(segment
		(start 217.277188 -17.7038)
		(end 217.632788 -17.7038)
		(width 0.14224)
		(layer "In2.Cu")
		(net "M_A_DQ<17>")
	)
	(segment
		(start 217.846148 -18.571464)
		(end 217.846148 -21.905214)
		(width 0.14224)
		(layer "In2.Cu")
		(net "M_A_DQ<17>")
	)
	(segment
		(start 217.632788 -17.7038)
		(end 218.002612 -18.073624)
		(width 0.14224)
		(layer "In2.Cu")
		(net "M_A_DQ<17>")
	)
	(segment
		(start 230.556308 -57.226708)
		(end 231.093518 -57.226708)
		(width 0.14224)
		(layer "In2.Cu")
		(net "M_A_DQ<17>")
	)
	(segment
		(start 230.3018 -56.9722)
		(end 230.556308 -57.226708)
		(width 0.14224)
		(layer "In2.Cu")
		(net "M_A_DQ<17>")
	)
	(segment
		(start 216.799922 -17.226534)
		(end 217.277188 -17.7038)
		(width 0.14224)
		(layer "In2.Cu")
		(net "M_A_DQ<17>")
	)
	(segment
		(start 233.021124 -58.062114)
		(end 233.425746 -58.466736)
		(width 0.0889)
		(layer "In2.Cu")
		(net "M_A_DQ<17>")
	)
	(segment
		(start 236.459522 -57.66689)
		(end 236.483652 -57.66689)
		(width 0.0889)
		(layer "In2.Cu")
		(net "M_A_DQ<17>")
	)
	(segment
		(start 217.472006 -22.279356)
		(end 216.990168 -22.761194)
		(width 0.14224)
		(layer "In2.Cu")
		(net "M_A_DQ<17>")
	)
	(segment
		(start 237.692438 -57.742836)
		(end 238.187738 -57.076086)
		(width 0.0889)
		(layer "In2.Cu")
		(net "M_A_DQ<17>")
	)
	(segment
		(start 216.990168 -23.111968)
		(end 217.290396 -23.412196)
		(width 0.14224)
		(layer "In2.Cu")
		(net "M_A_DQ<17>")
	)
	(segment
		(start 233.425746 -58.466736)
		(end 234.771692 -58.466736)
		(width 0.0889)
		(layer "In2.Cu")
		(net "M_A_DQ<17>")
	)
	(segment
		(start 235.100368 -58.266838)
		(end 235.205016 -58.16219)
		(width 0.0889)
		(layer "In2.Cu")
		(net "M_A_DQ<17>")
	)
	(segment
		(start 231.928924 -58.062114)
		(end 233.021124 -58.062114)
		(width 0.0889)
		(layer "In2.Cu")
		(net "M_A_DQ<17>")
	)
	(segment
		(start 237.311184 -57.971436)
		(end 237.347252 -57.971436)
		(width 0.0889)
		(layer "In2.Cu")
		(net "M_A_DQ<17>")
	)
	(segment
		(start 217.015568 -32.606742)
		(end 216.659968 -32.962342)
		(width 0.14224)
		(layer "In2.Cu")
		(net "M_A_DQ<17>")
	)
	(segment
		(start 218.002612 -18.415)
		(end 217.846148 -18.571464)
		(width 0.14224)
		(layer "In2.Cu")
		(net "M_A_DQ<17>")
	)
	(segment
		(start 216.659968 -32.962342)
		(end 216.659968 -42.746168)
		(width 0.14224)
		(layer "In2.Cu")
		(net "M_A_DQ<17>")
	)
	(segment
		(start 217.015568 -24.093424)
		(end 217.015568 -32.606742)
		(width 0.14224)
		(layer "In2.Cu")
		(net "M_A_DQ<17>")
	)
	(arc
		(start 236.483652 -57.66689)
		(mid 236.689327 -57.688896)
		(end 236.880146 -57.768744)
		(width 0.0889)
		(layer "In2.Cu")
		(net "M_A_DQ<17>")
	)
	(arc
		(start 237.347252 -57.971436)
		(mid 237.537181 -57.913566)
		(end 237.675928 -57.771538)
		(width 0.0889)
		(layer "In2.Cu")
		(net "M_A_DQ<17>")
	)
	(arc
		(start 236.123988 -57.867042)
		(mid 236.265671 -57.723238)
		(end 236.459522 -57.66689)
		(width 0.0889)
		(layer "In2.Cu")
		(net "M_A_DQ<17>")
	)
	(arc
		(start 237.122716 -57.91454)
		(mid 237.2134 -57.954737)
		(end 237.311184 -57.971436)
		(width 0.0889)
		(layer "In2.Cu")
		(net "M_A_DQ<17>")
	)
	(arc
		(start 235.633768 -58.16219)
		(mid 235.916985 -58.077909)
		(end 236.123988 -57.867042)
		(width 0.0889)
		(layer "In2.Cu")
		(net "M_A_DQ<17>")
	)
	(arc
		(start 234.771692 -58.466736)
		(mid 234.961621 -58.408866)
		(end 235.100368 -58.266838)
		(width 0.0889)
		(layer "In2.Cu")
		(net "M_A_DQ<17>")
	)
	(segment
		(start 217.569034 -19.177)
		(end 217.472006 -18.161)
		(width 0.1651)
		(layer "F.Cu")
		(net "M_A_DQ<16>")
	)
	(segment
		(start 217.650314 -20.023582)
		(end 217.649806 -20.023582)
		(width 0.1651)
		(layer "F.Cu")
		(net "M_A_DQ<16>")
	)
	(segment
		(start 237.042198 -58.06694)
		(end 236.470698 -58.06694)
		(width 0.1016)
		(layer "F.Cu")
		(net "M_A_DQ<16>")
	)
	(segment
		(start 217.649806 -20.023582)
		(end 217.569034 -19.177)
		(width 0.1651)
		(layer "F.Cu")
		(net "M_A_DQ<16>")
	)
	(via
		(at 216.799922 -23.560278)
		(size 0.508)
		(drill 0.254)
		(layers "F.Cu" "B.Cu")
		(net "M_A_DQ<16>")
	)
	(via
		(at 236.470698 -58.06694)
		(size 0.508)
		(drill 0.254)
		(layers "F.Cu" "B.Cu")
		(net "M_A_DQ<16>")
	)
	(via
		(at 217.472006 -18.161)
		(size 0.508)
		(drill 0.254)
		(layers "F.Cu" "B.Cu")
		(net "M_A_DQ<16>")
	)
	(segment
		(start 216.80043 -24.824182)
		(end 216.799922 -24.824182)
		(width 0.1651)
		(layer "B.Cu")
		(net "M_A_DQ<16>")
	)
	(segment
		(start 216.799922 -24.824182)
		(end 216.799922 -23.560278)
		(width 0.1651)
		(layer "B.Cu")
		(net "M_A_DQ<16>")
	)
	(segment
		(start 216.34196 -27.46375)
		(end 216.09304 -27.46375)
		(width 0.14224)
		(layer "In2.Cu")
		(net "M_A_DQ<16>")
	)
	(segment
		(start 216.4842 -26.95575)
		(end 216.4842 -27.32151)
		(width 0.14224)
		(layer "In2.Cu")
		(net "M_A_DQ<16>")
	)
	(segment
		(start 215.9508 -30.20695)
		(end 215.9508 -30.57271)
		(width 0.14224)
		(layer "In2.Cu")
		(net "M_A_DQ<16>")
	)
	(segment
		(start 215.9508 -29.27223)
		(end 216.09304 -29.41447)
		(width 0.14224)
		(layer "In2.Cu")
		(net "M_A_DQ<16>")
	)
	(segment
		(start 216.862406 -20.903946)
		(end 217.251788 -21.293328)
		(width 0.14224)
		(layer "In2.Cu")
		(net "M_A_DQ<16>")
	)
	(segment
		(start 216.34196 -31.36519)
		(end 216.09304 -31.36519)
		(width 0.14224)
		(layer "In2.Cu")
		(net "M_A_DQ<16>")
	)
	(segment
		(start 216.09304 -28.11399)
		(end 216.34196 -28.11399)
		(width 0.14224)
		(layer "In2.Cu")
		(net "M_A_DQ<16>")
	)
	(segment
		(start 216.4842 -28.25623)
		(end 216.4842 -28.62199)
		(width 0.14224)
		(layer "In2.Cu")
		(net "M_A_DQ<16>")
	)
	(segment
		(start 231.846628 -58.252614)
		(end 232.942892 -58.252614)
		(width 0.0889)
		(layer "In2.Cu")
		(net "M_A_DQ<16>")
	)
	(segment
		(start 216.515188 -23.275544)
		(end 216.799922 -23.560278)
		(width 0.14224)
		(layer "In2.Cu")
		(net "M_A_DQ<16>")
	)
	(segment
		(start 216.34196 -26.81351)
		(end 216.4842 -26.95575)
		(width 0.14224)
		(layer "In2.Cu")
		(net "M_A_DQ<16>")
	)
	(segment
		(start 215.9508 -27.97175)
		(end 216.09304 -28.11399)
		(width 0.14224)
		(layer "In2.Cu")
		(net "M_A_DQ<16>")
	)
	(segment
		(start 215.9508 -26.67127)
		(end 216.09304 -26.81351)
		(width 0.14224)
		(layer "In2.Cu")
		(net "M_A_DQ<16>")
	)
	(segment
		(start 232.942892 -58.252614)
		(end 233.347514 -58.657236)
		(width 0.0889)
		(layer "In2.Cu")
		(net "M_A_DQ<16>")
	)
	(segment
		(start 216.4842 -25.65527)
		(end 216.4842 -26.02103)
		(width 0.14224)
		(layer "In2.Cu")
		(net "M_A_DQ<16>")
	)
	(segment
		(start 216.34196 -29.41447)
		(end 216.4842 -29.55671)
		(width 0.14224)
		(layer "In2.Cu")
		(net "M_A_DQ<16>")
	)
	(segment
		(start 216.09304 -30.71495)
		(end 216.34196 -30.71495)
		(width 0.14224)
		(layer "In2.Cu")
		(net "M_A_DQ<16>")
	)
	(segment
		(start 217.251788 -18.381218)
		(end 217.251788 -18.965672)
		(width 0.14224)
		(layer "In2.Cu")
		(net "M_A_DQ<16>")
	)
	(segment
		(start 235.975398 -58.732928)
		(end 236.470698 -58.06694)
		(width 0.0889)
		(layer "In2.Cu")
		(net "M_A_DQ<16>")
	)
	(segment
		(start 217.179906 -20.2819)
		(end 216.862406 -20.5994)
		(width 0.14224)
		(layer "In2.Cu")
		(net "M_A_DQ<16>")
	)
	(segment
		(start 216.4842 -27.32151)
		(end 216.34196 -27.46375)
		(width 0.14224)
		(layer "In2.Cu")
		(net "M_A_DQ<16>")
	)
	(segment
		(start 216.4842 -30.85719)
		(end 216.4842 -31.22295)
		(width 0.14224)
		(layer "In2.Cu")
		(net "M_A_DQ<16>")
	)
	(segment
		(start 216.09304 -25.51303)
		(end 216.34196 -25.51303)
		(width 0.14224)
		(layer "In2.Cu")
		(net "M_A_DQ<16>")
	)
	(segment
		(start 231.253792 -57.874408)
		(end 231.468422 -57.874408)
		(width 0.0889)
		(layer "In2.Cu")
		(net "M_A_DQ<16>")
	)
	(segment
		(start 215.9508 -26.30551)
		(end 215.9508 -26.67127)
		(width 0.14224)
		(layer "In2.Cu")
		(net "M_A_DQ<16>")
	)
	(segment
		(start 217.472006 -18.161)
		(end 217.251788 -18.381218)
		(width 0.14224)
		(layer "In2.Cu")
		(net "M_A_DQ<16>")
	)
	(segment
		(start 216.09304 -29.41447)
		(end 216.34196 -29.41447)
		(width 0.14224)
		(layer "In2.Cu")
		(net "M_A_DQ<16>")
	)
	(segment
		(start 216.1286 -24.2316)
		(end 216.1286 -24.6634)
		(width 0.14224)
		(layer "In2.Cu")
		(net "M_A_DQ<16>")
	)
	(segment
		(start 235.958888 -58.761884)
		(end 235.975398 -58.732928)
		(width 0.0889)
		(layer "In2.Cu")
		(net "M_A_DQ<16>")
	)
	(segment
		(start 233.347514 -58.657236)
		(end 234.608624 -58.657236)
		(width 0.0889)
		(layer "In2.Cu")
		(net "M_A_DQ<16>")
	)
	(segment
		(start 216.34196 -30.06471)
		(end 216.09304 -30.06471)
		(width 0.14224)
		(layer "In2.Cu")
		(net "M_A_DQ<16>")
	)
	(segment
		(start 215.9508 -28.90647)
		(end 215.9508 -29.27223)
		(width 0.14224)
		(layer "In2.Cu")
		(net "M_A_DQ<16>")
	)
	(segment
		(start 217.179906 -20.0533)
		(end 217.179906 -20.2819)
		(width 0.14224)
		(layer "In2.Cu")
		(net "M_A_DQ<16>")
	)
	(segment
		(start 234.608878 -58.65749)
		(end 234.771438 -58.65749)
		(width 0.0889)
		(layer "In2.Cu")
		(net "M_A_DQ<16>")
	)
	(segment
		(start 216.34196 -26.16327)
		(end 216.09304 -26.16327)
		(width 0.14224)
		(layer "In2.Cu")
		(net "M_A_DQ<16>")
	)
	(segment
		(start 217.251788 -21.293328)
		(end 217.251788 -21.7932)
		(width 0.14224)
		(layer "In2.Cu")
		(net "M_A_DQ<16>")
	)
	(segment
		(start 217.251788 -18.965672)
		(end 216.837006 -19.380454)
		(width 0.14224)
		(layer "In2.Cu")
		(net "M_A_DQ<16>")
	)
	(segment
		(start 216.09304 -26.16327)
		(end 215.9508 -26.30551)
		(width 0.14224)
		(layer "In2.Cu")
		(net "M_A_DQ<16>")
	)
	(segment
		(start 216.34196 -28.11399)
		(end 216.4842 -28.25623)
		(width 0.14224)
		(layer "In2.Cu")
		(net "M_A_DQ<16>")
	)
	(segment
		(start 216.09304 -28.76423)
		(end 215.9508 -28.90647)
		(width 0.14224)
		(layer "In2.Cu")
		(net "M_A_DQ<16>")
	)
	(segment
		(start 215.9508 -30.57271)
		(end 216.09304 -30.71495)
		(width 0.14224)
		(layer "In2.Cu")
		(net "M_A_DQ<16>")
	)
	(segment
		(start 216.09304 -27.46375)
		(end 215.9508 -27.60599)
		(width 0.14224)
		(layer "In2.Cu")
		(net "M_A_DQ<16>")
	)
	(segment
		(start 216.515188 -22.5298)
		(end 216.515188 -23.275544)
		(width 0.14224)
		(layer "In2.Cu")
		(net "M_A_DQ<16>")
	)
	(segment
		(start 234.608624 -58.657236)
		(end 234.608878 -58.65749)
		(width 0.0889)
		(layer "In2.Cu")
		(net "M_A_DQ<16>")
	)
	(segment
		(start 216.34196 -28.76423)
		(end 216.09304 -28.76423)
		(width 0.14224)
		(layer "In2.Cu")
		(net "M_A_DQ<16>")
	)
	(segment
		(start 230.305864 -57.874408)
		(end 231.253792 -57.874408)
		(width 0.14224)
		(layer "In2.Cu")
		(net "M_A_DQ<16>")
	)
	(segment
		(start 215.9508 -24.8412)
		(end 215.9508 -25.37079)
		(width 0.14224)
		(layer "In2.Cu")
		(net "M_A_DQ<16>")
	)
	(segment
		(start 216.09304 -31.36519)
		(end 215.9508 -31.50743)
		(width 0.14224)
		(layer "In2.Cu")
		(net "M_A_DQ<16>")
	)
	(segment
		(start 216.837006 -19.7104)
		(end 217.179906 -20.0533)
		(width 0.14224)
		(layer "In2.Cu")
		(net "M_A_DQ<16>")
	)
	(segment
		(start 216.4842 -29.55671)
		(end 216.4842 -29.92247)
		(width 0.14224)
		(layer "In2.Cu")
		(net "M_A_DQ<16>")
	)
	(segment
		(start 235.137198 -58.633614)
		(end 235.265468 -58.761884)
		(width 0.0889)
		(layer "In2.Cu")
		(net "M_A_DQ<16>")
	)
	(segment
		(start 216.837006 -19.380454)
		(end 216.837006 -19.7104)
		(width 0.14224)
		(layer "In2.Cu")
		(net "M_A_DQ<16>")
	)
	(segment
		(start 216.4842 -28.62199)
		(end 216.34196 -28.76423)
		(width 0.14224)
		(layer "In2.Cu")
		(net "M_A_DQ<16>")
	)
	(segment
		(start 216.34196 -30.71495)
		(end 216.4842 -30.85719)
		(width 0.14224)
		(layer "In2.Cu")
		(net "M_A_DQ<16>")
	)
	(segment
		(start 216.4842 -29.92247)
		(end 216.34196 -30.06471)
		(width 0.14224)
		(layer "In2.Cu")
		(net "M_A_DQ<16>")
	)
	(segment
		(start 234.92079 -58.633614)
		(end 235.137198 -58.633614)
		(width 0.0889)
		(layer "In2.Cu")
		(net "M_A_DQ<16>")
	)
	(segment
		(start 216.4842 -26.02103)
		(end 216.34196 -26.16327)
		(width 0.14224)
		(layer "In2.Cu")
		(net "M_A_DQ<16>")
	)
	(segment
		(start 216.1286 -24.6634)
		(end 215.9508 -24.8412)
		(width 0.14224)
		(layer "In2.Cu")
		(net "M_A_DQ<16>")
	)
	(segment
		(start 216.862406 -20.5994)
		(end 216.862406 -20.903946)
		(width 0.14224)
		(layer "In2.Cu")
		(net "M_A_DQ<16>")
	)
	(segment
		(start 216.09304 -30.06471)
		(end 215.9508 -30.20695)
		(width 0.14224)
		(layer "In2.Cu")
		(net "M_A_DQ<16>")
	)
	(segment
		(start 217.251788 -21.7932)
		(end 216.515188 -22.5298)
		(width 0.14224)
		(layer "In2.Cu")
		(net "M_A_DQ<16>")
	)
	(segment
		(start 216.09304 -26.81351)
		(end 216.34196 -26.81351)
		(width 0.14224)
		(layer "In2.Cu")
		(net "M_A_DQ<16>")
	)
	(segment
		(start 216.799922 -23.560278)
		(end 216.1286 -24.2316)
		(width 0.14224)
		(layer "In2.Cu")
		(net "M_A_DQ<16>")
	)
	(segment
		(start 215.9508 -25.37079)
		(end 216.09304 -25.51303)
		(width 0.14224)
		(layer "In2.Cu")
		(net "M_A_DQ<16>")
	)
	(segment
		(start 215.9508 -43.519344)
		(end 230.305864 -57.874408)
		(width 0.14224)
		(layer "In2.Cu")
		(net "M_A_DQ<16>")
	)
	(segment
		(start 216.4842 -31.22295)
		(end 216.34196 -31.36519)
		(width 0.14224)
		(layer "In2.Cu")
		(net "M_A_DQ<16>")
	)
	(segment
		(start 215.9508 -31.50743)
		(end 215.9508 -43.519344)
		(width 0.14224)
		(layer "In2.Cu")
		(net "M_A_DQ<16>")
	)
	(segment
		(start 215.9508 -27.60599)
		(end 215.9508 -27.97175)
		(width 0.14224)
		(layer "In2.Cu")
		(net "M_A_DQ<16>")
	)
	(segment
		(start 231.468422 -57.874408)
		(end 231.846628 -58.252614)
		(width 0.0889)
		(layer "In2.Cu")
		(net "M_A_DQ<16>")
	)
	(segment
		(start 216.34196 -25.51303)
		(end 216.4842 -25.65527)
		(width 0.14224)
		(layer "In2.Cu")
		(net "M_A_DQ<16>")
	)
	(arc
		(start 234.771438 -58.65749)
		(mid 234.846883 -58.650359)
		(end 234.92079 -58.633614)
		(width 0.0889)
		(layer "In2.Cu")
		(net "M_A_DQ<16>")
	)
	(arc
		(start 235.265468 -58.761884)
		(mid 235.612178 -58.962195)
		(end 235.958888 -58.761884)
		(width 0.0889)
		(layer "In2.Cu")
		(net "M_A_DQ<16>")
	)
	(segment
		(start 216.747344 -35.206686)
		(end 217.090244 -35.206686)
		(width 0.1651)
		(layer "F.Cu")
		(net "M_A_DQ<15>")
	)
	(segment
		(start 216.417144 -37.981128)
		(end 216.582244 -37.816028)
		(width 0.1651)
		(layer "F.Cu")
		(net "M_A_DQ<15>")
	)
	(segment
		(start 212.54974 -22.279356)
		(end 212.032596 -22.7965)
		(width 0.1651)
		(layer "F.Cu")
		(net "M_A_DQ<15>")
	)
	(segment
		(start 211.699856 -15.423642)
		(end 211.699856 -16.687546)
		(width 0.1651)
		(layer "F.Cu")
		(net "M_A_DQ<15>")
	)
	(segment
		(start 215.909144 -32.639)
		(end 215.909144 -37.816028)
		(width 0.1651)
		(layer "F.Cu")
		(net "M_A_DQ<15>")
	)
	(segment
		(start 217.090244 -38.654228)
		(end 216.074244 -38.654228)
		(width 0.1651)
		(layer "F.Cu")
		(net "M_A_DQ<15>")
	)
	(segment
		(start 216.074244 -37.981128)
		(end 216.417144 -37.981128)
		(width 0.1651)
		(layer "F.Cu")
		(net "M_A_DQ<15>")
	)
	(segment
		(start 216.582244 -35.371786)
		(end 216.747344 -35.206686)
		(width 0.1651)
		(layer "F.Cu")
		(net "M_A_DQ<15>")
	)
	(segment
		(start 217.255344 -35.371786)
		(end 217.255344 -38.489128)
		(width 0.1651)
		(layer "F.Cu")
		(net "M_A_DQ<15>")
	)
	(segment
		(start 216.074244 -38.654228)
		(end 215.909144 -38.819328)
		(width 0.1651)
		(layer "F.Cu")
		(net "M_A_DQ<15>")
	)
	(segment
		(start 233.44505 -55.59044)
		(end 234.466638 -55.59044)
		(width 0.0889)
		(layer "F.Cu")
		(net "M_A_DQ<15>")
	)
	(segment
		(start 212.217 -23.3426)
		(end 212.217 -24.9428)
		(width 0.1651)
		(layer "F.Cu")
		(net "M_A_DQ<15>")
	)
	(segment
		(start 215.909144 -39.50843)
		(end 230.883714 -54.483)
		(width 0.1651)
		(layer "F.Cu")
		(net "M_A_DQ<15>")
	)
	(segment
		(start 211.700364 -15.423642)
		(end 211.699856 -15.423642)
		(width 0.1651)
		(layer "F.Cu")
		(net "M_A_DQ<15>")
	)
	(segment
		(start 216.582244 -37.816028)
		(end 216.582244 -35.371786)
		(width 0.1651)
		(layer "F.Cu")
		(net "M_A_DQ<15>")
	)
	(segment
		(start 212.217 -24.9428)
		(end 215.909144 -28.634944)
		(width 0.1651)
		(layer "F.Cu")
		(net "M_A_DQ<15>")
	)
	(segment
		(start 212.032596 -23.158196)
		(end 212.217 -23.3426)
		(width 0.1651)
		(layer "F.Cu")
		(net "M_A_DQ<15>")
	)
	(segment
		(start 215.909144 -38.819328)
		(end 215.909144 -39.50843)
		(width 0.1651)
		(layer "F.Cu")
		(net "M_A_DQ<15>")
	)
	(segment
		(start 233.063034 -55.208424)
		(end 233.44505 -55.59044)
		(width 0.0889)
		(layer "F.Cu")
		(net "M_A_DQ<15>")
	)
	(segment
		(start 215.909144 -28.634944)
		(end 215.909144 -32.639)
		(width 0.1651)
		(layer "F.Cu")
		(net "M_A_DQ<15>")
	)
	(segment
		(start 231.756712 -54.483)
		(end 232.482136 -55.208424)
		(width 0.0889)
		(layer "F.Cu")
		(net "M_A_DQ<15>")
	)
	(segment
		(start 230.883714 -54.483)
		(end 231.756712 -54.483)
		(width 0.0889)
		(layer "F.Cu")
		(net "M_A_DQ<15>")
	)
	(segment
		(start 217.090244 -35.206686)
		(end 217.255344 -35.371786)
		(width 0.1651)
		(layer "F.Cu")
		(net "M_A_DQ<15>")
	)
	(segment
		(start 212.032596 -22.7965)
		(end 212.032596 -23.158196)
		(width 0.1651)
		(layer "F.Cu")
		(net "M_A_DQ<15>")
	)
	(segment
		(start 232.482136 -55.208424)
		(end 233.063034 -55.208424)
		(width 0.0889)
		(layer "F.Cu")
		(net "M_A_DQ<15>")
	)
	(segment
		(start 217.255344 -38.489128)
		(end 217.090244 -38.654228)
		(width 0.1651)
		(layer "F.Cu")
		(net "M_A_DQ<15>")
	)
	(segment
		(start 215.909144 -37.816028)
		(end 216.074244 -37.981128)
		(width 0.1651)
		(layer "F.Cu")
		(net "M_A_DQ<15>")
	)
	(via
		(at 211.699856 -16.687546)
		(size 0.508)
		(drill 0.254)
		(layers "F.Cu" "B.Cu")
		(net "M_A_DQ<15>")
	)
	(via
		(at 215.909144 -32.639)
		(size 0.508)
		(drill 0.254)
		(layers "F.Cu" "B.Cu")
		(net "M_A_DQ<15>")
	)
	(via
		(at 212.54974 -22.279356)
		(size 0.508)
		(drill 0.254)
		(layers "F.Cu" "B.Cu")
		(net "M_A_DQ<15>")
	)
	(segment
		(start 212.550502 -20.224242)
		(end 212.550502 -22.278594)
		(width 0.1651)
		(layer "B.Cu")
		(net "M_A_DQ<15>")
	)
	(segment
		(start 212.550502 -22.278594)
		(end 212.54974 -22.279356)
		(width 0.1651)
		(layer "B.Cu")
		(net "M_A_DQ<15>")
	)
	(segment
		(start 213.057994 -18.1102)
		(end 212.600794 -17.653)
		(width 0.14224)
		(layer "In2.Cu")
		(net "M_A_DQ<15>")
	)
	(segment
		(start 212.016594 -17.3228)
		(end 212.016594 -17.004284)
		(width 0.14224)
		(layer "In2.Cu")
		(net "M_A_DQ<15>")
	)
	(segment
		(start 212.902546 -18.621248)
		(end 213.057994 -18.4658)
		(width 0.14224)
		(layer "In2.Cu")
		(net "M_A_DQ<15>")
	)
	(segment
		(start 212.600794 -17.653)
		(end 212.346794 -17.653)
		(width 0.14224)
		(layer "In2.Cu")
		(net "M_A_DQ<15>")
	)
	(segment
		(start 212.54974 -22.279356)
		(end 212.902546 -21.92655)
		(width 0.14224)
		(layer "In2.Cu")
		(net "M_A_DQ<15>")
	)
	(segment
		(start 213.057994 -18.4658)
		(end 213.057994 -18.1102)
		(width 0.14224)
		(layer "In2.Cu")
		(net "M_A_DQ<15>")
	)
	(segment
		(start 212.016594 -17.004284)
		(end 211.699856 -16.687546)
		(width 0.14224)
		(layer "In2.Cu")
		(net "M_A_DQ<15>")
	)
	(segment
		(start 212.902546 -21.92655)
		(end 212.902546 -18.621248)
		(width 0.14224)
		(layer "In2.Cu")
		(net "M_A_DQ<15>")
	)
	(segment
		(start 212.346794 -17.653)
		(end 212.016594 -17.3228)
		(width 0.14224)
		(layer "In2.Cu")
		(net "M_A_DQ<15>")
	)
	(segment
		(start 212.200236 -27.58694)
		(end 212.899498 -26.887678)
		(width 0.1651)
		(layer "F.Cu")
		(net "M_A_DQ<14>")
	)
	(segment
		(start 213.375494 -27.363674)
		(end 212.676232 -28.062936)
		(width 0.1651)
		(layer "F.Cu")
		(net "M_A_DQ<14>")
	)
	(segment
		(start 212.442552 -28.062936)
		(end 212.200236 -27.82062)
		(width 0.1651)
		(layer "F.Cu")
		(net "M_A_DQ<14>")
	)
	(segment
		(start 211.947506 -25.935686)
		(end 211.947506 -25.702006)
		(width 0.1651)
		(layer "F.Cu")
		(net "M_A_DQ<14>")
	)
	(segment
		(start 213.85149 -27.60599)
		(end 213.609174 -27.363674)
		(width 0.1651)
		(layer "F.Cu")
		(net "M_A_DQ<14>")
	)
	(segment
		(start 214.327486 -28.315666)
		(end 213.628224 -29.014928)
		(width 0.1651)
		(layer "F.Cu")
		(net "M_A_DQ<14>")
	)
	(segment
		(start 214.222584 -31.42869)
		(end 214.387684 -31.26359)
		(width 0.1651)
		(layer "F.Cu")
		(net "M_A_DQ<14>")
	)
	(segment
		(start 212.423502 -26.411682)
		(end 211.72424 -27.110944)
		(width 0.1651)
		(layer "F.Cu")
		(net "M_A_DQ<14>")
	)
	(segment
		(start 232.749598 -55.59044)
		(end 232.513378 -55.59044)
		(width 0.0889)
		(layer "F.Cu")
		(net "M_A_DQ<14>")
	)
	(segment
		(start 230.564182 -55.118)
		(end 215.215216 -39.769034)
		(width 0.1651)
		(layer "F.Cu")
		(net "M_A_DQ<14>")
	)
	(segment
		(start 211.72424 -27.110944)
		(end 211.49056 -27.110944)
		(width 0.1651)
		(layer "F.Cu")
		(net "M_A_DQ<14>")
	)
	(segment
		(start 215.050116 -31.26359)
		(end 215.215216 -31.09849)
		(width 0.1651)
		(layer "F.Cu")
		(net "M_A_DQ<14>")
	)
	(segment
		(start 214.387684 -31.26359)
		(end 215.050116 -31.26359)
		(width 0.1651)
		(layer "F.Cu")
		(net "M_A_DQ<14>")
	)
	(segment
		(start 212.682074 -18.69948)
		(end 212.549994 -18.5674)
		(width 0.1651)
		(layer "F.Cu")
		(net "M_A_DQ<14>")
	)
	(segment
		(start 212.899498 -26.887678)
		(end 212.899498 -26.653998)
		(width 0.1651)
		(layer "F.Cu")
		(net "M_A_DQ<14>")
	)
	(segment
		(start 212.657182 -26.411682)
		(end 212.423502 -26.411682)
		(width 0.1651)
		(layer "F.Cu")
		(net "M_A_DQ<14>")
	)
	(segment
		(start 212.549994 -20.023582)
		(end 212.549994 -19.05)
		(width 0.1651)
		(layer "F.Cu")
		(net "M_A_DQ<14>")
	)
	(segment
		(start 211.248244 -26.634948)
		(end 211.947506 -25.935686)
		(width 0.1651)
		(layer "F.Cu")
		(net "M_A_DQ<14>")
	)
	(segment
		(start 213.394544 -29.014928)
		(end 213.152228 -28.772612)
		(width 0.1651)
		(layer "F.Cu")
		(net "M_A_DQ<14>")
	)
	(segment
		(start 213.152228 -28.538932)
		(end 213.85149 -27.83967)
		(width 0.1651)
		(layer "F.Cu")
		(net "M_A_DQ<14>")
	)
	(segment
		(start 211.455 -25.2095)
		(end 211.455 -23.805134)
		(width 0.1651)
		(layer "F.Cu")
		(net "M_A_DQ<14>")
	)
	(segment
		(start 215.215216 -39.769034)
		(end 215.215216 -35.052)
		(width 0.1651)
		(layer "F.Cu")
		(net "M_A_DQ<14>")
	)
	(segment
		(start 211.248244 -26.868628)
		(end 211.248244 -26.634948)
		(width 0.1651)
		(layer "F.Cu")
		(net "M_A_DQ<14>")
	)
	(segment
		(start 212.676232 -28.062936)
		(end 212.442552 -28.062936)
		(width 0.1651)
		(layer "F.Cu")
		(net "M_A_DQ<14>")
	)
	(segment
		(start 212.682074 -18.91792)
		(end 212.682074 -18.69948)
		(width 0.1651)
		(layer "F.Cu")
		(net "M_A_DQ<14>")
	)
	(segment
		(start 214.387684 -31.93669)
		(end 214.222584 -31.77159)
		(width 0.1651)
		(layer "F.Cu")
		(net "M_A_DQ<14>")
	)
	(segment
		(start 232.513378 -55.59044)
		(end 232.040938 -55.118)
		(width 0.0889)
		(layer "F.Cu")
		(net "M_A_DQ<14>")
	)
	(segment
		(start 212.899498 -26.653998)
		(end 212.657182 -26.411682)
		(width 0.1651)
		(layer "F.Cu")
		(net "M_A_DQ<14>")
	)
	(segment
		(start 212.550502 -20.023582)
		(end 212.549994 -20.023582)
		(width 0.1651)
		(layer "F.Cu")
		(net "M_A_DQ<14>")
	)
	(segment
		(start 215.215216 -33.44799)
		(end 215.050116 -33.28289)
		(width 0.1651)
		(layer "F.Cu")
		(net "M_A_DQ<14>")
	)
	(segment
		(start 211.49056 -27.110944)
		(end 211.248244 -26.868628)
		(width 0.1651)
		(layer "F.Cu")
		(net "M_A_DQ<14>")
	)
	(segment
		(start 214.7443 -32.60979)
		(end 215.050116 -32.60979)
		(width 0.1651)
		(layer "F.Cu")
		(net "M_A_DQ<14>")
	)
	(segment
		(start 215.215216 -35.052)
		(end 215.215216 -33.44799)
		(width 0.1651)
		(layer "F.Cu")
		(net "M_A_DQ<14>")
	)
	(segment
		(start 211.947506 -25.702006)
		(end 211.455 -25.2095)
		(width 0.1651)
		(layer "F.Cu")
		(net "M_A_DQ<14>")
	)
	(segment
		(start 213.628224 -29.014928)
		(end 213.394544 -29.014928)
		(width 0.1651)
		(layer "F.Cu")
		(net "M_A_DQ<14>")
	)
	(segment
		(start 214.7443 -33.28289)
		(end 214.5792 -33.11779)
		(width 0.1651)
		(layer "F.Cu")
		(net "M_A_DQ<14>")
	)
	(segment
		(start 214.5792 -33.11779)
		(end 214.5792 -32.77489)
		(width 0.1651)
		(layer "F.Cu")
		(net "M_A_DQ<14>")
	)
	(segment
		(start 214.5792 -32.77489)
		(end 214.7443 -32.60979)
		(width 0.1651)
		(layer "F.Cu")
		(net "M_A_DQ<14>")
	)
	(segment
		(start 213.609174 -27.363674)
		(end 213.375494 -27.363674)
		(width 0.1651)
		(layer "F.Cu")
		(net "M_A_DQ<14>")
	)
	(segment
		(start 212.200236 -27.82062)
		(end 212.200236 -27.58694)
		(width 0.1651)
		(layer "F.Cu")
		(net "M_A_DQ<14>")
	)
	(segment
		(start 214.222584 -31.77159)
		(end 214.222584 -31.42869)
		(width 0.1651)
		(layer "F.Cu")
		(net "M_A_DQ<14>")
	)
	(segment
		(start 212.549994 -18.5674)
		(end 212.549994 -18.262854)
		(width 0.1651)
		(layer "F.Cu")
		(net "M_A_DQ<14>")
	)
	(segment
		(start 215.050116 -32.60979)
		(end 215.215216 -32.44469)
		(width 0.1651)
		(layer "F.Cu")
		(net "M_A_DQ<14>")
	)
	(segment
		(start 215.215216 -28.969716)
		(end 214.561166 -28.315666)
		(width 0.1651)
		(layer "F.Cu")
		(net "M_A_DQ<14>")
	)
	(segment
		(start 213.85149 -27.83967)
		(end 213.85149 -27.60599)
		(width 0.1651)
		(layer "F.Cu")
		(net "M_A_DQ<14>")
	)
	(segment
		(start 215.215216 -32.10179)
		(end 215.050116 -31.93669)
		(width 0.1651)
		(layer "F.Cu")
		(net "M_A_DQ<14>")
	)
	(segment
		(start 212.549994 -19.05)
		(end 212.682074 -18.91792)
		(width 0.1651)
		(layer "F.Cu")
		(net "M_A_DQ<14>")
	)
	(segment
		(start 213.152228 -28.772612)
		(end 213.152228 -28.538932)
		(width 0.1651)
		(layer "F.Cu")
		(net "M_A_DQ<14>")
	)
	(segment
		(start 212.549994 -18.262854)
		(end 212.54974 -18.2626)
		(width 0.1651)
		(layer "F.Cu")
		(net "M_A_DQ<14>")
	)
	(segment
		(start 215.050116 -33.28289)
		(end 214.7443 -33.28289)
		(width 0.1651)
		(layer "F.Cu")
		(net "M_A_DQ<14>")
	)
	(segment
		(start 215.215216 -31.09849)
		(end 215.215216 -28.969716)
		(width 0.1651)
		(layer "F.Cu")
		(net "M_A_DQ<14>")
	)
	(segment
		(start 232.040938 -55.118)
		(end 230.564182 -55.118)
		(width 0.0889)
		(layer "F.Cu")
		(net "M_A_DQ<14>")
	)
	(segment
		(start 214.561166 -28.315666)
		(end 214.327486 -28.315666)
		(width 0.1651)
		(layer "F.Cu")
		(net "M_A_DQ<14>")
	)
	(segment
		(start 215.215216 -32.44469)
		(end 215.215216 -32.10179)
		(width 0.1651)
		(layer "F.Cu")
		(net "M_A_DQ<14>")
	)
	(segment
		(start 211.455 -23.805134)
		(end 211.699856 -23.560278)
		(width 0.1651)
		(layer "F.Cu")
		(net "M_A_DQ<14>")
	)
	(segment
		(start 215.050116 -31.93669)
		(end 214.387684 -31.93669)
		(width 0.1651)
		(layer "F.Cu")
		(net "M_A_DQ<14>")
	)
	(via
		(at 211.699856 -23.560278)
		(size 0.508)
		(drill 0.254)
		(layers "F.Cu" "B.Cu")
		(net "M_A_DQ<14>")
	)
	(via
		(at 215.215216 -35.052)
		(size 0.508)
		(drill 0.254)
		(layers "F.Cu" "B.Cu")
		(net "M_A_DQ<14>")
	)
	(via
		(at 212.54974 -18.2626)
		(size 0.508)
		(drill 0.254)
		(layers "F.Cu" "B.Cu")
		(net "M_A_DQ<14>")
	)
	(segment
		(start 211.699856 -24.824182)
		(end 211.699856 -23.560278)
		(width 0.1651)
		(layer "B.Cu")
		(net "M_A_DQ<14>")
	)
	(segment
		(start 211.700364 -24.824182)
		(end 211.699856 -24.824182)
		(width 0.1651)
		(layer "B.Cu")
		(net "M_A_DQ<14>")
	)
	(segment
		(start 211.464144 -22.530054)
		(end 212.236812 -21.757386)
		(width 0.14224)
		(layer "In2.Cu")
		(net "M_A_DQ<14>")
	)
	(segment
		(start 211.811362 -19.589496)
		(end 211.811362 -19.278854)
		(width 0.14224)
		(layer "In2.Cu")
		(net "M_A_DQ<14>")
	)
	(segment
		(start 212.236812 -21.757386)
		(end 212.236812 -21.405596)
		(width 0.14224)
		(layer "In2.Cu")
		(net "M_A_DQ<14>")
	)
	(segment
		(start 211.811362 -19.278854)
		(end 212.175344 -18.914872)
		(width 0.14224)
		(layer "In2.Cu")
		(net "M_A_DQ<14>")
	)
	(segment
		(start 212.175344 -18.914872)
		(end 212.175344 -18.636996)
		(width 0.14224)
		(layer "In2.Cu")
		(net "M_A_DQ<14>")
	)
	(segment
		(start 211.811362 -20.980146)
		(end 211.811362 -20.694904)
		(width 0.14224)
		(layer "In2.Cu")
		(net "M_A_DQ<14>")
	)
	(segment
		(start 211.811362 -20.694904)
		(end 212.192362 -20.313904)
		(width 0.14224)
		(layer "In2.Cu")
		(net "M_A_DQ<14>")
	)
	(segment
		(start 212.192362 -20.313904)
		(end 212.192362 -19.970496)
		(width 0.14224)
		(layer "In2.Cu")
		(net "M_A_DQ<14>")
	)
	(segment
		(start 211.464144 -23.324566)
		(end 211.464144 -22.530054)
		(width 0.14224)
		(layer "In2.Cu")
		(net "M_A_DQ<14>")
	)
	(segment
		(start 211.699856 -23.560278)
		(end 211.464144 -23.324566)
		(width 0.14224)
		(layer "In2.Cu")
		(net "M_A_DQ<14>")
	)
	(segment
		(start 212.192362 -19.970496)
		(end 211.811362 -19.589496)
		(width 0.14224)
		(layer "In2.Cu")
		(net "M_A_DQ<14>")
	)
	(segment
		(start 212.175344 -18.636996)
		(end 212.54974 -18.2626)
		(width 0.14224)
		(layer "In2.Cu")
		(net "M_A_DQ<14>")
	)
	(segment
		(start 212.236812 -21.405596)
		(end 211.811362 -20.980146)
		(width 0.14224)
		(layer "In2.Cu")
		(net "M_A_DQ<14>")
	)
	(segment
		(start 232.065576 -59.221624)
		(end 232.196386 -59.090814)
		(width 0.0889)
		(layer "F.Cu")
		(net "M_A_DQ<13>")
	)
	(segment
		(start 213.802214 -44.007532)
		(end 229.016306 -59.221624)
		(width 0.1651)
		(layer "F.Cu")
		(net "M_A_DQ<13>")
	)
	(segment
		(start 232.196386 -59.090814)
		(end 232.983024 -59.090814)
		(width 0.0889)
		(layer "F.Cu")
		(net "M_A_DQ<13>")
	)
	(segment
		(start 206.05496 -23.04288)
		(end 206.375 -23.8252)
		(width 0.1651)
		(layer "F.Cu")
		(net "M_A_DQ<13>")
	)
	(segment
		(start 205.750414 -15.423642)
		(end 205.749906 -15.423642)
		(width 0.1651)
		(layer "F.Cu")
		(net "M_A_DQ<13>")
	)
	(segment
		(start 232.983024 -59.090814)
		(end 233.44505 -59.55284)
		(width 0.0889)
		(layer "F.Cu")
		(net "M_A_DQ<13>")
	)
	(segment
		(start 208.6356 -30.950916)
		(end 208.6356 -38.840918)
		(width 0.1651)
		(layer "F.Cu")
		(net "M_A_DQ<13>")
	)
	(segment
		(start 229.016306 -59.221624)
		(end 232.065576 -59.221624)
		(width 0.1651)
		(layer "F.Cu")
		(net "M_A_DQ<13>")
	)
	(segment
		(start 233.44505 -59.55284)
		(end 234.466638 -59.55284)
		(width 0.0889)
		(layer "F.Cu")
		(net "M_A_DQ<13>")
	)
	(segment
		(start 206.375 -28.690316)
		(end 208.6356 -30.950916)
		(width 0.1651)
		(layer "F.Cu")
		(net "M_A_DQ<13>")
	)
	(segment
		(start 205.749906 -15.423642)
		(end 205.749906 -16.687546)
		(width 0.1651)
		(layer "F.Cu")
		(net "M_A_DQ<13>")
	)
	(segment
		(start 206.05496 -22.747986)
		(end 206.05496 -23.04288)
		(width 0.1651)
		(layer "F.Cu")
		(net "M_A_DQ<13>")
	)
	(segment
		(start 208.6356 -38.840918)
		(end 213.802214 -44.007532)
		(width 0.1651)
		(layer "F.Cu")
		(net "M_A_DQ<13>")
	)
	(segment
		(start 206.375 -23.8252)
		(end 206.375 -28.690316)
		(width 0.1651)
		(layer "F.Cu")
		(net "M_A_DQ<13>")
	)
	(segment
		(start 206.52359 -22.279356)
		(end 206.05496 -22.747986)
		(width 0.1651)
		(layer "F.Cu")
		(net "M_A_DQ<13>")
	)
	(via
		(at 206.52359 -22.279356)
		(size 0.508)
		(drill 0.254)
		(layers "F.Cu" "B.Cu")
		(net "M_A_DQ<13>")
	)
	(via
		(at 213.802214 -44.007532)
		(size 0.508)
		(drill 0.254)
		(layers "F.Cu" "B.Cu")
		(net "M_A_DQ<13>")
	)
	(via
		(at 205.749906 -16.687546)
		(size 0.508)
		(drill 0.254)
		(layers "F.Cu" "B.Cu")
		(net "M_A_DQ<13>")
	)
	(segment
		(start 206.600298 -20.224242)
		(end 206.59979 -20.224242)
		(width 0.1651)
		(layer "B.Cu")
		(net "M_A_DQ<13>")
	)
	(segment
		(start 206.59979 -22.203156)
		(end 206.52359 -22.279356)
		(width 0.1651)
		(layer "B.Cu")
		(net "M_A_DQ<13>")
	)
	(segment
		(start 206.59979 -20.224242)
		(end 206.59979 -22.203156)
		(width 0.1651)
		(layer "B.Cu")
		(net "M_A_DQ<13>")
	)
	(segment
		(start 207.031844 -18.053304)
		(end 206.63154 -17.653)
		(width 0.14224)
		(layer "In2.Cu")
		(net "M_A_DQ<13>")
	)
	(segment
		(start 206.834994 -18.66265)
		(end 207.031844 -18.4658)
		(width 0.14224)
		(layer "In2.Cu")
		(net "M_A_DQ<13>")
	)
	(segment
		(start 205.749906 -17.082262)
		(end 205.749906 -16.687546)
		(width 0.14224)
		(layer "In2.Cu")
		(net "M_A_DQ<13>")
	)
	(segment
		(start 207.031844 -18.4658)
		(end 207.031844 -18.053304)
		(width 0.14224)
		(layer "In2.Cu")
		(net "M_A_DQ<13>")
	)
	(segment
		(start 206.52359 -22.279356)
		(end 206.834994 -21.967952)
		(width 0.14224)
		(layer "In2.Cu")
		(net "M_A_DQ<13>")
	)
	(segment
		(start 206.320644 -17.653)
		(end 205.749906 -17.082262)
		(width 0.14224)
		(layer "In2.Cu")
		(net "M_A_DQ<13>")
	)
	(segment
		(start 206.63154 -17.653)
		(end 206.320644 -17.653)
		(width 0.14224)
		(layer "In2.Cu")
		(net "M_A_DQ<13>")
	)
	(segment
		(start 206.834994 -21.967952)
		(end 206.834994 -18.66265)
		(width 0.14224)
		(layer "In2.Cu")
		(net "M_A_DQ<13>")
	)
	(segment
		(start 205.6892 -24.68245)
		(end 205.6892 -23.620984)
		(width 0.1651)
		(layer "F.Cu")
		(net "M_A_DQ<12>")
	)
	(segment
		(start 207.965802 -39.125652)
		(end 207.965802 -31.435802)
		(width 0.1651)
		(layer "F.Cu")
		(net "M_A_DQ<12>")
	)
	(segment
		(start 206.59979 -18.692368)
		(end 206.501746 -18.161)
		(width 0.1651)
		(layer "F.Cu")
		(net "M_A_DQ<12>")
	)
	(segment
		(start 206.600298 -20.023582)
		(end 206.59979 -20.023582)
		(width 0.1651)
		(layer "F.Cu")
		(net "M_A_DQ<12>")
	)
	(segment
		(start 204.9018 -25.35555)
		(end 204.9018 -25.01265)
		(width 0.1651)
		(layer "F.Cu")
		(net "M_A_DQ<12>")
	)
	(segment
		(start 232.0798 -59.869324)
		(end 228.709474 -59.869324)
		(width 0.1651)
		(layer "F.Cu")
		(net "M_A_DQ<12>")
	)
	(segment
		(start 205.6892 -25.68575)
		(end 205.5241 -25.52065)
		(width 0.1651)
		(layer "F.Cu")
		(net "M_A_DQ<12>")
	)
	(segment
		(start 205.6892 -29.1592)
		(end 205.6892 -25.68575)
		(width 0.1651)
		(layer "F.Cu")
		(net "M_A_DQ<12>")
	)
	(segment
		(start 206.59979 -20.023582)
		(end 206.59979 -18.692368)
		(width 0.1651)
		(layer "F.Cu")
		(net "M_A_DQ<12>")
	)
	(segment
		(start 232.433114 -59.869324)
		(end 232.0798 -59.869324)
		(width 0.0889)
		(layer "F.Cu")
		(net "M_A_DQ<12>")
	)
	(segment
		(start 205.5241 -25.52065)
		(end 205.0669 -25.52065)
		(width 0.1651)
		(layer "F.Cu")
		(net "M_A_DQ<12>")
	)
	(segment
		(start 205.0669 -24.84755)
		(end 205.5241 -24.84755)
		(width 0.1651)
		(layer "F.Cu")
		(net "M_A_DQ<12>")
	)
	(segment
		(start 205.0669 -25.52065)
		(end 204.9018 -25.35555)
		(width 0.1651)
		(layer "F.Cu")
		(net "M_A_DQ<12>")
	)
	(segment
		(start 232.749598 -59.55284)
		(end 232.433114 -59.869324)
		(width 0.0889)
		(layer "F.Cu")
		(net "M_A_DQ<12>")
	)
	(segment
		(start 228.709474 -59.869324)
		(end 207.965802 -39.125652)
		(width 0.1651)
		(layer "F.Cu")
		(net "M_A_DQ<12>")
	)
	(segment
		(start 205.6892 -23.620984)
		(end 205.749906 -23.560278)
		(width 0.1651)
		(layer "F.Cu")
		(net "M_A_DQ<12>")
	)
	(segment
		(start 207.965802 -31.435802)
		(end 205.6892 -29.1592)
		(width 0.1651)
		(layer "F.Cu")
		(net "M_A_DQ<12>")
	)
	(segment
		(start 204.9018 -25.01265)
		(end 205.0669 -24.84755)
		(width 0.1651)
		(layer "F.Cu")
		(net "M_A_DQ<12>")
	)
	(segment
		(start 205.5241 -24.84755)
		(end 205.6892 -24.68245)
		(width 0.1651)
		(layer "F.Cu")
		(net "M_A_DQ<12>")
	)
	(via
		(at 205.749906 -23.560278)
		(size 0.508)
		(drill 0.254)
		(layers "F.Cu" "B.Cu")
		(net "M_A_DQ<12>")
	)
	(via
		(at 206.501746 -18.161)
		(size 0.508)
		(drill 0.254)
		(layers "F.Cu" "B.Cu")
		(net "M_A_DQ<12>")
	)
	(segment
		(start 205.749906 -24.824182)
		(end 205.749906 -23.560278)
		(width 0.1651)
		(layer "B.Cu")
		(net "M_A_DQ<12>")
	)
	(segment
		(start 205.750414 -24.824182)
		(end 205.749906 -24.824182)
		(width 0.1651)
		(layer "B.Cu")
		(net "M_A_DQ<12>")
	)
	(segment
		(start 205.874112 -20.6375)
		(end 206.242412 -20.2692)
		(width 0.14224)
		(layer "In2.Cu")
		(net "M_A_DQ<12>")
	)
	(segment
		(start 206.225394 -21.818854)
		(end 206.225394 -21.344128)
		(width 0.14224)
		(layer "In2.Cu")
		(net "M_A_DQ<12>")
	)
	(segment
		(start 206.225394 -21.344128)
		(end 205.874112 -20.992846)
		(width 0.14224)
		(layer "In2.Cu")
		(net "M_A_DQ<12>")
	)
	(segment
		(start 205.749906 -23.560278)
		(end 205.514194 -23.324566)
		(width 0.14224)
		(layer "In2.Cu")
		(net "M_A_DQ<12>")
	)
	(segment
		(start 206.242412 -20.2692)
		(end 206.242412 -19.9644)
		(width 0.14224)
		(layer "In2.Cu")
		(net "M_A_DQ<12>")
	)
	(segment
		(start 205.861412 -19.5834)
		(end 205.861412 -19.278854)
		(width 0.14224)
		(layer "In2.Cu")
		(net "M_A_DQ<12>")
	)
	(segment
		(start 205.861412 -19.278854)
		(end 206.225394 -18.914872)
		(width 0.14224)
		(layer "In2.Cu")
		(net "M_A_DQ<12>")
	)
	(segment
		(start 205.514194 -23.324566)
		(end 205.514194 -22.530054)
		(width 0.14224)
		(layer "In2.Cu")
		(net "M_A_DQ<12>")
	)
	(segment
		(start 206.225394 -18.914872)
		(end 206.225394 -18.437352)
		(width 0.14224)
		(layer "In2.Cu")
		(net "M_A_DQ<12>")
	)
	(segment
		(start 205.514194 -22.530054)
		(end 206.225394 -21.818854)
		(width 0.14224)
		(layer "In2.Cu")
		(net "M_A_DQ<12>")
	)
	(segment
		(start 206.242412 -19.9644)
		(end 205.861412 -19.5834)
		(width 0.14224)
		(layer "In2.Cu")
		(net "M_A_DQ<12>")
	)
	(segment
		(start 205.874112 -20.992846)
		(end 205.874112 -20.6375)
		(width 0.14224)
		(layer "In2.Cu")
		(net "M_A_DQ<12>")
	)
	(segment
		(start 206.225394 -18.437352)
		(end 206.501746 -18.161)
		(width 0.14224)
		(layer "In2.Cu")
		(net "M_A_DQ<12>")
	)
	(segment
		(start 217.878152 -29.912564)
		(end 217.437462 -29.912564)
		(width 0.1651)
		(layer "F.Cu")
		(net "M_A_DQ<11>")
	)
	(segment
		(start 218.017598 -40.662352)
		(end 218.017598 -31.877)
		(width 0.1651)
		(layer "F.Cu")
		(net "M_A_DQ<11>")
	)
	(segment
		(start 233.094022 -54.979824)
		(end 232.523284 -54.979824)
		(width 0.0889)
		(layer "F.Cu")
		(net "M_A_DQ<11>")
	)
	(segment
		(start 217.310462 -30.039564)
		(end 217.310462 -33.434782)
		(width 0.1651)
		(layer "F.Cu")
		(net "M_A_DQ<11>")
	)
	(segment
		(start 213.370668 -22.912324)
		(end 213.616794 -22.912324)
		(width 0.1651)
		(layer "F.Cu")
		(net "M_A_DQ<11>")
	)
	(segment
		(start 234.466638 -54.59984)
		(end 233.474006 -54.59984)
		(width 0.0889)
		(layer "F.Cu")
		(net "M_A_DQ<11>")
	)
	(segment
		(start 216.627202 -33.434782)
		(end 216.627202 -28.210002)
		(width 0.1651)
		(layer "F.Cu")
		(net "M_A_DQ<11>")
	)
	(segment
		(start 213.399878 -15.423642)
		(end 213.399878 -16.687546)
		(width 0.1651)
		(layer "F.Cu")
		(net "M_A_DQ<11>")
	)
	(segment
		(start 217.145362 -33.599882)
		(end 216.792302 -33.599882)
		(width 0.1651)
		(layer "F.Cu")
		(net "M_A_DQ<11>")
	)
	(segment
		(start 213.616794 -22.912324)
		(end 214.249762 -22.279356)
		(width 0.1651)
		(layer "F.Cu")
		(net "M_A_DQ<11>")
	)
	(segment
		(start 216.792302 -33.599882)
		(end 216.627202 -33.434782)
		(width 0.1651)
		(layer "F.Cu")
		(net "M_A_DQ<11>")
	)
	(segment
		(start 232.523284 -54.979824)
		(end 231.482646 -53.939186)
		(width 0.0889)
		(layer "F.Cu")
		(net "M_A_DQ<11>")
	)
	(segment
		(start 231.482646 -53.939186)
		(end 231.294432 -53.939186)
		(width 0.0889)
		(layer "F.Cu")
		(net "M_A_DQ<11>")
	)
	(segment
		(start 218.017598 -31.877)
		(end 218.017598 -30.05201)
		(width 0.1651)
		(layer "F.Cu")
		(net "M_A_DQ<11>")
	)
	(segment
		(start 218.017598 -30.05201)
		(end 217.878152 -29.912564)
		(width 0.1651)
		(layer "F.Cu")
		(net "M_A_DQ<11>")
	)
	(segment
		(start 233.474006 -54.59984)
		(end 233.094022 -54.979824)
		(width 0.0889)
		(layer "F.Cu")
		(net "M_A_DQ<11>")
	)
	(segment
		(start 212.926168 -23.356824)
		(end 213.370668 -22.912324)
		(width 0.1651)
		(layer "F.Cu")
		(net "M_A_DQ<11>")
	)
	(segment
		(start 212.926168 -24.508968)
		(end 212.926168 -23.356824)
		(width 0.1651)
		(layer "F.Cu")
		(net "M_A_DQ<11>")
	)
	(segment
		(start 217.310462 -33.434782)
		(end 217.145362 -33.599882)
		(width 0.1651)
		(layer "F.Cu")
		(net "M_A_DQ<11>")
	)
	(segment
		(start 217.437462 -29.912564)
		(end 217.310462 -30.039564)
		(width 0.1651)
		(layer "F.Cu")
		(net "M_A_DQ<11>")
	)
	(segment
		(start 213.400386 -15.423642)
		(end 213.399878 -15.423642)
		(width 0.1651)
		(layer "F.Cu")
		(net "M_A_DQ<11>")
	)
	(segment
		(start 231.294432 -53.939186)
		(end 218.017598 -40.662352)
		(width 0.1651)
		(layer "F.Cu")
		(net "M_A_DQ<11>")
	)
	(segment
		(start 216.627202 -28.210002)
		(end 212.926168 -24.508968)
		(width 0.1651)
		(layer "F.Cu")
		(net "M_A_DQ<11>")
	)
	(via
		(at 218.017598 -31.877)
		(size 0.508)
		(drill 0.254)
		(layers "F.Cu" "B.Cu")
		(net "M_A_DQ<11>")
	)
	(via
		(at 213.399878 -16.687546)
		(size 0.508)
		(drill 0.254)
		(layers "F.Cu" "B.Cu")
		(net "M_A_DQ<11>")
	)
	(via
		(at 214.249762 -22.279356)
		(size 0.508)
		(drill 0.254)
		(layers "F.Cu" "B.Cu")
		(net "M_A_DQ<11>")
	)
	(segment
		(start 214.250524 -22.278594)
		(end 214.249762 -22.279356)
		(width 0.1651)
		(layer "B.Cu")
		(net "M_A_DQ<11>")
	)
	(segment
		(start 214.250524 -20.224242)
		(end 214.250524 -22.278594)
		(width 0.1651)
		(layer "B.Cu")
		(net "M_A_DQ<11>")
	)
	(segment
		(start 214.249762 -22.279356)
		(end 214.602568 -21.92655)
		(width 0.14224)
		(layer "In2.Cu")
		(net "M_A_DQ<11>")
	)
	(segment
		(start 214.758016 -18.1102)
		(end 214.300816 -17.653)
		(width 0.14224)
		(layer "In2.Cu")
		(net "M_A_DQ<11>")
	)
	(segment
		(start 214.758016 -18.4658)
		(end 214.758016 -18.1102)
		(width 0.14224)
		(layer "In2.Cu")
		(net "M_A_DQ<11>")
	)
	(segment
		(start 213.716616 -17.3228)
		(end 213.716616 -17.004284)
		(width 0.14224)
		(layer "In2.Cu")
		(net "M_A_DQ<11>")
	)
	(segment
		(start 214.602568 -21.92655)
		(end 214.602568 -18.621248)
		(width 0.14224)
		(layer "In2.Cu")
		(net "M_A_DQ<11>")
	)
	(segment
		(start 214.602568 -18.621248)
		(end 214.758016 -18.4658)
		(width 0.14224)
		(layer "In2.Cu")
		(net "M_A_DQ<11>")
	)
	(segment
		(start 213.716616 -17.004284)
		(end 213.399878 -16.687546)
		(width 0.14224)
		(layer "In2.Cu")
		(net "M_A_DQ<11>")
	)
	(segment
		(start 214.300816 -17.653)
		(end 214.046816 -17.653)
		(width 0.14224)
		(layer "In2.Cu")
		(net "M_A_DQ<11>")
	)
	(segment
		(start 214.046816 -17.653)
		(end 213.716616 -17.3228)
		(width 0.14224)
		(layer "In2.Cu")
		(net "M_A_DQ<11>")
	)
	(segment
		(start 214.249762 -18.539968)
		(end 214.249762 -18.2626)
		(width 0.1651)
		(layer "F.Cu")
		(net "M_A_DQ<10>")
	)
	(segment
		(start 214.381334 -18.89506)
		(end 214.381334 -18.67154)
		(width 0.1651)
		(layer "F.Cu")
		(net "M_A_DQ<10>")
	)
	(segment
		(start 215.587072 -25.02916)
		(end 215.344756 -25.271476)
		(width 0.1651)
		(layer "F.Cu")
		(net "M_A_DQ<10>")
	)
	(segment
		(start 219.541852 -27.798268)
		(end 219.541852 -28.031948)
		(width 0.1651)
		(layer "F.Cu")
		(net "M_A_DQ<10>")
	)
	(segment
		(start 219.065856 -28.274264)
		(end 215.820752 -25.02916)
		(width 0.1651)
		(layer "F.Cu")
		(net "M_A_DQ<10>")
	)
	(segment
		(start 214.250524 -19.02587)
		(end 214.381334 -18.89506)
		(width 0.1651)
		(layer "F.Cu")
		(net "M_A_DQ<10>")
	)
	(segment
		(start 232.343452 -54.193694)
		(end 232.749598 -54.59984)
		(width 0.0889)
		(layer "F.Cu")
		(net "M_A_DQ<10>")
	)
	(segment
		(start 215.344756 -25.271476)
		(end 215.344756 -25.505156)
		(width 0.1651)
		(layer "F.Cu")
		(net "M_A_DQ<10>")
	)
	(segment
		(start 215.587072 -24.077168)
		(end 215.820752 -24.077168)
		(width 0.1651)
		(layer "F.Cu")
		(net "M_A_DQ<10>")
	)
	(segment
		(start 232.343452 -54.03342)
		(end 232.343452 -54.193694)
		(width 0.0889)
		(layer "F.Cu")
		(net "M_A_DQ<10>")
	)
	(segment
		(start 214.63508 -24.79548)
		(end 214.86876 -24.79548)
		(width 0.1651)
		(layer "F.Cu")
		(net "M_A_DQ<10>")
	)
	(segment
		(start 218.700604 -40.390572)
		(end 231.788208 -53.478176)
		(width 0.1651)
		(layer "F.Cu")
		(net "M_A_DQ<10>")
	)
	(segment
		(start 218.700604 -28.861004)
		(end 218.700604 -35.814)
		(width 0.1651)
		(layer "F.Cu")
		(net "M_A_DQ<10>")
	)
	(segment
		(start 231.788208 -53.478176)
		(end 232.343452 -54.03342)
		(width 0.0889)
		(layer "F.Cu")
		(net "M_A_DQ<10>")
	)
	(segment
		(start 214.381334 -18.67154)
		(end 214.249762 -18.539968)
		(width 0.1651)
		(layer "F.Cu")
		(net "M_A_DQ<10>")
	)
	(segment
		(start 215.820752 -25.02916)
		(end 215.587072 -25.02916)
		(width 0.1651)
		(layer "F.Cu")
		(net "M_A_DQ<10>")
	)
	(segment
		(start 213.399878 -23.560278)
		(end 214.63508 -24.79548)
		(width 0.1651)
		(layer "F.Cu")
		(net "M_A_DQ<10>")
	)
	(segment
		(start 219.541852 -28.031948)
		(end 219.299536 -28.274264)
		(width 0.1651)
		(layer "F.Cu")
		(net "M_A_DQ<10>")
	)
	(segment
		(start 214.250524 -20.023582)
		(end 214.250524 -19.02587)
		(width 0.1651)
		(layer "F.Cu")
		(net "M_A_DQ<10>")
	)
	(segment
		(start 218.700604 -35.814)
		(end 218.700604 -40.390572)
		(width 0.1651)
		(layer "F.Cu")
		(net "M_A_DQ<10>")
	)
	(segment
		(start 215.344756 -25.505156)
		(end 218.700604 -28.861004)
		(width 0.1651)
		(layer "F.Cu")
		(net "M_A_DQ<10>")
	)
	(segment
		(start 215.820752 -24.077168)
		(end 219.541852 -27.798268)
		(width 0.1651)
		(layer "F.Cu")
		(net "M_A_DQ<10>")
	)
	(segment
		(start 219.299536 -28.274264)
		(end 219.065856 -28.274264)
		(width 0.1651)
		(layer "F.Cu")
		(net "M_A_DQ<10>")
	)
	(segment
		(start 214.86876 -24.79548)
		(end 215.587072 -24.077168)
		(width 0.1651)
		(layer "F.Cu")
		(net "M_A_DQ<10>")
	)
	(via
		(at 213.399878 -23.560278)
		(size 0.508)
		(drill 0.254)
		(layers "F.Cu" "B.Cu")
		(net "M_A_DQ<10>")
	)
	(via
		(at 218.700604 -35.814)
		(size 0.508)
		(drill 0.254)
		(layers "F.Cu" "B.Cu")
		(net "M_A_DQ<10>")
	)
	(via
		(at 214.249762 -18.2626)
		(size 0.508)
		(drill 0.254)
		(layers "F.Cu" "B.Cu")
		(net "M_A_DQ<10>")
	)
	(segment
		(start 213.400386 -24.824182)
		(end 213.399878 -24.824182)
		(width 0.1651)
		(layer "B.Cu")
		(net "M_A_DQ<10>")
	)
	(segment
		(start 213.399878 -24.824182)
		(end 213.399878 -23.560278)
		(width 0.1651)
		(layer "B.Cu")
		(net "M_A_DQ<10>")
	)
	(segment
		(start 213.115144 -23.275544)
		(end 213.115144 -22.5298)
		(width 0.14224)
		(layer "In2.Cu")
		(net "M_A_DQ<10>")
	)
	(segment
		(start 213.851744 -18.660618)
		(end 214.249762 -18.2626)
		(width 0.14224)
		(layer "In2.Cu")
		(net "M_A_DQ<10>")
	)
	(segment
		(start 213.506812 -19.659346)
		(end 213.506812 -19.310604)
		(width 0.14224)
		(layer "In2.Cu")
		(net "M_A_DQ<10>")
	)
	(segment
		(start 213.506812 -19.310604)
		(end 213.851744 -18.965672)
		(width 0.14224)
		(layer "In2.Cu")
		(net "M_A_DQ<10>")
	)
	(segment
		(start 213.851744 -18.965672)
		(end 213.851744 -18.660618)
		(width 0.14224)
		(layer "In2.Cu")
		(net "M_A_DQ<10>")
	)
	(segment
		(start 213.964012 -21.680932)
		(end 213.964012 -21.4122)
		(width 0.14224)
		(layer "In2.Cu")
		(net "M_A_DQ<10>")
	)
	(segment
		(start 213.506812 -20.955)
		(end 213.506812 -20.55495)
		(width 0.14224)
		(layer "In2.Cu")
		(net "M_A_DQ<10>")
	)
	(segment
		(start 213.399878 -23.560278)
		(end 213.115144 -23.275544)
		(width 0.14224)
		(layer "In2.Cu")
		(net "M_A_DQ<10>")
	)
	(segment
		(start 213.506812 -20.55495)
		(end 213.811612 -20.25015)
		(width 0.14224)
		(layer "In2.Cu")
		(net "M_A_DQ<10>")
	)
	(segment
		(start 213.964012 -21.4122)
		(end 213.506812 -20.955)
		(width 0.14224)
		(layer "In2.Cu")
		(net "M_A_DQ<10>")
	)
	(segment
		(start 213.811612 -20.25015)
		(end 213.811612 -19.964146)
		(width 0.14224)
		(layer "In2.Cu")
		(net "M_A_DQ<10>")
	)
	(segment
		(start 213.115144 -22.5298)
		(end 213.964012 -21.680932)
		(width 0.14224)
		(layer "In2.Cu")
		(net "M_A_DQ<10>")
	)
	(segment
		(start 213.811612 -19.964146)
		(end 213.506812 -19.659346)
		(width 0.14224)
		(layer "In2.Cu")
		(net "M_A_DQ<10>")
	)
	(segment
		(start 198.949818 -20.023582)
		(end 198.869046 -19.177)
		(width 0.1651)
		(layer "F.Cu")
		(net "M_A_DQ<0>")
	)
	(segment
		(start 198.950326 -20.023582)
		(end 198.949818 -20.023582)
		(width 0.1651)
		(layer "F.Cu")
		(net "M_A_DQ<0>")
	)
	(segment
		(start 232.749598 -65.49644)
		(end 232.101898 -65.49644)
		(width 0.1016)
		(layer "F.Cu")
		(net "M_A_DQ<0>")
	)
	(segment
		(start 198.869046 -19.177)
		(end 198.772018 -18.161)
		(width 0.1651)
		(layer "F.Cu")
		(net "M_A_DQ<0>")
	)
	(via
		(at 198.772018 -18.161)
		(size 0.508)
		(drill 0.254)
		(layers "F.Cu" "B.Cu")
		(net "M_A_DQ<0>")
	)
	(via
		(at 198.099934 -23.560278)
		(size 0.508)
		(drill 0.254)
		(layers "F.Cu" "B.Cu")
		(net "M_A_DQ<0>")
	)
	(via
		(at 232.101898 -65.49644)
		(size 0.508)
		(drill 0.254)
		(layers "F.Cu" "B.Cu")
		(net "M_A_DQ<0>")
	)
	(segment
		(start 198.099934 -24.824182)
		(end 198.099934 -23.560278)
		(width 0.1651)
		(layer "B.Cu")
		(net "M_A_DQ<0>")
	)
	(segment
		(start 198.100442 -24.824182)
		(end 198.099934 -24.824182)
		(width 0.1651)
		(layer "B.Cu")
		(net "M_A_DQ<0>")
	)
	(segment
		(start 198.356728 -29.419296)
		(end 198.498968 -29.561536)
		(width 0.14224)
		(layer "In2.Cu")
		(net "M_A_DQ<0>")
	)
	(segment
		(start 198.00824 -30.069536)
		(end 197.866 -30.211776)
		(width 0.14224)
		(layer "In2.Cu")
		(net "M_A_DQ<0>")
	)
	(segment
		(start 198.5518 -18.381218)
		(end 198.5518 -18.965672)
		(width 0.14224)
		(layer "In2.Cu")
		(net "M_A_DQ<0>")
	)
	(segment
		(start 197.866 -31.512256)
		(end 197.866 -31.878016)
		(width 0.14224)
		(layer "In2.Cu")
		(net "M_A_DQ<0>")
	)
	(segment
		(start 198.00824 -31.370016)
		(end 197.866 -31.512256)
		(width 0.14224)
		(layer "In2.Cu")
		(net "M_A_DQ<0>")
	)
	(segment
		(start 198.162418 -20.903946)
		(end 198.5518 -21.293328)
		(width 0.14224)
		(layer "In2.Cu")
		(net "M_A_DQ<0>")
	)
	(segment
		(start 197.492112 -27.50439)
		(end 197.724522 -27.7368)
		(width 0.14224)
		(layer "In2.Cu")
		(net "M_A_DQ<0>")
	)
	(segment
		(start 197.866 -30.211776)
		(end 197.866 -30.577536)
		(width 0.14224)
		(layer "In2.Cu")
		(net "M_A_DQ<0>")
	)
	(segment
		(start 197.866 -30.577536)
		(end 198.00824 -30.719776)
		(width 0.14224)
		(layer "In2.Cu")
		(net "M_A_DQ<0>")
	)
	(segment
		(start 198.479918 -20.2819)
		(end 198.162418 -20.5994)
		(width 0.14224)
		(layer "In2.Cu")
		(net "M_A_DQ<0>")
	)
	(segment
		(start 197.8152 -23.275544)
		(end 198.099934 -23.560278)
		(width 0.14224)
		(layer "In2.Cu")
		(net "M_A_DQ<0>")
	)
	(segment
		(start 198.498968 -30.862016)
		(end 198.498968 -31.227776)
		(width 0.14224)
		(layer "In2.Cu")
		(net "M_A_DQ<0>")
	)
	(segment
		(start 198.356728 -28.769056)
		(end 198.00824 -28.769056)
		(width 0.14224)
		(layer "In2.Cu")
		(net "M_A_DQ<0>")
	)
	(segment
		(start 198.5518 -21.7932)
		(end 197.8152 -22.5298)
		(width 0.14224)
		(layer "In2.Cu")
		(net "M_A_DQ<0>")
	)
	(segment
		(start 198.356728 -32.020256)
		(end 198.498968 -32.162496)
		(width 0.14224)
		(layer "In2.Cu")
		(net "M_A_DQ<0>")
	)
	(segment
		(start 198.137018 -19.7104)
		(end 198.479918 -20.0533)
		(width 0.14224)
		(layer "In2.Cu")
		(net "M_A_DQ<0>")
	)
	(segment
		(start 198.00824 -29.419296)
		(end 198.356728 -29.419296)
		(width 0.14224)
		(layer "In2.Cu")
		(net "M_A_DQ<0>")
	)
	(segment
		(start 197.866 -28.911296)
		(end 197.866 -29.277056)
		(width 0.14224)
		(layer "In2.Cu")
		(net "M_A_DQ<0>")
	)
	(segment
		(start 231.873806 -65.49644)
		(end 232.101898 -65.49644)
		(width 0.0889)
		(layer "In2.Cu")
		(net "M_A_DQ<0>")
	)
	(segment
		(start 198.356728 -30.069536)
		(end 198.00824 -30.069536)
		(width 0.14224)
		(layer "In2.Cu")
		(net "M_A_DQ<0>")
	)
	(segment
		(start 198.498968 -36.59124)
		(end 228.03993 -66.132202)
		(width 0.14224)
		(layer "In2.Cu")
		(net "M_A_DQ<0>")
	)
	(segment
		(start 230.632 -66.132202)
		(end 231.238044 -66.132202)
		(width 0.0889)
		(layer "In2.Cu")
		(net "M_A_DQ<0>")
	)
	(segment
		(start 197.866 -31.878016)
		(end 198.00824 -32.020256)
		(width 0.14224)
		(layer "In2.Cu")
		(net "M_A_DQ<0>")
	)
	(segment
		(start 198.498968 -29.561536)
		(end 198.498968 -29.927296)
		(width 0.14224)
		(layer "In2.Cu")
		(net "M_A_DQ<0>")
	)
	(segment
		(start 198.162418 -20.5994)
		(end 198.162418 -20.903946)
		(width 0.14224)
		(layer "In2.Cu")
		(net "M_A_DQ<0>")
	)
	(segment
		(start 231.238044 -66.132202)
		(end 231.873806 -65.49644)
		(width 0.0889)
		(layer "In2.Cu")
		(net "M_A_DQ<0>")
	)
	(segment
		(start 198.5518 -21.293328)
		(end 198.5518 -21.7932)
		(width 0.14224)
		(layer "In2.Cu")
		(net "M_A_DQ<0>")
	)
	(segment
		(start 198.137018 -19.380454)
		(end 198.137018 -19.7104)
		(width 0.14224)
		(layer "In2.Cu")
		(net "M_A_DQ<0>")
	)
	(segment
		(start 198.498968 -29.927296)
		(end 198.356728 -30.069536)
		(width 0.14224)
		(layer "In2.Cu")
		(net "M_A_DQ<0>")
	)
	(segment
		(start 198.498968 -27.856688)
		(end 198.498968 -28.626816)
		(width 0.14224)
		(layer "In2.Cu")
		(net "M_A_DQ<0>")
	)
	(segment
		(start 198.00824 -30.719776)
		(end 198.356728 -30.719776)
		(width 0.14224)
		(layer "In2.Cu")
		(net "M_A_DQ<0>")
	)
	(segment
		(start 228.03993 -66.132202)
		(end 230.632 -66.132202)
		(width 0.14224)
		(layer "In2.Cu")
		(net "M_A_DQ<0>")
	)
	(segment
		(start 198.498968 -31.227776)
		(end 198.356728 -31.370016)
		(width 0.14224)
		(layer "In2.Cu")
		(net "M_A_DQ<0>")
	)
	(segment
		(start 197.492112 -24.1681)
		(end 197.492112 -27.50439)
		(width 0.14224)
		(layer "In2.Cu")
		(net "M_A_DQ<0>")
	)
	(segment
		(start 197.8152 -22.5298)
		(end 197.8152 -23.275544)
		(width 0.14224)
		(layer "In2.Cu")
		(net "M_A_DQ<0>")
	)
	(segment
		(start 198.37908 -27.7368)
		(end 198.498968 -27.856688)
		(width 0.14224)
		(layer "In2.Cu")
		(net "M_A_DQ<0>")
	)
	(segment
		(start 197.866 -29.277056)
		(end 198.00824 -29.419296)
		(width 0.14224)
		(layer "In2.Cu")
		(net "M_A_DQ<0>")
	)
	(segment
		(start 197.724522 -27.7368)
		(end 198.37908 -27.7368)
		(width 0.14224)
		(layer "In2.Cu")
		(net "M_A_DQ<0>")
	)
	(segment
		(start 198.356728 -31.370016)
		(end 198.00824 -31.370016)
		(width 0.14224)
		(layer "In2.Cu")
		(net "M_A_DQ<0>")
	)
	(segment
		(start 198.479918 -20.0533)
		(end 198.479918 -20.2819)
		(width 0.14224)
		(layer "In2.Cu")
		(net "M_A_DQ<0>")
	)
	(segment
		(start 198.00824 -28.769056)
		(end 197.866 -28.911296)
		(width 0.14224)
		(layer "In2.Cu")
		(net "M_A_DQ<0>")
	)
	(segment
		(start 198.5518 -18.965672)
		(end 198.137018 -19.380454)
		(width 0.14224)
		(layer "In2.Cu")
		(net "M_A_DQ<0>")
	)
	(segment
		(start 198.00824 -32.020256)
		(end 198.356728 -32.020256)
		(width 0.14224)
		(layer "In2.Cu")
		(net "M_A_DQ<0>")
	)
	(segment
		(start 198.356728 -30.719776)
		(end 198.498968 -30.862016)
		(width 0.14224)
		(layer "In2.Cu")
		(net "M_A_DQ<0>")
	)
	(segment
		(start 198.772018 -18.161)
		(end 198.5518 -18.381218)
		(width 0.14224)
		(layer "In2.Cu")
		(net "M_A_DQ<0>")
	)
	(segment
		(start 198.099934 -23.560278)
		(end 197.492112 -24.1681)
		(width 0.14224)
		(layer "In2.Cu")
		(net "M_A_DQ<0>")
	)
	(segment
		(start 198.498968 -32.162496)
		(end 198.498968 -36.59124)
		(width 0.14224)
		(layer "In2.Cu")
		(net "M_A_DQ<0>")
	)
	(segment
		(start 198.498968 -28.626816)
		(end 198.356728 -28.769056)
		(width 0.14224)
		(layer "In2.Cu")
		(net "M_A_DQ<0>")
	)
	(segment
		(start 269.5194 -49.885346)
		(end 269.69085 -49.713896)
		(width 0.1651)
		(layer "F.Cu")
		(net "M_A_CS_N<7>")
	)
	(segment
		(start 267.948156 -54.104286)
		(end 268.348714 -54.104286)
		(width 0.1651)
		(layer "F.Cu")
		(net "M_A_CS_N<7>")
	)
	(segment
		(start 268.348714 -54.104286)
		(end 269.5194 -52.9336)
		(width 0.1651)
		(layer "F.Cu")
		(net "M_A_CS_N<7>")
	)
	(segment
		(start 276.987 -26.424382)
		(end 278.4856 -24.925782)
		(width 0.1651)
		(layer "F.Cu")
		(net "M_A_CS_N<7>")
	)
	(segment
		(start 278.282654 -21.800058)
		(end 277.999952 -21.517356)
		(width 0.1651)
		(layer "F.Cu")
		(net "M_A_CS_N<7>")
	)
	(segment
		(start 269.5194 -52.9336)
		(end 269.5194 -49.885346)
		(width 0.1651)
		(layer "F.Cu")
		(net "M_A_CS_N<7>")
	)
	(segment
		(start 278.4856 -24.925782)
		(end 278.4856 -22.6314)
		(width 0.1651)
		(layer "F.Cu")
		(net "M_A_CS_N<7>")
	)
	(segment
		(start 269.69085 -33.720532)
		(end 276.987 -26.424382)
		(width 0.1651)
		(layer "F.Cu")
		(net "M_A_CS_N<7>")
	)
	(segment
		(start 269.69085 -49.713896)
		(end 269.69085 -33.720532)
		(width 0.1651)
		(layer "F.Cu")
		(net "M_A_CS_N<7>")
	)
	(segment
		(start 278.282654 -22.428454)
		(end 278.282654 -21.800058)
		(width 0.1651)
		(layer "F.Cu")
		(net "M_A_CS_N<7>")
	)
	(segment
		(start 278.4856 -22.6314)
		(end 278.282654 -22.428454)
		(width 0.1651)
		(layer "F.Cu")
		(net "M_A_CS_N<7>")
	)
	(via
		(at 277.999952 -21.517356)
		(size 0.508)
		(drill 0.254)
		(layers "F.Cu" "B.Cu")
		(net "M_A_CS_N<7>")
	)
	(via
		(at 276.987 -26.424382)
		(size 0.508)
		(drill 0.254)
		(layers "F.Cu" "B.Cu")
		(net "M_A_CS_N<7>")
	)
	(segment
		(start 277.999952 -20.224242)
		(end 277.999952 -21.517356)
		(width 0.1651)
		(layer "B.Cu")
		(net "M_A_CS_N<7>")
	)
	(segment
		(start 278.00046 -20.224242)
		(end 277.999952 -20.224242)
		(width 0.1651)
		(layer "B.Cu")
		(net "M_A_CS_N<7>")
	)
	(segment
		(start 276.848824 -25.837896)
		(end 276.848824 -25.604216)
		(width 0.1651)
		(layer "F.Cu")
		(net "M_A_CS_N<6>")
	)
	(segment
		(start 276.399244 -24.920956)
		(end 276.63267 -24.68753)
		(width 0.1651)
		(layer "F.Cu")
		(net "M_A_CS_N<6>")
	)
	(segment
		(start 275.897848 -26.527252)
		(end 275.465286 -26.09469)
		(width 0.1651)
		(layer "F.Cu")
		(net "M_A_CS_N<6>")
	)
	(segment
		(start 268.7447 -52.12334)
		(end 268.9606 -51.90744)
		(width 0.1651)
		(layer "F.Cu")
		(net "M_A_CS_N<6>")
	)
	(segment
		(start 269.18666 -49.43094)
		(end 269.18666 -33.47212)
		(width 0.1651)
		(layer "F.Cu")
		(net "M_A_CS_N<6>")
	)
	(segment
		(start 276.86635 -24.68753)
		(end 277.31593 -25.13711)
		(width 0.1651)
		(layer "F.Cu")
		(net "M_A_CS_N<6>")
	)
	(segment
		(start 276.63267 -24.68753)
		(end 276.86635 -24.68753)
		(width 0.1651)
		(layer "F.Cu")
		(net "M_A_CS_N<6>")
	)
	(segment
		(start 277.7998 -24.88692)
		(end 277.7998 -23.051008)
		(width 0.1651)
		(layer "F.Cu")
		(net "M_A_CS_N<6>")
	)
	(segment
		(start 277.7998 -23.051008)
		(end 277.999952 -22.850856)
		(width 0.1651)
		(layer "F.Cu")
		(net "M_A_CS_N<6>")
	)
	(segment
		(start 268.9606 -49.657)
		(end 269.18666 -49.43094)
		(width 0.1651)
		(layer "F.Cu")
		(net "M_A_CS_N<6>")
	)
	(segment
		(start 274.610068 -28.048712)
		(end 275.897848 -26.760932)
		(width 0.1651)
		(layer "F.Cu")
		(net "M_A_CS_N<6>")
	)
	(segment
		(start 268.9606 -51.90744)
		(end 268.9606 -49.657)
		(width 0.1651)
		(layer "F.Cu")
		(net "M_A_CS_N<6>")
	)
	(segment
		(start 277.54961 -25.13711)
		(end 277.7998 -24.88692)
		(width 0.1651)
		(layer "F.Cu")
		(net "M_A_CS_N<6>")
	)
	(segment
		(start 276.399244 -25.154636)
		(end 276.399244 -24.920956)
		(width 0.1651)
		(layer "F.Cu")
		(net "M_A_CS_N<6>")
	)
	(segment
		(start 267.948156 -52.12334)
		(end 268.7447 -52.12334)
		(width 0.1651)
		(layer "F.Cu")
		(net "M_A_CS_N<6>")
	)
	(segment
		(start 276.378924 -26.074116)
		(end 276.612604 -26.074116)
		(width 0.1651)
		(layer "F.Cu")
		(net "M_A_CS_N<6>")
	)
	(segment
		(start 275.465286 -26.09469)
		(end 275.465286 -25.86101)
		(width 0.1651)
		(layer "F.Cu")
		(net "M_A_CS_N<6>")
	)
	(segment
		(start 269.18666 -33.47212)
		(end 274.610068 -28.048712)
		(width 0.1651)
		(layer "F.Cu")
		(net "M_A_CS_N<6>")
	)
	(segment
		(start 275.932392 -25.627584)
		(end 276.378924 -26.074116)
		(width 0.1651)
		(layer "F.Cu")
		(net "M_A_CS_N<6>")
	)
	(segment
		(start 275.897848 -26.760932)
		(end 275.897848 -26.527252)
		(width 0.1651)
		(layer "F.Cu")
		(net "M_A_CS_N<6>")
	)
	(segment
		(start 276.612604 -26.074116)
		(end 276.848824 -25.837896)
		(width 0.1651)
		(layer "F.Cu")
		(net "M_A_CS_N<6>")
	)
	(segment
		(start 276.848824 -25.604216)
		(end 276.399244 -25.154636)
		(width 0.1651)
		(layer "F.Cu")
		(net "M_A_CS_N<6>")
	)
	(segment
		(start 277.31593 -25.13711)
		(end 277.54961 -25.13711)
		(width 0.1651)
		(layer "F.Cu")
		(net "M_A_CS_N<6>")
	)
	(segment
		(start 275.465286 -25.86101)
		(end 275.698712 -25.627584)
		(width 0.1651)
		(layer "F.Cu")
		(net "M_A_CS_N<6>")
	)
	(segment
		(start 275.698712 -25.627584)
		(end 275.932392 -25.627584)
		(width 0.1651)
		(layer "F.Cu")
		(net "M_A_CS_N<6>")
	)
	(via
		(at 274.610068 -28.048712)
		(size 0.508)
		(drill 0.254)
		(layers "F.Cu" "B.Cu")
		(net "M_A_CS_N<6>")
	)
	(via
		(at 277.999952 -22.850856)
		(size 0.508)
		(drill 0.254)
		(layers "F.Cu" "B.Cu")
		(net "M_A_CS_N<6>")
	)
	(segment
		(start 278.00046 -24.824182)
		(end 277.999952 -24.824182)
		(width 0.1651)
		(layer "B.Cu")
		(net "M_A_CS_N<6>")
	)
	(segment
		(start 277.999952 -24.824182)
		(end 277.999952 -22.850856)
		(width 0.1651)
		(layer "B.Cu")
		(net "M_A_CS_N<6>")
	)
	(segment
		(start 274.32 -24.714454)
		(end 274.111212 -24.923242)
		(width 0.1651)
		(layer "F.Cu")
		(net "M_A_CS_N<5>")
	)
	(segment
		(start 274.32 -23.622)
		(end 274.32 -24.714454)
		(width 0.1651)
		(layer "F.Cu")
		(net "M_A_CS_N<5>")
	)
	(segment
		(start 274.111212 -24.923242)
		(end 273.774154 -24.923242)
		(width 0.1651)
		(layer "F.Cu")
		(net "M_A_CS_N<5>")
	)
	(segment
		(start 264.95248 -50.270918)
		(end 264.51433 -51.132486)
		(width 0.0889)
		(layer "F.Cu")
		(net "M_A_CS_N<5>")
	)
	(segment
		(start 274.599908 -22.850856)
		(end 274.599908 -23.342092)
		(width 0.1651)
		(layer "F.Cu")
		(net "M_A_CS_N<5>")
	)
	(segment
		(start 273.6088 -24.276304)
		(end 273.4437 -24.111204)
		(width 0.1651)
		(layer "F.Cu")
		(net "M_A_CS_N<5>")
	)
	(segment
		(start 271.4498 -27.185874)
		(end 266.66571 -31.969964)
		(width 0.1651)
		(layer "F.Cu")
		(net "M_A_CS_N<5>")
	)
	(segment
		(start 271.8816 -25.6032)
		(end 271.4498 -26.035)
		(width 0.1651)
		(layer "F.Cu")
		(net "M_A_CS_N<5>")
	)
	(segment
		(start 274.599908 -23.342092)
		(end 274.32 -23.622)
		(width 0.1651)
		(layer "F.Cu")
		(net "M_A_CS_N<5>")
	)
	(segment
		(start 266.66571 -47.720758)
		(end 266.66571 -48.113188)
		(width 0.0889)
		(layer "F.Cu")
		(net "M_A_CS_N<5>")
	)
	(segment
		(start 272.542254 -25.6032)
		(end 271.8816 -25.6032)
		(width 0.1651)
		(layer "F.Cu")
		(net "M_A_CS_N<5>")
	)
	(segment
		(start 272.909284 -25.23617)
		(end 272.542254 -25.6032)
		(width 0.1651)
		(layer "F.Cu")
		(net "M_A_CS_N<5>")
	)
	(segment
		(start 266.66571 -31.969964)
		(end 266.66571 -47.720758)
		(width 0.1651)
		(layer "F.Cu")
		(net "M_A_CS_N<5>")
	)
	(segment
		(start 265.304778 -49.47412)
		(end 265.185906 -49.7078)
		(width 0.0889)
		(layer "F.Cu")
		(net "M_A_CS_N<5>")
	)
	(segment
		(start 271.4498 -26.035)
		(end 271.4498 -26.593038)
		(width 0.1651)
		(layer "F.Cu")
		(net "M_A_CS_N<5>")
	)
	(segment
		(start 265.185906 -49.7078)
		(end 264.95248 -50.270918)
		(width 0.0889)
		(layer "F.Cu")
		(net "M_A_CS_N<5>")
	)
	(segment
		(start 273.105626 -24.111204)
		(end 272.909284 -24.307546)
		(width 0.1651)
		(layer "F.Cu")
		(net "M_A_CS_N<5>")
	)
	(segment
		(start 272.909284 -24.307546)
		(end 272.909284 -25.23617)
		(width 0.1651)
		(layer "F.Cu")
		(net "M_A_CS_N<5>")
	)
	(segment
		(start 273.4437 -24.111204)
		(end 273.105626 -24.111204)
		(width 0.1651)
		(layer "F.Cu")
		(net "M_A_CS_N<5>")
	)
	(segment
		(start 266.66571 -48.113188)
		(end 265.304778 -49.47412)
		(width 0.0889)
		(layer "F.Cu")
		(net "M_A_CS_N<5>")
	)
	(segment
		(start 273.6088 -24.757888)
		(end 273.6088 -24.276304)
		(width 0.1651)
		(layer "F.Cu")
		(net "M_A_CS_N<5>")
	)
	(segment
		(start 273.774154 -24.923242)
		(end 273.6088 -24.757888)
		(width 0.1651)
		(layer "F.Cu")
		(net "M_A_CS_N<5>")
	)
	(segment
		(start 271.4498 -26.593038)
		(end 271.4498 -27.185874)
		(width 0.1651)
		(layer "F.Cu")
		(net "M_A_CS_N<5>")
	)
	(via
		(at 274.599908 -22.850856)
		(size 0.508)
		(drill 0.254)
		(layers "F.Cu" "B.Cu")
		(net "M_A_CS_N<5>")
	)
	(via
		(at 271.4498 -26.593038)
		(size 0.508)
		(drill 0.254)
		(layers "F.Cu" "B.Cu")
		(net "M_A_CS_N<5>")
	)
	(segment
		(start 274.599908 -24.824182)
		(end 274.599908 -22.850856)
		(width 0.1651)
		(layer "B.Cu")
		(net "M_A_CS_N<5>")
	)
	(segment
		(start 274.600416 -24.824182)
		(end 274.599908 -24.824182)
		(width 0.1651)
		(layer "B.Cu")
		(net "M_A_CS_N<5>")
	)
	(segment
		(start 266.16914 -27.99334)
		(end 266.16914 -27.73426)
		(width 0.1651)
		(layer "F.Cu")
		(net "M_A_CS_N<4>")
	)
	(segment
		(start 266.93622 -27.63266)
		(end 267.183362 -27.63266)
		(width 0.1651)
		(layer "F.Cu")
		(net "M_A_CS_N<4>")
	)
	(segment
		(start 269.360396 -22.195028)
		(end 269.639288 -22.195028)
		(width 0.1651)
		(layer "F.Cu")
		(net "M_A_CS_N<4>")
	)
	(segment
		(start 266.378944 -28.203144)
		(end 266.16914 -27.99334)
		(width 0.1651)
		(layer "F.Cu")
		(net "M_A_CS_N<4>")
	)
	(segment
		(start 266.48664 -27.41676)
		(end 266.72032 -27.41676)
		(width 0.1651)
		(layer "F.Cu")
		(net "M_A_CS_N<4>")
	)
	(segment
		(start 267.4112 -25.6794)
		(end 268.59357 -24.49703)
		(width 0.1651)
		(layer "F.Cu")
		(net "M_A_CS_N<4>")
	)
	(segment
		(start 269.9766 -23.187152)
		(end 270.349726 -23.560278)
		(width 0.1651)
		(layer "F.Cu")
		(net "M_A_CS_N<4>")
	)
	(segment
		(start 269.639288 -22.195028)
		(end 269.9766 -22.53234)
		(width 0.1651)
		(layer "F.Cu")
		(net "M_A_CS_N<4>")
	)
	(segment
		(start 262.79729 -49.419764)
		(end 264.14476 -48.072294)
		(width 0.0889)
		(layer "F.Cu")
		(net "M_A_CS_N<4>")
	)
	(segment
		(start 269.352522 -24.72055)
		(end 269.6464 -24.426672)
		(width 0.1651)
		(layer "F.Cu")
		(net "M_A_CS_N<4>")
	)
	(segment
		(start 268.59357 -24.49703)
		(end 268.82725 -24.49703)
		(width 0.1651)
		(layer "F.Cu")
		(net "M_A_CS_N<4>")
	)
	(segment
		(start 269.05077 -24.72055)
		(end 269.352522 -24.72055)
		(width 0.1651)
		(layer "F.Cu")
		(net "M_A_CS_N<4>")
	)
	(segment
		(start 264.14476 -30.671262)
		(end 265.654536 -29.161486)
		(width 0.1651)
		(layer "F.Cu")
		(net "M_A_CS_N<4>")
	)
	(segment
		(start 266.378944 -28.437078)
		(end 266.378944 -28.203144)
		(width 0.1651)
		(layer "F.Cu")
		(net "M_A_CS_N<4>")
	)
	(segment
		(start 269.6464 -24.426672)
		(end 269.6464 -24.1554)
		(width 0.1651)
		(layer "F.Cu")
		(net "M_A_CS_N<4>")
	)
	(segment
		(start 269.6464 -24.1554)
		(end 269.294356 -23.803356)
		(width 0.1651)
		(layer "F.Cu")
		(net "M_A_CS_N<4>")
	)
	(segment
		(start 267.183362 -27.63266)
		(end 267.4112 -27.404822)
		(width 0.1651)
		(layer "F.Cu")
		(net "M_A_CS_N<4>")
	)
	(segment
		(start 265.654536 -29.161486)
		(end 266.378944 -28.437078)
		(width 0.1651)
		(layer "F.Cu")
		(net "M_A_CS_N<4>")
	)
	(segment
		(start 266.16914 -27.73426)
		(end 266.48664 -27.41676)
		(width 0.1651)
		(layer "F.Cu")
		(net "M_A_CS_N<4>")
	)
	(segment
		(start 268.863064 -22.69236)
		(end 269.360396 -22.195028)
		(width 0.1651)
		(layer "F.Cu")
		(net "M_A_CS_N<4>")
	)
	(segment
		(start 269.294356 -23.422356)
		(end 268.863064 -22.991064)
		(width 0.1651)
		(layer "F.Cu")
		(net "M_A_CS_N<4>")
	)
	(segment
		(start 268.863064 -22.991064)
		(end 268.863064 -22.69236)
		(width 0.1651)
		(layer "F.Cu")
		(net "M_A_CS_N<4>")
	)
	(segment
		(start 269.294356 -23.803356)
		(end 269.294356 -23.422356)
		(width 0.1651)
		(layer "F.Cu")
		(net "M_A_CS_N<4>")
	)
	(segment
		(start 264.14476 -47.470568)
		(end 264.14476 -30.671262)
		(width 0.1651)
		(layer "F.Cu")
		(net "M_A_CS_N<4>")
	)
	(segment
		(start 269.9766 -22.53234)
		(end 269.9766 -23.187152)
		(width 0.1651)
		(layer "F.Cu")
		(net "M_A_CS_N<4>")
	)
	(segment
		(start 262.79729 -50.141886)
		(end 262.79729 -49.419764)
		(width 0.0889)
		(layer "F.Cu")
		(net "M_A_CS_N<4>")
	)
	(segment
		(start 266.72032 -27.41676)
		(end 266.93622 -27.63266)
		(width 0.1651)
		(layer "F.Cu")
		(net "M_A_CS_N<4>")
	)
	(segment
		(start 268.82725 -24.49703)
		(end 269.05077 -24.72055)
		(width 0.1651)
		(layer "F.Cu")
		(net "M_A_CS_N<4>")
	)
	(segment
		(start 264.14476 -48.072294)
		(end 264.14476 -47.470568)
		(width 0.0889)
		(layer "F.Cu")
		(net "M_A_CS_N<4>")
	)
	(segment
		(start 267.4112 -27.404822)
		(end 267.4112 -25.6794)
		(width 0.1651)
		(layer "F.Cu")
		(net "M_A_CS_N<4>")
	)
	(via
		(at 270.349726 -23.560278)
		(size 0.508)
		(drill 0.254)
		(layers "F.Cu" "B.Cu")
		(net "M_A_CS_N<4>")
	)
	(via
		(at 265.654536 -29.161486)
		(size 0.508)
		(drill 0.254)
		(layers "F.Cu" "B.Cu")
		(net "M_A_CS_N<4>")
	)
	(segment
		(start 270.34998 -24.824182)
		(end 270.34998 -23.560532)
		(width 0.1651)
		(layer "B.Cu")
		(net "M_A_CS_N<4>")
	)
	(segment
		(start 270.34998 -23.560532)
		(end 270.349726 -23.560278)
		(width 0.1651)
		(layer "B.Cu")
		(net "M_A_CS_N<4>")
	)
	(segment
		(start 270.350488 -24.824182)
		(end 270.34998 -24.824182)
		(width 0.1651)
		(layer "B.Cu")
		(net "M_A_CS_N<4>")
	)
	(segment
		(start 277.368 -22.6568)
		(end 277.2918 -22.6568)
		(width 0.1651)
		(layer "F.Cu")
		(net "M_A_CS_N<3>")
	)
	(segment
		(start 267.205206 -52.123594)
		(end 266.23137 -52.123594)
		(width 0.1651)
		(layer "F.Cu")
		(net "M_A_CS_N<3>")
	)
	(segment
		(start 276.6568 -23.8506)
		(end 274.759928 -25.747472)
		(width 0.1651)
		(layer "F.Cu")
		(net "M_A_CS_N<3>")
	)
	(segment
		(start 266.23137 -52.123594)
		(end 266.231116 -52.12334)
		(width 0.1651)
		(layer "F.Cu")
		(net "M_A_CS_N<3>")
	)
	(segment
		(start 274.759928 -27.14625)
		(end 268.68247 -33.223708)
		(width 0.1651)
		(layer "F.Cu")
		(net "M_A_CS_N<3>")
	)
	(segment
		(start 276.6568 -23.2918)
		(end 276.6568 -23.8506)
		(width 0.1651)
		(layer "F.Cu")
		(net "M_A_CS_N<3>")
	)
	(segment
		(start 267.725398 -51.603402)
		(end 267.205206 -52.123594)
		(width 0.1651)
		(layer "F.Cu")
		(net "M_A_CS_N<3>")
	)
	(segment
		(start 277.622 -21.971)
		(end 277.622 -22.4028)
		(width 0.1651)
		(layer "F.Cu")
		(net "M_A_CS_N<3>")
	)
	(segment
		(start 268.68247 -49.17313)
		(end 268.4272 -49.4284)
		(width 0.1651)
		(layer "F.Cu")
		(net "M_A_CS_N<3>")
	)
	(segment
		(start 274.759928 -26.445718)
		(end 274.759928 -27.14625)
		(width 0.1651)
		(layer "F.Cu")
		(net "M_A_CS_N<3>")
	)
	(segment
		(start 277.4696 -21.310854)
		(end 277.4696 -21.8186)
		(width 0.1651)
		(layer "F.Cu")
		(net "M_A_CS_N<3>")
	)
	(segment
		(start 277.4696 -21.8186)
		(end 277.622 -21.971)
		(width 0.1651)
		(layer "F.Cu")
		(net "M_A_CS_N<3>")
	)
	(segment
		(start 274.759928 -25.747472)
		(end 274.759928 -26.445718)
		(width 0.1651)
		(layer "F.Cu")
		(net "M_A_CS_N<3>")
	)
	(segment
		(start 277.999952 -20.780502)
		(end 277.4696 -21.310854)
		(width 0.1651)
		(layer "F.Cu")
		(net "M_A_CS_N<3>")
	)
	(segment
		(start 277.2918 -22.6568)
		(end 276.6568 -23.2918)
		(width 0.1651)
		(layer "F.Cu")
		(net "M_A_CS_N<3>")
	)
	(segment
		(start 268.4272 -51.238404)
		(end 268.062202 -51.603402)
		(width 0.1651)
		(layer "F.Cu")
		(net "M_A_CS_N<3>")
	)
	(segment
		(start 278.00046 -20.023582)
		(end 277.999952 -20.023582)
		(width 0.1651)
		(layer "F.Cu")
		(net "M_A_CS_N<3>")
	)
	(segment
		(start 268.4272 -49.4284)
		(end 268.4272 -51.238404)
		(width 0.1651)
		(layer "F.Cu")
		(net "M_A_CS_N<3>")
	)
	(segment
		(start 277.999952 -20.023582)
		(end 277.999952 -20.780502)
		(width 0.1651)
		(layer "F.Cu")
		(net "M_A_CS_N<3>")
	)
	(segment
		(start 268.062202 -51.603402)
		(end 267.725398 -51.603402)
		(width 0.1651)
		(layer "F.Cu")
		(net "M_A_CS_N<3>")
	)
	(segment
		(start 277.622 -22.4028)
		(end 277.368 -22.6568)
		(width 0.1651)
		(layer "F.Cu")
		(net "M_A_CS_N<3>")
	)
	(segment
		(start 268.68247 -33.223708)
		(end 268.68247 -49.17313)
		(width 0.1651)
		(layer "F.Cu")
		(net "M_A_CS_N<3>")
	)
	(via
		(at 274.759928 -26.445718)
		(size 0.508)
		(drill 0.254)
		(layers "F.Cu" "B.Cu")
		(net "M_A_CS_N<3>")
	)
	(segment
		(start 277.999952 -15.423642)
		(end 277.999952 -16.718788)
		(width 0.1651)
		(layer "F.Cu")
		(net "M_A_CS_N<2>")
	)
	(segment
		(start 274.100544 -27.053032)
		(end 274.100544 -26.652728)
		(width 0.1651)
		(layer "F.Cu")
		(net "M_A_CS_N<2>")
	)
	(segment
		(start 268.17828 -32.975296)
		(end 272.90395 -28.249626)
		(width 0.1651)
		(layer "F.Cu")
		(net "M_A_CS_N<2>")
	)
	(segment
		(start 268.17828 -48.93437)
		(end 268.17828 -48.438054)
		(width 0.0889)
		(layer "F.Cu")
		(net "M_A_CS_N<2>")
	)
	(segment
		(start 274.100544 -26.652728)
		(end 273.635216 -26.1874)
		(width 0.1651)
		(layer "F.Cu")
		(net "M_A_CS_N<2>")
	)
	(segment
		(start 268.17828 -48.438054)
		(end 268.17828 -32.975296)
		(width 0.1651)
		(layer "F.Cu")
		(net "M_A_CS_N<2>")
	)
	(segment
		(start 278.00046 -15.423642)
		(end 277.999952 -15.423642)
		(width 0.1651)
		(layer "F.Cu")
		(net "M_A_CS_N<2>")
	)
	(segment
		(start 266.231116 -51.132486)
		(end 266.726162 -50.466752)
		(width 0.0889)
		(layer "F.Cu")
		(net "M_A_CS_N<2>")
	)
	(segment
		(start 266.726162 -50.466752)
		(end 266.915138 -50.197512)
		(width 0.0889)
		(layer "F.Cu")
		(net "M_A_CS_N<2>")
	)
	(segment
		(start 272.90395 -28.249626)
		(end 274.100544 -27.053032)
		(width 0.1651)
		(layer "F.Cu")
		(net "M_A_CS_N<2>")
	)
	(segment
		(start 266.915138 -50.197512)
		(end 268.17828 -48.93437)
		(width 0.0889)
		(layer "F.Cu")
		(net "M_A_CS_N<2>")
	)
	(via
		(at 277.999952 -16.718788)
		(size 0.4572)
		(drill 0.2032)
		(layers "F.Cu" "B.Cu")
		(net "M_A_CS_N<2>")
	)
	(via
		(at 273.635216 -26.1874)
		(size 0.508)
		(drill 0.254)
		(layers "F.Cu" "B.Cu")
		(net "M_A_CS_N<2>")
	)
	(via
		(at 272.90395 -28.249626)
		(size 0.508)
		(drill 0.254)
		(layers "F.Cu" "B.Cu")
		(net "M_A_CS_N<2>")
	)
	(segment
		(start 274.067016 -25.7556)
		(end 274.2692 -25.7556)
		(width 0.14224)
		(layer "In9.Cu")
		(net "M_A_CS_N<2>")
	)
	(segment
		(start 274.2692 -25.7556)
		(end 277.622 -22.4028)
		(width 0.14224)
		(layer "In9.Cu")
		(net "M_A_CS_N<2>")
	)
	(segment
		(start 277.622 -21.9202)
		(end 277.5204 -21.8186)
		(width 0.14224)
		(layer "In9.Cu")
		(net "M_A_CS_N<2>")
	)
	(segment
		(start 273.635216 -26.1874)
		(end 274.067016 -25.7556)
		(width 0.14224)
		(layer "In9.Cu")
		(net "M_A_CS_N<2>")
	)
	(segment
		(start 277.589488 -19.336512)
		(end 277.589488 -17.129252)
		(width 0.14224)
		(layer "In9.Cu")
		(net "M_A_CS_N<2>")
	)
	(segment
		(start 277.622 -22.4028)
		(end 277.622 -21.9202)
		(width 0.14224)
		(layer "In9.Cu")
		(net "M_A_CS_N<2>")
	)
	(segment
		(start 277.5204 -21.8186)
		(end 277.5204 -19.4056)
		(width 0.14224)
		(layer "In9.Cu")
		(net "M_A_CS_N<2>")
	)
	(segment
		(start 277.5204 -19.4056)
		(end 277.589488 -19.336512)
		(width 0.14224)
		(layer "In9.Cu")
		(net "M_A_CS_N<2>")
	)
	(segment
		(start 277.589488 -17.129252)
		(end 277.999952 -16.718788)
		(width 0.14224)
		(layer "In9.Cu")
		(net "M_A_CS_N<2>")
	)
	(segment
		(start 264.16762 -50.932588)
		(end 264.162794 -50.941224)
		(width 0.0889)
		(layer "F.Cu")
		(net "M_A_CS_N<1>")
	)
	(segment
		(start 270.8402 -27.042872)
		(end 269.422372 -28.4607)
		(width 0.1651)
		(layer "F.Cu")
		(net "M_A_CS_N<1>")
	)
	(segment
		(start 265.176 -48.9712)
		(end 264.78738 -48.9712)
		(width 0.0889)
		(layer "F.Cu")
		(net "M_A_CS_N<1>")
	)
	(segment
		(start 266.16152 -47.624492)
		(end 266.16152 -47.98568)
		(width 0.0889)
		(layer "F.Cu")
		(net "M_A_CS_N<1>")
	)
	(segment
		(start 264.184384 -51.361594)
		(end 264.51433 -52.12334)
		(width 0.0889)
		(layer "F.Cu")
		(net "M_A_CS_N<1>")
	)
	(segment
		(start 264.78738 -48.9712)
		(end 264.092944 -49.665636)
		(width 0.0889)
		(layer "F.Cu")
		(net "M_A_CS_N<1>")
	)
	(segment
		(start 264.16762 -51.332638)
		(end 264.184384 -51.361594)
		(width 0.0889)
		(layer "F.Cu")
		(net "M_A_CS_N<1>")
	)
	(segment
		(start 264.17397 -50.92192)
		(end 264.16762 -50.932588)
		(width 0.0889)
		(layer "F.Cu")
		(net "M_A_CS_N<1>")
	)
	(segment
		(start 266.16152 -47.98568)
		(end 265.176 -48.9712)
		(width 0.0889)
		(layer "F.Cu")
		(net "M_A_CS_N<1>")
	)
	(segment
		(start 270.8402 -26.667206)
		(end 270.8402 -27.042872)
		(width 0.1651)
		(layer "F.Cu")
		(net "M_A_CS_N<1>")
	)
	(segment
		(start 269.422372 -28.4607)
		(end 266.16152 -31.721552)
		(width 0.1651)
		(layer "F.Cu")
		(net "M_A_CS_N<1>")
	)
	(segment
		(start 270.364458 -26.191464)
		(end 270.8402 -26.667206)
		(width 0.1651)
		(layer "F.Cu")
		(net "M_A_CS_N<1>")
	)
	(segment
		(start 264.092944 -49.665636)
		(end 264.092944 -50.0634)
		(width 0.0889)
		(layer "F.Cu")
		(net "M_A_CS_N<1>")
	)
	(segment
		(start 266.16152 -31.721552)
		(end 266.16152 -47.624492)
		(width 0.1651)
		(layer "F.Cu")
		(net "M_A_CS_N<1>")
	)
	(segment
		(start 274.600416 -15.423642)
		(end 274.599908 -15.423642)
		(width 0.1651)
		(layer "F.Cu")
		(net "M_A_CS_N<1>")
	)
	(segment
		(start 274.599908 -15.423642)
		(end 274.599908 -16.714978)
		(width 0.1651)
		(layer "F.Cu")
		(net "M_A_CS_N<1>")
	)
	(via
		(at 270.364458 -26.191464)
		(size 0.508)
		(drill 0.254)
		(layers "F.Cu" "B.Cu")
		(net "M_A_CS_N<1>")
	)
	(via
		(at 269.422372 -28.4607)
		(size 0.508)
		(drill 0.254)
		(layers "F.Cu" "B.Cu")
		(net "M_A_CS_N<1>")
	)
	(via
		(at 274.599908 -16.714978)
		(size 0.508)
		(drill 0.254)
		(layers "F.Cu" "B.Cu")
		(net "M_A_CS_N<1>")
	)
	(arc
		(start 264.162794 -50.941224)
		(mid 264.114039 -51.137576)
		(end 264.16762 -51.332638)
		(width 0.0889)
		(layer "F.Cu")
		(net "M_A_CS_N<1>")
	)
	(arc
		(start 264.092944 -50.0634)
		(mid 264.111926 -50.207642)
		(end 264.16762 -50.342038)
		(width 0.0889)
		(layer "F.Cu")
		(net "M_A_CS_N<1>")
	)
	(arc
		(start 264.16762 -50.342038)
		(mid 264.246842 -50.631156)
		(end 264.17397 -50.92192)
		(width 0.0889)
		(layer "F.Cu")
		(net "M_A_CS_N<1>")
	)
	(segment
		(start 274.2946 -21.9202)
		(end 274.0406 -21.6662)
		(width 0.14224)
		(layer "In9.Cu")
		(net "M_A_CS_N<1>")
	)
	(segment
		(start 274.16379 -19.239992)
		(end 274.16379 -17.75841)
		(width 0.14224)
		(layer "In9.Cu")
		(net "M_A_CS_N<1>")
	)
	(segment
		(start 270.876522 -25.6794)
		(end 270.9164 -25.6794)
		(width 0.14224)
		(layer "In9.Cu")
		(net "M_A_CS_N<1>")
	)
	(segment
		(start 274.2946 -22.3012)
		(end 274.2946 -21.9202)
		(width 0.14224)
		(layer "In9.Cu")
		(net "M_A_CS_N<1>")
	)
	(segment
		(start 274.2692 -19.345402)
		(end 274.16379 -19.239992)
		(width 0.14224)
		(layer "In9.Cu")
		(net "M_A_CS_N<1>")
	)
	(segment
		(start 274.16379 -17.75841)
		(end 274.599908 -17.322292)
		(width 0.14224)
		(layer "In9.Cu")
		(net "M_A_CS_N<1>")
	)
	(segment
		(start 274.0406 -21.1836)
		(end 274.2692 -20.955)
		(width 0.14224)
		(layer "In9.Cu")
		(net "M_A_CS_N<1>")
	)
	(segment
		(start 270.9164 -25.6794)
		(end 274.2946 -22.3012)
		(width 0.14224)
		(layer "In9.Cu")
		(net "M_A_CS_N<1>")
	)
	(segment
		(start 274.2692 -20.955)
		(end 274.2692 -19.345402)
		(width 0.14224)
		(layer "In9.Cu")
		(net "M_A_CS_N<1>")
	)
	(segment
		(start 274.0406 -21.6662)
		(end 274.0406 -21.1836)
		(width 0.14224)
		(layer "In9.Cu")
		(net "M_A_CS_N<1>")
	)
	(segment
		(start 274.599908 -17.322292)
		(end 274.599908 -16.714978)
		(width 0.14224)
		(layer "In9.Cu")
		(net "M_A_CS_N<1>")
	)
	(segment
		(start 270.364458 -26.191464)
		(end 270.876522 -25.6794)
		(width 0.14224)
		(layer "In9.Cu")
		(net "M_A_CS_N<1>")
	)
	(segment
		(start 262.58901 -50.52441)
		(end 262.45058 -50.342038)
		(width 0.0889)
		(layer "F.Cu")
		(net "M_A_CS_N<0>")
	)
	(segment
		(start 262.805164 -51.6763)
		(end 263.136634 -51.34483)
		(width 0.0889)
		(layer "F.Cu")
		(net "M_A_CS_N<0>")
	)
	(segment
		(start 262.714232 -51.6763)
		(end 262.805164 -51.6763)
		(width 0.0889)
		(layer "F.Cu")
		(net "M_A_CS_N<0>")
	)
	(segment
		(start 263.64057 -48.19523)
		(end 263.64057 -45.621702)
		(width 0.0889)
		(layer "F.Cu")
		(net "M_A_CS_N<0>")
	)
	(segment
		(start 262.749284 -50.652426)
		(end 262.58901 -50.52441)
		(width 0.0889)
		(layer "F.Cu")
		(net "M_A_CS_N<0>")
	)
	(segment
		(start 262.2296 -52.327556)
		(end 262.2296 -52.160932)
		(width 0.0889)
		(layer "F.Cu")
		(net "M_A_CS_N<0>")
	)
	(segment
		(start 270.350488 -15.423642)
		(end 270.34998 -15.423642)
		(width 0.1651)
		(layer "F.Cu")
		(net "M_A_CS_N<0>")
	)
	(segment
		(start 262.892286 -50.743612)
		(end 262.749284 -50.652426)
		(width 0.0889)
		(layer "F.Cu")
		(net "M_A_CS_N<0>")
	)
	(segment
		(start 261.93877 -52.618386)
		(end 262.2296 -52.327556)
		(width 0.0889)
		(layer "F.Cu")
		(net "M_A_CS_N<0>")
	)
	(segment
		(start 264.707878 -28.828746)
		(end 265.504168 -27.636978)
		(width 0.1651)
		(layer "F.Cu")
		(net "M_A_CS_N<0>")
	)
	(segment
		(start 262.2296 -52.160932)
		(end 262.714232 -51.6763)
		(width 0.0889)
		(layer "F.Cu")
		(net "M_A_CS_N<0>")
	)
	(segment
		(start 262.388858 -50.114454)
		(end 262.388858 -49.446942)
		(width 0.0889)
		(layer "F.Cu")
		(net "M_A_CS_N<0>")
	)
	(segment
		(start 263.64057 -45.621702)
		(end 263.64057 -30.426152)
		(width 0.1651)
		(layer "F.Cu")
		(net "M_A_CS_N<0>")
	)
	(segment
		(start 270.34998 -16.718534)
		(end 270.350234 -16.718788)
		(width 0.1651)
		(layer "F.Cu")
		(net "M_A_CS_N<0>")
	)
	(segment
		(start 262.388858 -49.446942)
		(end 263.64057 -48.19523)
		(width 0.0889)
		(layer "F.Cu")
		(net "M_A_CS_N<0>")
	)
	(segment
		(start 263.64057 -30.426152)
		(end 264.707878 -28.828746)
		(width 0.1651)
		(layer "F.Cu")
		(net "M_A_CS_N<0>")
	)
	(segment
		(start 265.504168 -27.636978)
		(end 266.196064 -26.945082)
		(width 0.1651)
		(layer "F.Cu")
		(net "M_A_CS_N<0>")
	)
	(segment
		(start 270.34998 -15.423642)
		(end 270.34998 -16.718534)
		(width 0.1651)
		(layer "F.Cu")
		(net "M_A_CS_N<0>")
	)
	(segment
		(start 266.196064 -26.945082)
		(end 266.949682 -26.191464)
		(width 0.1651)
		(layer "F.Cu")
		(net "M_A_CS_N<0>")
	)
	(via
		(at 270.350234 -16.718788)
		(size 0.4572)
		(drill 0.2032)
		(layers "F.Cu" "B.Cu")
		(net "M_A_CS_N<0>")
	)
	(via
		(at 266.196064 -26.945082)
		(size 0.508)
		(drill 0.254)
		(layers "F.Cu" "B.Cu")
		(net "M_A_CS_N<0>")
	)
	(via
		(at 266.949682 -26.191464)
		(size 0.508)
		(drill 0.254)
		(layers "F.Cu" "B.Cu")
		(net "M_A_CS_N<0>")
	)
	(arc
		(start 262.45058 -50.342038)
		(mid 262.40494 -50.232257)
		(end 262.388858 -50.114454)
		(width 0.0889)
		(layer "F.Cu")
		(net "M_A_CS_N<0>")
	)
	(arc
		(start 263.136634 -51.34483)
		(mid 263.168137 -50.981764)
		(end 262.892286 -50.743612)
		(width 0.0889)
		(layer "F.Cu")
		(net "M_A_CS_N<0>")
	)
	(segment
		(start 267.6906 -25.5524)
		(end 270.8402 -22.4028)
		(width 0.14224)
		(layer "In9.Cu")
		(net "M_A_CS_N<0>")
	)
	(segment
		(start 270.6878 -21.6916)
		(end 270.6878 -21.1582)
		(width 0.14224)
		(layer "In9.Cu")
		(net "M_A_CS_N<0>")
	)
	(segment
		(start 270.760698 -21.085302)
		(end 270.760698 -18.411698)
		(width 0.14224)
		(layer "In9.Cu")
		(net "M_A_CS_N<0>")
	)
	(segment
		(start 270.6878 -21.1582)
		(end 270.760698 -21.085302)
		(width 0.14224)
		(layer "In9.Cu")
		(net "M_A_CS_N<0>")
	)
	(segment
		(start 270.760698 -18.411698)
		(end 270.349726 -18.000726)
		(width 0.14224)
		(layer "In9.Cu")
		(net "M_A_CS_N<0>")
	)
	(segment
		(start 270.349726 -16.719296)
		(end 270.350234 -16.718788)
		(width 0.14224)
		(layer "In9.Cu")
		(net "M_A_CS_N<0>")
	)
	(segment
		(start 270.8402 -22.4028)
		(end 270.8402 -21.844)
		(width 0.14224)
		(layer "In9.Cu")
		(net "M_A_CS_N<0>")
	)
	(segment
		(start 270.349726 -18.000726)
		(end 270.349726 -16.719296)
		(width 0.14224)
		(layer "In9.Cu")
		(net "M_A_CS_N<0>")
	)
	(segment
		(start 266.949682 -26.191464)
		(end 267.588746 -25.5524)
		(width 0.14224)
		(layer "In9.Cu")
		(net "M_A_CS_N<0>")
	)
	(segment
		(start 267.588746 -25.5524)
		(end 267.6906 -25.5524)
		(width 0.14224)
		(layer "In9.Cu")
		(net "M_A_CS_N<0>")
	)
	(segment
		(start 270.8402 -21.844)
		(end 270.6878 -21.6916)
		(width 0.14224)
		(layer "In9.Cu")
		(net "M_A_CS_N<0>")
	)
	(segment
		(start 257.269234 -22.568408)
		(end 257.120644 -22.716998)
		(width 0.1651)
		(layer "F.Cu")
		(net "M_A_CLK_DP<3>")
	)
	(segment
		(start 258.43865 -46.871382)
		(end 258.48945 -46.922182)
		(width 0.0889)
		(layer "F.Cu")
		(net "M_A_CLK_DP<3>")
	)
	(segment
		(start 258.43865 -30.448758)
		(end 258.43865 -46.871382)
		(width 0.1651)
		(layer "F.Cu")
		(net "M_A_CLK_DP<3>")
	)
	(segment
		(start 258.152392 -48.562768)
		(end 258.152392 -50.105818)
		(width 0.0889)
		(layer "F.Cu")
		(net "M_A_CLK_DP<3>")
	)
	(segment
		(start 256.704592 -22.716998)
		(end 256.40665 -23.01494)
		(width 0.1651)
		(layer "F.Cu")
		(net "M_A_CLK_DP<3>")
	)
	(segment
		(start 257.269234 -22.435312)
		(end 257.269234 -22.568408)
		(width 0.1651)
		(layer "F.Cu")
		(net "M_A_CLK_DP<3>")
	)
	(segment
		(start 256.30505 -24.099012)
		(end 256.30505 -28.315158)
		(width 0.1651)
		(layer "F.Cu")
		(net "M_A_CLK_DP<3>")
	)
	(segment
		(start 258.48945 -46.922182)
		(end 258.48945 -48.22571)
		(width 0.0889)
		(layer "F.Cu")
		(net "M_A_CLK_DP<3>")
	)
	(segment
		(start 257.120644 -22.716998)
		(end 256.704592 -22.716998)
		(width 0.1651)
		(layer "F.Cu")
		(net "M_A_CLK_DP<3>")
	)
	(segment
		(start 256.898394 -28.908502)
		(end 258.43865 -30.448758)
		(width 0.1651)
		(layer "F.Cu")
		(net "M_A_CLK_DP<3>")
	)
	(segment
		(start 256.40665 -23.997412)
		(end 256.30505 -24.099012)
		(width 0.1651)
		(layer "F.Cu")
		(net "M_A_CLK_DP<3>")
	)
	(segment
		(start 257.932936 -50.307494)
		(end 257.64617 -50.141886)
		(width 0.0889)
		(layer "F.Cu")
		(net "M_A_CLK_DP<3>")
	)
	(segment
		(start 258.48945 -48.22571)
		(end 258.152392 -48.562768)
		(width 0.0889)
		(layer "F.Cu")
		(net "M_A_CLK_DP<3>")
	)
	(segment
		(start 258.05511 -50.295556)
		(end 258.043172 -50.307494)
		(width 0.0889)
		(layer "F.Cu")
		(net "M_A_CLK_DP<3>")
	)
	(segment
		(start 258.043172 -50.307494)
		(end 257.932936 -50.307494)
		(width 0.0889)
		(layer "F.Cu")
		(net "M_A_CLK_DP<3>")
	)
	(segment
		(start 258.152392 -50.105818)
		(end 258.05511 -50.295556)
		(width 0.0889)
		(layer "F.Cu")
		(net "M_A_CLK_DP<3>")
	)
	(segment
		(start 256.30505 -28.315158)
		(end 256.898394 -28.908502)
		(width 0.1651)
		(layer "F.Cu")
		(net "M_A_CLK_DP<3>")
	)
	(segment
		(start 256.40665 -23.01494)
		(end 256.40665 -23.997412)
		(width 0.1651)
		(layer "F.Cu")
		(net "M_A_CLK_DP<3>")
	)
	(segment
		(start 257.058922 -22.225)
		(end 257.269234 -22.435312)
		(width 0.1651)
		(layer "F.Cu")
		(net "M_A_CLK_DP<3>")
	)
	(via
		(at 257.058922 -22.225)
		(size 0.508)
		(drill 0.254)
		(layers "F.Cu" "B.Cu")
		(net "M_A_CLK_DP<3>")
	)
	(via
		(at 256.898394 -28.908502)
		(size 0.508)
		(drill 0.254)
		(layers "F.Cu" "B.Cu")
		(net "M_A_CLK_DP<3>")
	)
	(segment
		(start 256.750312 -20.224242)
		(end 256.749804 -20.224242)
		(width 0.1651)
		(layer "B.Cu")
		(net "M_A_CLK_DP<3>")
	)
	(segment
		(start 257.184398 -21.345144)
		(end 257.184398 -22.099524)
		(width 0.1651)
		(layer "B.Cu")
		(net "M_A_CLK_DP<3>")
	)
	(segment
		(start 256.749804 -20.91055)
		(end 257.184398 -21.345144)
		(width 0.1651)
		(layer "B.Cu")
		(net "M_A_CLK_DP<3>")
	)
	(segment
		(start 256.749804 -20.224242)
		(end 256.749804 -20.91055)
		(width 0.1651)
		(layer "B.Cu")
		(net "M_A_CLK_DP<3>")
	)
	(segment
		(start 257.184398 -22.099524)
		(end 257.058922 -22.225)
		(width 0.1651)
		(layer "B.Cu")
		(net "M_A_CLK_DP<3>")
	)
	(segment
		(start 259.86613 -26.43251)
		(end 258.975606 -26.43251)
		(width 0.1651)
		(layer "F.Cu")
		(net "M_A_CLK_DP<1>")
	)
	(segment
		(start 259.34035 -22.568662)
		(end 259.799582 -23.027894)
		(width 0.1651)
		(layer "F.Cu")
		(net "M_A_CLK_DP<1>")
	)
	(segment
		(start 257.028696 -21.292058)
		(end 257.364738 -21.6281)
		(width 0.1651)
		(layer "F.Cu")
		(net "M_A_CLK_DP<1>")
	)
	(segment
		(start 259.0546 -25.73655)
		(end 259.16255 -25.6286)
		(width 0.1651)
		(layer "F.Cu")
		(net "M_A_CLK_DP<1>")
	)
	(segment
		(start 259.860288 -49.821338)
		(end 259.860288 -50.207418)
		(width 0.0889)
		(layer "F.Cu")
		(net "M_A_CLK_DP<1>")
	)
	(segment
		(start 257.364738 -21.6281)
		(end 259.085842 -21.6281)
		(width 0.1651)
		(layer "F.Cu")
		(net "M_A_CLK_DP<1>")
	)
	(segment
		(start 258.382008 -26.43251)
		(end 258.045966 -26.768552)
		(width 0.1651)
		(layer "F.Cu")
		(net "M_A_CLK_DP<1>")
	)
	(segment
		(start 256.749804 -20.678394)
		(end 257.028696 -20.957286)
		(width 0.1651)
		(layer "F.Cu")
		(net "M_A_CLK_DP<1>")
	)
	(segment
		(start 260.288532 -47.231554)
		(end 260.490462 -47.231554)
		(width 0.0889)
		(layer "F.Cu")
		(net "M_A_CLK_DP<1>")
	)
	(segment
		(start 260.03123 -26.26741)
		(end 259.86613 -26.43251)
		(width 0.1651)
		(layer "F.Cu")
		(net "M_A_CLK_DP<1>")
	)
	(segment
		(start 259.36321 -50.14341)
		(end 259.36321 -50.141886)
		(width 0.0889)
		(layer "F.Cu")
		(net "M_A_CLK_DP<1>")
	)
	(segment
		(start 260.490462 -47.231554)
		(end 260.579362 -47.320454)
		(width 0.0889)
		(layer "F.Cu")
		(net "M_A_CLK_DP<1>")
	)
	(segment
		(start 260.579362 -47.739554)
		(end 260.490462 -47.828454)
		(width 0.0889)
		(layer "F.Cu")
		(net "M_A_CLK_DP<1>")
	)
	(segment
		(start 259.860288 -50.207418)
		(end 259.719318 -50.348388)
		(width 0.0889)
		(layer "F.Cu")
		(net "M_A_CLK_DP<1>")
	)
	(segment
		(start 258.398264 -25.73655)
		(end 259.0546 -25.73655)
		(width 0.1651)
		(layer "F.Cu")
		(net "M_A_CLK_DP<1>")
	)
	(segment
		(start 258.062222 -24.31796)
		(end 258.062222 -25.400508)
		(width 0.1651)
		(layer "F.Cu")
		(net "M_A_CLK_DP<1>")
	)
	(segment
		(start 260.03123 -46.50867)
		(end 260.03123 -46.519846)
		(width 0.0889)
		(layer "F.Cu")
		(net "M_A_CLK_DP<1>")
	)
	(segment
		(start 258.975606 -26.43251)
		(end 258.382008 -26.43251)
		(width 0.1651)
		(layer "F.Cu")
		(net "M_A_CLK_DP<1>")
	)
	(segment
		(start 258.045966 -27.353768)
		(end 258.382008 -27.68981)
		(width 0.1651)
		(layer "F.Cu")
		(net "M_A_CLK_DP<1>")
	)
	(segment
		(start 260.490462 -47.828454)
		(end 260.12394 -47.828454)
		(width 0.0889)
		(layer "F.Cu")
		(net "M_A_CLK_DP<1>")
	)
	(segment
		(start 258.382008 -27.68981)
		(end 259.86613 -27.68981)
		(width 0.1651)
		(layer "F.Cu")
		(net "M_A_CLK_DP<1>")
	)
	(segment
		(start 259.34035 -21.882608)
		(end 259.34035 -22.568662)
		(width 0.1651)
		(layer "F.Cu")
		(net "M_A_CLK_DP<1>")
	)
	(segment
		(start 260.088126 -46.576742)
		(end 260.088126 -47.031148)
		(width 0.0889)
		(layer "F.Cu")
		(net "M_A_CLK_DP<1>")
	)
	(segment
		(start 259.649468 -23.981918)
		(end 258.398264 -23.981918)
		(width 0.1651)
		(layer "F.Cu")
		(net "M_A_CLK_DP<1>")
	)
	(segment
		(start 260.03123 -46.519846)
		(end 260.088126 -46.576742)
		(width 0.0889)
		(layer "F.Cu")
		(net "M_A_CLK_DP<1>")
	)
	(segment
		(start 257.028696 -20.957286)
		(end 257.028696 -21.292058)
		(width 0.1651)
		(layer "F.Cu")
		(net "M_A_CLK_DP<1>")
	)
	(segment
		(start 259.542026 -49.503076)
		(end 259.860288 -49.821338)
		(width 0.0889)
		(layer "F.Cu")
		(net "M_A_CLK_DP<1>")
	)
	(segment
		(start 259.568188 -50.348388)
		(end 259.36321 -50.14341)
		(width 0.0889)
		(layer "F.Cu")
		(net "M_A_CLK_DP<1>")
	)
	(segment
		(start 259.799582 -23.831804)
		(end 259.649468 -23.981918)
		(width 0.1651)
		(layer "F.Cu")
		(net "M_A_CLK_DP<1>")
	)
	(segment
		(start 259.86613 -27.68981)
		(end 260.03123 -27.85491)
		(width 0.1651)
		(layer "F.Cu")
		(net "M_A_CLK_DP<1>")
	)
	(segment
		(start 258.045966 -26.768552)
		(end 258.045966 -27.353768)
		(width 0.1651)
		(layer "F.Cu")
		(net "M_A_CLK_DP<1>")
	)
	(segment
		(start 259.719318 -50.348388)
		(end 259.568188 -50.348388)
		(width 0.0889)
		(layer "F.Cu")
		(net "M_A_CLK_DP<1>")
	)
	(segment
		(start 260.579362 -47.320454)
		(end 260.579362 -47.739554)
		(width 0.0889)
		(layer "F.Cu")
		(net "M_A_CLK_DP<1>")
	)
	(segment
		(start 256.749804 -20.023582)
		(end 256.749804 -20.678394)
		(width 0.1651)
		(layer "F.Cu")
		(net "M_A_CLK_DP<1>")
	)
	(segment
		(start 259.88518 -48.067214)
		(end 259.88518 -48.54067)
		(width 0.0889)
		(layer "F.Cu")
		(net "M_A_CLK_DP<1>")
	)
	(segment
		(start 259.640832 -25.6286)
		(end 260.03123 -26.018998)
		(width 0.1651)
		(layer "F.Cu")
		(net "M_A_CLK_DP<1>")
	)
	(segment
		(start 258.062222 -25.400508)
		(end 258.398264 -25.73655)
		(width 0.1651)
		(layer "F.Cu")
		(net "M_A_CLK_DP<1>")
	)
	(segment
		(start 259.542026 -48.883824)
		(end 259.542026 -49.503076)
		(width 0.0889)
		(layer "F.Cu")
		(net "M_A_CLK_DP<1>")
	)
	(segment
		(start 260.03123 -26.018998)
		(end 260.03123 -26.26741)
		(width 0.1651)
		(layer "F.Cu")
		(net "M_A_CLK_DP<1>")
	)
	(segment
		(start 260.12394 -47.828454)
		(end 259.88518 -48.067214)
		(width 0.0889)
		(layer "F.Cu")
		(net "M_A_CLK_DP<1>")
	)
	(segment
		(start 260.088126 -47.031148)
		(end 260.288532 -47.231554)
		(width 0.0889)
		(layer "F.Cu")
		(net "M_A_CLK_DP<1>")
	)
	(segment
		(start 259.085842 -21.6281)
		(end 259.34035 -21.882608)
		(width 0.1651)
		(layer "F.Cu")
		(net "M_A_CLK_DP<1>")
	)
	(segment
		(start 259.16255 -25.6286)
		(end 259.640832 -25.6286)
		(width 0.1651)
		(layer "F.Cu")
		(net "M_A_CLK_DP<1>")
	)
	(segment
		(start 260.03123 -27.85491)
		(end 260.03123 -46.50867)
		(width 0.1651)
		(layer "F.Cu")
		(net "M_A_CLK_DP<1>")
	)
	(segment
		(start 258.398264 -23.981918)
		(end 258.062222 -24.31796)
		(width 0.1651)
		(layer "F.Cu")
		(net "M_A_CLK_DP<1>")
	)
	(segment
		(start 259.799582 -23.027894)
		(end 259.799582 -23.831804)
		(width 0.1651)
		(layer "F.Cu")
		(net "M_A_CLK_DP<1>")
	)
	(segment
		(start 259.88518 -48.54067)
		(end 259.542026 -48.883824)
		(width 0.0889)
		(layer "F.Cu")
		(net "M_A_CLK_DP<1>")
	)
	(segment
		(start 256.750312 -20.023582)
		(end 256.749804 -20.023582)
		(width 0.1651)
		(layer "F.Cu")
		(net "M_A_CLK_DP<1>")
	)
	(via
		(at 258.975606 -26.43251)
		(size 0.508)
		(drill 0.254)
		(layers "F.Cu" "B.Cu")
		(net "M_A_CLK_DP<1>")
	)
	(segment
		(start 259.304536 -48.324516)
		(end 258.9149 -48.714152)
		(width 0.0889)
		(layer "F.Cu")
		(net "M_A_CLK_DP<2>")
	)
	(segment
		(start 258.77266 -50.137314)
		(end 258.772152 -50.137822)
		(width 0.0889)
		(layer "F.Cu")
		(net "M_A_CLK_DP<2>")
	)
	(segment
		(start 257.249676 -24.50084)
		(end 257.125216 -24.6253)
		(width 0.1651)
		(layer "F.Cu")
		(net "M_A_CLK_DP<2>")
	)
	(segment
		(start 257.249676 -27.831288)
		(end 258.38277 -28.964382)
		(width 0.1651)
		(layer "F.Cu")
		(net "M_A_CLK_DP<2>")
	)
	(segment
		(start 257.249676 -27.435556)
		(end 257.249676 -27.831288)
		(width 0.1651)
		(layer "F.Cu")
		(net "M_A_CLK_DP<2>")
	)
	(segment
		(start 258.9149 -49.679606)
		(end 258.77266 -49.821846)
		(width 0.0889)
		(layer "F.Cu")
		(net "M_A_CLK_DP<2>")
	)
	(segment
		(start 257.125216 -24.980392)
		(end 257.249676 -25.104852)
		(width 0.1651)
		(layer "F.Cu")
		(net "M_A_CLK_DP<2>")
	)
	(segment
		(start 258.857496 -29.439108)
		(end 259.23494 -29.816552)
		(width 0.1651)
		(layer "F.Cu")
		(net "M_A_CLK_DP<2>")
	)
	(segment
		(start 257.249676 -25.104852)
		(end 257.249676 -25.466802)
		(width 0.1651)
		(layer "F.Cu")
		(net "M_A_CLK_DP<2>")
	)
	(segment
		(start 257.125216 -24.6253)
		(end 257.125216 -24.980392)
		(width 0.1651)
		(layer "F.Cu")
		(net "M_A_CLK_DP<2>")
	)
	(segment
		(start 257.124962 -25.96896)
		(end 257.249676 -26.093674)
		(width 0.1651)
		(layer "F.Cu")
		(net "M_A_CLK_DP<2>")
	)
	(segment
		(start 259.23494 -29.816552)
		(end 259.23494 -46.402244)
		(width 0.1651)
		(layer "F.Cu")
		(net "M_A_CLK_DP<2>")
	)
	(segment
		(start 258.9149 -48.714152)
		(end 258.9149 -49.679606)
		(width 0.0889)
		(layer "F.Cu")
		(net "M_A_CLK_DP<2>")
	)
	(segment
		(start 257.249676 -25.466802)
		(end 257.124962 -25.591516)
		(width 0.1651)
		(layer "F.Cu")
		(net "M_A_CLK_DP<2>")
	)
	(segment
		(start 257.249676 -23.595076)
		(end 257.249676 -24.50084)
		(width 0.1651)
		(layer "F.Cu")
		(net "M_A_CLK_DP<2>")
	)
	(segment
		(start 258.567936 -53.013864)
		(end 258.50469 -52.950618)
		(width 0.0889)
		(layer "F.Cu")
		(net "M_A_CLK_DP<2>")
	)
	(segment
		(start 258.38277 -28.964382)
		(end 258.38277 -29.140404)
		(width 0.1651)
		(layer "F.Cu")
		(net "M_A_CLK_DP<2>")
	)
	(segment
		(start 258.38277 -29.140404)
		(end 258.681474 -29.439108)
		(width 0.1651)
		(layer "F.Cu")
		(net "M_A_CLK_DP<2>")
	)
	(segment
		(start 259.304536 -46.47184)
		(end 259.304536 -48.324516)
		(width 0.0889)
		(layer "F.Cu")
		(net "M_A_CLK_DP<2>")
	)
	(segment
		(start 258.77266 -49.821846)
		(end 258.77266 -50.137314)
		(width 0.0889)
		(layer "F.Cu")
		(net "M_A_CLK_DP<2>")
	)
	(segment
		(start 258.8514 -50.837846)
		(end 258.8514 -50.837592)
		(width 0.0889)
		(layer "F.Cu")
		(net "M_A_CLK_DP<2>")
	)
	(segment
		(start 257.1496 -23.495)
		(end 257.249676 -23.595076)
		(width 0.1651)
		(layer "F.Cu")
		(net "M_A_CLK_DP<2>")
	)
	(segment
		(start 258.50469 -52.950618)
		(end 258.50469 -52.618386)
		(width 0.0889)
		(layer "F.Cu")
		(net "M_A_CLK_DP<2>")
	)
	(segment
		(start 259.23494 -46.402244)
		(end 259.304536 -46.47184)
		(width 0.0889)
		(layer "F.Cu")
		(net "M_A_CLK_DP<2>")
	)
	(segment
		(start 257.124962 -25.591516)
		(end 257.124962 -25.96896)
		(width 0.1651)
		(layer "F.Cu")
		(net "M_A_CLK_DP<2>")
	)
	(segment
		(start 258.681474 -29.439108)
		(end 258.857496 -29.439108)
		(width 0.1651)
		(layer "F.Cu")
		(net "M_A_CLK_DP<2>")
	)
	(segment
		(start 257.249676 -26.093674)
		(end 257.249676 -27.435556)
		(width 0.1651)
		(layer "F.Cu")
		(net "M_A_CLK_DP<2>")
	)
	(via
		(at 257.1496 -23.495)
		(size 0.508)
		(drill 0.254)
		(layers "F.Cu" "B.Cu")
		(net "M_A_CLK_DP<2>")
	)
	(via
		(at 257.249676 -27.435556)
		(size 0.508)
		(drill 0.254)
		(layers "F.Cu" "B.Cu")
		(net "M_A_CLK_DP<2>")
	)
	(arc
		(start 258.8514 -51.828192)
		(mid 258.772269 -52.123594)
		(end 258.8514 -52.418996)
		(width 0.0889)
		(layer "F.Cu")
		(net "M_A_CLK_DP<2>")
	)
	(arc
		(start 258.8514 -50.837592)
		(mid 258.772269 -51.132994)
		(end 258.8514 -51.428396)
		(width 0.0889)
		(layer "F.Cu")
		(net "M_A_CLK_DP<2>")
	)
	(arc
		(start 258.8514 -51.428396)
		(mid 258.904899 -51.628294)
		(end 258.8514 -51.828192)
		(width 0.0889)
		(layer "F.Cu")
		(net "M_A_CLK_DP<2>")
	)
	(arc
		(start 258.8514 -50.437542)
		(mid 258.905026 -50.637694)
		(end 258.8514 -50.837846)
		(width 0.0889)
		(layer "F.Cu")
		(net "M_A_CLK_DP<2>")
	)
	(arc
		(start 258.772152 -50.137822)
		(mid 258.791781 -50.292967)
		(end 258.8514 -50.437542)
		(width 0.0889)
		(layer "F.Cu")
		(net "M_A_CLK_DP<2>")
	)
	(arc
		(start 258.8514 -52.418996)
		(mid 258.865837 -52.790797)
		(end 258.567936 -53.013864)
		(width 0.0889)
		(layer "F.Cu")
		(net "M_A_CLK_DP<2>")
	)
	(segment
		(start 256.750312 -24.824182)
		(end 256.749804 -24.824182)
		(width 0.1651)
		(layer "B.Cu")
		(net "M_A_CLK_DP<2>")
	)
	(segment
		(start 256.749804 -24.824182)
		(end 256.749804 -23.894796)
		(width 0.1651)
		(layer "B.Cu")
		(net "M_A_CLK_DP<2>")
	)
	(segment
		(start 256.749804 -23.894796)
		(end 257.1496 -23.495)
		(width 0.1651)
		(layer "B.Cu")
		(net "M_A_CLK_DP<2>")
	)
	(segment
		(start 260.445504 -50.224944)
		(end 260.56844 -50.437542)
		(width 0.0889)
		(layer "F.Cu")
		(net "M_A_CLK_DP<0>")
	)
	(segment
		(start 257.028696 -16.84655)
		(end 257.028696 -17.215612)
		(width 0.1651)
		(layer "F.Cu")
		(net "M_A_CLK_DP<0>")
	)
	(segment
		(start 260.82752 -25.680416)
		(end 260.82752 -26.399744)
		(width 0.1651)
		(layer "F.Cu")
		(net "M_A_CLK_DP<0>")
	)
	(segment
		(start 260.80466 -20.154646)
		(end 260.80466 -20.649946)
		(width 0.1651)
		(layer "F.Cu")
		(net "M_A_CLK_DP<0>")
	)
	(segment
		(start 260.552692 -25.405588)
		(end 260.82752 -25.680416)
		(width 0.1651)
		(layer "F.Cu")
		(net "M_A_CLK_DP<0>")
	)
	(segment
		(start 260.439916 -24.32939)
		(end 260.439916 -24.82469)
		(width 0.1651)
		(layer "F.Cu")
		(net "M_A_CLK_DP<0>")
	)
	(segment
		(start 261.16534 -48.216566)
		(end 260.445504 -48.936402)
		(width 0.0889)
		(layer "F.Cu")
		(net "M_A_CLK_DP<0>")
	)
	(segment
		(start 257.3782 -17.565116)
		(end 257.98907 -17.8181)
		(width 0.1651)
		(layer "F.Cu")
		(net "M_A_CLK_DP<0>")
	)
	(segment
		(start 260.82752 -26.399744)
		(end 260.82752 -26.883106)
		(width 0.1651)
		(layer "F.Cu")
		(net "M_A_CLK_DP<0>")
	)
	(segment
		(start 260.877304 -46.093888)
		(end 260.877304 -46.453552)
		(width 0.0889)
		(layer "F.Cu")
		(net "M_A_CLK_DP<0>")
	)
	(segment
		(start 260.877304 -46.453552)
		(end 261.16534 -46.741588)
		(width 0.0889)
		(layer "F.Cu")
		(net "M_A_CLK_DP<0>")
	)
	(segment
		(start 260.847078 -22.165564)
		(end 260.552692 -22.876256)
		(width 0.1651)
		(layer "F.Cu")
		(net "M_A_CLK_DP<0>")
	)
	(segment
		(start 260.92658 -21.97354)
		(end 260.847078 -22.165564)
		(width 0.1651)
		(layer "F.Cu")
		(net "M_A_CLK_DP<0>")
	)
	(segment
		(start 260.445504 -48.936402)
		(end 260.445504 -50.224944)
		(width 0.0889)
		(layer "F.Cu")
		(net "M_A_CLK_DP<0>")
	)
	(segment
		(start 260.82752 -26.883106)
		(end 260.723888 -26.986738)
		(width 0.1651)
		(layer "F.Cu")
		(net "M_A_CLK_DP<0>")
	)
	(segment
		(start 261.16534 -46.741588)
		(end 261.16534 -48.216566)
		(width 0.0889)
		(layer "F.Cu")
		(net "M_A_CLK_DP<0>")
	)
	(segment
		(start 260.92658 -19.451066)
		(end 260.92658 -20.032726)
		(width 0.1651)
		(layer "F.Cu")
		(net "M_A_CLK_DP<0>")
	)
	(segment
		(start 260.82752 -46.044104)
		(end 260.877304 -46.093888)
		(width 0.0889)
		(layer "F.Cu")
		(net "M_A_CLK_DP<0>")
	)
	(segment
		(start 256.749804 -15.423642)
		(end 256.749804 -16.567658)
		(width 0.1651)
		(layer "F.Cu")
		(net "M_A_CLK_DP<0>")
	)
	(segment
		(start 260.92658 -20.771866)
		(end 260.92658 -21.97354)
		(width 0.1651)
		(layer "F.Cu")
		(net "M_A_CLK_DP<0>")
	)
	(segment
		(start 260.439916 -24.82469)
		(end 260.552692 -24.937466)
		(width 0.1651)
		(layer "F.Cu")
		(net "M_A_CLK_DP<0>")
	)
	(segment
		(start 260.82752 -27.436318)
		(end 260.82752 -46.042072)
		(width 0.1651)
		(layer "F.Cu")
		(net "M_A_CLK_DP<0>")
	)
	(segment
		(start 260.552692 -24.216614)
		(end 260.439916 -24.32939)
		(width 0.1651)
		(layer "F.Cu")
		(net "M_A_CLK_DP<0>")
	)
	(segment
		(start 260.591808 -18.642838)
		(end 260.92658 -19.451066)
		(width 0.1651)
		(layer "F.Cu")
		(net "M_A_CLK_DP<0>")
	)
	(segment
		(start 259.36321 -51.46421)
		(end 259.36321 -51.132486)
		(width 0.0889)
		(layer "F.Cu")
		(net "M_A_CLK_DP<0>")
	)
	(segment
		(start 260.723888 -27.332686)
		(end 260.82752 -27.436318)
		(width 0.1651)
		(layer "F.Cu")
		(net "M_A_CLK_DP<0>")
	)
	(segment
		(start 258.975352 -17.8181)
		(end 260.326632 -18.377662)
		(width 0.1651)
		(layer "F.Cu")
		(net "M_A_CLK_DP<0>")
	)
	(segment
		(start 260.92658 -20.032726)
		(end 260.80466 -20.154646)
		(width 0.1651)
		(layer "F.Cu")
		(net "M_A_CLK_DP<0>")
	)
	(segment
		(start 260.326632 -18.377662)
		(end 260.591808 -18.642838)
		(width 0.1651)
		(layer "F.Cu")
		(net "M_A_CLK_DP<0>")
	)
	(segment
		(start 260.552692 -22.876256)
		(end 260.552692 -24.216614)
		(width 0.1651)
		(layer "F.Cu")
		(net "M_A_CLK_DP<0>")
	)
	(segment
		(start 260.552692 -24.937466)
		(end 260.552692 -25.405588)
		(width 0.1651)
		(layer "F.Cu")
		(net "M_A_CLK_DP<0>")
	)
	(segment
		(start 257.98907 -17.8181)
		(end 258.975352 -17.8181)
		(width 0.1651)
		(layer "F.Cu")
		(net "M_A_CLK_DP<0>")
	)
	(segment
		(start 259.42671 -51.52771)
		(end 259.36321 -51.46421)
		(width 0.0889)
		(layer "F.Cu")
		(net "M_A_CLK_DP<0>")
	)
	(segment
		(start 256.750312 -15.423642)
		(end 256.749804 -15.423642)
		(width 0.1651)
		(layer "F.Cu")
		(net "M_A_CLK_DP<0>")
	)
	(segment
		(start 260.723888 -26.986738)
		(end 260.723888 -27.332686)
		(width 0.1651)
		(layer "F.Cu")
		(net "M_A_CLK_DP<0>")
	)
	(segment
		(start 256.749804 -16.567658)
		(end 257.028696 -16.84655)
		(width 0.1651)
		(layer "F.Cu")
		(net "M_A_CLK_DP<0>")
	)
	(segment
		(start 257.028696 -17.215612)
		(end 257.3782 -17.565116)
		(width 0.1651)
		(layer "F.Cu")
		(net "M_A_CLK_DP<0>")
	)
	(segment
		(start 260.82752 -46.042072)
		(end 260.82752 -46.044104)
		(width 0.0889)
		(layer "F.Cu")
		(net "M_A_CLK_DP<0>")
	)
	(segment
		(start 260.232906 -51.03749)
		(end 260.20014 -51.03749)
		(width 0.0889)
		(layer "F.Cu")
		(net "M_A_CLK_DP<0>")
	)
	(segment
		(start 260.80466 -20.649946)
		(end 260.92658 -20.771866)
		(width 0.1651)
		(layer "F.Cu")
		(net "M_A_CLK_DP<0>")
	)
	(via
		(at 260.82752 -26.399744)
		(size 0.508)
		(drill 0.254)
		(layers "F.Cu" "B.Cu")
		(net "M_A_CLK_DP<0>")
	)
	(arc
		(start 260.56844 -50.437542)
		(mid 260.621917 -50.633233)
		(end 260.572504 -50.829972)
		(width 0.0889)
		(layer "F.Cu")
		(net "M_A_CLK_DP<0>")
	)
	(arc
		(start 260.572504 -50.829972)
		(mid 260.430322 -50.978908)
		(end 260.232906 -51.03749)
		(width 0.0889)
		(layer "F.Cu")
		(net "M_A_CLK_DP<0>")
	)
	(arc
		(start 260.20014 -51.03749)
		(mid 259.916923 -51.121771)
		(end 259.70992 -51.332638)
		(width 0.0889)
		(layer "F.Cu")
		(net "M_A_CLK_DP<0>")
	)
	(arc
		(start 259.70992 -51.332638)
		(mid 259.590337 -51.462155)
		(end 259.42671 -51.52771)
		(width 0.0889)
		(layer "F.Cu")
		(net "M_A_CLK_DP<0>")
	)
	(segment
		(start 258.263136 -50.497994)
		(end 258.50469 -50.63744)
		(width 0.0889)
		(layer "F.Cu")
		(net "M_A_CLK_DN<3>")
	)
	(segment
		(start 258.73075 -46.89348)
		(end 258.67995 -46.94428)
		(width 0.0889)
		(layer "F.Cu")
		(net "M_A_CLK_DN<3>")
	)
	(segment
		(start 258.67995 -46.94428)
		(end 258.67995 -48.304704)
		(width 0.0889)
		(layer "F.Cu")
		(net "M_A_CLK_DN<3>")
	)
	(segment
		(start 256.59715 -28.194)
		(end 258.73075 -30.3276)
		(width 0.1651)
		(layer "F.Cu")
		(net "M_A_CLK_DN<3>")
	)
	(segment
		(start 256.82575 -23.009098)
		(end 256.69875 -23.136098)
		(width 0.1651)
		(layer "F.Cu")
		(net "M_A_CLK_DN<3>")
	)
	(segment
		(start 258.73075 -30.3276)
		(end 258.73075 -46.871382)
		(width 0.1651)
		(layer "F.Cu")
		(net "M_A_CLK_DN<3>")
	)
	(segment
		(start 258.227576 -50.37709)
		(end 258.263136 -50.497994)
		(width 0.0889)
		(layer "F.Cu")
		(net "M_A_CLK_DN<3>")
	)
	(segment
		(start 258.342892 -50.151792)
		(end 258.227576 -50.37709)
		(width 0.0889)
		(layer "F.Cu")
		(net "M_A_CLK_DN<3>")
	)
	(segment
		(start 257.769868 -22.225)
		(end 257.561334 -22.433534)
		(width 0.1651)
		(layer "F.Cu")
		(net "M_A_CLK_DN<3>")
	)
	(segment
		(start 257.561334 -22.689566)
		(end 257.241802 -23.009098)
		(width 0.1651)
		(layer "F.Cu")
		(net "M_A_CLK_DN<3>")
	)
	(segment
		(start 256.59715 -26.337006)
		(end 256.59715 -28.194)
		(width 0.1651)
		(layer "F.Cu")
		(net "M_A_CLK_DN<3>")
	)
	(segment
		(start 257.241802 -23.009098)
		(end 256.82575 -23.009098)
		(width 0.1651)
		(layer "F.Cu")
		(net "M_A_CLK_DN<3>")
	)
	(segment
		(start 256.59715 -24.22017)
		(end 256.59715 -26.337006)
		(width 0.1651)
		(layer "F.Cu")
		(net "M_A_CLK_DN<3>")
	)
	(segment
		(start 256.69875 -23.136098)
		(end 256.69875 -24.11857)
		(width 0.1651)
		(layer "F.Cu")
		(net "M_A_CLK_DN<3>")
	)
	(segment
		(start 257.561334 -22.433534)
		(end 257.561334 -22.689566)
		(width 0.1651)
		(layer "F.Cu")
		(net "M_A_CLK_DN<3>")
	)
	(segment
		(start 256.69875 -24.11857)
		(end 256.59715 -24.22017)
		(width 0.1651)
		(layer "F.Cu")
		(net "M_A_CLK_DN<3>")
	)
	(segment
		(start 258.342892 -48.641762)
		(end 258.342892 -50.151792)
		(width 0.0889)
		(layer "F.Cu")
		(net "M_A_CLK_DN<3>")
	)
	(segment
		(start 258.67995 -48.304704)
		(end 258.342892 -48.641762)
		(width 0.0889)
		(layer "F.Cu")
		(net "M_A_CLK_DN<3>")
	)
	(segment
		(start 258.73075 -46.871382)
		(end 258.73075 -46.89348)
		(width 0.0889)
		(layer "F.Cu")
		(net "M_A_CLK_DN<3>")
	)
	(via
		(at 256.59715 -26.337006)
		(size 0.508)
		(drill 0.254)
		(layers "F.Cu" "B.Cu")
		(net "M_A_CLK_DN<3>")
	)
	(via
		(at 257.769868 -22.225)
		(size 0.508)
		(drill 0.254)
		(layers "F.Cu" "B.Cu")
		(net "M_A_CLK_DN<3>")
	)
	(segment
		(start 257.476498 -21.93163)
		(end 257.769868 -22.225)
		(width 0.1651)
		(layer "B.Cu")
		(net "M_A_CLK_DN<3>")
	)
	(segment
		(start 257.599942 -20.224242)
		(end 257.599942 -21.216112)
		(width 0.1651)
		(layer "B.Cu")
		(net "M_A_CLK_DN<3>")
	)
	(segment
		(start 257.476498 -21.339556)
		(end 257.476498 -21.93163)
		(width 0.1651)
		(layer "B.Cu")
		(net "M_A_CLK_DN<3>")
	)
	(segment
		(start 257.60045 -20.224242)
		(end 257.599942 -20.224242)
		(width 0.1651)
		(layer "B.Cu")
		(net "M_A_CLK_DN<3>")
	)
	(segment
		(start 257.599942 -21.216112)
		(end 257.476498 -21.339556)
		(width 0.1651)
		(layer "B.Cu")
		(net "M_A_CLK_DN<3>")
	)
	(segment
		(start 259.770626 -24.274018)
		(end 258.519422 -24.274018)
		(width 0.1651)
		(layer "F.Cu")
		(net "M_A_CLK_DN<1>")
	)
	(segment
		(start 260.278626 -46.553374)
		(end 260.32333 -46.50867)
		(width 0.0889)
		(layer "F.Cu")
		(net "M_A_CLK_DN<1>")
	)
	(segment
		(start 258.519422 -24.274018)
		(end 258.354322 -24.439118)
		(width 0.1651)
		(layer "F.Cu")
		(net "M_A_CLK_DN<1>")
	)
	(segment
		(start 259.63245 -21.76145)
		(end 259.63245 -22.447504)
		(width 0.1651)
		(layer "F.Cu")
		(net "M_A_CLK_DN<1>")
	)
	(segment
		(start 259.207 -21.336)
		(end 259.63245 -21.76145)
		(width 0.1651)
		(layer "F.Cu")
		(net "M_A_CLK_DN<1>")
	)
	(segment
		(start 260.769862 -47.24146)
		(end 260.569456 -47.041054)
		(width 0.0889)
		(layer "F.Cu")
		(net "M_A_CLK_DN<1>")
	)
	(segment
		(start 259.987288 -26.72461)
		(end 258.503166 -26.72461)
		(width 0.1651)
		(layer "F.Cu")
		(net "M_A_CLK_DN<1>")
	)
	(segment
		(start 258.354322 -25.27935)
		(end 258.519422 -25.44445)
		(width 0.1651)
		(layer "F.Cu")
		(net "M_A_CLK_DN<1>")
	)
	(segment
		(start 259.76199 -25.3365)
		(end 260.32333 -25.89784)
		(width 0.1651)
		(layer "F.Cu")
		(net "M_A_CLK_DN<1>")
	)
	(segment
		(start 258.338066 -26.88971)
		(end 258.338066 -27.23261)
		(width 0.1651)
		(layer "F.Cu")
		(net "M_A_CLK_DN<1>")
	)
	(segment
		(start 260.050788 -50.286412)
		(end 260.050788 -49.742344)
		(width 0.0889)
		(layer "F.Cu")
		(net "M_A_CLK_DN<1>")
	)
	(segment
		(start 259.968492 -50.520092)
		(end 259.968492 -50.368708)
		(width 0.0889)
		(layer "F.Cu")
		(net "M_A_CLK_DN<1>")
	)
	(segment
		(start 258.933442 -25.44445)
		(end 259.041392 -25.3365)
		(width 0.1651)
		(layer "F.Cu")
		(net "M_A_CLK_DN<1>")
	)
	(segment
		(start 260.32333 -26.388568)
		(end 259.987288 -26.72461)
		(width 0.1651)
		(layer "F.Cu")
		(net "M_A_CLK_DN<1>")
	)
	(segment
		(start 257.599942 -20.61464)
		(end 257.320796 -20.893786)
		(width 0.1651)
		(layer "F.Cu")
		(net "M_A_CLK_DN<1>")
	)
	(segment
		(start 260.08584 -50.63744)
		(end 259.968492 -50.520092)
		(width 0.0889)
		(layer "F.Cu")
		(net "M_A_CLK_DN<1>")
	)
	(segment
		(start 259.63245 -22.447504)
		(end 260.091682 -22.906736)
		(width 0.1651)
		(layer "F.Cu")
		(net "M_A_CLK_DN<1>")
	)
	(segment
		(start 259.987288 -27.39771)
		(end 260.32333 -27.733752)
		(width 0.1651)
		(layer "F.Cu")
		(net "M_A_CLK_DN<1>")
	)
	(segment
		(start 259.041392 -25.3365)
		(end 259.76199 -25.3365)
		(width 0.1651)
		(layer "F.Cu")
		(net "M_A_CLK_DN<1>")
	)
	(segment
		(start 257.320796 -21.1709)
		(end 257.485896 -21.336)
		(width 0.1651)
		(layer "F.Cu")
		(net "M_A_CLK_DN<1>")
	)
	(segment
		(start 260.07568 -48.619664)
		(end 260.07568 -48.146208)
		(width 0.0889)
		(layer "F.Cu")
		(net "M_A_CLK_DN<1>")
	)
	(segment
		(start 260.202934 -48.018954)
		(end 260.569456 -48.018954)
		(width 0.0889)
		(layer "F.Cu")
		(net "M_A_CLK_DN<1>")
	)
	(segment
		(start 260.769862 -47.818548)
		(end 260.769862 -47.24146)
		(width 0.0889)
		(layer "F.Cu")
		(net "M_A_CLK_DN<1>")
	)
	(segment
		(start 257.599942 -20.023582)
		(end 257.599942 -20.61464)
		(width 0.1651)
		(layer "F.Cu")
		(net "M_A_CLK_DN<1>")
	)
	(segment
		(start 258.503166 -26.72461)
		(end 258.338066 -26.88971)
		(width 0.1651)
		(layer "F.Cu")
		(net "M_A_CLK_DN<1>")
	)
	(segment
		(start 258.354322 -24.439118)
		(end 258.354322 -25.27935)
		(width 0.1651)
		(layer "F.Cu")
		(net "M_A_CLK_DN<1>")
	)
	(segment
		(start 260.32333 -46.50867)
		(end 260.32333 -28.20289)
		(width 0.1651)
		(layer "F.Cu")
		(net "M_A_CLK_DN<1>")
	)
	(segment
		(start 258.503166 -27.39771)
		(end 259.987288 -27.39771)
		(width 0.1651)
		(layer "F.Cu")
		(net "M_A_CLK_DN<1>")
	)
	(segment
		(start 257.485896 -21.336)
		(end 259.207 -21.336)
		(width 0.1651)
		(layer "F.Cu")
		(net "M_A_CLK_DN<1>")
	)
	(segment
		(start 259.732526 -48.962818)
		(end 260.07568 -48.619664)
		(width 0.0889)
		(layer "F.Cu")
		(net "M_A_CLK_DN<1>")
	)
	(segment
		(start 260.278626 -46.952154)
		(end 260.278626 -46.553374)
		(width 0.0889)
		(layer "F.Cu")
		(net "M_A_CLK_DN<1>")
	)
	(segment
		(start 259.968492 -50.368708)
		(end 260.050788 -50.286412)
		(width 0.0889)
		(layer "F.Cu")
		(net "M_A_CLK_DN<1>")
	)
	(segment
		(start 260.367526 -47.041054)
		(end 260.278626 -46.952154)
		(width 0.0889)
		(layer "F.Cu")
		(net "M_A_CLK_DN<1>")
	)
	(segment
		(start 260.091682 -22.906736)
		(end 260.091682 -23.952962)
		(width 0.1651)
		(layer "F.Cu")
		(net "M_A_CLK_DN<1>")
	)
	(segment
		(start 260.569456 -47.041054)
		(end 260.367526 -47.041054)
		(width 0.0889)
		(layer "F.Cu")
		(net "M_A_CLK_DN<1>")
	)
	(segment
		(start 260.32333 -25.89784)
		(end 260.32333 -26.388568)
		(width 0.1651)
		(layer "F.Cu")
		(net "M_A_CLK_DN<1>")
	)
	(segment
		(start 260.22173 -50.63744)
		(end 260.08584 -50.63744)
		(width 0.0889)
		(layer "F.Cu")
		(net "M_A_CLK_DN<1>")
	)
	(segment
		(start 260.07568 -48.146208)
		(end 260.202934 -48.018954)
		(width 0.0889)
		(layer "F.Cu")
		(net "M_A_CLK_DN<1>")
	)
	(segment
		(start 258.338066 -27.23261)
		(end 258.503166 -27.39771)
		(width 0.1651)
		(layer "F.Cu")
		(net "M_A_CLK_DN<1>")
	)
	(segment
		(start 260.569456 -48.018954)
		(end 260.769862 -47.818548)
		(width 0.0889)
		(layer "F.Cu")
		(net "M_A_CLK_DN<1>")
	)
	(segment
		(start 257.320796 -20.893786)
		(end 257.320796 -21.1709)
		(width 0.1651)
		(layer "F.Cu")
		(net "M_A_CLK_DN<1>")
	)
	(segment
		(start 259.732526 -49.424082)
		(end 259.732526 -48.962818)
		(width 0.0889)
		(layer "F.Cu")
		(net "M_A_CLK_DN<1>")
	)
	(segment
		(start 260.091682 -23.952962)
		(end 259.770626 -24.274018)
		(width 0.1651)
		(layer "F.Cu")
		(net "M_A_CLK_DN<1>")
	)
	(segment
		(start 257.60045 -20.023582)
		(end 257.599942 -20.023582)
		(width 0.1651)
		(layer "F.Cu")
		(net "M_A_CLK_DN<1>")
	)
	(segment
		(start 260.32333 -27.733752)
		(end 260.32333 -28.20289)
		(width 0.1651)
		(layer "F.Cu")
		(net "M_A_CLK_DN<1>")
	)
	(segment
		(start 260.050788 -49.742344)
		(end 259.732526 -49.424082)
		(width 0.0889)
		(layer "F.Cu")
		(net "M_A_CLK_DN<1>")
	)
	(segment
		(start 258.519422 -25.44445)
		(end 258.933442 -25.44445)
		(width 0.1651)
		(layer "F.Cu")
		(net "M_A_CLK_DN<1>")
	)
	(via
		(at 260.32333 -28.20289)
		(size 0.508)
		(drill 0.254)
		(layers "F.Cu" "B.Cu")
		(net "M_A_CLK_DN<1>")
	)
	(segment
		(start 259.495036 -46.439328)
		(end 259.495036 -48.40351)
		(width 0.0889)
		(layer "F.Cu")
		(net "M_A_CLK_DN<2>")
	)
	(segment
		(start 259.1054 -48.793146)
		(end 259.1054 -49.7586)
		(width 0.0889)
		(layer "F.Cu")
		(net "M_A_CLK_DN<2>")
	)
	(segment
		(start 258.576826 -53.205634)
		(end 258.50469 -53.27777)
		(width 0.0889)
		(layer "F.Cu")
		(net "M_A_CLK_DN<2>")
	)
	(segment
		(start 257.86461 -23.495)
		(end 257.541776 -23.817834)
		(width 0.1651)
		(layer "F.Cu")
		(net "M_A_CLK_DN<2>")
	)
	(segment
		(start 259.52704 -46.407324)
		(end 259.495036 -46.439328)
		(width 0.0889)
		(layer "F.Cu")
		(net "M_A_CLK_DN<2>")
	)
	(segment
		(start 259.029454 -29.197808)
		(end 259.52704 -29.695394)
		(width 0.1651)
		(layer "F.Cu")
		(net "M_A_CLK_DN<2>")
	)
	(segment
		(start 259.1054 -49.7586)
		(end 258.96316 -49.90084)
		(width 0.0889)
		(layer "F.Cu")
		(net "M_A_CLK_DN<2>")
	)
	(segment
		(start 259.495036 -48.40351)
		(end 259.1054 -48.793146)
		(width 0.0889)
		(layer "F.Cu")
		(net "M_A_CLK_DN<2>")
	)
	(segment
		(start 258.50469 -53.27777)
		(end 258.50469 -53.60924)
		(width 0.0889)
		(layer "F.Cu")
		(net "M_A_CLK_DN<2>")
	)
	(segment
		(start 258.96316 -49.90084)
		(end 258.96316 -50.139346)
		(width 0.0889)
		(layer "F.Cu")
		(net "M_A_CLK_DN<2>")
	)
	(segment
		(start 259.52704 -29.695394)
		(end 259.52704 -46.407324)
		(width 0.1651)
		(layer "F.Cu")
		(net "M_A_CLK_DN<2>")
	)
	(segment
		(start 257.541776 -27.71013)
		(end 259.029454 -29.197808)
		(width 0.1651)
		(layer "F.Cu")
		(net "M_A_CLK_DN<2>")
	)
	(segment
		(start 257.541776 -23.817834)
		(end 257.541776 -27.71013)
		(width 0.1651)
		(layer "F.Cu")
		(net "M_A_CLK_DN<2>")
	)
	(via
		(at 257.86461 -23.495)
		(size 0.508)
		(drill 0.254)
		(layers "F.Cu" "B.Cu")
		(net "M_A_CLK_DN<2>")
	)
	(via
		(at 259.029454 -29.197808)
		(size 0.508)
		(drill 0.254)
		(layers "F.Cu" "B.Cu")
		(net "M_A_CLK_DN<2>")
	)
	(arc
		(start 259.0165 -50.342292)
		(mid 259.095631 -50.637694)
		(end 259.0165 -50.933096)
		(width 0.0889)
		(layer "F.Cu")
		(net "M_A_CLK_DN<2>")
	)
	(arc
		(start 258.598162 -53.202586)
		(mid 258.587508 -53.204207)
		(end 258.576826 -53.205634)
		(width 0.0889)
		(layer "F.Cu")
		(net "M_A_CLK_DN<2>")
	)
	(arc
		(start 259.0165 -51.923696)
		(mid 258.963001 -52.123594)
		(end 259.0165 -52.323492)
		(width 0.0889)
		(layer "F.Cu")
		(net "M_A_CLK_DN<2>")
	)
	(arc
		(start 258.96316 -50.139346)
		(mid 258.976296 -50.244375)
		(end 259.0165 -50.342292)
		(width 0.0889)
		(layer "F.Cu")
		(net "M_A_CLK_DN<2>")
	)
	(arc
		(start 259.0165 -52.323492)
		(mid 259.038266 -52.87288)
		(end 258.598162 -53.202586)
		(width 0.0889)
		(layer "F.Cu")
		(net "M_A_CLK_DN<2>")
	)
	(arc
		(start 259.0165 -51.332892)
		(mid 259.095631 -51.628294)
		(end 259.0165 -51.923696)
		(width 0.0889)
		(layer "F.Cu")
		(net "M_A_CLK_DN<2>")
	)
	(arc
		(start 259.0165 -50.933096)
		(mid 258.963001 -51.132994)
		(end 259.0165 -51.332892)
		(width 0.0889)
		(layer "F.Cu")
		(net "M_A_CLK_DN<2>")
	)
	(segment
		(start 257.599942 -24.824182)
		(end 257.599942 -23.759668)
		(width 0.1651)
		(layer "B.Cu")
		(net "M_A_CLK_DN<2>")
	)
	(segment
		(start 257.599942 -23.759668)
		(end 257.86461 -23.495)
		(width 0.1651)
		(layer "B.Cu")
		(net "M_A_CLK_DN<2>")
	)
	(segment
		(start 257.60045 -24.824182)
		(end 257.599942 -24.824182)
		(width 0.1651)
		(layer "B.Cu")
		(net "M_A_CLK_DN<2>")
	)
	(segment
		(start 259.033518 -17.526)
		(end 258.047236 -17.526)
		(width 0.1651)
		(layer "F.Cu")
		(net "M_A_CLK_DN<0>")
	)
	(segment
		(start 260.49224 -18.129758)
		(end 259.033518 -17.526)
		(width 0.1651)
		(layer "F.Cu")
		(net "M_A_CLK_DN<0>")
	)
	(segment
		(start 261.21868 -22.031706)
		(end 261.21868 -19.3929)
		(width 0.1651)
		(layer "F.Cu")
		(net "M_A_CLK_DN<0>")
	)
	(segment
		(start 261.11962 -46.041564)
		(end 261.11962 -46.061122)
		(width 0.0889)
		(layer "F.Cu")
		(net "M_A_CLK_DN<0>")
	)
	(segment
		(start 261.21868 -19.3929)
		(end 260.839712 -18.47723)
		(width 0.1651)
		(layer "F.Cu")
		(net "M_A_CLK_DN<0>")
	)
	(segment
		(start 257.543808 -17.317212)
		(end 257.320796 -17.094454)
		(width 0.1651)
		(layer "F.Cu")
		(net "M_A_CLK_DN<0>")
	)
	(segment
		(start 257.320796 -17.094454)
		(end 257.320796 -16.821404)
		(width 0.1651)
		(layer "F.Cu")
		(net "M_A_CLK_DN<0>")
	)
	(segment
		(start 261.11962 -29.249624)
		(end 261.11962 -25.559258)
		(width 0.1651)
		(layer "F.Cu")
		(net "M_A_CLK_DN<0>")
	)
	(segment
		(start 257.599942 -16.542258)
		(end 257.599942 -15.423642)
		(width 0.1651)
		(layer "F.Cu")
		(net "M_A_CLK_DN<0>")
	)
	(segment
		(start 260.733286 -50.341784)
		(end 260.73354 -50.342038)
		(width 0.0889)
		(layer "F.Cu")
		(net "M_A_CLK_DN<0>")
	)
	(segment
		(start 261.067804 -46.112938)
		(end 261.067804 -46.374558)
		(width 0.0889)
		(layer "F.Cu")
		(net "M_A_CLK_DN<0>")
	)
	(segment
		(start 260.839712 -18.47723)
		(end 260.49224 -18.129758)
		(width 0.1651)
		(layer "F.Cu")
		(net "M_A_CLK_DN<0>")
	)
	(segment
		(start 258.047236 -17.526)
		(end 257.543808 -17.317212)
		(width 0.1651)
		(layer "F.Cu")
		(net "M_A_CLK_DN<0>")
	)
	(segment
		(start 260.23951 -51.22799)
		(end 260.206744 -51.22799)
		(width 0.0889)
		(layer "F.Cu")
		(net "M_A_CLK_DN<0>")
	)
	(segment
		(start 259.36321 -51.791616)
		(end 259.36321 -52.12334)
		(width 0.0889)
		(layer "F.Cu")
		(net "M_A_CLK_DN<0>")
	)
	(segment
		(start 261.163308 -22.165564)
		(end 261.21868 -22.031706)
		(width 0.1651)
		(layer "F.Cu")
		(net "M_A_CLK_DN<0>")
	)
	(segment
		(start 261.11962 -25.559258)
		(end 260.844792 -25.28443)
		(width 0.1651)
		(layer "F.Cu")
		(net "M_A_CLK_DN<0>")
	)
	(segment
		(start 261.11962 -29.249624)
		(end 261.11962 -46.041564)
		(width 0.1651)
		(layer "F.Cu")
		(net "M_A_CLK_DN<0>")
	)
	(segment
		(start 260.636004 -49.015396)
		(end 260.636004 -50.173636)
		(width 0.0889)
		(layer "F.Cu")
		(net "M_A_CLK_DN<0>")
	)
	(segment
		(start 261.067804 -46.374558)
		(end 261.35584 -46.662594)
		(width 0.0889)
		(layer "F.Cu")
		(net "M_A_CLK_DN<0>")
	)
	(segment
		(start 260.844792 -22.934422)
		(end 261.163308 -22.165564)
		(width 0.1651)
		(layer "F.Cu")
		(net "M_A_CLK_DN<0>")
	)
	(segment
		(start 260.636004 -50.173636)
		(end 260.733286 -50.341784)
		(width 0.0889)
		(layer "F.Cu")
		(net "M_A_CLK_DN<0>")
	)
	(segment
		(start 257.320796 -16.821404)
		(end 257.599942 -16.542258)
		(width 0.1651)
		(layer "F.Cu")
		(net "M_A_CLK_DN<0>")
	)
	(segment
		(start 257.599942 -15.423642)
		(end 257.60045 -15.423642)
		(width 0.1651)
		(layer "F.Cu")
		(net "M_A_CLK_DN<0>")
	)
	(segment
		(start 261.35584 -46.662594)
		(end 261.35584 -48.29556)
		(width 0.0889)
		(layer "F.Cu")
		(net "M_A_CLK_DN<0>")
	)
	(segment
		(start 261.35584 -48.29556)
		(end 260.636004 -49.015396)
		(width 0.0889)
		(layer "F.Cu")
		(net "M_A_CLK_DN<0>")
	)
	(segment
		(start 261.11962 -46.061122)
		(end 261.067804 -46.112938)
		(width 0.0889)
		(layer "F.Cu")
		(net "M_A_CLK_DN<0>")
	)
	(segment
		(start 260.844792 -25.28443)
		(end 260.844792 -22.934422)
		(width 0.1651)
		(layer "F.Cu")
		(net "M_A_CLK_DN<0>")
	)
	(segment
		(start 259.435854 -51.718972)
		(end 259.36321 -51.791616)
		(width 0.0889)
		(layer "F.Cu")
		(net "M_A_CLK_DN<0>")
	)
	(via
		(at 261.11962 -29.249624)
		(size 0.508)
		(drill 0.254)
		(layers "F.Cu" "B.Cu")
		(net "M_A_CLK_DN<0>")
	)
	(arc
		(start 259.456936 -51.715924)
		(mid 259.446409 -51.717542)
		(end 259.435854 -51.718972)
		(width 0.0889)
		(layer "F.Cu")
		(net "M_A_CLK_DN<0>")
	)
	(arc
		(start 260.73354 -50.342038)
		(mid 260.812762 -50.631156)
		(end 260.73989 -50.92192)
		(width 0.0889)
		(layer "F.Cu")
		(net "M_A_CLK_DN<0>")
	)
	(arc
		(start 260.73989 -50.92192)
		(mid 260.530375 -51.141474)
		(end 260.23951 -51.22799)
		(width 0.0889)
		(layer "F.Cu")
		(net "M_A_CLK_DN<0>")
	)
	(arc
		(start 259.87502 -51.427888)
		(mid 259.698492 -51.619105)
		(end 259.456936 -51.715924)
		(width 0.0889)
		(layer "F.Cu")
		(net "M_A_CLK_DN<0>")
	)
	(arc
		(start 260.206744 -51.22799)
		(mid 260.015102 -51.285156)
		(end 259.87502 -51.427888)
		(width 0.0889)
		(layer "F.Cu")
		(net "M_A_CLK_DN<0>")
	)
	(segment
		(start 251.434346 -48.074072)
		(end 252.143514 -48.78324)
		(width 0.0889)
		(layer "F.Cu")
		(net "M_A_CKE<3>")
	)
	(segment
		(start 244.5004 -22.6568)
		(end 244.5004 -23.0378)
		(width 0.1651)
		(layer "F.Cu")
		(net "M_A_CKE<3>")
	)
	(segment
		(start 251.434346 -46.852078)
		(end 251.434346 -48.074072)
		(width 0.0889)
		(layer "F.Cu")
		(net "M_A_CKE<3>")
	)
	(segment
		(start 245.745 -26.797)
		(end 247.4722 -28.5242)
		(width 0.1651)
		(layer "F.Cu")
		(net "M_A_CKE<3>")
	)
	(segment
		(start 244.5004 -23.0378)
		(end 244.2972 -23.241)
		(width 0.1651)
		(layer "F.Cu")
		(net "M_A_CKE<3>")
	)
	(segment
		(start 244.3226 -22.479)
		(end 244.5004 -22.6568)
		(width 0.1651)
		(layer "F.Cu")
		(net "M_A_CKE<3>")
	)
	(segment
		(start 251.9934 -49.7332)
		(end 251.9934 -50.343054)
		(width 0.0889)
		(layer "F.Cu")
		(net "M_A_CKE<3>")
	)
	(segment
		(start 245.745 -26.491946)
		(end 245.745 -26.797)
		(width 0.1651)
		(layer "F.Cu")
		(net "M_A_CKE<3>")
	)
	(segment
		(start 252.143514 -49.583086)
		(end 251.9934 -49.7332)
		(width 0.0889)
		(layer "F.Cu")
		(net "M_A_CKE<3>")
	)
	(segment
		(start 251.37999 -46.797722)
		(end 251.434346 -46.852078)
		(width 0.0889)
		(layer "F.Cu")
		(net "M_A_CKE<3>")
	)
	(segment
		(start 247.4722 -30.734)
		(end 251.37999 -34.64179)
		(width 0.1651)
		(layer "F.Cu")
		(net "M_A_CKE<3>")
	)
	(segment
		(start 251.37999 -34.64179)
		(end 251.37999 -46.338744)
		(width 0.1651)
		(layer "F.Cu")
		(net "M_A_CKE<3>")
	)
	(segment
		(start 251.37999 -46.338744)
		(end 251.37999 -46.797722)
		(width 0.0889)
		(layer "F.Cu")
		(net "M_A_CKE<3>")
	)
	(segment
		(start 244.2972 -25.044146)
		(end 245.745 -26.491946)
		(width 0.1651)
		(layer "F.Cu")
		(net "M_A_CKE<3>")
	)
	(segment
		(start 247.4722 -28.5242)
		(end 247.4722 -29.256228)
		(width 0.1651)
		(layer "F.Cu")
		(net "M_A_CKE<3>")
	)
	(segment
		(start 247.4722 -29.256228)
		(end 247.4722 -30.734)
		(width 0.1651)
		(layer "F.Cu")
		(net "M_A_CKE<3>")
	)
	(segment
		(start 251.9934 -50.343054)
		(end 252.495304 -50.844958)
		(width 0.0889)
		(layer "F.Cu")
		(net "M_A_CKE<3>")
	)
	(segment
		(start 244.2972 -23.241)
		(end 244.2972 -25.044146)
		(width 0.1651)
		(layer "F.Cu")
		(net "M_A_CKE<3>")
	)
	(segment
		(start 252.495304 -50.844958)
		(end 252.495304 -51.132486)
		(width 0.0889)
		(layer "F.Cu")
		(net "M_A_CKE<3>")
	)
	(segment
		(start 252.143514 -48.78324)
		(end 252.143514 -49.583086)
		(width 0.0889)
		(layer "F.Cu")
		(net "M_A_CKE<3>")
	)
	(segment
		(start 243.999766 -21.517356)
		(end 244.3226 -21.84019)
		(width 0.1651)
		(layer "F.Cu")
		(net "M_A_CKE<3>")
	)
	(segment
		(start 244.3226 -21.84019)
		(end 244.3226 -22.479)
		(width 0.1651)
		(layer "F.Cu")
		(net "M_A_CKE<3>")
	)
	(via
		(at 243.999766 -21.517356)
		(size 0.508)
		(drill 0.254)
		(layers "F.Cu" "B.Cu")
		(net "M_A_CKE<3>")
	)
	(via
		(at 247.4722 -29.256228)
		(size 0.508)
		(drill 0.254)
		(layers "F.Cu" "B.Cu")
		(net "M_A_CKE<3>")
	)
	(segment
		(start 243.999766 -20.224242)
		(end 243.999766 -21.517356)
		(width 0.1651)
		(layer "B.Cu")
		(net "M_A_CKE<3>")
	)
	(segment
		(start 244.000274 -20.224242)
		(end 243.999766 -20.224242)
		(width 0.1651)
		(layer "B.Cu")
		(net "M_A_CKE<3>")
	)
	(segment
		(start 247.09755 -27.26055)
		(end 248.0056 -28.1686)
		(width 0.1651)
		(layer "F.Cu")
		(net "M_A_CKE<2>")
	)
	(segment
		(start 244.849904 -23.534878)
		(end 244.849904 -24.682704)
		(width 0.1651)
		(layer "F.Cu")
		(net "M_A_CKE<2>")
	)
	(segment
		(start 244.849904 -24.682704)
		(end 246.2911 -26.1239)
		(width 0.1651)
		(layer "F.Cu")
		(net "M_A_CKE<2>")
	)
	(segment
		(start 246.2911 -26.4541)
		(end 247.09755 -27.26055)
		(width 0.1651)
		(layer "F.Cu")
		(net "M_A_CKE<2>")
	)
	(segment
		(start 251.88418 -46.385226)
		(end 251.88418 -47.864268)
		(width 0.0889)
		(layer "F.Cu")
		(net "M_A_CKE<2>")
	)
	(segment
		(start 252.675644 -49.961546)
		(end 252.495304 -50.141886)
		(width 0.0889)
		(layer "F.Cu")
		(net "M_A_CKE<2>")
	)
	(segment
		(start 251.88418 -34.384234)
		(end 251.88418 -46.385226)
		(width 0.1651)
		(layer "F.Cu")
		(net "M_A_CKE<2>")
	)
	(segment
		(start 246.2911 -26.1239)
		(end 246.2911 -26.4541)
		(width 0.1651)
		(layer "F.Cu")
		(net "M_A_CKE<2>")
	)
	(segment
		(start 248.0056 -30.505654)
		(end 251.88418 -34.384234)
		(width 0.1651)
		(layer "F.Cu")
		(net "M_A_CKE<2>")
	)
	(segment
		(start 251.88418 -47.864268)
		(end 252.675644 -48.655732)
		(width 0.0889)
		(layer "F.Cu")
		(net "M_A_CKE<2>")
	)
	(segment
		(start 248.0056 -28.1686)
		(end 248.0056 -30.505654)
		(width 0.1651)
		(layer "F.Cu")
		(net "M_A_CKE<2>")
	)
	(segment
		(start 252.675644 -48.655732)
		(end 252.675644 -49.961546)
		(width 0.0889)
		(layer "F.Cu")
		(net "M_A_CKE<2>")
	)
	(via
		(at 247.09755 -27.26055)
		(size 0.508)
		(drill 0.254)
		(layers "F.Cu" "B.Cu")
		(net "M_A_CKE<2>")
	)
	(via
		(at 244.849904 -23.534878)
		(size 0.508)
		(drill 0.254)
		(layers "F.Cu" "B.Cu")
		(net "M_A_CKE<2>")
	)
	(segment
		(start 244.850412 -24.824182)
		(end 244.849904 -24.824182)
		(width 0.1651)
		(layer "B.Cu")
		(net "M_A_CKE<2>")
	)
	(segment
		(start 244.849904 -24.824182)
		(end 244.849904 -23.534878)
		(width 0.1651)
		(layer "B.Cu")
		(net "M_A_CKE<2>")
	)
	(segment
		(start 246.9642 -28.7782)
		(end 246.9642 -30.988)
		(width 0.1651)
		(layer "F.Cu")
		(net "M_A_CKE<1>")
	)
	(segment
		(start 251.006356 -47.00651)
		(end 251.006356 -48.30572)
		(width 0.0889)
		(layer "F.Cu")
		(net "M_A_CKE<1>")
	)
	(segment
		(start 250.072652 -35.115246)
		(end 250.395994 -34.791904)
		(width 0.1651)
		(layer "F.Cu")
		(net "M_A_CKE<1>")
	)
	(segment
		(start 250.8758 -46.875954)
		(end 251.006356 -47.00651)
		(width 0.0889)
		(layer "F.Cu")
		(net "M_A_CKE<1>")
	)
	(segment
		(start 243.4844 -23.0378)
		(end 243.7892 -23.3426)
		(width 0.1651)
		(layer "F.Cu")
		(net "M_A_CKE<1>")
	)
	(segment
		(start 243.7384 -22.4536)
		(end 243.4844 -22.7076)
		(width 0.1651)
		(layer "F.Cu")
		(net "M_A_CKE<1>")
	)
	(segment
		(start 243.7892 -25.273)
		(end 245.237 -26.7208)
		(width 0.1651)
		(layer "F.Cu")
		(net "M_A_CKE<1>")
	)
	(segment
		(start 251.006356 -48.30572)
		(end 251.5616 -48.860964)
		(width 0.0889)
		(layer "F.Cu")
		(net "M_A_CKE<1>")
	)
	(segment
		(start 245.237 -27.051)
		(end 245.739412 -27.553412)
		(width 0.1651)
		(layer "F.Cu")
		(net "M_A_CKE<1>")
	)
	(segment
		(start 243.4082 -21.6662)
		(end 243.7384 -21.9964)
		(width 0.1651)
		(layer "F.Cu")
		(net "M_A_CKE<1>")
	)
	(segment
		(start 244.000274 -20.023582)
		(end 243.999766 -20.023582)
		(width 0.1651)
		(layer "F.Cu")
		(net "M_A_CKE<1>")
	)
	(segment
		(start 250.8758 -46.371002)
		(end 250.8758 -46.875954)
		(width 0.0889)
		(layer "F.Cu")
		(net "M_A_CKE<1>")
	)
	(segment
		(start 246.9642 -30.988)
		(end 250.01601 -34.03981)
		(width 0.1651)
		(layer "F.Cu")
		(net "M_A_CKE<1>")
	)
	(segment
		(start 251.5616 -48.860964)
		(end 251.5616 -50.562256)
		(width 0.0889)
		(layer "F.Cu")
		(net "M_A_CKE<1>")
	)
	(segment
		(start 250.01601 -34.03981)
		(end 250.01601 -34.219896)
		(width 0.1651)
		(layer "F.Cu")
		(net "M_A_CKE<1>")
	)
	(segment
		(start 249.590306 -34.6456)
		(end 249.590306 -34.87293)
		(width 0.1651)
		(layer "F.Cu")
		(net "M_A_CKE<1>")
	)
	(segment
		(start 243.4844 -22.7076)
		(end 243.4844 -23.0378)
		(width 0.1651)
		(layer "F.Cu")
		(net "M_A_CKE<1>")
	)
	(segment
		(start 243.4082 -21.3614)
		(end 243.4082 -21.6662)
		(width 0.1651)
		(layer "F.Cu")
		(net "M_A_CKE<1>")
	)
	(segment
		(start 250.8758 -35.091624)
		(end 250.8758 -46.371002)
		(width 0.1651)
		(layer "F.Cu")
		(net "M_A_CKE<1>")
	)
	(segment
		(start 249.832622 -35.115246)
		(end 250.072652 -35.115246)
		(width 0.1651)
		(layer "F.Cu")
		(net "M_A_CKE<1>")
	)
	(segment
		(start 243.999766 -20.023582)
		(end 243.999766 -20.769834)
		(width 0.1651)
		(layer "F.Cu")
		(net "M_A_CKE<1>")
	)
	(segment
		(start 243.999766 -20.769834)
		(end 243.4082 -21.3614)
		(width 0.1651)
		(layer "F.Cu")
		(net "M_A_CKE<1>")
	)
	(segment
		(start 245.237 -26.7208)
		(end 245.237 -27.051)
		(width 0.1651)
		(layer "F.Cu")
		(net "M_A_CKE<1>")
	)
	(segment
		(start 250.01601 -34.219896)
		(end 249.590306 -34.6456)
		(width 0.1651)
		(layer "F.Cu")
		(net "M_A_CKE<1>")
	)
	(segment
		(start 250.395994 -34.791904)
		(end 250.57608 -34.791904)
		(width 0.1651)
		(layer "F.Cu")
		(net "M_A_CKE<1>")
	)
	(segment
		(start 243.7384 -21.9964)
		(end 243.7384 -22.4536)
		(width 0.1651)
		(layer "F.Cu")
		(net "M_A_CKE<1>")
	)
	(segment
		(start 251.5616 -50.562256)
		(end 251.636784 -50.63744)
		(width 0.0889)
		(layer "F.Cu")
		(net "M_A_CKE<1>")
	)
	(segment
		(start 243.7892 -23.3426)
		(end 243.7892 -25.273)
		(width 0.1651)
		(layer "F.Cu")
		(net "M_A_CKE<1>")
	)
	(segment
		(start 249.590306 -34.87293)
		(end 249.832622 -35.115246)
		(width 0.1651)
		(layer "F.Cu")
		(net "M_A_CKE<1>")
	)
	(segment
		(start 245.739412 -27.553412)
		(end 246.9642 -28.7782)
		(width 0.1651)
		(layer "F.Cu")
		(net "M_A_CKE<1>")
	)
	(segment
		(start 250.57608 -34.791904)
		(end 250.8758 -35.091624)
		(width 0.1651)
		(layer "F.Cu")
		(net "M_A_CKE<1>")
	)
	(via
		(at 245.739412 -27.553412)
		(size 0.508)
		(drill 0.254)
		(layers "F.Cu" "B.Cu")
		(net "M_A_CKE<1>")
	)
	(segment
		(start 252.38837 -47.70882)
		(end 252.38837 -47.430944)
		(width 0.0889)
		(layer "F.Cu")
		(net "M_A_CKE<0>")
	)
	(segment
		(start 248.711974 -27.183588)
		(end 248.711974 -26.797508)
		(width 0.1651)
		(layer "F.Cu")
		(net "M_A_CKE<0>")
	)
	(segment
		(start 244.849904 -15.423642)
		(end 244.849904 -16.716756)
		(width 0.1651)
		(layer "F.Cu")
		(net "M_A_CKE<0>")
	)
	(segment
		(start 248.711974 -30.460442)
		(end 248.711974 -27.183588)
		(width 0.1651)
		(layer "F.Cu")
		(net "M_A_CKE<0>")
	)
	(segment
		(start 253.207774 -48.528224)
		(end 252.38837 -47.70882)
		(width 0.0889)
		(layer "F.Cu")
		(net "M_A_CKE<0>")
	)
	(segment
		(start 248.711974 -26.797508)
		(end 248.0818 -26.167334)
		(width 0.1651)
		(layer "F.Cu")
		(net "M_A_CKE<0>")
	)
	(segment
		(start 253.207774 -50.49139)
		(end 253.207774 -48.528224)
		(width 0.0889)
		(layer "F.Cu")
		(net "M_A_CKE<0>")
	)
	(segment
		(start 244.850412 -15.423642)
		(end 244.849904 -15.423642)
		(width 0.1651)
		(layer "F.Cu")
		(net "M_A_CKE<0>")
	)
	(segment
		(start 252.38837 -47.430944)
		(end 252.38837 -34.136838)
		(width 0.1651)
		(layer "F.Cu")
		(net "M_A_CKE<0>")
	)
	(segment
		(start 252.38837 -34.136838)
		(end 248.711974 -30.460442)
		(width 0.1651)
		(layer "F.Cu")
		(net "M_A_CKE<0>")
	)
	(segment
		(start 253.353824 -50.63744)
		(end 253.207774 -50.49139)
		(width 0.0889)
		(layer "F.Cu")
		(net "M_A_CKE<0>")
	)
	(via
		(at 248.711974 -27.183588)
		(size 0.508)
		(drill 0.254)
		(layers "F.Cu" "B.Cu")
		(net "M_A_CKE<0>")
	)
	(via
		(at 248.0818 -26.167334)
		(size 0.508)
		(drill 0.254)
		(layers "F.Cu" "B.Cu")
		(net "M_A_CKE<0>")
	)
	(via
		(at 244.849904 -16.716756)
		(size 0.4572)
		(drill 0.2032)
		(layers "F.Cu" "B.Cu")
		(net "M_A_CKE<0>")
	)
	(segment
		(start 245.220236 -21.852636)
		(end 245.220236 -21.276564)
		(width 0.14224)
		(layer "In11.Cu")
		(net "M_A_CKE<0>")
	)
	(segment
		(start 244.849904 -17.977104)
		(end 244.849904 -16.716756)
		(width 0.14224)
		(layer "In11.Cu")
		(net "M_A_CKE<0>")
	)
	(segment
		(start 245.220236 -21.276564)
		(end 245.287546 -21.209254)
		(width 0.14224)
		(layer "In11.Cu")
		(net "M_A_CKE<0>")
	)
	(segment
		(start 245.3894 -22.4536)
		(end 245.3894 -22.0218)
		(width 0.14224)
		(layer "In11.Cu")
		(net "M_A_CKE<0>")
	)
	(segment
		(start 245.287546 -18.414746)
		(end 244.849904 -17.977104)
		(width 0.14224)
		(layer "In11.Cu")
		(net "M_A_CKE<0>")
	)
	(segment
		(start 245.5672 -23.4442)
		(end 245.1862 -23.0632)
		(width 0.14224)
		(layer "In11.Cu")
		(net "M_A_CKE<0>")
	)
	(segment
		(start 245.3894 -22.0218)
		(end 245.220236 -21.852636)
		(width 0.14224)
		(layer "In11.Cu")
		(net "M_A_CKE<0>")
	)
	(segment
		(start 247.492266 -25.5778)
		(end 247.366536 -25.5778)
		(width 0.14224)
		(layer "In11.Cu")
		(net "M_A_CKE<0>")
	)
	(segment
		(start 245.5672 -23.778464)
		(end 245.5672 -23.4442)
		(width 0.14224)
		(layer "In11.Cu")
		(net "M_A_CKE<0>")
	)
	(segment
		(start 245.287546 -21.209254)
		(end 245.287546 -18.414746)
		(width 0.14224)
		(layer "In11.Cu")
		(net "M_A_CKE<0>")
	)
	(segment
		(start 247.366536 -25.5778)
		(end 245.5672 -23.778464)
		(width 0.14224)
		(layer "In11.Cu")
		(net "M_A_CKE<0>")
	)
	(segment
		(start 245.1862 -22.6568)
		(end 245.3894 -22.4536)
		(width 0.14224)
		(layer "In11.Cu")
		(net "M_A_CKE<0>")
	)
	(segment
		(start 245.1862 -23.0632)
		(end 245.1862 -22.6568)
		(width 0.14224)
		(layer "In11.Cu")
		(net "M_A_CKE<0>")
	)
	(segment
		(start 248.0818 -26.167334)
		(end 247.492266 -25.5778)
		(width 0.14224)
		(layer "In11.Cu")
		(net "M_A_CKE<0>")
	)
	(segment
		(start 276.29993 -20.023582)
		(end 276.29993 -18.734786)
		(width 0.10795)
		(layer "F.Cu")
		(net "M_A_C<2>")
	)
	(segment
		(start 276.29993 -18.734786)
		(end 276.300438 -18.734278)
		(width 0.10795)
		(layer "F.Cu")
		(net "M_A_C<2>")
	)
	(segment
		(start 267.089636 -52.618386)
		(end 266.518136 -52.618386)
		(width 0.1016)
		(layer "F.Cu")
		(net "M_A_C<2>")
	)
	(segment
		(start 276.300438 -20.023582)
		(end 276.29993 -20.023582)
		(width 0.10795)
		(layer "F.Cu")
		(net "M_A_C<2>")
	)
	(via
		(at 276.300438 -18.734278)
		(size 0.4572)
		(drill 0.2032)
		(layers "F.Cu" "B.Cu")
		(net "M_A_C<2>")
	)
	(via
		(at 266.518136 -52.618386)
		(size 0.508)
		(drill 0.254)
		(layers "F.Cu" "B.Cu")
		(net "M_A_C<2>")
	)
	(via
		(at 276.29993 -21.517356)
		(size 0.508)
		(drill 0.254)
		(layers "F.Cu" "B.Cu")
		(net "M_A_C<2>")
	)
	(segment
		(start 276.29993 -20.224242)
		(end 276.29993 -21.517356)
		(width 0.1651)
		(layer "B.Cu")
		(net "M_A_C<2>")
	)
	(segment
		(start 276.300438 -20.224242)
		(end 276.29993 -20.224242)
		(width 0.1651)
		(layer "B.Cu")
		(net "M_A_C<2>")
	)
	(segment
		(start 276.596602 -27.239468)
		(end 276.16277 -27.239468)
		(width 0.14224)
		(layer "In11.Cu")
		(net "M_A_C<2>")
	)
	(segment
		(start 267.1572 -51.979322)
		(end 267.1572 -50.3936)
		(width 0.0889)
		(layer "In11.Cu")
		(net "M_A_C<2>")
	)
	(segment
		(start 276.588474 -26.411174)
		(end 276.7584 -26.241248)
		(width 0.14224)
		(layer "In11.Cu")
		(net "M_A_C<2>")
	)
	(segment
		(start 267.1572 -50.3936)
		(end 268.682724 -48.868076)
		(width 0.0889)
		(layer "In11.Cu")
		(net "M_A_C<2>")
	)
	(segment
		(start 276.377654 -20.546568)
		(end 276.377654 -20.074382)
		(width 0.14224)
		(layer "In11.Cu")
		(net "M_A_C<2>")
	)
	(segment
		(start 276.874732 -22.722332)
		(end 276.6822 -22.5298)
		(width 0.14224)
		(layer "In11.Cu")
		(net "M_A_C<2>")
	)
	(segment
		(start 276.7838 -19.21764)
		(end 276.300438 -18.734278)
		(width 0.14224)
		(layer "In11.Cu")
		(net "M_A_C<2>")
	)
	(segment
		(start 276.7838 -19.668236)
		(end 276.7838 -19.21764)
		(width 0.14224)
		(layer "In11.Cu")
		(net "M_A_C<2>")
	)
	(segment
		(start 276.6822 -22.5298)
		(end 276.6822 -22.250146)
		(width 0.14224)
		(layer "In11.Cu")
		(net "M_A_C<2>")
	)
	(segment
		(start 276.006306 -27.083004)
		(end 276.006306 -26.587196)
		(width 0.14224)
		(layer "In11.Cu")
		(net "M_A_C<2>")
	)
	(segment
		(start 276.764242 -27.407108)
		(end 276.596602 -27.239468)
		(width 0.14224)
		(layer "In11.Cu")
		(net "M_A_C<2>")
	)
	(segment
		(start 276.16277 -27.239468)
		(end 276.006306 -27.083004)
		(width 0.14224)
		(layer "In11.Cu")
		(net "M_A_C<2>")
	)
	(segment
		(start 276.629622 -21.187664)
		(end 276.629622 -20.798536)
		(width 0.14224)
		(layer "In11.Cu")
		(net "M_A_C<2>")
	)
	(segment
		(start 276.6822 -22.250146)
		(end 276.4536 -22.021546)
		(width 0.14224)
		(layer "In11.Cu")
		(net "M_A_C<2>")
	)
	(segment
		(start 266.518136 -52.618386)
		(end 267.1572 -51.979322)
		(width 0.0889)
		(layer "In11.Cu")
		(net "M_A_C<2>")
	)
	(segment
		(start 276.7584 -26.241248)
		(end 276.7584 -24.321516)
		(width 0.14224)
		(layer "In11.Cu")
		(net "M_A_C<2>")
	)
	(segment
		(start 276.486366 -24.049482)
		(end 276.486366 -23.335234)
		(width 0.14224)
		(layer "In11.Cu")
		(net "M_A_C<2>")
	)
	(segment
		(start 276.486366 -23.335234)
		(end 276.874732 -22.946868)
		(width 0.14224)
		(layer "In11.Cu")
		(net "M_A_C<2>")
	)
	(segment
		(start 268.682724 -48.868076)
		(end 268.682724 -48.552354)
		(width 0.0889)
		(layer "In11.Cu")
		(net "M_A_C<2>")
	)
	(segment
		(start 276.4536 -21.671026)
		(end 276.29993 -21.517356)
		(width 0.14224)
		(layer "In11.Cu")
		(net "M_A_C<2>")
	)
	(segment
		(start 276.874732 -22.946868)
		(end 276.874732 -22.722332)
		(width 0.14224)
		(layer "In11.Cu")
		(net "M_A_C<2>")
	)
	(segment
		(start 276.7584 -24.321516)
		(end 276.486366 -24.049482)
		(width 0.14224)
		(layer "In11.Cu")
		(net "M_A_C<2>")
	)
	(segment
		(start 276.29993 -21.517356)
		(end 276.629622 -21.187664)
		(width 0.14224)
		(layer "In11.Cu")
		(net "M_A_C<2>")
	)
	(segment
		(start 276.764242 -27.714194)
		(end 276.764242 -27.407108)
		(width 0.14224)
		(layer "In11.Cu")
		(net "M_A_C<2>")
	)
	(segment
		(start 276.182328 -26.411174)
		(end 276.588474 -26.411174)
		(width 0.14224)
		(layer "In11.Cu")
		(net "M_A_C<2>")
	)
	(segment
		(start 276.377654 -20.074382)
		(end 276.7838 -19.668236)
		(width 0.14224)
		(layer "In11.Cu")
		(net "M_A_C<2>")
	)
	(segment
		(start 276.4536 -22.021546)
		(end 276.4536 -21.671026)
		(width 0.14224)
		(layer "In11.Cu")
		(net "M_A_C<2>")
	)
	(segment
		(start 268.682724 -35.795712)
		(end 276.764242 -27.714194)
		(width 0.14224)
		(layer "In11.Cu")
		(net "M_A_C<2>")
	)
	(segment
		(start 276.006306 -26.587196)
		(end 276.182328 -26.411174)
		(width 0.14224)
		(layer "In11.Cu")
		(net "M_A_C<2>")
	)
	(segment
		(start 268.682724 -48.552354)
		(end 268.682724 -35.795712)
		(width 0.14224)
		(layer "In11.Cu")
		(net "M_A_C<2>")
	)
	(segment
		(start 276.629622 -20.798536)
		(end 276.377654 -20.546568)
		(width 0.14224)
		(layer "In11.Cu")
		(net "M_A_C<2>")
	)
	(segment
		(start 247.39981 -20.023582)
		(end 247.39981 -18.734278)
		(width 0.1651)
		(layer "F.Cu")
		(net "M_A_BG<1>")
	)
	(segment
		(start 247.400318 -20.023582)
		(end 247.39981 -20.023582)
		(width 0.1651)
		(layer "F.Cu")
		(net "M_A_BG<1>")
	)
	(segment
		(start 252.495304 -52.12334)
		(end 251.923804 -52.12334)
		(width 0.1016)
		(layer "F.Cu")
		(net "M_A_BG<1>")
	)
	(via
		(at 247.39981 -18.734278)
		(size 0.4572)
		(drill 0.2032)
		(layers "F.Cu" "B.Cu")
		(net "M_A_BG<1>")
	)
	(via
		(at 247.39981 -21.488146)
		(size 0.508)
		(drill 0.254)
		(layers "F.Cu" "B.Cu")
		(net "M_A_BG<1>")
	)
	(via
		(at 251.923804 -52.12334)
		(size 0.508)
		(drill 0.254)
		(layers "F.Cu" "B.Cu")
		(net "M_A_BG<1>")
	)
	(segment
		(start 247.39981 -20.224242)
		(end 247.39981 -21.488146)
		(width 0.1651)
		(layer "B.Cu")
		(net "M_A_BG<1>")
	)
	(segment
		(start 247.400318 -20.224242)
		(end 247.39981 -20.224242)
		(width 0.1651)
		(layer "B.Cu")
		(net "M_A_BG<1>")
	)
	(segment
		(start 251.611384 -33.771078)
		(end 251.611384 -50.931826)
		(width 0.14224)
		(layer "In11.Cu")
		(net "M_A_BG<1>")
	)
	(segment
		(start 247.65 -29.809694)
		(end 251.611384 -33.771078)
		(width 0.14224)
		(layer "In11.Cu")
		(net "M_A_BG<1>")
	)
	(segment
		(start 247.62079 -23.42261)
		(end 247.62079 -24.55799)
		(width 0.14224)
		(layer "In11.Cu")
		(net "M_A_BG<1>")
	)
	(segment
		(start 247.73509 -19.069558)
		(end 247.73509 -20.877022)
		(width 0.14224)
		(layer "In11.Cu")
		(net "M_A_BG<1>")
	)
	(segment
		(start 247.62079 -24.55799)
		(end 248.6533 -25.5905)
		(width 0.14224)
		(layer "In11.Cu")
		(net "M_A_BG<1>")
	)
	(segment
		(start 247.39981 -18.734278)
		(end 247.73509 -19.069558)
		(width 0.14224)
		(layer "In11.Cu")
		(net "M_A_BG<1>")
	)
	(segment
		(start 247.8786 -23.1648)
		(end 247.62079 -23.42261)
		(width 0.14224)
		(layer "In11.Cu")
		(net "M_A_BG<1>")
	)
	(segment
		(start 247.65 -27.8765)
		(end 247.65 -29.809694)
		(width 0.14224)
		(layer "In11.Cu")
		(net "M_A_BG<1>")
	)
	(segment
		(start 251.611384 -51.1302)
		(end 251.923804 -52.12334)
		(width 0.0889)
		(layer "In11.Cu")
		(net "M_A_BG<1>")
	)
	(segment
		(start 247.73509 -20.877022)
		(end 247.39981 -21.212302)
		(width 0.14224)
		(layer "In11.Cu")
		(net "M_A_BG<1>")
	)
	(segment
		(start 247.39981 -21.212302)
		(end 247.39981 -21.488146)
		(width 0.14224)
		(layer "In11.Cu")
		(net "M_A_BG<1>")
	)
	(segment
		(start 248.6533 -25.5905)
		(end 248.6533 -26.8732)
		(width 0.14224)
		(layer "In11.Cu")
		(net "M_A_BG<1>")
	)
	(segment
		(start 248.6533 -26.8732)
		(end 247.65 -27.8765)
		(width 0.14224)
		(layer "In11.Cu")
		(net "M_A_BG<1>")
	)
	(segment
		(start 247.39981 -22.12721)
		(end 247.8786 -22.606)
		(width 0.14224)
		(layer "In11.Cu")
		(net "M_A_BG<1>")
	)
	(segment
		(start 247.8786 -22.606)
		(end 247.8786 -23.1648)
		(width 0.14224)
		(layer "In11.Cu")
		(net "M_A_BG<1>")
	)
	(segment
		(start 247.39981 -21.488146)
		(end 247.39981 -22.12721)
		(width 0.14224)
		(layer "In11.Cu")
		(net "M_A_BG<1>")
	)
	(segment
		(start 251.611384 -50.931826)
		(end 251.611384 -51.1302)
		(width 0.0889)
		(layer "In11.Cu")
		(net "M_A_BG<1>")
	)
	(segment
		(start 253.8222 -49.8856)
		(end 254.0254 -49.6824)
		(width 0.0889)
		(layer "F.Cu")
		(net "M_A_BG<0>")
	)
	(segment
		(start 253.39675 -33.640014)
		(end 249.7582 -30.001464)
		(width 0.1651)
		(layer "F.Cu")
		(net "M_A_BG<0>")
	)
	(segment
		(start 249.183906 -25.06345)
		(end 248.92381 -25.323546)
		(width 0.1651)
		(layer "F.Cu")
		(net "M_A_BG<0>")
	)
	(segment
		(start 249.651012 -25.530556)
		(end 249.651012 -25.350724)
		(width 0.1651)
		(layer "F.Cu")
		(net "M_A_BG<0>")
	)
	(segment
		(start 247.996964 -24.381968)
		(end 247.65635 -24.381968)
		(width 0.1651)
		(layer "F.Cu")
		(net "M_A_BG<0>")
	)
	(segment
		(start 249.363738 -25.06345)
		(end 249.183906 -25.06345)
		(width 0.1651)
		(layer "F.Cu")
		(net "M_A_BG<0>")
	)
	(segment
		(start 248.92381 -25.323546)
		(end 248.69013 -25.323546)
		(width 0.1651)
		(layer "F.Cu")
		(net "M_A_BG<0>")
	)
	(segment
		(start 253.8222 -50.179986)
		(end 253.8222 -49.8856)
		(width 0.0889)
		(layer "F.Cu")
		(net "M_A_BG<0>")
	)
	(segment
		(start 253.39675 -47.530004)
		(end 253.39675 -47.32274)
		(width 0.0889)
		(layer "F.Cu")
		(net "M_A_BG<0>")
	)
	(segment
		(start 249.7582 -30.001464)
		(end 249.7582 -28.03906)
		(width 0.1651)
		(layer "F.Cu")
		(net "M_A_BG<0>")
	)
	(segment
		(start 248.39168 -24.167084)
		(end 248.211848 -24.167084)
		(width 0.1651)
		(layer "F.Cu")
		(net "M_A_BG<0>")
	)
	(segment
		(start 249.651012 -25.350724)
		(end 249.363738 -25.06345)
		(width 0.1651)
		(layer "F.Cu")
		(net "M_A_BG<0>")
	)
	(segment
		(start 248.211848 -24.167084)
		(end 247.996964 -24.381968)
		(width 0.1651)
		(layer "F.Cu")
		(net "M_A_BG<0>")
	)
	(segment
		(start 247.39981 -24.125428)
		(end 247.39981 -22.850856)
		(width 0.1651)
		(layer "F.Cu")
		(net "M_A_BG<0>")
	)
	(segment
		(start 247.65635 -24.381968)
		(end 247.39981 -24.125428)
		(width 0.1651)
		(layer "F.Cu")
		(net "M_A_BG<0>")
	)
	(segment
		(start 247.400318 -15.423642)
		(end 247.39981 -15.423642)
		(width 0.1651)
		(layer "F.Cu")
		(net "M_A_BG<0>")
	)
	(segment
		(start 254.0254 -49.6824)
		(end 254.0254 -48.158654)
		(width 0.0889)
		(layer "F.Cu")
		(net "M_A_BG<0>")
	)
	(segment
		(start 248.456704 -24.85644)
		(end 248.678954 -24.63419)
		(width 0.1651)
		(layer "F.Cu")
		(net "M_A_BG<0>")
	)
	(segment
		(start 253.882398 -50.37074)
		(end 253.865634 -50.342038)
		(width 0.0889)
		(layer "F.Cu")
		(net "M_A_BG<0>")
	)
	(segment
		(start 248.69013 -25.323546)
		(end 248.456704 -25.09012)
		(width 0.1651)
		(layer "F.Cu")
		(net "M_A_BG<0>")
	)
	(segment
		(start 253.39675 -47.32274)
		(end 253.39675 -33.640014)
		(width 0.1651)
		(layer "F.Cu")
		(net "M_A_BG<0>")
	)
	(segment
		(start 248.456704 -25.09012)
		(end 248.456704 -24.85644)
		(width 0.1651)
		(layer "F.Cu")
		(net "M_A_BG<0>")
	)
	(segment
		(start 254.212344 -51.132486)
		(end 253.882398 -50.37074)
		(width 0.0889)
		(layer "F.Cu")
		(net "M_A_BG<0>")
	)
	(segment
		(start 249.7582 -28.03906)
		(end 249.7582 -26.391616)
		(width 0.1651)
		(layer "F.Cu")
		(net "M_A_BG<0>")
	)
	(segment
		(start 247.39981 -15.423642)
		(end 247.39981 -16.716756)
		(width 0.1651)
		(layer "F.Cu")
		(net "M_A_BG<0>")
	)
	(segment
		(start 249.390916 -25.790652)
		(end 249.651012 -25.530556)
		(width 0.1651)
		(layer "F.Cu")
		(net "M_A_BG<0>")
	)
	(segment
		(start 249.7582 -26.391616)
		(end 249.390916 -26.024332)
		(width 0.1651)
		(layer "F.Cu")
		(net "M_A_BG<0>")
	)
	(segment
		(start 248.678954 -24.454358)
		(end 248.39168 -24.167084)
		(width 0.1651)
		(layer "F.Cu")
		(net "M_A_BG<0>")
	)
	(segment
		(start 249.390916 -26.024332)
		(end 249.390916 -25.790652)
		(width 0.1651)
		(layer "F.Cu")
		(net "M_A_BG<0>")
	)
	(segment
		(start 248.678954 -24.63419)
		(end 248.678954 -24.454358)
		(width 0.1651)
		(layer "F.Cu")
		(net "M_A_BG<0>")
	)
	(segment
		(start 254.0254 -48.158654)
		(end 253.39675 -47.530004)
		(width 0.0889)
		(layer "F.Cu")
		(net "M_A_BG<0>")
	)
	(via
		(at 247.39981 -22.850856)
		(size 0.508)
		(drill 0.254)
		(layers "F.Cu" "B.Cu")
		(net "M_A_BG<0>")
	)
	(via
		(at 249.7582 -28.03906)
		(size 0.508)
		(drill 0.254)
		(layers "F.Cu" "B.Cu")
		(net "M_A_BG<0>")
	)
	(via
		(at 247.39981 -16.716756)
		(size 0.4572)
		(drill 0.2032)
		(layers "F.Cu" "B.Cu")
		(net "M_A_BG<0>")
	)
	(arc
		(start 253.865634 -50.342038)
		(mid 253.83328 -50.263866)
		(end 253.8222 -50.179986)
		(width 0.0889)
		(layer "F.Cu")
		(net "M_A_BG<0>")
	)
	(segment
		(start 247.39981 -24.824182)
		(end 247.39981 -22.850856)
		(width 0.1651)
		(layer "B.Cu")
		(net "M_A_BG<0>")
	)
	(segment
		(start 247.400318 -24.824182)
		(end 247.39981 -24.824182)
		(width 0.1651)
		(layer "B.Cu")
		(net "M_A_BG<0>")
	)
	(segment
		(start 247.39981 -17.06245)
		(end 247.39981 -16.716756)
		(width 0.14224)
		(layer "In9.Cu")
		(net "M_A_BG<0>")
	)
	(segment
		(start 247.23725 -20.761198)
		(end 247.36425 -20.634198)
		(width 0.14224)
		(layer "In9.Cu")
		(net "M_A_BG<0>")
	)
	(segment
		(start 246.8118 -19.359626)
		(end 246.990362 -19.181064)
		(width 0.14224)
		(layer "In9.Cu")
		(net "M_A_BG<0>")
	)
	(segment
		(start 246.990362 -19.181064)
		(end 246.990362 -18.499328)
		(width 0.14224)
		(layer "In9.Cu")
		(net "M_A_BG<0>")
	)
	(segment
		(start 247.292114 -18.197576)
		(end 247.739154 -18.197576)
		(width 0.14224)
		(layer "In9.Cu")
		(net "M_A_BG<0>")
	)
	(segment
		(start 247.911874 -18.024856)
		(end 247.911874 -17.574514)
		(width 0.14224)
		(layer "In9.Cu")
		(net "M_A_BG<0>")
	)
	(segment
		(start 246.8118 -20.916138)
		(end 246.96674 -20.761198)
		(width 0.14224)
		(layer "In9.Cu")
		(net "M_A_BG<0>")
	)
	(segment
		(start 246.990362 -18.499328)
		(end 247.292114 -18.197576)
		(width 0.14224)
		(layer "In9.Cu")
		(net "M_A_BG<0>")
	)
	(segment
		(start 247.739154 -18.197576)
		(end 247.911874 -18.024856)
		(width 0.14224)
		(layer "In9.Cu")
		(net "M_A_BG<0>")
	)
	(segment
		(start 247.39981 -22.25421)
		(end 246.8118 -21.6662)
		(width 0.14224)
		(layer "In9.Cu")
		(net "M_A_BG<0>")
	)
	(segment
		(start 246.96674 -20.761198)
		(end 247.23725 -20.761198)
		(width 0.14224)
		(layer "In9.Cu")
		(net "M_A_BG<0>")
	)
	(segment
		(start 247.911874 -17.574514)
		(end 247.39981 -17.06245)
		(width 0.14224)
		(layer "In9.Cu")
		(net "M_A_BG<0>")
	)
	(segment
		(start 247.36425 -20.225258)
		(end 247.23725 -20.098258)
		(width 0.14224)
		(layer "In9.Cu")
		(net "M_A_BG<0>")
	)
	(segment
		(start 247.39981 -22.850856)
		(end 247.39981 -22.25421)
		(width 0.14224)
		(layer "In9.Cu")
		(net "M_A_BG<0>")
	)
	(segment
		(start 247.36425 -20.634198)
		(end 247.36425 -20.225258)
		(width 0.14224)
		(layer "In9.Cu")
		(net "M_A_BG<0>")
	)
	(segment
		(start 246.8118 -21.6662)
		(end 246.8118 -20.916138)
		(width 0.14224)
		(layer "In9.Cu")
		(net "M_A_BG<0>")
	)
	(segment
		(start 247.23725 -20.098258)
		(end 246.96674 -20.098258)
		(width 0.14224)
		(layer "In9.Cu")
		(net "M_A_BG<0>")
	)
	(segment
		(start 246.8118 -19.943318)
		(end 246.8118 -19.359626)
		(width 0.14224)
		(layer "In9.Cu")
		(net "M_A_BG<0>")
	)
	(segment
		(start 246.96674 -20.098258)
		(end 246.8118 -19.943318)
		(width 0.14224)
		(layer "In9.Cu")
		(net "M_A_BG<0>")
	)
	(segment
		(start 266.949936 -18.734532)
		(end 266.95019 -18.734278)
		(width 0.1651)
		(layer "F.Cu")
		(net "M_A_BA<1>")
	)
	(segment
		(start 266.949936 -20.023582)
		(end 266.949936 -18.734532)
		(width 0.1651)
		(layer "F.Cu")
		(net "M_A_BA<1>")
	)
	(segment
		(start 266.950444 -20.023582)
		(end 266.949936 -20.023582)
		(width 0.1651)
		(layer "F.Cu")
		(net "M_A_BA<1>")
	)
	(segment
		(start 260.22173 -52.618386)
		(end 259.65023 -52.618386)
		(width 0.1016)
		(layer "F.Cu")
		(net "M_A_BA<1>")
	)
	(via
		(at 259.65023 -52.618386)
		(size 0.508)
		(drill 0.254)
		(layers "F.Cu" "B.Cu")
		(net "M_A_BA<1>")
	)
	(via
		(at 266.95019 -18.734278)
		(size 0.4572)
		(drill 0.2032)
		(layers "F.Cu" "B.Cu")
		(net "M_A_BA<1>")
	)
	(via
		(at 266.949682 -22.197568)
		(size 0.508)
		(drill 0.254)
		(layers "F.Cu" "B.Cu")
		(net "M_A_BA<1>")
	)
	(segment
		(start 266.949936 -20.224242)
		(end 266.949936 -22.197314)
		(width 0.1651)
		(layer "B.Cu")
		(net "M_A_BA<1>")
	)
	(segment
		(start 266.949936 -22.197314)
		(end 266.949682 -22.197568)
		(width 0.1651)
		(layer "B.Cu")
		(net "M_A_BA<1>")
	)
	(segment
		(start 266.950444 -20.224242)
		(end 266.949936 -20.224242)
		(width 0.1651)
		(layer "B.Cu")
		(net "M_A_BA<1>")
	)
	(segment
		(start 264.844276 -26.36393)
		(end 264.633456 -26.15311)
		(width 0.14224)
		(layer "In11.Cu")
		(net "M_A_BA<1>")
	)
	(segment
		(start 266.6746 -23.1394)
		(end 266.6746 -22.47265)
		(width 0.14224)
		(layer "In11.Cu")
		(net "M_A_BA<1>")
	)
	(segment
		(start 265.5062 -24.3078)
		(end 266.6746 -23.1394)
		(width 0.14224)
		(layer "In11.Cu")
		(net "M_A_BA<1>")
	)
	(segment
		(start 261.499604 -49.823878)
		(end 261.499604 -48.929036)
		(width 0.0889)
		(layer "In11.Cu")
		(net "M_A_BA<1>")
	)
	(segment
		(start 261.347204 -48.776636)
		(end 261.347204 -48.570642)
		(width 0.0889)
		(layer "In11.Cu")
		(net "M_A_BA<1>")
	)
	(segment
		(start 264.829036 -25.55113)
		(end 265.303 -25.55113)
		(width 0.14224)
		(layer "In11.Cu")
		(net "M_A_BA<1>")
	)
	(segment
		(start 261.347204 -48.570642)
		(end 261.347204 -31.057596)
		(width 0.14224)
		(layer "In11.Cu")
		(net "M_A_BA<1>")
	)
	(segment
		(start 266.949682 -18.734786)
		(end 266.95019 -18.734278)
		(width 0.14224)
		(layer "In11.Cu")
		(net "M_A_BA<1>")
	)
	(segment
		(start 266.6746 -22.47265)
		(end 266.949682 -22.197568)
		(width 0.14224)
		(layer "In11.Cu")
		(net "M_A_BA<1>")
	)
	(segment
		(start 265.5062 -25.34793)
		(end 265.5062 -24.3078)
		(width 0.14224)
		(layer "In11.Cu")
		(net "M_A_BA<1>")
	)
	(segment
		(start 265.279886 -26.36393)
		(end 264.844276 -26.36393)
		(width 0.14224)
		(layer "In11.Cu")
		(net "M_A_BA<1>")
	)
	(segment
		(start 259.65023 -52.618386)
		(end 259.65023 -51.673252)
		(width 0.0889)
		(layer "In11.Cu")
		(net "M_A_BA<1>")
	)
	(segment
		(start 259.65023 -51.673252)
		(end 260.106668 -51.217068)
		(width 0.0889)
		(layer "In11.Cu")
		(net "M_A_BA<1>")
	)
	(segment
		(start 261.347204 -31.057596)
		(end 265.49858 -26.90622)
		(width 0.14224)
		(layer "In11.Cu")
		(net "M_A_BA<1>")
	)
	(segment
		(start 265.49858 -26.582624)
		(end 265.279886 -26.36393)
		(width 0.14224)
		(layer "In11.Cu")
		(net "M_A_BA<1>")
	)
	(segment
		(start 261.499604 -48.929036)
		(end 261.347204 -48.776636)
		(width 0.0889)
		(layer "In11.Cu")
		(net "M_A_BA<1>")
	)
	(segment
		(start 264.633456 -26.15311)
		(end 264.633456 -25.74671)
		(width 0.14224)
		(layer "In11.Cu")
		(net "M_A_BA<1>")
	)
	(segment
		(start 265.49858 -26.90622)
		(end 265.49858 -26.582624)
		(width 0.14224)
		(layer "In11.Cu")
		(net "M_A_BA<1>")
	)
	(segment
		(start 264.633456 -25.74671)
		(end 264.829036 -25.55113)
		(width 0.14224)
		(layer "In11.Cu")
		(net "M_A_BA<1>")
	)
	(segment
		(start 265.303 -25.55113)
		(end 265.5062 -25.34793)
		(width 0.14224)
		(layer "In11.Cu")
		(net "M_A_BA<1>")
	)
	(segment
		(start 260.106668 -51.217068)
		(end 261.499604 -49.823878)
		(width 0.0889)
		(layer "In11.Cu")
		(net "M_A_BA<1>")
	)
	(segment
		(start 266.949682 -22.197568)
		(end 266.949682 -18.734786)
		(width 0.14224)
		(layer "In11.Cu")
		(net "M_A_BA<1>")
	)
	(segment
		(start 262.972804 -48.100996)
		(end 261.93877 -49.13503)
		(width 0.0889)
		(layer "F.Cu")
		(net "M_A_BA<0>")
	)
	(segment
		(start 267.79982 -22.850856)
		(end 267.620496 -22.671532)
		(width 0.1651)
		(layer "F.Cu")
		(net "M_A_BA<0>")
	)
	(segment
		(start 266.986004 -22.671532)
		(end 266.438888 -23.218648)
		(width 0.1651)
		(layer "F.Cu")
		(net "M_A_BA<0>")
	)
	(segment
		(start 267.79982 -16.718534)
		(end 267.800074 -16.718788)
		(width 0.1651)
		(layer "F.Cu")
		(net "M_A_BA<0>")
	)
	(segment
		(start 267.800328 -15.423642)
		(end 267.79982 -15.423642)
		(width 0.1651)
		(layer "F.Cu")
		(net "M_A_BA<0>")
	)
	(segment
		(start 267.620496 -22.671532)
		(end 266.986004 -22.671532)
		(width 0.1651)
		(layer "F.Cu")
		(net "M_A_BA<0>")
	)
	(segment
		(start 264.8712 -25.8826)
		(end 264.607548 -26.146252)
		(width 0.1651)
		(layer "F.Cu")
		(net "M_A_BA<0>")
	)
	(segment
		(start 264.201148 -26.146252)
		(end 262.63219 -27.71521)
		(width 0.1651)
		(layer "F.Cu")
		(net "M_A_BA<0>")
	)
	(segment
		(start 266.438888 -23.908512)
		(end 264.8712 -25.4762)
		(width 0.1651)
		(layer "F.Cu")
		(net "M_A_BA<0>")
	)
	(segment
		(start 262.63219 -27.71521)
		(end 262.63219 -29.255974)
		(width 0.1651)
		(layer "F.Cu")
		(net "M_A_BA<0>")
	)
	(segment
		(start 264.8712 -25.4762)
		(end 264.8712 -25.8826)
		(width 0.1651)
		(layer "F.Cu")
		(net "M_A_BA<0>")
	)
	(segment
		(start 264.607548 -26.146252)
		(end 264.201148 -26.146252)
		(width 0.1651)
		(layer "F.Cu")
		(net "M_A_BA<0>")
	)
	(segment
		(start 262.63219 -29.255974)
		(end 262.63219 -45.843444)
		(width 0.1651)
		(layer "F.Cu")
		(net "M_A_BA<0>")
	)
	(segment
		(start 262.972804 -46.466506)
		(end 262.972804 -48.100996)
		(width 0.0889)
		(layer "F.Cu")
		(net "M_A_BA<0>")
	)
	(segment
		(start 266.438888 -23.218648)
		(end 266.438888 -23.908512)
		(width 0.1651)
		(layer "F.Cu")
		(net "M_A_BA<0>")
	)
	(segment
		(start 262.63219 -46.125892)
		(end 262.972804 -46.466506)
		(width 0.0889)
		(layer "F.Cu")
		(net "M_A_BA<0>")
	)
	(segment
		(start 262.63219 -45.843444)
		(end 262.63219 -46.125892)
		(width 0.0889)
		(layer "F.Cu")
		(net "M_A_BA<0>")
	)
	(segment
		(start 267.79982 -15.423642)
		(end 267.79982 -16.718534)
		(width 0.1651)
		(layer "F.Cu")
		(net "M_A_BA<0>")
	)
	(segment
		(start 261.93877 -49.13503)
		(end 261.93877 -50.63744)
		(width 0.0889)
		(layer "F.Cu")
		(net "M_A_BA<0>")
	)
	(via
		(at 267.79982 -22.850856)
		(size 0.508)
		(drill 0.254)
		(layers "F.Cu" "B.Cu")
		(net "M_A_BA<0>")
	)
	(via
		(at 262.63219 -29.255974)
		(size 0.508)
		(drill 0.254)
		(layers "F.Cu" "B.Cu")
		(net "M_A_BA<0>")
	)
	(via
		(at 267.800074 -16.718788)
		(size 0.4572)
		(drill 0.2032)
		(layers "F.Cu" "B.Cu")
		(net "M_A_BA<0>")
	)
	(segment
		(start 267.79982 -24.824182)
		(end 267.79982 -22.850856)
		(width 0.1651)
		(layer "B.Cu")
		(net "M_A_BA<0>")
	)
	(segment
		(start 267.800328 -24.824182)
		(end 267.79982 -24.824182)
		(width 0.1651)
		(layer "B.Cu")
		(net "M_A_BA<0>")
	)
	(segment
		(start 267.390118 -17.128744)
		(end 267.800074 -16.718788)
		(width 0.14224)
		(layer "In9.Cu")
		(net "M_A_BA<0>")
	)
	(segment
		(start 267.541502 -21.974302)
		(end 267.276326 -21.709126)
		(width 0.14224)
		(layer "In9.Cu")
		(net "M_A_BA<0>")
	)
	(segment
		(start 267.276326 -21.709126)
		(end 267.276326 -20.712938)
		(width 0.14224)
		(layer "In9.Cu")
		(net "M_A_BA<0>")
	)
	(segment
		(start 267.541502 -22.592538)
		(end 267.541502 -21.974302)
		(width 0.14224)
		(layer "In9.Cu")
		(net "M_A_BA<0>")
	)
	(segment
		(start 267.390118 -20.599146)
		(end 267.390118 -17.128744)
		(width 0.14224)
		(layer "In9.Cu")
		(net "M_A_BA<0>")
	)
	(segment
		(start 267.276326 -20.712938)
		(end 267.390118 -20.599146)
		(width 0.14224)
		(layer "In9.Cu")
		(net "M_A_BA<0>")
	)
	(segment
		(start 267.79982 -22.850856)
		(end 267.541502 -22.592538)
		(width 0.14224)
		(layer "In9.Cu")
		(net "M_A_BA<0>")
	)
	(segment
		(start 250.2916 -24.851868)
		(end 250.2916 -26.433526)
		(width 0.1651)
		(layer "F.Cu")
		(net "M_A_ALERT_N")
	)
	(segment
		(start 250.2916 -29.782262)
		(end 253.90094 -33.391602)
		(width 0.1651)
		(layer "F.Cu")
		(net "M_A_ALERT_N")
	)
	(segment
		(start 254.3302 -47.9806)
		(end 254.3302 -50.02403)
		(width 0.0889)
		(layer "F.Cu")
		(net "M_A_ALERT_N")
	)
	(segment
		(start 254.3302 -50.02403)
		(end 254.212344 -50.141886)
		(width 0.0889)
		(layer "F.Cu")
		(net "M_A_ALERT_N")
	)
	(segment
		(start 250.2916 -26.433526)
		(end 250.2916 -29.782262)
		(width 0.1651)
		(layer "F.Cu")
		(net "M_A_ALERT_N")
	)
	(segment
		(start 248.249948 -22.197568)
		(end 248.249948 -22.810216)
		(width 0.1651)
		(layer "F.Cu")
		(net "M_A_ALERT_N")
	)
	(segment
		(start 253.90094 -33.391602)
		(end 253.90094 -47.33544)
		(width 0.1651)
		(layer "F.Cu")
		(net "M_A_ALERT_N")
	)
	(segment
		(start 248.250456 -20.023582)
		(end 248.249948 -20.023582)
		(width 0.1651)
		(layer "F.Cu")
		(net "M_A_ALERT_N")
	)
	(segment
		(start 248.249948 -22.810216)
		(end 250.2916 -24.851868)
		(width 0.1651)
		(layer "F.Cu")
		(net "M_A_ALERT_N")
	)
	(segment
		(start 253.90094 -47.33544)
		(end 253.90094 -47.55134)
		(width 0.0889)
		(layer "F.Cu")
		(net "M_A_ALERT_N")
	)
	(segment
		(start 248.249948 -20.023582)
		(end 248.249948 -18.734278)
		(width 0.1651)
		(layer "F.Cu")
		(net "M_A_ALERT_N")
	)
	(segment
		(start 253.90094 -47.55134)
		(end 254.3302 -47.9806)
		(width 0.0889)
		(layer "F.Cu")
		(net "M_A_ALERT_N")
	)
	(via
		(at 248.249948 -18.734278)
		(size 0.4572)
		(drill 0.2032)
		(layers "F.Cu" "B.Cu")
		(net "M_A_ALERT_N")
	)
	(via
		(at 248.249948 -22.197568)
		(size 0.508)
		(drill 0.254)
		(layers "F.Cu" "B.Cu")
		(net "M_A_ALERT_N")
	)
	(via
		(at 250.2916 -26.433526)
		(size 0.508)
		(drill 0.254)
		(layers "F.Cu" "B.Cu")
		(net "M_A_ALERT_N")
	)
	(segment
		(start 248.250456 -20.224242)
		(end 248.249948 -20.224242)
		(width 0.1651)
		(layer "B.Cu")
		(net "M_A_ALERT_N")
	)
	(segment
		(start 248.249948 -20.224242)
		(end 248.249948 -22.197568)
		(width 0.1651)
		(layer "B.Cu")
		(net "M_A_ALERT_N")
	)
	(segment
		(start 248.031 -18.953226)
		(end 248.249948 -18.734278)
		(width 0.14224)
		(layer "In9.Cu")
		(net "M_A_ALERT_N")
	)
	(segment
		(start 248.031 -21.97862)
		(end 248.031 -18.953226)
		(width 0.14224)
		(layer "In9.Cu")
		(net "M_A_ALERT_N")
	)
	(segment
		(start 248.249948 -22.197568)
		(end 248.031 -21.97862)
		(width 0.14224)
		(layer "In9.Cu")
		(net "M_A_ALERT_N")
	)
	(segment
		(start 254.146304 -51.645566)
		(end 253.753874 -51.253136)
		(width 0.0889)
		(layer "F.Cu")
		(net "M_A_ACT_N")
	)
	(segment
		(start 255.07061 -53.60924)
		(end 255.070102 -53.608224)
		(width 0.0889)
		(layer "F.Cu")
		(net "M_A_ACT_N")
	)
	(segment
		(start 252.89256 -33.888426)
		(end 249.2248 -30.220666)
		(width 0.1651)
		(layer "F.Cu")
		(net "M_A_ACT_N")
	)
	(segment
		(start 247.2436 -25.146)
		(end 246.549926 -24.452326)
		(width 0.1651)
		(layer "F.Cu")
		(net "M_A_ACT_N")
	)
	(segment
		(start 249.2248 -29.247592)
		(end 249.2248 -26.5938)
		(width 0.1651)
		(layer "F.Cu")
		(net "M_A_ACT_N")
	)
	(segment
		(start 253.621286 -50.1396)
		(end 253.621286 -48.282098)
		(width 0.0889)
		(layer "F.Cu")
		(net "M_A_ACT_N")
	)
	(segment
		(start 246.549926 -15.423642)
		(end 246.549926 -16.716756)
		(width 0.1651)
		(layer "F.Cu")
		(net "M_A_ACT_N")
	)
	(segment
		(start 246.550434 -15.423642)
		(end 246.549926 -15.423642)
		(width 0.1651)
		(layer "F.Cu")
		(net "M_A_ACT_N")
	)
	(segment
		(start 253.753874 -51.253136)
		(end 253.753874 -50.646584)
		(width 0.0889)
		(layer "F.Cu")
		(net "M_A_ACT_N")
	)
	(segment
		(start 252.89256 -47.40275)
		(end 252.89256 -33.888426)
		(width 0.1651)
		(layer "F.Cu")
		(net "M_A_ACT_N")
	)
	(segment
		(start 249.2248 -26.5938)
		(end 247.777 -25.146)
		(width 0.1651)
		(layer "F.Cu")
		(net "M_A_ACT_N")
	)
	(segment
		(start 247.777 -25.146)
		(end 247.2436 -25.146)
		(width 0.1651)
		(layer "F.Cu")
		(net "M_A_ACT_N")
	)
	(segment
		(start 255.070102 -53.608224)
		(end 254.729488 -53.025294)
		(width 0.0889)
		(layer "F.Cu")
		(net "M_A_ACT_N")
	)
	(segment
		(start 249.2248 -30.220666)
		(end 249.2248 -29.247592)
		(width 0.1651)
		(layer "F.Cu")
		(net "M_A_ACT_N")
	)
	(segment
		(start 246.549926 -24.452326)
		(end 246.549926 -23.560278)
		(width 0.1651)
		(layer "F.Cu")
		(net "M_A_ACT_N")
	)
	(segment
		(start 252.89256 -47.553372)
		(end 252.89256 -47.40275)
		(width 0.0889)
		(layer "F.Cu")
		(net "M_A_ACT_N")
	)
	(segment
		(start 254.349504 -51.74742)
		(end 254.146304 -51.645566)
		(width 0.0889)
		(layer "F.Cu")
		(net "M_A_ACT_N")
	)
	(segment
		(start 254.729488 -53.025294)
		(end 254.612394 -52.12842)
		(width 0.0889)
		(layer "F.Cu")
		(net "M_A_ACT_N")
	)
	(segment
		(start 253.621286 -48.282098)
		(end 252.89256 -47.553372)
		(width 0.0889)
		(layer "F.Cu")
		(net "M_A_ACT_N")
	)
	(via
		(at 246.549926 -16.716756)
		(size 0.4572)
		(drill 0.2032)
		(layers "F.Cu" "B.Cu")
		(net "M_A_ACT_N")
	)
	(via
		(at 249.2248 -29.247592)
		(size 0.508)
		(drill 0.254)
		(layers "F.Cu" "B.Cu")
		(net "M_A_ACT_N")
	)
	(via
		(at 246.549926 -23.560278)
		(size 0.508)
		(drill 0.254)
		(layers "F.Cu" "B.Cu")
		(net "M_A_ACT_N")
	)
	(arc
		(start 253.700534 -50.437288)
		(mid 253.641172 -50.293698)
		(end 253.621286 -50.1396)
		(width 0.0889)
		(layer "F.Cu")
		(net "M_A_ACT_N")
	)
	(arc
		(start 253.753874 -50.646584)
		(mid 253.741568 -50.538279)
		(end 253.700534 -50.437288)
		(width 0.0889)
		(layer "F.Cu")
		(net "M_A_ACT_N")
	)
	(arc
		(start 254.612394 -52.12842)
		(mid 254.541612 -51.896078)
		(end 254.349504 -51.74742)
		(width 0.0889)
		(layer "F.Cu")
		(net "M_A_ACT_N")
	)
	(segment
		(start 246.549926 -24.824182)
		(end 246.549926 -23.560278)
		(width 0.1651)
		(layer "B.Cu")
		(net "M_A_ACT_N")
	)
	(segment
		(start 246.550434 -24.824182)
		(end 246.549926 -24.824182)
		(width 0.1651)
		(layer "B.Cu")
		(net "M_A_ACT_N")
	)
	(segment
		(start 246.549926 -23.560278)
		(end 246.549926 -22.902926)
		(width 0.14224)
		(layer "In9.Cu")
		(net "M_A_ACT_N")
	)
	(segment
		(start 246.0244 -21.995892)
		(end 246.2022 -21.818092)
		(width 0.14224)
		(layer "In9.Cu")
		(net "M_A_ACT_N")
	)
	(segment
		(start 246.2022 -21.818092)
		(end 246.2022 -19.40179)
		(width 0.14224)
		(layer "In9.Cu")
		(net "M_A_ACT_N")
	)
	(segment
		(start 246.109744 -17.156938)
		(end 246.549926 -16.716756)
		(width 0.14224)
		(layer "In9.Cu")
		(net "M_A_ACT_N")
	)
	(segment
		(start 246.2022 -19.40179)
		(end 246.109744 -19.309334)
		(width 0.14224)
		(layer "In9.Cu")
		(net "M_A_ACT_N")
	)
	(segment
		(start 246.549926 -22.902926)
		(end 246.0244 -22.3774)
		(width 0.14224)
		(layer "In9.Cu")
		(net "M_A_ACT_N")
	)
	(segment
		(start 246.109744 -19.309334)
		(end 246.109744 -17.156938)
		(width 0.14224)
		(layer "In9.Cu")
		(net "M_A_ACT_N")
	)
	(segment
		(start 246.0244 -22.3774)
		(end 246.0244 -21.995892)
		(width 0.14224)
		(layer "In9.Cu")
		(net "M_A_ACT_N")
	)
	(segment
		(start 243.15039 -15.423642)
		(end 243.149882 -15.423642)
		(width 0.10795)
		(layer "F.Cu")
		(net "M_ABC_RST_N")
	)
	(segment
		(start 243.149882 3.778758)
		(end 243.149882 1.946148)
		(width 0.10795)
		(layer "F.Cu")
		(net "M_ABC_RST_N")
	)
	(segment
		(start 243.149882 -15.423642)
		(end 243.149882 -17.157446)
		(width 0.10795)
		(layer "F.Cu")
		(net "M_ABC_RST_N")
	)
	(segment
		(start 243.15039 -5.822442)
		(end 243.149882 -5.822442)
		(width 0.10795)
		(layer "F.Cu")
		(net "M_ABC_RST_N")
	)
	(segment
		(start 251.636784 -57.57164)
		(end 251.065284 -58.56224)
		(width 0.1016)
		(layer "F.Cu")
		(net "M_ABC_RST_N")
	)
	(segment
		(start 243.15039 3.778758)
		(end 243.149882 3.778758)
		(width 0.10795)
		(layer "F.Cu")
		(net "M_ABC_RST_N")
	)
	(segment
		(start 243.149882 -17.157446)
		(end 243.214144 -17.221708)
		(width 0.10795)
		(layer "F.Cu")
		(net "M_ABC_RST_N")
	)
	(segment
		(start 243.149882 1.946148)
		(end 243.27231 1.82372)
		(width 0.10795)
		(layer "F.Cu")
		(net "M_ABC_RST_N")
	)
	(segment
		(start 243.149882 -5.822442)
		(end 243.149882 -7.115556)
		(width 0.10795)
		(layer "F.Cu")
		(net "M_ABC_RST_N")
	)
	(via
		(at 243.214144 -17.221708)
		(size 0.4572)
		(drill 0.2032)
		(layers "F.Cu" "B.Cu")
		(net "M_ABC_RST_N")
	)
	(via
		(at 243.149882 -23.534878)
		(size 0.508)
		(drill 0.254)
		(layers "F.Cu" "B.Cu")
		(net "M_ABC_RST_N")
	)
	(via
		(at 243.149882 -13.933678)
		(size 0.4572)
		(drill 0.2032)
		(layers "F.Cu" "B.Cu")
		(net "M_ABC_RST_N")
	)
	(via
		(at 251.065284 -58.56224)
		(size 0.508)
		(drill 0.254)
		(layers "F.Cu" "B.Cu")
		(net "M_ABC_RST_N")
	)
	(via
		(at 243.149882 -4.332478)
		(size 0.4572)
		(drill 0.2032)
		(layers "F.Cu" "B.Cu")
		(net "M_ABC_RST_N")
	)
	(via
		(at 243.27231 1.82372)
		(size 0.508)
		(drill 0.254)
		(layers "F.Cu" "B.Cu")
		(net "M_ABC_RST_N")
	)
	(via
		(at 243.149882 -7.115556)
		(size 0.4572)
		(drill 0.2032)
		(layers "F.Cu" "B.Cu")
		(net "M_ABC_RST_N")
	)
	(segment
		(start 243.15039 -15.222982)
		(end 243.149882 -15.222982)
		(width 0.10795)
		(layer "B.Cu")
		(net "M_ABC_RST_N")
	)
	(segment
		(start 243.149882 -5.621782)
		(end 243.149882 -4.332478)
		(width 0.10795)
		(layer "B.Cu")
		(net "M_ABC_RST_N")
	)
	(segment
		(start 243.149882 -24.824182)
		(end 243.149882 -23.534878)
		(width 0.10795)
		(layer "B.Cu")
		(net "M_ABC_RST_N")
	)
	(segment
		(start 243.15039 -5.621782)
		(end 243.149882 -5.621782)
		(width 0.10795)
		(layer "B.Cu")
		(net "M_ABC_RST_N")
	)
	(segment
		(start 243.149882 -15.222982)
		(end 243.149882 -13.933678)
		(width 0.10795)
		(layer "B.Cu")
		(net "M_ABC_RST_N")
	)
	(segment
		(start 243.15039 -24.824182)
		(end 243.149882 -24.824182)
		(width 0.10795)
		(layer "B.Cu")
		(net "M_ABC_RST_N")
	)
	(segment
		(start 243.149882 -23.534878)
		(end 243.149882 -24.1554)
		(width 0.089408)
		(layer "In4.Cu")
		(net "M_ABC_RST_N")
	)
	(segment
		(start 249.7836 -56.2356)
		(end 250.19 -56.642)
		(width 0.089408)
		(layer "In4.Cu")
		(net "M_ABC_RST_N")
	)
	(segment
		(start 243.149882 -24.1554)
		(end 244.221 -25.226518)
		(width 0.089408)
		(layer "In4.Cu")
		(net "M_ABC_RST_N")
	)
	(segment
		(start 244.221 -27.693112)
		(end 250.6218 -34.093912)
		(width 0.089408)
		(layer "In4.Cu")
		(net "M_ABC_RST_N")
	)
	(segment
		(start 250.19 -56.642)
		(end 250.444 -56.642)
		(width 0.089408)
		(layer "In4.Cu")
		(net "M_ABC_RST_N")
	)
	(segment
		(start 250.4059 -50.8889)
		(end 250.317 -50.9778)
		(width 0.089408)
		(layer "In4.Cu")
		(net "M_ABC_RST_N")
	)
	(segment
		(start 249.7836 -54.9402)
		(end 249.7836 -56.2356)
		(width 0.089408)
		(layer "In4.Cu")
		(net "M_ABC_RST_N")
	)
	(segment
		(start 250.6218 -34.093912)
		(end 250.6218 -46.101254)
		(width 0.089408)
		(layer "In4.Cu")
		(net "M_ABC_RST_N")
	)
	(segment
		(start 250.317 -54.4068)
		(end 249.7836 -54.9402)
		(width 0.089408)
		(layer "In4.Cu")
		(net "M_ABC_RST_N")
	)
	(segment
		(start 250.444 -56.642)
		(end 251.065284 -57.263284)
		(width 0.089408)
		(layer "In4.Cu")
		(net "M_ABC_RST_N")
	)
	(segment
		(start 250.6218 -46.101254)
		(end 250.317 -46.406054)
		(width 0.089408)
		(layer "In4.Cu")
		(net "M_ABC_RST_N")
	)
	(segment
		(start 250.317 -50.9778)
		(end 250.317 -54.4068)
		(width 0.089408)
		(layer "In4.Cu")
		(net "M_ABC_RST_N")
	)
	(segment
		(start 244.221 -25.226518)
		(end 244.221 -27.693112)
		(width 0.089408)
		(layer "In4.Cu")
		(net "M_ABC_RST_N")
	)
	(segment
		(start 251.065284 -57.263284)
		(end 251.065284 -58.56224)
		(width 0.089408)
		(layer "In4.Cu")
		(net "M_ABC_RST_N")
	)
	(segment
		(start 250.317 -46.406054)
		(end 250.317 -50.1904)
		(width 0.089408)
		(layer "In4.Cu")
		(net "M_ABC_RST_N")
	)
	(segment
		(start 250.317 -50.1904)
		(end 250.4059 -50.2793)
		(width 0.089408)
		(layer "In4.Cu")
		(net "M_ABC_RST_N")
	)
	(segment
		(start 250.4059 -50.2793)
		(end 250.4059 -50.8889)
		(width 0.089408)
		(layer "In4.Cu")
		(net "M_ABC_RST_N")
	)
	(segment
		(start 243.149882 -13.933678)
		(end 243.5606 -14.344396)
		(width 0.089408)
		(layer "In11.Cu")
		(net "M_ABC_RST_N")
	)
	(segment
		(start 243.586 -4.768596)
		(end 243.586 -6.679438)
		(width 0.089408)
		(layer "In11.Cu")
		(net "M_ABC_RST_N")
	)
	(segment
		(start 243.6876 -22.479)
		(end 243.5098 -22.6568)
		(width 0.089408)
		(layer "In11.Cu")
		(net "M_ABC_RST_N")
	)
	(segment
		(start 243.27231 0.94869)
		(end 243.5606 0.6604)
		(width 0.089408)
		(layer "In11.Cu")
		(net "M_ABC_RST_N")
	)
	(segment
		(start 243.149882 -4.332478)
		(end 243.586 -4.768596)
		(width 0.089408)
		(layer "In11.Cu")
		(net "M_ABC_RST_N")
	)
	(segment
		(start 243.5606 -14.344396)
		(end 243.5606 -16.875252)
		(width 0.089408)
		(layer "In11.Cu")
		(net "M_ABC_RST_N")
	)
	(segment
		(start 243.586 -6.679438)
		(end 243.149882 -7.115556)
		(width 0.089408)
		(layer "In11.Cu")
		(net "M_ABC_RST_N")
	)
	(segment
		(start 243.713 -12.573)
		(end 243.713 -13.37056)
		(width 0.089408)
		(layer "In11.Cu")
		(net "M_ABC_RST_N")
	)
	(segment
		(start 243.5098 -23.17496)
		(end 243.149882 -23.534878)
		(width 0.089408)
		(layer "In11.Cu")
		(net "M_ABC_RST_N")
	)
	(segment
		(start 243.5606 -12.4206)
		(end 243.713 -12.573)
		(width 0.089408)
		(layer "In11.Cu")
		(net "M_ABC_RST_N")
	)
	(segment
		(start 243.6622 -2.667)
		(end 243.6622 -3.6576)
		(width 0.089408)
		(layer "In11.Cu")
		(net "M_ABC_RST_N")
	)
	(segment
		(start 243.654834 -17.221708)
		(end 243.775992 -17.342866)
		(width 0.089408)
		(layer "In11.Cu")
		(net "M_ABC_RST_N")
	)
	(segment
		(start 243.775992 -17.342866)
		(end 243.775992 -19.926808)
		(width 0.089408)
		(layer "In11.Cu")
		(net "M_ABC_RST_N")
	)
	(segment
		(start 243.5606 -21.8186)
		(end 243.6876 -21.9456)
		(width 0.089408)
		(layer "In11.Cu")
		(net "M_ABC_RST_N")
	)
	(segment
		(start 243.5098 -22.6568)
		(end 243.5098 -23.17496)
		(width 0.089408)
		(layer "In11.Cu")
		(net "M_ABC_RST_N")
	)
	(segment
		(start 243.149882 -7.115556)
		(end 243.713 -7.678674)
		(width 0.089408)
		(layer "In11.Cu")
		(net "M_ABC_RST_N")
	)
	(segment
		(start 243.5606 -20.1422)
		(end 243.5606 -21.8186)
		(width 0.089408)
		(layer "In11.Cu")
		(net "M_ABC_RST_N")
	)
	(segment
		(start 243.713 -7.678674)
		(end 243.713 -8.711946)
		(width 0.089408)
		(layer "In11.Cu")
		(net "M_ABC_RST_N")
	)
	(segment
		(start 243.5606 -16.875252)
		(end 243.214144 -17.221708)
		(width 0.089408)
		(layer "In11.Cu")
		(net "M_ABC_RST_N")
	)
	(segment
		(start 243.27231 1.82372)
		(end 243.27231 0.94869)
		(width 0.089408)
		(layer "In11.Cu")
		(net "M_ABC_RST_N")
	)
	(segment
		(start 243.214144 -17.221708)
		(end 243.654834 -17.221708)
		(width 0.089408)
		(layer "In11.Cu")
		(net "M_ABC_RST_N")
	)
	(segment
		(start 243.5606 0.6604)
		(end 243.5606 -2.5654)
		(width 0.089408)
		(layer "In11.Cu")
		(net "M_ABC_RST_N")
	)
	(segment
		(start 243.149882 -4.169918)
		(end 243.149882 -4.332478)
		(width 0.089408)
		(layer "In11.Cu")
		(net "M_ABC_RST_N")
	)
	(segment
		(start 243.5606 -2.5654)
		(end 243.6622 -2.667)
		(width 0.089408)
		(layer "In11.Cu")
		(net "M_ABC_RST_N")
	)
	(segment
		(start 243.775992 -19.926808)
		(end 243.5606 -20.1422)
		(width 0.089408)
		(layer "In11.Cu")
		(net "M_ABC_RST_N")
	)
	(segment
		(start 243.6876 -21.9456)
		(end 243.6876 -22.479)
		(width 0.089408)
		(layer "In11.Cu")
		(net "M_ABC_RST_N")
	)
	(segment
		(start 243.713 -13.37056)
		(end 243.149882 -13.933678)
		(width 0.089408)
		(layer "In11.Cu")
		(net "M_ABC_RST_N")
	)
	(segment
		(start 243.713 -8.711946)
		(end 243.5606 -8.864346)
		(width 0.089408)
		(layer "In11.Cu")
		(net "M_ABC_RST_N")
	)
	(segment
		(start 243.5606 -8.864346)
		(end 243.5606 -12.4206)
		(width 0.089408)
		(layer "In11.Cu")
		(net "M_ABC_RST_N")
	)
	(segment
		(start 243.6622 -3.6576)
		(end 243.149882 -4.169918)
		(width 0.089408)
		(layer "In11.Cu")
		(net "M_ABC_RST_N")
	)
	(segment
		(start 251.636784 -63.51524)
		(end 251.065284 -63.51524)
		(width 0.254)
		(layer "F.Cu")
		(net "M_A_CPU_VREF")
	)
	(segment
		(start 192.786 -23.396194)
		(end 191.897 -23.396194)
		(width 0.4064)
		(layer "F.Cu")
		(net "M_A_CPU_VREF")
	)
	(segment
		(start 191.897 -23.396194)
		(end 191.2874 -23.396194)
		(width 0.4064)
		(layer "F.Cu")
		(net "M_A_CPU_VREF")
	)
	(via
		(at 191.2874 -23.396194)
		(size 0.508)
		(drill 0.254)
		(layers "F.Cu" "B.Cu")
		(net "M_A_CPU_VREF")
	)
	(via
		(at 202.777598 -46.028864)
		(size 0.508)
		(drill 0.254)
		(layers "F.Cu" "B.Cu")
		(net "M_A_CPU_VREF")
	)
	(via
		(at 251.065284 -63.51524)
		(size 0.508)
		(drill 0.254)
		(layers "F.Cu" "B.Cu")
		(net "M_A_CPU_VREF")
	)
	(segment
		(start 191.2366 -29.7434)
		(end 191.7446 -29.2354)
		(width 0.254)
		(layer "In2.Cu")
		(net "M_A_CPU_VREF")
	)
	(segment
		(start 191.2366 -23.446994)
		(end 191.2874 -23.396194)
		(width 0.254)
		(layer "In2.Cu")
		(net "M_A_CPU_VREF")
	)
	(segment
		(start 191.2366 -34.8742)
		(end 191.2366 -29.7434)
		(width 0.254)
		(layer "In2.Cu")
		(net "M_A_CPU_VREF")
	)
	(segment
		(start 202.777598 -46.028864)
		(end 202.391264 -46.028864)
		(width 0.254)
		(layer "In2.Cu")
		(net "M_A_CPU_VREF")
	)
	(segment
		(start 202.391264 -46.028864)
		(end 191.2366 -34.8742)
		(width 0.254)
		(layer "In2.Cu")
		(net "M_A_CPU_VREF")
	)
	(segment
		(start 191.7446 -29.2354)
		(end 191.7446 -25.146)
		(width 0.254)
		(layer "In2.Cu")
		(net "M_A_CPU_VREF")
	)
	(segment
		(start 191.2366 -24.638)
		(end 191.2366 -23.446994)
		(width 0.254)
		(layer "In2.Cu")
		(net "M_A_CPU_VREF")
	)
	(segment
		(start 191.7446 -25.146)
		(end 191.2366 -24.638)
		(width 0.254)
		(layer "In2.Cu")
		(net "M_A_CPU_VREF")
	)
	(segment
		(start 249.517154 -62.994286)
		(end 249.15368 -62.994286)
		(width 0.2286)
		(layer "In7.Cu")
		(net "M_A_CPU_VREF")
	)
	(segment
		(start 247.487948 -61.064394)
		(end 247.161558 -60.738004)
		(width 0.2286)
		(layer "In7.Cu")
		(net "M_A_CPU_VREF")
	)
	(segment
		(start 246.057166 -59.031632)
		(end 245.7196 -59.031632)
		(width 0.2286)
		(layer "In7.Cu")
		(net "M_A_CPU_VREF")
	)
	(segment
		(start 207.483202 -50.823622)
		(end 207.102202 -51.204622)
		(width 0.254)
		(layer "In7.Cu")
		(net "M_A_CPU_VREF")
	)
	(segment
		(start 237.134654 -55.069486)
		(end 236.690408 -54.62524)
		(width 0.2286)
		(layer "In7.Cu")
		(net "M_A_CPU_VREF")
	)
	(segment
		(start 209.0801 -50.823622)
		(end 207.483202 -50.823622)
		(width 0.254)
		(layer "In7.Cu")
		(net "M_A_CPU_VREF")
	)
	(segment
		(start 248.878598 -62.330076)
		(end 248.95937 -62.24905)
		(width 0.2286)
		(layer "In7.Cu")
		(net "M_A_CPU_VREF")
	)
	(segment
		(start 235.806742 -55.069486)
		(end 235.417614 -55.069486)
		(width 0.2286)
		(layer "In7.Cu")
		(net "M_A_CPU_VREF")
	)
	(segment
		(start 248.320814 -61.55944)
		(end 247.825768 -61.064394)
		(width 0.2286)
		(layer "In7.Cu")
		(net "M_A_CPU_VREF")
	)
	(segment
		(start 237.523782 -55.069486)
		(end 237.134654 -55.069486)
		(width 0.2286)
		(layer "In7.Cu")
		(net "M_A_CPU_VREF")
	)
	(segment
		(start 233.9086 -54.62524)
		(end 232.573322 -54.62524)
		(width 0.254)
		(layer "In7.Cu")
		(net "M_A_CPU_VREF")
	)
	(segment
		(start 241.816382 -55.61584)
		(end 241.478562 -55.61584)
		(width 0.2286)
		(layer "In7.Cu")
		(net "M_A_CPU_VREF")
	)
	(segment
		(start 210.147154 -51.890676)
		(end 209.0801 -50.823622)
		(width 0.254)
		(layer "In7.Cu")
		(net "M_A_CPU_VREF")
	)
	(segment
		(start 250.038108 -63.51524)
		(end 249.517154 -62.994286)
		(width 0.2286)
		(layer "In7.Cu")
		(net "M_A_CPU_VREF")
	)
	(segment
		(start 205.777846 -51.204622)
		(end 202.454002 -47.880778)
		(width 0.254)
		(layer "In7.Cu")
		(net "M_A_CPU_VREF")
	)
	(segment
		(start 240.124488 -54.62524)
		(end 239.685068 -54.62524)
		(width 0.2286)
		(layer "In7.Cu")
		(net "M_A_CPU_VREF")
	)
	(segment
		(start 248.95937 -61.834522)
		(end 248.684288 -61.55944)
		(width 0.2286)
		(layer "In7.Cu")
		(net "M_A_CPU_VREF")
	)
	(segment
		(start 237.968028 -54.62524)
		(end 237.523782 -55.069486)
		(width 0.2286)
		(layer "In7.Cu")
		(net "M_A_CPU_VREF")
	)
	(segment
		(start 248.95937 -62.24905)
		(end 248.95937 -61.834522)
		(width 0.2286)
		(layer "In7.Cu")
		(net "M_A_CPU_VREF")
	)
	(segment
		(start 239.240822 -55.069486)
		(end 238.851694 -55.069486)
		(width 0.2286)
		(layer "In7.Cu")
		(net "M_A_CPU_VREF")
	)
	(segment
		(start 238.407448 -54.62524)
		(end 237.968028 -54.62524)
		(width 0.2286)
		(layer "In7.Cu")
		(net "M_A_CPU_VREF")
	)
	(segment
		(start 243.14404 -56.555132)
		(end 242.700302 -56.111394)
		(width 0.2286)
		(layer "In7.Cu")
		(net "M_A_CPU_VREF")
	)
	(segment
		(start 240.568734 -55.069486)
		(end 240.124488 -54.62524)
		(width 0.2286)
		(layer "In7.Cu")
		(net "M_A_CPU_VREF")
	)
	(segment
		(start 235.417614 -55.069486)
		(end 234.973368 -54.62524)
		(width 0.2286)
		(layer "In7.Cu")
		(net "M_A_CPU_VREF")
	)
	(segment
		(start 246.967248 -59.57824)
		(end 246.603774 -59.57824)
		(width 0.2286)
		(layer "In7.Cu")
		(net "M_A_CPU_VREF")
	)
	(segment
		(start 239.685068 -54.62524)
		(end 239.240822 -55.069486)
		(width 0.2286)
		(layer "In7.Cu")
		(net "M_A_CPU_VREF")
	)
	(segment
		(start 244.886988 -58.58764)
		(end 244.391688 -58.09234)
		(width 0.2286)
		(layer "In7.Cu")
		(net "M_A_CPU_VREF")
	)
	(segment
		(start 242.311936 -56.111394)
		(end 241.816382 -55.61584)
		(width 0.2286)
		(layer "In7.Cu")
		(net "M_A_CPU_VREF")
	)
	(segment
		(start 243.80825 -57.296304)
		(end 243.80825 -56.881522)
		(width 0.2286)
		(layer "In7.Cu")
		(net "M_A_CPU_VREF")
	)
	(segment
		(start 243.727478 -57.377076)
		(end 243.80825 -57.296304)
		(width 0.2286)
		(layer "In7.Cu")
		(net "M_A_CPU_VREF")
	)
	(segment
		(start 207.102202 -51.204622)
		(end 205.777846 -51.204622)
		(width 0.254)
		(layer "In7.Cu")
		(net "M_A_CPU_VREF")
	)
	(segment
		(start 251.065284 -63.51524)
		(end 250.038108 -63.51524)
		(width 0.2286)
		(layer "In7.Cu")
		(net "M_A_CPU_VREF")
	)
	(segment
		(start 248.878598 -62.719204)
		(end 248.878598 -62.330076)
		(width 0.2286)
		(layer "In7.Cu")
		(net "M_A_CPU_VREF")
	)
	(segment
		(start 241.478562 -55.61584)
		(end 240.932208 -55.069486)
		(width 0.2286)
		(layer "In7.Cu")
		(net "M_A_CPU_VREF")
	)
	(segment
		(start 247.24233 -59.853322)
		(end 246.967248 -59.57824)
		(width 0.2286)
		(layer "In7.Cu")
		(net "M_A_CPU_VREF")
	)
	(segment
		(start 245.275608 -58.58764)
		(end 244.886988 -58.58764)
		(width 0.2286)
		(layer "In7.Cu")
		(net "M_A_CPU_VREF")
	)
	(segment
		(start 248.684288 -61.55944)
		(end 248.320814 -61.55944)
		(width 0.2286)
		(layer "In7.Cu")
		(net "M_A_CPU_VREF")
	)
	(segment
		(start 247.161558 -60.738004)
		(end 247.161558 -60.323222)
		(width 0.2286)
		(layer "In7.Cu")
		(net "M_A_CPU_VREF")
	)
	(segment
		(start 243.727478 -57.766204)
		(end 243.727478 -57.377076)
		(width 0.2286)
		(layer "In7.Cu")
		(net "M_A_CPU_VREF")
	)
	(segment
		(start 234.973368 -54.62524)
		(end 233.9086 -54.62524)
		(width 0.2286)
		(layer "In7.Cu")
		(net "M_A_CPU_VREF")
	)
	(segment
		(start 245.7196 -59.031632)
		(end 245.275608 -58.58764)
		(width 0.2286)
		(layer "In7.Cu")
		(net "M_A_CPU_VREF")
	)
	(segment
		(start 247.825768 -61.064394)
		(end 247.487948 -61.064394)
		(width 0.2286)
		(layer "In7.Cu")
		(net "M_A_CPU_VREF")
	)
	(segment
		(start 242.700302 -56.111394)
		(end 242.311936 -56.111394)
		(width 0.2286)
		(layer "In7.Cu")
		(net "M_A_CPU_VREF")
	)
	(segment
		(start 202.454002 -46.35246)
		(end 202.777598 -46.028864)
		(width 0.254)
		(layer "In7.Cu")
		(net "M_A_CPU_VREF")
	)
	(segment
		(start 244.053614 -58.09234)
		(end 243.727478 -57.766204)
		(width 0.2286)
		(layer "In7.Cu")
		(net "M_A_CPU_VREF")
	)
	(segment
		(start 240.932208 -55.069486)
		(end 240.568734 -55.069486)
		(width 0.2286)
		(layer "In7.Cu")
		(net "M_A_CPU_VREF")
	)
	(segment
		(start 247.24233 -60.24245)
		(end 247.24233 -59.853322)
		(width 0.2286)
		(layer "In7.Cu")
		(net "M_A_CPU_VREF")
	)
	(segment
		(start 202.454002 -47.880778)
		(end 202.454002 -46.35246)
		(width 0.254)
		(layer "In7.Cu")
		(net "M_A_CPU_VREF")
	)
	(segment
		(start 238.851694 -55.069486)
		(end 238.407448 -54.62524)
		(width 0.2286)
		(layer "In7.Cu")
		(net "M_A_CPU_VREF")
	)
	(segment
		(start 229.838758 -51.890676)
		(end 210.147154 -51.890676)
		(width 0.254)
		(layer "In7.Cu")
		(net "M_A_CPU_VREF")
	)
	(segment
		(start 232.573322 -54.62524)
		(end 229.838758 -51.890676)
		(width 0.254)
		(layer "In7.Cu")
		(net "M_A_CPU_VREF")
	)
	(segment
		(start 244.391688 -58.09234)
		(end 244.053614 -58.09234)
		(width 0.2286)
		(layer "In7.Cu")
		(net "M_A_CPU_VREF")
	)
	(segment
		(start 243.80825 -56.881522)
		(end 243.48186 -56.555132)
		(width 0.2286)
		(layer "In7.Cu")
		(net "M_A_CPU_VREF")
	)
	(segment
		(start 247.161558 -60.323222)
		(end 247.24233 -60.24245)
		(width 0.2286)
		(layer "In7.Cu")
		(net "M_A_CPU_VREF")
	)
	(segment
		(start 236.250988 -54.62524)
		(end 235.806742 -55.069486)
		(width 0.2286)
		(layer "In7.Cu")
		(net "M_A_CPU_VREF")
	)
	(segment
		(start 243.48186 -56.555132)
		(end 243.14404 -56.555132)
		(width 0.2286)
		(layer "In7.Cu")
		(net "M_A_CPU_VREF")
	)
	(segment
		(start 246.603774 -59.57824)
		(end 246.057166 -59.031632)
		(width 0.2286)
		(layer "In7.Cu")
		(net "M_A_CPU_VREF")
	)
	(segment
		(start 236.690408 -54.62524)
		(end 236.250988 -54.62524)
		(width 0.2286)
		(layer "In7.Cu")
		(net "M_A_CPU_VREF")
	)
	(segment
		(start 249.15368 -62.994286)
		(end 248.878598 -62.719204)
		(width 0.2286)
		(layer "In7.Cu")
		(net "M_A_CPU_VREF")
	)
	(segment
		(start 382.98501 -92.691966)
		(end 382.98501 -93.544898)
		(width 0.0889)
		(layer "F.Cu")
		(net "LPC_LAD3_IO3")
	)
	(segment
		(start 381.28956 -88.74506)
		(end 381.28956 -89.93378)
		(width 0.10795)
		(layer "F.Cu")
		(net "LPC_LAD3_IO3")
	)
	(segment
		(start 381.28956 -89.93378)
		(end 381.9398 -90.58402)
		(width 0.10795)
		(layer "F.Cu")
		(net "LPC_LAD3_IO3")
	)
	(segment
		(start 381.9398 -91.1479)
		(end 382.406144 -91.614244)
		(width 0.10795)
		(layer "F.Cu")
		(net "LPC_LAD3_IO3")
	)
	(segment
		(start 381.9398 -90.58402)
		(end 381.9398 -91.1479)
		(width 0.10795)
		(layer "F.Cu")
		(net "LPC_LAD3_IO3")
	)
	(segment
		(start 382.6256 -91.8337)
		(end 382.6256 -92.332556)
		(width 0.0889)
		(layer "F.Cu")
		(net "LPC_LAD3_IO3")
	)
	(segment
		(start 382.406144 -91.614244)
		(end 382.6256 -91.8337)
		(width 0.0889)
		(layer "F.Cu")
		(net "LPC_LAD3_IO3")
	)
	(segment
		(start 382.6256 -92.332556)
		(end 382.98501 -92.691966)
		(width 0.0889)
		(layer "F.Cu")
		(net "LPC_LAD3_IO3")
	)
	(segment
		(start 380.746 -88.2015)
		(end 381.28956 -88.74506)
		(width 0.10795)
		(layer "F.Cu")
		(net "LPC_LAD3_IO3")
	)
	(segment
		(start 25.010618 -98.461068)
		(end 24.530812 -98.461068)
		(width 0.127)
		(layer "F.Cu")
		(net "ISENSE_PVSA_CPU1_IMON")
	)
	(segment
		(start 29.56941 -95.068136)
		(end 27.2796 -95.068136)
		(width 0.127)
		(layer "F.Cu")
		(net "ISENSE_PVSA_CPU1_IMON")
	)
	(segment
		(start 23.468076 -98.451416)
		(end 22.921722 -97.905062)
		(width 0.127)
		(layer "F.Cu")
		(net "ISENSE_PVSA_CPU1_IMON")
	)
	(segment
		(start 30.63113 -96.129856)
		(end 29.56941 -95.068136)
		(width 0.127)
		(layer "F.Cu")
		(net "ISENSE_PVSA_CPU1_IMON")
	)
	(segment
		(start 24.518112 -98.448368)
		(end 24.515064 -98.451416)
		(width 0.127)
		(layer "F.Cu")
		(net "ISENSE_PVSA_CPU1_IMON")
	)
	(segment
		(start 21.231098 -95.801434)
		(end 21.231098 -95.3516)
		(width 0.127)
		(layer "F.Cu")
		(net "ISENSE_PVSA_CPU1_IMON")
	)
	(segment
		(start 26.543 -95.804736)
		(end 26.543 -96.928686)
		(width 0.127)
		(layer "F.Cu")
		(net "ISENSE_PVSA_CPU1_IMON")
	)
	(segment
		(start 23.697184 -98.451416)
		(end 23.468076 -98.451416)
		(width 0.127)
		(layer "F.Cu")
		(net "ISENSE_PVSA_CPU1_IMON")
	)
	(segment
		(start 26.543 -96.928686)
		(end 25.010618 -98.461068)
		(width 0.127)
		(layer "F.Cu")
		(net "ISENSE_PVSA_CPU1_IMON")
	)
	(segment
		(start 22.921722 -96.878648)
		(end 22.59711 -96.554036)
		(width 0.127)
		(layer "F.Cu")
		(net "ISENSE_PVSA_CPU1_IMON")
	)
	(segment
		(start 22.921722 -97.905062)
		(end 22.921722 -96.878648)
		(width 0.127)
		(layer "F.Cu")
		(net "ISENSE_PVSA_CPU1_IMON")
	)
	(segment
		(start 31.02991 -96.129856)
		(end 30.63113 -96.129856)
		(width 0.127)
		(layer "F.Cu")
		(net "ISENSE_PVSA_CPU1_IMON")
	)
	(segment
		(start 26.850848 -95.496888)
		(end 26.543 -95.804736)
		(width 0.127)
		(layer "F.Cu")
		(net "ISENSE_PVSA_CPU1_IMON")
	)
	(segment
		(start 24.530812 -98.461068)
		(end 24.518112 -98.448368)
		(width 0.127)
		(layer "F.Cu")
		(net "ISENSE_PVSA_CPU1_IMON")
	)
	(segment
		(start 22.59711 -96.554036)
		(end 21.9837 -96.554036)
		(width 0.127)
		(layer "F.Cu")
		(net "ISENSE_PVSA_CPU1_IMON")
	)
	(segment
		(start 27.2796 -95.068136)
		(end 26.850848 -95.496888)
		(width 0.127)
		(layer "F.Cu")
		(net "ISENSE_PVSA_CPU1_IMON")
	)
	(segment
		(start 21.9837 -96.554036)
		(end 21.231098 -95.801434)
		(width 0.127)
		(layer "F.Cu")
		(net "ISENSE_PVSA_CPU1_IMON")
	)
	(segment
		(start 24.515064 -98.451416)
		(end 23.697184 -98.451416)
		(width 0.127)
		(layer "F.Cu")
		(net "ISENSE_PVSA_CPU1_IMON")
	)
	(via
		(at 26.850848 -95.496888)
		(size 0.508)
		(drill 0.254)
		(layers "F.Cu" "B.Cu")
		(net "ISENSE_PVSA_CPU1_IMON")
	)
	(segment
		(start 186.977274 -74.295)
		(end 187.3885 -74.295)
		(width 0.127)
		(layer "F.Cu")
		(net "ISENSE_PVSA_CPU0_IMON")
	)
	(segment
		(start 186.077098 -73.394824)
		(end 186.977274 -74.295)
		(width 0.127)
		(layer "F.Cu")
		(net "ISENSE_PVSA_CPU0_IMON")
	)
	(segment
		(start 187.3885 -75.057)
		(end 187.3885 -74.295)
		(width 0.127)
		(layer "F.Cu")
		(net "ISENSE_PVSA_CPU0_IMON")
	)
	(segment
		(start 195.262754 -95.933768)
		(end 194.989958 -95.933768)
		(width 0.127)
		(layer "F.Cu")
		(net "ISENSE_PVSA_CPU0_IMON")
	)
	(segment
		(start 194.749928 -95.693738)
		(end 194.089274 -95.693738)
		(width 0.127)
		(layer "F.Cu")
		(net "ISENSE_PVSA_CPU0_IMON")
	)
	(segment
		(start 196.017642 -96.129856)
		(end 195.458842 -96.129856)
		(width 0.127)
		(layer "F.Cu")
		(net "ISENSE_PVSA_CPU0_IMON")
	)
	(segment
		(start 194.989958 -95.933768)
		(end 194.749928 -95.693738)
		(width 0.127)
		(layer "F.Cu")
		(net "ISENSE_PVSA_CPU0_IMON")
	)
	(segment
		(start 187.3885 -75.919076)
		(end 187.3885 -75.057)
		(width 0.127)
		(layer "F.Cu")
		(net "ISENSE_PVSA_CPU0_IMON")
	)
	(segment
		(start 195.458842 -96.129856)
		(end 195.262754 -95.933768)
		(width 0.127)
		(layer "F.Cu")
		(net "ISENSE_PVSA_CPU0_IMON")
	)
	(segment
		(start 186.077098 -72.7456)
		(end 186.077098 -73.394824)
		(width 0.127)
		(layer "F.Cu")
		(net "ISENSE_PVSA_CPU0_IMON")
	)
	(via
		(at 187.3885 -75.919076)
		(size 0.508)
		(drill 0.254)
		(layers "F.Cu" "B.Cu")
		(net "ISENSE_PVSA_CPU0_IMON")
	)
	(via
		(at 194.089274 -95.693738)
		(size 0.508)
		(drill 0.254)
		(layers "F.Cu" "B.Cu")
		(net "ISENSE_PVSA_CPU0_IMON")
	)
	(segment
		(start 193.167 -95.050864)
		(end 193.444622 -95.328486)
		(width 0.127)
		(layer "In11.Cu")
		(net "ISENSE_PVSA_CPU0_IMON")
	)
	(segment
		(start 193.444622 -95.328486)
		(end 193.724022 -95.328486)
		(width 0.127)
		(layer "In11.Cu")
		(net "ISENSE_PVSA_CPU0_IMON")
	)
	(segment
		(start 193.724022 -95.328486)
		(end 194.089274 -95.693738)
		(width 0.127)
		(layer "In11.Cu")
		(net "ISENSE_PVSA_CPU0_IMON")
	)
	(segment
		(start 187.705238 -78.544674)
		(end 186.2582 -79.991712)
		(width 0.127)
		(layer "In11.Cu")
		(net "ISENSE_PVSA_CPU0_IMON")
	)
	(segment
		(start 187.4266 -84.17941)
		(end 187.4266 -89.08161)
		(width 0.127)
		(layer "In11.Cu")
		(net "ISENSE_PVSA_CPU0_IMON")
	)
	(segment
		(start 188.99759 -90.6526)
		(end 191.211454 -90.6526)
		(width 0.127)
		(layer "In11.Cu")
		(net "ISENSE_PVSA_CPU0_IMON")
	)
	(segment
		(start 186.2582 -83.01101)
		(end 187.4266 -84.17941)
		(width 0.127)
		(layer "In11.Cu")
		(net "ISENSE_PVSA_CPU0_IMON")
	)
	(segment
		(start 187.3885 -75.919076)
		(end 187.705238 -76.235814)
		(width 0.127)
		(layer "In11.Cu")
		(net "ISENSE_PVSA_CPU0_IMON")
	)
	(segment
		(start 193.167 -94.4372)
		(end 193.167 -95.050864)
		(width 0.127)
		(layer "In11.Cu")
		(net "ISENSE_PVSA_CPU0_IMON")
	)
	(segment
		(start 186.2582 -79.991712)
		(end 186.2582 -83.01101)
		(width 0.127)
		(layer "In11.Cu")
		(net "ISENSE_PVSA_CPU0_IMON")
	)
	(segment
		(start 192.1002 -91.541346)
		(end 192.1002 -93.3704)
		(width 0.127)
		(layer "In11.Cu")
		(net "ISENSE_PVSA_CPU0_IMON")
	)
	(segment
		(start 191.211454 -90.6526)
		(end 192.1002 -91.541346)
		(width 0.127)
		(layer "In11.Cu")
		(net "ISENSE_PVSA_CPU0_IMON")
	)
	(segment
		(start 192.1002 -93.3704)
		(end 193.167 -94.4372)
		(width 0.127)
		(layer "In11.Cu")
		(net "ISENSE_PVSA_CPU0_IMON")
	)
	(segment
		(start 187.4266 -89.08161)
		(end 188.99759 -90.6526)
		(width 0.127)
		(layer "In11.Cu")
		(net "ISENSE_PVSA_CPU0_IMON")
	)
	(segment
		(start 187.705238 -76.235814)
		(end 187.705238 -78.544674)
		(width 0.127)
		(layer "In11.Cu")
		(net "ISENSE_PVSA_CPU0_IMON")
	)
	(segment
		(start 23.574756 -94.212156)
		(end 24.05634 -94.212156)
		(width 0.127)
		(layer "F.Cu")
		(net "ISENSE_PVCCIN_CPU1_PH5_IMON")
	)
	(segment
		(start 25.864312 -94.258384)
		(end 25.787096 -94.3356)
		(width 0.127)
		(layer "F.Cu")
		(net "ISENSE_PVCCIN_CPU1_PH5_IMON")
	)
	(segment
		(start 25.787096 -94.3356)
		(end 25.04186 -94.3356)
		(width 0.127)
		(layer "F.Cu")
		(net "ISENSE_PVCCIN_CPU1_PH5_IMON")
	)
	(segment
		(start 30.353254 -87.884)
		(end 29.716984 -87.884)
		(width 0.127)
		(layer "F.Cu")
		(net "ISENSE_PVCCIN_CPU1_PH5_IMON")
	)
	(segment
		(start 31.02991 -88.001856)
		(end 30.47111 -88.001856)
		(width 0.127)
		(layer "F.Cu")
		(net "ISENSE_PVCCIN_CPU1_PH5_IMON")
	)
	(segment
		(start 22.900132 -93.055948)
		(end 23.3934 -93.549216)
		(width 0.127)
		(layer "F.Cu")
		(net "ISENSE_PVCCIN_CPU1_PH5_IMON")
	)
	(segment
		(start 25.04186 -94.3356)
		(end 24.609044 -94.3356)
		(width 0.127)
		(layer "F.Cu")
		(net "ISENSE_PVCCIN_CPU1_PH5_IMON")
	)
	(segment
		(start 24.609044 -94.3356)
		(end 24.4856 -94.212156)
		(width 0.127)
		(layer "F.Cu")
		(net "ISENSE_PVCCIN_CPU1_PH5_IMON")
	)
	(segment
		(start 29.716984 -87.884)
		(end 29.339032 -87.506048)
		(width 0.127)
		(layer "F.Cu")
		(net "ISENSE_PVCCIN_CPU1_PH5_IMON")
	)
	(segment
		(start 23.3934 -93.549216)
		(end 23.3934 -94.0308)
		(width 0.127)
		(layer "F.Cu")
		(net "ISENSE_PVCCIN_CPU1_PH5_IMON")
	)
	(segment
		(start 24.4856 -94.212156)
		(end 24.05634 -94.212156)
		(width 0.127)
		(layer "F.Cu")
		(net "ISENSE_PVCCIN_CPU1_PH5_IMON")
	)
	(segment
		(start 23.3934 -94.0308)
		(end 23.574756 -94.212156)
		(width 0.127)
		(layer "F.Cu")
		(net "ISENSE_PVCCIN_CPU1_PH5_IMON")
	)
	(segment
		(start 22.3266 -93.055948)
		(end 22.900132 -93.055948)
		(width 0.127)
		(layer "F.Cu")
		(net "ISENSE_PVCCIN_CPU1_PH5_IMON")
	)
	(segment
		(start 30.47111 -88.001856)
		(end 30.353254 -87.884)
		(width 0.127)
		(layer "F.Cu")
		(net "ISENSE_PVCCIN_CPU1_PH5_IMON")
	)
	(via
		(at 25.864312 -94.258384)
		(size 0.508)
		(drill 0.254)
		(layers "F.Cu" "B.Cu")
		(net "ISENSE_PVCCIN_CPU1_PH5_IMON")
	)
	(via
		(at 29.339032 -87.506048)
		(size 0.508)
		(drill 0.254)
		(layers "F.Cu" "B.Cu")
		(net "ISENSE_PVCCIN_CPU1_PH5_IMON")
	)
	(segment
		(start 28.8925 -90.1827)
		(end 28.8925 -87.490808)
		(width 0.127)
		(layer "In4.Cu")
		(net "ISENSE_PVCCIN_CPU1_PH5_IMON")
	)
	(segment
		(start 26.043636 -94.07906)
		(end 26.365454 -94.07906)
		(width 0.127)
		(layer "In4.Cu")
		(net "ISENSE_PVCCIN_CPU1_PH5_IMON")
	)
	(segment
		(start 28.321 -90.7542)
		(end 28.8925 -90.1827)
		(width 0.127)
		(layer "In4.Cu")
		(net "ISENSE_PVCCIN_CPU1_PH5_IMON")
	)
	(segment
		(start 28.8925 -87.490808)
		(end 29.0195 -87.363808)
		(width 0.127)
		(layer "In4.Cu")
		(net "ISENSE_PVCCIN_CPU1_PH5_IMON")
	)
	(segment
		(start 28.321 -92.123514)
		(end 28.321 -90.7542)
		(width 0.127)
		(layer "In4.Cu")
		(net "ISENSE_PVCCIN_CPU1_PH5_IMON")
	)
	(segment
		(start 25.864312 -94.258384)
		(end 26.043636 -94.07906)
		(width 0.127)
		(layer "In4.Cu")
		(net "ISENSE_PVCCIN_CPU1_PH5_IMON")
	)
	(segment
		(start 29.199586 -87.363808)
		(end 29.339032 -87.506048)
		(width 0.127)
		(layer "In4.Cu")
		(net "ISENSE_PVCCIN_CPU1_PH5_IMON")
	)
	(segment
		(start 29.0195 -87.363808)
		(end 29.199586 -87.363808)
		(width 0.127)
		(layer "In4.Cu")
		(net "ISENSE_PVCCIN_CPU1_PH5_IMON")
	)
	(segment
		(start 26.365454 -94.07906)
		(end 28.321 -92.123514)
		(width 0.127)
		(layer "In4.Cu")
		(net "ISENSE_PVCCIN_CPU1_PH5_IMON")
	)
	(segment
		(start 24.86914 -92.25788)
		(end 25.02408 -92.41282)
		(width 0.127)
		(layer "F.Cu")
		(net "ISENSE_PVCCIN_CPU1_PH4_IMON")
	)
	(segment
		(start 29.42844 -79.28864)
		(end 29.339032 -79.378048)
		(width 0.127)
		(layer "F.Cu")
		(net "ISENSE_PVCCIN_CPU1_PH4_IMON")
	)
	(segment
		(start 24.03602 -92.25788)
		(end 24.034242 -92.256102)
		(width 0.127)
		(layer "F.Cu")
		(net "ISENSE_PVCCIN_CPU1_PH4_IMON")
	)
	(segment
		(start 29.885894 -79.28864)
		(end 29.42844 -79.28864)
		(width 0.127)
		(layer "F.Cu")
		(net "ISENSE_PVCCIN_CPU1_PH4_IMON")
	)
	(segment
		(start 31.02991 -79.873856)
		(end 30.47111 -79.873856)
		(width 0.127)
		(layer "F.Cu")
		(net "ISENSE_PVCCIN_CPU1_PH4_IMON")
	)
	(segment
		(start 25.67686 -92.41282)
		(end 25.84958 -92.2401)
		(width 0.127)
		(layer "F.Cu")
		(net "ISENSE_PVCCIN_CPU1_PH4_IMON")
	)
	(segment
		(start 30.47111 -79.873856)
		(end 29.885894 -79.28864)
		(width 0.127)
		(layer "F.Cu")
		(net "ISENSE_PVCCIN_CPU1_PH4_IMON")
	)
	(segment
		(start 25.02408 -92.41282)
		(end 25.67686 -92.41282)
		(width 0.127)
		(layer "F.Cu")
		(net "ISENSE_PVCCIN_CPU1_PH4_IMON")
	)
	(segment
		(start 24.03602 -92.25788)
		(end 24.86914 -92.25788)
		(width 0.127)
		(layer "F.Cu")
		(net "ISENSE_PVCCIN_CPU1_PH4_IMON")
	)
	(segment
		(start 24.034242 -92.256102)
		(end 22.3266 -92.256102)
		(width 0.127)
		(layer "F.Cu")
		(net "ISENSE_PVCCIN_CPU1_PH4_IMON")
	)
	(via
		(at 29.339032 -79.378048)
		(size 0.508)
		(drill 0.254)
		(layers "F.Cu" "B.Cu")
		(net "ISENSE_PVCCIN_CPU1_PH4_IMON")
	)
	(via
		(at 25.84958 -92.2401)
		(size 0.508)
		(drill 0.254)
		(layers "F.Cu" "B.Cu")
		(net "ISENSE_PVCCIN_CPU1_PH4_IMON")
	)
	(segment
		(start 28.702 -79.377794)
		(end 28.933902 -79.145892)
		(width 0.127)
		(layer "In4.Cu")
		(net "ISENSE_PVCCIN_CPU1_PH4_IMON")
	)
	(segment
		(start 27.686 -87.26678)
		(end 28.28544 -86.66734)
		(width 0.127)
		(layer "In4.Cu")
		(net "ISENSE_PVCCIN_CPU1_PH4_IMON")
	)
	(segment
		(start 28.28544 -86.66734)
		(end 28.28544 -83.0707)
		(width 0.127)
		(layer "In4.Cu")
		(net "ISENSE_PVCCIN_CPU1_PH4_IMON")
	)
	(segment
		(start 29.106876 -79.145892)
		(end 29.339032 -79.378048)
		(width 0.127)
		(layer "In4.Cu")
		(net "ISENSE_PVCCIN_CPU1_PH4_IMON")
	)
	(segment
		(start 25.84958 -92.2401)
		(end 26.38044 -92.2401)
		(width 0.127)
		(layer "In4.Cu")
		(net "ISENSE_PVCCIN_CPU1_PH4_IMON")
	)
	(segment
		(start 28.933902 -79.145892)
		(end 29.106876 -79.145892)
		(width 0.127)
		(layer "In4.Cu")
		(net "ISENSE_PVCCIN_CPU1_PH4_IMON")
	)
	(segment
		(start 28.702 -82.65414)
		(end 28.702 -79.377794)
		(width 0.127)
		(layer "In4.Cu")
		(net "ISENSE_PVCCIN_CPU1_PH4_IMON")
	)
	(segment
		(start 28.28544 -83.0707)
		(end 28.702 -82.65414)
		(width 0.127)
		(layer "In4.Cu")
		(net "ISENSE_PVCCIN_CPU1_PH4_IMON")
	)
	(segment
		(start 27.686 -90.93454)
		(end 27.686 -87.26678)
		(width 0.127)
		(layer "In4.Cu")
		(net "ISENSE_PVCCIN_CPU1_PH4_IMON")
	)
	(segment
		(start 26.38044 -92.2401)
		(end 27.686 -90.93454)
		(width 0.127)
		(layer "In4.Cu")
		(net "ISENSE_PVCCIN_CPU1_PH4_IMON")
	)
	(segment
		(start 25.02916 -90.50274)
		(end 25.56002 -90.50274)
		(width 0.127)
		(layer "F.Cu")
		(net "ISENSE_PVCCIN_CPU1_PH3_IMON")
	)
	(segment
		(start 24.892 -90.6399)
		(end 25.02916 -90.50274)
		(width 0.127)
		(layer "F.Cu")
		(net "ISENSE_PVCCIN_CPU1_PH3_IMON")
	)
	(segment
		(start 22.993858 -91.456002)
		(end 22.3266 -91.456002)
		(width 0.127)
		(layer "F.Cu")
		(net "ISENSE_PVCCIN_CPU1_PH3_IMON")
	)
	(segment
		(start 24.03602 -90.6399)
		(end 24.892 -90.6399)
		(width 0.127)
		(layer "F.Cu")
		(net "ISENSE_PVCCIN_CPU1_PH3_IMON")
	)
	(segment
		(start 31.02991 -71.745856)
		(end 30.47111 -71.745856)
		(width 0.127)
		(layer "F.Cu")
		(net "ISENSE_PVCCIN_CPU1_PH3_IMON")
	)
	(segment
		(start 23.80996 -90.6399)
		(end 22.993858 -91.456002)
		(width 0.127)
		(layer "F.Cu")
		(net "ISENSE_PVCCIN_CPU1_PH3_IMON")
	)
	(segment
		(start 30.47111 -71.745856)
		(end 30.353254 -71.628)
		(width 0.127)
		(layer "F.Cu")
		(net "ISENSE_PVCCIN_CPU1_PH3_IMON")
	)
	(segment
		(start 25.56002 -90.50274)
		(end 25.94864 -90.11412)
		(width 0.127)
		(layer "F.Cu")
		(net "ISENSE_PVCCIN_CPU1_PH3_IMON")
	)
	(segment
		(start 24.03602 -90.6399)
		(end 23.80996 -90.6399)
		(width 0.127)
		(layer "F.Cu")
		(net "ISENSE_PVCCIN_CPU1_PH3_IMON")
	)
	(segment
		(start 29.716984 -71.628)
		(end 29.339032 -71.250048)
		(width 0.127)
		(layer "F.Cu")
		(net "ISENSE_PVCCIN_CPU1_PH3_IMON")
	)
	(segment
		(start 30.353254 -71.628)
		(end 29.716984 -71.628)
		(width 0.127)
		(layer "F.Cu")
		(net "ISENSE_PVCCIN_CPU1_PH3_IMON")
	)
	(via
		(at 29.339032 -71.250048)
		(size 0.508)
		(drill 0.254)
		(layers "F.Cu" "B.Cu")
		(net "ISENSE_PVCCIN_CPU1_PH3_IMON")
	)
	(via
		(at 25.94864 -90.11412)
		(size 0.508)
		(drill 0.254)
		(layers "F.Cu" "B.Cu")
		(net "ISENSE_PVCCIN_CPU1_PH3_IMON")
	)
	(segment
		(start 25.94864 -90.11412)
		(end 26.07564 -89.98712)
		(width 0.127)
		(layer "In4.Cu")
		(net "ISENSE_PVCCIN_CPU1_PH3_IMON")
	)
	(segment
		(start 28.69946 -73.4314)
		(end 28.69946 -71.078852)
		(width 0.127)
		(layer "In4.Cu")
		(net "ISENSE_PVCCIN_CPU1_PH3_IMON")
	)
	(segment
		(start 27.64028 -86.362286)
		(end 27.64028 -81.15046)
		(width 0.127)
		(layer "In4.Cu")
		(net "ISENSE_PVCCIN_CPU1_PH3_IMON")
	)
	(segment
		(start 26.07564 -89.98712)
		(end 26.766774 -89.98712)
		(width 0.127)
		(layer "In4.Cu")
		(net "ISENSE_PVCCIN_CPU1_PH3_IMON")
	)
	(segment
		(start 27.042364 -89.71153)
		(end 27.042364 -86.960202)
		(width 0.127)
		(layer "In4.Cu")
		(net "ISENSE_PVCCIN_CPU1_PH3_IMON")
	)
	(segment
		(start 27.305 -80.81518)
		(end 27.305 -74.82586)
		(width 0.127)
		(layer "In4.Cu")
		(net "ISENSE_PVCCIN_CPU1_PH3_IMON")
	)
	(segment
		(start 28.69946 -71.078852)
		(end 28.82646 -70.951852)
		(width 0.127)
		(layer "In4.Cu")
		(net "ISENSE_PVCCIN_CPU1_PH3_IMON")
	)
	(segment
		(start 27.305 -74.82586)
		(end 28.69946 -73.4314)
		(width 0.127)
		(layer "In4.Cu")
		(net "ISENSE_PVCCIN_CPU1_PH3_IMON")
	)
	(segment
		(start 27.042364 -86.960202)
		(end 27.64028 -86.362286)
		(width 0.127)
		(layer "In4.Cu")
		(net "ISENSE_PVCCIN_CPU1_PH3_IMON")
	)
	(segment
		(start 27.64028 -81.15046)
		(end 27.305 -80.81518)
		(width 0.127)
		(layer "In4.Cu")
		(net "ISENSE_PVCCIN_CPU1_PH3_IMON")
	)
	(segment
		(start 29.040836 -70.951852)
		(end 29.339032 -71.250048)
		(width 0.127)
		(layer "In4.Cu")
		(net "ISENSE_PVCCIN_CPU1_PH3_IMON")
	)
	(segment
		(start 26.766774 -89.98712)
		(end 27.042364 -89.71153)
		(width 0.127)
		(layer "In4.Cu")
		(net "ISENSE_PVCCIN_CPU1_PH3_IMON")
	)
	(segment
		(start 28.82646 -70.951852)
		(end 29.040836 -70.951852)
		(width 0.127)
		(layer "In4.Cu")
		(net "ISENSE_PVCCIN_CPU1_PH3_IMON")
	)
	(segment
		(start 31.02991 -63.617856)
		(end 30.47111 -63.617856)
		(width 0.127)
		(layer "F.Cu")
		(net "ISENSE_PVCCIN_CPU1_PH2_IMON")
	)
	(segment
		(start 22.780498 -90.655902)
		(end 22.3266 -90.655902)
		(width 0.127)
		(layer "F.Cu")
		(net "ISENSE_PVCCIN_CPU1_PH2_IMON")
	)
	(segment
		(start 24.007826 -88.730582)
		(end 24.007826 -88.93556)
		(width 0.127)
		(layer "F.Cu")
		(net "ISENSE_PVCCIN_CPU1_PH2_IMON")
	)
	(segment
		(start 22.969728 -89.973658)
		(end 22.969728 -90.466672)
		(width 0.127)
		(layer "F.Cu")
		(net "ISENSE_PVCCIN_CPU1_PH2_IMON")
	)
	(segment
		(start 29.940758 -63.087504)
		(end 29.336238 -63.087504)
		(width 0.127)
		(layer "F.Cu")
		(net "ISENSE_PVCCIN_CPU1_PH2_IMON")
	)
	(segment
		(start 30.47111 -63.617856)
		(end 29.940758 -63.087504)
		(width 0.127)
		(layer "F.Cu")
		(net "ISENSE_PVCCIN_CPU1_PH2_IMON")
	)
	(segment
		(start 24.007826 -88.93556)
		(end 22.969728 -89.973658)
		(width 0.127)
		(layer "F.Cu")
		(net "ISENSE_PVCCIN_CPU1_PH2_IMON")
	)
	(segment
		(start 24.163274 -88.575134)
		(end 25.035002 -88.575134)
		(width 0.127)
		(layer "F.Cu")
		(net "ISENSE_PVCCIN_CPU1_PH2_IMON")
	)
	(segment
		(start 25.035002 -88.575134)
		(end 25.857454 -88.575134)
		(width 0.127)
		(layer "F.Cu")
		(net "ISENSE_PVCCIN_CPU1_PH2_IMON")
	)
	(segment
		(start 25.857454 -88.575134)
		(end 25.91816 -88.63584)
		(width 0.127)
		(layer "F.Cu")
		(net "ISENSE_PVCCIN_CPU1_PH2_IMON")
	)
	(segment
		(start 22.969728 -90.466672)
		(end 22.780498 -90.655902)
		(width 0.127)
		(layer "F.Cu")
		(net "ISENSE_PVCCIN_CPU1_PH2_IMON")
	)
	(segment
		(start 24.007826 -88.730582)
		(end 24.163274 -88.575134)
		(width 0.127)
		(layer "F.Cu")
		(net "ISENSE_PVCCIN_CPU1_PH2_IMON")
	)
	(via
		(at 25.91816 -88.63584)
		(size 0.508)
		(drill 0.254)
		(layers "F.Cu" "B.Cu")
		(net "ISENSE_PVCCIN_CPU1_PH2_IMON")
	)
	(via
		(at 29.336238 -63.087504)
		(size 0.508)
		(drill 0.254)
		(layers "F.Cu" "B.Cu")
		(net "ISENSE_PVCCIN_CPU1_PH2_IMON")
	)
	(segment
		(start 26.92654 -86.13648)
		(end 26.92654 -82.03184)
		(width 0.127)
		(layer "In4.Cu")
		(net "ISENSE_PVCCIN_CPU1_PH2_IMON")
	)
	(segment
		(start 28.2829 -64.50838)
		(end 28.2829 -63.169546)
		(width 0.127)
		(layer "In4.Cu")
		(net "ISENSE_PVCCIN_CPU1_PH2_IMON")
	)
	(segment
		(start 25.5524 -72.47001)
		(end 27.54122 -70.48119)
		(width 0.127)
		(layer "In4.Cu")
		(net "ISENSE_PVCCIN_CPU1_PH2_IMON")
	)
	(segment
		(start 25.91816 -88.63584)
		(end 26.3779 -88.1761)
		(width 0.127)
		(layer "In4.Cu")
		(net "ISENSE_PVCCIN_CPU1_PH2_IMON")
	)
	(segment
		(start 27.54122 -65.25006)
		(end 28.2829 -64.50838)
		(width 0.127)
		(layer "In4.Cu")
		(net "ISENSE_PVCCIN_CPU1_PH2_IMON")
	)
	(segment
		(start 26.3779 -88.1761)
		(end 26.3779 -86.68512)
		(width 0.127)
		(layer "In4.Cu")
		(net "ISENSE_PVCCIN_CPU1_PH2_IMON")
	)
	(segment
		(start 26.92654 -82.03184)
		(end 25.5524 -80.6577)
		(width 0.127)
		(layer "In4.Cu")
		(net "ISENSE_PVCCIN_CPU1_PH2_IMON")
	)
	(segment
		(start 26.3779 -86.68512)
		(end 26.92654 -86.13648)
		(width 0.127)
		(layer "In4.Cu")
		(net "ISENSE_PVCCIN_CPU1_PH2_IMON")
	)
	(segment
		(start 28.593796 -62.85865)
		(end 29.075634 -62.85865)
		(width 0.127)
		(layer "In4.Cu")
		(net "ISENSE_PVCCIN_CPU1_PH2_IMON")
	)
	(segment
		(start 28.2829 -63.169546)
		(end 28.593796 -62.85865)
		(width 0.127)
		(layer "In4.Cu")
		(net "ISENSE_PVCCIN_CPU1_PH2_IMON")
	)
	(segment
		(start 29.304488 -63.087504)
		(end 29.336238 -63.087504)
		(width 0.127)
		(layer "In4.Cu")
		(net "ISENSE_PVCCIN_CPU1_PH2_IMON")
	)
	(segment
		(start 25.5524 -80.6577)
		(end 25.5524 -72.47001)
		(width 0.127)
		(layer "In4.Cu")
		(net "ISENSE_PVCCIN_CPU1_PH2_IMON")
	)
	(segment
		(start 27.54122 -70.48119)
		(end 27.54122 -65.25006)
		(width 0.127)
		(layer "In4.Cu")
		(net "ISENSE_PVCCIN_CPU1_PH2_IMON")
	)
	(segment
		(start 29.075634 -62.85865)
		(end 29.304488 -63.087504)
		(width 0.127)
		(layer "In4.Cu")
		(net "ISENSE_PVCCIN_CPU1_PH2_IMON")
	)
	(segment
		(start 24.853392 -86.824566)
		(end 24.123142 -86.824566)
		(width 0.127)
		(layer "F.Cu")
		(net "ISENSE_PVCCIN_CPU1_PH1_IMON")
	)
	(segment
		(start 26.43378 -87.11692)
		(end 25.496266 -87.11692)
		(width 0.127)
		(layer "F.Cu")
		(net "ISENSE_PVCCIN_CPU1_PH1_IMON")
	)
	(segment
		(start 23.29434 -87.4776)
		(end 23.14194 -87.63)
		(width 0.127)
		(layer "F.Cu")
		(net "ISENSE_PVCCIN_CPU1_PH1_IMON")
	)
	(segment
		(start 25.496266 -87.11692)
		(end 25.028652 -86.649306)
		(width 0.127)
		(layer "F.Cu")
		(net "ISENSE_PVCCIN_CPU1_PH1_IMON")
	)
	(segment
		(start 25.028652 -86.649306)
		(end 24.853392 -86.824566)
		(width 0.127)
		(layer "F.Cu")
		(net "ISENSE_PVCCIN_CPU1_PH1_IMON")
	)
	(segment
		(start 30.47111 -55.489856)
		(end 30.353254 -55.372)
		(width 0.127)
		(layer "F.Cu")
		(net "ISENSE_PVCCIN_CPU1_PH1_IMON")
	)
	(segment
		(start 30.353254 -55.372)
		(end 29.716984 -55.372)
		(width 0.127)
		(layer "F.Cu")
		(net "ISENSE_PVCCIN_CPU1_PH1_IMON")
	)
	(segment
		(start 23.14194 -88.81872)
		(end 22.40026 -89.5604)
		(width 0.127)
		(layer "F.Cu")
		(net "ISENSE_PVCCIN_CPU1_PH1_IMON")
	)
	(segment
		(start 22.40026 -89.5604)
		(end 21.630894 -89.5604)
		(width 0.127)
		(layer "F.Cu")
		(net "ISENSE_PVCCIN_CPU1_PH1_IMON")
	)
	(segment
		(start 31.02991 -55.489856)
		(end 30.47111 -55.489856)
		(width 0.127)
		(layer "F.Cu")
		(net "ISENSE_PVCCIN_CPU1_PH1_IMON")
	)
	(segment
		(start 23.14194 -87.63)
		(end 23.14194 -88.81872)
		(width 0.127)
		(layer "F.Cu")
		(net "ISENSE_PVCCIN_CPU1_PH1_IMON")
	)
	(segment
		(start 23.901908 -87.0458)
		(end 24.123142 -86.824566)
		(width 0.127)
		(layer "F.Cu")
		(net "ISENSE_PVCCIN_CPU1_PH1_IMON")
	)
	(segment
		(start 29.716984 -55.372)
		(end 29.339032 -54.994048)
		(width 0.127)
		(layer "F.Cu")
		(net "ISENSE_PVCCIN_CPU1_PH1_IMON")
	)
	(segment
		(start 23.29434 -87.0458)
		(end 23.29434 -87.4776)
		(width 0.127)
		(layer "F.Cu")
		(net "ISENSE_PVCCIN_CPU1_PH1_IMON")
	)
	(segment
		(start 23.29434 -87.0458)
		(end 23.901908 -87.0458)
		(width 0.127)
		(layer "F.Cu")
		(net "ISENSE_PVCCIN_CPU1_PH1_IMON")
	)
	(via
		(at 29.339032 -54.994048)
		(size 0.508)
		(drill 0.254)
		(layers "F.Cu" "B.Cu")
		(net "ISENSE_PVCCIN_CPU1_PH1_IMON")
	)
	(via
		(at 25.028652 -86.649306)
		(size 0.508)
		(drill 0.254)
		(layers "F.Cu" "B.Cu")
		(net "ISENSE_PVCCIN_CPU1_PH1_IMON")
	)
	(via
		(at 26.43378 -87.11692)
		(size 0.762)
		(drill 0.381)
		(layers "F.Cu" "B.Cu")
		(net "ISENSE_PVCCIN_CPU1_PH1_IMON")
	)
	(segment
		(start 28.4226 -55.067962)
		(end 28.68041 -54.810152)
		(width 0.127)
		(layer "In4.Cu")
		(net "ISENSE_PVCCIN_CPU1_PH1_IMON")
	)
	(segment
		(start 25.028652 -86.649306)
		(end 25.5778 -86.100158)
		(width 0.127)
		(layer "In4.Cu")
		(net "ISENSE_PVCCIN_CPU1_PH1_IMON")
	)
	(segment
		(start 26.90622 -59.10199)
		(end 28.4226 -57.58561)
		(width 0.127)
		(layer "In4.Cu")
		(net "ISENSE_PVCCIN_CPU1_PH1_IMON")
	)
	(segment
		(start 25.5778 -85.7885)
		(end 24.82342 -85.03412)
		(width 0.127)
		(layer "In4.Cu")
		(net "ISENSE_PVCCIN_CPU1_PH1_IMON")
	)
	(segment
		(start 25.5778 -86.100158)
		(end 25.5778 -85.7885)
		(width 0.127)
		(layer "In4.Cu")
		(net "ISENSE_PVCCIN_CPU1_PH1_IMON")
	)
	(segment
		(start 24.82342 -85.03412)
		(end 24.82342 -80.60182)
		(width 0.127)
		(layer "In4.Cu")
		(net "ISENSE_PVCCIN_CPU1_PH1_IMON")
	)
	(segment
		(start 28.68041 -54.810152)
		(end 29.155136 -54.810152)
		(width 0.127)
		(layer "In4.Cu")
		(net "ISENSE_PVCCIN_CPU1_PH1_IMON")
	)
	(segment
		(start 24.332946 -80.111346)
		(end 24.332946 -75.906376)
		(width 0.127)
		(layer "In4.Cu")
		(net "ISENSE_PVCCIN_CPU1_PH1_IMON")
	)
	(segment
		(start 24.7142 -75.525122)
		(end 24.7142 -70.624446)
		(width 0.127)
		(layer "In4.Cu")
		(net "ISENSE_PVCCIN_CPU1_PH1_IMON")
	)
	(segment
		(start 29.155136 -54.810152)
		(end 29.339032 -54.994048)
		(width 0.127)
		(layer "In4.Cu")
		(net "ISENSE_PVCCIN_CPU1_PH1_IMON")
	)
	(segment
		(start 24.7142 -70.624446)
		(end 26.90622 -68.432426)
		(width 0.127)
		(layer "In4.Cu")
		(net "ISENSE_PVCCIN_CPU1_PH1_IMON")
	)
	(segment
		(start 26.90622 -68.432426)
		(end 26.90622 -59.10199)
		(width 0.127)
		(layer "In4.Cu")
		(net "ISENSE_PVCCIN_CPU1_PH1_IMON")
	)
	(segment
		(start 24.82342 -80.60182)
		(end 24.332946 -80.111346)
		(width 0.127)
		(layer "In4.Cu")
		(net "ISENSE_PVCCIN_CPU1_PH1_IMON")
	)
	(segment
		(start 24.332946 -75.906376)
		(end 24.7142 -75.525122)
		(width 0.127)
		(layer "In4.Cu")
		(net "ISENSE_PVCCIN_CPU1_PH1_IMON")
	)
	(segment
		(start 28.4226 -57.58561)
		(end 28.4226 -55.067962)
		(width 0.127)
		(layer "In4.Cu")
		(net "ISENSE_PVCCIN_CPU1_PH1_IMON")
	)
	(segment
		(start 196.030342 -88.001856)
		(end 195.471542 -88.001856)
		(width 0.127)
		(layer "F.Cu")
		(net "ISENSE_PVCCIN_CPU0_PH5_IMON")
	)
	(segment
		(start 188.0616 -71.0946)
		(end 188.0616 -70.6628)
		(width 0.127)
		(layer "F.Cu")
		(net "ISENSE_PVCCIN_CPU0_PH5_IMON")
	)
	(segment
		(start 189.2046 -71.4629)
		(end 189.3316 -71.5899)
		(width 0.127)
		(layer "F.Cu")
		(net "ISENSE_PVCCIN_CPU0_PH5_IMON")
	)
	(segment
		(start 188.0616 -70.6628)
		(end 187.7822 -70.3834)
		(width 0.127)
		(layer "F.Cu")
		(net "ISENSE_PVCCIN_CPU0_PH5_IMON")
	)
	(segment
		(start 188.5696 -71.4629)
		(end 189.2046 -71.4629)
		(width 0.127)
		(layer "F.Cu")
		(net "ISENSE_PVCCIN_CPU0_PH5_IMON")
	)
	(segment
		(start 190.3349 -71.5899)
		(end 190.4492 -71.7042)
		(width 0.127)
		(layer "F.Cu")
		(net "ISENSE_PVCCIN_CPU0_PH5_IMON")
	)
	(segment
		(start 188.4299 -71.4629)
		(end 188.0616 -71.0946)
		(width 0.127)
		(layer "F.Cu")
		(net "ISENSE_PVCCIN_CPU0_PH5_IMON")
	)
	(segment
		(start 187.7822 -70.3834)
		(end 187.6298 -70.3834)
		(width 0.127)
		(layer "F.Cu")
		(net "ISENSE_PVCCIN_CPU0_PH5_IMON")
	)
	(segment
		(start 195.353686 -87.884)
		(end 194.717416 -87.884)
		(width 0.127)
		(layer "F.Cu")
		(net "ISENSE_PVCCIN_CPU0_PH5_IMON")
	)
	(segment
		(start 188.5696 -71.4629)
		(end 188.4299 -71.4629)
		(width 0.127)
		(layer "F.Cu")
		(net "ISENSE_PVCCIN_CPU0_PH5_IMON")
	)
	(segment
		(start 187.563252 -70.449948)
		(end 187.1726 -70.449948)
		(width 0.127)
		(layer "F.Cu")
		(net "ISENSE_PVCCIN_CPU0_PH5_IMON")
	)
	(segment
		(start 194.717416 -87.884)
		(end 194.339464 -87.506048)
		(width 0.127)
		(layer "F.Cu")
		(net "ISENSE_PVCCIN_CPU0_PH5_IMON")
	)
	(segment
		(start 189.3316 -71.5899)
		(end 190.3349 -71.5899)
		(width 0.127)
		(layer "F.Cu")
		(net "ISENSE_PVCCIN_CPU0_PH5_IMON")
	)
	(segment
		(start 187.6298 -70.3834)
		(end 187.563252 -70.449948)
		(width 0.127)
		(layer "F.Cu")
		(net "ISENSE_PVCCIN_CPU0_PH5_IMON")
	)
	(segment
		(start 195.471542 -88.001856)
		(end 195.353686 -87.884)
		(width 0.127)
		(layer "F.Cu")
		(net "ISENSE_PVCCIN_CPU0_PH5_IMON")
	)
	(via
		(at 190.4492 -71.7042)
		(size 0.508)
		(drill 0.254)
		(layers "F.Cu" "B.Cu")
		(net "ISENSE_PVCCIN_CPU0_PH5_IMON")
	)
	(via
		(at 194.339464 -87.506048)
		(size 0.508)
		(drill 0.254)
		(layers "F.Cu" "B.Cu")
		(net "ISENSE_PVCCIN_CPU0_PH5_IMON")
	)
	(segment
		(start 192.9384 -83.090004)
		(end 192.9384 -86.491064)
		(width 0.127)
		(layer "In11.Cu")
		(net "ISENSE_PVCCIN_CPU0_PH5_IMON")
	)
	(segment
		(start 190.7921 -80.943704)
		(end 192.9384 -83.090004)
		(width 0.127)
		(layer "In11.Cu")
		(net "ISENSE_PVCCIN_CPU0_PH5_IMON")
	)
	(segment
		(start 194.04457 -87.211154)
		(end 194.339464 -87.506048)
		(width 0.127)
		(layer "In11.Cu")
		(net "ISENSE_PVCCIN_CPU0_PH5_IMON")
	)
	(segment
		(start 190.4492 -71.7042)
		(end 190.7921 -72.0471)
		(width 0.127)
		(layer "In11.Cu")
		(net "ISENSE_PVCCIN_CPU0_PH5_IMON")
	)
	(segment
		(start 190.7921 -72.0471)
		(end 190.7921 -80.943704)
		(width 0.127)
		(layer "In11.Cu")
		(net "ISENSE_PVCCIN_CPU0_PH5_IMON")
	)
	(segment
		(start 192.9384 -86.491064)
		(end 193.65849 -87.211154)
		(width 0.127)
		(layer "In11.Cu")
		(net "ISENSE_PVCCIN_CPU0_PH5_IMON")
	)
	(segment
		(start 193.65849 -87.211154)
		(end 194.04457 -87.211154)
		(width 0.127)
		(layer "In11.Cu")
		(net "ISENSE_PVCCIN_CPU0_PH5_IMON")
	)
	(segment
		(start 189.1792 -69.5452)
		(end 187.833254 -69.5452)
		(width 0.127)
		(layer "F.Cu")
		(net "ISENSE_PVCCIN_CPU0_PH4_IMON")
	)
	(segment
		(start 190.9318 -70.3199)
		(end 191.601344 -70.3199)
		(width 0.127)
		(layer "F.Cu")
		(net "ISENSE_PVCCIN_CPU0_PH4_IMON")
	)
	(segment
		(start 194.945 -79.756)
		(end 194.567048 -79.378048)
		(width 0.127)
		(layer "F.Cu")
		(net "ISENSE_PVCCIN_CPU0_PH4_IMON")
	)
	(segment
		(start 194.567048 -79.378048)
		(end 194.339464 -79.378048)
		(width 0.127)
		(layer "F.Cu")
		(net "ISENSE_PVCCIN_CPU0_PH4_IMON")
	)
	(segment
		(start 195.353686 -79.756)
		(end 194.945 -79.756)
		(width 0.127)
		(layer "F.Cu")
		(net "ISENSE_PVCCIN_CPU0_PH4_IMON")
	)
	(segment
		(start 195.471542 -79.873856)
		(end 195.353686 -79.756)
		(width 0.127)
		(layer "F.Cu")
		(net "ISENSE_PVCCIN_CPU0_PH4_IMON")
	)
	(segment
		(start 189.8269 -70.1929)
		(end 189.1792 -69.5452)
		(width 0.127)
		(layer "F.Cu")
		(net "ISENSE_PVCCIN_CPU0_PH4_IMON")
	)
	(segment
		(start 191.601344 -70.3199)
		(end 191.730884 -70.19036)
		(width 0.127)
		(layer "F.Cu")
		(net "ISENSE_PVCCIN_CPU0_PH4_IMON")
	)
	(segment
		(start 190.1698 -70.1929)
		(end 189.8269 -70.1929)
		(width 0.127)
		(layer "F.Cu")
		(net "ISENSE_PVCCIN_CPU0_PH4_IMON")
	)
	(segment
		(start 187.833254 -69.5452)
		(end 187.728352 -69.650102)
		(width 0.127)
		(layer "F.Cu")
		(net "ISENSE_PVCCIN_CPU0_PH4_IMON")
	)
	(segment
		(start 187.728352 -69.650102)
		(end 187.1726 -69.650102)
		(width 0.127)
		(layer "F.Cu")
		(net "ISENSE_PVCCIN_CPU0_PH4_IMON")
	)
	(segment
		(start 190.1698 -70.1929)
		(end 190.8048 -70.1929)
		(width 0.127)
		(layer "F.Cu")
		(net "ISENSE_PVCCIN_CPU0_PH4_IMON")
	)
	(segment
		(start 196.030342 -79.873856)
		(end 195.471542 -79.873856)
		(width 0.127)
		(layer "F.Cu")
		(net "ISENSE_PVCCIN_CPU0_PH4_IMON")
	)
	(segment
		(start 190.8048 -70.1929)
		(end 190.9318 -70.3199)
		(width 0.127)
		(layer "F.Cu")
		(net "ISENSE_PVCCIN_CPU0_PH4_IMON")
	)
	(via
		(at 191.730884 -70.19036)
		(size 0.508)
		(drill 0.254)
		(layers "F.Cu" "B.Cu")
		(net "ISENSE_PVCCIN_CPU0_PH4_IMON")
	)
	(via
		(at 194.339464 -79.378048)
		(size 0.508)
		(drill 0.254)
		(layers "F.Cu" "B.Cu")
		(net "ISENSE_PVCCIN_CPU0_PH4_IMON")
	)
	(segment
		(start 192.377822 -70.105016)
		(end 192.377822 -70.80631)
		(width 0.127)
		(layer "In11.Cu")
		(net "ISENSE_PVCCIN_CPU0_PH4_IMON")
	)
	(segment
		(start 192.278 -77.851)
		(end 193.528442 -79.101442)
		(width 0.127)
		(layer "In11.Cu")
		(net "ISENSE_PVCCIN_CPU0_PH4_IMON")
	)
	(segment
		(start 192.266316 -69.99351)
		(end 192.377822 -70.105016)
		(width 0.127)
		(layer "In11.Cu")
		(net "ISENSE_PVCCIN_CPU0_PH4_IMON")
	)
	(segment
		(start 194.062858 -79.101442)
		(end 194.339464 -79.378048)
		(width 0.127)
		(layer "In11.Cu")
		(net "ISENSE_PVCCIN_CPU0_PH4_IMON")
	)
	(segment
		(start 193.528442 -79.101442)
		(end 194.062858 -79.101442)
		(width 0.127)
		(layer "In11.Cu")
		(net "ISENSE_PVCCIN_CPU0_PH4_IMON")
	)
	(segment
		(start 192.035176 -71.148956)
		(end 192.035176 -73.680828)
		(width 0.127)
		(layer "In11.Cu")
		(net "ISENSE_PVCCIN_CPU0_PH4_IMON")
	)
	(segment
		(start 192.377822 -70.80631)
		(end 192.035176 -71.148956)
		(width 0.127)
		(layer "In11.Cu")
		(net "ISENSE_PVCCIN_CPU0_PH4_IMON")
	)
	(segment
		(start 192.278 -73.923652)
		(end 192.278 -77.851)
		(width 0.127)
		(layer "In11.Cu")
		(net "ISENSE_PVCCIN_CPU0_PH4_IMON")
	)
	(segment
		(start 191.927734 -69.99351)
		(end 192.266316 -69.99351)
		(width 0.127)
		(layer "In11.Cu")
		(net "ISENSE_PVCCIN_CPU0_PH4_IMON")
	)
	(segment
		(start 192.035176 -73.680828)
		(end 192.278 -73.923652)
		(width 0.127)
		(layer "In11.Cu")
		(net "ISENSE_PVCCIN_CPU0_PH4_IMON")
	)
	(segment
		(start 191.730884 -70.19036)
		(end 191.927734 -69.99351)
		(width 0.127)
		(layer "In11.Cu")
		(net "ISENSE_PVCCIN_CPU0_PH4_IMON")
	)
	(segment
		(start 189.2808 -68.6943)
		(end 189.5602 -68.4149)
		(width 0.127)
		(layer "F.Cu")
		(net "ISENSE_PVCCIN_CPU0_PH3_IMON")
	)
	(segment
		(start 190.04026 -68.4149)
		(end 190.26886 -68.6435)
		(width 0.127)
		(layer "F.Cu")
		(net "ISENSE_PVCCIN_CPU0_PH3_IMON")
	)
	(segment
		(start 188.500512 -68.809108)
		(end 189.165992 -68.809108)
		(width 0.127)
		(layer "F.Cu")
		(net "ISENSE_PVCCIN_CPU0_PH3_IMON")
	)
	(segment
		(start 194.653916 -71.5645)
		(end 194.339464 -71.250048)
		(width 0.127)
		(layer "F.Cu")
		(net "ISENSE_PVCCIN_CPU0_PH3_IMON")
	)
	(segment
		(start 189.165992 -68.809108)
		(end 189.2808 -68.6943)
		(width 0.127)
		(layer "F.Cu")
		(net "ISENSE_PVCCIN_CPU0_PH3_IMON")
	)
	(segment
		(start 189.5602 -68.4149)
		(end 190.04026 -68.4149)
		(width 0.127)
		(layer "F.Cu")
		(net "ISENSE_PVCCIN_CPU0_PH3_IMON")
	)
	(segment
		(start 188.485018 -68.850002)
		(end 188.500512 -68.809108)
		(width 0.127)
		(layer "F.Cu")
		(net "ISENSE_PVCCIN_CPU0_PH3_IMON")
	)
	(segment
		(start 196.030342 -71.745856)
		(end 195.690236 -71.745856)
		(width 0.127)
		(layer "F.Cu")
		(net "ISENSE_PVCCIN_CPU0_PH3_IMON")
	)
	(segment
		(start 195.50888 -71.5645)
		(end 194.653916 -71.5645)
		(width 0.127)
		(layer "F.Cu")
		(net "ISENSE_PVCCIN_CPU0_PH3_IMON")
	)
	(segment
		(start 195.690236 -71.745856)
		(end 195.50888 -71.5645)
		(width 0.127)
		(layer "F.Cu")
		(net "ISENSE_PVCCIN_CPU0_PH3_IMON")
	)
	(segment
		(start 187.1726 -68.850002)
		(end 188.485018 -68.850002)
		(width 0.127)
		(layer "F.Cu")
		(net "ISENSE_PVCCIN_CPU0_PH3_IMON")
	)
	(via
		(at 190.26886 -68.6435)
		(size 0.508)
		(drill 0.254)
		(layers "F.Cu" "B.Cu")
		(net "ISENSE_PVCCIN_CPU0_PH3_IMON")
	)
	(via
		(at 194.339464 -71.250048)
		(size 0.508)
		(drill 0.254)
		(layers "F.Cu" "B.Cu")
		(net "ISENSE_PVCCIN_CPU0_PH3_IMON")
	)
	(segment
		(start 194.083178 -70.993762)
		(end 194.339464 -71.250048)
		(width 0.127)
		(layer "In11.Cu")
		(net "ISENSE_PVCCIN_CPU0_PH3_IMON")
	)
	(segment
		(start 192.659 -68.3895)
		(end 192.786 -68.5165)
		(width 0.127)
		(layer "In11.Cu")
		(net "ISENSE_PVCCIN_CPU0_PH3_IMON")
	)
	(segment
		(start 192.786 -68.5165)
		(end 192.786 -69.16801)
		(width 0.127)
		(layer "In11.Cu")
		(net "ISENSE_PVCCIN_CPU0_PH3_IMON")
	)
	(segment
		(start 193.3194 -70.504558)
		(end 193.808604 -70.993762)
		(width 0.127)
		(layer "In11.Cu")
		(net "ISENSE_PVCCIN_CPU0_PH3_IMON")
	)
	(segment
		(start 193.3194 -69.70141)
		(end 193.3194 -70.504558)
		(width 0.127)
		(layer "In11.Cu")
		(net "ISENSE_PVCCIN_CPU0_PH3_IMON")
	)
	(segment
		(start 193.808604 -70.993762)
		(end 194.083178 -70.993762)
		(width 0.127)
		(layer "In11.Cu")
		(net "ISENSE_PVCCIN_CPU0_PH3_IMON")
	)
	(segment
		(start 190.26886 -68.6435)
		(end 190.52286 -68.3895)
		(width 0.127)
		(layer "In11.Cu")
		(net "ISENSE_PVCCIN_CPU0_PH3_IMON")
	)
	(segment
		(start 192.786 -69.16801)
		(end 193.3194 -69.70141)
		(width 0.127)
		(layer "In11.Cu")
		(net "ISENSE_PVCCIN_CPU0_PH3_IMON")
	)
	(segment
		(start 190.52286 -68.3895)
		(end 192.659 -68.3895)
		(width 0.127)
		(layer "In11.Cu")
		(net "ISENSE_PVCCIN_CPU0_PH3_IMON")
	)
	(segment
		(start 189.963044 -66.969386)
		(end 190.629286 -66.969386)
		(width 0.127)
		(layer "F.Cu")
		(net "ISENSE_PVCCIN_CPU0_PH2_IMON")
	)
	(segment
		(start 188.85916 -66.79946)
		(end 188.94552 -66.79946)
		(width 0.127)
		(layer "F.Cu")
		(net "ISENSE_PVCCIN_CPU0_PH2_IMON")
	)
	(segment
		(start 187.1726 -68.049902)
		(end 187.608718 -68.049902)
		(width 0.127)
		(layer "F.Cu")
		(net "ISENSE_PVCCIN_CPU0_PH2_IMON")
	)
	(segment
		(start 187.608718 -68.049902)
		(end 188.85916 -66.79946)
		(width 0.127)
		(layer "F.Cu")
		(net "ISENSE_PVCCIN_CPU0_PH2_IMON")
	)
	(segment
		(start 189.778386 -66.969386)
		(end 189.963044 -66.969386)
		(width 0.127)
		(layer "F.Cu")
		(net "ISENSE_PVCCIN_CPU0_PH2_IMON")
	)
	(segment
		(start 191.430402 -66.366898)
		(end 190.7286 -67.0687)
		(width 0.127)
		(layer "F.Cu")
		(net "ISENSE_PVCCIN_CPU0_PH2_IMON")
	)
	(segment
		(start 188.94552 -66.79946)
		(end 189.10427 -66.64071)
		(width 0.127)
		(layer "F.Cu")
		(net "ISENSE_PVCCIN_CPU0_PH2_IMON")
	)
	(segment
		(start 196.030342 -63.617856)
		(end 195.471542 -63.617856)
		(width 0.127)
		(layer "F.Cu")
		(net "ISENSE_PVCCIN_CPU0_PH2_IMON")
	)
	(segment
		(start 189.10427 -66.64071)
		(end 189.44971 -66.64071)
		(width 0.127)
		(layer "F.Cu")
		(net "ISENSE_PVCCIN_CPU0_PH2_IMON")
	)
	(segment
		(start 194.694048 -63.122048)
		(end 194.339464 -63.122048)
		(width 0.127)
		(layer "F.Cu")
		(net "ISENSE_PVCCIN_CPU0_PH2_IMON")
	)
	(segment
		(start 195.072 -63.5)
		(end 194.694048 -63.122048)
		(width 0.127)
		(layer "F.Cu")
		(net "ISENSE_PVCCIN_CPU0_PH2_IMON")
	)
	(segment
		(start 195.471542 -63.617856)
		(end 195.353686 -63.5)
		(width 0.127)
		(layer "F.Cu")
		(net "ISENSE_PVCCIN_CPU0_PH2_IMON")
	)
	(segment
		(start 190.629286 -66.969386)
		(end 190.7286 -67.0687)
		(width 0.127)
		(layer "F.Cu")
		(net "ISENSE_PVCCIN_CPU0_PH2_IMON")
	)
	(segment
		(start 189.44971 -66.64071)
		(end 189.778386 -66.969386)
		(width 0.127)
		(layer "F.Cu")
		(net "ISENSE_PVCCIN_CPU0_PH2_IMON")
	)
	(segment
		(start 191.582802 -64.568578)
		(end 191.430402 -64.720978)
		(width 0.127)
		(layer "F.Cu")
		(net "ISENSE_PVCCIN_CPU0_PH2_IMON")
	)
	(segment
		(start 191.430402 -64.720978)
		(end 191.430402 -66.366898)
		(width 0.127)
		(layer "F.Cu")
		(net "ISENSE_PVCCIN_CPU0_PH2_IMON")
	)
	(segment
		(start 195.353686 -63.5)
		(end 195.072 -63.5)
		(width 0.127)
		(layer "F.Cu")
		(net "ISENSE_PVCCIN_CPU0_PH2_IMON")
	)
	(via
		(at 191.582802 -64.568578)
		(size 0.508)
		(drill 0.254)
		(layers "F.Cu" "B.Cu")
		(net "ISENSE_PVCCIN_CPU0_PH2_IMON")
	)
	(via
		(at 194.339464 -63.122048)
		(size 0.508)
		(drill 0.254)
		(layers "F.Cu" "B.Cu")
		(net "ISENSE_PVCCIN_CPU0_PH2_IMON")
	)
	(segment
		(start 192.727072 -62.827408)
		(end 194.044824 -62.827408)
		(width 0.127)
		(layer "In11.Cu")
		(net "ISENSE_PVCCIN_CPU0_PH2_IMON")
	)
	(segment
		(start 191.582802 -64.568578)
		(end 191.431418 -64.417194)
		(width 0.127)
		(layer "In11.Cu")
		(net "ISENSE_PVCCIN_CPU0_PH2_IMON")
	)
	(segment
		(start 191.431418 -64.123062)
		(end 192.727072 -62.827408)
		(width 0.127)
		(layer "In11.Cu")
		(net "ISENSE_PVCCIN_CPU0_PH2_IMON")
	)
	(segment
		(start 191.431418 -64.417194)
		(end 191.431418 -64.123062)
		(width 0.127)
		(layer "In11.Cu")
		(net "ISENSE_PVCCIN_CPU0_PH2_IMON")
	)
	(segment
		(start 194.044824 -62.827408)
		(end 194.339464 -63.122048)
		(width 0.127)
		(layer "In11.Cu")
		(net "ISENSE_PVCCIN_CPU0_PH2_IMON")
	)
	(segment
		(start 195.353686 -55.372)
		(end 194.717416 -55.372)
		(width 0.127)
		(layer "F.Cu")
		(net "ISENSE_PVCCIN_CPU0_PH1_IMON")
	)
	(segment
		(start 188.98108 -65.71488)
		(end 188.98108 -65.865502)
		(width 0.127)
		(layer "F.Cu")
		(net "ISENSE_PVCCIN_CPU0_PH1_IMON")
	)
	(segment
		(start 186.476894 -66.418714)
		(end 186.819794 -66.075814)
		(width 0.127)
		(layer "F.Cu")
		(net "ISENSE_PVCCIN_CPU0_PH1_IMON")
	)
	(segment
		(start 186.819794 -66.075814)
		(end 187.603892 -66.075814)
		(width 0.127)
		(layer "F.Cu")
		(net "ISENSE_PVCCIN_CPU0_PH1_IMON")
	)
	(segment
		(start 189.63005 -65.29705)
		(end 189.41161 -65.29705)
		(width 0.127)
		(layer "F.Cu")
		(net "ISENSE_PVCCIN_CPU0_PH1_IMON")
	)
	(segment
		(start 195.471542 -55.489856)
		(end 195.353686 -55.372)
		(width 0.127)
		(layer "F.Cu")
		(net "ISENSE_PVCCIN_CPU0_PH1_IMON")
	)
	(segment
		(start 196.030342 -55.489856)
		(end 195.471542 -55.489856)
		(width 0.127)
		(layer "F.Cu")
		(net "ISENSE_PVCCIN_CPU0_PH1_IMON")
	)
	(segment
		(start 187.603892 -66.075814)
		(end 187.692538 -66.16446)
		(width 0.127)
		(layer "F.Cu")
		(net "ISENSE_PVCCIN_CPU0_PH1_IMON")
	)
	(segment
		(start 186.476894 -66.9544)
		(end 186.476894 -66.418714)
		(width 0.127)
		(layer "F.Cu")
		(net "ISENSE_PVCCIN_CPU0_PH1_IMON")
	)
	(segment
		(start 188.682122 -66.16446)
		(end 188.137038 -66.16446)
		(width 0.127)
		(layer "F.Cu")
		(net "ISENSE_PVCCIN_CPU0_PH1_IMON")
	)
	(segment
		(start 190.1698 -65.405)
		(end 189.738 -65.405)
		(width 0.127)
		(layer "F.Cu")
		(net "ISENSE_PVCCIN_CPU0_PH1_IMON")
	)
	(segment
		(start 194.717416 -55.372)
		(end 194.339464 -54.994048)
		(width 0.127)
		(layer "F.Cu")
		(net "ISENSE_PVCCIN_CPU0_PH1_IMON")
	)
	(segment
		(start 188.98108 -65.865502)
		(end 188.682122 -66.16446)
		(width 0.127)
		(layer "F.Cu")
		(net "ISENSE_PVCCIN_CPU0_PH1_IMON")
	)
	(segment
		(start 188.99378 -65.71488)
		(end 188.98108 -65.71488)
		(width 0.127)
		(layer "F.Cu")
		(net "ISENSE_PVCCIN_CPU0_PH1_IMON")
	)
	(segment
		(start 187.692538 -66.16446)
		(end 188.137038 -66.16446)
		(width 0.127)
		(layer "F.Cu")
		(net "ISENSE_PVCCIN_CPU0_PH1_IMON")
	)
	(segment
		(start 189.41161 -65.29705)
		(end 188.99378 -65.71488)
		(width 0.127)
		(layer "F.Cu")
		(net "ISENSE_PVCCIN_CPU0_PH1_IMON")
	)
	(segment
		(start 189.738 -65.405)
		(end 189.63005 -65.29705)
		(width 0.127)
		(layer "F.Cu")
		(net "ISENSE_PVCCIN_CPU0_PH1_IMON")
	)
	(via
		(at 190.1698 -65.405)
		(size 0.508)
		(drill 0.254)
		(layers "F.Cu" "B.Cu")
		(net "ISENSE_PVCCIN_CPU0_PH1_IMON")
	)
	(via
		(at 194.339464 -54.994048)
		(size 0.508)
		(drill 0.254)
		(layers "F.Cu" "B.Cu")
		(net "ISENSE_PVCCIN_CPU0_PH1_IMON")
	)
	(segment
		(start 195.3768 -55.266844)
		(end 195.3768 -57.40146)
		(width 0.127)
		(layer "In11.Cu")
		(net "ISENSE_PVCCIN_CPU0_PH1_IMON")
	)
	(segment
		(start 192.441068 -57.8485)
		(end 191.803782 -58.485786)
		(width 0.127)
		(layer "In11.Cu")
		(net "ISENSE_PVCCIN_CPU0_PH1_IMON")
	)
	(segment
		(start 194.90182 -54.791864)
		(end 195.3768 -55.266844)
		(width 0.127)
		(layer "In11.Cu")
		(net "ISENSE_PVCCIN_CPU0_PH1_IMON")
	)
	(segment
		(start 194.541648 -54.791864)
		(end 194.90182 -54.791864)
		(width 0.127)
		(layer "In11.Cu")
		(net "ISENSE_PVCCIN_CPU0_PH1_IMON")
	)
	(segment
		(start 189.738 -64.9732)
		(end 190.1698 -65.405)
		(width 0.127)
		(layer "In11.Cu")
		(net "ISENSE_PVCCIN_CPU0_PH1_IMON")
	)
	(segment
		(start 194.339464 -54.994048)
		(end 194.541648 -54.791864)
		(width 0.127)
		(layer "In11.Cu")
		(net "ISENSE_PVCCIN_CPU0_PH1_IMON")
	)
	(segment
		(start 189.738 -63.994792)
		(end 189.738 -64.9732)
		(width 0.127)
		(layer "In11.Cu")
		(net "ISENSE_PVCCIN_CPU0_PH1_IMON")
	)
	(segment
		(start 194.92976 -57.8485)
		(end 192.441068 -57.8485)
		(width 0.127)
		(layer "In11.Cu")
		(net "ISENSE_PVCCIN_CPU0_PH1_IMON")
	)
	(segment
		(start 191.803782 -61.92901)
		(end 189.738 -63.994792)
		(width 0.127)
		(layer "In11.Cu")
		(net "ISENSE_PVCCIN_CPU0_PH1_IMON")
	)
	(segment
		(start 191.803782 -58.485786)
		(end 191.803782 -61.92901)
		(width 0.127)
		(layer "In11.Cu")
		(net "ISENSE_PVCCIN_CPU0_PH1_IMON")
	)
	(segment
		(start 195.3768 -57.40146)
		(end 194.92976 -57.8485)
		(width 0.127)
		(layer "In11.Cu")
		(net "ISENSE_PVCCIN_CPU0_PH1_IMON")
	)
	(segment
		(start 422.275 -45.974254)
		(end 421.123364 -44.822618)
		(width 0.10795)
		(layer "F.Cu")
		(net "IRQ_SML1_PMBUS_ALERT_N")
	)
	(segment
		(start 423.249598 -50.165)
		(end 422.239948 -50.165)
		(width 0.10795)
		(layer "F.Cu")
		(net "IRQ_SML1_PMBUS_ALERT_N")
	)
	(segment
		(start 421.947594 -46.69155)
		(end 422.275 -46.364144)
		(width 0.10795)
		(layer "F.Cu")
		(net "IRQ_SML1_PMBUS_ALERT_N")
	)
	(segment
		(start 417.703 -83.439)
		(end 417.703 -82.55)
		(width 0.10795)
		(layer "F.Cu")
		(net "IRQ_SML1_PMBUS_ALERT_N")
	)
	(segment
		(start 418.338 -82.931)
		(end 417.957 -82.55)
		(width 0.10795)
		(layer "F.Cu")
		(net "IRQ_SML1_PMBUS_ALERT_N")
	)
	(segment
		(start 425.07662 -51.992022)
		(end 424.02887 -50.944272)
		(width 0.10795)
		(layer "F.Cu")
		(net "IRQ_SML1_PMBUS_ALERT_N")
	)
	(segment
		(start 421.947594 -47.346616)
		(end 421.947594 -46.69155)
		(width 0.10795)
		(layer "F.Cu")
		(net "IRQ_SML1_PMBUS_ALERT_N")
	)
	(segment
		(start 414.8836 -94.7166)
		(end 414.8836 -94.7674)
		(width 0.10795)
		(layer "F.Cu")
		(net "IRQ_SML1_PMBUS_ALERT_N")
	)
	(segment
		(start 418.973 -82.931)
		(end 419.885114 -82.931)
		(width 0.10795)
		(layer "F.Cu")
		(net "IRQ_SML1_PMBUS_ALERT_N")
	)
	(segment
		(start 424.02887 -50.944272)
		(end 423.249598 -50.165)
		(width 0.10795)
		(layer "F.Cu")
		(net "IRQ_SML1_PMBUS_ALERT_N")
	)
	(segment
		(start 422.275 -46.364144)
		(end 422.275 -45.974254)
		(width 0.10795)
		(layer "F.Cu")
		(net "IRQ_SML1_PMBUS_ALERT_N")
	)
	(segment
		(start 18.3134 -80.8609)
		(end 17.9832 -80.5307)
		(width 0.10795)
		(layer "F.Cu")
		(net "IRQ_SML1_PMBUS_ALERT_N")
	)
	(segment
		(start 425.07662 -53.333396)
		(end 425.07662 -51.992022)
		(width 0.10795)
		(layer "F.Cu")
		(net "IRQ_SML1_PMBUS_ALERT_N")
	)
	(segment
		(start 18.3134 -81.7372)
		(end 18.3134 -80.8609)
		(width 0.10795)
		(layer "F.Cu")
		(net "IRQ_SML1_PMBUS_ALERT_N")
	)
	(segment
		(start 421.123364 -42.96791)
		(end 420.69004 -42.534586)
		(width 0.10795)
		(layer "F.Cu")
		(net "IRQ_SML1_PMBUS_ALERT_N")
	)
	(segment
		(start 422.131998 -47.53102)
		(end 421.947594 -47.346616)
		(width 0.10795)
		(layer "F.Cu")
		(net "IRQ_SML1_PMBUS_ALERT_N")
	)
	(segment
		(start 422.131998 -50.05705)
		(end 422.131998 -47.53102)
		(width 0.10795)
		(layer "F.Cu")
		(net "IRQ_SML1_PMBUS_ALERT_N")
	)
	(segment
		(start 418.973 -82.931)
		(end 418.338 -82.931)
		(width 0.10795)
		(layer "F.Cu")
		(net "IRQ_SML1_PMBUS_ALERT_N")
	)
	(segment
		(start 417.957 -82.55)
		(end 417.703 -82.55)
		(width 0.10795)
		(layer "F.Cu")
		(net "IRQ_SML1_PMBUS_ALERT_N")
	)
	(segment
		(start 422.239948 -50.165)
		(end 422.131998 -50.05705)
		(width 0.10795)
		(layer "F.Cu")
		(net "IRQ_SML1_PMBUS_ALERT_N")
	)
	(segment
		(start 414.8836 -94.7674)
		(end 414.2486 -95.4024)
		(width 0.10795)
		(layer "F.Cu")
		(net "IRQ_SML1_PMBUS_ALERT_N")
	)
	(segment
		(start 421.123364 -44.822618)
		(end 421.123364 -42.96791)
		(width 0.10795)
		(layer "F.Cu")
		(net "IRQ_SML1_PMBUS_ALERT_N")
	)
	(via
		(at 341.569294 -126.563628)
		(size 0.508)
		(drill 0.254)
		(layers "F.Cu" "B.Cu")
		(net "IRQ_SML1_PMBUS_ALERT_N")
	)
	(via
		(at 425.07662 -53.333396)
		(size 0.508)
		(drill 0.254)
		(layers "F.Cu" "B.Cu")
		(net "IRQ_SML1_PMBUS_ALERT_N")
	)
	(via
		(at 424.02887 -50.944272)
		(size 0.762)
		(drill 0.381)
		(layers "F.Cu" "B.Cu")
		(net "IRQ_SML1_PMBUS_ALERT_N")
	)
	(via
		(at 414.2486 -95.4024)
		(size 0.508)
		(drill 0.254)
		(layers "F.Cu" "B.Cu")
		(net "IRQ_SML1_PMBUS_ALERT_N")
	)
	(via
		(at 18.3134 -81.7372)
		(size 0.508)
		(drill 0.254)
		(layers "F.Cu" "B.Cu")
		(net "IRQ_SML1_PMBUS_ALERT_N")
	)
	(via
		(at 419.885114 -82.931)
		(size 0.508)
		(drill 0.254)
		(layers "F.Cu" "B.Cu")
		(net "IRQ_SML1_PMBUS_ALERT_N")
	)
	(via
		(at 368.190272 -123.768104)
		(size 0.508)
		(drill 0.254)
		(layers "F.Cu" "B.Cu")
		(net "IRQ_SML1_PMBUS_ALERT_N")
	)
	(via
		(at 463.3468 -44.9326)
		(size 0.508)
		(drill 0.254)
		(layers "F.Cu" "B.Cu")
		(net "IRQ_SML1_PMBUS_ALERT_N")
	)
	(via
		(at 476.055944 -54.3052)
		(size 0.508)
		(drill 0.254)
		(layers "F.Cu" "B.Cu")
		(net "IRQ_SML1_PMBUS_ALERT_N")
	)
	(segment
		(start 345.83878 -127.148844)
		(end 348.76486 -127.148844)
		(width 0.089408)
		(layer "In2.Cu")
		(net "IRQ_SML1_PMBUS_ALERT_N")
	)
	(segment
		(start 341.569294 -126.563628)
		(end 341.615522 -126.5174)
		(width 0.089408)
		(layer "In2.Cu")
		(net "IRQ_SML1_PMBUS_ALERT_N")
	)
	(segment
		(start 345.207336 -126.5174)
		(end 345.83878 -127.148844)
		(width 0.089408)
		(layer "In2.Cu")
		(net "IRQ_SML1_PMBUS_ALERT_N")
	)
	(segment
		(start 348.76486 -127.148844)
		(end 349.061024 -127.445008)
		(width 0.089408)
		(layer "In2.Cu")
		(net "IRQ_SML1_PMBUS_ALERT_N")
	)
	(segment
		(start 368.270536 -123.848368)
		(end 368.190272 -123.768104)
		(width 0.089408)
		(layer "In2.Cu")
		(net "IRQ_SML1_PMBUS_ALERT_N")
	)
	(segment
		(start 349.061024 -127.445008)
		(end 354.419916 -127.445008)
		(width 0.089408)
		(layer "In2.Cu")
		(net "IRQ_SML1_PMBUS_ALERT_N")
	)
	(segment
		(start 365.723424 -127.315976)
		(end 368.270536 -124.768864)
		(width 0.089408)
		(layer "In2.Cu")
		(net "IRQ_SML1_PMBUS_ALERT_N")
	)
	(segment
		(start 368.270536 -124.768864)
		(end 368.270536 -123.848368)
		(width 0.089408)
		(layer "In2.Cu")
		(net "IRQ_SML1_PMBUS_ALERT_N")
	)
	(segment
		(start 354.419916 -127.445008)
		(end 354.548948 -127.315976)
		(width 0.089408)
		(layer "In2.Cu")
		(net "IRQ_SML1_PMBUS_ALERT_N")
	)
	(segment
		(start 354.548948 -127.315976)
		(end 365.723424 -127.315976)
		(width 0.089408)
		(layer "In2.Cu")
		(net "IRQ_SML1_PMBUS_ALERT_N")
	)
	(segment
		(start 341.615522 -126.5174)
		(end 345.207336 -126.5174)
		(width 0.089408)
		(layer "In2.Cu")
		(net "IRQ_SML1_PMBUS_ALERT_N")
	)
	(segment
		(start 368.270536 -123.88596)
		(end 368.270536 -123.848368)
		(width 0.089408)
		(layer "In4.Cu")
		(net "IRQ_SML1_PMBUS_ALERT_N")
	)
	(segment
		(start 476.381826 -61.51626)
		(end 476.381826 -54.631082)
		(width 0.089408)
		(layer "In4.Cu")
		(net "IRQ_SML1_PMBUS_ALERT_N")
	)
	(segment
		(start 419.885114 -82.931)
		(end 420.503096 -82.313018)
		(width 0.089408)
		(layer "In4.Cu")
		(net "IRQ_SML1_PMBUS_ALERT_N")
	)
	(segment
		(start 420.37127 -83.417156)
		(end 420.37127 -95.88119)
		(width 0.089408)
		(layer "In4.Cu")
		(net "IRQ_SML1_PMBUS_ALERT_N")
	)
	(segment
		(start 472.873324 -62.719204)
		(end 475.178882 -62.719204)
		(width 0.089408)
		(layer "In4.Cu")
		(net "IRQ_SML1_PMBUS_ALERT_N")
	)
	(segment
		(start 465.836 -64.059054)
		(end 465.836 -57.98185)
		(width 0.089408)
		(layer "In4.Cu")
		(net "IRQ_SML1_PMBUS_ALERT_N")
	)
	(segment
		(start 411.802834 -119.888)
		(end 407.3144 -119.888)
		(width 0.089408)
		(layer "In4.Cu")
		(net "IRQ_SML1_PMBUS_ALERT_N")
	)
	(segment
		(start 378.958094 -125.185678)
		(end 377.567952 -125.185678)
		(width 0.089408)
		(layer "In4.Cu")
		(net "IRQ_SML1_PMBUS_ALERT_N")
	)
	(segment
		(start 469.149938 -56.504586)
		(end 469.315546 -56.670194)
		(width 0.089408)
		(layer "In4.Cu")
		(net "IRQ_SML1_PMBUS_ALERT_N")
	)
	(segment
		(start 469.315546 -59.161426)
		(end 472.873324 -62.719204)
		(width 0.089408)
		(layer "In4.Cu")
		(net "IRQ_SML1_PMBUS_ALERT_N")
	)
	(segment
		(start 420.503096 -82.313018)
		(end 420.503096 -80.854296)
		(width 0.089408)
		(layer "In4.Cu")
		(net "IRQ_SML1_PMBUS_ALERT_N")
	)
	(segment
		(start 412.62173 -120.706896)
		(end 411.802834 -119.888)
		(width 0.089408)
		(layer "In4.Cu")
		(net "IRQ_SML1_PMBUS_ALERT_N")
	)
	(segment
		(start 407.3144 -119.888)
		(end 403.4536 -123.7488)
		(width 0.089408)
		(layer "In4.Cu")
		(net "IRQ_SML1_PMBUS_ALERT_N")
	)
	(segment
		(start 379.197108 -124.946918)
		(end 379.196854 -124.946918)
		(width 0.089408)
		(layer "In4.Cu")
		(net "IRQ_SML1_PMBUS_ALERT_N")
	)
	(segment
		(start 422.3766 -101.6508)
		(end 422.3766 -102.895146)
		(width 0.089408)
		(layer "In4.Cu")
		(net "IRQ_SML1_PMBUS_ALERT_N")
	)
	(segment
		(start 414.725612 -117.444012)
		(end 415.6202 -118.3386)
		(width 0.089408)
		(layer "In4.Cu")
		(net "IRQ_SML1_PMBUS_ALERT_N")
	)
	(segment
		(start 421.4368 -100.2411)
		(end 416.5981 -95.4024)
		(width 0.089408)
		(layer "In4.Cu")
		(net "IRQ_SML1_PMBUS_ALERT_N")
	)
	(segment
		(start 422.3766 -97.88652)
		(end 422.3766 -101.1936)
		(width 0.089408)
		(layer "In4.Cu")
		(net "IRQ_SML1_PMBUS_ALERT_N")
	)
	(segment
		(start 465.836 -57.98185)
		(end 467.313264 -56.504586)
		(width 0.089408)
		(layer "In4.Cu")
		(net "IRQ_SML1_PMBUS_ALERT_N")
	)
	(segment
		(start 377.567952 -125.185678)
		(end 377.329192 -124.946918)
		(width 0.089408)
		(layer "In4.Cu")
		(net "IRQ_SML1_PMBUS_ALERT_N")
	)
	(segment
		(start 376.384312 -124.946918)
		(end 375.3358 -123.898406)
		(width 0.089408)
		(layer "In4.Cu")
		(net "IRQ_SML1_PMBUS_ALERT_N")
	)
	(segment
		(start 416.5981 -95.4024)
		(end 414.2486 -95.4024)
		(width 0.089408)
		(layer "In4.Cu")
		(net "IRQ_SML1_PMBUS_ALERT_N")
	)
	(segment
		(start 422.153588 -65.44183)
		(end 423.435526 -64.159892)
		(width 0.089408)
		(layer "In4.Cu")
		(net "IRQ_SML1_PMBUS_ALERT_N")
	)
	(segment
		(start 419.7604 -76.202286)
		(end 422.153588 -73.809098)
		(width 0.089408)
		(layer "In4.Cu")
		(net "IRQ_SML1_PMBUS_ALERT_N")
	)
	(segment
		(start 465.071968 -64.823086)
		(end 465.836 -64.059054)
		(width 0.089408)
		(layer "In4.Cu")
		(net "IRQ_SML1_PMBUS_ALERT_N")
	)
	(segment
		(start 415.078164 -104.201468)
		(end 414.725612 -104.55402)
		(width 0.089408)
		(layer "In4.Cu")
		(net "IRQ_SML1_PMBUS_ALERT_N")
	)
	(segment
		(start 403.4536 -123.7488)
		(end 401.705826 -123.7488)
		(width 0.089408)
		(layer "In4.Cu")
		(net "IRQ_SML1_PMBUS_ALERT_N")
	)
	(segment
		(start 379.582172 -124.561854)
		(end 379.197108 -124.946918)
		(width 0.089408)
		(layer "In4.Cu")
		(net "IRQ_SML1_PMBUS_ALERT_N")
	)
	(segment
		(start 422.3766 -102.895146)
		(end 421.070278 -104.201468)
		(width 0.089408)
		(layer "In4.Cu")
		(net "IRQ_SML1_PMBUS_ALERT_N")
	)
	(segment
		(start 372.503192 -123.898406)
		(end 371.45468 -124.946918)
		(width 0.089408)
		(layer "In4.Cu")
		(net "IRQ_SML1_PMBUS_ALERT_N")
	)
	(segment
		(start 425.170854 -64.159892)
		(end 425.834048 -64.823086)
		(width 0.089408)
		(layer "In4.Cu")
		(net "IRQ_SML1_PMBUS_ALERT_N")
	)
	(segment
		(start 419.7604 -80.1116)
		(end 419.7604 -76.202286)
		(width 0.089408)
		(layer "In4.Cu")
		(net "IRQ_SML1_PMBUS_ALERT_N")
	)
	(segment
		(start 422.148 -101.4222)
		(end 421.77208 -101.4222)
		(width 0.089408)
		(layer "In4.Cu")
		(net "IRQ_SML1_PMBUS_ALERT_N")
	)
	(segment
		(start 419.885114 -82.931)
		(end 420.37127 -83.417156)
		(width 0.089408)
		(layer "In4.Cu")
		(net "IRQ_SML1_PMBUS_ALERT_N")
	)
	(segment
		(start 415.029904 -120.706896)
		(end 412.62173 -120.706896)
		(width 0.089408)
		(layer "In4.Cu")
		(net "IRQ_SML1_PMBUS_ALERT_N")
	)
	(segment
		(start 377.329192 -124.946918)
		(end 376.384312 -124.946918)
		(width 0.089408)
		(layer "In4.Cu")
		(net "IRQ_SML1_PMBUS_ALERT_N")
	)
	(segment
		(start 421.77208 -101.4222)
		(end 421.4368 -101.08692)
		(width 0.089408)
		(layer "In4.Cu")
		(net "IRQ_SML1_PMBUS_ALERT_N")
	)
	(segment
		(start 422.3766 -101.1936)
		(end 422.148 -101.4222)
		(width 0.089408)
		(layer "In4.Cu")
		(net "IRQ_SML1_PMBUS_ALERT_N")
	)
	(segment
		(start 420.37127 -95.88119)
		(end 422.3766 -97.88652)
		(width 0.089408)
		(layer "In4.Cu")
		(net "IRQ_SML1_PMBUS_ALERT_N")
	)
	(segment
		(start 475.178882 -62.719204)
		(end 476.381826 -61.51626)
		(width 0.089408)
		(layer "In4.Cu")
		(net "IRQ_SML1_PMBUS_ALERT_N")
	)
	(segment
		(start 425.834048 -64.823086)
		(end 465.071968 -64.823086)
		(width 0.089408)
		(layer "In4.Cu")
		(net "IRQ_SML1_PMBUS_ALERT_N")
	)
	(segment
		(start 415.6202 -120.1166)
		(end 415.029904 -120.706896)
		(width 0.089408)
		(layer "In4.Cu")
		(net "IRQ_SML1_PMBUS_ALERT_N")
	)
	(segment
		(start 401.705826 -123.7488)
		(end 400.892772 -124.561854)
		(width 0.089408)
		(layer "In4.Cu")
		(net "IRQ_SML1_PMBUS_ALERT_N")
	)
	(segment
		(start 423.435526 -64.159892)
		(end 425.170854 -64.159892)
		(width 0.089408)
		(layer "In4.Cu")
		(net "IRQ_SML1_PMBUS_ALERT_N")
	)
	(segment
		(start 415.6202 -118.3386)
		(end 415.6202 -120.1166)
		(width 0.089408)
		(layer "In4.Cu")
		(net "IRQ_SML1_PMBUS_ALERT_N")
	)
	(segment
		(start 375.3358 -123.898406)
		(end 372.503192 -123.898406)
		(width 0.089408)
		(layer "In4.Cu")
		(net "IRQ_SML1_PMBUS_ALERT_N")
	)
	(segment
		(start 421.070278 -104.201468)
		(end 415.078164 -104.201468)
		(width 0.089408)
		(layer "In4.Cu")
		(net "IRQ_SML1_PMBUS_ALERT_N")
	)
	(segment
		(start 422.153588 -73.809098)
		(end 422.153588 -65.44183)
		(width 0.089408)
		(layer "In4.Cu")
		(net "IRQ_SML1_PMBUS_ALERT_N")
	)
	(segment
		(start 467.313264 -56.504586)
		(end 469.149938 -56.504586)
		(width 0.089408)
		(layer "In4.Cu")
		(net "IRQ_SML1_PMBUS_ALERT_N")
	)
	(segment
		(start 368.270536 -123.848368)
		(end 368.190272 -123.768104)
		(width 0.089408)
		(layer "In4.Cu")
		(net "IRQ_SML1_PMBUS_ALERT_N")
	)
	(segment
		(start 400.892772 -124.561854)
		(end 379.582172 -124.561854)
		(width 0.089408)
		(layer "In4.Cu")
		(net "IRQ_SML1_PMBUS_ALERT_N")
	)
	(segment
		(start 476.381826 -54.631082)
		(end 476.055944 -54.3052)
		(width 0.089408)
		(layer "In4.Cu")
		(net "IRQ_SML1_PMBUS_ALERT_N")
	)
	(segment
		(start 420.503096 -80.854296)
		(end 419.7604 -80.1116)
		(width 0.089408)
		(layer "In4.Cu")
		(net "IRQ_SML1_PMBUS_ALERT_N")
	)
	(segment
		(start 421.4368 -101.08692)
		(end 421.4368 -100.2411)
		(width 0.089408)
		(layer "In4.Cu")
		(net "IRQ_SML1_PMBUS_ALERT_N")
	)
	(segment
		(start 414.725612 -104.55402)
		(end 414.725612 -117.444012)
		(width 0.089408)
		(layer "In4.Cu")
		(net "IRQ_SML1_PMBUS_ALERT_N")
	)
	(segment
		(start 422.148 -101.4222)
		(end 422.3766 -101.6508)
		(width 0.089408)
		(layer "In4.Cu")
		(net "IRQ_SML1_PMBUS_ALERT_N")
	)
	(segment
		(start 371.45468 -124.946918)
		(end 369.331494 -124.946918)
		(width 0.089408)
		(layer "In4.Cu")
		(net "IRQ_SML1_PMBUS_ALERT_N")
	)
	(segment
		(start 369.331494 -124.946918)
		(end 368.270536 -123.88596)
		(width 0.089408)
		(layer "In4.Cu")
		(net "IRQ_SML1_PMBUS_ALERT_N")
	)
	(segment
		(start 469.315546 -56.670194)
		(end 469.315546 -59.161426)
		(width 0.089408)
		(layer "In4.Cu")
		(net "IRQ_SML1_PMBUS_ALERT_N")
	)
	(segment
		(start 379.196854 -124.946918)
		(end 378.958094 -125.185678)
		(width 0.089408)
		(layer "In4.Cu")
		(net "IRQ_SML1_PMBUS_ALERT_N")
	)
	(segment
		(start 288.7726 -140.417042)
		(end 288.7726 -140.611352)
		(width 0.089408)
		(layer "In9.Cu")
		(net "IRQ_SML1_PMBUS_ALERT_N")
	)
	(segment
		(start 233.553 -140.386562)
		(end 233.553 -140.580872)
		(width 0.089408)
		(layer "In9.Cu")
		(net "IRQ_SML1_PMBUS_ALERT_N")
	)
	(segment
		(start 331.774546 -135.069326)
		(end 331.774546 -135.790686)
		(width 0.089408)
		(layer "In9.Cu")
		(net "IRQ_SML1_PMBUS_ALERT_N")
	)
	(segment
		(start 435.795166 -51.714908)
		(end 435.757828 -51.714908)
		(width 0.089408)
		(layer "In9.Cu")
		(net "IRQ_SML1_PMBUS_ALERT_N")
	)
	(segment
		(start 24.069548 -123.704604)
		(end 22.23643 -121.871486)
		(width 0.089408)
		(layer "In9.Cu")
		(net "IRQ_SML1_PMBUS_ALERT_N")
	)
	(segment
		(start 233.553 -140.580872)
		(end 232.519474 -141.614398)
		(width 0.089408)
		(layer "In9.Cu")
		(net "IRQ_SML1_PMBUS_ALERT_N")
	)
	(segment
		(start 331.774546 -135.790686)
		(end 329.66152 -137.903712)
		(width 0.089408)
		(layer "In9.Cu")
		(net "IRQ_SML1_PMBUS_ALERT_N")
	)
	(segment
		(start 463.3468 -44.9326)
		(end 463.3468 -45.9232)
		(width 0.089408)
		(layer "In9.Cu")
		(net "IRQ_SML1_PMBUS_ALERT_N")
	)
	(segment
		(start 288.7726 -140.611352)
		(end 287.175448 -142.208504)
		(width 0.089408)
		(layer "In9.Cu")
		(net "IRQ_SML1_PMBUS_ALERT_N")
	)
	(segment
		(start 14.835632 -84.173568)
		(end 14.835632 -82.816446)
		(width 0.089408)
		(layer "In9.Cu")
		(net "IRQ_SML1_PMBUS_ALERT_N")
	)
	(segment
		(start 329.66152 -137.903712)
		(end 326.2376 -137.903712)
		(width 0.089408)
		(layer "In9.Cu")
		(net "IRQ_SML1_PMBUS_ALERT_N")
	)
	(segment
		(start 18.042128 -109.306868)
		(end 18.042128 -102.395782)
		(width 0.089408)
		(layer "In9.Cu")
		(net "IRQ_SML1_PMBUS_ALERT_N")
	)
	(segment
		(start 426.104812 -53.333396)
		(end 425.07662 -53.333396)
		(width 0.089408)
		(layer "In9.Cu")
		(net "IRQ_SML1_PMBUS_ALERT_N")
	)
	(segment
		(start 167.157654 -142.506192)
		(end 166.553134 -141.901672)
		(width 0.089408)
		(layer "In9.Cu")
		(net "IRQ_SML1_PMBUS_ALERT_N")
	)
	(segment
		(start 334.609694 -132.234178)
		(end 331.774546 -135.069326)
		(width 0.089408)
		(layer "In9.Cu")
		(net "IRQ_SML1_PMBUS_ALERT_N")
	)
	(segment
		(start 235.173774 -138.765788)
		(end 233.553 -140.386562)
		(width 0.089408)
		(layer "In9.Cu")
		(net "IRQ_SML1_PMBUS_ALERT_N")
	)
	(segment
		(start 18.042128 -102.395782)
		(end 17.353026 -101.70668)
		(width 0.089408)
		(layer "In9.Cu")
		(net "IRQ_SML1_PMBUS_ALERT_N")
	)
	(segment
		(start 341.569294 -126.563628)
		(end 341.569294 -127.213106)
		(width 0.089408)
		(layer "In9.Cu")
		(net "IRQ_SML1_PMBUS_ALERT_N")
	)
	(segment
		(start 189.088776 -142.244826)
		(end 188.82741 -142.506192)
		(width 0.089408)
		(layer "In9.Cu")
		(net "IRQ_SML1_PMBUS_ALERT_N")
	)
	(segment
		(start 262.12165 -142.208504)
		(end 258.678934 -138.765788)
		(width 0.089408)
		(layer "In9.Cu")
		(net "IRQ_SML1_PMBUS_ALERT_N")
	)
	(segment
		(start 323.7738 -138.7602)
		(end 290.429442 -138.7602)
		(width 0.089408)
		(layer "In9.Cu")
		(net "IRQ_SML1_PMBUS_ALERT_N")
	)
	(segment
		(start 11.9888 -89.602056)
		(end 12.0142 -89.576656)
		(width 0.089408)
		(layer "In9.Cu")
		(net "IRQ_SML1_PMBUS_ALERT_N")
	)
	(segment
		(start 325.12 -137.414)
		(end 323.7738 -138.7602)
		(width 0.089408)
		(layer "In9.Cu")
		(net "IRQ_SML1_PMBUS_ALERT_N")
	)
	(segment
		(start 147.53844 -123.704604)
		(end 24.069548 -123.704604)
		(width 0.089408)
		(layer "In9.Cu")
		(net "IRQ_SML1_PMBUS_ALERT_N")
	)
	(segment
		(start 439.046874 -48.4632)
		(end 435.795166 -51.714908)
		(width 0.089408)
		(layer "In9.Cu")
		(net "IRQ_SML1_PMBUS_ALERT_N")
	)
	(segment
		(start 17.963896 -81.387696)
		(end 18.3134 -81.7372)
		(width 0.089408)
		(layer "In9.Cu")
		(net "IRQ_SML1_PMBUS_ALERT_N")
	)
	(segment
		(start 159.931862 -130.574542)
		(end 157.633416 -128.276096)
		(width 0.089408)
		(layer "In9.Cu")
		(net "IRQ_SML1_PMBUS_ALERT_N")
	)
	(segment
		(start 435.704234 -51.768502)
		(end 427.669706 -51.768502)
		(width 0.089408)
		(layer "In9.Cu")
		(net "IRQ_SML1_PMBUS_ALERT_N")
	)
	(segment
		(start 12.693396 -86.925404)
		(end 12.9032 -86.7156)
		(width 0.089408)
		(layer "In9.Cu")
		(net "IRQ_SML1_PMBUS_ALERT_N")
	)
	(segment
		(start 159.931608 -140.549376)
		(end 159.931608 -130.732784)
		(width 0.089408)
		(layer "In9.Cu")
		(net "IRQ_SML1_PMBUS_ALERT_N")
	)
	(segment
		(start 232.519474 -141.614398)
		(end 192.84315 -141.614398)
		(width 0.089408)
		(layer "In9.Cu")
		(net "IRQ_SML1_PMBUS_ALERT_N")
	)
	(segment
		(start 188.82741 -142.506192)
		(end 167.157654 -142.506192)
		(width 0.089408)
		(layer "In9.Cu")
		(net "IRQ_SML1_PMBUS_ALERT_N")
	)
	(segment
		(start 341.569294 -127.213106)
		(end 336.548222 -132.234178)
		(width 0.089408)
		(layer "In9.Cu")
		(net "IRQ_SML1_PMBUS_ALERT_N")
	)
	(segment
		(start 161.283904 -141.901672)
		(end 159.931608 -140.549376)
		(width 0.089408)
		(layer "In9.Cu")
		(net "IRQ_SML1_PMBUS_ALERT_N")
	)
	(segment
		(start 13.12418 -85.23732)
		(end 13.77188 -85.23732)
		(width 0.089408)
		(layer "In9.Cu")
		(net "IRQ_SML1_PMBUS_ALERT_N")
	)
	(segment
		(start 166.553134 -141.901672)
		(end 161.283904 -141.901672)
		(width 0.089408)
		(layer "In9.Cu")
		(net "IRQ_SML1_PMBUS_ALERT_N")
	)
	(segment
		(start 16.264382 -81.387696)
		(end 17.963896 -81.387696)
		(width 0.089408)
		(layer "In9.Cu")
		(net "IRQ_SML1_PMBUS_ALERT_N")
	)
	(segment
		(start 17.353026 -101.70668)
		(end 15.907258 -101.70668)
		(width 0.089408)
		(layer "In9.Cu")
		(net "IRQ_SML1_PMBUS_ALERT_N")
	)
	(segment
		(start 290.429442 -138.7602)
		(end 288.7726 -140.417042)
		(width 0.089408)
		(layer "In9.Cu")
		(net "IRQ_SML1_PMBUS_ALERT_N")
	)
	(segment
		(start 152.109932 -128.276096)
		(end 147.53844 -123.704604)
		(width 0.089408)
		(layer "In9.Cu")
		(net "IRQ_SML1_PMBUS_ALERT_N")
	)
	(segment
		(start 11.593068 -90.17)
		(end 11.9888 -89.774268)
		(width 0.089408)
		(layer "In9.Cu")
		(net "IRQ_SML1_PMBUS_ALERT_N")
	)
	(segment
		(start 325.747888 -137.414)
		(end 325.12 -137.414)
		(width 0.089408)
		(layer "In9.Cu")
		(net "IRQ_SML1_PMBUS_ALERT_N")
	)
	(segment
		(start 12.28725 -86.925404)
		(end 12.693396 -86.925404)
		(width 0.089408)
		(layer "In9.Cu")
		(net "IRQ_SML1_PMBUS_ALERT_N")
	)
	(segment
		(start 463.3468 -45.9232)
		(end 460.8068 -48.4632)
		(width 0.089408)
		(layer "In9.Cu")
		(net "IRQ_SML1_PMBUS_ALERT_N")
	)
	(segment
		(start 11.593068 -93.297248)
		(end 11.593068 -90.17)
		(width 0.089408)
		(layer "In9.Cu")
		(net "IRQ_SML1_PMBUS_ALERT_N")
	)
	(segment
		(start 13.77188 -85.23732)
		(end 14.835632 -84.173568)
		(width 0.089408)
		(layer "In9.Cu")
		(net "IRQ_SML1_PMBUS_ALERT_N")
	)
	(segment
		(start 22.23643 -121.871486)
		(end 22.23643 -113.50117)
		(width 0.089408)
		(layer "In9.Cu")
		(net "IRQ_SML1_PMBUS_ALERT_N")
	)
	(segment
		(start 460.8068 -48.4632)
		(end 439.046874 -48.4632)
		(width 0.089408)
		(layer "In9.Cu")
		(net "IRQ_SML1_PMBUS_ALERT_N")
	)
	(segment
		(start 435.757828 -51.714908)
		(end 435.704234 -51.768502)
		(width 0.089408)
		(layer "In9.Cu")
		(net "IRQ_SML1_PMBUS_ALERT_N")
	)
	(segment
		(start 427.669706 -51.768502)
		(end 426.104812 -53.333396)
		(width 0.089408)
		(layer "In9.Cu")
		(net "IRQ_SML1_PMBUS_ALERT_N")
	)
	(segment
		(start 258.678934 -138.765788)
		(end 235.173774 -138.765788)
		(width 0.089408)
		(layer "In9.Cu")
		(net "IRQ_SML1_PMBUS_ALERT_N")
	)
	(segment
		(start 157.633416 -128.276096)
		(end 152.109932 -128.276096)
		(width 0.089408)
		(layer "In9.Cu")
		(net "IRQ_SML1_PMBUS_ALERT_N")
	)
	(segment
		(start 12.0142 -87.198454)
		(end 12.28725 -86.925404)
		(width 0.089408)
		(layer "In9.Cu")
		(net "IRQ_SML1_PMBUS_ALERT_N")
	)
	(segment
		(start 14.835632 -82.816446)
		(end 16.264382 -81.387696)
		(width 0.089408)
		(layer "In9.Cu")
		(net "IRQ_SML1_PMBUS_ALERT_N")
	)
	(segment
		(start 12.442444 -94.146624)
		(end 11.593068 -93.297248)
		(width 0.089408)
		(layer "In9.Cu")
		(net "IRQ_SML1_PMBUS_ALERT_N")
	)
	(segment
		(start 192.212722 -142.244826)
		(end 189.088776 -142.244826)
		(width 0.089408)
		(layer "In9.Cu")
		(net "IRQ_SML1_PMBUS_ALERT_N")
	)
	(segment
		(start 11.9888 -89.774268)
		(end 11.9888 -89.602056)
		(width 0.089408)
		(layer "In9.Cu")
		(net "IRQ_SML1_PMBUS_ALERT_N")
	)
	(segment
		(start 326.2376 -137.903712)
		(end 325.747888 -137.414)
		(width 0.089408)
		(layer "In9.Cu")
		(net "IRQ_SML1_PMBUS_ALERT_N")
	)
	(segment
		(start 192.84315 -141.614398)
		(end 192.212722 -142.244826)
		(width 0.089408)
		(layer "In9.Cu")
		(net "IRQ_SML1_PMBUS_ALERT_N")
	)
	(segment
		(start 159.931608 -130.732784)
		(end 159.931862 -130.73253)
		(width 0.089408)
		(layer "In9.Cu")
		(net "IRQ_SML1_PMBUS_ALERT_N")
	)
	(segment
		(start 15.907258 -101.70668)
		(end 12.442444 -98.241866)
		(width 0.089408)
		(layer "In9.Cu")
		(net "IRQ_SML1_PMBUS_ALERT_N")
	)
	(segment
		(start 287.175448 -142.208504)
		(end 262.12165 -142.208504)
		(width 0.089408)
		(layer "In9.Cu")
		(net "IRQ_SML1_PMBUS_ALERT_N")
	)
	(segment
		(start 12.442444 -98.241866)
		(end 12.442444 -94.146624)
		(width 0.089408)
		(layer "In9.Cu")
		(net "IRQ_SML1_PMBUS_ALERT_N")
	)
	(segment
		(start 336.548222 -132.234178)
		(end 334.609694 -132.234178)
		(width 0.089408)
		(layer "In9.Cu")
		(net "IRQ_SML1_PMBUS_ALERT_N")
	)
	(segment
		(start 22.23643 -113.50117)
		(end 18.042128 -109.306868)
		(width 0.089408)
		(layer "In9.Cu")
		(net "IRQ_SML1_PMBUS_ALERT_N")
	)
	(segment
		(start 12.9032 -85.4583)
		(end 13.12418 -85.23732)
		(width 0.089408)
		(layer "In9.Cu")
		(net "IRQ_SML1_PMBUS_ALERT_N")
	)
	(segment
		(start 12.9032 -86.7156)
		(end 12.9032 -85.4583)
		(width 0.089408)
		(layer "In9.Cu")
		(net "IRQ_SML1_PMBUS_ALERT_N")
	)
	(segment
		(start 159.931862 -130.73253)
		(end 159.931862 -130.574542)
		(width 0.089408)
		(layer "In9.Cu")
		(net "IRQ_SML1_PMBUS_ALERT_N")
	)
	(segment
		(start 12.0142 -89.576656)
		(end 12.0142 -87.198454)
		(width 0.089408)
		(layer "In9.Cu")
		(net "IRQ_SML1_PMBUS_ALERT_N")
	)
	(segment
		(start 475.901512 -54.3052)
		(end 475.814136 -54.217824)
		(width 0.089408)
		(layer "In11.Cu")
		(net "IRQ_SML1_PMBUS_ALERT_N")
	)
	(segment
		(start 471.174064 -47.96028)
		(end 471.174064 -47.959264)
		(width 0.089408)
		(layer "In11.Cu")
		(net "IRQ_SML1_PMBUS_ALERT_N")
	)
	(segment
		(start 475.398846 -53.802534)
		(end 475.262702 -53.66639)
		(width 0.089408)
		(layer "In11.Cu")
		(net "IRQ_SML1_PMBUS_ALERT_N")
	)
	(segment
		(start 475.814136 -54.217824)
		(end 475.814136 -54.048406)
		(width 0.089408)
		(layer "In11.Cu")
		(net "IRQ_SML1_PMBUS_ALERT_N")
	)
	(segment
		(start 463.625692 -45.9867)
		(end 463.625692 -45.211492)
		(width 0.089408)
		(layer "In11.Cu")
		(net "IRQ_SML1_PMBUS_ALERT_N")
	)
	(segment
		(start 475.413832 -53.802534)
		(end 475.398846 -53.802534)
		(width 0.089408)
		(layer "In11.Cu")
		(net "IRQ_SML1_PMBUS_ALERT_N")
	)
	(segment
		(start 471.174064 -47.959264)
		(end 470.719658 -47.504858)
		(width 0.089408)
		(layer "In11.Cu")
		(net "IRQ_SML1_PMBUS_ALERT_N")
	)
	(segment
		(start 475.425262 -53.813964)
		(end 475.413832 -53.802534)
		(width 0.089408)
		(layer "In11.Cu")
		(net "IRQ_SML1_PMBUS_ALERT_N")
	)
	(segment
		(start 473.877386 -52.364894)
		(end 473.799408 -52.286916)
		(width 0.089408)
		(layer "In11.Cu")
		(net "IRQ_SML1_PMBUS_ALERT_N")
	)
	(segment
		(start 473.877386 -53.14696)
		(end 473.877386 -52.364894)
		(width 0.089408)
		(layer "In11.Cu")
		(net "IRQ_SML1_PMBUS_ALERT_N")
	)
	(segment
		(start 476.055944 -54.3052)
		(end 475.901512 -54.3052)
		(width 0.089408)
		(layer "In11.Cu")
		(net "IRQ_SML1_PMBUS_ALERT_N")
	)
	(segment
		(start 463.625692 -45.211492)
		(end 463.3468 -44.9326)
		(width 0.089408)
		(layer "In11.Cu")
		(net "IRQ_SML1_PMBUS_ALERT_N")
	)
	(segment
		(start 475.814136 -54.048406)
		(end 475.579694 -53.813964)
		(width 0.089408)
		(layer "In11.Cu")
		(net "IRQ_SML1_PMBUS_ALERT_N")
	)
	(segment
		(start 473.799408 -52.28463)
		(end 473.157296 -51.642518)
		(width 0.089408)
		(layer "In11.Cu")
		(net "IRQ_SML1_PMBUS_ALERT_N")
	)
	(segment
		(start 473.799408 -52.286916)
		(end 473.799408 -52.28463)
		(width 0.089408)
		(layer "In11.Cu")
		(net "IRQ_SML1_PMBUS_ALERT_N")
	)
	(segment
		(start 470.719658 -47.504858)
		(end 465.14385 -47.504858)
		(width 0.089408)
		(layer "In11.Cu")
		(net "IRQ_SML1_PMBUS_ALERT_N")
	)
	(segment
		(start 473.157296 -49.942496)
		(end 471.648536 -48.433736)
		(width 0.089408)
		(layer "In11.Cu")
		(net "IRQ_SML1_PMBUS_ALERT_N")
	)
	(segment
		(start 471.648536 -48.433736)
		(end 471.64752 -48.433736)
		(width 0.089408)
		(layer "In11.Cu")
		(net "IRQ_SML1_PMBUS_ALERT_N")
	)
	(segment
		(start 474.396816 -53.66639)
		(end 473.877386 -53.14696)
		(width 0.089408)
		(layer "In11.Cu")
		(net "IRQ_SML1_PMBUS_ALERT_N")
	)
	(segment
		(start 465.14385 -47.504858)
		(end 463.625692 -45.9867)
		(width 0.089408)
		(layer "In11.Cu")
		(net "IRQ_SML1_PMBUS_ALERT_N")
	)
	(segment
		(start 475.262702 -53.66639)
		(end 474.396816 -53.66639)
		(width 0.089408)
		(layer "In11.Cu")
		(net "IRQ_SML1_PMBUS_ALERT_N")
	)
	(segment
		(start 471.64752 -48.433736)
		(end 471.174064 -47.96028)
		(width 0.089408)
		(layer "In11.Cu")
		(net "IRQ_SML1_PMBUS_ALERT_N")
	)
	(segment
		(start 473.157296 -51.642518)
		(end 473.157296 -49.942496)
		(width 0.089408)
		(layer "In11.Cu")
		(net "IRQ_SML1_PMBUS_ALERT_N")
	)
	(segment
		(start 475.579694 -53.813964)
		(end 475.425262 -53.813964)
		(width 0.089408)
		(layer "In11.Cu")
		(net "IRQ_SML1_PMBUS_ALERT_N")
	)
	(segment
		(start 418.719 -60.2742)
		(end 423.942256 -55.050944)
		(width 0.10795)
		(layer "F.Cu")
		(net "IRQ_SML0_ALERT_N")
	)
	(segment
		(start 401.334986 -109.164374)
		(end 401.334732 -109.16412)
		(width 0.0889)
		(layer "F.Cu")
		(net "IRQ_SML0_ALERT_N")
	)
	(segment
		(start 402.65477 -109.348524)
		(end 401.828 -109.348524)
		(width 0.0889)
		(layer "F.Cu")
		(net "IRQ_SML0_ALERT_N")
	)
	(segment
		(start 407.001472 -111.05388)
		(end 406.739598 -110.792006)
		(width 0.10795)
		(layer "F.Cu")
		(net "IRQ_SML0_ALERT_N")
	)
	(segment
		(start 423.942256 -55.050944)
		(end 423.942256 -53.888132)
		(width 0.10795)
		(layer "F.Cu")
		(net "IRQ_SML0_ALERT_N")
	)
	(segment
		(start 423.595038 -53.540914)
		(end 421.248332 -53.540914)
		(width 0.10795)
		(layer "F.Cu")
		(net "IRQ_SML0_ALERT_N")
	)
	(segment
		(start 421.013636 -50.306986)
		(end 420.68369 -50.636932)
		(width 0.10795)
		(layer "F.Cu")
		(net "IRQ_SML0_ALERT_N")
	)
	(segment
		(start 400.925284 -108.935774)
		(end 400.545808 -108.935774)
		(width 0.0889)
		(layer "F.Cu")
		(net "IRQ_SML0_ALERT_N")
	)
	(segment
		(start 421.130984 -53.423566)
		(end 421.130984 -52.17668)
		(width 0.10795)
		(layer "F.Cu")
		(net "IRQ_SML0_ALERT_N")
	)
	(segment
		(start 409.5115 -110.617)
		(end 409.07462 -111.05388)
		(width 0.10795)
		(layer "F.Cu")
		(net "IRQ_SML0_ALERT_N")
	)
	(segment
		(start 422.216326 -50.53965)
		(end 421.983662 -50.306986)
		(width 0.10795)
		(layer "F.Cu")
		(net "IRQ_SML0_ALERT_N")
	)
	(segment
		(start 401.828 -109.348524)
		(end 401.64385 -109.164374)
		(width 0.0889)
		(layer "F.Cu")
		(net "IRQ_SML0_ALERT_N")
	)
	(segment
		(start 418.290248 -40.13454)
		(end 418.690298 -40.53459)
		(width 0.10795)
		(layer "F.Cu")
		(net "IRQ_SML0_ALERT_N")
	)
	(segment
		(start 421.983662 -50.306986)
		(end 421.013636 -50.306986)
		(width 0.10795)
		(layer "F.Cu")
		(net "IRQ_SML0_ALERT_N")
	)
	(segment
		(start 406.739598 -110.792006)
		(end 406.739598 -110.702598)
		(width 0.10795)
		(layer "F.Cu")
		(net "IRQ_SML0_ALERT_N")
	)
	(segment
		(start 417.453826 -59.518804)
		(end 417.453826 -59.687968)
		(width 0.10795)
		(layer "F.Cu")
		(net "IRQ_SML0_ALERT_N")
	)
	(segment
		(start 422.216326 -51.235864)
		(end 422.216326 -50.53965)
		(width 0.10795)
		(layer "F.Cu")
		(net "IRQ_SML0_ALERT_N")
	)
	(segment
		(start 403.377146 -109.198156)
		(end 402.805138 -109.198156)
		(width 0.0889)
		(layer "F.Cu")
		(net "IRQ_SML0_ALERT_N")
	)
	(segment
		(start 402.805138 -109.198156)
		(end 402.65477 -109.348524)
		(width 0.0889)
		(layer "F.Cu")
		(net "IRQ_SML0_ALERT_N")
	)
	(segment
		(start 401.15363 -109.16412)
		(end 400.925284 -108.935774)
		(width 0.0889)
		(layer "F.Cu")
		(net "IRQ_SML0_ALERT_N")
	)
	(segment
		(start 406.739598 -110.702598)
		(end 405.384 -109.347)
		(width 0.10795)
		(layer "F.Cu")
		(net "IRQ_SML0_ALERT_N")
	)
	(segment
		(start 409.07462 -111.05388)
		(end 407.001472 -111.05388)
		(width 0.10795)
		(layer "F.Cu")
		(net "IRQ_SML0_ALERT_N")
	)
	(segment
		(start 409.5115 -110.617)
		(end 410.1465 -110.617)
		(width 0.10795)
		(layer "F.Cu")
		(net "IRQ_SML0_ALERT_N")
	)
	(segment
		(start 421.130984 -52.17668)
		(end 421.505634 -51.80203)
		(width 0.10795)
		(layer "F.Cu")
		(net "IRQ_SML0_ALERT_N")
	)
	(segment
		(start 403.704044 -109.347)
		(end 403.5552 -109.198156)
		(width 0.10795)
		(layer "F.Cu")
		(net "IRQ_SML0_ALERT_N")
	)
	(segment
		(start 403.5552 -109.198156)
		(end 403.377146 -109.198156)
		(width 0.10795)
		(layer "F.Cu")
		(net "IRQ_SML0_ALERT_N")
	)
	(segment
		(start 421.65016 -51.80203)
		(end 422.216326 -51.235864)
		(width 0.10795)
		(layer "F.Cu")
		(net "IRQ_SML0_ALERT_N")
	)
	(segment
		(start 421.505634 -51.80203)
		(end 421.65016 -51.80203)
		(width 0.10795)
		(layer "F.Cu")
		(net "IRQ_SML0_ALERT_N")
	)
	(segment
		(start 401.64385 -109.164374)
		(end 401.334986 -109.164374)
		(width 0.0889)
		(layer "F.Cu")
		(net "IRQ_SML0_ALERT_N")
	)
	(segment
		(start 417.453826 -59.687968)
		(end 418.040058 -60.2742)
		(width 0.10795)
		(layer "F.Cu")
		(net "IRQ_SML0_ALERT_N")
	)
	(segment
		(start 421.248332 -53.540914)
		(end 421.130984 -53.423566)
		(width 0.10795)
		(layer "F.Cu")
		(net "IRQ_SML0_ALERT_N")
	)
	(segment
		(start 423.942256 -53.888132)
		(end 423.595038 -53.540914)
		(width 0.10795)
		(layer "F.Cu")
		(net "IRQ_SML0_ALERT_N")
	)
	(segment
		(start 417.348924 -59.413902)
		(end 417.453826 -59.518804)
		(width 0.10795)
		(layer "F.Cu")
		(net "IRQ_SML0_ALERT_N")
	)
	(segment
		(start 400.545808 -108.935774)
		(end 400.465036 -108.855002)
		(width 0.0889)
		(layer "F.Cu")
		(net "IRQ_SML0_ALERT_N")
	)
	(segment
		(start 405.384 -109.347)
		(end 403.704044 -109.347)
		(width 0.10795)
		(layer "F.Cu")
		(net "IRQ_SML0_ALERT_N")
	)
	(segment
		(start 418.040058 -60.2742)
		(end 418.719 -60.2742)
		(width 0.10795)
		(layer "F.Cu")
		(net "IRQ_SML0_ALERT_N")
	)
	(segment
		(start 401.334732 -109.16412)
		(end 401.15363 -109.16412)
		(width 0.0889)
		(layer "F.Cu")
		(net "IRQ_SML0_ALERT_N")
	)
	(via
		(at 418.690298 -40.53459)
		(size 0.4572)
		(drill 0.2032)
		(layers "F.Cu" "B.Cu")
		(net "IRQ_SML0_ALERT_N")
	)
	(via
		(at 467.345014 -39.841932)
		(size 0.508)
		(drill 0.254)
		(layers "F.Cu" "B.Cu")
		(net "IRQ_SML0_ALERT_N")
	)
	(via
		(at 409.5115 -110.617)
		(size 0.508)
		(drill 0.254)
		(layers "F.Cu" "B.Cu")
		(net "IRQ_SML0_ALERT_N")
	)
	(via
		(at 474.686122 -52.81168)
		(size 0.508)
		(drill 0.254)
		(layers "F.Cu" "B.Cu")
		(net "IRQ_SML0_ALERT_N")
	)
	(via
		(at 417.348924 -59.413902)
		(size 0.508)
		(drill 0.254)
		(layers "F.Cu" "B.Cu")
		(net "IRQ_SML0_ALERT_N")
	)
	(segment
		(start 412.438342 -65.521078)
		(end 412.438342 -65.173098)
		(width 0.089408)
		(layer "In2.Cu")
		(net "IRQ_SML0_ALERT_N")
	)
	(segment
		(start 411.580076 -68.420234)
		(end 411.580076 -67.786758)
		(width 0.089408)
		(layer "In2.Cu")
		(net "IRQ_SML0_ALERT_N")
	)
	(segment
		(start 410.248862 -98.082862)
		(end 410.147262 -97.981262)
		(width 0.089408)
		(layer "In2.Cu")
		(net "IRQ_SML0_ALERT_N")
	)
	(segment
		(start 468.464138 -54.9148)
		(end 467.113112 -56.265826)
		(width 0.089408)
		(layer "In2.Cu")
		(net "IRQ_SML0_ALERT_N")
	)
	(segment
		(start 410.147262 -97.981262)
		(end 410.147262 -88.615266)
		(width 0.089408)
		(layer "In2.Cu")
		(net "IRQ_SML0_ALERT_N")
	)
	(segment
		(start 413.271462 -57.911746)
		(end 415.846768 -57.911746)
		(width 0.089408)
		(layer "In2.Cu")
		(net "IRQ_SML0_ALERT_N")
	)
	(segment
		(start 411.579314 -66.764662)
		(end 411.579314 -66.380106)
		(width 0.089408)
		(layer "In2.Cu")
		(net "IRQ_SML0_ALERT_N")
	)
	(segment
		(start 411.579822 -67.786504)
		(end 411.579822 -66.76517)
		(width 0.089408)
		(layer "In2.Cu")
		(net "IRQ_SML0_ALERT_N")
	)
	(segment
		(start 407.408888 -81.499456)
		(end 407.408634 -81.49971)
		(width 0.089408)
		(layer "In2.Cu")
		(net "IRQ_SML0_ALERT_N")
	)
	(segment
		(start 436.511954 -55.379112)
		(end 435.131718 -53.998876)
		(width 0.089408)
		(layer "In2.Cu")
		(net "IRQ_SML0_ALERT_N")
	)
	(segment
		(start 411.579314 -66.380106)
		(end 412.438342 -65.521078)
		(width 0.089408)
		(layer "In2.Cu")
		(net "IRQ_SML0_ALERT_N")
	)
	(segment
		(start 407.408634 -81.49971)
		(end 407.09215 -81.49971)
		(width 0.089408)
		(layer "In2.Cu")
		(net "IRQ_SML0_ALERT_N")
	)
	(segment
		(start 469.155272 -53.391816)
		(end 468.464138 -54.08295)
		(width 0.089408)
		(layer "In2.Cu")
		(net "IRQ_SML0_ALERT_N")
	)
	(segment
		(start 474.686122 -52.81168)
		(end 474.61805 -52.743608)
		(width 0.089408)
		(layer "In2.Cu")
		(net "IRQ_SML0_ALERT_N")
	)
	(segment
		(start 428.456852 -55.128414)
		(end 422.091866 -55.128414)
		(width 0.089408)
		(layer "In2.Cu")
		(net "IRQ_SML0_ALERT_N")
	)
	(segment
		(start 472.596718 -52.743608)
		(end 471.94851 -53.391816)
		(width 0.089408)
		(layer "In2.Cu")
		(net "IRQ_SML0_ALERT_N")
	)
	(segment
		(start 410.173678 -70.418706)
		(end 410.530294 -70.418706)
		(width 0.089408)
		(layer "In2.Cu")
		(net "IRQ_SML0_ALERT_N")
	)
	(segment
		(start 464.393026 -56.265826)
		(end 463.506312 -55.379112)
		(width 0.089408)
		(layer "In2.Cu")
		(net "IRQ_SML0_ALERT_N")
	)
	(segment
		(start 411.252416 -69.696584)
		(end 411.252416 -68.747894)
		(width 0.089408)
		(layer "In2.Cu")
		(net "IRQ_SML0_ALERT_N")
	)
	(segment
		(start 408.791918 -81.499456)
		(end 407.408888 -81.499456)
		(width 0.089408)
		(layer "In2.Cu")
		(net "IRQ_SML0_ALERT_N")
	)
	(segment
		(start 409.130246 -87.612474)
		(end 409.130246 -81.837784)
		(width 0.089408)
		(layer "In2.Cu")
		(net "IRQ_SML0_ALERT_N")
	)
	(segment
		(start 463.506312 -55.379112)
		(end 436.511954 -55.379112)
		(width 0.089408)
		(layer "In2.Cu")
		(net "IRQ_SML0_ALERT_N")
	)
	(segment
		(start 411.252416 -68.747894)
		(end 411.580076 -68.420234)
		(width 0.089408)
		(layer "In2.Cu")
		(net "IRQ_SML0_ALERT_N")
	)
	(segment
		(start 405.63673 -79.727806)
		(end 405.636984 -79.727552)
		(width 0.089408)
		(layer "In2.Cu")
		(net "IRQ_SML0_ALERT_N")
	)
	(segment
		(start 411.579822 -66.76517)
		(end 411.579314 -66.764662)
		(width 0.089408)
		(layer "In2.Cu")
		(net "IRQ_SML0_ALERT_N")
	)
	(segment
		(start 429.58639 -53.998876)
		(end 428.456852 -55.128414)
		(width 0.089408)
		(layer "In2.Cu")
		(net "IRQ_SML0_ALERT_N")
	)
	(segment
		(start 412.44012 -63.833248)
		(end 412.157672 -63.5508)
		(width 0.089408)
		(layer "In2.Cu")
		(net "IRQ_SML0_ALERT_N")
	)
	(segment
		(start 405.636984 -79.727552)
		(end 405.636984 -78.812136)
		(width 0.089408)
		(layer "In2.Cu")
		(net "IRQ_SML0_ALERT_N")
	)
	(segment
		(start 405.63673 -80.04429)
		(end 405.63673 -79.727806)
		(width 0.089408)
		(layer "In2.Cu")
		(net "IRQ_SML0_ALERT_N")
	)
	(segment
		(start 412.157672 -63.5508)
		(end 412.157672 -59.025536)
		(width 0.089408)
		(layer "In2.Cu")
		(net "IRQ_SML0_ALERT_N")
	)
	(segment
		(start 417.806378 -59.413902)
		(end 417.348924 -59.413902)
		(width 0.089408)
		(layer "In2.Cu")
		(net "IRQ_SML0_ALERT_N")
	)
	(segment
		(start 409.14447 -87.612474)
		(end 409.130246 -87.612474)
		(width 0.089408)
		(layer "In2.Cu")
		(net "IRQ_SML0_ALERT_N")
	)
	(segment
		(start 474.61805 -52.743608)
		(end 472.596718 -52.743608)
		(width 0.089408)
		(layer "In2.Cu")
		(net "IRQ_SML0_ALERT_N")
	)
	(segment
		(start 435.131718 -53.998876)
		(end 429.58639 -53.998876)
		(width 0.089408)
		(layer "In2.Cu")
		(net "IRQ_SML0_ALERT_N")
	)
	(segment
		(start 409.5115 -110.617)
		(end 410.248862 -109.879638)
		(width 0.089408)
		(layer "In2.Cu")
		(net "IRQ_SML0_ALERT_N")
	)
	(segment
		(start 411.580076 -67.786758)
		(end 411.579822 -67.786504)
		(width 0.089408)
		(layer "In2.Cu")
		(net "IRQ_SML0_ALERT_N")
	)
	(segment
		(start 405.16556 -75.426824)
		(end 410.173678 -70.418706)
		(width 0.089408)
		(layer "In2.Cu")
		(net "IRQ_SML0_ALERT_N")
	)
	(segment
		(start 410.147262 -88.615266)
		(end 409.14447 -87.612474)
		(width 0.089408)
		(layer "In2.Cu")
		(net "IRQ_SML0_ALERT_N")
	)
	(segment
		(start 412.157672 -59.025536)
		(end 413.271462 -57.911746)
		(width 0.089408)
		(layer "In2.Cu")
		(net "IRQ_SML0_ALERT_N")
	)
	(segment
		(start 412.438342 -65.173098)
		(end 412.44012 -65.17132)
		(width 0.089408)
		(layer "In2.Cu")
		(net "IRQ_SML0_ALERT_N")
	)
	(segment
		(start 471.94851 -53.391816)
		(end 469.155272 -53.391816)
		(width 0.089408)
		(layer "In2.Cu")
		(net "IRQ_SML0_ALERT_N")
	)
	(segment
		(start 405.636984 -78.812136)
		(end 405.16556 -78.340712)
		(width 0.089408)
		(layer "In2.Cu")
		(net "IRQ_SML0_ALERT_N")
	)
	(segment
		(start 405.16556 -78.340712)
		(end 405.16556 -75.426824)
		(width 0.089408)
		(layer "In2.Cu")
		(net "IRQ_SML0_ALERT_N")
	)
	(segment
		(start 410.248862 -109.879638)
		(end 410.248862 -98.082862)
		(width 0.089408)
		(layer "In2.Cu")
		(net "IRQ_SML0_ALERT_N")
	)
	(segment
		(start 409.130246 -81.837784)
		(end 408.791918 -81.499456)
		(width 0.089408)
		(layer "In2.Cu")
		(net "IRQ_SML0_ALERT_N")
	)
	(segment
		(start 415.846768 -57.911746)
		(end 417.348924 -59.413902)
		(width 0.089408)
		(layer "In2.Cu")
		(net "IRQ_SML0_ALERT_N")
	)
	(segment
		(start 410.530294 -70.418706)
		(end 411.252416 -69.696584)
		(width 0.089408)
		(layer "In2.Cu")
		(net "IRQ_SML0_ALERT_N")
	)
	(segment
		(start 412.44012 -65.17132)
		(end 412.44012 -63.833248)
		(width 0.089408)
		(layer "In2.Cu")
		(net "IRQ_SML0_ALERT_N")
	)
	(segment
		(start 467.113112 -56.265826)
		(end 464.393026 -56.265826)
		(width 0.089408)
		(layer "In2.Cu")
		(net "IRQ_SML0_ALERT_N")
	)
	(segment
		(start 468.464138 -54.08295)
		(end 468.464138 -54.9148)
		(width 0.089408)
		(layer "In2.Cu")
		(net "IRQ_SML0_ALERT_N")
	)
	(segment
		(start 422.091866 -55.128414)
		(end 417.806378 -59.413902)
		(width 0.089408)
		(layer "In2.Cu")
		(net "IRQ_SML0_ALERT_N")
	)
	(segment
		(start 407.09215 -81.49971)
		(end 405.63673 -80.04429)
		(width 0.089408)
		(layer "In2.Cu")
		(net "IRQ_SML0_ALERT_N")
	)
	(segment
		(start 464.731862 -40.129206)
		(end 464.998308 -40.129206)
		(width 0.089408)
		(layer "In4.Cu")
		(net "IRQ_SML0_ALERT_N")
	)
	(segment
		(start 443.969394 -38.515798)
		(end 444.117476 -38.66388)
		(width 0.089408)
		(layer "In4.Cu")
		(net "IRQ_SML0_ALERT_N")
	)
	(segment
		(start 446.236852 -38.66388)
		(end 448.553332 -36.3474)
		(width 0.089408)
		(layer "In4.Cu")
		(net "IRQ_SML0_ALERT_N")
	)
	(segment
		(start 458.254354 -36.107878)
		(end 460.476346 -38.32987)
		(width 0.089408)
		(layer "In4.Cu")
		(net "IRQ_SML0_ALERT_N")
	)
	(segment
		(start 421.269668 -41.725088)
		(end 421.466772 -41.527984)
		(width 0.089408)
		(layer "In4.Cu")
		(net "IRQ_SML0_ALERT_N")
	)
	(segment
		(start 464.998308 -40.129206)
		(end 465.295234 -40.426132)
		(width 0.089408)
		(layer "In4.Cu")
		(net "IRQ_SML0_ALERT_N")
	)
	(segment
		(start 448.553332 -36.3474)
		(end 456.21194 -36.3474)
		(width 0.089408)
		(layer "In4.Cu")
		(net "IRQ_SML0_ALERT_N")
	)
	(segment
		(start 419.288976 -40.944546)
		(end 419.630098 -40.944546)
		(width 0.089408)
		(layer "In4.Cu")
		(net "IRQ_SML0_ALERT_N")
	)
	(segment
		(start 466.216238 -40.426132)
		(end 466.800438 -39.841932)
		(width 0.089408)
		(layer "In4.Cu")
		(net "IRQ_SML0_ALERT_N")
	)
	(segment
		(start 420.087806 -41.725088)
		(end 421.269668 -41.725088)
		(width 0.089408)
		(layer "In4.Cu")
		(net "IRQ_SML0_ALERT_N")
	)
	(segment
		(start 443.398656 -38.515798)
		(end 443.969394 -38.515798)
		(width 0.089408)
		(layer "In4.Cu")
		(net "IRQ_SML0_ALERT_N")
	)
	(segment
		(start 421.466772 -41.141396)
		(end 421.663622 -40.944546)
		(width 0.089408)
		(layer "In4.Cu")
		(net "IRQ_SML0_ALERT_N")
	)
	(segment
		(start 434.36032 -39.047928)
		(end 442.866526 -39.047928)
		(width 0.089408)
		(layer "In4.Cu")
		(net "IRQ_SML0_ALERT_N")
	)
	(segment
		(start 423.363136 -40.186102)
		(end 425.230798 -40.186102)
		(width 0.089408)
		(layer "In4.Cu")
		(net "IRQ_SML0_ALERT_N")
	)
	(segment
		(start 419.630098 -40.944546)
		(end 419.91534 -41.229788)
		(width 0.089408)
		(layer "In4.Cu")
		(net "IRQ_SML0_ALERT_N")
	)
	(segment
		(start 442.866526 -39.047928)
		(end 443.398656 -38.515798)
		(width 0.089408)
		(layer "In4.Cu")
		(net "IRQ_SML0_ALERT_N")
	)
	(segment
		(start 465.295234 -40.426132)
		(end 466.216238 -40.426132)
		(width 0.089408)
		(layer "In4.Cu")
		(net "IRQ_SML0_ALERT_N")
	)
	(segment
		(start 418.87902 -40.53459)
		(end 419.288976 -40.944546)
		(width 0.089408)
		(layer "In4.Cu")
		(net "IRQ_SML0_ALERT_N")
	)
	(segment
		(start 456.21194 -36.3474)
		(end 456.451462 -36.107878)
		(width 0.089408)
		(layer "In4.Cu")
		(net "IRQ_SML0_ALERT_N")
	)
	(segment
		(start 462.932526 -38.32987)
		(end 464.731862 -40.129206)
		(width 0.089408)
		(layer "In4.Cu")
		(net "IRQ_SML0_ALERT_N")
	)
	(segment
		(start 433.017168 -37.704776)
		(end 434.36032 -39.047928)
		(width 0.089408)
		(layer "In4.Cu")
		(net "IRQ_SML0_ALERT_N")
	)
	(segment
		(start 419.91534 -41.552622)
		(end 420.087806 -41.725088)
		(width 0.089408)
		(layer "In4.Cu")
		(net "IRQ_SML0_ALERT_N")
	)
	(segment
		(start 425.230798 -40.186102)
		(end 427.712124 -37.704776)
		(width 0.089408)
		(layer "In4.Cu")
		(net "IRQ_SML0_ALERT_N")
	)
	(segment
		(start 421.663622 -40.944546)
		(end 422.604692 -40.944546)
		(width 0.089408)
		(layer "In4.Cu")
		(net "IRQ_SML0_ALERT_N")
	)
	(segment
		(start 444.117476 -38.66388)
		(end 446.236852 -38.66388)
		(width 0.089408)
		(layer "In4.Cu")
		(net "IRQ_SML0_ALERT_N")
	)
	(segment
		(start 422.604692 -40.944546)
		(end 423.363136 -40.186102)
		(width 0.089408)
		(layer "In4.Cu")
		(net "IRQ_SML0_ALERT_N")
	)
	(segment
		(start 456.451462 -36.107878)
		(end 458.254354 -36.107878)
		(width 0.089408)
		(layer "In4.Cu")
		(net "IRQ_SML0_ALERT_N")
	)
	(segment
		(start 460.476346 -38.32987)
		(end 462.932526 -38.32987)
		(width 0.089408)
		(layer "In4.Cu")
		(net "IRQ_SML0_ALERT_N")
	)
	(segment
		(start 466.800438 -39.841932)
		(end 467.345014 -39.841932)
		(width 0.089408)
		(layer "In4.Cu")
		(net "IRQ_SML0_ALERT_N")
	)
	(segment
		(start 427.712124 -37.704776)
		(end 433.017168 -37.704776)
		(width 0.089408)
		(layer "In4.Cu")
		(net "IRQ_SML0_ALERT_N")
	)
	(segment
		(start 421.466772 -41.527984)
		(end 421.466772 -41.141396)
		(width 0.089408)
		(layer "In4.Cu")
		(net "IRQ_SML0_ALERT_N")
	)
	(segment
		(start 418.690298 -40.53459)
		(end 418.87902 -40.53459)
		(width 0.089408)
		(layer "In4.Cu")
		(net "IRQ_SML0_ALERT_N")
	)
	(segment
		(start 419.91534 -41.229788)
		(end 419.91534 -41.552622)
		(width 0.089408)
		(layer "In4.Cu")
		(net "IRQ_SML0_ALERT_N")
	)
	(segment
		(start 468.06358 -43.085512)
		(end 468.06358 -40.559736)
		(width 0.089408)
		(layer "In11.Cu")
		(net "IRQ_SML0_ALERT_N")
	)
	(segment
		(start 471.506296 -45.936662)
		(end 471.506296 -45.925232)
		(width 0.089408)
		(layer "In11.Cu")
		(net "IRQ_SML0_ALERT_N")
	)
	(segment
		(start 468.06358 -40.559736)
		(end 467.345776 -39.841932)
		(width 0.089408)
		(layer "In11.Cu")
		(net "IRQ_SML0_ALERT_N")
	)
	(segment
		(start 471.506296 -45.925232)
		(end 471.248994 -45.66793)
		(width 0.089408)
		(layer "In11.Cu")
		(net "IRQ_SML0_ALERT_N")
	)
	(segment
		(start 474.924628 -52.573174)
		(end 474.924628 -50.654458)
		(width 0.089408)
		(layer "In11.Cu")
		(net "IRQ_SML0_ALERT_N")
	)
	(segment
		(start 471.248994 -45.66793)
		(end 470.645998 -45.66793)
		(width 0.089408)
		(layer "In11.Cu")
		(net "IRQ_SML0_ALERT_N")
	)
	(segment
		(start 467.345776 -39.841932)
		(end 467.345014 -39.841932)
		(width 0.089408)
		(layer "In11.Cu")
		(net "IRQ_SML0_ALERT_N")
	)
	(segment
		(start 472.804998 -48.534828)
		(end 472.804998 -47.746158)
		(width 0.089408)
		(layer "In11.Cu")
		(net "IRQ_SML0_ALERT_N")
	)
	(segment
		(start 472.070938 -47.012098)
		(end 472.070938 -46.501304)
		(width 0.089408)
		(layer "In11.Cu")
		(net "IRQ_SML0_ALERT_N")
	)
	(segment
		(start 470.645998 -45.66793)
		(end 468.06358 -43.085512)
		(width 0.089408)
		(layer "In11.Cu")
		(net "IRQ_SML0_ALERT_N")
	)
	(segment
		(start 474.924628 -50.654458)
		(end 472.804998 -48.534828)
		(width 0.089408)
		(layer "In11.Cu")
		(net "IRQ_SML0_ALERT_N")
	)
	(segment
		(start 472.070938 -46.501304)
		(end 471.506296 -45.936662)
		(width 0.089408)
		(layer "In11.Cu")
		(net "IRQ_SML0_ALERT_N")
	)
	(segment
		(start 474.686122 -52.81168)
		(end 474.924628 -52.573174)
		(width 0.089408)
		(layer "In11.Cu")
		(net "IRQ_SML0_ALERT_N")
	)
	(segment
		(start 472.804998 -47.746158)
		(end 472.070938 -47.012098)
		(width 0.089408)
		(layer "In11.Cu")
		(net "IRQ_SML0_ALERT_N")
	)
	(segment
		(start 406.52446 -42.534586)
		(end 407.090118 -42.534586)
		(width 0.10795)
		(layer "F.Cu")
		(net "IRQ_PVDDQ_KLM_VRHOT_LVT3_N")
	)
	(segment
		(start -2.28346 -132.85216)
		(end -2.28346 -133.373114)
		(width 0.10795)
		(layer "F.Cu")
		(net "IRQ_PVDDQ_KLM_VRHOT_LVT3_N")
	)
	(segment
		(start -2.28346 -133.373114)
		(end -2.4384 -133.528054)
		(width 0.10795)
		(layer "F.Cu")
		(net "IRQ_PVDDQ_KLM_VRHOT_LVT3_N")
	)
	(segment
		(start 173.2407 -127.00762)
		(end 173.22546 -126.99238)
		(width 0.10795)
		(layer "F.Cu")
		(net "IRQ_PVDDQ_KLM_VRHOT_LVT3_N")
	)
	(segment
		(start 173.2407 -128.00838)
		(end 173.2407 -127.00762)
		(width 0.10795)
		(layer "F.Cu")
		(net "IRQ_PVDDQ_KLM_VRHOT_LVT3_N")
	)
	(segment
		(start 398.63395 -98.69424)
		(end 399.12925 -98.464116)
		(width 0.10795)
		(layer "F.Cu")
		(net "IRQ_PVDDQ_KLM_VRHOT_LVT3_N")
	)
	(segment
		(start -2.4384 -133.528054)
		(end -2.4384 -133.6294)
		(width 0.10795)
		(layer "F.Cu")
		(net "IRQ_PVDDQ_KLM_VRHOT_LVT3_N")
	)
	(via
		(at 166.3954 -155.9814)
		(size 0.508)
		(drill 0.254)
		(layers "F.Cu" "B.Cu")
		(net "IRQ_PVDDQ_KLM_VRHOT_LVT3_N")
	)
	(via
		(at 416.334702 -126.170436)
		(size 0.508)
		(drill 0.254)
		(layers "F.Cu" "B.Cu")
		(net "IRQ_PVDDQ_KLM_VRHOT_LVT3_N")
	)
	(via
		(at -2.4384 -133.6294)
		(size 0.508)
		(drill 0.254)
		(layers "F.Cu" "B.Cu")
		(net "IRQ_PVDDQ_KLM_VRHOT_LVT3_N")
	)
	(via
		(at 173.2407 -128.00838)
		(size 0.508)
		(drill 0.254)
		(layers "F.Cu" "B.Cu")
		(net "IRQ_PVDDQ_KLM_VRHOT_LVT3_N")
	)
	(via
		(at 399.12925 -98.464116)
		(size 0.508)
		(drill 0.254)
		(layers "F.Cu" "B.Cu")
		(net "IRQ_PVDDQ_KLM_VRHOT_LVT3_N")
	)
	(via
		(at 397.360394 -80.06334)
		(size 0.508)
		(drill 0.254)
		(layers "F.Cu" "B.Cu")
		(net "IRQ_PVDDQ_KLM_VRHOT_LVT3_N")
	)
	(via
		(at 406.52446 -42.534586)
		(size 0.4572)
		(drill 0.2032)
		(layers "F.Cu" "B.Cu")
		(net "IRQ_PVDDQ_KLM_VRHOT_LVT3_N")
	)
	(segment
		(start 399.629884 -98.464116)
		(end 399.12925 -98.464116)
		(width 0.10795)
		(layer "B.Cu")
		(net "IRQ_PVDDQ_KLM_VRHOT_LVT3_N")
	)
	(segment
		(start 412.655004 -114.63782)
		(end 412.655004 -108.744512)
		(width 0.10795)
		(layer "B.Cu")
		(net "IRQ_PVDDQ_KLM_VRHOT_LVT3_N")
	)
	(segment
		(start 414.617408 -106.256582)
		(end 412.655004 -104.294178)
		(width 0.10795)
		(layer "B.Cu")
		(net "IRQ_PVDDQ_KLM_VRHOT_LVT3_N")
	)
	(segment
		(start 169.672 -132.569966)
		(end 170.1546 -132.087366)
		(width 0.10795)
		(layer "B.Cu")
		(net "IRQ_PVDDQ_KLM_VRHOT_LVT3_N")
	)
	(segment
		(start 169.672 -133.9342)
		(end 169.672 -132.569966)
		(width 0.10795)
		(layer "B.Cu")
		(net "IRQ_PVDDQ_KLM_VRHOT_LVT3_N")
	)
	(segment
		(start 165.3794 -154.94)
		(end 165.3794 -149.0726)
		(width 0.10795)
		(layer "B.Cu")
		(net "IRQ_PVDDQ_KLM_VRHOT_LVT3_N")
	)
	(segment
		(start 416.334702 -126.170436)
		(end 416.334702 -125.709934)
		(width 0.10795)
		(layer "B.Cu")
		(net "IRQ_PVDDQ_KLM_VRHOT_LVT3_N")
	)
	(segment
		(start 401.70735 -96.38665)
		(end 399.629884 -98.464116)
		(width 0.10795)
		(layer "B.Cu")
		(net "IRQ_PVDDQ_KLM_VRHOT_LVT3_N")
	)
	(segment
		(start 164.5158 -145.7198)
		(end 165.0746 -145.161)
		(width 0.10795)
		(layer "B.Cu")
		(net "IRQ_PVDDQ_KLM_VRHOT_LVT3_N")
	)
	(segment
		(start 415.199322 -124.574554)
		(end 415.199322 -121.083578)
		(width 0.10795)
		(layer "B.Cu")
		(net "IRQ_PVDDQ_KLM_VRHOT_LVT3_N")
	)
	(segment
		(start 165.0746 -145.161)
		(end 168.1988 -145.161)
		(width 0.10795)
		(layer "B.Cu")
		(net "IRQ_PVDDQ_KLM_VRHOT_LVT3_N")
	)
	(segment
		(start 404.990554 -96.059244)
		(end 404.882604 -95.951294)
		(width 0.10795)
		(layer "B.Cu")
		(net "IRQ_PVDDQ_KLM_VRHOT_LVT3_N")
	)
	(segment
		(start 402.24329 -96.38665)
		(end 401.70735 -96.38665)
		(width 0.10795)
		(layer "B.Cu")
		(net "IRQ_PVDDQ_KLM_VRHOT_LVT3_N")
	)
	(segment
		(start 413.0294 -115.012216)
		(end 412.655004 -114.63782)
		(width 0.10795)
		(layer "B.Cu")
		(net "IRQ_PVDDQ_KLM_VRHOT_LVT3_N")
	)
	(segment
		(start 170.1546 -131.135882)
		(end 171.022264 -130.268218)
		(width 0.10795)
		(layer "B.Cu")
		(net "IRQ_PVDDQ_KLM_VRHOT_LVT3_N")
	)
	(segment
		(start 412.655004 -108.744512)
		(end 414.617408 -106.782108)
		(width 0.10795)
		(layer "B.Cu")
		(net "IRQ_PVDDQ_KLM_VRHOT_LVT3_N")
	)
	(segment
		(start 172.261022 -129.67081)
		(end 172.261022 -128.988058)
		(width 0.10795)
		(layer "B.Cu")
		(net "IRQ_PVDDQ_KLM_VRHOT_LVT3_N")
	)
	(segment
		(start 416.334702 -125.709934)
		(end 415.199322 -124.574554)
		(width 0.10795)
		(layer "B.Cu")
		(net "IRQ_PVDDQ_KLM_VRHOT_LVT3_N")
	)
	(segment
		(start 169.109898 -138.070844)
		(end 169.109898 -134.496302)
		(width 0.10795)
		(layer "B.Cu")
		(net "IRQ_PVDDQ_KLM_VRHOT_LVT3_N")
	)
	(segment
		(start 402.678646 -95.951294)
		(end 402.24329 -96.38665)
		(width 0.10795)
		(layer "B.Cu")
		(net "IRQ_PVDDQ_KLM_VRHOT_LVT3_N")
	)
	(segment
		(start 404.882604 -95.951294)
		(end 402.678646 -95.951294)
		(width 0.10795)
		(layer "B.Cu")
		(net "IRQ_PVDDQ_KLM_VRHOT_LVT3_N")
	)
	(segment
		(start 165.3794 -149.0726)
		(end 164.5158 -148.209)
		(width 0.10795)
		(layer "B.Cu")
		(net "IRQ_PVDDQ_KLM_VRHOT_LVT3_N")
	)
	(segment
		(start 171.103798 -144.6784)
		(end 171.9326 -143.849598)
		(width 0.10795)
		(layer "B.Cu")
		(net "IRQ_PVDDQ_KLM_VRHOT_LVT3_N")
	)
	(segment
		(start 171.022264 -130.268218)
		(end 171.663614 -130.268218)
		(width 0.10795)
		(layer "B.Cu")
		(net "IRQ_PVDDQ_KLM_VRHOT_LVT3_N")
	)
	(segment
		(start 168.6814 -144.6784)
		(end 171.103798 -144.6784)
		(width 0.10795)
		(layer "B.Cu")
		(net "IRQ_PVDDQ_KLM_VRHOT_LVT3_N")
	)
	(segment
		(start 413.0294 -118.913656)
		(end 413.0294 -115.012216)
		(width 0.10795)
		(layer "B.Cu")
		(net "IRQ_PVDDQ_KLM_VRHOT_LVT3_N")
	)
	(segment
		(start 164.5158 -148.209)
		(end 164.5158 -145.7198)
		(width 0.10795)
		(layer "B.Cu")
		(net "IRQ_PVDDQ_KLM_VRHOT_LVT3_N")
	)
	(segment
		(start 171.9326 -143.849598)
		(end 171.9326 -140.893546)
		(width 0.10795)
		(layer "B.Cu")
		(net "IRQ_PVDDQ_KLM_VRHOT_LVT3_N")
	)
	(segment
		(start 166.3954 -155.956)
		(end 165.3794 -154.94)
		(width 0.10795)
		(layer "B.Cu")
		(net "IRQ_PVDDQ_KLM_VRHOT_LVT3_N")
	)
	(segment
		(start 166.3954 -155.9814)
		(end 166.3954 -155.956)
		(width 0.10795)
		(layer "B.Cu")
		(net "IRQ_PVDDQ_KLM_VRHOT_LVT3_N")
	)
	(segment
		(start 171.663614 -130.268218)
		(end 172.261022 -129.67081)
		(width 0.10795)
		(layer "B.Cu")
		(net "IRQ_PVDDQ_KLM_VRHOT_LVT3_N")
	)
	(segment
		(start 404.990554 -97.170748)
		(end 404.990554 -96.059244)
		(width 0.10795)
		(layer "B.Cu")
		(net "IRQ_PVDDQ_KLM_VRHOT_LVT3_N")
	)
	(segment
		(start 169.109898 -134.496302)
		(end 169.672 -133.9342)
		(width 0.10795)
		(layer "B.Cu")
		(net "IRQ_PVDDQ_KLM_VRHOT_LVT3_N")
	)
	(segment
		(start 170.1546 -132.087366)
		(end 170.1546 -131.135882)
		(width 0.10795)
		(layer "B.Cu")
		(net "IRQ_PVDDQ_KLM_VRHOT_LVT3_N")
	)
	(segment
		(start 168.1988 -145.161)
		(end 168.6814 -144.6784)
		(width 0.10795)
		(layer "B.Cu")
		(net "IRQ_PVDDQ_KLM_VRHOT_LVT3_N")
	)
	(segment
		(start 171.9326 -140.893546)
		(end 169.109898 -138.070844)
		(width 0.10795)
		(layer "B.Cu")
		(net "IRQ_PVDDQ_KLM_VRHOT_LVT3_N")
	)
	(segment
		(start 415.199322 -121.083578)
		(end 413.0294 -118.913656)
		(width 0.10795)
		(layer "B.Cu")
		(net "IRQ_PVDDQ_KLM_VRHOT_LVT3_N")
	)
	(segment
		(start 172.261022 -128.988058)
		(end 173.2407 -128.00838)
		(width 0.10795)
		(layer "B.Cu")
		(net "IRQ_PVDDQ_KLM_VRHOT_LVT3_N")
	)
	(segment
		(start 405.159464 -97.339658)
		(end 404.990554 -97.170748)
		(width 0.10795)
		(layer "B.Cu")
		(net "IRQ_PVDDQ_KLM_VRHOT_LVT3_N")
	)
	(segment
		(start 414.617408 -106.782108)
		(end 414.617408 -106.256582)
		(width 0.10795)
		(layer "B.Cu")
		(net "IRQ_PVDDQ_KLM_VRHOT_LVT3_N")
	)
	(segment
		(start 410.343858 -97.339658)
		(end 405.159464 -97.339658)
		(width 0.10795)
		(layer "B.Cu")
		(net "IRQ_PVDDQ_KLM_VRHOT_LVT3_N")
	)
	(segment
		(start 412.655004 -99.650804)
		(end 410.343858 -97.339658)
		(width 0.10795)
		(layer "B.Cu")
		(net "IRQ_PVDDQ_KLM_VRHOT_LVT3_N")
	)
	(segment
		(start 412.655004 -104.294178)
		(end 412.655004 -99.650804)
		(width 0.10795)
		(layer "B.Cu")
		(net "IRQ_PVDDQ_KLM_VRHOT_LVT3_N")
	)
	(segment
		(start 397.360394 -82.090514)
		(end 399.000472 -83.730592)
		(width 0.089408)
		(layer "In2.Cu")
		(net "IRQ_PVDDQ_KLM_VRHOT_LVT3_N")
	)
	(segment
		(start 398.21612 -86.018624)
		(end 398.21612 -88.13292)
		(width 0.089408)
		(layer "In2.Cu")
		(net "IRQ_PVDDQ_KLM_VRHOT_LVT3_N")
	)
	(segment
		(start 398.219422 -88.136222)
		(end 398.219422 -90.787982)
		(width 0.089408)
		(layer "In2.Cu")
		(net "IRQ_PVDDQ_KLM_VRHOT_LVT3_N")
	)
	(segment
		(start 398.219422 -90.787982)
		(end 398.47774 -91.0463)
		(width 0.089408)
		(layer "In2.Cu")
		(net "IRQ_PVDDQ_KLM_VRHOT_LVT3_N")
	)
	(segment
		(start 400.091148 -97.949512)
		(end 399.576544 -98.464116)
		(width 0.089408)
		(layer "In2.Cu")
		(net "IRQ_PVDDQ_KLM_VRHOT_LVT3_N")
	)
	(segment
		(start 398.47774 -94.240604)
		(end 400.091148 -95.854012)
		(width 0.089408)
		(layer "In2.Cu")
		(net "IRQ_PVDDQ_KLM_VRHOT_LVT3_N")
	)
	(segment
		(start 399.576544 -98.464116)
		(end 399.12925 -98.464116)
		(width 0.089408)
		(layer "In2.Cu")
		(net "IRQ_PVDDQ_KLM_VRHOT_LVT3_N")
	)
	(segment
		(start 397.360394 -80.06334)
		(end 397.360394 -82.090514)
		(width 0.089408)
		(layer "In2.Cu")
		(net "IRQ_PVDDQ_KLM_VRHOT_LVT3_N")
	)
	(segment
		(start 398.47774 -91.0463)
		(end 398.47774 -94.240604)
		(width 0.089408)
		(layer "In2.Cu")
		(net "IRQ_PVDDQ_KLM_VRHOT_LVT3_N")
	)
	(segment
		(start 400.091148 -95.854012)
		(end 400.091148 -97.949512)
		(width 0.089408)
		(layer "In2.Cu")
		(net "IRQ_PVDDQ_KLM_VRHOT_LVT3_N")
	)
	(segment
		(start 399.000472 -85.234272)
		(end 398.21612 -86.018624)
		(width 0.089408)
		(layer "In2.Cu")
		(net "IRQ_PVDDQ_KLM_VRHOT_LVT3_N")
	)
	(segment
		(start 399.000472 -83.730592)
		(end 399.000472 -85.234272)
		(width 0.089408)
		(layer "In2.Cu")
		(net "IRQ_PVDDQ_KLM_VRHOT_LVT3_N")
	)
	(segment
		(start 398.21612 -88.13292)
		(end 398.219422 -88.136222)
		(width 0.089408)
		(layer "In2.Cu")
		(net "IRQ_PVDDQ_KLM_VRHOT_LVT3_N")
	)
	(segment
		(start 423.601388 -137.269982)
		(end 417.651438 -131.320032)
		(width 0.089408)
		(layer "In9.Cu")
		(net "IRQ_PVDDQ_KLM_VRHOT_LVT3_N")
	)
	(segment
		(start 99.824794 -157.355032)
		(end 100.078794 -157.101032)
		(width 0.089408)
		(layer "In9.Cu")
		(net "IRQ_PVDDQ_KLM_VRHOT_LVT3_N")
	)
	(segment
		(start 417.333938 -129.026666)
		(end 417.343336 -129.017268)
		(width 0.089408)
		(layer "In9.Cu")
		(net "IRQ_PVDDQ_KLM_VRHOT_LVT3_N")
	)
	(segment
		(start 14.224 -154.94)
		(end 17.7165 -158.4325)
		(width 0.089408)
		(layer "In9.Cu")
		(net "IRQ_PVDDQ_KLM_VRHOT_LVT3_N")
	)
	(segment
		(start 432.776884 -140.755116)
		(end 431.01514 -140.755116)
		(width 0.089408)
		(layer "In9.Cu")
		(net "IRQ_PVDDQ_KLM_VRHOT_LVT3_N")
	)
	(segment
		(start 365.207296 -154.213814)
		(end 368.078512 -157.08503)
		(width 0.089408)
		(layer "In9.Cu")
		(net "IRQ_PVDDQ_KLM_VRHOT_LVT3_N")
	)
	(segment
		(start -0.06731 -143.297656)
		(end 12.746736 -143.297656)
		(width 0.089408)
		(layer "In9.Cu")
		(net "IRQ_PVDDQ_KLM_VRHOT_LVT3_N")
	)
	(segment
		(start 187.672218 -158.208218)
		(end 264.447782 -158.208218)
		(width 0.089408)
		(layer "In9.Cu")
		(net "IRQ_PVDDQ_KLM_VRHOT_LVT3_N")
	)
	(segment
		(start 12.746736 -143.297656)
		(end 14.224 -144.77492)
		(width 0.089408)
		(layer "In9.Cu")
		(net "IRQ_PVDDQ_KLM_VRHOT_LVT3_N")
	)
	(segment
		(start 164.05606 -157.101032)
		(end 165.175692 -155.9814)
		(width 0.089408)
		(layer "In9.Cu")
		(net "IRQ_PVDDQ_KLM_VRHOT_LVT3_N")
	)
	(segment
		(start 430.072038 -148.99386)
		(end 431.568352 -148.99386)
		(width 0.089408)
		(layer "In9.Cu")
		(net "IRQ_PVDDQ_KLM_VRHOT_LVT3_N")
	)
	(segment
		(start 330.480416 -158.342584)
		(end 331.997304 -156.825696)
		(width 0.089408)
		(layer "In9.Cu")
		(net "IRQ_PVDDQ_KLM_VRHOT_LVT3_N")
	)
	(segment
		(start 405.864314 -43.194732)
		(end 405.150828 -43.194732)
		(width 0.089408)
		(layer "In9.Cu")
		(net "IRQ_PVDDQ_KLM_VRHOT_LVT3_N")
	)
	(segment
		(start 408.410156 -154.80284)
		(end 408.41295 -154.802332)
		(width 0.089408)
		(layer "In9.Cu")
		(net "IRQ_PVDDQ_KLM_VRHOT_LVT3_N")
	)
	(segment
		(start 353.358704 -153.550112)
		(end 355.778816 -151.13)
		(width 0.089408)
		(layer "In9.Cu")
		(net "IRQ_PVDDQ_KLM_VRHOT_LVT3_N")
	)
	(segment
		(start 417.343336 -129.017268)
		(end 417.343336 -128.565148)
		(width 0.089408)
		(layer "In9.Cu")
		(net "IRQ_PVDDQ_KLM_VRHOT_LVT3_N")
	)
	(segment
		(start 417.34105 -128.231138)
		(end 417.343336 -128.228852)
		(width 0.089408)
		(layer "In9.Cu")
		(net "IRQ_PVDDQ_KLM_VRHOT_LVT3_N")
	)
	(segment
		(start 394.11402 -156.5148)
		(end 398.4752 -156.5148)
		(width 0.089408)
		(layer "In9.Cu")
		(net "IRQ_PVDDQ_KLM_VRHOT_LVT3_N")
	)
	(segment
		(start 264.795 -157.861)
		(end 279.490932 -157.861)
		(width 0.089408)
		(layer "In9.Cu")
		(net "IRQ_PVDDQ_KLM_VRHOT_LVT3_N")
	)
	(segment
		(start 431.01514 -140.755116)
		(end 428.848266 -138.588242)
		(width 0.089408)
		(layer "In9.Cu")
		(net "IRQ_PVDDQ_KLM_VRHOT_LVT3_N")
	)
	(segment
		(start 26.222706 -156.784294)
		(end 29.017214 -156.784294)
		(width 0.089408)
		(layer "In9.Cu")
		(net "IRQ_PVDDQ_KLM_VRHOT_LVT3_N")
	)
	(segment
		(start 264.447782 -158.208218)
		(end 264.795 -157.861)
		(width 0.089408)
		(layer "In9.Cu")
		(net "IRQ_PVDDQ_KLM_VRHOT_LVT3_N")
	)
	(segment
		(start 410.58084 -154.802332)
		(end 412.997904 -157.219396)
		(width 0.089408)
		(layer "In9.Cu")
		(net "IRQ_PVDDQ_KLM_VRHOT_LVT3_N")
	)
	(segment
		(start -1.204976 -136.797796)
		(end -1.44018 -137.033)
		(width 0.089408)
		(layer "In9.Cu")
		(net "IRQ_PVDDQ_KLM_VRHOT_LVT3_N")
	)
	(segment
		(start 407.28138 -155.931616)
		(end 408.410156 -154.80284)
		(width 0.089408)
		(layer "In9.Cu")
		(net "IRQ_PVDDQ_KLM_VRHOT_LVT3_N")
	)
	(segment
		(start -2.4384 -133.6294)
		(end -2.159254 -133.6294)
		(width 0.089408)
		(layer "In9.Cu")
		(net "IRQ_PVDDQ_KLM_VRHOT_LVT3_N")
	)
	(segment
		(start 397.783812 -79.252572)
		(end 397.360394 -79.67599)
		(width 0.089408)
		(layer "In9.Cu")
		(net "IRQ_PVDDQ_KLM_VRHOT_LVT3_N")
	)
	(segment
		(start 348.709488 -156.825696)
		(end 348.893384 -157.009592)
		(width 0.089408)
		(layer "In9.Cu")
		(net "IRQ_PVDDQ_KLM_VRHOT_LVT3_N")
	)
	(segment
		(start 355.778816 -151.13)
		(end 357.886254 -151.13)
		(width 0.089408)
		(layer "In9.Cu")
		(net "IRQ_PVDDQ_KLM_VRHOT_LVT3_N")
	)
	(segment
		(start 24.5745 -158.4325)
		(end 26.222706 -156.784294)
		(width 0.089408)
		(layer "In9.Cu")
		(net "IRQ_PVDDQ_KLM_VRHOT_LVT3_N")
	)
	(segment
		(start 399.167604 -71.36765)
		(end 398.51711 -72.018144)
		(width 0.089408)
		(layer "In9.Cu")
		(net "IRQ_PVDDQ_KLM_VRHOT_LVT3_N")
	)
	(segment
		(start 279.490932 -157.861)
		(end 279.972516 -158.342584)
		(width 0.089408)
		(layer "In9.Cu")
		(net "IRQ_PVDDQ_KLM_VRHOT_LVT3_N")
	)
	(segment
		(start 425.303696 -150.0124)
		(end 429.053498 -150.0124)
		(width 0.089408)
		(layer "In9.Cu")
		(net "IRQ_PVDDQ_KLM_VRHOT_LVT3_N")
	)
	(segment
		(start 399.4785 -76.09459)
		(end 398.74317 -76.82992)
		(width 0.089408)
		(layer "In9.Cu")
		(net "IRQ_PVDDQ_KLM_VRHOT_LVT3_N")
	)
	(segment
		(start 14.224 -144.77492)
		(end 14.224 -154.94)
		(width 0.089408)
		(layer "In9.Cu")
		(net "IRQ_PVDDQ_KLM_VRHOT_LVT3_N")
	)
	(segment
		(start 350.74987 -157.009592)
		(end 353.358704 -154.400758)
		(width 0.089408)
		(layer "In9.Cu")
		(net "IRQ_PVDDQ_KLM_VRHOT_LVT3_N")
	)
	(segment
		(start 404.531068 -43.99153)
		(end 403.63775 -44.884848)
		(width 0.089408)
		(layer "In9.Cu")
		(net "IRQ_PVDDQ_KLM_VRHOT_LVT3_N")
	)
	(segment
		(start 423.710608 -152.108408)
		(end 423.710608 -151.605488)
		(width 0.089408)
		(layer "In9.Cu")
		(net "IRQ_PVDDQ_KLM_VRHOT_LVT3_N")
	)
	(segment
		(start 362.423202 -150.52675)
		(end 365.207296 -153.310844)
		(width 0.089408)
		(layer "In9.Cu")
		(net "IRQ_PVDDQ_KLM_VRHOT_LVT3_N")
	)
	(segment
		(start 404.590758 -43.75531)
		(end 404.531068 -43.815)
		(width 0.089408)
		(layer "In9.Cu")
		(net "IRQ_PVDDQ_KLM_VRHOT_LVT3_N")
	)
	(segment
		(start 166.795704 -151.914606)
		(end 168.260014 -150.450296)
		(width 0.089408)
		(layer "In9.Cu")
		(net "IRQ_PVDDQ_KLM_VRHOT_LVT3_N")
	)
	(segment
		(start 398.74317 -77.357986)
		(end 397.783812 -78.317344)
		(width 0.089408)
		(layer "In9.Cu")
		(net "IRQ_PVDDQ_KLM_VRHOT_LVT3_N")
	)
	(segment
		(start 398.4752 -156.5148)
		(end 399.401792 -155.588208)
		(width 0.089408)
		(layer "In9.Cu")
		(net "IRQ_PVDDQ_KLM_VRHOT_LVT3_N")
	)
	(segment
		(start 179.7812 -153.458418)
		(end 179.7812 -154.245818)
		(width 0.089408)
		(layer "In9.Cu")
		(net "IRQ_PVDDQ_KLM_VRHOT_LVT3_N")
	)
	(segment
		(start 412.997904 -157.219396)
		(end 421.78097 -157.219396)
		(width 0.089408)
		(layer "In9.Cu")
		(net "IRQ_PVDDQ_KLM_VRHOT_LVT3_N")
	)
	(segment
		(start 421.78097 -157.219396)
		(end 423.718228 -155.282138)
		(width 0.089408)
		(layer "In9.Cu")
		(net "IRQ_PVDDQ_KLM_VRHOT_LVT3_N")
	)
	(segment
		(start 435.38394 -144.874996)
		(end 435.38394 -143.362172)
		(width 0.089408)
		(layer "In9.Cu")
		(net "IRQ_PVDDQ_KLM_VRHOT_LVT3_N")
	)
	(segment
		(start 401.06981 -56.220106)
		(end 402.717 -57.867296)
		(width 0.089408)
		(layer "In9.Cu")
		(net "IRQ_PVDDQ_KLM_VRHOT_LVT3_N")
	)
	(segment
		(start 403.63775 -45.757592)
		(end 401.070064 -48.325278)
		(width 0.089408)
		(layer "In9.Cu")
		(net "IRQ_PVDDQ_KLM_VRHOT_LVT3_N")
	)
	(segment
		(start 100.078794 -157.101032)
		(end 164.05606 -157.101032)
		(width 0.089408)
		(layer "In9.Cu")
		(net "IRQ_PVDDQ_KLM_VRHOT_LVT3_N")
	)
	(segment
		(start 404.781512 -43.564048)
		(end 404.781512 -43.564302)
		(width 0.089408)
		(layer "In9.Cu")
		(net "IRQ_PVDDQ_KLM_VRHOT_LVT3_N")
	)
	(segment
		(start 435.38394 -145.178272)
		(end 435.38394 -145.11782)
		(width 0.089408)
		(layer "In9.Cu")
		(net "IRQ_PVDDQ_KLM_VRHOT_LVT3_N")
	)
	(segment
		(start 397.783812 -78.317344)
		(end 397.783812 -79.252572)
		(width 0.089408)
		(layer "In9.Cu")
		(net "IRQ_PVDDQ_KLM_VRHOT_LVT3_N")
	)
	(segment
		(start 406.52446 -42.534586)
		(end 405.864314 -43.194732)
		(width 0.089408)
		(layer "In9.Cu")
		(net "IRQ_PVDDQ_KLM_VRHOT_LVT3_N")
	)
	(segment
		(start 429.053498 -150.0124)
		(end 430.072038 -148.99386)
		(width 0.089408)
		(layer "In9.Cu")
		(net "IRQ_PVDDQ_KLM_VRHOT_LVT3_N")
	)
	(segment
		(start 182.249064 -156.713682)
		(end 186.177682 -156.713682)
		(width 0.089408)
		(layer "In9.Cu")
		(net "IRQ_PVDDQ_KLM_VRHOT_LVT3_N")
	)
	(segment
		(start 417.651438 -130.45567)
		(end 417.333938 -130.13817)
		(width 0.089408)
		(layer "In9.Cu")
		(net "IRQ_PVDDQ_KLM_VRHOT_LVT3_N")
	)
	(segment
		(start 423.718228 -152.116028)
		(end 423.710608 -152.108408)
		(width 0.089408)
		(layer "In9.Cu")
		(net "IRQ_PVDDQ_KLM_VRHOT_LVT3_N")
	)
	(segment
		(start 166.795704 -155.581096)
		(end 166.795704 -151.914606)
		(width 0.089408)
		(layer "In9.Cu")
		(net "IRQ_PVDDQ_KLM_VRHOT_LVT3_N")
	)
	(segment
		(start -4.666488 -139.525502)
		(end -4.666488 -141.941804)
		(width 0.089408)
		(layer "In9.Cu")
		(net "IRQ_PVDDQ_KLM_VRHOT_LVT3_N")
	)
	(segment
		(start 29.017214 -156.784294)
		(end 29.587952 -157.355032)
		(width 0.089408)
		(layer "In9.Cu")
		(net "IRQ_PVDDQ_KLM_VRHOT_LVT3_N")
	)
	(segment
		(start 427.347634 -138.588242)
		(end 426.029374 -137.269982)
		(width 0.089408)
		(layer "In9.Cu")
		(net "IRQ_PVDDQ_KLM_VRHOT_LVT3_N")
	)
	(segment
		(start 279.972516 -158.342584)
		(end 330.480416 -158.342584)
		(width 0.089408)
		(layer "In9.Cu")
		(net "IRQ_PVDDQ_KLM_VRHOT_LVT3_N")
	)
	(segment
		(start 399.4785 -73.732898)
		(end 399.4785 -76.09459)
		(width 0.089408)
		(layer "In9.Cu")
		(net "IRQ_PVDDQ_KLM_VRHOT_LVT3_N")
	)
	(segment
		(start 398.51711 -72.771508)
		(end 399.4785 -73.732898)
		(width 0.089408)
		(layer "In9.Cu")
		(net "IRQ_PVDDQ_KLM_VRHOT_LVT3_N")
	)
	(segment
		(start -2.159254 -133.6294)
		(end -1.204976 -134.583678)
		(width 0.089408)
		(layer "In9.Cu")
		(net "IRQ_PVDDQ_KLM_VRHOT_LVT3_N")
	)
	(segment
		(start -4.666488 -141.941804)
		(end -2.890012 -143.71828)
		(width 0.089408)
		(layer "In9.Cu")
		(net "IRQ_PVDDQ_KLM_VRHOT_LVT3_N")
	)
	(segment
		(start 404.531068 -43.815)
		(end 404.531068 -43.99153)
		(width 0.089408)
		(layer "In9.Cu")
		(net "IRQ_PVDDQ_KLM_VRHOT_LVT3_N")
	)
	(segment
		(start 402.717 -60.482226)
		(end 402.717254 -60.48248)
		(width 0.089408)
		(layer "In9.Cu")
		(net "IRQ_PVDDQ_KLM_VRHOT_LVT3_N")
	)
	(segment
		(start 435.38394 -143.362172)
		(end 432.776884 -140.755116)
		(width 0.089408)
		(layer "In9.Cu")
		(net "IRQ_PVDDQ_KLM_VRHOT_LVT3_N")
	)
	(segment
		(start 431.568352 -148.99386)
		(end 435.38394 -145.178272)
		(width 0.089408)
		(layer "In9.Cu")
		(net "IRQ_PVDDQ_KLM_VRHOT_LVT3_N")
	)
	(segment
		(start 417.651438 -131.320032)
		(end 417.651438 -130.45567)
		(width 0.089408)
		(layer "In9.Cu")
		(net "IRQ_PVDDQ_KLM_VRHOT_LVT3_N")
	)
	(segment
		(start 402.717508 -62.30493)
		(end 401.37588 -63.646558)
		(width 0.089408)
		(layer "In9.Cu")
		(net "IRQ_PVDDQ_KLM_VRHOT_LVT3_N")
	)
	(segment
		(start 168.260014 -150.450296)
		(end 176.773078 -150.450296)
		(width 0.089408)
		(layer "In9.Cu")
		(net "IRQ_PVDDQ_KLM_VRHOT_LVT3_N")
	)
	(segment
		(start 368.078512 -157.08503)
		(end 371.38483 -157.08503)
		(width 0.089408)
		(layer "In9.Cu")
		(net "IRQ_PVDDQ_KLM_VRHOT_LVT3_N")
	)
	(segment
		(start 358.489504 -150.52675)
		(end 362.423202 -150.52675)
		(width 0.089408)
		(layer "In9.Cu")
		(net "IRQ_PVDDQ_KLM_VRHOT_LVT3_N")
	)
	(segment
		(start 398.51711 -72.018144)
		(end 398.51711 -72.771508)
		(width 0.089408)
		(layer "In9.Cu")
		(net "IRQ_PVDDQ_KLM_VRHOT_LVT3_N")
	)
	(segment
		(start 29.587952 -157.355032)
		(end 99.824794 -157.355032)
		(width 0.089408)
		(layer "In9.Cu")
		(net "IRQ_PVDDQ_KLM_VRHOT_LVT3_N")
	)
	(segment
		(start 403.63775 -44.884848)
		(end 403.63775 -45.757592)
		(width 0.089408)
		(layer "In9.Cu")
		(net "IRQ_PVDDQ_KLM_VRHOT_LVT3_N")
	)
	(segment
		(start 402.717 -57.867296)
		(end 402.717 -60.482226)
		(width 0.089408)
		(layer "In9.Cu")
		(net "IRQ_PVDDQ_KLM_VRHOT_LVT3_N")
	)
	(segment
		(start 365.207296 -153.310844)
		(end 365.207296 -154.213814)
		(width 0.089408)
		(layer "In9.Cu")
		(net "IRQ_PVDDQ_KLM_VRHOT_LVT3_N")
	)
	(segment
		(start 357.886254 -151.13)
		(end 358.489504 -150.52675)
		(width 0.089408)
		(layer "In9.Cu")
		(net "IRQ_PVDDQ_KLM_VRHOT_LVT3_N")
	)
	(segment
		(start 417.343336 -128.565148)
		(end 417.34105 -128.562862)
		(width 0.089408)
		(layer "In9.Cu")
		(net "IRQ_PVDDQ_KLM_VRHOT_LVT3_N")
	)
	(segment
		(start 426.029374 -137.269982)
		(end 423.601388 -137.269982)
		(width 0.089408)
		(layer "In9.Cu")
		(net "IRQ_PVDDQ_KLM_VRHOT_LVT3_N")
	)
	(segment
		(start -0.487934 -143.71828)
		(end -0.06731 -143.297656)
		(width 0.089408)
		(layer "In9.Cu")
		(net "IRQ_PVDDQ_KLM_VRHOT_LVT3_N")
	)
	(segment
		(start 417.333938 -130.13817)
		(end 417.333938 -129.026666)
		(width 0.089408)
		(layer "In9.Cu")
		(net "IRQ_PVDDQ_KLM_VRHOT_LVT3_N")
	)
	(segment
		(start 401.06981 -55.745126)
		(end 401.06981 -56.220106)
		(width 0.089408)
		(layer "In9.Cu")
		(net "IRQ_PVDDQ_KLM_VRHOT_LVT3_N")
	)
	(segment
		(start -1.44018 -137.033)
		(end -2.173986 -137.033)
		(width 0.089408)
		(layer "In9.Cu")
		(net "IRQ_PVDDQ_KLM_VRHOT_LVT3_N")
	)
	(segment
		(start 398.74317 -76.82992)
		(end 398.74317 -77.357986)
		(width 0.089408)
		(layer "In9.Cu")
		(net "IRQ_PVDDQ_KLM_VRHOT_LVT3_N")
	)
	(segment
		(start -2.890012 -143.71828)
		(end -0.487934 -143.71828)
		(width 0.089408)
		(layer "In9.Cu")
		(net "IRQ_PVDDQ_KLM_VRHOT_LVT3_N")
	)
	(segment
		(start 417.34105 -128.562862)
		(end 417.34105 -128.231138)
		(width 0.089408)
		(layer "In9.Cu")
		(net "IRQ_PVDDQ_KLM_VRHOT_LVT3_N")
	)
	(segment
		(start 401.37588 -66.490342)
		(end 399.16735 -68.698872)
		(width 0.089408)
		(layer "In9.Cu")
		(net "IRQ_PVDDQ_KLM_VRHOT_LVT3_N")
	)
	(segment
		(start 404.590758 -43.755056)
		(end 404.590758 -43.75531)
		(width 0.089408)
		(layer "In9.Cu")
		(net "IRQ_PVDDQ_KLM_VRHOT_LVT3_N")
	)
	(segment
		(start -2.173986 -137.033)
		(end -4.666488 -139.525502)
		(width 0.089408)
		(layer "In9.Cu")
		(net "IRQ_PVDDQ_KLM_VRHOT_LVT3_N")
	)
	(segment
		(start 17.7165 -158.4325)
		(end 24.5745 -158.4325)
		(width 0.089408)
		(layer "In9.Cu")
		(net "IRQ_PVDDQ_KLM_VRHOT_LVT3_N")
	)
	(segment
		(start 392.412728 -158.216092)
		(end 394.11402 -156.5148)
		(width 0.089408)
		(layer "In9.Cu")
		(net "IRQ_PVDDQ_KLM_VRHOT_LVT3_N")
	)
	(segment
		(start 401.070064 -55.744872)
		(end 401.06981 -55.745126)
		(width 0.089408)
		(layer "In9.Cu")
		(net "IRQ_PVDDQ_KLM_VRHOT_LVT3_N")
	)
	(segment
		(start 435.384194 -145.117566)
		(end 435.384194 -144.87525)
		(width 0.089408)
		(layer "In9.Cu")
		(net "IRQ_PVDDQ_KLM_VRHOT_LVT3_N")
	)
	(segment
		(start 371.38483 -157.08503)
		(end 372.515892 -158.216092)
		(width 0.089408)
		(layer "In9.Cu")
		(net "IRQ_PVDDQ_KLM_VRHOT_LVT3_N")
	)
	(segment
		(start 423.710608 -151.605488)
		(end 425.303696 -150.0124)
		(width 0.089408)
		(layer "In9.Cu")
		(net "IRQ_PVDDQ_KLM_VRHOT_LVT3_N")
	)
	(segment
		(start 403.245574 -155.588208)
		(end 403.588982 -155.931616)
		(width 0.089408)
		(layer "In9.Cu")
		(net "IRQ_PVDDQ_KLM_VRHOT_LVT3_N")
	)
	(segment
		(start 402.717254 -61.037216)
		(end 402.717508 -61.03747)
		(width 0.089408)
		(layer "In9.Cu")
		(net "IRQ_PVDDQ_KLM_VRHOT_LVT3_N")
	)
	(segment
		(start 401.070064 -48.325278)
		(end 401.070064 -55.744872)
		(width 0.089408)
		(layer "In9.Cu")
		(net "IRQ_PVDDQ_KLM_VRHOT_LVT3_N")
	)
	(segment
		(start 417.343336 -128.228852)
		(end 417.343336 -127.17907)
		(width 0.089408)
		(layer "In9.Cu")
		(net "IRQ_PVDDQ_KLM_VRHOT_LVT3_N")
	)
	(segment
		(start 417.343336 -127.17907)
		(end 416.334702 -126.170436)
		(width 0.089408)
		(layer "In9.Cu")
		(net "IRQ_PVDDQ_KLM_VRHOT_LVT3_N")
	)
	(segment
		(start 399.16735 -68.85686)
		(end 399.167604 -68.857114)
		(width 0.089408)
		(layer "In9.Cu")
		(net "IRQ_PVDDQ_KLM_VRHOT_LVT3_N")
	)
	(segment
		(start 372.515892 -158.216092)
		(end 392.412728 -158.216092)
		(width 0.089408)
		(layer "In9.Cu")
		(net "IRQ_PVDDQ_KLM_VRHOT_LVT3_N")
	)
	(segment
		(start 403.588982 -155.931616)
		(end 407.28138 -155.931616)
		(width 0.089408)
		(layer "In9.Cu")
		(net "IRQ_PVDDQ_KLM_VRHOT_LVT3_N")
	)
	(segment
		(start 404.781512 -43.564302)
		(end 404.590758 -43.755056)
		(width 0.089408)
		(layer "In9.Cu")
		(net "IRQ_PVDDQ_KLM_VRHOT_LVT3_N")
	)
	(segment
		(start 405.150828 -43.194732)
		(end 404.781512 -43.564048)
		(width 0.089408)
		(layer "In9.Cu")
		(net "IRQ_PVDDQ_KLM_VRHOT_LVT3_N")
	)
	(segment
		(start 186.177682 -156.713682)
		(end 187.672218 -158.208218)
		(width 0.089408)
		(layer "In9.Cu")
		(net "IRQ_PVDDQ_KLM_VRHOT_LVT3_N")
	)
	(segment
		(start 402.717254 -60.48248)
		(end 402.717254 -61.037216)
		(width 0.089408)
		(layer "In9.Cu")
		(net "IRQ_PVDDQ_KLM_VRHOT_LVT3_N")
	)
	(segment
		(start 331.997304 -156.825696)
		(end 348.709488 -156.825696)
		(width 0.089408)
		(layer "In9.Cu")
		(net "IRQ_PVDDQ_KLM_VRHOT_LVT3_N")
	)
	(segment
		(start 401.37588 -63.646558)
		(end 401.37588 -66.490342)
		(width 0.089408)
		(layer "In9.Cu")
		(net "IRQ_PVDDQ_KLM_VRHOT_LVT3_N")
	)
	(segment
		(start 402.717508 -61.03747)
		(end 402.717508 -62.30493)
		(width 0.089408)
		(layer "In9.Cu")
		(net "IRQ_PVDDQ_KLM_VRHOT_LVT3_N")
	)
	(segment
		(start -1.204976 -134.583678)
		(end -1.204976 -136.797796)
		(width 0.089408)
		(layer "In9.Cu")
		(net "IRQ_PVDDQ_KLM_VRHOT_LVT3_N")
	)
	(segment
		(start 165.175692 -155.9814)
		(end 166.3954 -155.9814)
		(width 0.089408)
		(layer "In9.Cu")
		(net "IRQ_PVDDQ_KLM_VRHOT_LVT3_N")
	)
	(segment
		(start 423.718228 -155.282138)
		(end 423.718228 -152.116028)
		(width 0.089408)
		(layer "In9.Cu")
		(net "IRQ_PVDDQ_KLM_VRHOT_LVT3_N")
	)
	(segment
		(start 348.893384 -157.009592)
		(end 350.74987 -157.009592)
		(width 0.089408)
		(layer "In9.Cu")
		(net "IRQ_PVDDQ_KLM_VRHOT_LVT3_N")
	)
	(segment
		(start 179.7812 -154.245818)
		(end 182.249064 -156.713682)
		(width 0.089408)
		(layer "In9.Cu")
		(net "IRQ_PVDDQ_KLM_VRHOT_LVT3_N")
	)
	(segment
		(start 399.401792 -155.588208)
		(end 403.245574 -155.588208)
		(width 0.089408)
		(layer "In9.Cu")
		(net "IRQ_PVDDQ_KLM_VRHOT_LVT3_N")
	)
	(segment
		(start 435.38394 -145.11782)
		(end 435.384194 -145.117566)
		(width 0.089408)
		(layer "In9.Cu")
		(net "IRQ_PVDDQ_KLM_VRHOT_LVT3_N")
	)
	(segment
		(start 435.384194 -144.87525)
		(end 435.38394 -144.874996)
		(width 0.089408)
		(layer "In9.Cu")
		(net "IRQ_PVDDQ_KLM_VRHOT_LVT3_N")
	)
	(segment
		(start 353.358704 -154.400758)
		(end 353.358704 -153.550112)
		(width 0.089408)
		(layer "In9.Cu")
		(net "IRQ_PVDDQ_KLM_VRHOT_LVT3_N")
	)
	(segment
		(start 399.16735 -68.698872)
		(end 399.16735 -68.85686)
		(width 0.089408)
		(layer "In9.Cu")
		(net "IRQ_PVDDQ_KLM_VRHOT_LVT3_N")
	)
	(segment
		(start 397.360394 -79.67599)
		(end 397.360394 -80.06334)
		(width 0.089408)
		(layer "In9.Cu")
		(net "IRQ_PVDDQ_KLM_VRHOT_LVT3_N")
	)
	(segment
		(start 176.773078 -150.450296)
		(end 179.7812 -153.458418)
		(width 0.089408)
		(layer "In9.Cu")
		(net "IRQ_PVDDQ_KLM_VRHOT_LVT3_N")
	)
	(segment
		(start 399.167604 -68.857114)
		(end 399.167604 -71.36765)
		(width 0.089408)
		(layer "In9.Cu")
		(net "IRQ_PVDDQ_KLM_VRHOT_LVT3_N")
	)
	(segment
		(start 428.848266 -138.588242)
		(end 427.347634 -138.588242)
		(width 0.089408)
		(layer "In9.Cu")
		(net "IRQ_PVDDQ_KLM_VRHOT_LVT3_N")
	)
	(segment
		(start 166.3954 -155.9814)
		(end 166.795704 -155.581096)
		(width 0.089408)
		(layer "In9.Cu")
		(net "IRQ_PVDDQ_KLM_VRHOT_LVT3_N")
	)
	(segment
		(start 408.41295 -154.802332)
		(end 410.58084 -154.802332)
		(width 0.089408)
		(layer "In9.Cu")
		(net "IRQ_PVDDQ_KLM_VRHOT_LVT3_N")
	)
	(segment
		(start 14.684248 -4.43103)
		(end 15.750032 -3.365246)
		(width 0.10795)
		(layer "F.Cu")
		(net "IRQ_PVDDQ_GHJ_VRHOT_LVT3_N")
	)
	(segment
		(start 396.751048 -57.896252)
		(end 397.703548 -58.848752)
		(width 0.10795)
		(layer "F.Cu")
		(net "IRQ_PVDDQ_GHJ_VRHOT_LVT3_N")
	)
	(segment
		(start 390.644888 -59.944)
		(end 389.717788 -60.8711)
		(width 0.10795)
		(layer "F.Cu")
		(net "IRQ_PVDDQ_GHJ_VRHOT_LVT3_N")
	)
	(segment
		(start 400.313652 -61.679074)
		(end 400.81327 -61.179456)
		(width 0.10795)
		(layer "F.Cu")
		(net "IRQ_PVDDQ_GHJ_VRHOT_LVT3_N")
	)
	(segment
		(start 386.743702 -60.8711)
		(end 386.359908 -61.254894)
		(width 0.10795)
		(layer "F.Cu")
		(net "IRQ_PVDDQ_GHJ_VRHOT_LVT3_N")
	)
	(segment
		(start 386.359908 -61.254894)
		(end 385.997958 -61.254894)
		(width 0.10795)
		(layer "F.Cu")
		(net "IRQ_PVDDQ_GHJ_VRHOT_LVT3_N")
	)
	(segment
		(start 377.700032 -62.970664)
		(end 377.679204 -62.949836)
		(width 0.10795)
		(layer "F.Cu")
		(net "IRQ_PVDDQ_GHJ_VRHOT_LVT3_N")
	)
	(segment
		(start 397.703548 -58.848752)
		(end 397.703548 -60.589668)
		(width 0.10795)
		(layer "F.Cu")
		(net "IRQ_PVDDQ_GHJ_VRHOT_LVT3_N")
	)
	(segment
		(start 385.997958 -61.254894)
		(end 385.303776 -60.560712)
		(width 0.10795)
		(layer "F.Cu")
		(net "IRQ_PVDDQ_GHJ_VRHOT_LVT3_N")
	)
	(segment
		(start 392.692636 -57.896252)
		(end 396.751048 -57.896252)
		(width 0.10795)
		(layer "F.Cu")
		(net "IRQ_PVDDQ_GHJ_VRHOT_LVT3_N")
	)
	(segment
		(start 403.675596 -55.126382)
		(end 403.99335 -55.126382)
		(width 0.10795)
		(layer "F.Cu")
		(net "IRQ_PVDDQ_GHJ_VRHOT_LVT3_N")
	)
	(segment
		(start 382.667256 -60.560712)
		(end 380.257304 -62.970664)
		(width 0.10795)
		(layer "F.Cu")
		(net "IRQ_PVDDQ_GHJ_VRHOT_LVT3_N")
	)
	(segment
		(start 389.717788 -60.8711)
		(end 386.743702 -60.8711)
		(width 0.10795)
		(layer "F.Cu")
		(net "IRQ_PVDDQ_GHJ_VRHOT_LVT3_N")
	)
	(segment
		(start 385.303776 -60.560712)
		(end 382.667256 -60.560712)
		(width 0.10795)
		(layer "F.Cu")
		(net "IRQ_PVDDQ_GHJ_VRHOT_LVT3_N")
	)
	(segment
		(start 412.690056 -41.73474)
		(end 412.312104 -42.112692)
		(width 0.10795)
		(layer "F.Cu")
		(net "IRQ_PVDDQ_GHJ_VRHOT_LVT3_N")
	)
	(segment
		(start 400.81327 -61.179456)
		(end 400.81327 -57.988708)
		(width 0.10795)
		(layer "F.Cu")
		(net "IRQ_PVDDQ_GHJ_VRHOT_LVT3_N")
	)
	(segment
		(start 397.703548 -60.589668)
		(end 398.792954 -61.679074)
		(width 0.10795)
		(layer "F.Cu")
		(net "IRQ_PVDDQ_GHJ_VRHOT_LVT3_N")
	)
	(segment
		(start 390.644888 -59.944)
		(end 392.692636 -57.896252)
		(width 0.10795)
		(layer "F.Cu")
		(net "IRQ_PVDDQ_GHJ_VRHOT_LVT3_N")
	)
	(segment
		(start 380.257304 -62.970664)
		(end 377.700032 -62.970664)
		(width 0.10795)
		(layer "F.Cu")
		(net "IRQ_PVDDQ_GHJ_VRHOT_LVT3_N")
	)
	(segment
		(start 395.66215 -101.039676)
		(end 395.16685 -101.2698)
		(width 0.10795)
		(layer "F.Cu")
		(net "IRQ_PVDDQ_GHJ_VRHOT_LVT3_N")
	)
	(segment
		(start 14.209268 -4.43103)
		(end 14.684248 -4.43103)
		(width 0.10795)
		(layer "F.Cu")
		(net "IRQ_PVDDQ_GHJ_VRHOT_LVT3_N")
	)
	(segment
		(start 400.81327 -57.988708)
		(end 403.675596 -55.126382)
		(width 0.10795)
		(layer "F.Cu")
		(net "IRQ_PVDDQ_GHJ_VRHOT_LVT3_N")
	)
	(segment
		(start 398.792954 -61.679074)
		(end 400.313652 -61.679074)
		(width 0.10795)
		(layer "F.Cu")
		(net "IRQ_PVDDQ_GHJ_VRHOT_LVT3_N")
	)
	(via
		(at 395.66215 -101.039676)
		(size 0.508)
		(drill 0.254)
		(layers "F.Cu" "B.Cu")
		(net "IRQ_PVDDQ_GHJ_VRHOT_LVT3_N")
	)
	(via
		(at 408.754834 -88.434164)
		(size 0.508)
		(drill 0.254)
		(layers "F.Cu" "B.Cu")
		(net "IRQ_PVDDQ_GHJ_VRHOT_LVT3_N")
	)
	(via
		(at 412.312104 -42.112692)
		(size 0.4572)
		(drill 0.2032)
		(layers "F.Cu" "B.Cu")
		(net "IRQ_PVDDQ_GHJ_VRHOT_LVT3_N")
	)
	(via
		(at 413.035496 -57.2135)
		(size 0.508)
		(drill 0.254)
		(layers "F.Cu" "B.Cu")
		(net "IRQ_PVDDQ_GHJ_VRHOT_LVT3_N")
	)
	(via
		(at 406.2222 -88.9508)
		(size 0.6604)
		(drill 0.3302)
		(layers "F.Cu" "B.Cu")
		(net "IRQ_PVDDQ_GHJ_VRHOT_LVT3_N")
	)
	(via
		(at 15.750032 -3.365246)
		(size 0.508)
		(drill 0.254)
		(layers "F.Cu" "B.Cu")
		(net "IRQ_PVDDQ_GHJ_VRHOT_LVT3_N")
	)
	(via
		(at 403.99335 -55.126382)
		(size 0.508)
		(drill 0.254)
		(layers "F.Cu" "B.Cu")
		(net "IRQ_PVDDQ_GHJ_VRHOT_LVT3_N")
	)
	(via
		(at 390.644888 -59.944)
		(size 0.508)
		(drill 0.254)
		(layers "F.Cu" "B.Cu")
		(net "IRQ_PVDDQ_GHJ_VRHOT_LVT3_N")
	)
	(via
		(at 377.679204 -62.949836)
		(size 0.508)
		(drill 0.254)
		(layers "F.Cu" "B.Cu")
		(net "IRQ_PVDDQ_GHJ_VRHOT_LVT3_N")
	)
	(segment
		(start 410.170376 -88.176354)
		(end 409.884118 -88.176354)
		(width 0.10795)
		(layer "B.Cu")
		(net "IRQ_PVDDQ_GHJ_VRHOT_LVT3_N")
	)
	(segment
		(start 394.626084 -98.58629)
		(end 394.626084 -98.259138)
		(width 0.10795)
		(layer "B.Cu")
		(net "IRQ_PVDDQ_GHJ_VRHOT_LVT3_N")
	)
	(segment
		(start 402.138134 -89.371424)
		(end 402.914358 -88.5952)
		(width 0.10795)
		(layer "B.Cu")
		(net "IRQ_PVDDQ_GHJ_VRHOT_LVT3_N")
	)
	(segment
		(start 398.805654 -93.366082)
		(end 398.805654 -92.737178)
		(width 0.10795)
		(layer "B.Cu")
		(net "IRQ_PVDDQ_GHJ_VRHOT_LVT3_N")
	)
	(segment
		(start 405.8666 -88.5952)
		(end 406.2222 -88.9508)
		(width 0.10795)
		(layer "B.Cu")
		(net "IRQ_PVDDQ_GHJ_VRHOT_LVT3_N")
	)
	(segment
		(start 395.607032 -96.960944)
		(end 395.607032 -96.623886)
		(width 0.10795)
		(layer "B.Cu")
		(net "IRQ_PVDDQ_GHJ_VRHOT_LVT3_N")
	)
	(segment
		(start 403.99335 -55.910734)
		(end 403.99335 -55.126382)
		(width 0.10795)
		(layer "B.Cu")
		(net "IRQ_PVDDQ_GHJ_VRHOT_LVT3_N")
	)
	(segment
		(start 413.035496 -57.2135)
		(end 413.01543 -57.2135)
		(width 0.10795)
		(layer "B.Cu")
		(net "IRQ_PVDDQ_GHJ_VRHOT_LVT3_N")
	)
	(segment
		(start 398.805654 -92.737178)
		(end 399.600166 -91.942666)
		(width 0.10795)
		(layer "B.Cu")
		(net "IRQ_PVDDQ_GHJ_VRHOT_LVT3_N")
	)
	(segment
		(start 408.754834 -88.434164)
		(end 409.012644 -88.176354)
		(width 0.10795)
		(layer "B.Cu")
		(net "IRQ_PVDDQ_GHJ_VRHOT_LVT3_N")
	)
	(segment
		(start 395.66215 -100.038408)
		(end 395.101826 -99.478084)
		(width 0.10795)
		(layer "B.Cu")
		(net "IRQ_PVDDQ_GHJ_VRHOT_LVT3_N")
	)
	(segment
		(start 395.607032 -96.623886)
		(end 396.112238 -96.11868)
		(width 0.10795)
		(layer "B.Cu")
		(net "IRQ_PVDDQ_GHJ_VRHOT_LVT3_N")
	)
	(segment
		(start 409.72613 -57.8612)
		(end 405.943816 -57.8612)
		(width 0.10795)
		(layer "B.Cu")
		(net "IRQ_PVDDQ_GHJ_VRHOT_LVT3_N")
	)
	(segment
		(start 395.101826 -99.478084)
		(end 395.101826 -99.062032)
		(width 0.10795)
		(layer "B.Cu")
		(net "IRQ_PVDDQ_GHJ_VRHOT_LVT3_N")
	)
	(segment
		(start 397.882364 -93.890592)
		(end 397.882618 -93.890846)
		(width 0.10795)
		(layer "B.Cu")
		(net "IRQ_PVDDQ_GHJ_VRHOT_LVT3_N")
	)
	(segment
		(start 401.03298 -89.371424)
		(end 402.138134 -89.371424)
		(width 0.10795)
		(layer "B.Cu")
		(net "IRQ_PVDDQ_GHJ_VRHOT_LVT3_N")
	)
	(segment
		(start 395.66215 -101.039676)
		(end 395.66215 -100.038408)
		(width 0.10795)
		(layer "B.Cu")
		(net "IRQ_PVDDQ_GHJ_VRHOT_LVT3_N")
	)
	(segment
		(start 406.5778 -89.3064)
		(end 410.34081 -89.3064)
		(width 0.10795)
		(layer "B.Cu")
		(net "IRQ_PVDDQ_GHJ_VRHOT_LVT3_N")
	)
	(segment
		(start 395.101826 -99.062032)
		(end 394.626084 -98.58629)
		(width 0.10795)
		(layer "B.Cu")
		(net "IRQ_PVDDQ_GHJ_VRHOT_LVT3_N")
	)
	(segment
		(start 410.56052 -88.566498)
		(end 410.170376 -88.176354)
		(width 0.10795)
		(layer "B.Cu")
		(net "IRQ_PVDDQ_GHJ_VRHOT_LVT3_N")
	)
	(segment
		(start 398.055846 -93.890846)
		(end 398.0561 -93.890592)
		(width 0.10795)
		(layer "B.Cu")
		(net "IRQ_PVDDQ_GHJ_VRHOT_LVT3_N")
	)
	(segment
		(start 399.600166 -90.804238)
		(end 401.03298 -89.371424)
		(width 0.10795)
		(layer "B.Cu")
		(net "IRQ_PVDDQ_GHJ_VRHOT_LVT3_N")
	)
	(segment
		(start 406.2222 -88.9508)
		(end 406.5778 -89.3064)
		(width 0.10795)
		(layer "B.Cu")
		(net "IRQ_PVDDQ_GHJ_VRHOT_LVT3_N")
	)
	(segment
		(start 410.34081 -89.3064)
		(end 410.56052 -89.08669)
		(width 0.10795)
		(layer "B.Cu")
		(net "IRQ_PVDDQ_GHJ_VRHOT_LVT3_N")
	)
	(segment
		(start 399.600166 -91.942666)
		(end 399.600166 -90.804238)
		(width 0.10795)
		(layer "B.Cu")
		(net "IRQ_PVDDQ_GHJ_VRHOT_LVT3_N")
	)
	(segment
		(start 398.0561 -93.890592)
		(end 398.281144 -93.890592)
		(width 0.10795)
		(layer "B.Cu")
		(net "IRQ_PVDDQ_GHJ_VRHOT_LVT3_N")
	)
	(segment
		(start 397.377158 -93.890592)
		(end 397.882364 -93.890592)
		(width 0.10795)
		(layer "B.Cu")
		(net "IRQ_PVDDQ_GHJ_VRHOT_LVT3_N")
	)
	(segment
		(start 396.112238 -96.11868)
		(end 396.112238 -95.155512)
		(width 0.10795)
		(layer "B.Cu")
		(net "IRQ_PVDDQ_GHJ_VRHOT_LVT3_N")
	)
	(segment
		(start 397.882618 -93.890846)
		(end 398.055846 -93.890846)
		(width 0.10795)
		(layer "B.Cu")
		(net "IRQ_PVDDQ_GHJ_VRHOT_LVT3_N")
	)
	(segment
		(start 394.626084 -98.259138)
		(end 395.151356 -97.733866)
		(width 0.10795)
		(layer "B.Cu")
		(net "IRQ_PVDDQ_GHJ_VRHOT_LVT3_N")
	)
	(segment
		(start 412.121096 -56.319166)
		(end 411.268164 -56.319166)
		(width 0.10795)
		(layer "B.Cu")
		(net "IRQ_PVDDQ_GHJ_VRHOT_LVT3_N")
	)
	(segment
		(start 413.01543 -57.2135)
		(end 412.121096 -56.319166)
		(width 0.10795)
		(layer "B.Cu")
		(net "IRQ_PVDDQ_GHJ_VRHOT_LVT3_N")
	)
	(segment
		(start 396.112238 -95.155512)
		(end 397.377158 -93.890592)
		(width 0.10795)
		(layer "B.Cu")
		(net "IRQ_PVDDQ_GHJ_VRHOT_LVT3_N")
	)
	(segment
		(start 395.151356 -97.41662)
		(end 395.607032 -96.960944)
		(width 0.10795)
		(layer "B.Cu")
		(net "IRQ_PVDDQ_GHJ_VRHOT_LVT3_N")
	)
	(segment
		(start 398.281144 -93.890592)
		(end 398.805654 -93.366082)
		(width 0.10795)
		(layer "B.Cu")
		(net "IRQ_PVDDQ_GHJ_VRHOT_LVT3_N")
	)
	(segment
		(start 402.914358 -88.5952)
		(end 405.8666 -88.5952)
		(width 0.10795)
		(layer "B.Cu")
		(net "IRQ_PVDDQ_GHJ_VRHOT_LVT3_N")
	)
	(segment
		(start 411.268164 -56.319166)
		(end 409.72613 -57.8612)
		(width 0.10795)
		(layer "B.Cu")
		(net "IRQ_PVDDQ_GHJ_VRHOT_LVT3_N")
	)
	(segment
		(start 405.943816 -57.8612)
		(end 403.99335 -55.910734)
		(width 0.10795)
		(layer "B.Cu")
		(net "IRQ_PVDDQ_GHJ_VRHOT_LVT3_N")
	)
	(segment
		(start 409.012644 -88.176354)
		(end 409.884118 -88.176354)
		(width 0.10795)
		(layer "B.Cu")
		(net "IRQ_PVDDQ_GHJ_VRHOT_LVT3_N")
	)
	(segment
		(start 410.56052 -89.08669)
		(end 410.56052 -88.566498)
		(width 0.10795)
		(layer "B.Cu")
		(net "IRQ_PVDDQ_GHJ_VRHOT_LVT3_N")
	)
	(segment
		(start 395.151356 -97.733866)
		(end 395.151356 -97.41662)
		(width 0.10795)
		(layer "B.Cu")
		(net "IRQ_PVDDQ_GHJ_VRHOT_LVT3_N")
	)
	(segment
		(start 391.673334 -52.338224)
		(end 391.673334 -58.365898)
		(width 0.089408)
		(layer "In2.Cu")
		(net "IRQ_PVDDQ_GHJ_VRHOT_LVT3_N")
	)
	(segment
		(start 390.649206 -46.53407)
		(end 390.649206 -46.692058)
		(width 0.089408)
		(layer "In2.Cu")
		(net "IRQ_PVDDQ_GHJ_VRHOT_LVT3_N")
	)
	(segment
		(start 390.64946 -46.488604)
		(end 390.649714 -46.488858)
		(width 0.089408)
		(layer "In2.Cu")
		(net "IRQ_PVDDQ_GHJ_VRHOT_LVT3_N")
	)
	(segment
		(start 390.64946 -46.692312)
		(end 390.64946 -47.008796)
		(width 0.089408)
		(layer "In2.Cu")
		(net "IRQ_PVDDQ_GHJ_VRHOT_LVT3_N")
	)
	(segment
		(start 405.06396 -79.489808)
		(end 405.063706 -79.490062)
		(width 0.089408)
		(layer "In2.Cu")
		(net "IRQ_PVDDQ_GHJ_VRHOT_LVT3_N")
	)
	(segment
		(start 390.649714 -47.00905)
		(end 390.649714 -47.167038)
		(width 0.089408)
		(layer "In2.Cu")
		(net "IRQ_PVDDQ_GHJ_VRHOT_LVT3_N")
	)
	(segment
		(start 390.649714 -47.167038)
		(end 390.868408 -47.385732)
		(width 0.089408)
		(layer "In2.Cu")
		(net "IRQ_PVDDQ_GHJ_VRHOT_LVT3_N")
	)
	(segment
		(start 407.533856 -82.752184)
		(end 407.533856 -87.369396)
		(width 0.089408)
		(layer "In2.Cu")
		(net "IRQ_PVDDQ_GHJ_VRHOT_LVT3_N")
	)
	(segment
		(start 408.598624 -88.434164)
		(end 408.754834 -88.434164)
		(width 0.089408)
		(layer "In2.Cu")
		(net "IRQ_PVDDQ_GHJ_VRHOT_LVT3_N")
	)
	(segment
		(start 390.644888 -59.394344)
		(end 390.644888 -59.944)
		(width 0.089408)
		(layer "In2.Cu")
		(net "IRQ_PVDDQ_GHJ_VRHOT_LVT3_N")
	)
	(segment
		(start 404.56612 -78.55204)
		(end 405.06396 -79.04988)
		(width 0.089408)
		(layer "In2.Cu")
		(net "IRQ_PVDDQ_GHJ_VRHOT_LVT3_N")
	)
	(segment
		(start 410.86786 -68.591938)
		(end 405.177244 -74.282554)
		(width 0.089408)
		(layer "In2.Cu")
		(net "IRQ_PVDDQ_GHJ_VRHOT_LVT3_N")
	)
	(segment
		(start 400.657568 -43.84802)
		(end 397.709644 -43.84802)
		(width 0.089408)
		(layer "In2.Cu")
		(net "IRQ_PVDDQ_GHJ_VRHOT_LVT3_N")
	)
	(segment
		(start 397.709644 -43.84802)
		(end 396.277592 -45.280072)
		(width 0.089408)
		(layer "In2.Cu")
		(net "IRQ_PVDDQ_GHJ_VRHOT_LVT3_N")
	)
	(segment
		(start 407.533856 -87.369396)
		(end 408.598624 -88.434164)
		(width 0.089408)
		(layer "In2.Cu")
		(net "IRQ_PVDDQ_GHJ_VRHOT_LVT3_N")
	)
	(segment
		(start 391.878058 -45.279564)
		(end 391.87755 -45.280072)
		(width 0.089408)
		(layer "In2.Cu")
		(net "IRQ_PVDDQ_GHJ_VRHOT_LVT3_N")
	)
	(segment
		(start 391.700004 -45.280072)
		(end 390.64946 -46.330616)
		(width 0.089408)
		(layer "In2.Cu")
		(net "IRQ_PVDDQ_GHJ_VRHOT_LVT3_N")
	)
	(segment
		(start 412.312104 -41.903904)
		(end 411.8864 -41.4782)
		(width 0.089408)
		(layer "In2.Cu")
		(net "IRQ_PVDDQ_GHJ_VRHOT_LVT3_N")
	)
	(segment
		(start 412.16326 -56.341264)
		(end 411.609794 -56.341264)
		(width 0.089408)
		(layer "In2.Cu")
		(net "IRQ_PVDDQ_GHJ_VRHOT_LVT3_N")
	)
	(segment
		(start 405.06396 -79.04988)
		(end 405.06396 -79.489808)
		(width 0.089408)
		(layer "In2.Cu")
		(net "IRQ_PVDDQ_GHJ_VRHOT_LVT3_N")
	)
	(segment
		(start 391.673334 -58.365898)
		(end 390.644888 -59.394344)
		(width 0.089408)
		(layer "In2.Cu")
		(net "IRQ_PVDDQ_GHJ_VRHOT_LVT3_N")
	)
	(segment
		(start 392.194542 -45.280072)
		(end 392.194288 -45.279818)
		(width 0.089408)
		(layer "In2.Cu")
		(net "IRQ_PVDDQ_GHJ_VRHOT_LVT3_N")
	)
	(segment
		(start 405.177244 -74.604372)
		(end 404.56612 -75.215496)
		(width 0.089408)
		(layer "In2.Cu")
		(net "IRQ_PVDDQ_GHJ_VRHOT_LVT3_N")
	)
	(segment
		(start 392.036046 -45.279564)
		(end 391.878058 -45.279564)
		(width 0.089408)
		(layer "In2.Cu")
		(net "IRQ_PVDDQ_GHJ_VRHOT_LVT3_N")
	)
	(segment
		(start 390.868408 -51.533298)
		(end 391.673334 -52.338224)
		(width 0.089408)
		(layer "In2.Cu")
		(net "IRQ_PVDDQ_GHJ_VRHOT_LVT3_N")
	)
	(segment
		(start 404.56612 -75.215496)
		(end 404.56612 -78.55204)
		(width 0.089408)
		(layer "In2.Cu")
		(net "IRQ_PVDDQ_GHJ_VRHOT_LVT3_N")
	)
	(segment
		(start 405.177244 -74.282554)
		(end 405.177244 -74.604372)
		(width 0.089408)
		(layer "In2.Cu")
		(net "IRQ_PVDDQ_GHJ_VRHOT_LVT3_N")
	)
	(segment
		(start 403.687788 -40.8178)
		(end 400.657568 -43.84802)
		(width 0.089408)
		(layer "In2.Cu")
		(net "IRQ_PVDDQ_GHJ_VRHOT_LVT3_N")
	)
	(segment
		(start 412.312104 -42.112692)
		(end 412.312104 -41.903904)
		(width 0.089408)
		(layer "In2.Cu")
		(net "IRQ_PVDDQ_GHJ_VRHOT_LVT3_N")
	)
	(segment
		(start 411.8864 -41.1734)
		(end 411.671262 -40.958262)
		(width 0.089408)
		(layer "In2.Cu")
		(net "IRQ_PVDDQ_GHJ_VRHOT_LVT3_N")
	)
	(segment
		(start 405.063706 -79.490062)
		(end 405.063706 -80.282034)
		(width 0.089408)
		(layer "In2.Cu")
		(net "IRQ_PVDDQ_GHJ_VRHOT_LVT3_N")
	)
	(segment
		(start 390.649714 -46.533562)
		(end 390.649206 -46.53407)
		(width 0.089408)
		(layer "In2.Cu")
		(net "IRQ_PVDDQ_GHJ_VRHOT_LVT3_N")
	)
	(segment
		(start 392.0363 -45.279818)
		(end 392.036046 -45.279564)
		(width 0.089408)
		(layer "In2.Cu")
		(net "IRQ_PVDDQ_GHJ_VRHOT_LVT3_N")
	)
	(segment
		(start 410.86786 -57.083198)
		(end 410.86786 -68.591938)
		(width 0.089408)
		(layer "In2.Cu")
		(net "IRQ_PVDDQ_GHJ_VRHOT_LVT3_N")
	)
	(segment
		(start 413.035496 -57.2135)
		(end 412.16326 -56.341264)
		(width 0.089408)
		(layer "In2.Cu")
		(net "IRQ_PVDDQ_GHJ_VRHOT_LVT3_N")
	)
	(segment
		(start 411.8864 -41.4782)
		(end 411.8864 -41.1734)
		(width 0.089408)
		(layer "In2.Cu")
		(net "IRQ_PVDDQ_GHJ_VRHOT_LVT3_N")
	)
	(segment
		(start 391.87755 -45.280072)
		(end 391.700004 -45.280072)
		(width 0.089408)
		(layer "In2.Cu")
		(net "IRQ_PVDDQ_GHJ_VRHOT_LVT3_N")
	)
	(segment
		(start 390.64946 -46.330616)
		(end 390.64946 -46.488604)
		(width 0.089408)
		(layer "In2.Cu")
		(net "IRQ_PVDDQ_GHJ_VRHOT_LVT3_N")
	)
	(segment
		(start 405.063706 -80.282034)
		(end 407.533856 -82.752184)
		(width 0.089408)
		(layer "In2.Cu")
		(net "IRQ_PVDDQ_GHJ_VRHOT_LVT3_N")
	)
	(segment
		(start 407.200862 -40.958262)
		(end 407.0604 -40.8178)
		(width 0.089408)
		(layer "In2.Cu")
		(net "IRQ_PVDDQ_GHJ_VRHOT_LVT3_N")
	)
	(segment
		(start 411.609794 -56.341264)
		(end 410.86786 -57.083198)
		(width 0.089408)
		(layer "In2.Cu")
		(net "IRQ_PVDDQ_GHJ_VRHOT_LVT3_N")
	)
	(segment
		(start 411.671262 -40.958262)
		(end 407.200862 -40.958262)
		(width 0.089408)
		(layer "In2.Cu")
		(net "IRQ_PVDDQ_GHJ_VRHOT_LVT3_N")
	)
	(segment
		(start 396.277592 -45.280072)
		(end 392.194542 -45.280072)
		(width 0.089408)
		(layer "In2.Cu")
		(net "IRQ_PVDDQ_GHJ_VRHOT_LVT3_N")
	)
	(segment
		(start 407.0604 -40.8178)
		(end 403.687788 -40.8178)
		(width 0.089408)
		(layer "In2.Cu")
		(net "IRQ_PVDDQ_GHJ_VRHOT_LVT3_N")
	)
	(segment
		(start 392.194288 -45.279818)
		(end 392.0363 -45.279818)
		(width 0.089408)
		(layer "In2.Cu")
		(net "IRQ_PVDDQ_GHJ_VRHOT_LVT3_N")
	)
	(segment
		(start 390.868408 -47.385732)
		(end 390.868408 -51.533298)
		(width 0.089408)
		(layer "In2.Cu")
		(net "IRQ_PVDDQ_GHJ_VRHOT_LVT3_N")
	)
	(segment
		(start 390.64946 -47.008796)
		(end 390.649714 -47.00905)
		(width 0.089408)
		(layer "In2.Cu")
		(net "IRQ_PVDDQ_GHJ_VRHOT_LVT3_N")
	)
	(segment
		(start 390.649206 -46.692058)
		(end 390.64946 -46.692312)
		(width 0.089408)
		(layer "In2.Cu")
		(net "IRQ_PVDDQ_GHJ_VRHOT_LVT3_N")
	)
	(segment
		(start 390.649714 -46.488858)
		(end 390.649714 -46.533562)
		(width 0.089408)
		(layer "In2.Cu")
		(net "IRQ_PVDDQ_GHJ_VRHOT_LVT3_N")
	)
	(segment
		(start 167.469566 -3.098292)
		(end 167.469566 -2.262632)
		(width 0.089408)
		(layer "In11.Cu")
		(net "IRQ_PVDDQ_GHJ_VRHOT_LVT3_N")
	)
	(segment
		(start 183.451754 3.55727)
		(end 183.759094 3.24993)
		(width 0.089408)
		(layer "In11.Cu")
		(net "IRQ_PVDDQ_GHJ_VRHOT_LVT3_N")
	)
	(segment
		(start 324.90664 2.725166)
		(end 324.295516 3.33629)
		(width 0.089408)
		(layer "In11.Cu")
		(net "IRQ_PVDDQ_GHJ_VRHOT_LVT3_N")
	)
	(segment
		(start 172.66666 -4.03098)
		(end 171.416726 -4.03098)
		(width 0.089408)
		(layer "In11.Cu")
		(net "IRQ_PVDDQ_GHJ_VRHOT_LVT3_N")
	)
	(segment
		(start 327.584816 -31.387796)
		(end 327.584816 -27.416252)
		(width 0.089408)
		(layer "In11.Cu")
		(net "IRQ_PVDDQ_GHJ_VRHOT_LVT3_N")
	)
	(segment
		(start 324.85838 -1.963166)
		(end 324.90664 -1.914906)
		(width 0.089408)
		(layer "In11.Cu")
		(net "IRQ_PVDDQ_GHJ_VRHOT_LVT3_N")
	)
	(segment
		(start 176.74209 -4.71805)
		(end 176.74209 -5.491988)
		(width 0.089408)
		(layer "In11.Cu")
		(net "IRQ_PVDDQ_GHJ_VRHOT_LVT3_N")
	)
	(segment
		(start 16.36522 -1.78562)
		(end 15.750032 -2.400808)
		(width 0.089408)
		(layer "In11.Cu")
		(net "IRQ_PVDDQ_GHJ_VRHOT_LVT3_N")
	)
	(segment
		(start 171.416726 -4.03098)
		(end 170.86707 -3.481324)
		(width 0.089408)
		(layer "In11.Cu")
		(net "IRQ_PVDDQ_GHJ_VRHOT_LVT3_N")
	)
	(segment
		(start 28.908756 4.389374)
		(end 28.025344 3.505962)
		(width 0.089408)
		(layer "In11.Cu")
		(net "IRQ_PVDDQ_GHJ_VRHOT_LVT3_N")
	)
	(segment
		(start 19.992594 3.505962)
		(end 16.36522 -0.121412)
		(width 0.089408)
		(layer "In11.Cu")
		(net "IRQ_PVDDQ_GHJ_VRHOT_LVT3_N")
	)
	(segment
		(start 167.852598 -3.481324)
		(end 167.469566 -3.098292)
		(width 0.089408)
		(layer "In11.Cu")
		(net "IRQ_PVDDQ_GHJ_VRHOT_LVT3_N")
	)
	(segment
		(start 329.258168 -35.496246)
		(end 329.258168 -33.061148)
		(width 0.089408)
		(layer "In11.Cu")
		(net "IRQ_PVDDQ_GHJ_VRHOT_LVT3_N")
	)
	(segment
		(start 326.24522 -10.606786)
		(end 324.85838 -9.219946)
		(width 0.089408)
		(layer "In11.Cu")
		(net "IRQ_PVDDQ_GHJ_VRHOT_LVT3_N")
	)
	(segment
		(start 103.40721 3.777996)
		(end 102.795832 4.389374)
		(width 0.089408)
		(layer "In11.Cu")
		(net "IRQ_PVDDQ_GHJ_VRHOT_LVT3_N")
	)
	(segment
		(start 174.710852 -6.075172)
		(end 172.66666 -4.03098)
		(width 0.089408)
		(layer "In11.Cu")
		(net "IRQ_PVDDQ_GHJ_VRHOT_LVT3_N")
	)
	(segment
		(start 170.86707 -3.481324)
		(end 167.852598 -3.481324)
		(width 0.089408)
		(layer "In11.Cu")
		(net "IRQ_PVDDQ_GHJ_VRHOT_LVT3_N")
	)
	(segment
		(start 329.021948 -10.606786)
		(end 326.24522 -10.606786)
		(width 0.089408)
		(layer "In11.Cu")
		(net "IRQ_PVDDQ_GHJ_VRHOT_LVT3_N")
	)
	(segment
		(start 365.993934 -48.55845)
		(end 356.767892 -39.332408)
		(width 0.089408)
		(layer "In11.Cu")
		(net "IRQ_PVDDQ_GHJ_VRHOT_LVT3_N")
	)
	(segment
		(start 378.225304 -62.403736)
		(end 378.225304 -59.81827)
		(width 0.089408)
		(layer "In11.Cu")
		(net "IRQ_PVDDQ_GHJ_VRHOT_LVT3_N")
	)
	(segment
		(start 183.926988 4.352036)
		(end 183.698388 4.123436)
		(width 0.089408)
		(layer "In11.Cu")
		(net "IRQ_PVDDQ_GHJ_VRHOT_LVT3_N")
	)
	(segment
		(start 324.857872 -4.726432)
		(end 324.857872 -4.410456)
		(width 0.089408)
		(layer "In11.Cu")
		(net "IRQ_PVDDQ_GHJ_VRHOT_LVT3_N")
	)
	(segment
		(start 118.14302 3.777996)
		(end 103.40721 3.777996)
		(width 0.089408)
		(layer "In11.Cu")
		(net "IRQ_PVDDQ_GHJ_VRHOT_LVT3_N")
	)
	(segment
		(start 176.74209 -5.491988)
		(end 176.158906 -6.075172)
		(width 0.089408)
		(layer "In11.Cu")
		(net "IRQ_PVDDQ_GHJ_VRHOT_LVT3_N")
	)
	(segment
		(start 330.067412 -11.65225)
		(end 329.021948 -10.606786)
		(width 0.089408)
		(layer "In11.Cu")
		(net "IRQ_PVDDQ_GHJ_VRHOT_LVT3_N")
	)
	(segment
		(start 183.759094 -1.408938)
		(end 181.413658 -3.754374)
		(width 0.089408)
		(layer "In11.Cu")
		(net "IRQ_PVDDQ_GHJ_VRHOT_LVT3_N")
	)
	(segment
		(start 322.10883 4.352036)
		(end 183.926988 4.352036)
		(width 0.089408)
		(layer "In11.Cu")
		(net "IRQ_PVDDQ_GHJ_VRHOT_LVT3_N")
	)
	(segment
		(start 353.27336 -41.288462)
		(end 336.674206 -41.288462)
		(width 0.089408)
		(layer "In11.Cu")
		(net "IRQ_PVDDQ_GHJ_VRHOT_LVT3_N")
	)
	(segment
		(start 167.469566 -2.262632)
		(end 165.246304 -0.03937)
		(width 0.089408)
		(layer "In11.Cu")
		(net "IRQ_PVDDQ_GHJ_VRHOT_LVT3_N")
	)
	(segment
		(start 165.246304 -0.03937)
		(end 165.246304 3.32359)
		(width 0.089408)
		(layer "In11.Cu")
		(net "IRQ_PVDDQ_GHJ_VRHOT_LVT3_N")
	)
	(segment
		(start 328.547476 -15.292324)
		(end 330.067412 -13.772388)
		(width 0.089408)
		(layer "In11.Cu")
		(net "IRQ_PVDDQ_GHJ_VRHOT_LVT3_N")
	)
	(segment
		(start 176.158906 -6.075172)
		(end 174.710852 -6.075172)
		(width 0.089408)
		(layer "In11.Cu")
		(net "IRQ_PVDDQ_GHJ_VRHOT_LVT3_N")
	)
	(segment
		(start 324.85838 -9.219946)
		(end 324.85838 -4.72694)
		(width 0.089408)
		(layer "In11.Cu")
		(net "IRQ_PVDDQ_GHJ_VRHOT_LVT3_N")
	)
	(segment
		(start 324.295516 3.33629)
		(end 323.124576 3.33629)
		(width 0.089408)
		(layer "In11.Cu")
		(net "IRQ_PVDDQ_GHJ_VRHOT_LVT3_N")
	)
	(segment
		(start 377.54306 -59.136026)
		(end 377.54306 -56.938926)
		(width 0.089408)
		(layer "In11.Cu")
		(net "IRQ_PVDDQ_GHJ_VRHOT_LVT3_N")
	)
	(segment
		(start 324.85838 -4.409948)
		(end 324.85838 -1.963166)
		(width 0.089408)
		(layer "In11.Cu")
		(net "IRQ_PVDDQ_GHJ_VRHOT_LVT3_N")
	)
	(segment
		(start 336.674206 -41.288462)
		(end 334.901032 -39.515288)
		(width 0.089408)
		(layer "In11.Cu")
		(net "IRQ_PVDDQ_GHJ_VRHOT_LVT3_N")
	)
	(segment
		(start 370.845334 -53.131466)
		(end 370.845334 -52.210716)
		(width 0.089408)
		(layer "In11.Cu")
		(net "IRQ_PVDDQ_GHJ_VRHOT_LVT3_N")
	)
	(segment
		(start 333.02956 -38.701472)
		(end 332.463394 -38.701472)
		(width 0.089408)
		(layer "In11.Cu")
		(net "IRQ_PVDDQ_GHJ_VRHOT_LVT3_N")
	)
	(segment
		(start 28.025344 3.505962)
		(end 19.992594 3.505962)
		(width 0.089408)
		(layer "In11.Cu")
		(net "IRQ_PVDDQ_GHJ_VRHOT_LVT3_N")
	)
	(segment
		(start 183.698388 4.123436)
		(end 183.686196 4.123436)
		(width 0.089408)
		(layer "In11.Cu")
		(net "IRQ_PVDDQ_GHJ_VRHOT_LVT3_N")
	)
	(segment
		(start 324.857872 -4.410456)
		(end 324.85838 -4.409948)
		(width 0.089408)
		(layer "In11.Cu")
		(net "IRQ_PVDDQ_GHJ_VRHOT_LVT3_N")
	)
	(segment
		(start 15.750032 -2.400808)
		(end 15.750032 -3.365246)
		(width 0.089408)
		(layer "In11.Cu")
		(net "IRQ_PVDDQ_GHJ_VRHOT_LVT3_N")
	)
	(segment
		(start 183.759094 3.24993)
		(end 183.759094 -1.408938)
		(width 0.089408)
		(layer "In11.Cu")
		(net "IRQ_PVDDQ_GHJ_VRHOT_LVT3_N")
	)
	(segment
		(start 377.54306 -56.938926)
		(end 376.617992 -56.013858)
		(width 0.089408)
		(layer "In11.Cu")
		(net "IRQ_PVDDQ_GHJ_VRHOT_LVT3_N")
	)
	(segment
		(start 324.681342 -24.512778)
		(end 324.681342 -16.763238)
		(width 0.089408)
		(layer "In11.Cu")
		(net "IRQ_PVDDQ_GHJ_VRHOT_LVT3_N")
	)
	(segment
		(start 333.843376 -39.515288)
		(end 333.02956 -38.701472)
		(width 0.089408)
		(layer "In11.Cu")
		(net "IRQ_PVDDQ_GHJ_VRHOT_LVT3_N")
	)
	(segment
		(start 181.413658 -3.754374)
		(end 179.616354 -3.754374)
		(width 0.089408)
		(layer "In11.Cu")
		(net "IRQ_PVDDQ_GHJ_VRHOT_LVT3_N")
	)
	(segment
		(start 324.90664 -1.914906)
		(end 324.90664 2.725166)
		(width 0.089408)
		(layer "In11.Cu")
		(net "IRQ_PVDDQ_GHJ_VRHOT_LVT3_N")
	)
	(segment
		(start 323.124576 3.33629)
		(end 322.10883 4.352036)
		(width 0.089408)
		(layer "In11.Cu")
		(net "IRQ_PVDDQ_GHJ_VRHOT_LVT3_N")
	)
	(segment
		(start 164.35959 4.210304)
		(end 118.575328 4.210304)
		(width 0.089408)
		(layer "In11.Cu")
		(net "IRQ_PVDDQ_GHJ_VRHOT_LVT3_N")
	)
	(segment
		(start 329.258168 -33.061148)
		(end 327.584816 -31.387796)
		(width 0.089408)
		(layer "In11.Cu")
		(net "IRQ_PVDDQ_GHJ_VRHOT_LVT3_N")
	)
	(segment
		(start 355.229414 -39.332408)
		(end 353.27336 -41.288462)
		(width 0.089408)
		(layer "In11.Cu")
		(net "IRQ_PVDDQ_GHJ_VRHOT_LVT3_N")
	)
	(segment
		(start 330.067412 -13.772388)
		(end 330.067412 -11.65225)
		(width 0.089408)
		(layer "In11.Cu")
		(net "IRQ_PVDDQ_GHJ_VRHOT_LVT3_N")
	)
	(segment
		(start 367.193068 -48.55845)
		(end 365.993934 -48.55845)
		(width 0.089408)
		(layer "In11.Cu")
		(net "IRQ_PVDDQ_GHJ_VRHOT_LVT3_N")
	)
	(segment
		(start 326.152256 -15.292324)
		(end 328.547476 -15.292324)
		(width 0.089408)
		(layer "In11.Cu")
		(net "IRQ_PVDDQ_GHJ_VRHOT_LVT3_N")
	)
	(segment
		(start 373.727726 -56.013858)
		(end 370.845334 -53.131466)
		(width 0.089408)
		(layer "In11.Cu")
		(net "IRQ_PVDDQ_GHJ_VRHOT_LVT3_N")
	)
	(segment
		(start 177.266092 -4.194048)
		(end 176.74209 -4.71805)
		(width 0.089408)
		(layer "In11.Cu")
		(net "IRQ_PVDDQ_GHJ_VRHOT_LVT3_N")
	)
	(segment
		(start 378.225304 -59.81827)
		(end 377.54306 -59.136026)
		(width 0.089408)
		(layer "In11.Cu")
		(net "IRQ_PVDDQ_GHJ_VRHOT_LVT3_N")
	)
	(segment
		(start 102.795832 4.389374)
		(end 28.908756 4.389374)
		(width 0.089408)
		(layer "In11.Cu")
		(net "IRQ_PVDDQ_GHJ_VRHOT_LVT3_N")
	)
	(segment
		(start 334.901032 -39.515288)
		(end 333.843376 -39.515288)
		(width 0.089408)
		(layer "In11.Cu")
		(net "IRQ_PVDDQ_GHJ_VRHOT_LVT3_N")
	)
	(segment
		(start 183.451754 3.888994)
		(end 183.451754 3.55727)
		(width 0.089408)
		(layer "In11.Cu")
		(net "IRQ_PVDDQ_GHJ_VRHOT_LVT3_N")
	)
	(segment
		(start 377.679204 -62.949836)
		(end 378.225304 -62.403736)
		(width 0.089408)
		(layer "In11.Cu")
		(net "IRQ_PVDDQ_GHJ_VRHOT_LVT3_N")
	)
	(segment
		(start 324.85838 -4.72694)
		(end 324.857872 -4.726432)
		(width 0.089408)
		(layer "In11.Cu")
		(net "IRQ_PVDDQ_GHJ_VRHOT_LVT3_N")
	)
	(segment
		(start 183.686196 4.123436)
		(end 183.451754 3.888994)
		(width 0.089408)
		(layer "In11.Cu")
		(net "IRQ_PVDDQ_GHJ_VRHOT_LVT3_N")
	)
	(segment
		(start 327.584816 -27.416252)
		(end 324.681342 -24.512778)
		(width 0.089408)
		(layer "In11.Cu")
		(net "IRQ_PVDDQ_GHJ_VRHOT_LVT3_N")
	)
	(segment
		(start 356.767892 -39.332408)
		(end 355.229414 -39.332408)
		(width 0.089408)
		(layer "In11.Cu")
		(net "IRQ_PVDDQ_GHJ_VRHOT_LVT3_N")
	)
	(segment
		(start 332.463394 -38.701472)
		(end 329.258168 -35.496246)
		(width 0.089408)
		(layer "In11.Cu")
		(net "IRQ_PVDDQ_GHJ_VRHOT_LVT3_N")
	)
	(segment
		(start 179.616354 -3.754374)
		(end 179.17668 -4.194048)
		(width 0.089408)
		(layer "In11.Cu")
		(net "IRQ_PVDDQ_GHJ_VRHOT_LVT3_N")
	)
	(segment
		(start 179.17668 -4.194048)
		(end 177.266092 -4.194048)
		(width 0.089408)
		(layer "In11.Cu")
		(net "IRQ_PVDDQ_GHJ_VRHOT_LVT3_N")
	)
	(segment
		(start 324.681342 -16.763238)
		(end 326.152256 -15.292324)
		(width 0.089408)
		(layer "In11.Cu")
		(net "IRQ_PVDDQ_GHJ_VRHOT_LVT3_N")
	)
	(segment
		(start 370.845334 -52.210716)
		(end 367.193068 -48.55845)
		(width 0.089408)
		(layer "In11.Cu")
		(net "IRQ_PVDDQ_GHJ_VRHOT_LVT3_N")
	)
	(segment
		(start 165.246304 3.32359)
		(end 164.35959 4.210304)
		(width 0.089408)
		(layer "In11.Cu")
		(net "IRQ_PVDDQ_GHJ_VRHOT_LVT3_N")
	)
	(segment
		(start 376.617992 -56.013858)
		(end 373.727726 -56.013858)
		(width 0.089408)
		(layer "In11.Cu")
		(net "IRQ_PVDDQ_GHJ_VRHOT_LVT3_N")
	)
	(segment
		(start 16.36522 -0.121412)
		(end 16.36522 -1.78562)
		(width 0.089408)
		(layer "In11.Cu")
		(net "IRQ_PVDDQ_GHJ_VRHOT_LVT3_N")
	)
	(segment
		(start 118.575328 4.210304)
		(end 118.14302 3.777996)
		(width 0.089408)
		(layer "In11.Cu")
		(net "IRQ_PVDDQ_GHJ_VRHOT_LVT3_N")
	)
	(segment
		(start 423.890186 -42.763186)
		(end 423.890186 -42.534586)
		(width 0.10795)
		(layer "F.Cu")
		(net "IRQ_PVDDQ_DEF_VRHOT_LVT3_N")
	)
	(segment
		(start 363.7788 -133.1087)
		(end 363.7788 -132.59816)
		(width 0.10795)
		(layer "F.Cu")
		(net "IRQ_PVDDQ_DEF_VRHOT_LVT3_N")
	)
	(segment
		(start 424.267376 -45.059346)
		(end 424.267376 -43.140376)
		(width 0.10795)
		(layer "F.Cu")
		(net "IRQ_PVDDQ_DEF_VRHOT_LVT3_N")
	)
	(segment
		(start 425.427648 -46.219618)
		(end 424.267376 -45.059346)
		(width 0.10795)
		(layer "F.Cu")
		(net "IRQ_PVDDQ_DEF_VRHOT_LVT3_N")
	)
	(segment
		(start 363.7788 -132.59816)
		(end 363.64926 -132.46862)
		(width 0.10795)
		(layer "F.Cu")
		(net "IRQ_PVDDQ_DEF_VRHOT_LVT3_N")
	)
	(segment
		(start 424.267376 -43.140376)
		(end 423.890186 -42.763186)
		(width 0.10795)
		(layer "F.Cu")
		(net "IRQ_PVDDQ_DEF_VRHOT_LVT3_N")
	)
	(segment
		(start 425.427648 -46.482)
		(end 425.427648 -46.219618)
		(width 0.10795)
		(layer "F.Cu")
		(net "IRQ_PVDDQ_DEF_VRHOT_LVT3_N")
	)
	(segment
		(start 396.65275 -100.41128)
		(end 397.14805 -100.181156)
		(width 0.10795)
		(layer "F.Cu")
		(net "IRQ_PVDDQ_DEF_VRHOT_LVT3_N")
	)
	(via
		(at 376.77725 -116.42725)
		(size 0.508)
		(drill 0.254)
		(layers "F.Cu" "B.Cu")
		(net "IRQ_PVDDQ_DEF_VRHOT_LVT3_N")
	)
	(via
		(at 363.64926 -132.46862)
		(size 0.508)
		(drill 0.254)
		(layers "F.Cu" "B.Cu")
		(net "IRQ_PVDDQ_DEF_VRHOT_LVT3_N")
	)
	(via
		(at 425.427648 -46.482)
		(size 0.508)
		(drill 0.254)
		(layers "F.Cu" "B.Cu")
		(net "IRQ_PVDDQ_DEF_VRHOT_LVT3_N")
	)
	(via
		(at 397.14805 -100.181156)
		(size 0.508)
		(drill 0.254)
		(layers "F.Cu" "B.Cu")
		(net "IRQ_PVDDQ_DEF_VRHOT_LVT3_N")
	)
	(via
		(at 408.97556 -91.0209)
		(size 0.508)
		(drill 0.254)
		(layers "F.Cu" "B.Cu")
		(net "IRQ_PVDDQ_DEF_VRHOT_LVT3_N")
	)
	(via
		(at 428.6377 -54.292754)
		(size 0.508)
		(drill 0.254)
		(layers "F.Cu" "B.Cu")
		(net "IRQ_PVDDQ_DEF_VRHOT_LVT3_N")
	)
	(via
		(at 405.149304 -89.722198)
		(size 0.6604)
		(drill 0.3302)
		(layers "F.Cu" "B.Cu")
		(net "IRQ_PVDDQ_DEF_VRHOT_LVT3_N")
	)
	(segment
		(start 396.156942 -97.803208)
		(end 396.156942 -97.441766)
		(width 0.10795)
		(layer "B.Cu")
		(net "IRQ_PVDDQ_DEF_VRHOT_LVT3_N")
	)
	(segment
		(start 410.6037 -89.830402)
		(end 410.6037 -90.66276)
		(width 0.10795)
		(layer "B.Cu")
		(net "IRQ_PVDDQ_DEF_VRHOT_LVT3_N")
	)
	(segment
		(start 408.97556 -90.951304)
		(end 409.08351 -90.843354)
		(width 0.10795)
		(layer "B.Cu")
		(net "IRQ_PVDDQ_DEF_VRHOT_LVT3_N")
	)
	(segment
		(start 396.702026 -96.896682)
		(end 396.702026 -96.490282)
		(width 0.10795)
		(layer "B.Cu")
		(net "IRQ_PVDDQ_DEF_VRHOT_LVT3_N")
	)
	(segment
		(start 408.97556 -91.0209)
		(end 408.97556 -90.951304)
		(width 0.10795)
		(layer "B.Cu")
		(net "IRQ_PVDDQ_DEF_VRHOT_LVT3_N")
	)
	(segment
		(start 405.149304 -89.722198)
		(end 410.495496 -89.722198)
		(width 0.10795)
		(layer "B.Cu")
		(net "IRQ_PVDDQ_DEF_VRHOT_LVT3_N")
	)
	(segment
		(start 397.14805 -100.181156)
		(end 396.845282 -100.181156)
		(width 0.10795)
		(layer "B.Cu")
		(net "IRQ_PVDDQ_DEF_VRHOT_LVT3_N")
	)
	(segment
		(start 397.083534 -96.108774)
		(end 397.083534 -95.403924)
		(width 0.10795)
		(layer "B.Cu")
		(net "IRQ_PVDDQ_DEF_VRHOT_LVT3_N")
	)
	(segment
		(start 395.666468 -98.655632)
		(end 395.666468 -98.293682)
		(width 0.10795)
		(layer "B.Cu")
		(net "IRQ_PVDDQ_DEF_VRHOT_LVT3_N")
	)
	(segment
		(start 410.495496 -89.722198)
		(end 410.6037 -89.830402)
		(width 0.10795)
		(layer "B.Cu")
		(net "IRQ_PVDDQ_DEF_VRHOT_LVT3_N")
	)
	(segment
		(start 399.835116 -92.040202)
		(end 399.835116 -90.901774)
		(width 0.10795)
		(layer "B.Cu")
		(net "IRQ_PVDDQ_DEF_VRHOT_LVT3_N")
	)
	(segment
		(start 396.845282 -100.181156)
		(end 396.231364 -99.567238)
		(width 0.10795)
		(layer "B.Cu")
		(net "IRQ_PVDDQ_DEF_VRHOT_LVT3_N")
	)
	(segment
		(start 396.702026 -96.490282)
		(end 397.083534 -96.108774)
		(width 0.10795)
		(layer "B.Cu")
		(net "IRQ_PVDDQ_DEF_VRHOT_LVT3_N")
	)
	(segment
		(start 404.876 -89.722198)
		(end 405.149304 -89.722198)
		(width 0.10795)
		(layer "B.Cu")
		(net "IRQ_PVDDQ_DEF_VRHOT_LVT3_N")
	)
	(segment
		(start 404.784306 -89.630504)
		(end 404.876 -89.722198)
		(width 0.10795)
		(layer "B.Cu")
		(net "IRQ_PVDDQ_DEF_VRHOT_LVT3_N")
	)
	(segment
		(start 396.231364 -99.567238)
		(end 396.231364 -99.220528)
		(width 0.10795)
		(layer "B.Cu")
		(net "IRQ_PVDDQ_DEF_VRHOT_LVT3_N")
	)
	(segment
		(start 396.231364 -99.220528)
		(end 395.666468 -98.655632)
		(width 0.10795)
		(layer "B.Cu")
		(net "IRQ_PVDDQ_DEF_VRHOT_LVT3_N")
	)
	(segment
		(start 410.6037 -90.66276)
		(end 410.423106 -90.843354)
		(width 0.10795)
		(layer "B.Cu")
		(net "IRQ_PVDDQ_DEF_VRHOT_LVT3_N")
	)
	(segment
		(start 399.835116 -90.901774)
		(end 401.106386 -89.630504)
		(width 0.10795)
		(layer "B.Cu")
		(net "IRQ_PVDDQ_DEF_VRHOT_LVT3_N")
	)
	(segment
		(start 395.666468 -98.293682)
		(end 396.156942 -97.803208)
		(width 0.10795)
		(layer "B.Cu")
		(net "IRQ_PVDDQ_DEF_VRHOT_LVT3_N")
	)
	(segment
		(start 410.423106 -90.843354)
		(end 409.884118 -90.843354)
		(width 0.10795)
		(layer "B.Cu")
		(net "IRQ_PVDDQ_DEF_VRHOT_LVT3_N")
	)
	(segment
		(start 397.083534 -95.403924)
		(end 399.015204 -93.472254)
		(width 0.10795)
		(layer "B.Cu")
		(net "IRQ_PVDDQ_DEF_VRHOT_LVT3_N")
	)
	(segment
		(start 396.156942 -97.441766)
		(end 396.702026 -96.896682)
		(width 0.10795)
		(layer "B.Cu")
		(net "IRQ_PVDDQ_DEF_VRHOT_LVT3_N")
	)
	(segment
		(start 399.015204 -92.860114)
		(end 399.835116 -92.040202)
		(width 0.10795)
		(layer "B.Cu")
		(net "IRQ_PVDDQ_DEF_VRHOT_LVT3_N")
	)
	(segment
		(start 399.015204 -93.472254)
		(end 399.015204 -92.860114)
		(width 0.10795)
		(layer "B.Cu")
		(net "IRQ_PVDDQ_DEF_VRHOT_LVT3_N")
	)
	(segment
		(start 401.106386 -89.630504)
		(end 404.784306 -89.630504)
		(width 0.10795)
		(layer "B.Cu")
		(net "IRQ_PVDDQ_DEF_VRHOT_LVT3_N")
	)
	(segment
		(start 409.08351 -90.843354)
		(end 409.884118 -90.843354)
		(width 0.10795)
		(layer "B.Cu")
		(net "IRQ_PVDDQ_DEF_VRHOT_LVT3_N")
	)
	(segment
		(start 427.993048 -54.937406)
		(end 428.6377 -54.292754)
		(width 0.089408)
		(layer "In2.Cu")
		(net "IRQ_PVDDQ_DEF_VRHOT_LVT3_N")
	)
	(segment
		(start 419.27399 -57.676034)
		(end 422.012618 -54.937406)
		(width 0.089408)
		(layer "In2.Cu")
		(net "IRQ_PVDDQ_DEF_VRHOT_LVT3_N")
	)
	(segment
		(start 405.368252 -74.68362)
		(end 405.368252 -74.361802)
		(width 0.089408)
		(layer "In2.Cu")
		(net "IRQ_PVDDQ_DEF_VRHOT_LVT3_N")
	)
	(segment
		(start 411.388306 -66.84391)
		(end 411.388306 -66.276474)
		(width 0.089408)
		(layer "In2.Cu")
		(net "IRQ_PVDDQ_DEF_VRHOT_LVT3_N")
	)
	(segment
		(start 411.389068 -67.866006)
		(end 411.388814 -67.865752)
		(width 0.089408)
		(layer "In2.Cu")
		(net "IRQ_PVDDQ_DEF_VRHOT_LVT3_N")
	)
	(segment
		(start 413.236918 -57.676034)
		(end 419.27399 -57.676034)
		(width 0.089408)
		(layer "In2.Cu")
		(net "IRQ_PVDDQ_DEF_VRHOT_LVT3_N")
	)
	(segment
		(start 411.966664 -58.946288)
		(end 413.236918 -57.676034)
		(width 0.089408)
		(layer "In2.Cu")
		(net "IRQ_PVDDQ_DEF_VRHOT_LVT3_N")
	)
	(segment
		(start 405.254714 -79.56931)
		(end 405.254968 -79.569056)
		(width 0.089408)
		(layer "In2.Cu")
		(net "IRQ_PVDDQ_DEF_VRHOT_LVT3_N")
	)
	(segment
		(start 407.76652 -87.331804)
		(end 407.76652 -82.714592)
		(width 0.089408)
		(layer "In2.Cu")
		(net "IRQ_PVDDQ_DEF_VRHOT_LVT3_N")
	)
	(segment
		(start 404.76678 -75.285092)
		(end 405.368252 -74.68362)
		(width 0.089408)
		(layer "In2.Cu")
		(net "IRQ_PVDDQ_DEF_VRHOT_LVT3_N")
	)
	(segment
		(start 407.76652 -82.714592)
		(end 405.254714 -80.202786)
		(width 0.089408)
		(layer "In2.Cu")
		(net "IRQ_PVDDQ_DEF_VRHOT_LVT3_N")
	)
	(segment
		(start 405.254714 -80.202786)
		(end 405.254714 -79.56931)
		(width 0.089408)
		(layer "In2.Cu")
		(net "IRQ_PVDDQ_DEF_VRHOT_LVT3_N")
	)
	(segment
		(start 411.388814 -67.865752)
		(end 411.388814 -66.844418)
		(width 0.089408)
		(layer "In2.Cu")
		(net "IRQ_PVDDQ_DEF_VRHOT_LVT3_N")
	)
	(segment
		(start 408.429206 -87.99449)
		(end 407.76652 -87.331804)
		(width 0.089408)
		(layer "In2.Cu")
		(net "IRQ_PVDDQ_DEF_VRHOT_LVT3_N")
	)
	(segment
		(start 408.985974 -87.99449)
		(end 408.429206 -87.99449)
		(width 0.089408)
		(layer "In2.Cu")
		(net "IRQ_PVDDQ_DEF_VRHOT_LVT3_N")
	)
	(segment
		(start 408.97556 -91.0209)
		(end 408.97556 -90.95613)
		(width 0.089408)
		(layer "In2.Cu")
		(net "IRQ_PVDDQ_DEF_VRHOT_LVT3_N")
	)
	(segment
		(start 405.368252 -74.361802)
		(end 411.389068 -68.340986)
		(width 0.089408)
		(layer "In2.Cu")
		(net "IRQ_PVDDQ_DEF_VRHOT_LVT3_N")
	)
	(segment
		(start 411.389068 -68.340986)
		(end 411.389068 -67.866006)
		(width 0.089408)
		(layer "In2.Cu")
		(net "IRQ_PVDDQ_DEF_VRHOT_LVT3_N")
	)
	(segment
		(start 411.388814 -66.844418)
		(end 411.388306 -66.84391)
		(width 0.089408)
		(layer "In2.Cu")
		(net "IRQ_PVDDQ_DEF_VRHOT_LVT3_N")
	)
	(segment
		(start 405.254968 -78.970632)
		(end 404.76678 -78.482444)
		(width 0.089408)
		(layer "In2.Cu")
		(net "IRQ_PVDDQ_DEF_VRHOT_LVT3_N")
	)
	(segment
		(start 422.012618 -54.937406)
		(end 427.993048 -54.937406)
		(width 0.089408)
		(layer "In2.Cu")
		(net "IRQ_PVDDQ_DEF_VRHOT_LVT3_N")
	)
	(segment
		(start 411.388306 -66.276474)
		(end 412.24708 -65.4177)
		(width 0.089408)
		(layer "In2.Cu")
		(net "IRQ_PVDDQ_DEF_VRHOT_LVT3_N")
	)
	(segment
		(start 408.97556 -90.95613)
		(end 409.45816 -90.47353)
		(width 0.089408)
		(layer "In2.Cu")
		(net "IRQ_PVDDQ_DEF_VRHOT_LVT3_N")
	)
	(segment
		(start 404.76678 -78.482444)
		(end 404.76678 -75.285092)
		(width 0.089408)
		(layer "In2.Cu")
		(net "IRQ_PVDDQ_DEF_VRHOT_LVT3_N")
	)
	(segment
		(start 409.45816 -88.466676)
		(end 408.985974 -87.99449)
		(width 0.089408)
		(layer "In2.Cu")
		(net "IRQ_PVDDQ_DEF_VRHOT_LVT3_N")
	)
	(segment
		(start 411.966664 -63.651384)
		(end 411.966664 -58.946288)
		(width 0.089408)
		(layer "In2.Cu")
		(net "IRQ_PVDDQ_DEF_VRHOT_LVT3_N")
	)
	(segment
		(start 405.254968 -79.569056)
		(end 405.254968 -78.970632)
		(width 0.089408)
		(layer "In2.Cu")
		(net "IRQ_PVDDQ_DEF_VRHOT_LVT3_N")
	)
	(segment
		(start 412.24708 -63.9318)
		(end 411.966664 -63.651384)
		(width 0.089408)
		(layer "In2.Cu")
		(net "IRQ_PVDDQ_DEF_VRHOT_LVT3_N")
	)
	(segment
		(start 409.45816 -90.47353)
		(end 409.45816 -88.466676)
		(width 0.089408)
		(layer "In2.Cu")
		(net "IRQ_PVDDQ_DEF_VRHOT_LVT3_N")
	)
	(segment
		(start 412.24708 -65.4177)
		(end 412.24708 -63.9318)
		(width 0.089408)
		(layer "In2.Cu")
		(net "IRQ_PVDDQ_DEF_VRHOT_LVT3_N")
	)
	(segment
		(start 382.38557 -102.92207)
		(end 381.89027 -103.41737)
		(width 0.089408)
		(layer "In4.Cu")
		(net "IRQ_PVDDQ_DEF_VRHOT_LVT3_N")
	)
	(segment
		(start 397.14805 -100.181156)
		(end 396.947136 -100.181156)
		(width 0.089408)
		(layer "In4.Cu")
		(net "IRQ_PVDDQ_DEF_VRHOT_LVT3_N")
	)
	(segment
		(start 383.029206 -101.221286)
		(end 382.778 -101.472492)
		(width 0.089408)
		(layer "In4.Cu")
		(net "IRQ_PVDDQ_DEF_VRHOT_LVT3_N")
	)
	(segment
		(start 379.71603 -109.419644)
		(end 379.265942 -109.869732)
		(width 0.089408)
		(layer "In4.Cu")
		(net "IRQ_PVDDQ_DEF_VRHOT_LVT3_N")
	)
	(segment
		(start 380.259336 -108.11002)
		(end 379.71603 -108.653326)
		(width 0.089408)
		(layer "In4.Cu")
		(net "IRQ_PVDDQ_DEF_VRHOT_LVT3_N")
	)
	(segment
		(start 377.22175 -114.550698)
		(end 377.22175 -115.98275)
		(width 0.089408)
		(layer "In4.Cu")
		(net "IRQ_PVDDQ_DEF_VRHOT_LVT3_N")
	)
	(segment
		(start 380.506732 -105.975912)
		(end 380.506732 -106.638598)
		(width 0.089408)
		(layer "In4.Cu")
		(net "IRQ_PVDDQ_DEF_VRHOT_LVT3_N")
	)
	(segment
		(start 382.778 -101.472492)
		(end 382.778 -102.198932)
		(width 0.089408)
		(layer "In4.Cu")
		(net "IRQ_PVDDQ_DEF_VRHOT_LVT3_N")
	)
	(segment
		(start 396.1892 -99.285552)
		(end 395.798548 -98.8949)
		(width 0.089408)
		(layer "In4.Cu")
		(net "IRQ_PVDDQ_DEF_VRHOT_LVT3_N")
	)
	(segment
		(start 381.89027 -103.41737)
		(end 381.89027 -104.084882)
		(width 0.089408)
		(layer "In4.Cu")
		(net "IRQ_PVDDQ_DEF_VRHOT_LVT3_N")
	)
	(segment
		(start 380.68758 -106.819446)
		(end 380.68758 -107.150154)
		(width 0.089408)
		(layer "In4.Cu")
		(net "IRQ_PVDDQ_DEF_VRHOT_LVT3_N")
	)
	(segment
		(start 393.58443 -98.298762)
		(end 393.351004 -98.065336)
		(width 0.089408)
		(layer "In4.Cu")
		(net "IRQ_PVDDQ_DEF_VRHOT_LVT3_N")
	)
	(segment
		(start 383.392426 -101.221286)
		(end 383.029206 -101.221286)
		(width 0.089408)
		(layer "In4.Cu")
		(net "IRQ_PVDDQ_DEF_VRHOT_LVT3_N")
	)
	(segment
		(start 384.930904 -101.438456)
		(end 383.609596 -101.438456)
		(width 0.089408)
		(layer "In4.Cu")
		(net "IRQ_PVDDQ_DEF_VRHOT_LVT3_N")
	)
	(segment
		(start 382.38557 -102.591362)
		(end 382.38557 -102.92207)
		(width 0.089408)
		(layer "In4.Cu")
		(net "IRQ_PVDDQ_DEF_VRHOT_LVT3_N")
	)
	(segment
		(start 390.3472 -98.8949)
		(end 387.600952 -98.8949)
		(width 0.089408)
		(layer "In4.Cu")
		(net "IRQ_PVDDQ_DEF_VRHOT_LVT3_N")
	)
	(segment
		(start 393.58443 -98.43643)
		(end 393.58443 -98.298762)
		(width 0.089408)
		(layer "In4.Cu")
		(net "IRQ_PVDDQ_DEF_VRHOT_LVT3_N")
	)
	(segment
		(start 391.039096 -98.065336)
		(end 390.80567 -98.298762)
		(width 0.089408)
		(layer "In4.Cu")
		(net "IRQ_PVDDQ_DEF_VRHOT_LVT3_N")
	)
	(segment
		(start 380.506732 -106.638598)
		(end 380.68758 -106.819446)
		(width 0.089408)
		(layer "In4.Cu")
		(net "IRQ_PVDDQ_DEF_VRHOT_LVT3_N")
	)
	(segment
		(start 393.351004 -98.065336)
		(end 391.039096 -98.065336)
		(width 0.089408)
		(layer "In4.Cu")
		(net "IRQ_PVDDQ_DEF_VRHOT_LVT3_N")
	)
	(segment
		(start 378.751084 -113.021364)
		(end 377.22175 -114.550698)
		(width 0.089408)
		(layer "In4.Cu")
		(net "IRQ_PVDDQ_DEF_VRHOT_LVT3_N")
	)
	(segment
		(start 387.14553 -99.48799)
		(end 386.912104 -99.721416)
		(width 0.089408)
		(layer "In4.Cu")
		(net "IRQ_PVDDQ_DEF_VRHOT_LVT3_N")
	)
	(segment
		(start 379.265942 -109.869732)
		(end 379.265942 -110.225332)
		(width 0.089408)
		(layer "In4.Cu")
		(net "IRQ_PVDDQ_DEF_VRHOT_LVT3_N")
	)
	(segment
		(start 385.65963 -100.34651)
		(end 385.16433 -100.84181)
		(width 0.089408)
		(layer "In4.Cu")
		(net "IRQ_PVDDQ_DEF_VRHOT_LVT3_N")
	)
	(segment
		(start 379.781054 -111.101886)
		(end 379.259846 -111.623094)
		(width 0.089408)
		(layer "In4.Cu")
		(net "IRQ_PVDDQ_DEF_VRHOT_LVT3_N")
	)
	(segment
		(start 383.609596 -101.438456)
		(end 383.392426 -101.221286)
		(width 0.089408)
		(layer "In4.Cu")
		(net "IRQ_PVDDQ_DEF_VRHOT_LVT3_N")
	)
	(segment
		(start 386.912104 -99.721416)
		(end 385.954016 -99.721416)
		(width 0.089408)
		(layer "In4.Cu")
		(net "IRQ_PVDDQ_DEF_VRHOT_LVT3_N")
	)
	(segment
		(start 387.600952 -98.8949)
		(end 387.14553 -99.350322)
		(width 0.089408)
		(layer "In4.Cu")
		(net "IRQ_PVDDQ_DEF_VRHOT_LVT3_N")
	)
	(segment
		(start 382.065022 -104.417622)
		(end 380.506732 -105.975912)
		(width 0.089408)
		(layer "In4.Cu")
		(net "IRQ_PVDDQ_DEF_VRHOT_LVT3_N")
	)
	(segment
		(start 380.259336 -107.578398)
		(end 380.259336 -108.11002)
		(width 0.089408)
		(layer "In4.Cu")
		(net "IRQ_PVDDQ_DEF_VRHOT_LVT3_N")
	)
	(segment
		(start 382.065022 -104.259634)
		(end 382.065022 -104.417622)
		(width 0.089408)
		(layer "In4.Cu")
		(net "IRQ_PVDDQ_DEF_VRHOT_LVT3_N")
	)
	(segment
		(start 380.68758 -107.150154)
		(end 380.259336 -107.578398)
		(width 0.089408)
		(layer "In4.Cu")
		(net "IRQ_PVDDQ_DEF_VRHOT_LVT3_N")
	)
	(segment
		(start 381.89027 -104.084882)
		(end 382.065022 -104.259634)
		(width 0.089408)
		(layer "In4.Cu")
		(net "IRQ_PVDDQ_DEF_VRHOT_LVT3_N")
	)
	(segment
		(start 379.265942 -110.225332)
		(end 379.781054 -110.740444)
		(width 0.089408)
		(layer "In4.Cu")
		(net "IRQ_PVDDQ_DEF_VRHOT_LVT3_N")
	)
	(segment
		(start 396.1892 -99.42322)
		(end 396.1892 -99.285552)
		(width 0.089408)
		(layer "In4.Cu")
		(net "IRQ_PVDDQ_DEF_VRHOT_LVT3_N")
	)
	(segment
		(start 390.80567 -98.43643)
		(end 390.3472 -98.8949)
		(width 0.089408)
		(layer "In4.Cu")
		(net "IRQ_PVDDQ_DEF_VRHOT_LVT3_N")
	)
	(segment
		(start 379.71603 -108.653326)
		(end 379.71603 -109.419644)
		(width 0.089408)
		(layer "In4.Cu")
		(net "IRQ_PVDDQ_DEF_VRHOT_LVT3_N")
	)
	(segment
		(start 378.751084 -112.62868)
		(end 378.751084 -113.021364)
		(width 0.089408)
		(layer "In4.Cu")
		(net "IRQ_PVDDQ_DEF_VRHOT_LVT3_N")
	)
	(segment
		(start 377.22175 -115.98275)
		(end 376.77725 -116.42725)
		(width 0.089408)
		(layer "In4.Cu")
		(net "IRQ_PVDDQ_DEF_VRHOT_LVT3_N")
	)
	(segment
		(start 379.781054 -110.740444)
		(end 379.781054 -111.101886)
		(width 0.089408)
		(layer "In4.Cu")
		(net "IRQ_PVDDQ_DEF_VRHOT_LVT3_N")
	)
	(segment
		(start 394.0429 -98.8949)
		(end 393.58443 -98.43643)
		(width 0.089408)
		(layer "In4.Cu")
		(net "IRQ_PVDDQ_DEF_VRHOT_LVT3_N")
	)
	(segment
		(start 395.798548 -98.8949)
		(end 394.0429 -98.8949)
		(width 0.089408)
		(layer "In4.Cu")
		(net "IRQ_PVDDQ_DEF_VRHOT_LVT3_N")
	)
	(segment
		(start 385.16433 -100.84181)
		(end 385.16433 -101.20503)
		(width 0.089408)
		(layer "In4.Cu")
		(net "IRQ_PVDDQ_DEF_VRHOT_LVT3_N")
	)
	(segment
		(start 385.954016 -99.721416)
		(end 385.65963 -100.015802)
		(width 0.089408)
		(layer "In4.Cu")
		(net "IRQ_PVDDQ_DEF_VRHOT_LVT3_N")
	)
	(segment
		(start 396.947136 -100.181156)
		(end 396.1892 -99.42322)
		(width 0.089408)
		(layer "In4.Cu")
		(net "IRQ_PVDDQ_DEF_VRHOT_LVT3_N")
	)
	(segment
		(start 379.259846 -111.623094)
		(end 379.259846 -112.119918)
		(width 0.089408)
		(layer "In4.Cu")
		(net "IRQ_PVDDQ_DEF_VRHOT_LVT3_N")
	)
	(segment
		(start 390.80567 -98.298762)
		(end 390.80567 -98.43643)
		(width 0.089408)
		(layer "In4.Cu")
		(net "IRQ_PVDDQ_DEF_VRHOT_LVT3_N")
	)
	(segment
		(start 379.259846 -112.119918)
		(end 378.751084 -112.62868)
		(width 0.089408)
		(layer "In4.Cu")
		(net "IRQ_PVDDQ_DEF_VRHOT_LVT3_N")
	)
	(segment
		(start 385.16433 -101.20503)
		(end 384.930904 -101.438456)
		(width 0.089408)
		(layer "In4.Cu")
		(net "IRQ_PVDDQ_DEF_VRHOT_LVT3_N")
	)
	(segment
		(start 382.778 -102.198932)
		(end 382.38557 -102.591362)
		(width 0.089408)
		(layer "In4.Cu")
		(net "IRQ_PVDDQ_DEF_VRHOT_LVT3_N")
	)
	(segment
		(start 387.14553 -99.350322)
		(end 387.14553 -99.48799)
		(width 0.089408)
		(layer "In4.Cu")
		(net "IRQ_PVDDQ_DEF_VRHOT_LVT3_N")
	)
	(segment
		(start 385.65963 -100.015802)
		(end 385.65963 -100.34651)
		(width 0.089408)
		(layer "In4.Cu")
		(net "IRQ_PVDDQ_DEF_VRHOT_LVT3_N")
	)
	(segment
		(start 371.415564 -127.645668)
		(end 371.415564 -125.872494)
		(width 0.089408)
		(layer "In9.Cu")
		(net "IRQ_PVDDQ_DEF_VRHOT_LVT3_N")
	)
	(segment
		(start 366.592612 -132.46862)
		(end 371.415564 -127.645668)
		(width 0.089408)
		(layer "In9.Cu")
		(net "IRQ_PVDDQ_DEF_VRHOT_LVT3_N")
	)
	(segment
		(start 371.415564 -125.872494)
		(end 372.197884 -125.090174)
		(width 0.089408)
		(layer "In9.Cu")
		(net "IRQ_PVDDQ_DEF_VRHOT_LVT3_N")
	)
	(segment
		(start 375.8311 -117.3353)
		(end 376.73915 -116.42725)
		(width 0.089408)
		(layer "In9.Cu")
		(net "IRQ_PVDDQ_DEF_VRHOT_LVT3_N")
	)
	(segment
		(start 375.8311 -119.4435)
		(end 375.8311 -117.3353)
		(width 0.089408)
		(layer "In9.Cu")
		(net "IRQ_PVDDQ_DEF_VRHOT_LVT3_N")
	)
	(segment
		(start 372.197884 -125.090174)
		(end 372.197884 -123.076716)
		(width 0.089408)
		(layer "In9.Cu")
		(net "IRQ_PVDDQ_DEF_VRHOT_LVT3_N")
	)
	(segment
		(start 376.73915 -116.42725)
		(end 376.77725 -116.42725)
		(width 0.089408)
		(layer "In9.Cu")
		(net "IRQ_PVDDQ_DEF_VRHOT_LVT3_N")
	)
	(segment
		(start 372.197884 -123.076716)
		(end 375.8311 -119.4435)
		(width 0.089408)
		(layer "In9.Cu")
		(net "IRQ_PVDDQ_DEF_VRHOT_LVT3_N")
	)
	(segment
		(start 363.64926 -132.46862)
		(end 366.592612 -132.46862)
		(width 0.089408)
		(layer "In9.Cu")
		(net "IRQ_PVDDQ_DEF_VRHOT_LVT3_N")
	)
	(segment
		(start 425.382182 -48.547782)
		(end 425.382182 -46.527466)
		(width 0.089408)
		(layer "In11.Cu")
		(net "IRQ_PVDDQ_DEF_VRHOT_LVT3_N")
	)
	(segment
		(start 427.73092 -51.706526)
		(end 426.530008 -50.505614)
		(width 0.089408)
		(layer "In11.Cu")
		(net "IRQ_PVDDQ_DEF_VRHOT_LVT3_N")
	)
	(segment
		(start 426.530008 -49.695608)
		(end 425.382182 -48.547782)
		(width 0.089408)
		(layer "In11.Cu")
		(net "IRQ_PVDDQ_DEF_VRHOT_LVT3_N")
	)
	(segment
		(start 426.530008 -50.505614)
		(end 426.530008 -49.695608)
		(width 0.089408)
		(layer "In11.Cu")
		(net "IRQ_PVDDQ_DEF_VRHOT_LVT3_N")
	)
	(segment
		(start 425.382182 -46.527466)
		(end 425.427648 -46.482)
		(width 0.089408)
		(layer "In11.Cu")
		(net "IRQ_PVDDQ_DEF_VRHOT_LVT3_N")
	)
	(segment
		(start 428.6377 -54.292754)
		(end 427.73092 -53.385974)
		(width 0.089408)
		(layer "In11.Cu")
		(net "IRQ_PVDDQ_DEF_VRHOT_LVT3_N")
	)
	(segment
		(start 427.73092 -53.385974)
		(end 427.73092 -51.706526)
		(width 0.089408)
		(layer "In11.Cu")
		(net "IRQ_PVDDQ_DEF_VRHOT_LVT3_N")
	)
	(segment
		(start 398.13865 -96.11868)
		(end 398.674336 -96.012508)
		(width 0.10795)
		(layer "F.Cu")
		(net "IRQ_PVDDQ_ABC_VRHOT_LVT3_N")
	)
	(segment
		(start 413.490156 -40.93464)
		(end 413.090106 -41.33469)
		(width 0.10795)
		(layer "F.Cu")
		(net "IRQ_PVDDQ_ABC_VRHOT_LVT3_N")
	)
	(segment
		(start 337.947 -21.1582)
		(end 337.8962 -21.209)
		(width 0.10795)
		(layer "F.Cu")
		(net "IRQ_PVDDQ_ABC_VRHOT_LVT3_N")
	)
	(segment
		(start 337.947 -20.5232)
		(end 337.947 -21.1582)
		(width 0.10795)
		(layer "F.Cu")
		(net "IRQ_PVDDQ_ABC_VRHOT_LVT3_N")
	)
	(via
		(at 398.5133 -25.210008)
		(size 0.6604)
		(drill 0.3302)
		(layers "F.Cu" "B.Cu")
		(net "IRQ_PVDDQ_ABC_VRHOT_LVT3_N")
	)
	(via
		(at 337.8962 -21.209)
		(size 0.508)
		(drill 0.254)
		(layers "F.Cu" "B.Cu")
		(net "IRQ_PVDDQ_ABC_VRHOT_LVT3_N")
	)
	(via
		(at 398.674336 -96.012508)
		(size 0.508)
		(drill 0.254)
		(layers "F.Cu" "B.Cu")
		(net "IRQ_PVDDQ_ABC_VRHOT_LVT3_N")
	)
	(via
		(at 392.575288 -9.699752)
		(size 0.508)
		(drill 0.254)
		(layers "F.Cu" "B.Cu")
		(net "IRQ_PVDDQ_ABC_VRHOT_LVT3_N")
	)
	(via
		(at 409.03398 -91.92006)
		(size 0.508)
		(drill 0.254)
		(layers "F.Cu" "B.Cu")
		(net "IRQ_PVDDQ_ABC_VRHOT_LVT3_N")
	)
	(via
		(at 413.91713 -55.30215)
		(size 0.508)
		(drill 0.254)
		(layers "F.Cu" "B.Cu")
		(net "IRQ_PVDDQ_ABC_VRHOT_LVT3_N")
	)
	(via
		(at 413.090106 -41.33469)
		(size 0.4572)
		(drill 0.2032)
		(layers "F.Cu" "B.Cu")
		(net "IRQ_PVDDQ_ABC_VRHOT_LVT3_N")
	)
	(segment
		(start 400.368262 -36.002976)
		(end 400.605244 -36.002976)
		(width 0.10795)
		(layer "B.Cu")
		(net "IRQ_PVDDQ_ABC_VRHOT_LVT3_N")
	)
	(segment
		(start 398.831308 -31.168086)
		(end 399.40484 -31.741618)
		(width 0.10795)
		(layer "B.Cu")
		(net "IRQ_PVDDQ_ABC_VRHOT_LVT3_N")
	)
	(segment
		(start 397.9164 -8.4074)
		(end 398.738852 -9.229852)
		(width 0.10795)
		(layer "B.Cu")
		(net "IRQ_PVDDQ_ABC_VRHOT_LVT3_N")
	)
	(segment
		(start 404.801832 -90.599006)
		(end 402.67128 -90.599006)
		(width 0.10795)
		(layer "B.Cu")
		(net "IRQ_PVDDQ_ABC_VRHOT_LVT3_N")
	)
	(segment
		(start 409.884118 -93.510354)
		(end 409.309062 -93.510354)
		(width 0.10795)
		(layer "B.Cu")
		(net "IRQ_PVDDQ_ABC_VRHOT_LVT3_N")
	)
	(segment
		(start 398.674336 -94.59595)
		(end 398.674336 -96.012508)
		(width 0.10795)
		(layer "B.Cu")
		(net "IRQ_PVDDQ_ABC_VRHOT_LVT3_N")
	)
	(segment
		(start 407.411936 -91.4654)
		(end 405.668226 -91.4654)
		(width 0.10795)
		(layer "B.Cu")
		(net "IRQ_PVDDQ_ABC_VRHOT_LVT3_N")
	)
	(segment
		(start 413.766762 -46.734984)
		(end 413.022796 -47.47895)
		(width 0.10795)
		(layer "B.Cu")
		(net "IRQ_PVDDQ_ABC_VRHOT_LVT3_N")
	)
	(segment
		(start 406.456642 -43.171618)
		(end 406.945084 -42.683176)
		(width 0.10795)
		(layer "B.Cu")
		(net "IRQ_PVDDQ_ABC_VRHOT_LVT3_N")
	)
	(segment
		(start 408.425396 -40.942514)
		(end 408.689048 -40.678862)
		(width 0.10795)
		(layer "B.Cu")
		(net "IRQ_PVDDQ_ABC_VRHOT_LVT3_N")
	)
	(segment
		(start 401.572222 -43.634406)
		(end 404.253954 -43.634406)
		(width 0.10795)
		(layer "B.Cu")
		(net "IRQ_PVDDQ_ABC_VRHOT_LVT3_N")
	)
	(segment
		(start 406.945084 -41.727882)
		(end 407.730452 -40.942514)
		(width 0.10795)
		(layer "B.Cu")
		(net "IRQ_PVDDQ_ABC_VRHOT_LVT3_N")
	)
	(segment
		(start 409.201112 -93.402404)
		(end 409.201112 -92.087192)
		(width 0.10795)
		(layer "B.Cu")
		(net "IRQ_PVDDQ_ABC_VRHOT_LVT3_N")
	)
	(segment
		(start 413.766762 -46.226984)
		(end 413.766762 -46.734984)
		(width 0.10795)
		(layer "B.Cu")
		(net "IRQ_PVDDQ_ABC_VRHOT_LVT3_N")
	)
	(segment
		(start 413.23514 -45.695362)
		(end 413.766762 -46.226984)
		(width 0.10795)
		(layer "B.Cu")
		(net "IRQ_PVDDQ_ABC_VRHOT_LVT3_N")
	)
	(segment
		(start 400.854926 -36.872926)
		(end 400.377152 -37.3507)
		(width 0.10795)
		(layer "B.Cu")
		(net "IRQ_PVDDQ_ABC_VRHOT_LVT3_N")
	)
	(segment
		(start 412.705804 -41.975278)
		(end 412.705804 -42.262044)
		(width 0.10795)
		(layer "B.Cu")
		(net "IRQ_PVDDQ_ABC_VRHOT_LVT3_N")
	)
	(segment
		(start 399.40484 -31.741618)
		(end 399.40484 -31.98495)
		(width 0.10795)
		(layer "B.Cu")
		(net "IRQ_PVDDQ_ABC_VRHOT_LVT3_N")
	)
	(segment
		(start 405.668226 -91.4654)
		(end 404.801832 -90.599006)
		(width 0.10795)
		(layer "B.Cu")
		(net "IRQ_PVDDQ_ABC_VRHOT_LVT3_N")
	)
	(segment
		(start 400.118326 -27.894026)
		(end 400.118326 -28.416504)
		(width 0.10795)
		(layer "B.Cu")
		(net "IRQ_PVDDQ_ABC_VRHOT_LVT3_N")
	)
	(segment
		(start 398.069054 -14.825218)
		(end 398.069054 -17.197832)
		(width 0.10795)
		(layer "B.Cu")
		(net "IRQ_PVDDQ_ABC_VRHOT_LVT3_N")
	)
	(segment
		(start 399.429732 -29.805122)
		(end 398.831308 -30.403546)
		(width 0.10795)
		(layer "B.Cu")
		(net "IRQ_PVDDQ_ABC_VRHOT_LVT3_N")
	)
	(segment
		(start 407.730452 -40.942514)
		(end 408.425396 -40.942514)
		(width 0.10795)
		(layer "B.Cu")
		(net "IRQ_PVDDQ_ABC_VRHOT_LVT3_N")
	)
	(segment
		(start 411.649164 -40.150542)
		(end 411.895798 -40.397176)
		(width 0.10795)
		(layer "B.Cu")
		(net "IRQ_PVDDQ_ABC_VRHOT_LVT3_N")
	)
	(segment
		(start 404.716742 -43.171618)
		(end 406.456642 -43.171618)
		(width 0.10795)
		(layer "B.Cu")
		(net "IRQ_PVDDQ_ABC_VRHOT_LVT3_N")
	)
	(segment
		(start 413.125666 -44.712636)
		(end 413.23514 -44.82211)
		(width 0.10795)
		(layer "B.Cu")
		(net "IRQ_PVDDQ_ABC_VRHOT_LVT3_N")
	)
	(segment
		(start 411.895798 -40.683434)
		(end 412.131256 -40.918892)
		(width 0.10795)
		(layer "B.Cu")
		(net "IRQ_PVDDQ_ABC_VRHOT_LVT3_N")
	)
	(segment
		(start 399.40484 -31.98495)
		(end 399.408904 -31.98495)
		(width 0.10795)
		(layer "B.Cu")
		(net "IRQ_PVDDQ_ABC_VRHOT_LVT3_N")
	)
	(segment
		(start 409.309062 -93.510354)
		(end 409.201112 -93.402404)
		(width 0.10795)
		(layer "B.Cu")
		(net "IRQ_PVDDQ_ABC_VRHOT_LVT3_N")
	)
	(segment
		(start 398.432274 -42.34053)
		(end 398.432274 -42.707814)
		(width 0.10795)
		(layer "B.Cu")
		(net "IRQ_PVDDQ_ABC_VRHOT_LVT3_N")
	)
	(segment
		(start 412.131256 -40.918892)
		(end 412.674308 -40.918892)
		(width 0.10795)
		(layer "B.Cu")
		(net "IRQ_PVDDQ_ABC_VRHOT_LVT3_N")
	)
	(segment
		(start 397.748252 -17.518634)
		(end 397.748252 -20.187666)
		(width 0.10795)
		(layer "B.Cu")
		(net "IRQ_PVDDQ_ABC_VRHOT_LVT3_N")
	)
	(segment
		(start 401.048982 -44.157646)
		(end 401.572222 -43.634406)
		(width 0.10795)
		(layer "B.Cu")
		(net "IRQ_PVDDQ_ABC_VRHOT_LVT3_N")
	)
	(segment
		(start 399.466308 -26.83129)
		(end 399.466308 -27.242008)
		(width 0.10795)
		(layer "B.Cu")
		(net "IRQ_PVDDQ_ABC_VRHOT_LVT3_N")
	)
	(segment
		(start 399.373598 -41.399206)
		(end 398.432274 -42.34053)
		(width 0.10795)
		(layer "B.Cu")
		(net "IRQ_PVDDQ_ABC_VRHOT_LVT3_N")
	)
	(segment
		(start 400.377152 -37.3507)
		(end 399.654268 -37.3507)
		(width 0.10795)
		(layer "B.Cu")
		(net "IRQ_PVDDQ_ABC_VRHOT_LVT3_N")
	)
	(segment
		(start 398.432274 -42.707814)
		(end 399.882106 -44.157646)
		(width 0.10795)
		(layer "B.Cu")
		(net "IRQ_PVDDQ_ABC_VRHOT_LVT3_N")
	)
	(segment
		(start 412.423356 -42.545)
		(end 412.215838 -42.545)
		(width 0.10795)
		(layer "B.Cu")
		(net "IRQ_PVDDQ_ABC_VRHOT_LVT3_N")
	)
	(segment
		(start 399.429732 -29.105098)
		(end 399.429732 -29.805122)
		(width 0.10795)
		(layer "B.Cu")
		(net "IRQ_PVDDQ_ABC_VRHOT_LVT3_N")
	)
	(segment
		(start 408.036268 -92.089732)
		(end 407.411936 -91.4654)
		(width 0.10795)
		(layer "B.Cu")
		(net "IRQ_PVDDQ_ABC_VRHOT_LVT3_N")
	)
	(segment
		(start 413.23514 -44.82211)
		(end 413.23514 -45.695362)
		(width 0.10795)
		(layer "B.Cu")
		(net "IRQ_PVDDQ_ABC_VRHOT_LVT3_N")
	)
	(segment
		(start 400.854926 -36.252658)
		(end 400.854926 -36.872926)
		(width 0.10795)
		(layer "B.Cu")
		(net "IRQ_PVDDQ_ABC_VRHOT_LVT3_N")
	)
	(segment
		(start 399.373598 -37.63137)
		(end 399.373598 -41.399206)
		(width 0.10795)
		(layer "B.Cu")
		(net "IRQ_PVDDQ_ABC_VRHOT_LVT3_N")
	)
	(segment
		(start 398.069054 -17.197832)
		(end 397.748252 -17.518634)
		(width 0.10795)
		(layer "B.Cu")
		(net "IRQ_PVDDQ_ABC_VRHOT_LVT3_N")
	)
	(segment
		(start 413.090106 -41.33469)
		(end 412.70682 -41.717976)
		(width 0.10795)
		(layer "B.Cu")
		(net "IRQ_PVDDQ_ABC_VRHOT_LVT3_N")
	)
	(segment
		(start 400.605244 -36.002976)
		(end 400.854926 -36.252658)
		(width 0.10795)
		(layer "B.Cu")
		(net "IRQ_PVDDQ_ABC_VRHOT_LVT3_N")
	)
	(segment
		(start 399.535396 -35.17011)
		(end 400.368262 -36.002976)
		(width 0.10795)
		(layer "B.Cu")
		(net "IRQ_PVDDQ_ABC_VRHOT_LVT3_N")
	)
	(segment
		(start 404.253954 -43.634406)
		(end 404.716742 -43.171618)
		(width 0.10795)
		(layer "B.Cu")
		(net "IRQ_PVDDQ_ABC_VRHOT_LVT3_N")
	)
	(segment
		(start 411.997398 -43.417998)
		(end 412.120842 -43.541442)
		(width 0.10795)
		(layer "B.Cu")
		(net "IRQ_PVDDQ_ABC_VRHOT_LVT3_N")
	)
	(segment
		(start 398.5133 -25.878282)
		(end 399.466308 -26.83129)
		(width 0.10795)
		(layer "B.Cu")
		(net "IRQ_PVDDQ_ABC_VRHOT_LVT3_N")
	)
	(segment
		(start 412.120842 -43.541442)
		(end 412.900622 -43.541442)
		(width 0.10795)
		(layer "B.Cu")
		(net "IRQ_PVDDQ_ABC_VRHOT_LVT3_N")
	)
	(segment
		(start 398.263364 -24.960072)
		(end 398.5133 -25.210008)
		(width 0.10795)
		(layer "B.Cu")
		(net "IRQ_PVDDQ_ABC_VRHOT_LVT3_N")
	)
	(segment
		(start 398.738852 -14.15542)
		(end 398.069054 -14.825218)
		(width 0.10795)
		(layer "B.Cu")
		(net "IRQ_PVDDQ_ABC_VRHOT_LVT3_N")
	)
	(segment
		(start 402.67128 -90.599006)
		(end 398.674336 -94.59595)
		(width 0.10795)
		(layer "B.Cu")
		(net "IRQ_PVDDQ_ABC_VRHOT_LVT3_N")
	)
	(segment
		(start 412.215838 -42.545)
		(end 411.997398 -42.76344)
		(width 0.10795)
		(layer "B.Cu")
		(net "IRQ_PVDDQ_ABC_VRHOT_LVT3_N")
	)
	(segment
		(start 411.997398 -42.76344)
		(end 411.997398 -43.417998)
		(width 0.10795)
		(layer "B.Cu")
		(net "IRQ_PVDDQ_ABC_VRHOT_LVT3_N")
	)
	(segment
		(start 412.696406 -42.27195)
		(end 412.423356 -42.545)
		(width 0.10795)
		(layer "B.Cu")
		(net "IRQ_PVDDQ_ABC_VRHOT_LVT3_N")
	)
	(segment
		(start 406.945084 -42.683176)
		(end 406.945084 -41.727882)
		(width 0.10795)
		(layer "B.Cu")
		(net "IRQ_PVDDQ_ABC_VRHOT_LVT3_N")
	)
	(segment
		(start 398.5133 -25.210008)
		(end 398.5133 -25.878282)
		(width 0.10795)
		(layer "B.Cu")
		(net "IRQ_PVDDQ_ABC_VRHOT_LVT3_N")
	)
	(segment
		(start 412.674308 -40.918892)
		(end 413.090106 -41.33469)
		(width 0.10795)
		(layer "B.Cu")
		(net "IRQ_PVDDQ_ABC_VRHOT_LVT3_N")
	)
	(segment
		(start 413.872426 -55.30215)
		(end 413.91713 -55.30215)
		(width 0.10795)
		(layer "B.Cu")
		(net "IRQ_PVDDQ_ABC_VRHOT_LVT3_N")
	)
	(segment
		(start 399.535396 -33.288224)
		(end 399.535396 -35.17011)
		(width 0.10795)
		(layer "B.Cu")
		(net "IRQ_PVDDQ_ABC_VRHOT_LVT3_N")
	)
	(segment
		(start 392.575288 -9.699752)
		(end 392.575288 -9.374632)
		(width 0.10795)
		(layer "B.Cu")
		(net "IRQ_PVDDQ_ABC_VRHOT_LVT3_N")
	)
	(segment
		(start 413.022796 -54.45252)
		(end 413.872426 -55.30215)
		(width 0.10795)
		(layer "B.Cu")
		(net "IRQ_PVDDQ_ABC_VRHOT_LVT3_N")
	)
	(segment
		(start 392.575288 -9.374632)
		(end 393.54252 -8.4074)
		(width 0.10795)
		(layer "B.Cu")
		(net "IRQ_PVDDQ_ABC_VRHOT_LVT3_N")
	)
	(segment
		(start 398.738852 -9.229852)
		(end 398.738852 -14.15542)
		(width 0.10795)
		(layer "B.Cu")
		(net "IRQ_PVDDQ_ABC_VRHOT_LVT3_N")
	)
	(segment
		(start 412.705804 -42.262044)
		(end 412.696406 -42.271442)
		(width 0.10795)
		(layer "B.Cu")
		(net "IRQ_PVDDQ_ABC_VRHOT_LVT3_N")
	)
	(segment
		(start 399.466308 -27.242008)
		(end 400.118326 -27.894026)
		(width 0.10795)
		(layer "B.Cu")
		(net "IRQ_PVDDQ_ABC_VRHOT_LVT3_N")
	)
	(segment
		(start 413.022796 -47.47895)
		(end 413.022796 -54.45252)
		(width 0.10795)
		(layer "B.Cu")
		(net "IRQ_PVDDQ_ABC_VRHOT_LVT3_N")
	)
	(segment
		(start 408.93111 -40.150542)
		(end 411.649164 -40.150542)
		(width 0.10795)
		(layer "B.Cu")
		(net "IRQ_PVDDQ_ABC_VRHOT_LVT3_N")
	)
	(segment
		(start 412.696406 -42.271442)
		(end 412.696406 -42.27195)
		(width 0.10795)
		(layer "B.Cu")
		(net "IRQ_PVDDQ_ABC_VRHOT_LVT3_N")
	)
	(segment
		(start 399.408904 -33.161732)
		(end 399.535396 -33.288224)
		(width 0.10795)
		(layer "B.Cu")
		(net "IRQ_PVDDQ_ABC_VRHOT_LVT3_N")
	)
	(segment
		(start 399.882106 -44.157646)
		(end 401.048982 -44.157646)
		(width 0.10795)
		(layer "B.Cu")
		(net "IRQ_PVDDQ_ABC_VRHOT_LVT3_N")
	)
	(segment
		(start 408.689048 -40.678862)
		(end 408.689048 -40.392604)
		(width 0.10795)
		(layer "B.Cu")
		(net "IRQ_PVDDQ_ABC_VRHOT_LVT3_N")
	)
	(segment
		(start 397.748252 -20.187666)
		(end 398.263364 -20.702778)
		(width 0.10795)
		(layer "B.Cu")
		(net "IRQ_PVDDQ_ABC_VRHOT_LVT3_N")
	)
	(segment
		(start 411.895798 -40.397176)
		(end 411.895798 -40.683434)
		(width 0.10795)
		(layer "B.Cu")
		(net "IRQ_PVDDQ_ABC_VRHOT_LVT3_N")
	)
	(segment
		(start 393.54252 -8.4074)
		(end 397.9164 -8.4074)
		(width 0.10795)
		(layer "B.Cu")
		(net "IRQ_PVDDQ_ABC_VRHOT_LVT3_N")
	)
	(segment
		(start 413.125666 -43.766486)
		(end 413.125666 -44.712636)
		(width 0.10795)
		(layer "B.Cu")
		(net "IRQ_PVDDQ_ABC_VRHOT_LVT3_N")
	)
	(segment
		(start 412.900622 -43.541442)
		(end 413.125666 -43.766486)
		(width 0.10795)
		(layer "B.Cu")
		(net "IRQ_PVDDQ_ABC_VRHOT_LVT3_N")
	)
	(segment
		(start 409.201112 -92.087192)
		(end 409.03398 -91.92006)
		(width 0.10795)
		(layer "B.Cu")
		(net "IRQ_PVDDQ_ABC_VRHOT_LVT3_N")
	)
	(segment
		(start 412.70682 -41.974262)
		(end 412.705804 -41.975278)
		(width 0.10795)
		(layer "B.Cu")
		(net "IRQ_PVDDQ_ABC_VRHOT_LVT3_N")
	)
	(segment
		(start 398.263364 -20.702778)
		(end 398.263364 -24.960072)
		(width 0.10795)
		(layer "B.Cu")
		(net "IRQ_PVDDQ_ABC_VRHOT_LVT3_N")
	)
	(segment
		(start 398.831308 -30.403546)
		(end 398.831308 -31.168086)
		(width 0.10795)
		(layer "B.Cu")
		(net "IRQ_PVDDQ_ABC_VRHOT_LVT3_N")
	)
	(segment
		(start 399.654268 -37.3507)
		(end 399.373598 -37.63137)
		(width 0.10795)
		(layer "B.Cu")
		(net "IRQ_PVDDQ_ABC_VRHOT_LVT3_N")
	)
	(segment
		(start 408.689048 -40.392604)
		(end 408.93111 -40.150542)
		(width 0.10795)
		(layer "B.Cu")
		(net "IRQ_PVDDQ_ABC_VRHOT_LVT3_N")
	)
	(segment
		(start 399.408904 -31.98495)
		(end 399.408904 -33.161732)
		(width 0.10795)
		(layer "B.Cu")
		(net "IRQ_PVDDQ_ABC_VRHOT_LVT3_N")
	)
	(segment
		(start 400.118326 -28.416504)
		(end 399.429732 -29.105098)
		(width 0.10795)
		(layer "B.Cu")
		(net "IRQ_PVDDQ_ABC_VRHOT_LVT3_N")
	)
	(segment
		(start 409.03398 -91.92006)
		(end 408.864308 -92.089732)
		(width 0.10795)
		(layer "B.Cu")
		(net "IRQ_PVDDQ_ABC_VRHOT_LVT3_N")
	)
	(segment
		(start 408.864308 -92.089732)
		(end 408.036268 -92.089732)
		(width 0.10795)
		(layer "B.Cu")
		(net "IRQ_PVDDQ_ABC_VRHOT_LVT3_N")
	)
	(segment
		(start 412.70682 -41.717976)
		(end 412.70682 -41.974262)
		(width 0.10795)
		(layer "B.Cu")
		(net "IRQ_PVDDQ_ABC_VRHOT_LVT3_N")
	)
	(segment
		(start 407.993088 -90.777314)
		(end 409.03398 -91.818206)
		(width 0.089408)
		(layer "In2.Cu")
		(net "IRQ_PVDDQ_ABC_VRHOT_LVT3_N")
	)
	(segment
		(start 404.795228 -74.124058)
		(end 404.795228 -74.445876)
		(width 0.089408)
		(layer "In2.Cu")
		(net "IRQ_PVDDQ_ABC_VRHOT_LVT3_N")
	)
	(segment
		(start 409.03398 -91.818206)
		(end 409.03398 -91.92006)
		(width 0.089408)
		(layer "In2.Cu")
		(net "IRQ_PVDDQ_ABC_VRHOT_LVT3_N")
	)
	(segment
		(start 404.795228 -74.445876)
		(end 404.17242 -75.068684)
		(width 0.089408)
		(layer "In2.Cu")
		(net "IRQ_PVDDQ_ABC_VRHOT_LVT3_N")
	)
	(segment
		(start 411.451298 -55.959248)
		(end 410.485844 -56.924702)
		(width 0.089408)
		(layer "In2.Cu")
		(net "IRQ_PVDDQ_ABC_VRHOT_LVT3_N")
	)
	(segment
		(start 404.681944 -79.208376)
		(end 404.681944 -79.331312)
		(width 0.089408)
		(layer "In2.Cu")
		(net "IRQ_PVDDQ_ABC_VRHOT_LVT3_N")
	)
	(segment
		(start 404.68169 -79.331566)
		(end 404.68169 -80.44053)
		(width 0.089408)
		(layer "In2.Cu")
		(net "IRQ_PVDDQ_ABC_VRHOT_LVT3_N")
	)
	(segment
		(start 406.533096 -87.000334)
		(end 407.993088 -88.460326)
		(width 0.089408)
		(layer "In2.Cu")
		(net "IRQ_PVDDQ_ABC_VRHOT_LVT3_N")
	)
	(segment
		(start 413.260032 -55.959248)
		(end 411.451298 -55.959248)
		(width 0.089408)
		(layer "In2.Cu")
		(net "IRQ_PVDDQ_ABC_VRHOT_LVT3_N")
	)
	(segment
		(start 410.485844 -68.433442)
		(end 404.795228 -74.124058)
		(width 0.089408)
		(layer "In2.Cu")
		(net "IRQ_PVDDQ_ABC_VRHOT_LVT3_N")
	)
	(segment
		(start 406.533096 -82.291936)
		(end 406.533096 -87.000334)
		(width 0.089408)
		(layer "In2.Cu")
		(net "IRQ_PVDDQ_ABC_VRHOT_LVT3_N")
	)
	(segment
		(start 404.68169 -80.44053)
		(end 406.533096 -82.291936)
		(width 0.089408)
		(layer "In2.Cu")
		(net "IRQ_PVDDQ_ABC_VRHOT_LVT3_N")
	)
	(segment
		(start 404.17242 -75.068684)
		(end 404.17242 -78.698852)
		(width 0.089408)
		(layer "In2.Cu")
		(net "IRQ_PVDDQ_ABC_VRHOT_LVT3_N")
	)
	(segment
		(start 404.17242 -78.698852)
		(end 404.681944 -79.208376)
		(width 0.089408)
		(layer "In2.Cu")
		(net "IRQ_PVDDQ_ABC_VRHOT_LVT3_N")
	)
	(segment
		(start 404.681944 -79.331312)
		(end 404.68169 -79.331566)
		(width 0.089408)
		(layer "In2.Cu")
		(net "IRQ_PVDDQ_ABC_VRHOT_LVT3_N")
	)
	(segment
		(start 410.485844 -56.924702)
		(end 410.485844 -68.433442)
		(width 0.089408)
		(layer "In2.Cu")
		(net "IRQ_PVDDQ_ABC_VRHOT_LVT3_N")
	)
	(segment
		(start 413.91713 -55.30215)
		(end 413.260032 -55.959248)
		(width 0.089408)
		(layer "In2.Cu")
		(net "IRQ_PVDDQ_ABC_VRHOT_LVT3_N")
	)
	(segment
		(start 407.993088 -88.460326)
		(end 407.993088 -90.777314)
		(width 0.089408)
		(layer "In2.Cu")
		(net "IRQ_PVDDQ_ABC_VRHOT_LVT3_N")
	)
	(segment
		(start 363.529372 -27.640788)
		(end 355.405944 -35.764216)
		(width 0.089408)
		(layer "In11.Cu")
		(net "IRQ_PVDDQ_ABC_VRHOT_LVT3_N")
	)
	(segment
		(start 372.02618 -8.640318)
		(end 372.02618 -9.99744)
		(width 0.089408)
		(layer "In11.Cu")
		(net "IRQ_PVDDQ_ABC_VRHOT_LVT3_N")
	)
	(segment
		(start 391.3759 -9.380728)
		(end 391.22985 -9.526778)
		(width 0.089408)
		(layer "In11.Cu")
		(net "IRQ_PVDDQ_ABC_VRHOT_LVT3_N")
	)
	(segment
		(start 378.148342 -9.526778)
		(end 376.254264 -7.6327)
		(width 0.089408)
		(layer "In11.Cu")
		(net "IRQ_PVDDQ_ABC_VRHOT_LVT3_N")
	)
	(segment
		(start 373.033798 -7.6327)
		(end 372.02618 -8.640318)
		(width 0.089408)
		(layer "In11.Cu")
		(net "IRQ_PVDDQ_ABC_VRHOT_LVT3_N")
	)
	(segment
		(start 376.254264 -7.6327)
		(end 373.033798 -7.6327)
		(width 0.089408)
		(layer "In11.Cu")
		(net "IRQ_PVDDQ_ABC_VRHOT_LVT3_N")
	)
	(segment
		(start 391.22985 -9.526778)
		(end 378.148342 -9.526778)
		(width 0.089408)
		(layer "In11.Cu")
		(net "IRQ_PVDDQ_ABC_VRHOT_LVT3_N")
	)
	(segment
		(start 392.256264 -9.380728)
		(end 391.3759 -9.380728)
		(width 0.089408)
		(layer "In11.Cu")
		(net "IRQ_PVDDQ_ABC_VRHOT_LVT3_N")
	)
	(segment
		(start 337.920838 -35.764216)
		(end 337.662266 -35.505644)
		(width 0.089408)
		(layer "In11.Cu")
		(net "IRQ_PVDDQ_ABC_VRHOT_LVT3_N")
	)
	(segment
		(start 334.428338 -21.088096)
		(end 335.362042 -21.088096)
		(width 0.089408)
		(layer "In11.Cu")
		(net "IRQ_PVDDQ_ABC_VRHOT_LVT3_N")
	)
	(segment
		(start 335.80197 -21.528024)
		(end 337.577176 -21.528024)
		(width 0.089408)
		(layer "In11.Cu")
		(net "IRQ_PVDDQ_ABC_VRHOT_LVT3_N")
	)
	(segment
		(start 363.529372 -18.494248)
		(end 363.529372 -27.640788)
		(width 0.089408)
		(layer "In11.Cu")
		(net "IRQ_PVDDQ_ABC_VRHOT_LVT3_N")
	)
	(segment
		(start 392.575288 -9.699752)
		(end 392.256264 -9.380728)
		(width 0.089408)
		(layer "In11.Cu")
		(net "IRQ_PVDDQ_ABC_VRHOT_LVT3_N")
	)
	(segment
		(start 337.577176 -21.528024)
		(end 337.8962 -21.209)
		(width 0.089408)
		(layer "In11.Cu")
		(net "IRQ_PVDDQ_ABC_VRHOT_LVT3_N")
	)
	(segment
		(start 332.078584 -31.0007)
		(end 332.078584 -23.43785)
		(width 0.089408)
		(layer "In11.Cu")
		(net "IRQ_PVDDQ_ABC_VRHOT_LVT3_N")
	)
	(segment
		(start 335.362042 -21.088096)
		(end 335.80197 -21.528024)
		(width 0.089408)
		(layer "In11.Cu")
		(net "IRQ_PVDDQ_ABC_VRHOT_LVT3_N")
	)
	(segment
		(start 355.405944 -35.764216)
		(end 337.920838 -35.764216)
		(width 0.089408)
		(layer "In11.Cu")
		(net "IRQ_PVDDQ_ABC_VRHOT_LVT3_N")
	)
	(segment
		(start 337.662266 -35.505644)
		(end 336.583528 -35.505644)
		(width 0.089408)
		(layer "In11.Cu")
		(net "IRQ_PVDDQ_ABC_VRHOT_LVT3_N")
	)
	(segment
		(start 372.02618 -9.99744)
		(end 363.529372 -18.494248)
		(width 0.089408)
		(layer "In11.Cu")
		(net "IRQ_PVDDQ_ABC_VRHOT_LVT3_N")
	)
	(segment
		(start 336.583528 -35.505644)
		(end 332.078584 -31.0007)
		(width 0.089408)
		(layer "In11.Cu")
		(net "IRQ_PVDDQ_ABC_VRHOT_LVT3_N")
	)
	(segment
		(start 332.078584 -23.43785)
		(end 334.428338 -21.088096)
		(width 0.089408)
		(layer "In11.Cu")
		(net "IRQ_PVDDQ_ABC_VRHOT_LVT3_N")
	)
	(segment
		(start 380.985014 -93.544898)
		(end 380.953264 -93.513148)
		(width 0.0889)
		(layer "F.Cu")
		(net "PU_IRQ_PCH_SCI_WHEA_N")
	)
	(segment
		(start 380.953264 -92.52585)
		(end 380.554484 -92.12707)
		(width 0.0889)
		(layer "F.Cu")
		(net "PU_IRQ_PCH_SCI_WHEA_N")
	)
	(segment
		(start 380.953264 -93.513148)
		(end 380.953264 -92.52585)
		(width 0.0889)
		(layer "F.Cu")
		(net "PU_IRQ_PCH_SCI_WHEA_N")
	)
	(via
		(at 380.554484 -92.12707)
		(size 0.508)
		(drill 0.254)
		(layers "F.Cu" "B.Cu")
		(net "PU_IRQ_PCH_SCI_WHEA_N")
	)
	(via
		(at 381.34544 -93.29928)
		(size 0.6604)
		(drill 0.3302)
		(layers "F.Cu" "B.Cu")
		(net "PU_IRQ_PCH_SCI_WHEA_N")
	)
	(segment
		(start 381.26416 -88.44534)
		(end 381.508 -88.2015)
		(width 0.10795)
		(layer "B.Cu")
		(net "PU_IRQ_PCH_SCI_WHEA_N")
	)
	(segment
		(start 381.34544 -93.29928)
		(end 381.34544 -92.918026)
		(width 0.10795)
		(layer "B.Cu")
		(net "PU_IRQ_PCH_SCI_WHEA_N")
	)
	(segment
		(start 380.554484 -92.12707)
		(end 381.26416 -91.417394)
		(width 0.10795)
		(layer "B.Cu")
		(net "PU_IRQ_PCH_SCI_WHEA_N")
	)
	(segment
		(start 381.34544 -92.918026)
		(end 380.554484 -92.12707)
		(width 0.10795)
		(layer "B.Cu")
		(net "PU_IRQ_PCH_SCI_WHEA_N")
	)
	(segment
		(start 381.26416 -91.417394)
		(end 381.26416 -88.44534)
		(width 0.10795)
		(layer "B.Cu")
		(net "PU_IRQ_PCH_SCI_WHEA_N")
	)
	(segment
		(start 378.82195 -96.9772)
		(end 379.31725 -96.747076)
		(width 0.10795)
		(layer "F.Cu")
		(net "IRQ_LVC3_WAKE_N")
	)
	(via
		(at 387.6421 -59.5122)
		(size 0.508)
		(drill 0.254)
		(layers "F.Cu" "B.Cu")
		(net "IRQ_LVC3_WAKE_N")
	)
	(via
		(at 379.31725 -96.747076)
		(size 0.508)
		(drill 0.254)
		(layers "F.Cu" "B.Cu")
		(net "IRQ_LVC3_WAKE_N")
	)
	(via
		(at 396.520416 -59.50077)
		(size 0.508)
		(drill 0.254)
		(layers "F.Cu" "B.Cu")
		(net "IRQ_LVC3_WAKE_N")
	)
	(via
		(at 423.037 -57.404)
		(size 0.6604)
		(drill 0.3302)
		(layers "F.Cu" "B.Cu")
		(net "IRQ_LVC3_WAKE_N")
	)
	(via
		(at 402.005546 -64.172084)
		(size 0.508)
		(drill 0.254)
		(layers "F.Cu" "B.Cu")
		(net "IRQ_LVC3_WAKE_N")
	)
	(segment
		(start 414.98266 -59.455812)
		(end 413.014414 -59.455812)
		(width 0.10795)
		(layer "B.Cu")
		(net "IRQ_LVC3_WAKE_N")
	)
	(segment
		(start 376.849132 -94.081346)
		(end 376.427746 -94.081346)
		(width 0.10795)
		(layer "B.Cu")
		(net "IRQ_LVC3_WAKE_N")
	)
	(segment
		(start 466.006688 -56.388)
		(end 435.326028 -56.388)
		(width 0.10795)
		(layer "B.Cu")
		(net "IRQ_LVC3_WAKE_N")
	)
	(segment
		(start 373.4054 -91.70162)
		(end 373.4054 -91.567)
		(width 0.10795)
		(layer "B.Cu")
		(net "IRQ_LVC3_WAKE_N")
	)
	(segment
		(start 404.892002 -61.87186)
		(end 403.331172 -61.87186)
		(width 0.10795)
		(layer "B.Cu")
		(net "IRQ_LVC3_WAKE_N")
	)
	(segment
		(start 387.864096 -59.404504)
		(end 391.888472 -59.404504)
		(width 0.10795)
		(layer "B.Cu")
		(net "IRQ_LVC3_WAKE_N")
	)
	(segment
		(start 392.398758 -59.91479)
		(end 394.471398 -59.91479)
		(width 0.10795)
		(layer "B.Cu")
		(net "IRQ_LVC3_WAKE_N")
	)
	(segment
		(start 374.03151 -92.32773)
		(end 373.4054 -91.70162)
		(width 0.10795)
		(layer "B.Cu")
		(net "IRQ_LVC3_WAKE_N")
	)
	(segment
		(start 394.471398 -59.91479)
		(end 394.885418 -59.50077)
		(width 0.10795)
		(layer "B.Cu")
		(net "IRQ_LVC3_WAKE_N")
	)
	(segment
		(start 471.243152 -52.885848)
		(end 470.652348 -53.476652)
		(width 0.10795)
		(layer "B.Cu")
		(net "IRQ_LVC3_WAKE_N")
	)
	(segment
		(start 480.753928 -53.373528)
		(end 480.3648 -52.9844)
		(width 0.10795)
		(layer "B.Cu")
		(net "IRQ_LVC3_WAKE_N")
	)
	(segment
		(start 387.7564 -59.5122)
		(end 387.864096 -59.404504)
		(width 0.10795)
		(layer "B.Cu")
		(net "IRQ_LVC3_WAKE_N")
	)
	(segment
		(start 423.037 -57.404)
		(end 422.741852 -57.699148)
		(width 0.10795)
		(layer "B.Cu")
		(net "IRQ_LVC3_WAKE_N")
	)
	(segment
		(start 472.868498 -52.885848)
		(end 471.243152 -52.885848)
		(width 0.10795)
		(layer "B.Cu")
		(net "IRQ_LVC3_WAKE_N")
	)
	(segment
		(start 410.138626 -62.3316)
		(end 407.350214 -62.3316)
		(width 0.10795)
		(layer "B.Cu")
		(net "IRQ_LVC3_WAKE_N")
	)
	(segment
		(start 379.7173 -96.758252)
		(end 379.7173 -96.7359)
		(width 0.0889)
		(layer "B.Cu")
		(net "IRQ_LVC3_WAKE_N")
	)
	(segment
		(start 413.014414 -59.455812)
		(end 410.138626 -62.3316)
		(width 0.10795)
		(layer "B.Cu")
		(net "IRQ_LVC3_WAKE_N")
	)
	(segment
		(start 470.652348 -53.476652)
		(end 468.918036 -53.476652)
		(width 0.10795)
		(layer "B.Cu")
		(net "IRQ_LVC3_WAKE_N")
	)
	(segment
		(start 376.427746 -94.081346)
		(end 376.01017 -93.66377)
		(width 0.10795)
		(layer "B.Cu")
		(net "IRQ_LVC3_WAKE_N")
	)
	(segment
		(start 433.111402 -54.55539)
		(end 433.111148 -54.555644)
		(width 0.10795)
		(layer "B.Cu")
		(net "IRQ_LVC3_WAKE_N")
	)
	(segment
		(start 477.494346 -52.9844)
		(end 477.243648 -53.235098)
		(width 0.10795)
		(layer "B.Cu")
		(net "IRQ_LVC3_WAKE_N")
	)
	(segment
		(start 433.111148 -54.555644)
		(end 429.605948 -54.555644)
		(width 0.10795)
		(layer "B.Cu")
		(net "IRQ_LVC3_WAKE_N")
	)
	(segment
		(start 391.888472 -59.404504)
		(end 392.398758 -59.91479)
		(width 0.10795)
		(layer "B.Cu")
		(net "IRQ_LVC3_WAKE_N")
	)
	(segment
		(start 406.899618 -61.881004)
		(end 404.901146 -61.881004)
		(width 0.10795)
		(layer "B.Cu")
		(net "IRQ_LVC3_WAKE_N")
	)
	(segment
		(start 379.222 -95.717614)
		(end 378.917708 -95.413322)
		(width 0.0889)
		(layer "B.Cu")
		(net "IRQ_LVC3_WAKE_N")
	)
	(segment
		(start 417.397438 -57.699148)
		(end 415.64052 -59.456066)
		(width 0.10795)
		(layer "B.Cu")
		(net "IRQ_LVC3_WAKE_N")
	)
	(segment
		(start 481.601272 -53.373528)
		(end 480.753928 -53.373528)
		(width 0.10795)
		(layer "B.Cu")
		(net "IRQ_LVC3_WAKE_N")
	)
	(segment
		(start 394.885418 -59.50077)
		(end 396.520416 -59.50077)
		(width 0.10795)
		(layer "B.Cu")
		(net "IRQ_LVC3_WAKE_N")
	)
	(segment
		(start 476.58909 -53.235098)
		(end 475.65056 -52.296568)
		(width 0.10795)
		(layer "B.Cu")
		(net "IRQ_LVC3_WAKE_N")
	)
	(segment
		(start 376.01017 -93.66377)
		(end 374.632474 -93.66377)
		(width 0.10795)
		(layer "B.Cu")
		(net "IRQ_LVC3_WAKE_N")
	)
	(segment
		(start 422.741852 -57.699148)
		(end 417.397438 -57.699148)
		(width 0.10795)
		(layer "B.Cu")
		(net "IRQ_LVC3_WAKE_N")
	)
	(segment
		(start 403.331172 -61.87186)
		(end 402.005546 -63.197486)
		(width 0.10795)
		(layer "B.Cu")
		(net "IRQ_LVC3_WAKE_N")
	)
	(segment
		(start 435.326028 -56.388)
		(end 433.493418 -54.55539)
		(width 0.10795)
		(layer "B.Cu")
		(net "IRQ_LVC3_WAKE_N")
	)
	(segment
		(start 415.64052 -59.456066)
		(end 414.982914 -59.456066)
		(width 0.10795)
		(layer "B.Cu")
		(net "IRQ_LVC3_WAKE_N")
	)
	(segment
		(start 374.03151 -93.062806)
		(end 374.03151 -92.32773)
		(width 0.10795)
		(layer "B.Cu")
		(net "IRQ_LVC3_WAKE_N")
	)
	(segment
		(start 379.48616 -97.040192)
		(end 379.5649 -97.061274)
		(width 0.0889)
		(layer "B.Cu")
		(net "IRQ_LVC3_WAKE_N")
	)
	(segment
		(start 379.222 -95.910146)
		(end 379.222 -95.717614)
		(width 0.0889)
		(layer "B.Cu")
		(net "IRQ_LVC3_WAKE_N")
	)
	(segment
		(start 374.632474 -93.66377)
		(end 374.03151 -93.062806)
		(width 0.10795)
		(layer "B.Cu")
		(net "IRQ_LVC3_WAKE_N")
	)
	(segment
		(start 426.757592 -57.404)
		(end 423.037 -57.404)
		(width 0.10795)
		(layer "B.Cu")
		(net "IRQ_LVC3_WAKE_N")
	)
	(segment
		(start 404.901146 -61.881004)
		(end 404.892002 -61.87186)
		(width 0.10795)
		(layer "B.Cu")
		(net "IRQ_LVC3_WAKE_N")
	)
	(segment
		(start 378.917708 -95.413322)
		(end 378.129546 -94.62516)
		(width 0.10795)
		(layer "B.Cu")
		(net "IRQ_LVC3_WAKE_N")
	)
	(segment
		(start 407.350214 -62.3316)
		(end 406.899618 -61.881004)
		(width 0.10795)
		(layer "B.Cu")
		(net "IRQ_LVC3_WAKE_N")
	)
	(segment
		(start 414.982914 -59.456066)
		(end 414.98266 -59.455812)
		(width 0.10795)
		(layer "B.Cu")
		(net "IRQ_LVC3_WAKE_N")
	)
	(segment
		(start 481.838 -53.1368)
		(end 481.601272 -53.373528)
		(width 0.10795)
		(layer "B.Cu")
		(net "IRQ_LVC3_WAKE_N")
	)
	(segment
		(start 480.3648 -52.9844)
		(end 477.494346 -52.9844)
		(width 0.10795)
		(layer "B.Cu")
		(net "IRQ_LVC3_WAKE_N")
	)
	(segment
		(start 433.493418 -54.55539)
		(end 433.111402 -54.55539)
		(width 0.10795)
		(layer "B.Cu")
		(net "IRQ_LVC3_WAKE_N")
	)
	(segment
		(start 402.005546 -63.197486)
		(end 402.005546 -64.172084)
		(width 0.10795)
		(layer "B.Cu")
		(net "IRQ_LVC3_WAKE_N")
	)
	(segment
		(start 475.65056 -52.296568)
		(end 473.457778 -52.296568)
		(width 0.10795)
		(layer "B.Cu")
		(net "IRQ_LVC3_WAKE_N")
	)
	(segment
		(start 387.6421 -59.5122)
		(end 387.7564 -59.5122)
		(width 0.10795)
		(layer "B.Cu")
		(net "IRQ_LVC3_WAKE_N")
	)
	(segment
		(start 468.918036 -53.476652)
		(end 466.006688 -56.388)
		(width 0.10795)
		(layer "B.Cu")
		(net "IRQ_LVC3_WAKE_N")
	)
	(segment
		(start 377.392946 -94.62516)
		(end 376.849132 -94.081346)
		(width 0.10795)
		(layer "B.Cu")
		(net "IRQ_LVC3_WAKE_N")
	)
	(segment
		(start 379.31725 -96.747076)
		(end 379.48616 -97.040192)
		(width 0.0889)
		(layer "B.Cu")
		(net "IRQ_LVC3_WAKE_N")
	)
	(segment
		(start 477.243648 -53.235098)
		(end 476.58909 -53.235098)
		(width 0.10795)
		(layer "B.Cu")
		(net "IRQ_LVC3_WAKE_N")
	)
	(segment
		(start 473.457778 -52.296568)
		(end 472.868498 -52.885848)
		(width 0.10795)
		(layer "B.Cu")
		(net "IRQ_LVC3_WAKE_N")
	)
	(segment
		(start 378.129546 -94.62516)
		(end 377.392946 -94.62516)
		(width 0.10795)
		(layer "B.Cu")
		(net "IRQ_LVC3_WAKE_N")
	)
	(segment
		(start 429.605948 -54.555644)
		(end 426.757592 -57.404)
		(width 0.10795)
		(layer "B.Cu")
		(net "IRQ_LVC3_WAKE_N")
	)
	(arc
		(start 379.7173 -96.7359)
		(mid 379.66095 -96.54205)
		(end 379.517148 -96.400366)
		(width 0.0889)
		(layer "B.Cu")
		(net "IRQ_LVC3_WAKE_N")
	)
	(arc
		(start 379.517148 -96.400366)
		(mid 379.306284 -96.193362)
		(end 379.222 -95.910146)
		(width 0.0889)
		(layer "B.Cu")
		(net "IRQ_LVC3_WAKE_N")
	)
	(arc
		(start 379.5649 -97.061274)
		(mid 379.674812 -96.926712)
		(end 379.7173 -96.758252)
		(width 0.0889)
		(layer "B.Cu")
		(net "IRQ_LVC3_WAKE_N")
	)
	(segment
		(start 379.136148 -85.231732)
		(end 379.136148 -92.42552)
		(width 0.089408)
		(layer "In9.Cu")
		(net "IRQ_LVC3_WAKE_N")
	)
	(segment
		(start 384.646932 -70.78853)
		(end 384.532124 -70.903338)
		(width 0.089408)
		(layer "In9.Cu")
		(net "IRQ_LVC3_WAKE_N")
	)
	(segment
		(start 385.945634 -69.691758)
		(end 384.848862 -70.78853)
		(width 0.089408)
		(layer "In9.Cu")
		(net "IRQ_LVC3_WAKE_N")
	)
	(segment
		(start 387.432296 -60.827158)
		(end 387.432296 -61.824108)
		(width 0.089408)
		(layer "In9.Cu")
		(net "IRQ_LVC3_WAKE_N")
	)
	(segment
		(start 380.528576 -83.57997)
		(end 380.528576 -83.839304)
		(width 0.089408)
		(layer "In9.Cu")
		(net "IRQ_LVC3_WAKE_N")
	)
	(segment
		(start 379.22073 -94.870524)
		(end 379.22073 -96.650556)
		(width 0.089408)
		(layer "In9.Cu")
		(net "IRQ_LVC3_WAKE_N")
	)
	(segment
		(start 384.065018 -73.42505)
		(end 383.402586 -74.087482)
		(width 0.089408)
		(layer "In9.Cu")
		(net "IRQ_LVC3_WAKE_N")
	)
	(segment
		(start 380.528576 -83.839304)
		(end 379.136148 -85.231732)
		(width 0.089408)
		(layer "In9.Cu")
		(net "IRQ_LVC3_WAKE_N")
	)
	(segment
		(start 382.023112 -79.596488)
		(end 382.72974 -80.303116)
		(width 0.089408)
		(layer "In9.Cu")
		(net "IRQ_LVC3_WAKE_N")
	)
	(segment
		(start 387.6421 -59.5503)
		(end 387.7056 -59.6138)
		(width 0.089408)
		(layer "In9.Cu")
		(net "IRQ_LVC3_WAKE_N")
	)
	(segment
		(start 382.72974 -81.378806)
		(end 380.528576 -83.57997)
		(width 0.089408)
		(layer "In9.Cu")
		(net "IRQ_LVC3_WAKE_N")
	)
	(segment
		(start 384.188716 -73.42505)
		(end 384.065018 -73.42505)
		(width 0.089408)
		(layer "In9.Cu")
		(net "IRQ_LVC3_WAKE_N")
	)
	(segment
		(start 383.402586 -74.087482)
		(end 383.402586 -76.166472)
		(width 0.089408)
		(layer "In9.Cu")
		(net "IRQ_LVC3_WAKE_N")
	)
	(segment
		(start 386.117338 -69.517006)
		(end 385.945634 -69.68871)
		(width 0.089408)
		(layer "In9.Cu")
		(net "IRQ_LVC3_WAKE_N")
	)
	(segment
		(start 384.532124 -73.081642)
		(end 384.188716 -73.42505)
		(width 0.089408)
		(layer "In9.Cu")
		(net "IRQ_LVC3_WAKE_N")
	)
	(segment
		(start 379.22073 -96.650556)
		(end 379.31725 -96.747076)
		(width 0.089408)
		(layer "In9.Cu")
		(net "IRQ_LVC3_WAKE_N")
	)
	(segment
		(start 387.432296 -61.824108)
		(end 386.117338 -63.139066)
		(width 0.089408)
		(layer "In9.Cu")
		(net "IRQ_LVC3_WAKE_N")
	)
	(segment
		(start 386.117338 -63.139066)
		(end 386.117338 -69.517006)
		(width 0.089408)
		(layer "In9.Cu")
		(net "IRQ_LVC3_WAKE_N")
	)
	(segment
		(start 387.7056 -60.553854)
		(end 387.432296 -60.827158)
		(width 0.089408)
		(layer "In9.Cu")
		(net "IRQ_LVC3_WAKE_N")
	)
	(segment
		(start 383.402586 -76.166472)
		(end 382.023112 -77.545946)
		(width 0.089408)
		(layer "In9.Cu")
		(net "IRQ_LVC3_WAKE_N")
	)
	(segment
		(start 384.848862 -70.78853)
		(end 384.646932 -70.78853)
		(width 0.089408)
		(layer "In9.Cu")
		(net "IRQ_LVC3_WAKE_N")
	)
	(segment
		(start 385.945634 -69.68871)
		(end 385.945634 -69.691758)
		(width 0.089408)
		(layer "In9.Cu")
		(net "IRQ_LVC3_WAKE_N")
	)
	(segment
		(start 384.532124 -70.903338)
		(end 384.532124 -73.081642)
		(width 0.089408)
		(layer "In9.Cu")
		(net "IRQ_LVC3_WAKE_N")
	)
	(segment
		(start 379.136402 -92.425774)
		(end 379.136402 -94.786196)
		(width 0.089408)
		(layer "In9.Cu")
		(net "IRQ_LVC3_WAKE_N")
	)
	(segment
		(start 382.72974 -80.303116)
		(end 382.72974 -81.378806)
		(width 0.089408)
		(layer "In9.Cu")
		(net "IRQ_LVC3_WAKE_N")
	)
	(segment
		(start 387.6421 -59.5122)
		(end 387.6421 -59.5503)
		(width 0.089408)
		(layer "In9.Cu")
		(net "IRQ_LVC3_WAKE_N")
	)
	(segment
		(start 382.023112 -77.545946)
		(end 382.023112 -79.596488)
		(width 0.089408)
		(layer "In9.Cu")
		(net "IRQ_LVC3_WAKE_N")
	)
	(segment
		(start 379.136402 -94.786196)
		(end 379.22073 -94.870524)
		(width 0.089408)
		(layer "In9.Cu")
		(net "IRQ_LVC3_WAKE_N")
	)
	(segment
		(start 379.136148 -92.42552)
		(end 379.136402 -92.425774)
		(width 0.089408)
		(layer "In9.Cu")
		(net "IRQ_LVC3_WAKE_N")
	)
	(segment
		(start 387.7056 -59.6138)
		(end 387.7056 -60.553854)
		(width 0.089408)
		(layer "In9.Cu")
		(net "IRQ_LVC3_WAKE_N")
	)
	(segment
		(start 397.411448 -61.412882)
		(end 397.002 -61.003434)
		(width 0.089408)
		(layer "In11.Cu")
		(net "IRQ_LVC3_WAKE_N")
	)
	(segment
		(start 396.594584 -59.50077)
		(end 396.520416 -59.50077)
		(width 0.089408)
		(layer "In11.Cu")
		(net "IRQ_LVC3_WAKE_N")
	)
	(segment
		(start 400.855688 -63.881)
		(end 398.38757 -61.412882)
		(width 0.089408)
		(layer "In11.Cu")
		(net "IRQ_LVC3_WAKE_N")
	)
	(segment
		(start 401.714462 -63.881)
		(end 400.855688 -63.881)
		(width 0.089408)
		(layer "In11.Cu")
		(net "IRQ_LVC3_WAKE_N")
	)
	(segment
		(start 397.002 -59.908186)
		(end 396.594584 -59.50077)
		(width 0.089408)
		(layer "In11.Cu")
		(net "IRQ_LVC3_WAKE_N")
	)
	(segment
		(start 398.38757 -61.412882)
		(end 397.411448 -61.412882)
		(width 0.089408)
		(layer "In11.Cu")
		(net "IRQ_LVC3_WAKE_N")
	)
	(segment
		(start 402.005546 -64.172084)
		(end 401.714462 -63.881)
		(width 0.089408)
		(layer "In11.Cu")
		(net "IRQ_LVC3_WAKE_N")
	)
	(segment
		(start 397.002 -61.003434)
		(end 397.002 -59.908186)
		(width 0.089408)
		(layer "In11.Cu")
		(net "IRQ_LVC3_WAKE_N")
	)
	(segment
		(start 384.03657 -78.902814)
		(end 384.03657 -78.140814)
		(width 0.10795)
		(layer "F.Cu")
		(net "H_CPU_MSMI_G_N")
	)
	(segment
		(start 384.03657 -78.140814)
		(end 384.661664 -78.140814)
		(width 0.10795)
		(layer "F.Cu")
		(net "H_CPU_MSMI_G_N")
	)
	(segment
		(start 384.661664 -78.140814)
		(end 385.064 -77.738478)
		(width 0.10795)
		(layer "F.Cu")
		(net "H_CPU_MSMI_G_N")
	)
	(segment
		(start 385.064 -77.738478)
		(end 386.326888 -77.738478)
		(width 0.10795)
		(layer "F.Cu")
		(net "H_CPU_MSMI_G_N")
	)
	(segment
		(start 382.905762 -76.915264)
		(end 382.898904 -76.908406)
		(width 0.10795)
		(layer "F.Cu")
		(net "H_CPU_ERR2_G_R_N")
	)
	(segment
		(start 384.422904 -76.915264)
		(end 383.660904 -76.915264)
		(width 0.10795)
		(layer "F.Cu")
		(net "H_CPU_ERR2_G_R_N")
	)
	(segment
		(start 383.660904 -76.915264)
		(end 382.905762 -76.915264)
		(width 0.10795)
		(layer "F.Cu")
		(net "H_CPU_ERR2_G_R_N")
	)
	(segment
		(start 382.898904 -76.908406)
		(end 382.131062 -76.908406)
		(width 0.10795)
		(layer "F.Cu")
		(net "H_CPU_ERR2_G_R_N")
	)
	(segment
		(start 371.754146 -58.27776)
		(end 372.373906 -57.658)
		(width 0.10795)
		(layer "B.Cu")
		(net "H_CPU_CATERR_G_N")
	)
	(segment
		(start 372.373906 -57.658)
		(end 372.8085 -57.658)
		(width 0.10795)
		(layer "B.Cu")
		(net "H_CPU_CATERR_G_N")
	)
	(segment
		(start 372.8085 -57.658)
		(end 372.8085 -56.769)
		(width 0.10795)
		(layer "B.Cu")
		(net "H_CPU_CATERR_G_N")
	)
	(segment
		(start 370.3955 -58.27776)
		(end 371.754146 -58.27776)
		(width 0.10795)
		(layer "B.Cu")
		(net "H_CPU_CATERR_G_N")
	)
	(segment
		(start 130.231388 -61.847984)
		(end 130.802888 -61.847984)
		(width 0.1016)
		(layer "F.Cu")
		(net "H_CPU1_THERMTRIP_G_N")
	)
	(via
		(at 370.725192 -56.319674)
		(size 0.508)
		(drill 0.254)
		(layers "F.Cu" "B.Cu")
		(net "H_CPU1_THERMTRIP_G_N")
	)
	(via
		(at 183.025288 -22.5298)
		(size 0.508)
		(drill 0.254)
		(layers "F.Cu" "B.Cu")
		(net "H_CPU1_THERMTRIP_G_N")
	)
	(via
		(at 321.2338 -39.3192)
		(size 0.508)
		(drill 0.254)
		(layers "F.Cu" "B.Cu")
		(net "H_CPU1_THERMTRIP_G_N")
	)
	(via
		(at 158.623 -61.087)
		(size 0.508)
		(drill 0.254)
		(layers "F.Cu" "B.Cu")
		(net "H_CPU1_THERMTRIP_G_N")
	)
	(via
		(at 130.802888 -61.847984)
		(size 0.508)
		(drill 0.254)
		(layers "F.Cu" "B.Cu")
		(net "H_CPU1_THERMTRIP_G_N")
	)
	(segment
		(start 372.2624 -55.8546)
		(end 372.2878 -55.88)
		(width 0.10795)
		(layer "B.Cu")
		(net "H_CPU1_THERMTRIP_G_N")
	)
	(segment
		(start 370.725192 -56.319674)
		(end 371.190266 -55.8546)
		(width 0.10795)
		(layer "B.Cu")
		(net "H_CPU1_THERMTRIP_G_N")
	)
	(segment
		(start 372.3132 -56.913272)
		(end 371.598952 -57.62752)
		(width 0.10795)
		(layer "B.Cu")
		(net "H_CPU1_THERMTRIP_G_N")
	)
	(segment
		(start 372.484904 -56.346598)
		(end 372.3132 -56.518302)
		(width 0.10795)
		(layer "B.Cu")
		(net "H_CPU1_THERMTRIP_G_N")
	)
	(segment
		(start 372.2878 -55.88)
		(end 372.8085 -55.88)
		(width 0.10795)
		(layer "B.Cu")
		(net "H_CPU1_THERMTRIP_G_N")
	)
	(segment
		(start 372.8085 -55.88)
		(end 372.8085 -56.233568)
		(width 0.10795)
		(layer "B.Cu")
		(net "H_CPU1_THERMTRIP_G_N")
	)
	(segment
		(start 372.69547 -56.346598)
		(end 372.484904 -56.346598)
		(width 0.10795)
		(layer "B.Cu")
		(net "H_CPU1_THERMTRIP_G_N")
	)
	(segment
		(start 372.8085 -56.233568)
		(end 372.69547 -56.346598)
		(width 0.10795)
		(layer "B.Cu")
		(net "H_CPU1_THERMTRIP_G_N")
	)
	(segment
		(start 371.190266 -55.8546)
		(end 372.2624 -55.8546)
		(width 0.10795)
		(layer "B.Cu")
		(net "H_CPU1_THERMTRIP_G_N")
	)
	(segment
		(start 372.3132 -56.518302)
		(end 372.3132 -56.913272)
		(width 0.10795)
		(layer "B.Cu")
		(net "H_CPU1_THERMTRIP_G_N")
	)
	(segment
		(start 371.598952 -57.62752)
		(end 370.3955 -57.62752)
		(width 0.10795)
		(layer "B.Cu")
		(net "H_CPU1_THERMTRIP_G_N")
	)
	(segment
		(start 135.396478 -60.780422)
		(end 135.7249 -60.452)
		(width 0.089408)
		(layer "In9.Cu")
		(net "H_CPU1_THERMTRIP_G_N")
	)
	(segment
		(start 151.3586 -60.6298)
		(end 158.1658 -60.6298)
		(width 0.089408)
		(layer "In9.Cu")
		(net "H_CPU1_THERMTRIP_G_N")
	)
	(segment
		(start 186.400186 -23.623016)
		(end 187.951618 -25.174448)
		(width 0.089408)
		(layer "In9.Cu")
		(net "H_CPU1_THERMTRIP_G_N")
	)
	(segment
		(start 304.995072 -30.382972)
		(end 313.54649 -38.93439)
		(width 0.089408)
		(layer "In9.Cu")
		(net "H_CPU1_THERMTRIP_G_N")
	)
	(segment
		(start 134.754874 -62.554104)
		(end 134.748524 -62.543436)
		(width 0.0889)
		(layer "In9.Cu")
		(net "H_CPU1_THERMTRIP_G_N")
	)
	(segment
		(start 139.044934 -58.5724)
		(end 139.1412 -58.476134)
		(width 0.0889)
		(layer "In9.Cu")
		(net "H_CPU1_THERMTRIP_G_N")
	)
	(segment
		(start 183.594248 -23.09876)
		(end 186.001914 -23.09876)
		(width 0.089408)
		(layer "In9.Cu")
		(net "H_CPU1_THERMTRIP_G_N")
	)
	(segment
		(start 134.854696 -60.96889)
		(end 135.396478 -60.780422)
		(width 0.0889)
		(layer "In9.Cu")
		(net "H_CPU1_THERMTRIP_G_N")
	)
	(segment
		(start 136.00176 -60.452)
		(end 136.6774 -59.77636)
		(width 0.089408)
		(layer "In9.Cu")
		(net "H_CPU1_THERMTRIP_G_N")
	)
	(segment
		(start 134.748524 -61.552836)
		(end 134.743698 -61.5442)
		(width 0.0889)
		(layer "In9.Cu")
		(net "H_CPU1_THERMTRIP_G_N")
	)
	(segment
		(start 263.25957 -28.178252)
		(end 265.46429 -30.382972)
		(width 0.089408)
		(layer "In9.Cu")
		(net "H_CPU1_THERMTRIP_G_N")
	)
	(segment
		(start 191.922146 -24.734266)
		(end 192.617344 -24.734266)
		(width 0.089408)
		(layer "In9.Cu")
		(net "H_CPU1_THERMTRIP_G_N")
	)
	(segment
		(start 244.036088 -25.423368)
		(end 245.098824 -25.423368)
		(width 0.089408)
		(layer "In9.Cu")
		(net "H_CPU1_THERMTRIP_G_N")
	)
	(segment
		(start 135.7249 -60.452)
		(end 136.00176 -60.452)
		(width 0.089408)
		(layer "In9.Cu")
		(net "H_CPU1_THERMTRIP_G_N")
	)
	(segment
		(start 130.802888 -61.847984)
		(end 131.826 -61.847984)
		(width 0.089408)
		(layer "In9.Cu")
		(net "H_CPU1_THERMTRIP_G_N")
	)
	(segment
		(start 143.7386 -58.3184)
		(end 144.571974 -57.485026)
		(width 0.089408)
		(layer "In9.Cu")
		(net "H_CPU1_THERMTRIP_G_N")
	)
	(segment
		(start 265.46429 -30.382972)
		(end 304.995072 -30.382972)
		(width 0.089408)
		(layer "In9.Cu")
		(net "H_CPU1_THERMTRIP_G_N")
	)
	(segment
		(start 131.826 -61.847984)
		(end 132.1054 -62.127384)
		(width 0.089408)
		(layer "In9.Cu")
		(net "H_CPU1_THERMTRIP_G_N")
	)
	(segment
		(start 245.391686 -25.71623)
		(end 259.444744 -25.71623)
		(width 0.089408)
		(layer "In9.Cu")
		(net "H_CPU1_THERMTRIP_G_N")
	)
	(segment
		(start 134.754874 -61.563504)
		(end 134.748524 -61.552836)
		(width 0.0889)
		(layer "In9.Cu")
		(net "H_CPU1_THERMTRIP_G_N")
	)
	(segment
		(start 134.225538 -63.429134)
		(end 134.258304 -63.429134)
		(width 0.0889)
		(layer "In9.Cu")
		(net "H_CPU1_THERMTRIP_G_N")
	)
	(segment
		(start 192.617344 -24.734266)
		(end 192.831974 -24.948896)
		(width 0.089408)
		(layer "In9.Cu")
		(net "H_CPU1_THERMTRIP_G_N")
	)
	(segment
		(start 132.7404 -64.3128)
		(end 133.128512 -63.924688)
		(width 0.0889)
		(layer "In9.Cu")
		(net "H_CPU1_THERMTRIP_G_N")
	)
	(segment
		(start 320.84899 -38.93439)
		(end 321.2338 -39.3192)
		(width 0.089408)
		(layer "In9.Cu")
		(net "H_CPU1_THERMTRIP_G_N")
	)
	(segment
		(start 187.951618 -25.174448)
		(end 191.481964 -25.174448)
		(width 0.089408)
		(layer "In9.Cu")
		(net "H_CPU1_THERMTRIP_G_N")
	)
	(segment
		(start 259.449062 -25.718008)
		(end 261.909306 -28.178252)
		(width 0.089408)
		(layer "In9.Cu")
		(net "H_CPU1_THERMTRIP_G_N")
	)
	(segment
		(start 243.561616 -24.948896)
		(end 244.036088 -25.423368)
		(width 0.089408)
		(layer "In9.Cu")
		(net "H_CPU1_THERMTRIP_G_N")
	)
	(segment
		(start 261.909306 -28.178252)
		(end 263.25957 -28.178252)
		(width 0.089408)
		(layer "In9.Cu")
		(net "H_CPU1_THERMTRIP_G_N")
	)
	(segment
		(start 140.231368 -57.981088)
		(end 140.26134 -57.981088)
		(width 0.0889)
		(layer "In9.Cu")
		(net "H_CPU1_THERMTRIP_G_N")
	)
	(segment
		(start 183.025288 -22.5298)
		(end 183.594248 -23.09876)
		(width 0.089408)
		(layer "In9.Cu")
		(net "H_CPU1_THERMTRIP_G_N")
	)
	(segment
		(start 142.5448 -58.3184)
		(end 143.7386 -58.3184)
		(width 0.089408)
		(layer "In9.Cu")
		(net "H_CPU1_THERMTRIP_G_N")
	)
	(segment
		(start 142.207488 -57.981088)
		(end 142.5448 -58.3184)
		(width 0.0889)
		(layer "In9.Cu")
		(net "H_CPU1_THERMTRIP_G_N")
	)
	(segment
		(start 192.831974 -24.948896)
		(end 243.561616 -24.948896)
		(width 0.089408)
		(layer "In9.Cu")
		(net "H_CPU1_THERMTRIP_G_N")
	)
	(segment
		(start 138.9634 -58.5724)
		(end 139.044934 -58.5724)
		(width 0.0889)
		(layer "In9.Cu")
		(net "H_CPU1_THERMTRIP_G_N")
	)
	(segment
		(start 259.444744 -25.71623)
		(end 259.449062 -25.718008)
		(width 0.089408)
		(layer "In9.Cu")
		(net "H_CPU1_THERMTRIP_G_N")
	)
	(segment
		(start 139.141454 -58.476388)
		(end 139.400788 -58.476388)
		(width 0.0889)
		(layer "In9.Cu")
		(net "H_CPU1_THERMTRIP_G_N")
	)
	(segment
		(start 191.481964 -25.174448)
		(end 191.922146 -24.734266)
		(width 0.089408)
		(layer "In9.Cu")
		(net "H_CPU1_THERMTRIP_G_N")
	)
	(segment
		(start 245.098824 -25.423368)
		(end 245.391686 -25.71623)
		(width 0.089408)
		(layer "In9.Cu")
		(net "H_CPU1_THERMTRIP_G_N")
	)
	(segment
		(start 141.948408 -57.981088)
		(end 142.207488 -57.981088)
		(width 0.0889)
		(layer "In9.Cu")
		(net "H_CPU1_THERMTRIP_G_N")
	)
	(segment
		(start 137.06602 -59.77636)
		(end 137.4775 -59.36488)
		(width 0.089408)
		(layer "In9.Cu")
		(net "H_CPU1_THERMTRIP_G_N")
	)
	(segment
		(start 134.748524 -62.543436)
		(end 134.743698 -62.5348)
		(width 0.0889)
		(layer "In9.Cu")
		(net "H_CPU1_THERMTRIP_G_N")
	)
	(segment
		(start 134.748524 -61.152786)
		(end 134.854696 -60.96889)
		(width 0.0889)
		(layer "In9.Cu")
		(net "H_CPU1_THERMTRIP_G_N")
	)
	(segment
		(start 133.128512 -63.924688)
		(end 133.395974 -63.924688)
		(width 0.0889)
		(layer "In9.Cu")
		(net "H_CPU1_THERMTRIP_G_N")
	)
	(segment
		(start 313.54649 -38.93439)
		(end 320.84899 -38.93439)
		(width 0.089408)
		(layer "In9.Cu")
		(net "H_CPU1_THERMTRIP_G_N")
	)
	(segment
		(start 186.400186 -23.497032)
		(end 186.400186 -23.623016)
		(width 0.089408)
		(layer "In9.Cu")
		(net "H_CPU1_THERMTRIP_G_N")
	)
	(segment
		(start 132.3848 -64.3128)
		(end 132.7404 -64.3128)
		(width 0.089408)
		(layer "In9.Cu")
		(net "H_CPU1_THERMTRIP_G_N")
	)
	(segment
		(start 158.1658 -60.6298)
		(end 158.623 -61.087)
		(width 0.089408)
		(layer "In9.Cu")
		(net "H_CPU1_THERMTRIP_G_N")
	)
	(segment
		(start 137.8585 -59.36488)
		(end 138.299952 -58.923428)
		(width 0.089408)
		(layer "In9.Cu")
		(net "H_CPU1_THERMTRIP_G_N")
	)
	(segment
		(start 137.4775 -59.36488)
		(end 137.8585 -59.36488)
		(width 0.089408)
		(layer "In9.Cu")
		(net "H_CPU1_THERMTRIP_G_N")
	)
	(segment
		(start 186.001914 -23.09876)
		(end 186.400186 -23.497032)
		(width 0.089408)
		(layer "In9.Cu")
		(net "H_CPU1_THERMTRIP_G_N")
	)
	(segment
		(start 132.1054 -64.0334)
		(end 132.3848 -64.3128)
		(width 0.089408)
		(layer "In9.Cu")
		(net "H_CPU1_THERMTRIP_G_N")
	)
	(segment
		(start 136.6774 -59.77636)
		(end 137.06602 -59.77636)
		(width 0.089408)
		(layer "In9.Cu")
		(net "H_CPU1_THERMTRIP_G_N")
	)
	(segment
		(start 132.1054 -62.127384)
		(end 132.1054 -64.0334)
		(width 0.089408)
		(layer "In9.Cu")
		(net "H_CPU1_THERMTRIP_G_N")
	)
	(segment
		(start 144.571974 -57.485026)
		(end 148.213826 -57.485026)
		(width 0.089408)
		(layer "In9.Cu")
		(net "H_CPU1_THERMTRIP_G_N")
	)
	(segment
		(start 148.213826 -57.485026)
		(end 151.3586 -60.6298)
		(width 0.089408)
		(layer "In9.Cu")
		(net "H_CPU1_THERMTRIP_G_N")
	)
	(segment
		(start 139.1412 -58.476134)
		(end 139.141454 -58.476388)
		(width 0.0889)
		(layer "In9.Cu")
		(net "H_CPU1_THERMTRIP_G_N")
	)
	(segment
		(start 138.299952 -58.923428)
		(end 138.612372 -58.923428)
		(width 0.089408)
		(layer "In9.Cu")
		(net "H_CPU1_THERMTRIP_G_N")
	)
	(segment
		(start 138.612372 -58.923428)
		(end 138.9634 -58.5724)
		(width 0.089408)
		(layer "In9.Cu")
		(net "H_CPU1_THERMTRIP_G_N")
	)
	(arc
		(start 133.395974 -63.924688)
		(mid 133.681398 -63.841221)
		(end 133.890004 -63.629286)
		(width 0.0889)
		(layer "In9.Cu")
		(net "H_CPU1_THERMTRIP_G_N")
	)
	(arc
		(start 134.748524 -62.143386)
		(mid 134.827746 -61.854268)
		(end 134.754874 -61.563504)
		(width 0.0889)
		(layer "In9.Cu")
		(net "H_CPU1_THERMTRIP_G_N")
	)
	(arc
		(start 134.743698 -62.5348)
		(mid 134.694943 -62.338448)
		(end 134.748524 -62.143386)
		(width 0.0889)
		(layer "In9.Cu")
		(net "H_CPU1_THERMTRIP_G_N")
	)
	(arc
		(start 134.258304 -63.429134)
		(mid 134.750694 -63.130201)
		(end 134.754874 -62.554104)
		(width 0.0889)
		(layer "In9.Cu")
		(net "H_CPU1_THERMTRIP_G_N")
	)
	(arc
		(start 140.593064 -58.180986)
		(mid 141.104874 -58.476525)
		(end 141.616684 -58.180986)
		(width 0.0889)
		(layer "In9.Cu")
		(net "H_CPU1_THERMTRIP_G_N")
	)
	(arc
		(start 141.616684 -58.180986)
		(mid 141.756763 -58.03825)
		(end 141.948408 -57.981088)
		(width 0.0889)
		(layer "In9.Cu")
		(net "H_CPU1_THERMTRIP_G_N")
	)
	(arc
		(start 140.26134 -57.981088)
		(mid 140.452982 -58.038254)
		(end 140.593064 -58.180986)
		(width 0.0889)
		(layer "In9.Cu")
		(net "H_CPU1_THERMTRIP_G_N")
	)
	(arc
		(start 134.743698 -61.5442)
		(mid 134.694943 -61.347848)
		(end 134.748524 -61.152786)
		(width 0.0889)
		(layer "In9.Cu")
		(net "H_CPU1_THERMTRIP_G_N")
	)
	(arc
		(start 139.400788 -58.476388)
		(mid 139.688933 -58.394069)
		(end 139.899644 -58.180986)
		(width 0.0889)
		(layer "In9.Cu")
		(net "H_CPU1_THERMTRIP_G_N")
	)
	(arc
		(start 133.890004 -63.629286)
		(mid 134.031687 -63.485482)
		(end 134.225538 -63.429134)
		(width 0.0889)
		(layer "In9.Cu")
		(net "H_CPU1_THERMTRIP_G_N")
	)
	(arc
		(start 139.899644 -58.180986)
		(mid 140.039723 -58.03825)
		(end 140.231368 -57.981088)
		(width 0.0889)
		(layer "In9.Cu")
		(net "H_CPU1_THERMTRIP_G_N")
	)
	(segment
		(start 182.692548 -22.86254)
		(end 182.692548 -29.803852)
		(width 0.089408)
		(layer "In11.Cu")
		(net "H_CPU1_THERMTRIP_G_N")
	)
	(segment
		(start 322.050918 -40.136318)
		(end 322.609464 -40.136318)
		(width 0.089408)
		(layer "In11.Cu")
		(net "H_CPU1_THERMTRIP_G_N")
	)
	(segment
		(start 323.469 -40.995854)
		(end 323.469 -41.5798)
		(width 0.089408)
		(layer "In11.Cu")
		(net "H_CPU1_THERMTRIP_G_N")
	)
	(segment
		(start 159.127444 -43.183556)
		(end 159.127444 -60.582556)
		(width 0.089408)
		(layer "In11.Cu")
		(net "H_CPU1_THERMTRIP_G_N")
	)
	(segment
		(start 367.80216 -53.396642)
		(end 370.725192 -56.319674)
		(width 0.089408)
		(layer "In11.Cu")
		(net "H_CPU1_THERMTRIP_G_N")
	)
	(segment
		(start 365.207042 -53.396642)
		(end 367.80216 -53.396642)
		(width 0.089408)
		(layer "In11.Cu")
		(net "H_CPU1_THERMTRIP_G_N")
	)
	(segment
		(start 159.6771 -42.6339)
		(end 159.127444 -43.183556)
		(width 0.089408)
		(layer "In11.Cu")
		(net "H_CPU1_THERMTRIP_G_N")
	)
	(segment
		(start 160.349946 -41.9608)
		(end 159.6771 -42.6339)
		(width 0.089408)
		(layer "In11.Cu")
		(net "H_CPU1_THERMTRIP_G_N")
	)
	(segment
		(start 159.127444 -60.582556)
		(end 158.623 -61.087)
		(width 0.089408)
		(layer "In11.Cu")
		(net "H_CPU1_THERMTRIP_G_N")
	)
	(segment
		(start 328.9554 -47.0662)
		(end 358.8766 -47.0662)
		(width 0.089408)
		(layer "In11.Cu")
		(net "H_CPU1_THERMTRIP_G_N")
	)
	(segment
		(start 170.5356 -41.9608)
		(end 160.349946 -41.9608)
		(width 0.089408)
		(layer "In11.Cu")
		(net "H_CPU1_THERMTRIP_G_N")
	)
	(segment
		(start 322.609464 -40.136318)
		(end 323.469 -40.995854)
		(width 0.089408)
		(layer "In11.Cu")
		(net "H_CPU1_THERMTRIP_G_N")
	)
	(segment
		(start 321.2338 -39.3192)
		(end 322.050918 -40.136318)
		(width 0.089408)
		(layer "In11.Cu")
		(net "H_CPU1_THERMTRIP_G_N")
	)
	(segment
		(start 358.8766 -47.0662)
		(end 365.207042 -53.396642)
		(width 0.089408)
		(layer "In11.Cu")
		(net "H_CPU1_THERMTRIP_G_N")
	)
	(segment
		(start 183.025288 -22.5298)
		(end 182.692548 -22.86254)
		(width 0.089408)
		(layer "In11.Cu")
		(net "H_CPU1_THERMTRIP_G_N")
	)
	(segment
		(start 323.469 -41.5798)
		(end 328.9554 -47.0662)
		(width 0.089408)
		(layer "In11.Cu")
		(net "H_CPU1_THERMTRIP_G_N")
	)
	(segment
		(start 182.692548 -29.803852)
		(end 170.5356 -41.9608)
		(width 0.089408)
		(layer "In11.Cu")
		(net "H_CPU1_THERMTRIP_G_N")
	)
	(segment
		(start 129.372868 -62.343538)
		(end 129.944368 -62.343538)
		(width 0.1016)
		(layer "F.Cu")
		(net "H_CPU1_PROCHOT_G_N")
	)
	(via
		(at 374.507506 -52.735734)
		(size 0.508)
		(drill 0.254)
		(layers "F.Cu" "B.Cu")
		(net "H_CPU1_PROCHOT_G_N")
	)
	(via
		(at 260.7818 -0.4318)
		(size 0.508)
		(drill 0.254)
		(layers "F.Cu" "B.Cu")
		(net "H_CPU1_PROCHOT_G_N")
	)
	(via
		(at 192.068704 1.0922)
		(size 0.508)
		(drill 0.254)
		(layers "F.Cu" "B.Cu")
		(net "H_CPU1_PROCHOT_G_N")
	)
	(via
		(at 370.562632 -47.675546)
		(size 0.508)
		(drill 0.254)
		(layers "F.Cu" "B.Cu")
		(net "H_CPU1_PROCHOT_G_N")
	)
	(via
		(at 374.113298 -51.941984)
		(size 0.6604)
		(drill 0.3302)
		(layers "F.Cu" "B.Cu")
		(net "H_CPU1_PROCHOT_G_N")
	)
	(via
		(at 330.6826 -31.5976)
		(size 0.508)
		(drill 0.254)
		(layers "F.Cu" "B.Cu")
		(net "H_CPU1_PROCHOT_G_N")
	)
	(via
		(at 129.944368 -62.343538)
		(size 0.508)
		(drill 0.254)
		(layers "F.Cu" "B.Cu")
		(net "H_CPU1_PROCHOT_G_N")
	)
	(segment
		(start 390.818624 -44.985432)
		(end 390.818624 -45.24629)
		(width 0.10795)
		(layer "B.Cu")
		(net "H_CPU1_PROCHOT_G_N")
	)
	(segment
		(start 372.9482 -46.8376)
		(end 372.9482 -47.854362)
		(width 0.10795)
		(layer "B.Cu")
		(net "H_CPU1_PROCHOT_G_N")
	)
	(segment
		(start 383.875026 -45.616876)
		(end 383.875026 -46.738794)
		(width 0.10795)
		(layer "B.Cu")
		(net "H_CPU1_PROCHOT_G_N")
	)
	(segment
		(start 380.111 -48.133)
		(end 379.5268 -48.7172)
		(width 0.10795)
		(layer "B.Cu")
		(net "H_CPU1_PROCHOT_G_N")
	)
	(segment
		(start 372.9482 -46.8376)
		(end 372.349268 -47.436532)
		(width 0.10795)
		(layer "B.Cu")
		(net "H_CPU1_PROCHOT_G_N")
	)
	(segment
		(start 391.573512 -44.900088)
		(end 390.903968 -44.900088)
		(width 0.10795)
		(layer "B.Cu")
		(net "H_CPU1_PROCHOT_G_N")
	)
	(segment
		(start 372.9482 -47.854362)
		(end 372.711472 -48.09109)
		(width 0.10795)
		(layer "B.Cu")
		(net "H_CPU1_PROCHOT_G_N")
	)
	(segment
		(start 130.15722 -65.359026)
		(end 130.369564 -65.146682)
		(width 0.10795)
		(layer "B.Cu")
		(net "H_CPU1_PROCHOT_G_N")
	)
	(segment
		(start 386.514594 -44.466002)
		(end 386.514594 -43.892216)
		(width 0.10795)
		(layer "B.Cu")
		(net "H_CPU1_PROCHOT_G_N")
	)
	(segment
		(start 130.369564 -62.768734)
		(end 129.944368 -62.343538)
		(width 0.10795)
		(layer "B.Cu")
		(net "H_CPU1_PROCHOT_G_N")
	)
	(segment
		(start 383.875026 -46.738794)
		(end 384.25501 -47.118778)
		(width 0.10795)
		(layer "B.Cu")
		(net "H_CPU1_PROCHOT_G_N")
	)
	(segment
		(start 386.514594 -43.892216)
		(end 386.316728 -43.69435)
		(width 0.10795)
		(layer "B.Cu")
		(net "H_CPU1_PROCHOT_G_N")
	)
	(segment
		(start 372.349268 -47.436532)
		(end 372.169436 -47.436532)
		(width 0.10795)
		(layer "B.Cu")
		(net "H_CPU1_PROCHOT_G_N")
	)
	(segment
		(start 390.732772 -45.332142)
		(end 387.380734 -45.332142)
		(width 0.10795)
		(layer "B.Cu")
		(net "H_CPU1_PROCHOT_G_N")
	)
	(segment
		(start 373.9896 -51.818286)
		(end 374.113298 -51.941984)
		(width 0.10795)
		(layer "B.Cu")
		(net "H_CPU1_PROCHOT_G_N")
	)
	(segment
		(start 374.63095 -49.54905)
		(end 373.9896 -50.1904)
		(width 0.10795)
		(layer "B.Cu")
		(net "H_CPU1_PROCHOT_G_N")
	)
	(segment
		(start 380.746 -48.006)
		(end 380.619 -48.133)
		(width 0.10795)
		(layer "B.Cu")
		(net "H_CPU1_PROCHOT_G_N")
	)
	(segment
		(start 374.113298 -51.941984)
		(end 374.507506 -52.336192)
		(width 0.10795)
		(layer "B.Cu")
		(net "H_CPU1_PROCHOT_G_N")
	)
	(segment
		(start 377.04395 -49.54905)
		(end 374.63095 -49.54905)
		(width 0.10795)
		(layer "B.Cu")
		(net "H_CPU1_PROCHOT_G_N")
	)
	(segment
		(start 385.125214 -43.69435)
		(end 384.84175 -43.977814)
		(width 0.10795)
		(layer "B.Cu")
		(net "H_CPU1_PROCHOT_G_N")
	)
	(segment
		(start 390.903968 -44.900088)
		(end 390.818624 -44.985432)
		(width 0.10795)
		(layer "B.Cu")
		(net "H_CPU1_PROCHOT_G_N")
	)
	(segment
		(start 381.52578 -47.38878)
		(end 380.746 -47.38878)
		(width 0.10795)
		(layer "B.Cu")
		(net "H_CPU1_PROCHOT_G_N")
	)
	(segment
		(start 383.996184 -47.80407)
		(end 381.94107 -47.80407)
		(width 0.10795)
		(layer "B.Cu")
		(net "H_CPU1_PROCHOT_G_N")
	)
	(segment
		(start 130.15722 -65.670938)
		(end 130.15722 -65.359026)
		(width 0.10795)
		(layer "B.Cu")
		(net "H_CPU1_PROCHOT_G_N")
	)
	(segment
		(start 380.619 -48.133)
		(end 380.111 -48.133)
		(width 0.10795)
		(layer "B.Cu")
		(net "H_CPU1_PROCHOT_G_N")
	)
	(segment
		(start 130.369564 -65.146682)
		(end 130.369564 -62.768734)
		(width 0.10795)
		(layer "B.Cu")
		(net "H_CPU1_PROCHOT_G_N")
	)
	(segment
		(start 386.316728 -43.69435)
		(end 385.125214 -43.69435)
		(width 0.10795)
		(layer "B.Cu")
		(net "H_CPU1_PROCHOT_G_N")
	)
	(segment
		(start 384.25501 -47.118778)
		(end 384.25501 -47.545244)
		(width 0.10795)
		(layer "B.Cu")
		(net "H_CPU1_PROCHOT_G_N")
	)
	(segment
		(start 387.380734 -45.332142)
		(end 386.514594 -44.466002)
		(width 0.10795)
		(layer "B.Cu")
		(net "H_CPU1_PROCHOT_G_N")
	)
	(segment
		(start 384.84175 -43.977814)
		(end 384.84175 -44.650152)
		(width 0.10795)
		(layer "B.Cu")
		(net "H_CPU1_PROCHOT_G_N")
	)
	(segment
		(start 370.562632 -47.675546)
		(end 370.685568 -47.798482)
		(width 0.10795)
		(layer "B.Cu")
		(net "H_CPU1_PROCHOT_G_N")
	)
	(segment
		(start 372.711472 -48.09109)
		(end 371.959886 -48.09109)
		(width 0.10795)
		(layer "B.Cu")
		(net "H_CPU1_PROCHOT_G_N")
	)
	(segment
		(start 379.5268 -48.7172)
		(end 377.8758 -48.7172)
		(width 0.10795)
		(layer "B.Cu")
		(net "H_CPU1_PROCHOT_G_N")
	)
	(segment
		(start 371.959886 -48.09109)
		(end 371.667278 -47.798482)
		(width 0.10795)
		(layer "B.Cu")
		(net "H_CPU1_PROCHOT_G_N")
	)
	(segment
		(start 384.25501 -47.545244)
		(end 383.996184 -47.80407)
		(width 0.10795)
		(layer "B.Cu")
		(net "H_CPU1_PROCHOT_G_N")
	)
	(segment
		(start 370.685568 -47.798482)
		(end 371.362986 -47.798482)
		(width 0.10795)
		(layer "B.Cu")
		(net "H_CPU1_PROCHOT_G_N")
	)
	(segment
		(start 377.8758 -48.7172)
		(end 377.04395 -49.54905)
		(width 0.10795)
		(layer "B.Cu")
		(net "H_CPU1_PROCHOT_G_N")
	)
	(segment
		(start 390.818624 -45.24629)
		(end 390.732772 -45.332142)
		(width 0.10795)
		(layer "B.Cu")
		(net "H_CPU1_PROCHOT_G_N")
	)
	(segment
		(start 381.94107 -47.80407)
		(end 381.52578 -47.38878)
		(width 0.10795)
		(layer "B.Cu")
		(net "H_CPU1_PROCHOT_G_N")
	)
	(segment
		(start 380.746 -47.38878)
		(end 380.746 -48.006)
		(width 0.10795)
		(layer "B.Cu")
		(net "H_CPU1_PROCHOT_G_N")
	)
	(segment
		(start 374.507506 -52.336192)
		(end 374.507506 -52.735734)
		(width 0.10795)
		(layer "B.Cu")
		(net "H_CPU1_PROCHOT_G_N")
	)
	(segment
		(start 384.84175 -44.650152)
		(end 383.875026 -45.616876)
		(width 0.10795)
		(layer "B.Cu")
		(net "H_CPU1_PROCHOT_G_N")
	)
	(segment
		(start 373.9896 -50.1904)
		(end 373.9896 -51.818286)
		(width 0.10795)
		(layer "B.Cu")
		(net "H_CPU1_PROCHOT_G_N")
	)
	(segment
		(start 371.667278 -47.798482)
		(end 371.362986 -47.798482)
		(width 0.10795)
		(layer "B.Cu")
		(net "H_CPU1_PROCHOT_G_N")
	)
	(segment
		(start 258.997196 2.590038)
		(end 258.49326 3.093974)
		(width 0.089408)
		(layer "In2.Cu")
		(net "H_CPU1_PROCHOT_G_N")
	)
	(segment
		(start 193.92392 3.09372)
		(end 192.068704 1.238504)
		(width 0.089408)
		(layer "In2.Cu")
		(net "H_CPU1_PROCHOT_G_N")
	)
	(segment
		(start 260.67766 -0.32766)
		(end 260.67766 0.6604)
		(width 0.089408)
		(layer "In2.Cu")
		(net "H_CPU1_PROCHOT_G_N")
	)
	(segment
		(start 258.49326 3.093974)
		(end 193.924682 3.093974)
		(width 0.089408)
		(layer "In2.Cu")
		(net "H_CPU1_PROCHOT_G_N")
	)
	(segment
		(start 192.068704 1.238504)
		(end 192.068704 1.0922)
		(width 0.089408)
		(layer "In2.Cu")
		(net "H_CPU1_PROCHOT_G_N")
	)
	(segment
		(start 193.924682 3.093974)
		(end 193.92392 3.09372)
		(width 0.089408)
		(layer "In2.Cu")
		(net "H_CPU1_PROCHOT_G_N")
	)
	(segment
		(start 260.67766 0.6604)
		(end 258.997196 2.340864)
		(width 0.089408)
		(layer "In2.Cu")
		(net "H_CPU1_PROCHOT_G_N")
	)
	(segment
		(start 258.997196 2.340864)
		(end 258.997196 2.590038)
		(width 0.089408)
		(layer "In2.Cu")
		(net "H_CPU1_PROCHOT_G_N")
	)
	(segment
		(start 260.7818 -0.4318)
		(end 260.67766 -0.32766)
		(width 0.089408)
		(layer "In2.Cu")
		(net "H_CPU1_PROCHOT_G_N")
	)
	(segment
		(start 323.811392 -27.281886)
		(end 324.073266 -27.914092)
		(width 0.089408)
		(layer "In4.Cu")
		(net "H_CPU1_PROCHOT_G_N")
	)
	(segment
		(start 320.206624 -1.563624)
		(end 320.9036 -2.2606)
		(width 0.089408)
		(layer "In4.Cu")
		(net "H_CPU1_PROCHOT_G_N")
	)
	(segment
		(start 260.7818 -0.4318)
		(end 262.2296 -1.8796)
		(width 0.089408)
		(layer "In4.Cu")
		(net "H_CPU1_PROCHOT_G_N")
	)
	(segment
		(start 262.859012 -5.041392)
		(end 264.003536 -5.041392)
		(width 0.089408)
		(layer "In4.Cu")
		(net "H_CPU1_PROCHOT_G_N")
	)
	(segment
		(start 329.665584 -30.1752)
		(end 329.665584 -30.875224)
		(width 0.089408)
		(layer "In4.Cu")
		(net "H_CPU1_PROCHOT_G_N")
	)
	(segment
		(start 262.2296 -1.8796)
		(end 262.2296 -4.41198)
		(width 0.089408)
		(layer "In4.Cu")
		(net "H_CPU1_PROCHOT_G_N")
	)
	(segment
		(start 321.183 -24.0538)
		(end 322.834 -24.0538)
		(width 0.089408)
		(layer "In4.Cu")
		(net "H_CPU1_PROCHOT_G_N")
	)
	(segment
		(start 266.554966 -1.6002)
		(end 266.591542 -1.563624)
		(width 0.089408)
		(layer "In4.Cu")
		(net "H_CPU1_PROCHOT_G_N")
	)
	(segment
		(start 265.9634 -1.6002)
		(end 266.554966 -1.6002)
		(width 0.089408)
		(layer "In4.Cu")
		(net "H_CPU1_PROCHOT_G_N")
	)
	(segment
		(start 264.7696 -4.275328)
		(end 264.7696 -2.794)
		(width 0.089408)
		(layer "In4.Cu")
		(net "H_CPU1_PROCHOT_G_N")
	)
	(segment
		(start 323.811392 -25.716992)
		(end 323.811392 -27.281886)
		(width 0.089408)
		(layer "In4.Cu")
		(net "H_CPU1_PROCHOT_G_N")
	)
	(segment
		(start 323.4436 -24.6634)
		(end 323.4436 -25.3492)
		(width 0.089408)
		(layer "In4.Cu")
		(net "H_CPU1_PROCHOT_G_N")
	)
	(segment
		(start 320.9036 -2.2606)
		(end 320.9036 -23.7744)
		(width 0.089408)
		(layer "In4.Cu")
		(net "H_CPU1_PROCHOT_G_N")
	)
	(segment
		(start 323.4436 -25.3492)
		(end 323.811392 -25.716992)
		(width 0.089408)
		(layer "In4.Cu")
		(net "H_CPU1_PROCHOT_G_N")
	)
	(segment
		(start 264.7696 -2.794)
		(end 265.9634 -1.6002)
		(width 0.089408)
		(layer "In4.Cu")
		(net "H_CPU1_PROCHOT_G_N")
	)
	(segment
		(start 324.420738 -28.261564)
		(end 325.422768 -28.6766)
		(width 0.089408)
		(layer "In4.Cu")
		(net "H_CPU1_PROCHOT_G_N")
	)
	(segment
		(start 324.073266 -27.914092)
		(end 324.420738 -28.261564)
		(width 0.089408)
		(layer "In4.Cu")
		(net "H_CPU1_PROCHOT_G_N")
	)
	(segment
		(start 328.166984 -28.6766)
		(end 329.665584 -30.1752)
		(width 0.089408)
		(layer "In4.Cu")
		(net "H_CPU1_PROCHOT_G_N")
	)
	(segment
		(start 325.422768 -28.6766)
		(end 328.166984 -28.6766)
		(width 0.089408)
		(layer "In4.Cu")
		(net "H_CPU1_PROCHOT_G_N")
	)
	(segment
		(start 266.591542 -1.563624)
		(end 320.206624 -1.563624)
		(width 0.089408)
		(layer "In4.Cu")
		(net "H_CPU1_PROCHOT_G_N")
	)
	(segment
		(start 322.834 -24.0538)
		(end 323.4436 -24.6634)
		(width 0.089408)
		(layer "In4.Cu")
		(net "H_CPU1_PROCHOT_G_N")
	)
	(segment
		(start 330.38796 -31.5976)
		(end 330.6826 -31.5976)
		(width 0.089408)
		(layer "In4.Cu")
		(net "H_CPU1_PROCHOT_G_N")
	)
	(segment
		(start 329.665584 -30.875224)
		(end 330.38796 -31.5976)
		(width 0.089408)
		(layer "In4.Cu")
		(net "H_CPU1_PROCHOT_G_N")
	)
	(segment
		(start 264.003536 -5.041392)
		(end 264.7696 -4.275328)
		(width 0.089408)
		(layer "In4.Cu")
		(net "H_CPU1_PROCHOT_G_N")
	)
	(segment
		(start 320.9036 -23.7744)
		(end 321.183 -24.0538)
		(width 0.089408)
		(layer "In4.Cu")
		(net "H_CPU1_PROCHOT_G_N")
	)
	(segment
		(start 262.2296 -4.41198)
		(end 262.859012 -5.041392)
		(width 0.089408)
		(layer "In4.Cu")
		(net "H_CPU1_PROCHOT_G_N")
	)
	(segment
		(start 191.204088 -13.211556)
		(end 189.472824 -14.94282)
		(width 0.089408)
		(layer "In11.Cu")
		(net "H_CPU1_PROCHOT_G_N")
	)
	(segment
		(start 171.920154 -21.6916)
		(end 170.535092 -23.076662)
		(width 0.089408)
		(layer "In11.Cu")
		(net "H_CPU1_PROCHOT_G_N")
	)
	(segment
		(start 334.558386 -36.906454)
		(end 335.073244 -37.421312)
		(width 0.089408)
		(layer "In11.Cu")
		(net "H_CPU1_PROCHOT_G_N")
	)
	(segment
		(start 130.817874 -55.313834)
		(end 130.785108 -55.313834)
		(width 0.0889)
		(layer "In11.Cu")
		(net "H_CPU1_PROCHOT_G_N")
	)
	(segment
		(start 130.295904 -58.5724)
		(end 130.291078 -58.581036)
		(width 0.0889)
		(layer "In11.Cu")
		(net "H_CPU1_PROCHOT_G_N")
	)
	(segment
		(start 374.507506 -52.735734)
		(end 373.788686 -52.016914)
		(width 0.089408)
		(layer "In11.Cu")
		(net "H_CPU1_PROCHOT_G_N")
	)
	(segment
		(start 191.306704 -10.579862)
		(end 191.204088 -10.682478)
		(width 0.089408)
		(layer "In11.Cu")
		(net "H_CPU1_PROCHOT_G_N")
	)
	(segment
		(start 170.535092 -23.076662)
		(end 161.124138 -26.9748)
		(width 0.089408)
		(layer "In11.Cu")
		(net "H_CPU1_PROCHOT_G_N")
	)
	(segment
		(start 332.95971 -33.199832)
		(end 332.95971 -35.01771)
		(width 0.089408)
		(layer "In11.Cu")
		(net "H_CPU1_PROCHOT_G_N")
	)
	(segment
		(start 357.355902 -36.72967)
		(end 365.635032 -45.0088)
		(width 0.089408)
		(layer "In11.Cu")
		(net "H_CPU1_PROCHOT_G_N")
	)
	(segment
		(start 370.561362 -47.676816)
		(end 370.562632 -47.675546)
		(width 0.089408)
		(layer "In11.Cu")
		(net "H_CPU1_PROCHOT_G_N")
	)
	(segment
		(start 132.007864 -54.618636)
		(end 132.004562 -54.624478)
		(width 0.0889)
		(layer "In11.Cu")
		(net "H_CPU1_PROCHOT_G_N")
	)
	(segment
		(start 192.068704 1.0922)
		(end 192.068704 0.652018)
		(width 0.0889)
		(layer "In11.Cu")
		(net "H_CPU1_PROCHOT_G_N")
	)
	(segment
		(start 191.306704 -8.609076)
		(end 191.306704 -10.579862)
		(width 0.089408)
		(layer "In11.Cu")
		(net "H_CPU1_PROCHOT_G_N")
	)
	(segment
		(start 130.291078 -60.562236)
		(end 130.284728 -60.572904)
		(width 0.0889)
		(layer "In11.Cu")
		(net "H_CPU1_PROCHOT_G_N")
	)
	(segment
		(start 191.033146 -2.235454)
		(end 191.033146 -6.068568)
		(width 0.089408)
		(layer "In11.Cu")
		(net "H_CPU1_PROCHOT_G_N")
	)
	(segment
		(start 130.291078 -57.590436)
		(end 130.284728 -57.601104)
		(width 0.0889)
		(layer "In11.Cu")
		(net "H_CPU1_PROCHOT_G_N")
	)
	(segment
		(start 191.204088 -10.682478)
		(end 191.204088 -13.211556)
		(width 0.089408)
		(layer "In11.Cu")
		(net "H_CPU1_PROCHOT_G_N")
	)
	(segment
		(start 131.661408 -54.818788)
		(end 131.639818 -54.818788)
		(width 0.0889)
		(layer "In11.Cu")
		(net "H_CPU1_PROCHOT_G_N")
	)
	(segment
		(start 332.95971 -35.01771)
		(end 334.558386 -36.616386)
		(width 0.089408)
		(layer "In11.Cu")
		(net "H_CPU1_PROCHOT_G_N")
	)
	(segment
		(start 370.54409 -47.657004)
		(end 370.562632 -47.675546)
		(width 0.089408)
		(layer "In11.Cu")
		(net "H_CPU1_PROCHOT_G_N")
	)
	(segment
		(start 130.284728 -59.160918)
		(end 130.291078 -59.171586)
		(width 0.0889)
		(layer "In11.Cu")
		(net "H_CPU1_PROCHOT_G_N")
	)
	(segment
		(start 133.38937 -53.827934)
		(end 133.36524 -53.827934)
		(width 0.0889)
		(layer "In11.Cu")
		(net "H_CPU1_PROCHOT_G_N")
	)
	(segment
		(start 370.561362 -47.889922)
		(end 370.561362 -47.676816)
		(width 0.089408)
		(layer "In11.Cu")
		(net "H_CPU1_PROCHOT_G_N")
	)
	(segment
		(start 191.4906 -6.526022)
		(end 191.4906 -8.42518)
		(width 0.089408)
		(layer "In11.Cu")
		(net "H_CPU1_PROCHOT_G_N")
	)
	(segment
		(start 352.862642 -36.72967)
		(end 357.355902 -36.72967)
		(width 0.089408)
		(layer "In11.Cu")
		(net "H_CPU1_PROCHOT_G_N")
	)
	(segment
		(start 138.499342 -52.854606)
		(end 138.017504 -53.132736)
		(width 0.0889)
		(layer "In11.Cu")
		(net "H_CPU1_PROCHOT_G_N")
	)
	(segment
		(start 189.472824 -14.94282)
		(end 185.421778 -14.94282)
		(width 0.089408)
		(layer "In11.Cu")
		(net "H_CPU1_PROCHOT_G_N")
	)
	(segment
		(start 161.124138 -26.9748)
		(end 158.237174 -29.861764)
		(width 0.089408)
		(layer "In11.Cu")
		(net "H_CPU1_PROCHOT_G_N")
	)
	(segment
		(start 158.237174 -29.861764)
		(end 155.448762 -36.593272)
		(width 0.089408)
		(layer "In11.Cu")
		(net "H_CPU1_PROCHOT_G_N")
	)
	(segment
		(start 184.639712 -18.04797)
		(end 183.434482 -19.2532)
		(width 0.089408)
		(layer "In11.Cu")
		(net "H_CPU1_PROCHOT_G_N")
	)
	(segment
		(start 172.305726 -21.6916)
		(end 171.920154 -21.6916)
		(width 0.089408)
		(layer "In11.Cu")
		(net "H_CPU1_PROCHOT_G_N")
	)
	(segment
		(start 335.073244 -37.421312)
		(end 352.171 -37.421312)
		(width 0.089408)
		(layer "In11.Cu")
		(net "H_CPU1_PROCHOT_G_N")
	)
	(segment
		(start 130.291078 -56.599836)
		(end 130.284728 -56.610504)
		(width 0.0889)
		(layer "In11.Cu")
		(net "H_CPU1_PROCHOT_G_N")
	)
	(segment
		(start 134.258304 -53.332634)
		(end 134.215124 -53.332634)
		(width 0.0889)
		(layer "In11.Cu")
		(net "H_CPU1_PROCHOT_G_N")
	)
	(segment
		(start 174.744126 -19.2532)
		(end 172.305726 -21.6916)
		(width 0.089408)
		(layer "In11.Cu")
		(net "H_CPU1_PROCHOT_G_N")
	)
	(segment
		(start 130.291078 -61.552836)
		(end 130.284728 -61.563504)
		(width 0.0889)
		(layer "In11.Cu")
		(net "H_CPU1_PROCHOT_G_N")
	)
	(segment
		(start 369.398804 -47.657004)
		(end 370.54409 -47.657004)
		(width 0.089408)
		(layer "In11.Cu")
		(net "H_CPU1_PROCHOT_G_N")
	)
	(segment
		(start 130.295904 -56.5912)
		(end 130.291078 -56.599836)
		(width 0.0889)
		(layer "In11.Cu")
		(net "H_CPU1_PROCHOT_G_N")
	)
	(segment
		(start 132.53466 -54.323234)
		(end 132.501894 -54.323234)
		(width 0.0889)
		(layer "In11.Cu")
		(net "H_CPU1_PROCHOT_G_N")
	)
	(segment
		(start 192.068704 -1.199896)
		(end 191.496696 -1.771904)
		(width 0.0889)
		(layer "In11.Cu")
		(net "H_CPU1_PROCHOT_G_N")
	)
	(segment
		(start 135.975344 -53.332634)
		(end 135.932164 -53.332634)
		(width 0.0889)
		(layer "In11.Cu")
		(net "H_CPU1_PROCHOT_G_N")
	)
	(segment
		(start 373.788686 -51.117246)
		(end 370.561362 -47.889922)
		(width 0.089408)
		(layer "In11.Cu")
		(net "H_CPU1_PROCHOT_G_N")
	)
	(segment
		(start 352.171 -37.421312)
		(end 352.862642 -36.72967)
		(width 0.089408)
		(layer "In11.Cu")
		(net "H_CPU1_PROCHOT_G_N")
	)
	(segment
		(start 185.421778 -14.94282)
		(end 184.639712 -15.724886)
		(width 0.089408)
		(layer "In11.Cu")
		(net "H_CPU1_PROCHOT_G_N")
	)
	(segment
		(start 139.187428 -52.854606)
		(end 138.499342 -52.854606)
		(width 0.089408)
		(layer "In11.Cu")
		(net "H_CPU1_PROCHOT_G_N")
	)
	(segment
		(start 191.4906 -8.42518)
		(end 191.306704 -8.609076)
		(width 0.089408)
		(layer "In11.Cu")
		(net "H_CPU1_PROCHOT_G_N")
	)
	(segment
		(start 191.033146 -6.068568)
		(end 191.4906 -6.526022)
		(width 0.089408)
		(layer "In11.Cu")
		(net "H_CPU1_PROCHOT_G_N")
	)
	(segment
		(start 130.295904 -61.5442)
		(end 130.291078 -61.552836)
		(width 0.0889)
		(layer "In11.Cu")
		(net "H_CPU1_PROCHOT_G_N")
	)
	(segment
		(start 373.788686 -52.016914)
		(end 373.788686 -51.117246)
		(width 0.089408)
		(layer "In11.Cu")
		(net "H_CPU1_PROCHOT_G_N")
	)
	(segment
		(start 130.295904 -57.5818)
		(end 130.291078 -57.590436)
		(width 0.0889)
		(layer "In11.Cu")
		(net "H_CPU1_PROCHOT_G_N")
	)
	(segment
		(start 183.434482 -19.2532)
		(end 174.744126 -19.2532)
		(width 0.089408)
		(layer "In11.Cu")
		(net "H_CPU1_PROCHOT_G_N")
	)
	(segment
		(start 192.068704 0.652018)
		(end 192.068704 -1.199896)
		(width 0.089408)
		(layer "In11.Cu")
		(net "H_CPU1_PROCHOT_G_N")
	)
	(segment
		(start 184.639712 -15.724886)
		(end 184.639712 -18.04797)
		(width 0.089408)
		(layer "In11.Cu")
		(net "H_CPU1_PROCHOT_G_N")
	)
	(segment
		(start 366.7506 -45.0088)
		(end 369.398804 -47.657004)
		(width 0.089408)
		(layer "In11.Cu")
		(net "H_CPU1_PROCHOT_G_N")
	)
	(segment
		(start 365.635032 -45.0088)
		(end 366.7506 -45.0088)
		(width 0.089408)
		(layer "In11.Cu")
		(net "H_CPU1_PROCHOT_G_N")
	)
	(segment
		(start 191.496696 -1.771904)
		(end 191.033146 -2.235454)
		(width 0.089408)
		(layer "In11.Cu")
		(net "H_CPU1_PROCHOT_G_N")
	)
	(segment
		(start 137.688828 -53.332634)
		(end 137.649204 -53.332634)
		(width 0.0889)
		(layer "In11.Cu")
		(net "H_CPU1_PROCHOT_G_N")
	)
	(segment
		(start 331.357478 -31.5976)
		(end 332.95971 -33.199832)
		(width 0.089408)
		(layer "In11.Cu")
		(net "H_CPU1_PROCHOT_G_N")
	)
	(segment
		(start 130.295904 -60.5536)
		(end 130.291078 -60.562236)
		(width 0.0889)
		(layer "In11.Cu")
		(net "H_CPU1_PROCHOT_G_N")
	)
	(segment
		(start 334.558386 -36.616386)
		(end 334.558386 -36.906454)
		(width 0.089408)
		(layer "In11.Cu")
		(net "H_CPU1_PROCHOT_G_N")
	)
	(segment
		(start 155.448762 -36.593272)
		(end 139.187428 -52.854606)
		(width 0.089408)
		(layer "In11.Cu")
		(net "H_CPU1_PROCHOT_G_N")
	)
	(segment
		(start 330.6826 -31.5976)
		(end 331.357478 -31.5976)
		(width 0.089408)
		(layer "In11.Cu")
		(net "H_CPU1_PROCHOT_G_N")
	)
	(arc
		(start 130.291078 -59.171586)
		(mid 130.344577 -59.371484)
		(end 130.291078 -59.571382)
		(width 0.0889)
		(layer "In11.Cu")
		(net "H_CPU1_PROCHOT_G_N")
	)
	(arc
		(start 135.441944 -53.627782)
		(mid 135.095234 -53.828093)
		(end 134.748524 -53.627782)
		(width 0.0889)
		(layer "In11.Cu")
		(net "H_CPU1_PROCHOT_G_N")
	)
	(arc
		(start 132.501894 -54.323234)
		(mid 132.21647 -54.406701)
		(end 132.007864 -54.618636)
		(width 0.0889)
		(layer "In11.Cu")
		(net "H_CPU1_PROCHOT_G_N")
	)
	(arc
		(start 137.649204 -53.332634)
		(mid 137.365987 -53.416915)
		(end 137.158984 -53.627782)
		(width 0.0889)
		(layer "In11.Cu")
		(net "H_CPU1_PROCHOT_G_N")
	)
	(arc
		(start 138.017504 -53.132736)
		(mid 137.87876 -53.274769)
		(end 137.688828 -53.332634)
		(width 0.0889)
		(layer "In11.Cu")
		(net "H_CPU1_PROCHOT_G_N")
	)
	(arc
		(start 130.291078 -57.190386)
		(mid 130.344548 -57.385449)
		(end 130.295904 -57.5818)
		(width 0.0889)
		(layer "In11.Cu")
		(net "H_CPU1_PROCHOT_G_N")
	)
	(arc
		(start 130.291078 -58.581036)
		(mid 130.211856 -58.870154)
		(end 130.284728 -59.160918)
		(width 0.0889)
		(layer "In11.Cu")
		(net "H_CPU1_PROCHOT_G_N")
	)
	(arc
		(start 137.158984 -53.627782)
		(mid 136.812274 -53.828093)
		(end 136.465564 -53.627782)
		(width 0.0889)
		(layer "In11.Cu")
		(net "H_CPU1_PROCHOT_G_N")
	)
	(arc
		(start 130.291078 -61.152786)
		(mid 130.344548 -61.347849)
		(end 130.295904 -61.5442)
		(width 0.0889)
		(layer "In11.Cu")
		(net "H_CPU1_PROCHOT_G_N")
	)
	(arc
		(start 133.724904 -53.627782)
		(mid 133.583221 -53.771586)
		(end 133.38937 -53.827934)
		(width 0.0889)
		(layer "In11.Cu")
		(net "H_CPU1_PROCHOT_G_N")
	)
	(arc
		(start 134.215124 -53.332634)
		(mid 133.931907 -53.416915)
		(end 133.724904 -53.627782)
		(width 0.0889)
		(layer "In11.Cu")
		(net "H_CPU1_PROCHOT_G_N")
	)
	(arc
		(start 135.932164 -53.332634)
		(mid 135.648947 -53.416915)
		(end 135.441944 -53.627782)
		(width 0.0889)
		(layer "In11.Cu")
		(net "H_CPU1_PROCHOT_G_N")
	)
	(arc
		(start 131.639818 -54.818788)
		(mid 131.356601 -54.903069)
		(end 131.149598 -55.113936)
		(width 0.0889)
		(layer "In11.Cu")
		(net "H_CPU1_PROCHOT_G_N")
	)
	(arc
		(start 130.785108 -55.313834)
		(mid 130.286857 -55.616674)
		(end 130.291078 -56.199786)
		(width 0.0889)
		(layer "In11.Cu")
		(net "H_CPU1_PROCHOT_G_N")
	)
	(arc
		(start 134.748524 -53.627782)
		(mid 134.54152 -53.416918)
		(end 134.258304 -53.332634)
		(width 0.0889)
		(layer "In11.Cu")
		(net "H_CPU1_PROCHOT_G_N")
	)
	(arc
		(start 130.291078 -59.571382)
		(mid 130.211947 -59.866784)
		(end 130.291078 -60.162186)
		(width 0.0889)
		(layer "In11.Cu")
		(net "H_CPU1_PROCHOT_G_N")
	)
	(arc
		(start 130.284728 -61.563504)
		(mid 130.090049 -61.942831)
		(end 129.944368 -62.343538)
		(width 0.0889)
		(layer "In11.Cu")
		(net "H_CPU1_PROCHOT_G_N")
	)
	(arc
		(start 136.465564 -53.627782)
		(mid 136.25856 -53.416918)
		(end 135.975344 -53.332634)
		(width 0.0889)
		(layer "In11.Cu")
		(net "H_CPU1_PROCHOT_G_N")
	)
	(arc
		(start 133.36524 -53.827934)
		(mid 133.077095 -53.910253)
		(end 132.866384 -54.123336)
		(width 0.0889)
		(layer "In11.Cu")
		(net "H_CPU1_PROCHOT_G_N")
	)
	(arc
		(start 132.866384 -54.123336)
		(mid 132.726305 -54.266072)
		(end 132.53466 -54.323234)
		(width 0.0889)
		(layer "In11.Cu")
		(net "H_CPU1_PROCHOT_G_N")
	)
	(arc
		(start 130.291078 -56.199786)
		(mid 130.344548 -56.394849)
		(end 130.295904 -56.5912)
		(width 0.0889)
		(layer "In11.Cu")
		(net "H_CPU1_PROCHOT_G_N")
	)
	(arc
		(start 130.284728 -60.572904)
		(mid 130.21193 -60.863667)
		(end 130.291078 -61.152786)
		(width 0.0889)
		(layer "In11.Cu")
		(net "H_CPU1_PROCHOT_G_N")
	)
	(arc
		(start 130.291078 -60.162186)
		(mid 130.344548 -60.357249)
		(end 130.295904 -60.5536)
		(width 0.0889)
		(layer "In11.Cu")
		(net "H_CPU1_PROCHOT_G_N")
	)
	(arc
		(start 132.004562 -54.624478)
		(mid 131.858596 -54.766877)
		(end 131.661408 -54.818788)
		(width 0.0889)
		(layer "In11.Cu")
		(net "H_CPU1_PROCHOT_G_N")
	)
	(arc
		(start 130.291078 -58.180986)
		(mid 130.344548 -58.376049)
		(end 130.295904 -58.5724)
		(width 0.0889)
		(layer "In11.Cu")
		(net "H_CPU1_PROCHOT_G_N")
	)
	(arc
		(start 130.284728 -57.601104)
		(mid 130.21193 -57.891867)
		(end 130.291078 -58.180986)
		(width 0.0889)
		(layer "In11.Cu")
		(net "H_CPU1_PROCHOT_G_N")
	)
	(arc
		(start 130.284728 -56.610504)
		(mid 130.21193 -56.901267)
		(end 130.291078 -57.190386)
		(width 0.0889)
		(layer "In11.Cu")
		(net "H_CPU1_PROCHOT_G_N")
	)
	(arc
		(start 131.149598 -55.113936)
		(mid 131.009519 -55.256672)
		(end 130.817874 -55.313834)
		(width 0.0889)
		(layer "In11.Cu")
		(net "H_CPU1_PROCHOT_G_N")
	)
	(segment
		(start 383.14757 -78.902814)
		(end 383.14757 -79.512414)
		(width 0.10795)
		(layer "F.Cu")
		(net "H_CPU1_MSMI_G_N")
	)
	(segment
		(start 125.938788 -67.296538)
		(end 126.510288 -67.296538)
		(width 0.1016)
		(layer "F.Cu")
		(net "H_CPU1_MSMI_G_N")
	)
	(via
		(at 331.9526 -33.462976)
		(size 0.508)
		(drill 0.254)
		(layers "F.Cu" "B.Cu")
		(net "H_CPU1_MSMI_G_N")
	)
	(via
		(at 126.510288 -67.296538)
		(size 0.508)
		(drill 0.254)
		(layers "F.Cu" "B.Cu")
		(net "H_CPU1_MSMI_G_N")
	)
	(via
		(at 383.97434 -79.01178)
		(size 0.6604)
		(drill 0.3302)
		(layers "F.Cu" "B.Cu")
		(net "H_CPU1_MSMI_G_N")
	)
	(via
		(at 383.14757 -79.512414)
		(size 0.508)
		(drill 0.254)
		(layers "F.Cu" "B.Cu")
		(net "H_CPU1_MSMI_G_N")
	)
	(segment
		(start 126.551944 -67.338194)
		(end 127.592582 -67.338194)
		(width 0.10795)
		(layer "B.Cu")
		(net "H_CPU1_MSMI_G_N")
	)
	(segment
		(start 383.97434 -79.01178)
		(end 383.473706 -79.512414)
		(width 0.10795)
		(layer "B.Cu")
		(net "H_CPU1_MSMI_G_N")
	)
	(segment
		(start 127.592582 -67.338194)
		(end 128.042416 -66.88836)
		(width 0.10795)
		(layer "B.Cu")
		(net "H_CPU1_MSMI_G_N")
	)
	(segment
		(start 128.747012 -67.181984)
		(end 128.8796 -67.181984)
		(width 0.10795)
		(layer "B.Cu")
		(net "H_CPU1_MSMI_G_N")
	)
	(segment
		(start 126.510288 -67.296538)
		(end 126.551944 -67.338194)
		(width 0.10795)
		(layer "B.Cu")
		(net "H_CPU1_MSMI_G_N")
	)
	(segment
		(start 128.042416 -66.88836)
		(end 128.453388 -66.88836)
		(width 0.10795)
		(layer "B.Cu")
		(net "H_CPU1_MSMI_G_N")
	)
	(segment
		(start 128.453388 -66.88836)
		(end 128.747012 -67.181984)
		(width 0.10795)
		(layer "B.Cu")
		(net "H_CPU1_MSMI_G_N")
	)
	(segment
		(start 383.473706 -79.512414)
		(end 383.14757 -79.512414)
		(width 0.10795)
		(layer "B.Cu")
		(net "H_CPU1_MSMI_G_N")
	)
	(segment
		(start 180.426868 -17.1958)
		(end 181.348126 -17.1958)
		(width 0.089408)
		(layer "In9.Cu")
		(net "H_CPU1_MSMI_G_N")
	)
	(segment
		(start 121.233946 -61.29909)
		(end 120.806464 -61.29909)
		(width 0.089408)
		(layer "In9.Cu")
		(net "H_CPU1_MSMI_G_N")
	)
	(segment
		(start 194.982338 -5.970778)
		(end 258.857242 -5.970778)
		(width 0.089408)
		(layer "In9.Cu")
		(net "H_CPU1_MSMI_G_N")
	)
	(segment
		(start 266.798044 -9.651238)
		(end 323.203824 -9.651238)
		(width 0.089408)
		(layer "In9.Cu")
		(net "H_CPU1_MSMI_G_N")
	)
	(segment
		(start 128.886712 -33.73628)
		(end 147.840446 -33.73628)
		(width 0.089408)
		(layer "In9.Cu")
		(net "H_CPU1_MSMI_G_N")
	)
	(segment
		(start 126.510288 -67.296538)
		(end 126.510288 -67.09537)
		(width 0.089408)
		(layer "In9.Cu")
		(net "H_CPU1_MSMI_G_N")
	)
	(segment
		(start 184.594246 -14.150848)
		(end 185.59272 -13.152374)
		(width 0.089408)
		(layer "In9.Cu")
		(net "H_CPU1_MSMI_G_N")
	)
	(segment
		(start 181.99989 -16.544036)
		(end 181.99989 -16.104108)
		(width 0.089408)
		(layer "In9.Cu")
		(net "H_CPU1_MSMI_G_N")
	)
	(segment
		(start 123.438412 -62.797944)
		(end 122.954288 -62.31382)
		(width 0.089408)
		(layer "In9.Cu")
		(net "H_CPU1_MSMI_G_N")
	)
	(segment
		(start 323.203824 -9.651238)
		(end 324.942454 -11.389868)
		(width 0.089408)
		(layer "In9.Cu")
		(net "H_CPU1_MSMI_G_N")
	)
	(segment
		(start 187.850272 -9.891522)
		(end 189.6618 -9.891522)
		(width 0.089408)
		(layer "In9.Cu")
		(net "H_CPU1_MSMI_G_N")
	)
	(segment
		(start 330.77658 -25.037034)
		(end 331.813916 -26.07437)
		(width 0.089408)
		(layer "In9.Cu")
		(net "H_CPU1_MSMI_G_N")
	)
	(segment
		(start 159.194754 -20.67052)
		(end 160.256474 -19.6088)
		(width 0.089408)
		(layer "In9.Cu")
		(net "H_CPU1_MSMI_G_N")
	)
	(segment
		(start 329.398884 -16.79194)
		(end 329.398884 -22.628352)
		(width 0.089408)
		(layer "In9.Cu")
		(net "H_CPU1_MSMI_G_N")
	)
	(segment
		(start 119.817388 -60.527692)
		(end 119.817388 -52.953412)
		(width 0.089408)
		(layer "In9.Cu")
		(net "H_CPU1_MSMI_G_N")
	)
	(segment
		(start 326.919844 -15.26921)
		(end 327.876154 -15.26921)
		(width 0.089408)
		(layer "In9.Cu")
		(net "H_CPU1_MSMI_G_N")
	)
	(segment
		(start 324.942454 -11.389868)
		(end 324.942454 -13.29182)
		(width 0.089408)
		(layer "In9.Cu")
		(net "H_CPU1_MSMI_G_N")
	)
	(segment
		(start 263.140952 -9.805416)
		(end 264.040112 -9.805416)
		(width 0.089408)
		(layer "In9.Cu")
		(net "H_CPU1_MSMI_G_N")
	)
	(segment
		(start 191.470026 -8.083296)
		(end 192.86982 -8.083296)
		(width 0.089408)
		(layer "In9.Cu")
		(net "H_CPU1_MSMI_G_N")
	)
	(segment
		(start 126.510288 -67.09537)
		(end 125.699774 -66.284856)
		(width 0.089408)
		(layer "In9.Cu")
		(net "H_CPU1_MSMI_G_N")
	)
	(segment
		(start 125.08103 -64.200786)
		(end 123.678188 -62.797944)
		(width 0.089408)
		(layer "In9.Cu")
		(net "H_CPU1_MSMI_G_N")
	)
	(segment
		(start 261.541514 -8.65505)
		(end 261.990586 -8.65505)
		(width 0.089408)
		(layer "In9.Cu")
		(net "H_CPU1_MSMI_G_N")
	)
	(segment
		(start 189.6618 -9.891522)
		(end 191.470026 -8.083296)
		(width 0.089408)
		(layer "In9.Cu")
		(net "H_CPU1_MSMI_G_N")
	)
	(segment
		(start 331.813916 -26.07437)
		(end 331.813916 -33.324292)
		(width 0.089408)
		(layer "In9.Cu")
		(net "H_CPU1_MSMI_G_N")
	)
	(segment
		(start 330.77658 -24.006048)
		(end 330.77658 -25.037034)
		(width 0.089408)
		(layer "In9.Cu")
		(net "H_CPU1_MSMI_G_N")
	)
	(segment
		(start 178.478688 -19.14398)
		(end 180.426868 -17.1958)
		(width 0.089408)
		(layer "In9.Cu")
		(net "H_CPU1_MSMI_G_N")
	)
	(segment
		(start 121.697496 -61.76264)
		(end 121.233946 -61.29909)
		(width 0.089408)
		(layer "In9.Cu")
		(net "H_CPU1_MSMI_G_N")
	)
	(segment
		(start 125.08103 -65.80378)
		(end 125.08103 -64.200786)
		(width 0.089408)
		(layer "In9.Cu")
		(net "H_CPU1_MSMI_G_N")
	)
	(segment
		(start 264.315956 -9.529572)
		(end 266.676378 -9.529572)
		(width 0.089408)
		(layer "In9.Cu")
		(net "H_CPU1_MSMI_G_N")
	)
	(segment
		(start 125.699774 -66.284856)
		(end 125.562106 -66.284856)
		(width 0.089408)
		(layer "In9.Cu")
		(net "H_CPU1_MSMI_G_N")
	)
	(segment
		(start 122.698764 -50.072036)
		(end 122.698764 -39.924228)
		(width 0.089408)
		(layer "In9.Cu")
		(net "H_CPU1_MSMI_G_N")
	)
	(segment
		(start 152.293574 -29.300932)
		(end 152.293574 -29.283152)
		(width 0.089408)
		(layer "In9.Cu")
		(net "H_CPU1_MSMI_G_N")
	)
	(segment
		(start 148.442426 -33.15208)
		(end 152.293574 -29.300932)
		(width 0.089408)
		(layer "In9.Cu")
		(net "H_CPU1_MSMI_G_N")
	)
	(segment
		(start 324.942454 -13.29182)
		(end 326.919844 -15.26921)
		(width 0.089408)
		(layer "In9.Cu")
		(net "H_CPU1_MSMI_G_N")
	)
	(segment
		(start 123.678188 -62.797944)
		(end 123.438412 -62.797944)
		(width 0.089408)
		(layer "In9.Cu")
		(net "H_CPU1_MSMI_G_N")
	)
	(segment
		(start 192.86982 -8.083296)
		(end 194.982338 -5.970778)
		(width 0.089408)
		(layer "In9.Cu")
		(net "H_CPU1_MSMI_G_N")
	)
	(segment
		(start 185.633106 -13.109702)
		(end 185.633106 -12.108688)
		(width 0.089408)
		(layer "In9.Cu")
		(net "H_CPU1_MSMI_G_N")
	)
	(segment
		(start 156.94914 -25.851358)
		(end 157.315408 -25.851358)
		(width 0.089408)
		(layer "In9.Cu")
		(net "H_CPU1_MSMI_G_N")
	)
	(segment
		(start 264.040112 -9.805416)
		(end 264.315956 -9.529572)
		(width 0.089408)
		(layer "In9.Cu")
		(net "H_CPU1_MSMI_G_N")
	)
	(segment
		(start 183.95315 -14.150848)
		(end 184.594246 -14.150848)
		(width 0.089408)
		(layer "In9.Cu")
		(net "H_CPU1_MSMI_G_N")
	)
	(segment
		(start 120.337834 -60.83046)
		(end 120.120156 -60.83046)
		(width 0.089408)
		(layer "In9.Cu")
		(net "H_CPU1_MSMI_G_N")
	)
	(segment
		(start 176.389792 -19.14398)
		(end 178.478688 -19.14398)
		(width 0.089408)
		(layer "In9.Cu")
		(net "H_CPU1_MSMI_G_N")
	)
	(segment
		(start 168.462198 -19.6088)
		(end 169.424858 -18.64614)
		(width 0.089408)
		(layer "In9.Cu")
		(net "H_CPU1_MSMI_G_N")
	)
	(segment
		(start 261.990586 -8.65505)
		(end 263.140952 -9.805416)
		(width 0.089408)
		(layer "In9.Cu")
		(net "H_CPU1_MSMI_G_N")
	)
	(segment
		(start 266.676378 -9.529572)
		(end 266.798044 -9.651238)
		(width 0.089408)
		(layer "In9.Cu")
		(net "H_CPU1_MSMI_G_N")
	)
	(segment
		(start 169.424858 -18.64614)
		(end 173.957488 -18.64614)
		(width 0.089408)
		(layer "In9.Cu")
		(net "H_CPU1_MSMI_G_N")
	)
	(segment
		(start 154.07513 -28.725368)
		(end 156.94914 -25.851358)
		(width 0.089408)
		(layer "In9.Cu")
		(net "H_CPU1_MSMI_G_N")
	)
	(segment
		(start 185.59272 -13.150088)
		(end 185.633106 -13.109702)
		(width 0.089408)
		(layer "In9.Cu")
		(net "H_CPU1_MSMI_G_N")
	)
	(segment
		(start 159.194754 -23.972012)
		(end 159.194754 -20.67052)
		(width 0.089408)
		(layer "In9.Cu")
		(net "H_CPU1_MSMI_G_N")
	)
	(segment
		(start 122.609102 -62.31382)
		(end 122.057922 -61.76264)
		(width 0.089408)
		(layer "In9.Cu")
		(net "H_CPU1_MSMI_G_N")
	)
	(segment
		(start 152.851358 -28.725368)
		(end 154.07513 -28.725368)
		(width 0.089408)
		(layer "In9.Cu")
		(net "H_CPU1_MSMI_G_N")
	)
	(segment
		(start 181.348126 -17.1958)
		(end 181.99989 -16.544036)
		(width 0.089408)
		(layer "In9.Cu")
		(net "H_CPU1_MSMI_G_N")
	)
	(segment
		(start 125.562106 -66.284856)
		(end 125.08103 -65.80378)
		(width 0.089408)
		(layer "In9.Cu")
		(net "H_CPU1_MSMI_G_N")
	)
	(segment
		(start 173.957488 -18.64614)
		(end 174.73676 -19.425412)
		(width 0.089408)
		(layer "In9.Cu")
		(net "H_CPU1_MSMI_G_N")
	)
	(segment
		(start 157.315408 -25.851358)
		(end 159.194754 -23.972012)
		(width 0.089408)
		(layer "In9.Cu")
		(net "H_CPU1_MSMI_G_N")
	)
	(segment
		(start 329.398884 -22.628352)
		(end 330.77658 -24.006048)
		(width 0.089408)
		(layer "In9.Cu")
		(net "H_CPU1_MSMI_G_N")
	)
	(segment
		(start 122.954288 -62.31382)
		(end 122.609102 -62.31382)
		(width 0.089408)
		(layer "In9.Cu")
		(net "H_CPU1_MSMI_G_N")
	)
	(segment
		(start 258.857242 -5.970778)
		(end 261.541514 -8.65505)
		(width 0.089408)
		(layer "In9.Cu")
		(net "H_CPU1_MSMI_G_N")
	)
	(segment
		(start 331.813916 -33.324292)
		(end 331.9526 -33.462976)
		(width 0.089408)
		(layer "In9.Cu")
		(net "H_CPU1_MSMI_G_N")
	)
	(segment
		(start 185.59272 -13.152374)
		(end 185.59272 -13.150088)
		(width 0.089408)
		(layer "In9.Cu")
		(net "H_CPU1_MSMI_G_N")
	)
	(segment
		(start 119.817388 -52.953412)
		(end 122.698764 -50.072036)
		(width 0.089408)
		(layer "In9.Cu")
		(net "H_CPU1_MSMI_G_N")
	)
	(segment
		(start 185.633106 -12.108688)
		(end 187.850272 -9.891522)
		(width 0.089408)
		(layer "In9.Cu")
		(net "H_CPU1_MSMI_G_N")
	)
	(segment
		(start 148.424646 -33.15208)
		(end 148.442426 -33.15208)
		(width 0.089408)
		(layer "In9.Cu")
		(net "H_CPU1_MSMI_G_N")
	)
	(segment
		(start 122.698764 -39.924228)
		(end 128.886712 -33.73628)
		(width 0.089408)
		(layer "In9.Cu")
		(net "H_CPU1_MSMI_G_N")
	)
	(segment
		(start 120.120156 -60.83046)
		(end 119.817388 -60.527692)
		(width 0.089408)
		(layer "In9.Cu")
		(net "H_CPU1_MSMI_G_N")
	)
	(segment
		(start 120.806464 -61.29909)
		(end 120.337834 -60.83046)
		(width 0.089408)
		(layer "In9.Cu")
		(net "H_CPU1_MSMI_G_N")
	)
	(segment
		(start 160.256474 -19.6088)
		(end 168.462198 -19.6088)
		(width 0.089408)
		(layer "In9.Cu")
		(net "H_CPU1_MSMI_G_N")
	)
	(segment
		(start 181.99989 -16.104108)
		(end 183.95315 -14.150848)
		(width 0.089408)
		(layer "In9.Cu")
		(net "H_CPU1_MSMI_G_N")
	)
	(segment
		(start 176.10836 -19.425412)
		(end 176.389792 -19.14398)
		(width 0.089408)
		(layer "In9.Cu")
		(net "H_CPU1_MSMI_G_N")
	)
	(segment
		(start 147.840446 -33.73628)
		(end 148.424646 -33.15208)
		(width 0.089408)
		(layer "In9.Cu")
		(net "H_CPU1_MSMI_G_N")
	)
	(segment
		(start 327.876154 -15.26921)
		(end 329.398884 -16.79194)
		(width 0.089408)
		(layer "In9.Cu")
		(net "H_CPU1_MSMI_G_N")
	)
	(segment
		(start 122.057922 -61.76264)
		(end 121.697496 -61.76264)
		(width 0.089408)
		(layer "In9.Cu")
		(net "H_CPU1_MSMI_G_N")
	)
	(segment
		(start 152.293574 -29.283152)
		(end 152.851358 -28.725368)
		(width 0.089408)
		(layer "In9.Cu")
		(net "H_CPU1_MSMI_G_N")
	)
	(segment
		(start 174.73676 -19.425412)
		(end 176.10836 -19.425412)
		(width 0.089408)
		(layer "In9.Cu")
		(net "H_CPU1_MSMI_G_N")
	)
	(segment
		(start 378.357384 -54.582314)
		(end 378.122434 -54.347364)
		(width 0.089408)
		(layer "In11.Cu")
		(net "H_CPU1_MSMI_G_N")
	)
	(segment
		(start 331.9526 -35.451034)
		(end 331.9526 -33.462976)
		(width 0.089408)
		(layer "In11.Cu")
		(net "H_CPU1_MSMI_G_N")
	)
	(segment
		(start 383.608072 -79.051912)
		(end 383.608072 -76.62672)
		(width 0.089408)
		(layer "In11.Cu")
		(net "H_CPU1_MSMI_G_N")
	)
	(segment
		(start 354.713794 -37.490908)
		(end 353.234752 -38.969696)
		(width 0.089408)
		(layer "In11.Cu")
		(net "H_CPU1_MSMI_G_N")
	)
	(segment
		(start 379.94082 -63.16599)
		(end 379.94082 -63.091822)
		(width 0.089408)
		(layer "In11.Cu")
		(net "H_CPU1_MSMI_G_N")
	)
	(segment
		(start 380.704344 -62.315344)
		(end 380.711202 -62.308486)
		(width 0.089408)
		(layer "In11.Cu")
		(net "H_CPU1_MSMI_G_N")
	)
	(segment
		(start 380.710948 -60.405518)
		(end 381.368046 -59.74842)
		(width 0.089408)
		(layer "In11.Cu")
		(net "H_CPU1_MSMI_G_N")
	)
	(segment
		(start 380.722124 -58.317638)
		(end 380.720346 -58.319416)
		(width 0.089408)
		(layer "In11.Cu")
		(net "H_CPU1_MSMI_G_N")
	)
	(segment
		(start 380.569216 -58.317638)
		(end 380.273052 -58.317638)
		(width 0.089408)
		(layer "In11.Cu")
		(net "H_CPU1_MSMI_G_N")
	)
	(segment
		(start 335.806288 -38.5064)
		(end 334.548734 -38.5064)
		(width 0.089408)
		(layer "In11.Cu")
		(net "H_CPU1_MSMI_G_N")
	)
	(segment
		(start 379.94209 -63.535814)
		(end 379.94082 -63.16599)
		(width 0.089408)
		(layer "In11.Cu")
		(net "H_CPU1_MSMI_G_N")
	)
	(segment
		(start 367.745518 -47.020988)
		(end 366.526318 -47.020988)
		(width 0.089408)
		(layer "In11.Cu")
		(net "H_CPU1_MSMI_G_N")
	)
	(segment
		(start 381.239776 -66.128392)
		(end 381.239776 -64.862456)
		(width 0.089408)
		(layer "In11.Cu")
		(net "H_CPU1_MSMI_G_N")
	)
	(segment
		(start 379.942852 -63.798704)
		(end 379.942344 -63.647828)
		(width 0.089408)
		(layer "In11.Cu")
		(net "H_CPU1_MSMI_G_N")
	)
	(segment
		(start 376.733054 -54.347364)
		(end 376.7328 -54.34711)
		(width 0.089408)
		(layer "In11.Cu")
		(net "H_CPU1_MSMI_G_N")
	)
	(segment
		(start 376.574558 -54.347364)
		(end 374.617488 -54.347364)
		(width 0.089408)
		(layer "In11.Cu")
		(net "H_CPU1_MSMI_G_N")
	)
	(segment
		(start 379.942344 -63.647828)
		(end 379.942344 -63.536068)
		(width 0.089408)
		(layer "In11.Cu")
		(net "H_CPU1_MSMI_G_N")
	)
	(segment
		(start 374.617488 -54.347364)
		(end 372.969536 -52.699412)
		(width 0.089408)
		(layer "In11.Cu")
		(net "H_CPU1_MSMI_G_N")
	)
	(segment
		(start 381.368046 -58.631836)
		(end 381.053848 -58.317638)
		(width 0.089408)
		(layer "In11.Cu")
		(net "H_CPU1_MSMI_G_N")
	)
	(segment
		(start 376.574812 -54.34711)
		(end 376.574558 -54.347364)
		(width 0.089408)
		(layer "In11.Cu")
		(net "H_CPU1_MSMI_G_N")
	)
	(segment
		(start 383.304796 -76.323444)
		(end 383.304796 -73.790556)
		(width 0.089408)
		(layer "In11.Cu")
		(net "H_CPU1_MSMI_G_N")
	)
	(segment
		(start 379.942344 -63.536068)
		(end 379.94209 -63.535814)
		(width 0.089408)
		(layer "In11.Cu")
		(net "H_CPU1_MSMI_G_N")
	)
	(segment
		(start 383.216404 -68.10502)
		(end 381.239776 -66.128392)
		(width 0.089408)
		(layer "In11.Cu")
		(net "H_CPU1_MSMI_G_N")
	)
	(segment
		(start 380.984252 -64.606932)
		(end 380.537466 -64.606932)
		(width 0.089408)
		(layer "In11.Cu")
		(net "H_CPU1_MSMI_G_N")
	)
	(segment
		(start 383.304796 -73.790556)
		(end 383.622296 -73.473056)
		(width 0.089408)
		(layer "In11.Cu")
		(net "H_CPU1_MSMI_G_N")
	)
	(segment
		(start 383.622296 -73.473056)
		(end 383.622296 -72.521572)
		(width 0.089408)
		(layer "In11.Cu")
		(net "H_CPU1_MSMI_G_N")
	)
	(segment
		(start 379.942344 -64.01181)
		(end 379.942344 -63.799466)
		(width 0.089408)
		(layer "In11.Cu")
		(net "H_CPU1_MSMI_G_N")
	)
	(segment
		(start 380.570994 -58.319416)
		(end 380.569216 -58.317638)
		(width 0.089408)
		(layer "In11.Cu")
		(net "H_CPU1_MSMI_G_N")
	)
	(segment
		(start 334.548734 -38.5064)
		(end 333.165704 -37.12337)
		(width 0.089408)
		(layer "In11.Cu")
		(net "H_CPU1_MSMI_G_N")
	)
	(segment
		(start 381.239776 -64.862456)
		(end 380.984252 -64.606932)
		(width 0.089408)
		(layer "In11.Cu")
		(net "H_CPU1_MSMI_G_N")
	)
	(segment
		(start 383.622296 -72.521572)
		(end 383.024126 -71.923402)
		(width 0.089408)
		(layer "In11.Cu")
		(net "H_CPU1_MSMI_G_N")
	)
	(segment
		(start 383.216404 -70.499732)
		(end 383.216404 -68.10502)
		(width 0.089408)
		(layer "In11.Cu")
		(net "H_CPU1_MSMI_G_N")
	)
	(segment
		(start 383.14757 -79.512414)
		(end 383.608072 -79.051912)
		(width 0.089408)
		(layer "In11.Cu")
		(net "H_CPU1_MSMI_G_N")
	)
	(segment
		(start 378.122434 -54.347364)
		(end 376.733054 -54.347364)
		(width 0.089408)
		(layer "In11.Cu")
		(net "H_CPU1_MSMI_G_N")
	)
	(segment
		(start 372.969536 -52.699412)
		(end 372.969536 -52.245006)
		(width 0.089408)
		(layer "In11.Cu")
		(net "H_CPU1_MSMI_G_N")
	)
	(segment
		(start 380.537466 -64.606932)
		(end 379.942344 -64.01181)
		(width 0.089408)
		(layer "In11.Cu")
		(net "H_CPU1_MSMI_G_N")
	)
	(segment
		(start 383.024126 -70.69201)
		(end 383.216404 -70.499732)
		(width 0.089408)
		(layer "In11.Cu")
		(net "H_CPU1_MSMI_G_N")
	)
	(segment
		(start 372.969536 -52.245006)
		(end 367.745518 -47.020988)
		(width 0.089408)
		(layer "In11.Cu")
		(net "H_CPU1_MSMI_G_N")
	)
	(segment
		(start 380.710948 -62.045088)
		(end 380.710948 -60.405518)
		(width 0.089408)
		(layer "In11.Cu")
		(net "H_CPU1_MSMI_G_N")
	)
	(segment
		(start 381.368046 -59.74842)
		(end 381.368046 -58.631836)
		(width 0.089408)
		(layer "In11.Cu")
		(net "H_CPU1_MSMI_G_N")
	)
	(segment
		(start 383.608072 -76.62672)
		(end 383.304796 -76.323444)
		(width 0.089408)
		(layer "In11.Cu")
		(net "H_CPU1_MSMI_G_N")
	)
	(segment
		(start 380.711202 -62.308486)
		(end 380.711202 -62.045342)
		(width 0.089408)
		(layer "In11.Cu")
		(net "H_CPU1_MSMI_G_N")
	)
	(segment
		(start 381.053848 -58.317638)
		(end 380.722124 -58.317638)
		(width 0.089408)
		(layer "In11.Cu")
		(net "H_CPU1_MSMI_G_N")
	)
	(segment
		(start 354.844604 -37.404294)
		(end 354.713794 -37.490908)
		(width 0.089408)
		(layer "In11.Cu")
		(net "H_CPU1_MSMI_G_N")
	)
	(segment
		(start 383.024126 -71.923402)
		(end 383.024126 -70.69201)
		(width 0.089408)
		(layer "In11.Cu")
		(net "H_CPU1_MSMI_G_N")
	)
	(segment
		(start 380.720346 -58.319416)
		(end 380.570994 -58.319416)
		(width 0.089408)
		(layer "In11.Cu")
		(net "H_CPU1_MSMI_G_N")
	)
	(segment
		(start 379.942344 -63.799466)
		(end 379.942852 -63.798704)
		(width 0.089408)
		(layer "In11.Cu")
		(net "H_CPU1_MSMI_G_N")
	)
	(segment
		(start 336.269584 -38.969696)
		(end 335.806288 -38.5064)
		(width 0.089408)
		(layer "In11.Cu")
		(net "H_CPU1_MSMI_G_N")
	)
	(segment
		(start 380.711202 -62.045342)
		(end 380.710948 -62.045088)
		(width 0.089408)
		(layer "In11.Cu")
		(net "H_CPU1_MSMI_G_N")
	)
	(segment
		(start 376.7328 -54.34711)
		(end 376.574812 -54.34711)
		(width 0.089408)
		(layer "In11.Cu")
		(net "H_CPU1_MSMI_G_N")
	)
	(segment
		(start 333.165704 -37.12337)
		(end 333.165704 -36.664138)
		(width 0.089408)
		(layer "In11.Cu")
		(net "H_CPU1_MSMI_G_N")
	)
	(segment
		(start 378.357384 -56.40197)
		(end 378.357384 -54.582314)
		(width 0.089408)
		(layer "In11.Cu")
		(net "H_CPU1_MSMI_G_N")
	)
	(segment
		(start 380.704344 -62.328298)
		(end 380.704344 -62.315344)
		(width 0.089408)
		(layer "In11.Cu")
		(net "H_CPU1_MSMI_G_N")
	)
	(segment
		(start 356.909624 -37.404294)
		(end 354.844604 -37.404294)
		(width 0.089408)
		(layer "In11.Cu")
		(net "H_CPU1_MSMI_G_N")
	)
	(segment
		(start 379.94082 -63.091822)
		(end 380.704344 -62.328298)
		(width 0.089408)
		(layer "In11.Cu")
		(net "H_CPU1_MSMI_G_N")
	)
	(segment
		(start 333.165704 -36.664138)
		(end 331.9526 -35.451034)
		(width 0.089408)
		(layer "In11.Cu")
		(net "H_CPU1_MSMI_G_N")
	)
	(segment
		(start 380.273052 -58.317638)
		(end 378.357384 -56.40197)
		(width 0.089408)
		(layer "In11.Cu")
		(net "H_CPU1_MSMI_G_N")
	)
	(segment
		(start 366.526318 -47.020988)
		(end 356.909624 -37.404294)
		(width 0.089408)
		(layer "In11.Cu")
		(net "H_CPU1_MSMI_G_N")
	)
	(segment
		(start 353.234752 -38.969696)
		(end 336.269584 -38.969696)
		(width 0.089408)
		(layer "In11.Cu")
		(net "H_CPU1_MSMI_G_N")
	)
	(segment
		(start 438.2135 -17.5895)
		(end 437.7055 -17.0815)
		(width 0.10795)
		(layer "F.Cu")
		(net "H_CPU1_MEMKLM_MEMHOT_G_N")
	)
	(segment
		(start 162.8521 -124.438156)
		(end 163.585144 -125.1712)
		(width 0.10795)
		(layer "F.Cu")
		(net "H_CPU1_MEMKLM_MEMHOT_G_N")
	)
	(segment
		(start 437.7055 -16.891)
		(end 437.7055 -16.129)
		(width 0.10795)
		(layer "F.Cu")
		(net "H_CPU1_MEMKLM_MEMHOT_G_N")
	)
	(segment
		(start 170.22699 -125.111002)
		(end 169.452798 -125.111002)
		(width 0.10795)
		(layer "F.Cu")
		(net "H_CPU1_MEMKLM_MEMHOT_G_N")
	)
	(segment
		(start 170.526202 -125.111002)
		(end 172.40758 -126.99238)
		(width 0.10795)
		(layer "F.Cu")
		(net "H_CPU1_MEMKLM_MEMHOT_G_N")
	)
	(segment
		(start 163.88842 -123.22302)
		(end 163.06292 -123.22302)
		(width 0.10795)
		(layer "F.Cu")
		(net "H_CPU1_MEMKLM_MEMHOT_G_N")
	)
	(segment
		(start 170.22699 -125.111002)
		(end 170.526202 -125.111002)
		(width 0.10795)
		(layer "F.Cu")
		(net "H_CPU1_MEMKLM_MEMHOT_G_N")
	)
	(segment
		(start 163.585144 -125.1712)
		(end 163.9316 -125.1712)
		(width 0.10795)
		(layer "F.Cu")
		(net "H_CPU1_MEMKLM_MEMHOT_G_N")
	)
	(segment
		(start 163.06292 -123.22302)
		(end 162.8521 -123.0122)
		(width 0.10795)
		(layer "F.Cu")
		(net "H_CPU1_MEMKLM_MEMHOT_G_N")
	)
	(segment
		(start 169.452798 -125.111002)
		(end 168.4274 -126.1364)
		(width 0.10795)
		(layer "F.Cu")
		(net "H_CPU1_MEMKLM_MEMHOT_G_N")
	)
	(segment
		(start 131.948174 -63.829184)
		(end 132.519674 -63.829184)
		(width 0.1016)
		(layer "F.Cu")
		(net "H_CPU1_MEMKLM_MEMHOT_G_N")
	)
	(segment
		(start 162.8521 -123.0122)
		(end 162.8521 -124.438156)
		(width 0.10795)
		(layer "F.Cu")
		(net "H_CPU1_MEMKLM_MEMHOT_G_N")
	)
	(segment
		(start 163.9316 -125.1712)
		(end 164.8968 -126.1364)
		(width 0.10795)
		(layer "F.Cu")
		(net "H_CPU1_MEMKLM_MEMHOT_G_N")
	)
	(segment
		(start 172.40758 -126.99238)
		(end 172.57522 -126.99238)
		(width 0.10795)
		(layer "F.Cu")
		(net "H_CPU1_MEMKLM_MEMHOT_G_N")
	)
	(segment
		(start 168.4274 -126.1364)
		(end 166.0652 -126.1364)
		(width 0.10795)
		(layer "F.Cu")
		(net "H_CPU1_MEMKLM_MEMHOT_G_N")
	)
	(segment
		(start 164.8968 -126.1364)
		(end 166.0652 -126.1364)
		(width 0.10795)
		(layer "F.Cu")
		(net "H_CPU1_MEMKLM_MEMHOT_G_N")
	)
	(segment
		(start 437.7055 -16.129)
		(end 438.4675 -16.129)
		(width 0.10795)
		(layer "F.Cu")
		(net "H_CPU1_MEMKLM_MEMHOT_G_N")
	)
	(segment
		(start 438.270396 -17.5895)
		(end 438.2135 -17.5895)
		(width 0.10795)
		(layer "F.Cu")
		(net "H_CPU1_MEMKLM_MEMHOT_G_N")
	)
	(segment
		(start 437.7055 -17.0815)
		(end 437.7055 -16.891)
		(width 0.10795)
		(layer "F.Cu")
		(net "H_CPU1_MEMKLM_MEMHOT_G_N")
	)
	(via
		(at 170.22699 -125.111002)
		(size 0.762)
		(drill 0.381)
		(layers "F.Cu" "B.Cu")
		(net "H_CPU1_MEMKLM_MEMHOT_G_N")
	)
	(via
		(at 132.519674 -63.829184)
		(size 0.508)
		(drill 0.254)
		(layers "F.Cu" "B.Cu")
		(net "H_CPU1_MEMKLM_MEMHOT_G_N")
	)
	(via
		(at 369.316 -65.9638)
		(size 0.508)
		(drill 0.254)
		(layers "F.Cu" "B.Cu")
		(net "H_CPU1_MEMKLM_MEMHOT_G_N")
	)
	(via
		(at 116.4336 -70.2056)
		(size 0.508)
		(drill 0.254)
		(layers "F.Cu" "B.Cu")
		(net "H_CPU1_MEMKLM_MEMHOT_G_N")
	)
	(via
		(at 191.9986 -150.7871)
		(size 0.508)
		(drill 0.254)
		(layers "F.Cu" "B.Cu")
		(net "H_CPU1_MEMKLM_MEMHOT_G_N")
	)
	(via
		(at 438.270396 -17.5895)
		(size 0.508)
		(drill 0.254)
		(layers "F.Cu" "B.Cu")
		(net "H_CPU1_MEMKLM_MEMHOT_G_N")
	)
	(via
		(at 162.8521 -123.0122)
		(size 0.508)
		(drill 0.254)
		(layers "F.Cu" "B.Cu")
		(net "H_CPU1_MEMKLM_MEMHOT_G_N")
	)
	(via
		(at 166.0652 -126.1364)
		(size 0.508)
		(drill 0.254)
		(layers "F.Cu" "B.Cu")
		(net "H_CPU1_MEMKLM_MEMHOT_G_N")
	)
	(segment
		(start 116.4336 -70.2056)
		(end 116.3574 -70.2056)
		(width 0.10795)
		(layer "B.Cu")
		(net "H_CPU1_MEMKLM_MEMHOT_G_N")
	)
	(segment
		(start 116.3574 -70.2056)
		(end 115.824 -70.739)
		(width 0.10795)
		(layer "B.Cu")
		(net "H_CPU1_MEMKLM_MEMHOT_G_N")
	)
	(segment
		(start 376.70867 -64.721232)
		(end 375.48439 -65.945512)
		(width 0.089408)
		(layer "In2.Cu")
		(net "H_CPU1_MEMKLM_MEMHOT_G_N")
	)
	(segment
		(start 406.628346 -26.077672)
		(end 406.566116 -26.077672)
		(width 0.089408)
		(layer "In2.Cu")
		(net "H_CPU1_MEMKLM_MEMHOT_G_N")
	)
	(segment
		(start 379.433582 -55.779416)
		(end 379.254258 -55.95874)
		(width 0.089408)
		(layer "In2.Cu")
		(net "H_CPU1_MEMKLM_MEMHOT_G_N")
	)
	(segment
		(start 373.64797 -65.945512)
		(end 373.209058 -65.5066)
		(width 0.089408)
		(layer "In2.Cu")
		(net "H_CPU1_MEMKLM_MEMHOT_G_N")
	)
	(segment
		(start 385.98602 -31.85668)
		(end 385.0386 -32.8041)
		(width 0.089408)
		(layer "In2.Cu")
		(net "H_CPU1_MEMKLM_MEMHOT_G_N")
	)
	(segment
		(start 387.856222 -28.3591)
		(end 387.550152 -28.05303)
		(width 0.089408)
		(layer "In2.Cu")
		(net "H_CPU1_MEMKLM_MEMHOT_G_N")
	)
	(segment
		(start 427.28388 -20.260818)
		(end 426.409612 -21.135086)
		(width 0.089408)
		(layer "In2.Cu")
		(net "H_CPU1_MEMKLM_MEMHOT_G_N")
	)
	(segment
		(start 385.0386 -32.8041)
		(end 385.0386 -33.8201)
		(width 0.089408)
		(layer "In2.Cu")
		(net "H_CPU1_MEMKLM_MEMHOT_G_N")
	)
	(segment
		(start 395.357858 -27.051)
		(end 392.374882 -27.051)
		(width 0.089408)
		(layer "In2.Cu")
		(net "H_CPU1_MEMKLM_MEMHOT_G_N")
	)
	(segment
		(start 400.170904 -26.794714)
		(end 395.614144 -26.794714)
		(width 0.089408)
		(layer "In2.Cu")
		(net "H_CPU1_MEMKLM_MEMHOT_G_N")
	)
	(segment
		(start 405.578564 -26.373836)
		(end 404.401782 -26.373836)
		(width 0.089408)
		(layer "In2.Cu")
		(net "H_CPU1_MEMKLM_MEMHOT_G_N")
	)
	(segment
		(start 404.066756 -26.708862)
		(end 403.1488 -26.708862)
		(width 0.089408)
		(layer "In2.Cu")
		(net "H_CPU1_MEMKLM_MEMHOT_G_N")
	)
	(segment
		(start 380.820676 -38.127432)
		(end 380.57201 -38.376098)
		(width 0.089408)
		(layer "In2.Cu")
		(net "H_CPU1_MEMKLM_MEMHOT_G_N")
	)
	(segment
		(start 378.300488 -63.12154)
		(end 378.05106 -63.370968)
		(width 0.089408)
		(layer "In2.Cu")
		(net "H_CPU1_MEMKLM_MEMHOT_G_N")
	)
	(segment
		(start 395.614144 -26.794714)
		(end 395.357858 -27.051)
		(width 0.089408)
		(layer "In2.Cu")
		(net "H_CPU1_MEMKLM_MEMHOT_G_N")
	)
	(segment
		(start 385.210812 -33.992312)
		(end 385.210812 -35.463226)
		(width 0.089408)
		(layer "In2.Cu")
		(net "H_CPU1_MEMKLM_MEMHOT_G_N")
	)
	(segment
		(start 373.209058 -65.5066)
		(end 369.7732 -65.5066)
		(width 0.089408)
		(layer "In2.Cu")
		(net "H_CPU1_MEMKLM_MEMHOT_G_N")
	)
	(segment
		(start 406.566116 -26.077672)
		(end 406.565862 -26.077418)
		(width 0.089408)
		(layer "In2.Cu")
		(net "H_CPU1_MEMKLM_MEMHOT_G_N")
	)
	(segment
		(start 432.064922 -19.463766)
		(end 431.26787 -20.260818)
		(width 0.089408)
		(layer "In2.Cu")
		(net "H_CPU1_MEMKLM_MEMHOT_G_N")
	)
	(segment
		(start 380.965456 -41.5798)
		(end 380.965456 -45.11802)
		(width 0.089408)
		(layer "In2.Cu")
		(net "H_CPU1_MEMKLM_MEMHOT_G_N")
	)
	(segment
		(start 385.98602 -28.901136)
		(end 385.98602 -31.85668)
		(width 0.089408)
		(layer "In2.Cu")
		(net "H_CPU1_MEMKLM_MEMHOT_G_N")
	)
	(segment
		(start 381.110744 -41.434512)
		(end 380.965456 -41.5798)
		(width 0.089408)
		(layer "In2.Cu")
		(net "H_CPU1_MEMKLM_MEMHOT_G_N")
	)
	(segment
		(start 380.57201 -38.376098)
		(end 380.57201 -40.506904)
		(width 0.089408)
		(layer "In2.Cu")
		(net "H_CPU1_MEMKLM_MEMHOT_G_N")
	)
	(segment
		(start 375.48439 -65.945512)
		(end 373.64797 -65.945512)
		(width 0.089408)
		(layer "In2.Cu")
		(net "H_CPU1_MEMKLM_MEMHOT_G_N")
	)
	(segment
		(start 404.401782 -26.373836)
		(end 404.066756 -26.708862)
		(width 0.089408)
		(layer "In2.Cu")
		(net "H_CPU1_MEMKLM_MEMHOT_G_N")
	)
	(segment
		(start 402.94179 -26.915872)
		(end 400.292062 -26.915872)
		(width 0.089408)
		(layer "In2.Cu")
		(net "H_CPU1_MEMKLM_MEMHOT_G_N")
	)
	(segment
		(start 408.956002 -26.343864)
		(end 406.93467 -26.343864)
		(width 0.089408)
		(layer "In2.Cu")
		(net "H_CPU1_MEMKLM_MEMHOT_G_N")
	)
	(segment
		(start 406.234138 -26.077418)
		(end 406.233884 -26.077672)
		(width 0.089408)
		(layer "In2.Cu")
		(net "H_CPU1_MEMKLM_MEMHOT_G_N")
	)
	(segment
		(start 406.233884 -26.077672)
		(end 405.874728 -26.077672)
		(width 0.089408)
		(layer "In2.Cu")
		(net "H_CPU1_MEMKLM_MEMHOT_G_N")
	)
	(segment
		(start 406.565862 -26.077418)
		(end 406.234138 -26.077418)
		(width 0.089408)
		(layer "In2.Cu")
		(net "H_CPU1_MEMKLM_MEMHOT_G_N")
	)
	(segment
		(start 392.374882 -27.051)
		(end 391.765282 -27.6606)
		(width 0.089408)
		(layer "In2.Cu")
		(net "H_CPU1_MEMKLM_MEMHOT_G_N")
	)
	(segment
		(start 432.545998 -19.463766)
		(end 432.064922 -19.463766)
		(width 0.089408)
		(layer "In2.Cu")
		(net "H_CPU1_MEMKLM_MEMHOT_G_N")
	)
	(segment
		(start 385.0386 -33.8201)
		(end 385.210812 -33.992312)
		(width 0.089408)
		(layer "In2.Cu")
		(net "H_CPU1_MEMKLM_MEMHOT_G_N")
	)
	(segment
		(start 406.93467 -26.343864)
		(end 406.934416 -26.34361)
		(width 0.089408)
		(layer "In2.Cu")
		(net "H_CPU1_MEMKLM_MEMHOT_G_N")
	)
	(segment
		(start 381.110744 -41.045638)
		(end 381.110744 -41.434512)
		(width 0.089408)
		(layer "In2.Cu")
		(net "H_CPU1_MEMKLM_MEMHOT_G_N")
	)
	(segment
		(start 420.638986 -23.530814)
		(end 414.37687 -23.530814)
		(width 0.089408)
		(layer "In2.Cu")
		(net "H_CPU1_MEMKLM_MEMHOT_G_N")
	)
	(segment
		(start 426.409612 -21.135086)
		(end 423.240962 -21.135086)
		(width 0.089408)
		(layer "In2.Cu")
		(net "H_CPU1_MEMKLM_MEMHOT_G_N")
	)
	(segment
		(start 376.937524 -63.57112)
		(end 376.930666 -63.57112)
		(width 0.089408)
		(layer "In2.Cu")
		(net "H_CPU1_MEMKLM_MEMHOT_G_N")
	)
	(segment
		(start 379.433582 -46.649894)
		(end 379.433582 -55.779416)
		(width 0.089408)
		(layer "In2.Cu")
		(net "H_CPU1_MEMKLM_MEMHOT_G_N")
	)
	(segment
		(start 406.934416 -26.34361)
		(end 406.894284 -26.34361)
		(width 0.089408)
		(layer "In2.Cu")
		(net "H_CPU1_MEMKLM_MEMHOT_G_N")
	)
	(segment
		(start 383.55143 -36.681664)
		(end 382.105662 -38.127432)
		(width 0.089408)
		(layer "In2.Cu")
		(net "H_CPU1_MEMKLM_MEMHOT_G_N")
	)
	(segment
		(start 369.7732 -65.5066)
		(end 369.316 -65.9638)
		(width 0.089408)
		(layer "In2.Cu")
		(net "H_CPU1_MEMKLM_MEMHOT_G_N")
	)
	(segment
		(start 378.300488 -57.309766)
		(end 378.300488 -63.12154)
		(width 0.089408)
		(layer "In2.Cu")
		(net "H_CPU1_MEMKLM_MEMHOT_G_N")
	)
	(segment
		(start 437.447436 -18.792952)
		(end 433.216812 -18.792952)
		(width 0.089408)
		(layer "In2.Cu")
		(net "H_CPU1_MEMKLM_MEMHOT_G_N")
	)
	(segment
		(start 377.137676 -63.370968)
		(end 376.937524 -63.57112)
		(width 0.089408)
		(layer "In2.Cu")
		(net "H_CPU1_MEMKLM_MEMHOT_G_N")
	)
	(segment
		(start 405.874728 -26.077672)
		(end 405.578564 -26.373836)
		(width 0.089408)
		(layer "In2.Cu")
		(net "H_CPU1_MEMKLM_MEMHOT_G_N")
	)
	(segment
		(start 380.965456 -45.11802)
		(end 379.433582 -46.649894)
		(width 0.089408)
		(layer "In2.Cu")
		(net "H_CPU1_MEMKLM_MEMHOT_G_N")
	)
	(segment
		(start 411.999684 -25.908)
		(end 409.391866 -25.908)
		(width 0.089408)
		(layer "In2.Cu")
		(net "H_CPU1_MEMKLM_MEMHOT_G_N")
	)
	(segment
		(start 389.095488 -27.6606)
		(end 388.396988 -28.3591)
		(width 0.089408)
		(layer "In2.Cu")
		(net "H_CPU1_MEMKLM_MEMHOT_G_N")
	)
	(segment
		(start 379.254258 -55.95874)
		(end 379.254258 -56.355996)
		(width 0.089408)
		(layer "In2.Cu")
		(net "H_CPU1_MEMKLM_MEMHOT_G_N")
	)
	(segment
		(start 431.26787 -20.260818)
		(end 427.28388 -20.260818)
		(width 0.089408)
		(layer "In2.Cu")
		(net "H_CPU1_MEMKLM_MEMHOT_G_N")
	)
	(segment
		(start 387.550152 -28.05303)
		(end 386.834126 -28.05303)
		(width 0.089408)
		(layer "In2.Cu")
		(net "H_CPU1_MEMKLM_MEMHOT_G_N")
	)
	(segment
		(start 376.930666 -63.57112)
		(end 376.70867 -63.793116)
		(width 0.089408)
		(layer "In2.Cu")
		(net "H_CPU1_MEMKLM_MEMHOT_G_N")
	)
	(segment
		(start 379.254258 -56.355996)
		(end 378.300488 -57.309766)
		(width 0.089408)
		(layer "In2.Cu")
		(net "H_CPU1_MEMKLM_MEMHOT_G_N")
	)
	(segment
		(start 383.992374 -36.681664)
		(end 383.55143 -36.681664)
		(width 0.089408)
		(layer "In2.Cu")
		(net "H_CPU1_MEMKLM_MEMHOT_G_N")
	)
	(segment
		(start 385.210812 -35.463226)
		(end 383.992374 -36.681664)
		(width 0.089408)
		(layer "In2.Cu")
		(net "H_CPU1_MEMKLM_MEMHOT_G_N")
	)
	(segment
		(start 403.1488 -26.708862)
		(end 402.94179 -26.915872)
		(width 0.089408)
		(layer "In2.Cu")
		(net "H_CPU1_MEMKLM_MEMHOT_G_N")
	)
	(segment
		(start 400.292062 -26.915872)
		(end 400.170904 -26.794714)
		(width 0.089408)
		(layer "In2.Cu")
		(net "H_CPU1_MEMKLM_MEMHOT_G_N")
	)
	(segment
		(start 391.765282 -27.6606)
		(end 389.095488 -27.6606)
		(width 0.089408)
		(layer "In2.Cu")
		(net "H_CPU1_MEMKLM_MEMHOT_G_N")
	)
	(segment
		(start 376.70867 -63.793116)
		(end 376.70867 -64.721232)
		(width 0.089408)
		(layer "In2.Cu")
		(net "H_CPU1_MEMKLM_MEMHOT_G_N")
	)
	(segment
		(start 382.105662 -38.127432)
		(end 380.820676 -38.127432)
		(width 0.089408)
		(layer "In2.Cu")
		(net "H_CPU1_MEMKLM_MEMHOT_G_N")
	)
	(segment
		(start 414.37687 -23.530814)
		(end 411.999684 -25.908)
		(width 0.089408)
		(layer "In2.Cu")
		(net "H_CPU1_MEMKLM_MEMHOT_G_N")
	)
	(segment
		(start 423.240962 -21.135086)
		(end 421.572944 -22.803104)
		(width 0.089408)
		(layer "In2.Cu")
		(net "H_CPU1_MEMKLM_MEMHOT_G_N")
	)
	(segment
		(start 386.834126 -28.05303)
		(end 385.98602 -28.901136)
		(width 0.089408)
		(layer "In2.Cu")
		(net "H_CPU1_MEMKLM_MEMHOT_G_N")
	)
	(segment
		(start 433.216812 -18.792952)
		(end 432.545998 -19.463766)
		(width 0.089408)
		(layer "In2.Cu")
		(net "H_CPU1_MEMKLM_MEMHOT_G_N")
	)
	(segment
		(start 438.270396 -17.969992)
		(end 437.447436 -18.792952)
		(width 0.089408)
		(layer "In2.Cu")
		(net "H_CPU1_MEMKLM_MEMHOT_G_N")
	)
	(segment
		(start 388.396988 -28.3591)
		(end 387.856222 -28.3591)
		(width 0.089408)
		(layer "In2.Cu")
		(net "H_CPU1_MEMKLM_MEMHOT_G_N")
	)
	(segment
		(start 378.05106 -63.370968)
		(end 377.137676 -63.370968)
		(width 0.089408)
		(layer "In2.Cu")
		(net "H_CPU1_MEMKLM_MEMHOT_G_N")
	)
	(segment
		(start 421.366696 -22.803104)
		(end 420.638986 -23.530814)
		(width 0.089408)
		(layer "In2.Cu")
		(net "H_CPU1_MEMKLM_MEMHOT_G_N")
	)
	(segment
		(start 421.572944 -22.803104)
		(end 421.366696 -22.803104)
		(width 0.089408)
		(layer "In2.Cu")
		(net "H_CPU1_MEMKLM_MEMHOT_G_N")
	)
	(segment
		(start 406.894284 -26.34361)
		(end 406.628346 -26.077672)
		(width 0.089408)
		(layer "In2.Cu")
		(net "H_CPU1_MEMKLM_MEMHOT_G_N")
	)
	(segment
		(start 409.391866 -25.908)
		(end 408.956002 -26.343864)
		(width 0.089408)
		(layer "In2.Cu")
		(net "H_CPU1_MEMKLM_MEMHOT_G_N")
	)
	(segment
		(start 438.270396 -17.5895)
		(end 438.270396 -17.969992)
		(width 0.089408)
		(layer "In2.Cu")
		(net "H_CPU1_MEMKLM_MEMHOT_G_N")
	)
	(segment
		(start 380.57201 -40.506904)
		(end 381.110744 -41.045638)
		(width 0.089408)
		(layer "In2.Cu")
		(net "H_CPU1_MEMKLM_MEMHOT_G_N")
	)
	(segment
		(start 333.963264 -74.434192)
		(end 335.19364 -73.203816)
		(width 0.089408)
		(layer "In4.Cu")
		(net "H_CPU1_MEMKLM_MEMHOT_G_N")
	)
	(segment
		(start 264.627868 -156.145738)
		(end 281.375612 -156.145738)
		(width 0.089408)
		(layer "In4.Cu")
		(net "H_CPU1_MEMKLM_MEMHOT_G_N")
	)
	(segment
		(start 331.507592 -84.892388)
		(end 331.507592 -82.367628)
		(width 0.089408)
		(layer "In4.Cu")
		(net "H_CPU1_MEMKLM_MEMHOT_G_N")
	)
	(segment
		(start 337.105752 -73.203816)
		(end 338.806536 -71.503032)
		(width 0.089408)
		(layer "In4.Cu")
		(net "H_CPU1_MEMKLM_MEMHOT_G_N")
	)
	(segment
		(start 367.884964 -66.797936)
		(end 368.7191 -65.9638)
		(width 0.089408)
		(layer "In4.Cu")
		(net "H_CPU1_MEMKLM_MEMHOT_G_N")
	)
	(segment
		(start 353.752912 -70.171056)
		(end 354.329492 -69.594476)
		(width 0.089408)
		(layer "In4.Cu")
		(net "H_CPU1_MEMKLM_MEMHOT_G_N")
	)
	(segment
		(start 358.785668 -70.82282)
		(end 362.650532 -70.82282)
		(width 0.089408)
		(layer "In4.Cu")
		(net "H_CPU1_MEMKLM_MEMHOT_G_N")
	)
	(segment
		(start 333.963264 -79.911956)
		(end 333.963264 -74.434192)
		(width 0.089408)
		(layer "In4.Cu")
		(net "H_CPU1_MEMKLM_MEMHOT_G_N")
	)
	(segment
		(start 327.1139 -126.483618)
		(end 327.1139 -124.379482)
		(width 0.089408)
		(layer "In4.Cu")
		(net "H_CPU1_MEMKLM_MEMHOT_G_N")
	)
	(segment
		(start 366.690148 -66.797682)
		(end 366.690402 -66.797936)
		(width 0.089408)
		(layer "In4.Cu")
		(net "H_CPU1_MEMKLM_MEMHOT_G_N")
	)
	(segment
		(start 335.19364 -73.203816)
		(end 337.105752 -73.203816)
		(width 0.089408)
		(layer "In4.Cu")
		(net "H_CPU1_MEMKLM_MEMHOT_G_N")
	)
	(segment
		(start 330.612496 -129.982214)
		(end 327.1139 -126.483618)
		(width 0.089408)
		(layer "In4.Cu")
		(net "H_CPU1_MEMKLM_MEMHOT_G_N")
	)
	(segment
		(start 354.329492 -69.594476)
		(end 354.329746 -69.594476)
		(width 0.089408)
		(layer "In4.Cu")
		(net "H_CPU1_MEMKLM_MEMHOT_G_N")
	)
	(segment
		(start 338.806536 -71.503032)
		(end 339.245194 -71.503032)
		(width 0.089408)
		(layer "In4.Cu")
		(net "H_CPU1_MEMKLM_MEMHOT_G_N")
	)
	(segment
		(start 325.144384 -137.449814)
		(end 325.144384 -136.861296)
		(width 0.089408)
		(layer "In4.Cu")
		(net "H_CPU1_MEMKLM_MEMHOT_G_N")
	)
	(segment
		(start 329.858116 -132.917184)
		(end 330.612496 -132.162804)
		(width 0.089408)
		(layer "In4.Cu")
		(net "H_CPU1_MEMKLM_MEMHOT_G_N")
	)
	(segment
		(start 321.758564 -156.600398)
		(end 324.17512 -154.183842)
		(width 0.089408)
		(layer "In4.Cu")
		(net "H_CPU1_MEMKLM_MEMHOT_G_N")
	)
	(segment
		(start 366.373664 -66.797682)
		(end 366.690148 -66.797682)
		(width 0.089408)
		(layer "In4.Cu")
		(net "H_CPU1_MEMKLM_MEMHOT_G_N")
	)
	(segment
		(start 325.408036 -118.14429)
		(end 325.408036 -116.138198)
		(width 0.089408)
		(layer "In4.Cu")
		(net "H_CPU1_MEMKLM_MEMHOT_G_N")
	)
	(segment
		(start 323.890894 -138.703304)
		(end 325.144384 -137.449814)
		(width 0.089408)
		(layer "In4.Cu")
		(net "H_CPU1_MEMKLM_MEMHOT_G_N")
	)
	(segment
		(start 362.650532 -70.82282)
		(end 363.64418 -69.829172)
		(width 0.089408)
		(layer "In4.Cu")
		(net "H_CPU1_MEMKLM_MEMHOT_G_N")
	)
	(segment
		(start 324.17512 -147.17776)
		(end 323.890894 -146.893534)
		(width 0.089408)
		(layer "In4.Cu")
		(net "H_CPU1_MEMKLM_MEMHOT_G_N")
	)
	(segment
		(start 339.245194 -71.503032)
		(end 340.037674 -70.710552)
		(width 0.089408)
		(layer "In4.Cu")
		(net "H_CPU1_MEMKLM_MEMHOT_G_N")
	)
	(segment
		(start 354.330762 -69.59346)
		(end 357.556308 -69.59346)
		(width 0.089408)
		(layer "In4.Cu")
		(net "H_CPU1_MEMKLM_MEMHOT_G_N")
	)
	(segment
		(start 346.005658 -69.975984)
		(end 352.509836 -69.975984)
		(width 0.089408)
		(layer "In4.Cu")
		(net "H_CPU1_MEMKLM_MEMHOT_G_N")
	)
	(segment
		(start 264.312146 -156.46146)
		(end 264.627868 -156.145738)
		(width 0.089408)
		(layer "In4.Cu")
		(net "H_CPU1_MEMKLM_MEMHOT_G_N")
	)
	(segment
		(start 281.830272 -156.600398)
		(end 321.758564 -156.600398)
		(width 0.089408)
		(layer "In4.Cu")
		(net "H_CPU1_MEMKLM_MEMHOT_G_N")
	)
	(segment
		(start 363.64418 -69.829172)
		(end 363.64418 -69.527166)
		(width 0.089408)
		(layer "In4.Cu")
		(net "H_CPU1_MEMKLM_MEMHOT_G_N")
	)
	(segment
		(start 325.144384 -136.861296)
		(end 324.636384 -136.353296)
		(width 0.089408)
		(layer "In4.Cu")
		(net "H_CPU1_MEMKLM_MEMHOT_G_N")
	)
	(segment
		(start 331.507592 -82.367628)
		(end 333.963264 -79.911956)
		(width 0.089408)
		(layer "In4.Cu")
		(net "H_CPU1_MEMKLM_MEMHOT_G_N")
	)
	(segment
		(start 352.704908 -70.171056)
		(end 353.752912 -70.171056)
		(width 0.089408)
		(layer "In4.Cu")
		(net "H_CPU1_MEMKLM_MEMHOT_G_N")
	)
	(segment
		(start 340.037674 -70.710552)
		(end 345.27109 -70.710552)
		(width 0.089408)
		(layer "In4.Cu")
		(net "H_CPU1_MEMKLM_MEMHOT_G_N")
	)
	(segment
		(start 326.101202 -132.917184)
		(end 329.858116 -132.917184)
		(width 0.089408)
		(layer "In4.Cu")
		(net "H_CPU1_MEMKLM_MEMHOT_G_N")
	)
	(segment
		(start 354.329746 -69.594476)
		(end 354.330762 -69.59346)
		(width 0.089408)
		(layer "In4.Cu")
		(net "H_CPU1_MEMKLM_MEMHOT_G_N")
	)
	(segment
		(start 352.509836 -69.975984)
		(end 352.704908 -70.171056)
		(width 0.089408)
		(layer "In4.Cu")
		(net "H_CPU1_MEMKLM_MEMHOT_G_N")
	)
	(segment
		(start 324.636384 -134.382002)
		(end 326.101202 -132.917184)
		(width 0.089408)
		(layer "In4.Cu")
		(net "H_CPU1_MEMKLM_MEMHOT_G_N")
	)
	(segment
		(start 325.750682 -123.016264)
		(end 325.750682 -118.486936)
		(width 0.089408)
		(layer "In4.Cu")
		(net "H_CPU1_MEMKLM_MEMHOT_G_N")
	)
	(segment
		(start 194.924172 -156.46146)
		(end 264.312146 -156.46146)
		(width 0.089408)
		(layer "In4.Cu")
		(net "H_CPU1_MEMKLM_MEMHOT_G_N")
	)
	(segment
		(start 324.636384 -136.353296)
		(end 324.636384 -134.382002)
		(width 0.089408)
		(layer "In4.Cu")
		(net "H_CPU1_MEMKLM_MEMHOT_G_N")
	)
	(segment
		(start 330.612496 -132.162804)
		(end 330.612496 -129.982214)
		(width 0.089408)
		(layer "In4.Cu")
		(net "H_CPU1_MEMKLM_MEMHOT_G_N")
	)
	(segment
		(start 192.4431 -153.980388)
		(end 194.924172 -156.46146)
		(width 0.089408)
		(layer "In4.Cu")
		(net "H_CPU1_MEMKLM_MEMHOT_G_N")
	)
	(segment
		(start 324.17512 -154.183842)
		(end 324.17512 -147.17776)
		(width 0.089408)
		(layer "In4.Cu")
		(net "H_CPU1_MEMKLM_MEMHOT_G_N")
	)
	(segment
		(start 324.456298 -115.18646)
		(end 324.456298 -91.943682)
		(width 0.089408)
		(layer "In4.Cu")
		(net "H_CPU1_MEMKLM_MEMHOT_G_N")
	)
	(segment
		(start 368.7191 -65.9638)
		(end 369.316 -65.9638)
		(width 0.089408)
		(layer "In4.Cu")
		(net "H_CPU1_MEMKLM_MEMHOT_G_N")
	)
	(segment
		(start 345.27109 -70.710552)
		(end 346.005658 -69.975984)
		(width 0.089408)
		(layer "In4.Cu")
		(net "H_CPU1_MEMKLM_MEMHOT_G_N")
	)
	(segment
		(start 327.1139 -124.379482)
		(end 325.750682 -123.016264)
		(width 0.089408)
		(layer "In4.Cu")
		(net "H_CPU1_MEMKLM_MEMHOT_G_N")
	)
	(segment
		(start 191.9986 -150.7871)
		(end 192.4431 -151.2316)
		(width 0.089408)
		(layer "In4.Cu")
		(net "H_CPU1_MEMKLM_MEMHOT_G_N")
	)
	(segment
		(start 192.4431 -151.2316)
		(end 192.4431 -153.980388)
		(width 0.089408)
		(layer "In4.Cu")
		(net "H_CPU1_MEMKLM_MEMHOT_G_N")
	)
	(segment
		(start 323.890894 -146.893534)
		(end 323.890894 -138.703304)
		(width 0.089408)
		(layer "In4.Cu")
		(net "H_CPU1_MEMKLM_MEMHOT_G_N")
	)
	(segment
		(start 366.690402 -66.797936)
		(end 367.884964 -66.797936)
		(width 0.089408)
		(layer "In4.Cu")
		(net "H_CPU1_MEMKLM_MEMHOT_G_N")
	)
	(segment
		(start 357.556308 -69.59346)
		(end 358.785668 -70.82282)
		(width 0.089408)
		(layer "In4.Cu")
		(net "H_CPU1_MEMKLM_MEMHOT_G_N")
	)
	(segment
		(start 325.750682 -118.486936)
		(end 325.408036 -118.14429)
		(width 0.089408)
		(layer "In4.Cu")
		(net "H_CPU1_MEMKLM_MEMHOT_G_N")
	)
	(segment
		(start 363.64418 -69.527166)
		(end 366.373664 -66.797682)
		(width 0.089408)
		(layer "In4.Cu")
		(net "H_CPU1_MEMKLM_MEMHOT_G_N")
	)
	(segment
		(start 281.375612 -156.145738)
		(end 281.830272 -156.600398)
		(width 0.089408)
		(layer "In4.Cu")
		(net "H_CPU1_MEMKLM_MEMHOT_G_N")
	)
	(segment
		(start 324.456298 -91.943682)
		(end 331.507592 -84.892388)
		(width 0.089408)
		(layer "In4.Cu")
		(net "H_CPU1_MEMKLM_MEMHOT_G_N")
	)
	(segment
		(start 325.408036 -116.138198)
		(end 324.456298 -115.18646)
		(width 0.089408)
		(layer "In4.Cu")
		(net "H_CPU1_MEMKLM_MEMHOT_G_N")
	)
	(segment
		(start 159.1945 -119.96293)
		(end 162.24377 -123.0122)
		(width 0.089408)
		(layer "In11.Cu")
		(net "H_CPU1_MEMKLM_MEMHOT_G_N")
	)
	(segment
		(start 116.7384 -69.3928)
		(end 117.475 -69.3928)
		(width 0.089408)
		(layer "In11.Cu")
		(net "H_CPU1_MEMKLM_MEMHOT_G_N")
	)
	(segment
		(start 118.6688 -67.7926)
		(end 119.1768 -67.2846)
		(width 0.089408)
		(layer "In11.Cu")
		(net "H_CPU1_MEMKLM_MEMHOT_G_N")
	)
	(segment
		(start 121.2342 -67.2846)
		(end 121.6914 -66.8274)
		(width 0.089408)
		(layer "In11.Cu")
		(net "H_CPU1_MEMKLM_MEMHOT_G_N")
	)
	(segment
		(start 166.243 -142.2654)
		(end 160.5534 -142.2654)
		(width 0.089408)
		(layer "In11.Cu")
		(net "H_CPU1_MEMKLM_MEMHOT_G_N")
	)
	(segment
		(start 116.4336 -69.6976)
		(end 116.7384 -69.3928)
		(width 0.089408)
		(layer "In11.Cu")
		(net "H_CPU1_MEMKLM_MEMHOT_G_N")
	)
	(segment
		(start 191.9986 -149.283928)
		(end 191.927734 -149.213062)
		(width 0.089408)
		(layer "In11.Cu")
		(net "H_CPU1_MEMKLM_MEMHOT_G_N")
	)
	(segment
		(start 191.334644 -147.786598)
		(end 187.087764 -147.786598)
		(width 0.089408)
		(layer "In11.Cu")
		(net "H_CPU1_MEMKLM_MEMHOT_G_N")
	)
	(segment
		(start 156.440378 -119.37238)
		(end 157.030928 -119.96293)
		(width 0.089408)
		(layer "In11.Cu")
		(net "H_CPU1_MEMKLM_MEMHOT_G_N")
	)
	(segment
		(start 159.8168 -141.5288)
		(end 159.8168 -130.201924)
		(width 0.089408)
		(layer "In11.Cu")
		(net "H_CPU1_MEMKLM_MEMHOT_G_N")
	)
	(segment
		(start 157.030928 -119.96293)
		(end 159.1945 -119.96293)
		(width 0.089408)
		(layer "In11.Cu")
		(net "H_CPU1_MEMKLM_MEMHOT_G_N")
	)
	(segment
		(start 127.559816 -65.406016)
		(end 127.905256 -65.751456)
		(width 0.0889)
		(layer "In11.Cu")
		(net "H_CPU1_MEMKLM_MEMHOT_G_N")
	)
	(segment
		(start 129.926588 -91.661488)
		(end 129.959354 -91.661488)
		(width 0.0889)
		(layer "In11.Cu")
		(net "H_CPU1_MEMKLM_MEMHOT_G_N")
	)
	(segment
		(start 159.8168 -130.201924)
		(end 163.882324 -126.1364)
		(width 0.089408)
		(layer "In11.Cu")
		(net "H_CPU1_MEMKLM_MEMHOT_G_N")
	)
	(segment
		(start 120.844056 -86.407244)
		(end 120.847358 -86.413086)
		(width 0.0889)
		(layer "In11.Cu")
		(net "H_CPU1_MEMKLM_MEMHOT_G_N")
	)
	(segment
		(start 129.064258 -91.165934)
		(end 129.097024 -91.165934)
		(width 0.0889)
		(layer "In11.Cu")
		(net "H_CPU1_MEMKLM_MEMHOT_G_N")
	)
	(segment
		(start 131.643628 -92.652088)
		(end 131.661408 -92.652088)
		(width 0.0889)
		(layer "In11.Cu")
		(net "H_CPU1_MEMKLM_MEMHOT_G_N")
	)
	(segment
		(start 124.328936 -66.704464)
		(end 124.822966 -66.210434)
		(width 0.0889)
		(layer "In11.Cu")
		(net "H_CPU1_MEMKLM_MEMHOT_G_N")
	)
	(segment
		(start 119.228108 -85.6742)
		(end 119.7864 -85.6742)
		(width 0.089408)
		(layer "In11.Cu")
		(net "H_CPU1_MEMKLM_MEMHOT_G_N")
	)
	(segment
		(start 120.79224 -67.2846)
		(end 121.2342 -67.2846)
		(width 0.089408)
		(layer "In11.Cu")
		(net "H_CPU1_MEMKLM_MEMHOT_G_N")
	)
	(segment
		(start 191.927734 -149.213062)
		(end 191.927734 -148.379688)
		(width 0.089408)
		(layer "In11.Cu")
		(net "H_CPU1_MEMKLM_MEMHOT_G_N")
	)
	(segment
		(start 138.961622 -96.928178)
		(end 138.961622 -99.947222)
		(width 0.0889)
		(layer "In11.Cu")
		(net "H_CPU1_MEMKLM_MEMHOT_G_N")
	)
	(segment
		(start 116.677694 -71.9582)
		(end 116.677694 -83.123786)
		(width 0.089408)
		(layer "In11.Cu")
		(net "H_CPU1_MEMKLM_MEMHOT_G_N")
	)
	(segment
		(start 160.5534 -142.2654)
		(end 159.8168 -141.5288)
		(width 0.089408)
		(layer "In11.Cu")
		(net "H_CPU1_MEMKLM_MEMHOT_G_N")
	)
	(segment
		(start 138.511534 -96.614488)
		(end 138.5443 -96.614488)
		(width 0.0889)
		(layer "In11.Cu")
		(net "H_CPU1_MEMKLM_MEMHOT_G_N")
	)
	(segment
		(start 127.045974 -65.406016)
		(end 127.559816 -65.406016)
		(width 0.0889)
		(layer "In11.Cu")
		(net "H_CPU1_MEMKLM_MEMHOT_G_N")
	)
	(segment
		(start 119.5832 -67.2846)
		(end 119.993918 -67.695318)
		(width 0.089408)
		(layer "In11.Cu")
		(net "H_CPU1_MEMKLM_MEMHOT_G_N")
	)
	(segment
		(start 118.237 -67.7926)
		(end 118.6688 -67.7926)
		(width 0.089408)
		(layer "In11.Cu")
		(net "H_CPU1_MEMKLM_MEMHOT_G_N")
	)
	(segment
		(start 123.451874 -66.704464)
		(end 124.328936 -66.704464)
		(width 0.0889)
		(layer "In11.Cu")
		(net "H_CPU1_MEMKLM_MEMHOT_G_N")
	)
	(segment
		(start 120.381522 -67.695318)
		(end 120.79224 -67.2846)
		(width 0.089408)
		(layer "In11.Cu")
		(net "H_CPU1_MEMKLM_MEMHOT_G_N")
	)
	(segment
		(start 183.515 -142.7734)
		(end 166.751 -142.7734)
		(width 0.089408)
		(layer "In11.Cu")
		(net "H_CPU1_MEMKLM_MEMHOT_G_N")
	)
	(segment
		(start 132.494782 -93.147134)
		(end 132.53085 -93.147134)
		(width 0.0889)
		(layer "In11.Cu")
		(net "H_CPU1_MEMKLM_MEMHOT_G_N")
	)
	(segment
		(start 121.341388 -86.708488)
		(end 121.374154 -86.708488)
		(width 0.0889)
		(layer "In11.Cu")
		(net "H_CPU1_MEMKLM_MEMHOT_G_N")
	)
	(segment
		(start 116.4336 -70.2056)
		(end 116.036852 -70.602348)
		(width 0.089408)
		(layer "In11.Cu")
		(net "H_CPU1_MEMKLM_MEMHOT_G_N")
	)
	(segment
		(start 137.649204 -96.118934)
		(end 137.68197 -96.118934)
		(width 0.0889)
		(layer "In11.Cu")
		(net "H_CPU1_MEMKLM_MEMHOT_G_N")
	)
	(segment
		(start 126.488698 -65.715388)
		(end 126.521464 -65.715388)
		(width 0.0889)
		(layer "In11.Cu")
		(net "H_CPU1_MEMKLM_MEMHOT_G_N")
	)
	(segment
		(start 119.993918 -67.695318)
		(end 120.381522 -67.695318)
		(width 0.089408)
		(layer "In11.Cu")
		(net "H_CPU1_MEMKLM_MEMHOT_G_N")
	)
	(segment
		(start 116.4336 -70.2056)
		(end 116.4336 -69.6976)
		(width 0.089408)
		(layer "In11.Cu")
		(net "H_CPU1_MEMKLM_MEMHOT_G_N")
	)
	(segment
		(start 162.24377 -123.0122)
		(end 162.8521 -123.0122)
		(width 0.089408)
		(layer "In11.Cu")
		(net "H_CPU1_MEMKLM_MEMHOT_G_N")
	)
	(segment
		(start 128.699514 -65.296034)
		(end 129.225802 -64.769746)
		(width 0.0889)
		(layer "In11.Cu")
		(net "H_CPU1_MEMKLM_MEMHOT_G_N")
	)
	(segment
		(start 128.209548 -90.670888)
		(end 128.242314 -90.670888)
		(width 0.0889)
		(layer "In11.Cu")
		(net "H_CPU1_MEMKLM_MEMHOT_G_N")
	)
	(segment
		(start 119.1768 -67.2846)
		(end 119.5832 -67.2846)
		(width 0.089408)
		(layer "In11.Cu")
		(net "H_CPU1_MEMKLM_MEMHOT_G_N")
	)
	(segment
		(start 124.775468 -88.689688)
		(end 124.808234 -88.689688)
		(width 0.0889)
		(layer "In11.Cu")
		(net "H_CPU1_MEMKLM_MEMHOT_G_N")
	)
	(segment
		(start 117.8052 -68.2244)
		(end 118.237 -67.7926)
		(width 0.089408)
		(layer "In11.Cu")
		(net "H_CPU1_MEMKLM_MEMHOT_G_N")
	)
	(segment
		(start 185.540904 -146.239738)
		(end 185.540904 -144.799304)
		(width 0.089408)
		(layer "In11.Cu")
		(net "H_CPU1_MEMKLM_MEMHOT_G_N")
	)
	(segment
		(start 138.961622 -100.689918)
		(end 155.585922 -117.314218)
		(width 0.089408)
		(layer "In11.Cu")
		(net "H_CPU1_MEMKLM_MEMHOT_G_N")
	)
	(segment
		(start 125.630178 -89.184734)
		(end 125.662944 -89.184734)
		(width 0.0889)
		(layer "In11.Cu")
		(net "H_CPU1_MEMKLM_MEMHOT_G_N")
	)
	(segment
		(start 127.905256 -65.751456)
		(end 128.398524 -65.751456)
		(width 0.0889)
		(layer "In11.Cu")
		(net "H_CPU1_MEMKLM_MEMHOT_G_N")
	)
	(segment
		(start 122.49531 -67.19951)
		(end 122.956828 -67.19951)
		(width 0.0889)
		(layer "In11.Cu")
		(net "H_CPU1_MEMKLM_MEMHOT_G_N")
	)
	(segment
		(start 128.398524 -65.751456)
		(end 128.590294 -65.559686)
		(width 0.0889)
		(layer "In11.Cu")
		(net "H_CPU1_MEMKLM_MEMHOT_G_N")
	)
	(segment
		(start 185.540904 -144.799304)
		(end 183.515 -142.7734)
		(width 0.089408)
		(layer "In11.Cu")
		(net "H_CPU1_MEMKLM_MEMHOT_G_N")
	)
	(segment
		(start 123.913138 -88.194134)
		(end 123.945904 -88.194134)
		(width 0.0889)
		(layer "In11.Cu")
		(net "H_CPU1_MEMKLM_MEMHOT_G_N")
	)
	(segment
		(start 132.004562 -92.846398)
		(end 132.007864 -92.85224)
		(width 0.0889)
		(layer "In11.Cu")
		(net "H_CPU1_MEMKLM_MEMHOT_G_N")
	)
	(segment
		(start 138.961622 -99.947222)
		(end 138.961622 -100.689918)
		(width 0.089408)
		(layer "In11.Cu")
		(net "H_CPU1_MEMKLM_MEMHOT_G_N")
	)
	(segment
		(start 132.004562 -64.530478)
		(end 132.007864 -64.524636)
		(width 0.0889)
		(layer "In11.Cu")
		(net "H_CPU1_MEMKLM_MEMHOT_G_N")
	)
	(segment
		(start 121.6914 -66.8274)
		(end 122.1232 -66.8274)
		(width 0.089408)
		(layer "In11.Cu")
		(net "H_CPU1_MEMKLM_MEMHOT_G_N")
	)
	(segment
		(start 155.585922 -117.314218)
		(end 155.86964 -117.314218)
		(width 0.089408)
		(layer "In11.Cu")
		(net "H_CPU1_MEMKLM_MEMHOT_G_N")
	)
	(segment
		(start 163.882324 -126.1364)
		(end 166.0652 -126.1364)
		(width 0.089408)
		(layer "In11.Cu")
		(net "H_CPU1_MEMKLM_MEMHOT_G_N")
	)
	(segment
		(start 129.225802 -64.769746)
		(end 129.935224 -64.769746)
		(width 0.0889)
		(layer "In11.Cu")
		(net "H_CPU1_MEMKLM_MEMHOT_G_N")
	)
	(segment
		(start 191.927734 -148.379688)
		(end 191.334644 -147.786598)
		(width 0.089408)
		(layer "In11.Cu")
		(net "H_CPU1_MEMKLM_MEMHOT_G_N")
	)
	(segment
		(start 130.781298 -92.156534)
		(end 130.814064 -92.156534)
		(width 0.0889)
		(layer "In11.Cu")
		(net "H_CPU1_MEMKLM_MEMHOT_G_N")
	)
	(segment
		(start 124.822966 -66.210434)
		(end 125.666754 -66.210434)
		(width 0.0889)
		(layer "In11.Cu")
		(net "H_CPU1_MEMKLM_MEMHOT_G_N")
	)
	(segment
		(start 120.479312 -86.212934)
		(end 120.500902 -86.212934)
		(width 0.0889)
		(layer "In11.Cu")
		(net "H_CPU1_MEMKLM_MEMHOT_G_N")
	)
	(segment
		(start 122.196098 -87.203534)
		(end 122.228864 -87.203534)
		(width 0.0889)
		(layer "In11.Cu")
		(net "H_CPU1_MEMKLM_MEMHOT_G_N")
	)
	(segment
		(start 126.492508 -89.680288)
		(end 126.525274 -89.680288)
		(width 0.0889)
		(layer "In11.Cu")
		(net "H_CPU1_MEMKLM_MEMHOT_G_N")
	)
	(segment
		(start 134.22376 -94.137988)
		(end 134.24789 -94.137988)
		(width 0.0889)
		(layer "In11.Cu")
		(net "H_CPU1_MEMKLM_MEMHOT_G_N")
	)
	(segment
		(start 187.087764 -147.786598)
		(end 185.540904 -146.239738)
		(width 0.089408)
		(layer "In11.Cu")
		(net "H_CPU1_MEMKLM_MEMHOT_G_N")
	)
	(segment
		(start 122.956828 -67.19951)
		(end 123.451874 -66.704464)
		(width 0.0889)
		(layer "In11.Cu")
		(net "H_CPU1_MEMKLM_MEMHOT_G_N")
	)
	(segment
		(start 117.8052 -69.0626)
		(end 117.8052 -68.2244)
		(width 0.089408)
		(layer "In11.Cu")
		(net "H_CPU1_MEMKLM_MEMHOT_G_N")
	)
	(segment
		(start 133.360414 -93.642688)
		(end 133.39318 -93.642688)
		(width 0.0889)
		(layer "In11.Cu")
		(net "H_CPU1_MEMKLM_MEMHOT_G_N")
	)
	(segment
		(start 119.7864 -85.6742)
		(end 119.9134 -85.8012)
		(width 0.089408)
		(layer "In11.Cu")
		(net "H_CPU1_MEMKLM_MEMHOT_G_N")
	)
	(segment
		(start 117.475 -69.3928)
		(end 117.8052 -69.0626)
		(width 0.089408)
		(layer "In11.Cu")
		(net "H_CPU1_MEMKLM_MEMHOT_G_N")
	)
	(segment
		(start 123.058428 -87.699088)
		(end 123.091194 -87.699088)
		(width 0.0889)
		(layer "In11.Cu")
		(net "H_CPU1_MEMKLM_MEMHOT_G_N")
	)
	(segment
		(start 119.9134 -85.8012)
		(end 120.024906 -85.972904)
		(width 0.0889)
		(layer "In11.Cu")
		(net "H_CPU1_MEMKLM_MEMHOT_G_N")
	)
	(segment
		(start 191.9986 -150.7871)
		(end 191.9986 -149.283928)
		(width 0.089408)
		(layer "In11.Cu")
		(net "H_CPU1_MEMKLM_MEMHOT_G_N")
	)
	(segment
		(start 136.79932 -95.623888)
		(end 136.82726 -95.623888)
		(width 0.0889)
		(layer "In11.Cu")
		(net "H_CPU1_MEMKLM_MEMHOT_G_N")
	)
	(segment
		(start 122.1232 -66.8274)
		(end 122.49531 -67.19951)
		(width 0.089408)
		(layer "In11.Cu")
		(net "H_CPU1_MEMKLM_MEMHOT_G_N")
	)
	(segment
		(start 135.935974 -95.128588)
		(end 135.971788 -95.128588)
		(width 0.0889)
		(layer "In11.Cu")
		(net "H_CPU1_MEMKLM_MEMHOT_G_N")
	)
	(segment
		(start 116.036852 -70.602348)
		(end 116.036852 -71.317358)
		(width 0.089408)
		(layer "In11.Cu")
		(net "H_CPU1_MEMKLM_MEMHOT_G_N")
	)
	(segment
		(start 116.036852 -71.317358)
		(end 116.677694 -71.9582)
		(width 0.089408)
		(layer "In11.Cu")
		(net "H_CPU1_MEMKLM_MEMHOT_G_N")
	)
	(segment
		(start 156.440378 -117.884956)
		(end 156.440378 -119.37238)
		(width 0.089408)
		(layer "In11.Cu")
		(net "H_CPU1_MEMKLM_MEMHOT_G_N")
	)
	(segment
		(start 128.590294 -65.559686)
		(end 128.699514 -65.296034)
		(width 0.0889)
		(layer "In11.Cu")
		(net "H_CPU1_MEMKLM_MEMHOT_G_N")
	)
	(segment
		(start 116.677694 -83.123786)
		(end 119.228108 -85.6742)
		(width 0.089408)
		(layer "In11.Cu")
		(net "H_CPU1_MEMKLM_MEMHOT_G_N")
	)
	(segment
		(start 155.86964 -117.314218)
		(end 156.440378 -117.884956)
		(width 0.089408)
		(layer "In11.Cu")
		(net "H_CPU1_MEMKLM_MEMHOT_G_N")
	)
	(segment
		(start 135.073644 -94.633288)
		(end 135.113268 -94.633288)
		(width 0.0889)
		(layer "In11.Cu")
		(net "H_CPU1_MEMKLM_MEMHOT_G_N")
	)
	(segment
		(start 166.751 -142.7734)
		(end 166.243 -142.2654)
		(width 0.089408)
		(layer "In11.Cu")
		(net "H_CPU1_MEMKLM_MEMHOT_G_N")
	)
	(segment
		(start 127.347218 -90.175334)
		(end 127.379984 -90.175334)
		(width 0.0889)
		(layer "In11.Cu")
		(net "H_CPU1_MEMKLM_MEMHOT_G_N")
	)
	(arc
		(start 136.300464 -95.328486)
		(mid 136.511177 -95.541565)
		(end 136.79932 -95.623888)
		(width 0.0889)
		(layer "In11.Cu")
		(net "H_CPU1_MEMKLM_MEMHOT_G_N")
	)
	(arc
		(start 121.374154 -86.708488)
		(mid 121.565796 -86.765654)
		(end 121.705878 -86.908386)
		(width 0.0889)
		(layer "In11.Cu")
		(net "H_CPU1_MEMKLM_MEMHOT_G_N")
	)
	(arc
		(start 129.959354 -91.661488)
		(mid 130.150996 -91.718654)
		(end 130.291078 -91.861386)
		(width 0.0889)
		(layer "In11.Cu")
		(net "H_CPU1_MEMKLM_MEMHOT_G_N")
	)
	(arc
		(start 120.500902 -86.212934)
		(mid 120.698063 -86.264893)
		(end 120.844056 -86.407244)
		(width 0.0889)
		(layer "In11.Cu")
		(net "H_CPU1_MEMKLM_MEMHOT_G_N")
	)
	(arc
		(start 130.291078 -91.861386)
		(mid 130.498082 -92.07225)
		(end 130.781298 -92.156534)
		(width 0.0889)
		(layer "In11.Cu")
		(net "H_CPU1_MEMKLM_MEMHOT_G_N")
	)
	(arc
		(start 132.53085 -93.147134)
		(mid 132.7247 -93.203484)
		(end 132.866384 -93.347286)
		(width 0.0889)
		(layer "In11.Cu")
		(net "H_CPU1_MEMKLM_MEMHOT_G_N")
	)
	(arc
		(start 135.113268 -94.633288)
		(mid 135.303197 -94.691158)
		(end 135.441944 -94.833186)
		(width 0.0889)
		(layer "In11.Cu")
		(net "H_CPU1_MEMKLM_MEMHOT_G_N")
	)
	(arc
		(start 125.666754 -66.210434)
		(mid 125.858396 -66.153268)
		(end 125.998478 -66.010536)
		(width 0.0889)
		(layer "In11.Cu")
		(net "H_CPU1_MEMKLM_MEMHOT_G_N")
	)
	(arc
		(start 131.314698 -64.524636)
		(mid 131.657988 -64.724932)
		(end 132.004562 -64.530478)
		(width 0.0889)
		(layer "In11.Cu")
		(net "H_CPU1_MEMKLM_MEMHOT_G_N")
	)
	(arc
		(start 132.007864 -92.85224)
		(mid 132.213485 -93.062163)
		(end 132.494782 -93.147134)
		(width 0.0889)
		(layer "In11.Cu")
		(net "H_CPU1_MEMKLM_MEMHOT_G_N")
	)
	(arc
		(start 129.432558 -91.366086)
		(mid 129.641166 -91.578018)
		(end 129.926588 -91.661488)
		(width 0.0889)
		(layer "In11.Cu")
		(net "H_CPU1_MEMKLM_MEMHOT_G_N")
	)
	(arc
		(start 137.68197 -96.118934)
		(mid 137.87582 -96.175284)
		(end 138.017504 -96.319086)
		(width 0.0889)
		(layer "In11.Cu")
		(net "H_CPU1_MEMKLM_MEMHOT_G_N")
	)
	(arc
		(start 126.521464 -65.715388)
		(mid 126.715314 -65.659038)
		(end 126.856998 -65.515236)
		(width 0.0889)
		(layer "In11.Cu")
		(net "H_CPU1_MEMKLM_MEMHOT_G_N")
	)
	(arc
		(start 127.715518 -90.375486)
		(mid 127.924126 -90.587418)
		(end 128.209548 -90.670888)
		(width 0.0889)
		(layer "In11.Cu")
		(net "H_CPU1_MEMKLM_MEMHOT_G_N")
	)
	(arc
		(start 121.705878 -86.908386)
		(mid 121.912882 -87.11925)
		(end 122.196098 -87.203534)
		(width 0.0889)
		(layer "In11.Cu")
		(net "H_CPU1_MEMKLM_MEMHOT_G_N")
	)
	(arc
		(start 120.847358 -86.413086)
		(mid 121.055966 -86.625018)
		(end 121.341388 -86.708488)
		(width 0.0889)
		(layer "In11.Cu")
		(net "H_CPU1_MEMKLM_MEMHOT_G_N")
	)
	(arc
		(start 131.661408 -92.652088)
		(mid 131.858569 -92.704047)
		(end 132.004562 -92.846398)
		(width 0.0889)
		(layer "In11.Cu")
		(net "H_CPU1_MEMKLM_MEMHOT_G_N")
	)
	(arc
		(start 136.82726 -95.623888)
		(mid 137.018902 -95.681054)
		(end 137.158984 -95.823786)
		(width 0.0889)
		(layer "In11.Cu")
		(net "H_CPU1_MEMKLM_MEMHOT_G_N")
	)
	(arc
		(start 126.525274 -89.680288)
		(mid 126.716916 -89.737454)
		(end 126.856998 -89.880186)
		(width 0.0889)
		(layer "In11.Cu")
		(net "H_CPU1_MEMKLM_MEMHOT_G_N")
	)
	(arc
		(start 137.158984 -95.823786)
		(mid 137.365988 -96.03465)
		(end 137.649204 -96.118934)
		(width 0.0889)
		(layer "In11.Cu")
		(net "H_CPU1_MEMKLM_MEMHOT_G_N")
	)
	(arc
		(start 132.007864 -64.524636)
		(mid 132.242878 -64.161535)
		(end 132.519674 -63.829184)
		(width 0.0889)
		(layer "In11.Cu")
		(net "H_CPU1_MEMKLM_MEMHOT_G_N")
	)
	(arc
		(start 124.281438 -88.394286)
		(mid 124.490046 -88.606218)
		(end 124.775468 -88.689688)
		(width 0.0889)
		(layer "In11.Cu")
		(net "H_CPU1_MEMKLM_MEMHOT_G_N")
	)
	(arc
		(start 122.564398 -87.403686)
		(mid 122.773006 -87.615618)
		(end 123.058428 -87.699088)
		(width 0.0889)
		(layer "In11.Cu")
		(net "H_CPU1_MEMKLM_MEMHOT_G_N")
	)
	(arc
		(start 138.876024 -96.814386)
		(mid 138.915378 -96.873874)
		(end 138.961622 -96.928178)
		(width 0.0889)
		(layer "In11.Cu")
		(net "H_CPU1_MEMKLM_MEMHOT_G_N")
	)
	(arc
		(start 135.441944 -94.833186)
		(mid 135.650552 -95.045118)
		(end 135.935974 -95.128588)
		(width 0.0889)
		(layer "In11.Cu")
		(net "H_CPU1_MEMKLM_MEMHOT_G_N")
	)
	(arc
		(start 125.998478 -66.010536)
		(mid 126.205482 -65.799672)
		(end 126.488698 -65.715388)
		(width 0.0889)
		(layer "In11.Cu")
		(net "H_CPU1_MEMKLM_MEMHOT_G_N")
	)
	(arc
		(start 129.935224 -64.769746)
		(mid 130.140838 -64.687385)
		(end 130.291078 -64.524636)
		(width 0.0889)
		(layer "In11.Cu")
		(net "H_CPU1_MEMKLM_MEMHOT_G_N")
	)
	(arc
		(start 127.379984 -90.175334)
		(mid 127.573834 -90.231684)
		(end 127.715518 -90.375486)
		(width 0.0889)
		(layer "In11.Cu")
		(net "H_CPU1_MEMKLM_MEMHOT_G_N")
	)
	(arc
		(start 126.856998 -89.880186)
		(mid 127.064002 -90.09105)
		(end 127.347218 -90.175334)
		(width 0.0889)
		(layer "In11.Cu")
		(net "H_CPU1_MEMKLM_MEMHOT_G_N")
	)
	(arc
		(start 131.149598 -92.356686)
		(mid 131.358206 -92.568618)
		(end 131.643628 -92.652088)
		(width 0.0889)
		(layer "In11.Cu")
		(net "H_CPU1_MEMKLM_MEMHOT_G_N")
	)
	(arc
		(start 126.856998 -65.515236)
		(mid 126.936851 -65.435316)
		(end 127.045974 -65.406016)
		(width 0.0889)
		(layer "In11.Cu")
		(net "H_CPU1_MEMKLM_MEMHOT_G_N")
	)
	(arc
		(start 133.724904 -93.842586)
		(mid 133.935617 -94.055665)
		(end 134.22376 -94.137988)
		(width 0.0889)
		(layer "In11.Cu")
		(net "H_CPU1_MEMKLM_MEMHOT_G_N")
	)
	(arc
		(start 134.24789 -94.137988)
		(mid 134.44174 -94.194338)
		(end 134.583424 -94.33814)
		(width 0.0889)
		(layer "In11.Cu")
		(net "H_CPU1_MEMKLM_MEMHOT_G_N")
	)
	(arc
		(start 125.662944 -89.184734)
		(mid 125.856794 -89.241084)
		(end 125.998478 -89.384886)
		(width 0.0889)
		(layer "In11.Cu")
		(net "H_CPU1_MEMKLM_MEMHOT_G_N")
	)
	(arc
		(start 125.139958 -88.889586)
		(mid 125.346962 -89.10045)
		(end 125.630178 -89.184734)
		(width 0.0889)
		(layer "In11.Cu")
		(net "H_CPU1_MEMKLM_MEMHOT_G_N")
	)
	(arc
		(start 123.945904 -88.194134)
		(mid 124.139754 -88.250484)
		(end 124.281438 -88.394286)
		(width 0.0889)
		(layer "In11.Cu")
		(net "H_CPU1_MEMKLM_MEMHOT_G_N")
	)
	(arc
		(start 135.971788 -95.128588)
		(mid 136.161717 -95.186458)
		(end 136.300464 -95.328486)
		(width 0.0889)
		(layer "In11.Cu")
		(net "H_CPU1_MEMKLM_MEMHOT_G_N")
	)
	(arc
		(start 128.242314 -90.670888)
		(mid 128.433956 -90.728054)
		(end 128.574038 -90.870786)
		(width 0.0889)
		(layer "In11.Cu")
		(net "H_CPU1_MEMKLM_MEMHOT_G_N")
	)
	(arc
		(start 138.5443 -96.614488)
		(mid 138.735942 -96.671654)
		(end 138.876024 -96.814386)
		(width 0.0889)
		(layer "In11.Cu")
		(net "H_CPU1_MEMKLM_MEMHOT_G_N")
	)
	(arc
		(start 129.097024 -91.165934)
		(mid 129.290874 -91.222284)
		(end 129.432558 -91.366086)
		(width 0.0889)
		(layer "In11.Cu")
		(net "H_CPU1_MEMKLM_MEMHOT_G_N")
	)
	(arc
		(start 132.866384 -93.347286)
		(mid 133.074992 -93.559218)
		(end 133.360414 -93.642688)
		(width 0.0889)
		(layer "In11.Cu")
		(net "H_CPU1_MEMKLM_MEMHOT_G_N")
	)
	(arc
		(start 123.091194 -87.699088)
		(mid 123.282836 -87.756254)
		(end 123.422918 -87.898986)
		(width 0.0889)
		(layer "In11.Cu")
		(net "H_CPU1_MEMKLM_MEMHOT_G_N")
	)
	(arc
		(start 125.998478 -89.384886)
		(mid 126.207086 -89.596818)
		(end 126.492508 -89.680288)
		(width 0.0889)
		(layer "In11.Cu")
		(net "H_CPU1_MEMKLM_MEMHOT_G_N")
	)
	(arc
		(start 130.814064 -92.156534)
		(mid 131.007914 -92.212884)
		(end 131.149598 -92.356686)
		(width 0.0889)
		(layer "In11.Cu")
		(net "H_CPU1_MEMKLM_MEMHOT_G_N")
	)
	(arc
		(start 134.583424 -94.33814)
		(mid 134.790428 -94.549004)
		(end 135.073644 -94.633288)
		(width 0.0889)
		(layer "In11.Cu")
		(net "H_CPU1_MEMKLM_MEMHOT_G_N")
	)
	(arc
		(start 120.024906 -85.972904)
		(mid 120.224651 -86.144898)
		(end 120.479312 -86.212934)
		(width 0.0889)
		(layer "In11.Cu")
		(net "H_CPU1_MEMKLM_MEMHOT_G_N")
	)
	(arc
		(start 133.39318 -93.642688)
		(mid 133.584822 -93.699854)
		(end 133.724904 -93.842586)
		(width 0.0889)
		(layer "In11.Cu")
		(net "H_CPU1_MEMKLM_MEMHOT_G_N")
	)
	(arc
		(start 128.574038 -90.870786)
		(mid 128.781042 -91.08165)
		(end 129.064258 -91.165934)
		(width 0.0889)
		(layer "In11.Cu")
		(net "H_CPU1_MEMKLM_MEMHOT_G_N")
	)
	(arc
		(start 124.808234 -88.689688)
		(mid 124.999876 -88.746854)
		(end 125.139958 -88.889586)
		(width 0.0889)
		(layer "In11.Cu")
		(net "H_CPU1_MEMKLM_MEMHOT_G_N")
	)
	(arc
		(start 130.291078 -64.524636)
		(mid 130.802888 -64.228969)
		(end 131.314698 -64.524636)
		(width 0.0889)
		(layer "In11.Cu")
		(net "H_CPU1_MEMKLM_MEMHOT_G_N")
	)
	(arc
		(start 122.228864 -87.203534)
		(mid 122.422714 -87.259884)
		(end 122.564398 -87.403686)
		(width 0.0889)
		(layer "In11.Cu")
		(net "H_CPU1_MEMKLM_MEMHOT_G_N")
	)
	(arc
		(start 138.017504 -96.319086)
		(mid 138.226112 -96.531018)
		(end 138.511534 -96.614488)
		(width 0.0889)
		(layer "In11.Cu")
		(net "H_CPU1_MEMKLM_MEMHOT_G_N")
	)
	(arc
		(start 123.422918 -87.898986)
		(mid 123.629922 -88.10985)
		(end 123.913138 -88.194134)
		(width 0.0889)
		(layer "In11.Cu")
		(net "H_CPU1_MEMKLM_MEMHOT_G_N")
	)
	(segment
		(start 172.6438 -124.3076)
		(end 172.85335 -124.51715)
		(width 0.10795)
		(layer "F.Cu")
		(net "H_CPU1_MEMKLM_MEMHOT")
	)
	(segment
		(start 173.6598 -124.3076)
		(end 172.6438 -124.3076)
		(width 0.10795)
		(layer "F.Cu")
		(net "H_CPU1_MEMKLM_MEMHOT")
	)
	(segment
		(start 173.8757 -124.5235)
		(end 173.6598 -124.3076)
		(width 0.10795)
		(layer "F.Cu")
		(net "H_CPU1_MEMKLM_MEMHOT")
	)
	(segment
		(start 173.22546 -124.69876)
		(end 173.22546 -125.21438)
		(width 0.10795)
		(layer "F.Cu")
		(net "H_CPU1_MEMKLM_MEMHOT")
	)
	(segment
		(start 173.04385 -124.51715)
		(end 173.22546 -124.69876)
		(width 0.10795)
		(layer "F.Cu")
		(net "H_CPU1_MEMKLM_MEMHOT")
	)
	(segment
		(start 173.8757 -125.21438)
		(end 173.8757 -124.5235)
		(width 0.10795)
		(layer "F.Cu")
		(net "H_CPU1_MEMKLM_MEMHOT")
	)
	(segment
		(start 172.85335 -124.51715)
		(end 173.04385 -124.51715)
		(width 0.10795)
		(layer "F.Cu")
		(net "H_CPU1_MEMKLM_MEMHOT")
	)
	(via
		(at 172.6438 -124.3076)
		(size 0.508)
		(drill 0.254)
		(layers "F.Cu" "B.Cu")
		(net "H_CPU1_MEMKLM_MEMHOT")
	)
	(segment
		(start 172.847 -124.5108)
		(end 172.847 -125.222)
		(width 0.10795)
		(layer "B.Cu")
		(net "H_CPU1_MEMKLM_MEMHOT")
	)
	(segment
		(start 172.6438 -124.3076)
		(end 172.847 -124.5108)
		(width 0.10795)
		(layer "B.Cu")
		(net "H_CPU1_MEMKLM_MEMHOT")
	)
	(segment
		(start 166.4462 -124.5235)
		(end 166.6367 -124.333)
		(width 0.10795)
		(layer "F.Cu")
		(net "H_CPU1_MEMGHJ_MEMHOT_G_N")
	)
	(segment
		(start 438.4675 -15.367)
		(end 437.7055 -15.367)
		(width 0.10795)
		(layer "F.Cu")
		(net "H_CPU1_MEMGHJ_MEMHOT_G_N")
	)
	(segment
		(start 439.039 -14.3256)
		(end 438.7596 -14.605)
		(width 0.10795)
		(layer "F.Cu")
		(net "H_CPU1_MEMGHJ_MEMHOT_G_N")
	)
	(segment
		(start 438.7596 -14.605)
		(end 437.7055 -14.605)
		(width 0.10795)
		(layer "F.Cu")
		(net "H_CPU1_MEMGHJ_MEMHOT_G_N")
	)
	(segment
		(start 437.7055 -15.367)
		(end 437.7055 -14.605)
		(width 0.10795)
		(layer "F.Cu")
		(net "H_CPU1_MEMGHJ_MEMHOT_G_N")
	)
	(segment
		(start 165.66642 -124.5235)
		(end 166.4462 -124.5235)
		(width 0.10795)
		(layer "F.Cu")
		(net "H_CPU1_MEMGHJ_MEMHOT_G_N")
	)
	(segment
		(start 131.948174 -64.819784)
		(end 132.519674 -64.819784)
		(width 0.1016)
		(layer "F.Cu")
		(net "H_CPU1_MEMGHJ_MEMHOT_G_N")
	)
	(segment
		(start 440.2836 -14.3256)
		(end 439.039 -14.3256)
		(width 0.10795)
		(layer "F.Cu")
		(net "H_CPU1_MEMGHJ_MEMHOT_G_N")
	)
	(segment
		(start 440.7281 -14.7701)
		(end 440.2836 -14.3256)
		(width 0.10795)
		(layer "F.Cu")
		(net "H_CPU1_MEMGHJ_MEMHOT_G_N")
	)
	(via
		(at 166.6367 -124.333)
		(size 0.508)
		(drill 0.254)
		(layers "F.Cu" "B.Cu")
		(net "H_CPU1_MEMGHJ_MEMHOT_G_N")
	)
	(via
		(at 408.626056 -81.89976)
		(size 0.508)
		(drill 0.254)
		(layers "F.Cu" "B.Cu")
		(net "H_CPU1_MEMGHJ_MEMHOT_G_N")
	)
	(via
		(at 463.35696 -21.25472)
		(size 0.508)
		(drill 0.254)
		(layers "F.Cu" "B.Cu")
		(net "H_CPU1_MEMGHJ_MEMHOT_G_N")
	)
	(via
		(at 408.6479 -87.33409)
		(size 0.508)
		(drill 0.254)
		(layers "F.Cu" "B.Cu")
		(net "H_CPU1_MEMGHJ_MEMHOT_G_N")
	)
	(via
		(at 117.772434 -81.124044)
		(size 0.508)
		(drill 0.254)
		(layers "F.Cu" "B.Cu")
		(net "H_CPU1_MEMGHJ_MEMHOT_G_N")
	)
	(via
		(at 334.2894 -138.0236)
		(size 0.508)
		(drill 0.254)
		(layers "F.Cu" "B.Cu")
		(net "H_CPU1_MEMGHJ_MEMHOT_G_N")
	)
	(via
		(at 132.519674 -64.819784)
		(size 0.508)
		(drill 0.254)
		(layers "F.Cu" "B.Cu")
		(net "H_CPU1_MEMGHJ_MEMHOT_G_N")
	)
	(via
		(at 440.7281 -14.7701)
		(size 0.508)
		(drill 0.254)
		(layers "F.Cu" "B.Cu")
		(net "H_CPU1_MEMGHJ_MEMHOT_G_N")
	)
	(segment
		(start 408.6479 -87.33409)
		(end 408.270202 -87.711788)
		(width 0.10795)
		(layer "B.Cu")
		(net "H_CPU1_MEMGHJ_MEMHOT_G_N")
	)
	(segment
		(start 117.412516 -81.483962)
		(end 117.094 -81.483962)
		(width 0.10795)
		(layer "B.Cu")
		(net "H_CPU1_MEMGHJ_MEMHOT_G_N")
	)
	(segment
		(start 117.772434 -81.124044)
		(end 117.412516 -81.483962)
		(width 0.10795)
		(layer "B.Cu")
		(net "H_CPU1_MEMGHJ_MEMHOT_G_N")
	)
	(segment
		(start 408.378152 -88.94445)
		(end 409.050236 -88.94445)
		(width 0.10795)
		(layer "B.Cu")
		(net "H_CPU1_MEMGHJ_MEMHOT_G_N")
	)
	(segment
		(start 408.270202 -87.711788)
		(end 408.270202 -88.8365)
		(width 0.10795)
		(layer "B.Cu")
		(net "H_CPU1_MEMGHJ_MEMHOT_G_N")
	)
	(segment
		(start 409.050236 -88.94445)
		(end 409.168092 -88.826594)
		(width 0.10795)
		(layer "B.Cu")
		(net "H_CPU1_MEMGHJ_MEMHOT_G_N")
	)
	(segment
		(start 409.168092 -88.826594)
		(end 409.884118 -88.826594)
		(width 0.10795)
		(layer "B.Cu")
		(net "H_CPU1_MEMGHJ_MEMHOT_G_N")
	)
	(segment
		(start 408.270202 -88.8365)
		(end 408.378152 -88.94445)
		(width 0.10795)
		(layer "B.Cu")
		(net "H_CPU1_MEMGHJ_MEMHOT_G_N")
	)
	(segment
		(start 408.329384 -87.015574)
		(end 408.329384 -82.277966)
		(width 0.089408)
		(layer "In2.Cu")
		(net "H_CPU1_MEMGHJ_MEMHOT_G_N")
	)
	(segment
		(start 408.626056 -81.981294)
		(end 408.626056 -81.89976)
		(width 0.089408)
		(layer "In2.Cu")
		(net "H_CPU1_MEMGHJ_MEMHOT_G_N")
	)
	(segment
		(start 408.6479 -87.33409)
		(end 408.329384 -87.015574)
		(width 0.089408)
		(layer "In2.Cu")
		(net "H_CPU1_MEMGHJ_MEMHOT_G_N")
	)
	(segment
		(start 408.329384 -82.277966)
		(end 408.626056 -81.981294)
		(width 0.089408)
		(layer "In2.Cu")
		(net "H_CPU1_MEMGHJ_MEMHOT_G_N")
	)
	(segment
		(start 387.340856 -84.279994)
		(end 388.113778 -84.279994)
		(width 0.089408)
		(layer "In4.Cu")
		(net "H_CPU1_MEMGHJ_MEMHOT_G_N")
	)
	(segment
		(start 393.851638 -81.757266)
		(end 394.183362 -81.757266)
		(width 0.089408)
		(layer "In4.Cu")
		(net "H_CPU1_MEMGHJ_MEMHOT_G_N")
	)
	(segment
		(start 343.788492 -73.494646)
		(end 345.206066 -73.494646)
		(width 0.089408)
		(layer "In4.Cu")
		(net "H_CPU1_MEMGHJ_MEMHOT_G_N")
	)
	(segment
		(start 394.183362 -81.757266)
		(end 394.489432 -81.451196)
		(width 0.089408)
		(layer "In4.Cu")
		(net "H_CPU1_MEMGHJ_MEMHOT_G_N")
	)
	(segment
		(start 392.61288 -81.787492)
		(end 392.975846 -81.424526)
		(width 0.089408)
		(layer "In4.Cu")
		(net "H_CPU1_MEMGHJ_MEMHOT_G_N")
	)
	(segment
		(start 448.418204 -14.18336)
		(end 441.31484 -14.18336)
		(width 0.089408)
		(layer "In4.Cu")
		(net "H_CPU1_MEMGHJ_MEMHOT_G_N")
	)
	(segment
		(start 386.652262 -83.5914)
		(end 387.340856 -84.279994)
		(width 0.089408)
		(layer "In4.Cu")
		(net "H_CPU1_MEMGHJ_MEMHOT_G_N")
	)
	(segment
		(start 364.946438 -74.775822)
		(end 364.946438 -78.409038)
		(width 0.089408)
		(layer "In4.Cu")
		(net "H_CPU1_MEMGHJ_MEMHOT_G_N")
	)
	(segment
		(start 334.090264 -136.79932)
		(end 334.211168 -136.678416)
		(width 0.089408)
		(layer "In4.Cu")
		(net "H_CPU1_MEMGHJ_MEMHOT_G_N")
	)
	(segment
		(start 407.10993 -81.74355)
		(end 408.469846 -81.74355)
		(width 0.089408)
		(layer "In4.Cu")
		(net "H_CPU1_MEMGHJ_MEMHOT_G_N")
	)
	(segment
		(start 334.2894 -138.0236)
		(end 334.090264 -137.824464)
		(width 0.089408)
		(layer "In4.Cu")
		(net "H_CPU1_MEMGHJ_MEMHOT_G_N")
	)
	(segment
		(start 388.742428 -83.651344)
		(end 389.618728 -83.651344)
		(width 0.089408)
		(layer "In4.Cu")
		(net "H_CPU1_MEMGHJ_MEMHOT_G_N")
	)
	(segment
		(start 362.763562 -72.592946)
		(end 364.946438 -74.775822)
		(width 0.089408)
		(layer "In4.Cu")
		(net "H_CPU1_MEMGHJ_MEMHOT_G_N")
	)
	(segment
		(start 403.18182 -80.531716)
		(end 405.898096 -80.531716)
		(width 0.089408)
		(layer "In4.Cu")
		(net "H_CPU1_MEMGHJ_MEMHOT_G_N")
	)
	(segment
		(start 329.720956 -112.291114)
		(end 328.841862 -111.41202)
		(width 0.089408)
		(layer "In4.Cu")
		(net "H_CPU1_MEMGHJ_MEMHOT_G_N")
	)
	(segment
		(start 351.241614 -71.69658)
		(end 352.104706 -72.559672)
		(width 0.089408)
		(layer "In4.Cu")
		(net "H_CPU1_MEMGHJ_MEMHOT_G_N")
	)
	(segment
		(start 392.975846 -81.424526)
		(end 393.518898 -81.424526)
		(width 0.089408)
		(layer "In4.Cu")
		(net "H_CPU1_MEMGHJ_MEMHOT_G_N")
	)
	(segment
		(start 398.996662 -81.451196)
		(end 400.103848 -80.34401)
		(width 0.089408)
		(layer "In4.Cu")
		(net "H_CPU1_MEMGHJ_MEMHOT_G_N")
	)
	(segment
		(start 364.946438 -78.409038)
		(end 366.141 -79.6036)
		(width 0.089408)
		(layer "In4.Cu")
		(net "H_CPU1_MEMGHJ_MEMHOT_G_N")
	)
	(segment
		(start 380.4031 -83.2739)
		(end 383.6924 -83.2739)
		(width 0.089408)
		(layer "In4.Cu")
		(net "H_CPU1_MEMGHJ_MEMHOT_G_N")
	)
	(segment
		(start 366.633506 -79.6036)
		(end 367.571782 -80.541876)
		(width 0.089408)
		(layer "In4.Cu")
		(net "H_CPU1_MEMGHJ_MEMHOT_G_N")
	)
	(segment
		(start 441.31484 -14.18336)
		(end 440.7281 -14.7701)
		(width 0.089408)
		(layer "In4.Cu")
		(net "H_CPU1_MEMGHJ_MEMHOT_G_N")
	)
	(segment
		(start 451.195694 -17.46377)
		(end 451.195948 -17.463516)
		(width 0.089408)
		(layer "In4.Cu")
		(net "H_CPU1_MEMGHJ_MEMHOT_G_N")
	)
	(segment
		(start 384.0099 -83.5914)
		(end 384.71094 -83.5914)
		(width 0.089408)
		(layer "In4.Cu")
		(net "H_CPU1_MEMGHJ_MEMHOT_G_N")
	)
	(segment
		(start 334.211168 -132.719064)
		(end 335.769204 -131.161028)
		(width 0.089408)
		(layer "In4.Cu")
		(net "H_CPU1_MEMGHJ_MEMHOT_G_N")
	)
	(segment
		(start 339.166708 -75.59421)
		(end 340.54161 -75.59421)
		(width 0.089408)
		(layer "In4.Cu")
		(net "H_CPU1_MEMGHJ_MEMHOT_G_N")
	)
	(segment
		(start 334.836516 -85.557868)
		(end 337.838796 -82.547968)
		(width 0.089408)
		(layer "In4.Cu")
		(net "H_CPU1_MEMGHJ_MEMHOT_G_N")
	)
	(segment
		(start 330.650596 -122.677428)
		(end 329.720956 -121.747788)
		(width 0.089408)
		(layer "In4.Cu")
		(net "H_CPU1_MEMGHJ_MEMHOT_G_N")
	)
	(segment
		(start 390.386062 -82.88401)
		(end 391.895838 -82.88401)
		(width 0.089408)
		(layer "In4.Cu")
		(net "H_CPU1_MEMGHJ_MEMHOT_G_N")
	)
	(segment
		(start 460.8957 -19.879056)
		(end 455.731372 -19.879056)
		(width 0.089408)
		(layer "In4.Cu")
		(net "H_CPU1_MEMGHJ_MEMHOT_G_N")
	)
	(segment
		(start 337.838796 -82.547968)
		(end 337.838796 -80.415638)
		(width 0.089408)
		(layer "In4.Cu")
		(net "H_CPU1_MEMGHJ_MEMHOT_G_N")
	)
	(segment
		(start 385.68122 -84.33054)
		(end 386.42036 -83.5914)
		(width 0.089408)
		(layer "In4.Cu")
		(net "H_CPU1_MEMGHJ_MEMHOT_G_N")
	)
	(segment
		(start 386.42036 -83.5914)
		(end 386.652262 -83.5914)
		(width 0.089408)
		(layer "In4.Cu")
		(net "H_CPU1_MEMGHJ_MEMHOT_G_N")
	)
	(segment
		(start 338.073238 -80.181196)
		(end 338.087208 -80.181196)
		(width 0.089408)
		(layer "In4.Cu")
		(net "H_CPU1_MEMGHJ_MEMHOT_G_N")
	)
	(segment
		(start 379.4252 -84.2518)
		(end 380.4031 -83.2739)
		(width 0.089408)
		(layer "In4.Cu")
		(net "H_CPU1_MEMGHJ_MEMHOT_G_N")
	)
	(segment
		(start 371.853714 -84.498942)
		(end 373.74576 -84.498942)
		(width 0.089408)
		(layer "In4.Cu")
		(net "H_CPU1_MEMGHJ_MEMHOT_G_N")
	)
	(segment
		(start 352.2726 -72.592946)
		(end 362.763562 -72.592946)
		(width 0.089408)
		(layer "In4.Cu")
		(net "H_CPU1_MEMGHJ_MEMHOT_G_N")
	)
	(segment
		(start 335.769204 -131.161028)
		(end 335.769204 -126.100332)
		(width 0.089408)
		(layer "In4.Cu")
		(net "H_CPU1_MEMGHJ_MEMHOT_G_N")
	)
	(segment
		(start 383.6924 -83.2739)
		(end 384.0099 -83.5914)
		(width 0.089408)
		(layer "In4.Cu")
		(net "H_CPU1_MEMGHJ_MEMHOT_G_N")
	)
	(segment
		(start 384.91922 -84.1375)
		(end 385.11226 -84.33054)
		(width 0.089408)
		(layer "In4.Cu")
		(net "H_CPU1_MEMGHJ_MEMHOT_G_N")
	)
	(segment
		(start 367.571782 -80.958182)
		(end 367.9952 -81.3816)
		(width 0.089408)
		(layer "In4.Cu")
		(net "H_CPU1_MEMGHJ_MEMHOT_G_N")
	)
	(segment
		(start 334.090264 -137.824464)
		(end 334.090264 -136.79932)
		(width 0.089408)
		(layer "In4.Cu")
		(net "H_CPU1_MEMGHJ_MEMHOT_G_N")
	)
	(segment
		(start 334.836516 -87.03183)
		(end 334.836516 -85.557868)
		(width 0.089408)
		(layer "In4.Cu")
		(net "H_CPU1_MEMGHJ_MEMHOT_G_N")
	)
	(segment
		(start 338.087208 -80.181196)
		(end 338.746592 -79.520034)
		(width 0.089408)
		(layer "In4.Cu")
		(net "H_CPU1_MEMGHJ_MEMHOT_G_N")
	)
	(segment
		(start 394.489432 -81.451196)
		(end 398.996662 -81.451196)
		(width 0.089408)
		(layer "In4.Cu")
		(net "H_CPU1_MEMGHJ_MEMHOT_G_N")
	)
	(segment
		(start 451.195948 -16.961104)
		(end 448.418204 -14.18336)
		(width 0.089408)
		(layer "In4.Cu")
		(net "H_CPU1_MEMGHJ_MEMHOT_G_N")
	)
	(segment
		(start 455.43597 -19.583654)
		(end 453.246236 -19.583654)
		(width 0.089408)
		(layer "In4.Cu")
		(net "H_CPU1_MEMGHJ_MEMHOT_G_N")
	)
	(segment
		(start 329.720956 -121.747788)
		(end 329.720956 -112.291114)
		(width 0.089408)
		(layer "In4.Cu")
		(net "H_CPU1_MEMGHJ_MEMHOT_G_N")
	)
	(segment
		(start 463.35696 -21.25472)
		(end 463.290158 -21.321522)
		(width 0.089408)
		(layer "In4.Cu")
		(net "H_CPU1_MEMGHJ_MEMHOT_G_N")
	)
	(segment
		(start 373.992902 -84.2518)
		(end 379.4252 -84.2518)
		(width 0.089408)
		(layer "In4.Cu")
		(net "H_CPU1_MEMGHJ_MEMHOT_G_N")
	)
	(segment
		(start 451.195948 -17.463516)
		(end 451.195948 -16.961104)
		(width 0.089408)
		(layer "In4.Cu")
		(net "H_CPU1_MEMGHJ_MEMHOT_G_N")
	)
	(segment
		(start 388.113778 -84.279994)
		(end 388.742428 -83.651344)
		(width 0.089408)
		(layer "In4.Cu")
		(net "H_CPU1_MEMGHJ_MEMHOT_G_N")
	)
	(segment
		(start 391.895838 -82.88401)
		(end 392.61288 -82.166968)
		(width 0.089408)
		(layer "In4.Cu")
		(net "H_CPU1_MEMGHJ_MEMHOT_G_N")
	)
	(segment
		(start 345.206066 -73.494646)
		(end 347.004132 -71.69658)
		(width 0.089408)
		(layer "In4.Cu")
		(net "H_CPU1_MEMGHJ_MEMHOT_G_N")
	)
	(segment
		(start 352.104706 -72.559672)
		(end 352.2726 -72.592946)
		(width 0.089408)
		(layer "In4.Cu")
		(net "H_CPU1_MEMGHJ_MEMHOT_G_N")
	)
	(segment
		(start 402.58873 -80.905096)
		(end 402.80844 -80.905096)
		(width 0.089408)
		(layer "In4.Cu")
		(net "H_CPU1_MEMGHJ_MEMHOT_G_N")
	)
	(segment
		(start 341.589106 -74.546714)
		(end 342.736424 -74.546714)
		(width 0.089408)
		(layer "In4.Cu")
		(net "H_CPU1_MEMGHJ_MEMHOT_G_N")
	)
	(segment
		(start 368.736372 -81.3816)
		(end 371.853714 -84.498942)
		(width 0.089408)
		(layer "In4.Cu")
		(net "H_CPU1_MEMGHJ_MEMHOT_G_N")
	)
	(segment
		(start 338.746592 -79.520034)
		(end 338.746592 -76.014326)
		(width 0.089408)
		(layer "In4.Cu")
		(net "H_CPU1_MEMGHJ_MEMHOT_G_N")
	)
	(segment
		(start 342.736424 -74.546714)
		(end 343.788492 -73.494646)
		(width 0.089408)
		(layer "In4.Cu")
		(net "H_CPU1_MEMGHJ_MEMHOT_G_N")
	)
	(segment
		(start 400.103848 -80.34401)
		(end 402.027644 -80.34401)
		(width 0.089408)
		(layer "In4.Cu")
		(net "H_CPU1_MEMGHJ_MEMHOT_G_N")
	)
	(segment
		(start 451.195694 -17.533112)
		(end 451.195694 -17.46377)
		(width 0.089408)
		(layer "In4.Cu")
		(net "H_CPU1_MEMGHJ_MEMHOT_G_N")
	)
	(segment
		(start 328.841862 -93.026484)
		(end 334.836516 -87.03183)
		(width 0.089408)
		(layer "In4.Cu")
		(net "H_CPU1_MEMGHJ_MEMHOT_G_N")
	)
	(segment
		(start 453.246236 -19.583654)
		(end 451.195694 -17.533112)
		(width 0.089408)
		(layer "In4.Cu")
		(net "H_CPU1_MEMGHJ_MEMHOT_G_N")
	)
	(segment
		(start 340.54161 -75.59421)
		(end 341.589106 -74.546714)
		(width 0.089408)
		(layer "In4.Cu")
		(net "H_CPU1_MEMGHJ_MEMHOT_G_N")
	)
	(segment
		(start 455.731372 -19.879056)
		(end 455.43597 -19.583654)
		(width 0.089408)
		(layer "In4.Cu")
		(net "H_CPU1_MEMGHJ_MEMHOT_G_N")
	)
	(segment
		(start 463.290158 -21.321522)
		(end 462.338166 -21.321522)
		(width 0.089408)
		(layer "In4.Cu")
		(net "H_CPU1_MEMGHJ_MEMHOT_G_N")
	)
	(segment
		(start 334.211168 -136.678416)
		(end 334.211168 -132.719064)
		(width 0.089408)
		(layer "In4.Cu")
		(net "H_CPU1_MEMGHJ_MEMHOT_G_N")
	)
	(segment
		(start 332.3463 -122.677428)
		(end 330.650596 -122.677428)
		(width 0.089408)
		(layer "In4.Cu")
		(net "H_CPU1_MEMGHJ_MEMHOT_G_N")
	)
	(segment
		(start 347.004132 -71.69658)
		(end 351.241614 -71.69658)
		(width 0.089408)
		(layer "In4.Cu")
		(net "H_CPU1_MEMGHJ_MEMHOT_G_N")
	)
	(segment
		(start 392.61288 -82.166968)
		(end 392.61288 -81.787492)
		(width 0.089408)
		(layer "In4.Cu")
		(net "H_CPU1_MEMGHJ_MEMHOT_G_N")
	)
	(segment
		(start 338.746592 -76.014326)
		(end 339.166708 -75.59421)
		(width 0.089408)
		(layer "In4.Cu")
		(net "H_CPU1_MEMGHJ_MEMHOT_G_N")
	)
	(segment
		(start 462.338166 -21.321522)
		(end 460.8957 -19.879056)
		(width 0.089408)
		(layer "In4.Cu")
		(net "H_CPU1_MEMGHJ_MEMHOT_G_N")
	)
	(segment
		(start 337.838796 -80.415638)
		(end 338.073238 -80.181196)
		(width 0.089408)
		(layer "In4.Cu")
		(net "H_CPU1_MEMGHJ_MEMHOT_G_N")
	)
	(segment
		(start 328.841862 -111.41202)
		(end 328.841862 -93.026484)
		(width 0.089408)
		(layer "In4.Cu")
		(net "H_CPU1_MEMGHJ_MEMHOT_G_N")
	)
	(segment
		(start 405.898096 -80.531716)
		(end 407.10993 -81.74355)
		(width 0.089408)
		(layer "In4.Cu")
		(net "H_CPU1_MEMGHJ_MEMHOT_G_N")
	)
	(segment
		(start 389.618728 -83.651344)
		(end 390.386062 -82.88401)
		(width 0.089408)
		(layer "In4.Cu")
		(net "H_CPU1_MEMGHJ_MEMHOT_G_N")
	)
	(segment
		(start 402.80844 -80.905096)
		(end 403.18182 -80.531716)
		(width 0.089408)
		(layer "In4.Cu")
		(net "H_CPU1_MEMGHJ_MEMHOT_G_N")
	)
	(segment
		(start 393.518898 -81.424526)
		(end 393.851638 -81.757266)
		(width 0.089408)
		(layer "In4.Cu")
		(net "H_CPU1_MEMGHJ_MEMHOT_G_N")
	)
	(segment
		(start 385.11226 -84.33054)
		(end 385.68122 -84.33054)
		(width 0.089408)
		(layer "In4.Cu")
		(net "H_CPU1_MEMGHJ_MEMHOT_G_N")
	)
	(segment
		(start 384.71094 -83.5914)
		(end 384.91922 -83.79968)
		(width 0.089408)
		(layer "In4.Cu")
		(net "H_CPU1_MEMGHJ_MEMHOT_G_N")
	)
	(segment
		(start 335.769204 -126.100332)
		(end 332.3463 -122.677428)
		(width 0.089408)
		(layer "In4.Cu")
		(net "H_CPU1_MEMGHJ_MEMHOT_G_N")
	)
	(segment
		(start 367.9952 -81.3816)
		(end 368.736372 -81.3816)
		(width 0.089408)
		(layer "In4.Cu")
		(net "H_CPU1_MEMGHJ_MEMHOT_G_N")
	)
	(segment
		(start 384.91922 -83.79968)
		(end 384.91922 -84.1375)
		(width 0.089408)
		(layer "In4.Cu")
		(net "H_CPU1_MEMGHJ_MEMHOT_G_N")
	)
	(segment
		(start 367.571782 -80.541876)
		(end 367.571782 -80.958182)
		(width 0.089408)
		(layer "In4.Cu")
		(net "H_CPU1_MEMGHJ_MEMHOT_G_N")
	)
	(segment
		(start 402.027644 -80.34401)
		(end 402.58873 -80.905096)
		(width 0.089408)
		(layer "In4.Cu")
		(net "H_CPU1_MEMGHJ_MEMHOT_G_N")
	)
	(segment
		(start 373.74576 -84.498942)
		(end 373.992902 -84.2518)
		(width 0.089408)
		(layer "In4.Cu")
		(net "H_CPU1_MEMGHJ_MEMHOT_G_N")
	)
	(segment
		(start 408.469846 -81.74355)
		(end 408.626056 -81.89976)
		(width 0.089408)
		(layer "In4.Cu")
		(net "H_CPU1_MEMGHJ_MEMHOT_G_N")
	)
	(segment
		(start 366.141 -79.6036)
		(end 366.633506 -79.6036)
		(width 0.089408)
		(layer "In4.Cu")
		(net "H_CPU1_MEMGHJ_MEMHOT_G_N")
	)
	(segment
		(start 410.246576 -84.661248)
		(end 411.280102 -83.627722)
		(width 0.089408)
		(layer "In9.Cu")
		(net "H_CPU1_MEMGHJ_MEMHOT_G_N")
	)
	(segment
		(start 415.483548 -62.018164)
		(end 415.628328 -61.873384)
		(width 0.089408)
		(layer "In9.Cu")
		(net "H_CPU1_MEMGHJ_MEMHOT_G_N")
	)
	(segment
		(start 465.325714 -50.225452)
		(end 465.325714 -48.715676)
		(width 0.089408)
		(layer "In9.Cu")
		(net "H_CPU1_MEMGHJ_MEMHOT_G_N")
	)
	(segment
		(start 463.319622 -28.703778)
		(end 465.300568 -26.722832)
		(width 0.089408)
		(layer "In9.Cu")
		(net "H_CPU1_MEMGHJ_MEMHOT_G_N")
	)
	(segment
		(start 408.6479 -87.33409)
		(end 410.246576 -85.735414)
		(width 0.089408)
		(layer "In9.Cu")
		(net "H_CPU1_MEMGHJ_MEMHOT_G_N")
	)
	(segment
		(start 411.280102 -83.627722)
		(end 413.017462 -83.627722)
		(width 0.089408)
		(layer "In9.Cu")
		(net "H_CPU1_MEMGHJ_MEMHOT_G_N")
	)
	(segment
		(start 465.02193 -44.101004)
		(end 463.512408 -42.591482)
		(width 0.089408)
		(layer "In9.Cu")
		(net "H_CPU1_MEMGHJ_MEMHOT_G_N")
	)
	(segment
		(start 414.941512 -71.71817)
		(end 414.941512 -68.259706)
		(width 0.089408)
		(layer "In9.Cu")
		(net "H_CPU1_MEMGHJ_MEMHOT_G_N")
	)
	(segment
		(start 414.941512 -68.259706)
		(end 415.278316 -67.922902)
		(width 0.089408)
		(layer "In9.Cu")
		(net "H_CPU1_MEMGHJ_MEMHOT_G_N")
	)
	(segment
		(start 420.939468 -55.19547)
		(end 423.780458 -55.19547)
		(width 0.089408)
		(layer "In9.Cu")
		(net "H_CPU1_MEMGHJ_MEMHOT_G_N")
	)
	(segment
		(start 465.300568 -26.722832)
		(end 465.300568 -23.947374)
		(width 0.089408)
		(layer "In9.Cu")
		(net "H_CPU1_MEMGHJ_MEMHOT_G_N")
	)
	(segment
		(start 426.076364 -54.172612)
		(end 427.90745 -52.341526)
		(width 0.089408)
		(layer "In9.Cu")
		(net "H_CPU1_MEMGHJ_MEMHOT_G_N")
	)
	(segment
		(start 438.695592 -52.31511)
		(end 439.374534 -51.636168)
		(width 0.089408)
		(layer "In9.Cu")
		(net "H_CPU1_MEMGHJ_MEMHOT_G_N")
	)
	(segment
		(start 463.319622 -34.431986)
		(end 463.319622 -28.703778)
		(width 0.089408)
		(layer "In9.Cu")
		(net "H_CPU1_MEMGHJ_MEMHOT_G_N")
	)
	(segment
		(start 463.512408 -39.44747)
		(end 461.8736 -37.808662)
		(width 0.089408)
		(layer "In9.Cu")
		(net "H_CPU1_MEMGHJ_MEMHOT_G_N")
	)
	(segment
		(start 414.335214 -78.75905)
		(end 414.335214 -72.324468)
		(width 0.089408)
		(layer "In9.Cu")
		(net "H_CPU1_MEMGHJ_MEMHOT_G_N")
	)
	(segment
		(start 413.671004 -79.424276)
		(end 413.671004 -79.42326)
		(width 0.089408)
		(layer "In9.Cu")
		(net "H_CPU1_MEMGHJ_MEMHOT_G_N")
	)
	(segment
		(start 414.335214 -72.324468)
		(end 414.941512 -71.71817)
		(width 0.089408)
		(layer "In9.Cu")
		(net "H_CPU1_MEMGHJ_MEMHOT_G_N")
	)
	(segment
		(start 465.325714 -48.715676)
		(end 465.02193 -48.411892)
		(width 0.089408)
		(layer "In9.Cu")
		(net "H_CPU1_MEMGHJ_MEMHOT_G_N")
	)
	(segment
		(start 463.914998 -51.636168)
		(end 465.325714 -50.225452)
		(width 0.089408)
		(layer "In9.Cu")
		(net "H_CPU1_MEMGHJ_MEMHOT_G_N")
	)
	(segment
		(start 435.968394 -52.31511)
		(end 438.695592 -52.31511)
		(width 0.089408)
		(layer "In9.Cu")
		(net "H_CPU1_MEMGHJ_MEMHOT_G_N")
	)
	(segment
		(start 423.780458 -55.19547)
		(end 424.803316 -54.172612)
		(width 0.089408)
		(layer "In9.Cu")
		(net "H_CPU1_MEMGHJ_MEMHOT_G_N")
	)
	(segment
		(start 410.246576 -85.735414)
		(end 410.246576 -84.661248)
		(width 0.089408)
		(layer "In9.Cu")
		(net "H_CPU1_MEMGHJ_MEMHOT_G_N")
	)
	(segment
		(start 415.278316 -67.764914)
		(end 415.278062 -67.76466)
		(width 0.089408)
		(layer "In9.Cu")
		(net "H_CPU1_MEMGHJ_MEMHOT_G_N")
	)
	(segment
		(start 439.374534 -51.636168)
		(end 463.914998 -51.636168)
		(width 0.089408)
		(layer "In9.Cu")
		(net "H_CPU1_MEMGHJ_MEMHOT_G_N")
	)
	(segment
		(start 415.628328 -61.873384)
		(end 415.628328 -60.147708)
		(width 0.089408)
		(layer "In9.Cu")
		(net "H_CPU1_MEMGHJ_MEMHOT_G_N")
	)
	(segment
		(start 415.278062 -67.76466)
		(end 415.278062 -64.136778)
		(width 0.089408)
		(layer "In9.Cu")
		(net "H_CPU1_MEMGHJ_MEMHOT_G_N")
	)
	(segment
		(start 435.941978 -52.341526)
		(end 435.968394 -52.31511)
		(width 0.089408)
		(layer "In9.Cu")
		(net "H_CPU1_MEMGHJ_MEMHOT_G_N")
	)
	(segment
		(start 461.8736 -35.878008)
		(end 463.319622 -34.431986)
		(width 0.089408)
		(layer "In9.Cu")
		(net "H_CPU1_MEMGHJ_MEMHOT_G_N")
	)
	(segment
		(start 465.300568 -23.947374)
		(end 463.35696 -22.003766)
		(width 0.089408)
		(layer "In9.Cu")
		(net "H_CPU1_MEMGHJ_MEMHOT_G_N")
	)
	(segment
		(start 465.02193 -48.411892)
		(end 465.02193 -44.101004)
		(width 0.089408)
		(layer "In9.Cu")
		(net "H_CPU1_MEMGHJ_MEMHOT_G_N")
	)
	(segment
		(start 413.017462 -83.627722)
		(end 413.278066 -83.367118)
		(width 0.089408)
		(layer "In9.Cu")
		(net "H_CPU1_MEMGHJ_MEMHOT_G_N")
	)
	(segment
		(start 415.483548 -58.958734)
		(end 418.33546 -56.106822)
		(width 0.089408)
		(layer "In9.Cu")
		(net "H_CPU1_MEMGHJ_MEMHOT_G_N")
	)
	(segment
		(start 415.483548 -60.002928)
		(end 415.483548 -58.958734)
		(width 0.089408)
		(layer "In9.Cu")
		(net "H_CPU1_MEMGHJ_MEMHOT_G_N")
	)
	(segment
		(start 415.628328 -60.147708)
		(end 415.483548 -60.002928)
		(width 0.089408)
		(layer "In9.Cu")
		(net "H_CPU1_MEMGHJ_MEMHOT_G_N")
	)
	(segment
		(start 413.671004 -79.42326)
		(end 414.335214 -78.75905)
		(width 0.089408)
		(layer "In9.Cu")
		(net "H_CPU1_MEMGHJ_MEMHOT_G_N")
	)
	(segment
		(start 415.483548 -63.931292)
		(end 415.483548 -62.018164)
		(width 0.089408)
		(layer "In9.Cu")
		(net "H_CPU1_MEMGHJ_MEMHOT_G_N")
	)
	(segment
		(start 413.278066 -83.367118)
		(end 413.278066 -79.817214)
		(width 0.089408)
		(layer "In9.Cu")
		(net "H_CPU1_MEMGHJ_MEMHOT_G_N")
	)
	(segment
		(start 415.278316 -67.922902)
		(end 415.278316 -67.764914)
		(width 0.089408)
		(layer "In9.Cu")
		(net "H_CPU1_MEMGHJ_MEMHOT_G_N")
	)
	(segment
		(start 424.803316 -54.172612)
		(end 426.076364 -54.172612)
		(width 0.089408)
		(layer "In9.Cu")
		(net "H_CPU1_MEMGHJ_MEMHOT_G_N")
	)
	(segment
		(start 463.512408 -42.591482)
		(end 463.512408 -39.44747)
		(width 0.089408)
		(layer "In9.Cu")
		(net "H_CPU1_MEMGHJ_MEMHOT_G_N")
	)
	(segment
		(start 461.8736 -37.808662)
		(end 461.8736 -35.878008)
		(width 0.089408)
		(layer "In9.Cu")
		(net "H_CPU1_MEMGHJ_MEMHOT_G_N")
	)
	(segment
		(start 427.90745 -52.341526)
		(end 435.941978 -52.341526)
		(width 0.089408)
		(layer "In9.Cu")
		(net "H_CPU1_MEMGHJ_MEMHOT_G_N")
	)
	(segment
		(start 420.028116 -56.106822)
		(end 420.939468 -55.19547)
		(width 0.089408)
		(layer "In9.Cu")
		(net "H_CPU1_MEMGHJ_MEMHOT_G_N")
	)
	(segment
		(start 413.278066 -79.817214)
		(end 413.671004 -79.424276)
		(width 0.089408)
		(layer "In9.Cu")
		(net "H_CPU1_MEMGHJ_MEMHOT_G_N")
	)
	(segment
		(start 463.35696 -22.003766)
		(end 463.35696 -21.25472)
		(width 0.089408)
		(layer "In9.Cu")
		(net "H_CPU1_MEMGHJ_MEMHOT_G_N")
	)
	(segment
		(start 418.33546 -56.106822)
		(end 420.028116 -56.106822)
		(width 0.089408)
		(layer "In9.Cu")
		(net "H_CPU1_MEMGHJ_MEMHOT_G_N")
	)
	(segment
		(start 415.278062 -64.136778)
		(end 415.483548 -63.931292)
		(width 0.089408)
		(layer "In9.Cu")
		(net "H_CPU1_MEMGHJ_MEMHOT_G_N")
	)
	(segment
		(start 139.827 -97.2566)
		(end 139.489434 -96.919034)
		(width 0.0889)
		(layer "In11.Cu")
		(net "H_CPU1_MEMGHJ_MEMHOT_G_N")
	)
	(segment
		(start 126.819152 -65.884552)
		(end 126.669038 -65.884552)
		(width 0.0889)
		(layer "In11.Cu")
		(net "H_CPU1_MEMGHJ_MEMHOT_G_N")
	)
	(segment
		(start 119.869204 -68.5038)
		(end 119.7102 -68.5038)
		(width 0.0889)
		(layer "In11.Cu")
		(net "H_CPU1_MEMGHJ_MEMHOT_G_N")
	)
	(segment
		(start 324.122034 -149.714966)
		(end 324.122034 -154.70505)
		(width 0.089408)
		(layer "In11.Cu")
		(net "H_CPU1_MEMGHJ_MEMHOT_G_N")
	)
	(segment
		(start 265.307064 -157.425644)
		(end 189.330584 -157.425644)
		(width 0.089408)
		(layer "In11.Cu")
		(net "H_CPU1_MEMGHJ_MEMHOT_G_N")
	)
	(segment
		(start 120.904 -86.1314)
		(end 120.904 -85.448902)
		(width 0.0889)
		(layer "In11.Cu")
		(net "H_CPU1_MEMGHJ_MEMHOT_G_N")
	)
	(segment
		(start 334.2894 -138.0236)
		(end 334.0608 -138.2522)
		(width 0.089408)
		(layer "In11.Cu")
		(net "H_CPU1_MEMGHJ_MEMHOT_G_N")
	)
	(segment
		(start 121.793 -67.7164)
		(end 121.2088 -68.3006)
		(width 0.0889)
		(layer "In11.Cu")
		(net "H_CPU1_MEMGHJ_MEMHOT_G_N")
	)
	(segment
		(start 120.0912 -85.217)
		(end 119.126 -85.217)
		(width 0.089408)
		(layer "In11.Cu")
		(net "H_CPU1_MEMGHJ_MEMHOT_G_N")
	)
	(segment
		(start 117.00002 -79.891128)
		(end 117.325648 -80.677258)
		(width 0.089408)
		(layer "In11.Cu")
		(net "H_CPU1_MEMGHJ_MEMHOT_G_N")
	)
	(segment
		(start 136.825228 -95.433134)
		(end 136.801098 -95.433134)
		(width 0.0889)
		(layer "In11.Cu")
		(net "H_CPU1_MEMGHJ_MEMHOT_G_N")
	)
	(segment
		(start 155.707334 -117.02161)
		(end 140.6906 -102.004876)
		(width 0.089408)
		(layer "In11.Cu")
		(net "H_CPU1_MEMGHJ_MEMHOT_G_N")
	)
	(segment
		(start 120.904 -85.448902)
		(end 120.672098 -85.217)
		(width 0.0889)
		(layer "In11.Cu")
		(net "H_CPU1_MEMGHJ_MEMHOT_G_N")
	)
	(segment
		(start 172.14596 -146.21002)
		(end 171.17568 -147.1803)
		(width 0.089408)
		(layer "In11.Cu")
		(net "H_CPU1_MEMGHJ_MEMHOT_G_N")
	)
	(segment
		(start 265.406632 -157.326076)
		(end 265.307064 -157.425644)
		(width 0.089408)
		(layer "In11.Cu")
		(net "H_CPU1_MEMGHJ_MEMHOT_G_N")
	)
	(segment
		(start 327.7616 -142.0114)
		(end 325.5264 -142.0114)
		(width 0.089408)
		(layer "In11.Cu")
		(net "H_CPU1_MEMGHJ_MEMHOT_G_N")
	)
	(segment
		(start 120.672098 -85.217)
		(end 120.0912 -85.217)
		(width 0.0889)
		(layer "In11.Cu")
		(net "H_CPU1_MEMGHJ_MEMHOT_G_N")
	)
	(segment
		(start 117.849142 -82.804)
		(end 117.772434 -82.618834)
		(width 0.089408)
		(layer "In11.Cu")
		(net "H_CPU1_MEMGHJ_MEMHOT_G_N")
	)
	(segment
		(start 123.420632 -67.0052)
		(end 122.709432 -67.7164)
		(width 0.0889)
		(layer "In11.Cu")
		(net "H_CPU1_MEMGHJ_MEMHOT_G_N")
	)
	(segment
		(start 132.537454 -92.956634)
		(end 132.519674 -92.956634)
		(width 0.0889)
		(layer "In11.Cu")
		(net "H_CPU1_MEMGHJ_MEMHOT_G_N")
	)
	(segment
		(start 127.823722 -66.585338)
		(end 127.668528 -66.430144)
		(width 0.0889)
		(layer "In11.Cu")
		(net "H_CPU1_MEMGHJ_MEMHOT_G_N")
	)
	(segment
		(start 128.111758 -66.704464)
		(end 127.823722 -66.585338)
		(width 0.0889)
		(layer "In11.Cu")
		(net "H_CPU1_MEMGHJ_MEMHOT_G_N")
	)
	(segment
		(start 324.122034 -154.70505)
		(end 321.716654 -157.11043)
		(width 0.089408)
		(layer "In11.Cu")
		(net "H_CPU1_MEMGHJ_MEMHOT_G_N")
	)
	(segment
		(start 120.381268 -68.685664)
		(end 120.051068 -68.685664)
		(width 0.0889)
		(layer "In11.Cu")
		(net "H_CPU1_MEMGHJ_MEMHOT_G_N")
	)
	(segment
		(start 120.766332 -68.3006)
		(end 120.381268 -68.685664)
		(width 0.0889)
		(layer "In11.Cu")
		(net "H_CPU1_MEMGHJ_MEMHOT_G_N")
	)
	(segment
		(start 164.570664 -124.333)
		(end 166.6367 -124.333)
		(width 0.089408)
		(layer "In11.Cu")
		(net "H_CPU1_MEMGHJ_MEMHOT_G_N")
	)
	(segment
		(start 324.620128 -149.216872)
		(end 324.122034 -149.714966)
		(width 0.089408)
		(layer "In11.Cu")
		(net "H_CPU1_MEMGHJ_MEMHOT_G_N")
	)
	(segment
		(start 121.380758 -86.517988)
		(end 121.359168 -86.517988)
		(width 0.0889)
		(layer "In11.Cu")
		(net "H_CPU1_MEMGHJ_MEMHOT_G_N")
	)
	(segment
		(start 132.17652 -92.762324)
		(end 132.173218 -92.756482)
		(width 0.0889)
		(layer "In11.Cu")
		(net "H_CPU1_MEMGHJ_MEMHOT_G_N")
	)
	(segment
		(start 331.12964 -138.2522)
		(end 329.057 -140.32484)
		(width 0.089408)
		(layer "In11.Cu")
		(net "H_CPU1_MEMGHJ_MEMHOT_G_N")
	)
	(segment
		(start 119.7102 -68.5038)
		(end 119.5324 -68.326)
		(width 0.0889)
		(layer "In11.Cu")
		(net "H_CPU1_MEMGHJ_MEMHOT_G_N")
	)
	(segment
		(start 173.76394 -146.21002)
		(end 172.14596 -146.21002)
		(width 0.089408)
		(layer "In11.Cu")
		(net "H_CPU1_MEMGHJ_MEMHOT_G_N")
	)
	(segment
		(start 334.0608 -138.2522)
		(end 331.12964 -138.2522)
		(width 0.089408)
		(layer "In11.Cu")
		(net "H_CPU1_MEMGHJ_MEMHOT_G_N")
	)
	(segment
		(start 187.085478 -150.026624)
		(end 186.055 -148.996146)
		(width 0.089408)
		(layer "In11.Cu")
		(net "H_CPU1_MEMGHJ_MEMHOT_G_N")
	)
	(segment
		(start 187.085478 -155.180538)
		(end 187.085478 -150.026624)
		(width 0.089408)
		(layer "In11.Cu")
		(net "H_CPU1_MEMGHJ_MEMHOT_G_N")
	)
	(segment
		(start 121.2088 -68.3006)
		(end 120.766332 -68.3006)
		(width 0.0889)
		(layer "In11.Cu")
		(net "H_CPU1_MEMGHJ_MEMHOT_G_N")
	)
	(segment
		(start 325.5264 -142.0114)
		(end 324.620128 -142.917672)
		(width 0.089408)
		(layer "In11.Cu")
		(net "H_CPU1_MEMGHJ_MEMHOT_G_N")
	)
	(segment
		(start 119.5324 -68.326)
		(end 119.126 -68.326)
		(width 0.0889)
		(layer "In11.Cu")
		(net "H_CPU1_MEMGHJ_MEMHOT_G_N")
	)
	(segment
		(start 119.126 -85.217)
		(end 118.65229 -84.74329)
		(width 0.089408)
		(layer "In11.Cu")
		(net "H_CPU1_MEMGHJ_MEMHOT_G_N")
	)
	(segment
		(start 119.126 -68.326)
		(end 117.00002 -70.45198)
		(width 0.0889)
		(layer "In11.Cu")
		(net "H_CPU1_MEMGHJ_MEMHOT_G_N")
	)
	(segment
		(start 128.571498 -66.525394)
		(end 128.392428 -66.704464)
		(width 0.0889)
		(layer "In11.Cu")
		(net "H_CPU1_MEMGHJ_MEMHOT_G_N")
	)
	(segment
		(start 164.7698 -122.4661)
		(end 162.11169 -122.4661)
		(width 0.089408)
		(layer "In11.Cu")
		(net "H_CPU1_MEMGHJ_MEMHOT_G_N")
	)
	(segment
		(start 166.6367 -124.333)
		(end 164.7698 -122.4661)
		(width 0.089408)
		(layer "In11.Cu")
		(net "H_CPU1_MEMGHJ_MEMHOT_G_N")
	)
	(segment
		(start 174.73422 -147.1803)
		(end 173.76394 -146.21002)
		(width 0.089408)
		(layer "In11.Cu")
		(net "H_CPU1_MEMGHJ_MEMHOT_G_N")
	)
	(segment
		(start 161.036762 -146.609562)
		(end 160.421066 -145.993866)
		(width 0.089408)
		(layer "In11.Cu")
		(net "H_CPU1_MEMGHJ_MEMHOT_G_N")
	)
	(segment
		(start 139.489434 -96.919034)
		(end 139.372848 -96.919034)
		(width 0.0889)
		(layer "In11.Cu")
		(net "H_CPU1_MEMGHJ_MEMHOT_G_N")
	)
	(segment
		(start 128.895094 -65.369948)
		(end 128.710436 -65.815718)
		(width 0.0889)
		(layer "In11.Cu")
		(net "H_CPU1_MEMGHJ_MEMHOT_G_N")
	)
	(segment
		(start 128.392428 -66.704464)
		(end 128.111758 -66.704464)
		(width 0.0889)
		(layer "In11.Cu")
		(net "H_CPU1_MEMGHJ_MEMHOT_G_N")
	)
	(segment
		(start 127.14986 -66.21526)
		(end 126.819152 -65.884552)
		(width 0.0889)
		(layer "In11.Cu")
		(net "H_CPU1_MEMGHJ_MEMHOT_G_N")
	)
	(segment
		(start 138.550904 -96.423988)
		(end 138.518138 -96.423988)
		(width 0.0889)
		(layer "In11.Cu")
		(net "H_CPU1_MEMGHJ_MEMHOT_G_N")
	)
	(segment
		(start 128.710436 -66.190114)
		(end 128.571498 -66.525394)
		(width 0.0889)
		(layer "In11.Cu")
		(net "H_CPU1_MEMGHJ_MEMHOT_G_N")
	)
	(segment
		(start 134.249668 -93.947234)
		(end 134.221728 -93.947234)
		(width 0.0889)
		(layer "In11.Cu")
		(net "H_CPU1_MEMGHJ_MEMHOT_G_N")
	)
	(segment
		(start 122.709432 -67.7164)
		(end 121.793 -67.7164)
		(width 0.0889)
		(layer "In11.Cu")
		(net "H_CPU1_MEMGHJ_MEMHOT_G_N")
	)
	(segment
		(start 159.004508 -118.345204)
		(end 157.680914 -117.02161)
		(width 0.089408)
		(layer "In11.Cu")
		(net "H_CPU1_MEMGHJ_MEMHOT_G_N")
	)
	(segment
		(start 265.408918 -157.326076)
		(end 265.406632 -157.326076)
		(width 0.089408)
		(layer "In11.Cu")
		(net "H_CPU1_MEMGHJ_MEMHOT_G_N")
	)
	(segment
		(start 120.051068 -68.685664)
		(end 119.869204 -68.5038)
		(width 0.0889)
		(layer "In11.Cu")
		(net "H_CPU1_MEMGHJ_MEMHOT_G_N")
	)
	(segment
		(start 125.673358 -66.400934)
		(end 125.450346 -66.400934)
		(width 0.0889)
		(layer "In11.Cu")
		(net "H_CPU1_MEMGHJ_MEMHOT_G_N")
	)
	(segment
		(start 180.2257 -147.1803)
		(end 174.73422 -147.1803)
		(width 0.089408)
		(layer "In11.Cu")
		(net "H_CPU1_MEMGHJ_MEMHOT_G_N")
	)
	(segment
		(start 131.6863 -92.461588)
		(end 131.650232 -92.461588)
		(width 0.0889)
		(layer "In11.Cu")
		(net "H_CPU1_MEMGHJ_MEMHOT_G_N")
	)
	(segment
		(start 121.016014 -86.323678)
		(end 120.904 -86.1314)
		(width 0.0889)
		(layer "In11.Cu")
		(net "H_CPU1_MEMGHJ_MEMHOT_G_N")
	)
	(segment
		(start 127.668528 -66.430144)
		(end 127.14986 -66.21526)
		(width 0.0889)
		(layer "In11.Cu")
		(net "H_CPU1_MEMGHJ_MEMHOT_G_N")
	)
	(segment
		(start 180.848 -146.558)
		(end 180.2257 -147.1803)
		(width 0.089408)
		(layer "In11.Cu")
		(net "H_CPU1_MEMGHJ_MEMHOT_G_N")
	)
	(segment
		(start 125.450346 -66.400934)
		(end 124.661168 -66.727832)
		(width 0.0889)
		(layer "In11.Cu")
		(net "H_CPU1_MEMGHJ_MEMHOT_G_N")
	)
	(segment
		(start 123.952508 -88.003634)
		(end 123.919742 -88.003634)
		(width 0.0889)
		(layer "In11.Cu")
		(net "H_CPU1_MEMGHJ_MEMHOT_G_N")
	)
	(segment
		(start 265.624564 -157.11043)
		(end 265.408918 -157.326076)
		(width 0.089408)
		(layer "In11.Cu")
		(net "H_CPU1_MEMGHJ_MEMHOT_G_N")
	)
	(segment
		(start 159.004508 -119.358918)
		(end 159.004508 -118.345204)
		(width 0.089408)
		(layer "In11.Cu")
		(net "H_CPU1_MEMGHJ_MEMHOT_G_N")
	)
	(segment
		(start 139.827 -98.9076)
		(end 139.827 -97.2566)
		(width 0.0889)
		(layer "In11.Cu")
		(net "H_CPU1_MEMGHJ_MEMHOT_G_N")
	)
	(segment
		(start 186.055 -148.082)
		(end 184.531 -146.558)
		(width 0.089408)
		(layer "In11.Cu")
		(net "H_CPU1_MEMGHJ_MEMHOT_G_N")
	)
	(segment
		(start 171.17568 -147.1803)
		(end 162.414966 -147.1803)
		(width 0.089408)
		(layer "In11.Cu")
		(net "H_CPU1_MEMGHJ_MEMHOT_G_N")
	)
	(segment
		(start 128.710436 -65.815718)
		(end 128.710436 -66.190114)
		(width 0.0889)
		(layer "In11.Cu")
		(net "H_CPU1_MEMGHJ_MEMHOT_G_N")
	)
	(segment
		(start 162.11169 -122.4661)
		(end 159.004508 -119.358918)
		(width 0.089408)
		(layer "In11.Cu")
		(net "H_CPU1_MEMGHJ_MEMHOT_G_N")
	)
	(segment
		(start 129.965958 -91.470988)
		(end 129.933192 -91.470988)
		(width 0.0889)
		(layer "In11.Cu")
		(net "H_CPU1_MEMGHJ_MEMHOT_G_N")
	)
	(segment
		(start 129.103628 -90.975434)
		(end 129.070862 -90.975434)
		(width 0.0889)
		(layer "In11.Cu")
		(net "H_CPU1_MEMGHJ_MEMHOT_G_N")
	)
	(segment
		(start 126.528068 -65.905888)
		(end 126.495302 -65.905888)
		(width 0.0889)
		(layer "In11.Cu")
		(net "H_CPU1_MEMGHJ_MEMHOT_G_N")
	)
	(segment
		(start 162.414966 -147.1803)
		(end 161.036762 -146.609562)
		(width 0.089408)
		(layer "In11.Cu")
		(net "H_CPU1_MEMGHJ_MEMHOT_G_N")
	)
	(segment
		(start 117.772434 -82.618834)
		(end 117.772434 -81.124044)
		(width 0.089408)
		(layer "In11.Cu")
		(net "H_CPU1_MEMGHJ_MEMHOT_G_N")
	)
	(segment
		(start 329.057 -140.716)
		(end 327.7616 -142.0114)
		(width 0.089408)
		(layer "In11.Cu")
		(net "H_CPU1_MEMGHJ_MEMHOT_G_N")
	)
	(segment
		(start 158.9532 -129.950464)
		(end 164.570664 -124.333)
		(width 0.089408)
		(layer "In11.Cu")
		(net "H_CPU1_MEMGHJ_MEMHOT_G_N")
	)
	(segment
		(start 117.00002 -70.73138)
		(end 117.00002 -79.891128)
		(width 0.089408)
		(layer "In11.Cu")
		(net "H_CPU1_MEMGHJ_MEMHOT_G_N")
	)
	(segment
		(start 329.057 -140.32484)
		(end 329.057 -140.716)
		(width 0.089408)
		(layer "In11.Cu")
		(net "H_CPU1_MEMGHJ_MEMHOT_G_N")
	)
	(segment
		(start 186.055 -148.996146)
		(end 186.055 -148.082)
		(width 0.089408)
		(layer "In11.Cu")
		(net "H_CPU1_MEMGHJ_MEMHOT_G_N")
	)
	(segment
		(start 157.680914 -117.02161)
		(end 155.707334 -117.02161)
		(width 0.089408)
		(layer "In11.Cu")
		(net "H_CPU1_MEMGHJ_MEMHOT_G_N")
	)
	(segment
		(start 135.113014 -94.442534)
		(end 135.0772 -94.442534)
		(width 0.0889)
		(layer "In11.Cu")
		(net "H_CPU1_MEMGHJ_MEMHOT_G_N")
	)
	(segment
		(start 117.00002 -70.45198)
		(end 117.00002 -70.73138)
		(width 0.0889)
		(layer "In11.Cu")
		(net "H_CPU1_MEMGHJ_MEMHOT_G_N")
	)
	(segment
		(start 127.386588 -89.984834)
		(end 127.353822 -89.984834)
		(width 0.0889)
		(layer "In11.Cu")
		(net "H_CPU1_MEMGHJ_MEMHOT_G_N")
	)
	(segment
		(start 118.65229 -84.74329)
		(end 117.849142 -82.804)
		(width 0.089408)
		(layer "In11.Cu")
		(net "H_CPU1_MEMGHJ_MEMHOT_G_N")
	)
	(segment
		(start 123.097798 -87.508588)
		(end 123.065032 -87.508588)
		(width 0.0889)
		(layer "In11.Cu")
		(net "H_CPU1_MEMGHJ_MEMHOT_G_N")
	)
	(segment
		(start 135.975344 -94.937834)
		(end 135.93572 -94.937834)
		(width 0.0889)
		(layer "In11.Cu")
		(net "H_CPU1_MEMGHJ_MEMHOT_G_N")
	)
	(segment
		(start 124.661168 -66.727832)
		(end 124.3838 -67.0052)
		(width 0.0889)
		(layer "In11.Cu")
		(net "H_CPU1_MEMGHJ_MEMHOT_G_N")
	)
	(segment
		(start 140.6906 -99.7712)
		(end 139.827 -98.9076)
		(width 0.089408)
		(layer "In11.Cu")
		(net "H_CPU1_MEMGHJ_MEMHOT_G_N")
	)
	(segment
		(start 321.716654 -157.11043)
		(end 265.624564 -157.11043)
		(width 0.089408)
		(layer "In11.Cu")
		(net "H_CPU1_MEMGHJ_MEMHOT_G_N")
	)
	(segment
		(start 324.620128 -142.917672)
		(end 324.620128 -149.216872)
		(width 0.089408)
		(layer "In11.Cu")
		(net "H_CPU1_MEMGHJ_MEMHOT_G_N")
	)
	(segment
		(start 122.235468 -87.013034)
		(end 122.202702 -87.013034)
		(width 0.0889)
		(layer "In11.Cu")
		(net "H_CPU1_MEMGHJ_MEMHOT_G_N")
	)
	(segment
		(start 140.6906 -102.004876)
		(end 140.6906 -99.7712)
		(width 0.089408)
		(layer "In11.Cu")
		(net "H_CPU1_MEMGHJ_MEMHOT_G_N")
	)
	(segment
		(start 160.421066 -145.993866)
		(end 160.06572 -145.135854)
		(width 0.089408)
		(layer "In11.Cu")
		(net "H_CPU1_MEMGHJ_MEMHOT_G_N")
	)
	(segment
		(start 137.688574 -95.928434)
		(end 137.655808 -95.928434)
		(width 0.0889)
		(layer "In11.Cu")
		(net "H_CPU1_MEMGHJ_MEMHOT_G_N")
	)
	(segment
		(start 126.531878 -89.489788)
		(end 126.499112 -89.489788)
		(width 0.0889)
		(layer "In11.Cu")
		(net "H_CPU1_MEMGHJ_MEMHOT_G_N")
	)
	(segment
		(start 133.399784 -93.452188)
		(end 133.367018 -93.452188)
		(width 0.0889)
		(layer "In11.Cu")
		(net "H_CPU1_MEMGHJ_MEMHOT_G_N")
	)
	(segment
		(start 189.330584 -157.425644)
		(end 187.085478 -155.180538)
		(width 0.089408)
		(layer "In11.Cu")
		(net "H_CPU1_MEMGHJ_MEMHOT_G_N")
	)
	(segment
		(start 129.304796 -64.960246)
		(end 128.895094 -65.369948)
		(width 0.0889)
		(layer "In11.Cu")
		(net "H_CPU1_MEMGHJ_MEMHOT_G_N")
	)
	(segment
		(start 160.06572 -145.135854)
		(end 158.9532 -142.450058)
		(width 0.089408)
		(layer "In11.Cu")
		(net "H_CPU1_MEMGHJ_MEMHOT_G_N")
	)
	(segment
		(start 130.820668 -91.966034)
		(end 130.787902 -91.966034)
		(width 0.0889)
		(layer "In11.Cu")
		(net "H_CPU1_MEMGHJ_MEMHOT_G_N")
	)
	(segment
		(start 124.3838 -67.0052)
		(end 123.420632 -67.0052)
		(width 0.0889)
		(layer "In11.Cu")
		(net "H_CPU1_MEMGHJ_MEMHOT_G_N")
	)
	(segment
		(start 184.531 -146.558)
		(end 180.848 -146.558)
		(width 0.089408)
		(layer "In11.Cu")
		(net "H_CPU1_MEMGHJ_MEMHOT_G_N")
	)
	(segment
		(start 128.248918 -90.480388)
		(end 128.216152 -90.480388)
		(width 0.0889)
		(layer "In11.Cu")
		(net "H_CPU1_MEMGHJ_MEMHOT_G_N")
	)
	(segment
		(start 158.9532 -142.450058)
		(end 158.9532 -129.950464)
		(width 0.089408)
		(layer "In11.Cu")
		(net "H_CPU1_MEMGHJ_MEMHOT_G_N")
	)
	(segment
		(start 124.814838 -88.499188)
		(end 124.782072 -88.499188)
		(width 0.0889)
		(layer "In11.Cu")
		(net "H_CPU1_MEMGHJ_MEMHOT_G_N")
	)
	(segment
		(start 125.669548 -88.994234)
		(end 125.636782 -88.994234)
		(width 0.0889)
		(layer "In11.Cu")
		(net "H_CPU1_MEMGHJ_MEMHOT_G_N")
	)
	(segment
		(start 117.325648 -80.677258)
		(end 117.772434 -81.124044)
		(width 0.089408)
		(layer "In11.Cu")
		(net "H_CPU1_MEMGHJ_MEMHOT_G_N")
	)
	(segment
		(start 129.949194 -64.960246)
		(end 129.304796 -64.960246)
		(width 0.0889)
		(layer "In11.Cu")
		(net "H_CPU1_MEMGHJ_MEMHOT_G_N")
	)
	(arc
		(start 123.919742 -88.003634)
		(mid 123.7281 -87.946468)
		(end 123.588018 -87.803736)
		(width 0.0889)
		(layer "In11.Cu")
		(net "H_CPU1_MEMGHJ_MEMHOT_G_N")
	)
	(arc
		(start 132.009134 -64.911732)
		(mid 131.826416 -64.917148)
		(end 131.643628 -64.915288)
		(width 0.0889)
		(layer "In11.Cu")
		(net "H_CPU1_MEMGHJ_MEMHOT_G_N")
	)
	(arc
		(start 124.446538 -88.299036)
		(mid 124.23793 -88.087104)
		(end 123.952508 -88.003634)
		(width 0.0889)
		(layer "In11.Cu")
		(net "H_CPU1_MEMGHJ_MEMHOT_G_N")
	)
	(arc
		(start 133.890004 -93.747336)
		(mid 133.683 -93.536472)
		(end 133.399784 -93.452188)
		(width 0.0889)
		(layer "In11.Cu")
		(net "H_CPU1_MEMGHJ_MEMHOT_G_N")
	)
	(arc
		(start 126.499112 -89.489788)
		(mid 126.305262 -89.433438)
		(end 126.163578 -89.289636)
		(width 0.0889)
		(layer "In11.Cu")
		(net "H_CPU1_MEMGHJ_MEMHOT_G_N")
	)
	(arc
		(start 122.729498 -87.308436)
		(mid 122.52089 -87.096504)
		(end 122.235468 -87.013034)
		(width 0.0889)
		(layer "In11.Cu")
		(net "H_CPU1_MEMGHJ_MEMHOT_G_N")
	)
	(arc
		(start 122.202702 -87.013034)
		(mid 122.01106 -86.955868)
		(end 121.870978 -86.813136)
		(width 0.0889)
		(layer "In11.Cu")
		(net "H_CPU1_MEMGHJ_MEMHOT_G_N")
	)
	(arc
		(start 134.748524 -94.242636)
		(mid 134.537811 -94.029557)
		(end 134.249668 -93.947234)
		(width 0.0889)
		(layer "In11.Cu")
		(net "H_CPU1_MEMGHJ_MEMHOT_G_N")
	)
	(arc
		(start 128.739138 -90.775536)
		(mid 128.532134 -90.564672)
		(end 128.248918 -90.480388)
		(width 0.0889)
		(layer "In11.Cu")
		(net "H_CPU1_MEMGHJ_MEMHOT_G_N")
	)
	(arc
		(start 127.880618 -90.280236)
		(mid 127.67201 -90.068304)
		(end 127.386588 -89.984834)
		(width 0.0889)
		(layer "In11.Cu")
		(net "H_CPU1_MEMGHJ_MEMHOT_G_N")
	)
	(arc
		(start 133.031484 -93.252036)
		(mid 132.822876 -93.040104)
		(end 132.537454 -92.956634)
		(width 0.0889)
		(layer "In11.Cu")
		(net "H_CPU1_MEMGHJ_MEMHOT_G_N")
	)
	(arc
		(start 131.149598 -64.619886)
		(mid 130.802888 -64.419575)
		(end 130.456178 -64.619886)
		(width 0.0889)
		(layer "In11.Cu")
		(net "H_CPU1_MEMGHJ_MEMHOT_G_N")
	)
	(arc
		(start 132.519674 -92.956634)
		(mid 132.322513 -92.904675)
		(end 132.17652 -92.762324)
		(width 0.0889)
		(layer "In11.Cu")
		(net "H_CPU1_MEMGHJ_MEMHOT_G_N")
	)
	(arc
		(start 123.065032 -87.508588)
		(mid 122.871182 -87.452238)
		(end 122.729498 -87.308436)
		(width 0.0889)
		(layer "In11.Cu")
		(net "H_CPU1_MEMGHJ_MEMHOT_G_N")
	)
	(arc
		(start 130.456178 -91.766136)
		(mid 130.249174 -91.555272)
		(end 129.965958 -91.470988)
		(width 0.0889)
		(layer "In11.Cu")
		(net "H_CPU1_MEMGHJ_MEMHOT_G_N")
	)
	(arc
		(start 125.636782 -88.994234)
		(mid 125.44514 -88.937068)
		(end 125.305058 -88.794336)
		(width 0.0889)
		(layer "In11.Cu")
		(net "H_CPU1_MEMGHJ_MEMHOT_G_N")
	)
	(arc
		(start 130.456178 -64.619886)
		(mid 130.242174 -64.848865)
		(end 129.949194 -64.960246)
		(width 0.0889)
		(layer "In11.Cu")
		(net "H_CPU1_MEMGHJ_MEMHOT_G_N")
	)
	(arc
		(start 129.933192 -91.470988)
		(mid 129.739342 -91.414638)
		(end 129.597658 -91.270836)
		(width 0.0889)
		(layer "In11.Cu")
		(net "H_CPU1_MEMGHJ_MEMHOT_G_N")
	)
	(arc
		(start 139.041124 -96.719136)
		(mid 138.83412 -96.508272)
		(end 138.550904 -96.423988)
		(width 0.0889)
		(layer "In11.Cu")
		(net "H_CPU1_MEMGHJ_MEMHOT_G_N")
	)
	(arc
		(start 126.495302 -65.905888)
		(mid 126.30366 -65.963054)
		(end 126.163578 -66.105786)
		(width 0.0889)
		(layer "In11.Cu")
		(net "H_CPU1_MEMGHJ_MEMHOT_G_N")
	)
	(arc
		(start 125.305058 -88.794336)
		(mid 125.098054 -88.583472)
		(end 124.814838 -88.499188)
		(width 0.0889)
		(layer "In11.Cu")
		(net "H_CPU1_MEMGHJ_MEMHOT_G_N")
	)
	(arc
		(start 135.607044 -94.737936)
		(mid 135.398436 -94.526004)
		(end 135.113014 -94.442534)
		(width 0.0889)
		(layer "In11.Cu")
		(net "H_CPU1_MEMGHJ_MEMHOT_G_N")
	)
	(arc
		(start 126.163578 -89.289636)
		(mid 125.95497 -89.077704)
		(end 125.669548 -88.994234)
		(width 0.0889)
		(layer "In11.Cu")
		(net "H_CPU1_MEMGHJ_MEMHOT_G_N")
	)
	(arc
		(start 126.163578 -66.105786)
		(mid 125.956574 -66.31665)
		(end 125.673358 -66.400934)
		(width 0.0889)
		(layer "In11.Cu")
		(net "H_CPU1_MEMGHJ_MEMHOT_G_N")
	)
	(arc
		(start 131.650232 -92.461588)
		(mid 131.456382 -92.405238)
		(end 131.314698 -92.261436)
		(width 0.0889)
		(layer "In11.Cu")
		(net "H_CPU1_MEMGHJ_MEMHOT_G_N")
	)
	(arc
		(start 129.070862 -90.975434)
		(mid 128.87922 -90.918268)
		(end 128.739138 -90.775536)
		(width 0.0889)
		(layer "In11.Cu")
		(net "H_CPU1_MEMGHJ_MEMHOT_G_N")
	)
	(arc
		(start 131.314698 -92.261436)
		(mid 131.10609 -92.049504)
		(end 130.820668 -91.966034)
		(width 0.0889)
		(layer "In11.Cu")
		(net "H_CPU1_MEMGHJ_MEMHOT_G_N")
	)
	(arc
		(start 135.93572 -94.937834)
		(mid 135.745791 -94.879964)
		(end 135.607044 -94.737936)
		(width 0.0889)
		(layer "In11.Cu")
		(net "H_CPU1_MEMGHJ_MEMHOT_G_N")
	)
	(arc
		(start 139.372848 -96.919034)
		(mid 139.181206 -96.861868)
		(end 139.041124 -96.719136)
		(width 0.0889)
		(layer "In11.Cu")
		(net "H_CPU1_MEMGHJ_MEMHOT_G_N")
	)
	(arc
		(start 126.669038 -65.884552)
		(mid 126.599199 -65.899487)
		(end 126.528068 -65.905888)
		(width 0.0889)
		(layer "In11.Cu")
		(net "H_CPU1_MEMGHJ_MEMHOT_G_N")
	)
	(arc
		(start 137.655808 -95.928434)
		(mid 137.464166 -95.871268)
		(end 137.324084 -95.728536)
		(width 0.0889)
		(layer "In11.Cu")
		(net "H_CPU1_MEMGHJ_MEMHOT_G_N")
	)
	(arc
		(start 127.022098 -89.784936)
		(mid 126.815094 -89.574072)
		(end 126.531878 -89.489788)
		(width 0.0889)
		(layer "In11.Cu")
		(net "H_CPU1_MEMGHJ_MEMHOT_G_N")
	)
	(arc
		(start 138.518138 -96.423988)
		(mid 138.324288 -96.367638)
		(end 138.182604 -96.223836)
		(width 0.0889)
		(layer "In11.Cu")
		(net "H_CPU1_MEMGHJ_MEMHOT_G_N")
	)
	(arc
		(start 132.173218 -92.756482)
		(mid 131.967597 -92.546559)
		(end 131.6863 -92.461588)
		(width 0.0889)
		(layer "In11.Cu")
		(net "H_CPU1_MEMGHJ_MEMHOT_G_N")
	)
	(arc
		(start 131.643628 -64.915288)
		(mid 131.358204 -64.831821)
		(end 131.149598 -64.619886)
		(width 0.0889)
		(layer "In11.Cu")
		(net "H_CPU1_MEMGHJ_MEMHOT_G_N")
	)
	(arc
		(start 130.787902 -91.966034)
		(mid 130.59626 -91.908868)
		(end 130.456178 -91.766136)
		(width 0.0889)
		(layer "In11.Cu")
		(net "H_CPU1_MEMGHJ_MEMHOT_G_N")
	)
	(arc
		(start 128.216152 -90.480388)
		(mid 128.022302 -90.424038)
		(end 127.880618 -90.280236)
		(width 0.0889)
		(layer "In11.Cu")
		(net "H_CPU1_MEMGHJ_MEMHOT_G_N")
	)
	(arc
		(start 123.588018 -87.803736)
		(mid 123.381014 -87.592872)
		(end 123.097798 -87.508588)
		(width 0.0889)
		(layer "In11.Cu")
		(net "H_CPU1_MEMGHJ_MEMHOT_G_N")
	)
	(arc
		(start 132.519674 -64.819784)
		(mid 132.267365 -64.882194)
		(end 132.009134 -64.911732)
		(width 0.0889)
		(layer "In11.Cu")
		(net "H_CPU1_MEMGHJ_MEMHOT_G_N")
	)
	(arc
		(start 136.801098 -95.433134)
		(mid 136.607248 -95.376784)
		(end 136.465564 -95.232982)
		(width 0.0889)
		(layer "In11.Cu")
		(net "H_CPU1_MEMGHJ_MEMHOT_G_N")
	)
	(arc
		(start 121.359168 -86.517988)
		(mid 121.162007 -86.466029)
		(end 121.016014 -86.323678)
		(width 0.0889)
		(layer "In11.Cu")
		(net "H_CPU1_MEMGHJ_MEMHOT_G_N")
	)
	(arc
		(start 124.782072 -88.499188)
		(mid 124.588222 -88.442838)
		(end 124.446538 -88.299036)
		(width 0.0889)
		(layer "In11.Cu")
		(net "H_CPU1_MEMGHJ_MEMHOT_G_N")
	)
	(arc
		(start 129.597658 -91.270836)
		(mid 129.38905 -91.058904)
		(end 129.103628 -90.975434)
		(width 0.0889)
		(layer "In11.Cu")
		(net "H_CPU1_MEMGHJ_MEMHOT_G_N")
	)
	(arc
		(start 136.465564 -95.232982)
		(mid 136.25856 -95.022118)
		(end 135.975344 -94.937834)
		(width 0.0889)
		(layer "In11.Cu")
		(net "H_CPU1_MEMGHJ_MEMHOT_G_N")
	)
	(arc
		(start 133.367018 -93.452188)
		(mid 133.173168 -93.395838)
		(end 133.031484 -93.252036)
		(width 0.0889)
		(layer "In11.Cu")
		(net "H_CPU1_MEMGHJ_MEMHOT_G_N")
	)
	(arc
		(start 134.221728 -93.947234)
		(mid 134.030086 -93.890068)
		(end 133.890004 -93.747336)
		(width 0.0889)
		(layer "In11.Cu")
		(net "H_CPU1_MEMGHJ_MEMHOT_G_N")
	)
	(arc
		(start 121.870978 -86.813136)
		(mid 121.663974 -86.602272)
		(end 121.380758 -86.517988)
		(width 0.0889)
		(layer "In11.Cu")
		(net "H_CPU1_MEMGHJ_MEMHOT_G_N")
	)
	(arc
		(start 137.324084 -95.728536)
		(mid 137.113371 -95.515457)
		(end 136.825228 -95.433134)
		(width 0.0889)
		(layer "In11.Cu")
		(net "H_CPU1_MEMGHJ_MEMHOT_G_N")
	)
	(arc
		(start 135.0772 -94.442534)
		(mid 134.887271 -94.384664)
		(end 134.748524 -94.242636)
		(width 0.0889)
		(layer "In11.Cu")
		(net "H_CPU1_MEMGHJ_MEMHOT_G_N")
	)
	(arc
		(start 138.182604 -96.223836)
		(mid 137.973996 -96.011904)
		(end 137.688574 -95.928434)
		(width 0.0889)
		(layer "In11.Cu")
		(net "H_CPU1_MEMGHJ_MEMHOT_G_N")
	)
	(arc
		(start 127.353822 -89.984834)
		(mid 127.16218 -89.927668)
		(end 127.022098 -89.784936)
		(width 0.0889)
		(layer "In11.Cu")
		(net "H_CPU1_MEMGHJ_MEMHOT_G_N")
	)
	(via
		(at 409.702 -85.8266)
		(size 0.6604)
		(drill 0.3302)
		(layers "F.Cu" "B.Cu")
		(net "H_CPU1_MEMGHJ_MEMHOT")
	)
	(segment
		(start 411.662118 -88.176354)
		(end 412.356554 -88.176354)
		(width 0.10795)
		(layer "B.Cu")
		(net "H_CPU1_MEMGHJ_MEMHOT")
	)
	(segment
		(start 410.99359 -87.569548)
		(end 410.99359 -88.077548)
		(width 0.10795)
		(layer "B.Cu")
		(net "H_CPU1_MEMGHJ_MEMHOT")
	)
	(segment
		(start 412.4833 -89.284302)
		(end 412.619698 -89.4207)
		(width 0.10795)
		(layer "B.Cu")
		(net "H_CPU1_MEMGHJ_MEMHOT")
	)
	(segment
		(start 409.702 -85.8266)
		(end 410.977842 -87.102442)
		(width 0.10795)
		(layer "B.Cu")
		(net "H_CPU1_MEMGHJ_MEMHOT")
	)
	(segment
		(start 412.4833 -88.3031)
		(end 412.4833 -89.284302)
		(width 0.10795)
		(layer "B.Cu")
		(net "H_CPU1_MEMGHJ_MEMHOT")
	)
	(segment
		(start 412.619698 -89.4207)
		(end 413.0548 -89.4207)
		(width 0.10795)
		(layer "B.Cu")
		(net "H_CPU1_MEMGHJ_MEMHOT")
	)
	(segment
		(start 411.092396 -88.176354)
		(end 411.662118 -88.176354)
		(width 0.10795)
		(layer "B.Cu")
		(net "H_CPU1_MEMGHJ_MEMHOT")
	)
	(segment
		(start 411.554168 -87.102442)
		(end 411.662118 -87.210392)
		(width 0.10795)
		(layer "B.Cu")
		(net "H_CPU1_MEMGHJ_MEMHOT")
	)
	(segment
		(start 412.356554 -88.176354)
		(end 412.4833 -88.3031)
		(width 0.10795)
		(layer "B.Cu")
		(net "H_CPU1_MEMGHJ_MEMHOT")
	)
	(segment
		(start 411.662118 -87.526114)
		(end 411.037024 -87.526114)
		(width 0.10795)
		(layer "B.Cu")
		(net "H_CPU1_MEMGHJ_MEMHOT")
	)
	(segment
		(start 410.977842 -87.102442)
		(end 411.554168 -87.102442)
		(width 0.10795)
		(layer "B.Cu")
		(net "H_CPU1_MEMGHJ_MEMHOT")
	)
	(segment
		(start 410.99359 -88.077548)
		(end 411.092396 -88.176354)
		(width 0.10795)
		(layer "B.Cu")
		(net "H_CPU1_MEMGHJ_MEMHOT")
	)
	(segment
		(start 411.662118 -87.210392)
		(end 411.662118 -87.526114)
		(width 0.10795)
		(layer "B.Cu")
		(net "H_CPU1_MEMGHJ_MEMHOT")
	)
	(segment
		(start 411.037024 -87.526114)
		(end 410.99359 -87.569548)
		(width 0.10795)
		(layer "B.Cu")
		(net "H_CPU1_MEMGHJ_MEMHOT")
	)
	(segment
		(start 131.089908 -69.277738)
		(end 131.661408 -69.277738)
		(width 0.1016)
		(layer "F.Cu")
		(net "H_CPU1_FIVR_FAULT_G")
	)
	(via
		(at 131.661408 -69.277738)
		(size 0.508)
		(drill 0.254)
		(layers "F.Cu" "B.Cu")
		(net "H_CPU1_FIVR_FAULT_G")
	)
	(via
		(at 325.576946 -49.07026)
		(size 0.508)
		(drill 0.254)
		(layers "F.Cu" "B.Cu")
		(net "H_CPU1_FIVR_FAULT_G")
	)
	(via
		(at 370.412772 -61.722)
		(size 0.508)
		(drill 0.254)
		(layers "F.Cu" "B.Cu")
		(net "H_CPU1_FIVR_FAULT_G")
	)
	(segment
		(start 368.9477 -62.357)
		(end 368.332512 -61.741812)
		(width 0.10795)
		(layer "B.Cu")
		(net "H_CPU1_FIVR_FAULT_G")
	)
	(segment
		(start 370.412772 -61.726826)
		(end 370.412772 -61.722)
		(width 0.10795)
		(layer "B.Cu")
		(net "H_CPU1_FIVR_FAULT_G")
	)
	(segment
		(start 368.332512 -61.741812)
		(end 368.332512 -60.091828)
		(width 0.10795)
		(layer "B.Cu")
		(net "H_CPU1_FIVR_FAULT_G")
	)
	(segment
		(start 370.459 -62.357)
		(end 370.459 -61.763402)
		(width 0.10795)
		(layer "B.Cu")
		(net "H_CPU1_FIVR_FAULT_G")
	)
	(segment
		(start 368.8461 -59.57824)
		(end 370.3955 -59.57824)
		(width 0.10795)
		(layer "B.Cu")
		(net "H_CPU1_FIVR_FAULT_G")
	)
	(segment
		(start 370.459 -62.357)
		(end 368.9477 -62.357)
		(width 0.10795)
		(layer "B.Cu")
		(net "H_CPU1_FIVR_FAULT_G")
	)
	(segment
		(start 370.417598 -61.722)
		(end 370.417598 -61.726826)
		(width 0.10795)
		(layer "B.Cu")
		(net "H_CPU1_FIVR_FAULT_G")
	)
	(segment
		(start 370.459 -61.763402)
		(end 370.417598 -61.722)
		(width 0.10795)
		(layer "B.Cu")
		(net "H_CPU1_FIVR_FAULT_G")
	)
	(segment
		(start 368.332512 -60.091828)
		(end 368.8461 -59.57824)
		(width 0.10795)
		(layer "B.Cu")
		(net "H_CPU1_FIVR_FAULT_G")
	)
	(segment
		(start 370.417598 -61.726826)
		(end 370.412772 -61.726826)
		(width 0.10795)
		(layer "B.Cu")
		(net "H_CPU1_FIVR_FAULT_G")
	)
	(segment
		(start 153.228294 -29.440378)
		(end 148.205952 -34.46272)
		(width 0.089408)
		(layer "In9.Cu")
		(net "H_CPU1_FIVR_FAULT_G")
	)
	(segment
		(start 182.635906 -16.807688)
		(end 181.611778 -17.831816)
		(width 0.089408)
		(layer "In9.Cu")
		(net "H_CPU1_FIVR_FAULT_G")
	)
	(segment
		(start 176.654206 -20.061428)
		(end 174.972472 -20.061428)
		(width 0.089408)
		(layer "In9.Cu")
		(net "H_CPU1_FIVR_FAULT_G")
	)
	(segment
		(start 174.972472 -20.061428)
		(end 173.049184 -21.984716)
		(width 0.089408)
		(layer "In9.Cu")
		(net "H_CPU1_FIVR_FAULT_G")
	)
	(segment
		(start 123.581922 -40.084502)
		(end 123.581922 -50.230278)
		(width 0.089408)
		(layer "In9.Cu")
		(net "H_CPU1_FIVR_FAULT_G")
	)
	(segment
		(start 125.930914 -61.40196)
		(end 126.280672 -61.751718)
		(width 0.089408)
		(layer "In9.Cu")
		(net "H_CPU1_FIVR_FAULT_G")
	)
	(segment
		(start 326.653144 -15.905226)
		(end 324.306438 -13.55852)
		(width 0.089408)
		(layer "In9.Cu")
		(net "H_CPU1_FIVR_FAULT_G")
	)
	(segment
		(start 327.725532 -46.441106)
		(end 330.696824 -43.469814)
		(width 0.089408)
		(layer "In9.Cu")
		(net "H_CPU1_FIVR_FAULT_G")
	)
	(segment
		(start 329.477878 -23.607014)
		(end 328.71918 -22.848316)
		(width 0.089408)
		(layer "In9.Cu")
		(net "H_CPU1_FIVR_FAULT_G")
	)
	(segment
		(start 186.269122 -12.37234)
		(end 186.269122 -13.37564)
		(width 0.089408)
		(layer "In9.Cu")
		(net "H_CPU1_FIVR_FAULT_G")
	)
	(segment
		(start 128.423924 -61.803788)
		(end 129.017014 -62.396878)
		(width 0.089408)
		(layer "In9.Cu")
		(net "H_CPU1_FIVR_FAULT_G")
	)
	(segment
		(start 122.093482 -59.85256)
		(end 122.60072 -60.359798)
		(width 0.089408)
		(layer "In9.Cu")
		(net "H_CPU1_FIVR_FAULT_G")
	)
	(segment
		(start 122.60072 -60.359798)
		(end 122.971306 -60.359798)
		(width 0.089408)
		(layer "In9.Cu")
		(net "H_CPU1_FIVR_FAULT_G")
	)
	(segment
		(start 262.917432 -10.481564)
		(end 261.726934 -9.291066)
		(width 0.089408)
		(layer "In9.Cu")
		(net "H_CPU1_FIVR_FAULT_G")
	)
	(segment
		(start 123.581922 -50.230278)
		(end 121.773442 -52.038758)
		(width 0.089408)
		(layer "In9.Cu")
		(net "H_CPU1_FIVR_FAULT_G")
	)
	(segment
		(start 330.578968 -38.672516)
		(end 330.578968 -33.348422)
		(width 0.089408)
		(layer "In9.Cu")
		(net "H_CPU1_FIVR_FAULT_G")
	)
	(segment
		(start 330.915264 -40.93083)
		(end 330.915264 -39.008812)
		(width 0.089408)
		(layer "In9.Cu")
		(net "H_CPU1_FIVR_FAULT_G")
	)
	(segment
		(start 186.269122 -13.37564)
		(end 184.815226 -14.829536)
		(width 0.089408)
		(layer "In9.Cu")
		(net "H_CPU1_FIVR_FAULT_G")
	)
	(segment
		(start 261.277862 -9.291066)
		(end 258.672838 -6.686042)
		(width 0.089408)
		(layer "In9.Cu")
		(net "H_CPU1_FIVR_FAULT_G")
	)
	(segment
		(start 159.910018 -21.097748)
		(end 159.910018 -25.173432)
		(width 0.089408)
		(layer "In9.Cu")
		(net "H_CPU1_FIVR_FAULT_G")
	)
	(segment
		(start 328.7522 -27.3812)
		(end 328.7522 -25.846278)
		(width 0.089408)
		(layer "In9.Cu")
		(net "H_CPU1_FIVR_FAULT_G")
	)
	(segment
		(start 130.401822 -63.227458)
		(end 130.401822 -65.001648)
		(width 0.089408)
		(layer "In9.Cu")
		(net "H_CPU1_FIVR_FAULT_G")
	)
	(segment
		(start 329.477878 -28.106878)
		(end 328.7522 -27.3812)
		(width 0.089408)
		(layer "In9.Cu")
		(net "H_CPU1_FIVR_FAULT_G")
	)
	(segment
		(start 178.729894 -19.792696)
		(end 176.922938 -19.792696)
		(width 0.089408)
		(layer "In9.Cu")
		(net "H_CPU1_FIVR_FAULT_G")
	)
	(segment
		(start 124.456444 -61.40196)
		(end 125.930914 -61.40196)
		(width 0.089408)
		(layer "In9.Cu")
		(net "H_CPU1_FIVR_FAULT_G")
	)
	(segment
		(start 160.683702 -20.324064)
		(end 159.910018 -21.097748)
		(width 0.089408)
		(layer "In9.Cu")
		(net "H_CPU1_FIVR_FAULT_G")
	)
	(segment
		(start 184.17413 -14.829536)
		(end 182.635906 -16.36776)
		(width 0.089408)
		(layer "In9.Cu")
		(net "H_CPU1_FIVR_FAULT_G")
	)
	(segment
		(start 131.953 -65.8876)
		(end 132.08 -66.0146)
		(width 0.089408)
		(layer "In9.Cu")
		(net "H_CPU1_FIVR_FAULT_G")
	)
	(segment
		(start 121.85015 -59.85256)
		(end 122.093482 -59.85256)
		(width 0.089408)
		(layer "In9.Cu")
		(net "H_CPU1_FIVR_FAULT_G")
	)
	(segment
		(start 123.90374 -60.849256)
		(end 124.456444 -61.40196)
		(width 0.089408)
		(layer "In9.Cu")
		(net "H_CPU1_FIVR_FAULT_G")
	)
	(segment
		(start 328.71918 -22.848316)
		(end 328.71918 -17.011904)
		(width 0.089408)
		(layer "In9.Cu")
		(net "H_CPU1_FIVR_FAULT_G")
	)
	(segment
		(start 170.61053 -21.984716)
		(end 168.949878 -20.324064)
		(width 0.089408)
		(layer "In9.Cu")
		(net "H_CPU1_FIVR_FAULT_G")
	)
	(segment
		(start 127.67437 -61.39434)
		(end 128.083818 -61.803788)
		(width 0.089408)
		(layer "In9.Cu")
		(net "H_CPU1_FIVR_FAULT_G")
	)
	(segment
		(start 189.96787 -10.527538)
		(end 188.113924 -10.527538)
		(width 0.089408)
		(layer "In9.Cu")
		(net "H_CPU1_FIVR_FAULT_G")
	)
	(segment
		(start 324.306438 -11.669776)
		(end 322.92417 -10.287508)
		(width 0.089408)
		(layer "In9.Cu")
		(net "H_CPU1_FIVR_FAULT_G")
	)
	(segment
		(start 188.113924 -10.527538)
		(end 186.269122 -12.37234)
		(width 0.089408)
		(layer "In9.Cu")
		(net "H_CPU1_FIVR_FAULT_G")
	)
	(segment
		(start 181.611778 -17.831816)
		(end 180.690774 -17.831816)
		(width 0.089408)
		(layer "In9.Cu")
		(net "H_CPU1_FIVR_FAULT_G")
	)
	(segment
		(start 182.635906 -16.36776)
		(end 182.635906 -16.807688)
		(width 0.089408)
		(layer "In9.Cu")
		(net "H_CPU1_FIVR_FAULT_G")
	)
	(segment
		(start 324.306438 -13.55852)
		(end 324.306438 -11.669776)
		(width 0.089408)
		(layer "In9.Cu")
		(net "H_CPU1_FIVR_FAULT_G")
	)
	(segment
		(start 326.387968 -46.441106)
		(end 327.725532 -46.441106)
		(width 0.089408)
		(layer "In9.Cu")
		(net "H_CPU1_FIVR_FAULT_G")
	)
	(segment
		(start 132.08 -66.0146)
		(end 132.08 -68.859146)
		(width 0.089408)
		(layer "In9.Cu")
		(net "H_CPU1_FIVR_FAULT_G")
	)
	(segment
		(start 148.205952 -34.46272)
		(end 129.203704 -34.46272)
		(width 0.089408)
		(layer "In9.Cu")
		(net "H_CPU1_FIVR_FAULT_G")
	)
	(segment
		(start 176.922938 -19.792696)
		(end 176.654206 -20.061428)
		(width 0.089408)
		(layer "In9.Cu")
		(net "H_CPU1_FIVR_FAULT_G")
	)
	(segment
		(start 264.79373 -10.287508)
		(end 264.599674 -10.481564)
		(width 0.089408)
		(layer "In9.Cu")
		(net "H_CPU1_FIVR_FAULT_G")
	)
	(segment
		(start 155.27655 -28.535884)
		(end 154.372056 -29.440378)
		(width 0.089408)
		(layer "In9.Cu")
		(net "H_CPU1_FIVR_FAULT_G")
	)
	(segment
		(start 129.017014 -62.396878)
		(end 129.433574 -62.396878)
		(width 0.089408)
		(layer "In9.Cu")
		(net "H_CPU1_FIVR_FAULT_G")
	)
	(segment
		(start 121.767854 -52.038758)
		(end 121.534428 -52.272184)
		(width 0.089408)
		(layer "In9.Cu")
		(net "H_CPU1_FIVR_FAULT_G")
	)
	(segment
		(start 126.776226 -61.751718)
		(end 127.133604 -61.39434)
		(width 0.089408)
		(layer "In9.Cu")
		(net "H_CPU1_FIVR_FAULT_G")
	)
	(segment
		(start 128.083818 -61.803788)
		(end 128.423924 -61.803788)
		(width 0.089408)
		(layer "In9.Cu")
		(net "H_CPU1_FIVR_FAULT_G")
	)
	(segment
		(start 132.08 -68.859146)
		(end 131.661408 -69.277738)
		(width 0.089408)
		(layer "In9.Cu")
		(net "H_CPU1_FIVR_FAULT_G")
	)
	(segment
		(start 173.049184 -21.984716)
		(end 170.61053 -21.984716)
		(width 0.089408)
		(layer "In9.Cu")
		(net "H_CPU1_FIVR_FAULT_G")
	)
	(segment
		(start 195.166742 -6.686042)
		(end 193.133472 -8.719312)
		(width 0.089408)
		(layer "In9.Cu")
		(net "H_CPU1_FIVR_FAULT_G")
	)
	(segment
		(start 121.773442 -52.038758)
		(end 121.767854 -52.038758)
		(width 0.089408)
		(layer "In9.Cu")
		(net "H_CPU1_FIVR_FAULT_G")
	)
	(segment
		(start 129.203704 -34.46272)
		(end 123.581922 -40.084502)
		(width 0.089408)
		(layer "In9.Cu")
		(net "H_CPU1_FIVR_FAULT_G")
	)
	(segment
		(start 129.433574 -62.396878)
		(end 129.779014 -62.742318)
		(width 0.089408)
		(layer "In9.Cu")
		(net "H_CPU1_FIVR_FAULT_G")
	)
	(segment
		(start 159.910018 -25.173432)
		(end 156.547566 -28.535884)
		(width 0.089408)
		(layer "In9.Cu")
		(net "H_CPU1_FIVR_FAULT_G")
	)
	(segment
		(start 131.5466 -65.8876)
		(end 131.953 -65.8876)
		(width 0.089408)
		(layer "In9.Cu")
		(net "H_CPU1_FIVR_FAULT_G")
	)
	(segment
		(start 330.696824 -41.14927)
		(end 330.915264 -40.93083)
		(width 0.089408)
		(layer "In9.Cu")
		(net "H_CPU1_FIVR_FAULT_G")
	)
	(segment
		(start 191.776096 -8.719312)
		(end 189.96787 -10.527538)
		(width 0.089408)
		(layer "In9.Cu")
		(net "H_CPU1_FIVR_FAULT_G")
	)
	(segment
		(start 168.949878 -20.324064)
		(end 160.683702 -20.324064)
		(width 0.089408)
		(layer "In9.Cu")
		(net "H_CPU1_FIVR_FAULT_G")
	)
	(segment
		(start 330.696824 -43.469814)
		(end 330.696824 -41.14927)
		(width 0.089408)
		(layer "In9.Cu")
		(net "H_CPU1_FIVR_FAULT_G")
	)
	(segment
		(start 329.477878 -32.247332)
		(end 329.477878 -28.106878)
		(width 0.089408)
		(layer "In9.Cu")
		(net "H_CPU1_FIVR_FAULT_G")
	)
	(segment
		(start 330.915264 -39.008812)
		(end 330.578968 -38.672516)
		(width 0.089408)
		(layer "In9.Cu")
		(net "H_CPU1_FIVR_FAULT_G")
	)
	(segment
		(start 156.547566 -28.535884)
		(end 155.27655 -28.535884)
		(width 0.089408)
		(layer "In9.Cu")
		(net "H_CPU1_FIVR_FAULT_G")
	)
	(segment
		(start 328.71918 -17.011904)
		(end 327.612502 -15.905226)
		(width 0.089408)
		(layer "In9.Cu")
		(net "H_CPU1_FIVR_FAULT_G")
	)
	(segment
		(start 131.064 -65.405)
		(end 131.5466 -65.8876)
		(width 0.089408)
		(layer "In9.Cu")
		(net "H_CPU1_FIVR_FAULT_G")
	)
	(segment
		(start 325.576946 -47.252128)
		(end 326.387968 -46.441106)
		(width 0.089408)
		(layer "In9.Cu")
		(net "H_CPU1_FIVR_FAULT_G")
	)
	(segment
		(start 122.971306 -60.359798)
		(end 123.460764 -60.849256)
		(width 0.089408)
		(layer "In9.Cu")
		(net "H_CPU1_FIVR_FAULT_G")
	)
	(segment
		(start 127.133604 -61.39434)
		(end 127.67437 -61.39434)
		(width 0.089408)
		(layer "In9.Cu")
		(net "H_CPU1_FIVR_FAULT_G")
	)
	(segment
		(start 322.92417 -10.287508)
		(end 264.79373 -10.287508)
		(width 0.089408)
		(layer "In9.Cu")
		(net "H_CPU1_FIVR_FAULT_G")
	)
	(segment
		(start 264.599674 -10.481564)
		(end 262.917432 -10.481564)
		(width 0.089408)
		(layer "In9.Cu")
		(net "H_CPU1_FIVR_FAULT_G")
	)
	(segment
		(start 261.726934 -9.291066)
		(end 261.277862 -9.291066)
		(width 0.089408)
		(layer "In9.Cu")
		(net "H_CPU1_FIVR_FAULT_G")
	)
	(segment
		(start 328.7522 -25.846278)
		(end 329.477878 -25.1206)
		(width 0.089408)
		(layer "In9.Cu")
		(net "H_CPU1_FIVR_FAULT_G")
	)
	(segment
		(start 329.477878 -25.1206)
		(end 329.477878 -23.607014)
		(width 0.089408)
		(layer "In9.Cu")
		(net "H_CPU1_FIVR_FAULT_G")
	)
	(segment
		(start 180.690774 -17.831816)
		(end 178.729894 -19.792696)
		(width 0.089408)
		(layer "In9.Cu")
		(net "H_CPU1_FIVR_FAULT_G")
	)
	(segment
		(start 129.779014 -62.742318)
		(end 129.916682 -62.742318)
		(width 0.089408)
		(layer "In9.Cu")
		(net "H_CPU1_FIVR_FAULT_G")
	)
	(segment
		(start 121.534428 -52.272184)
		(end 121.534428 -59.536838)
		(width 0.089408)
		(layer "In9.Cu")
		(net "H_CPU1_FIVR_FAULT_G")
	)
	(segment
		(start 325.576946 -49.07026)
		(end 325.576946 -47.252128)
		(width 0.089408)
		(layer "In9.Cu")
		(net "H_CPU1_FIVR_FAULT_G")
	)
	(segment
		(start 129.916682 -62.742318)
		(end 130.401822 -63.227458)
		(width 0.089408)
		(layer "In9.Cu")
		(net "H_CPU1_FIVR_FAULT_G")
	)
	(segment
		(start 193.133472 -8.719312)
		(end 191.776096 -8.719312)
		(width 0.089408)
		(layer "In9.Cu")
		(net "H_CPU1_FIVR_FAULT_G")
	)
	(segment
		(start 123.460764 -60.849256)
		(end 123.90374 -60.849256)
		(width 0.089408)
		(layer "In9.Cu")
		(net "H_CPU1_FIVR_FAULT_G")
	)
	(segment
		(start 184.815226 -14.829536)
		(end 184.17413 -14.829536)
		(width 0.089408)
		(layer "In9.Cu")
		(net "H_CPU1_FIVR_FAULT_G")
	)
	(segment
		(start 121.534428 -59.536838)
		(end 121.85015 -59.85256)
		(width 0.089408)
		(layer "In9.Cu")
		(net "H_CPU1_FIVR_FAULT_G")
	)
	(segment
		(start 258.672838 -6.686042)
		(end 195.166742 -6.686042)
		(width 0.089408)
		(layer "In9.Cu")
		(net "H_CPU1_FIVR_FAULT_G")
	)
	(segment
		(start 130.401822 -65.001648)
		(end 130.805174 -65.405)
		(width 0.089408)
		(layer "In9.Cu")
		(net "H_CPU1_FIVR_FAULT_G")
	)
	(segment
		(start 126.280672 -61.751718)
		(end 126.776226 -61.751718)
		(width 0.089408)
		(layer "In9.Cu")
		(net "H_CPU1_FIVR_FAULT_G")
	)
	(segment
		(start 330.578968 -33.348422)
		(end 329.477878 -32.247332)
		(width 0.089408)
		(layer "In9.Cu")
		(net "H_CPU1_FIVR_FAULT_G")
	)
	(segment
		(start 154.372056 -29.440378)
		(end 153.228294 -29.440378)
		(width 0.089408)
		(layer "In9.Cu")
		(net "H_CPU1_FIVR_FAULT_G")
	)
	(segment
		(start 327.612502 -15.905226)
		(end 326.653144 -15.905226)
		(width 0.089408)
		(layer "In9.Cu")
		(net "H_CPU1_FIVR_FAULT_G")
	)
	(segment
		(start 130.805174 -65.405)
		(end 131.064 -65.405)
		(width 0.089408)
		(layer "In9.Cu")
		(net "H_CPU1_FIVR_FAULT_G")
	)
	(segment
		(start 341.915242 -53.265324)
		(end 342.573102 -53.923184)
		(width 0.089408)
		(layer "In11.Cu")
		(net "H_CPU1_FIVR_FAULT_G")
	)
	(segment
		(start 365.04499 -56.914288)
		(end 365.045244 -56.914034)
		(width 0.089408)
		(layer "In11.Cu")
		(net "H_CPU1_FIVR_FAULT_G")
	)
	(segment
		(start 341.915242 -52.967382)
		(end 341.915242 -53.265324)
		(width 0.089408)
		(layer "In11.Cu")
		(net "H_CPU1_FIVR_FAULT_G")
	)
	(segment
		(start 365.203232 -56.914034)
		(end 365.203486 -56.91378)
		(width 0.089408)
		(layer "In11.Cu")
		(net "H_CPU1_FIVR_FAULT_G")
	)
	(segment
		(start 357.07955 -52.015898)
		(end 357.07955 -52.613814)
		(width 0.089408)
		(layer "In11.Cu")
		(net "H_CPU1_FIVR_FAULT_G")
	)
	(segment
		(start 360.090466 -52.983892)
		(end 364.020862 -56.914288)
		(width 0.089408)
		(layer "In11.Cu")
		(net "H_CPU1_FIVR_FAULT_G")
	)
	(segment
		(start 369.847622 -61.277246)
		(end 370.292376 -61.722)
		(width 0.089408)
		(layer "In11.Cu")
		(net "H_CPU1_FIVR_FAULT_G")
	)
	(segment
		(start 337.853782 -51.48453)
		(end 337.854036 -51.484276)
		(width 0.089408)
		(layer "In11.Cu")
		(net "H_CPU1_FIVR_FAULT_G")
	)
	(segment
		(start 342.573102 -53.923184)
		(end 347.983048 -53.923184)
		(width 0.089408)
		(layer "In11.Cu")
		(net "H_CPU1_FIVR_FAULT_G")
	)
	(segment
		(start 365.361982 -56.914288)
		(end 365.48441 -56.914288)
		(width 0.089408)
		(layer "In11.Cu")
		(net "H_CPU1_FIVR_FAULT_G")
	)
	(segment
		(start 365.361474 -56.91378)
		(end 365.361982 -56.914288)
		(width 0.089408)
		(layer "In11.Cu")
		(net "H_CPU1_FIVR_FAULT_G")
	)
	(segment
		(start 357.449628 -52.983892)
		(end 360.090466 -52.983892)
		(width 0.089408)
		(layer "In11.Cu")
		(net "H_CPU1_FIVR_FAULT_G")
	)
	(segment
		(start 357.07955 -52.613814)
		(end 357.449628 -52.983892)
		(width 0.089408)
		(layer "In11.Cu")
		(net "H_CPU1_FIVR_FAULT_G")
	)
	(segment
		(start 350.709992 -51.19624)
		(end 356.259892 -51.19624)
		(width 0.089408)
		(layer "In11.Cu")
		(net "H_CPU1_FIVR_FAULT_G")
	)
	(segment
		(start 337.854036 -51.484276)
		(end 340.432136 -51.484276)
		(width 0.089408)
		(layer "In11.Cu")
		(net "H_CPU1_FIVR_FAULT_G")
	)
	(segment
		(start 356.259892 -51.19624)
		(end 357.07955 -52.015898)
		(width 0.089408)
		(layer "In11.Cu")
		(net "H_CPU1_FIVR_FAULT_G")
	)
	(segment
		(start 370.292376 -61.722)
		(end 370.412772 -61.722)
		(width 0.089408)
		(layer "In11.Cu")
		(net "H_CPU1_FIVR_FAULT_G")
	)
	(segment
		(start 325.576946 -49.07026)
		(end 327.991216 -51.48453)
		(width 0.089408)
		(layer "In11.Cu")
		(net "H_CPU1_FIVR_FAULT_G")
	)
	(segment
		(start 365.045244 -56.914034)
		(end 365.203232 -56.914034)
		(width 0.089408)
		(layer "In11.Cu")
		(net "H_CPU1_FIVR_FAULT_G")
	)
	(segment
		(start 347.983048 -53.923184)
		(end 350.709992 -51.19624)
		(width 0.089408)
		(layer "In11.Cu")
		(net "H_CPU1_FIVR_FAULT_G")
	)
	(segment
		(start 365.203486 -56.91378)
		(end 365.361474 -56.91378)
		(width 0.089408)
		(layer "In11.Cu")
		(net "H_CPU1_FIVR_FAULT_G")
	)
	(segment
		(start 340.432136 -51.484276)
		(end 341.915242 -52.967382)
		(width 0.089408)
		(layer "In11.Cu")
		(net "H_CPU1_FIVR_FAULT_G")
	)
	(segment
		(start 369.847368 -61.277246)
		(end 369.847622 -61.277246)
		(width 0.089408)
		(layer "In11.Cu")
		(net "H_CPU1_FIVR_FAULT_G")
	)
	(segment
		(start 364.020862 -56.914288)
		(end 365.04499 -56.914288)
		(width 0.089408)
		(layer "In11.Cu")
		(net "H_CPU1_FIVR_FAULT_G")
	)
	(segment
		(start 365.48441 -56.914288)
		(end 369.847368 -61.277246)
		(width 0.089408)
		(layer "In11.Cu")
		(net "H_CPU1_FIVR_FAULT_G")
	)
	(segment
		(start 327.991216 -51.48453)
		(end 337.853782 -51.48453)
		(width 0.089408)
		(layer "In11.Cu")
		(net "H_CPU1_FIVR_FAULT_G")
	)
	(segment
		(start 160.908746 -70.739)
		(end 158.623254 -70.739)
		(width 0.10795)
		(layer "F.Cu")
		(net "H_CPU1_FAST_WAKE_N")
	)
	(segment
		(start 161.723832 -70.54469)
		(end 161.103056 -70.54469)
		(width 0.10795)
		(layer "F.Cu")
		(net "H_CPU1_FAST_WAKE_N")
	)
	(segment
		(start 158.623254 -70.739)
		(end 157.042866 -69.158612)
		(width 0.10795)
		(layer "F.Cu")
		(net "H_CPU1_FAST_WAKE_N")
	)
	(segment
		(start 157.042866 -69.158612)
		(end 157.042866 -63.853822)
		(width 0.10795)
		(layer "F.Cu")
		(net "H_CPU1_FAST_WAKE_N")
	)
	(segment
		(start 130.231388 -63.829184)
		(end 130.802888 -63.829184)
		(width 0.1016)
		(layer "F.Cu")
		(net "H_CPU1_FAST_WAKE_N")
	)
	(segment
		(start 161.103056 -70.54469)
		(end 160.908746 -70.739)
		(width 0.10795)
		(layer "F.Cu")
		(net "H_CPU1_FAST_WAKE_N")
	)
	(via
		(at 130.802888 -63.829184)
		(size 0.508)
		(drill 0.254)
		(layers "F.Cu" "B.Cu")
		(net "H_CPU1_FAST_WAKE_N")
	)
	(via
		(at 157.042866 -63.853822)
		(size 0.508)
		(drill 0.254)
		(layers "F.Cu" "B.Cu")
		(net "H_CPU1_FAST_WAKE_N")
	)
	(segment
		(start 161.544 -66.929)
		(end 158.468822 -63.853822)
		(width 0.10795)
		(layer "B.Cu")
		(net "H_CPU1_FAST_WAKE_N")
	)
	(segment
		(start 162.179 -68.707)
		(end 161.77895 -68.707)
		(width 0.10795)
		(layer "B.Cu")
		(net "H_CPU1_FAST_WAKE_N")
	)
	(segment
		(start 158.468822 -63.853822)
		(end 157.042866 -63.853822)
		(width 0.10795)
		(layer "B.Cu")
		(net "H_CPU1_FAST_WAKE_N")
	)
	(segment
		(start 161.544 -68.47205)
		(end 161.544 -66.929)
		(width 0.10795)
		(layer "B.Cu")
		(net "H_CPU1_FAST_WAKE_N")
	)
	(segment
		(start 161.77895 -68.707)
		(end 161.544 -68.47205)
		(width 0.10795)
		(layer "B.Cu")
		(net "H_CPU1_FAST_WAKE_N")
	)
	(segment
		(start 135.932164 -63.429134)
		(end 135.96493 -63.429134)
		(width 0.0889)
		(layer "In11.Cu")
		(net "H_CPU1_FAST_WAKE_N")
	)
	(segment
		(start 136.794494 -63.924688)
		(end 136.82726 -63.924688)
		(width 0.0889)
		(layer "In11.Cu")
		(net "H_CPU1_FAST_WAKE_N")
	)
	(segment
		(start 137.649204 -64.419734)
		(end 137.68197 -64.419734)
		(width 0.0889)
		(layer "In11.Cu")
		(net "H_CPU1_FAST_WAKE_N")
	)
	(segment
		(start 133.360414 -63.924688)
		(end 133.395974 -63.924688)
		(width 0.0889)
		(layer "In11.Cu")
		(net "H_CPU1_FAST_WAKE_N")
	)
	(segment
		(start 131.643628 -63.924688)
		(end 131.679188 -63.924688)
		(width 0.0889)
		(layer "In11.Cu")
		(net "H_CPU1_FAST_WAKE_N")
	)
	(segment
		(start 141.292326 -66.400934)
		(end 141.393926 -66.502534)
		(width 0.0889)
		(layer "In11.Cu")
		(net "H_CPU1_FAST_WAKE_N")
	)
	(segment
		(start 132.173218 -63.629286)
		(end 132.17652 -63.623444)
		(width 0.0889)
		(layer "In11.Cu")
		(net "H_CPU1_FAST_WAKE_N")
	)
	(segment
		(start 141.393926 -66.502534)
		(end 142.252954 -66.502534)
		(width 0.0889)
		(layer "In11.Cu")
		(net "H_CPU1_FAST_WAKE_N")
	)
	(segment
		(start 144.901666 -63.853822)
		(end 157.042866 -63.853822)
		(width 0.089408)
		(layer "In11.Cu")
		(net "H_CPU1_FAST_WAKE_N")
	)
	(segment
		(start 139.366244 -65.410334)
		(end 139.39901 -65.410334)
		(width 0.0889)
		(layer "In11.Cu")
		(net "H_CPU1_FAST_WAKE_N")
	)
	(segment
		(start 134.225538 -63.429134)
		(end 134.258304 -63.429134)
		(width 0.0889)
		(layer "In11.Cu")
		(net "H_CPU1_FAST_WAKE_N")
	)
	(segment
		(start 135.080248 -62.934088)
		(end 135.11022 -62.934088)
		(width 0.0889)
		(layer "In11.Cu")
		(net "H_CPU1_FAST_WAKE_N")
	)
	(segment
		(start 141.083284 -66.400934)
		(end 141.292326 -66.400934)
		(width 0.0889)
		(layer "In11.Cu")
		(net "H_CPU1_FAST_WAKE_N")
	)
	(segment
		(start 130.860546 -63.886842)
		(end 131.452366 -63.886842)
		(width 0.0889)
		(layer "In11.Cu")
		(net "H_CPU1_FAST_WAKE_N")
	)
	(segment
		(start 132.519674 -63.429134)
		(end 132.53085 -63.429134)
		(width 0.0889)
		(layer "In11.Cu")
		(net "H_CPU1_FAST_WAKE_N")
	)
	(segment
		(start 140.228574 -65.905888)
		(end 140.26134 -65.905888)
		(width 0.0889)
		(layer "In11.Cu")
		(net "H_CPU1_FAST_WAKE_N")
	)
	(segment
		(start 130.802888 -63.829184)
		(end 130.860546 -63.886842)
		(width 0.0889)
		(layer "In11.Cu")
		(net "H_CPU1_FAST_WAKE_N")
	)
	(segment
		(start 142.354554 -66.400934)
		(end 144.901666 -63.853822)
		(width 0.089408)
		(layer "In11.Cu")
		(net "H_CPU1_FAST_WAKE_N")
	)
	(segment
		(start 142.252954 -66.502534)
		(end 142.354554 -66.400934)
		(width 0.0889)
		(layer "In11.Cu")
		(net "H_CPU1_FAST_WAKE_N")
	)
	(segment
		(start 138.511534 -64.915288)
		(end 138.5443 -64.915288)
		(width 0.0889)
		(layer "In11.Cu")
		(net "H_CPU1_FAST_WAKE_N")
	)
	(arc
		(start 136.300464 -63.629286)
		(mid 136.509072 -63.841218)
		(end 136.794494 -63.924688)
		(width 0.0889)
		(layer "In11.Cu")
		(net "H_CPU1_FAST_WAKE_N")
	)
	(arc
		(start 134.258304 -63.429134)
		(mid 134.541521 -63.344853)
		(end 134.748524 -63.133986)
		(width 0.0889)
		(layer "In11.Cu")
		(net "H_CPU1_FAST_WAKE_N")
	)
	(arc
		(start 133.890004 -63.629286)
		(mid 134.031687 -63.485482)
		(end 134.225538 -63.429134)
		(width 0.0889)
		(layer "In11.Cu")
		(net "H_CPU1_FAST_WAKE_N")
	)
	(arc
		(start 132.866384 -63.629286)
		(mid 133.074992 -63.841218)
		(end 133.360414 -63.924688)
		(width 0.0889)
		(layer "In11.Cu")
		(net "H_CPU1_FAST_WAKE_N")
	)
	(arc
		(start 132.53085 -63.429134)
		(mid 132.7247 -63.485484)
		(end 132.866384 -63.629286)
		(width 0.0889)
		(layer "In11.Cu")
		(net "H_CPU1_FAST_WAKE_N")
	)
	(arc
		(start 139.39901 -65.410334)
		(mid 139.59286 -65.466684)
		(end 139.734544 -65.610486)
		(width 0.0889)
		(layer "In11.Cu")
		(net "H_CPU1_FAST_WAKE_N")
	)
	(arc
		(start 137.158984 -64.124586)
		(mid 137.365988 -64.33545)
		(end 137.649204 -64.419734)
		(width 0.0889)
		(layer "In11.Cu")
		(net "H_CPU1_FAST_WAKE_N")
	)
	(arc
		(start 138.017504 -64.619886)
		(mid 138.226112 -64.831818)
		(end 138.511534 -64.915288)
		(width 0.0889)
		(layer "In11.Cu")
		(net "H_CPU1_FAST_WAKE_N")
	)
	(arc
		(start 132.17652 -63.623444)
		(mid 132.322486 -63.481045)
		(end 132.519674 -63.429134)
		(width 0.0889)
		(layer "In11.Cu")
		(net "H_CPU1_FAST_WAKE_N")
	)
	(arc
		(start 136.82726 -63.924688)
		(mid 137.018902 -63.981854)
		(end 137.158984 -64.124586)
		(width 0.0889)
		(layer "In11.Cu")
		(net "H_CPU1_FAST_WAKE_N")
	)
	(arc
		(start 140.593064 -66.105786)
		(mid 140.800068 -66.31665)
		(end 141.083284 -66.400934)
		(width 0.0889)
		(layer "In11.Cu")
		(net "H_CPU1_FAST_WAKE_N")
	)
	(arc
		(start 138.876024 -65.115186)
		(mid 139.083028 -65.32605)
		(end 139.366244 -65.410334)
		(width 0.0889)
		(layer "In11.Cu")
		(net "H_CPU1_FAST_WAKE_N")
	)
	(arc
		(start 135.11022 -62.934088)
		(mid 135.301862 -62.991254)
		(end 135.441944 -63.133986)
		(width 0.0889)
		(layer "In11.Cu")
		(net "H_CPU1_FAST_WAKE_N")
	)
	(arc
		(start 131.452366 -63.886842)
		(mid 131.546424 -63.913716)
		(end 131.643628 -63.924688)
		(width 0.0889)
		(layer "In11.Cu")
		(net "H_CPU1_FAST_WAKE_N")
	)
	(arc
		(start 135.441944 -63.133986)
		(mid 135.648948 -63.34485)
		(end 135.932164 -63.429134)
		(width 0.0889)
		(layer "In11.Cu")
		(net "H_CPU1_FAST_WAKE_N")
	)
	(arc
		(start 138.5443 -64.915288)
		(mid 138.735942 -64.972454)
		(end 138.876024 -65.115186)
		(width 0.0889)
		(layer "In11.Cu")
		(net "H_CPU1_FAST_WAKE_N")
	)
	(arc
		(start 139.734544 -65.610486)
		(mid 139.943152 -65.822418)
		(end 140.228574 -65.905888)
		(width 0.0889)
		(layer "In11.Cu")
		(net "H_CPU1_FAST_WAKE_N")
	)
	(arc
		(start 133.395974 -63.924688)
		(mid 133.681398 -63.841221)
		(end 133.890004 -63.629286)
		(width 0.0889)
		(layer "In11.Cu")
		(net "H_CPU1_FAST_WAKE_N")
	)
	(arc
		(start 140.26134 -65.905888)
		(mid 140.452982 -65.963054)
		(end 140.593064 -66.105786)
		(width 0.0889)
		(layer "In11.Cu")
		(net "H_CPU1_FAST_WAKE_N")
	)
	(arc
		(start 137.68197 -64.419734)
		(mid 137.87582 -64.476084)
		(end 138.017504 -64.619886)
		(width 0.0889)
		(layer "In11.Cu")
		(net "H_CPU1_FAST_WAKE_N")
	)
	(arc
		(start 131.679188 -63.924688)
		(mid 131.964612 -63.841221)
		(end 132.173218 -63.629286)
		(width 0.0889)
		(layer "In11.Cu")
		(net "H_CPU1_FAST_WAKE_N")
	)
	(arc
		(start 134.748524 -63.133986)
		(mid 134.888603 -62.99125)
		(end 135.080248 -62.934088)
		(width 0.0889)
		(layer "In11.Cu")
		(net "H_CPU1_FAST_WAKE_N")
	)
	(arc
		(start 135.96493 -63.429134)
		(mid 136.15878 -63.485484)
		(end 136.300464 -63.629286)
		(width 0.0889)
		(layer "In11.Cu")
		(net "H_CPU1_FAST_WAKE_N")
	)
	(segment
		(start 132.806694 -66.305938)
		(end 133.378194 -66.305938)
		(width 0.1016)
		(layer "F.Cu")
		(net "H_CPU1_ERR2_G_N")
	)
	(segment
		(start 380.321312 -77.818488)
		(end 380.283466 -77.818488)
		(width 0.10795)
		(layer "F.Cu")
		(net "H_CPU1_ERR2_G_N")
	)
	(segment
		(start 381.29083 -76.84897)
		(end 380.321312 -77.818488)
		(width 0.10795)
		(layer "F.Cu")
		(net "H_CPU1_ERR2_G_N")
	)
	(segment
		(start 381.805688 -76.019406)
		(end 381.29083 -76.534264)
		(width 0.10795)
		(layer "F.Cu")
		(net "H_CPU1_ERR2_G_N")
	)
	(segment
		(start 381.29083 -76.534264)
		(end 381.29083 -76.84897)
		(width 0.10795)
		(layer "F.Cu")
		(net "H_CPU1_ERR2_G_N")
	)
	(segment
		(start 382.131062 -76.019406)
		(end 381.805688 -76.019406)
		(width 0.10795)
		(layer "F.Cu")
		(net "H_CPU1_ERR2_G_N")
	)
	(via
		(at 161.139378 -73.13041)
		(size 0.508)
		(drill 0.254)
		(layers "F.Cu" "B.Cu")
		(net "H_CPU1_ERR2_G_N")
	)
	(via
		(at 319.405 -36.068)
		(size 0.6604)
		(drill 0.3302)
		(layers "F.Cu" "B.Cu")
		(net "H_CPU1_ERR2_G_N")
	)
	(via
		(at 133.378194 -66.305938)
		(size 0.508)
		(drill 0.254)
		(layers "F.Cu" "B.Cu")
		(net "H_CPU1_ERR2_G_N")
	)
	(via
		(at 193.8909 -20.62988)
		(size 0.508)
		(drill 0.254)
		(layers "F.Cu" "B.Cu")
		(net "H_CPU1_ERR2_G_N")
	)
	(via
		(at 380.283466 -77.818488)
		(size 0.508)
		(drill 0.254)
		(layers "F.Cu" "B.Cu")
		(net "H_CPU1_ERR2_G_N")
	)
	(via
		(at 320.0273 -36.7411)
		(size 0.508)
		(drill 0.254)
		(layers "F.Cu" "B.Cu")
		(net "H_CPU1_ERR2_G_N")
	)
	(segment
		(start 319.405 -36.1188)
		(end 320.0273 -36.7411)
		(width 0.10795)
		(layer "B.Cu")
		(net "H_CPU1_ERR2_G_N")
	)
	(segment
		(start 319.405 -36.068)
		(end 319.405 -36.1188)
		(width 0.10795)
		(layer "B.Cu")
		(net "H_CPU1_ERR2_G_N")
	)
	(segment
		(start 133.67131 -66.136774)
		(end 133.378194 -66.305938)
		(width 0.0889)
		(layer "In4.Cu")
		(net "H_CPU1_ERR2_G_N")
	)
	(segment
		(start 144.087342 -66.571876)
		(end 141.481556 -66.571876)
		(width 0.089408)
		(layer "In4.Cu")
		(net "H_CPU1_ERR2_G_N")
	)
	(segment
		(start 155.184348 -68.581778)
		(end 146.097244 -68.581778)
		(width 0.089408)
		(layer "In4.Cu")
		(net "H_CPU1_ERR2_G_N")
	)
	(segment
		(start 138.5443 -65.905888)
		(end 138.514328 -65.905888)
		(width 0.0889)
		(layer "In4.Cu")
		(net "H_CPU1_ERR2_G_N")
	)
	(segment
		(start 139.409424 -66.400934)
		(end 139.366244 -66.400934)
		(width 0.0889)
		(layer "In4.Cu")
		(net "H_CPU1_ERR2_G_N")
	)
	(segment
		(start 141.481556 -66.571876)
		(end 141.310614 -66.400934)
		(width 0.089408)
		(layer "In4.Cu")
		(net "H_CPU1_ERR2_G_N")
	)
	(segment
		(start 136.82726 -65.905888)
		(end 136.797288 -65.905888)
		(width 0.0889)
		(layer "In4.Cu")
		(net "H_CPU1_ERR2_G_N")
	)
	(segment
		(start 160.717992 -72.709024)
		(end 159.311594 -72.709024)
		(width 0.089408)
		(layer "In4.Cu")
		(net "H_CPU1_ERR2_G_N")
	)
	(segment
		(start 146.097244 -68.581778)
		(end 144.087342 -66.571876)
		(width 0.089408)
		(layer "In4.Cu")
		(net "H_CPU1_ERR2_G_N")
	)
	(segment
		(start 161.139378 -73.13041)
		(end 160.717992 -72.709024)
		(width 0.089408)
		(layer "In4.Cu")
		(net "H_CPU1_ERR2_G_N")
	)
	(segment
		(start 134.258304 -66.400934)
		(end 134.215124 -66.400934)
		(width 0.0889)
		(layer "In4.Cu")
		(net "H_CPU1_ERR2_G_N")
	)
	(segment
		(start 140.26134 -65.905888)
		(end 140.231368 -65.905888)
		(width 0.0889)
		(layer "In4.Cu")
		(net "H_CPU1_ERR2_G_N")
	)
	(segment
		(start 135.975344 -66.400934)
		(end 135.932164 -66.400934)
		(width 0.0889)
		(layer "In4.Cu")
		(net "H_CPU1_ERR2_G_N")
	)
	(segment
		(start 141.310614 -66.400934)
		(end 141.083284 -66.400934)
		(width 0.0889)
		(layer "In4.Cu")
		(net "H_CPU1_ERR2_G_N")
	)
	(segment
		(start 137.692384 -66.400934)
		(end 137.649204 -66.400934)
		(width 0.0889)
		(layer "In4.Cu")
		(net "H_CPU1_ERR2_G_N")
	)
	(segment
		(start 135.11022 -65.905888)
		(end 135.080248 -65.905888)
		(width 0.0889)
		(layer "In4.Cu")
		(net "H_CPU1_ERR2_G_N")
	)
	(segment
		(start 159.311594 -72.709024)
		(end 155.184348 -68.581778)
		(width 0.089408)
		(layer "In4.Cu")
		(net "H_CPU1_ERR2_G_N")
	)
	(segment
		(start 133.760718 -66.160904)
		(end 133.67131 -66.136774)
		(width 0.0889)
		(layer "In4.Cu")
		(net "H_CPU1_ERR2_G_N")
	)
	(arc
		(start 134.748524 -66.105786)
		(mid 134.54152 -66.31665)
		(end 134.258304 -66.400934)
		(width 0.0889)
		(layer "In4.Cu")
		(net "H_CPU1_ERR2_G_N")
	)
	(arc
		(start 138.182604 -66.105786)
		(mid 137.9756 -66.31665)
		(end 137.692384 -66.400934)
		(width 0.0889)
		(layer "In4.Cu")
		(net "H_CPU1_ERR2_G_N")
	)
	(arc
		(start 140.593064 -66.105786)
		(mid 140.452985 -65.96305)
		(end 140.26134 -65.905888)
		(width 0.0889)
		(layer "In4.Cu")
		(net "H_CPU1_ERR2_G_N")
	)
	(arc
		(start 135.441944 -66.105786)
		(mid 135.301865 -65.96305)
		(end 135.11022 -65.905888)
		(width 0.0889)
		(layer "In4.Cu")
		(net "H_CPU1_ERR2_G_N")
	)
	(arc
		(start 135.080248 -65.905888)
		(mid 134.888606 -65.963054)
		(end 134.748524 -66.105786)
		(width 0.0889)
		(layer "In4.Cu")
		(net "H_CPU1_ERR2_G_N")
	)
	(arc
		(start 138.876024 -66.105786)
		(mid 138.735945 -65.96305)
		(end 138.5443 -65.905888)
		(width 0.0889)
		(layer "In4.Cu")
		(net "H_CPU1_ERR2_G_N")
	)
	(arc
		(start 139.899644 -66.105786)
		(mid 139.69264 -66.31665)
		(end 139.409424 -66.400934)
		(width 0.0889)
		(layer "In4.Cu")
		(net "H_CPU1_ERR2_G_N")
	)
	(arc
		(start 136.797288 -65.905888)
		(mid 136.605646 -65.963054)
		(end 136.465564 -66.105786)
		(width 0.0889)
		(layer "In4.Cu")
		(net "H_CPU1_ERR2_G_N")
	)
	(arc
		(start 135.932164 -66.400934)
		(mid 135.648947 -66.316653)
		(end 135.441944 -66.105786)
		(width 0.0889)
		(layer "In4.Cu")
		(net "H_CPU1_ERR2_G_N")
	)
	(arc
		(start 137.158984 -66.105786)
		(mid 137.018905 -65.96305)
		(end 136.82726 -65.905888)
		(width 0.0889)
		(layer "In4.Cu")
		(net "H_CPU1_ERR2_G_N")
	)
	(arc
		(start 138.514328 -65.905888)
		(mid 138.322686 -65.963054)
		(end 138.182604 -66.105786)
		(width 0.0889)
		(layer "In4.Cu")
		(net "H_CPU1_ERR2_G_N")
	)
	(arc
		(start 139.366244 -66.400934)
		(mid 139.083027 -66.316653)
		(end 138.876024 -66.105786)
		(width 0.0889)
		(layer "In4.Cu")
		(net "H_CPU1_ERR2_G_N")
	)
	(arc
		(start 134.215124 -66.400934)
		(mid 133.960459 -66.332905)
		(end 133.760718 -66.160904)
		(width 0.0889)
		(layer "In4.Cu")
		(net "H_CPU1_ERR2_G_N")
	)
	(arc
		(start 140.231368 -65.905888)
		(mid 140.039726 -65.963054)
		(end 139.899644 -66.105786)
		(width 0.0889)
		(layer "In4.Cu")
		(net "H_CPU1_ERR2_G_N")
	)
	(arc
		(start 141.083284 -66.400934)
		(mid 140.800067 -66.316653)
		(end 140.593064 -66.105786)
		(width 0.0889)
		(layer "In4.Cu")
		(net "H_CPU1_ERR2_G_N")
	)
	(arc
		(start 136.465564 -66.105786)
		(mid 136.25856 -66.31665)
		(end 135.975344 -66.400934)
		(width 0.0889)
		(layer "In4.Cu")
		(net "H_CPU1_ERR2_G_N")
	)
	(arc
		(start 137.649204 -66.400934)
		(mid 137.365987 -66.316653)
		(end 137.158984 -66.105786)
		(width 0.0889)
		(layer "In4.Cu")
		(net "H_CPU1_ERR2_G_N")
	)
	(segment
		(start 319.461896 -37.306504)
		(end 317.842138 -37.306504)
		(width 0.089408)
		(layer "In9.Cu")
		(net "H_CPU1_ERR2_G_N")
	)
	(segment
		(start 244.4496 -22.734524)
		(end 244.165628 -22.450552)
		(width 0.089408)
		(layer "In9.Cu")
		(net "H_CPU1_ERR2_G_N")
	)
	(segment
		(start 243.44122 -22.59838)
		(end 243.108734 -22.59838)
		(width 0.089408)
		(layer "In9.Cu")
		(net "H_CPU1_ERR2_G_N")
	)
	(segment
		(start 243.108734 -22.59838)
		(end 242.7732 -22.262846)
		(width 0.089408)
		(layer "In9.Cu")
		(net "H_CPU1_ERR2_G_N")
	)
	(segment
		(start 245.876064 -23.960328)
		(end 244.709188 -23.960328)
		(width 0.089408)
		(layer "In9.Cu")
		(net "H_CPU1_ERR2_G_N")
	)
	(segment
		(start 306.566062 -25.39365)
		(end 279.147778 -25.39365)
		(width 0.089408)
		(layer "In9.Cu")
		(net "H_CPU1_ERR2_G_N")
	)
	(segment
		(start 244.4496 -23.70074)
		(end 244.4496 -22.734524)
		(width 0.089408)
		(layer "In9.Cu")
		(net "H_CPU1_ERR2_G_N")
	)
	(segment
		(start 242.7732 -22.186646)
		(end 240.821718 -20.235164)
		(width 0.089408)
		(layer "In9.Cu")
		(net "H_CPU1_ERR2_G_N")
	)
	(segment
		(start 194.285616 -20.235164)
		(end 193.8909 -20.62988)
		(width 0.089408)
		(layer "In9.Cu")
		(net "H_CPU1_ERR2_G_N")
	)
	(segment
		(start 243.589048 -22.450552)
		(end 243.44122 -22.59838)
		(width 0.089408)
		(layer "In9.Cu")
		(net "H_CPU1_ERR2_G_N")
	)
	(segment
		(start 263.74725 -26.715212)
		(end 262.516366 -26.715212)
		(width 0.089408)
		(layer "In9.Cu")
		(net "H_CPU1_ERR2_G_N")
	)
	(segment
		(start 266.225782 -29.193744)
		(end 263.74725 -26.715212)
		(width 0.089408)
		(layer "In9.Cu")
		(net "H_CPU1_ERR2_G_N")
	)
	(segment
		(start 279.147778 -25.39365)
		(end 275.347684 -29.193744)
		(width 0.089408)
		(layer "In9.Cu")
		(net "H_CPU1_ERR2_G_N")
	)
	(segment
		(start 242.7732 -22.262846)
		(end 242.7732 -22.186646)
		(width 0.089408)
		(layer "In9.Cu")
		(net "H_CPU1_ERR2_G_N")
	)
	(segment
		(start 320.0273 -36.7411)
		(end 319.461896 -37.306504)
		(width 0.089408)
		(layer "In9.Cu")
		(net "H_CPU1_ERR2_G_N")
	)
	(segment
		(start 313.592972 -32.42056)
		(end 306.566062 -25.39365)
		(width 0.089408)
		(layer "In9.Cu")
		(net "H_CPU1_ERR2_G_N")
	)
	(segment
		(start 313.592972 -33.057338)
		(end 313.592972 -32.42056)
		(width 0.089408)
		(layer "In9.Cu")
		(net "H_CPU1_ERR2_G_N")
	)
	(segment
		(start 275.347684 -29.193744)
		(end 266.225782 -29.193744)
		(width 0.089408)
		(layer "In9.Cu")
		(net "H_CPU1_ERR2_G_N")
	)
	(segment
		(start 317.842138 -37.306504)
		(end 313.592972 -33.057338)
		(width 0.089408)
		(layer "In9.Cu")
		(net "H_CPU1_ERR2_G_N")
	)
	(segment
		(start 244.709188 -23.960328)
		(end 244.4496 -23.70074)
		(width 0.089408)
		(layer "In9.Cu")
		(net "H_CPU1_ERR2_G_N")
	)
	(segment
		(start 244.165628 -22.450552)
		(end 243.589048 -22.450552)
		(width 0.089408)
		(layer "In9.Cu")
		(net "H_CPU1_ERR2_G_N")
	)
	(segment
		(start 260.054344 -24.25319)
		(end 246.168926 -24.25319)
		(width 0.089408)
		(layer "In9.Cu")
		(net "H_CPU1_ERR2_G_N")
	)
	(segment
		(start 246.168926 -24.25319)
		(end 245.876064 -23.960328)
		(width 0.089408)
		(layer "In9.Cu")
		(net "H_CPU1_ERR2_G_N")
	)
	(segment
		(start 240.821718 -20.235164)
		(end 194.285616 -20.235164)
		(width 0.089408)
		(layer "In9.Cu")
		(net "H_CPU1_ERR2_G_N")
	)
	(segment
		(start 262.516366 -26.715212)
		(end 260.054344 -24.25319)
		(width 0.089408)
		(layer "In9.Cu")
		(net "H_CPU1_ERR2_G_N")
	)
	(segment
		(start 377.918218 -70.449694)
		(end 377.918218 -68.54063)
		(width 0.089408)
		(layer "In11.Cu")
		(net "H_CPU1_ERR2_G_N")
	)
	(segment
		(start 322.535296 -41.04513)
		(end 322.100448 -40.610282)
		(width 0.089408)
		(layer "In11.Cu")
		(net "H_CPU1_ERR2_G_N")
	)
	(segment
		(start 366.141762 -54.307232)
		(end 365.74095 -54.307232)
		(width 0.089408)
		(layer "In11.Cu")
		(net "H_CPU1_ERR2_G_N")
	)
	(segment
		(start 191.2112 -24.3586)
		(end 188.1632 -24.3586)
		(width 0.089408)
		(layer "In11.Cu")
		(net "H_CPU1_ERR2_G_N")
	)
	(segment
		(start 376.174 -65.115186)
		(end 376.358912 -64.930274)
		(width 0.089408)
		(layer "In11.Cu")
		(net "H_CPU1_ERR2_G_N")
	)
	(segment
		(start 378.8029 -77.299566)
		(end 378.8029 -75.640692)
		(width 0.089408)
		(layer "In11.Cu")
		(net "H_CPU1_ERR2_G_N")
	)
	(segment
		(start 320.0273 -39.459408)
		(end 320.0273 -36.7411)
		(width 0.089408)
		(layer "In11.Cu")
		(net "H_CPU1_ERR2_G_N")
	)
	(segment
		(start 377.216416 -68.004944)
		(end 377.216416 -67.844416)
		(width 0.089408)
		(layer "In11.Cu")
		(net "H_CPU1_ERR2_G_N")
	)
	(segment
		(start 193.536062 -20.984718)
		(end 193.536062 -22.033738)
		(width 0.089408)
		(layer "In11.Cu")
		(net "H_CPU1_ERR2_G_N")
	)
	(segment
		(start 377.601226 -68.223638)
		(end 377.43511 -68.223638)
		(width 0.089408)
		(layer "In11.Cu")
		(net "H_CPU1_ERR2_G_N")
	)
	(segment
		(start 377.216416 -67.844416)
		(end 377.118118 -67.746118)
		(width 0.089408)
		(layer "In11.Cu")
		(net "H_CPU1_ERR2_G_N")
	)
	(segment
		(start 187.2488 -30.38856)
		(end 167.431466 -50.205894)
		(width 0.089408)
		(layer "In11.Cu")
		(net "H_CPU1_ERR2_G_N")
	)
	(segment
		(start 366.870488 -54.307232)
		(end 366.870234 -54.307486)
		(width 0.089408)
		(layer "In11.Cu")
		(net "H_CPU1_ERR2_G_N")
	)
	(segment
		(start 375.725944 -61.64199)
		(end 374.321324 -60.23737)
		(width 0.089408)
		(layer "In11.Cu")
		(net "H_CPU1_ERR2_G_N")
	)
	(segment
		(start 161.94024 -73.65619)
		(end 161.665158 -73.65619)
		(width 0.089408)
		(layer "In11.Cu")
		(net "H_CPU1_ERR2_G_N")
	)
	(segment
		(start 193.536062 -22.033738)
		(end 191.2112 -24.3586)
		(width 0.089408)
		(layer "In11.Cu")
		(net "H_CPU1_ERR2_G_N")
	)
	(segment
		(start 365.740696 -54.307486)
		(end 365.031528 -54.307486)
		(width 0.089408)
		(layer "In11.Cu")
		(net "H_CPU1_ERR2_G_N")
	)
	(segment
		(start 370.459 -57.15)
		(end 367.616486 -54.307486)
		(width 0.089408)
		(layer "In11.Cu")
		(net "H_CPU1_ERR2_G_N")
	)
	(segment
		(start 162.7378 -65.856612)
		(end 162.7378 -67.0052)
		(width 0.089408)
		(layer "In11.Cu")
		(net "H_CPU1_ERR2_G_N")
	)
	(segment
		(start 164.3761 -64.218312)
		(end 162.7378 -65.856612)
		(width 0.089408)
		(layer "In11.Cu")
		(net "H_CPU1_ERR2_G_N")
	)
	(segment
		(start 328.897996 -47.956216)
		(end 322.535296 -41.593516)
		(width 0.089408)
		(layer "In11.Cu")
		(net "H_CPU1_ERR2_G_N")
	)
	(segment
		(start 370.87556 -57.15)
		(end 370.459 -57.15)
		(width 0.089408)
		(layer "In11.Cu")
		(net "H_CPU1_ERR2_G_N")
	)
	(segment
		(start 377.118118 -67.74053)
		(end 376.899424 -67.521836)
		(width 0.089408)
		(layer "In11.Cu")
		(net "H_CPU1_ERR2_G_N")
	)
	(segment
		(start 367.616486 -54.307486)
		(end 367.271554 -54.307486)
		(width 0.089408)
		(layer "In11.Cu")
		(net "H_CPU1_ERR2_G_N")
	)
	(segment
		(start 377.171458 -71.196454)
		(end 377.918218 -70.449694)
		(width 0.089408)
		(layer "In11.Cu")
		(net "H_CPU1_ERR2_G_N")
	)
	(segment
		(start 161.665158 -73.65619)
		(end 161.139378 -73.13041)
		(width 0.089408)
		(layer "In11.Cu")
		(net "H_CPU1_ERR2_G_N")
	)
	(segment
		(start 377.118118 -67.746118)
		(end 377.118118 -67.74053)
		(width 0.089408)
		(layer "In11.Cu")
		(net "H_CPU1_ERR2_G_N")
	)
	(segment
		(start 366.142016 -54.307486)
		(end 366.141762 -54.307232)
		(width 0.089408)
		(layer "In11.Cu")
		(net "H_CPU1_ERR2_G_N")
	)
	(segment
		(start 376.358912 -64.930274)
		(end 376.358912 -63.809372)
		(width 0.089408)
		(layer "In11.Cu")
		(net "H_CPU1_ERR2_G_N")
	)
	(segment
		(start 162.490912 -72.305926)
		(end 162.490912 -73.105518)
		(width 0.089408)
		(layer "In11.Cu")
		(net "H_CPU1_ERR2_G_N")
	)
	(segment
		(start 376.899424 -67.521836)
		(end 376.893836 -67.521836)
		(width 0.089408)
		(layer "In11.Cu")
		(net "H_CPU1_ERR2_G_N")
	)
	(segment
		(start 358.680258 -47.956216)
		(end 328.897996 -47.956216)
		(width 0.089408)
		(layer "In11.Cu")
		(net "H_CPU1_ERR2_G_N")
	)
	(segment
		(start 322.100448 -40.610282)
		(end 321.178174 -40.610282)
		(width 0.089408)
		(layer "In11.Cu")
		(net "H_CPU1_ERR2_G_N")
	)
	(segment
		(start 378.8029 -75.640692)
		(end 377.171458 -74.00925)
		(width 0.089408)
		(layer "In11.Cu")
		(net "H_CPU1_ERR2_G_N")
	)
	(segment
		(start 377.43511 -68.223638)
		(end 377.216416 -68.004944)
		(width 0.089408)
		(layer "In11.Cu")
		(net "H_CPU1_ERR2_G_N")
	)
	(segment
		(start 380.283466 -77.818488)
		(end 380.176278 -77.7113)
		(width 0.089408)
		(layer "In11.Cu")
		(net "H_CPU1_ERR2_G_N")
	)
	(segment
		(start 161.757868 -67.985132)
		(end 161.757868 -71.572882)
		(width 0.089408)
		(layer "In11.Cu")
		(net "H_CPU1_ERR2_G_N")
	)
	(segment
		(start 379.214634 -77.7113)
		(end 378.8029 -77.299566)
		(width 0.089408)
		(layer "In11.Cu")
		(net "H_CPU1_ERR2_G_N")
	)
	(segment
		(start 161.757868 -71.572882)
		(end 162.490912 -72.305926)
		(width 0.089408)
		(layer "In11.Cu")
		(net "H_CPU1_ERR2_G_N")
	)
	(segment
		(start 377.918218 -68.54063)
		(end 377.601226 -68.223638)
		(width 0.089408)
		(layer "In11.Cu")
		(net "H_CPU1_ERR2_G_N")
	)
	(segment
		(start 322.535296 -41.593516)
		(end 322.535296 -41.04513)
		(width 0.089408)
		(layer "In11.Cu")
		(net "H_CPU1_ERR2_G_N")
	)
	(segment
		(start 372.383304 -58.762392)
		(end 372.383304 -58.657744)
		(width 0.089408)
		(layer "In11.Cu")
		(net "H_CPU1_ERR2_G_N")
	)
	(segment
		(start 321.178174 -40.610282)
		(end 320.0273 -39.459408)
		(width 0.089408)
		(layer "In11.Cu")
		(net "H_CPU1_ERR2_G_N")
	)
	(segment
		(start 376.174 -66.802)
		(end 376.174 -65.115186)
		(width 0.089408)
		(layer "In11.Cu")
		(net "H_CPU1_ERR2_G_N")
	)
	(segment
		(start 365.031528 -54.307486)
		(end 358.680258 -47.956216)
		(width 0.089408)
		(layer "In11.Cu")
		(net "H_CPU1_ERR2_G_N")
	)
	(segment
		(start 373.858282 -60.23737)
		(end 372.383304 -58.762392)
		(width 0.089408)
		(layer "In11.Cu")
		(net "H_CPU1_ERR2_G_N")
	)
	(segment
		(start 188.1632 -24.3586)
		(end 187.2488 -25.273)
		(width 0.089408)
		(layer "In11.Cu")
		(net "H_CPU1_ERR2_G_N")
	)
	(segment
		(start 367.271554 -54.307486)
		(end 367.2713 -54.307232)
		(width 0.089408)
		(layer "In11.Cu")
		(net "H_CPU1_ERR2_G_N")
	)
	(segment
		(start 376.893836 -67.521836)
		(end 376.174 -66.802)
		(width 0.089408)
		(layer "In11.Cu")
		(net "H_CPU1_ERR2_G_N")
	)
	(segment
		(start 377.171458 -74.00925)
		(end 377.171458 -71.196454)
		(width 0.089408)
		(layer "In11.Cu")
		(net "H_CPU1_ERR2_G_N")
	)
	(segment
		(start 167.431466 -60.406534)
		(end 164.3761 -63.4619)
		(width 0.089408)
		(layer "In11.Cu")
		(net "H_CPU1_ERR2_G_N")
	)
	(segment
		(start 187.2488 -25.273)
		(end 187.2488 -30.38856)
		(width 0.089408)
		(layer "In11.Cu")
		(net "H_CPU1_ERR2_G_N")
	)
	(segment
		(start 366.870234 -54.307486)
		(end 366.142016 -54.307486)
		(width 0.089408)
		(layer "In11.Cu")
		(net "H_CPU1_ERR2_G_N")
	)
	(segment
		(start 167.431466 -50.205894)
		(end 167.431466 -60.406534)
		(width 0.089408)
		(layer "In11.Cu")
		(net "H_CPU1_ERR2_G_N")
	)
	(segment
		(start 374.321324 -60.23737)
		(end 373.858282 -60.23737)
		(width 0.089408)
		(layer "In11.Cu")
		(net "H_CPU1_ERR2_G_N")
	)
	(segment
		(start 162.490912 -73.105518)
		(end 161.94024 -73.65619)
		(width 0.089408)
		(layer "In11.Cu")
		(net "H_CPU1_ERR2_G_N")
	)
	(segment
		(start 162.7378 -67.0052)
		(end 161.757868 -67.985132)
		(width 0.089408)
		(layer "In11.Cu")
		(net "H_CPU1_ERR2_G_N")
	)
	(segment
		(start 375.725944 -63.176404)
		(end 375.725944 -61.64199)
		(width 0.089408)
		(layer "In11.Cu")
		(net "H_CPU1_ERR2_G_N")
	)
	(segment
		(start 367.2713 -54.307232)
		(end 366.870488 -54.307232)
		(width 0.089408)
		(layer "In11.Cu")
		(net "H_CPU1_ERR2_G_N")
	)
	(segment
		(start 380.176278 -77.7113)
		(end 379.214634 -77.7113)
		(width 0.089408)
		(layer "In11.Cu")
		(net "H_CPU1_ERR2_G_N")
	)
	(segment
		(start 365.74095 -54.307232)
		(end 365.740696 -54.307486)
		(width 0.089408)
		(layer "In11.Cu")
		(net "H_CPU1_ERR2_G_N")
	)
	(segment
		(start 376.358912 -63.809372)
		(end 375.725944 -63.176404)
		(width 0.089408)
		(layer "In11.Cu")
		(net "H_CPU1_ERR2_G_N")
	)
	(segment
		(start 193.8909 -20.62988)
		(end 193.536062 -20.984718)
		(width 0.089408)
		(layer "In11.Cu")
		(net "H_CPU1_ERR2_G_N")
	)
	(segment
		(start 164.3761 -63.4619)
		(end 164.3761 -64.218312)
		(width 0.089408)
		(layer "In11.Cu")
		(net "H_CPU1_ERR2_G_N")
	)
	(segment
		(start 372.383304 -58.657744)
		(end 370.87556 -57.15)
		(width 0.089408)
		(layer "In11.Cu")
		(net "H_CPU1_ERR2_G_N")
	)
	(segment
		(start 158.665672 -73.109328)
		(end 158.6484 -73.1266)
		(width 0.10795)
		(layer "F.Cu")
		(net "H_CPU1_CATERR_G_N")
	)
	(segment
		(start 159.64535 -73.109328)
		(end 158.665672 -73.109328)
		(width 0.10795)
		(layer "F.Cu")
		(net "H_CPU1_CATERR_G_N")
	)
	(segment
		(start 131.089908 -66.305938)
		(end 131.661408 -66.305938)
		(width 0.1016)
		(layer "F.Cu")
		(net "H_CPU1_CATERR_G_N")
	)
	(via
		(at 321.728084 -38.23716)
		(size 0.508)
		(drill 0.254)
		(layers "F.Cu" "B.Cu")
		(net "H_CPU1_CATERR_G_N")
	)
	(via
		(at 159.64535 -73.109328)
		(size 0.508)
		(drill 0.254)
		(layers "F.Cu" "B.Cu")
		(net "H_CPU1_CATERR_G_N")
	)
	(via
		(at 185.429652 -22.455632)
		(size 0.508)
		(drill 0.254)
		(layers "F.Cu" "B.Cu")
		(net "H_CPU1_CATERR_G_N")
	)
	(via
		(at 158.6484 -73.1266)
		(size 0.762)
		(drill 0.381)
		(layers "F.Cu" "B.Cu")
		(net "H_CPU1_CATERR_G_N")
	)
	(via
		(at 373.6213 -58.335926)
		(size 0.508)
		(drill 0.254)
		(layers "F.Cu" "B.Cu")
		(net "H_CPU1_CATERR_G_N")
	)
	(via
		(at 131.661408 -66.305938)
		(size 0.508)
		(drill 0.254)
		(layers "F.Cu" "B.Cu")
		(net "H_CPU1_CATERR_G_N")
	)
	(segment
		(start 161.507678 -71.247)
		(end 159.64535 -73.109328)
		(width 0.10795)
		(layer "B.Cu")
		(net "H_CPU1_CATERR_G_N")
	)
	(segment
		(start 162.179 -71.247)
		(end 161.507678 -71.247)
		(width 0.10795)
		(layer "B.Cu")
		(net "H_CPU1_CATERR_G_N")
	)
	(segment
		(start 373.6975 -58.259726)
		(end 373.6213 -58.335926)
		(width 0.10795)
		(layer "B.Cu")
		(net "H_CPU1_CATERR_G_N")
	)
	(segment
		(start 373.6975 -57.658)
		(end 373.6975 -58.259726)
		(width 0.10795)
		(layer "B.Cu")
		(net "H_CPU1_CATERR_G_N")
	)
	(segment
		(start 136.049258 -67.271392)
		(end 136.5504 -66.77025)
		(width 0.089408)
		(layer "In4.Cu")
		(net "H_CPU1_CATERR_G_N")
	)
	(segment
		(start 135.636 -67.271392)
		(end 136.049258 -67.271392)
		(width 0.089408)
		(layer "In4.Cu")
		(net "H_CPU1_CATERR_G_N")
	)
	(segment
		(start 135.217408 -66.8528)
		(end 135.636 -67.271392)
		(width 0.089408)
		(layer "In4.Cu")
		(net "H_CPU1_CATERR_G_N")
	)
	(segment
		(start 140.8684 -67.2846)
		(end 141.1986 -67.2846)
		(width 0.089408)
		(layer "In4.Cu")
		(net "H_CPU1_CATERR_G_N")
	)
	(segment
		(start 133.1214 -66.7258)
		(end 133.5024 -66.7258)
		(width 0.089408)
		(layer "In4.Cu")
		(net "H_CPU1_CATERR_G_N")
	)
	(segment
		(start 131.661408 -66.305938)
		(end 131.758182 -66.209164)
		(width 0.089408)
		(layer "In4.Cu")
		(net "H_CPU1_CATERR_G_N")
	)
	(segment
		(start 155.1051 -68.772786)
		(end 159.441642 -73.109328)
		(width 0.089408)
		(layer "In4.Cu")
		(net "H_CPU1_CATERR_G_N")
	)
	(segment
		(start 141.1986 -67.2846)
		(end 141.6304 -66.8528)
		(width 0.089408)
		(layer "In4.Cu")
		(net "H_CPU1_CATERR_G_N")
	)
	(segment
		(start 139.065 -67.2338)
		(end 139.6238 -67.2338)
		(width 0.089408)
		(layer "In4.Cu")
		(net "H_CPU1_CATERR_G_N")
	)
	(segment
		(start 140.081 -66.7766)
		(end 140.3604 -66.7766)
		(width 0.089408)
		(layer "In4.Cu")
		(net "H_CPU1_CATERR_G_N")
	)
	(segment
		(start 136.87425 -66.77025)
		(end 137.3124 -67.2084)
		(width 0.089408)
		(layer "In4.Cu")
		(net "H_CPU1_CATERR_G_N")
	)
	(segment
		(start 136.5504 -66.77025)
		(end 136.87425 -66.77025)
		(width 0.089408)
		(layer "In4.Cu")
		(net "H_CPU1_CATERR_G_N")
	)
	(segment
		(start 133.5024 -66.7258)
		(end 134.0104 -67.2338)
		(width 0.089408)
		(layer "In4.Cu")
		(net "H_CPU1_CATERR_G_N")
	)
	(segment
		(start 137.3124 -67.2084)
		(end 137.8458 -67.2084)
		(width 0.089408)
		(layer "In4.Cu")
		(net "H_CPU1_CATERR_G_N")
	)
	(segment
		(start 146.017996 -68.772786)
		(end 155.1051 -68.772786)
		(width 0.089408)
		(layer "In4.Cu")
		(net "H_CPU1_CATERR_G_N")
	)
	(segment
		(start 132.604764 -66.209164)
		(end 133.1214 -66.7258)
		(width 0.089408)
		(layer "In4.Cu")
		(net "H_CPU1_CATERR_G_N")
	)
	(segment
		(start 144.09801 -66.8528)
		(end 146.017996 -68.772786)
		(width 0.089408)
		(layer "In4.Cu")
		(net "H_CPU1_CATERR_G_N")
	)
	(segment
		(start 134.0104 -67.2338)
		(end 134.493 -67.2338)
		(width 0.089408)
		(layer "In4.Cu")
		(net "H_CPU1_CATERR_G_N")
	)
	(segment
		(start 141.6304 -66.8528)
		(end 144.09801 -66.8528)
		(width 0.089408)
		(layer "In4.Cu")
		(net "H_CPU1_CATERR_G_N")
	)
	(segment
		(start 159.441642 -73.109328)
		(end 159.64535 -73.109328)
		(width 0.089408)
		(layer "In4.Cu")
		(net "H_CPU1_CATERR_G_N")
	)
	(segment
		(start 134.874 -66.8528)
		(end 135.217408 -66.8528)
		(width 0.089408)
		(layer "In4.Cu")
		(net "H_CPU1_CATERR_G_N")
	)
	(segment
		(start 140.3604 -66.7766)
		(end 140.8684 -67.2846)
		(width 0.089408)
		(layer "In4.Cu")
		(net "H_CPU1_CATERR_G_N")
	)
	(segment
		(start 138.2776 -66.7766)
		(end 138.6078 -66.7766)
		(width 0.089408)
		(layer "In4.Cu")
		(net "H_CPU1_CATERR_G_N")
	)
	(segment
		(start 134.493 -67.2338)
		(end 134.874 -66.8528)
		(width 0.089408)
		(layer "In4.Cu")
		(net "H_CPU1_CATERR_G_N")
	)
	(segment
		(start 139.6238 -67.2338)
		(end 140.081 -66.7766)
		(width 0.089408)
		(layer "In4.Cu")
		(net "H_CPU1_CATERR_G_N")
	)
	(segment
		(start 137.8458 -67.2084)
		(end 138.2776 -66.7766)
		(width 0.089408)
		(layer "In4.Cu")
		(net "H_CPU1_CATERR_G_N")
	)
	(segment
		(start 138.6078 -66.7766)
		(end 139.065 -67.2338)
		(width 0.089408)
		(layer "In4.Cu")
		(net "H_CPU1_CATERR_G_N")
	)
	(segment
		(start 131.758182 -66.209164)
		(end 132.604764 -66.209164)
		(width 0.089408)
		(layer "In4.Cu")
		(net "H_CPU1_CATERR_G_N")
	)
	(segment
		(start 188.030866 -24.98344)
		(end 191.379856 -24.98344)
		(width 0.089408)
		(layer "In9.Cu")
		(net "H_CPU1_CATERR_G_N")
	)
	(segment
		(start 262.030718 -27.885644)
		(end 263.380982 -27.885644)
		(width 0.089408)
		(layer "In9.Cu")
		(net "H_CPU1_CATERR_G_N")
	)
	(segment
		(start 259.568696 -25.423622)
		(end 262.030718 -27.885644)
		(width 0.089408)
		(layer "In9.Cu")
		(net "H_CPU1_CATERR_G_N")
	)
	(segment
		(start 245.683278 -25.423622)
		(end 259.568696 -25.423622)
		(width 0.089408)
		(layer "In9.Cu")
		(net "H_CPU1_CATERR_G_N")
	)
	(segment
		(start 243.675154 -24.648414)
		(end 244.1575 -25.13076)
		(width 0.089408)
		(layer "In9.Cu")
		(net "H_CPU1_CATERR_G_N")
	)
	(segment
		(start 191.379856 -24.98344)
		(end 192.7479 -23.615396)
		(width 0.089408)
		(layer "In9.Cu")
		(net "H_CPU1_CATERR_G_N")
	)
	(segment
		(start 186.591194 -23.417784)
		(end 186.591194 -23.543768)
		(width 0.089408)
		(layer "In9.Cu")
		(net "H_CPU1_CATERR_G_N")
	)
	(segment
		(start 194.491356 -23.615396)
		(end 195.524374 -24.648414)
		(width 0.089408)
		(layer "In9.Cu")
		(net "H_CPU1_CATERR_G_N")
	)
	(segment
		(start 263.380982 -27.885644)
		(end 265.656314 -30.160976)
		(width 0.089408)
		(layer "In9.Cu")
		(net "H_CPU1_CATERR_G_N")
	)
	(segment
		(start 245.390416 -25.13076)
		(end 245.683278 -25.423622)
		(width 0.089408)
		(layer "In9.Cu")
		(net "H_CPU1_CATERR_G_N")
	)
	(segment
		(start 321.295014 -38.67023)
		(end 321.728084 -38.23716)
		(width 0.089408)
		(layer "In9.Cu")
		(net "H_CPU1_CATERR_G_N")
	)
	(segment
		(start 185.429652 -22.455632)
		(end 185.87212 -22.8981)
		(width 0.089408)
		(layer "In9.Cu")
		(net "H_CPU1_CATERR_G_N")
	)
	(segment
		(start 185.87212 -22.8981)
		(end 186.07151 -22.8981)
		(width 0.089408)
		(layer "In9.Cu")
		(net "H_CPU1_CATERR_G_N")
	)
	(segment
		(start 265.656314 -30.160976)
		(end 305.187096 -30.160976)
		(width 0.089408)
		(layer "In9.Cu")
		(net "H_CPU1_CATERR_G_N")
	)
	(segment
		(start 186.591194 -23.543768)
		(end 188.030866 -24.98344)
		(width 0.089408)
		(layer "In9.Cu")
		(net "H_CPU1_CATERR_G_N")
	)
	(segment
		(start 195.524374 -24.648414)
		(end 243.675154 -24.648414)
		(width 0.089408)
		(layer "In9.Cu")
		(net "H_CPU1_CATERR_G_N")
	)
	(segment
		(start 313.69635 -38.67023)
		(end 321.295014 -38.67023)
		(width 0.089408)
		(layer "In9.Cu")
		(net "H_CPU1_CATERR_G_N")
	)
	(segment
		(start 244.1575 -25.13076)
		(end 245.390416 -25.13076)
		(width 0.089408)
		(layer "In9.Cu")
		(net "H_CPU1_CATERR_G_N")
	)
	(segment
		(start 192.7479 -23.615396)
		(end 194.491356 -23.615396)
		(width 0.089408)
		(layer "In9.Cu")
		(net "H_CPU1_CATERR_G_N")
	)
	(segment
		(start 186.07151 -22.8981)
		(end 186.591194 -23.417784)
		(width 0.089408)
		(layer "In9.Cu")
		(net "H_CPU1_CATERR_G_N")
	)
	(segment
		(start 305.187096 -30.160976)
		(end 313.69635 -38.67023)
		(width 0.089408)
		(layer "In9.Cu")
		(net "H_CPU1_CATERR_G_N")
	)
	(segment
		(start 185.158888 -31.236412)
		(end 166.487348 -49.907952)
		(width 0.089408)
		(layer "In11.Cu")
		(net "H_CPU1_CATERR_G_N")
	)
	(segment
		(start 373.6213 -58.335926)
		(end 373.6213 -57.528968)
		(width 0.089408)
		(layer "In11.Cu")
		(net "H_CPU1_CATERR_G_N")
	)
	(segment
		(start 166.487348 -49.907952)
		(end 166.487348 -59.651646)
		(width 0.089408)
		(layer "In11.Cu")
		(net "H_CPU1_CATERR_G_N")
	)
	(segment
		(start 159.831786 -71.103744)
		(end 159.831786 -72.922892)
		(width 0.089408)
		(layer "In11.Cu")
		(net "H_CPU1_CATERR_G_N")
	)
	(segment
		(start 333.959454 -45.71746)
		(end 332.434438 -44.192444)
		(width 0.089408)
		(layer "In11.Cu")
		(net "H_CPU1_CATERR_G_N")
	)
	(segment
		(start 322.305934 -38.23716)
		(end 321.728084 -38.23716)
		(width 0.089408)
		(layer "In11.Cu")
		(net "H_CPU1_CATERR_G_N")
	)
	(segment
		(start 358.200198 -45.71746)
		(end 333.959454 -45.71746)
		(width 0.089408)
		(layer "In11.Cu")
		(net "H_CPU1_CATERR_G_N")
	)
	(segment
		(start 159.33547 -66.803524)
		(end 159.33547 -70.607428)
		(width 0.089408)
		(layer "In11.Cu")
		(net "H_CPU1_CATERR_G_N")
	)
	(segment
		(start 366.704626 -51.973988)
		(end 364.773718 -51.973988)
		(width 0.089408)
		(layer "In11.Cu")
		(net "H_CPU1_CATERR_G_N")
	)
	(segment
		(start 373.6213 -57.528968)
		(end 368.73307 -52.640738)
		(width 0.089408)
		(layer "In11.Cu")
		(net "H_CPU1_CATERR_G_N")
	)
	(segment
		(start 358.200452 -45.717206)
		(end 358.200198 -45.71746)
		(width 0.089408)
		(layer "In11.Cu")
		(net "H_CPU1_CATERR_G_N")
	)
	(segment
		(start 364.773718 -51.973988)
		(end 358.516936 -45.717206)
		(width 0.089408)
		(layer "In11.Cu")
		(net "H_CPU1_CATERR_G_N")
	)
	(segment
		(start 358.516936 -45.717206)
		(end 358.200452 -45.717206)
		(width 0.089408)
		(layer "In11.Cu")
		(net "H_CPU1_CATERR_G_N")
	)
	(segment
		(start 368.73307 -52.640738)
		(end 367.371376 -52.640738)
		(width 0.089408)
		(layer "In11.Cu")
		(net "H_CPU1_CATERR_G_N")
	)
	(segment
		(start 326.156574 -42.0878)
		(end 322.305934 -38.23716)
		(width 0.089408)
		(layer "In11.Cu")
		(net "H_CPU1_CATERR_G_N")
	)
	(segment
		(start 330.205588 -44.192444)
		(end 328.100944 -42.0878)
		(width 0.089408)
		(layer "In11.Cu")
		(net "H_CPU1_CATERR_G_N")
	)
	(segment
		(start 332.434438 -44.192444)
		(end 330.205588 -44.192444)
		(width 0.089408)
		(layer "In11.Cu")
		(net "H_CPU1_CATERR_G_N")
	)
	(segment
		(start 185.158888 -22.726396)
		(end 185.158888 -31.236412)
		(width 0.089408)
		(layer "In11.Cu")
		(net "H_CPU1_CATERR_G_N")
	)
	(segment
		(start 328.100944 -42.0878)
		(end 326.156574 -42.0878)
		(width 0.089408)
		(layer "In11.Cu")
		(net "H_CPU1_CATERR_G_N")
	)
	(segment
		(start 185.429652 -22.455632)
		(end 185.158888 -22.726396)
		(width 0.089408)
		(layer "In11.Cu")
		(net "H_CPU1_CATERR_G_N")
	)
	(segment
		(start 166.487348 -59.651646)
		(end 159.33547 -66.803524)
		(width 0.089408)
		(layer "In11.Cu")
		(net "H_CPU1_CATERR_G_N")
	)
	(segment
		(start 159.831786 -72.922892)
		(end 159.64535 -73.109328)
		(width 0.089408)
		(layer "In11.Cu")
		(net "H_CPU1_CATERR_G_N")
	)
	(segment
		(start 367.371376 -52.640738)
		(end 366.704626 -51.973988)
		(width 0.089408)
		(layer "In11.Cu")
		(net "H_CPU1_CATERR_G_N")
	)
	(segment
		(start 159.33547 -70.607428)
		(end 159.831786 -71.103744)
		(width 0.089408)
		(layer "In11.Cu")
		(net "H_CPU1_CATERR_G_N")
	)
	(segment
		(start 295.23182 -61.847984)
		(end 295.80332 -61.847984)
		(width 0.1016)
		(layer "F.Cu")
		(net "H_CPU0_THERMTRIP_G_N")
	)
	(segment
		(start 384.094228 -74.731118)
		(end 384.234182 -74.871072)
		(width 0.10795)
		(layer "F.Cu")
		(net "H_CPU0_THERMTRIP_G_N")
	)
	(segment
		(start 384.094228 -74.502518)
		(end 384.094228 -74.731118)
		(width 0.10795)
		(layer "F.Cu")
		(net "H_CPU0_THERMTRIP_G_N")
	)
	(segment
		(start 384.234182 -74.871072)
		(end 384.234182 -75.137518)
		(width 0.10795)
		(layer "F.Cu")
		(net "H_CPU0_THERMTRIP_G_N")
	)
	(segment
		(start 384.234182 -75.137518)
		(end 386.326888 -75.137518)
		(width 0.10795)
		(layer "F.Cu")
		(net "H_CPU0_THERMTRIP_G_N")
	)
	(via
		(at 295.80332 -61.847984)
		(size 0.508)
		(drill 0.254)
		(layers "F.Cu" "B.Cu")
		(net "H_CPU0_THERMTRIP_G_N")
	)
	(via
		(at 387.5151 -63.1698)
		(size 0.508)
		(drill 0.254)
		(layers "F.Cu" "B.Cu")
		(net "H_CPU0_THERMTRIP_G_N")
	)
	(via
		(at 384.094228 -74.502518)
		(size 0.508)
		(drill 0.254)
		(layers "F.Cu" "B.Cu")
		(net "H_CPU0_THERMTRIP_G_N")
	)
	(via
		(at 367.919 -65.4558)
		(size 0.508)
		(drill 0.254)
		(layers "F.Cu" "B.Cu")
		(net "H_CPU0_THERMTRIP_G_N")
	)
	(segment
		(start 383.6924 -70.95363)
		(end 383.6924 -72.128634)
		(width 0.089408)
		(layer "In2.Cu")
		(net "H_CPU0_THERMTRIP_G_N")
	)
	(segment
		(start 387.5151 -63.1698)
		(end 386.88518 -63.1698)
		(width 0.089408)
		(layer "In2.Cu")
		(net "H_CPU0_THERMTRIP_G_N")
	)
	(segment
		(start 386.88518 -63.1698)
		(end 385.662424 -64.392556)
		(width 0.089408)
		(layer "In2.Cu")
		(net "H_CPU0_THERMTRIP_G_N")
	)
	(segment
		(start 383.6924 -72.128634)
		(end 384.422904 -72.859138)
		(width 0.089408)
		(layer "In2.Cu")
		(net "H_CPU0_THERMTRIP_G_N")
	)
	(segment
		(start 385.662424 -68.983606)
		(end 383.6924 -70.95363)
		(width 0.089408)
		(layer "In2.Cu")
		(net "H_CPU0_THERMTRIP_G_N")
	)
	(segment
		(start 384.422904 -73.914762)
		(end 384.094228 -74.243438)
		(width 0.089408)
		(layer "In2.Cu")
		(net "H_CPU0_THERMTRIP_G_N")
	)
	(segment
		(start 384.094228 -74.243438)
		(end 384.094228 -74.502518)
		(width 0.089408)
		(layer "In2.Cu")
		(net "H_CPU0_THERMTRIP_G_N")
	)
	(segment
		(start 385.662424 -64.392556)
		(end 385.662424 -68.983606)
		(width 0.089408)
		(layer "In2.Cu")
		(net "H_CPU0_THERMTRIP_G_N")
	)
	(segment
		(start 384.422904 -72.859138)
		(end 384.422904 -73.914762)
		(width 0.089408)
		(layer "In2.Cu")
		(net "H_CPU0_THERMTRIP_G_N")
	)
	(segment
		(start 376.390408 -63.556896)
		(end 375.827798 -62.994286)
		(width 0.089408)
		(layer "In4.Cu")
		(net "H_CPU0_THERMTRIP_G_N")
	)
	(segment
		(start 371.671596 -62.994286)
		(end 370.758974 -63.906908)
		(width 0.089408)
		(layer "In4.Cu")
		(net "H_CPU0_THERMTRIP_G_N")
	)
	(segment
		(start 375.827798 -62.994286)
		(end 371.671596 -62.994286)
		(width 0.089408)
		(layer "In4.Cu")
		(net "H_CPU0_THERMTRIP_G_N")
	)
	(segment
		(start 379.975872 -63.370968)
		(end 378.561346 -63.370968)
		(width 0.089408)
		(layer "In4.Cu")
		(net "H_CPU0_THERMTRIP_G_N")
	)
	(segment
		(start 377.430792 -63.708026)
		(end 377.279662 -63.556896)
		(width 0.089408)
		(layer "In4.Cu")
		(net "H_CPU0_THERMTRIP_G_N")
	)
	(segment
		(start 381.816356 -62.865)
		(end 380.48184 -62.865)
		(width 0.089408)
		(layer "In4.Cu")
		(net "H_CPU0_THERMTRIP_G_N")
	)
	(segment
		(start 378.224288 -63.708026)
		(end 377.430792 -63.708026)
		(width 0.089408)
		(layer "In4.Cu")
		(net "H_CPU0_THERMTRIP_G_N")
	)
	(segment
		(start 384.885946 -64.922654)
		(end 383.87401 -64.922654)
		(width 0.089408)
		(layer "In4.Cu")
		(net "H_CPU0_THERMTRIP_G_N")
	)
	(segment
		(start 380.48184 -62.865)
		(end 379.975872 -63.370968)
		(width 0.089408)
		(layer "In4.Cu")
		(net "H_CPU0_THERMTRIP_G_N")
	)
	(segment
		(start 369.016788 -63.906908)
		(end 367.919 -65.004696)
		(width 0.089408)
		(layer "In4.Cu")
		(net "H_CPU0_THERMTRIP_G_N")
	)
	(segment
		(start 383.87401 -64.922654)
		(end 381.816356 -62.865)
		(width 0.089408)
		(layer "In4.Cu")
		(net "H_CPU0_THERMTRIP_G_N")
	)
	(segment
		(start 387.4897 -63.1444)
		(end 386.6642 -63.1444)
		(width 0.089408)
		(layer "In4.Cu")
		(net "H_CPU0_THERMTRIP_G_N")
	)
	(segment
		(start 377.279662 -63.556896)
		(end 376.390408 -63.556896)
		(width 0.089408)
		(layer "In4.Cu")
		(net "H_CPU0_THERMTRIP_G_N")
	)
	(segment
		(start 387.5151 -63.1698)
		(end 387.4897 -63.1444)
		(width 0.089408)
		(layer "In4.Cu")
		(net "H_CPU0_THERMTRIP_G_N")
	)
	(segment
		(start 378.561346 -63.370968)
		(end 378.224288 -63.708026)
		(width 0.089408)
		(layer "In4.Cu")
		(net "H_CPU0_THERMTRIP_G_N")
	)
	(segment
		(start 367.919 -65.004696)
		(end 367.919 -65.4558)
		(width 0.089408)
		(layer "In4.Cu")
		(net "H_CPU0_THERMTRIP_G_N")
	)
	(segment
		(start 370.758974 -63.906908)
		(end 369.016788 -63.906908)
		(width 0.089408)
		(layer "In4.Cu")
		(net "H_CPU0_THERMTRIP_G_N")
	)
	(segment
		(start 386.6642 -63.1444)
		(end 384.885946 -64.922654)
		(width 0.089408)
		(layer "In4.Cu")
		(net "H_CPU0_THERMTRIP_G_N")
	)
	(segment
		(start 363.8804 -60.579)
		(end 365.259366 -60.579)
		(width 0.089408)
		(layer "In11.Cu")
		(net "H_CPU0_THERMTRIP_G_N")
	)
	(segment
		(start 318.717168 -59.83605)
		(end 322.697602 -55.855616)
		(width 0.089408)
		(layer "In11.Cu")
		(net "H_CPU0_THERMTRIP_G_N")
	)
	(segment
		(start 295.451784 -60.666122)
		(end 295.45661 -60.657486)
		(width 0.0889)
		(layer "In11.Cu")
		(net "H_CPU0_THERMTRIP_G_N")
	)
	(segment
		(start 298.36364 -57.981088)
		(end 298.396406 -57.981088)
		(width 0.0889)
		(layer "In11.Cu")
		(net "H_CPU0_THERMTRIP_G_N")
	)
	(segment
		(start 299.22597 -57.485534)
		(end 299.258736 -57.485534)
		(width 0.0889)
		(layer "In11.Cu")
		(net "H_CPU0_THERMTRIP_G_N")
	)
	(segment
		(start 297.17365 -58.67654)
		(end 297.176952 -58.670698)
		(width 0.0889)
		(layer "In11.Cu")
		(net "H_CPU0_THERMTRIP_G_N")
	)
	(segment
		(start 318.671194 -59.881262)
		(end 318.716406 -59.83605)
		(width 0.089408)
		(layer "In11.Cu")
		(net "H_CPU0_THERMTRIP_G_N")
	)
	(segment
		(start 295.451784 -61.656722)
		(end 295.45661 -61.648086)
		(width 0.0889)
		(layer "In11.Cu")
		(net "H_CPU0_THERMTRIP_G_N")
	)
	(segment
		(start 315.955426 -59.881262)
		(end 318.671194 -59.881262)
		(width 0.089408)
		(layer "In11.Cu")
		(net "H_CPU0_THERMTRIP_G_N")
	)
	(segment
		(start 351.157794 -53.888894)
		(end 352.517202 -53.888894)
		(width 0.089408)
		(layer "In11.Cu")
		(net "H_CPU0_THERMTRIP_G_N")
	)
	(segment
		(start 297.520106 -58.476388)
		(end 297.53306 -58.476388)
		(width 0.0889)
		(layer "In11.Cu")
		(net "H_CPU0_THERMTRIP_G_N")
	)
	(segment
		(start 366.630712 -64.167512)
		(end 367.919 -65.4558)
		(width 0.089408)
		(layer "In11.Cu")
		(net "H_CPU0_THERMTRIP_G_N")
	)
	(segment
		(start 358.609392 -55.307992)
		(end 363.8804 -60.579)
		(width 0.089408)
		(layer "In11.Cu")
		(net "H_CPU0_THERMTRIP_G_N")
	)
	(segment
		(start 302.66005 -55.504334)
		(end 302.692816 -55.504334)
		(width 0.0889)
		(layer "In11.Cu")
		(net "H_CPU0_THERMTRIP_G_N")
	)
	(segment
		(start 310.172862 -54.098698)
		(end 315.955426 -59.881262)
		(width 0.089408)
		(layer "In11.Cu")
		(net "H_CPU0_THERMTRIP_G_N")
	)
	(segment
		(start 295.80332 -61.847984)
		(end 295.547288 -61.995812)
		(width 0.0889)
		(layer "In11.Cu")
		(net "H_CPU0_THERMTRIP_G_N")
	)
	(segment
		(start 365.259366 -60.579)
		(end 366.07496 -61.394594)
		(width 0.089408)
		(layer "In11.Cu")
		(net "H_CPU0_THERMTRIP_G_N")
	)
	(segment
		(start 296.643806 -58.971688)
		(end 296.68343 -58.971688)
		(width 0.0889)
		(layer "In11.Cu")
		(net "H_CPU0_THERMTRIP_G_N")
	)
	(segment
		(start 354.217986 -55.589678)
		(end 355.332792 -55.589678)
		(width 0.089408)
		(layer "In11.Cu")
		(net "H_CPU0_THERMTRIP_G_N")
	)
	(segment
		(start 366.07496 -61.394594)
		(end 366.07496 -63.05042)
		(width 0.089408)
		(layer "In11.Cu")
		(net "H_CPU0_THERMTRIP_G_N")
	)
	(segment
		(start 352.517202 -53.888894)
		(end 354.217986 -55.589678)
		(width 0.089408)
		(layer "In11.Cu")
		(net "H_CPU0_THERMTRIP_G_N")
	)
	(segment
		(start 355.614478 -55.307992)
		(end 358.609392 -55.307992)
		(width 0.089408)
		(layer "In11.Cu")
		(net "H_CPU0_THERMTRIP_G_N")
	)
	(segment
		(start 295.45661 -61.648086)
		(end 295.46296 -61.637418)
		(width 0.0889)
		(layer "In11.Cu")
		(net "H_CPU0_THERMTRIP_G_N")
	)
	(segment
		(start 366.07496 -63.05042)
		(end 366.630712 -63.606172)
		(width 0.089408)
		(layer "In11.Cu")
		(net "H_CPU0_THERMTRIP_G_N")
	)
	(segment
		(start 300.94301 -56.494934)
		(end 300.975776 -56.494934)
		(width 0.0889)
		(layer "In11.Cu")
		(net "H_CPU0_THERMTRIP_G_N")
	)
	(segment
		(start 318.716406 -59.83605)
		(end 318.717168 -59.83605)
		(width 0.089408)
		(layer "In11.Cu")
		(net "H_CPU0_THERMTRIP_G_N")
	)
	(segment
		(start 349.191072 -55.855616)
		(end 351.157794 -53.888894)
		(width 0.089408)
		(layer "In11.Cu")
		(net "H_CPU0_THERMTRIP_G_N")
	)
	(segment
		(start 355.332792 -55.589678)
		(end 355.614478 -55.307992)
		(width 0.089408)
		(layer "In11.Cu")
		(net "H_CPU0_THERMTRIP_G_N")
	)
	(segment
		(start 304.37709 -54.513734)
		(end 304.93843 -54.513734)
		(width 0.0889)
		(layer "In11.Cu")
		(net "H_CPU0_THERMTRIP_G_N")
	)
	(segment
		(start 366.630712 -63.606172)
		(end 366.630712 -64.167512)
		(width 0.089408)
		(layer "In11.Cu")
		(net "H_CPU0_THERMTRIP_G_N")
	)
	(segment
		(start 295.45661 -60.657486)
		(end 295.46296 -60.646818)
		(width 0.0889)
		(layer "In11.Cu")
		(net "H_CPU0_THERMTRIP_G_N")
	)
	(segment
		(start 295.547288 -61.995812)
		(end 295.431464 -61.995812)
		(width 0.0889)
		(layer "In11.Cu")
		(net "H_CPU0_THERMTRIP_G_N")
	)
	(segment
		(start 305.353466 -54.098698)
		(end 310.172862 -54.098698)
		(width 0.089408)
		(layer "In11.Cu")
		(net "H_CPU0_THERMTRIP_G_N")
	)
	(segment
		(start 301.79772 -55.999888)
		(end 301.830486 -55.999888)
		(width 0.0889)
		(layer "In11.Cu")
		(net "H_CPU0_THERMTRIP_G_N")
	)
	(segment
		(start 322.697602 -55.855616)
		(end 349.191072 -55.855616)
		(width 0.089408)
		(layer "In11.Cu")
		(net "H_CPU0_THERMTRIP_G_N")
	)
	(segment
		(start 304.93843 -54.513734)
		(end 305.353466 -54.098698)
		(width 0.0889)
		(layer "In11.Cu")
		(net "H_CPU0_THERMTRIP_G_N")
	)
	(segment
		(start 295.785286 -59.466988)
		(end 295.8211 -59.466988)
		(width 0.0889)
		(layer "In11.Cu")
		(net "H_CPU0_THERMTRIP_G_N")
	)
	(segment
		(start 300.08068 -56.990488)
		(end 300.113446 -56.990488)
		(width 0.0889)
		(layer "In11.Cu")
		(net "H_CPU0_THERMTRIP_G_N")
	)
	(segment
		(start 303.51476 -55.009288)
		(end 303.547526 -55.009288)
		(width 0.0889)
		(layer "In11.Cu")
		(net "H_CPU0_THERMTRIP_G_N")
	)
	(arc
		(start 302.692816 -55.504334)
		(mid 302.976033 -55.420053)
		(end 303.183036 -55.209186)
		(width 0.0889)
		(layer "In11.Cu")
		(net "H_CPU0_THERMTRIP_G_N")
	)
	(arc
		(start 300.113446 -56.990488)
		(mid 300.39887 -56.907021)
		(end 300.607476 -56.695086)
		(width 0.0889)
		(layer "In11.Cu")
		(net "H_CPU0_THERMTRIP_G_N")
	)
	(arc
		(start 295.45661 -61.057536)
		(mid 295.40314 -60.862473)
		(end 295.451784 -60.666122)
		(width 0.0889)
		(layer "In11.Cu")
		(net "H_CPU0_THERMTRIP_G_N")
	)
	(arc
		(start 295.46296 -61.637418)
		(mid 295.535758 -61.346655)
		(end 295.45661 -61.057536)
		(width 0.0889)
		(layer "In11.Cu")
		(net "H_CPU0_THERMTRIP_G_N")
	)
	(arc
		(start 301.830486 -55.999888)
		(mid 302.11591 -55.916421)
		(end 302.324516 -55.704486)
		(width 0.0889)
		(layer "In11.Cu")
		(net "H_CPU0_THERMTRIP_G_N")
	)
	(arc
		(start 297.53306 -58.476388)
		(mid 297.821205 -58.394069)
		(end 298.031916 -58.180986)
		(width 0.0889)
		(layer "In11.Cu")
		(net "H_CPU0_THERMTRIP_G_N")
	)
	(arc
		(start 298.890436 -57.685686)
		(mid 299.032119 -57.541882)
		(end 299.22597 -57.485534)
		(width 0.0889)
		(layer "In11.Cu")
		(net "H_CPU0_THERMTRIP_G_N")
	)
	(arc
		(start 296.68343 -58.971688)
		(mid 296.966647 -58.887407)
		(end 297.17365 -58.67654)
		(width 0.0889)
		(layer "In11.Cu")
		(net "H_CPU0_THERMTRIP_G_N")
	)
	(arc
		(start 297.176952 -58.670698)
		(mid 297.322918 -58.528299)
		(end 297.520106 -58.476388)
		(width 0.0889)
		(layer "In11.Cu")
		(net "H_CPU0_THERMTRIP_G_N")
	)
	(arc
		(start 298.031916 -58.180986)
		(mid 298.171995 -58.03825)
		(end 298.36364 -57.981088)
		(width 0.0889)
		(layer "In11.Cu")
		(net "H_CPU0_THERMTRIP_G_N")
	)
	(arc
		(start 300.607476 -56.695086)
		(mid 300.749159 -56.551282)
		(end 300.94301 -56.494934)
		(width 0.0889)
		(layer "In11.Cu")
		(net "H_CPU0_THERMTRIP_G_N")
	)
	(arc
		(start 298.396406 -57.981088)
		(mid 298.68183 -57.897621)
		(end 298.890436 -57.685686)
		(width 0.0889)
		(layer "In11.Cu")
		(net "H_CPU0_THERMTRIP_G_N")
	)
	(arc
		(start 295.8211 -59.466988)
		(mid 296.106524 -59.383521)
		(end 296.31513 -59.171586)
		(width 0.0889)
		(layer "In11.Cu")
		(net "H_CPU0_THERMTRIP_G_N")
	)
	(arc
		(start 300.975776 -56.494934)
		(mid 301.258993 -56.410653)
		(end 301.465996 -56.199786)
		(width 0.0889)
		(layer "In11.Cu")
		(net "H_CPU0_THERMTRIP_G_N")
	)
	(arc
		(start 303.183036 -55.209186)
		(mid 303.323115 -55.06645)
		(end 303.51476 -55.009288)
		(width 0.0889)
		(layer "In11.Cu")
		(net "H_CPU0_THERMTRIP_G_N")
	)
	(arc
		(start 296.31513 -59.171586)
		(mid 296.453874 -59.029553)
		(end 296.643806 -58.971688)
		(width 0.0889)
		(layer "In11.Cu")
		(net "H_CPU0_THERMTRIP_G_N")
	)
	(arc
		(start 295.431464 -61.995812)
		(mid 295.403894 -61.824009)
		(end 295.451784 -61.656722)
		(width 0.0889)
		(layer "In11.Cu")
		(net "H_CPU0_THERMTRIP_G_N")
	)
	(arc
		(start 295.45661 -60.066936)
		(mid 295.4522 -59.674473)
		(end 295.785286 -59.466988)
		(width 0.0889)
		(layer "In11.Cu")
		(net "H_CPU0_THERMTRIP_G_N")
	)
	(arc
		(start 301.465996 -56.199786)
		(mid 301.606075 -56.05705)
		(end 301.79772 -55.999888)
		(width 0.0889)
		(layer "In11.Cu")
		(net "H_CPU0_THERMTRIP_G_N")
	)
	(arc
		(start 302.324516 -55.704486)
		(mid 302.466199 -55.560682)
		(end 302.66005 -55.504334)
		(width 0.0889)
		(layer "In11.Cu")
		(net "H_CPU0_THERMTRIP_G_N")
	)
	(arc
		(start 299.748956 -57.190386)
		(mid 299.889035 -57.04765)
		(end 300.08068 -56.990488)
		(width 0.0889)
		(layer "In11.Cu")
		(net "H_CPU0_THERMTRIP_G_N")
	)
	(arc
		(start 299.258736 -57.485534)
		(mid 299.541953 -57.401253)
		(end 299.748956 -57.190386)
		(width 0.0889)
		(layer "In11.Cu")
		(net "H_CPU0_THERMTRIP_G_N")
	)
	(arc
		(start 303.547526 -55.009288)
		(mid 303.83295 -54.925821)
		(end 304.041556 -54.713886)
		(width 0.0889)
		(layer "In11.Cu")
		(net "H_CPU0_THERMTRIP_G_N")
	)
	(arc
		(start 304.041556 -54.713886)
		(mid 304.183239 -54.570082)
		(end 304.37709 -54.513734)
		(width 0.0889)
		(layer "In11.Cu")
		(net "H_CPU0_THERMTRIP_G_N")
	)
	(arc
		(start 295.46296 -60.646818)
		(mid 295.535758 -60.356055)
		(end 295.45661 -60.066936)
		(width 0.0889)
		(layer "In11.Cu")
		(net "H_CPU0_THERMTRIP_G_N")
	)
	(segment
		(start 294.3733 -62.343538)
		(end 294.9448 -62.343538)
		(width 0.1016)
		(layer "F.Cu")
		(net "H_CPU0_PROCHOT_G_N")
	)
	(via
		(at 294.9448 -62.343538)
		(size 0.508)
		(drill 0.254)
		(layers "F.Cu" "B.Cu")
		(net "H_CPU0_PROCHOT_G_N")
	)
	(via
		(at 374.231916 -38.924484)
		(size 0.508)
		(drill 0.254)
		(layers "F.Cu" "B.Cu")
		(net "H_CPU0_PROCHOT_G_N")
	)
	(via
		(at 394.220954 -43.701462)
		(size 0.508)
		(drill 0.254)
		(layers "F.Cu" "B.Cu")
		(net "H_CPU0_PROCHOT_G_N")
	)
	(via
		(at 377.24334 -34.248598)
		(size 0.508)
		(drill 0.254)
		(layers "F.Cu" "B.Cu")
		(net "H_CPU0_PROCHOT_G_N")
	)
	(via
		(at 337.838796 -54.991)
		(size 0.508)
		(drill 0.254)
		(layers "F.Cu" "B.Cu")
		(net "H_CPU0_PROCHOT_G_N")
	)
	(via
		(at 375.701052 -33.10128)
		(size 0.6604)
		(drill 0.3302)
		(layers "F.Cu" "B.Cu")
		(net "H_CPU0_PROCHOT_G_N")
	)
	(via
		(at 374.620282 -46.29785)
		(size 0.508)
		(drill 0.254)
		(layers "F.Cu" "B.Cu")
		(net "H_CPU0_PROCHOT_G_N")
	)
	(segment
		(start 357.728774 -44.75861)
		(end 357.728774 -39.61511)
		(width 0.10795)
		(layer "B.Cu")
		(net "H_CPU0_PROCHOT_G_N")
	)
	(segment
		(start 373.180102 -31.270702)
		(end 373.761 -31.8516)
		(width 0.10795)
		(layer "B.Cu")
		(net "H_CPU0_PROCHOT_G_N")
	)
	(segment
		(start 394.1191 -43.599608)
		(end 394.220954 -43.701462)
		(width 0.10795)
		(layer "B.Cu")
		(net "H_CPU0_PROCHOT_G_N")
	)
	(segment
		(start 366.073182 -31.270702)
		(end 373.180102 -31.270702)
		(width 0.10795)
		(layer "B.Cu")
		(net "H_CPU0_PROCHOT_G_N")
	)
	(segment
		(start 374.231916 -38.363906)
		(end 374.231916 -38.924484)
		(width 0.10795)
		(layer "B.Cu")
		(net "H_CPU0_PROCHOT_G_N")
	)
	(segment
		(start 376.84837 -34.248598)
		(end 375.701052 -33.10128)
		(width 0.10795)
		(layer "B.Cu")
		(net "H_CPU0_PROCHOT_G_N")
	)
	(segment
		(start 339.486494 -52.844192)
		(end 341.759286 -50.5714)
		(width 0.10795)
		(layer "B.Cu")
		(net "H_CPU0_PROCHOT_G_N")
	)
	(segment
		(start 337.838796 -55.355998)
		(end 337.838796 -54.991)
		(width 0.10795)
		(layer "B.Cu")
		(net "H_CPU0_PROCHOT_G_N")
	)
	(segment
		(start 374.381268 -46.536864)
		(end 374.381268 -47.566326)
		(width 0.10795)
		(layer "B.Cu")
		(net "H_CPU0_PROCHOT_G_N")
	)
	(segment
		(start 373.8372 -46.0756)
		(end 374.398032 -46.0756)
		(width 0.10795)
		(layer "B.Cu")
		(net "H_CPU0_PROCHOT_G_N")
	)
	(segment
		(start 337.838796 -54.991)
		(end 339.486494 -53.343302)
		(width 0.10795)
		(layer "B.Cu")
		(net "H_CPU0_PROCHOT_G_N")
	)
	(segment
		(start 338.0232 -55.9943)
		(end 338.0232 -55.540402)
		(width 0.10795)
		(layer "B.Cu")
		(net "H_CPU0_PROCHOT_G_N")
	)
	(segment
		(start 351.915984 -50.5714)
		(end 357.728774 -44.75861)
		(width 0.10795)
		(layer "B.Cu")
		(net "H_CPU0_PROCHOT_G_N")
	)
	(segment
		(start 393.351512 -43.599608)
		(end 394.1191 -43.599608)
		(width 0.10795)
		(layer "B.Cu")
		(net "H_CPU0_PROCHOT_G_N")
	)
	(segment
		(start 339.486494 -53.343302)
		(end 339.486494 -52.844192)
		(width 0.10795)
		(layer "B.Cu")
		(net "H_CPU0_PROCHOT_G_N")
	)
	(segment
		(start 374.381268 -48.328326)
		(end 374.381268 -47.566326)
		(width 0.10795)
		(layer "B.Cu")
		(net "H_CPU0_PROCHOT_G_N")
	)
	(segment
		(start 373.761 -31.8516)
		(end 374.451372 -31.8516)
		(width 0.10795)
		(layer "B.Cu")
		(net "H_CPU0_PROCHOT_G_N")
	)
	(segment
		(start 341.759286 -50.5714)
		(end 351.915984 -50.5714)
		(width 0.10795)
		(layer "B.Cu")
		(net "H_CPU0_PROCHOT_G_N")
	)
	(segment
		(start 374.398032 -46.0756)
		(end 374.620282 -46.29785)
		(width 0.10795)
		(layer "B.Cu")
		(net "H_CPU0_PROCHOT_G_N")
	)
	(segment
		(start 357.728774 -39.61511)
		(end 366.073182 -31.270702)
		(width 0.10795)
		(layer "B.Cu")
		(net "H_CPU0_PROCHOT_G_N")
	)
	(segment
		(start 374.620282 -46.29785)
		(end 374.381268 -46.536864)
		(width 0.10795)
		(layer "B.Cu")
		(net "H_CPU0_PROCHOT_G_N")
	)
	(segment
		(start 374.451372 -31.8516)
		(end 375.701052 -33.10128)
		(width 0.10795)
		(layer "B.Cu")
		(net "H_CPU0_PROCHOT_G_N")
	)
	(segment
		(start 377.24334 -34.248598)
		(end 376.84837 -34.248598)
		(width 0.10795)
		(layer "B.Cu")
		(net "H_CPU0_PROCHOT_G_N")
	)
	(segment
		(start 338.0232 -55.540402)
		(end 337.838796 -55.355998)
		(width 0.10795)
		(layer "B.Cu")
		(net "H_CPU0_PROCHOT_G_N")
	)
	(segment
		(start 380.074424 -41.8592)
		(end 377.54306 -41.8592)
		(width 0.089408)
		(layer "In4.Cu")
		(net "H_CPU0_PROCHOT_G_N")
	)
	(segment
		(start 394.220954 -43.701462)
		(end 394.029692 -43.5102)
		(width 0.089408)
		(layer "In4.Cu")
		(net "H_CPU0_PROCHOT_G_N")
	)
	(segment
		(start 387.588252 -43.014646)
		(end 386.337302 -41.763696)
		(width 0.089408)
		(layer "In4.Cu")
		(net "H_CPU0_PROCHOT_G_N")
	)
	(segment
		(start 377.54306 -41.8592)
		(end 375.168922 -39.485062)
		(width 0.089408)
		(layer "In4.Cu")
		(net "H_CPU0_PROCHOT_G_N")
	)
	(segment
		(start 374.792494 -39.485062)
		(end 374.231916 -38.924484)
		(width 0.089408)
		(layer "In4.Cu")
		(net "H_CPU0_PROCHOT_G_N")
	)
	(segment
		(start 381.295402 -42.277538)
		(end 380.877064 -41.8592)
		(width 0.089408)
		(layer "In4.Cu")
		(net "H_CPU0_PROCHOT_G_N")
	)
	(segment
		(start 380.877064 -41.8592)
		(end 380.65202 -41.8592)
		(width 0.089408)
		(layer "In4.Cu")
		(net "H_CPU0_PROCHOT_G_N")
	)
	(segment
		(start 380.650496 -41.860724)
		(end 380.075948 -41.860724)
		(width 0.089408)
		(layer "In4.Cu")
		(net "H_CPU0_PROCHOT_G_N")
	)
	(segment
		(start 388.303262 -43.5102)
		(end 387.807708 -43.014646)
		(width 0.089408)
		(layer "In4.Cu")
		(net "H_CPU0_PROCHOT_G_N")
	)
	(segment
		(start 386.337302 -41.763696)
		(end 383.051304 -41.763696)
		(width 0.089408)
		(layer "In4.Cu")
		(net "H_CPU0_PROCHOT_G_N")
	)
	(segment
		(start 383.051304 -41.763696)
		(end 382.537462 -42.277538)
		(width 0.089408)
		(layer "In4.Cu")
		(net "H_CPU0_PROCHOT_G_N")
	)
	(segment
		(start 375.168922 -39.485062)
		(end 374.792494 -39.485062)
		(width 0.089408)
		(layer "In4.Cu")
		(net "H_CPU0_PROCHOT_G_N")
	)
	(segment
		(start 380.65202 -41.8592)
		(end 380.650496 -41.860724)
		(width 0.089408)
		(layer "In4.Cu")
		(net "H_CPU0_PROCHOT_G_N")
	)
	(segment
		(start 380.075948 -41.860724)
		(end 380.074424 -41.8592)
		(width 0.089408)
		(layer "In4.Cu")
		(net "H_CPU0_PROCHOT_G_N")
	)
	(segment
		(start 382.537462 -42.277538)
		(end 381.295402 -42.277538)
		(width 0.089408)
		(layer "In4.Cu")
		(net "H_CPU0_PROCHOT_G_N")
	)
	(segment
		(start 394.029692 -43.5102)
		(end 388.303262 -43.5102)
		(width 0.089408)
		(layer "In4.Cu")
		(net "H_CPU0_PROCHOT_G_N")
	)
	(segment
		(start 387.807708 -43.014646)
		(end 387.588252 -43.014646)
		(width 0.089408)
		(layer "In4.Cu")
		(net "H_CPU0_PROCHOT_G_N")
	)
	(segment
		(start 377.24334 -34.248598)
		(end 375.156476 -36.335462)
		(width 0.089408)
		(layer "In9.Cu")
		(net "H_CPU0_PROCHOT_G_N")
	)
	(segment
		(start 375.156476 -36.335462)
		(end 375.156476 -37.999924)
		(width 0.089408)
		(layer "In9.Cu")
		(net "H_CPU0_PROCHOT_G_N")
	)
	(segment
		(start 375.156476 -37.999924)
		(end 374.231916 -38.924484)
		(width 0.089408)
		(layer "In9.Cu")
		(net "H_CPU0_PROCHOT_G_N")
	)
	(segment
		(start 295.29151 -60.562236)
		(end 295.296336 -60.5536)
		(width 0.0889)
		(layer "In11.Cu")
		(net "H_CPU0_PROCHOT_G_N")
	)
	(segment
		(start 374.231916 -42.455084)
		(end 373.03964 -43.64736)
		(width 0.089408)
		(layer "In11.Cu")
		(net "H_CPU0_PROCHOT_G_N")
	)
	(segment
		(start 374.620282 -46.105572)
		(end 374.620282 -46.29785)
		(width 0.089408)
		(layer "In11.Cu")
		(net "H_CPU0_PROCHOT_G_N")
	)
	(segment
		(start 305.057302 -54.120542)
		(end 305.412648 -53.765196)
		(width 0.089408)
		(layer "In11.Cu")
		(net "H_CPU0_PROCHOT_G_N")
	)
	(segment
		(start 311.837578 -52.400454)
		(end 312.744104 -53.30698)
		(width 0.089408)
		(layer "In11.Cu")
		(net "H_CPU0_PROCHOT_G_N")
	)
	(segment
		(start 296.64406 -58.780934)
		(end 296.674032 -58.780934)
		(width 0.0889)
		(layer "In11.Cu")
		(net "H_CPU0_PROCHOT_G_N")
	)
	(segment
		(start 295.78173 -59.276234)
		(end 295.821354 -59.276234)
		(width 0.0889)
		(layer "In11.Cu")
		(net "H_CPU0_PROCHOT_G_N")
	)
	(segment
		(start 323.127878 -54.470808)
		(end 335.3308 -54.470808)
		(width 0.089408)
		(layer "In11.Cu")
		(net "H_CPU0_PROCHOT_G_N")
	)
	(segment
		(start 305.412648 -53.765196)
		(end 309.84317 -53.765196)
		(width 0.089408)
		(layer "In11.Cu")
		(net "H_CPU0_PROCHOT_G_N")
	)
	(segment
		(start 337.37042 -54.471824)
		(end 337.838796 -54.9402)
		(width 0.089408)
		(layer "In11.Cu")
		(net "H_CPU0_PROCHOT_G_N")
	)
	(segment
		(start 300.074076 -56.799988)
		(end 300.106842 -56.799988)
		(width 0.0889)
		(layer "In11.Cu")
		(net "H_CPU0_PROCHOT_G_N")
	)
	(segment
		(start 301.791116 -55.809388)
		(end 301.823882 -55.809388)
		(width 0.0889)
		(layer "In11.Cu")
		(net "H_CPU0_PROCHOT_G_N")
	)
	(segment
		(start 299.219366 -57.295034)
		(end 299.252132 -57.295034)
		(width 0.0889)
		(layer "In11.Cu")
		(net "H_CPU0_PROCHOT_G_N")
	)
	(segment
		(start 316.241938 -59.161426)
		(end 318.43726 -59.161426)
		(width 0.089408)
		(layer "In11.Cu")
		(net "H_CPU0_PROCHOT_G_N")
	)
	(segment
		(start 374.231916 -38.924484)
		(end 374.231916 -42.455084)
		(width 0.089408)
		(layer "In11.Cu")
		(net "H_CPU0_PROCHOT_G_N")
	)
	(segment
		(start 311.207912 -52.400454)
		(end 311.837578 -52.400454)
		(width 0.089408)
		(layer "In11.Cu")
		(net "H_CPU0_PROCHOT_G_N")
	)
	(segment
		(start 309.84317 -53.765196)
		(end 311.207912 -52.400454)
		(width 0.089408)
		(layer "In11.Cu")
		(net "H_CPU0_PROCHOT_G_N")
	)
	(segment
		(start 335.3308 -54.470808)
		(end 335.331816 -54.471824)
		(width 0.089408)
		(layer "In11.Cu")
		(net "H_CPU0_PROCHOT_G_N")
	)
	(segment
		(start 300.936406 -56.304434)
		(end 300.969172 -56.304434)
		(width 0.0889)
		(layer "In11.Cu")
		(net "H_CPU0_PROCHOT_G_N")
	)
	(segment
		(start 312.744104 -53.30698)
		(end 312.744104 -55.663592)
		(width 0.089408)
		(layer "In11.Cu")
		(net "H_CPU0_PROCHOT_G_N")
	)
	(segment
		(start 304.85461 -54.323234)
		(end 305.057302 -54.120542)
		(width 0.0889)
		(layer "In11.Cu")
		(net "H_CPU0_PROCHOT_G_N")
	)
	(segment
		(start 295.29151 -61.552836)
		(end 295.296336 -61.5442)
		(width 0.0889)
		(layer "In11.Cu")
		(net "H_CPU0_PROCHOT_G_N")
	)
	(segment
		(start 303.508156 -54.818788)
		(end 303.540922 -54.818788)
		(width 0.0889)
		(layer "In11.Cu")
		(net "H_CPU0_PROCHOT_G_N")
	)
	(segment
		(start 318.43726 -59.161426)
		(end 323.127878 -54.470808)
		(width 0.089408)
		(layer "In11.Cu")
		(net "H_CPU0_PROCHOT_G_N")
	)
	(segment
		(start 337.838796 -54.9402)
		(end 337.838796 -54.991)
		(width 0.089408)
		(layer "In11.Cu")
		(net "H_CPU0_PROCHOT_G_N")
	)
	(segment
		(start 335.331816 -54.471824)
		(end 337.37042 -54.471824)
		(width 0.089408)
		(layer "In11.Cu")
		(net "H_CPU0_PROCHOT_G_N")
	)
	(segment
		(start 302.653446 -55.313834)
		(end 302.686212 -55.313834)
		(width 0.0889)
		(layer "In11.Cu")
		(net "H_CPU0_PROCHOT_G_N")
	)
	(segment
		(start 297.507152 -58.285634)
		(end 297.535092 -58.285634)
		(width 0.0889)
		(layer "In11.Cu")
		(net "H_CPU0_PROCHOT_G_N")
	)
	(segment
		(start 295.237916 -62.174374)
		(end 295.261792 -62.084966)
		(width 0.0889)
		(layer "In11.Cu")
		(net "H_CPU0_PROCHOT_G_N")
	)
	(segment
		(start 373.03964 -43.64736)
		(end 373.03964 -44.52493)
		(width 0.089408)
		(layer "In11.Cu")
		(net "H_CPU0_PROCHOT_G_N")
	)
	(segment
		(start 298.357036 -57.790588)
		(end 298.389802 -57.790588)
		(width 0.0889)
		(layer "In11.Cu")
		(net "H_CPU0_PROCHOT_G_N")
	)
	(segment
		(start 312.744104 -55.663592)
		(end 316.241938 -59.161426)
		(width 0.089408)
		(layer "In11.Cu")
		(net "H_CPU0_PROCHOT_G_N")
	)
	(segment
		(start 304.370486 -54.323234)
		(end 304.85461 -54.323234)
		(width 0.0889)
		(layer "In11.Cu")
		(net "H_CPU0_PROCHOT_G_N")
	)
	(segment
		(start 295.28516 -60.572904)
		(end 295.29151 -60.562236)
		(width 0.0889)
		(layer "In11.Cu")
		(net "H_CPU0_PROCHOT_G_N")
	)
	(segment
		(start 295.28516 -61.563504)
		(end 295.29151 -61.552836)
		(width 0.0889)
		(layer "In11.Cu")
		(net "H_CPU0_PROCHOT_G_N")
	)
	(segment
		(start 373.03964 -44.52493)
		(end 374.620282 -46.105572)
		(width 0.089408)
		(layer "In11.Cu")
		(net "H_CPU0_PROCHOT_G_N")
	)
	(segment
		(start 294.9448 -62.343538)
		(end 295.237916 -62.174374)
		(width 0.0889)
		(layer "In11.Cu")
		(net "H_CPU0_PROCHOT_G_N")
	)
	(arc
		(start 303.876456 -54.618636)
		(mid 304.085064 -54.406704)
		(end 304.370486 -54.323234)
		(width 0.0889)
		(layer "In11.Cu")
		(net "H_CPU0_PROCHOT_G_N")
	)
	(arc
		(start 303.017936 -55.113936)
		(mid 303.22494 -54.903072)
		(end 303.508156 -54.818788)
		(width 0.0889)
		(layer "In11.Cu")
		(net "H_CPU0_PROCHOT_G_N")
	)
	(arc
		(start 295.261792 -62.084966)
		(mid 295.21278 -61.821517)
		(end 295.28516 -61.563504)
		(width 0.0889)
		(layer "In11.Cu")
		(net "H_CPU0_PROCHOT_G_N")
	)
	(arc
		(start 303.540922 -54.818788)
		(mid 303.734772 -54.762438)
		(end 303.876456 -54.618636)
		(width 0.0889)
		(layer "In11.Cu")
		(net "H_CPU0_PROCHOT_G_N")
	)
	(arc
		(start 296.15003 -59.076336)
		(mid 296.358638 -58.864404)
		(end 296.64406 -58.780934)
		(width 0.0889)
		(layer "In11.Cu")
		(net "H_CPU0_PROCHOT_G_N")
	)
	(arc
		(start 299.583856 -57.095136)
		(mid 299.79086 -56.884272)
		(end 300.074076 -56.799988)
		(width 0.0889)
		(layer "In11.Cu")
		(net "H_CPU0_PROCHOT_G_N")
	)
	(arc
		(start 295.296336 -60.5536)
		(mid 295.345091 -60.357248)
		(end 295.29151 -60.162186)
		(width 0.0889)
		(layer "In11.Cu")
		(net "H_CPU0_PROCHOT_G_N")
	)
	(arc
		(start 295.29151 -59.571382)
		(mid 295.498514 -59.360518)
		(end 295.78173 -59.276234)
		(width 0.0889)
		(layer "In11.Cu")
		(net "H_CPU0_PROCHOT_G_N")
	)
	(arc
		(start 302.686212 -55.313834)
		(mid 302.877854 -55.256668)
		(end 303.017936 -55.113936)
		(width 0.0889)
		(layer "In11.Cu")
		(net "H_CPU0_PROCHOT_G_N")
	)
	(arc
		(start 298.725336 -57.590436)
		(mid 298.933944 -57.378504)
		(end 299.219366 -57.295034)
		(width 0.0889)
		(layer "In11.Cu")
		(net "H_CPU0_PROCHOT_G_N")
	)
	(arc
		(start 300.106842 -56.799988)
		(mid 300.300692 -56.743638)
		(end 300.442376 -56.599836)
		(width 0.0889)
		(layer "In11.Cu")
		(net "H_CPU0_PROCHOT_G_N")
	)
	(arc
		(start 295.29151 -61.152786)
		(mid 295.212288 -60.863668)
		(end 295.28516 -60.572904)
		(width 0.0889)
		(layer "In11.Cu")
		(net "H_CPU0_PROCHOT_G_N")
	)
	(arc
		(start 302.159416 -55.609236)
		(mid 302.368024 -55.397304)
		(end 302.653446 -55.313834)
		(width 0.0889)
		(layer "In11.Cu")
		(net "H_CPU0_PROCHOT_G_N")
	)
	(arc
		(start 299.252132 -57.295034)
		(mid 299.443774 -57.237868)
		(end 299.583856 -57.095136)
		(width 0.0889)
		(layer "In11.Cu")
		(net "H_CPU0_PROCHOT_G_N")
	)
	(arc
		(start 295.296336 -61.5442)
		(mid 295.345091 -61.347848)
		(end 295.29151 -61.152786)
		(width 0.0889)
		(layer "In11.Cu")
		(net "H_CPU0_PROCHOT_G_N")
	)
	(arc
		(start 297.866816 -58.085736)
		(mid 298.07382 -57.874872)
		(end 298.357036 -57.790588)
		(width 0.0889)
		(layer "In11.Cu")
		(net "H_CPU0_PROCHOT_G_N")
	)
	(arc
		(start 300.969172 -56.304434)
		(mid 301.160814 -56.247268)
		(end 301.300896 -56.104536)
		(width 0.0889)
		(layer "In11.Cu")
		(net "H_CPU0_PROCHOT_G_N")
	)
	(arc
		(start 298.389802 -57.790588)
		(mid 298.583652 -57.734238)
		(end 298.725336 -57.590436)
		(width 0.0889)
		(layer "In11.Cu")
		(net "H_CPU0_PROCHOT_G_N")
	)
	(arc
		(start 300.442376 -56.599836)
		(mid 300.650984 -56.387904)
		(end 300.936406 -56.304434)
		(width 0.0889)
		(layer "In11.Cu")
		(net "H_CPU0_PROCHOT_G_N")
	)
	(arc
		(start 295.821354 -59.276234)
		(mid 296.011283 -59.218364)
		(end 296.15003 -59.076336)
		(width 0.0889)
		(layer "In11.Cu")
		(net "H_CPU0_PROCHOT_G_N")
	)
	(arc
		(start 297.008296 -58.581036)
		(mid 297.219009 -58.367957)
		(end 297.507152 -58.285634)
		(width 0.0889)
		(layer "In11.Cu")
		(net "H_CPU0_PROCHOT_G_N")
	)
	(arc
		(start 301.823882 -55.809388)
		(mid 302.017732 -55.753038)
		(end 302.159416 -55.609236)
		(width 0.0889)
		(layer "In11.Cu")
		(net "H_CPU0_PROCHOT_G_N")
	)
	(arc
		(start 301.300896 -56.104536)
		(mid 301.5079 -55.893672)
		(end 301.791116 -55.809388)
		(width 0.0889)
		(layer "In11.Cu")
		(net "H_CPU0_PROCHOT_G_N")
	)
	(arc
		(start 296.674032 -58.780934)
		(mid 296.867135 -58.724415)
		(end 297.008296 -58.581036)
		(width 0.0889)
		(layer "In11.Cu")
		(net "H_CPU0_PROCHOT_G_N")
	)
	(arc
		(start 297.535092 -58.285634)
		(mid 297.726734 -58.228468)
		(end 297.866816 -58.085736)
		(width 0.0889)
		(layer "In11.Cu")
		(net "H_CPU0_PROCHOT_G_N")
	)
	(arc
		(start 295.29151 -60.162186)
		(mid 295.212379 -59.866784)
		(end 295.29151 -59.571382)
		(width 0.0889)
		(layer "In11.Cu")
		(net "H_CPU0_PROCHOT_G_N")
	)
	(segment
		(start 357.740458 -72.269858)
		(end 357.029766 -71.559166)
		(width 0.10795)
		(layer "F.Cu")
		(net "H_CPU0_MSMI_G_N")
	)
	(segment
		(start 372.8593 -83.09102)
		(end 373.47017 -83.09102)
		(width 0.10795)
		(layer "F.Cu")
		(net "H_CPU0_MSMI_G_N")
	)
	(segment
		(start 290.93922 -67.296538)
		(end 291.51072 -67.296538)
		(width 0.1016)
		(layer "F.Cu")
		(net "H_CPU0_MSMI_G_N")
	)
	(segment
		(start 282.365196 -72.853804)
		(end 283.717746 -72.853804)
		(width 0.10795)
		(layer "F.Cu")
		(net "H_CPU0_MSMI_G_N")
	)
	(segment
		(start 365.881666 -81.358994)
		(end 367.695734 -81.358994)
		(width 0.10795)
		(layer "F.Cu")
		(net "H_CPU0_MSMI_G_N")
	)
	(segment
		(start 382.504442 -78.61554)
		(end 382.979168 -78.140814)
		(width 0.10795)
		(layer "F.Cu")
		(net "H_CPU0_MSMI_G_N")
	)
	(segment
		(start 371.964966 -82.196686)
		(end 372.8593 -83.09102)
		(width 0.10795)
		(layer "F.Cu")
		(net "H_CPU0_MSMI_G_N")
	)
	(segment
		(start 367.695734 -81.342484)
		(end 367.918746 -81.119472)
		(width 0.10795)
		(layer "F.Cu")
		(net "H_CPU0_MSMI_G_N")
	)
	(segment
		(start 357.029766 -71.559166)
		(end 356.688644 -71.559166)
		(width 0.10795)
		(layer "F.Cu")
		(net "H_CPU0_MSMI_G_N")
	)
	(segment
		(start 373.47017 -83.09102)
		(end 373.776748 -82.784442)
		(width 0.10795)
		(layer "F.Cu")
		(net "H_CPU0_MSMI_G_N")
	)
	(segment
		(start 367.918746 -81.119472)
		(end 369.914678 -81.119472)
		(width 0.10795)
		(layer "F.Cu")
		(net "H_CPU0_MSMI_G_N")
	)
	(segment
		(start 367.695734 -81.358994)
		(end 367.695734 -81.342484)
		(width 0.10795)
		(layer "F.Cu")
		(net "H_CPU0_MSMI_G_N")
	)
	(segment
		(start 360.501692 -72.269858)
		(end 363.699044 -75.466956)
		(width 0.10795)
		(layer "F.Cu")
		(net "H_CPU0_MSMI_G_N")
	)
	(segment
		(start 359.566718 -72.269858)
		(end 360.501692 -72.269858)
		(width 0.10795)
		(layer "F.Cu")
		(net "H_CPU0_MSMI_G_N")
	)
	(segment
		(start 363.699044 -75.466956)
		(end 363.727238 -75.495404)
		(width 0.10795)
		(layer "F.Cu")
		(net "H_CPU0_MSMI_G_N")
	)
	(segment
		(start 363.727238 -75.495404)
		(end 363.727238 -79.204566)
		(width 0.10795)
		(layer "F.Cu")
		(net "H_CPU0_MSMI_G_N")
	)
	(segment
		(start 282.067 -73.152)
		(end 282.365196 -72.853804)
		(width 0.10795)
		(layer "F.Cu")
		(net "H_CPU0_MSMI_G_N")
	)
	(segment
		(start 359.566718 -72.269858)
		(end 357.740458 -72.269858)
		(width 0.10795)
		(layer "F.Cu")
		(net "H_CPU0_MSMI_G_N")
	)
	(segment
		(start 382.979168 -78.140814)
		(end 383.14757 -78.140814)
		(width 0.10795)
		(layer "F.Cu")
		(net "H_CPU0_MSMI_G_N")
	)
	(segment
		(start 363.727238 -79.204566)
		(end 365.881666 -81.358994)
		(width 0.10795)
		(layer "F.Cu")
		(net "H_CPU0_MSMI_G_N")
	)
	(segment
		(start 373.776748 -82.784442)
		(end 373.776748 -82.684874)
		(width 0.10795)
		(layer "F.Cu")
		(net "H_CPU0_MSMI_G_N")
	)
	(segment
		(start 370.30406 -81.508854)
		(end 371.964966 -82.196686)
		(width 0.10795)
		(layer "F.Cu")
		(net "H_CPU0_MSMI_G_N")
	)
	(segment
		(start 369.914678 -81.119472)
		(end 370.30406 -81.508854)
		(width 0.10795)
		(layer "F.Cu")
		(net "H_CPU0_MSMI_G_N")
	)
	(via
		(at 382.504442 -78.61554)
		(size 0.508)
		(drill 0.254)
		(layers "F.Cu" "B.Cu")
		(net "H_CPU0_MSMI_G_N")
	)
	(via
		(at 373.776748 -82.684874)
		(size 0.508)
		(drill 0.254)
		(layers "F.Cu" "B.Cu")
		(net "H_CPU0_MSMI_G_N")
	)
	(via
		(at 356.688644 -71.559166)
		(size 0.508)
		(drill 0.254)
		(layers "F.Cu" "B.Cu")
		(net "H_CPU0_MSMI_G_N")
	)
	(via
		(at 283.717746 -72.853804)
		(size 0.508)
		(drill 0.254)
		(layers "F.Cu" "B.Cu")
		(net "H_CPU0_MSMI_G_N")
	)
	(via
		(at 359.566718 -72.269858)
		(size 0.762)
		(drill 0.381)
		(layers "F.Cu" "B.Cu")
		(net "H_CPU0_MSMI_G_N")
	)
	(via
		(at 291.51072 -67.296538)
		(size 0.508)
		(drill 0.254)
		(layers "F.Cu" "B.Cu")
		(net "H_CPU0_MSMI_G_N")
	)
	(segment
		(start 382.504442 -78.61554)
		(end 382.423162 -78.69682)
		(width 0.10795)
		(layer "B.Cu")
		(net "H_CPU0_MSMI_G_N")
	)
	(segment
		(start 374.236234 -82.226912)
		(end 373.778272 -82.684874)
		(width 0.10795)
		(layer "B.Cu")
		(net "H_CPU0_MSMI_G_N")
	)
	(segment
		(start 379.365256 -78.69682)
		(end 378.580396 -77.91196)
		(width 0.10795)
		(layer "B.Cu")
		(net "H_CPU0_MSMI_G_N")
	)
	(segment
		(start 377.16206 -78.41869)
		(end 376.89155 -78.6892)
		(width 0.10795)
		(layer "B.Cu")
		(net "H_CPU0_MSMI_G_N")
	)
	(segment
		(start 374.608852 -81.512664)
		(end 374.236234 -81.885282)
		(width 0.10795)
		(layer "B.Cu")
		(net "H_CPU0_MSMI_G_N")
	)
	(segment
		(start 382.423162 -78.69682)
		(end 379.365256 -78.69682)
		(width 0.10795)
		(layer "B.Cu")
		(net "H_CPU0_MSMI_G_N")
	)
	(segment
		(start 378.580396 -77.91196)
		(end 377.386342 -77.91196)
		(width 0.10795)
		(layer "B.Cu")
		(net "H_CPU0_MSMI_G_N")
	)
	(segment
		(start 377.16206 -78.136242)
		(end 377.16206 -78.41869)
		(width 0.10795)
		(layer "B.Cu")
		(net "H_CPU0_MSMI_G_N")
	)
	(segment
		(start 375.562114 -78.936342)
		(end 375.562114 -79.272892)
		(width 0.10795)
		(layer "B.Cu")
		(net "H_CPU0_MSMI_G_N")
	)
	(segment
		(start 374.608852 -80.226154)
		(end 374.608852 -81.512664)
		(width 0.10795)
		(layer "B.Cu")
		(net "H_CPU0_MSMI_G_N")
	)
	(segment
		(start 373.778272 -82.684874)
		(end 373.776748 -82.684874)
		(width 0.10795)
		(layer "B.Cu")
		(net "H_CPU0_MSMI_G_N")
	)
	(segment
		(start 376.89155 -78.6892)
		(end 375.809256 -78.6892)
		(width 0.10795)
		(layer "B.Cu")
		(net "H_CPU0_MSMI_G_N")
	)
	(segment
		(start 375.562114 -79.272892)
		(end 374.608852 -80.226154)
		(width 0.10795)
		(layer "B.Cu")
		(net "H_CPU0_MSMI_G_N")
	)
	(segment
		(start 374.236234 -81.885282)
		(end 374.236234 -82.226912)
		(width 0.10795)
		(layer "B.Cu")
		(net "H_CPU0_MSMI_G_N")
	)
	(segment
		(start 377.386342 -77.91196)
		(end 377.16206 -78.136242)
		(width 0.10795)
		(layer "B.Cu")
		(net "H_CPU0_MSMI_G_N")
	)
	(segment
		(start 375.809256 -78.6892)
		(end 375.562114 -78.936342)
		(width 0.10795)
		(layer "B.Cu")
		(net "H_CPU0_MSMI_G_N")
	)
	(segment
		(start 292.017704 -68.590922)
		(end 292.02253 -68.582286)
		(width 0.0889)
		(layer "In11.Cu")
		(net "H_CPU0_MSMI_G_N")
	)
	(segment
		(start 295.823894 -70.17258)
		(end 295.82364 -70.172834)
		(width 0.0889)
		(layer "In11.Cu")
		(net "H_CPU0_MSMI_G_N")
	)
	(segment
		(start 295.82364 -70.172834)
		(end 295.792144 -70.172834)
		(width 0.0889)
		(layer "In11.Cu")
		(net "H_CPU0_MSMI_G_N")
	)
	(segment
		(start 285.84017 -71.140828)
		(end 285.84017 -70.14083)
		(width 0.089408)
		(layer "In11.Cu")
		(net "H_CPU0_MSMI_G_N")
	)
	(segment
		(start 305.26736 -69.868542)
		(end 305.226212 -69.868542)
		(width 0.089408)
		(layer "In11.Cu")
		(net "H_CPU0_MSMI_G_N")
	)
	(segment
		(start 288.3662 -68.7324)
		(end 288.798 -68.3006)
		(width 0.089408)
		(layer "In11.Cu")
		(net "H_CPU0_MSMI_G_N")
	)
	(segment
		(start 307.517292 -70.387718)
		(end 307.03139 -69.901816)
		(width 0.089408)
		(layer "In11.Cu")
		(net "H_CPU0_MSMI_G_N")
	)
	(segment
		(start 290.410646 -67.46748)
		(end 290.47567 -67.402456)
		(width 0.0889)
		(layer "In11.Cu")
		(net "H_CPU0_MSMI_G_N")
	)
	(segment
		(start 284.6578 -72.323198)
		(end 285.84017 -71.140828)
		(width 0.089408)
		(layer "In11.Cu")
		(net "H_CPU0_MSMI_G_N")
	)
	(segment
		(start 307.977032 -70.387718)
		(end 307.517292 -70.387718)
		(width 0.089408)
		(layer "In11.Cu")
		(net "H_CPU0_MSMI_G_N")
	)
	(segment
		(start 283.717746 -72.853804)
		(end 283.717746 -72.747632)
		(width 0.089408)
		(layer "In11.Cu")
		(net "H_CPU0_MSMI_G_N")
	)
	(segment
		(start 291.53231 -67.696588)
		(end 291.499544 -67.696588)
		(width 0.0889)
		(layer "In11.Cu")
		(net "H_CPU0_MSMI_G_N")
	)
	(segment
		(start 352.47707 -66.50355)
		(end 336.795364 -66.50355)
		(width 0.089408)
		(layer "In11.Cu")
		(net "H_CPU0_MSMI_G_N")
	)
	(segment
		(start 294.96639 -69.677534)
		(end 294.92321 -69.677534)
		(width 0.0889)
		(layer "In11.Cu")
		(net "H_CPU0_MSMI_G_N")
	)
	(segment
		(start 289.687 -67.7672)
		(end 290.110926 -67.7672)
		(width 0.089408)
		(layer "In11.Cu")
		(net "H_CPU0_MSMI_G_N")
	)
	(segment
		(start 356.688644 -70.715124)
		(end 352.47707 -66.50355)
		(width 0.089408)
		(layer "In11.Cu")
		(net "H_CPU0_MSMI_G_N")
	)
	(segment
		(start 290.47567 -67.402456)
		(end 290.477702 -67.402456)
		(width 0.0889)
		(layer "In11.Cu")
		(net "H_CPU0_MSMI_G_N")
	)
	(segment
		(start 296.675302 -69.868542)
		(end 296.641266 -69.868542)
		(width 0.089408)
		(layer "In11.Cu")
		(net "H_CPU0_MSMI_G_N")
	)
	(segment
		(start 291.196522 -67.544188)
		(end 291.217604 -67.465448)
		(width 0.0889)
		(layer "In11.Cu")
		(net "H_CPU0_MSMI_G_N")
	)
	(segment
		(start 287.2486 -68.7324)
		(end 288.3662 -68.7324)
		(width 0.089408)
		(layer "In11.Cu")
		(net "H_CPU0_MSMI_G_N")
	)
	(segment
		(start 288.798 -68.3006)
		(end 289.1536 -68.3006)
		(width 0.089408)
		(layer "In11.Cu")
		(net "H_CPU0_MSMI_G_N")
	)
	(segment
		(start 292.38702 -69.182234)
		(end 292.354254 -69.182234)
		(width 0.0889)
		(layer "In11.Cu")
		(net "H_CPU0_MSMI_G_N")
	)
	(segment
		(start 289.1536 -68.3006)
		(end 289.687 -67.7672)
		(width 0.089408)
		(layer "In11.Cu")
		(net "H_CPU0_MSMI_G_N")
	)
	(segment
		(start 283.717746 -72.747632)
		(end 284.14218 -72.323198)
		(width 0.089408)
		(layer "In11.Cu")
		(net "H_CPU0_MSMI_G_N")
	)
	(segment
		(start 302.6918 -70.363588)
		(end 302.659034 -70.363588)
		(width 0.089408)
		(layer "In11.Cu")
		(net "H_CPU0_MSMI_G_N")
	)
	(segment
		(start 290.4871 -67.393058)
		(end 290.904676 -67.393058)
		(width 0.0889)
		(layer "In11.Cu")
		(net "H_CPU0_MSMI_G_N")
	)
	(segment
		(start 285.84017 -70.14083)
		(end 287.2486 -68.7324)
		(width 0.089408)
		(layer "In11.Cu")
		(net "H_CPU0_MSMI_G_N")
	)
	(segment
		(start 291.432742 -67.21856)
		(end 291.51072 -67.296538)
		(width 0.0889)
		(layer "In11.Cu")
		(net "H_CPU0_MSMI_G_N")
	)
	(segment
		(start 284.14218 -72.323198)
		(end 284.6578 -72.323198)
		(width 0.089408)
		(layer "In11.Cu")
		(net "H_CPU0_MSMI_G_N")
	)
	(segment
		(start 291.079174 -67.21856)
		(end 291.432742 -67.21856)
		(width 0.0889)
		(layer "In11.Cu")
		(net "H_CPU0_MSMI_G_N")
	)
	(segment
		(start 290.904676 -67.393058)
		(end 291.079174 -67.21856)
		(width 0.0889)
		(layer "In11.Cu")
		(net "H_CPU0_MSMI_G_N")
	)
	(segment
		(start 309.127144 -71.53783)
		(end 307.977032 -70.387718)
		(width 0.089408)
		(layer "In11.Cu")
		(net "H_CPU0_MSMI_G_N")
	)
	(segment
		(start 290.110926 -67.7672)
		(end 290.410646 -67.46748)
		(width 0.089408)
		(layer "In11.Cu")
		(net "H_CPU0_MSMI_G_N")
	)
	(segment
		(start 291.217604 -67.465448)
		(end 291.51072 -67.296538)
		(width 0.0889)
		(layer "In11.Cu")
		(net "H_CPU0_MSMI_G_N")
	)
	(segment
		(start 303.55032 -69.868542)
		(end 303.51095 -69.868542)
		(width 0.089408)
		(layer "In11.Cu")
		(net "H_CPU0_MSMI_G_N")
	)
	(segment
		(start 331.761084 -71.53783)
		(end 309.127144 -71.53783)
		(width 0.089408)
		(layer "In11.Cu")
		(net "H_CPU0_MSMI_G_N")
	)
	(segment
		(start 336.795364 -66.50355)
		(end 331.761084 -71.53783)
		(width 0.089408)
		(layer "In11.Cu")
		(net "H_CPU0_MSMI_G_N")
	)
	(segment
		(start 290.477702 -67.402456)
		(end 290.4871 -67.393058)
		(width 0.0889)
		(layer "In11.Cu")
		(net "H_CPU0_MSMI_G_N")
	)
	(segment
		(start 297.532298 -70.363588)
		(end 297.499532 -70.363588)
		(width 0.089408)
		(layer "In11.Cu")
		(net "H_CPU0_MSMI_G_N")
	)
	(segment
		(start 356.688644 -71.559166)
		(end 356.688644 -70.715124)
		(width 0.089408)
		(layer "In11.Cu")
		(net "H_CPU0_MSMI_G_N")
	)
	(segment
		(start 292.02253 -68.582286)
		(end 292.02888 -68.571618)
		(width 0.0889)
		(layer "In11.Cu")
		(net "H_CPU0_MSMI_G_N")
	)
	(arc
		(start 299.583602 -70.563486)
		(mid 299.237146 -70.363395)
		(end 298.89069 -70.563486)
		(width 0.089408)
		(layer "In11.Cu")
		(net "H_CPU0_MSMI_G_N")
	)
	(arc
		(start 306.451762 -69.57314)
		(mid 306.105306 -69.372922)
		(end 305.75885 -69.57314)
		(width 0.089408)
		(layer "In11.Cu")
		(net "H_CPU0_MSMI_G_N")
	)
	(arc
		(start 304.04181 -69.57314)
		(mid 303.834281 -69.784424)
		(end 303.55032 -69.868542)
		(width 0.089408)
		(layer "In11.Cu")
		(net "H_CPU0_MSMI_G_N")
	)
	(arc
		(start 293.24554 -69.677788)
		(mid 293.202179 -69.675675)
		(end 293.158926 -69.671946)
		(width 0.0889)
		(layer "In11.Cu")
		(net "H_CPU0_MSMI_G_N")
	)
	(arc
		(start 296.641266 -69.868542)
		(mid 296.439109 -69.892958)
		(end 296.248582 -69.964808)
		(width 0.089408)
		(layer "In11.Cu")
		(net "H_CPU0_MSMI_G_N")
	)
	(arc
		(start 303.51095 -69.868542)
		(mid 303.321621 -69.926513)
		(end 303.18329 -70.068186)
		(width 0.089408)
		(layer "In11.Cu")
		(net "H_CPU0_MSMI_G_N")
	)
	(arc
		(start 307.03139 -69.901816)
		(mid 306.768536 -69.846045)
		(end 306.545742 -69.695822)
		(width 0.089408)
		(layer "In11.Cu")
		(net "H_CPU0_MSMI_G_N")
	)
	(arc
		(start 293.73957 -69.97319)
		(mid 293.530962 -69.761258)
		(end 293.24554 -69.677788)
		(width 0.0889)
		(layer "In11.Cu")
		(net "H_CPU0_MSMI_G_N")
	)
	(arc
		(start 305.226212 -69.868542)
		(mid 304.942251 -69.784424)
		(end 304.734722 -69.57314)
		(width 0.089408)
		(layer "In11.Cu")
		(net "H_CPU0_MSMI_G_N")
	)
	(arc
		(start 302.32477 -70.563486)
		(mid 301.812706 -70.859245)
		(end 301.300642 -70.563486)
		(width 0.089408)
		(layer "In11.Cu")
		(net "H_CPU0_MSMI_G_N")
	)
	(arc
		(start 292.88105 -69.477636)
		(mid 292.672442 -69.265704)
		(end 292.38702 -69.182234)
		(width 0.0889)
		(layer "In11.Cu")
		(net "H_CPU0_MSMI_G_N")
	)
	(arc
		(start 294.92321 -69.677534)
		(mid 294.639993 -69.761815)
		(end 294.43299 -69.972682)
		(width 0.0889)
		(layer "In11.Cu")
		(net "H_CPU0_MSMI_G_N")
	)
	(arc
		(start 301.300642 -70.563486)
		(mid 300.954186 -70.363395)
		(end 300.60773 -70.563486)
		(width 0.089408)
		(layer "In11.Cu")
		(net "H_CPU0_MSMI_G_N")
	)
	(arc
		(start 297.499532 -70.363588)
		(mid 297.215571 -70.27947)
		(end 297.008042 -70.068186)
		(width 0.089408)
		(layer "In11.Cu")
		(net "H_CPU0_MSMI_G_N")
	)
	(arc
		(start 295.45661 -69.972682)
		(mid 295.249606 -69.761818)
		(end 294.96639 -69.677534)
		(width 0.0889)
		(layer "In11.Cu")
		(net "H_CPU0_MSMI_G_N")
	)
	(arc
		(start 296.248582 -69.964808)
		(mid 296.060284 -70.117839)
		(end 295.823894 -70.17258)
		(width 0.089408)
		(layer "In11.Cu")
		(net "H_CPU0_MSMI_G_N")
	)
	(arc
		(start 293.158926 -69.671946)
		(mid 292.998405 -69.605663)
		(end 292.88105 -69.477636)
		(width 0.0889)
		(layer "In11.Cu")
		(net "H_CPU0_MSMI_G_N")
	)
	(arc
		(start 300.60773 -70.563486)
		(mid 300.095666 -70.859245)
		(end 299.583602 -70.563486)
		(width 0.089408)
		(layer "In11.Cu")
		(net "H_CPU0_MSMI_G_N")
	)
	(arc
		(start 292.354254 -69.182234)
		(mid 292.021336 -68.980243)
		(end 292.017704 -68.590922)
		(width 0.0889)
		(layer "In11.Cu")
		(net "H_CPU0_MSMI_G_N")
	)
	(arc
		(start 303.18329 -70.068186)
		(mid 302.975761 -70.27947)
		(end 302.6918 -70.363588)
		(width 0.089408)
		(layer "In11.Cu")
		(net "H_CPU0_MSMI_G_N")
	)
	(arc
		(start 297.866562 -70.563486)
		(mid 297.725405 -70.420101)
		(end 297.532298 -70.363588)
		(width 0.089408)
		(layer "In11.Cu")
		(net "H_CPU0_MSMI_G_N")
	)
	(arc
		(start 295.792144 -70.172834)
		(mid 295.598294 -70.116484)
		(end 295.45661 -69.972682)
		(width 0.0889)
		(layer "In11.Cu")
		(net "H_CPU0_MSMI_G_N")
	)
	(arc
		(start 302.659034 -70.363588)
		(mid 302.465931 -70.420107)
		(end 302.32477 -70.563486)
		(width 0.089408)
		(layer "In11.Cu")
		(net "H_CPU0_MSMI_G_N")
	)
	(arc
		(start 304.734722 -69.57314)
		(mid 304.388266 -69.372922)
		(end 304.04181 -69.57314)
		(width 0.089408)
		(layer "In11.Cu")
		(net "H_CPU0_MSMI_G_N")
	)
	(arc
		(start 305.75885 -69.57314)
		(mid 305.551321 -69.784424)
		(end 305.26736 -69.868542)
		(width 0.089408)
		(layer "In11.Cu")
		(net "H_CPU0_MSMI_G_N")
	)
	(arc
		(start 297.008042 -70.068186)
		(mid 296.867519 -69.925285)
		(end 296.675302 -69.868542)
		(width 0.089408)
		(layer "In11.Cu")
		(net "H_CPU0_MSMI_G_N")
	)
	(arc
		(start 291.499544 -67.696588)
		(mid 291.331107 -67.654055)
		(end 291.196522 -67.544188)
		(width 0.0889)
		(layer "In11.Cu")
		(net "H_CPU0_MSMI_G_N")
	)
	(arc
		(start 294.43299 -69.972682)
		(mid 294.086373 -70.173086)
		(end 293.73957 -69.97319)
		(width 0.0889)
		(layer "In11.Cu")
		(net "H_CPU0_MSMI_G_N")
	)
	(arc
		(start 292.02888 -68.571618)
		(mid 292.024849 -67.995436)
		(end 291.53231 -67.696588)
		(width 0.0889)
		(layer "In11.Cu")
		(net "H_CPU0_MSMI_G_N")
	)
	(arc
		(start 298.89069 -70.563486)
		(mid 298.378626 -70.859245)
		(end 297.866562 -70.563486)
		(width 0.089408)
		(layer "In11.Cu")
		(net "H_CPU0_MSMI_G_N")
	)
	(arc
		(start 306.545742 -69.695822)
		(mid 306.494724 -69.637566)
		(end 306.451762 -69.57314)
		(width 0.089408)
		(layer "In11.Cu")
		(net "H_CPU0_MSMI_G_N")
	)
	(segment
		(start 437.769 -13.843)
		(end 438.531 -13.843)
		(width 0.10795)
		(layer "F.Cu")
		(net "H_CPU0_MEMDEF_MEMHOT_G_N")
	)
	(segment
		(start 435.813454 -18.415)
		(end 436.880508 -17.347946)
		(width 0.10795)
		(layer "F.Cu")
		(net "H_CPU0_MEMDEF_MEMHOT_G_N")
	)
	(segment
		(start 432.770026 -22.405594)
		(end 433.121562 -22.405594)
		(width 0.10795)
		(layer "F.Cu")
		(net "H_CPU0_MEMDEF_MEMHOT_G_N")
	)
	(segment
		(start 438.531 -13.843)
		(end 439.293 -13.843)
		(width 0.10795)
		(layer "F.Cu")
		(net "H_CPU0_MEMDEF_MEMHOT_G_N")
	)
	(segment
		(start 440.9694 -17.8308)
		(end 441.4774 -17.3228)
		(width 0.10795)
		(layer "F.Cu")
		(net "H_CPU0_MEMDEF_MEMHOT_G_N")
	)
	(segment
		(start 438.09539 -18.011902)
		(end 438.474866 -18.011902)
		(width 0.10795)
		(layer "F.Cu")
		(net "H_CPU0_MEMDEF_MEMHOT_G_N")
	)
	(segment
		(start 441.4774 -17.3228)
		(end 441.4774 -14.5034)
		(width 0.10795)
		(layer "F.Cu")
		(net "H_CPU0_MEMDEF_MEMHOT_G_N")
	)
	(segment
		(start 438.474866 -18.011902)
		(end 438.655968 -17.8308)
		(width 0.10795)
		(layer "F.Cu")
		(net "H_CPU0_MEMDEF_MEMHOT_G_N")
	)
	(segment
		(start 296.948606 -63.829184)
		(end 297.520106 -63.829184)
		(width 0.1016)
		(layer "F.Cu")
		(net "H_CPU0_MEMDEF_MEMHOT_G_N")
	)
	(segment
		(start 430.6062 -23.823422)
		(end 431.080164 -23.349458)
		(width 0.10795)
		(layer "F.Cu")
		(net "H_CPU0_MEMDEF_MEMHOT_G_N")
	)
	(segment
		(start 437.431434 -17.347946)
		(end 438.09539 -18.011902)
		(width 0.10795)
		(layer "F.Cu")
		(net "H_CPU0_MEMDEF_MEMHOT_G_N")
	)
	(segment
		(start 435.277514 -18.415)
		(end 435.813454 -18.415)
		(width 0.10795)
		(layer "F.Cu")
		(net "H_CPU0_MEMDEF_MEMHOT_G_N")
	)
	(segment
		(start 431.080164 -23.349458)
		(end 431.826162 -23.349458)
		(width 0.10795)
		(layer "F.Cu")
		(net "H_CPU0_MEMDEF_MEMHOT_G_N")
	)
	(segment
		(start 435.06263 -19.619976)
		(end 435.06263 -18.629884)
		(width 0.10795)
		(layer "F.Cu")
		(net "H_CPU0_MEMDEF_MEMHOT_G_N")
	)
	(segment
		(start 433.5272 -21.999956)
		(end 433.5272 -21.155406)
		(width 0.10795)
		(layer "F.Cu")
		(net "H_CPU0_MEMDEF_MEMHOT_G_N")
	)
	(segment
		(start 431.826162 -23.349458)
		(end 432.770026 -22.405594)
		(width 0.10795)
		(layer "F.Cu")
		(net "H_CPU0_MEMDEF_MEMHOT_G_N")
	)
	(segment
		(start 438.655968 -17.8308)
		(end 440.9694 -17.8308)
		(width 0.10795)
		(layer "F.Cu")
		(net "H_CPU0_MEMDEF_MEMHOT_G_N")
	)
	(segment
		(start 441.4774 -14.5034)
		(end 440.817 -13.843)
		(width 0.10795)
		(layer "F.Cu")
		(net "H_CPU0_MEMDEF_MEMHOT_G_N")
	)
	(segment
		(start 435.06263 -18.629884)
		(end 435.277514 -18.415)
		(width 0.10795)
		(layer "F.Cu")
		(net "H_CPU0_MEMDEF_MEMHOT_G_N")
	)
	(segment
		(start 440.817 -13.843)
		(end 439.293 -13.843)
		(width 0.10795)
		(layer "F.Cu")
		(net "H_CPU0_MEMDEF_MEMHOT_G_N")
	)
	(segment
		(start 433.5272 -21.155406)
		(end 435.06263 -19.619976)
		(width 0.10795)
		(layer "F.Cu")
		(net "H_CPU0_MEMDEF_MEMHOT_G_N")
	)
	(segment
		(start 433.121562 -22.405594)
		(end 433.5272 -21.999956)
		(width 0.10795)
		(layer "F.Cu")
		(net "H_CPU0_MEMDEF_MEMHOT_G_N")
	)
	(segment
		(start 436.880508 -17.347946)
		(end 437.431434 -17.347946)
		(width 0.10795)
		(layer "F.Cu")
		(net "H_CPU0_MEMDEF_MEMHOT_G_N")
	)
	(segment
		(start 430.6062 -24.056848)
		(end 430.6062 -23.823422)
		(width 0.10795)
		(layer "F.Cu")
		(net "H_CPU0_MEMDEF_MEMHOT_G_N")
	)
	(via
		(at 332.9813 -64.9351)
		(size 0.508)
		(drill 0.254)
		(layers "F.Cu" "B.Cu")
		(net "H_CPU0_MEMDEF_MEMHOT_G_N")
	)
	(via
		(at 297.520106 -63.829184)
		(size 0.508)
		(drill 0.254)
		(layers "F.Cu" "B.Cu")
		(net "H_CPU0_MEMDEF_MEMHOT_G_N")
	)
	(via
		(at 389.90651 -41.7322)
		(size 0.508)
		(drill 0.254)
		(layers "F.Cu" "B.Cu")
		(net "H_CPU0_MEMDEF_MEMHOT_G_N")
	)
	(via
		(at 365.6838 -64.2874)
		(size 0.508)
		(drill 0.254)
		(layers "F.Cu" "B.Cu")
		(net "H_CPU0_MEMDEF_MEMHOT_G_N")
	)
	(via
		(at 332.26502 -64.1604)
		(size 0.6604)
		(drill 0.3302)
		(layers "F.Cu" "B.Cu")
		(net "H_CPU0_MEMDEF_MEMHOT_G_N")
	)
	(via
		(at 385.099052 -78.930246)
		(size 0.508)
		(drill 0.254)
		(layers "F.Cu" "B.Cu")
		(net "H_CPU0_MEMDEF_MEMHOT_G_N")
	)
	(via
		(at 408.282648 -91.66733)
		(size 0.508)
		(drill 0.254)
		(layers "F.Cu" "B.Cu")
		(net "H_CPU0_MEMDEF_MEMHOT_G_N")
	)
	(via
		(at 403.3012 -78.2828)
		(size 0.508)
		(drill 0.254)
		(layers "F.Cu" "B.Cu")
		(net "H_CPU0_MEMDEF_MEMHOT_G_N")
	)
	(via
		(at 391.520934 -27.112468)
		(size 0.508)
		(drill 0.254)
		(layers "F.Cu" "B.Cu")
		(net "H_CPU0_MEMDEF_MEMHOT_G_N")
	)
	(via
		(at 430.6062 -24.056848)
		(size 0.508)
		(drill 0.254)
		(layers "F.Cu" "B.Cu")
		(net "H_CPU0_MEMDEF_MEMHOT_G_N")
	)
	(via
		(at 378.1806 -43.834304)
		(size 0.508)
		(drill 0.254)
		(layers "F.Cu" "B.Cu")
		(net "H_CPU0_MEMDEF_MEMHOT_G_N")
	)
	(segment
		(start 331.5716 -64.464946)
		(end 331.5716 -65.0494)
		(width 0.10795)
		(layer "B.Cu")
		(net "H_CPU0_MEMDEF_MEMHOT_G_N")
	)
	(segment
		(start 409.884118 -91.493594)
		(end 408.456384 -91.493594)
		(width 0.10795)
		(layer "B.Cu")
		(net "H_CPU0_MEMDEF_MEMHOT_G_N")
	)
	(segment
		(start 389.90651 -41.7322)
		(end 389.90651 -43.574208)
		(width 0.10795)
		(layer "B.Cu")
		(net "H_CPU0_MEMDEF_MEMHOT_G_N")
	)
	(segment
		(start 378.334016 -43.834304)
		(end 379.49632 -42.672)
		(width 0.10795)
		(layer "B.Cu")
		(net "H_CPU0_MEMDEF_MEMHOT_G_N")
	)
	(segment
		(start 331.5716 -65.0494)
		(end 331.317092 -65.303908)
		(width 0.10795)
		(layer "B.Cu")
		(net "H_CPU0_MEMDEF_MEMHOT_G_N")
	)
	(segment
		(start 332.9813 -64.3509)
		(end 332.7908 -64.1604)
		(width 0.10795)
		(layer "B.Cu")
		(net "H_CPU0_MEMDEF_MEMHOT_G_N")
	)
	(segment
		(start 387.350762 -42.041826)
		(end 389.508238 -42.041826)
		(width 0.10795)
		(layer "B.Cu")
		(net "H_CPU0_MEMDEF_MEMHOT_G_N")
	)
	(segment
		(start 379.49632 -42.672)
		(end 384.175 -42.672)
		(width 0.10795)
		(layer "B.Cu")
		(net "H_CPU0_MEMDEF_MEMHOT_G_N")
	)
	(segment
		(start 389.508238 -42.041826)
		(end 389.817864 -41.7322)
		(width 0.10795)
		(layer "B.Cu")
		(net "H_CPU0_MEMDEF_MEMHOT_G_N")
	)
	(segment
		(start 331.876146 -64.1604)
		(end 331.5716 -64.464946)
		(width 0.10795)
		(layer "B.Cu")
		(net "H_CPU0_MEMDEF_MEMHOT_G_N")
	)
	(segment
		(start 378.1806 -43.834304)
		(end 378.334016 -43.834304)
		(width 0.10795)
		(layer "B.Cu")
		(net "H_CPU0_MEMDEF_MEMHOT_G_N")
	)
	(segment
		(start 332.7908 -64.1604)
		(end 332.26502 -64.1604)
		(width 0.10795)
		(layer "B.Cu")
		(net "H_CPU0_MEMDEF_MEMHOT_G_N")
	)
	(segment
		(start 408.456384 -91.493594)
		(end 408.282648 -91.66733)
		(width 0.10795)
		(layer "B.Cu")
		(net "H_CPU0_MEMDEF_MEMHOT_G_N")
	)
	(segment
		(start 331.317092 -65.303908)
		(end 330.984606 -65.303908)
		(width 0.10795)
		(layer "B.Cu")
		(net "H_CPU0_MEMDEF_MEMHOT_G_N")
	)
	(segment
		(start 389.817864 -41.7322)
		(end 389.90651 -41.7322)
		(width 0.10795)
		(layer "B.Cu")
		(net "H_CPU0_MEMDEF_MEMHOT_G_N")
	)
	(segment
		(start 385.33705 -41.50995)
		(end 386.818886 -41.50995)
		(width 0.10795)
		(layer "B.Cu")
		(net "H_CPU0_MEMDEF_MEMHOT_G_N")
	)
	(segment
		(start 384.175 -42.672)
		(end 385.33705 -41.50995)
		(width 0.10795)
		(layer "B.Cu")
		(net "H_CPU0_MEMDEF_MEMHOT_G_N")
	)
	(segment
		(start 332.26502 -64.1604)
		(end 331.876146 -64.1604)
		(width 0.10795)
		(layer "B.Cu")
		(net "H_CPU0_MEMDEF_MEMHOT_G_N")
	)
	(segment
		(start 332.9813 -64.9351)
		(end 332.9813 -64.3509)
		(width 0.10795)
		(layer "B.Cu")
		(net "H_CPU0_MEMDEF_MEMHOT_G_N")
	)
	(segment
		(start 386.818886 -41.50995)
		(end 387.350762 -42.041826)
		(width 0.10795)
		(layer "B.Cu")
		(net "H_CPU0_MEMDEF_MEMHOT_G_N")
	)
	(segment
		(start 403.3012 -78.2828)
		(end 404.314152 -79.295752)
		(width 0.089408)
		(layer "In2.Cu")
		(net "H_CPU0_MEMDEF_MEMHOT_G_N")
	)
	(segment
		(start 404.314152 -79.295752)
		(end 404.314152 -80.487012)
		(width 0.089408)
		(layer "In2.Cu")
		(net "H_CPU0_MEMDEF_MEMHOT_G_N")
	)
	(segment
		(start 406.240488 -82.413348)
		(end 406.240488 -89.62517)
		(width 0.089408)
		(layer "In2.Cu")
		(net "H_CPU0_MEMDEF_MEMHOT_G_N")
	)
	(segment
		(start 404.314152 -80.487012)
		(end 406.240488 -82.413348)
		(width 0.089408)
		(layer "In2.Cu")
		(net "H_CPU0_MEMDEF_MEMHOT_G_N")
	)
	(segment
		(start 406.240488 -89.62517)
		(end 408.282648 -91.66733)
		(width 0.089408)
		(layer "In2.Cu")
		(net "H_CPU0_MEMDEF_MEMHOT_G_N")
	)
	(segment
		(start 390.888474 -79.028544)
		(end 391.045446 -79.028544)
		(width 0.089408)
		(layer "In4.Cu")
		(net "H_CPU0_MEMDEF_MEMHOT_G_N")
	)
	(segment
		(start 401.495514 -27.537664)
		(end 401.294854 -27.537664)
		(width 0.089408)
		(layer "In4.Cu")
		(net "H_CPU0_MEMDEF_MEMHOT_G_N")
	)
	(segment
		(start 396.947644 -79.249016)
		(end 397.115792 -79.417164)
		(width 0.089408)
		(layer "In4.Cu")
		(net "H_CPU0_MEMDEF_MEMHOT_G_N")
	)
	(segment
		(start 402.710142 -27.817064)
		(end 402.216366 -27.323288)
		(width 0.089408)
		(layer "In4.Cu")
		(net "H_CPU0_MEMDEF_MEMHOT_G_N")
	)
	(segment
		(start 409.500832 -25.048972)
		(end 408.709114 -25.84069)
		(width 0.089408)
		(layer "In4.Cu")
		(net "H_CPU0_MEMDEF_MEMHOT_G_N")
	)
	(segment
		(start 406.735534 -27.149044)
		(end 404.652226 -27.149044)
		(width 0.089408)
		(layer "In4.Cu")
		(net "H_CPU0_MEMDEF_MEMHOT_G_N")
	)
	(segment
		(start 400.911822 -77.521562)
		(end 401.67306 -78.2828)
		(width 0.089408)
		(layer "In4.Cu")
		(net "H_CPU0_MEMDEF_MEMHOT_G_N")
	)
	(segment
		(start 430.466754 -24.079454)
		(end 429.991774 -24.554434)
		(width 0.089408)
		(layer "In4.Cu")
		(net "H_CPU0_MEMDEF_MEMHOT_G_N")
	)
	(segment
		(start 411.259528 -25.048972)
		(end 409.500832 -25.048972)
		(width 0.089408)
		(layer "In4.Cu")
		(net "H_CPU0_MEMDEF_MEMHOT_G_N")
	)
	(segment
		(start 396.58671 -77.56017)
		(end 396.947644 -77.921104)
		(width 0.089408)
		(layer "In4.Cu")
		(net "H_CPU0_MEMDEF_MEMHOT_G_N")
	)
	(segment
		(start 415.363152 -23.758144)
		(end 414.68294 -24.438356)
		(width 0.089408)
		(layer "In4.Cu")
		(net "H_CPU0_MEMDEF_MEMHOT_G_N")
	)
	(segment
		(start 396.460726 -27.595322)
		(end 392.003788 -27.595322)
		(width 0.089408)
		(layer "In4.Cu")
		(net "H_CPU0_MEMDEF_MEMHOT_G_N")
	)
	(segment
		(start 396.947644 -77.921104)
		(end 396.947644 -79.249016)
		(width 0.089408)
		(layer "In4.Cu")
		(net "H_CPU0_MEMDEF_MEMHOT_G_N")
	)
	(segment
		(start 430.583594 -24.079454)
		(end 430.466754 -24.079454)
		(width 0.089408)
		(layer "In4.Cu")
		(net "H_CPU0_MEMDEF_MEMHOT_G_N")
	)
	(segment
		(start 401.67306 -78.2828)
		(end 403.3012 -78.2828)
		(width 0.089408)
		(layer "In4.Cu")
		(net "H_CPU0_MEMDEF_MEMHOT_G_N")
	)
	(segment
		(start 399.978118 -27.537664)
		(end 399.623534 -27.18308)
		(width 0.089408)
		(layer "In4.Cu")
		(net "H_CPU0_MEMDEF_MEMHOT_G_N")
	)
	(segment
		(start 428.973488 -23.920196)
		(end 426.553122 -23.920196)
		(width 0.089408)
		(layer "In4.Cu")
		(net "H_CPU0_MEMDEF_MEMHOT_G_N")
	)
	(segment
		(start 426.553122 -23.920196)
		(end 426.161708 -24.31161)
		(width 0.089408)
		(layer "In4.Cu")
		(net "H_CPU0_MEMDEF_MEMHOT_G_N")
	)
	(segment
		(start 398.763998 -77.521562)
		(end 400.911822 -77.521562)
		(width 0.089408)
		(layer "In4.Cu")
		(net "H_CPU0_MEMDEF_MEMHOT_G_N")
	)
	(segment
		(start 402.216366 -27.323288)
		(end 401.70989 -27.323288)
		(width 0.089408)
		(layer "In4.Cu")
		(net "H_CPU0_MEMDEF_MEMHOT_G_N")
	)
	(segment
		(start 426.161708 -24.31161)
		(end 422.128188 -24.31161)
		(width 0.089408)
		(layer "In4.Cu")
		(net "H_CPU0_MEMDEF_MEMHOT_G_N")
	)
	(segment
		(start 386.80517 -79.836772)
		(end 390.080246 -79.836772)
		(width 0.089408)
		(layer "In4.Cu")
		(net "H_CPU0_MEMDEF_MEMHOT_G_N")
	)
	(segment
		(start 395.585188 -77.56017)
		(end 396.58671 -77.56017)
		(width 0.089408)
		(layer "In4.Cu")
		(net "H_CPU0_MEMDEF_MEMHOT_G_N")
	)
	(segment
		(start 408.043888 -25.84069)
		(end 406.735534 -27.149044)
		(width 0.089408)
		(layer "In4.Cu")
		(net "H_CPU0_MEMDEF_MEMHOT_G_N")
	)
	(segment
		(start 397.776954 -79.233522)
		(end 397.776954 -78.508606)
		(width 0.089408)
		(layer "In4.Cu")
		(net "H_CPU0_MEMDEF_MEMHOT_G_N")
	)
	(segment
		(start 392.529314 -78.086966)
		(end 392.656822 -77.959458)
		(width 0.089408)
		(layer "In4.Cu")
		(net "H_CPU0_MEMDEF_MEMHOT_G_N")
	)
	(segment
		(start 401.2946 -27.53741)
		(end 400.81962 -27.53741)
		(width 0.089408)
		(layer "In4.Cu")
		(net "H_CPU0_MEMDEF_MEMHOT_G_N")
	)
	(segment
		(start 429.991774 -24.554434)
		(end 429.607726 -24.554434)
		(width 0.089408)
		(layer "In4.Cu")
		(net "H_CPU0_MEMDEF_MEMHOT_G_N")
	)
	(segment
		(start 397.115792 -79.417164)
		(end 397.593312 -79.417164)
		(width 0.089408)
		(layer "In4.Cu")
		(net "H_CPU0_MEMDEF_MEMHOT_G_N")
	)
	(segment
		(start 429.607726 -24.554434)
		(end 428.973488 -23.920196)
		(width 0.089408)
		(layer "In4.Cu")
		(net "H_CPU0_MEMDEF_MEMHOT_G_N")
	)
	(segment
		(start 400.81962 -27.53741)
		(end 400.819366 -27.537664)
		(width 0.089408)
		(layer "In4.Cu")
		(net "H_CPU0_MEMDEF_MEMHOT_G_N")
	)
	(segment
		(start 385.099052 -78.930246)
		(end 385.898644 -78.930246)
		(width 0.089408)
		(layer "In4.Cu")
		(net "H_CPU0_MEMDEF_MEMHOT_G_N")
	)
	(segment
		(start 404.652226 -27.149044)
		(end 403.984206 -27.817064)
		(width 0.089408)
		(layer "In4.Cu")
		(net "H_CPU0_MEMDEF_MEMHOT_G_N")
	)
	(segment
		(start 399.623534 -27.18308)
		(end 396.872968 -27.18308)
		(width 0.089408)
		(layer "In4.Cu")
		(net "H_CPU0_MEMDEF_MEMHOT_G_N")
	)
	(segment
		(start 395.1859 -77.959458)
		(end 395.585188 -77.56017)
		(width 0.089408)
		(layer "In4.Cu")
		(net "H_CPU0_MEMDEF_MEMHOT_G_N")
	)
	(segment
		(start 390.080246 -79.836772)
		(end 390.888474 -79.028544)
		(width 0.089408)
		(layer "In4.Cu")
		(net "H_CPU0_MEMDEF_MEMHOT_G_N")
	)
	(segment
		(start 401.70989 -27.323288)
		(end 401.495514 -27.537664)
		(width 0.089408)
		(layer "In4.Cu")
		(net "H_CPU0_MEMDEF_MEMHOT_G_N")
	)
	(segment
		(start 403.984206 -27.817064)
		(end 402.710142 -27.817064)
		(width 0.089408)
		(layer "In4.Cu")
		(net "H_CPU0_MEMDEF_MEMHOT_G_N")
	)
	(segment
		(start 385.898644 -78.930246)
		(end 386.80517 -79.836772)
		(width 0.089408)
		(layer "In4.Cu")
		(net "H_CPU0_MEMDEF_MEMHOT_G_N")
	)
	(segment
		(start 411.870144 -24.438356)
		(end 411.259528 -25.048972)
		(width 0.089408)
		(layer "In4.Cu")
		(net "H_CPU0_MEMDEF_MEMHOT_G_N")
	)
	(segment
		(start 430.6062 -24.056848)
		(end 430.583594 -24.079454)
		(width 0.089408)
		(layer "In4.Cu")
		(net "H_CPU0_MEMDEF_MEMHOT_G_N")
	)
	(segment
		(start 396.872968 -27.18308)
		(end 396.460726 -27.595322)
		(width 0.089408)
		(layer "In4.Cu")
		(net "H_CPU0_MEMDEF_MEMHOT_G_N")
	)
	(segment
		(start 391.987024 -78.086966)
		(end 392.529314 -78.086966)
		(width 0.089408)
		(layer "In4.Cu")
		(net "H_CPU0_MEMDEF_MEMHOT_G_N")
	)
	(segment
		(start 408.709114 -25.84069)
		(end 408.043888 -25.84069)
		(width 0.089408)
		(layer "In4.Cu")
		(net "H_CPU0_MEMDEF_MEMHOT_G_N")
	)
	(segment
		(start 397.776954 -78.508606)
		(end 398.763998 -77.521562)
		(width 0.089408)
		(layer "In4.Cu")
		(net "H_CPU0_MEMDEF_MEMHOT_G_N")
	)
	(segment
		(start 397.593312 -79.417164)
		(end 397.776954 -79.233522)
		(width 0.089408)
		(layer "In4.Cu")
		(net "H_CPU0_MEMDEF_MEMHOT_G_N")
	)
	(segment
		(start 392.656822 -77.959458)
		(end 395.1859 -77.959458)
		(width 0.089408)
		(layer "In4.Cu")
		(net "H_CPU0_MEMDEF_MEMHOT_G_N")
	)
	(segment
		(start 392.003788 -27.595322)
		(end 391.520934 -27.112468)
		(width 0.089408)
		(layer "In4.Cu")
		(net "H_CPU0_MEMDEF_MEMHOT_G_N")
	)
	(segment
		(start 391.045446 -79.028544)
		(end 391.987024 -78.086966)
		(width 0.089408)
		(layer "In4.Cu")
		(net "H_CPU0_MEMDEF_MEMHOT_G_N")
	)
	(segment
		(start 400.819366 -27.537664)
		(end 399.978118 -27.537664)
		(width 0.089408)
		(layer "In4.Cu")
		(net "H_CPU0_MEMDEF_MEMHOT_G_N")
	)
	(segment
		(start 421.574722 -23.758144)
		(end 415.363152 -23.758144)
		(width 0.089408)
		(layer "In4.Cu")
		(net "H_CPU0_MEMDEF_MEMHOT_G_N")
	)
	(segment
		(start 414.68294 -24.438356)
		(end 411.870144 -24.438356)
		(width 0.089408)
		(layer "In4.Cu")
		(net "H_CPU0_MEMDEF_MEMHOT_G_N")
	)
	(segment
		(start 401.294854 -27.537664)
		(end 401.2946 -27.53741)
		(width 0.089408)
		(layer "In4.Cu")
		(net "H_CPU0_MEMDEF_MEMHOT_G_N")
	)
	(segment
		(start 422.128188 -24.31161)
		(end 421.574722 -23.758144)
		(width 0.089408)
		(layer "In4.Cu")
		(net "H_CPU0_MEMDEF_MEMHOT_G_N")
	)
	(segment
		(start 389.938006 -64.746632)
		(end 388.332472 -66.352166)
		(width 0.089408)
		(layer "In9.Cu")
		(net "H_CPU0_MEMDEF_MEMHOT_G_N")
	)
	(segment
		(start 386.755132 -73.859898)
		(end 386.755132 -75.843638)
		(width 0.089408)
		(layer "In9.Cu")
		(net "H_CPU0_MEMDEF_MEMHOT_G_N")
	)
	(segment
		(start 389.90651 -41.7322)
		(end 389.968232 -41.670478)
		(width 0.089408)
		(layer "In9.Cu")
		(net "H_CPU0_MEMDEF_MEMHOT_G_N")
	)
	(segment
		(start 388.5184 -71.024496)
		(end 387.310122 -72.232774)
		(width 0.089408)
		(layer "In9.Cu")
		(net "H_CPU0_MEMDEF_MEMHOT_G_N")
	)
	(segment
		(start 389.23468 -45.6311)
		(end 389.23468 -51.584606)
		(width 0.089408)
		(layer "In9.Cu")
		(net "H_CPU0_MEMDEF_MEMHOT_G_N")
	)
	(segment
		(start 371.961664 -51.40579)
		(end 369.661694 -53.70576)
		(width 0.089408)
		(layer "In9.Cu")
		(net "H_CPU0_MEMDEF_MEMHOT_G_N")
	)
	(segment
		(start 387.310122 -73.304908)
		(end 386.755132 -73.859898)
		(width 0.089408)
		(layer "In9.Cu")
		(net "H_CPU0_MEMDEF_MEMHOT_G_N")
	)
	(segment
		(start 389.90651 -44.95927)
		(end 389.23468 -45.6311)
		(width 0.089408)
		(layer "In9.Cu")
		(net "H_CPU0_MEMDEF_MEMHOT_G_N")
	)
	(segment
		(start 385.099052 -77.499718)
		(end 385.099052 -78.930246)
		(width 0.089408)
		(layer "In9.Cu")
		(net "H_CPU0_MEMDEF_MEMHOT_G_N")
	)
	(segment
		(start 389.968232 -41.670478)
		(end 389.968232 -41.233598)
		(width 0.089408)
		(layer "In9.Cu")
		(net "H_CPU0_MEMDEF_MEMHOT_G_N")
	)
	(segment
		(start 387.310122 -72.232774)
		(end 387.310122 -73.304908)
		(width 0.089408)
		(layer "In9.Cu")
		(net "H_CPU0_MEMDEF_MEMHOT_G_N")
	)
	(segment
		(start 388.332472 -69.982334)
		(end 388.5184 -70.168262)
		(width 0.089408)
		(layer "In9.Cu")
		(net "H_CPU0_MEMDEF_MEMHOT_G_N")
	)
	(segment
		(start 365.6838 -64.0842)
		(end 365.6838 -64.2874)
		(width 0.089408)
		(layer "In9.Cu")
		(net "H_CPU0_MEMDEF_MEMHOT_G_N")
	)
	(segment
		(start 367.127536 -62.640464)
		(end 365.6838 -64.0842)
		(width 0.089408)
		(layer "In9.Cu")
		(net "H_CPU0_MEMDEF_MEMHOT_G_N")
	)
	(segment
		(start 378.1806 -43.834304)
		(end 377.884944 -43.538648)
		(width 0.089408)
		(layer "In9.Cu")
		(net "H_CPU0_MEMDEF_MEMHOT_G_N")
	)
	(segment
		(start 373.111014 -46.349412)
		(end 373.111014 -46.90618)
		(width 0.089408)
		(layer "In9.Cu")
		(net "H_CPU0_MEMDEF_MEMHOT_G_N")
	)
	(segment
		(start 389.899398 -33.316926)
		(end 388.381494 -31.799022)
		(width 0.089408)
		(layer "In9.Cu")
		(net "H_CPU0_MEMDEF_MEMHOT_G_N")
	)
	(segment
		(start 389.489696 -51.839622)
		(end 389.489696 -52.794662)
		(width 0.089408)
		(layer "In9.Cu")
		(net "H_CPU0_MEMDEF_MEMHOT_G_N")
	)
	(segment
		(start 388.381494 -31.132526)
		(end 388.557008 -30.957012)
		(width 0.089408)
		(layer "In9.Cu")
		(net "H_CPU0_MEMDEF_MEMHOT_G_N")
	)
	(segment
		(start 369.661694 -53.70576)
		(end 369.661694 -62.202314)
		(width 0.089408)
		(layer "In9.Cu")
		(net "H_CPU0_MEMDEF_MEMHOT_G_N")
	)
	(segment
		(start 374.844818 -43.78452)
		(end 374.844818 -44.615608)
		(width 0.089408)
		(layer "In9.Cu")
		(net "H_CPU0_MEMDEF_MEMHOT_G_N")
	)
	(segment
		(start 373.111014 -46.90618)
		(end 371.961664 -48.05553)
		(width 0.089408)
		(layer "In9.Cu")
		(net "H_CPU0_MEMDEF_MEMHOT_G_N")
	)
	(segment
		(start 388.557008 -30.957012)
		(end 388.557008 -30.076394)
		(width 0.089408)
		(layer "In9.Cu")
		(net "H_CPU0_MEMDEF_MEMHOT_G_N")
	)
	(segment
		(start 371.961664 -48.05553)
		(end 371.961664 -51.40579)
		(width 0.089408)
		(layer "In9.Cu")
		(net "H_CPU0_MEMDEF_MEMHOT_G_N")
	)
	(segment
		(start 375.09069 -43.538648)
		(end 374.844818 -43.78452)
		(width 0.089408)
		(layer "In9.Cu")
		(net "H_CPU0_MEMDEF_MEMHOT_G_N")
	)
	(segment
		(start 390.540748 -40.661082)
		(end 390.540748 -38.422072)
		(width 0.089408)
		(layer "In9.Cu")
		(net "H_CPU0_MEMDEF_MEMHOT_G_N")
	)
	(segment
		(start 388.332472 -66.352166)
		(end 388.332472 -69.982334)
		(width 0.089408)
		(layer "In9.Cu")
		(net "H_CPU0_MEMDEF_MEMHOT_G_N")
	)
	(segment
		(start 388.557008 -30.076394)
		(end 391.520934 -27.112468)
		(width 0.089408)
		(layer "In9.Cu")
		(net "H_CPU0_MEMDEF_MEMHOT_G_N")
	)
	(segment
		(start 369.223544 -62.640464)
		(end 367.127536 -62.640464)
		(width 0.089408)
		(layer "In9.Cu")
		(net "H_CPU0_MEMDEF_MEMHOT_G_N")
	)
	(segment
		(start 389.938006 -59.56046)
		(end 389.938006 -64.746632)
		(width 0.089408)
		(layer "In9.Cu")
		(net "H_CPU0_MEMDEF_MEMHOT_G_N")
	)
	(segment
		(start 389.899398 -37.780722)
		(end 389.899398 -33.316926)
		(width 0.089408)
		(layer "In9.Cu")
		(net "H_CPU0_MEMDEF_MEMHOT_G_N")
	)
	(segment
		(start 369.661694 -62.202314)
		(end 369.223544 -62.640464)
		(width 0.089408)
		(layer "In9.Cu")
		(net "H_CPU0_MEMDEF_MEMHOT_G_N")
	)
	(segment
		(start 390.669018 -53.973984)
		(end 390.669018 -58.829448)
		(width 0.089408)
		(layer "In9.Cu")
		(net "H_CPU0_MEMDEF_MEMHOT_G_N")
	)
	(segment
		(start 389.90651 -41.7322)
		(end 389.90651 -44.95927)
		(width 0.089408)
		(layer "In9.Cu")
		(net "H_CPU0_MEMDEF_MEMHOT_G_N")
	)
	(segment
		(start 390.669018 -58.829448)
		(end 389.938006 -59.56046)
		(width 0.089408)
		(layer "In9.Cu")
		(net "H_CPU0_MEMDEF_MEMHOT_G_N")
	)
	(segment
		(start 388.381494 -31.799022)
		(end 388.381494 -31.132526)
		(width 0.089408)
		(layer "In9.Cu")
		(net "H_CPU0_MEMDEF_MEMHOT_G_N")
	)
	(segment
		(start 390.540748 -38.422072)
		(end 389.899398 -37.780722)
		(width 0.089408)
		(layer "In9.Cu")
		(net "H_CPU0_MEMDEF_MEMHOT_G_N")
	)
	(segment
		(start 389.23468 -51.584606)
		(end 389.489696 -51.839622)
		(width 0.089408)
		(layer "In9.Cu")
		(net "H_CPU0_MEMDEF_MEMHOT_G_N")
	)
	(segment
		(start 374.844818 -44.615608)
		(end 373.111014 -46.349412)
		(width 0.089408)
		(layer "In9.Cu")
		(net "H_CPU0_MEMDEF_MEMHOT_G_N")
	)
	(segment
		(start 388.5184 -70.168262)
		(end 388.5184 -71.024496)
		(width 0.089408)
		(layer "In9.Cu")
		(net "H_CPU0_MEMDEF_MEMHOT_G_N")
	)
	(segment
		(start 389.489696 -52.794662)
		(end 390.669018 -53.973984)
		(width 0.089408)
		(layer "In9.Cu")
		(net "H_CPU0_MEMDEF_MEMHOT_G_N")
	)
	(segment
		(start 377.884944 -43.538648)
		(end 375.09069 -43.538648)
		(width 0.089408)
		(layer "In9.Cu")
		(net "H_CPU0_MEMDEF_MEMHOT_G_N")
	)
	(segment
		(start 389.968232 -41.233598)
		(end 390.540748 -40.661082)
		(width 0.089408)
		(layer "In9.Cu")
		(net "H_CPU0_MEMDEF_MEMHOT_G_N")
	)
	(segment
		(start 386.755132 -75.843638)
		(end 385.099052 -77.499718)
		(width 0.089408)
		(layer "In9.Cu")
		(net "H_CPU0_MEMDEF_MEMHOT_G_N")
	)
	(segment
		(start 354.439474 -63.151512)
		(end 354.893626 -62.69736)
		(width 0.089408)
		(layer "In11.Cu")
		(net "H_CPU0_MEMDEF_MEMHOT_G_N")
	)
	(segment
		(start 299.244258 -62.438788)
		(end 299.230034 -62.438788)
		(width 0.089408)
		(layer "In11.Cu")
		(net "H_CPU0_MEMDEF_MEMHOT_G_N")
	)
	(segment
		(start 332.9813 -64.9351)
		(end 332.21676 -64.17056)
		(width 0.089408)
		(layer "In11.Cu")
		(net "H_CPU0_MEMDEF_MEMHOT_G_N")
	)
	(segment
		(start 364.5408 -64.9732)
		(end 365.2266 -64.2874)
		(width 0.089408)
		(layer "In11.Cu")
		(net "H_CPU0_MEMDEF_MEMHOT_G_N")
	)
	(segment
		(start 334.764888 -63.151512)
		(end 354.439474 -63.151512)
		(width 0.089408)
		(layer "In11.Cu")
		(net "H_CPU0_MEMDEF_MEMHOT_G_N")
	)
	(segment
		(start 325.675498 -64.17056)
		(end 324.677786 -63.172848)
		(width 0.089408)
		(layer "In11.Cu")
		(net "H_CPU0_MEMDEF_MEMHOT_G_N")
	)
	(segment
		(start 324.677786 -63.172848)
		(end 323.092826 -63.172848)
		(width 0.089408)
		(layer "In11.Cu")
		(net "H_CPU0_MEMDEF_MEMHOT_G_N")
	)
	(segment
		(start 356.803452 -63.342774)
		(end 362.351828 -63.342774)
		(width 0.089408)
		(layer "In11.Cu")
		(net "H_CPU0_MEMDEF_MEMHOT_G_N")
	)
	(segment
		(start 332.9813 -64.9351)
		(end 334.764888 -63.151512)
		(width 0.089408)
		(layer "In11.Cu")
		(net "H_CPU0_MEMDEF_MEMHOT_G_N")
	)
	(segment
		(start 313.172856 -64.897)
		(end 311.210198 -62.934342)
		(width 0.089408)
		(layer "In11.Cu")
		(net "H_CPU0_MEMDEF_MEMHOT_G_N")
	)
	(segment
		(start 300.11624 -62.934342)
		(end 300.075092 -62.934342)
		(width 0.089408)
		(layer "In11.Cu")
		(net "H_CPU0_MEMDEF_MEMHOT_G_N")
	)
	(segment
		(start 365.2266 -64.2874)
		(end 365.6838 -64.2874)
		(width 0.089408)
		(layer "In11.Cu")
		(net "H_CPU0_MEMDEF_MEMHOT_G_N")
	)
	(segment
		(start 311.210198 -62.934342)
		(end 305.226212 -62.934342)
		(width 0.089408)
		(layer "In11.Cu")
		(net "H_CPU0_MEMDEF_MEMHOT_G_N")
	)
	(segment
		(start 356.158038 -62.69736)
		(end 356.803452 -63.342774)
		(width 0.089408)
		(layer "In11.Cu")
		(net "H_CPU0_MEMDEF_MEMHOT_G_N")
	)
	(segment
		(start 321.368674 -64.897)
		(end 313.172856 -64.897)
		(width 0.089408)
		(layer "In11.Cu")
		(net "H_CPU0_MEMDEF_MEMHOT_G_N")
	)
	(segment
		(start 362.351828 -63.342774)
		(end 363.982254 -64.9732)
		(width 0.089408)
		(layer "In11.Cu")
		(net "H_CPU0_MEMDEF_MEMHOT_G_N")
	)
	(segment
		(start 354.893626 -62.69736)
		(end 356.158038 -62.69736)
		(width 0.089408)
		(layer "In11.Cu")
		(net "H_CPU0_MEMDEF_MEMHOT_G_N")
	)
	(segment
		(start 298.3992 -62.934342)
		(end 298.366434 -62.934342)
		(width 0.089408)
		(layer "In11.Cu")
		(net "H_CPU0_MEMDEF_MEMHOT_G_N")
	)
	(segment
		(start 323.092826 -63.172848)
		(end 321.368674 -64.897)
		(width 0.089408)
		(layer "In11.Cu")
		(net "H_CPU0_MEMDEF_MEMHOT_G_N")
	)
	(segment
		(start 332.21676 -64.17056)
		(end 325.675498 -64.17056)
		(width 0.089408)
		(layer "In11.Cu")
		(net "H_CPU0_MEMDEF_MEMHOT_G_N")
	)
	(segment
		(start 303.740312 -62.934342)
		(end 301.792132 -62.934342)
		(width 0.089408)
		(layer "In11.Cu")
		(net "H_CPU0_MEMDEF_MEMHOT_G_N")
	)
	(segment
		(start 304.04181 -62.63894)
		(end 303.937416 -62.820296)
		(width 0.089408)
		(layer "In11.Cu")
		(net "H_CPU0_MEMDEF_MEMHOT_G_N")
	)
	(segment
		(start 300.961298 -62.438788)
		(end 300.947074 -62.438788)
		(width 0.089408)
		(layer "In11.Cu")
		(net "H_CPU0_MEMDEF_MEMHOT_G_N")
	)
	(segment
		(start 363.982254 -64.9732)
		(end 364.5408 -64.9732)
		(width 0.089408)
		(layer "In11.Cu")
		(net "H_CPU0_MEMDEF_MEMHOT_G_N")
	)
	(segment
		(start 304.395378 -62.438788)
		(end 304.381154 -62.438788)
		(width 0.089408)
		(layer "In11.Cu")
		(net "H_CPU0_MEMDEF_MEMHOT_G_N")
	)
	(arc
		(start 299.230034 -62.438788)
		(mid 299.034002 -62.494172)
		(end 298.89069 -62.63894)
		(width 0.089408)
		(layer "In11.Cu")
		(net "H_CPU0_MEMDEF_MEMHOT_G_N")
	)
	(arc
		(start 304.381154 -62.438788)
		(mid 304.185122 -62.494172)
		(end 304.04181 -62.63894)
		(width 0.089408)
		(layer "In11.Cu")
		(net "H_CPU0_MEMDEF_MEMHOT_G_N")
	)
	(arc
		(start 305.226212 -62.934342)
		(mid 304.942251 -62.850224)
		(end 304.734722 -62.63894)
		(width 0.089408)
		(layer "In11.Cu")
		(net "H_CPU0_MEMDEF_MEMHOT_G_N")
	)
	(arc
		(start 301.792132 -62.934342)
		(mid 301.508171 -62.850224)
		(end 301.300642 -62.63894)
		(width 0.089408)
		(layer "In11.Cu")
		(net "H_CPU0_MEMDEF_MEMHOT_G_N")
	)
	(arc
		(start 300.075092 -62.934342)
		(mid 299.791131 -62.850224)
		(end 299.583602 -62.63894)
		(width 0.089408)
		(layer "In11.Cu")
		(net "H_CPU0_MEMDEF_MEMHOT_G_N")
	)
	(arc
		(start 300.60773 -62.63894)
		(mid 300.400201 -62.850224)
		(end 300.11624 -62.934342)
		(width 0.089408)
		(layer "In11.Cu")
		(net "H_CPU0_MEMDEF_MEMHOT_G_N")
	)
	(arc
		(start 300.947074 -62.438788)
		(mid 300.751042 -62.494172)
		(end 300.60773 -62.63894)
		(width 0.089408)
		(layer "In11.Cu")
		(net "H_CPU0_MEMDEF_MEMHOT_G_N")
	)
	(arc
		(start 298.03217 -63.13424)
		(mid 297.795562 -63.496024)
		(end 297.520106 -63.829184)
		(width 0.089408)
		(layer "In11.Cu")
		(net "H_CPU0_MEMDEF_MEMHOT_G_N")
	)
	(arc
		(start 303.937416 -62.820296)
		(mid 303.854174 -62.903782)
		(end 303.740312 -62.934342)
		(width 0.089408)
		(layer "In11.Cu")
		(net "H_CPU0_MEMDEF_MEMHOT_G_N")
	)
	(arc
		(start 299.583602 -62.63894)
		(mid 299.440291 -62.494169)
		(end 299.244258 -62.438788)
		(width 0.089408)
		(layer "In11.Cu")
		(net "H_CPU0_MEMDEF_MEMHOT_G_N")
	)
	(arc
		(start 304.734722 -62.63894)
		(mid 304.591411 -62.494169)
		(end 304.395378 -62.438788)
		(width 0.089408)
		(layer "In11.Cu")
		(net "H_CPU0_MEMDEF_MEMHOT_G_N")
	)
	(arc
		(start 298.89069 -62.63894)
		(mid 298.683161 -62.850224)
		(end 298.3992 -62.934342)
		(width 0.089408)
		(layer "In11.Cu")
		(net "H_CPU0_MEMDEF_MEMHOT_G_N")
	)
	(arc
		(start 301.300642 -62.63894)
		(mid 301.157331 -62.494169)
		(end 300.961298 -62.438788)
		(width 0.089408)
		(layer "In11.Cu")
		(net "H_CPU0_MEMDEF_MEMHOT_G_N")
	)
	(arc
		(start 298.366434 -62.934342)
		(mid 298.173331 -62.990861)
		(end 298.03217 -63.13424)
		(width 0.089408)
		(layer "In11.Cu")
		(net "H_CPU0_MEMDEF_MEMHOT_G_N")
	)
	(via
		(at 413.1564 -90.650822)
		(size 0.508)
		(drill 0.254)
		(layers "F.Cu" "B.Cu")
		(net "H_CPU0_MEMDEF_MEMHOT")
	)
	(segment
		(start 410.970476 -90.764106)
		(end 410.970476 -90.260424)
		(width 0.10795)
		(layer "B.Cu")
		(net "H_CPU0_MEMDEF_MEMHOT")
	)
	(segment
		(start 411.037786 -90.193114)
		(end 411.662118 -90.193114)
		(width 0.10795)
		(layer "B.Cu")
		(net "H_CPU0_MEMDEF_MEMHOT")
	)
	(segment
		(start 413.1564 -90.650822)
		(end 413.1564 -91.1098)
		(width 0.10795)
		(layer "B.Cu")
		(net "H_CPU0_MEMDEF_MEMHOT")
	)
	(segment
		(start 411.049724 -90.843354)
		(end 410.970476 -90.764106)
		(width 0.10795)
		(layer "B.Cu")
		(net "H_CPU0_MEMDEF_MEMHOT")
	)
	(segment
		(start 413.1564 -91.1098)
		(end 413.059118 -91.207082)
		(width 0.10795)
		(layer "B.Cu")
		(net "H_CPU0_MEMDEF_MEMHOT")
	)
	(segment
		(start 413.059118 -91.207082)
		(end 413.059118 -91.539314)
		(width 0.10795)
		(layer "B.Cu")
		(net "H_CPU0_MEMDEF_MEMHOT")
	)
	(segment
		(start 411.662118 -90.843354)
		(end 411.049724 -90.843354)
		(width 0.10795)
		(layer "B.Cu")
		(net "H_CPU0_MEMDEF_MEMHOT")
	)
	(segment
		(start 410.970476 -90.260424)
		(end 411.037786 -90.193114)
		(width 0.10795)
		(layer "B.Cu")
		(net "H_CPU0_MEMDEF_MEMHOT")
	)
	(segment
		(start 411.662118 -90.193114)
		(end 412.976314 -90.193114)
		(width 0.10795)
		(layer "B.Cu")
		(net "H_CPU0_MEMDEF_MEMHOT")
	)
	(segment
		(start 412.976314 -90.193114)
		(end 413.1564 -90.3732)
		(width 0.10795)
		(layer "B.Cu")
		(net "H_CPU0_MEMDEF_MEMHOT")
	)
	(segment
		(start 413.1564 -90.3732)
		(end 413.1564 -90.650822)
		(width 0.10795)
		(layer "B.Cu")
		(net "H_CPU0_MEMDEF_MEMHOT")
	)
	(segment
		(start 396.108174 -22.27707)
		(end 395.76883 -23.982172)
		(width 0.10795)
		(layer "F.Cu")
		(net "H_CPU0_MEMABC_MEMHOT_G_N")
	)
	(segment
		(start 406.146 -15.621)
		(end 405.74595 -16.02105)
		(width 0.10795)
		(layer "F.Cu")
		(net "H_CPU0_MEMABC_MEMHOT_G_N")
	)
	(segment
		(start 443.253876 -13.361924)
		(end 443.253876 -14.123924)
		(width 0.10795)
		(layer "F.Cu")
		(net "H_CPU0_MEMABC_MEMHOT_G_N")
	)
	(segment
		(start 396.789148 -21.25853)
		(end 396.108174 -22.27707)
		(width 0.10795)
		(layer "F.Cu")
		(net "H_CPU0_MEMABC_MEMHOT_G_N")
	)
	(segment
		(start 404.6728 -16.02105)
		(end 403.950424 -16.02105)
		(width 0.10795)
		(layer "F.Cu")
		(net "H_CPU0_MEMABC_MEMHOT_G_N")
	)
	(segment
		(start 401.767294 -17.586706)
		(end 399.874486 -19.479514)
		(width 0.10795)
		(layer "F.Cu")
		(net "H_CPU0_MEMABC_MEMHOT_G_N")
	)
	(segment
		(start 405.74595 -16.02105)
		(end 404.6728 -16.02105)
		(width 0.10795)
		(layer "F.Cu")
		(net "H_CPU0_MEMABC_MEMHOT_G_N")
	)
	(segment
		(start 296.948606 -64.819784)
		(end 297.520106 -64.819784)
		(width 0.1016)
		(layer "F.Cu")
		(net "H_CPU0_MEMABC_MEMHOT_G_N")
	)
	(segment
		(start 443.253876 -12.599924)
		(end 443.253876 -13.361924)
		(width 0.10795)
		(layer "F.Cu")
		(net "H_CPU0_MEMABC_MEMHOT_G_N")
	)
	(segment
		(start 402.384768 -17.586706)
		(end 401.767294 -17.586706)
		(width 0.10795)
		(layer "F.Cu")
		(net "H_CPU0_MEMABC_MEMHOT_G_N")
	)
	(segment
		(start 403.950424 -16.02105)
		(end 402.384768 -17.586706)
		(width 0.10795)
		(layer "F.Cu")
		(net "H_CPU0_MEMABC_MEMHOT_G_N")
	)
	(segment
		(start 443.253876 -11.964924)
		(end 443.253876 -12.599924)
		(width 0.10795)
		(layer "F.Cu")
		(net "H_CPU0_MEMABC_MEMHOT_G_N")
	)
	(segment
		(start 395.650466 -24.0792)
		(end 395.2748 -24.0792)
		(width 0.10795)
		(layer "F.Cu")
		(net "H_CPU0_MEMABC_MEMHOT_G_N")
	)
	(segment
		(start 399.874486 -19.479514)
		(end 396.789148 -21.25853)
		(width 0.10795)
		(layer "F.Cu")
		(net "H_CPU0_MEMABC_MEMHOT_G_N")
	)
	(segment
		(start 395.76883 -23.982172)
		(end 395.650466 -24.0792)
		(width 0.10795)
		(layer "F.Cu")
		(net "H_CPU0_MEMABC_MEMHOT_G_N")
	)
	(via
		(at 395.2748 -24.0792)
		(size 0.508)
		(drill 0.254)
		(layers "F.Cu" "B.Cu")
		(net "H_CPU0_MEMABC_MEMHOT_G_N")
	)
	(via
		(at 404.6728 -16.02105)
		(size 0.762)
		(drill 0.381)
		(layers "F.Cu" "B.Cu")
		(net "H_CPU0_MEMABC_MEMHOT_G_N")
	)
	(via
		(at 443.253876 -11.964924)
		(size 0.508)
		(drill 0.254)
		(layers "F.Cu" "B.Cu")
		(net "H_CPU0_MEMABC_MEMHOT_G_N")
	)
	(via
		(at 365.2012 -65.6082)
		(size 0.508)
		(drill 0.254)
		(layers "F.Cu" "B.Cu")
		(net "H_CPU0_MEMABC_MEMHOT_G_N")
	)
	(via
		(at 401.782788 -92.90558)
		(size 0.508)
		(drill 0.254)
		(layers "F.Cu" "B.Cu")
		(net "H_CPU0_MEMABC_MEMHOT_G_N")
	)
	(via
		(at 406.146 -15.621)
		(size 0.508)
		(drill 0.254)
		(layers "F.Cu" "B.Cu")
		(net "H_CPU0_MEMABC_MEMHOT_G_N")
	)
	(via
		(at 379.119638 -43.849544)
		(size 0.508)
		(drill 0.254)
		(layers "F.Cu" "B.Cu")
		(net "H_CPU0_MEMABC_MEMHOT_G_N")
	)
	(via
		(at 277.3934 -67.183)
		(size 0.508)
		(drill 0.254)
		(layers "F.Cu" "B.Cu")
		(net "H_CPU0_MEMABC_MEMHOT_G_N")
	)
	(via
		(at 297.520106 -64.819784)
		(size 0.508)
		(drill 0.254)
		(layers "F.Cu" "B.Cu")
		(net "H_CPU0_MEMABC_MEMHOT_G_N")
	)
	(via
		(at 383.8194 -47.31385)
		(size 0.508)
		(drill 0.254)
		(layers "F.Cu" "B.Cu")
		(net "H_CPU0_MEMABC_MEMHOT_G_N")
	)
	(via
		(at 395.141704 -31.313882)
		(size 0.508)
		(drill 0.254)
		(layers "F.Cu" "B.Cu")
		(net "H_CPU0_MEMABC_MEMHOT_G_N")
	)
	(segment
		(start 276.479 -68.503546)
		(end 276.479 -68.58)
		(width 0.10795)
		(layer "B.Cu")
		(net "H_CPU0_MEMABC_MEMHOT_G_N")
	)
	(segment
		(start 408.408886 -92.451682)
		(end 407.886154 -92.451682)
		(width 0.10795)
		(layer "B.Cu")
		(net "H_CPU0_MEMABC_MEMHOT_G_N")
	)
	(segment
		(start 384.4798 -44.64558)
		(end 383.544572 -45.580808)
		(width 0.10795)
		(layer "B.Cu")
		(net "H_CPU0_MEMABC_MEMHOT_G_N")
	)
	(segment
		(start 386.876544 -44.2214)
		(end 386.876544 -43.742102)
		(width 0.10795)
		(layer "B.Cu")
		(net "H_CPU0_MEMABC_MEMHOT_G_N")
	)
	(segment
		(start 409.401518 -94.160594)
		(end 408.839162 -93.598238)
		(width 0.10795)
		(layer "B.Cu")
		(net "H_CPU0_MEMABC_MEMHOT_G_N")
	)
	(segment
		(start 404.925784 -91.871038)
		(end 404.557484 -91.502738)
		(width 0.10795)
		(layer "B.Cu")
		(net "H_CPU0_MEMABC_MEMHOT_G_N")
	)
	(segment
		(start 386.466842 -43.3324)
		(end 384.9751 -43.3324)
		(width 0.10795)
		(layer "B.Cu")
		(net "H_CPU0_MEMABC_MEMHOT_G_N")
	)
	(segment
		(start 383.544572 -45.580808)
		(end 383.544572 -47.039022)
		(width 0.10795)
		(layer "B.Cu")
		(net "H_CPU0_MEMABC_MEMHOT_G_N")
	)
	(segment
		(start 386.876544 -43.742102)
		(end 386.466842 -43.3324)
		(width 0.10795)
		(layer "B.Cu")
		(net "H_CPU0_MEMABC_MEMHOT_G_N")
	)
	(segment
		(start 408.839162 -92.881958)
		(end 408.408886 -92.451682)
		(width 0.10795)
		(layer "B.Cu")
		(net "H_CPU0_MEMABC_MEMHOT_G_N")
	)
	(segment
		(start 409.884118 -94.160594)
		(end 409.401518 -94.160594)
		(width 0.10795)
		(layer "B.Cu")
		(net "H_CPU0_MEMABC_MEMHOT_G_N")
	)
	(segment
		(start 388.12851 -44.874688)
		(end 387.529832 -44.874688)
		(width 0.10795)
		(layer "B.Cu")
		(net "H_CPU0_MEMABC_MEMHOT_G_N")
	)
	(segment
		(start 384.4798 -43.8277)
		(end 384.4798 -44.64558)
		(width 0.10795)
		(layer "B.Cu")
		(net "H_CPU0_MEMABC_MEMHOT_G_N")
	)
	(segment
		(start 407.886154 -92.451682)
		(end 407.30551 -91.871038)
		(width 0.10795)
		(layer "B.Cu")
		(net "H_CPU0_MEMABC_MEMHOT_G_N")
	)
	(segment
		(start 404.557484 -91.502738)
		(end 402.557742 -91.502738)
		(width 0.10795)
		(layer "B.Cu")
		(net "H_CPU0_MEMABC_MEMHOT_G_N")
	)
	(segment
		(start 384.9751 -43.3324)
		(end 384.4798 -43.8277)
		(width 0.10795)
		(layer "B.Cu")
		(net "H_CPU0_MEMABC_MEMHOT_G_N")
	)
	(segment
		(start 387.529832 -44.874688)
		(end 386.876544 -44.2214)
		(width 0.10795)
		(layer "B.Cu")
		(net "H_CPU0_MEMABC_MEMHOT_G_N")
	)
	(segment
		(start 408.839162 -93.598238)
		(end 408.839162 -92.881958)
		(width 0.10795)
		(layer "B.Cu")
		(net "H_CPU0_MEMABC_MEMHOT_G_N")
	)
	(segment
		(start 407.30551 -91.871038)
		(end 404.925784 -91.871038)
		(width 0.10795)
		(layer "B.Cu")
		(net "H_CPU0_MEMABC_MEMHOT_G_N")
	)
	(segment
		(start 276.756368 -68.226178)
		(end 276.479 -68.503546)
		(width 0.10795)
		(layer "B.Cu")
		(net "H_CPU0_MEMABC_MEMHOT_G_N")
	)
	(segment
		(start 277.014178 -67.562222)
		(end 277.014178 -67.98691)
		(width 0.10795)
		(layer "B.Cu")
		(net "H_CPU0_MEMABC_MEMHOT_G_N")
	)
	(segment
		(start 277.014178 -67.98691)
		(end 276.77491 -68.226178)
		(width 0.10795)
		(layer "B.Cu")
		(net "H_CPU0_MEMABC_MEMHOT_G_N")
	)
	(segment
		(start 277.3934 -67.183)
		(end 277.014178 -67.562222)
		(width 0.10795)
		(layer "B.Cu")
		(net "H_CPU0_MEMABC_MEMHOT_G_N")
	)
	(segment
		(start 276.77491 -68.226178)
		(end 276.756368 -68.226178)
		(width 0.10795)
		(layer "B.Cu")
		(net "H_CPU0_MEMABC_MEMHOT_G_N")
	)
	(segment
		(start 383.544572 -47.039022)
		(end 383.8194 -47.31385)
		(width 0.10795)
		(layer "B.Cu")
		(net "H_CPU0_MEMABC_MEMHOT_G_N")
	)
	(segment
		(start 401.782788 -92.277692)
		(end 401.782788 -92.90558)
		(width 0.10795)
		(layer "B.Cu")
		(net "H_CPU0_MEMABC_MEMHOT_G_N")
	)
	(segment
		(start 402.557742 -91.502738)
		(end 401.782788 -92.277692)
		(width 0.10795)
		(layer "B.Cu")
		(net "H_CPU0_MEMABC_MEMHOT_G_N")
	)
	(segment
		(start 281.1018 -69.469)
		(end 282.6258 -69.469)
		(width 0.089408)
		(layer "In2.Cu")
		(net "H_CPU0_MEMABC_MEMHOT_G_N")
	)
	(segment
		(start 288.036 -67.7418)
		(end 288.150808 -67.7418)
		(width 0.089408)
		(layer "In2.Cu")
		(net "H_CPU0_MEMABC_MEMHOT_G_N")
	)
	(segment
		(start 289.54603 -66.346578)
		(end 290.882578 -66.346578)
		(width 0.089408)
		(layer "In2.Cu")
		(net "H_CPU0_MEMABC_MEMHOT_G_N")
	)
	(segment
		(start 395.141704 -31.603442)
		(end 395.141704 -31.313882)
		(width 0.089408)
		(layer "In2.Cu")
		(net "H_CPU0_MEMABC_MEMHOT_G_N")
	)
	(segment
		(start 277.3934 -67.183)
		(end 277.4442 -67.1322)
		(width 0.089408)
		(layer "In2.Cu")
		(net "H_CPU0_MEMABC_MEMHOT_G_N")
	)
	(segment
		(start 279.7302 -68.0974)
		(end 281.1018 -69.469)
		(width 0.089408)
		(layer "In2.Cu")
		(net "H_CPU0_MEMABC_MEMHOT_G_N")
	)
	(segment
		(start 294.714422 -65.121282)
		(end 294.802052 -65.033906)
		(width 0.0889)
		(layer "In2.Cu")
		(net "H_CPU0_MEMABC_MEMHOT_G_N")
	)
	(segment
		(start 292.35146 -66.210434)
		(end 292.384226 -66.210434)
		(width 0.0889)
		(layer "In2.Cu")
		(net "H_CPU0_MEMABC_MEMHOT_G_N")
	)
	(segment
		(start 293.9542 -65.5066)
		(end 294.074088 -65.386712)
		(width 0.0889)
		(layer "In2.Cu")
		(net "H_CPU0_MEMABC_MEMHOT_G_N")
	)
	(segment
		(start 286.68726 -68.2498)
		(end 287.528 -68.2498)
		(width 0.089408)
		(layer "In2.Cu")
		(net "H_CPU0_MEMABC_MEMHOT_G_N")
	)
	(segment
		(start 295.78554 -64.229234)
		(end 295.8211 -64.229234)
		(width 0.0889)
		(layer "In2.Cu")
		(net "H_CPU0_MEMABC_MEMHOT_G_N")
	)
	(segment
		(start 285.74746 -69.1896)
		(end 286.68726 -68.2498)
		(width 0.089408)
		(layer "In2.Cu")
		(net "H_CPU0_MEMABC_MEMHOT_G_N")
	)
	(segment
		(start 388.368286 -37.746178)
		(end 388.368286 -36.986972)
		(width 0.089408)
		(layer "In2.Cu")
		(net "H_CPU0_MEMABC_MEMHOT_G_N")
	)
	(segment
		(start 287.528 -68.2498)
		(end 288.036 -67.7418)
		(width 0.089408)
		(layer "In2.Cu")
		(net "H_CPU0_MEMABC_MEMHOT_G_N")
	)
	(segment
		(start 383.8194 -47.31385)
		(end 385.78663 -45.34662)
		(width 0.089408)
		(layer "In2.Cu")
		(net "H_CPU0_MEMABC_MEMHOT_G_N")
	)
	(segment
		(start 394.233146 -32.512)
		(end 395.141704 -31.603442)
		(width 0.089408)
		(layer "In2.Cu")
		(net "H_CPU0_MEMABC_MEMHOT_G_N")
	)
	(segment
		(start 277.4442 -67.1322)
		(end 278.5364 -67.1322)
		(width 0.089408)
		(layer "In2.Cu")
		(net "H_CPU0_MEMABC_MEMHOT_G_N")
	)
	(segment
		(start 294.802052 -65.033906)
		(end 295.22801 -64.607948)
		(width 0.0889)
		(layer "In2.Cu")
		(net "H_CPU0_MEMABC_MEMHOT_G_N")
	)
	(segment
		(start 390.162034 -35.193224)
		(end 390.162034 -34.373312)
		(width 0.089408)
		(layer "In2.Cu")
		(net "H_CPU0_MEMABC_MEMHOT_G_N")
	)
	(segment
		(start 297.137836 -64.964564)
		(end 297.227244 -64.988694)
		(width 0.0889)
		(layer "In2.Cu")
		(net "H_CPU0_MEMABC_MEMHOT_G_N")
	)
	(segment
		(start 385.78663 -40.327834)
		(end 388.368286 -37.746178)
		(width 0.089408)
		(layer "In2.Cu")
		(net "H_CPU0_MEMABC_MEMHOT_G_N")
	)
	(segment
		(start 388.368286 -36.986972)
		(end 390.162034 -35.193224)
		(width 0.089408)
		(layer "In2.Cu")
		(net "H_CPU0_MEMABC_MEMHOT_G_N")
	)
	(segment
		(start 390.162034 -34.373312)
		(end 391.515346 -33.02)
		(width 0.089408)
		(layer "In2.Cu")
		(net "H_CPU0_MEMABC_MEMHOT_G_N")
	)
	(segment
		(start 392.176 -33.02)
		(end 392.684 -32.512)
		(width 0.089408)
		(layer "In2.Cu")
		(net "H_CPU0_MEMABC_MEMHOT_G_N")
	)
	(segment
		(start 282.9052 -69.1896)
		(end 285.74746 -69.1896)
		(width 0.089408)
		(layer "In2.Cu")
		(net "H_CPU0_MEMABC_MEMHOT_G_N")
	)
	(segment
		(start 279.5016 -68.0974)
		(end 279.7302 -68.0974)
		(width 0.089408)
		(layer "In2.Cu")
		(net "H_CPU0_MEMABC_MEMHOT_G_N")
	)
	(segment
		(start 392.684 -32.512)
		(end 394.233146 -32.512)
		(width 0.089408)
		(layer "In2.Cu")
		(net "H_CPU0_MEMABC_MEMHOT_G_N")
	)
	(segment
		(start 288.150808 -67.7418)
		(end 289.54603 -66.346578)
		(width 0.089408)
		(layer "In2.Cu")
		(net "H_CPU0_MEMABC_MEMHOT_G_N")
	)
	(segment
		(start 297.227244 -64.988694)
		(end 297.520106 -64.819784)
		(width 0.0889)
		(layer "In2.Cu")
		(net "H_CPU0_MEMABC_MEMHOT_G_N")
	)
	(segment
		(start 296.650664 -64.724788)
		(end 296.686732 -64.724788)
		(width 0.0889)
		(layer "In2.Cu")
		(net "H_CPU0_MEMABC_MEMHOT_G_N")
	)
	(segment
		(start 282.6258 -69.469)
		(end 282.9052 -69.1896)
		(width 0.089408)
		(layer "In2.Cu")
		(net "H_CPU0_MEMABC_MEMHOT_G_N")
	)
	(segment
		(start 293.20617 -65.715388)
		(end 293.450264 -65.715388)
		(width 0.0889)
		(layer "In2.Cu")
		(net "H_CPU0_MEMABC_MEMHOT_G_N")
	)
	(segment
		(start 385.78663 -45.34662)
		(end 385.78663 -40.327834)
		(width 0.089408)
		(layer "In2.Cu")
		(net "H_CPU0_MEMABC_MEMHOT_G_N")
	)
	(segment
		(start 278.5364 -67.1322)
		(end 279.5016 -68.0974)
		(width 0.089408)
		(layer "In2.Cu")
		(net "H_CPU0_MEMABC_MEMHOT_G_N")
	)
	(segment
		(start 391.515346 -33.02)
		(end 392.176 -33.02)
		(width 0.089408)
		(layer "In2.Cu")
		(net "H_CPU0_MEMABC_MEMHOT_G_N")
	)
	(arc
		(start 295.8211 -64.229234)
		(mid 296.106524 -64.312701)
		(end 296.31513 -64.524636)
		(width 0.0889)
		(layer "In2.Cu")
		(net "H_CPU0_MEMABC_MEMHOT_G_N")
	)
	(arc
		(start 292.71595 -66.010536)
		(mid 292.922954 -65.799672)
		(end 293.20617 -65.715388)
		(width 0.0889)
		(layer "In2.Cu")
		(net "H_CPU0_MEMABC_MEMHOT_G_N")
	)
	(arc
		(start 290.882578 -66.346578)
		(mid 291.033762 -66.395749)
		(end 291.14496 -66.509392)
		(width 0.0889)
		(layer "In2.Cu")
		(net "H_CPU0_MEMABC_MEMHOT_G_N")
	)
	(arc
		(start 294.074088 -65.386712)
		(mid 294.292943 -65.240478)
		(end 294.5511 -65.1891)
		(width 0.0889)
		(layer "In2.Cu")
		(net "H_CPU0_MEMABC_MEMHOT_G_N")
	)
	(arc
		(start 293.450264 -65.715388)
		(mid 293.723012 -65.661135)
		(end 293.9542 -65.5066)
		(width 0.0889)
		(layer "In2.Cu")
		(net "H_CPU0_MEMABC_MEMHOT_G_N")
	)
	(arc
		(start 295.22801 -64.607948)
		(mid 295.262488 -64.568372)
		(end 295.29151 -64.524636)
		(width 0.0889)
		(layer "In2.Cu")
		(net "H_CPU0_MEMABC_MEMHOT_G_N")
	)
	(arc
		(start 296.31513 -64.524636)
		(mid 296.456813 -64.66844)
		(end 296.650664 -64.724788)
		(width 0.0889)
		(layer "In2.Cu")
		(net "H_CPU0_MEMABC_MEMHOT_G_N")
	)
	(arc
		(start 294.5511 -65.1891)
		(mid 294.6395 -65.171423)
		(end 294.714422 -65.121282)
		(width 0.0889)
		(layer "In2.Cu")
		(net "H_CPU0_MEMABC_MEMHOT_G_N")
	)
	(arc
		(start 291.85743 -66.505836)
		(mid 292.066038 -66.293904)
		(end 292.35146 -66.210434)
		(width 0.0889)
		(layer "In2.Cu")
		(net "H_CPU0_MEMABC_MEMHOT_G_N")
	)
	(arc
		(start 296.686732 -64.724788)
		(mid 296.939522 -64.793428)
		(end 297.137836 -64.964564)
		(width 0.0889)
		(layer "In2.Cu")
		(net "H_CPU0_MEMABC_MEMHOT_G_N")
	)
	(arc
		(start 291.14496 -66.509392)
		(mid 291.502163 -66.712149)
		(end 291.85743 -66.505836)
		(width 0.0889)
		(layer "In2.Cu")
		(net "H_CPU0_MEMABC_MEMHOT_G_N")
	)
	(arc
		(start 292.384226 -66.210434)
		(mid 292.575868 -66.153268)
		(end 292.71595 -66.010536)
		(width 0.0889)
		(layer "In2.Cu")
		(net "H_CPU0_MEMABC_MEMHOT_G_N")
	)
	(arc
		(start 295.29151 -64.524636)
		(mid 295.500118 -64.312704)
		(end 295.78554 -64.229234)
		(width 0.0889)
		(layer "In2.Cu")
		(net "H_CPU0_MEMABC_MEMHOT_G_N")
	)
	(segment
		(start 439.703718 -12.626848)
		(end 437.439054 -14.891512)
		(width 0.089408)
		(layer "In4.Cu")
		(net "H_CPU0_MEMABC_MEMHOT_G_N")
	)
	(segment
		(start 437.439054 -14.891512)
		(end 423.577766 -14.891512)
		(width 0.089408)
		(layer "In4.Cu")
		(net "H_CPU0_MEMABC_MEMHOT_G_N")
	)
	(segment
		(start 442.591952 -12.626848)
		(end 440.018424 -12.626848)
		(width 0.089408)
		(layer "In4.Cu")
		(net "H_CPU0_MEMABC_MEMHOT_G_N")
	)
	(segment
		(start 440.01817 -12.626594)
		(end 439.775854 -12.626594)
		(width 0.089408)
		(layer "In4.Cu")
		(net "H_CPU0_MEMABC_MEMHOT_G_N")
	)
	(segment
		(start 409.472892 -12.294108)
		(end 406.146 -15.621)
		(width 0.089408)
		(layer "In4.Cu")
		(net "H_CPU0_MEMABC_MEMHOT_G_N")
	)
	(segment
		(start 439.775854 -12.626594)
		(end 439.7756 -12.626848)
		(width 0.089408)
		(layer "In4.Cu")
		(net "H_CPU0_MEMABC_MEMHOT_G_N")
	)
	(segment
		(start 439.7756 -12.626848)
		(end 439.703718 -12.626848)
		(width 0.089408)
		(layer "In4.Cu")
		(net "H_CPU0_MEMABC_MEMHOT_G_N")
	)
	(segment
		(start 423.577766 -14.891512)
		(end 420.980362 -12.294108)
		(width 0.089408)
		(layer "In4.Cu")
		(net "H_CPU0_MEMABC_MEMHOT_G_N")
	)
	(segment
		(start 440.018424 -12.626848)
		(end 440.01817 -12.626594)
		(width 0.089408)
		(layer "In4.Cu")
		(net "H_CPU0_MEMABC_MEMHOT_G_N")
	)
	(segment
		(start 443.253876 -11.964924)
		(end 442.591952 -12.626848)
		(width 0.089408)
		(layer "In4.Cu")
		(net "H_CPU0_MEMABC_MEMHOT_G_N")
	)
	(segment
		(start 420.980362 -12.294108)
		(end 409.472892 -12.294108)
		(width 0.089408)
		(layer "In4.Cu")
		(net "H_CPU0_MEMABC_MEMHOT_G_N")
	)
	(segment
		(start 370.817902 -61.899038)
		(end 369.687602 -63.029338)
		(width 0.089408)
		(layer "In9.Cu")
		(net "H_CPU0_MEMABC_MEMHOT_G_N")
	)
	(segment
		(start 373.5197 -47.085504)
		(end 372.343934 -48.26127)
		(width 0.089408)
		(layer "In9.Cu")
		(net "H_CPU0_MEMABC_MEMHOT_G_N")
	)
	(segment
		(start 379.119638 -43.849544)
		(end 378.696982 -44.2722)
		(width 0.089408)
		(layer "In9.Cu")
		(net "H_CPU0_MEMABC_MEMHOT_G_N")
	)
	(segment
		(start 374.93448 -45.066458)
		(end 373.5197 -46.481238)
		(width 0.089408)
		(layer "In9.Cu")
		(net "H_CPU0_MEMABC_MEMHOT_G_N")
	)
	(segment
		(start 373.5197 -46.481238)
		(end 373.5197 -47.085504)
		(width 0.089408)
		(layer "In9.Cu")
		(net "H_CPU0_MEMABC_MEMHOT_G_N")
	)
	(segment
		(start 396.217648 -25.809702)
		(end 396.217648 -24.836882)
		(width 0.089408)
		(layer "In9.Cu")
		(net "H_CPU0_MEMABC_MEMHOT_G_N")
	)
	(segment
		(start 367.355374 -63.029084)
		(end 366.275112 -64.109346)
		(width 0.089408)
		(layer "In9.Cu")
		(net "H_CPU0_MEMABC_MEMHOT_G_N")
	)
	(segment
		(start 366.275112 -64.109346)
		(end 366.275112 -64.661542)
		(width 0.089408)
		(layer "In9.Cu")
		(net "H_CPU0_MEMABC_MEMHOT_G_N")
	)
	(segment
		(start 372.343934 -56.44769)
		(end 370.817902 -57.973722)
		(width 0.089408)
		(layer "In9.Cu")
		(net "H_CPU0_MEMABC_MEMHOT_G_N")
	)
	(segment
		(start 377.072398 -45.066458)
		(end 374.93448 -45.066458)
		(width 0.089408)
		(layer "In9.Cu")
		(net "H_CPU0_MEMABC_MEMHOT_G_N")
	)
	(segment
		(start 372.343934 -48.26127)
		(end 372.343934 -56.44769)
		(width 0.089408)
		(layer "In9.Cu")
		(net "H_CPU0_MEMABC_MEMHOT_G_N")
	)
	(segment
		(start 366.275112 -64.661542)
		(end 365.328454 -65.6082)
		(width 0.089408)
		(layer "In9.Cu")
		(net "H_CPU0_MEMABC_MEMHOT_G_N")
	)
	(segment
		(start 377.866656 -44.2722)
		(end 377.072398 -45.066458)
		(width 0.089408)
		(layer "In9.Cu")
		(net "H_CPU0_MEMABC_MEMHOT_G_N")
	)
	(segment
		(start 365.328454 -65.6082)
		(end 365.2012 -65.6082)
		(width 0.089408)
		(layer "In9.Cu")
		(net "H_CPU0_MEMABC_MEMHOT_G_N")
	)
	(segment
		(start 369.687602 -63.029338)
		(end 368.098832 -63.029338)
		(width 0.089408)
		(layer "In9.Cu")
		(net "H_CPU0_MEMABC_MEMHOT_G_N")
	)
	(segment
		(start 368.098578 -63.029084)
		(end 367.355374 -63.029084)
		(width 0.089408)
		(layer "In9.Cu")
		(net "H_CPU0_MEMABC_MEMHOT_G_N")
	)
	(segment
		(start 396.217648 -24.836882)
		(end 395.459966 -24.0792)
		(width 0.089408)
		(layer "In9.Cu")
		(net "H_CPU0_MEMABC_MEMHOT_G_N")
	)
	(segment
		(start 370.817902 -57.973722)
		(end 370.817902 -61.899038)
		(width 0.089408)
		(layer "In9.Cu")
		(net "H_CPU0_MEMABC_MEMHOT_G_N")
	)
	(segment
		(start 395.141704 -26.885646)
		(end 396.217648 -25.809702)
		(width 0.089408)
		(layer "In9.Cu")
		(net "H_CPU0_MEMABC_MEMHOT_G_N")
	)
	(segment
		(start 368.098832 -63.029338)
		(end 368.098578 -63.029084)
		(width 0.089408)
		(layer "In9.Cu")
		(net "H_CPU0_MEMABC_MEMHOT_G_N")
	)
	(segment
		(start 378.696982 -44.2722)
		(end 377.866656 -44.2722)
		(width 0.089408)
		(layer "In9.Cu")
		(net "H_CPU0_MEMABC_MEMHOT_G_N")
	)
	(segment
		(start 395.459966 -24.0792)
		(end 395.2748 -24.0792)
		(width 0.089408)
		(layer "In9.Cu")
		(net "H_CPU0_MEMABC_MEMHOT_G_N")
	)
	(segment
		(start 395.141704 -31.313882)
		(end 395.141704 -26.885646)
		(width 0.089408)
		(layer "In9.Cu")
		(net "H_CPU0_MEMABC_MEMHOT_G_N")
	)
	(segment
		(start 384.236722 -46.896528)
		(end 385.775454 -46.896528)
		(width 0.089408)
		(layer "In11.Cu")
		(net "H_CPU0_MEMABC_MEMHOT_G_N")
	)
	(segment
		(start 308.807104 -65.906142)
		(end 310.37022 -67.469258)
		(width 0.089408)
		(layer "In11.Cu")
		(net "H_CPU0_MEMABC_MEMHOT_G_N")
	)
	(segment
		(start 305.234594 -65.906142)
		(end 305.26736 -65.906142)
		(width 0.089408)
		(layer "In11.Cu")
		(net "H_CPU0_MEMABC_MEMHOT_G_N")
	)
	(segment
		(start 380.453138 -43.707812)
		(end 379.26137 -43.707812)
		(width 0.089408)
		(layer "In11.Cu")
		(net "H_CPU0_MEMABC_MEMHOT_G_N")
	)
	(segment
		(start 310.37022 -67.469258)
		(end 312.110374 -67.469258)
		(width 0.089408)
		(layer "In11.Cu")
		(net "H_CPU0_MEMABC_MEMHOT_G_N")
	)
	(segment
		(start 397.59636 -72.135238)
		(end 397.59636 -73.07072)
		(width 0.089408)
		(layer "In11.Cu")
		(net "H_CPU0_MEMABC_MEMHOT_G_N")
	)
	(segment
		(start 398.06118 -73.53554)
		(end 398.06118 -75.192382)
		(width 0.089408)
		(layer "In11.Cu")
		(net "H_CPU0_MEMABC_MEMHOT_G_N")
	)
	(segment
		(start 379.26137 -43.707812)
		(end 379.119638 -43.849544)
		(width 0.089408)
		(layer "In11.Cu")
		(net "H_CPU0_MEMABC_MEMHOT_G_N")
	)
	(segment
		(start 300.947074 -66.401188)
		(end 300.978316 -66.401188)
		(width 0.089408)
		(layer "In11.Cu")
		(net "H_CPU0_MEMABC_MEMHOT_G_N")
	)
	(segment
		(start 387.155436 -49.28108)
		(end 388.269226 -50.39487)
		(width 0.089408)
		(layer "In11.Cu")
		(net "H_CPU0_MEMABC_MEMHOT_G_N")
	)
	(segment
		(start 312.110374 -67.469258)
		(end 312.478166 -67.101466)
		(width 0.089408)
		(layer "In11.Cu")
		(net "H_CPU0_MEMABC_MEMHOT_G_N")
	)
	(segment
		(start 399.153126 -77.261466)
		(end 399.553176 -77.661516)
		(width 0.089408)
		(layer "In11.Cu")
		(net "H_CPU0_MEMABC_MEMHOT_G_N")
	)
	(segment
		(start 383.8194 -47.31385)
		(end 384.236722 -46.896528)
		(width 0.089408)
		(layer "In11.Cu")
		(net "H_CPU0_MEMABC_MEMHOT_G_N")
	)
	(segment
		(start 387.155436 -48.27651)
		(end 387.155436 -49.28108)
		(width 0.089408)
		(layer "In11.Cu")
		(net "H_CPU0_MEMABC_MEMHOT_G_N")
	)
	(segment
		(start 394.438886 -58.27776)
		(end 394.438886 -64.220344)
		(width 0.089408)
		(layer "In11.Cu")
		(net "H_CPU0_MEMABC_MEMHOT_G_N")
	)
	(segment
		(start 363.7026 -67.1068)
		(end 365.2012 -65.6082)
		(width 0.089408)
		(layer "In11.Cu")
		(net "H_CPU0_MEMABC_MEMHOT_G_N")
	)
	(segment
		(start 360.220768 -64.234822)
		(end 363.092746 -67.1068)
		(width 0.089408)
		(layer "In11.Cu")
		(net "H_CPU0_MEMABC_MEMHOT_G_N")
	)
	(segment
		(start 388.269226 -52.1081)
		(end 394.438886 -58.27776)
		(width 0.089408)
		(layer "In11.Cu")
		(net "H_CPU0_MEMABC_MEMHOT_G_N")
	)
	(segment
		(start 399.589244 -79.961486)
		(end 399.27911 -80.27162)
		(width 0.089408)
		(layer "In11.Cu")
		(net "H_CPU0_MEMABC_MEMHOT_G_N")
	)
	(segment
		(start 383.8194 -47.074074)
		(end 380.453138 -43.707812)
		(width 0.089408)
		(layer "In11.Cu")
		(net "H_CPU0_MEMABC_MEMHOT_G_N")
	)
	(segment
		(start 306.943252 -65.906142)
		(end 308.807104 -65.906142)
		(width 0.089408)
		(layer "In11.Cu")
		(net "H_CPU0_MEMABC_MEMHOT_G_N")
	)
	(segment
		(start 355.841046 -63.461392)
		(end 356.614476 -64.234822)
		(width 0.089408)
		(layer "In11.Cu")
		(net "H_CPU0_MEMABC_MEMHOT_G_N")
	)
	(segment
		(start 399.27911 -83.17484)
		(end 399.806922 -83.702652)
		(width 0.089408)
		(layer "In11.Cu")
		(net "H_CPU0_MEMABC_MEMHOT_G_N")
	)
	(segment
		(start 363.092746 -67.1068)
		(end 363.7026 -67.1068)
		(width 0.089408)
		(layer "In11.Cu")
		(net "H_CPU0_MEMABC_MEMHOT_G_N")
	)
	(segment
		(start 395.941042 -70.47992)
		(end 397.59636 -72.135238)
		(width 0.089408)
		(layer "In11.Cu")
		(net "H_CPU0_MEMABC_MEMHOT_G_N")
	)
	(segment
		(start 399.553176 -78.88859)
		(end 399.589244 -78.924658)
		(width 0.089408)
		(layer "In11.Cu")
		(net "H_CPU0_MEMABC_MEMHOT_G_N")
	)
	(segment
		(start 399.27911 -80.27162)
		(end 399.27911 -83.17484)
		(width 0.089408)
		(layer "In11.Cu")
		(net "H_CPU0_MEMABC_MEMHOT_G_N")
	)
	(segment
		(start 385.775454 -46.896528)
		(end 387.155436 -48.27651)
		(width 0.089408)
		(layer "In11.Cu")
		(net "H_CPU0_MEMABC_MEMHOT_G_N")
	)
	(segment
		(start 400.49831 -89.00033)
		(end 400.82851 -89.33053)
		(width 0.089408)
		(layer "In11.Cu")
		(net "H_CPU0_MEMABC_MEMHOT_G_N")
	)
	(segment
		(start 388.269226 -50.39487)
		(end 388.269226 -52.1081)
		(width 0.089408)
		(layer "In11.Cu")
		(net "H_CPU0_MEMABC_MEMHOT_G_N")
	)
	(segment
		(start 399.553176 -77.661516)
		(end 399.553176 -78.88859)
		(width 0.089408)
		(layer "In11.Cu")
		(net "H_CPU0_MEMABC_MEMHOT_G_N")
	)
	(segment
		(start 400.49831 -85.295994)
		(end 400.49831 -89.00033)
		(width 0.089408)
		(layer "In11.Cu")
		(net "H_CPU0_MEMABC_MEMHOT_G_N")
	)
	(segment
		(start 354.756466 -63.915544)
		(end 355.210618 -63.461392)
		(width 0.089408)
		(layer "In11.Cu")
		(net "H_CPU0_MEMABC_MEMHOT_G_N")
	)
	(segment
		(start 398.06118 -75.192382)
		(end 399.153126 -76.284328)
		(width 0.089408)
		(layer "In11.Cu")
		(net "H_CPU0_MEMABC_MEMHOT_G_N")
	)
	(segment
		(start 399.589244 -78.924658)
		(end 399.589244 -79.961486)
		(width 0.089408)
		(layer "In11.Cu")
		(net "H_CPU0_MEMABC_MEMHOT_G_N")
	)
	(segment
		(start 297.520106 -64.819784)
		(end 297.957494 -65.576958)
		(width 0.089408)
		(layer "In11.Cu")
		(net "H_CPU0_MEMABC_MEMHOT_G_N")
	)
	(segment
		(start 399.153126 -76.284328)
		(end 399.153126 -77.261466)
		(width 0.089408)
		(layer "In11.Cu")
		(net "H_CPU0_MEMABC_MEMHOT_G_N")
	)
	(segment
		(start 335.543144 -63.915544)
		(end 354.756466 -63.915544)
		(width 0.089408)
		(layer "In11.Cu")
		(net "H_CPU0_MEMABC_MEMHOT_G_N")
	)
	(segment
		(start 399.806922 -84.604606)
		(end 400.49831 -85.295994)
		(width 0.089408)
		(layer "In11.Cu")
		(net "H_CPU0_MEMABC_MEMHOT_G_N")
	)
	(segment
		(start 312.478166 -67.101466)
		(end 332.357222 -67.101466)
		(width 0.089408)
		(layer "In11.Cu")
		(net "H_CPU0_MEMABC_MEMHOT_G_N")
	)
	(segment
		(start 397.59636 -73.07072)
		(end 398.06118 -73.53554)
		(width 0.089408)
		(layer "In11.Cu")
		(net "H_CPU0_MEMABC_MEMHOT_G_N")
	)
	(segment
		(start 394.438886 -64.220344)
		(end 395.941042 -65.7225)
		(width 0.089408)
		(layer "In11.Cu")
		(net "H_CPU0_MEMABC_MEMHOT_G_N")
	)
	(segment
		(start 395.941042 -65.7225)
		(end 395.941042 -70.47992)
		(width 0.089408)
		(layer "In11.Cu")
		(net "H_CPU0_MEMABC_MEMHOT_G_N")
	)
	(segment
		(start 355.210618 -63.461392)
		(end 355.841046 -63.461392)
		(width 0.089408)
		(layer "In11.Cu")
		(net "H_CPU0_MEMABC_MEMHOT_G_N")
	)
	(segment
		(start 298.378118 -66.801238)
		(end 298.395136 -66.801238)
		(width 0.089408)
		(layer "In11.Cu")
		(net "H_CPU0_MEMABC_MEMHOT_G_N")
	)
	(segment
		(start 399.806922 -83.702652)
		(end 399.806922 -84.604606)
		(width 0.089408)
		(layer "In11.Cu")
		(net "H_CPU0_MEMABC_MEMHOT_G_N")
	)
	(segment
		(start 332.357222 -67.101466)
		(end 335.543144 -63.915544)
		(width 0.089408)
		(layer "In11.Cu")
		(net "H_CPU0_MEMABC_MEMHOT_G_N")
	)
	(segment
		(start 356.614476 -64.234822)
		(end 360.220768 -64.234822)
		(width 0.089408)
		(layer "In11.Cu")
		(net "H_CPU0_MEMABC_MEMHOT_G_N")
	)
	(segment
		(start 400.82851 -89.33053)
		(end 400.82851 -91.951302)
		(width 0.089408)
		(layer "In11.Cu")
		(net "H_CPU0_MEMABC_MEMHOT_G_N")
	)
	(segment
		(start 400.82851 -91.951302)
		(end 401.782788 -92.90558)
		(width 0.089408)
		(layer "In11.Cu")
		(net "H_CPU0_MEMABC_MEMHOT_G_N")
	)
	(segment
		(start 383.8194 -47.31385)
		(end 383.8194 -47.074074)
		(width 0.089408)
		(layer "In11.Cu")
		(net "H_CPU0_MEMABC_MEMHOT_G_N")
	)
	(arc
		(start 300.978316 -66.401188)
		(mid 301.260218 -66.316325)
		(end 301.46625 -66.10604)
		(width 0.089408)
		(layer "In11.Cu")
		(net "H_CPU0_MEMABC_MEMHOT_G_N")
	)
	(arc
		(start 302.159162 -66.10604)
		(mid 302.671226 -66.401672)
		(end 303.18329 -66.10604)
		(width 0.089408)
		(layer "In11.Cu")
		(net "H_CPU0_MEMABC_MEMHOT_G_N")
	)
	(arc
		(start 298.704 -66.679826)
		(mid 298.884768 -66.537056)
		(end 299.089064 -66.430652)
		(width 0.089408)
		(layer "In11.Cu")
		(net "H_CPU0_MEMABC_MEMHOT_G_N")
	)
	(arc
		(start 297.949366 -66.553588)
		(mid 298.13056 -66.73485)
		(end 298.378118 -66.801238)
		(width 0.089408)
		(layer "In11.Cu")
		(net "H_CPU0_MEMABC_MEMHOT_G_N")
	)
	(arc
		(start 297.949366 -66.058288)
		(mid 297.883051 -66.305938)
		(end 297.949366 -66.553588)
		(width 0.089408)
		(layer "In11.Cu")
		(net "H_CPU0_MEMABC_MEMHOT_G_N")
	)
	(arc
		(start 303.18329 -66.10604)
		(mid 303.529746 -65.905949)
		(end 303.876202 -66.10604)
		(width 0.089408)
		(layer "In11.Cu")
		(net "H_CPU0_MEMABC_MEMHOT_G_N")
	)
	(arc
		(start 304.90033 -66.10604)
		(mid 305.041487 -65.962655)
		(end 305.234594 -65.906142)
		(width 0.089408)
		(layer "In11.Cu")
		(net "H_CPU0_MEMABC_MEMHOT_G_N")
	)
	(arc
		(start 299.387768 -66.430652)
		(mid 299.499906 -66.499671)
		(end 299.583602 -66.60134)
		(width 0.089408)
		(layer "In11.Cu")
		(net "H_CPU0_MEMABC_MEMHOT_G_N")
	)
	(arc
		(start 298.395136 -66.801238)
		(mid 298.560015 -66.767124)
		(end 298.704 -66.679826)
		(width 0.089408)
		(layer "In11.Cu")
		(net "H_CPU0_MEMABC_MEMHOT_G_N")
	)
	(arc
		(start 297.957494 -65.576958)
		(mid 298.015815 -65.818686)
		(end 297.949366 -66.058288)
		(width 0.089408)
		(layer "In11.Cu")
		(net "H_CPU0_MEMABC_MEMHOT_G_N")
	)
	(arc
		(start 303.876202 -66.10604)
		(mid 304.388266 -66.401672)
		(end 304.90033 -66.10604)
		(width 0.089408)
		(layer "In11.Cu")
		(net "H_CPU0_MEMABC_MEMHOT_G_N")
	)
	(arc
		(start 305.75885 -65.61074)
		(mid 306.105306 -65.410522)
		(end 306.451762 -65.61074)
		(width 0.089408)
		(layer "In11.Cu")
		(net "H_CPU0_MEMABC_MEMHOT_G_N")
	)
	(arc
		(start 300.60773 -66.60134)
		(mid 300.751041 -66.456569)
		(end 300.947074 -66.401188)
		(width 0.089408)
		(layer "In11.Cu")
		(net "H_CPU0_MEMABC_MEMHOT_G_N")
	)
	(arc
		(start 299.089064 -66.430652)
		(mid 299.238416 -66.401447)
		(end 299.387768 -66.430652)
		(width 0.089408)
		(layer "In11.Cu")
		(net "H_CPU0_MEMABC_MEMHOT_G_N")
	)
	(arc
		(start 306.451762 -65.61074)
		(mid 306.659291 -65.822024)
		(end 306.943252 -65.906142)
		(width 0.089408)
		(layer "In11.Cu")
		(net "H_CPU0_MEMABC_MEMHOT_G_N")
	)
	(arc
		(start 301.46625 -66.10604)
		(mid 301.812706 -65.905949)
		(end 302.159162 -66.10604)
		(width 0.089408)
		(layer "In11.Cu")
		(net "H_CPU0_MEMABC_MEMHOT_G_N")
	)
	(arc
		(start 305.26736 -65.906142)
		(mid 305.551321 -65.822024)
		(end 305.75885 -65.61074)
		(width 0.089408)
		(layer "In11.Cu")
		(net "H_CPU0_MEMABC_MEMHOT_G_N")
	)
	(arc
		(start 299.583602 -66.60134)
		(mid 300.095666 -66.897099)
		(end 300.60773 -66.60134)
		(width 0.089408)
		(layer "In11.Cu")
		(net "H_CPU0_MEMABC_MEMHOT_G_N")
	)
	(via
		(at 412.7246 -95.8596)
		(size 0.6604)
		(drill 0.3302)
		(layers "F.Cu" "B.Cu")
		(net "H_CPU0_MEMABC_MEMHOT")
	)
	(segment
		(start 411.034992 -93.510354)
		(end 411.662118 -93.510354)
		(width 0.10795)
		(layer "B.Cu")
		(net "H_CPU0_MEMABC_MEMHOT")
	)
	(segment
		(start 412.7246 -95.8596)
		(end 412.7246 -95.5802)
		(width 0.10795)
		(layer "B.Cu")
		(net "H_CPU0_MEMABC_MEMHOT")
	)
	(segment
		(start 411.662118 -92.860114)
		(end 411.046422 -92.860114)
		(width 0.10795)
		(layer "B.Cu")
		(net "H_CPU0_MEMABC_MEMHOT")
	)
	(segment
		(start 413.0294 -95.2754)
		(end 413.0294 -94.9198)
		(width 0.10795)
		(layer "B.Cu")
		(net "H_CPU0_MEMABC_MEMHOT")
	)
	(segment
		(start 412.7246 -95.5802)
		(end 413.0294 -95.2754)
		(width 0.10795)
		(layer "B.Cu")
		(net "H_CPU0_MEMABC_MEMHOT")
	)
	(segment
		(start 411.046422 -92.860114)
		(end 410.969206 -92.93733)
		(width 0.10795)
		(layer "B.Cu")
		(net "H_CPU0_MEMABC_MEMHOT")
	)
	(segment
		(start 412.6738 -94.9198)
		(end 412.4706 -94.7166)
		(width 0.10795)
		(layer "B.Cu")
		(net "H_CPU0_MEMABC_MEMHOT")
	)
	(segment
		(start 413.0294 -94.9198)
		(end 412.6738 -94.9198)
		(width 0.10795)
		(layer "B.Cu")
		(net "H_CPU0_MEMABC_MEMHOT")
	)
	(segment
		(start 410.969206 -92.93733)
		(end 410.969206 -93.444568)
		(width 0.10795)
		(layer "B.Cu")
		(net "H_CPU0_MEMABC_MEMHOT")
	)
	(segment
		(start 412.4706 -93.6752)
		(end 412.305754 -93.510354)
		(width 0.10795)
		(layer "B.Cu")
		(net "H_CPU0_MEMABC_MEMHOT")
	)
	(segment
		(start 410.969206 -93.444568)
		(end 411.034992 -93.510354)
		(width 0.10795)
		(layer "B.Cu")
		(net "H_CPU0_MEMABC_MEMHOT")
	)
	(segment
		(start 412.4706 -94.7166)
		(end 412.4706 -93.6752)
		(width 0.10795)
		(layer "B.Cu")
		(net "H_CPU0_MEMABC_MEMHOT")
	)
	(segment
		(start 412.305754 -93.510354)
		(end 411.662118 -93.510354)
		(width 0.10795)
		(layer "B.Cu")
		(net "H_CPU0_MEMABC_MEMHOT")
	)
	(segment
		(start 382.50749 -77.895196)
		(end 382.894586 -77.5081)
		(width 0.10795)
		(layer "F.Cu")
		(net "H_CPU0_FIVR_FAULT_G")
	)
	(segment
		(start 296.66184 -69.277738)
		(end 296.09034 -69.277738)
		(width 0.1016)
		(layer "F.Cu")
		(net "H_CPU0_FIVR_FAULT_G")
	)
	(segment
		(start 384.5941 -77.5081)
		(end 385.013962 -77.088238)
		(width 0.10795)
		(layer "F.Cu")
		(net "H_CPU0_FIVR_FAULT_G")
	)
	(segment
		(start 385.013962 -77.088238)
		(end 386.326888 -77.088238)
		(width 0.10795)
		(layer "F.Cu")
		(net "H_CPU0_FIVR_FAULT_G")
	)
	(segment
		(start 382.894586 -77.5081)
		(end 384.5941 -77.5081)
		(width 0.10795)
		(layer "F.Cu")
		(net "H_CPU0_FIVR_FAULT_G")
	)
	(via
		(at 361.545378 -71.561706)
		(size 0.6604)
		(drill 0.3302)
		(layers "F.Cu" "B.Cu")
		(net "H_CPU0_FIVR_FAULT_G")
	)
	(via
		(at 356.969568 -72.141588)
		(size 0.508)
		(drill 0.254)
		(layers "F.Cu" "B.Cu")
		(net "H_CPU0_FIVR_FAULT_G")
	)
	(via
		(at 382.50749 -77.895196)
		(size 0.508)
		(drill 0.254)
		(layers "F.Cu" "B.Cu")
		(net "H_CPU0_FIVR_FAULT_G")
	)
	(via
		(at 296.66184 -69.277738)
		(size 0.508)
		(drill 0.254)
		(layers "F.Cu" "B.Cu")
		(net "H_CPU0_FIVR_FAULT_G")
	)
	(segment
		(start 366.58931 -75.111102)
		(end 366.143286 -75.111102)
		(width 0.10795)
		(layer "B.Cu")
		(net "H_CPU0_FIVR_FAULT_G")
	)
	(segment
		(start 376.868944 -75.477624)
		(end 376.586242 -75.477624)
		(width 0.10795)
		(layer "B.Cu")
		(net "H_CPU0_FIVR_FAULT_G")
	)
	(segment
		(start 369.8748 -73.9394)
		(end 369.315746 -73.9394)
		(width 0.10795)
		(layer "B.Cu")
		(net "H_CPU0_FIVR_FAULT_G")
	)
	(segment
		(start 380.813564 -78.483968)
		(end 379.651768 -78.483968)
		(width 0.10795)
		(layer "B.Cu")
		(net "H_CPU0_FIVR_FAULT_G")
	)
	(segment
		(start 377.386342 -77.07757)
		(end 377.16206 -76.853288)
		(width 0.10795)
		(layer "B.Cu")
		(net "H_CPU0_FIVR_FAULT_G")
	)
	(segment
		(start 376.36196 -75.253342)
		(end 376.36196 -74.97064)
		(width 0.10795)
		(layer "B.Cu")
		(net "H_CPU0_FIVR_FAULT_G")
	)
	(segment
		(start 376.586242 -75.477624)
		(end 376.36196 -75.253342)
		(width 0.10795)
		(layer "B.Cu")
		(net "H_CPU0_FIVR_FAULT_G")
	)
	(segment
		(start 366.955832 -75.477624)
		(end 366.58931 -75.111102)
		(width 0.10795)
		(layer "B.Cu")
		(net "H_CPU0_FIVR_FAULT_G")
	)
	(segment
		(start 381.402336 -77.895196)
		(end 380.813564 -78.483968)
		(width 0.10795)
		(layer "B.Cu")
		(net "H_CPU0_FIVR_FAULT_G")
	)
	(segment
		(start 377.16206 -75.77074)
		(end 376.868944 -75.477624)
		(width 0.10795)
		(layer "B.Cu")
		(net "H_CPU0_FIVR_FAULT_G")
	)
	(segment
		(start 366.143286 -75.111102)
		(end 362.59389 -71.561706)
		(width 0.10795)
		(layer "B.Cu")
		(net "H_CPU0_FIVR_FAULT_G")
	)
	(segment
		(start 377.16206 -76.853288)
		(end 377.16206 -75.77074)
		(width 0.10795)
		(layer "B.Cu")
		(net "H_CPU0_FIVR_FAULT_G")
	)
	(segment
		(start 356.969568 -72.141588)
		(end 357.54945 -71.561706)
		(width 0.10795)
		(layer "B.Cu")
		(net "H_CPU0_FIVR_FAULT_G")
	)
	(segment
		(start 378.24537 -77.07757)
		(end 377.386342 -77.07757)
		(width 0.10795)
		(layer "B.Cu")
		(net "H_CPU0_FIVR_FAULT_G")
	)
	(segment
		(start 370.028978 -74.093578)
		(end 369.8748 -73.9394)
		(width 0.10795)
		(layer "B.Cu")
		(net "H_CPU0_FIVR_FAULT_G")
	)
	(segment
		(start 357.54945 -71.561706)
		(end 361.545378 -71.561706)
		(width 0.10795)
		(layer "B.Cu")
		(net "H_CPU0_FIVR_FAULT_G")
	)
	(segment
		(start 382.50749 -77.895196)
		(end 381.402336 -77.895196)
		(width 0.10795)
		(layer "B.Cu")
		(net "H_CPU0_FIVR_FAULT_G")
	)
	(segment
		(start 368.32413 -74.931016)
		(end 368.32413 -75.287378)
		(width 0.10795)
		(layer "B.Cu")
		(net "H_CPU0_FIVR_FAULT_G")
	)
	(segment
		(start 379.651768 -78.483968)
		(end 378.24537 -77.07757)
		(width 0.10795)
		(layer "B.Cu")
		(net "H_CPU0_FIVR_FAULT_G")
	)
	(segment
		(start 376.36196 -74.97064)
		(end 375.484898 -74.093578)
		(width 0.10795)
		(layer "B.Cu")
		(net "H_CPU0_FIVR_FAULT_G")
	)
	(segment
		(start 368.32413 -75.287378)
		(end 368.133884 -75.477624)
		(width 0.10795)
		(layer "B.Cu")
		(net "H_CPU0_FIVR_FAULT_G")
	)
	(segment
		(start 368.133884 -75.477624)
		(end 366.955832 -75.477624)
		(width 0.10795)
		(layer "B.Cu")
		(net "H_CPU0_FIVR_FAULT_G")
	)
	(segment
		(start 362.59389 -71.561706)
		(end 361.545378 -71.561706)
		(width 0.10795)
		(layer "B.Cu")
		(net "H_CPU0_FIVR_FAULT_G")
	)
	(segment
		(start 375.484898 -74.093578)
		(end 370.028978 -74.093578)
		(width 0.10795)
		(layer "B.Cu")
		(net "H_CPU0_FIVR_FAULT_G")
	)
	(segment
		(start 369.315746 -73.9394)
		(end 368.32413 -74.931016)
		(width 0.10795)
		(layer "B.Cu")
		(net "H_CPU0_FIVR_FAULT_G")
	)
	(segment
		(start 331.683868 -71.162672)
		(end 309.167276 -71.162672)
		(width 0.0889)
		(layer "In11.Cu")
		(net "H_CPU0_FIVR_FAULT_G")
	)
	(segment
		(start 356.969568 -72.141588)
		(end 357.093012 -72.018144)
		(width 0.089408)
		(layer "In11.Cu")
		(net "H_CPU0_FIVR_FAULT_G")
	)
	(segment
		(start 357.093012 -72.018144)
		(end 357.093012 -70.849236)
		(width 0.089408)
		(layer "In11.Cu")
		(net "H_CPU0_FIVR_FAULT_G")
	)
	(segment
		(start 309.167276 -71.162672)
		(end 308.177438 -70.172834)
		(width 0.089408)
		(layer "In11.Cu")
		(net "H_CPU0_FIVR_FAULT_G")
	)
	(segment
		(start 307.195982 -69.691758)
		(end 306.997354 -69.691758)
		(width 0.089408)
		(layer "In11.Cu")
		(net "H_CPU0_FIVR_FAULT_G")
	)
	(segment
		(start 297.108118 -69.88048)
		(end 296.66184 -69.277738)
		(width 0.089408)
		(layer "In11.Cu")
		(net "H_CPU0_FIVR_FAULT_G")
	)
	(segment
		(start 297.17619 -69.976492)
		(end 297.173904 -69.972682)
		(width 0.089408)
		(layer "In11.Cu")
		(net "H_CPU0_FIVR_FAULT_G")
	)
	(segment
		(start 336.533998 -66.312542)
		(end 331.683868 -71.162672)
		(width 0.089408)
		(layer "In11.Cu")
		(net "H_CPU0_FIVR_FAULT_G")
	)
	(segment
		(start 297.54068 -70.17258)
		(end 297.520106 -70.17258)
		(width 0.089408)
		(layer "In11.Cu")
		(net "H_CPU0_FIVR_FAULT_G")
	)
	(segment
		(start 303.545494 -69.67728)
		(end 303.509172 -69.67728)
		(width 0.089408)
		(layer "In11.Cu")
		(net "H_CPU0_FIVR_FAULT_G")
	)
	(segment
		(start 308.177438 -70.172834)
		(end 307.677058 -70.172834)
		(width 0.089408)
		(layer "In11.Cu")
		(net "H_CPU0_FIVR_FAULT_G")
	)
	(segment
		(start 352.556318 -66.312542)
		(end 336.533998 -66.312542)
		(width 0.089408)
		(layer "In11.Cu")
		(net "H_CPU0_FIVR_FAULT_G")
	)
	(segment
		(start 305.262534 -69.67728)
		(end 305.231038 -69.67728)
		(width 0.089408)
		(layer "In11.Cu")
		(net "H_CPU0_FIVR_FAULT_G")
	)
	(segment
		(start 307.677058 -70.172834)
		(end 307.195982 -69.691758)
		(width 0.089408)
		(layer "In11.Cu")
		(net "H_CPU0_FIVR_FAULT_G")
	)
	(segment
		(start 357.093012 -70.849236)
		(end 352.556318 -66.312542)
		(width 0.089408)
		(layer "In11.Cu")
		(net "H_CPU0_FIVR_FAULT_G")
	)
	(segment
		(start 302.683418 -70.17258)
		(end 302.650652 -70.17258)
		(width 0.089408)
		(layer "In11.Cu")
		(net "H_CPU0_FIVR_FAULT_G")
	)
	(arc
		(start 300.442122 -70.467982)
		(mid 300.095666 -70.668073)
		(end 299.74921 -70.467982)
		(width 0.089408)
		(layer "In11.Cu")
		(net "H_CPU0_FIVR_FAULT_G")
	)
	(arc
		(start 298.725082 -70.467982)
		(mid 298.378626 -70.668073)
		(end 298.03217 -70.467982)
		(width 0.089408)
		(layer "In11.Cu")
		(net "H_CPU0_FIVR_FAULT_G")
	)
	(arc
		(start 303.876202 -69.477382)
		(mid 303.7366 -69.619938)
		(end 303.545494 -69.67728)
		(width 0.089408)
		(layer "In11.Cu")
		(net "H_CPU0_FIVR_FAULT_G")
	)
	(arc
		(start 301.46625 -70.467982)
		(mid 300.954186 -70.172223)
		(end 300.442122 -70.467982)
		(width 0.089408)
		(layer "In11.Cu")
		(net "H_CPU0_FIVR_FAULT_G")
	)
	(arc
		(start 304.90033 -69.477382)
		(mid 304.388266 -69.181623)
		(end 303.876202 -69.477382)
		(width 0.089408)
		(layer "In11.Cu")
		(net "H_CPU0_FIVR_FAULT_G")
	)
	(arc
		(start 306.997354 -69.691758)
		(mid 306.826085 -69.65769)
		(end 306.68087 -69.560694)
		(width 0.089408)
		(layer "In11.Cu")
		(net "H_CPU0_FIVR_FAULT_G")
	)
	(arc
		(start 299.74921 -70.467982)
		(mid 299.237146 -70.172223)
		(end 298.725082 -70.467982)
		(width 0.089408)
		(layer "In11.Cu")
		(net "H_CPU0_FIVR_FAULT_G")
	)
	(arc
		(start 303.017682 -69.972682)
		(mid 302.876525 -70.116067)
		(end 302.683418 -70.17258)
		(width 0.089408)
		(layer "In11.Cu")
		(net "H_CPU0_FIVR_FAULT_G")
	)
	(arc
		(start 306.61737 -69.477382)
		(mid 306.105306 -69.181623)
		(end 305.593242 -69.477382)
		(width 0.089408)
		(layer "In11.Cu")
		(net "H_CPU0_FIVR_FAULT_G")
	)
	(arc
		(start 298.03217 -70.467982)
		(mid 297.824641 -70.256698)
		(end 297.54068 -70.17258)
		(width 0.089408)
		(layer "In11.Cu")
		(net "H_CPU0_FIVR_FAULT_G")
	)
	(arc
		(start 303.509172 -69.67728)
		(mid 303.225211 -69.761398)
		(end 303.017682 -69.972682)
		(width 0.089408)
		(layer "In11.Cu")
		(net "H_CPU0_FIVR_FAULT_G")
	)
	(arc
		(start 302.650652 -70.17258)
		(mid 302.366691 -70.256698)
		(end 302.159162 -70.467982)
		(width 0.089408)
		(layer "In11.Cu")
		(net "H_CPU0_FIVR_FAULT_G")
	)
	(arc
		(start 297.520106 -70.17258)
		(mid 297.322173 -70.120106)
		(end 297.17619 -69.976492)
		(width 0.089408)
		(layer "In11.Cu")
		(net "H_CPU0_FIVR_FAULT_G")
	)
	(arc
		(start 297.173904 -69.972682)
		(mid 297.143222 -69.925004)
		(end 297.108118 -69.88048)
		(width 0.089408)
		(layer "In11.Cu")
		(net "H_CPU0_FIVR_FAULT_G")
	)
	(arc
		(start 302.159162 -70.467982)
		(mid 301.812706 -70.668073)
		(end 301.46625 -70.467982)
		(width 0.089408)
		(layer "In11.Cu")
		(net "H_CPU0_FIVR_FAULT_G")
	)
	(arc
		(start 306.68087 -69.560694)
		(mid 306.646395 -69.521116)
		(end 306.61737 -69.477382)
		(width 0.089408)
		(layer "In11.Cu")
		(net "H_CPU0_FIVR_FAULT_G")
	)
	(arc
		(start 305.231038 -69.67728)
		(mid 305.039937 -69.61993)
		(end 304.90033 -69.477382)
		(width 0.089408)
		(layer "In11.Cu")
		(net "H_CPU0_FIVR_FAULT_G")
	)
	(arc
		(start 305.593242 -69.477382)
		(mid 305.45364 -69.619938)
		(end 305.262534 -69.67728)
		(width 0.089408)
		(layer "In11.Cu")
		(net "H_CPU0_FIVR_FAULT_G")
	)
	(segment
		(start 295.23182 -63.829184)
		(end 295.80332 -63.829184)
		(width 0.1016)
		(layer "F.Cu")
		(net "H_CPU0_FAST_WAKE_N")
	)
	(segment
		(start 159.594042 -71.43369)
		(end 159.392366 -71.232014)
		(width 0.10795)
		(layer "F.Cu")
		(net "H_CPU0_FAST_WAKE_N")
	)
	(segment
		(start 161.723832 -71.43369)
		(end 159.594042 -71.43369)
		(width 0.10795)
		(layer "F.Cu")
		(net "H_CPU0_FAST_WAKE_N")
	)
	(via
		(at 295.80332 -63.829184)
		(size 0.508)
		(drill 0.254)
		(layers "F.Cu" "B.Cu")
		(net "H_CPU0_FAST_WAKE_N")
	)
	(via
		(at 322.701412 -61.84646)
		(size 0.508)
		(drill 0.254)
		(layers "F.Cu" "B.Cu")
		(net "H_CPU0_FAST_WAKE_N")
	)
	(via
		(at 186.114436 -20.987004)
		(size 0.508)
		(drill 0.254)
		(layers "F.Cu" "B.Cu")
		(net "H_CPU0_FAST_WAKE_N")
	)
	(via
		(at 324.189598 -61.84646)
		(size 0.6604)
		(drill 0.3302)
		(layers "F.Cu" "B.Cu")
		(net "H_CPU0_FAST_WAKE_N")
	)
	(via
		(at 159.392366 -71.232014)
		(size 0.508)
		(drill 0.254)
		(layers "F.Cu" "B.Cu")
		(net "H_CPU0_FAST_WAKE_N")
	)
	(segment
		(start 322.701412 -61.84646)
		(end 324.189598 -61.84646)
		(width 0.10795)
		(layer "B.Cu")
		(net "H_CPU0_FAST_WAKE_N")
	)
	(segment
		(start 324.949058 -61.087)
		(end 324.189598 -61.84646)
		(width 0.10795)
		(layer "B.Cu")
		(net "H_CPU0_FAST_WAKE_N")
	)
	(segment
		(start 327.025 -61.087)
		(end 324.949058 -61.087)
		(width 0.10795)
		(layer "B.Cu")
		(net "H_CPU0_FAST_WAKE_N")
	)
	(segment
		(start 327.025 -60.325)
		(end 327.025 -61.087)
		(width 0.10795)
		(layer "B.Cu")
		(net "H_CPU0_FAST_WAKE_N")
	)
	(segment
		(start 186.826906 -20.60702)
		(end 187.442094 -19.991832)
		(width 0.089408)
		(layer "In9.Cu")
		(net "H_CPU0_FAST_WAKE_N")
	)
	(segment
		(start 325.312532 -42.456862)
		(end 325.312532 -44.886372)
		(width 0.089408)
		(layer "In9.Cu")
		(net "H_CPU0_FAST_WAKE_N")
	)
	(segment
		(start 265.933936 -16.314674)
		(end 266.337034 -16.314674)
		(width 0.089408)
		(layer "In9.Cu")
		(net "H_CPU0_FAST_WAKE_N")
	)
	(segment
		(start 320.900806 -16.522192)
		(end 320.900806 -27.892502)
		(width 0.089408)
		(layer "In9.Cu")
		(net "H_CPU0_FAST_WAKE_N")
	)
	(segment
		(start 191.564768 -19.798792)
		(end 192.455292 -18.908268)
		(width 0.089408)
		(layer "In9.Cu")
		(net "H_CPU0_FAST_WAKE_N")
	)
	(segment
		(start 263.090152 -20.248626)
		(end 264.378186 -20.248626)
		(width 0.089408)
		(layer "In9.Cu")
		(net "H_CPU0_FAST_WAKE_N")
	)
	(segment
		(start 324.862698 -35.765994)
		(end 325.762874 -36.66617)
		(width 0.089408)
		(layer "In9.Cu")
		(net "H_CPU0_FAST_WAKE_N")
	)
	(segment
		(start 264.378186 -20.248626)
		(end 265.506454 -19.120358)
		(width 0.089408)
		(layer "In9.Cu")
		(net "H_CPU0_FAST_WAKE_N")
	)
	(segment
		(start 322.472558 -54.592982)
		(end 322.472558 -61.617606)
		(width 0.089408)
		(layer "In9.Cu")
		(net "H_CPU0_FAST_WAKE_N")
	)
	(segment
		(start 192.455292 -18.325846)
		(end 195.832222 -14.948916)
		(width 0.089408)
		(layer "In9.Cu")
		(net "H_CPU0_FAST_WAKE_N")
	)
	(segment
		(start 324.862698 -33.888172)
		(end 324.862698 -35.765994)
		(width 0.089408)
		(layer "In9.Cu")
		(net "H_CPU0_FAST_WAKE_N")
	)
	(segment
		(start 265.506454 -19.120358)
		(end 265.506454 -18.757646)
		(width 0.089408)
		(layer "In9.Cu")
		(net "H_CPU0_FAST_WAKE_N")
	)
	(segment
		(start 323.457062 -30.448758)
		(end 323.457062 -32.482536)
		(width 0.089408)
		(layer "In9.Cu")
		(net "H_CPU0_FAST_WAKE_N")
	)
	(segment
		(start 323.457062 -32.482536)
		(end 324.862698 -33.888172)
		(width 0.089408)
		(layer "In9.Cu")
		(net "H_CPU0_FAST_WAKE_N")
	)
	(segment
		(start 190.18377 -19.798792)
		(end 191.564768 -19.798792)
		(width 0.089408)
		(layer "In9.Cu")
		(net "H_CPU0_FAST_WAKE_N")
	)
	(segment
		(start 322.821554 -49.340516)
		(end 324.295516 -50.814478)
		(width 0.089408)
		(layer "In9.Cu")
		(net "H_CPU0_FAST_WAKE_N")
	)
	(segment
		(start 324.295516 -50.814478)
		(end 324.295516 -52.770024)
		(width 0.089408)
		(layer "In9.Cu")
		(net "H_CPU0_FAST_WAKE_N")
	)
	(segment
		(start 186.49442 -20.60702)
		(end 186.826906 -20.60702)
		(width 0.089408)
		(layer "In9.Cu")
		(net "H_CPU0_FAST_WAKE_N")
	)
	(segment
		(start 258.625086 -15.76578)
		(end 259.20192 -16.342614)
		(width 0.089408)
		(layer "In9.Cu")
		(net "H_CPU0_FAST_WAKE_N")
	)
	(segment
		(start 265.699494 -16.88084)
		(end 265.699494 -16.549116)
		(width 0.089408)
		(layer "In9.Cu")
		(net "H_CPU0_FAST_WAKE_N")
	)
	(segment
		(start 324.295516 -52.770024)
		(end 322.472558 -54.592982)
		(width 0.089408)
		(layer "In9.Cu")
		(net "H_CPU0_FAST_WAKE_N")
	)
	(segment
		(start 325.312532 -44.886372)
		(end 322.821554 -47.37735)
		(width 0.089408)
		(layer "In9.Cu")
		(net "H_CPU0_FAST_WAKE_N")
	)
	(segment
		(start 259.20192 -16.360394)
		(end 263.090152 -20.248626)
		(width 0.089408)
		(layer "In9.Cu")
		(net "H_CPU0_FAST_WAKE_N")
	)
	(segment
		(start 266.504166 -16.147542)
		(end 320.526156 -16.147542)
		(width 0.089408)
		(layer "In9.Cu")
		(net "H_CPU0_FAST_WAKE_N")
	)
	(segment
		(start 187.442094 -19.991832)
		(end 189.99073 -19.991832)
		(width 0.089408)
		(layer "In9.Cu")
		(net "H_CPU0_FAST_WAKE_N")
	)
	(segment
		(start 322.472558 -61.617606)
		(end 322.701412 -61.84646)
		(width 0.089408)
		(layer "In9.Cu")
		(net "H_CPU0_FAST_WAKE_N")
	)
	(segment
		(start 266.337034 -16.314674)
		(end 266.504166 -16.147542)
		(width 0.089408)
		(layer "In9.Cu")
		(net "H_CPU0_FAST_WAKE_N")
	)
	(segment
		(start 189.99073 -19.991832)
		(end 190.18377 -19.798792)
		(width 0.089408)
		(layer "In9.Cu")
		(net "H_CPU0_FAST_WAKE_N")
	)
	(segment
		(start 265.506454 -18.757646)
		(end 266.15771 -18.10639)
		(width 0.089408)
		(layer "In9.Cu")
		(net "H_CPU0_FAST_WAKE_N")
	)
	(segment
		(start 257.790442 -14.948916)
		(end 258.607306 -15.76578)
		(width 0.089408)
		(layer "In9.Cu")
		(net "H_CPU0_FAST_WAKE_N")
	)
	(segment
		(start 325.762874 -36.66617)
		(end 325.762874 -42.00652)
		(width 0.089408)
		(layer "In9.Cu")
		(net "H_CPU0_FAST_WAKE_N")
	)
	(segment
		(start 186.114436 -20.987004)
		(end 186.49442 -20.60702)
		(width 0.089408)
		(layer "In9.Cu")
		(net "H_CPU0_FAST_WAKE_N")
	)
	(segment
		(start 320.900806 -27.892502)
		(end 323.457062 -30.448758)
		(width 0.089408)
		(layer "In9.Cu")
		(net "H_CPU0_FAST_WAKE_N")
	)
	(segment
		(start 266.15771 -17.339056)
		(end 265.699494 -16.88084)
		(width 0.089408)
		(layer "In9.Cu")
		(net "H_CPU0_FAST_WAKE_N")
	)
	(segment
		(start 195.832222 -14.948916)
		(end 257.790442 -14.948916)
		(width 0.089408)
		(layer "In9.Cu")
		(net "H_CPU0_FAST_WAKE_N")
	)
	(segment
		(start 322.821554 -47.37735)
		(end 322.821554 -49.340516)
		(width 0.089408)
		(layer "In9.Cu")
		(net "H_CPU0_FAST_WAKE_N")
	)
	(segment
		(start 258.607306 -15.76578)
		(end 258.625086 -15.76578)
		(width 0.089408)
		(layer "In9.Cu")
		(net "H_CPU0_FAST_WAKE_N")
	)
	(segment
		(start 266.15771 -18.10639)
		(end 266.15771 -17.339056)
		(width 0.089408)
		(layer "In9.Cu")
		(net "H_CPU0_FAST_WAKE_N")
	)
	(segment
		(start 192.455292 -18.908268)
		(end 192.455292 -18.325846)
		(width 0.089408)
		(layer "In9.Cu")
		(net "H_CPU0_FAST_WAKE_N")
	)
	(segment
		(start 265.699494 -16.549116)
		(end 265.933936 -16.314674)
		(width 0.089408)
		(layer "In9.Cu")
		(net "H_CPU0_FAST_WAKE_N")
	)
	(segment
		(start 320.526156 -16.147542)
		(end 320.900806 -16.522192)
		(width 0.089408)
		(layer "In9.Cu")
		(net "H_CPU0_FAST_WAKE_N")
	)
	(segment
		(start 259.20192 -16.342614)
		(end 259.20192 -16.360394)
		(width 0.089408)
		(layer "In9.Cu")
		(net "H_CPU0_FAST_WAKE_N")
	)
	(segment
		(start 325.762874 -42.00652)
		(end 325.312532 -42.456862)
		(width 0.089408)
		(layer "In9.Cu")
		(net "H_CPU0_FAST_WAKE_N")
	)
	(segment
		(start 184.83326 -31.124906)
		(end 184.83326 -31.14294)
		(width 0.089408)
		(layer "In11.Cu")
		(net "H_CPU0_FAST_WAKE_N")
	)
	(segment
		(start 311.317386 -62.743334)
		(end 305.239674 -62.743334)
		(width 0.089408)
		(layer "In11.Cu")
		(net "H_CPU0_FAST_WAKE_N")
	)
	(segment
		(start 300.102778 -62.743334)
		(end 300.088554 -62.743334)
		(width 0.089408)
		(layer "In11.Cu")
		(net "H_CPU0_FAST_WAKE_N")
	)
	(segment
		(start 304.40884 -62.24778)
		(end 304.367692 -62.24778)
		(width 0.089408)
		(layer "In11.Cu")
		(net "H_CPU0_FAST_WAKE_N")
	)
	(segment
		(start 184.96788 -30.990286)
		(end 184.83326 -31.124906)
		(width 0.089408)
		(layer "In11.Cu")
		(net "H_CPU0_FAST_WAKE_N")
	)
	(segment
		(start 303.876202 -62.543182)
		(end 303.814988 -62.649354)
		(width 0.089408)
		(layer "In11.Cu")
		(net "H_CPU0_FAST_WAKE_N")
	)
	(segment
		(start 186.114436 -20.987004)
		(end 184.96788 -22.13356)
		(width 0.089408)
		(layer "In11.Cu")
		(net "H_CPU0_FAST_WAKE_N")
	)
	(segment
		(start 298.385738 -62.743334)
		(end 298.354496 -62.743334)
		(width 0.089408)
		(layer "In11.Cu")
		(net "H_CPU0_FAST_WAKE_N")
	)
	(segment
		(start 297.532298 -63.23838)
		(end 297.28922 -63.23838)
		(width 0.089408)
		(layer "In11.Cu")
		(net "H_CPU0_FAST_WAKE_N")
	)
	(segment
		(start 313.178444 -64.604392)
		(end 311.317386 -62.743334)
		(width 0.089408)
		(layer "In11.Cu")
		(net "H_CPU0_FAST_WAKE_N")
	)
	(segment
		(start 297.28922 -63.23838)
		(end 297.0911 -63.581788)
		(width 0.089408)
		(layer "In11.Cu")
		(net "H_CPU0_FAST_WAKE_N")
	)
	(segment
		(start 321.384168 -64.604392)
		(end 313.178444 -64.604392)
		(width 0.089408)
		(layer "In11.Cu")
		(net "H_CPU0_FAST_WAKE_N")
	)
	(segment
		(start 296.67835 -63.829438)
		(end 296.66184 -63.829438)
		(width 0.089408)
		(layer "In11.Cu")
		(net "H_CPU0_FAST_WAKE_N")
	)
	(segment
		(start 299.25772 -62.24778)
		(end 299.216572 -62.24778)
		(width 0.089408)
		(layer "In11.Cu")
		(net "H_CPU0_FAST_WAKE_N")
	)
	(segment
		(start 322.701412 -63.287148)
		(end 321.384168 -64.604392)
		(width 0.089408)
		(layer "In11.Cu")
		(net "H_CPU0_FAST_WAKE_N")
	)
	(segment
		(start 184.96788 -22.13356)
		(end 184.96788 -30.990286)
		(width 0.089408)
		(layer "In11.Cu")
		(net "H_CPU0_FAST_WAKE_N")
	)
	(segment
		(start 159.042862 -66.682112)
		(end 159.042862 -70.88251)
		(width 0.089408)
		(layer "In11.Cu")
		(net "H_CPU0_FAST_WAKE_N")
	)
	(segment
		(start 296.66184 -63.829438)
		(end 295.80332 -63.829184)
		(width 0.089408)
		(layer "In11.Cu")
		(net "H_CPU0_FAST_WAKE_N")
	)
	(segment
		(start 159.042862 -70.88251)
		(end 159.392366 -71.232014)
		(width 0.089408)
		(layer "In11.Cu")
		(net "H_CPU0_FAST_WAKE_N")
	)
	(segment
		(start 162.464496 -53.511704)
		(end 162.464496 -63.260478)
		(width 0.089408)
		(layer "In11.Cu")
		(net "H_CPU0_FAST_WAKE_N")
	)
	(segment
		(start 303.652174 -62.743334)
		(end 301.805594 -62.743334)
		(width 0.089408)
		(layer "In11.Cu")
		(net "H_CPU0_FAST_WAKE_N")
	)
	(segment
		(start 184.83326 -31.14294)
		(end 162.464496 -53.511704)
		(width 0.089408)
		(layer "In11.Cu")
		(net "H_CPU0_FAST_WAKE_N")
	)
	(segment
		(start 162.464496 -63.260478)
		(end 159.042862 -66.682112)
		(width 0.089408)
		(layer "In11.Cu")
		(net "H_CPU0_FAST_WAKE_N")
	)
	(segment
		(start 322.701412 -61.84646)
		(end 322.701412 -63.287148)
		(width 0.089408)
		(layer "In11.Cu")
		(net "H_CPU0_FAST_WAKE_N")
	)
	(segment
		(start 300.97476 -62.24778)
		(end 300.933612 -62.24778)
		(width 0.089408)
		(layer "In11.Cu")
		(net "H_CPU0_FAST_WAKE_N")
	)
	(arc
		(start 305.239674 -62.743334)
		(mid 305.043642 -62.68795)
		(end 304.90033 -62.543182)
		(width 0.089408)
		(layer "In11.Cu")
		(net "H_CPU0_FAST_WAKE_N")
	)
	(arc
		(start 303.814988 -62.649354)
		(mid 303.746177 -62.718175)
		(end 303.652174 -62.743334)
		(width 0.089408)
		(layer "In11.Cu")
		(net "H_CPU0_FAST_WAKE_N")
	)
	(arc
		(start 304.90033 -62.543182)
		(mid 304.692801 -62.331898)
		(end 304.40884 -62.24778)
		(width 0.089408)
		(layer "In11.Cu")
		(net "H_CPU0_FAST_WAKE_N")
	)
	(arc
		(start 299.74921 -62.543182)
		(mid 299.541681 -62.331898)
		(end 299.25772 -62.24778)
		(width 0.089408)
		(layer "In11.Cu")
		(net "H_CPU0_FAST_WAKE_N")
	)
	(arc
		(start 298.354496 -62.743334)
		(mid 298.072594 -62.828197)
		(end 297.866562 -63.038482)
		(width 0.089408)
		(layer "In11.Cu")
		(net "H_CPU0_FAST_WAKE_N")
	)
	(arc
		(start 298.725082 -62.543182)
		(mid 298.581771 -62.687953)
		(end 298.385738 -62.743334)
		(width 0.089408)
		(layer "In11.Cu")
		(net "H_CPU0_FAST_WAKE_N")
	)
	(arc
		(start 300.088554 -62.743334)
		(mid 299.892522 -62.68795)
		(end 299.74921 -62.543182)
		(width 0.089408)
		(layer "In11.Cu")
		(net "H_CPU0_FAST_WAKE_N")
	)
	(arc
		(start 301.805594 -62.743334)
		(mid 301.609562 -62.68795)
		(end 301.46625 -62.543182)
		(width 0.089408)
		(layer "In11.Cu")
		(net "H_CPU0_FAST_WAKE_N")
	)
	(arc
		(start 300.442122 -62.543182)
		(mid 300.298811 -62.687953)
		(end 300.102778 -62.743334)
		(width 0.089408)
		(layer "In11.Cu")
		(net "H_CPU0_FAST_WAKE_N")
	)
	(arc
		(start 304.367692 -62.24778)
		(mid 304.083731 -62.331898)
		(end 303.876202 -62.543182)
		(width 0.089408)
		(layer "In11.Cu")
		(net "H_CPU0_FAST_WAKE_N")
	)
	(arc
		(start 297.0911 -63.581788)
		(mid 296.916811 -63.75909)
		(end 296.67835 -63.829438)
		(width 0.089408)
		(layer "In11.Cu")
		(net "H_CPU0_FAST_WAKE_N")
	)
	(arc
		(start 301.46625 -62.543182)
		(mid 301.258721 -62.331898)
		(end 300.97476 -62.24778)
		(width 0.089408)
		(layer "In11.Cu")
		(net "H_CPU0_FAST_WAKE_N")
	)
	(arc
		(start 300.933612 -62.24778)
		(mid 300.649651 -62.331898)
		(end 300.442122 -62.543182)
		(width 0.089408)
		(layer "In11.Cu")
		(net "H_CPU0_FAST_WAKE_N")
	)
	(arc
		(start 299.216572 -62.24778)
		(mid 298.932611 -62.331898)
		(end 298.725082 -62.543182)
		(width 0.089408)
		(layer "In11.Cu")
		(net "H_CPU0_FAST_WAKE_N")
	)
	(arc
		(start 297.866562 -63.038482)
		(mid 297.725405 -63.181867)
		(end 297.532298 -63.23838)
		(width 0.089408)
		(layer "In11.Cu")
		(net "H_CPU0_FAST_WAKE_N")
	)
	(segment
		(start 381.211328 -75.543918)
		(end 380.929642 -75.825604)
		(width 0.10795)
		(layer "F.Cu")
		(net "H_CPU0_ERR2_G_N")
	)
	(segment
		(start 297.807126 -66.305938)
		(end 298.378626 -66.305938)
		(width 0.1016)
		(layer "F.Cu")
		(net "H_CPU0_ERR2_G_N")
	)
	(segment
		(start 380.929642 -75.825604)
		(end 380.929642 -76.226924)
		(width 0.10795)
		(layer "F.Cu")
		(net "H_CPU0_ERR2_G_N")
	)
	(segment
		(start 382.898904 -76.019406)
		(end 382.898904 -75.664568)
		(width 0.10795)
		(layer "F.Cu")
		(net "H_CPU0_ERR2_G_N")
	)
	(segment
		(start 382.898904 -75.664568)
		(end 382.778254 -75.543918)
		(width 0.10795)
		(layer "F.Cu")
		(net "H_CPU0_ERR2_G_N")
	)
	(segment
		(start 382.778254 -75.543918)
		(end 381.211328 -75.543918)
		(width 0.10795)
		(layer "F.Cu")
		(net "H_CPU0_ERR2_G_N")
	)
	(via
		(at 298.378626 -66.305938)
		(size 0.508)
		(drill 0.254)
		(layers "F.Cu" "B.Cu")
		(net "H_CPU0_ERR2_G_N")
	)
	(via
		(at 380.929642 -76.226924)
		(size 0.508)
		(drill 0.254)
		(layers "F.Cu" "B.Cu")
		(net "H_CPU0_ERR2_G_N")
	)
	(via
		(at 363.31271 -66.706496)
		(size 0.508)
		(drill 0.254)
		(layers "F.Cu" "B.Cu")
		(net "H_CPU0_ERR2_G_N")
	)
	(via
		(at 361.56265 -68.4784)
		(size 0.6604)
		(drill 0.3302)
		(layers "F.Cu" "B.Cu")
		(net "H_CPU0_ERR2_G_N")
	)
	(segment
		(start 368.097308 -74.684382)
		(end 369.1382 -73.64349)
		(width 0.10795)
		(layer "B.Cu")
		(net "H_CPU0_ERR2_G_N")
	)
	(segment
		(start 362.5088 -66.706496)
		(end 361.56265 -67.652646)
		(width 0.10795)
		(layer "B.Cu")
		(net "H_CPU0_ERR2_G_N")
	)
	(segment
		(start 361.56265 -67.652646)
		(end 361.56265 -68.4784)
		(width 0.10795)
		(layer "B.Cu")
		(net "H_CPU0_ERR2_G_N")
	)
	(segment
		(start 361.56265 -70.078854)
		(end 366.168178 -74.684382)
		(width 0.10795)
		(layer "B.Cu")
		(net "H_CPU0_ERR2_G_N")
	)
	(segment
		(start 378.094748 -75.103482)
		(end 379.997208 -75.103482)
		(width 0.10795)
		(layer "B.Cu")
		(net "H_CPU0_ERR2_G_N")
	)
	(segment
		(start 369.1382 -73.360788)
		(end 369.386612 -73.112376)
		(width 0.10795)
		(layer "B.Cu")
		(net "H_CPU0_ERR2_G_N")
	)
	(segment
		(start 369.386612 -73.112376)
		(end 369.703604 -73.112376)
		(width 0.10795)
		(layer "B.Cu")
		(net "H_CPU0_ERR2_G_N")
	)
	(segment
		(start 369.1382 -73.64349)
		(end 369.1382 -73.360788)
		(width 0.10795)
		(layer "B.Cu")
		(net "H_CPU0_ERR2_G_N")
	)
	(segment
		(start 369.951 -73.64222)
		(end 370.192808 -73.884028)
		(width 0.10795)
		(layer "B.Cu")
		(net "H_CPU0_ERR2_G_N")
	)
	(segment
		(start 376.875294 -73.884028)
		(end 378.094748 -75.103482)
		(width 0.10795)
		(layer "B.Cu")
		(net "H_CPU0_ERR2_G_N")
	)
	(segment
		(start 369.951 -73.359772)
		(end 369.951 -73.64222)
		(width 0.10795)
		(layer "B.Cu")
		(net "H_CPU0_ERR2_G_N")
	)
	(segment
		(start 370.192808 -73.884028)
		(end 376.875294 -73.884028)
		(width 0.10795)
		(layer "B.Cu")
		(net "H_CPU0_ERR2_G_N")
	)
	(segment
		(start 379.997208 -75.103482)
		(end 380.929642 -76.035916)
		(width 0.10795)
		(layer "B.Cu")
		(net "H_CPU0_ERR2_G_N")
	)
	(segment
		(start 380.929642 -76.035916)
		(end 380.929642 -76.226924)
		(width 0.10795)
		(layer "B.Cu")
		(net "H_CPU0_ERR2_G_N")
	)
	(segment
		(start 369.703604 -73.112376)
		(end 369.951 -73.359772)
		(width 0.10795)
		(layer "B.Cu")
		(net "H_CPU0_ERR2_G_N")
	)
	(segment
		(start 361.56265 -68.4784)
		(end 361.56265 -70.078854)
		(width 0.10795)
		(layer "B.Cu")
		(net "H_CPU0_ERR2_G_N")
	)
	(segment
		(start 366.168178 -74.684382)
		(end 368.097308 -74.684382)
		(width 0.10795)
		(layer "B.Cu")
		(net "H_CPU0_ERR2_G_N")
	)
	(segment
		(start 363.31271 -66.706496)
		(end 362.5088 -66.706496)
		(width 0.10795)
		(layer "B.Cu")
		(net "H_CPU0_ERR2_G_N")
	)
	(segment
		(start 300.966378 -66.21018)
		(end 300.933612 -66.21018)
		(width 0.089408)
		(layer "In11.Cu")
		(net "H_CPU0_ERR2_G_N")
	)
	(segment
		(start 299.30217 -66.213228)
		(end 299.274738 -66.21018)
		(width 0.089408)
		(layer "In11.Cu")
		(net "H_CPU0_ERR2_G_N")
	)
	(segment
		(start 312.248042 -66.784982)
		(end 311.840372 -67.192652)
		(width 0.089408)
		(layer "In11.Cu")
		(net "H_CPU0_ERR2_G_N")
	)
	(segment
		(start 363.31271 -66.706496)
		(end 360.60634 -64.000126)
		(width 0.089408)
		(layer "In11.Cu")
		(net "H_CPU0_ERR2_G_N")
	)
	(segment
		(start 354.677218 -63.724536)
		(end 335.463896 -63.724536)
		(width 0.089408)
		(layer "In11.Cu")
		(net "H_CPU0_ERR2_G_N")
	)
	(segment
		(start 298.617894 -66.066416)
		(end 298.378626 -66.305938)
		(width 0.089408)
		(layer "In11.Cu")
		(net "H_CPU0_ERR2_G_N")
	)
	(segment
		(start 355.920294 -63.270384)
		(end 355.13137 -63.270384)
		(width 0.089408)
		(layer "In11.Cu")
		(net "H_CPU0_ERR2_G_N")
	)
	(segment
		(start 356.650036 -64.000126)
		(end 355.920294 -63.270384)
		(width 0.089408)
		(layer "In11.Cu")
		(net "H_CPU0_ERR2_G_N")
	)
	(segment
		(start 355.13137 -63.270384)
		(end 354.677218 -63.724536)
		(width 0.089408)
		(layer "In11.Cu")
		(net "H_CPU0_ERR2_G_N")
	)
	(segment
		(start 360.60634 -64.000126)
		(end 356.650036 -64.000126)
		(width 0.089408)
		(layer "In11.Cu")
		(net "H_CPU0_ERR2_G_N")
	)
	(segment
		(start 335.463896 -63.724536)
		(end 332.40345 -66.784982)
		(width 0.089408)
		(layer "In11.Cu")
		(net "H_CPU0_ERR2_G_N")
	)
	(segment
		(start 311.840372 -67.192652)
		(end 310.5023 -67.192652)
		(width 0.089408)
		(layer "In11.Cu")
		(net "H_CPU0_ERR2_G_N")
	)
	(segment
		(start 332.40345 -66.784982)
		(end 312.248042 -66.784982)
		(width 0.089408)
		(layer "In11.Cu")
		(net "H_CPU0_ERR2_G_N")
	)
	(segment
		(start 309.024782 -65.715134)
		(end 306.956714 -65.715134)
		(width 0.089408)
		(layer "In11.Cu")
		(net "H_CPU0_ERR2_G_N")
	)
	(segment
		(start 305.253898 -65.715134)
		(end 305.222656 -65.715134)
		(width 0.089408)
		(layer "In11.Cu")
		(net "H_CPU0_ERR2_G_N")
	)
	(segment
		(start 310.5023 -67.192652)
		(end 309.024782 -65.715134)
		(width 0.089408)
		(layer "In11.Cu")
		(net "H_CPU0_ERR2_G_N")
	)
	(segment
		(start 299.274738 -66.21018)
		(end 299.224954 -66.21018)
		(width 0.089408)
		(layer "In11.Cu")
		(net "H_CPU0_ERR2_G_N")
	)
	(arc
		(start 304.734722 -66.010282)
		(mid 304.388266 -66.210373)
		(end 304.04181 -66.010282)
		(width 0.089408)
		(layer "In11.Cu")
		(net "H_CPU0_ERR2_G_N")
	)
	(arc
		(start 302.32477 -66.010282)
		(mid 301.812706 -65.71465)
		(end 301.300642 -66.010282)
		(width 0.089408)
		(layer "In11.Cu")
		(net "H_CPU0_ERR2_G_N")
	)
	(arc
		(start 300.933612 -66.21018)
		(mid 300.649651 -66.294298)
		(end 300.442122 -66.505582)
		(width 0.089408)
		(layer "In11.Cu")
		(net "H_CPU0_ERR2_G_N")
	)
	(arc
		(start 303.017682 -66.010282)
		(mid 302.671226 -66.210373)
		(end 302.32477 -66.010282)
		(width 0.089408)
		(layer "In11.Cu")
		(net "H_CPU0_ERR2_G_N")
	)
	(arc
		(start 298.807886 -66.058288)
		(mid 298.711276 -66.025322)
		(end 298.617894 -66.066416)
		(width 0.089408)
		(layer "In11.Cu")
		(net "H_CPU0_ERR2_G_N")
	)
	(arc
		(start 301.300642 -66.010282)
		(mid 301.159485 -66.153667)
		(end 300.966378 -66.21018)
		(width 0.089408)
		(layer "In11.Cu")
		(net "H_CPU0_ERR2_G_N")
	)
	(arc
		(start 300.442122 -66.505582)
		(mid 300.095666 -66.7058)
		(end 299.74921 -66.505582)
		(width 0.089408)
		(layer "In11.Cu")
		(net "H_CPU0_ERR2_G_N")
	)
	(arc
		(start 299.74921 -66.505582)
		(mid 299.560589 -66.306052)
		(end 299.30217 -66.213228)
		(width 0.089408)
		(layer "In11.Cu")
		(net "H_CPU0_ERR2_G_N")
	)
	(arc
		(start 299.224954 -66.21018)
		(mid 299.003024 -66.171021)
		(end 298.807886 -66.058288)
		(width 0.089408)
		(layer "In11.Cu")
		(net "H_CPU0_ERR2_G_N")
	)
	(arc
		(start 305.593242 -65.514982)
		(mid 305.449931 -65.659753)
		(end 305.253898 -65.715134)
		(width 0.089408)
		(layer "In11.Cu")
		(net "H_CPU0_ERR2_G_N")
	)
	(arc
		(start 305.222656 -65.715134)
		(mid 304.940754 -65.799997)
		(end 304.734722 -66.010282)
		(width 0.089408)
		(layer "In11.Cu")
		(net "H_CPU0_ERR2_G_N")
	)
	(arc
		(start 306.956714 -65.715134)
		(mid 306.760682 -65.65975)
		(end 306.61737 -65.514982)
		(width 0.089408)
		(layer "In11.Cu")
		(net "H_CPU0_ERR2_G_N")
	)
	(arc
		(start 306.61737 -65.514982)
		(mid 306.105306 -65.219223)
		(end 305.593242 -65.514982)
		(width 0.089408)
		(layer "In11.Cu")
		(net "H_CPU0_ERR2_G_N")
	)
	(arc
		(start 304.04181 -66.010282)
		(mid 303.529746 -65.71465)
		(end 303.017682 -66.010282)
		(width 0.089408)
		(layer "In11.Cu")
		(net "H_CPU0_ERR2_G_N")
	)
	(segment
		(start 296.66184 -66.305938)
		(end 296.09034 -66.305938)
		(width 0.1016)
		(layer "F.Cu")
		(net "H_CPU0_CATERR_G_N")
	)
	(via
		(at 364.1598 -64.5668)
		(size 0.508)
		(drill 0.254)
		(layers "F.Cu" "B.Cu")
		(net "H_CPU0_CATERR_G_N")
	)
	(via
		(at 324.965822 -62.890908)
		(size 0.508)
		(drill 0.254)
		(layers "F.Cu" "B.Cu")
		(net "H_CPU0_CATERR_G_N")
	)
	(via
		(at 320.903854 -61.185806)
		(size 0.6604)
		(drill 0.3302)
		(layers "F.Cu" "B.Cu")
		(net "H_CPU0_CATERR_G_N")
	)
	(via
		(at 296.66184 -66.305938)
		(size 0.508)
		(drill 0.254)
		(layers "F.Cu" "B.Cu")
		(net "H_CPU0_CATERR_G_N")
	)
	(segment
		(start 299.139864 -61.38164)
		(end 299.422566 -61.38164)
		(width 0.0889)
		(layer "B.Cu")
		(net "H_CPU0_CATERR_G_N")
	)
	(segment
		(start 296.66184 -66.105024)
		(end 297.415204 -65.35166)
		(width 0.0889)
		(layer "B.Cu")
		(net "H_CPU0_CATERR_G_N")
	)
	(segment
		(start 298.903898 -62.167262)
		(end 298.82846 -62.091824)
		(width 0.0889)
		(layer "B.Cu")
		(net "H_CPU0_CATERR_G_N")
	)
	(segment
		(start 302.654716 -59.371484)
		(end 302.69434 -59.371484)
		(width 0.0889)
		(layer "B.Cu")
		(net "H_CPU0_CATERR_G_N")
	)
	(segment
		(start 307.345588 -57.981088)
		(end 307.6702 -58.3057)
		(width 0.0889)
		(layer "B.Cu")
		(net "H_CPU0_CATERR_G_N")
	)
	(segment
		(start 317.433198 -59.496452)
		(end 319.837054 -60.484766)
		(width 0.10795)
		(layer "B.Cu")
		(net "H_CPU0_CATERR_G_N")
	)
	(segment
		(start 374.468898 -55.207154)
		(end 374.513348 -55.162704)
		(width 0.10795)
		(layer "B.Cu")
		(net "H_CPU0_CATERR_G_N")
	)
	(segment
		(start 374.468898 -56.359552)
		(end 374.468898 -55.207154)
		(width 0.10795)
		(layer "B.Cu")
		(net "H_CPU0_CATERR_G_N")
	)
	(segment
		(start 298.411646 -63.881)
		(end 298.8056 -63.487046)
		(width 0.0889)
		(layer "B.Cu")
		(net "H_CPU0_CATERR_G_N")
	)
	(segment
		(start 297.415204 -65.35166)
		(end 297.69562 -65.35166)
		(width 0.0889)
		(layer "B.Cu")
		(net "H_CPU0_CATERR_G_N")
	)
	(segment
		(start 298.2468 -63.881)
		(end 298.411646 -63.881)
		(width 0.0889)
		(layer "B.Cu")
		(net "H_CPU0_CATERR_G_N")
	)
	(segment
		(start 361.314492 -62.381892)
		(end 363.4994 -64.5668)
		(width 0.10795)
		(layer "B.Cu")
		(net "H_CPU0_CATERR_G_N")
	)
	(segment
		(start 305.2318 -57.981088)
		(end 305.261772 -57.981088)
		(width 0.0889)
		(layer "B.Cu")
		(net "H_CPU0_CATERR_G_N")
	)
	(segment
		(start 367.798096 -55.576216)
		(end 366.757966 -56.616346)
		(width 0.10795)
		(layer "B.Cu")
		(net "H_CPU0_CATERR_G_N")
	)
	(segment
		(start 361.314492 -59.144408)
		(end 361.314492 -62.381892)
		(width 0.10795)
		(layer "B.Cu")
		(net "H_CPU0_CATERR_G_N")
	)
	(segment
		(start 300.82998 -60.35802)
		(end 301.16018 -60.35802)
		(width 0.0889)
		(layer "B.Cu")
		(net "H_CPU0_CATERR_G_N")
	)
	(segment
		(start 298.8056 -63.487046)
		(end 298.8056 -62.684914)
		(width 0.0889)
		(layer "B.Cu")
		(net "H_CPU0_CATERR_G_N")
	)
	(segment
		(start 308.787546 -57.5945)
		(end 309.188358 -57.5945)
		(width 0.0889)
		(layer "B.Cu")
		(net "H_CPU0_CATERR_G_N")
	)
	(segment
		(start 298.02709 -65.02019)
		(end 298.02709 -64.65189)
		(width 0.0889)
		(layer "B.Cu")
		(net "H_CPU0_CATERR_G_N")
	)
	(segment
		(start 297.942 -64.5668)
		(end 297.942 -64.1858)
		(width 0.0889)
		(layer "B.Cu")
		(net "H_CPU0_CATERR_G_N")
	)
	(segment
		(start 373.0244 -55.1434)
		(end 372.364254 -55.1434)
		(width 0.10795)
		(layer "B.Cu")
		(net "H_CPU0_CATERR_G_N")
	)
	(segment
		(start 371.985032 -55.522622)
		(end 370.257578 -55.522622)
		(width 0.10795)
		(layer "B.Cu")
		(net "H_CPU0_CATERR_G_N")
	)
	(segment
		(start 323.20103 -62.292484)
		(end 322.587366 -62.292484)
		(width 0.10795)
		(layer "B.Cu")
		(net "H_CPU0_CATERR_G_N")
	)
	(segment
		(start 325.554848 -62.889638)
		(end 326.595486 -61.849)
		(width 0.10795)
		(layer "B.Cu")
		(net "H_CPU0_CATERR_G_N")
	)
	(segment
		(start 372.364254 -55.1434)
		(end 371.985032 -55.522622)
		(width 0.10795)
		(layer "B.Cu")
		(net "H_CPU0_CATERR_G_N")
	)
	(segment
		(start 374.32107 -54.5338)
		(end 373.634 -54.5338)
		(width 0.10795)
		(layer "B.Cu")
		(net "H_CPU0_CATERR_G_N")
	)
	(segment
		(start 298.82846 -62.091824)
		(end 298.82846 -61.693044)
		(width 0.0889)
		(layer "B.Cu")
		(net "H_CPU0_CATERR_G_N")
	)
	(segment
		(start 306.94884 -57.981088)
		(end 307.345588 -57.981088)
		(width 0.0889)
		(layer "B.Cu")
		(net "H_CPU0_CATERR_G_N")
	)
	(segment
		(start 370.257578 -55.522622)
		(end 370.203984 -55.576216)
		(width 0.10795)
		(layer "B.Cu")
		(net "H_CPU0_CATERR_G_N")
	)
	(segment
		(start 301.16018 -60.35802)
		(end 301.651416 -59.866784)
		(width 0.0889)
		(layer "B.Cu")
		(net "H_CPU0_CATERR_G_N")
	)
	(segment
		(start 309.567834 -57.215024)
		(end 312.709814 -57.215024)
		(width 0.10795)
		(layer "B.Cu")
		(net "H_CPU0_CATERR_G_N")
	)
	(segment
		(start 322.587366 -62.292484)
		(end 320.903854 -61.185806)
		(width 0.10795)
		(layer "B.Cu")
		(net "H_CPU0_CATERR_G_N")
	)
	(segment
		(start 308.076346 -58.3057)
		(end 308.787546 -57.5945)
		(width 0.0889)
		(layer "B.Cu")
		(net "H_CPU0_CATERR_G_N")
	)
	(segment
		(start 366.757966 -56.616346)
		(end 363.11332 -56.616346)
		(width 0.10795)
		(layer "B.Cu")
		(net "H_CPU0_CATERR_G_N")
	)
	(segment
		(start 298.82846 -61.693044)
		(end 299.139864 -61.38164)
		(width 0.0889)
		(layer "B.Cu")
		(net "H_CPU0_CATERR_G_N")
	)
	(segment
		(start 298.903898 -62.586616)
		(end 298.903898 -62.167262)
		(width 0.0889)
		(layer "B.Cu")
		(net "H_CPU0_CATERR_G_N")
	)
	(segment
		(start 374.05945 -56.769)
		(end 374.468898 -56.359552)
		(width 0.10795)
		(layer "B.Cu")
		(net "H_CPU0_CATERR_G_N")
	)
	(segment
		(start 319.837054 -60.484766)
		(end 320.903854 -61.185806)
		(width 0.10795)
		(layer "B.Cu")
		(net "H_CPU0_CATERR_G_N")
	)
	(segment
		(start 296.66184 -66.305938)
		(end 296.66184 -66.105024)
		(width 0.0889)
		(layer "B.Cu")
		(net "H_CPU0_CATERR_G_N")
	)
	(segment
		(start 298.02709 -64.65189)
		(end 297.942 -64.5668)
		(width 0.0889)
		(layer "B.Cu")
		(net "H_CPU0_CATERR_G_N")
	)
	(segment
		(start 363.11332 -56.616346)
		(end 361.699302 -58.030364)
		(width 0.10795)
		(layer "B.Cu")
		(net "H_CPU0_CATERR_G_N")
	)
	(segment
		(start 312.709814 -57.215024)
		(end 316.082172 -58.608468)
		(width 0.10795)
		(layer "B.Cu")
		(net "H_CPU0_CATERR_G_N")
	)
	(segment
		(start 323.799454 -62.890908)
		(end 323.20103 -62.292484)
		(width 0.10795)
		(layer "B.Cu")
		(net "H_CPU0_CATERR_G_N")
	)
	(segment
		(start 307.6702 -58.3057)
		(end 308.076346 -58.3057)
		(width 0.0889)
		(layer "B.Cu")
		(net "H_CPU0_CATERR_G_N")
	)
	(segment
		(start 373.634 -54.5338)
		(end 373.0244 -55.1434)
		(width 0.10795)
		(layer "B.Cu")
		(net "H_CPU0_CATERR_G_N")
	)
	(segment
		(start 299.422566 -61.38164)
		(end 299.983906 -60.8203)
		(width 0.0889)
		(layer "B.Cu")
		(net "H_CPU0_CATERR_G_N")
	)
	(segment
		(start 304.383694 -58.380884)
		(end 304.408332 -58.380884)
		(width 0.0889)
		(layer "B.Cu")
		(net "H_CPU0_CATERR_G_N")
	)
	(segment
		(start 301.651416 -59.866784)
		(end 301.829216 -59.866784)
		(width 0.0889)
		(layer "B.Cu")
		(net "H_CPU0_CATERR_G_N")
	)
	(segment
		(start 316.082172 -58.608468)
		(end 317.433198 -59.496452)
		(width 0.10795)
		(layer "B.Cu")
		(net "H_CPU0_CATERR_G_N")
	)
	(segment
		(start 299.983906 -60.8203)
		(end 300.3677 -60.8203)
		(width 0.0889)
		(layer "B.Cu")
		(net "H_CPU0_CATERR_G_N")
	)
	(segment
		(start 361.699302 -58.759598)
		(end 361.314492 -59.144408)
		(width 0.10795)
		(layer "B.Cu")
		(net "H_CPU0_CATERR_G_N")
	)
	(segment
		(start 370.203984 -55.576216)
		(end 367.798096 -55.576216)
		(width 0.10795)
		(layer "B.Cu")
		(net "H_CPU0_CATERR_G_N")
	)
	(segment
		(start 297.69562 -65.35166)
		(end 298.02709 -65.02019)
		(width 0.0889)
		(layer "B.Cu")
		(net "H_CPU0_CATERR_G_N")
	)
	(segment
		(start 363.4994 -64.5668)
		(end 364.1598 -64.5668)
		(width 0.10795)
		(layer "B.Cu")
		(net "H_CPU0_CATERR_G_N")
	)
	(segment
		(start 374.513348 -54.726078)
		(end 374.32107 -54.5338)
		(width 0.10795)
		(layer "B.Cu")
		(net "H_CPU0_CATERR_G_N")
	)
	(segment
		(start 303.517554 -58.876184)
		(end 303.55286 -58.876184)
		(width 0.0889)
		(layer "B.Cu")
		(net "H_CPU0_CATERR_G_N")
	)
	(segment
		(start 300.3677 -60.8203)
		(end 300.82998 -60.35802)
		(width 0.0889)
		(layer "B.Cu")
		(net "H_CPU0_CATERR_G_N")
	)
	(segment
		(start 326.595486 -61.849)
		(end 327.025 -61.849)
		(width 0.10795)
		(layer "B.Cu")
		(net "H_CPU0_CATERR_G_N")
	)
	(segment
		(start 324.965822 -62.890908)
		(end 325.554848 -62.889638)
		(width 0.10795)
		(layer "B.Cu")
		(net "H_CPU0_CATERR_G_N")
	)
	(segment
		(start 374.513348 -55.162704)
		(end 374.513348 -54.726078)
		(width 0.10795)
		(layer "B.Cu")
		(net "H_CPU0_CATERR_G_N")
	)
	(segment
		(start 324.965822 -62.890908)
		(end 323.799454 -62.890908)
		(width 0.10795)
		(layer "B.Cu")
		(net "H_CPU0_CATERR_G_N")
	)
	(segment
		(start 309.188358 -57.5945)
		(end 309.567834 -57.215024)
		(width 0.10795)
		(layer "B.Cu")
		(net "H_CPU0_CATERR_G_N")
	)
	(segment
		(start 297.942 -64.1858)
		(end 298.2468 -63.881)
		(width 0.0889)
		(layer "B.Cu")
		(net "H_CPU0_CATERR_G_N")
	)
	(segment
		(start 361.699302 -58.030364)
		(end 361.699302 -58.759598)
		(width 0.10795)
		(layer "B.Cu")
		(net "H_CPU0_CATERR_G_N")
	)
	(segment
		(start 373.6975 -56.769)
		(end 374.05945 -56.769)
		(width 0.10795)
		(layer "B.Cu")
		(net "H_CPU0_CATERR_G_N")
	)
	(segment
		(start 298.8056 -62.684914)
		(end 298.903898 -62.586616)
		(width 0.0889)
		(layer "B.Cu")
		(net "H_CPU0_CATERR_G_N")
	)
	(arc
		(start 304.408332 -58.380884)
		(mid 304.603693 -58.332032)
		(end 304.763424 -58.209434)
		(width 0.0889)
		(layer "B.Cu")
		(net "H_CPU0_CATERR_G_N")
	)
	(arc
		(start 305.593496 -58.180986)
		(mid 306.105306 -58.476525)
		(end 306.617116 -58.180986)
		(width 0.0889)
		(layer "B.Cu")
		(net "H_CPU0_CATERR_G_N")
	)
	(arc
		(start 302.241966 -59.619134)
		(mid 302.416255 -59.441832)
		(end 302.654716 -59.371484)
		(width 0.0889)
		(layer "B.Cu")
		(net "H_CPU0_CATERR_G_N")
	)
	(arc
		(start 306.617116 -58.180986)
		(mid 306.757195 -58.03825)
		(end 306.94884 -57.981088)
		(width 0.0889)
		(layer "B.Cu")
		(net "H_CPU0_CATERR_G_N")
	)
	(arc
		(start 302.69434 -59.371484)
		(mid 302.92903 -59.299689)
		(end 303.100486 -59.124088)
		(width 0.0889)
		(layer "B.Cu")
		(net "H_CPU0_CATERR_G_N")
	)
	(arc
		(start 303.959006 -58.628788)
		(mid 304.138433 -58.448445)
		(end 304.383694 -58.380884)
		(width 0.0889)
		(layer "B.Cu")
		(net "H_CPU0_CATERR_G_N")
	)
	(arc
		(start 303.55286 -58.876184)
		(mid 303.78755 -58.804389)
		(end 303.959006 -58.628788)
		(width 0.0889)
		(layer "B.Cu")
		(net "H_CPU0_CATERR_G_N")
	)
	(arc
		(start 304.763424 -58.209434)
		(mid 304.97127 -58.041237)
		(end 305.2318 -57.981088)
		(width 0.0889)
		(layer "B.Cu")
		(net "H_CPU0_CATERR_G_N")
	)
	(arc
		(start 301.829216 -59.866784)
		(mid 302.067677 -59.796436)
		(end 302.241966 -59.619134)
		(width 0.0889)
		(layer "B.Cu")
		(net "H_CPU0_CATERR_G_N")
	)
	(arc
		(start 303.100486 -59.124088)
		(mid 303.276598 -58.945591)
		(end 303.517554 -58.876184)
		(width 0.0889)
		(layer "B.Cu")
		(net "H_CPU0_CATERR_G_N")
	)
	(arc
		(start 305.261772 -57.981088)
		(mid 305.453414 -58.038254)
		(end 305.593496 -58.180986)
		(width 0.0889)
		(layer "B.Cu")
		(net "H_CPU0_CATERR_G_N")
	)
	(segment
		(start 325.489316 -63.414402)
		(end 324.965822 -62.890908)
		(width 0.089408)
		(layer "In11.Cu")
		(net "H_CPU0_CATERR_G_N")
	)
	(segment
		(start 356.237032 -62.506098)
		(end 356.079044 -62.506098)
		(width 0.089408)
		(layer "In11.Cu")
		(net "H_CPU0_CATERR_G_N")
	)
	(segment
		(start 354.814378 -62.506352)
		(end 354.360226 -62.960504)
		(width 0.089408)
		(layer "In11.Cu")
		(net "H_CPU0_CATERR_G_N")
	)
	(segment
		(start 334.68564 -62.960504)
		(end 334.231742 -63.414402)
		(width 0.089408)
		(layer "In11.Cu")
		(net "H_CPU0_CATERR_G_N")
	)
	(segment
		(start 364.1598 -64.5668)
		(end 362.744766 -63.151766)
		(width 0.089408)
		(layer "In11.Cu")
		(net "H_CPU0_CATERR_G_N")
	)
	(segment
		(start 356.07879 -62.506352)
		(end 354.814378 -62.506352)
		(width 0.089408)
		(layer "In11.Cu")
		(net "H_CPU0_CATERR_G_N")
	)
	(segment
		(start 362.744766 -63.151766)
		(end 356.8827 -63.151766)
		(width 0.089408)
		(layer "In11.Cu")
		(net "H_CPU0_CATERR_G_N")
	)
	(segment
		(start 356.079044 -62.506098)
		(end 356.07879 -62.506352)
		(width 0.089408)
		(layer "In11.Cu")
		(net "H_CPU0_CATERR_G_N")
	)
	(segment
		(start 334.231742 -63.414402)
		(end 325.489316 -63.414402)
		(width 0.089408)
		(layer "In11.Cu")
		(net "H_CPU0_CATERR_G_N")
	)
	(segment
		(start 356.8827 -63.151766)
		(end 356.237032 -62.506098)
		(width 0.089408)
		(layer "In11.Cu")
		(net "H_CPU0_CATERR_G_N")
	)
	(segment
		(start 354.360226 -62.960504)
		(end 334.68564 -62.960504)
		(width 0.089408)
		(layer "In11.Cu")
		(net "H_CPU0_CATERR_G_N")
	)
	(segment
		(start 411.914086 -112.322356)
		(end 411.908244 -112.322356)
		(width 0.10795)
		(layer "F.Cu")
		(net "FM_THROTTLE_N")
	)
	(segment
		(start 407.060654 -112.848644)
		(end 407.0604 -112.848898)
		(width 0.10795)
		(layer "F.Cu")
		(net "FM_THROTTLE_N")
	)
	(segment
		(start 420.69004 -41.73474)
		(end 420.690294 -41.73474)
		(width 0.089408)
		(layer "F.Cu")
		(net "FM_THROTTLE_N")
	)
	(segment
		(start 408.62504 -112.32642)
		(end 408.62504 -112.48136)
		(width 0.10795)
		(layer "F.Cu")
		(net "FM_THROTTLE_N")
	)
	(segment
		(start 420.690294 -41.73474)
		(end 421.09009 -42.134536)
		(width 0.089408)
		(layer "F.Cu")
		(net "FM_THROTTLE_N")
	)
	(segment
		(start 408.257756 -112.848644)
		(end 407.060654 -112.848644)
		(width 0.10795)
		(layer "F.Cu")
		(net "FM_THROTTLE_N")
	)
	(segment
		(start 413.4612 -111.506)
		(end 415.645854 -111.506)
		(width 0.10795)
		(layer "F.Cu")
		(net "FM_THROTTLE_N")
	)
	(segment
		(start 417.27374 -112.27054)
		(end 419.73627 -109.80801)
		(width 0.10795)
		(layer "F.Cu")
		(net "FM_THROTTLE_N")
	)
	(segment
		(start 412.139892 -112.09655)
		(end 411.914086 -112.322356)
		(width 0.10795)
		(layer "F.Cu")
		(net "FM_THROTTLE_N")
	)
	(segment
		(start 413.3342 -111.9378)
		(end 413.17545 -112.09655)
		(width 0.10795)
		(layer "F.Cu")
		(net "FM_THROTTLE_N")
	)
	(segment
		(start 408.62504 -112.48136)
		(end 408.257756 -112.848644)
		(width 0.10795)
		(layer "F.Cu")
		(net "FM_THROTTLE_N")
	)
	(segment
		(start 411.381956 -112.848644)
		(end 409.147264 -112.848644)
		(width 0.10795)
		(layer "F.Cu")
		(net "FM_THROTTLE_N")
	)
	(segment
		(start 419.73627 -109.80801)
		(end 422.001696 -109.80801)
		(width 0.10795)
		(layer "F.Cu")
		(net "FM_THROTTLE_N")
	)
	(segment
		(start 413.3342 -111.633)
		(end 413.4612 -111.506)
		(width 0.10795)
		(layer "F.Cu")
		(net "FM_THROTTLE_N")
	)
	(segment
		(start 415.645854 -111.506)
		(end 416.410394 -112.27054)
		(width 0.10795)
		(layer "F.Cu")
		(net "FM_THROTTLE_N")
	)
	(segment
		(start 413.3342 -111.633)
		(end 413.3342 -111.9378)
		(width 0.10795)
		(layer "F.Cu")
		(net "FM_THROTTLE_N")
	)
	(segment
		(start 411.908244 -112.322356)
		(end 411.381956 -112.848644)
		(width 0.10795)
		(layer "F.Cu")
		(net "FM_THROTTLE_N")
	)
	(segment
		(start 409.147264 -112.848644)
		(end 408.62504 -112.32642)
		(width 0.10795)
		(layer "F.Cu")
		(net "FM_THROTTLE_N")
	)
	(segment
		(start 413.17545 -112.09655)
		(end 412.139892 -112.09655)
		(width 0.10795)
		(layer "F.Cu")
		(net "FM_THROTTLE_N")
	)
	(segment
		(start 416.410394 -112.27054)
		(end 417.27374 -112.27054)
		(width 0.10795)
		(layer "F.Cu")
		(net "FM_THROTTLE_N")
	)
	(segment
		(start 422.849548 -110.655862)
		(end 422.849548 -111.26089)
		(width 0.10795)
		(layer "F.Cu")
		(net "FM_THROTTLE_N")
	)
	(segment
		(start 422.001696 -109.80801)
		(end 422.849548 -110.655862)
		(width 0.10795)
		(layer "F.Cu")
		(net "FM_THROTTLE_N")
	)
	(via
		(at 397.887444 -46.04258)
		(size 0.508)
		(drill 0.254)
		(layers "F.Cu" "B.Cu")
		(net "FM_THROTTLE_N")
	)
	(via
		(at 421.09009 -42.134536)
		(size 0.4572)
		(drill 0.2032)
		(layers "F.Cu" "B.Cu")
		(net "FM_THROTTLE_N")
	)
	(via
		(at 389.221218 -90.55862)
		(size 0.508)
		(drill 0.254)
		(layers "F.Cu" "B.Cu")
		(net "FM_THROTTLE_N")
	)
	(via
		(at 407.0604 -112.848898)
		(size 0.508)
		(drill 0.254)
		(layers "F.Cu" "B.Cu")
		(net "FM_THROTTLE_N")
	)
	(via
		(at 392.69035 -99.322636)
		(size 0.508)
		(drill 0.254)
		(layers "F.Cu" "B.Cu")
		(net "FM_THROTTLE_N")
	)
	(via
		(at 422.849548 -111.26089)
		(size 0.508)
		(drill 0.254)
		(layers "F.Cu" "B.Cu")
		(net "FM_THROTTLE_N")
	)
	(via
		(at 422.115488 -85.98281)
		(size 0.6604)
		(drill 0.3302)
		(layers "F.Cu" "B.Cu")
		(net "FM_THROTTLE_N")
	)
	(segment
		(start 421.184578 -78.717394)
		(end 421.489378 -78.412594)
		(width 0.10795)
		(layer "B.Cu")
		(net "FM_THROTTLE_N")
	)
	(segment
		(start 386.76326 -45.7454)
		(end 397.229838 -45.7454)
		(width 0.10795)
		(layer "B.Cu")
		(net "FM_THROTTLE_N")
	)
	(segment
		(start 422.115488 -86.258908)
		(end 422.115488 -85.98281)
		(width 0.10795)
		(layer "B.Cu")
		(net "FM_THROTTLE_N")
	)
	(segment
		(start 422.350946 -110.762288)
		(end 422.350946 -103.930704)
		(width 0.10795)
		(layer "B.Cu")
		(net "FM_THROTTLE_N")
	)
	(segment
		(start 422.849548 -111.26089)
		(end 422.350946 -110.762288)
		(width 0.10795)
		(layer "B.Cu")
		(net "FM_THROTTLE_N")
	)
	(segment
		(start 422.966388 -103.315262)
		(end 422.966388 -97.080832)
		(width 0.10795)
		(layer "B.Cu")
		(net "FM_THROTTLE_N")
	)
	(segment
		(start 421.489378 -78.412594)
		(end 421.956992 -78.412594)
		(width 0.10795)
		(layer "B.Cu")
		(net "FM_THROTTLE_N")
	)
	(segment
		(start 422.238932 -95.463106)
		(end 422.475914 -95.226124)
		(width 0.10795)
		(layer "B.Cu")
		(net "FM_THROTTLE_N")
	)
	(segment
		(start 422.475914 -95.226124)
		(end 422.475914 -86.619334)
		(width 0.10795)
		(layer "B.Cu")
		(net "FM_THROTTLE_N")
	)
	(segment
		(start 386.709666 -45.691806)
		(end 386.76326 -45.7454)
		(width 0.10795)
		(layer "B.Cu")
		(net "FM_THROTTLE_N")
	)
	(segment
		(start 421.184578 -79.48295)
		(end 421.184578 -78.717394)
		(width 0.10795)
		(layer "B.Cu")
		(net "FM_THROTTLE_N")
	)
	(segment
		(start 422.115488 -85.292946)
		(end 422.646602 -84.761832)
		(width 0.10795)
		(layer "B.Cu")
		(net "FM_THROTTLE_N")
	)
	(segment
		(start 397.527018 -46.04258)
		(end 397.887444 -46.04258)
		(width 0.10795)
		(layer "B.Cu")
		(net "FM_THROTTLE_N")
	)
	(segment
		(start 422.966388 -97.080832)
		(end 422.238932 -96.353376)
		(width 0.10795)
		(layer "B.Cu")
		(net "FM_THROTTLE_N")
	)
	(segment
		(start 422.646602 -84.761832)
		(end 422.646602 -80.944974)
		(width 0.10795)
		(layer "B.Cu")
		(net "FM_THROTTLE_N")
	)
	(segment
		(start 422.115488 -85.98281)
		(end 422.115488 -85.292946)
		(width 0.10795)
		(layer "B.Cu")
		(net "FM_THROTTLE_N")
	)
	(segment
		(start 422.475914 -86.619334)
		(end 422.115488 -86.258908)
		(width 0.10795)
		(layer "B.Cu")
		(net "FM_THROTTLE_N")
	)
	(segment
		(start 422.238932 -96.353376)
		(end 422.238932 -95.463106)
		(width 0.10795)
		(layer "B.Cu")
		(net "FM_THROTTLE_N")
	)
	(segment
		(start 422.350946 -103.930704)
		(end 422.966388 -103.315262)
		(width 0.10795)
		(layer "B.Cu")
		(net "FM_THROTTLE_N")
	)
	(segment
		(start 422.646602 -80.944974)
		(end 421.184578 -79.48295)
		(width 0.10795)
		(layer "B.Cu")
		(net "FM_THROTTLE_N")
	)
	(segment
		(start 397.229838 -45.7454)
		(end 397.527018 -46.04258)
		(width 0.10795)
		(layer "B.Cu")
		(net "FM_THROTTLE_N")
	)
	(segment
		(start 407.00198 -43.51655)
		(end 406.845516 -43.360086)
		(width 0.089408)
		(layer "In2.Cu")
		(net "FM_THROTTLE_N")
	)
	(segment
		(start 410.67355 -43.51655)
		(end 407.00198 -43.51655)
		(width 0.089408)
		(layer "In2.Cu")
		(net "FM_THROTTLE_N")
	)
	(segment
		(start 420.290498 -42.134536)
		(end 419.463728 -42.961306)
		(width 0.089408)
		(layer "In2.Cu")
		(net "FM_THROTTLE_N")
	)
	(segment
		(start 406.845516 -43.360086)
		(end 404.810214 -43.360086)
		(width 0.089408)
		(layer "In2.Cu")
		(net "FM_THROTTLE_N")
	)
	(segment
		(start 419.463728 -42.961306)
		(end 418.188394 -42.961306)
		(width 0.089408)
		(layer "In2.Cu")
		(net "FM_THROTTLE_N")
	)
	(segment
		(start 411.5562 -44.3992)
		(end 410.67355 -43.51655)
		(width 0.089408)
		(layer "In2.Cu")
		(net "FM_THROTTLE_N")
	)
	(segment
		(start 421.09009 -42.134536)
		(end 420.290498 -42.134536)
		(width 0.089408)
		(layer "In2.Cu")
		(net "FM_THROTTLE_N")
	)
	(segment
		(start 415.3916 -44.3992)
		(end 411.5562 -44.3992)
		(width 0.089408)
		(layer "In2.Cu")
		(net "FM_THROTTLE_N")
	)
	(segment
		(start 402.02866 -46.14164)
		(end 397.986504 -46.14164)
		(width 0.089408)
		(layer "In2.Cu")
		(net "FM_THROTTLE_N")
	)
	(segment
		(start 417.8173 -43.3324)
		(end 416.4584 -43.3324)
		(width 0.089408)
		(layer "In2.Cu")
		(net "FM_THROTTLE_N")
	)
	(segment
		(start 416.4584 -43.3324)
		(end 415.3916 -44.3992)
		(width 0.089408)
		(layer "In2.Cu")
		(net "FM_THROTTLE_N")
	)
	(segment
		(start 397.986504 -46.14164)
		(end 397.887444 -46.04258)
		(width 0.089408)
		(layer "In2.Cu")
		(net "FM_THROTTLE_N")
	)
	(segment
		(start 418.188394 -42.961306)
		(end 417.8173 -43.3324)
		(width 0.089408)
		(layer "In2.Cu")
		(net "FM_THROTTLE_N")
	)
	(segment
		(start 404.810214 -43.360086)
		(end 402.02866 -46.14164)
		(width 0.089408)
		(layer "In2.Cu")
		(net "FM_THROTTLE_N")
	)
	(segment
		(start 393.19454 -102.811326)
		(end 393.599924 -103.21671)
		(width 0.0889)
		(layer "In4.Cu")
		(net "FM_THROTTLE_N")
	)
	(segment
		(start 392.69035 -102.10419)
		(end 393.19454 -102.60838)
		(width 0.0889)
		(layer "In4.Cu")
		(net "FM_THROTTLE_N")
	)
	(segment
		(start 397.941038 -103.21671)
		(end 398.002506 -103.155242)
		(width 0.0889)
		(layer "In4.Cu")
		(net "FM_THROTTLE_N")
	)
	(segment
		(start 393.19454 -102.60838)
		(end 393.19454 -102.811326)
		(width 0.0889)
		(layer "In4.Cu")
		(net "FM_THROTTLE_N")
	)
	(segment
		(start 405.3586 -111.147098)
		(end 407.0604 -112.848898)
		(width 0.089408)
		(layer "In4.Cu")
		(net "FM_THROTTLE_N")
	)
	(segment
		(start 399.460974 -103.155242)
		(end 399.913856 -103.608124)
		(width 0.0889)
		(layer "In4.Cu")
		(net "FM_THROTTLE_N")
	)
	(segment
		(start 405.3586 -109.847634)
		(end 405.3586 -111.147098)
		(width 0.089408)
		(layer "In4.Cu")
		(net "FM_THROTTLE_N")
	)
	(segment
		(start 398.002506 -103.155242)
		(end 399.460974 -103.155242)
		(width 0.0889)
		(layer "In4.Cu")
		(net "FM_THROTTLE_N")
	)
	(segment
		(start 391.79627 -100.015802)
		(end 391.79627 -100.45065)
		(width 0.089408)
		(layer "In4.Cu")
		(net "FM_THROTTLE_N")
	)
	(segment
		(start 392.489436 -99.322636)
		(end 391.79627 -100.015802)
		(width 0.089408)
		(layer "In4.Cu")
		(net "FM_THROTTLE_N")
	)
	(segment
		(start 400.52244 -104.216708)
		(end 400.52244 -105.987596)
		(width 0.089408)
		(layer "In4.Cu")
		(net "FM_THROTTLE_N")
	)
	(segment
		(start 404.578566 -109.0676)
		(end 405.3586 -109.847634)
		(width 0.089408)
		(layer "In4.Cu")
		(net "FM_THROTTLE_N")
	)
	(segment
		(start 400.52244 -105.987596)
		(end 403.602444 -109.0676)
		(width 0.089408)
		(layer "In4.Cu")
		(net "FM_THROTTLE_N")
	)
	(segment
		(start 399.913856 -103.608124)
		(end 400.52244 -104.216708)
		(width 0.089408)
		(layer "In4.Cu")
		(net "FM_THROTTLE_N")
	)
	(segment
		(start 392.69035 -101.77907)
		(end 392.69035 -102.10419)
		(width 0.089408)
		(layer "In4.Cu")
		(net "FM_THROTTLE_N")
	)
	(segment
		(start 391.79627 -100.45065)
		(end 392.21283 -100.86721)
		(width 0.089408)
		(layer "In4.Cu")
		(net "FM_THROTTLE_N")
	)
	(segment
		(start 403.602444 -109.0676)
		(end 404.578566 -109.0676)
		(width 0.089408)
		(layer "In4.Cu")
		(net "FM_THROTTLE_N")
	)
	(segment
		(start 392.69035 -99.322636)
		(end 392.489436 -99.322636)
		(width 0.089408)
		(layer "In4.Cu")
		(net "FM_THROTTLE_N")
	)
	(segment
		(start 392.21283 -101.30155)
		(end 392.69035 -101.77907)
		(width 0.089408)
		(layer "In4.Cu")
		(net "FM_THROTTLE_N")
	)
	(segment
		(start 392.21283 -100.86721)
		(end 392.21283 -101.30155)
		(width 0.089408)
		(layer "In4.Cu")
		(net "FM_THROTTLE_N")
	)
	(segment
		(start 393.599924 -103.21671)
		(end 397.941038 -103.21671)
		(width 0.0889)
		(layer "In4.Cu")
		(net "FM_THROTTLE_N")
	)
	(segment
		(start 393.151106 -83.368134)
		(end 393.808712 -82.710528)
		(width 0.089408)
		(layer "In9.Cu")
		(net "FM_THROTTLE_N")
	)
	(segment
		(start 398.170654 -46.900592)
		(end 398.170654 -46.32579)
		(width 0.089408)
		(layer "In9.Cu")
		(net "FM_THROTTLE_N")
	)
	(segment
		(start 398.25803 -61.767212)
		(end 398.25803 -60.658248)
		(width 0.089408)
		(layer "In9.Cu")
		(net "FM_THROTTLE_N")
	)
	(segment
		(start 398.257776 -61.838332)
		(end 398.257776 -61.767466)
		(width 0.089408)
		(layer "In9.Cu")
		(net "FM_THROTTLE_N")
	)
	(segment
		(start 389.418068 -90.36177)
		(end 389.418068 -88.502998)
		(width 0.089408)
		(layer "In9.Cu")
		(net "FM_THROTTLE_N")
	)
	(segment
		(start 394.417804 -81.687162)
		(end 394.417804 -81.122774)
		(width 0.089408)
		(layer "In9.Cu")
		(net "FM_THROTTLE_N")
	)
	(segment
		(start 398.257776 -60.657994)
		(end 398.257776 -58.69178)
		(width 0.089408)
		(layer "In9.Cu")
		(net "FM_THROTTLE_N")
	)
	(segment
		(start 396.614142 -69.672454)
		(end 396.614142 -65.294002)
		(width 0.089408)
		(layer "In9.Cu")
		(net "FM_THROTTLE_N")
	)
	(segment
		(start 398.25803 -60.658248)
		(end 398.257776 -60.657994)
		(width 0.089408)
		(layer "In9.Cu")
		(net "FM_THROTTLE_N")
	)
	(segment
		(start 398.257776 -61.767466)
		(end 398.25803 -61.767212)
		(width 0.089408)
		(layer "In9.Cu")
		(net "FM_THROTTLE_N")
	)
	(segment
		(start 392.005312 -85.915754)
		(end 392.005312 -84.67217)
		(width 0.089408)
		(layer "In9.Cu")
		(net "FM_THROTTLE_N")
	)
	(segment
		(start 389.418068 -88.502998)
		(end 392.005312 -85.915754)
		(width 0.089408)
		(layer "In9.Cu")
		(net "FM_THROTTLE_N")
	)
	(segment
		(start 394.055092 -80.760062)
		(end 394.055092 -79.480664)
		(width 0.089408)
		(layer "In9.Cu")
		(net "FM_THROTTLE_N")
	)
	(segment
		(start 394.055092 -79.480664)
		(end 393.465304 -78.890876)
		(width 0.089408)
		(layer "In9.Cu")
		(net "FM_THROTTLE_N")
	)
	(segment
		(start 398.257776 -58.69178)
		(end 397.944086 -58.37809)
		(width 0.089408)
		(layer "In9.Cu")
		(net "FM_THROTTLE_N")
	)
	(segment
		(start 394.417804 -81.122774)
		(end 394.055092 -80.760062)
		(width 0.089408)
		(layer "In9.Cu")
		(net "FM_THROTTLE_N")
	)
	(segment
		(start 395.319504 -76.135992)
		(end 395.319504 -70.967092)
		(width 0.089408)
		(layer "In9.Cu")
		(net "FM_THROTTLE_N")
	)
	(segment
		(start 397.036544 -64.8716)
		(end 397.399764 -64.8716)
		(width 0.089408)
		(layer "In9.Cu")
		(net "FM_THROTTLE_N")
	)
	(segment
		(start 394.002768 -77.786992)
		(end 394.002768 -77.452728)
		(width 0.089408)
		(layer "In9.Cu")
		(net "FM_THROTTLE_N")
	)
	(segment
		(start 397.90116 -64.370204)
		(end 397.90116 -62.194948)
		(width 0.089408)
		(layer "In9.Cu")
		(net "FM_THROTTLE_N")
	)
	(segment
		(start 393.465304 -78.324456)
		(end 394.002768 -77.786992)
		(width 0.089408)
		(layer "In9.Cu")
		(net "FM_THROTTLE_N")
	)
	(segment
		(start 393.09167 -83.368134)
		(end 393.151106 -83.368134)
		(width 0.089408)
		(layer "In9.Cu")
		(net "FM_THROTTLE_N")
	)
	(segment
		(start 397.944086 -58.37809)
		(end 397.944086 -47.12716)
		(width 0.089408)
		(layer "In9.Cu")
		(net "FM_THROTTLE_N")
	)
	(segment
		(start 397.399764 -64.8716)
		(end 397.90116 -64.370204)
		(width 0.089408)
		(layer "In9.Cu")
		(net "FM_THROTTLE_N")
	)
	(segment
		(start 394.002768 -77.452728)
		(end 395.319504 -76.135992)
		(width 0.089408)
		(layer "In9.Cu")
		(net "FM_THROTTLE_N")
	)
	(segment
		(start 392.110468 -84.567014)
		(end 392.110468 -84.349336)
		(width 0.089408)
		(layer "In9.Cu")
		(net "FM_THROTTLE_N")
	)
	(segment
		(start 392.110468 -84.349336)
		(end 393.09167 -83.368134)
		(width 0.089408)
		(layer "In9.Cu")
		(net "FM_THROTTLE_N")
	)
	(segment
		(start 397.90116 -62.194948)
		(end 398.257776 -61.838332)
		(width 0.089408)
		(layer "In9.Cu")
		(net "FM_THROTTLE_N")
	)
	(segment
		(start 392.005312 -84.67217)
		(end 392.110468 -84.567014)
		(width 0.089408)
		(layer "In9.Cu")
		(net "FM_THROTTLE_N")
	)
	(segment
		(start 398.170654 -46.32579)
		(end 397.887444 -46.04258)
		(width 0.089408)
		(layer "In9.Cu")
		(net "FM_THROTTLE_N")
	)
	(segment
		(start 395.319504 -70.967092)
		(end 396.614142 -69.672454)
		(width 0.089408)
		(layer "In9.Cu")
		(net "FM_THROTTLE_N")
	)
	(segment
		(start 389.221218 -90.55862)
		(end 389.418068 -90.36177)
		(width 0.089408)
		(layer "In9.Cu")
		(net "FM_THROTTLE_N")
	)
	(segment
		(start 396.614142 -65.294002)
		(end 397.036544 -64.8716)
		(width 0.089408)
		(layer "In9.Cu")
		(net "FM_THROTTLE_N")
	)
	(segment
		(start 393.808712 -82.710528)
		(end 393.808712 -82.296254)
		(width 0.089408)
		(layer "In9.Cu")
		(net "FM_THROTTLE_N")
	)
	(segment
		(start 397.944086 -47.12716)
		(end 398.170654 -46.900592)
		(width 0.089408)
		(layer "In9.Cu")
		(net "FM_THROTTLE_N")
	)
	(segment
		(start 393.808712 -82.296254)
		(end 394.417804 -81.687162)
		(width 0.089408)
		(layer "In9.Cu")
		(net "FM_THROTTLE_N")
	)
	(segment
		(start 393.465304 -78.890876)
		(end 393.465304 -78.324456)
		(width 0.089408)
		(layer "In9.Cu")
		(net "FM_THROTTLE_N")
	)
	(segment
		(start 391.287 -95.9358)
		(end 391.6426 -96.2914)
		(width 0.089408)
		(layer "In11.Cu")
		(net "FM_THROTTLE_N")
	)
	(segment
		(start 391.287 -95.4532)
		(end 391.287 -95.9358)
		(width 0.089408)
		(layer "In11.Cu")
		(net "FM_THROTTLE_N")
	)
	(segment
		(start 392.684 -98.298)
		(end 392.684 -99.316286)
		(width 0.089408)
		(layer "In11.Cu")
		(net "FM_THROTTLE_N")
	)
	(segment
		(start 391.6426 -96.7994)
		(end 392.2014 -97.3582)
		(width 0.089408)
		(layer "In11.Cu")
		(net "FM_THROTTLE_N")
	)
	(segment
		(start 392.684 -99.316286)
		(end 392.69035 -99.322636)
		(width 0.089408)
		(layer "In11.Cu")
		(net "FM_THROTTLE_N")
	)
	(segment
		(start 391.6426 -96.2914)
		(end 391.6426 -96.7994)
		(width 0.089408)
		(layer "In11.Cu")
		(net "FM_THROTTLE_N")
	)
	(segment
		(start 389.03529 -93.20149)
		(end 391.287 -95.4532)
		(width 0.089408)
		(layer "In11.Cu")
		(net "FM_THROTTLE_N")
	)
	(segment
		(start 392.2014 -97.8154)
		(end 392.684 -98.298)
		(width 0.089408)
		(layer "In11.Cu")
		(net "FM_THROTTLE_N")
	)
	(segment
		(start 389.03529 -90.744548)
		(end 389.03529 -93.20149)
		(width 0.089408)
		(layer "In11.Cu")
		(net "FM_THROTTLE_N")
	)
	(segment
		(start 389.221218 -90.55862)
		(end 389.03529 -90.744548)
		(width 0.089408)
		(layer "In11.Cu")
		(net "FM_THROTTLE_N")
	)
	(segment
		(start 392.2014 -97.3582)
		(end 392.2014 -97.8154)
		(width 0.089408)
		(layer "In11.Cu")
		(net "FM_THROTTLE_N")
	)
	(segment
		(start 165.66642 -123.87326)
		(end 166.44874 -123.87326)
		(width 0.10795)
		(layer "F.Cu")
		(net "FM_SYS_THROTTLE_LVC3")
	)
	(segment
		(start 163.88842 -123.87326)
		(end 165.66642 -123.87326)
		(width 0.10795)
		(layer "F.Cu")
		(net "FM_SYS_THROTTLE_LVC3")
	)
	(segment
		(start 166.44874 -123.87326)
		(end 166.6494 -123.6726)
		(width 0.10795)
		(layer "F.Cu")
		(net "FM_SYS_THROTTLE_LVC3")
	)
	(via
		(at 376.429016 -56.510682)
		(size 0.508)
		(drill 0.254)
		(layers "F.Cu" "B.Cu")
		(net "FM_SYS_THROTTLE_LVC3")
	)
	(via
		(at 186.352434 -19.154648)
		(size 0.508)
		(drill 0.254)
		(layers "F.Cu" "B.Cu")
		(net "FM_SYS_THROTTLE_LVC3")
	)
	(via
		(at 395.1732 -42.4942)
		(size 0.6604)
		(drill 0.3302)
		(layers "F.Cu" "B.Cu")
		(net "FM_SYS_THROTTLE_LVC3")
	)
	(via
		(at 166.6494 -123.6726)
		(size 0.508)
		(drill 0.254)
		(layers "F.Cu" "B.Cu")
		(net "FM_SYS_THROTTLE_LVC3")
	)
	(via
		(at 378.20981 -45.677328)
		(size 0.508)
		(drill 0.254)
		(layers "F.Cu" "B.Cu")
		(net "FM_SYS_THROTTLE_LVC3")
	)
	(segment
		(start 395.1732 -42.4942)
		(end 394.7922 -42.8752)
		(width 0.10795)
		(layer "B.Cu")
		(net "FM_SYS_THROTTLE_LVC3")
	)
	(segment
		(start 383.082546 -43.738546)
		(end 383.2225 -43.8785)
		(width 0.10795)
		(layer "B.Cu")
		(net "FM_SYS_THROTTLE_LVC3")
	)
	(segment
		(start 389.90651 -44.224448)
		(end 388.12851 -44.224448)
		(width 0.10795)
		(layer "B.Cu")
		(net "FM_SYS_THROTTLE_LVC3")
	)
	(segment
		(start 378.7902 -44.506896)
		(end 378.672598 -44.624498)
		(width 0.10795)
		(layer "B.Cu")
		(net "FM_SYS_THROTTLE_LVC3")
	)
	(segment
		(start 383.2225 -43.8785)
		(end 383.2225 -44.196)
		(width 0.10795)
		(layer "B.Cu")
		(net "FM_SYS_THROTTLE_LVC3")
	)
	(segment
		(start 387.238494 -43.591988)
		(end 387.238494 -44.03344)
		(width 0.10795)
		(layer "B.Cu")
		(net "FM_SYS_THROTTLE_LVC3")
	)
	(segment
		(start 383.2225 -44.196)
		(end 383.644902 -44.196)
		(width 0.10795)
		(layer "B.Cu")
		(net "FM_SYS_THROTTLE_LVC3")
	)
	(segment
		(start 391.573512 -44.249848)
		(end 389.93191 -44.249848)
		(width 0.10795)
		(layer "B.Cu")
		(net "FM_SYS_THROTTLE_LVC3")
	)
	(segment
		(start 387.429502 -44.224448)
		(end 388.12851 -44.224448)
		(width 0.10795)
		(layer "B.Cu")
		(net "FM_SYS_THROTTLE_LVC3")
	)
	(segment
		(start 383.644902 -44.196)
		(end 383.759964 -44.080938)
		(width 0.10795)
		(layer "B.Cu")
		(net "FM_SYS_THROTTLE_LVC3")
	)
	(segment
		(start 387.238494 -44.03344)
		(end 387.429502 -44.224448)
		(width 0.10795)
		(layer "B.Cu")
		(net "FM_SYS_THROTTLE_LVC3")
	)
	(segment
		(start 379.77699 -44.022264)
		(end 379.77699 -44.122086)
		(width 0.10795)
		(layer "B.Cu")
		(net "FM_SYS_THROTTLE_LVC3")
	)
	(segment
		(start 384.6195 -43.0784)
		(end 386.724906 -43.0784)
		(width 0.10795)
		(layer "B.Cu")
		(net "FM_SYS_THROTTLE_LVC3")
	)
	(segment
		(start 383.759964 -44.080938)
		(end 383.759964 -43.407584)
		(width 0.10795)
		(layer "B.Cu")
		(net "FM_SYS_THROTTLE_LVC3")
	)
	(segment
		(start 384.434588 -43.263312)
		(end 384.6195 -43.0784)
		(width 0.10795)
		(layer "B.Cu")
		(net "FM_SYS_THROTTLE_LVC3")
	)
	(segment
		(start 381.5334 -43.7515)
		(end 381.546354 -43.738546)
		(width 0.10795)
		(layer "B.Cu")
		(net "FM_SYS_THROTTLE_LVC3")
	)
	(segment
		(start 394.484352 -44.249848)
		(end 393.351512 -44.249848)
		(width 0.10795)
		(layer "B.Cu")
		(net "FM_SYS_THROTTLE_LVC3")
	)
	(segment
		(start 380.047754 -43.7515)
		(end 379.77699 -44.022264)
		(width 0.10795)
		(layer "B.Cu")
		(net "FM_SYS_THROTTLE_LVC3")
	)
	(segment
		(start 386.724906 -43.0784)
		(end 387.238494 -43.591988)
		(width 0.10795)
		(layer "B.Cu")
		(net "FM_SYS_THROTTLE_LVC3")
	)
	(segment
		(start 383.759964 -43.407584)
		(end 383.615692 -43.263312)
		(width 0.10795)
		(layer "B.Cu")
		(net "FM_SYS_THROTTLE_LVC3")
	)
	(segment
		(start 379.39218 -44.506896)
		(end 378.7902 -44.506896)
		(width 0.10795)
		(layer "B.Cu")
		(net "FM_SYS_THROTTLE_LVC3")
	)
	(segment
		(start 393.351512 -44.249848)
		(end 391.573512 -44.249848)
		(width 0.10795)
		(layer "B.Cu")
		(net "FM_SYS_THROTTLE_LVC3")
	)
	(segment
		(start 394.7922 -42.8752)
		(end 394.7922 -43.942)
		(width 0.10795)
		(layer "B.Cu")
		(net "FM_SYS_THROTTLE_LVC3")
	)
	(segment
		(start 378.672598 -44.624498)
		(end 378.672598 -45.21454)
		(width 0.10795)
		(layer "B.Cu")
		(net "FM_SYS_THROTTLE_LVC3")
	)
	(segment
		(start 394.7922 -43.942)
		(end 394.484352 -44.249848)
		(width 0.10795)
		(layer "B.Cu")
		(net "FM_SYS_THROTTLE_LVC3")
	)
	(segment
		(start 380.3904 -43.7515)
		(end 380.047754 -43.7515)
		(width 0.10795)
		(layer "B.Cu")
		(net "FM_SYS_THROTTLE_LVC3")
	)
	(segment
		(start 389.93191 -44.249848)
		(end 389.90651 -44.224448)
		(width 0.10795)
		(layer "B.Cu")
		(net "FM_SYS_THROTTLE_LVC3")
	)
	(segment
		(start 383.615692 -43.263312)
		(end 384.434588 -43.263312)
		(width 0.10795)
		(layer "B.Cu")
		(net "FM_SYS_THROTTLE_LVC3")
	)
	(segment
		(start 380.3904 -43.7515)
		(end 381.5334 -43.7515)
		(width 0.10795)
		(layer "B.Cu")
		(net "FM_SYS_THROTTLE_LVC3")
	)
	(segment
		(start 378.672598 -45.21454)
		(end 378.20981 -45.677328)
		(width 0.10795)
		(layer "B.Cu")
		(net "FM_SYS_THROTTLE_LVC3")
	)
	(segment
		(start 381.546354 -43.738546)
		(end 383.082546 -43.738546)
		(width 0.10795)
		(layer "B.Cu")
		(net "FM_SYS_THROTTLE_LVC3")
	)
	(segment
		(start 379.77699 -44.122086)
		(end 379.39218 -44.506896)
		(width 0.10795)
		(layer "B.Cu")
		(net "FM_SYS_THROTTLE_LVC3")
	)
	(segment
		(start 169.09034 -120.87098)
		(end 167.513 -119.29364)
		(width 0.089408)
		(layer "In2.Cu")
		(net "FM_SYS_THROTTLE_LVC3")
	)
	(segment
		(start 167.9702 -123.444)
		(end 169.09034 -122.32386)
		(width 0.089408)
		(layer "In2.Cu")
		(net "FM_SYS_THROTTLE_LVC3")
	)
	(segment
		(start 163.83762 -62.7634)
		(end 162.58286 -62.7634)
		(width 0.089408)
		(layer "In2.Cu")
		(net "FM_SYS_THROTTLE_LVC3")
	)
	(segment
		(start 166.6494 -123.6726)
		(end 166.83736 -123.6726)
		(width 0.089408)
		(layer "In2.Cu")
		(net "FM_SYS_THROTTLE_LVC3")
	)
	(segment
		(start 165.826948 -47.663608)
		(end 181.388004 -47.663608)
		(width 0.089408)
		(layer "In2.Cu")
		(net "FM_SYS_THROTTLE_LVC3")
	)
	(segment
		(start 173.116748 -60.799472)
		(end 165.801548 -60.799472)
		(width 0.089408)
		(layer "In2.Cu")
		(net "FM_SYS_THROTTLE_LVC3")
	)
	(segment
		(start 167.513 -119.29364)
		(end 167.513 -106.45648)
		(width 0.089408)
		(layer "In2.Cu")
		(net "FM_SYS_THROTTLE_LVC3")
	)
	(segment
		(start 176.211992 -70.537832)
		(end 175.09236 -69.4182)
		(width 0.089408)
		(layer "In2.Cu")
		(net "FM_SYS_THROTTLE_LVC3")
	)
	(segment
		(start 162.58286 -62.7634)
		(end 162.07232 -62.25286)
		(width 0.089408)
		(layer "In2.Cu")
		(net "FM_SYS_THROTTLE_LVC3")
	)
	(segment
		(start 165.801548 -60.799472)
		(end 163.83762 -62.7634)
		(width 0.089408)
		(layer "In2.Cu")
		(net "FM_SYS_THROTTLE_LVC3")
	)
	(segment
		(start 185.029348 -44.022264)
		(end 185.029348 -20.964652)
		(width 0.089408)
		(layer "In2.Cu")
		(net "FM_SYS_THROTTLE_LVC3")
	)
	(segment
		(start 181.388004 -47.663608)
		(end 185.029348 -44.022264)
		(width 0.089408)
		(layer "In2.Cu")
		(net "FM_SYS_THROTTLE_LVC3")
	)
	(segment
		(start 173.98492 -97.22866)
		(end 176.01946 -95.19412)
		(width 0.089408)
		(layer "In2.Cu")
		(net "FM_SYS_THROTTLE_LVC3")
	)
	(segment
		(start 174.32528 -69.4182)
		(end 171.99356 -67.08648)
		(width 0.089408)
		(layer "In2.Cu")
		(net "FM_SYS_THROTTLE_LVC3")
	)
	(segment
		(start 185.029348 -20.964652)
		(end 186.352434 -19.641566)
		(width 0.089408)
		(layer "In2.Cu")
		(net "FM_SYS_THROTTLE_LVC3")
	)
	(segment
		(start 167.06596 -123.444)
		(end 167.9702 -123.444)
		(width 0.089408)
		(layer "In2.Cu")
		(net "FM_SYS_THROTTLE_LVC3")
	)
	(segment
		(start 174.381668 -63.537592)
		(end 174.381668 -62.064392)
		(width 0.089408)
		(layer "In2.Cu")
		(net "FM_SYS_THROTTLE_LVC3")
	)
	(segment
		(start 161.331148 -58.766456)
		(end 161.331148 -52.159408)
		(width 0.089408)
		(layer "In2.Cu")
		(net "FM_SYS_THROTTLE_LVC3")
	)
	(segment
		(start 175.09236 -69.4182)
		(end 174.32528 -69.4182)
		(width 0.089408)
		(layer "In2.Cu")
		(net "FM_SYS_THROTTLE_LVC3")
	)
	(segment
		(start 174.381668 -62.064392)
		(end 173.116748 -60.799472)
		(width 0.089408)
		(layer "In2.Cu")
		(net "FM_SYS_THROTTLE_LVC3")
	)
	(segment
		(start 167.513 -106.45648)
		(end 173.98492 -99.98456)
		(width 0.089408)
		(layer "In2.Cu")
		(net "FM_SYS_THROTTLE_LVC3")
	)
	(segment
		(start 169.09034 -122.32386)
		(end 169.09034 -120.87098)
		(width 0.089408)
		(layer "In2.Cu")
		(net "FM_SYS_THROTTLE_LVC3")
	)
	(segment
		(start 186.352434 -19.641566)
		(end 186.352434 -19.154648)
		(width 0.089408)
		(layer "In2.Cu")
		(net "FM_SYS_THROTTLE_LVC3")
	)
	(segment
		(start 176.211992 -73.208388)
		(end 176.211992 -70.537832)
		(width 0.089408)
		(layer "In2.Cu")
		(net "FM_SYS_THROTTLE_LVC3")
	)
	(segment
		(start 162.07232 -59.507628)
		(end 161.331148 -58.766456)
		(width 0.089408)
		(layer "In2.Cu")
		(net "FM_SYS_THROTTLE_LVC3")
	)
	(segment
		(start 166.83736 -123.6726)
		(end 167.06596 -123.444)
		(width 0.089408)
		(layer "In2.Cu")
		(net "FM_SYS_THROTTLE_LVC3")
	)
	(segment
		(start 162.07232 -62.25286)
		(end 162.07232 -59.507628)
		(width 0.089408)
		(layer "In2.Cu")
		(net "FM_SYS_THROTTLE_LVC3")
	)
	(segment
		(start 171.99356 -67.08648)
		(end 171.99356 -65.9257)
		(width 0.089408)
		(layer "In2.Cu")
		(net "FM_SYS_THROTTLE_LVC3")
	)
	(segment
		(start 176.01946 -95.19412)
		(end 176.01946 -73.40092)
		(width 0.089408)
		(layer "In2.Cu")
		(net "FM_SYS_THROTTLE_LVC3")
	)
	(segment
		(start 171.99356 -65.9257)
		(end 174.381668 -63.537592)
		(width 0.089408)
		(layer "In2.Cu")
		(net "FM_SYS_THROTTLE_LVC3")
	)
	(segment
		(start 161.331148 -52.159408)
		(end 165.826948 -47.663608)
		(width 0.089408)
		(layer "In2.Cu")
		(net "FM_SYS_THROTTLE_LVC3")
	)
	(segment
		(start 176.01946 -73.40092)
		(end 176.211992 -73.208388)
		(width 0.089408)
		(layer "In2.Cu")
		(net "FM_SYS_THROTTLE_LVC3")
	)
	(segment
		(start 173.98492 -99.98456)
		(end 173.98492 -97.22866)
		(width 0.089408)
		(layer "In2.Cu")
		(net "FM_SYS_THROTTLE_LVC3")
	)
	(segment
		(start 378.220224 -45.734478)
		(end 378.220224 -45.677328)
		(width 0.089408)
		(layer "In9.Cu")
		(net "FM_SYS_THROTTLE_LVC3")
	)
	(segment
		(start 373.898414 -49.43856)
		(end 376.661172 -46.675802)
		(width 0.089408)
		(layer "In9.Cu")
		(net "FM_SYS_THROTTLE_LVC3")
	)
	(segment
		(start 378.220224 -45.677328)
		(end 378.20981 -45.677328)
		(width 0.089408)
		(layer "In9.Cu")
		(net "FM_SYS_THROTTLE_LVC3")
	)
	(segment
		(start 376.429016 -56.510682)
		(end 376.35688 -56.438546)
		(width 0.089408)
		(layer "In9.Cu")
		(net "FM_SYS_THROTTLE_LVC3")
	)
	(segment
		(start 376.35688 -56.438546)
		(end 376.35688 -55.805324)
		(width 0.089408)
		(layer "In9.Cu")
		(net "FM_SYS_THROTTLE_LVC3")
	)
	(segment
		(start 375.58599 -55.034434)
		(end 375.089166 -55.034434)
		(width 0.089408)
		(layer "In9.Cu")
		(net "FM_SYS_THROTTLE_LVC3")
	)
	(segment
		(start 375.089166 -55.034434)
		(end 373.898414 -53.843682)
		(width 0.089408)
		(layer "In9.Cu")
		(net "FM_SYS_THROTTLE_LVC3")
	)
	(segment
		(start 376.35688 -55.805324)
		(end 375.58599 -55.034434)
		(width 0.089408)
		(layer "In9.Cu")
		(net "FM_SYS_THROTTLE_LVC3")
	)
	(segment
		(start 373.898414 -53.843682)
		(end 373.898414 -49.43856)
		(width 0.089408)
		(layer "In9.Cu")
		(net "FM_SYS_THROTTLE_LVC3")
	)
	(segment
		(start 377.2789 -46.675802)
		(end 378.220224 -45.734478)
		(width 0.089408)
		(layer "In9.Cu")
		(net "FM_SYS_THROTTLE_LVC3")
	)
	(segment
		(start 376.661172 -46.675802)
		(end 377.2789 -46.675802)
		(width 0.089408)
		(layer "In9.Cu")
		(net "FM_SYS_THROTTLE_LVC3")
	)
	(segment
		(start 324.347078 3.014472)
		(end 323.176138 3.014472)
		(width 0.089408)
		(layer "In11.Cu")
		(net "FM_SYS_THROTTLE_LVC3")
	)
	(segment
		(start 187.2742 -18.232882)
		(end 186.352434 -19.154648)
		(width 0.089408)
		(layer "In11.Cu")
		(net "FM_SYS_THROTTLE_LVC3")
	)
	(segment
		(start 192.874392 -12.27582)
		(end 189.148212 -16.002)
		(width 0.089408)
		(layer "In11.Cu")
		(net "FM_SYS_THROTTLE_LVC3")
	)
	(segment
		(start 376.1232 -56.204866)
		(end 373.648478 -56.204866)
		(width 0.089408)
		(layer "In11.Cu")
		(net "FM_SYS_THROTTLE_LVC3")
	)
	(segment
		(start 192.874392 -6.219952)
		(end 192.874392 -12.27582)
		(width 0.089408)
		(layer "In11.Cu")
		(net "FM_SYS_THROTTLE_LVC3")
	)
	(segment
		(start 328.182986 -32.399986)
		(end 327.292208 -31.509208)
		(width 0.089408)
		(layer "In11.Cu")
		(net "FM_SYS_THROTTLE_LVC3")
	)
	(segment
		(start 327.292208 -27.537664)
		(end 324.388734 -24.63419)
		(width 0.089408)
		(layer "In11.Cu")
		(net "FM_SYS_THROTTLE_LVC3")
	)
	(segment
		(start 324.388734 -24.63419)
		(end 324.388734 -16.641826)
		(width 0.089408)
		(layer "In11.Cu")
		(net "FM_SYS_THROTTLE_LVC3")
	)
	(segment
		(start 353.352608 -41.47947)
		(end 336.594958 -41.47947)
		(width 0.089408)
		(layer "In11.Cu")
		(net "FM_SYS_THROTTLE_LVC3")
	)
	(segment
		(start 329.876404 -13.683996)
		(end 329.876404 -11.731498)
		(width 0.089408)
		(layer "In11.Cu")
		(net "FM_SYS_THROTTLE_LVC3")
	)
	(segment
		(start 324.5866 -9.218676)
		(end 324.5866 2.43205)
		(width 0.089408)
		(layer "In11.Cu")
		(net "FM_SYS_THROTTLE_LVC3")
	)
	(segment
		(start 192.913 -5.746242)
		(end 192.913 -6.181344)
		(width 0.089408)
		(layer "In11.Cu")
		(net "FM_SYS_THROTTLE_LVC3")
	)
	(segment
		(start 323.176138 3.014472)
		(end 322.029582 4.161028)
		(width 0.089408)
		(layer "In11.Cu")
		(net "FM_SYS_THROTTLE_LVC3")
	)
	(segment
		(start 326.030844 -14.999716)
		(end 328.560684 -14.999716)
		(width 0.089408)
		(layer "In11.Cu")
		(net "FM_SYS_THROTTLE_LVC3")
	)
	(segment
		(start 329.876404 -11.731498)
		(end 329.047094 -10.902188)
		(width 0.089408)
		(layer "In11.Cu")
		(net "FM_SYS_THROTTLE_LVC3")
	)
	(segment
		(start 365.905034 -48.749458)
		(end 356.678992 -39.523416)
		(width 0.089408)
		(layer "In11.Cu")
		(net "FM_SYS_THROTTLE_LVC3")
	)
	(segment
		(start 188.3918 -16.002)
		(end 187.2742 -17.1196)
		(width 0.089408)
		(layer "In11.Cu")
		(net "FM_SYS_THROTTLE_LVC3")
	)
	(segment
		(start 334.821784 -39.706296)
		(end 333.764128 -39.706296)
		(width 0.089408)
		(layer "In11.Cu")
		(net "FM_SYS_THROTTLE_LVC3")
	)
	(segment
		(start 324.5866 2.43205)
		(end 324.592188 2.437638)
		(width 0.089408)
		(layer "In11.Cu")
		(net "FM_SYS_THROTTLE_LVC3")
	)
	(segment
		(start 333.764128 -39.706296)
		(end 332.950312 -38.89248)
		(width 0.089408)
		(layer "In11.Cu")
		(net "FM_SYS_THROTTLE_LVC3")
	)
	(segment
		(start 324.592188 2.437638)
		(end 324.592188 2.769362)
		(width 0.089408)
		(layer "In11.Cu")
		(net "FM_SYS_THROTTLE_LVC3")
	)
	(segment
		(start 332.950312 -38.89248)
		(end 330.703682 -38.89248)
		(width 0.089408)
		(layer "In11.Cu")
		(net "FM_SYS_THROTTLE_LVC3")
	)
	(segment
		(start 328.560684 -14.999716)
		(end 329.876404 -13.683996)
		(width 0.089408)
		(layer "In11.Cu")
		(net "FM_SYS_THROTTLE_LVC3")
	)
	(segment
		(start 356.678992 -39.523416)
		(end 355.308662 -39.523416)
		(width 0.089408)
		(layer "In11.Cu")
		(net "FM_SYS_THROTTLE_LVC3")
	)
	(segment
		(start 192.913 -6.181344)
		(end 192.874392 -6.219952)
		(width 0.089408)
		(layer "In11.Cu")
		(net "FM_SYS_THROTTLE_LVC3")
	)
	(segment
		(start 322.029582 4.161028)
		(end 194.528948 4.161028)
		(width 0.089408)
		(layer "In11.Cu")
		(net "FM_SYS_THROTTLE_LVC3")
	)
	(segment
		(start 192.660016 2.292096)
		(end 192.660016 -5.493258)
		(width 0.089408)
		(layer "In11.Cu")
		(net "FM_SYS_THROTTLE_LVC3")
	)
	(segment
		(start 326.270112 -10.902188)
		(end 324.5866 -9.218676)
		(width 0.089408)
		(layer "In11.Cu")
		(net "FM_SYS_THROTTLE_LVC3")
	)
	(segment
		(start 370.654326 -52.289964)
		(end 367.11382 -48.749458)
		(width 0.089408)
		(layer "In11.Cu")
		(net "FM_SYS_THROTTLE_LVC3")
	)
	(segment
		(start 367.11382 -48.749458)
		(end 365.905034 -48.749458)
		(width 0.089408)
		(layer "In11.Cu")
		(net "FM_SYS_THROTTLE_LVC3")
	)
	(segment
		(start 355.308662 -39.523416)
		(end 353.352608 -41.47947)
		(width 0.089408)
		(layer "In11.Cu")
		(net "FM_SYS_THROTTLE_LVC3")
	)
	(segment
		(start 330.703682 -38.89248)
		(end 328.182986 -36.371784)
		(width 0.089408)
		(layer "In11.Cu")
		(net "FM_SYS_THROTTLE_LVC3")
	)
	(segment
		(start 324.388734 -16.641826)
		(end 326.030844 -14.999716)
		(width 0.089408)
		(layer "In11.Cu")
		(net "FM_SYS_THROTTLE_LVC3")
	)
	(segment
		(start 336.594958 -41.47947)
		(end 334.821784 -39.706296)
		(width 0.089408)
		(layer "In11.Cu")
		(net "FM_SYS_THROTTLE_LVC3")
	)
	(segment
		(start 373.648478 -56.204866)
		(end 370.654326 -53.210714)
		(width 0.089408)
		(layer "In11.Cu")
		(net "FM_SYS_THROTTLE_LVC3")
	)
	(segment
		(start 192.660016 -5.493258)
		(end 192.913 -5.746242)
		(width 0.089408)
		(layer "In11.Cu")
		(net "FM_SYS_THROTTLE_LVC3")
	)
	(segment
		(start 327.292208 -31.509208)
		(end 327.292208 -27.537664)
		(width 0.089408)
		(layer "In11.Cu")
		(net "FM_SYS_THROTTLE_LVC3")
	)
	(segment
		(start 370.654326 -53.210714)
		(end 370.654326 -52.289964)
		(width 0.089408)
		(layer "In11.Cu")
		(net "FM_SYS_THROTTLE_LVC3")
	)
	(segment
		(start 194.528948 4.161028)
		(end 192.660016 2.292096)
		(width 0.089408)
		(layer "In11.Cu")
		(net "FM_SYS_THROTTLE_LVC3")
	)
	(segment
		(start 329.047094 -10.902188)
		(end 326.270112 -10.902188)
		(width 0.089408)
		(layer "In11.Cu")
		(net "FM_SYS_THROTTLE_LVC3")
	)
	(segment
		(start 187.2742 -17.1196)
		(end 187.2742 -18.232882)
		(width 0.089408)
		(layer "In11.Cu")
		(net "FM_SYS_THROTTLE_LVC3")
	)
	(segment
		(start 189.148212 -16.002)
		(end 188.3918 -16.002)
		(width 0.089408)
		(layer "In11.Cu")
		(net "FM_SYS_THROTTLE_LVC3")
	)
	(segment
		(start 376.429016 -56.510682)
		(end 376.1232 -56.204866)
		(width 0.089408)
		(layer "In11.Cu")
		(net "FM_SYS_THROTTLE_LVC3")
	)
	(segment
		(start 324.592188 2.769362)
		(end 324.347078 3.014472)
		(width 0.089408)
		(layer "In11.Cu")
		(net "FM_SYS_THROTTLE_LVC3")
	)
	(segment
		(start 328.182986 -36.371784)
		(end 328.182986 -32.399986)
		(width 0.089408)
		(layer "In11.Cu")
		(net "FM_SYS_THROTTLE_LVC3")
	)
	(segment
		(start 392.472672 -93.329506)
		(end 392.472672 -93.329252)
		(width 0.0889)
		(layer "F.Cu")
		(net "FM_BIOS_SMI_ACTIVE_N")
	)
	(segment
		(start 392.460988 -93.813376)
		(end 392.461242 -93.813122)
		(width 0.0889)
		(layer "F.Cu")
		(net "FM_BIOS_SMI_ACTIVE_N")
	)
	(segment
		(start 394.17625 -99.55276)
		(end 394.447776 -99.426776)
		(width 0.10795)
		(layer "F.Cu")
		(net "FM_BIOS_SMI_ACTIVE_N")
	)
	(segment
		(start 392.66114 -93.140784)
		(end 392.66114 -92.33154)
		(width 0.0889)
		(layer "F.Cu")
		(net "FM_BIOS_SMI_ACTIVE_N")
	)
	(segment
		(start 394.5382 -99.384612)
		(end 394.67155 -99.322636)
		(width 0.10795)
		(layer "F.Cu")
		(net "FM_BIOS_SMI_ACTIVE_N")
	)
	(segment
		(start 392.485118 -93.959934)
		(end 392.460988 -93.935804)
		(width 0.0889)
		(layer "F.Cu")
		(net "FM_BIOS_SMI_ACTIVE_N")
	)
	(segment
		(start 392.461242 -93.813122)
		(end 392.461242 -93.340936)
		(width 0.0889)
		(layer "F.Cu")
		(net "FM_BIOS_SMI_ACTIVE_N")
	)
	(segment
		(start 392.460988 -93.935804)
		(end 392.460988 -93.813376)
		(width 0.0889)
		(layer "F.Cu")
		(net "FM_BIOS_SMI_ACTIVE_N")
	)
	(segment
		(start 392.461242 -93.340936)
		(end 392.472672 -93.329506)
		(width 0.0889)
		(layer "F.Cu")
		(net "FM_BIOS_SMI_ACTIVE_N")
	)
	(segment
		(start 392.472672 -93.329252)
		(end 392.66114 -93.140784)
		(width 0.0889)
		(layer "F.Cu")
		(net "FM_BIOS_SMI_ACTIVE_N")
	)
	(segment
		(start 409.890214 -37.334698)
		(end 410.290264 -36.934648)
		(width 0.10795)
		(layer "F.Cu")
		(net "FM_BIOS_SMI_ACTIVE_N")
	)
	(segment
		(start 394.447776 -99.426776)
		(end 394.5382 -99.384612)
		(width 0.10795)
		(layer "F.Cu")
		(net "FM_BIOS_SMI_ACTIVE_N")
	)
	(segment
		(start 392.66114 -92.33154)
		(end 391.9982 -91.6686)
		(width 0.0889)
		(layer "F.Cu")
		(net "FM_BIOS_SMI_ACTIVE_N")
	)
	(via
		(at 393.522962 -91.15425)
		(size 0.6604)
		(drill 0.3302)
		(layers "F.Cu" "B.Cu")
		(net "FM_BIOS_SMI_ACTIVE_N")
	)
	(via
		(at 391.9982 -91.6686)
		(size 0.508)
		(drill 0.254)
		(layers "F.Cu" "B.Cu")
		(net "FM_BIOS_SMI_ACTIVE_N")
	)
	(via
		(at 409.890214 -37.334698)
		(size 0.4572)
		(drill 0.2032)
		(layers "F.Cu" "B.Cu")
		(net "FM_BIOS_SMI_ACTIVE_N")
	)
	(via
		(at 394.67155 -99.322636)
		(size 0.508)
		(drill 0.254)
		(layers "F.Cu" "B.Cu")
		(net "FM_BIOS_SMI_ACTIVE_N")
	)
	(segment
		(start 393.522962 -91.15425)
		(end 395.944598 -88.732614)
		(width 0.10795)
		(layer "B.Cu")
		(net "FM_BIOS_SMI_ACTIVE_N")
	)
	(segment
		(start 391.9982 -91.6686)
		(end 393.008612 -91.6686)
		(width 0.10795)
		(layer "B.Cu")
		(net "FM_BIOS_SMI_ACTIVE_N")
	)
	(segment
		(start 395.944598 -88.732614)
		(end 395.944598 -88.724994)
		(width 0.10795)
		(layer "B.Cu")
		(net "FM_BIOS_SMI_ACTIVE_N")
	)
	(segment
		(start 395.944598 -88.724994)
		(end 396.113 -88.556592)
		(width 0.10795)
		(layer "B.Cu")
		(net "FM_BIOS_SMI_ACTIVE_N")
	)
	(segment
		(start 396.113 -88.556592)
		(end 396.113 -88.2015)
		(width 0.10795)
		(layer "B.Cu")
		(net "FM_BIOS_SMI_ACTIVE_N")
	)
	(segment
		(start 393.008612 -91.6686)
		(end 393.522962 -91.15425)
		(width 0.10795)
		(layer "B.Cu")
		(net "FM_BIOS_SMI_ACTIVE_N")
	)
	(segment
		(start 408.13482 -40.159686)
		(end 407.576274 -40.718232)
		(width 0.089408)
		(layer "In9.Cu")
		(net "FM_BIOS_SMI_ACTIVE_N")
	)
	(segment
		(start 408.666696 -39.887906)
		(end 408.394916 -40.159686)
		(width 0.089408)
		(layer "In9.Cu")
		(net "FM_BIOS_SMI_ACTIVE_N")
	)
	(segment
		(start 409.4734 -37.751512)
		(end 409.4734 -39.081202)
		(width 0.089408)
		(layer "In9.Cu")
		(net "FM_BIOS_SMI_ACTIVE_N")
	)
	(segment
		(start 396.741904 -78.108556)
		(end 396.741904 -82.276696)
		(width 0.089408)
		(layer "In9.Cu")
		(net "FM_BIOS_SMI_ACTIVE_N")
	)
	(segment
		(start 409.194762 -39.35984)
		(end 408.935174 -39.35984)
		(width 0.089408)
		(layer "In9.Cu")
		(net "FM_BIOS_SMI_ACTIVE_N")
	)
	(segment
		(start 403.158706 -44.82338)
		(end 403.158706 -45.696124)
		(width 0.089408)
		(layer "In9.Cu")
		(net "FM_BIOS_SMI_ACTIVE_N")
	)
	(segment
		(start 400.687794 -56.378602)
		(end 400.688048 -56.378856)
		(width 0.089408)
		(layer "In9.Cu")
		(net "FM_BIOS_SMI_ACTIVE_N")
	)
	(segment
		(start 403.158706 -45.696124)
		(end 400.688048 -48.166782)
		(width 0.089408)
		(layer "In9.Cu")
		(net "FM_BIOS_SMI_ACTIVE_N")
	)
	(segment
		(start 398.617948 -74.490072)
		(end 398.135094 -74.972926)
		(width 0.089408)
		(layer "In9.Cu")
		(net "FM_BIOS_SMI_ACTIVE_N")
	)
	(segment
		(start 392.6586 -89.6112)
		(end 393.1412 -90.0938)
		(width 0.089408)
		(layer "In9.Cu")
		(net "FM_BIOS_SMI_ACTIVE_N")
	)
	(segment
		(start 402.335238 -60.720732)
		(end 402.335238 -61.195712)
		(width 0.089408)
		(layer "In9.Cu")
		(net "FM_BIOS_SMI_ACTIVE_N")
	)
	(segment
		(start 400.688048 -48.166782)
		(end 400.688048 -55.586376)
		(width 0.089408)
		(layer "In9.Cu")
		(net "FM_BIOS_SMI_ACTIVE_N")
	)
	(segment
		(start 404.10257 -43.879516)
		(end 403.158706 -44.82338)
		(width 0.089408)
		(layer "In9.Cu")
		(net "FM_BIOS_SMI_ACTIVE_N")
	)
	(segment
		(start 408.935174 -39.35984)
		(end 408.666696 -39.628318)
		(width 0.089408)
		(layer "In9.Cu")
		(net "FM_BIOS_SMI_ACTIVE_N")
	)
	(segment
		(start 398.617948 -73.412858)
		(end 398.617948 -74.490072)
		(width 0.089408)
		(layer "In9.Cu")
		(net "FM_BIOS_SMI_ACTIVE_N")
	)
	(segment
		(start 400.687794 -55.58663)
		(end 400.687794 -56.378602)
		(width 0.089408)
		(layer "In9.Cu")
		(net "FM_BIOS_SMI_ACTIVE_N")
	)
	(segment
		(start 394.327888 -86.39429)
		(end 394.327888 -86.951312)
		(width 0.089408)
		(layer "In9.Cu")
		(net "FM_BIOS_SMI_ACTIVE_N")
	)
	(segment
		(start 407.357072 -40.718232)
		(end 405.325072 -42.750232)
		(width 0.089408)
		(layer "In9.Cu")
		(net "FM_BIOS_SMI_ACTIVE_N")
	)
	(segment
		(start 398.785588 -71.209154)
		(end 398.135094 -71.859648)
		(width 0.089408)
		(layer "In9.Cu")
		(net "FM_BIOS_SMI_ACTIVE_N")
	)
	(segment
		(start 402.334984 -58.140092)
		(end 402.334984 -60.720478)
		(width 0.089408)
		(layer "In9.Cu")
		(net "FM_BIOS_SMI_ACTIVE_N")
	)
	(segment
		(start 392.091672 -91.6686)
		(end 391.9982 -91.6686)
		(width 0.089408)
		(layer "In9.Cu")
		(net "FM_BIOS_SMI_ACTIVE_N")
	)
	(segment
		(start 392.6586 -88.6206)
		(end 392.6586 -89.6112)
		(width 0.089408)
		(layer "In9.Cu")
		(net "FM_BIOS_SMI_ACTIVE_N")
	)
	(segment
		(start 402.334984 -60.720478)
		(end 402.335238 -60.720732)
		(width 0.089408)
		(layer "In9.Cu")
		(net "FM_BIOS_SMI_ACTIVE_N")
	)
	(segment
		(start 396.741904 -82.276696)
		(end 395.845792 -83.172808)
		(width 0.089408)
		(layer "In9.Cu")
		(net "FM_BIOS_SMI_ACTIVE_N")
	)
	(segment
		(start 393.1412 -90.0938)
		(end 393.1412 -90.619072)
		(width 0.089408)
		(layer "In9.Cu")
		(net "FM_BIOS_SMI_ACTIVE_N")
	)
	(segment
		(start 404.10257 -43.702986)
		(end 404.10257 -43.879516)
		(width 0.089408)
		(layer "In9.Cu")
		(net "FM_BIOS_SMI_ACTIVE_N")
	)
	(segment
		(start 400.993864 -66.331846)
		(end 398.785334 -68.540376)
		(width 0.089408)
		(layer "In9.Cu")
		(net "FM_BIOS_SMI_ACTIVE_N")
	)
	(segment
		(start 407.576274 -40.718232)
		(end 407.357072 -40.718232)
		(width 0.089408)
		(layer "In9.Cu")
		(net "FM_BIOS_SMI_ACTIVE_N")
	)
	(segment
		(start 408.394916 -40.159686)
		(end 408.13482 -40.159686)
		(width 0.089408)
		(layer "In9.Cu")
		(net "FM_BIOS_SMI_ACTIVE_N")
	)
	(segment
		(start 398.135094 -74.972926)
		(end 398.135094 -77.149198)
		(width 0.089408)
		(layer "In9.Cu")
		(net "FM_BIOS_SMI_ACTIVE_N")
	)
	(segment
		(start 400.993864 -63.488062)
		(end 400.993864 -66.331846)
		(width 0.089408)
		(layer "In9.Cu")
		(net "FM_BIOS_SMI_ACTIVE_N")
	)
	(segment
		(start 395.845792 -84.876386)
		(end 394.327888 -86.39429)
		(width 0.089408)
		(layer "In9.Cu")
		(net "FM_BIOS_SMI_ACTIVE_N")
	)
	(segment
		(start 402.335492 -62.146434)
		(end 400.993864 -63.488062)
		(width 0.089408)
		(layer "In9.Cu")
		(net "FM_BIOS_SMI_ACTIVE_N")
	)
	(segment
		(start 398.135094 -72.930004)
		(end 398.617948 -73.412858)
		(width 0.089408)
		(layer "In9.Cu")
		(net "FM_BIOS_SMI_ACTIVE_N")
	)
	(segment
		(start 397.590518 -77.693774)
		(end 397.156686 -77.693774)
		(width 0.089408)
		(layer "In9.Cu")
		(net "FM_BIOS_SMI_ACTIVE_N")
	)
	(segment
		(start 402.335238 -61.195712)
		(end 402.335492 -61.195966)
		(width 0.089408)
		(layer "In9.Cu")
		(net "FM_BIOS_SMI_ACTIVE_N")
	)
	(segment
		(start 409.890214 -37.334698)
		(end 409.4734 -37.751512)
		(width 0.089408)
		(layer "In9.Cu")
		(net "FM_BIOS_SMI_ACTIVE_N")
	)
	(segment
		(start 405.055324 -42.750232)
		(end 404.10257 -43.702986)
		(width 0.089408)
		(layer "In9.Cu")
		(net "FM_BIOS_SMI_ACTIVE_N")
	)
	(segment
		(start 409.4734 -39.081202)
		(end 409.194762 -39.35984)
		(width 0.089408)
		(layer "In9.Cu")
		(net "FM_BIOS_SMI_ACTIVE_N")
	)
	(segment
		(start 398.135094 -71.859648)
		(end 398.135094 -72.930004)
		(width 0.089408)
		(layer "In9.Cu")
		(net "FM_BIOS_SMI_ACTIVE_N")
	)
	(segment
		(start 400.688048 -55.586376)
		(end 400.687794 -55.58663)
		(width 0.089408)
		(layer "In9.Cu")
		(net "FM_BIOS_SMI_ACTIVE_N")
	)
	(segment
		(start 393.1412 -90.619072)
		(end 392.091672 -91.6686)
		(width 0.089408)
		(layer "In9.Cu")
		(net "FM_BIOS_SMI_ACTIVE_N")
	)
	(segment
		(start 398.785588 -69.01561)
		(end 398.785588 -71.209154)
		(width 0.089408)
		(layer "In9.Cu")
		(net "FM_BIOS_SMI_ACTIVE_N")
	)
	(segment
		(start 408.666696 -39.628318)
		(end 408.666696 -39.887906)
		(width 0.089408)
		(layer "In9.Cu")
		(net "FM_BIOS_SMI_ACTIVE_N")
	)
	(segment
		(start 402.335492 -61.195966)
		(end 402.335492 -62.146434)
		(width 0.089408)
		(layer "In9.Cu")
		(net "FM_BIOS_SMI_ACTIVE_N")
	)
	(segment
		(start 400.688048 -56.493156)
		(end 402.334984 -58.140092)
		(width 0.089408)
		(layer "In9.Cu")
		(net "FM_BIOS_SMI_ACTIVE_N")
	)
	(segment
		(start 397.156686 -77.693774)
		(end 396.741904 -78.108556)
		(width 0.089408)
		(layer "In9.Cu")
		(net "FM_BIOS_SMI_ACTIVE_N")
	)
	(segment
		(start 398.785334 -69.015356)
		(end 398.785588 -69.01561)
		(width 0.089408)
		(layer "In9.Cu")
		(net "FM_BIOS_SMI_ACTIVE_N")
	)
	(segment
		(start 394.327888 -86.951312)
		(end 392.6586 -88.6206)
		(width 0.089408)
		(layer "In9.Cu")
		(net "FM_BIOS_SMI_ACTIVE_N")
	)
	(segment
		(start 398.135094 -77.149198)
		(end 397.590518 -77.693774)
		(width 0.089408)
		(layer "In9.Cu")
		(net "FM_BIOS_SMI_ACTIVE_N")
	)
	(segment
		(start 398.785334 -68.540376)
		(end 398.785334 -69.015356)
		(width 0.089408)
		(layer "In9.Cu")
		(net "FM_BIOS_SMI_ACTIVE_N")
	)
	(segment
		(start 405.325072 -42.750232)
		(end 405.055324 -42.750232)
		(width 0.089408)
		(layer "In9.Cu")
		(net "FM_BIOS_SMI_ACTIVE_N")
	)
	(segment
		(start 400.688048 -56.378856)
		(end 400.688048 -56.493156)
		(width 0.089408)
		(layer "In9.Cu")
		(net "FM_BIOS_SMI_ACTIVE_N")
	)
	(segment
		(start 395.845792 -83.172808)
		(end 395.845792 -84.876386)
		(width 0.089408)
		(layer "In9.Cu")
		(net "FM_BIOS_SMI_ACTIVE_N")
	)
	(segment
		(start 393.279884 -94.690946)
		(end 393.279884 -96.084136)
		(width 0.089408)
		(layer "In11.Cu")
		(net "FM_BIOS_SMI_ACTIVE_N")
	)
	(segment
		(start 392.558524 -93.969586)
		(end 393.279884 -94.690946)
		(width 0.089408)
		(layer "In11.Cu")
		(net "FM_BIOS_SMI_ACTIVE_N")
	)
	(segment
		(start 393.586716 -96.947228)
		(end 394.07973 -97.440242)
		(width 0.089408)
		(layer "In11.Cu")
		(net "FM_BIOS_SMI_ACTIVE_N")
	)
	(segment
		(start 393.279884 -96.084136)
		(end 393.586716 -96.390968)
		(width 0.089408)
		(layer "In11.Cu")
		(net "FM_BIOS_SMI_ACTIVE_N")
	)
	(segment
		(start 394.67155 -98.395282)
		(end 394.67155 -99.322636)
		(width 0.089408)
		(layer "In11.Cu")
		(net "FM_BIOS_SMI_ACTIVE_N")
	)
	(segment
		(start 394.07973 -97.803462)
		(end 394.67155 -98.395282)
		(width 0.089408)
		(layer "In11.Cu")
		(net "FM_BIOS_SMI_ACTIVE_N")
	)
	(segment
		(start 392.558524 -92.228924)
		(end 392.558524 -93.969586)
		(width 0.089408)
		(layer "In11.Cu")
		(net "FM_BIOS_SMI_ACTIVE_N")
	)
	(segment
		(start 391.9982 -91.6686)
		(end 392.558524 -92.228924)
		(width 0.089408)
		(layer "In11.Cu")
		(net "FM_BIOS_SMI_ACTIVE_N")
	)
	(segment
		(start 394.07973 -97.440242)
		(end 394.07973 -97.803462)
		(width 0.089408)
		(layer "In11.Cu")
		(net "FM_BIOS_SMI_ACTIVE_N")
	)
	(segment
		(start 393.586716 -96.390968)
		(end 393.586716 -96.947228)
		(width 0.089408)
		(layer "In11.Cu")
		(net "FM_BIOS_SMI_ACTIVE_N")
	)
	(segment
		(start 375.089928 -100.354892)
		(end 375.014236 -100.2792)
		(width 0.10795)
		(layer "F.Cu")
		(net "FM_SLPS4_N")
	)
	(segment
		(start 369.545108 -69.495162)
		(end 369.944904 -69.894958)
		(width 0.1016)
		(layer "F.Cu")
		(net "FM_SLPS4_N")
	)
	(segment
		(start 418.290248 -42.534586)
		(end 417.890198 -42.134536)
		(width 0.10795)
		(layer "F.Cu")
		(net "FM_SLPS4_N")
	)
	(segment
		(start 374.424702 -100.2792)
		(end 374.163082 -100.01758)
		(width 0.10795)
		(layer "F.Cu")
		(net "FM_SLPS4_N")
	)
	(segment
		(start 375.014236 -100.2792)
		(end 374.424702 -100.2792)
		(width 0.10795)
		(layer "F.Cu")
		(net "FM_SLPS4_N")
	)
	(via
		(at 417.890198 -42.134536)
		(size 0.4572)
		(drill 0.2032)
		(layers "F.Cu" "B.Cu")
		(net "FM_SLPS4_N")
	)
	(via
		(at 374.163082 -100.01758)
		(size 0.508)
		(drill 0.254)
		(layers "F.Cu" "B.Cu")
		(net "FM_SLPS4_N")
	)
	(via
		(at 407.2382 -47.0154)
		(size 0.508)
		(drill 0.254)
		(layers "F.Cu" "B.Cu")
		(net "FM_SLPS4_N")
	)
	(via
		(at 382.195324 -41.877234)
		(size 0.508)
		(drill 0.254)
		(layers "F.Cu" "B.Cu")
		(net "FM_SLPS4_N")
	)
	(via
		(at 369.545108 -69.495162)
		(size 0.4572)
		(drill 0.2032)
		(layers "F.Cu" "B.Cu")
		(net "FM_SLPS4_N")
	)
	(segment
		(start 379.715268 -56.582056)
		(end 379.715268 -56.196738)
		(width 0.089408)
		(layer "In2.Cu")
		(net "FM_SLPS4_N")
	)
	(segment
		(start 381.83566 -44.788328)
		(end 381.83566 -42.34942)
		(width 0.089408)
		(layer "In2.Cu")
		(net "FM_SLPS4_N")
	)
	(segment
		(start 381.83566 -42.34942)
		(end 382.195324 -41.989756)
		(width 0.089408)
		(layer "In2.Cu")
		(net "FM_SLPS4_N")
	)
	(segment
		(start 369.951 -67.30492)
		(end 370.724938 -66.530982)
		(width 0.089408)
		(layer "In2.Cu")
		(net "FM_SLPS4_N")
	)
	(segment
		(start 382.195324 -41.989756)
		(end 382.195324 -41.877234)
		(width 0.089408)
		(layer "In2.Cu")
		(net "FM_SLPS4_N")
	)
	(segment
		(start 379.815598 -46.80839)
		(end 381.83566 -44.788328)
		(width 0.089408)
		(layer "In2.Cu")
		(net "FM_SLPS4_N")
	)
	(segment
		(start 379.715268 -56.196738)
		(end 379.715014 -56.196484)
		(width 0.089408)
		(layer "In2.Cu")
		(net "FM_SLPS4_N")
	)
	(segment
		(start 377.770898 -65.224406)
		(end 377.770898 -64.492886)
		(width 0.089408)
		(layer "In2.Cu")
		(net "FM_SLPS4_N")
	)
	(segment
		(start 379.449076 -62.814708)
		(end 379.449076 -56.848248)
		(width 0.089408)
		(layer "In2.Cu")
		(net "FM_SLPS4_N")
	)
	(segment
		(start 376.464322 -66.530982)
		(end 377.770898 -65.224406)
		(width 0.089408)
		(layer "In2.Cu")
		(net "FM_SLPS4_N")
	)
	(segment
		(start 379.715014 -56.196484)
		(end 379.715014 -56.038496)
		(width 0.089408)
		(layer "In2.Cu")
		(net "FM_SLPS4_N")
	)
	(segment
		(start 379.715014 -56.038496)
		(end 379.815598 -55.937912)
		(width 0.089408)
		(layer "In2.Cu")
		(net "FM_SLPS4_N")
	)
	(segment
		(start 369.545108 -69.495162)
		(end 369.951 -69.08927)
		(width 0.089408)
		(layer "In2.Cu")
		(net "FM_SLPS4_N")
	)
	(segment
		(start 370.724938 -66.530982)
		(end 376.464322 -66.530982)
		(width 0.089408)
		(layer "In2.Cu")
		(net "FM_SLPS4_N")
	)
	(segment
		(start 377.770898 -64.492886)
		(end 379.449076 -62.814708)
		(width 0.089408)
		(layer "In2.Cu")
		(net "FM_SLPS4_N")
	)
	(segment
		(start 369.951 -69.08927)
		(end 369.951 -67.30492)
		(width 0.089408)
		(layer "In2.Cu")
		(net "FM_SLPS4_N")
	)
	(segment
		(start 379.815598 -55.937912)
		(end 379.815598 -46.80839)
		(width 0.089408)
		(layer "In2.Cu")
		(net "FM_SLPS4_N")
	)
	(segment
		(start 379.449076 -56.848248)
		(end 379.715268 -56.582056)
		(width 0.089408)
		(layer "In2.Cu")
		(net "FM_SLPS4_N")
	)
	(segment
		(start 382.694942 -41.377616)
		(end 382.195324 -41.877234)
		(width 0.089408)
		(layer "In4.Cu")
		(net "FM_SLPS4_N")
	)
	(segment
		(start 400.140932 -44.442126)
		(end 398.543526 -44.442126)
		(width 0.089408)
		(layer "In4.Cu")
		(net "FM_SLPS4_N")
	)
	(segment
		(start 388.286752 -42.115994)
		(end 387.09727 -42.115994)
		(width 0.089408)
		(layer "In4.Cu")
		(net "FM_SLPS4_N")
	)
	(segment
		(start 396.904972 -44.069)
		(end 396.796514 -43.960542)
		(width 0.089408)
		(layer "In4.Cu")
		(net "FM_SLPS4_N")
	)
	(segment
		(start 406.958038 -46.735238)
		(end 404.702772 -46.735238)
		(width 0.089408)
		(layer "In4.Cu")
		(net "FM_SLPS4_N")
	)
	(segment
		(start 389.426958 -43.2562)
		(end 388.286752 -42.115994)
		(width 0.089408)
		(layer "In4.Cu")
		(net "FM_SLPS4_N")
	)
	(segment
		(start 398.1704 -44.069)
		(end 396.904972 -44.069)
		(width 0.089408)
		(layer "In4.Cu")
		(net "FM_SLPS4_N")
	)
	(segment
		(start 404.702772 -46.735238)
		(end 404.474934 -46.5074)
		(width 0.089408)
		(layer "In4.Cu")
		(net "FM_SLPS4_N")
	)
	(segment
		(start 395.9352 -43.2562)
		(end 389.426958 -43.2562)
		(width 0.089408)
		(layer "In4.Cu")
		(net "FM_SLPS4_N")
	)
	(segment
		(start 404.474934 -46.5074)
		(end 402.206206 -46.5074)
		(width 0.089408)
		(layer "In4.Cu")
		(net "FM_SLPS4_N")
	)
	(segment
		(start 396.639542 -43.960542)
		(end 395.9352 -43.2562)
		(width 0.089408)
		(layer "In4.Cu")
		(net "FM_SLPS4_N")
	)
	(segment
		(start 402.206206 -46.5074)
		(end 400.140932 -44.442126)
		(width 0.089408)
		(layer "In4.Cu")
		(net "FM_SLPS4_N")
	)
	(segment
		(start 407.2382 -47.0154)
		(end 406.958038 -46.735238)
		(width 0.089408)
		(layer "In4.Cu")
		(net "FM_SLPS4_N")
	)
	(segment
		(start 398.543526 -44.442126)
		(end 398.1704 -44.069)
		(width 0.089408)
		(layer "In4.Cu")
		(net "FM_SLPS4_N")
	)
	(segment
		(start 396.796514 -43.960542)
		(end 396.639542 -43.960542)
		(width 0.089408)
		(layer "In4.Cu")
		(net "FM_SLPS4_N")
	)
	(segment
		(start 386.358892 -41.377616)
		(end 382.694942 -41.377616)
		(width 0.089408)
		(layer "In4.Cu")
		(net "FM_SLPS4_N")
	)
	(segment
		(start 387.09727 -42.115994)
		(end 386.358892 -41.377616)
		(width 0.089408)
		(layer "In4.Cu")
		(net "FM_SLPS4_N")
	)
	(segment
		(start 410.95295 -47.213012)
		(end 410.598112 -47.56785)
		(width 0.089408)
		(layer "In9.Cu")
		(net "FM_SLPS4_N")
	)
	(segment
		(start 411.041596 -46.721014)
		(end 411.041596 -46.721268)
		(width 0.089408)
		(layer "In9.Cu")
		(net "FM_SLPS4_N")
	)
	(segment
		(start 411.041596 -46.721268)
		(end 410.95295 -46.809914)
		(width 0.089408)
		(layer "In9.Cu")
		(net "FM_SLPS4_N")
	)
	(segment
		(start 411.187138 -46.575726)
		(end 411.041596 -46.721014)
		(width 0.089408)
		(layer "In9.Cu")
		(net "FM_SLPS4_N")
	)
	(segment
		(start 410.95295 -46.809914)
		(end 410.95295 -47.213012)
		(width 0.089408)
		(layer "In9.Cu")
		(net "FM_SLPS4_N")
	)
	(segment
		(start 407.79065 -47.56785)
		(end 407.2382 -47.0154)
		(width 0.089408)
		(layer "In9.Cu")
		(net "FM_SLPS4_N")
	)
	(segment
		(start 417.471606 -42.553128)
		(end 416.254946 -42.553128)
		(width 0.089408)
		(layer "In9.Cu")
		(net "FM_SLPS4_N")
	)
	(segment
		(start 410.598112 -47.56785)
		(end 407.79065 -47.56785)
		(width 0.089408)
		(layer "In9.Cu")
		(net "FM_SLPS4_N")
	)
	(segment
		(start 417.890198 -42.134536)
		(end 417.471606 -42.553128)
		(width 0.089408)
		(layer "In9.Cu")
		(net "FM_SLPS4_N")
	)
	(segment
		(start 412.232348 -46.575726)
		(end 411.187138 -46.575726)
		(width 0.089408)
		(layer "In9.Cu")
		(net "FM_SLPS4_N")
	)
	(segment
		(start 416.254946 -42.553128)
		(end 412.232348 -46.575726)
		(width 0.089408)
		(layer "In9.Cu")
		(net "FM_SLPS4_N")
	)
	(segment
		(start 369.444016 -92.609416)
		(end 366.429036 -89.594436)
		(width 0.089408)
		(layer "In11.Cu")
		(net "FM_SLPS4_N")
	)
	(segment
		(start 369.444016 -95.2373)
		(end 369.444016 -92.609416)
		(width 0.089408)
		(layer "In11.Cu")
		(net "FM_SLPS4_N")
	)
	(segment
		(start 365.424212 -82.959956)
		(end 365.424212 -79.986886)
		(width 0.089408)
		(layer "In11.Cu")
		(net "FM_SLPS4_N")
	)
	(segment
		(start 369.171728 -69.121782)
		(end 369.545108 -69.495162)
		(width 0.089408)
		(layer "In11.Cu")
		(net "FM_SLPS4_N")
	)
	(segment
		(start 372.0719 -94.2213)
		(end 370.6622 -95.631)
		(width 0.089408)
		(layer "In11.Cu")
		(net "FM_SLPS4_N")
	)
	(segment
		(start 374.163082 -100.01758)
		(end 374.6754 -99.505262)
		(width 0.089408)
		(layer "In11.Cu")
		(net "FM_SLPS4_N")
	)
	(segment
		(start 366.429036 -83.96478)
		(end 365.424212 -82.959956)
		(width 0.089408)
		(layer "In11.Cu")
		(net "FM_SLPS4_N")
	)
	(segment
		(start 365.762032 -72.509126)
		(end 365.762032 -69.55028)
		(width 0.089408)
		(layer "In11.Cu")
		(net "FM_SLPS4_N")
	)
	(segment
		(start 366.19053 -69.121782)
		(end 369.171728 -69.121782)
		(width 0.089408)
		(layer "In11.Cu")
		(net "FM_SLPS4_N")
	)
	(segment
		(start 365.913162 -72.660256)
		(end 365.762032 -72.509126)
		(width 0.089408)
		(layer "In11.Cu")
		(net "FM_SLPS4_N")
	)
	(segment
		(start 366.429036 -89.594436)
		(end 366.429036 -83.96478)
		(width 0.089408)
		(layer "In11.Cu")
		(net "FM_SLPS4_N")
	)
	(segment
		(start 372.999 -94.2213)
		(end 372.0719 -94.2213)
		(width 0.089408)
		(layer "In11.Cu")
		(net "FM_SLPS4_N")
	)
	(segment
		(start 365.424212 -79.986886)
		(end 365.913162 -77.543152)
		(width 0.089408)
		(layer "In11.Cu")
		(net "FM_SLPS4_N")
	)
	(segment
		(start 374.6754 -99.505262)
		(end 374.6754 -95.360998)
		(width 0.089408)
		(layer "In11.Cu")
		(net "FM_SLPS4_N")
	)
	(segment
		(start 365.762032 -69.55028)
		(end 366.19053 -69.121782)
		(width 0.089408)
		(layer "In11.Cu")
		(net "FM_SLPS4_N")
	)
	(segment
		(start 365.913162 -77.543152)
		(end 365.913162 -72.660256)
		(width 0.089408)
		(layer "In11.Cu")
		(net "FM_SLPS4_N")
	)
	(segment
		(start 374.437402 -95.123)
		(end 373.9007 -95.123)
		(width 0.089408)
		(layer "In11.Cu")
		(net "FM_SLPS4_N")
	)
	(segment
		(start 370.6622 -95.631)
		(end 369.837716 -95.631)
		(width 0.089408)
		(layer "In11.Cu")
		(net "FM_SLPS4_N")
	)
	(segment
		(start 374.6754 -95.360998)
		(end 374.437402 -95.123)
		(width 0.089408)
		(layer "In11.Cu")
		(net "FM_SLPS4_N")
	)
	(segment
		(start 369.837716 -95.631)
		(end 369.444016 -95.2373)
		(width 0.089408)
		(layer "In11.Cu")
		(net "FM_SLPS4_N")
	)
	(segment
		(start 373.9007 -95.123)
		(end 372.999 -94.2213)
		(width 0.089408)
		(layer "In11.Cu")
		(net "FM_SLPS4_N")
	)
	(segment
		(start 371.242844 -97.155)
		(end 371.947694 -97.85985)
		(width 0.10795)
		(layer "F.Cu")
		(net "FM_SLPS3_N")
	)
	(segment
		(start 418.290248 -44.02328)
		(end 418.290248 -44.122848)
		(width 0.10795)
		(layer "F.Cu")
		(net "FM_SLPS3_N")
	)
	(segment
		(start 419.354 -45.1866)
		(end 419.354 -45.371512)
		(width 0.10795)
		(layer "F.Cu")
		(net "FM_SLPS3_N")
	)
	(segment
		(start 380.96571 -72.53351)
		(end 379.306582 -72.53351)
		(width 0.10795)
		(layer "F.Cu")
		(net "FM_SLPS3_N")
	)
	(segment
		(start 383.429764 -73.572116)
		(end 384.313684 -73.572116)
		(width 0.10795)
		(layer "F.Cu")
		(net "FM_SLPS3_N")
	)
	(segment
		(start 389.058404 -74.149204)
		(end 389.058404 -74.657204)
		(width 0.10795)
		(layer "F.Cu")
		(net "FM_SLPS3_N")
	)
	(segment
		(start 382.026414 -73.594214)
		(end 380.96571 -72.53351)
		(width 0.10795)
		(layer "F.Cu")
		(net "FM_SLPS3_N")
	)
	(segment
		(start 418.289232 -43.704256)
		(end 418.289232 -44.022264)
		(width 0.10795)
		(layer "F.Cu")
		(net "FM_SLPS3_N")
	)
	(segment
		(start 418.290248 -43.70324)
		(end 418.289232 -43.704256)
		(width 0.10795)
		(layer "F.Cu")
		(net "FM_SLPS3_N")
	)
	(segment
		(start 388.3406 -73.4314)
		(end 389.058404 -74.149204)
		(width 0.10795)
		(layer "F.Cu")
		(net "FM_SLPS3_N")
	)
	(segment
		(start 384.4544 -73.4314)
		(end 388.3406 -73.4314)
		(width 0.10795)
		(layer "F.Cu")
		(net "FM_SLPS3_N")
	)
	(segment
		(start 418.289232 -44.022264)
		(end 418.290248 -44.02328)
		(width 0.10795)
		(layer "F.Cu")
		(net "FM_SLPS3_N")
	)
	(segment
		(start 382.624584 -73.594214)
		(end 382.026414 -73.594214)
		(width 0.10795)
		(layer "F.Cu")
		(net "FM_SLPS3_N")
	)
	(segment
		(start 370.967 -97.155)
		(end 371.242844 -97.155)
		(width 0.10795)
		(layer "F.Cu")
		(net "FM_SLPS3_N")
	)
	(segment
		(start 389.058404 -74.657204)
		(end 389.592566 -75.191366)
		(width 0.10795)
		(layer "F.Cu")
		(net "FM_SLPS3_N")
	)
	(segment
		(start 389.592566 -75.191366)
		(end 389.7376 -75.191366)
		(width 0.10795)
		(layer "F.Cu")
		(net "FM_SLPS3_N")
	)
	(segment
		(start 383.407666 -73.594214)
		(end 383.429764 -73.572116)
		(width 0.10795)
		(layer "F.Cu")
		(net "FM_SLPS3_N")
	)
	(segment
		(start 379.306582 -72.53351)
		(end 378.744988 -73.095104)
		(width 0.10795)
		(layer "F.Cu")
		(net "FM_SLPS3_N")
	)
	(segment
		(start 382.624584 -73.594214)
		(end 383.407666 -73.594214)
		(width 0.10795)
		(layer "F.Cu")
		(net "FM_SLPS3_N")
	)
	(segment
		(start 384.313684 -73.572116)
		(end 384.4544 -73.4314)
		(width 0.10795)
		(layer "F.Cu")
		(net "FM_SLPS3_N")
	)
	(segment
		(start 418.290248 -44.122848)
		(end 419.354 -45.1866)
		(width 0.10795)
		(layer "F.Cu")
		(net "FM_SLPS3_N")
	)
	(segment
		(start 418.290248 -43.334686)
		(end 418.290248 -43.70324)
		(width 0.10795)
		(layer "F.Cu")
		(net "FM_SLPS3_N")
	)
	(via
		(at 371.947694 -97.85985)
		(size 0.508)
		(drill 0.254)
		(layers "F.Cu" "B.Cu")
		(net "FM_SLPS3_N")
	)
	(via
		(at 419.354 -45.371512)
		(size 0.508)
		(drill 0.254)
		(layers "F.Cu" "B.Cu")
		(net "FM_SLPS3_N")
	)
	(via
		(at 427.063408 -49.807368)
		(size 0.508)
		(drill 0.254)
		(layers "F.Cu" "B.Cu")
		(net "FM_SLPS3_N")
	)
	(via
		(at 427.16704 -62.357)
		(size 0.508)
		(drill 0.254)
		(layers "F.Cu" "B.Cu")
		(net "FM_SLPS3_N")
	)
	(via
		(at 378.43841 -89.569798)
		(size 0.508)
		(drill 0.254)
		(layers "F.Cu" "B.Cu")
		(net "FM_SLPS3_N")
	)
	(via
		(at 424.960796 -115.10899)
		(size 0.508)
		(drill 0.254)
		(layers "F.Cu" "B.Cu")
		(net "FM_SLPS3_N")
	)
	(via
		(at 389.7376 -75.191366)
		(size 0.508)
		(drill 0.254)
		(layers "F.Cu" "B.Cu")
		(net "FM_SLPS3_N")
	)
	(via
		(at 389.531606 -93.055694)
		(size 0.508)
		(drill 0.254)
		(layers "F.Cu" "B.Cu")
		(net "FM_SLPS3_N")
	)
	(via
		(at 382.624584 -73.594214)
		(size 0.762)
		(drill 0.381)
		(layers "F.Cu" "B.Cu")
		(net "FM_SLPS3_N")
	)
	(via
		(at 471.045032 -140.387832)
		(size 0.508)
		(drill 0.254)
		(layers "F.Cu" "B.Cu")
		(net "FM_SLPS3_N")
	)
	(segment
		(start 471.460322 -140.803122)
		(end 471.045032 -140.387832)
		(width 0.10795)
		(layer "B.Cu")
		(net "FM_SLPS3_N")
	)
	(segment
		(start 473.660216 -141.038072)
		(end 472.4146 -141.038072)
		(width 0.10795)
		(layer "B.Cu")
		(net "FM_SLPS3_N")
	)
	(segment
		(start 472.186762 -140.810234)
		(end 471.530426 -140.810234)
		(width 0.10795)
		(layer "B.Cu")
		(net "FM_SLPS3_N")
	)
	(segment
		(start 471.530426 -140.810234)
		(end 471.523314 -140.803122)
		(width 0.10795)
		(layer "B.Cu")
		(net "FM_SLPS3_N")
	)
	(segment
		(start 471.523314 -140.803122)
		(end 471.460322 -140.803122)
		(width 0.10795)
		(layer "B.Cu")
		(net "FM_SLPS3_N")
	)
	(segment
		(start 472.4146 -141.038072)
		(end 472.186762 -140.810234)
		(width 0.10795)
		(layer "B.Cu")
		(net "FM_SLPS3_N")
	)
	(segment
		(start 420.543228 -45.576744)
		(end 419.559232 -45.576744)
		(width 0.089408)
		(layer "In2.Cu")
		(net "FM_SLPS3_N")
	)
	(segment
		(start 421.120316 -103.572564)
		(end 421.120316 -100.191316)
		(width 0.089408)
		(layer "In2.Cu")
		(net "FM_SLPS3_N")
	)
	(segment
		(start 392.061192 -51.056286)
		(end 392.061192 -48.646588)
		(width 0.089408)
		(layer "In2.Cu")
		(net "FM_SLPS3_N")
	)
	(segment
		(start 421.785796 -65.654428)
		(end 425.083224 -62.357)
		(width 0.089408)
		(layer "In2.Cu")
		(net "FM_SLPS3_N")
	)
	(segment
		(start 390.69264 -73.5076)
		(end 390.69264 -69.22262)
		(width 0.089408)
		(layer "In2.Cu")
		(net "FM_SLPS3_N")
	)
	(segment
		(start 404.72868 -45.171868)
		(end 409.010612 -45.171868)
		(width 0.089408)
		(layer "In2.Cu")
		(net "FM_SLPS3_N")
	)
	(segment
		(start 392.12774 -64.854328)
		(end 392.12774 -64.431926)
		(width 0.089408)
		(layer "In2.Cu")
		(net "FM_SLPS3_N")
	)
	(segment
		(start 379.889258 -89.569798)
		(end 378.43841 -89.569798)
		(width 0.089408)
		(layer "In2.Cu")
		(net "FM_SLPS3_N")
	)
	(segment
		(start 425.083224 -62.357)
		(end 427.16704 -62.357)
		(width 0.089408)
		(layer "In2.Cu")
		(net "FM_SLPS3_N")
	)
	(segment
		(start 420.636192 -112.44707)
		(end 420.636192 -104.056688)
		(width 0.089408)
		(layer "In2.Cu")
		(net "FM_SLPS3_N")
	)
	(segment
		(start 424.5229 -47.053754)
		(end 421.428418 -47.053754)
		(width 0.089408)
		(layer "In2.Cu")
		(net "FM_SLPS3_N")
	)
	(segment
		(start 380.20625 -93.561408)
		(end 380.10846 -93.463618)
		(width 0.089408)
		(layer "In2.Cu")
		(net "FM_SLPS3_N")
	)
	(segment
		(start 412.787592 -45.25772)
		(end 418.476176 -45.25772)
		(width 0.089408)
		(layer "In2.Cu")
		(net "FM_SLPS3_N")
	)
	(segment
		(start 410.3878 -45.752004)
		(end 410.774642 -45.365162)
		(width 0.089408)
		(layer "In2.Cu")
		(net "FM_SLPS3_N")
	)
	(segment
		(start 427.063408 -49.807368)
		(end 427.063408 -49.594262)
		(width 0.089408)
		(layer "In2.Cu")
		(net "FM_SLPS3_N")
	)
	(segment
		(start 389.81888 -68.34886)
		(end 389.81888 -67.163188)
		(width 0.089408)
		(layer "In2.Cu")
		(net "FM_SLPS3_N")
	)
	(segment
		(start 389.7376 -74.46264)
		(end 390.69264 -73.5076)
		(width 0.089408)
		(layer "In2.Cu")
		(net "FM_SLPS3_N")
	)
	(segment
		(start 389.531606 -93.101668)
		(end 389.071866 -93.561408)
		(width 0.089408)
		(layer "In2.Cu")
		(net "FM_SLPS3_N")
	)
	(segment
		(start 421.120316 -100.191316)
		(end 420.385748 -99.456748)
		(width 0.089408)
		(layer "In2.Cu")
		(net "FM_SLPS3_N")
	)
	(segment
		(start 393.582398 -47.125382)
		(end 402.775166 -47.125382)
		(width 0.089408)
		(layer "In2.Cu")
		(net "FM_SLPS3_N")
	)
	(segment
		(start 402.775166 -47.125382)
		(end 404.72868 -45.171868)
		(width 0.089408)
		(layer "In2.Cu")
		(net "FM_SLPS3_N")
	)
	(segment
		(start 422.6814 -93.358208)
		(end 422.6814 -80.306926)
		(width 0.089408)
		(layer "In2.Cu")
		(net "FM_SLPS3_N")
	)
	(segment
		(start 419.128702 -45.59681)
		(end 419.354 -45.371512)
		(width 0.089408)
		(layer "In2.Cu")
		(net "FM_SLPS3_N")
	)
	(segment
		(start 392.061192 -48.646588)
		(end 393.582398 -47.125382)
		(width 0.089408)
		(layer "In2.Cu")
		(net "FM_SLPS3_N")
	)
	(segment
		(start 411.423612 -45.365162)
		(end 411.630114 -45.571664)
		(width 0.089408)
		(layer "In2.Cu")
		(net "FM_SLPS3_N")
	)
	(segment
		(start 411.630114 -45.571664)
		(end 412.473648 -45.571664)
		(width 0.089408)
		(layer "In2.Cu")
		(net "FM_SLPS3_N")
	)
	(segment
		(start 419.559232 -45.576744)
		(end 419.354 -45.371512)
		(width 0.089408)
		(layer "In2.Cu")
		(net "FM_SLPS3_N")
	)
	(segment
		(start 389.071866 -93.561408)
		(end 380.20625 -93.561408)
		(width 0.089408)
		(layer "In2.Cu")
		(net "FM_SLPS3_N")
	)
	(segment
		(start 420.385748 -99.456748)
		(end 420.385748 -95.65386)
		(width 0.089408)
		(layer "In2.Cu")
		(net "FM_SLPS3_N")
	)
	(segment
		(start 409.010612 -45.171868)
		(end 409.590748 -45.752004)
		(width 0.089408)
		(layer "In2.Cu")
		(net "FM_SLPS3_N")
	)
	(segment
		(start 420.636192 -104.056688)
		(end 421.120316 -103.572564)
		(width 0.089408)
		(layer "In2.Cu")
		(net "FM_SLPS3_N")
	)
	(segment
		(start 420.385748 -95.65386)
		(end 422.6814 -93.358208)
		(width 0.089408)
		(layer "In2.Cu")
		(net "FM_SLPS3_N")
	)
	(segment
		(start 421.000682 -46.626018)
		(end 421.000682 -46.034198)
		(width 0.089408)
		(layer "In2.Cu")
		(net "FM_SLPS3_N")
	)
	(segment
		(start 427.063408 -49.594262)
		(end 424.5229 -47.053754)
		(width 0.089408)
		(layer "In2.Cu")
		(net "FM_SLPS3_N")
	)
	(segment
		(start 389.531606 -93.055694)
		(end 389.531606 -93.101668)
		(width 0.089408)
		(layer "In2.Cu")
		(net "FM_SLPS3_N")
	)
	(segment
		(start 393.851638 -52.846732)
		(end 392.061192 -51.056286)
		(width 0.089408)
		(layer "In2.Cu")
		(net "FM_SLPS3_N")
	)
	(segment
		(start 393.851638 -62.708028)
		(end 393.851638 -52.846732)
		(width 0.089408)
		(layer "In2.Cu")
		(net "FM_SLPS3_N")
	)
	(segment
		(start 418.476176 -45.25772)
		(end 418.815266 -45.59681)
		(width 0.089408)
		(layer "In2.Cu")
		(net "FM_SLPS3_N")
	)
	(segment
		(start 412.473648 -45.571664)
		(end 412.787592 -45.25772)
		(width 0.089408)
		(layer "In2.Cu")
		(net "FM_SLPS3_N")
	)
	(segment
		(start 410.774642 -45.365162)
		(end 411.423612 -45.365162)
		(width 0.089408)
		(layer "In2.Cu")
		(net "FM_SLPS3_N")
	)
	(segment
		(start 421.785796 -79.411322)
		(end 421.785796 -65.654428)
		(width 0.089408)
		(layer "In2.Cu")
		(net "FM_SLPS3_N")
	)
	(segment
		(start 392.12774 -64.431926)
		(end 393.851638 -62.708028)
		(width 0.089408)
		(layer "In2.Cu")
		(net "FM_SLPS3_N")
	)
	(segment
		(start 418.815266 -45.59681)
		(end 419.128702 -45.59681)
		(width 0.089408)
		(layer "In2.Cu")
		(net "FM_SLPS3_N")
	)
	(segment
		(start 389.7376 -75.191366)
		(end 389.7376 -74.46264)
		(width 0.089408)
		(layer "In2.Cu")
		(net "FM_SLPS3_N")
	)
	(segment
		(start 380.10846 -89.789)
		(end 379.889258 -89.569798)
		(width 0.089408)
		(layer "In2.Cu")
		(net "FM_SLPS3_N")
	)
	(segment
		(start 389.81888 -67.163188)
		(end 392.12774 -64.854328)
		(width 0.089408)
		(layer "In2.Cu")
		(net "FM_SLPS3_N")
	)
	(segment
		(start 421.000682 -46.034198)
		(end 420.543228 -45.576744)
		(width 0.089408)
		(layer "In2.Cu")
		(net "FM_SLPS3_N")
	)
	(segment
		(start 423.298112 -115.10899)
		(end 420.636192 -112.44707)
		(width 0.089408)
		(layer "In2.Cu")
		(net "FM_SLPS3_N")
	)
	(segment
		(start 424.960796 -115.10899)
		(end 423.298112 -115.10899)
		(width 0.089408)
		(layer "In2.Cu")
		(net "FM_SLPS3_N")
	)
	(segment
		(start 390.69264 -69.22262)
		(end 389.81888 -68.34886)
		(width 0.089408)
		(layer "In2.Cu")
		(net "FM_SLPS3_N")
	)
	(segment
		(start 421.428418 -47.053754)
		(end 421.000682 -46.626018)
		(width 0.089408)
		(layer "In2.Cu")
		(net "FM_SLPS3_N")
	)
	(segment
		(start 422.6814 -80.306926)
		(end 421.785796 -79.411322)
		(width 0.089408)
		(layer "In2.Cu")
		(net "FM_SLPS3_N")
	)
	(segment
		(start 409.590748 -45.752004)
		(end 410.3878 -45.752004)
		(width 0.089408)
		(layer "In2.Cu")
		(net "FM_SLPS3_N")
	)
	(segment
		(start 380.10846 -93.463618)
		(end 380.10846 -89.789)
		(width 0.089408)
		(layer "In2.Cu")
		(net "FM_SLPS3_N")
	)
	(segment
		(start 474.5736 -126.958344)
		(end 472.72448 -128.807464)
		(width 0.089408)
		(layer "In4.Cu")
		(net "FM_SLPS3_N")
	)
	(segment
		(start 472.72448 -130.82778)
		(end 473.02674 -131.13004)
		(width 0.089408)
		(layer "In4.Cu")
		(net "FM_SLPS3_N")
	)
	(segment
		(start 470.658952 -118.358412)
		(end 470.658952 -120.503188)
		(width 0.089408)
		(layer "In4.Cu")
		(net "FM_SLPS3_N")
	)
	(segment
		(start 473.763086 -139.646914)
		(end 472.567 -140.843)
		(width 0.089408)
		(layer "In4.Cu")
		(net "FM_SLPS3_N")
	)
	(segment
		(start 474.0783 -136.794748)
		(end 473.763086 -137.109962)
		(width 0.089408)
		(layer "In4.Cu")
		(net "FM_SLPS3_N")
	)
	(segment
		(start 378.663962 -89.79535)
		(end 378.663962 -92.780612)
		(width 0.089408)
		(layer "In4.Cu")
		(net "FM_SLPS3_N")
	)
	(segment
		(start 374.62841 -95.169736)
		(end 374.041416 -95.169736)
		(width 0.089408)
		(layer "In4.Cu")
		(net "FM_SLPS3_N")
	)
	(segment
		(start 473.02674 -131.13004)
		(end 473.02674 -132.747512)
		(width 0.089408)
		(layer "In4.Cu")
		(net "FM_SLPS3_N")
	)
	(segment
		(start 427.924722 -120.05183)
		(end 433.585874 -120.05183)
		(width 0.089408)
		(layer "In4.Cu")
		(net "FM_SLPS3_N")
	)
	(segment
		(start 437.086248 -116.952776)
		(end 442.018928 -116.952776)
		(width 0.089408)
		(layer "In4.Cu")
		(net "FM_SLPS3_N")
	)
	(segment
		(start 472.72448 -128.807464)
		(end 472.72448 -130.82778)
		(width 0.089408)
		(layer "In4.Cu")
		(net "FM_SLPS3_N")
	)
	(segment
		(start 443.122304 -115.8494)
		(end 463.846164 -115.8494)
		(width 0.089408)
		(layer "In4.Cu")
		(net "FM_SLPS3_N")
	)
	(segment
		(start 442.018928 -116.952776)
		(end 443.122304 -115.8494)
		(width 0.089408)
		(layer "In4.Cu")
		(net "FM_SLPS3_N")
	)
	(segment
		(start 473.02674 -132.747512)
		(end 474.0783 -133.799834)
		(width 0.089408)
		(layer "In4.Cu")
		(net "FM_SLPS3_N")
	)
	(segment
		(start 469.29294 -116.9924)
		(end 470.658952 -118.358412)
		(width 0.089408)
		(layer "In4.Cu")
		(net "FM_SLPS3_N")
	)
	(segment
		(start 378.138182 -93.306392)
		(end 376.491754 -93.306392)
		(width 0.089408)
		(layer "In4.Cu")
		(net "FM_SLPS3_N")
	)
	(segment
		(start 374.041416 -95.169736)
		(end 373.675402 -95.53575)
		(width 0.089408)
		(layer "In4.Cu")
		(net "FM_SLPS3_N")
	)
	(segment
		(start 464.989164 -116.9924)
		(end 469.29294 -116.9924)
		(width 0.089408)
		(layer "In4.Cu")
		(net "FM_SLPS3_N")
	)
	(segment
		(start 437.085994 -116.952522)
		(end 437.086248 -116.952776)
		(width 0.089408)
		(layer "In4.Cu")
		(net "FM_SLPS3_N")
	)
	(segment
		(start 472.567 -140.843)
		(end 471.5002 -140.843)
		(width 0.089408)
		(layer "In4.Cu")
		(net "FM_SLPS3_N")
	)
	(segment
		(start 424.960796 -115.10899)
		(end 424.960796 -117.087904)
		(width 0.089408)
		(layer "In4.Cu")
		(net "FM_SLPS3_N")
	)
	(segment
		(start 373.675402 -95.53575)
		(end 373.675402 -96.079056)
		(width 0.089408)
		(layer "In4.Cu")
		(net "FM_SLPS3_N")
	)
	(segment
		(start 378.663962 -92.780612)
		(end 378.138182 -93.306392)
		(width 0.089408)
		(layer "In4.Cu")
		(net "FM_SLPS3_N")
	)
	(segment
		(start 436.685182 -116.952522)
		(end 437.085994 -116.952522)
		(width 0.089408)
		(layer "In4.Cu")
		(net "FM_SLPS3_N")
	)
	(segment
		(start 474.0783 -133.799834)
		(end 474.0783 -136.794748)
		(width 0.089408)
		(layer "In4.Cu")
		(net "FM_SLPS3_N")
	)
	(segment
		(start 474.5736 -124.417836)
		(end 474.5736 -126.958344)
		(width 0.089408)
		(layer "In4.Cu")
		(net "FM_SLPS3_N")
	)
	(segment
		(start 378.43841 -89.569798)
		(end 378.663962 -89.79535)
		(width 0.089408)
		(layer "In4.Cu")
		(net "FM_SLPS3_N")
	)
	(segment
		(start 470.658952 -120.503188)
		(end 474.5736 -124.417836)
		(width 0.089408)
		(layer "In4.Cu")
		(net "FM_SLPS3_N")
	)
	(segment
		(start 473.763086 -137.109962)
		(end 473.763086 -139.646914)
		(width 0.089408)
		(layer "In4.Cu")
		(net "FM_SLPS3_N")
	)
	(segment
		(start 424.960796 -117.087904)
		(end 427.924722 -120.05183)
		(width 0.089408)
		(layer "In4.Cu")
		(net "FM_SLPS3_N")
	)
	(segment
		(start 471.5002 -140.843)
		(end 471.045032 -140.387832)
		(width 0.089408)
		(layer "In4.Cu")
		(net "FM_SLPS3_N")
	)
	(segment
		(start 376.491754 -93.306392)
		(end 374.62841 -95.169736)
		(width 0.089408)
		(layer "In4.Cu")
		(net "FM_SLPS3_N")
	)
	(segment
		(start 371.947694 -97.806764)
		(end 371.947694 -97.85985)
		(width 0.089408)
		(layer "In4.Cu")
		(net "FM_SLPS3_N")
	)
	(segment
		(start 373.675402 -96.079056)
		(end 371.947694 -97.806764)
		(width 0.089408)
		(layer "In4.Cu")
		(net "FM_SLPS3_N")
	)
	(segment
		(start 433.585874 -120.05183)
		(end 436.685182 -116.952522)
		(width 0.089408)
		(layer "In4.Cu")
		(net "FM_SLPS3_N")
	)
	(segment
		(start 463.846164 -115.8494)
		(end 464.989164 -116.9924)
		(width 0.089408)
		(layer "In4.Cu")
		(net "FM_SLPS3_N")
	)
	(segment
		(start 388.553706 -76.37526)
		(end 389.7376 -75.191366)
		(width 0.089408)
		(layer "In11.Cu")
		(net "FM_SLPS3_N")
	)
	(segment
		(start 427.19752 -50.718974)
		(end 427.431962 -50.953416)
		(width 0.089408)
		(layer "In11.Cu")
		(net "FM_SLPS3_N")
	)
	(segment
		(start 429.245522 -52.734718)
		(end 429.245522 -61.669422)
		(width 0.089408)
		(layer "In11.Cu")
		(net "FM_SLPS3_N")
	)
	(segment
		(start 389.45312 -79.439262)
		(end 388.553706 -78.539848)
		(width 0.089408)
		(layer "In11.Cu")
		(net "FM_SLPS3_N")
	)
	(segment
		(start 428.049944 -62.865)
		(end 427.67504 -62.865)
		(width 0.089408)
		(layer "In11.Cu")
		(net "FM_SLPS3_N")
	)
	(segment
		(start 427.19752 -50.686716)
		(end 427.19752 -50.718974)
		(width 0.089408)
		(layer "In11.Cu")
		(net "FM_SLPS3_N")
	)
	(segment
		(start 390.033764 -92.378784)
		(end 390.029192 -92.374212)
		(width 0.089408)
		(layer "In11.Cu")
		(net "FM_SLPS3_N")
	)
	(segment
		(start 390.029192 -92.374212)
		(end 390.029192 -88.898222)
		(width 0.089408)
		(layer "In11.Cu")
		(net "FM_SLPS3_N")
	)
	(segment
		(start 427.431962 -50.953416)
		(end 427.46422 -50.953416)
		(width 0.089408)
		(layer "In11.Cu")
		(net "FM_SLPS3_N")
	)
	(segment
		(start 427.67504 -62.865)
		(end 427.16704 -62.357)
		(width 0.089408)
		(layer "In11.Cu")
		(net "FM_SLPS3_N")
	)
	(segment
		(start 389.001 -82.20964)
		(end 389.45312 -81.75752)
		(width 0.089408)
		(layer "In11.Cu")
		(net "FM_SLPS3_N")
	)
	(segment
		(start 388.553706 -78.539848)
		(end 388.553706 -76.37526)
		(width 0.089408)
		(layer "In11.Cu")
		(net "FM_SLPS3_N")
	)
	(segment
		(start 390.033764 -92.553536)
		(end 390.033764 -92.378784)
		(width 0.089408)
		(layer "In11.Cu")
		(net "FM_SLPS3_N")
	)
	(segment
		(start 389.6614 -83.5914)
		(end 389.001 -82.931)
		(width 0.089408)
		(layer "In11.Cu")
		(net "FM_SLPS3_N")
	)
	(segment
		(start 427.063408 -49.807368)
		(end 427.063408 -50.552604)
		(width 0.089408)
		(layer "In11.Cu")
		(net "FM_SLPS3_N")
	)
	(segment
		(start 389.45312 -81.75752)
		(end 389.45312 -79.439262)
		(width 0.089408)
		(layer "In11.Cu")
		(net "FM_SLPS3_N")
	)
	(segment
		(start 427.063408 -50.552604)
		(end 427.19752 -50.686716)
		(width 0.089408)
		(layer "In11.Cu")
		(net "FM_SLPS3_N")
	)
	(segment
		(start 389.6614 -88.53043)
		(end 389.6614 -83.5914)
		(width 0.089408)
		(layer "In11.Cu")
		(net "FM_SLPS3_N")
	)
	(segment
		(start 389.001 -82.931)
		(end 389.001 -82.20964)
		(width 0.089408)
		(layer "In11.Cu")
		(net "FM_SLPS3_N")
	)
	(segment
		(start 390.029192 -88.898222)
		(end 389.6614 -88.53043)
		(width 0.089408)
		(layer "In11.Cu")
		(net "FM_SLPS3_N")
	)
	(segment
		(start 429.245522 -61.669422)
		(end 428.049944 -62.865)
		(width 0.089408)
		(layer "In11.Cu")
		(net "FM_SLPS3_N")
	)
	(segment
		(start 389.531606 -93.055694)
		(end 390.033764 -92.553536)
		(width 0.089408)
		(layer "In11.Cu")
		(net "FM_SLPS3_N")
	)
	(segment
		(start 427.46422 -50.953416)
		(end 429.245522 -52.734718)
		(width 0.089408)
		(layer "In11.Cu")
		(net "FM_SLPS3_N")
	)
	(segment
		(start 374.200674 -81.3435)
		(end 373.944896 -81.087722)
		(width 0.1016)
		(layer "F.Cu")
		(net "FM_PVCCIO_CPU1_EN")
	)
	(segment
		(start 373.944896 -81.087722)
		(end 373.944896 -80.294988)
		(width 0.1016)
		(layer "F.Cu")
		(net "FM_PVCCIO_CPU1_EN")
	)
	(via
		(at 165.862 -65.151)
		(size 0.6604)
		(drill 0.3302)
		(layers "F.Cu" "B.Cu")
		(net "FM_PVCCIO_CPU1_EN")
	)
	(via
		(at 166.3573 -64.375284)
		(size 0.508)
		(drill 0.254)
		(layers "F.Cu" "B.Cu")
		(net "FM_PVCCIO_CPU1_EN")
	)
	(via
		(at 319.8368 -42.7609)
		(size 0.508)
		(drill 0.254)
		(layers "F.Cu" "B.Cu")
		(net "FM_PVCCIO_CPU1_EN")
	)
	(via
		(at 188.3918 -25.908)
		(size 0.508)
		(drill 0.254)
		(layers "F.Cu" "B.Cu")
		(net "FM_PVCCIO_CPU1_EN")
	)
	(via
		(at 374.200674 -81.3435)
		(size 0.508)
		(drill 0.254)
		(layers "F.Cu" "B.Cu")
		(net "FM_PVCCIO_CPU1_EN")
	)
	(via
		(at 311.7088 -54.747922)
		(size 0.508)
		(drill 0.254)
		(layers "F.Cu" "B.Cu")
		(net "FM_PVCCIO_CPU1_EN")
	)
	(segment
		(start 319.8368 -44.4246)
		(end 319.8368 -42.7609)
		(width 0.10795)
		(layer "B.Cu")
		(net "FM_PVCCIO_CPU1_EN")
	)
	(segment
		(start 312.3438 -54.112922)
		(end 312.3438 -51.9176)
		(width 0.10795)
		(layer "B.Cu")
		(net "FM_PVCCIO_CPU1_EN")
	)
	(segment
		(start 165.862 -65.151)
		(end 166.3573 -64.6557)
		(width 0.10795)
		(layer "B.Cu")
		(net "FM_PVCCIO_CPU1_EN")
	)
	(segment
		(start 312.3438 -51.9176)
		(end 319.8368 -44.4246)
		(width 0.10795)
		(layer "B.Cu")
		(net "FM_PVCCIO_CPU1_EN")
	)
	(segment
		(start 166.3573 -64.6557)
		(end 166.3573 -64.375284)
		(width 0.10795)
		(layer "B.Cu")
		(net "FM_PVCCIO_CPU1_EN")
	)
	(segment
		(start 164.973 -66.3702)
		(end 164.973 -66.04)
		(width 0.10795)
		(layer "B.Cu")
		(net "FM_PVCCIO_CPU1_EN")
	)
	(segment
		(start 311.7088 -54.747922)
		(end 312.3438 -54.112922)
		(width 0.10795)
		(layer "B.Cu")
		(net "FM_PVCCIO_CPU1_EN")
	)
	(segment
		(start 164.973 -66.04)
		(end 165.862 -65.151)
		(width 0.10795)
		(layer "B.Cu")
		(net "FM_PVCCIO_CPU1_EN")
	)
	(segment
		(start 261.222998 -29.8323)
		(end 260.027674 -28.636976)
		(width 0.089408)
		(layer "In9.Cu")
		(net "FM_PVCCIO_CPU1_EN")
	)
	(segment
		(start 189.496954 -27.73172)
		(end 188.3918 -26.626566)
		(width 0.089408)
		(layer "In9.Cu")
		(net "FM_PVCCIO_CPU1_EN")
	)
	(segment
		(start 188.3918 -26.626566)
		(end 188.3918 -25.908)
		(width 0.089408)
		(layer "In9.Cu")
		(net "FM_PVCCIO_CPU1_EN")
	)
	(segment
		(start 223.948244 -29.423868)
		(end 222.256096 -27.73172)
		(width 0.089408)
		(layer "In9.Cu")
		(net "FM_PVCCIO_CPU1_EN")
	)
	(segment
		(start 319.2653 -42.1894)
		(end 314.183776 -42.1894)
		(width 0.089408)
		(layer "In9.Cu")
		(net "FM_PVCCIO_CPU1_EN")
	)
	(segment
		(start 262.71093 -29.8323)
		(end 261.222998 -29.8323)
		(width 0.089408)
		(layer "In9.Cu")
		(net "FM_PVCCIO_CPU1_EN")
	)
	(segment
		(start 319.8368 -42.7609)
		(end 319.2653 -42.1894)
		(width 0.089408)
		(layer "In9.Cu")
		(net "FM_PVCCIO_CPU1_EN")
	)
	(segment
		(start 241.679984 -29.423868)
		(end 223.948244 -29.423868)
		(width 0.089408)
		(layer "In9.Cu")
		(net "FM_PVCCIO_CPU1_EN")
	)
	(segment
		(start 314.183776 -42.1894)
		(end 303.679098 -31.684722)
		(width 0.089408)
		(layer "In9.Cu")
		(net "FM_PVCCIO_CPU1_EN")
	)
	(segment
		(start 260.027674 -28.636976)
		(end 242.466876 -28.636976)
		(width 0.089408)
		(layer "In9.Cu")
		(net "FM_PVCCIO_CPU1_EN")
	)
	(segment
		(start 222.256096 -27.73172)
		(end 189.496954 -27.73172)
		(width 0.089408)
		(layer "In9.Cu")
		(net "FM_PVCCIO_CPU1_EN")
	)
	(segment
		(start 264.563352 -31.684722)
		(end 262.71093 -29.8323)
		(width 0.089408)
		(layer "In9.Cu")
		(net "FM_PVCCIO_CPU1_EN")
	)
	(segment
		(start 303.679098 -31.684722)
		(end 264.563352 -31.684722)
		(width 0.089408)
		(layer "In9.Cu")
		(net "FM_PVCCIO_CPU1_EN")
	)
	(segment
		(start 242.466876 -28.636976)
		(end 241.679984 -29.423868)
		(width 0.089408)
		(layer "In9.Cu")
		(net "FM_PVCCIO_CPU1_EN")
	)
	(segment
		(start 188.3918 -30.353)
		(end 188.3918 -25.908)
		(width 0.089408)
		(layer "In11.Cu")
		(net "FM_PVCCIO_CPU1_EN")
	)
	(segment
		(start 166.4716 -62.97168)
		(end 168.346882 -61.096398)
		(width 0.089408)
		(layer "In11.Cu")
		(net "FM_PVCCIO_CPU1_EN")
	)
	(segment
		(start 359.294176 -54.925976)
		(end 363.3978 -59.0296)
		(width 0.089408)
		(layer "In11.Cu")
		(net "FM_PVCCIO_CPU1_EN")
	)
	(segment
		(start 363.3978 -59.0296)
		(end 365.8616 -59.0296)
		(width 0.089408)
		(layer "In11.Cu")
		(net "FM_PVCCIO_CPU1_EN")
	)
	(segment
		(start 311.7088 -54.747922)
		(end 311.7088 -55.042308)
		(width 0.089408)
		(layer "In11.Cu")
		(net "FM_PVCCIO_CPU1_EN")
	)
	(segment
		(start 350.999298 -53.506878)
		(end 352.701606 -53.506878)
		(width 0.089408)
		(layer "In11.Cu")
		(net "FM_PVCCIO_CPU1_EN")
	)
	(segment
		(start 352.701606 -53.506878)
		(end 354.40239 -55.207662)
		(width 0.089408)
		(layer "In11.Cu")
		(net "FM_PVCCIO_CPU1_EN")
	)
	(segment
		(start 318.558672 -59.454034)
		(end 322.539106 -55.4736)
		(width 0.089408)
		(layer "In11.Cu")
		(net "FM_PVCCIO_CPU1_EN")
	)
	(segment
		(start 369.259104 -64.477138)
		(end 369.259104 -64.828674)
		(width 0.089408)
		(layer "In11.Cu")
		(net "FM_PVCCIO_CPU1_EN")
	)
	(segment
		(start 168.346882 -61.096398)
		(end 168.346882 -50.397918)
		(width 0.089408)
		(layer "In11.Cu")
		(net "FM_PVCCIO_CPU1_EN")
	)
	(segment
		(start 371.674136 -67.18427)
		(end 371.674136 -67.608196)
		(width 0.089408)
		(layer "In11.Cu")
		(net "FM_PVCCIO_CPU1_EN")
	)
	(segment
		(start 367.9444 -63.162434)
		(end 369.259104 -64.477138)
		(width 0.089408)
		(layer "In11.Cu")
		(net "FM_PVCCIO_CPU1_EN")
	)
	(segment
		(start 166.4716 -64.260984)
		(end 166.4716 -62.97168)
		(width 0.089408)
		(layer "In11.Cu")
		(net "FM_PVCCIO_CPU1_EN")
	)
	(segment
		(start 349.032576 -55.4736)
		(end 350.999298 -53.506878)
		(width 0.089408)
		(layer "In11.Cu")
		(net "FM_PVCCIO_CPU1_EN")
	)
	(segment
		(start 372.890796 -68.824856)
		(end 372.890796 -80.033622)
		(width 0.089408)
		(layer "In11.Cu")
		(net "FM_PVCCIO_CPU1_EN")
	)
	(segment
		(start 369.259104 -64.828674)
		(end 371.13591 -66.70548)
		(width 0.089408)
		(layer "In11.Cu")
		(net "FM_PVCCIO_CPU1_EN")
	)
	(segment
		(start 355.088952 -55.207662)
		(end 355.370638 -54.925976)
		(width 0.089408)
		(layer "In11.Cu")
		(net "FM_PVCCIO_CPU1_EN")
	)
	(segment
		(start 311.7088 -55.042308)
		(end 316.120526 -59.454034)
		(width 0.089408)
		(layer "In11.Cu")
		(net "FM_PVCCIO_CPU1_EN")
	)
	(segment
		(start 355.370638 -54.925976)
		(end 359.294176 -54.925976)
		(width 0.089408)
		(layer "In11.Cu")
		(net "FM_PVCCIO_CPU1_EN")
	)
	(segment
		(start 371.195346 -66.70548)
		(end 371.674136 -67.18427)
		(width 0.089408)
		(layer "In11.Cu")
		(net "FM_PVCCIO_CPU1_EN")
	)
	(segment
		(start 367.9444 -61.1124)
		(end 367.9444 -63.162434)
		(width 0.089408)
		(layer "In11.Cu")
		(net "FM_PVCCIO_CPU1_EN")
	)
	(segment
		(start 365.8616 -59.0296)
		(end 367.9444 -61.1124)
		(width 0.089408)
		(layer "In11.Cu")
		(net "FM_PVCCIO_CPU1_EN")
	)
	(segment
		(start 166.3573 -64.375284)
		(end 166.4716 -64.260984)
		(width 0.089408)
		(layer "In11.Cu")
		(net "FM_PVCCIO_CPU1_EN")
	)
	(segment
		(start 168.346882 -50.397918)
		(end 188.3918 -30.353)
		(width 0.089408)
		(layer "In11.Cu")
		(net "FM_PVCCIO_CPU1_EN")
	)
	(segment
		(start 371.674136 -67.608196)
		(end 372.890796 -68.824856)
		(width 0.089408)
		(layer "In11.Cu")
		(net "FM_PVCCIO_CPU1_EN")
	)
	(segment
		(start 322.539106 -55.4736)
		(end 349.032576 -55.4736)
		(width 0.089408)
		(layer "In11.Cu")
		(net "FM_PVCCIO_CPU1_EN")
	)
	(segment
		(start 316.120526 -59.454034)
		(end 318.558672 -59.454034)
		(width 0.089408)
		(layer "In11.Cu")
		(net "FM_PVCCIO_CPU1_EN")
	)
	(segment
		(start 371.13591 -66.70548)
		(end 371.195346 -66.70548)
		(width 0.089408)
		(layer "In11.Cu")
		(net "FM_PVCCIO_CPU1_EN")
	)
	(segment
		(start 354.40239 -55.207662)
		(end 355.088952 -55.207662)
		(width 0.089408)
		(layer "In11.Cu")
		(net "FM_PVCCIO_CPU1_EN")
	)
	(segment
		(start 372.890796 -80.033622)
		(end 374.200674 -81.3435)
		(width 0.089408)
		(layer "In11.Cu")
		(net "FM_PVCCIO_CPU1_EN")
	)
	(segment
		(start 374.344692 -77.494892)
		(end 373.944896 -77.095096)
		(width 0.1016)
		(layer "F.Cu")
		(net "FM_PVCCIO_CPU0_EN")
	)
	(via
		(at 340.0298 -72.3138)
		(size 0.508)
		(drill 0.254)
		(layers "F.Cu" "B.Cu")
		(net "FM_PVCCIO_CPU0_EN")
	)
	(via
		(at 374.344692 -77.494892)
		(size 0.4572)
		(drill 0.2032)
		(layers "F.Cu" "B.Cu")
		(net "FM_PVCCIO_CPU0_EN")
	)
	(via
		(at 337.885278 -74.534522)
		(size 0.6604)
		(drill 0.3302)
		(layers "F.Cu" "B.Cu")
		(net "FM_PVCCIO_CPU0_EN")
	)
	(segment
		(start 337.603338 -81.332578)
		(end 337.603338 -79.979266)
		(width 0.10795)
		(layer "B.Cu")
		(net "FM_PVCCIO_CPU0_EN")
	)
	(segment
		(start 336.9818 -79.357728)
		(end 336.9818 -75.438)
		(width 0.10795)
		(layer "B.Cu")
		(net "FM_PVCCIO_CPU0_EN")
	)
	(segment
		(start 336.9818 -75.438)
		(end 337.885278 -74.534522)
		(width 0.10795)
		(layer "B.Cu")
		(net "FM_PVCCIO_CPU0_EN")
	)
	(segment
		(start 338.97316 -82.7024)
		(end 337.603338 -81.332578)
		(width 0.10795)
		(layer "B.Cu")
		(net "FM_PVCCIO_CPU0_EN")
	)
	(segment
		(start 337.603338 -79.979266)
		(end 336.9818 -79.357728)
		(width 0.10795)
		(layer "B.Cu")
		(net "FM_PVCCIO_CPU0_EN")
	)
	(segment
		(start 340.741 -82.7024)
		(end 338.97316 -82.7024)
		(width 0.10795)
		(layer "B.Cu")
		(net "FM_PVCCIO_CPU0_EN")
	)
	(segment
		(start 337.885278 -74.534522)
		(end 340.0298 -72.39)
		(width 0.10795)
		(layer "B.Cu")
		(net "FM_PVCCIO_CPU0_EN")
	)
	(segment
		(start 340.0298 -72.39)
		(end 340.0298 -72.3138)
		(width 0.10795)
		(layer "B.Cu")
		(net "FM_PVCCIO_CPU0_EN")
	)
	(segment
		(start 352.387916 -70.935088)
		(end 354.070158 -70.935088)
		(width 0.089408)
		(layer "In4.Cu")
		(net "FM_PVCCIO_CPU0_EN")
	)
	(segment
		(start 352.192844 -70.740016)
		(end 352.387916 -70.935088)
		(width 0.089408)
		(layer "In4.Cu")
		(net "FM_PVCCIO_CPU0_EN")
	)
	(segment
		(start 367.300002 -75.521312)
		(end 367.518696 -75.740006)
		(width 0.089408)
		(layer "In4.Cu")
		(net "FM_PVCCIO_CPU0_EN")
	)
	(segment
		(start 370.49964 -77.068426)
		(end 370.771928 -76.796138)
		(width 0.089408)
		(layer "In4.Cu")
		(net "FM_PVCCIO_CPU0_EN")
	)
	(segment
		(start 370.771928 -76.796138)
		(end 370.771928 -76.540106)
		(width 0.089408)
		(layer "In4.Cu")
		(net "FM_PVCCIO_CPU0_EN")
	)
	(segment
		(start 367.518696 -75.740006)
		(end 367.518696 -75.996292)
		(width 0.089408)
		(layer "In4.Cu")
		(net "FM_PVCCIO_CPU0_EN")
	)
	(segment
		(start 345.537282 -71.525384)
		(end 346.32265 -70.740016)
		(width 0.089408)
		(layer "In4.Cu")
		(net "FM_PVCCIO_CPU0_EN")
	)
	(segment
		(start 370.771928 -76.540106)
		(end 370.990622 -76.321412)
		(width 0.089408)
		(layer "In4.Cu")
		(net "FM_PVCCIO_CPU0_EN")
	)
	(segment
		(start 354.647754 -70.357492)
		(end 357.239316 -70.357492)
		(width 0.089408)
		(layer "In4.Cu")
		(net "FM_PVCCIO_CPU0_EN")
	)
	(segment
		(start 369.939824 -76.817982)
		(end 370.190268 -77.068426)
		(width 0.089408)
		(layer "In4.Cu")
		(net "FM_PVCCIO_CPU0_EN")
	)
	(segment
		(start 370.990622 -76.321412)
		(end 374.499378 -76.321412)
		(width 0.089408)
		(layer "In4.Cu")
		(net "FM_PVCCIO_CPU0_EN")
	)
	(segment
		(start 367.518696 -75.996292)
		(end 367.824004 -76.3016)
		(width 0.089408)
		(layer "In4.Cu")
		(net "FM_PVCCIO_CPU0_EN")
	)
	(segment
		(start 367.824004 -76.3016)
		(end 369.679982 -76.3016)
		(width 0.089408)
		(layer "In4.Cu")
		(net "FM_PVCCIO_CPU0_EN")
	)
	(segment
		(start 346.32265 -70.740016)
		(end 352.192844 -70.740016)
		(width 0.089408)
		(layer "In4.Cu")
		(net "FM_PVCCIO_CPU0_EN")
	)
	(segment
		(start 374.718072 -77.121512)
		(end 374.344692 -77.494892)
		(width 0.089408)
		(layer "In4.Cu")
		(net "FM_PVCCIO_CPU0_EN")
	)
	(segment
		(start 357.239316 -70.357492)
		(end 358.468676 -71.586852)
		(width 0.089408)
		(layer "In4.Cu")
		(net "FM_PVCCIO_CPU0_EN")
	)
	(segment
		(start 369.939824 -76.561442)
		(end 369.939824 -76.817982)
		(width 0.089408)
		(layer "In4.Cu")
		(net "FM_PVCCIO_CPU0_EN")
	)
	(segment
		(start 369.679982 -76.3016)
		(end 369.939824 -76.561442)
		(width 0.089408)
		(layer "In4.Cu")
		(net "FM_PVCCIO_CPU0_EN")
	)
	(segment
		(start 367.043208 -75.521312)
		(end 367.300002 -75.521312)
		(width 0.089408)
		(layer "In4.Cu")
		(net "FM_PVCCIO_CPU0_EN")
	)
	(segment
		(start 354.070158 -70.935088)
		(end 354.647754 -70.357492)
		(width 0.089408)
		(layer "In4.Cu")
		(net "FM_PVCCIO_CPU0_EN")
	)
	(segment
		(start 340.818216 -71.525384)
		(end 345.537282 -71.525384)
		(width 0.089408)
		(layer "In4.Cu")
		(net "FM_PVCCIO_CPU0_EN")
	)
	(segment
		(start 370.190268 -77.068426)
		(end 370.49964 -77.068426)
		(width 0.089408)
		(layer "In4.Cu")
		(net "FM_PVCCIO_CPU0_EN")
	)
	(segment
		(start 374.499378 -76.321412)
		(end 374.718072 -76.540106)
		(width 0.089408)
		(layer "In4.Cu")
		(net "FM_PVCCIO_CPU0_EN")
	)
	(segment
		(start 340.0298 -72.3138)
		(end 340.818216 -71.525384)
		(width 0.089408)
		(layer "In4.Cu")
		(net "FM_PVCCIO_CPU0_EN")
	)
	(segment
		(start 363.108748 -71.586852)
		(end 367.043208 -75.521312)
		(width 0.089408)
		(layer "In4.Cu")
		(net "FM_PVCCIO_CPU0_EN")
	)
	(segment
		(start 358.468676 -71.586852)
		(end 363.108748 -71.586852)
		(width 0.089408)
		(layer "In4.Cu")
		(net "FM_PVCCIO_CPU0_EN")
	)
	(segment
		(start 374.718072 -76.540106)
		(end 374.718072 -77.121512)
		(width 0.089408)
		(layer "In4.Cu")
		(net "FM_PVCCIO_CPU0_EN")
	)
	(segment
		(start 418.973 -83.580986)
		(end 419.859714 -83.580986)
		(width 0.10795)
		(layer "F.Cu")
		(net "FM_PMBUS_ALERT_BUF_EN")
	)
	(via
		(at 419.859714 -83.580986)
		(size 0.508)
		(drill 0.254)
		(layers "F.Cu" "B.Cu")
		(net "FM_PMBUS_ALERT_BUF_EN")
	)
	(via
		(at 418.823394 -82.984594)
		(size 0.6604)
		(drill 0.3302)
		(layers "F.Cu" "B.Cu")
		(net "FM_PMBUS_ALERT_BUF_EN")
	)
	(segment
		(start 418.823394 -82.984594)
		(end 418.577268 -82.738468)
		(width 0.10795)
		(layer "B.Cu")
		(net "FM_PMBUS_ALERT_BUF_EN")
	)
	(segment
		(start 418.577268 -82.738468)
		(end 418.577268 -81.3816)
		(width 0.10795)
		(layer "B.Cu")
		(net "FM_PMBUS_ALERT_BUF_EN")
	)
	(segment
		(start 419.220142 -79.222092)
		(end 419.220142 -81.153)
		(width 0.10795)
		(layer "B.Cu")
		(net "FM_PMBUS_ALERT_BUF_EN")
	)
	(segment
		(start 419.859714 -83.580986)
		(end 419.419786 -83.580986)
		(width 0.10795)
		(layer "B.Cu")
		(net "FM_PMBUS_ALERT_BUF_EN")
	)
	(segment
		(start 418.99205 -78.994)
		(end 419.220142 -79.222092)
		(width 0.10795)
		(layer "B.Cu")
		(net "FM_PMBUS_ALERT_BUF_EN")
	)
	(segment
		(start 418.805868 -81.153)
		(end 419.220142 -81.153)
		(width 0.10795)
		(layer "B.Cu")
		(net "FM_PMBUS_ALERT_BUF_EN")
	)
	(segment
		(start 419.419786 -83.580986)
		(end 418.823394 -82.984594)
		(width 0.10795)
		(layer "B.Cu")
		(net "FM_PMBUS_ALERT_BUF_EN")
	)
	(segment
		(start 418.577268 -81.3816)
		(end 418.805868 -81.153)
		(width 0.10795)
		(layer "B.Cu")
		(net "FM_PMBUS_ALERT_BUF_EN")
	)
	(segment
		(start 418.1475 -78.994)
		(end 418.99205 -78.994)
		(width 0.10795)
		(layer "B.Cu")
		(net "FM_PMBUS_ALERT_BUF_EN")
	)
	(segment
		(start 470.692988 -148.0185)
		(end 473.075 -148.0185)
		(width 0.10795)
		(layer "F.Cu")
		(net "FM_PCH_SATA_RAID_KEY_R")
	)
	(segment
		(start 470.2175 -148.493988)
		(end 470.692988 -148.0185)
		(width 0.10795)
		(layer "F.Cu")
		(net "FM_PCH_SATA_RAID_KEY_R")
	)
	(segment
		(start 473.075 -148.0185)
		(end 473.075 -146.7485)
		(width 0.10795)
		(layer "F.Cu")
		(net "FM_PCH_SATA_RAID_KEY_R")
	)
	(via
		(at 467.1568 -149.763226)
		(size 0.6604)
		(drill 0.3302)
		(layers "F.Cu" "B.Cu")
		(net "FM_PCH_SATA_RAID_KEY_R")
	)
	(segment
		(start 469.155526 -149.555962)
		(end 470.2175 -148.493988)
		(width 0.10795)
		(layer "B.Cu")
		(net "FM_PCH_SATA_RAID_KEY_R")
	)
	(segment
		(start 467.1568 -149.763226)
		(end 467.364064 -149.555962)
		(width 0.10795)
		(layer "B.Cu")
		(net "FM_PCH_SATA_RAID_KEY_R")
	)
	(segment
		(start 467.364064 -149.555962)
		(end 469.155526 -149.555962)
		(width 0.10795)
		(layer "B.Cu")
		(net "FM_PCH_SATA_RAID_KEY_R")
	)
	(segment
		(start 473.7354 -146.0246)
		(end 473.7354 -150.0886)
		(width 0.10795)
		(layer "F.Cu")
		(net "FM_PCH_SATA_RAID_KEY")
	)
	(segment
		(start 400.42211 -107.354878)
		(end 400.739102 -107.67187)
		(width 0.0889)
		(layer "F.Cu")
		(net "FM_PCH_SATA_RAID_KEY")
	)
	(segment
		(start 401.451826 -107.569254)
		(end 401.457922 -107.57535)
		(width 0.0889)
		(layer "F.Cu")
		(net "FM_PCH_SATA_RAID_KEY")
	)
	(segment
		(start 401.02155 -107.67187)
		(end 401.088606 -107.604814)
		(width 0.0889)
		(layer "F.Cu")
		(net "FM_PCH_SATA_RAID_KEY")
	)
	(segment
		(start 480.017582 -158.58871)
		(end 498.225318 -158.58871)
		(width 0.10795)
		(layer "F.Cu")
		(net "FM_PCH_SATA_RAID_KEY")
	)
	(segment
		(start 474.19768 -150.55088)
		(end 476.25508 -150.55088)
		(width 0.10795)
		(layer "F.Cu")
		(net "FM_PCH_SATA_RAID_KEY")
	)
	(segment
		(start 478.699322 -153.862786)
		(end 478.699322 -157.27045)
		(width 0.10795)
		(layer "F.Cu")
		(net "FM_PCH_SATA_RAID_KEY")
	)
	(segment
		(start 478.699322 -157.27045)
		(end 480.017582 -158.58871)
		(width 0.10795)
		(layer "F.Cu")
		(net "FM_PCH_SATA_RAID_KEY")
	)
	(segment
		(start 400.739102 -107.67187)
		(end 401.02155 -107.67187)
		(width 0.0889)
		(layer "F.Cu")
		(net "FM_PCH_SATA_RAID_KEY")
	)
	(segment
		(start 401.088606 -107.604814)
		(end 401.10283 -107.604814)
		(width 0.0889)
		(layer "F.Cu")
		(net "FM_PCH_SATA_RAID_KEY")
	)
	(segment
		(start 498.225318 -158.58871)
		(end 499.2116 -157.602428)
		(width 0.10795)
		(layer "F.Cu")
		(net "FM_PCH_SATA_RAID_KEY")
	)
	(segment
		(start 401.10283 -107.604814)
		(end 401.13839 -107.569254)
		(width 0.0889)
		(layer "F.Cu")
		(net "FM_PCH_SATA_RAID_KEY")
	)
	(segment
		(start 478.4344 -153.597864)
		(end 478.699322 -153.862786)
		(width 0.10795)
		(layer "F.Cu")
		(net "FM_PCH_SATA_RAID_KEY")
	)
	(segment
		(start 499.2116 -157.602428)
		(end 499.2116 -157.353)
		(width 0.10795)
		(layer "F.Cu")
		(net "FM_PCH_SATA_RAID_KEY")
	)
	(segment
		(start 401.13839 -107.569254)
		(end 401.451826 -107.569254)
		(width 0.0889)
		(layer "F.Cu")
		(net "FM_PCH_SATA_RAID_KEY")
	)
	(segment
		(start 476.25508 -150.55088)
		(end 478.4344 -152.7302)
		(width 0.10795)
		(layer "F.Cu")
		(net "FM_PCH_SATA_RAID_KEY")
	)
	(segment
		(start 473.5703 -145.8595)
		(end 473.7354 -146.0246)
		(width 0.10795)
		(layer "F.Cu")
		(net "FM_PCH_SATA_RAID_KEY")
	)
	(segment
		(start 402.444712 -107.884468)
		(end 402.905468 -107.884468)
		(width 0.0889)
		(layer "F.Cu")
		(net "FM_PCH_SATA_RAID_KEY")
	)
	(segment
		(start 402.135594 -107.57535)
		(end 402.444712 -107.884468)
		(width 0.0889)
		(layer "F.Cu")
		(net "FM_PCH_SATA_RAID_KEY")
	)
	(segment
		(start 400.05 -107.354878)
		(end 400.42211 -107.354878)
		(width 0.0889)
		(layer "F.Cu")
		(net "FM_PCH_SATA_RAID_KEY")
	)
	(segment
		(start 402.905468 -107.884468)
		(end 403.142196 -108.121196)
		(width 0.0889)
		(layer "F.Cu")
		(net "FM_PCH_SATA_RAID_KEY")
	)
	(segment
		(start 403.142196 -108.121196)
		(end 403.706584 -108.121196)
		(width 0.0889)
		(layer "F.Cu")
		(net "FM_PCH_SATA_RAID_KEY")
	)
	(segment
		(start 401.457922 -107.57535)
		(end 402.135594 -107.57535)
		(width 0.0889)
		(layer "F.Cu")
		(net "FM_PCH_SATA_RAID_KEY")
	)
	(segment
		(start 473.075 -145.8595)
		(end 473.5703 -145.8595)
		(width 0.10795)
		(layer "F.Cu")
		(net "FM_PCH_SATA_RAID_KEY")
	)
	(segment
		(start 473.7354 -150.0886)
		(end 474.19768 -150.55088)
		(width 0.10795)
		(layer "F.Cu")
		(net "FM_PCH_SATA_RAID_KEY")
	)
	(segment
		(start 478.4344 -152.7302)
		(end 478.4344 -153.597864)
		(width 0.10795)
		(layer "F.Cu")
		(net "FM_PCH_SATA_RAID_KEY")
	)
	(via
		(at 499.2116 -157.353)
		(size 0.508)
		(drill 0.254)
		(layers "F.Cu" "B.Cu")
		(net "FM_PCH_SATA_RAID_KEY")
	)
	(via
		(at 403.706584 -108.121196)
		(size 0.508)
		(drill 0.254)
		(layers "F.Cu" "B.Cu")
		(net "FM_PCH_SATA_RAID_KEY")
	)
	(via
		(at 421.851836 -102.853236)
		(size 0.508)
		(drill 0.254)
		(layers "F.Cu" "B.Cu")
		(net "FM_PCH_SATA_RAID_KEY")
	)
	(segment
		(start 420.735506 -103.969566)
		(end 415.03981 -103.969566)
		(width 0.089408)
		(layer "In4.Cu")
		(net "FM_PCH_SATA_RAID_KEY")
	)
	(segment
		(start 403.706584 -105.60177)
		(end 403.706584 -108.121196)
		(width 0.089408)
		(layer "In4.Cu")
		(net "FM_PCH_SATA_RAID_KEY")
	)
	(segment
		(start 414.518348 -104.491028)
		(end 414.518348 -105.30713)
		(width 0.089408)
		(layer "In4.Cu")
		(net "FM_PCH_SATA_RAID_KEY")
	)
	(segment
		(start 411.142942 -103.422196)
		(end 409.274264 -103.422196)
		(width 0.089408)
		(layer "In4.Cu")
		(net "FM_PCH_SATA_RAID_KEY")
	)
	(segment
		(start 409.274264 -103.422196)
		(end 408.471116 -104.225344)
		(width 0.089408)
		(layer "In4.Cu")
		(net "FM_PCH_SATA_RAID_KEY")
	)
	(segment
		(start 413.262318 -105.541572)
		(end 411.142942 -103.422196)
		(width 0.089408)
		(layer "In4.Cu")
		(net "FM_PCH_SATA_RAID_KEY")
	)
	(segment
		(start 414.518348 -105.30713)
		(end 414.283906 -105.541572)
		(width 0.089408)
		(layer "In4.Cu")
		(net "FM_PCH_SATA_RAID_KEY")
	)
	(segment
		(start 421.851836 -102.853236)
		(end 420.735506 -103.969566)
		(width 0.089408)
		(layer "In4.Cu")
		(net "FM_PCH_SATA_RAID_KEY")
	)
	(segment
		(start 414.283906 -105.541572)
		(end 413.262318 -105.541572)
		(width 0.089408)
		(layer "In4.Cu")
		(net "FM_PCH_SATA_RAID_KEY")
	)
	(segment
		(start 405.08301 -104.225344)
		(end 403.706584 -105.60177)
		(width 0.089408)
		(layer "In4.Cu")
		(net "FM_PCH_SATA_RAID_KEY")
	)
	(segment
		(start 408.471116 -104.225344)
		(end 405.08301 -104.225344)
		(width 0.089408)
		(layer "In4.Cu")
		(net "FM_PCH_SATA_RAID_KEY")
	)
	(segment
		(start 415.03981 -103.969566)
		(end 414.518348 -104.491028)
		(width 0.089408)
		(layer "In4.Cu")
		(net "FM_PCH_SATA_RAID_KEY")
	)
	(segment
		(start 421.851836 -102.853236)
		(end 422.639236 -103.640636)
		(width 0.089408)
		(layer "In9.Cu")
		(net "FM_PCH_SATA_RAID_KEY")
	)
	(segment
		(start 426.6438 -106.0196)
		(end 426.6438 -109.441996)
		(width 0.089408)
		(layer "In9.Cu")
		(net "FM_PCH_SATA_RAID_KEY")
	)
	(segment
		(start 497.862352 -110.381796)
		(end 501.20296 -113.722404)
		(width 0.089408)
		(layer "In9.Cu")
		(net "FM_PCH_SATA_RAID_KEY")
	)
	(segment
		(start 426.6438 -109.441996)
		(end 427.590204 -110.3884)
		(width 0.089408)
		(layer "In9.Cu")
		(net "FM_PCH_SATA_RAID_KEY")
	)
	(segment
		(start 482.596444 -111.477044)
		(end 491.132876 -111.477044)
		(width 0.089408)
		(layer "In9.Cu")
		(net "FM_PCH_SATA_RAID_KEY")
	)
	(segment
		(start 500.665496 -134.080504)
		(end 500.665496 -155.899104)
		(width 0.089408)
		(layer "In9.Cu")
		(net "FM_PCH_SATA_RAID_KEY")
	)
	(segment
		(start 501.20296 -133.54304)
		(end 500.665496 -134.080504)
		(width 0.089408)
		(layer "In9.Cu")
		(net "FM_PCH_SATA_RAID_KEY")
	)
	(segment
		(start 491.132876 -111.477044)
		(end 492.228124 -110.381796)
		(width 0.089408)
		(layer "In9.Cu")
		(net "FM_PCH_SATA_RAID_KEY")
	)
	(segment
		(start 422.639236 -103.640636)
		(end 424.264836 -103.640636)
		(width 0.089408)
		(layer "In9.Cu")
		(net "FM_PCH_SATA_RAID_KEY")
	)
	(segment
		(start 424.264836 -103.640636)
		(end 426.6438 -106.0196)
		(width 0.089408)
		(layer "In9.Cu")
		(net "FM_PCH_SATA_RAID_KEY")
	)
	(segment
		(start 481.5078 -110.3884)
		(end 482.596444 -111.477044)
		(width 0.089408)
		(layer "In9.Cu")
		(net "FM_PCH_SATA_RAID_KEY")
	)
	(segment
		(start 492.228124 -110.381796)
		(end 497.862352 -110.381796)
		(width 0.089408)
		(layer "In9.Cu")
		(net "FM_PCH_SATA_RAID_KEY")
	)
	(segment
		(start 427.590204 -110.3884)
		(end 481.5078 -110.3884)
		(width 0.089408)
		(layer "In9.Cu")
		(net "FM_PCH_SATA_RAID_KEY")
	)
	(segment
		(start 500.665496 -155.899104)
		(end 499.2116 -157.353)
		(width 0.089408)
		(layer "In9.Cu")
		(net "FM_PCH_SATA_RAID_KEY")
	)
	(segment
		(start 501.20296 -113.722404)
		(end 501.20296 -133.54304)
		(width 0.089408)
		(layer "In9.Cu")
		(net "FM_PCH_SATA_RAID_KEY")
	)
	(segment
		(start 382.3462 -99.526344)
		(end 382.397 -99.502722)
		(width 0.10795)
		(layer "F.Cu")
		(net "FM_PCH_LVC1_THERMTRIP_N")
	)
	(segment
		(start 382.397 -99.502722)
		(end 382.78435 -99.322636)
		(width 0.10795)
		(layer "F.Cu")
		(net "FM_PCH_LVC1_THERMTRIP_N")
	)
	(segment
		(start 382.28905 -99.55276)
		(end 382.3462 -99.526344)
		(width 0.10795)
		(layer "F.Cu")
		(net "FM_PCH_LVC1_THERMTRIP_N")
	)
	(via
		(at 377.4059 -89.027)
		(size 0.6604)
		(drill 0.3302)
		(layers "F.Cu" "B.Cu")
		(net "FM_PCH_LVC1_THERMTRIP_N")
	)
	(via
		(at 382.78435 -99.322636)
		(size 0.508)
		(drill 0.254)
		(layers "F.Cu" "B.Cu")
		(net "FM_PCH_LVC1_THERMTRIP_N")
	)
	(segment
		(start 375.038874 -86.02853)
		(end 375.038874 -86.829138)
		(width 0.10795)
		(layer "B.Cu")
		(net "FM_PCH_LVC1_THERMTRIP_N")
	)
	(segment
		(start 378.496068 -90.688668)
		(end 378.496068 -92.423996)
		(width 0.10795)
		(layer "B.Cu")
		(net "FM_PCH_LVC1_THERMTRIP_N")
	)
	(segment
		(start 380.195836 -94.123764)
		(end 380.195836 -94.268036)
		(width 0.10795)
		(layer "B.Cu")
		(net "FM_PCH_LVC1_THERMTRIP_N")
	)
	(segment
		(start 380.195836 -94.268036)
		(end 381.034036 -95.106236)
		(width 0.10795)
		(layer "B.Cu")
		(net "FM_PCH_LVC1_THERMTRIP_N")
	)
	(segment
		(start 382.3843 -97.584006)
		(end 382.3843 -97.616772)
		(width 0.0889)
		(layer "B.Cu")
		(net "FM_PCH_LVC1_THERMTRIP_N")
	)
	(segment
		(start 375.395236 -87.1855)
		(end 376.174 -87.1855)
		(width 0.10795)
		(layer "B.Cu")
		(net "FM_PCH_LVC1_THERMTRIP_N")
	)
	(segment
		(start 382.63957 -98.940112)
		(end 382.61544 -99.02952)
		(width 0.0889)
		(layer "B.Cu")
		(net "FM_PCH_LVC1_THERMTRIP_N")
	)
	(segment
		(start 376.174 -87.1855)
		(end 376.3645 -87.1855)
		(width 0.10795)
		(layer "B.Cu")
		(net "FM_PCH_LVC1_THERMTRIP_N")
	)
	(segment
		(start 377.6472 -89.8398)
		(end 378.496068 -90.688668)
		(width 0.10795)
		(layer "B.Cu")
		(net "FM_PCH_LVC1_THERMTRIP_N")
	)
	(segment
		(start 382.61544 -99.02952)
		(end 382.78435 -99.322636)
		(width 0.0889)
		(layer "B.Cu")
		(net "FM_PCH_LVC1_THERMTRIP_N")
	)
	(segment
		(start 381.889 -96.725486)
		(end 381.889 -96.758252)
		(width 0.0889)
		(layer "B.Cu")
		(net "FM_PCH_LVC1_THERMTRIP_N")
	)
	(segment
		(start 377.062746 -89.027)
		(end 377.4059 -89.027)
		(width 0.10795)
		(layer "B.Cu")
		(net "FM_PCH_LVC1_THERMTRIP_N")
	)
	(segment
		(start 378.496068 -92.423996)
		(end 380.195836 -94.123764)
		(width 0.10795)
		(layer "B.Cu")
		(net "FM_PCH_LVC1_THERMTRIP_N")
	)
	(segment
		(start 377.444 -89.027)
		(end 377.6472 -89.2302)
		(width 0.10795)
		(layer "B.Cu")
		(net "FM_PCH_LVC1_THERMTRIP_N")
	)
	(segment
		(start 381.034036 -95.106236)
		(end 381.3937 -95.4659)
		(width 0.0889)
		(layer "B.Cu")
		(net "FM_PCH_LVC1_THERMTRIP_N")
	)
	(segment
		(start 382.8796 -98.442526)
		(end 382.8796 -98.485706)
		(width 0.0889)
		(layer "B.Cu")
		(net "FM_PCH_LVC1_THERMTRIP_N")
	)
	(segment
		(start 377.6472 -89.2302)
		(end 377.6472 -89.8398)
		(width 0.10795)
		(layer "B.Cu")
		(net "FM_PCH_LVC1_THERMTRIP_N")
	)
	(segment
		(start 381.3937 -95.4659)
		(end 381.3937 -95.899732)
		(width 0.0889)
		(layer "B.Cu")
		(net "FM_PCH_LVC1_THERMTRIP_N")
	)
	(segment
		(start 376.6185 -88.582754)
		(end 377.062746 -89.027)
		(width 0.10795)
		(layer "B.Cu")
		(net "FM_PCH_LVC1_THERMTRIP_N")
	)
	(segment
		(start 376.3645 -87.1855)
		(end 376.6185 -87.4395)
		(width 0.10795)
		(layer "B.Cu")
		(net "FM_PCH_LVC1_THERMTRIP_N")
	)
	(segment
		(start 377.4059 -89.027)
		(end 377.444 -89.027)
		(width 0.10795)
		(layer "B.Cu")
		(net "FM_PCH_LVC1_THERMTRIP_N")
	)
	(segment
		(start 375.038874 -86.829138)
		(end 375.395236 -87.1855)
		(width 0.10795)
		(layer "B.Cu")
		(net "FM_PCH_LVC1_THERMTRIP_N")
	)
	(segment
		(start 376.6185 -87.4395)
		(end 376.6185 -88.582754)
		(width 0.10795)
		(layer "B.Cu")
		(net "FM_PCH_LVC1_THERMTRIP_N")
	)
	(arc
		(start 381.3937 -95.899732)
		(mid 381.45005 -96.093582)
		(end 381.593852 -96.235266)
		(width 0.0889)
		(layer "B.Cu")
		(net "FM_PCH_LVC1_THERMTRIP_N")
	)
	(arc
		(start 382.584452 -97.952306)
		(mid 382.795316 -98.15931)
		(end 382.8796 -98.442526)
		(width 0.0889)
		(layer "B.Cu")
		(net "FM_PCH_LVC1_THERMTRIP_N")
	)
	(arc
		(start 381.889 -96.758252)
		(mid 381.94535 -96.952102)
		(end 382.089152 -97.093786)
		(width 0.0889)
		(layer "B.Cu")
		(net "FM_PCH_LVC1_THERMTRIP_N")
	)
	(arc
		(start 382.3843 -97.616772)
		(mid 382.44065 -97.810622)
		(end 382.584452 -97.952306)
		(width 0.0889)
		(layer "B.Cu")
		(net "FM_PCH_LVC1_THERMTRIP_N")
	)
	(arc
		(start 382.089152 -97.093786)
		(mid 382.300016 -97.30079)
		(end 382.3843 -97.584006)
		(width 0.0889)
		(layer "B.Cu")
		(net "FM_PCH_LVC1_THERMTRIP_N")
	)
	(arc
		(start 381.593852 -96.235266)
		(mid 381.804716 -96.44227)
		(end 381.889 -96.725486)
		(width 0.0889)
		(layer "B.Cu")
		(net "FM_PCH_LVC1_THERMTRIP_N")
	)
	(arc
		(start 382.8796 -98.485706)
		(mid 382.811571 -98.740371)
		(end 382.63957 -98.940112)
		(width 0.0889)
		(layer "B.Cu")
		(net "FM_PCH_LVC1_THERMTRIP_N")
	)
	(segment
		(start 398.954752 -80.082644)
		(end 398.811496 -80.2259)
		(width 0.10795)
		(layer "F.Cu")
		(net "FM_PCH_BMC_THERMTRIP_N")
	)
	(segment
		(start 395.485112 -93.333316)
		(end 395.365478 -93.213682)
		(width 0.0889)
		(layer "F.Cu")
		(net "FM_PCH_BMC_THERMTRIP_N")
	)
	(segment
		(start 401.989798 -75.606402)
		(end 401.1676 -76.4286)
		(width 0.10795)
		(layer "F.Cu")
		(net "FM_PCH_BMC_THERMTRIP_N")
	)
	(segment
		(start 401.1676 -76.71943)
		(end 399.922238 -77.964792)
		(width 0.10795)
		(layer "F.Cu")
		(net "FM_PCH_BMC_THERMTRIP_N")
	)
	(segment
		(start 399.373344 -72.914002)
		(end 399.383758 -72.924416)
		(width 0.10795)
		(layer "F.Cu")
		(net "FM_PCH_BMC_THERMTRIP_N")
	)
	(segment
		(start 401.1676 -76.4286)
		(end 401.1676 -76.71943)
		(width 0.10795)
		(layer "F.Cu")
		(net "FM_PCH_BMC_THERMTRIP_N")
	)
	(segment
		(start 399.383758 -72.924416)
		(end 399.383758 -73.026778)
		(width 0.10795)
		(layer "F.Cu")
		(net "FM_PCH_BMC_THERMTRIP_N")
	)
	(segment
		(start 398.811496 -81.087722)
		(end 398.419574 -81.479644)
		(width 0.10795)
		(layer "F.Cu")
		(net "FM_PCH_BMC_THERMTRIP_N")
	)
	(segment
		(start 402.3868 -73.922382)
		(end 402.3868 -75.298808)
		(width 0.10795)
		(layer "F.Cu")
		(net "FM_PCH_BMC_THERMTRIP_N")
	)
	(segment
		(start 397.9799 -87.0839)
		(end 397.9799 -87.4649)
		(width 0.10795)
		(layer "F.Cu")
		(net "FM_PCH_BMC_THERMTRIP_N")
	)
	(segment
		(start 398.688052 -86.375748)
		(end 397.9799 -87.0839)
		(width 0.10795)
		(layer "F.Cu")
		(net "FM_PCH_BMC_THERMTRIP_N")
	)
	(segment
		(start 401.725638 -73.26122)
		(end 402.3868 -73.922382)
		(width 0.10795)
		(layer "F.Cu")
		(net "FM_PCH_BMC_THERMTRIP_N")
	)
	(segment
		(start 400.205702 -83.596988)
		(end 400.205702 -86.039706)
		(width 0.10795)
		(layer "F.Cu")
		(net "FM_PCH_BMC_THERMTRIP_N")
	)
	(segment
		(start 399.816574 -80.082644)
		(end 398.954752 -80.082644)
		(width 0.10795)
		(layer "F.Cu")
		(net "FM_PCH_BMC_THERMTRIP_N")
	)
	(segment
		(start 399.922238 -79.97698)
		(end 399.816574 -80.082644)
		(width 0.10795)
		(layer "F.Cu")
		(net "FM_PCH_BMC_THERMTRIP_N")
	)
	(segment
		(start 398.419574 -82.150204)
		(end 398.758918 -82.150204)
		(width 0.10795)
		(layer "F.Cu")
		(net "FM_PCH_BMC_THERMTRIP_N")
	)
	(segment
		(start 402.079206 -75.606402)
		(end 401.989798 -75.606402)
		(width 0.10795)
		(layer "F.Cu")
		(net "FM_PCH_BMC_THERMTRIP_N")
	)
	(segment
		(start 398.811496 -80.2259)
		(end 398.811496 -81.087722)
		(width 0.10795)
		(layer "F.Cu")
		(net "FM_PCH_BMC_THERMTRIP_N")
	)
	(segment
		(start 399.383758 -73.026778)
		(end 399.6182 -73.26122)
		(width 0.10795)
		(layer "F.Cu")
		(net "FM_PCH_BMC_THERMTRIP_N")
	)
	(segment
		(start 399.6182 -73.26122)
		(end 401.725638 -73.26122)
		(width 0.10795)
		(layer "F.Cu")
		(net "FM_PCH_BMC_THERMTRIP_N")
	)
	(segment
		(start 398.758918 -82.150204)
		(end 400.205702 -83.596988)
		(width 0.10795)
		(layer "F.Cu")
		(net "FM_PCH_BMC_THERMTRIP_N")
	)
	(segment
		(start 395.56944 -90.72626)
		(end 397.9799 -88.3158)
		(width 0.10795)
		(layer "F.Cu")
		(net "FM_PCH_BMC_THERMTRIP_N")
	)
	(segment
		(start 399.86966 -86.375748)
		(end 398.688052 -86.375748)
		(width 0.10795)
		(layer "F.Cu")
		(net "FM_PCH_BMC_THERMTRIP_N")
	)
	(segment
		(start 395.365478 -90.930222)
		(end 395.56944 -90.72626)
		(width 0.0889)
		(layer "F.Cu")
		(net "FM_PCH_BMC_THERMTRIP_N")
	)
	(segment
		(start 397.9799 -88.3158)
		(end 397.9799 -87.4649)
		(width 0.10795)
		(layer "F.Cu")
		(net "FM_PCH_BMC_THERMTRIP_N")
	)
	(segment
		(start 400.205702 -86.039706)
		(end 399.86966 -86.375748)
		(width 0.10795)
		(layer "F.Cu")
		(net "FM_PCH_BMC_THERMTRIP_N")
	)
	(segment
		(start 395.485112 -93.959934)
		(end 395.485112 -93.333316)
		(width 0.0889)
		(layer "F.Cu")
		(net "FM_PCH_BMC_THERMTRIP_N")
	)
	(segment
		(start 398.419574 -81.479644)
		(end 398.419574 -82.150204)
		(width 0.10795)
		(layer "F.Cu")
		(net "FM_PCH_BMC_THERMTRIP_N")
	)
	(segment
		(start 402.3868 -75.298808)
		(end 402.079206 -75.606402)
		(width 0.10795)
		(layer "F.Cu")
		(net "FM_PCH_BMC_THERMTRIP_N")
	)
	(segment
		(start 408.690064 -40.93464)
		(end 408.290014 -41.33469)
		(width 0.10795)
		(layer "F.Cu")
		(net "FM_PCH_BMC_THERMTRIP_N")
	)
	(segment
		(start 395.365478 -93.213682)
		(end 395.365478 -90.930222)
		(width 0.0889)
		(layer "F.Cu")
		(net "FM_PCH_BMC_THERMTRIP_N")
	)
	(segment
		(start 399.922238 -77.964792)
		(end 399.922238 -79.97698)
		(width 0.10795)
		(layer "F.Cu")
		(net "FM_PCH_BMC_THERMTRIP_N")
	)
	(via
		(at 408.290014 -41.33469)
		(size 0.4572)
		(drill 0.2032)
		(layers "F.Cu" "B.Cu")
		(net "FM_PCH_BMC_THERMTRIP_N")
	)
	(via
		(at 399.373344 -72.914002)
		(size 0.508)
		(drill 0.254)
		(layers "F.Cu" "B.Cu")
		(net "FM_PCH_BMC_THERMTRIP_N")
	)
	(via
		(at 398.33042 -72.98182)
		(size 0.6604)
		(drill 0.3302)
		(layers "F.Cu" "B.Cu")
		(net "FM_PCH_BMC_THERMTRIP_N")
	)
	(segment
		(start 399.373344 -72.914002)
		(end 398.398238 -72.914002)
		(width 0.10795)
		(layer "B.Cu")
		(net "FM_PCH_BMC_THERMTRIP_N")
	)
	(segment
		(start 398.398238 -72.914002)
		(end 398.33042 -72.98182)
		(width 0.10795)
		(layer "B.Cu")
		(net "FM_PCH_BMC_THERMTRIP_N")
	)
	(segment
		(start 399.358612 -68.777866)
		(end 401.566888 -66.56959)
		(width 0.089408)
		(layer "In9.Cu")
		(net "FM_PCH_BMC_THERMTRIP_N")
	)
	(segment
		(start 404.590758 -44.202096)
		(end 404.590758 -44.201842)
		(width 0.089408)
		(layer "In9.Cu")
		(net "FM_PCH_BMC_THERMTRIP_N")
	)
	(segment
		(start 401.261072 -55.82412)
		(end 401.261072 -50.04816)
		(width 0.089408)
		(layer "In9.Cu")
		(net "FM_PCH_BMC_THERMTRIP_N")
	)
	(segment
		(start 402.908516 -60.958222)
		(end 402.908262 -60.957968)
		(width 0.089408)
		(layer "In9.Cu")
		(net "FM_PCH_BMC_THERMTRIP_N")
	)
	(segment
		(start 403.895052 -45.770292)
		(end 403.895052 -45.746416)
		(width 0.0889)
		(layer "In9.Cu")
		(net "FM_PCH_BMC_THERMTRIP_N")
	)
	(segment
		(start 399.373344 -72.914002)
		(end 398.980914 -72.914002)
		(width 0.089408)
		(layer "In9.Cu")
		(net "FM_PCH_BMC_THERMTRIP_N")
	)
	(segment
		(start 402.908008 -57.788048)
		(end 401.260818 -56.140858)
		(width 0.089408)
		(layer "In9.Cu")
		(net "FM_PCH_BMC_THERMTRIP_N")
	)
	(segment
		(start 398.708118 -72.097392)
		(end 399.358612 -71.446898)
		(width 0.089408)
		(layer "In9.Cu")
		(net "FM_PCH_BMC_THERMTRIP_N")
	)
	(segment
		(start 402.908516 -62.384178)
		(end 402.908516 -60.958222)
		(width 0.089408)
		(layer "In9.Cu")
		(net "FM_PCH_BMC_THERMTRIP_N")
	)
	(segment
		(start 405.956008 -44.10964)
		(end 406.315164 -43.750484)
		(width 0.089408)
		(layer "In9.Cu")
		(net "FM_PCH_BMC_THERMTRIP_N")
	)
	(segment
		(start 402.908008 -60.402978)
		(end 402.908008 -57.788048)
		(width 0.089408)
		(layer "In9.Cu")
		(net "FM_PCH_BMC_THERMTRIP_N")
	)
	(segment
		(start 406.315164 -43.30954)
		(end 408.290014 -41.33469)
		(width 0.089408)
		(layer "In9.Cu")
		(net "FM_PCH_BMC_THERMTRIP_N")
	)
	(segment
		(start 401.261072 -50.04816)
		(end 401.299934 -50.009298)
		(width 0.089408)
		(layer "In9.Cu")
		(net "FM_PCH_BMC_THERMTRIP_N")
	)
	(segment
		(start 399.358612 -71.446898)
		(end 399.358612 -68.777866)
		(width 0.089408)
		(layer "In9.Cu")
		(net "FM_PCH_BMC_THERMTRIP_N")
	)
	(segment
		(start 401.566888 -63.725806)
		(end 402.908516 -62.384178)
		(width 0.089408)
		(layer "In9.Cu")
		(net "FM_PCH_BMC_THERMTRIP_N")
	)
	(segment
		(start 398.708118 -72.641206)
		(end 398.708118 -72.097392)
		(width 0.089408)
		(layer "In9.Cu")
		(net "FM_PCH_BMC_THERMTRIP_N")
	)
	(segment
		(start 401.260818 -56.140858)
		(end 401.260818 -55.824374)
		(width 0.089408)
		(layer "In9.Cu")
		(net "FM_PCH_BMC_THERMTRIP_N")
	)
	(segment
		(start 401.566888 -66.56959)
		(end 401.566888 -63.725806)
		(width 0.089408)
		(layer "In9.Cu")
		(net "FM_PCH_BMC_THERMTRIP_N")
	)
	(segment
		(start 402.908262 -60.403232)
		(end 402.908008 -60.402978)
		(width 0.089408)
		(layer "In9.Cu")
		(net "FM_PCH_BMC_THERMTRIP_N")
	)
	(segment
		(start 406.315164 -43.750484)
		(end 406.315164 -43.30954)
		(width 0.089408)
		(layer "In9.Cu")
		(net "FM_PCH_BMC_THERMTRIP_N")
	)
	(segment
		(start 402.908262 -60.957968)
		(end 402.908262 -60.403232)
		(width 0.089408)
		(layer "In9.Cu")
		(net "FM_PCH_BMC_THERMTRIP_N")
	)
	(segment
		(start 404.68296 -44.10964)
		(end 405.956008 -44.10964)
		(width 0.089408)
		(layer "In9.Cu")
		(net "FM_PCH_BMC_THERMTRIP_N")
	)
	(segment
		(start 401.299934 -50.009298)
		(end 401.299934 -48.36541)
		(width 0.0889)
		(layer "In9.Cu")
		(net "FM_PCH_BMC_THERMTRIP_N")
	)
	(segment
		(start 403.895052 -44.897802)
		(end 404.590758 -44.202096)
		(width 0.089408)
		(layer "In9.Cu")
		(net "FM_PCH_BMC_THERMTRIP_N")
	)
	(segment
		(start 404.590758 -44.201842)
		(end 404.68296 -44.10964)
		(width 0.089408)
		(layer "In9.Cu")
		(net "FM_PCH_BMC_THERMTRIP_N")
	)
	(segment
		(start 401.260818 -55.824374)
		(end 401.261072 -55.82412)
		(width 0.089408)
		(layer "In9.Cu")
		(net "FM_PCH_BMC_THERMTRIP_N")
	)
	(segment
		(start 398.980914 -72.914002)
		(end 398.708118 -72.641206)
		(width 0.089408)
		(layer "In9.Cu")
		(net "FM_PCH_BMC_THERMTRIP_N")
	)
	(segment
		(start 403.895052 -45.746416)
		(end 403.895052 -44.897802)
		(width 0.089408)
		(layer "In9.Cu")
		(net "FM_PCH_BMC_THERMTRIP_N")
	)
	(segment
		(start 401.299934 -48.36541)
		(end 403.895052 -45.770292)
		(width 0.0889)
		(layer "In9.Cu")
		(net "FM_PCH_BMC_THERMTRIP_N")
	)
	(segment
		(start 403.203664 -108.75772)
		(end 403.680168 -108.75772)
		(width 0.0889)
		(layer "F.Cu")
		(net "FM_PASSWORD_CLEAR_N")
	)
	(segment
		(start 401.977606 -107.95635)
		(end 402.310092 -108.288836)
		(width 0.0889)
		(layer "F.Cu")
		(net "FM_PASSWORD_CLEAR_N")
	)
	(segment
		(start 402.310092 -108.288836)
		(end 402.73478 -108.288836)
		(width 0.0889)
		(layer "F.Cu")
		(net "FM_PASSWORD_CLEAR_N")
	)
	(segment
		(start 406.562814 -109.860842)
		(end 407.1747 -109.860842)
		(width 0.10795)
		(layer "F.Cu")
		(net "FM_PASSWORD_CLEAR_N")
	)
	(segment
		(start 401.12315 -108.125514)
		(end 401.13839 -108.140754)
		(width 0.0889)
		(layer "F.Cu")
		(net "FM_PASSWORD_CLEAR_N")
	)
	(segment
		(start 407.854658 -109.860842)
		(end 407.8605 -109.855)
		(width 0.10795)
		(layer "F.Cu")
		(net "FM_PASSWORD_CLEAR_N")
	)
	(segment
		(start 404.14956 -108.613194)
		(end 405.315166 -108.613194)
		(width 0.10795)
		(layer "F.Cu")
		(net "FM_PASSWORD_CLEAR_N")
	)
	(segment
		(start 400.925284 -107.935776)
		(end 401.115022 -108.125514)
		(width 0.0889)
		(layer "F.Cu")
		(net "FM_PASSWORD_CLEAR_N")
	)
	(segment
		(start 403.680168 -108.75772)
		(end 404.005034 -108.75772)
		(width 0.10795)
		(layer "F.Cu")
		(net "FM_PASSWORD_CLEAR_N")
	)
	(segment
		(start 401.647406 -107.95635)
		(end 401.977606 -107.95635)
		(width 0.0889)
		(layer "F.Cu")
		(net "FM_PASSWORD_CLEAR_N")
	)
	(segment
		(start 401.463002 -108.140754)
		(end 401.647406 -107.95635)
		(width 0.0889)
		(layer "F.Cu")
		(net "FM_PASSWORD_CLEAR_N")
	)
	(segment
		(start 400.465036 -107.855004)
		(end 400.545808 -107.935776)
		(width 0.0889)
		(layer "F.Cu")
		(net "FM_PASSWORD_CLEAR_N")
	)
	(segment
		(start 407.1747 -109.860842)
		(end 407.854658 -109.860842)
		(width 0.10795)
		(layer "F.Cu")
		(net "FM_PASSWORD_CLEAR_N")
	)
	(segment
		(start 402.73478 -108.288836)
		(end 403.203664 -108.75772)
		(width 0.0889)
		(layer "F.Cu")
		(net "FM_PASSWORD_CLEAR_N")
	)
	(segment
		(start 404.005034 -108.75772)
		(end 404.14956 -108.613194)
		(width 0.10795)
		(layer "F.Cu")
		(net "FM_PASSWORD_CLEAR_N")
	)
	(segment
		(start 401.115022 -108.125514)
		(end 401.12315 -108.125514)
		(width 0.0889)
		(layer "F.Cu")
		(net "FM_PASSWORD_CLEAR_N")
	)
	(segment
		(start 405.315166 -108.613194)
		(end 406.562814 -109.860842)
		(width 0.10795)
		(layer "F.Cu")
		(net "FM_PASSWORD_CLEAR_N")
	)
	(segment
		(start 401.13839 -108.140754)
		(end 401.463002 -108.140754)
		(width 0.0889)
		(layer "F.Cu")
		(net "FM_PASSWORD_CLEAR_N")
	)
	(segment
		(start 400.545808 -107.935776)
		(end 400.925284 -107.935776)
		(width 0.0889)
		(layer "F.Cu")
		(net "FM_PASSWORD_CLEAR_N")
	)
	(via
		(at 421.549322 -54.23027)
		(size 0.508)
		(drill 0.254)
		(layers "F.Cu" "B.Cu")
		(net "FM_PASSWORD_CLEAR_N")
	)
	(via
		(at 407.1747 -109.860842)
		(size 0.508)
		(drill 0.254)
		(layers "F.Cu" "B.Cu")
		(net "FM_PASSWORD_CLEAR_N")
	)
	(via
		(at 462.600294 -43.183048)
		(size 0.508)
		(drill 0.254)
		(layers "F.Cu" "B.Cu")
		(net "FM_PASSWORD_CLEAR_N")
	)
	(via
		(at 405.766016 4.405884)
		(size 0.508)
		(drill 0.254)
		(layers "F.Cu" "B.Cu")
		(net "FM_PASSWORD_CLEAR_N")
	)
	(segment
		(start 477.40062 -8.28167)
		(end 477.40062 -7.930388)
		(width 0.089408)
		(layer "In2.Cu")
		(net "FM_PASSWORD_CLEAR_N")
	)
	(segment
		(start 485.657398 -17.334484)
		(end 480.228402 -17.334484)
		(width 0.089408)
		(layer "In2.Cu")
		(net "FM_PASSWORD_CLEAR_N")
	)
	(segment
		(start 492.639858 -24.316944)
		(end 485.657398 -17.334484)
		(width 0.089408)
		(layer "In2.Cu")
		(net "FM_PASSWORD_CLEAR_N")
	)
	(segment
		(start 472.758516 -43.580304)
		(end 473.830904 -43.580304)
		(width 0.089408)
		(layer "In2.Cu")
		(net "FM_PASSWORD_CLEAR_N")
	)
	(segment
		(start 469.85555 -44.118022)
		(end 470.520776 -43.452796)
		(width 0.089408)
		(layer "In2.Cu")
		(net "FM_PASSWORD_CLEAR_N")
	)
	(segment
		(start 463.6008 3.0226)
		(end 463.6008 3.71983)
		(width 0.089408)
		(layer "In2.Cu")
		(net "FM_PASSWORD_CLEAR_N")
	)
	(segment
		(start 403.77618 -74.924412)
		(end 404.413212 -74.28738)
		(width 0.089408)
		(layer "In2.Cu")
		(net "FM_PASSWORD_CLEAR_N")
	)
	(segment
		(start 492.955072 -37.11956)
		(end 494.157 -35.917632)
		(width 0.089408)
		(layer "In2.Cu")
		(net "FM_PASSWORD_CLEAR_N")
	)
	(segment
		(start 421.009826 -54.769766)
		(end 421.549322 -54.23027)
		(width 0.089408)
		(layer "In2.Cu")
		(net "FM_PASSWORD_CLEAR_N")
	)
	(segment
		(start 419.085014 4.995926)
		(end 418.884862 4.995926)
		(width 0.089408)
		(layer "In2.Cu")
		(net "FM_PASSWORD_CLEAR_N")
	)
	(segment
		(start 418.884608 4.995672)
		(end 410.457396 4.995672)
		(width 0.089408)
		(layer "In2.Cu")
		(net "FM_PASSWORD_CLEAR_N")
	)
	(segment
		(start 494.157 -34.113216)
		(end 492.365792 -32.322008)
		(width 0.089408)
		(layer "In2.Cu")
		(net "FM_PASSWORD_CLEAR_N")
	)
	(segment
		(start 406.731216 -105.351072)
		(end 404.7236 -103.343456)
		(width 0.089408)
		(layer "In2.Cu")
		(net "FM_PASSWORD_CLEAR_N")
	)
	(segment
		(start 492.365792 -28.529534)
		(end 492.639858 -28.255468)
		(width 0.089408)
		(layer "In2.Cu")
		(net "FM_PASSWORD_CLEAR_N")
	)
	(segment
		(start 403.936962 -87.968328)
		(end 405.06904 -86.83625)
		(width 0.089408)
		(layer "In2.Cu")
		(net "FM_PASSWORD_CLEAR_N")
	)
	(segment
		(start 463.6008 3.71983)
		(end 462.526126 4.794504)
		(width 0.089408)
		(layer "In2.Cu")
		(net "FM_PASSWORD_CLEAR_N")
	)
	(segment
		(start 403.322536 -82.19186)
		(end 403.322536 -79.144368)
		(width 0.089408)
		(layer "In2.Cu")
		(net "FM_PASSWORD_CLEAR_N")
	)
	(segment
		(start 468.782908 -2.122424)
		(end 468.311484 -1.651)
		(width 0.089408)
		(layer "In2.Cu")
		(net "FM_PASSWORD_CLEAR_N")
	)
	(segment
		(start 414.41243 -54.710838)
		(end 414.923224 -55.221632)
		(width 0.089408)
		(layer "In2.Cu")
		(net "FM_PASSWORD_CLEAR_N")
	)
	(segment
		(start 492.639858 -28.255468)
		(end 492.639858 -24.316944)
		(width 0.089408)
		(layer "In2.Cu")
		(net "FM_PASSWORD_CLEAR_N")
	)
	(segment
		(start 402.570696 -89.12225)
		(end 403.724618 -87.968328)
		(width 0.089408)
		(layer "In2.Cu")
		(net "FM_PASSWORD_CLEAR_N")
	)
	(segment
		(start 478.141538 -41.626028)
		(end 480.144836 -41.626028)
		(width 0.089408)
		(layer "In2.Cu")
		(net "FM_PASSWORD_CLEAR_N")
	)
	(segment
		(start 419.274752 -55.221632)
		(end 419.726618 -54.769766)
		(width 0.089408)
		(layer "In2.Cu")
		(net "FM_PASSWORD_CLEAR_N")
	)
	(segment
		(start 475.419166 -44.3484)
		(end 478.141538 -41.626028)
		(width 0.089408)
		(layer "In2.Cu")
		(net "FM_PASSWORD_CLEAR_N")
	)
	(segment
		(start 428.7266 4.794504)
		(end 425.580048 1.647952)
		(width 0.089408)
		(layer "In2.Cu")
		(net "FM_PASSWORD_CLEAR_N")
	)
	(segment
		(start 418.884862 4.995926)
		(end 418.884608 4.995672)
		(width 0.089408)
		(layer "In2.Cu")
		(net "FM_PASSWORD_CLEAR_N")
	)
	(segment
		(start 419.447472 4.995672)
		(end 419.285928 4.995672)
		(width 0.089408)
		(layer "In2.Cu")
		(net "FM_PASSWORD_CLEAR_N")
	)
	(segment
		(start 404.387558 -83.12404)
		(end 404.254716 -83.12404)
		(width 0.089408)
		(layer "In2.Cu")
		(net "FM_PASSWORD_CLEAR_N")
	)
	(segment
		(start 492.955072 -39.327328)
		(end 492.955072 -37.11956)
		(width 0.089408)
		(layer "In2.Cu")
		(net "FM_PASSWORD_CLEAR_N")
	)
	(segment
		(start 403.370034 -93.045534)
		(end 402.570696 -92.246196)
		(width 0.089408)
		(layer "In2.Cu")
		(net "FM_PASSWORD_CLEAR_N")
	)
	(segment
		(start 403.370034 -100.03409)
		(end 403.370034 -93.045534)
		(width 0.089408)
		(layer "In2.Cu")
		(net "FM_PASSWORD_CLEAR_N")
	)
	(segment
		(start 474.137228 -4.666996)
		(end 469.00084 -4.666996)
		(width 0.089408)
		(layer "In2.Cu")
		(net "FM_PASSWORD_CLEAR_N")
	)
	(segment
		(start 462.600294 -43.183048)
		(end 462.938114 -42.845228)
		(width 0.089408)
		(layer "In2.Cu")
		(net "FM_PASSWORD_CLEAR_N")
	)
	(segment
		(start 462.526126 4.794504)
		(end 428.7266 4.794504)
		(width 0.089408)
		(layer "In2.Cu")
		(net "FM_PASSWORD_CLEAR_N")
	)
	(segment
		(start 473.830904 -43.580304)
		(end 474.599 -44.3484)
		(width 0.089408)
		(layer "In2.Cu")
		(net "FM_PASSWORD_CLEAR_N")
	)
	(segment
		(start 403.322536 -79.144368)
		(end 402.709888 -78.53172)
		(width 0.089408)
		(layer "In2.Cu")
		(net "FM_PASSWORD_CLEAR_N")
	)
	(segment
		(start 412.159196 -54.710838)
		(end 414.41243 -54.710838)
		(width 0.089408)
		(layer "In2.Cu")
		(net "FM_PASSWORD_CLEAR_N")
	)
	(segment
		(start 490.2454 -42.037)
		(end 492.955072 -39.327328)
		(width 0.089408)
		(layer "In2.Cu")
		(net "FM_PASSWORD_CLEAR_N")
	)
	(segment
		(start 404.412958 -73.965816)
		(end 410.103828 -68.274946)
		(width 0.089408)
		(layer "In2.Cu")
		(net "FM_PASSWORD_CLEAR_N")
	)
	(segment
		(start 465.888832 -42.845228)
		(end 466.180424 -43.13682)
		(width 0.089408)
		(layer "In2.Cu")
		(net "FM_PASSWORD_CLEAR_N")
	)
	(segment
		(start 404.00732 -100.671376)
		(end 403.370034 -100.03409)
		(width 0.089408)
		(layer "In2.Cu")
		(net "FM_PASSWORD_CLEAR_N")
	)
	(segment
		(start 425.580048 1.647952)
		(end 422.795192 1.647952)
		(width 0.089408)
		(layer "In2.Cu")
		(net "FM_PASSWORD_CLEAR_N")
	)
	(segment
		(start 462.938114 -42.845228)
		(end 465.888832 -42.845228)
		(width 0.089408)
		(layer "In2.Cu")
		(net "FM_PASSWORD_CLEAR_N")
	)
	(segment
		(start 403.724618 -87.968328)
		(end 403.936962 -87.968328)
		(width 0.089408)
		(layer "In2.Cu")
		(net "FM_PASSWORD_CLEAR_N")
	)
	(segment
		(start 468.311484 -1.651)
		(end 466.057234 -1.651)
		(width 0.089408)
		(layer "In2.Cu")
		(net "FM_PASSWORD_CLEAR_N")
	)
	(segment
		(start 404.7236 -103.343456)
		(end 404.7236 -102.413054)
		(width 0.089408)
		(layer "In2.Cu")
		(net "FM_PASSWORD_CLEAR_N")
	)
	(segment
		(start 419.726618 -54.769766)
		(end 421.009826 -54.769766)
		(width 0.089408)
		(layer "In2.Cu")
		(net "FM_PASSWORD_CLEAR_N")
	)
	(segment
		(start 466.180424 -43.626024)
		(end 466.672422 -44.118022)
		(width 0.089408)
		(layer "In2.Cu")
		(net "FM_PASSWORD_CLEAR_N")
	)
	(segment
		(start 466.180424 -43.13682)
		(end 466.180424 -43.626024)
		(width 0.089408)
		(layer "In2.Cu")
		(net "FM_PASSWORD_CLEAR_N")
	)
	(segment
		(start 404.412958 -74.123804)
		(end 404.412958 -73.965816)
		(width 0.089408)
		(layer "In2.Cu")
		(net "FM_PASSWORD_CLEAR_N")
	)
	(segment
		(start 404.00732 -101.696774)
		(end 404.00732 -100.671376)
		(width 0.089408)
		(layer "In2.Cu")
		(net "FM_PASSWORD_CLEAR_N")
	)
	(segment
		(start 410.457396 4.995672)
		(end 409.32354 3.861816)
		(width 0.089408)
		(layer "In2.Cu")
		(net "FM_PASSWORD_CLEAR_N")
	)
	(segment
		(start 480.228402 -17.334484)
		(end 478.9424 -16.048482)
		(width 0.089408)
		(layer "In2.Cu")
		(net "FM_PASSWORD_CLEAR_N")
	)
	(segment
		(start 492.365792 -32.322008)
		(end 492.365792 -28.529534)
		(width 0.089408)
		(layer "In2.Cu")
		(net "FM_PASSWORD_CLEAR_N")
	)
	(segment
		(start 402.709888 -78.53172)
		(end 402.709888 -77.868526)
		(width 0.089408)
		(layer "In2.Cu")
		(net "FM_PASSWORD_CLEAR_N")
	)
	(segment
		(start 478.9424 -16.048482)
		(end 478.9424 -9.82345)
		(width 0.089408)
		(layer "In2.Cu")
		(net "FM_PASSWORD_CLEAR_N")
	)
	(segment
		(start 465.326984 0.419354)
		(end 465.326984 1.296416)
		(width 0.089408)
		(layer "In2.Cu")
		(net "FM_PASSWORD_CLEAR_N")
	)
	(segment
		(start 404.7236 -102.413054)
		(end 404.00732 -101.696774)
		(width 0.089408)
		(layer "In2.Cu")
		(net "FM_PASSWORD_CLEAR_N")
	)
	(segment
		(start 410.103828 -56.766206)
		(end 412.159196 -54.710838)
		(width 0.089408)
		(layer "In2.Cu")
		(net "FM_PASSWORD_CLEAR_N")
	)
	(segment
		(start 402.709888 -77.868526)
		(end 403.77618 -76.802234)
		(width 0.089408)
		(layer "In2.Cu")
		(net "FM_PASSWORD_CLEAR_N")
	)
	(segment
		(start 406.310084 3.861816)
		(end 405.766016 4.405884)
		(width 0.089408)
		(layer "In2.Cu")
		(net "FM_PASSWORD_CLEAR_N")
	)
	(segment
		(start 404.413212 -74.124058)
		(end 404.412958 -74.123804)
		(width 0.089408)
		(layer "In2.Cu")
		(net "FM_PASSWORD_CLEAR_N")
	)
	(segment
		(start 410.103828 -68.274946)
		(end 410.103828 -56.766206)
		(width 0.089408)
		(layer "In2.Cu")
		(net "FM_PASSWORD_CLEAR_N")
	)
	(segment
		(start 468.317072 -3.234182)
		(end 468.782908 -2.768346)
		(width 0.089408)
		(layer "In2.Cu")
		(net "FM_PASSWORD_CLEAR_N")
	)
	(segment
		(start 404.413212 -74.28738)
		(end 404.413212 -74.124058)
		(width 0.089408)
		(layer "In2.Cu")
		(net "FM_PASSWORD_CLEAR_N")
	)
	(segment
		(start 465.714842 -1.308608)
		(end 465.714842 0.031496)
		(width 0.089408)
		(layer "In2.Cu")
		(net "FM_PASSWORD_CLEAR_N")
	)
	(segment
		(start 468.782908 -2.768346)
		(end 468.782908 -2.122424)
		(width 0.089408)
		(layer "In2.Cu")
		(net "FM_PASSWORD_CLEAR_N")
	)
	(segment
		(start 474.599 -44.3484)
		(end 475.419166 -44.3484)
		(width 0.089408)
		(layer "In2.Cu")
		(net "FM_PASSWORD_CLEAR_N")
	)
	(segment
		(start 478.9424 -9.82345)
		(end 477.40062 -8.28167)
		(width 0.089408)
		(layer "In2.Cu")
		(net "FM_PASSWORD_CLEAR_N")
	)
	(segment
		(start 422.795192 1.647952)
		(end 419.447472 4.995672)
		(width 0.089408)
		(layer "In2.Cu")
		(net "FM_PASSWORD_CLEAR_N")
	)
	(segment
		(start 472.631008 -43.452796)
		(end 472.758516 -43.580304)
		(width 0.089408)
		(layer "In2.Cu")
		(net "FM_PASSWORD_CLEAR_N")
	)
	(segment
		(start 466.057234 -1.651)
		(end 465.714842 -1.308608)
		(width 0.089408)
		(layer "In2.Cu")
		(net "FM_PASSWORD_CLEAR_N")
	)
	(segment
		(start 404.254716 -83.12404)
		(end 403.322536 -82.19186)
		(width 0.089408)
		(layer "In2.Cu")
		(net "FM_PASSWORD_CLEAR_N")
	)
	(segment
		(start 407.1747 -109.860842)
		(end 406.731216 -109.417358)
		(width 0.089408)
		(layer "In2.Cu")
		(net "FM_PASSWORD_CLEAR_N")
	)
	(segment
		(start 470.520776 -43.452796)
		(end 472.631008 -43.452796)
		(width 0.089408)
		(layer "In2.Cu")
		(net "FM_PASSWORD_CLEAR_N")
	)
	(segment
		(start 480.555808 -42.037)
		(end 490.2454 -42.037)
		(width 0.089408)
		(layer "In2.Cu")
		(net "FM_PASSWORD_CLEAR_N")
	)
	(segment
		(start 468.317072 -3.983228)
		(end 468.317072 -3.234182)
		(width 0.089408)
		(layer "In2.Cu")
		(net "FM_PASSWORD_CLEAR_N")
	)
	(segment
		(start 465.326984 1.296416)
		(end 463.6008 3.0226)
		(width 0.089408)
		(layer "In2.Cu")
		(net "FM_PASSWORD_CLEAR_N")
	)
	(segment
		(start 469.00084 -4.666996)
		(end 468.317072 -3.983228)
		(width 0.089408)
		(layer "In2.Cu")
		(net "FM_PASSWORD_CLEAR_N")
	)
	(segment
		(start 419.285928 4.995672)
		(end 419.28542 4.99618)
		(width 0.089408)
		(layer "In2.Cu")
		(net "FM_PASSWORD_CLEAR_N")
	)
	(segment
		(start 406.731216 -109.417358)
		(end 406.731216 -105.351072)
		(width 0.089408)
		(layer "In2.Cu")
		(net "FM_PASSWORD_CLEAR_N")
	)
	(segment
		(start 480.144836 -41.626028)
		(end 480.555808 -42.037)
		(width 0.089408)
		(layer "In2.Cu")
		(net "FM_PASSWORD_CLEAR_N")
	)
	(segment
		(start 419.28542 4.99618)
		(end 419.085268 4.99618)
		(width 0.089408)
		(layer "In2.Cu")
		(net "FM_PASSWORD_CLEAR_N")
	)
	(segment
		(start 403.77618 -76.802234)
		(end 403.77618 -74.924412)
		(width 0.089408)
		(layer "In2.Cu")
		(net "FM_PASSWORD_CLEAR_N")
	)
	(segment
		(start 405.06904 -86.83625)
		(end 405.06904 -83.805522)
		(width 0.089408)
		(layer "In2.Cu")
		(net "FM_PASSWORD_CLEAR_N")
	)
	(segment
		(start 409.32354 3.861816)
		(end 406.310084 3.861816)
		(width 0.089408)
		(layer "In2.Cu")
		(net "FM_PASSWORD_CLEAR_N")
	)
	(segment
		(start 405.06904 -83.805522)
		(end 404.387558 -83.12404)
		(width 0.089408)
		(layer "In2.Cu")
		(net "FM_PASSWORD_CLEAR_N")
	)
	(segment
		(start 465.714842 0.031496)
		(end 465.326984 0.419354)
		(width 0.089408)
		(layer "In2.Cu")
		(net "FM_PASSWORD_CLEAR_N")
	)
	(segment
		(start 414.923224 -55.221632)
		(end 419.274752 -55.221632)
		(width 0.089408)
		(layer "In2.Cu")
		(net "FM_PASSWORD_CLEAR_N")
	)
	(segment
		(start 419.085268 4.99618)
		(end 419.085014 4.995926)
		(width 0.089408)
		(layer "In2.Cu")
		(net "FM_PASSWORD_CLEAR_N")
	)
	(segment
		(start 494.157 -35.917632)
		(end 494.157 -34.113216)
		(width 0.089408)
		(layer "In2.Cu")
		(net "FM_PASSWORD_CLEAR_N")
	)
	(segment
		(start 402.570696 -92.246196)
		(end 402.570696 -89.12225)
		(width 0.089408)
		(layer "In2.Cu")
		(net "FM_PASSWORD_CLEAR_N")
	)
	(segment
		(start 466.672422 -44.118022)
		(end 469.85555 -44.118022)
		(width 0.089408)
		(layer "In2.Cu")
		(net "FM_PASSWORD_CLEAR_N")
	)
	(segment
		(start 477.40062 -7.930388)
		(end 474.137228 -4.666996)
		(width 0.089408)
		(layer "In2.Cu")
		(net "FM_PASSWORD_CLEAR_N")
	)
	(segment
		(start 460.992982 -44.278042)
		(end 460.4004 -44.870624)
		(width 0.089408)
		(layer "In9.Cu")
		(net "FM_PASSWORD_CLEAR_N")
	)
	(segment
		(start 421.549322 -54.172104)
		(end 421.549322 -54.23027)
		(width 0.089408)
		(layer "In9.Cu")
		(net "FM_PASSWORD_CLEAR_N")
	)
	(segment
		(start 427.590458 -51.577494)
		(end 426.404278 -52.763674)
		(width 0.089408)
		(layer "In9.Cu")
		(net "FM_PASSWORD_CLEAR_N")
	)
	(segment
		(start 461.5053 -44.278042)
		(end 460.992982 -44.278042)
		(width 0.089408)
		(layer "In9.Cu")
		(net "FM_PASSWORD_CLEAR_N")
	)
	(segment
		(start 405.766016 4.405884)
		(end 405.766016 4.697984)
		(width 0.089408)
		(layer "In9.Cu")
		(net "FM_PASSWORD_CLEAR_N")
	)
	(segment
		(start 422.455594 -53.265832)
		(end 421.549322 -54.172104)
		(width 0.089408)
		(layer "In9.Cu")
		(net "FM_PASSWORD_CLEAR_N")
	)
	(segment
		(start 439.375296 -47.827184)
		(end 435.624986 -51.577494)
		(width 0.089408)
		(layer "In9.Cu")
		(net "FM_PASSWORD_CLEAR_N")
	)
	(segment
		(start 460.4004 -45.204888)
		(end 457.778104 -47.827184)
		(width 0.089408)
		(layer "In9.Cu")
		(net "FM_PASSWORD_CLEAR_N")
	)
	(segment
		(start 425.174156 -52.763674)
		(end 424.938444 -52.527962)
		(width 0.089408)
		(layer "In9.Cu")
		(net "FM_PASSWORD_CLEAR_N")
	)
	(segment
		(start 426.404278 -52.763674)
		(end 425.174156 -52.763674)
		(width 0.089408)
		(layer "In9.Cu")
		(net "FM_PASSWORD_CLEAR_N")
	)
	(segment
		(start 435.624986 -51.577494)
		(end 427.590458 -51.577494)
		(width 0.089408)
		(layer "In9.Cu")
		(net "FM_PASSWORD_CLEAR_N")
	)
	(segment
		(start 423.671492 -53.265832)
		(end 422.455594 -53.265832)
		(width 0.089408)
		(layer "In9.Cu")
		(net "FM_PASSWORD_CLEAR_N")
	)
	(segment
		(start 405.551132 4.912868)
		(end 377.530868 4.912868)
		(width 0.089408)
		(layer "In9.Cu")
		(net "FM_PASSWORD_CLEAR_N")
	)
	(segment
		(start 462.600294 -43.183048)
		(end 461.5053 -44.278042)
		(width 0.089408)
		(layer "In9.Cu")
		(net "FM_PASSWORD_CLEAR_N")
	)
	(segment
		(start 460.4004 -44.870624)
		(end 460.4004 -45.204888)
		(width 0.089408)
		(layer "In9.Cu")
		(net "FM_PASSWORD_CLEAR_N")
	)
	(segment
		(start 405.766016 4.697984)
		(end 405.551132 4.912868)
		(width 0.089408)
		(layer "In9.Cu")
		(net "FM_PASSWORD_CLEAR_N")
	)
	(segment
		(start 457.778104 -47.827184)
		(end 439.375296 -47.827184)
		(width 0.089408)
		(layer "In9.Cu")
		(net "FM_PASSWORD_CLEAR_N")
	)
	(segment
		(start 424.409362 -52.527962)
		(end 423.671492 -53.265832)
		(width 0.089408)
		(layer "In9.Cu")
		(net "FM_PASSWORD_CLEAR_N")
	)
	(segment
		(start 377.530868 4.912868)
		(end 376.428 3.81)
		(width 0.089408)
		(layer "In9.Cu")
		(net "FM_PASSWORD_CLEAR_N")
	)
	(segment
		(start 424.938444 -52.527962)
		(end 424.409362 -52.527962)
		(width 0.089408)
		(layer "In9.Cu")
		(net "FM_PASSWORD_CLEAR_N")
	)
	(segment
		(start 395.613636 -89.744804)
		(end 395.92504 -89.4334)
		(width 0.10795)
		(layer "F.Cu")
		(net "FM_NMI_EVENT_N")
	)
	(segment
		(start 395.92504 -86.929468)
		(end 396.040102 -86.814406)
		(width 0.10795)
		(layer "F.Cu")
		(net "FM_NMI_EVENT_N")
	)
	(segment
		(start 395.89456 -85.257894)
		(end 396.062454 -85.09)
		(width 0.10795)
		(layer "F.Cu")
		(net "FM_NMI_EVENT_N")
	)
	(segment
		(start 395.92504 -89.4334)
		(end 395.92504 -86.929468)
		(width 0.10795)
		(layer "F.Cu")
		(net "FM_NMI_EVENT_N")
	)
	(segment
		(start 395.613636 -89.7636)
		(end 395.613636 -89.744804)
		(width 0.10795)
		(layer "F.Cu")
		(net "FM_NMI_EVENT_N")
	)
	(segment
		(start 396.062454 -85.09)
		(end 396.367 -85.09)
		(width 0.10795)
		(layer "F.Cu")
		(net "FM_NMI_EVENT_N")
	)
	(segment
		(start 396.040102 -86.814406)
		(end 396.040102 -86.464394)
		(width 0.10795)
		(layer "F.Cu")
		(net "FM_NMI_EVENT_N")
	)
	(segment
		(start 395.89456 -86.318852)
		(end 395.89456 -85.257894)
		(width 0.10795)
		(layer "F.Cu")
		(net "FM_NMI_EVENT_N")
	)
	(segment
		(start 396.040102 -86.464394)
		(end 395.89456 -86.318852)
		(width 0.10795)
		(layer "F.Cu")
		(net "FM_NMI_EVENT_N")
	)
	(segment
		(start 394.67155 -95.888556)
		(end 394.17625 -96.11868)
		(width 0.10795)
		(layer "F.Cu")
		(net "FM_NMI_EVENT_N")
	)
	(via
		(at 394.67155 -95.888556)
		(size 0.508)
		(drill 0.254)
		(layers "F.Cu" "B.Cu")
		(net "FM_NMI_EVENT_N")
	)
	(via
		(at 395.613636 -89.7636)
		(size 0.508)
		(drill 0.254)
		(layers "F.Cu" "B.Cu")
		(net "FM_NMI_EVENT_N")
	)
	(via
		(at 394.9954 -90.424)
		(size 0.6604)
		(drill 0.3302)
		(layers "F.Cu" "B.Cu")
		(net "FM_NMI_EVENT_N")
	)
	(segment
		(start 395.613636 -89.7636)
		(end 395.613636 -89.805764)
		(width 0.10795)
		(layer "B.Cu")
		(net "FM_NMI_EVENT_N")
	)
	(segment
		(start 395.613636 -89.805764)
		(end 394.9954 -90.424)
		(width 0.10795)
		(layer "B.Cu")
		(net "FM_NMI_EVENT_N")
	)
	(segment
		(start 394.791438 -89.744804)
		(end 393.3698 -91.166442)
		(width 0.089408)
		(layer "In11.Cu")
		(net "FM_NMI_EVENT_N")
	)
	(segment
		(start 393.3698 -91.166442)
		(end 393.3698 -93.74505)
		(width 0.089408)
		(layer "In11.Cu")
		(net "FM_NMI_EVENT_N")
	)
	(segment
		(start 395.613636 -89.7636)
		(end 395.59484 -89.744804)
		(width 0.089408)
		(layer "In11.Cu")
		(net "FM_NMI_EVENT_N")
	)
	(segment
		(start 393.3698 -93.74505)
		(end 394.67155 -95.0468)
		(width 0.089408)
		(layer "In11.Cu")
		(net "FM_NMI_EVENT_N")
	)
	(segment
		(start 394.67155 -95.0468)
		(end 394.67155 -95.888556)
		(width 0.089408)
		(layer "In11.Cu")
		(net "FM_NMI_EVENT_N")
	)
	(segment
		(start 395.59484 -89.744804)
		(end 394.791438 -89.744804)
		(width 0.089408)
		(layer "In11.Cu")
		(net "FM_NMI_EVENT_N")
	)
	(segment
		(start 394.323824 -78.06436)
		(end 394.124688 -78.06436)
		(width 0.10795)
		(layer "F.Cu")
		(net "FM_CPU_MSMI_LVT3_R_N")
	)
	(segment
		(start 393.798806 -77.738478)
		(end 392.295888 -77.738478)
		(width 0.10795)
		(layer "F.Cu")
		(net "FM_CPU_MSMI_LVT3_R_N")
	)
	(segment
		(start 394.72235 -78.462886)
		(end 394.323824 -78.06436)
		(width 0.10795)
		(layer "F.Cu")
		(net "FM_CPU_MSMI_LVT3_R_N")
	)
	(segment
		(start 394.124688 -78.06436)
		(end 393.798806 -77.738478)
		(width 0.10795)
		(layer "F.Cu")
		(net "FM_CPU_MSMI_LVT3_R_N")
	)
	(segment
		(start 396.218156 -78.820518)
		(end 395.860524 -78.462886)
		(width 0.10795)
		(layer "F.Cu")
		(net "FM_CPU_MSMI_LVT3_N")
	)
	(segment
		(start 396.239238 -78.820518)
		(end 396.218156 -78.820518)
		(width 0.10795)
		(layer "F.Cu")
		(net "FM_CPU_MSMI_LVT3_N")
	)
	(segment
		(start 395.860524 -78.462886)
		(end 395.61135 -78.462886)
		(width 0.10795)
		(layer "F.Cu")
		(net "FM_CPU_MSMI_LVT3_N")
	)
	(segment
		(start 419.890194 -28.134564)
		(end 420.290244 -27.734514)
		(width 0.10795)
		(layer "F.Cu")
		(net "FM_CPU_MSMI_LVT3_N")
	)
	(segment
		(start 390.21385 -116.72316)
		(end 390.70915 -116.953284)
		(width 0.10795)
		(layer "F.Cu")
		(net "FM_CPU_MSMI_LVT3_N")
	)
	(segment
		(start 369.551712 -80.701642)
		(end 369.145058 -80.294988)
		(width 0.1016)
		(layer "F.Cu")
		(net "FM_CPU_MSMI_LVT3_N")
	)
	(via
		(at 420.290244 -27.734514)
		(size 0.4572)
		(drill 0.2032)
		(layers "F.Cu" "B.Cu")
		(net "FM_CPU_MSMI_LVT3_N")
	)
	(via
		(at 467.9696 -131.2672)
		(size 0.508)
		(drill 0.254)
		(layers "F.Cu" "B.Cu")
		(net "FM_CPU_MSMI_LVT3_N")
	)
	(via
		(at 388.552436 -81.207356)
		(size 0.508)
		(drill 0.254)
		(layers "F.Cu" "B.Cu")
		(net "FM_CPU_MSMI_LVT3_N")
	)
	(via
		(at 390.70915 -116.953284)
		(size 0.508)
		(drill 0.254)
		(layers "F.Cu" "B.Cu")
		(net "FM_CPU_MSMI_LVT3_N")
	)
	(via
		(at 396.239238 -78.820518)
		(size 0.508)
		(drill 0.254)
		(layers "F.Cu" "B.Cu")
		(net "FM_CPU_MSMI_LVT3_N")
	)
	(via
		(at 391.60831 -28.956)
		(size 0.508)
		(drill 0.254)
		(layers "F.Cu" "B.Cu")
		(net "FM_CPU_MSMI_LVT3_N")
	)
	(via
		(at 369.551712 -80.701642)
		(size 0.4572)
		(drill 0.2032)
		(layers "F.Cu" "B.Cu")
		(net "FM_CPU_MSMI_LVT3_N")
	)
	(segment
		(start 469.138 -131.2164)
		(end 468.0204 -131.2164)
		(width 0.10795)
		(layer "B.Cu")
		(net "FM_CPU_MSMI_LVT3_N")
	)
	(segment
		(start 468.0204 -131.2164)
		(end 467.9696 -131.2672)
		(width 0.10795)
		(layer "B.Cu")
		(net "FM_CPU_MSMI_LVT3_N")
	)
	(segment
		(start 465.8868 -135.1788)
		(end 462.8642 -135.1788)
		(width 0.089408)
		(layer "In2.Cu")
		(net "FM_CPU_MSMI_LVT3_N")
	)
	(segment
		(start 425.62526 -128.664462)
		(end 423.963592 -128.664462)
		(width 0.089408)
		(layer "In2.Cu")
		(net "FM_CPU_MSMI_LVT3_N")
	)
	(segment
		(start 393.2428 -120.3198)
		(end 392.7348 -119.8118)
		(width 0.089408)
		(layer "In2.Cu")
		(net "FM_CPU_MSMI_LVT3_N")
	)
	(segment
		(start 462.8642 -135.1788)
		(end 460.62392 -137.41908)
		(width 0.089408)
		(layer "In2.Cu")
		(net "FM_CPU_MSMI_LVT3_N")
	)
	(segment
		(start 392.7348 -119.8118)
		(end 392.7348 -119.4054)
		(width 0.089408)
		(layer "In2.Cu")
		(net "FM_CPU_MSMI_LVT3_N")
	)
	(segment
		(start 467.9696 -131.2672)
		(end 467.6902 -131.5466)
		(width 0.089408)
		(layer "In2.Cu")
		(net "FM_CPU_MSMI_LVT3_N")
	)
	(segment
		(start 390.968484 -116.953284)
		(end 390.70915 -116.953284)
		(width 0.089408)
		(layer "In2.Cu")
		(net "FM_CPU_MSMI_LVT3_N")
	)
	(segment
		(start 391.6934 -117.9576)
		(end 391.6934 -117.6782)
		(width 0.089408)
		(layer "In2.Cu")
		(net "FM_CPU_MSMI_LVT3_N")
	)
	(segment
		(start 394.1064 -121.8184)
		(end 393.7254 -121.4374)
		(width 0.089408)
		(layer "In2.Cu")
		(net "FM_CPU_MSMI_LVT3_N")
	)
	(segment
		(start 460.62392 -137.41908)
		(end 458.01788 -137.41908)
		(width 0.089408)
		(layer "In2.Cu")
		(net "FM_CPU_MSMI_LVT3_N")
	)
	(segment
		(start 420.930832 -128.664208)
		(end 420.003224 -127.7366)
		(width 0.089408)
		(layer "In2.Cu")
		(net "FM_CPU_MSMI_LVT3_N")
	)
	(segment
		(start 392.2014 -118.872)
		(end 392.2014 -118.4656)
		(width 0.089408)
		(layer "In2.Cu")
		(net "FM_CPU_MSMI_LVT3_N")
	)
	(segment
		(start 453.8472 -132.0038)
		(end 451.4342 -132.0038)
		(width 0.089408)
		(layer "In2.Cu")
		(net "FM_CPU_MSMI_LVT3_N")
	)
	(segment
		(start 437.703976 -129.8194)
		(end 433.907946 -126.02337)
		(width 0.089408)
		(layer "In2.Cu")
		(net "FM_CPU_MSMI_LVT3_N")
	)
	(segment
		(start 394.6398 -122.6566)
		(end 394.1064 -122.1232)
		(width 0.089408)
		(layer "In2.Cu")
		(net "FM_CPU_MSMI_LVT3_N")
	)
	(segment
		(start 443.357 -131.7244)
		(end 441.452 -129.8194)
		(width 0.089408)
		(layer "In2.Cu")
		(net "FM_CPU_MSMI_LVT3_N")
	)
	(segment
		(start 391.6934 -117.6782)
		(end 390.968484 -116.953284)
		(width 0.089408)
		(layer "In2.Cu")
		(net "FM_CPU_MSMI_LVT3_N")
	)
	(segment
		(start 467.6902 -131.5466)
		(end 467.6902 -133.3754)
		(width 0.089408)
		(layer "In2.Cu")
		(net "FM_CPU_MSMI_LVT3_N")
	)
	(segment
		(start 433.907946 -126.02337)
		(end 428.266352 -126.02337)
		(width 0.089408)
		(layer "In2.Cu")
		(net "FM_CPU_MSMI_LVT3_N")
	)
	(segment
		(start 441.452 -129.8194)
		(end 437.703976 -129.8194)
		(width 0.089408)
		(layer "In2.Cu")
		(net "FM_CPU_MSMI_LVT3_N")
	)
	(segment
		(start 393.7254 -121.1326)
		(end 393.2428 -120.65)
		(width 0.089408)
		(layer "In2.Cu")
		(net "FM_CPU_MSMI_LVT3_N")
	)
	(segment
		(start 467.6902 -133.3754)
		(end 465.8868 -135.1788)
		(width 0.089408)
		(layer "In2.Cu")
		(net "FM_CPU_MSMI_LVT3_N")
	)
	(segment
		(start 397.9672 -128.7272)
		(end 397.9672 -127.3556)
		(width 0.089408)
		(layer "In2.Cu")
		(net "FM_CPU_MSMI_LVT3_N")
	)
	(segment
		(start 395.1986 -124.1806)
		(end 395.1986 -123.6218)
		(width 0.089408)
		(layer "In2.Cu")
		(net "FM_CPU_MSMI_LVT3_N")
	)
	(segment
		(start 395.1986 -123.6218)
		(end 394.6398 -123.063)
		(width 0.089408)
		(layer "In2.Cu")
		(net "FM_CPU_MSMI_LVT3_N")
	)
	(segment
		(start 458.01788 -137.41908)
		(end 454.1012 -133.5024)
		(width 0.089408)
		(layer "In2.Cu")
		(net "FM_CPU_MSMI_LVT3_N")
	)
	(segment
		(start 402.0058 -127.7366)
		(end 400.2786 -129.4638)
		(width 0.089408)
		(layer "In2.Cu")
		(net "FM_CPU_MSMI_LVT3_N")
	)
	(segment
		(start 398.7038 -129.4638)
		(end 397.9672 -128.7272)
		(width 0.089408)
		(layer "In2.Cu")
		(net "FM_CPU_MSMI_LVT3_N")
	)
	(segment
		(start 423.963338 -128.664208)
		(end 420.930832 -128.664208)
		(width 0.089408)
		(layer "In2.Cu")
		(net "FM_CPU_MSMI_LVT3_N")
	)
	(segment
		(start 394.1064 -122.1232)
		(end 394.1064 -121.8184)
		(width 0.089408)
		(layer "In2.Cu")
		(net "FM_CPU_MSMI_LVT3_N")
	)
	(segment
		(start 423.963592 -128.664462)
		(end 423.963338 -128.664208)
		(width 0.089408)
		(layer "In2.Cu")
		(net "FM_CPU_MSMI_LVT3_N")
	)
	(segment
		(start 448.2592 -131.191)
		(end 447.7258 -131.7244)
		(width 0.089408)
		(layer "In2.Cu")
		(net "FM_CPU_MSMI_LVT3_N")
	)
	(segment
		(start 420.003224 -127.7366)
		(end 402.0058 -127.7366)
		(width 0.089408)
		(layer "In2.Cu")
		(net "FM_CPU_MSMI_LVT3_N")
	)
	(segment
		(start 454.1012 -132.2578)
		(end 453.8472 -132.0038)
		(width 0.089408)
		(layer "In2.Cu")
		(net "FM_CPU_MSMI_LVT3_N")
	)
	(segment
		(start 393.2428 -120.65)
		(end 393.2428 -120.3198)
		(width 0.089408)
		(layer "In2.Cu")
		(net "FM_CPU_MSMI_LVT3_N")
	)
	(segment
		(start 451.4342 -132.0038)
		(end 450.6214 -131.191)
		(width 0.089408)
		(layer "In2.Cu")
		(net "FM_CPU_MSMI_LVT3_N")
	)
	(segment
		(start 393.7254 -121.4374)
		(end 393.7254 -121.1326)
		(width 0.089408)
		(layer "In2.Cu")
		(net "FM_CPU_MSMI_LVT3_N")
	)
	(segment
		(start 454.1012 -133.5024)
		(end 454.1012 -132.2578)
		(width 0.089408)
		(layer "In2.Cu")
		(net "FM_CPU_MSMI_LVT3_N")
	)
	(segment
		(start 428.266352 -126.02337)
		(end 425.62526 -128.664462)
		(width 0.089408)
		(layer "In2.Cu")
		(net "FM_CPU_MSMI_LVT3_N")
	)
	(segment
		(start 447.7258 -131.7244)
		(end 443.357 -131.7244)
		(width 0.089408)
		(layer "In2.Cu")
		(net "FM_CPU_MSMI_LVT3_N")
	)
	(segment
		(start 394.6398 -123.063)
		(end 394.6398 -122.6566)
		(width 0.089408)
		(layer "In2.Cu")
		(net "FM_CPU_MSMI_LVT3_N")
	)
	(segment
		(start 392.2014 -118.4656)
		(end 391.6934 -117.9576)
		(width 0.089408)
		(layer "In2.Cu")
		(net "FM_CPU_MSMI_LVT3_N")
	)
	(segment
		(start 397.8148 -126.7968)
		(end 395.1986 -124.1806)
		(width 0.089408)
		(layer "In2.Cu")
		(net "FM_CPU_MSMI_LVT3_N")
	)
	(segment
		(start 397.9672 -127.3556)
		(end 397.8148 -127.2032)
		(width 0.089408)
		(layer "In2.Cu")
		(net "FM_CPU_MSMI_LVT3_N")
	)
	(segment
		(start 400.2786 -129.4638)
		(end 398.7038 -129.4638)
		(width 0.089408)
		(layer "In2.Cu")
		(net "FM_CPU_MSMI_LVT3_N")
	)
	(segment
		(start 392.7348 -119.4054)
		(end 392.2014 -118.872)
		(width 0.089408)
		(layer "In2.Cu")
		(net "FM_CPU_MSMI_LVT3_N")
	)
	(segment
		(start 397.8148 -127.2032)
		(end 397.8148 -126.7968)
		(width 0.089408)
		(layer "In2.Cu")
		(net "FM_CPU_MSMI_LVT3_N")
	)
	(segment
		(start 450.6214 -131.191)
		(end 448.2592 -131.191)
		(width 0.089408)
		(layer "In2.Cu")
		(net "FM_CPU_MSMI_LVT3_N")
	)
	(segment
		(start 388.552436 -81.207356)
		(end 388.552436 -81.201768)
		(width 0.089408)
		(layer "In4.Cu")
		(net "FM_CPU_MSMI_LVT3_N")
	)
	(segment
		(start 389.799576 -81.201768)
		(end 390.076944 -80.9244)
		(width 0.089408)
		(layer "In4.Cu")
		(net "FM_CPU_MSMI_LVT3_N")
	)
	(segment
		(start 406.776428 -28.978098)
		(end 405.537162 -28.978098)
		(width 0.089408)
		(layer "In4.Cu")
		(net "FM_CPU_MSMI_LVT3_N")
	)
	(segment
		(start 393.848082 -79.209392)
		(end 395.886686 -79.209392)
		(width 0.089408)
		(layer "In4.Cu")
		(net "FM_CPU_MSMI_LVT3_N")
	)
	(segment
		(start 418.28974 -27.28976)
		(end 417.559998 -26.560018)
		(width 0.089408)
		(layer "In4.Cu")
		(net "FM_CPU_MSMI_LVT3_N")
	)
	(segment
		(start 396.191486 -78.86827)
		(end 396.239238 -78.820518)
		(width 0.089408)
		(layer "In4.Cu")
		(net "FM_CPU_MSMI_LVT3_N")
	)
	(segment
		(start 387.564884 -82.18932)
		(end 388.552436 -81.201768)
		(width 0.089408)
		(layer "In4.Cu")
		(net "FM_CPU_MSMI_LVT3_N")
	)
	(segment
		(start 402.270976 -29.324554)
		(end 401.05711 -28.110688)
		(width 0.089408)
		(layer "In4.Cu")
		(net "FM_CPU_MSMI_LVT3_N")
	)
	(segment
		(start 405.190706 -29.324554)
		(end 402.270976 -29.324554)
		(width 0.089408)
		(layer "In4.Cu")
		(net "FM_CPU_MSMI_LVT3_N")
	)
	(segment
		(start 417.559998 -26.560018)
		(end 409.73502 -26.560018)
		(width 0.089408)
		(layer "In4.Cu")
		(net "FM_CPU_MSMI_LVT3_N")
	)
	(segment
		(start 419.684708 -28.109164)
		(end 418.484304 -28.109164)
		(width 0.089408)
		(layer "In4.Cu")
		(net "FM_CPU_MSMI_LVT3_N")
	)
	(segment
		(start 390.076944 -80.9244)
		(end 391.169144 -80.9244)
		(width 0.089408)
		(layer "In4.Cu")
		(net "FM_CPU_MSMI_LVT3_N")
	)
	(segment
		(start 409.73502 -26.560018)
		(end 409.126182 -27.168856)
		(width 0.089408)
		(layer "In4.Cu")
		(net "FM_CPU_MSMI_LVT3_N")
	)
	(segment
		(start 370.500402 -81.99247)
		(end 372.999762 -81.99247)
		(width 0.089408)
		(layer "In4.Cu")
		(net "FM_CPU_MSMI_LVT3_N")
	)
	(segment
		(start 400.56689 -28.110688)
		(end 400.145758 -28.53182)
		(width 0.089408)
		(layer "In4.Cu")
		(net "FM_CPU_MSMI_LVT3_N")
	)
	(segment
		(start 369.551712 -80.701642)
		(end 369.551712 -81.04378)
		(width 0.089408)
		(layer "In4.Cu")
		(net "FM_CPU_MSMI_LVT3_N")
	)
	(segment
		(start 374.211088 -82.360008)
		(end 386.285486 -82.360008)
		(width 0.089408)
		(layer "In4.Cu")
		(net "FM_CPU_MSMI_LVT3_N")
	)
	(segment
		(start 372.999762 -81.99247)
		(end 373.177562 -82.17027)
		(width 0.089408)
		(layer "In4.Cu")
		(net "FM_CPU_MSMI_LVT3_N")
	)
	(segment
		(start 391.169144 -80.9244)
		(end 392.618976 -79.474568)
		(width 0.089408)
		(layer "In4.Cu")
		(net "FM_CPU_MSMI_LVT3_N")
	)
	(segment
		(start 392.965178 -78.917292)
		(end 393.555982 -78.917292)
		(width 0.089408)
		(layer "In4.Cu")
		(net "FM_CPU_MSMI_LVT3_N")
	)
	(segment
		(start 392.03249 -28.53182)
		(end 391.60831 -28.956)
		(width 0.089408)
		(layer "In4.Cu")
		(net "FM_CPU_MSMI_LVT3_N")
	)
	(segment
		(start 418.484304 -28.109164)
		(end 418.28974 -27.9146)
		(width 0.089408)
		(layer "In4.Cu")
		(net "FM_CPU_MSMI_LVT3_N")
	)
	(segment
		(start 374.02135 -82.17027)
		(end 374.211088 -82.360008)
		(width 0.089408)
		(layer "In4.Cu")
		(net "FM_CPU_MSMI_LVT3_N")
	)
	(segment
		(start 369.551712 -81.04378)
		(end 370.500402 -81.99247)
		(width 0.089408)
		(layer "In4.Cu")
		(net "FM_CPU_MSMI_LVT3_N")
	)
	(segment
		(start 392.618976 -79.263494)
		(end 392.965178 -78.917292)
		(width 0.089408)
		(layer "In4.Cu")
		(net "FM_CPU_MSMI_LVT3_N")
	)
	(segment
		(start 408.322526 -27.753056)
		(end 408.00147 -27.753056)
		(width 0.089408)
		(layer "In4.Cu")
		(net "FM_CPU_MSMI_LVT3_N")
	)
	(segment
		(start 408.906726 -27.168856)
		(end 408.322526 -27.753056)
		(width 0.089408)
		(layer "In4.Cu")
		(net "FM_CPU_MSMI_LVT3_N")
	)
	(segment
		(start 373.177562 -82.17027)
		(end 374.02135 -82.17027)
		(width 0.089408)
		(layer "In4.Cu")
		(net "FM_CPU_MSMI_LVT3_N")
	)
	(segment
		(start 386.456174 -82.18932)
		(end 387.564884 -82.18932)
		(width 0.089408)
		(layer "In4.Cu")
		(net "FM_CPU_MSMI_LVT3_N")
	)
	(segment
		(start 409.126182 -27.168856)
		(end 408.906726 -27.168856)
		(width 0.089408)
		(layer "In4.Cu")
		(net "FM_CPU_MSMI_LVT3_N")
	)
	(segment
		(start 393.555982 -78.917292)
		(end 393.848082 -79.209392)
		(width 0.089408)
		(layer "In4.Cu")
		(net "FM_CPU_MSMI_LVT3_N")
	)
	(segment
		(start 420.290244 -27.734514)
		(end 420.059358 -27.734514)
		(width 0.089408)
		(layer "In4.Cu")
		(net "FM_CPU_MSMI_LVT3_N")
	)
	(segment
		(start 400.145758 -28.53182)
		(end 392.03249 -28.53182)
		(width 0.089408)
		(layer "In4.Cu")
		(net "FM_CPU_MSMI_LVT3_N")
	)
	(segment
		(start 418.28974 -27.9146)
		(end 418.28974 -27.28976)
		(width 0.089408)
		(layer "In4.Cu")
		(net "FM_CPU_MSMI_LVT3_N")
	)
	(segment
		(start 405.537162 -28.978098)
		(end 405.190706 -29.324554)
		(width 0.089408)
		(layer "In4.Cu")
		(net "FM_CPU_MSMI_LVT3_N")
	)
	(segment
		(start 395.886686 -79.209392)
		(end 396.191486 -78.904592)
		(width 0.089408)
		(layer "In4.Cu")
		(net "FM_CPU_MSMI_LVT3_N")
	)
	(segment
		(start 386.285486 -82.360008)
		(end 386.456174 -82.18932)
		(width 0.089408)
		(layer "In4.Cu")
		(net "FM_CPU_MSMI_LVT3_N")
	)
	(segment
		(start 388.552436 -81.201768)
		(end 389.799576 -81.201768)
		(width 0.089408)
		(layer "In4.Cu")
		(net "FM_CPU_MSMI_LVT3_N")
	)
	(segment
		(start 420.059358 -27.734514)
		(end 419.684708 -28.109164)
		(width 0.089408)
		(layer "In4.Cu")
		(net "FM_CPU_MSMI_LVT3_N")
	)
	(segment
		(start 408.00147 -27.753056)
		(end 406.776428 -28.978098)
		(width 0.089408)
		(layer "In4.Cu")
		(net "FM_CPU_MSMI_LVT3_N")
	)
	(segment
		(start 396.191486 -78.904592)
		(end 396.191486 -78.86827)
		(width 0.089408)
		(layer "In4.Cu")
		(net "FM_CPU_MSMI_LVT3_N")
	)
	(segment
		(start 401.05711 -28.110688)
		(end 400.56689 -28.110688)
		(width 0.089408)
		(layer "In4.Cu")
		(net "FM_CPU_MSMI_LVT3_N")
	)
	(segment
		(start 392.618976 -79.474568)
		(end 392.618976 -79.263494)
		(width 0.089408)
		(layer "In4.Cu")
		(net "FM_CPU_MSMI_LVT3_N")
	)
	(segment
		(start 390.411716 -72.355456)
		(end 390.411716 -73.6346)
		(width 0.089408)
		(layer "In9.Cu")
		(net "FM_CPU_MSMI_LVT3_N")
	)
	(segment
		(start 392.782298 -46.291246)
		(end 392.782298 -47.395892)
		(width 0.089408)
		(layer "In9.Cu")
		(net "FM_CPU_MSMI_LVT3_N")
	)
	(segment
		(start 393.701778 -41.7449)
		(end 393.490958 -41.95572)
		(width 0.089408)
		(layer "In9.Cu")
		(net "FM_CPU_MSMI_LVT3_N")
	)
	(segment
		(start 392.310874 -33.563052)
		(end 392.310874 -36.028122)
		(width 0.089408)
		(layer "In9.Cu")
		(net "FM_CPU_MSMI_LVT3_N")
	)
	(segment
		(start 390.411716 -72.010016)
		(end 390.411716 -72.19696)
		(width 0.089408)
		(layer "In9.Cu")
		(net "FM_CPU_MSMI_LVT3_N")
	)
	(segment
		(start 390.07669 -68.227956)
		(end 390.864344 -69.01561)
		(width 0.089408)
		(layer "In9.Cu")
		(net "FM_CPU_MSMI_LVT3_N")
	)
	(segment
		(start 392.932158 -61.390276)
		(end 392.519154 -61.80328)
		(width 0.089408)
		(layer "In9.Cu")
		(net "FM_CPU_MSMI_LVT3_N")
	)
	(segment
		(start 391.21969 -32.471868)
		(end 392.310874 -33.563052)
		(width 0.089408)
		(layer "In9.Cu")
		(net "FM_CPU_MSMI_LVT3_N")
	)
	(segment
		(start 390.411716 -72.19696)
		(end 390.411462 -72.197214)
		(width 0.089408)
		(layer "In9.Cu")
		(net "FM_CPU_MSMI_LVT3_N")
	)
	(segment
		(start 392.67765 -53.164994)
		(end 393.439904 -53.927248)
		(width 0.089408)
		(layer "In9.Cu")
		(net "FM_CPU_MSMI_LVT3_N")
	)
	(segment
		(start 390.411462 -72.197214)
		(end 390.411462 -72.355202)
		(width 0.089408)
		(layer "In9.Cu")
		(net "FM_CPU_MSMI_LVT3_N")
	)
	(segment
		(start 390.864344 -71.557388)
		(end 390.411716 -72.010016)
		(width 0.089408)
		(layer "In9.Cu")
		(net "FM_CPU_MSMI_LVT3_N")
	)
	(segment
		(start 392.519154 -61.80328)
		(end 392.519154 -64.640968)
		(width 0.089408)
		(layer "In9.Cu")
		(net "FM_CPU_MSMI_LVT3_N")
	)
	(segment
		(start 392.471402 -42.975784)
		(end 392.471402 -45.98035)
		(width 0.089408)
		(layer "In9.Cu")
		(net "FM_CPU_MSMI_LVT3_N")
	)
	(segment
		(start 390.411462 -72.355202)
		(end 390.411716 -72.355456)
		(width 0.089408)
		(layer "In9.Cu")
		(net "FM_CPU_MSMI_LVT3_N")
	)
	(segment
		(start 393.490958 -41.95572)
		(end 392.471402 -42.975784)
		(width 0.089408)
		(layer "In9.Cu")
		(net "FM_CPU_MSMI_LVT3_N")
	)
	(segment
		(start 392.035538 -51.328574)
		(end 392.035284 -51.328828)
		(width 0.089408)
		(layer "In9.Cu")
		(net "FM_CPU_MSMI_LVT3_N")
	)
	(segment
		(start 387.121654 -78.135734)
		(end 387.121654 -79.371952)
		(width 0.089408)
		(layer "In9.Cu")
		(net "FM_CPU_MSMI_LVT3_N")
	)
	(segment
		(start 393.701778 -40.447976)
		(end 393.701778 -41.7449)
		(width 0.089408)
		(layer "In9.Cu")
		(net "FM_CPU_MSMI_LVT3_N")
	)
	(segment
		(start 391.21969 -29.34462)
		(end 391.21969 -32.471868)
		(width 0.089408)
		(layer "In9.Cu")
		(net "FM_CPU_MSMI_LVT3_N")
	)
	(segment
		(start 392.035538 -48.142652)
		(end 392.035538 -51.328574)
		(width 0.089408)
		(layer "In9.Cu")
		(net "FM_CPU_MSMI_LVT3_N")
	)
	(segment
		(start 390.864344 -69.01561)
		(end 390.864344 -71.557388)
		(width 0.089408)
		(layer "In9.Cu")
		(net "FM_CPU_MSMI_LVT3_N")
	)
	(segment
		(start 389.337296 -74.70902)
		(end 389.337296 -75.920092)
		(width 0.089408)
		(layer "In9.Cu")
		(net "FM_CPU_MSMI_LVT3_N")
	)
	(segment
		(start 393.439904 -60.271914)
		(end 392.932158 -60.77966)
		(width 0.089408)
		(layer "In9.Cu")
		(net "FM_CPU_MSMI_LVT3_N")
	)
	(segment
		(start 390.07669 -67.083432)
		(end 390.07669 -68.227956)
		(width 0.089408)
		(layer "In9.Cu")
		(net "FM_CPU_MSMI_LVT3_N")
	)
	(segment
		(start 392.67765 -52.290472)
		(end 392.67765 -53.164994)
		(width 0.089408)
		(layer "In9.Cu")
		(net "FM_CPU_MSMI_LVT3_N")
	)
	(segment
		(start 392.471402 -45.98035)
		(end 392.782298 -46.291246)
		(width 0.089408)
		(layer "In9.Cu")
		(net "FM_CPU_MSMI_LVT3_N")
	)
	(segment
		(start 388.552436 -80.802734)
		(end 388.552436 -81.207356)
		(width 0.089408)
		(layer "In9.Cu")
		(net "FM_CPU_MSMI_LVT3_N")
	)
	(segment
		(start 392.519154 -64.640968)
		(end 390.07669 -67.083432)
		(width 0.089408)
		(layer "In9.Cu")
		(net "FM_CPU_MSMI_LVT3_N")
	)
	(segment
		(start 389.337296 -75.920092)
		(end 387.121654 -78.135734)
		(width 0.089408)
		(layer "In9.Cu")
		(net "FM_CPU_MSMI_LVT3_N")
	)
	(segment
		(start 391.60831 -28.956)
		(end 391.21969 -29.34462)
		(width 0.089408)
		(layer "In9.Cu")
		(net "FM_CPU_MSMI_LVT3_N")
	)
	(segment
		(start 392.932158 -60.77966)
		(end 392.932158 -61.390276)
		(width 0.089408)
		(layer "In9.Cu")
		(net "FM_CPU_MSMI_LVT3_N")
	)
	(segment
		(start 393.314428 -37.031676)
		(end 393.314428 -40.060626)
		(width 0.089408)
		(layer "In9.Cu")
		(net "FM_CPU_MSMI_LVT3_N")
	)
	(segment
		(start 392.782298 -47.395892)
		(end 392.035538 -48.142652)
		(width 0.089408)
		(layer "In9.Cu")
		(net "FM_CPU_MSMI_LVT3_N")
	)
	(segment
		(start 393.314428 -40.060626)
		(end 393.701778 -40.447976)
		(width 0.089408)
		(layer "In9.Cu")
		(net "FM_CPU_MSMI_LVT3_N")
	)
	(segment
		(start 393.439904 -53.927248)
		(end 393.439904 -60.271914)
		(width 0.089408)
		(layer "In9.Cu")
		(net "FM_CPU_MSMI_LVT3_N")
	)
	(segment
		(start 392.035284 -51.648106)
		(end 392.67765 -52.290472)
		(width 0.089408)
		(layer "In9.Cu")
		(net "FM_CPU_MSMI_LVT3_N")
	)
	(segment
		(start 387.121654 -79.371952)
		(end 388.552436 -80.802734)
		(width 0.089408)
		(layer "In9.Cu")
		(net "FM_CPU_MSMI_LVT3_N")
	)
	(segment
		(start 390.411716 -73.6346)
		(end 389.337296 -74.70902)
		(width 0.089408)
		(layer "In9.Cu")
		(net "FM_CPU_MSMI_LVT3_N")
	)
	(segment
		(start 392.035284 -51.328828)
		(end 392.035284 -51.648106)
		(width 0.089408)
		(layer "In9.Cu")
		(net "FM_CPU_MSMI_LVT3_N")
	)
	(segment
		(start 392.310874 -36.028122)
		(end 393.314428 -37.031676)
		(width 0.089408)
		(layer "In9.Cu")
		(net "FM_CPU_MSMI_LVT3_N")
	)
	(segment
		(start 399.14322 -99.630992)
		(end 399.741136 -100.228908)
		(width 0.089408)
		(layer "In11.Cu")
		(net "FM_CPU_MSMI_LVT3_N")
	)
	(segment
		(start 397.24457 -112.648746)
		(end 397.24457 -113.655602)
		(width 0.0889)
		(layer "In11.Cu")
		(net "FM_CPU_MSMI_LVT3_N")
	)
	(segment
		(start 395.845792 -86.068662)
		(end 396.053818 -86.276688)
		(width 0.089408)
		(layer "In11.Cu")
		(net "FM_CPU_MSMI_LVT3_N")
	)
	(segment
		(start 395.845792 -83.35772)
		(end 395.845792 -86.068662)
		(width 0.089408)
		(layer "In11.Cu")
		(net "FM_CPU_MSMI_LVT3_N")
	)
	(segment
		(start 395.7574 -116.083588)
		(end 395.7574 -116.116354)
		(width 0.0889)
		(layer "In11.Cu")
		(net "FM_CPU_MSMI_LVT3_N")
	)
	(segment
		(start 395.2621 -116.942108)
		(end 395.2621 -116.974874)
		(width 0.0889)
		(layer "In11.Cu")
		(net "FM_CPU_MSMI_LVT3_N")
	)
	(segment
		(start 391.112248 -117.018308)
		(end 391.047224 -116.953284)
		(width 0.0889)
		(layer "In11.Cu")
		(net "FM_CPU_MSMI_LVT3_N")
	)
	(segment
		(start 396.747492 -114.15268)
		(end 396.741904 -114.728244)
		(width 0.0889)
		(layer "In11.Cu")
		(net "FM_CPU_MSMI_LVT3_N")
	)
	(segment
		(start 395.164564 -91.651328)
		(end 395.164564 -92.931234)
		(width 0.089408)
		(layer "In11.Cu")
		(net "FM_CPU_MSMI_LVT3_N")
	)
	(segment
		(start 399.741136 -100.228908)
		(end 399.741136 -110.895892)
		(width 0.089408)
		(layer "In11.Cu")
		(net "FM_CPU_MSMI_LVT3_N")
	)
	(segment
		(start 396.239238 -78.820518)
		(end 396.239238 -82.964274)
		(width 0.089408)
		(layer "In11.Cu")
		(net "FM_CPU_MSMI_LVT3_N")
	)
	(segment
		(start 391.047224 -116.953284)
		(end 390.70915 -116.953284)
		(width 0.0889)
		(layer "In11.Cu")
		(net "FM_CPU_MSMI_LVT3_N")
	)
	(segment
		(start 399.14322 -99.16668)
		(end 399.14322 -99.630992)
		(width 0.089408)
		(layer "In11.Cu")
		(net "FM_CPU_MSMI_LVT3_N")
	)
	(segment
		(start 397.24457 -111.63681)
		(end 397.24457 -112.648746)
		(width 0.089408)
		(layer "In11.Cu")
		(net "FM_CPU_MSMI_LVT3_N")
	)
	(segment
		(start 397.84147 -94.615508)
		(end 399.58137 -96.355408)
		(width 0.089408)
		(layer "In11.Cu")
		(net "FM_CPU_MSMI_LVT3_N")
	)
	(segment
		(start 397.477996 -111.403384)
		(end 397.24457 -111.63681)
		(width 0.089408)
		(layer "In11.Cu")
		(net "FM_CPU_MSMI_LVT3_N")
	)
	(segment
		(start 395.164564 -92.931234)
		(end 396.848838 -94.615508)
		(width 0.089408)
		(layer "In11.Cu")
		(net "FM_CPU_MSMI_LVT3_N")
	)
	(segment
		(start 396.053818 -87.128604)
		(end 397.352266 -88.427052)
		(width 0.089408)
		(layer "In11.Cu")
		(net "FM_CPU_MSMI_LVT3_N")
	)
	(segment
		(start 396.239238 -82.964274)
		(end 395.845792 -83.35772)
		(width 0.089408)
		(layer "In11.Cu")
		(net "FM_CPU_MSMI_LVT3_N")
	)
	(segment
		(start 397.352266 -89.463626)
		(end 395.164564 -91.651328)
		(width 0.089408)
		(layer "In11.Cu")
		(net "FM_CPU_MSMI_LVT3_N")
	)
	(segment
		(start 396.053818 -86.276688)
		(end 396.053818 -87.128604)
		(width 0.089408)
		(layer "In11.Cu")
		(net "FM_CPU_MSMI_LVT3_N")
	)
	(segment
		(start 399.58137 -96.355408)
		(end 399.58137 -98.72853)
		(width 0.089408)
		(layer "In11.Cu")
		(net "FM_CPU_MSMI_LVT3_N")
	)
	(segment
		(start 397.352266 -88.427052)
		(end 397.352266 -89.463626)
		(width 0.089408)
		(layer "In11.Cu")
		(net "FM_CPU_MSMI_LVT3_N")
	)
	(segment
		(start 399.233644 -111.403384)
		(end 397.477996 -111.403384)
		(width 0.089408)
		(layer "In11.Cu")
		(net "FM_CPU_MSMI_LVT3_N")
	)
	(segment
		(start 396.741904 -114.728244)
		(end 396.741904 -114.964972)
		(width 0.0889)
		(layer "In11.Cu")
		(net "FM_CPU_MSMI_LVT3_N")
	)
	(segment
		(start 397.24457 -113.655602)
		(end 396.747492 -114.15268)
		(width 0.0889)
		(layer "In11.Cu")
		(net "FM_CPU_MSMI_LVT3_N")
	)
	(segment
		(start 399.58137 -98.72853)
		(end 399.14322 -99.16668)
		(width 0.089408)
		(layer "In11.Cu")
		(net "FM_CPU_MSMI_LVT3_N")
	)
	(segment
		(start 396.741904 -114.964972)
		(end 396.172182 -115.534694)
		(width 0.0889)
		(layer "In11.Cu")
		(net "FM_CPU_MSMI_LVT3_N")
	)
	(segment
		(start 396.848838 -94.615508)
		(end 397.84147 -94.615508)
		(width 0.089408)
		(layer "In11.Cu")
		(net "FM_CPU_MSMI_LVT3_N")
	)
	(segment
		(start 399.741136 -110.895892)
		(end 399.233644 -111.403384)
		(width 0.089408)
		(layer "In11.Cu")
		(net "FM_CPU_MSMI_LVT3_N")
	)
	(arc
		(start 392.394948 -117.465094)
		(mid 392.19505 -117.411595)
		(end 391.995152 -117.465094)
		(width 0.0889)
		(layer "In11.Cu")
		(net "FM_CPU_MSMI_LVT3_N")
	)
	(arc
		(start 393.385548 -117.465094)
		(mid 393.18565 -117.411595)
		(end 392.985752 -117.465094)
		(width 0.0889)
		(layer "In11.Cu")
		(net "FM_CPU_MSMI_LVT3_N")
	)
	(arc
		(start 394.376148 -117.465094)
		(mid 394.17625 -117.411595)
		(end 393.976352 -117.465094)
		(width 0.0889)
		(layer "In11.Cu")
		(net "FM_CPU_MSMI_LVT3_N")
	)
	(arc
		(start 395.7574 -116.116354)
		(mid 395.673119 -116.399571)
		(end 395.462252 -116.606574)
		(width 0.0889)
		(layer "In11.Cu")
		(net "FM_CPU_MSMI_LVT3_N")
	)
	(arc
		(start 391.995152 -117.465094)
		(mid 391.432884 -117.480536)
		(end 391.112248 -117.018308)
		(width 0.0889)
		(layer "In11.Cu")
		(net "FM_CPU_MSMI_LVT3_N")
	)
	(arc
		(start 395.2621 -116.974874)
		(mid 394.957657 -117.470351)
		(end 394.376148 -117.465094)
		(width 0.0889)
		(layer "In11.Cu")
		(net "FM_CPU_MSMI_LVT3_N")
	)
	(arc
		(start 395.957552 -115.748054)
		(mid 395.813748 -115.889737)
		(end 395.7574 -116.083588)
		(width 0.0889)
		(layer "In11.Cu")
		(net "FM_CPU_MSMI_LVT3_N")
	)
	(arc
		(start 395.462252 -116.606574)
		(mid 395.318448 -116.748257)
		(end 395.2621 -116.942108)
		(width 0.0889)
		(layer "In11.Cu")
		(net "FM_CPU_MSMI_LVT3_N")
	)
	(arc
		(start 396.172182 -115.534694)
		(mid 396.078755 -115.655344)
		(end 395.957552 -115.748054)
		(width 0.0889)
		(layer "In11.Cu")
		(net "FM_CPU_MSMI_LVT3_N")
	)
	(arc
		(start 393.976352 -117.465094)
		(mid 393.68095 -117.544225)
		(end 393.385548 -117.465094)
		(width 0.0889)
		(layer "In11.Cu")
		(net "FM_CPU_MSMI_LVT3_N")
	)
	(arc
		(start 392.985752 -117.465094)
		(mid 392.69035 -117.544225)
		(end 392.394948 -117.465094)
		(width 0.0889)
		(layer "In11.Cu")
		(net "FM_CPU_MSMI_LVT3_N")
	)
	(segment
		(start 403.396704 -40.0304)
		(end 404.300944 -40.93464)
		(width 0.10795)
		(layer "F.Cu")
		(net "FM_CPU_ERR2_LVT3_N")
	)
	(segment
		(start 391.20445 -116.72316)
		(end 391.69975 -116.953284)
		(width 0.10795)
		(layer "F.Cu")
		(net "FM_CPU_ERR2_LVT3_N")
	)
	(segment
		(start 393.961112 -76.984098)
		(end 394.05687 -77.079856)
		(width 0.10795)
		(layer "F.Cu")
		(net "FM_CPU_ERR2_LVT3_N")
	)
	(segment
		(start 404.300944 -40.93464)
		(end 407.090118 -40.93464)
		(width 0.10795)
		(layer "F.Cu")
		(net "FM_CPU_ERR2_LVT3_N")
	)
	(segment
		(start 395.376146 -77.079856)
		(end 395.5415 -76.914502)
		(width 0.10795)
		(layer "F.Cu")
		(net "FM_CPU_ERR2_LVT3_N")
	)
	(segment
		(start 393.857226 -76.984098)
		(end 393.961112 -76.984098)
		(width 0.10795)
		(layer "F.Cu")
		(net "FM_CPU_ERR2_LVT3_N")
	)
	(segment
		(start 395.5415 -76.914502)
		(end 395.5415 -76.581)
		(width 0.10795)
		(layer "F.Cu")
		(net "FM_CPU_ERR2_LVT3_N")
	)
	(segment
		(start 394.05687 -77.079856)
		(end 395.376146 -77.079856)
		(width 0.10795)
		(layer "F.Cu")
		(net "FM_CPU_ERR2_LVT3_N")
	)
	(via
		(at 391.69975 -116.953284)
		(size 0.508)
		(drill 0.254)
		(layers "F.Cu" "B.Cu")
		(net "FM_CPU_ERR2_LVT3_N")
	)
	(via
		(at 403.396704 -40.0304)
		(size 0.4572)
		(drill 0.2032)
		(layers "F.Cu" "B.Cu")
		(net "FM_CPU_ERR2_LVT3_N")
	)
	(via
		(at 393.857226 -76.984098)
		(size 0.508)
		(drill 0.254)
		(layers "F.Cu" "B.Cu")
		(net "FM_CPU_ERR2_LVT3_N")
	)
	(via
		(at 387.841744 -77.98181)
		(size 0.508)
		(drill 0.254)
		(layers "F.Cu" "B.Cu")
		(net "FM_CPU_ERR2_LVT3_N")
	)
	(segment
		(start 388.61619 -70.316344)
		(end 388.32028 -70.020434)
		(width 0.089408)
		(layer "In2.Cu")
		(net "FM_CPU_ERR2_LVT3_N")
	)
	(segment
		(start 390.398254 -47.45609)
		(end 390.266936 -47.324772)
		(width 0.089408)
		(layer "In2.Cu")
		(net "FM_CPU_ERR2_LVT3_N")
	)
	(segment
		(start 398.449546 -42.265854)
		(end 398.653 -42.0624)
		(width 0.089408)
		(layer "In2.Cu")
		(net "FM_CPU_ERR2_LVT3_N")
	)
	(segment
		(start 388.32028 -66.93408)
		(end 390.905238 -64.349122)
		(width 0.089408)
		(layer "In2.Cu")
		(net "FM_CPU_ERR2_LVT3_N")
	)
	(segment
		(start 398.653 -42.0624)
		(end 400.656044 -42.0624)
		(width 0.089408)
		(layer "In2.Cu")
		(net "FM_CPU_ERR2_LVT3_N")
	)
	(segment
		(start 390.398254 -51.798474)
		(end 390.398254 -47.45609)
		(width 0.089408)
		(layer "In2.Cu")
		(net "FM_CPU_ERR2_LVT3_N")
	)
	(segment
		(start 387.841744 -76.278994)
		(end 388.423912 -75.696826)
		(width 0.089408)
		(layer "In2.Cu")
		(net "FM_CPU_ERR2_LVT3_N")
	)
	(segment
		(start 390.267444 -46.17212)
		(end 391.65403 -44.785534)
		(width 0.089408)
		(layer "In2.Cu")
		(net "FM_CPU_ERR2_LVT3_N")
	)
	(segment
		(start 387.841744 -77.98181)
		(end 387.841744 -76.278994)
		(width 0.089408)
		(layer "In2.Cu")
		(net "FM_CPU_ERR2_LVT3_N")
	)
	(segment
		(start 387.881368 -72.357996)
		(end 388.61619 -71.623174)
		(width 0.089408)
		(layer "In2.Cu")
		(net "FM_CPU_ERR2_LVT3_N")
	)
	(segment
		(start 402.688044 -40.0304)
		(end 403.396704 -40.0304)
		(width 0.089408)
		(layer "In2.Cu")
		(net "FM_CPU_ERR2_LVT3_N")
	)
	(segment
		(start 387.881368 -73.292208)
		(end 387.881368 -72.357996)
		(width 0.089408)
		(layer "In2.Cu")
		(net "FM_CPU_ERR2_LVT3_N")
	)
	(segment
		(start 400.656044 -42.0624)
		(end 402.688044 -40.0304)
		(width 0.089408)
		(layer "In2.Cu")
		(net "FM_CPU_ERR2_LVT3_N")
	)
	(segment
		(start 390.266936 -46.375828)
		(end 390.267444 -46.37532)
		(width 0.089408)
		(layer "In2.Cu")
		(net "FM_CPU_ERR2_LVT3_N")
	)
	(segment
		(start 388.32028 -70.020434)
		(end 388.32028 -66.93408)
		(width 0.089408)
		(layer "In2.Cu")
		(net "FM_CPU_ERR2_LVT3_N")
	)
	(segment
		(start 390.905238 -61.064902)
		(end 390.046718 -60.206382)
		(width 0.089408)
		(layer "In2.Cu")
		(net "FM_CPU_ERR2_LVT3_N")
	)
	(segment
		(start 390.046718 -60.206382)
		(end 390.046718 -59.452002)
		(width 0.089408)
		(layer "In2.Cu")
		(net "FM_CPU_ERR2_LVT3_N")
	)
	(segment
		(start 390.266936 -47.324772)
		(end 390.266936 -46.375828)
		(width 0.089408)
		(layer "In2.Cu")
		(net "FM_CPU_ERR2_LVT3_N")
	)
	(segment
		(start 390.046718 -59.452002)
		(end 391.291318 -58.207402)
		(width 0.089408)
		(layer "In2.Cu")
		(net "FM_CPU_ERR2_LVT3_N")
	)
	(segment
		(start 388.61619 -71.623174)
		(end 388.61619 -70.316344)
		(width 0.089408)
		(layer "In2.Cu")
		(net "FM_CPU_ERR2_LVT3_N")
	)
	(segment
		(start 391.291318 -52.691538)
		(end 390.398254 -51.798474)
		(width 0.089408)
		(layer "In2.Cu")
		(net "FM_CPU_ERR2_LVT3_N")
	)
	(segment
		(start 390.905238 -64.349122)
		(end 390.905238 -61.064902)
		(width 0.089408)
		(layer "In2.Cu")
		(net "FM_CPU_ERR2_LVT3_N")
	)
	(segment
		(start 396.71244 -42.265854)
		(end 398.449546 -42.265854)
		(width 0.089408)
		(layer "In2.Cu")
		(net "FM_CPU_ERR2_LVT3_N")
	)
	(segment
		(start 388.423912 -73.834752)
		(end 387.881368 -73.292208)
		(width 0.089408)
		(layer "In2.Cu")
		(net "FM_CPU_ERR2_LVT3_N")
	)
	(segment
		(start 388.423912 -75.696826)
		(end 388.423912 -73.834752)
		(width 0.089408)
		(layer "In2.Cu")
		(net "FM_CPU_ERR2_LVT3_N")
	)
	(segment
		(start 390.267444 -46.37532)
		(end 390.267444 -46.17212)
		(width 0.089408)
		(layer "In2.Cu")
		(net "FM_CPU_ERR2_LVT3_N")
	)
	(segment
		(start 394.19276 -44.785534)
		(end 396.71244 -42.265854)
		(width 0.089408)
		(layer "In2.Cu")
		(net "FM_CPU_ERR2_LVT3_N")
	)
	(segment
		(start 391.291318 -58.207402)
		(end 391.291318 -52.691538)
		(width 0.089408)
		(layer "In2.Cu")
		(net "FM_CPU_ERR2_LVT3_N")
	)
	(segment
		(start 391.65403 -44.785534)
		(end 394.19276 -44.785534)
		(width 0.089408)
		(layer "In2.Cu")
		(net "FM_CPU_ERR2_LVT3_N")
	)
	(segment
		(start 393.857226 -76.984098)
		(end 392.551158 -76.984098)
		(width 0.089408)
		(layer "In4.Cu")
		(net "FM_CPU_ERR2_LVT3_N")
	)
	(segment
		(start 391.670032 -77.322934)
		(end 390.728454 -78.264512)
		(width 0.089408)
		(layer "In4.Cu")
		(net "FM_CPU_ERR2_LVT3_N")
	)
	(segment
		(start 392.551158 -76.984098)
		(end 392.212322 -77.322934)
		(width 0.089408)
		(layer "In4.Cu")
		(net "FM_CPU_ERR2_LVT3_N")
	)
	(segment
		(start 392.212322 -77.322934)
		(end 391.670032 -77.322934)
		(width 0.089408)
		(layer "In4.Cu")
		(net "FM_CPU_ERR2_LVT3_N")
	)
	(segment
		(start 390.728454 -78.264512)
		(end 388.822184 -78.264512)
		(width 0.089408)
		(layer "In4.Cu")
		(net "FM_CPU_ERR2_LVT3_N")
	)
	(segment
		(start 388.822184 -78.264512)
		(end 388.539482 -77.98181)
		(width 0.089408)
		(layer "In4.Cu")
		(net "FM_CPU_ERR2_LVT3_N")
	)
	(segment
		(start 388.539482 -77.98181)
		(end 387.841744 -77.98181)
		(width 0.089408)
		(layer "In4.Cu")
		(net "FM_CPU_ERR2_LVT3_N")
	)
	(segment
		(start 396.442946 -88.3285)
		(end 395.19352 -88.3285)
		(width 0.089408)
		(layer "In11.Cu")
		(net "FM_CPU_ERR2_LVT3_N")
	)
	(segment
		(start 396.749524 -98.629216)
		(end 396.749524 -98.299016)
		(width 0.0889)
		(layer "In11.Cu")
		(net "FM_CPU_ERR2_LVT3_N")
	)
	(segment
		(start 395.0716 -116.96446)
		(end 395.0716 -116.931694)
		(width 0.0889)
		(layer "In11.Cu")
		(net "FM_CPU_ERR2_LVT3_N")
	)
	(segment
		(start 396.25778 -113.350548)
		(end 396.25778 -113.34623)
		(width 0.0889)
		(layer "In11.Cu")
		(net "FM_CPU_ERR2_LVT3_N")
	)
	(segment
		(start 391.361676 -116.953284)
		(end 391.303764 -117.011196)
		(width 0.0889)
		(layer "In11.Cu")
		(net "FM_CPU_ERR2_LVT3_N")
	)
	(segment
		(start 396.749524 -98.299016)
		(end 397.12773 -97.92081)
		(width 0.0889)
		(layer "In11.Cu")
		(net "FM_CPU_ERR2_LVT3_N")
	)
	(segment
		(start 397.12773 -100.724462)
		(end 396.749524 -100.346256)
		(width 0.0889)
		(layer "In11.Cu")
		(net "FM_CPU_ERR2_LVT3_N")
	)
	(segment
		(start 395.19352 -88.3285)
		(end 393.941554 -87.076534)
		(width 0.089408)
		(layer "In11.Cu")
		(net "FM_CPU_ERR2_LVT3_N")
	)
	(segment
		(start 396.5575 -110.093252)
		(end 396.254224 -109.789976)
		(width 0.0889)
		(layer "In11.Cu")
		(net "FM_CPU_ERR2_LVT3_N")
	)
	(segment
		(start 393.941554 -83.654646)
		(end 394.949172 -82.647028)
		(width 0.089408)
		(layer "In11.Cu")
		(net "FM_CPU_ERR2_LVT3_N")
	)
	(segment
		(start 396.261336 -113.887504)
		(end 396.258796 -113.688876)
		(width 0.0889)
		(layer "In11.Cu")
		(net "FM_CPU_ERR2_LVT3_N")
	)
	(segment
		(start 396.254224 -109.789976)
		(end 396.254224 -109.459776)
		(width 0.0889)
		(layer "In11.Cu")
		(net "FM_CPU_ERR2_LVT3_N")
	)
	(segment
		(start 396.749524 -106.851958)
		(end 396.254224 -106.356658)
		(width 0.0889)
		(layer "In11.Cu")
		(net "FM_CPU_ERR2_LVT3_N")
	)
	(segment
		(start 396.254224 -105.992676)
		(end 395.758924 -105.497376)
		(width 0.0889)
		(layer "In11.Cu")
		(net "FM_CPU_ERR2_LVT3_N")
	)
	(segment
		(start 396.779242 -88.664796)
		(end 396.442946 -88.3285)
		(width 0.089408)
		(layer "In11.Cu")
		(net "FM_CPU_ERR2_LVT3_N")
	)
	(segment
		(start 396.749524 -100.346256)
		(end 396.749524 -100.016056)
		(width 0.0889)
		(layer "In11.Cu")
		(net "FM_CPU_ERR2_LVT3_N")
	)
	(segment
		(start 396.254224 -109.459776)
		(end 396.749524 -108.964476)
		(width 0.0889)
		(layer "In11.Cu")
		(net "FM_CPU_ERR2_LVT3_N")
	)
	(segment
		(start 396.749524 -96.581976)
		(end 397.05407 -96.27743)
		(width 0.0889)
		(layer "In11.Cu")
		(net "FM_CPU_ERR2_LVT3_N")
	)
	(segment
		(start 396.749524 -107.214416)
		(end 396.749524 -106.851958)
		(width 0.0889)
		(layer "In11.Cu")
		(net "FM_CPU_ERR2_LVT3_N")
	)
	(segment
		(start 396.254224 -113.684304)
		(end 396.254224 -113.354104)
		(width 0.0889)
		(layer "In11.Cu")
		(net "FM_CPU_ERR2_LVT3_N")
	)
	(segment
		(start 391.69975 -116.953284)
		(end 391.361676 -116.953284)
		(width 0.0889)
		(layer "In11.Cu")
		(net "FM_CPU_ERR2_LVT3_N")
	)
	(segment
		(start 396.749524 -101.733096)
		(end 397.12773 -101.35489)
		(width 0.0889)
		(layer "In11.Cu")
		(net "FM_CPU_ERR2_LVT3_N")
	)
	(segment
		(start 397.12773 -97.92081)
		(end 397.12773 -97.290382)
		(width 0.0889)
		(layer "In11.Cu")
		(net "FM_CPU_ERR2_LVT3_N")
	)
	(segment
		(start 395.758924 -104.704388)
		(end 396.749524 -103.713788)
		(width 0.0889)
		(layer "In11.Cu")
		(net "FM_CPU_ERR2_LVT3_N")
	)
	(segment
		(start 396.01775 -115.419886)
		(end 396.497048 -114.940588)
		(width 0.0889)
		(layer "In11.Cu")
		(net "FM_CPU_ERR2_LVT3_N")
	)
	(segment
		(start 396.779242 -89.225882)
		(end 396.779242 -88.664796)
		(width 0.089408)
		(layer "In11.Cu")
		(net "FM_CPU_ERR2_LVT3_N")
	)
	(segment
		(start 396.535656 -114.625374)
		(end 396.535656 -114.36096)
		(width 0.0889)
		(layer "In11.Cu")
		(net "FM_CPU_ERR2_LVT3_N")
	)
	(segment
		(start 396.749524 -100.016056)
		(end 397.12773 -99.63785)
		(width 0.0889)
		(layer "In11.Cu")
		(net "FM_CPU_ERR2_LVT3_N")
	)
	(segment
		(start 394.949172 -82.647028)
		(end 394.949172 -78.076044)
		(width 0.089408)
		(layer "In11.Cu")
		(net "FM_CPU_ERR2_LVT3_N")
	)
	(segment
		(start 396.535656 -114.36096)
		(end 396.53845 -114.32667)
		(width 0.0889)
		(layer "In11.Cu")
		(net "FM_CPU_ERR2_LVT3_N")
	)
	(segment
		(start 394.949172 -78.076044)
		(end 393.857226 -76.984098)
		(width 0.089408)
		(layer "In11.Cu")
		(net "FM_CPU_ERR2_LVT3_N")
	)
	(segment
		(start 397.05407 -95.72625)
		(end 396.676626 -95.348806)
		(width 0.0889)
		(layer "In11.Cu")
		(net "FM_CPU_ERR2_LVT3_N")
	)
	(segment
		(start 396.749524 -96.912176)
		(end 396.749524 -96.581976)
		(width 0.0889)
		(layer "In11.Cu")
		(net "FM_CPU_ERR2_LVT3_N")
	)
	(segment
		(start 397.05407 -96.27743)
		(end 397.05407 -95.72625)
		(width 0.0889)
		(layer "In11.Cu")
		(net "FM_CPU_ERR2_LVT3_N")
	)
	(segment
		(start 396.53845 -114.32667)
		(end 396.261336 -113.887504)
		(width 0.0889)
		(layer "In11.Cu")
		(net "FM_CPU_ERR2_LVT3_N")
	)
	(segment
		(start 396.676626 -95.348806)
		(end 394.552424 -93.224604)
		(width 0.089408)
		(layer "In11.Cu")
		(net "FM_CPU_ERR2_LVT3_N")
	)
	(segment
		(start 396.5575 -112.682274)
		(end 396.5575 -112.639094)
		(width 0.0889)
		(layer "In11.Cu")
		(net "FM_CPU_ERR2_LVT3_N")
	)
	(segment
		(start 394.552424 -93.224604)
		(end 394.552424 -91.4527)
		(width 0.089408)
		(layer "In11.Cu")
		(net "FM_CPU_ERR2_LVT3_N")
	)
	(segment
		(start 395.758924 -105.497376)
		(end 395.758924 -104.704388)
		(width 0.0889)
		(layer "In11.Cu")
		(net "FM_CPU_ERR2_LVT3_N")
	)
	(segment
		(start 397.12773 -99.63785)
		(end 397.12773 -99.007422)
		(width 0.0889)
		(layer "In11.Cu")
		(net "FM_CPU_ERR2_LVT3_N")
	)
	(segment
		(start 396.749524 -108.964476)
		(end 396.749524 -108.601256)
		(width 0.0889)
		(layer "In11.Cu")
		(net "FM_CPU_ERR2_LVT3_N")
	)
	(segment
		(start 397.12773 -99.007422)
		(end 396.749524 -98.629216)
		(width 0.0889)
		(layer "In11.Cu")
		(net "FM_CPU_ERR2_LVT3_N")
	)
	(segment
		(start 397.12773 -108.22305)
		(end 397.12773 -107.592622)
		(width 0.0889)
		(layer "In11.Cu")
		(net "FM_CPU_ERR2_LVT3_N")
	)
	(segment
		(start 396.749524 -108.601256)
		(end 397.12773 -108.22305)
		(width 0.0889)
		(layer "In11.Cu")
		(net "FM_CPU_ERR2_LVT3_N")
	)
	(segment
		(start 396.497048 -114.940588)
		(end 396.535656 -114.625374)
		(width 0.0889)
		(layer "In11.Cu")
		(net "FM_CPU_ERR2_LVT3_N")
	)
	(segment
		(start 396.5575 -110.965234)
		(end 396.5575 -110.093252)
		(width 0.0889)
		(layer "In11.Cu")
		(net "FM_CPU_ERR2_LVT3_N")
	)
	(segment
		(start 396.254224 -106.356658)
		(end 396.254224 -105.992676)
		(width 0.0889)
		(layer "In11.Cu")
		(net "FM_CPU_ERR2_LVT3_N")
	)
	(segment
		(start 397.12773 -107.592622)
		(end 396.749524 -107.214416)
		(width 0.0889)
		(layer "In11.Cu")
		(net "FM_CPU_ERR2_LVT3_N")
	)
	(segment
		(start 394.552424 -91.4527)
		(end 396.779242 -89.225882)
		(width 0.089408)
		(layer "In11.Cu")
		(net "FM_CPU_ERR2_LVT3_N")
	)
	(segment
		(start 393.941554 -87.076534)
		(end 393.941554 -83.654646)
		(width 0.089408)
		(layer "In11.Cu")
		(net "FM_CPU_ERR2_LVT3_N")
	)
	(segment
		(start 396.25778 -113.34623)
		(end 396.590266 -112.855502)
		(width 0.0889)
		(layer "In11.Cu")
		(net "FM_CPU_ERR2_LVT3_N")
	)
	(segment
		(start 397.12773 -97.290382)
		(end 396.749524 -96.912176)
		(width 0.0889)
		(layer "In11.Cu")
		(net "FM_CPU_ERR2_LVT3_N")
	)
	(segment
		(start 396.749524 -103.713788)
		(end 396.749524 -101.733096)
		(width 0.0889)
		(layer "In11.Cu")
		(net "FM_CPU_ERR2_LVT3_N")
	)
	(segment
		(start 395.5669 -116.10594)
		(end 395.5669 -116.073174)
		(width 0.0889)
		(layer "In11.Cu")
		(net "FM_CPU_ERR2_LVT3_N")
	)
	(segment
		(start 396.254224 -113.354104)
		(end 396.25778 -113.350548)
		(width 0.0889)
		(layer "In11.Cu")
		(net "FM_CPU_ERR2_LVT3_N")
	)
	(segment
		(start 397.12773 -101.35489)
		(end 397.12773 -100.724462)
		(width 0.0889)
		(layer "In11.Cu")
		(net "FM_CPU_ERR2_LVT3_N")
	)
	(segment
		(start 396.258796 -113.688876)
		(end 396.254224 -113.684304)
		(width 0.0889)
		(layer "In11.Cu")
		(net "FM_CPU_ERR2_LVT3_N")
	)
	(arc
		(start 393.481052 -117.299994)
		(mid 393.68095 -117.353493)
		(end 393.880848 -117.299994)
		(width 0.0889)
		(layer "In11.Cu")
		(net "FM_CPU_ERR2_LVT3_N")
	)
	(arc
		(start 396.5575 -112.639094)
		(mid 396.641781 -112.355877)
		(end 396.852648 -112.148874)
		(width 0.0889)
		(layer "In11.Cu")
		(net "FM_CPU_ERR2_LVT3_N")
	)
	(arc
		(start 396.852648 -111.455454)
		(mid 396.641784 -111.24845)
		(end 396.5575 -110.965234)
		(width 0.0889)
		(layer "In11.Cu")
		(net "FM_CPU_ERR2_LVT3_N")
	)
	(arc
		(start 394.471652 -117.299994)
		(mid 394.866899 -117.302577)
		(end 395.0716 -116.96446)
		(width 0.0889)
		(layer "In11.Cu")
		(net "FM_CPU_ERR2_LVT3_N")
	)
	(arc
		(start 393.880848 -117.299994)
		(mid 394.17625 -117.220863)
		(end 394.471652 -117.299994)
		(width 0.0889)
		(layer "In11.Cu")
		(net "FM_CPU_ERR2_LVT3_N")
	)
	(arc
		(start 396.590266 -112.855502)
		(mid 396.567371 -112.770118)
		(end 396.5575 -112.682274)
		(width 0.0889)
		(layer "In11.Cu")
		(net "FM_CPU_ERR2_LVT3_N")
	)
	(arc
		(start 395.862048 -115.582954)
		(mid 395.951615 -115.512608)
		(end 396.01775 -115.419886)
		(width 0.0889)
		(layer "In11.Cu")
		(net "FM_CPU_ERR2_LVT3_N")
	)
	(arc
		(start 391.303764 -117.011196)
		(mid 391.525214 -117.313417)
		(end 391.899648 -117.299994)
		(width 0.0889)
		(layer "In11.Cu")
		(net "FM_CPU_ERR2_LVT3_N")
	)
	(arc
		(start 395.5669 -116.073174)
		(mid 395.651181 -115.789957)
		(end 395.862048 -115.582954)
		(width 0.0889)
		(layer "In11.Cu")
		(net "FM_CPU_ERR2_LVT3_N")
	)
	(arc
		(start 392.890248 -117.299994)
		(mid 393.18565 -117.220863)
		(end 393.481052 -117.299994)
		(width 0.0889)
		(layer "In11.Cu")
		(net "FM_CPU_ERR2_LVT3_N")
	)
	(arc
		(start 391.899648 -117.299994)
		(mid 392.19505 -117.220863)
		(end 392.490452 -117.299994)
		(width 0.0889)
		(layer "In11.Cu")
		(net "FM_CPU_ERR2_LVT3_N")
	)
	(arc
		(start 396.852648 -112.148874)
		(mid 397.052959 -111.802164)
		(end 396.852648 -111.455454)
		(width 0.0889)
		(layer "In11.Cu")
		(net "FM_CPU_ERR2_LVT3_N")
	)
	(arc
		(start 392.490452 -117.299994)
		(mid 392.69035 -117.353493)
		(end 392.890248 -117.299994)
		(width 0.0889)
		(layer "In11.Cu")
		(net "FM_CPU_ERR2_LVT3_N")
	)
	(arc
		(start 395.366748 -116.441474)
		(mid 395.510552 -116.299791)
		(end 395.5669 -116.10594)
		(width 0.0889)
		(layer "In11.Cu")
		(net "FM_CPU_ERR2_LVT3_N")
	)
	(arc
		(start 395.0716 -116.931694)
		(mid 395.155881 -116.648477)
		(end 395.366748 -116.441474)
		(width 0.0889)
		(layer "In11.Cu")
		(net "FM_CPU_ERR2_LVT3_N")
	)
	(segment
		(start 367.945162 -79.894684)
		(end 368.344958 -79.494888)
		(width 0.1016)
		(layer "F.Cu")
		(net "FM_CPU_CATERR_LVT3_N")
	)
	(segment
		(start 410.290264 -40.93464)
		(end 409.890214 -41.33469)
		(width 0.10795)
		(layer "F.Cu")
		(net "FM_CPU_CATERR_LVT3_N")
	)
	(via
		(at 368.8588 -64.643)
		(size 0.508)
		(drill 0.254)
		(layers "F.Cu" "B.Cu")
		(net "FM_CPU_CATERR_LVT3_N")
	)
	(via
		(at 367.945162 -79.894684)
		(size 0.4572)
		(drill 0.2032)
		(layers "F.Cu" "B.Cu")
		(net "FM_CPU_CATERR_LVT3_N")
	)
	(via
		(at 403.756368 -64.127888)
		(size 0.508)
		(drill 0.254)
		(layers "F.Cu" "B.Cu")
		(net "FM_CPU_CATERR_LVT3_N")
	)
	(via
		(at 472.32062 -131.17322)
		(size 0.508)
		(drill 0.254)
		(layers "F.Cu" "B.Cu")
		(net "FM_CPU_CATERR_LVT3_N")
	)
	(via
		(at 426.4914 -71.524622)
		(size 0.508)
		(drill 0.254)
		(layers "F.Cu" "B.Cu")
		(net "FM_CPU_CATERR_LVT3_N")
	)
	(via
		(at 409.890214 -41.33469)
		(size 0.4572)
		(drill 0.2032)
		(layers "F.Cu" "B.Cu")
		(net "FM_CPU_CATERR_LVT3_N")
	)
	(via
		(at 419.003734 -60.014866)
		(size 0.6604)
		(drill 0.3302)
		(layers "F.Cu" "B.Cu")
		(net "FM_CPU_CATERR_LVT3_N")
	)
	(segment
		(start 405.253444 -64.6049)
		(end 404.534624 -63.88608)
		(width 0.10795)
		(layer "B.Cu")
		(net "FM_CPU_CATERR_LVT3_N")
	)
	(segment
		(start 411.280356 -62.89294)
		(end 409.231846 -64.94145)
		(width 0.10795)
		(layer "B.Cu")
		(net "FM_CPU_CATERR_LVT3_N")
	)
	(segment
		(start 426.052742 -67.26428)
		(end 425.155106 -68.161916)
		(width 0.10795)
		(layer "B.Cu")
		(net "FM_CPU_CATERR_LVT3_N")
	)
	(segment
		(start 408.851862 -64.94145)
		(end 408.229562 -64.94145)
		(width 0.10795)
		(layer "B.Cu")
		(net "FM_CPU_CATERR_LVT3_N")
	)
	(segment
		(start 407.861008 -64.941704)
		(end 407.860754 -64.94145)
		(width 0.10795)
		(layer "B.Cu")
		(net "FM_CPU_CATERR_LVT3_N")
	)
	(segment
		(start 367.119916 -64.074548)
		(end 367.722404 -64.677036)
		(width 0.10795)
		(layer "B.Cu")
		(net "FM_CPU_CATERR_LVT3_N")
	)
	(segment
		(start 418.283898 -60.734702)
		(end 415.925508 -60.734702)
		(width 0.10795)
		(layer "B.Cu")
		(net "FM_CPU_CATERR_LVT3_N")
	)
	(segment
		(start 424.785282 -59.493912)
		(end 425.495466 -60.204096)
		(width 0.10795)
		(layer "B.Cu")
		(net "FM_CPU_CATERR_LVT3_N")
	)
	(segment
		(start 426.4914 -71.4502)
		(end 426.4914 -71.524622)
		(width 0.10795)
		(layer "B.Cu")
		(net "FM_CPU_CATERR_LVT3_N")
	)
	(segment
		(start 403.998176 -63.88608)
		(end 403.756368 -64.127888)
		(width 0.10795)
		(layer "B.Cu")
		(net "FM_CPU_CATERR_LVT3_N")
	)
	(segment
		(start 419.003734 -60.014866)
		(end 418.283898 -60.734702)
		(width 0.10795)
		(layer "B.Cu")
		(net "FM_CPU_CATERR_LVT3_N")
	)
	(segment
		(start 425.155106 -68.161916)
		(end 425.155106 -70.113906)
		(width 0.10795)
		(layer "B.Cu")
		(net "FM_CPU_CATERR_LVT3_N")
	)
	(segment
		(start 407.686256 -64.94145)
		(end 407.349706 -64.6049)
		(width 0.10795)
		(layer "B.Cu")
		(net "FM_CPU_CATERR_LVT3_N")
	)
	(segment
		(start 408.229562 -64.94145)
		(end 408.229308 -64.941704)
		(width 0.10795)
		(layer "B.Cu")
		(net "FM_CPU_CATERR_LVT3_N")
	)
	(segment
		(start 409.22067 -64.94145)
		(end 409.220416 -64.941704)
		(width 0.10795)
		(layer "B.Cu")
		(net "FM_CPU_CATERR_LVT3_N")
	)
	(segment
		(start 425.495466 -62.597538)
		(end 426.052742 -63.154814)
		(width 0.10795)
		(layer "B.Cu")
		(net "FM_CPU_CATERR_LVT3_N")
	)
	(segment
		(start 409.220416 -64.941704)
		(end 408.852116 -64.941704)
		(width 0.10795)
		(layer "B.Cu")
		(net "FM_CPU_CATERR_LVT3_N")
	)
	(segment
		(start 404.534624 -63.88608)
		(end 403.998176 -63.88608)
		(width 0.10795)
		(layer "B.Cu")
		(net "FM_CPU_CATERR_LVT3_N")
	)
	(segment
		(start 408.852116 -64.941704)
		(end 408.851862 -64.94145)
		(width 0.10795)
		(layer "B.Cu")
		(net "FM_CPU_CATERR_LVT3_N")
	)
	(segment
		(start 426.052742 -63.154814)
		(end 426.052742 -67.26428)
		(width 0.10795)
		(layer "B.Cu")
		(net "FM_CPU_CATERR_LVT3_N")
	)
	(segment
		(start 407.349706 -64.6049)
		(end 405.253444 -64.6049)
		(width 0.10795)
		(layer "B.Cu")
		(net "FM_CPU_CATERR_LVT3_N")
	)
	(segment
		(start 367.722404 -64.677036)
		(end 368.824764 -64.677036)
		(width 0.10795)
		(layer "B.Cu")
		(net "FM_CPU_CATERR_LVT3_N")
	)
	(segment
		(start 425.495466 -60.204096)
		(end 425.495466 -62.597538)
		(width 0.10795)
		(layer "B.Cu")
		(net "FM_CPU_CATERR_LVT3_N")
	)
	(segment
		(start 419.003734 -60.014866)
		(end 419.524688 -59.493912)
		(width 0.10795)
		(layer "B.Cu")
		(net "FM_CPU_CATERR_LVT3_N")
	)
	(segment
		(start 472.27744 -131.2164)
		(end 472.32062 -131.17322)
		(width 0.10795)
		(layer "B.Cu")
		(net "FM_CPU_CATERR_LVT3_N")
	)
	(segment
		(start 367.119916 -63.346584)
		(end 367.119916 -64.074548)
		(width 0.10795)
		(layer "B.Cu")
		(net "FM_CPU_CATERR_LVT3_N")
	)
	(segment
		(start 419.524688 -59.493912)
		(end 424.785282 -59.493912)
		(width 0.10795)
		(layer "B.Cu")
		(net "FM_CPU_CATERR_LVT3_N")
	)
	(segment
		(start 413.76727 -62.89294)
		(end 411.280356 -62.89294)
		(width 0.10795)
		(layer "B.Cu")
		(net "FM_CPU_CATERR_LVT3_N")
	)
	(segment
		(start 368.824764 -64.677036)
		(end 368.8588 -64.643)
		(width 0.10795)
		(layer "B.Cu")
		(net "FM_CPU_CATERR_LVT3_N")
	)
	(segment
		(start 470.8906 -131.2164)
		(end 472.27744 -131.2164)
		(width 0.10795)
		(layer "B.Cu")
		(net "FM_CPU_CATERR_LVT3_N")
	)
	(segment
		(start 425.155106 -70.113906)
		(end 426.4914 -71.4502)
		(width 0.10795)
		(layer "B.Cu")
		(net "FM_CPU_CATERR_LVT3_N")
	)
	(segment
		(start 367.284 -63.1825)
		(end 367.119916 -63.346584)
		(width 0.10795)
		(layer "B.Cu")
		(net "FM_CPU_CATERR_LVT3_N")
	)
	(segment
		(start 408.229308 -64.941704)
		(end 407.861008 -64.941704)
		(width 0.10795)
		(layer "B.Cu")
		(net "FM_CPU_CATERR_LVT3_N")
	)
	(segment
		(start 407.860754 -64.94145)
		(end 407.686256 -64.94145)
		(width 0.10795)
		(layer "B.Cu")
		(net "FM_CPU_CATERR_LVT3_N")
	)
	(segment
		(start 415.925508 -60.734702)
		(end 413.76727 -62.89294)
		(width 0.10795)
		(layer "B.Cu")
		(net "FM_CPU_CATERR_LVT3_N")
	)
	(segment
		(start 409.231846 -64.94145)
		(end 409.22067 -64.94145)
		(width 0.10795)
		(layer "B.Cu")
		(net "FM_CPU_CATERR_LVT3_N")
	)
	(segment
		(start 389.091424 -63.608204)
		(end 389.233156 -63.466472)
		(width 0.089408)
		(layer "In4.Cu")
		(net "FM_CPU_CATERR_LVT3_N")
	)
	(segment
		(start 425.407836 -72.608186)
		(end 426.4914 -71.524622)
		(width 0.089408)
		(layer "In4.Cu")
		(net "FM_CPU_CATERR_LVT3_N")
	)
	(segment
		(start 469.171528 -117.285008)
		(end 464.867752 -117.285008)
		(width 0.089408)
		(layer "In4.Cu")
		(net "FM_CPU_CATERR_LVT3_N")
	)
	(segment
		(start 377.433332 -64.525398)
		(end 377.677172 -64.525398)
		(width 0.089408)
		(layer "In4.Cu")
		(net "FM_CPU_CATERR_LVT3_N")
	)
	(segment
		(start 442.14034 -117.245384)
		(end 436.964836 -117.245384)
		(width 0.089408)
		(layer "In4.Cu")
		(net "FM_CPU_CATERR_LVT3_N")
	)
	(segment
		(start 377.677172 -64.525398)
		(end 378.640594 -63.561976)
		(width 0.089408)
		(layer "In4.Cu")
		(net "FM_CPU_CATERR_LVT3_N")
	)
	(segment
		(start 381.83566 -63.1698)
		(end 383.893314 -65.227454)
		(width 0.089408)
		(layer "In4.Cu")
		(net "FM_CPU_CATERR_LVT3_N")
	)
	(segment
		(start 463.724752 -116.142008)
		(end 443.243716 -116.142008)
		(width 0.089408)
		(layer "In4.Cu")
		(net "FM_CPU_CATERR_LVT3_N")
	)
	(segment
		(start 384.8608 -65.227454)
		(end 386.48005 -63.608204)
		(width 0.089408)
		(layer "In4.Cu")
		(net "FM_CPU_CATERR_LVT3_N")
	)
	(segment
		(start 376.994928 -64.431672)
		(end 377.339606 -64.431672)
		(width 0.089408)
		(layer "In4.Cu")
		(net "FM_CPU_CATERR_LVT3_N")
	)
	(segment
		(start 474.280992 -126.836932)
		(end 474.280992 -124.539248)
		(width 0.089408)
		(layer "In4.Cu")
		(net "FM_CPU_CATERR_LVT3_N")
	)
	(segment
		(start 378.640594 -63.561976)
		(end 380.05512 -63.561976)
		(width 0.089408)
		(layer "In4.Cu")
		(net "FM_CPU_CATERR_LVT3_N")
	)
	(segment
		(start 472.32062 -131.17322)
		(end 472.32062 -128.797304)
		(width 0.089408)
		(layer "In4.Cu")
		(net "FM_CPU_CATERR_LVT3_N")
	)
	(segment
		(start 398.316958 -62.040008)
		(end 399.471134 -63.194184)
		(width 0.089408)
		(layer "In4.Cu")
		(net "FM_CPU_CATERR_LVT3_N")
	)
	(segment
		(start 470.272872 -120.531128)
		(end 470.272872 -118.386352)
		(width 0.089408)
		(layer "In4.Cu")
		(net "FM_CPU_CATERR_LVT3_N")
	)
	(segment
		(start 369.329462 -64.172338)
		(end 370.853208 -64.172338)
		(width 0.089408)
		(layer "In4.Cu")
		(net "FM_CPU_CATERR_LVT3_N")
	)
	(segment
		(start 383.893314 -65.227454)
		(end 384.8608 -65.227454)
		(width 0.089408)
		(layer "In4.Cu")
		(net "FM_CPU_CATERR_LVT3_N")
	)
	(segment
		(start 423.678604 -116.800376)
		(end 423.67835 -116.80063)
		(width 0.089408)
		(layer "In4.Cu")
		(net "FM_CPU_CATERR_LVT3_N")
	)
	(segment
		(start 428.046134 -120.344438)
		(end 428.04588 -120.344692)
		(width 0.089408)
		(layer "In4.Cu")
		(net "FM_CPU_CATERR_LVT3_N")
	)
	(segment
		(start 403.756368 -63.92672)
		(end 403.756368 -64.127888)
		(width 0.089408)
		(layer "In4.Cu")
		(net "FM_CPU_CATERR_LVT3_N")
	)
	(segment
		(start 425.407836 -107.646216)
		(end 425.407836 -72.608186)
		(width 0.089408)
		(layer "In4.Cu")
		(net "FM_CPU_CATERR_LVT3_N")
	)
	(segment
		(start 422.960546 -110.72876)
		(end 423.155364 -110.923578)
		(width 0.089408)
		(layer "In4.Cu")
		(net "FM_CPU_CATERR_LVT3_N")
	)
	(segment
		(start 443.243716 -116.142008)
		(end 442.14034 -117.245384)
		(width 0.089408)
		(layer "In4.Cu")
		(net "FM_CPU_CATERR_LVT3_N")
	)
	(segment
		(start 370.853208 -64.172338)
		(end 371.840252 -63.185294)
		(width 0.089408)
		(layer "In4.Cu")
		(net "FM_CPU_CATERR_LVT3_N")
	)
	(segment
		(start 423.995088 -116.800376)
		(end 423.678604 -116.800376)
		(width 0.089408)
		(layer "In4.Cu")
		(net "FM_CPU_CATERR_LVT3_N")
	)
	(segment
		(start 472.32062 -128.797304)
		(end 474.280992 -126.836932)
		(width 0.089408)
		(layer "In4.Cu")
		(net "FM_CPU_CATERR_LVT3_N")
	)
	(segment
		(start 371.840252 -63.185294)
		(end 375.74855 -63.185294)
		(width 0.089408)
		(layer "In4.Cu")
		(net "FM_CPU_CATERR_LVT3_N")
	)
	(segment
		(start 470.272872 -118.386352)
		(end 469.171528 -117.285008)
		(width 0.089408)
		(layer "In4.Cu")
		(net "FM_CPU_CATERR_LVT3_N")
	)
	(segment
		(start 399.471134 -63.194184)
		(end 403.023832 -63.194184)
		(width 0.089408)
		(layer "In4.Cu")
		(net "FM_CPU_CATERR_LVT3_N")
	)
	(segment
		(start 423.995342 -116.80063)
		(end 423.995088 -116.800376)
		(width 0.089408)
		(layer "In4.Cu")
		(net "FM_CPU_CATERR_LVT3_N")
	)
	(segment
		(start 421.666416 -116.80063)
		(end 421.5638 -116.698014)
		(width 0.089408)
		(layer "In4.Cu")
		(net "FM_CPU_CATERR_LVT3_N")
	)
	(segment
		(start 403.023832 -63.194184)
		(end 403.756368 -63.92672)
		(width 0.089408)
		(layer "In4.Cu")
		(net "FM_CPU_CATERR_LVT3_N")
	)
	(segment
		(start 423.155364 -110.923578)
		(end 423.92092 -110.923578)
		(width 0.089408)
		(layer "In4.Cu")
		(net "FM_CPU_CATERR_LVT3_N")
	)
	(segment
		(start 423.92092 -110.923578)
		(end 424.461686 -110.382812)
		(width 0.089408)
		(layer "In4.Cu")
		(net "FM_CPU_CATERR_LVT3_N")
	)
	(segment
		(start 422.056814 -110.72876)
		(end 422.960546 -110.72876)
		(width 0.089408)
		(layer "In4.Cu")
		(net "FM_CPU_CATERR_LVT3_N")
	)
	(segment
		(start 380.447296 -63.1698)
		(end 381.83566 -63.1698)
		(width 0.089408)
		(layer "In4.Cu")
		(net "FM_CPU_CATERR_LVT3_N")
	)
	(segment
		(start 427.803564 -120.344692)
		(end 424.259502 -116.80063)
		(width 0.089408)
		(layer "In4.Cu")
		(net "FM_CPU_CATERR_LVT3_N")
	)
	(segment
		(start 423.67835 -116.80063)
		(end 421.666416 -116.80063)
		(width 0.089408)
		(layer "In4.Cu")
		(net "FM_CPU_CATERR_LVT3_N")
	)
	(segment
		(start 436.964582 -117.24513)
		(end 436.806594 -117.24513)
		(width 0.089408)
		(layer "In4.Cu")
		(net "FM_CPU_CATERR_LVT3_N")
	)
	(segment
		(start 436.806594 -117.24513)
		(end 433.707286 -120.344438)
		(width 0.089408)
		(layer "In4.Cu")
		(net "FM_CPU_CATERR_LVT3_N")
	)
	(segment
		(start 421.5638 -116.698014)
		(end 421.5638 -111.221774)
		(width 0.089408)
		(layer "In4.Cu")
		(net "FM_CPU_CATERR_LVT3_N")
	)
	(segment
		(start 424.461686 -108.592366)
		(end 425.407836 -107.646216)
		(width 0.089408)
		(layer "In4.Cu")
		(net "FM_CPU_CATERR_LVT3_N")
	)
	(segment
		(start 424.461686 -110.382812)
		(end 424.461686 -108.592366)
		(width 0.089408)
		(layer "In4.Cu")
		(net "FM_CPU_CATERR_LVT3_N")
	)
	(segment
		(start 395.242542 -62.040008)
		(end 398.316958 -62.040008)
		(width 0.089408)
		(layer "In4.Cu")
		(net "FM_CPU_CATERR_LVT3_N")
	)
	(segment
		(start 386.48005 -63.608204)
		(end 389.091424 -63.608204)
		(width 0.089408)
		(layer "In4.Cu")
		(net "FM_CPU_CATERR_LVT3_N")
	)
	(segment
		(start 436.964836 -117.245384)
		(end 436.964582 -117.24513)
		(width 0.089408)
		(layer "In4.Cu")
		(net "FM_CPU_CATERR_LVT3_N")
	)
	(segment
		(start 464.867752 -117.285008)
		(end 463.724752 -116.142008)
		(width 0.089408)
		(layer "In4.Cu")
		(net "FM_CPU_CATERR_LVT3_N")
	)
	(segment
		(start 474.280992 -124.539248)
		(end 470.272872 -120.531128)
		(width 0.089408)
		(layer "In4.Cu")
		(net "FM_CPU_CATERR_LVT3_N")
	)
	(segment
		(start 433.707286 -120.344438)
		(end 428.046134 -120.344438)
		(width 0.089408)
		(layer "In4.Cu")
		(net "FM_CPU_CATERR_LVT3_N")
	)
	(segment
		(start 428.04588 -120.344692)
		(end 427.803564 -120.344692)
		(width 0.089408)
		(layer "In4.Cu")
		(net "FM_CPU_CATERR_LVT3_N")
	)
	(segment
		(start 424.259502 -116.80063)
		(end 423.995342 -116.80063)
		(width 0.089408)
		(layer "In4.Cu")
		(net "FM_CPU_CATERR_LVT3_N")
	)
	(segment
		(start 377.339606 -64.431672)
		(end 377.433332 -64.525398)
		(width 0.089408)
		(layer "In4.Cu")
		(net "FM_CPU_CATERR_LVT3_N")
	)
	(segment
		(start 380.05512 -63.561976)
		(end 380.447296 -63.1698)
		(width 0.089408)
		(layer "In4.Cu")
		(net "FM_CPU_CATERR_LVT3_N")
	)
	(segment
		(start 421.5638 -111.221774)
		(end 422.056814 -110.72876)
		(width 0.089408)
		(layer "In4.Cu")
		(net "FM_CPU_CATERR_LVT3_N")
	)
	(segment
		(start 375.74855 -63.185294)
		(end 376.994928 -64.431672)
		(width 0.089408)
		(layer "In4.Cu")
		(net "FM_CPU_CATERR_LVT3_N")
	)
	(segment
		(start 368.8588 -64.643)
		(end 369.329462 -64.172338)
		(width 0.089408)
		(layer "In4.Cu")
		(net "FM_CPU_CATERR_LVT3_N")
	)
	(segment
		(start 393.816078 -63.466472)
		(end 395.242542 -62.040008)
		(width 0.089408)
		(layer "In4.Cu")
		(net "FM_CPU_CATERR_LVT3_N")
	)
	(segment
		(start 389.233156 -63.466472)
		(end 393.816078 -63.466472)
		(width 0.089408)
		(layer "In4.Cu")
		(net "FM_CPU_CATERR_LVT3_N")
	)
	(segment
		(start 368.318542 -74.3966)
		(end 368.318542 -76.886054)
		(width 0.089408)
		(layer "In9.Cu")
		(net "FM_CPU_CATERR_LVT3_N")
	)
	(segment
		(start 367.571782 -69.340476)
		(end 367.571782 -73.64984)
		(width 0.089408)
		(layer "In9.Cu")
		(net "FM_CPU_CATERR_LVT3_N")
	)
	(segment
		(start 403.310852 -57.65038)
		(end 401.643088 -55.982616)
		(width 0.089408)
		(layer "In9.Cu")
		(net "FM_CPU_CATERR_LVT3_N")
	)
	(segment
		(start 403.310852 -63.289434)
		(end 403.310852 -57.65038)
		(width 0.089408)
		(layer "In9.Cu")
		(net "FM_CPU_CATERR_LVT3_N")
	)
	(segment
		(start 406.784302 -44.51223)
		(end 407.504392 -43.79214)
		(width 0.089408)
		(layer "In9.Cu")
		(net "FM_CPU_CATERR_LVT3_N")
	)
	(segment
		(start 368.899948 -79.468218)
		(end 368.375184 -79.468218)
		(width 0.089408)
		(layer "In9.Cu")
		(net "FM_CPU_CATERR_LVT3_N")
	)
	(segment
		(start 368.321844 -66.399156)
		(end 368.321844 -68.8467)
		(width 0.089408)
		(layer "In9.Cu")
		(net "FM_CPU_CATERR_LVT3_N")
	)
	(segment
		(start 368.8588 -65.8622)
		(end 368.321844 -66.399156)
		(width 0.089408)
		(layer "In9.Cu")
		(net "FM_CPU_CATERR_LVT3_N")
	)
	(segment
		(start 401.643088 -55.982616)
		(end 401.643088 -50.206656)
		(width 0.089408)
		(layer "In9.Cu")
		(net "FM_CPU_CATERR_LVT3_N")
	)
	(segment
		(start 408.910282 -41.75125)
		(end 409.473654 -41.75125)
		(width 0.089408)
		(layer "In9.Cu")
		(net "FM_CPU_CATERR_LVT3_N")
	)
	(segment
		(start 368.554 -77.121512)
		(end 368.899948 -77.121512)
		(width 0.089408)
		(layer "In9.Cu")
		(net "FM_CPU_CATERR_LVT3_N")
	)
	(segment
		(start 404.277068 -45.434504)
		(end 405.199342 -44.51223)
		(width 0.089408)
		(layer "In9.Cu")
		(net "FM_CPU_CATERR_LVT3_N")
	)
	(segment
		(start 403.756368 -64.127888)
		(end 403.756368 -63.73495)
		(width 0.089408)
		(layer "In9.Cu")
		(net "FM_CPU_CATERR_LVT3_N")
	)
	(segment
		(start 402.59508 -49.254664)
		(end 402.59508 -47.780448)
		(width 0.089408)
		(layer "In9.Cu")
		(net "FM_CPU_CATERR_LVT3_N")
	)
	(segment
		(start 409.473654 -41.75125)
		(end 409.890214 -41.33469)
		(width 0.089408)
		(layer "In9.Cu")
		(net "FM_CPU_CATERR_LVT3_N")
	)
	(segment
		(start 368.226594 -79.616808)
		(end 368.223038 -79.616808)
		(width 0.089408)
		(layer "In9.Cu")
		(net "FM_CPU_CATERR_LVT3_N")
	)
	(segment
		(start 403.756368 -63.73495)
		(end 403.310852 -63.289434)
		(width 0.089408)
		(layer "In9.Cu")
		(net "FM_CPU_CATERR_LVT3_N")
	)
	(segment
		(start 368.8588 -64.643)
		(end 368.8588 -65.8622)
		(width 0.089408)
		(layer "In9.Cu")
		(net "FM_CPU_CATERR_LVT3_N")
	)
	(segment
		(start 369.118642 -79.249524)
		(end 368.899948 -79.468218)
		(width 0.089408)
		(layer "In9.Cu")
		(net "FM_CPU_CATERR_LVT3_N")
	)
	(segment
		(start 402.59508 -47.780448)
		(end 403.916896 -46.458632)
		(width 0.089408)
		(layer "In9.Cu")
		(net "FM_CPU_CATERR_LVT3_N")
	)
	(segment
		(start 367.571782 -73.64984)
		(end 368.318542 -74.3966)
		(width 0.089408)
		(layer "In9.Cu")
		(net "FM_CPU_CATERR_LVT3_N")
	)
	(segment
		(start 368.223038 -79.616808)
		(end 367.945162 -79.894684)
		(width 0.089408)
		(layer "In9.Cu")
		(net "FM_CPU_CATERR_LVT3_N")
	)
	(segment
		(start 368.375184 -79.468218)
		(end 368.226594 -79.616808)
		(width 0.089408)
		(layer "In9.Cu")
		(net "FM_CPU_CATERR_LVT3_N")
	)
	(segment
		(start 369.118642 -77.340206)
		(end 369.118642 -79.249524)
		(width 0.089408)
		(layer "In9.Cu")
		(net "FM_CPU_CATERR_LVT3_N")
	)
	(segment
		(start 368.318542 -76.886054)
		(end 368.554 -77.121512)
		(width 0.089408)
		(layer "In9.Cu")
		(net "FM_CPU_CATERR_LVT3_N")
	)
	(segment
		(start 367.843562 -69.068696)
		(end 367.571782 -69.340476)
		(width 0.089408)
		(layer "In9.Cu")
		(net "FM_CPU_CATERR_LVT3_N")
	)
	(segment
		(start 401.643088 -50.206656)
		(end 402.59508 -49.254664)
		(width 0.089408)
		(layer "In9.Cu")
		(net "FM_CPU_CATERR_LVT3_N")
	)
	(segment
		(start 407.504392 -43.79214)
		(end 407.504392 -43.15714)
		(width 0.089408)
		(layer "In9.Cu")
		(net "FM_CPU_CATERR_LVT3_N")
	)
	(segment
		(start 368.321844 -68.8467)
		(end 368.099848 -69.068696)
		(width 0.089408)
		(layer "In9.Cu")
		(net "FM_CPU_CATERR_LVT3_N")
	)
	(segment
		(start 403.916896 -46.458632)
		(end 404.277068 -46.09846)
		(width 0.0889)
		(layer "In9.Cu")
		(net "FM_CPU_CATERR_LVT3_N")
	)
	(segment
		(start 407.504392 -43.15714)
		(end 408.910282 -41.75125)
		(width 0.089408)
		(layer "In9.Cu")
		(net "FM_CPU_CATERR_LVT3_N")
	)
	(segment
		(start 405.199342 -44.51223)
		(end 406.784302 -44.51223)
		(width 0.089408)
		(layer "In9.Cu")
		(net "FM_CPU_CATERR_LVT3_N")
	)
	(segment
		(start 368.099848 -69.068696)
		(end 367.843562 -69.068696)
		(width 0.089408)
		(layer "In9.Cu")
		(net "FM_CPU_CATERR_LVT3_N")
	)
	(segment
		(start 368.899948 -77.121512)
		(end 369.118642 -77.340206)
		(width 0.089408)
		(layer "In9.Cu")
		(net "FM_CPU_CATERR_LVT3_N")
	)
	(segment
		(start 404.277068 -46.09846)
		(end 404.277068 -45.434504)
		(width 0.089408)
		(layer "In9.Cu")
		(net "FM_CPU_CATERR_LVT3_N")
	)
	(via
		(at 368.404902 -62.651894)
		(size 0.508)
		(drill 0.254)
		(layers "F.Cu" "B.Cu")
		(net "FM_CPU1_THERMTRIP_LVT3_R_N")
	)
	(segment
		(start 369.443 -62.9285)
		(end 368.681508 -62.9285)
		(width 0.10795)
		(layer "B.Cu")
		(net "FM_CPU1_THERMTRIP_LVT3_R_N")
	)
	(segment
		(start 367.9952 -59.941714)
		(end 365.681006 -57.62752)
		(width 0.10795)
		(layer "B.Cu")
		(net "FM_CPU1_THERMTRIP_LVT3_R_N")
	)
	(segment
		(start 368.681508 -62.9285)
		(end 368.404902 -62.651894)
		(width 0.10795)
		(layer "B.Cu")
		(net "FM_CPU1_THERMTRIP_LVT3_R_N")
	)
	(segment
		(start 368.404902 -62.651894)
		(end 367.9952 -62.242192)
		(width 0.10795)
		(layer "B.Cu")
		(net "FM_CPU1_THERMTRIP_LVT3_R_N")
	)
	(segment
		(start 365.681006 -57.62752)
		(end 364.4265 -57.62752)
		(width 0.10795)
		(layer "B.Cu")
		(net "FM_CPU1_THERMTRIP_LVT3_R_N")
	)
	(segment
		(start 367.9952 -62.242192)
		(end 367.9952 -59.941714)
		(width 0.10795)
		(layer "B.Cu")
		(net "FM_CPU1_THERMTRIP_LVT3_R_N")
	)
	(segment
		(start 367.945162 -72.695308)
		(end 368.344958 -73.095104)
		(width 0.1016)
		(layer "F.Cu")
		(net "FM_CPU1_THERMTRIP_LVT3_N")
	)
	(via
		(at 368.771932 -65.505584)
		(size 0.6604)
		(drill 0.3302)
		(layers "F.Cu" "B.Cu")
		(net "FM_CPU1_THERMTRIP_LVT3_N")
	)
	(via
		(at 367.945162 -72.695308)
		(size 0.4572)
		(drill 0.2032)
		(layers "F.Cu" "B.Cu")
		(net "FM_CPU1_THERMTRIP_LVT3_N")
	)
	(segment
		(start 369.299998 -64.977518)
		(end 369.299998 -64.467994)
		(width 0.10795)
		(layer "B.Cu")
		(net "FM_CPU1_THERMTRIP_LVT3_N")
	)
	(segment
		(start 368.19459 -64.928242)
		(end 368.771932 -65.505584)
		(width 0.10795)
		(layer "B.Cu")
		(net "FM_CPU1_THERMTRIP_LVT3_N")
	)
	(segment
		(start 367.012982 -65.956688)
		(end 367.012982 -65.18783)
		(width 0.10795)
		(layer "B.Cu")
		(net "FM_CPU1_THERMTRIP_LVT3_N")
	)
	(segment
		(start 369.299998 -64.467994)
		(end 369.443 -64.324992)
		(width 0.10795)
		(layer "B.Cu")
		(net "FM_CPU1_THERMTRIP_LVT3_N")
	)
	(segment
		(start 366.760506 -71.281036)
		(end 366.760506 -67.662298)
		(width 0.10795)
		(layer "B.Cu")
		(net "FM_CPU1_THERMTRIP_LVT3_N")
	)
	(segment
		(start 367.27257 -64.928242)
		(end 368.19459 -64.928242)
		(width 0.10795)
		(layer "B.Cu")
		(net "FM_CPU1_THERMTRIP_LVT3_N")
	)
	(segment
		(start 366.24387 -67.145662)
		(end 366.24387 -66.7258)
		(width 0.10795)
		(layer "B.Cu")
		(net "FM_CPU1_THERMTRIP_LVT3_N")
	)
	(segment
		(start 368.771932 -65.505584)
		(end 369.299998 -64.977518)
		(width 0.10795)
		(layer "B.Cu")
		(net "FM_CPU1_THERMTRIP_LVT3_N")
	)
	(segment
		(start 367.945162 -72.465692)
		(end 366.760506 -71.281036)
		(width 0.10795)
		(layer "B.Cu")
		(net "FM_CPU1_THERMTRIP_LVT3_N")
	)
	(segment
		(start 369.443 -64.324992)
		(end 369.443 -63.8175)
		(width 0.10795)
		(layer "B.Cu")
		(net "FM_CPU1_THERMTRIP_LVT3_N")
	)
	(segment
		(start 366.760506 -67.662298)
		(end 366.24387 -67.145662)
		(width 0.10795)
		(layer "B.Cu")
		(net "FM_CPU1_THERMTRIP_LVT3_N")
	)
	(segment
		(start 367.945162 -72.695308)
		(end 367.945162 -72.465692)
		(width 0.10795)
		(layer "B.Cu")
		(net "FM_CPU1_THERMTRIP_LVT3_N")
	)
	(segment
		(start 367.012982 -65.18783)
		(end 367.27257 -64.928242)
		(width 0.10795)
		(layer "B.Cu")
		(net "FM_CPU1_THERMTRIP_LVT3_N")
	)
	(segment
		(start 366.24387 -66.7258)
		(end 367.012982 -65.956688)
		(width 0.10795)
		(layer "B.Cu")
		(net "FM_CPU1_THERMTRIP_LVT3_N")
	)
	(via
		(at 368.279426 -64.111886)
		(size 0.6604)
		(drill 0.3302)
		(layers "F.Cu" "B.Cu")
		(net "FM_CPU_CATERR_LVT3_R2_N")
	)
	(segment
		(start 367.284 -61.998352)
		(end 367.523268 -61.759084)
		(width 0.10795)
		(layer "B.Cu")
		(net "FM_CPU_CATERR_LVT3_R2_N")
	)
	(segment
		(start 367.284 -62.2935)
		(end 367.284 -61.998352)
		(width 0.10795)
		(layer "B.Cu")
		(net "FM_CPU_CATERR_LVT3_R2_N")
	)
	(segment
		(start 368.279426 -64.111886)
		(end 368.279426 -62.987428)
		(width 0.10795)
		(layer "B.Cu")
		(net "FM_CPU_CATERR_LVT3_R2_N")
	)
	(segment
		(start 365.81715 -58.27776)
		(end 364.4265 -58.27776)
		(width 0.10795)
		(layer "B.Cu")
		(net "FM_CPU_CATERR_LVT3_R2_N")
	)
	(segment
		(start 367.579402 -61.680598)
		(end 367.579402 -60.040012)
		(width 0.10795)
		(layer "B.Cu")
		(net "FM_CPU_CATERR_LVT3_R2_N")
	)
	(segment
		(start 367.585498 -62.2935)
		(end 367.284 -62.2935)
		(width 0.10795)
		(layer "B.Cu")
		(net "FM_CPU_CATERR_LVT3_R2_N")
	)
	(segment
		(start 368.279426 -62.987428)
		(end 367.585498 -62.2935)
		(width 0.10795)
		(layer "B.Cu")
		(net "FM_CPU_CATERR_LVT3_R2_N")
	)
	(segment
		(start 367.523268 -61.759084)
		(end 367.523268 -61.736732)
		(width 0.10795)
		(layer "B.Cu")
		(net "FM_CPU_CATERR_LVT3_R2_N")
	)
	(segment
		(start 367.579402 -60.040012)
		(end 365.81715 -58.27776)
		(width 0.10795)
		(layer "B.Cu")
		(net "FM_CPU_CATERR_LVT3_R2_N")
	)
	(segment
		(start 367.523268 -61.736732)
		(end 367.579402 -61.680598)
		(width 0.10795)
		(layer "B.Cu")
		(net "FM_CPU_CATERR_LVT3_R2_N")
	)
	(segment
		(start 391.414 -51.92014)
		(end 389.966454 -53.367686)
		(width 0.10795)
		(layer "F.Cu")
		(net "FM_CPU1_PROCHOT_LVT3_N")
	)
	(segment
		(start 398.002506 -42.661586)
		(end 396.285466 -42.661586)
		(width 0.10795)
		(layer "F.Cu")
		(net "FM_CPU1_PROCHOT_LVT3_N")
	)
	(segment
		(start 381.530606 -58.135266)
		(end 380.646432 -58.135266)
		(width 0.10795)
		(layer "F.Cu")
		(net "FM_CPU1_PROCHOT_LVT3_N")
	)
	(segment
		(start 368.992912 -61.7474)
		(end 368.992912 -61.799724)
		(width 0.10795)
		(layer "F.Cu")
		(net "FM_CPU1_PROCHOT_LVT3_N")
	)
	(segment
		(start 380.412498 -58.3692)
		(end 378.761752 -58.3692)
		(width 0.10795)
		(layer "F.Cu")
		(net "FM_CPU1_PROCHOT_LVT3_N")
	)
	(segment
		(start 395.20749 -43.739562)
		(end 395.20749 -44.158154)
		(width 0.10795)
		(layer "F.Cu")
		(net "FM_CPU1_PROCHOT_LVT3_N")
	)
	(segment
		(start 402.615146 -41.792652)
		(end 400.943064 -41.792652)
		(width 0.10795)
		(layer "F.Cu")
		(net "FM_CPU1_PROCHOT_LVT3_N")
	)
	(segment
		(start 402.615146 -41.4274)
		(end 402.615146 -41.792652)
		(width 0.10795)
		(layer "F.Cu")
		(net "FM_CPU1_PROCHOT_LVT3_N")
	)
	(segment
		(start 393.708382 -45.657262)
		(end 392.241024 -45.657262)
		(width 0.10795)
		(layer "F.Cu")
		(net "FM_CPU1_PROCHOT_LVT3_N")
	)
	(segment
		(start 374.711722 -60.7314)
		(end 370.008912 -60.7314)
		(width 0.10795)
		(layer "F.Cu")
		(net "FM_CPU1_PROCHOT_LVT3_N")
	)
	(segment
		(start 395.20749 -44.158154)
		(end 393.708382 -45.657262)
		(width 0.10795)
		(layer "F.Cu")
		(net "FM_CPU1_PROCHOT_LVT3_N")
	)
	(segment
		(start 389.285988 -57.500012)
		(end 382.16586 -57.500012)
		(width 0.10795)
		(layer "F.Cu")
		(net "FM_CPU1_PROCHOT_LVT3_N")
	)
	(segment
		(start 402.590254 -40.985948)
		(end 402.590254 -41.402508)
		(width 0.10795)
		(layer "F.Cu")
		(net "FM_CPU1_PROCHOT_LVT3_N")
	)
	(segment
		(start 396.285466 -42.661586)
		(end 395.20749 -43.739562)
		(width 0.10795)
		(layer "F.Cu")
		(net "FM_CPU1_PROCHOT_LVT3_N")
	)
	(segment
		(start 378.221494 -58.909458)
		(end 376.004582 -61.12637)
		(width 0.10795)
		(layer "F.Cu")
		(net "FM_CPU1_PROCHOT_LVT3_N")
	)
	(segment
		(start 382.16586 -57.500012)
		(end 381.530606 -58.135266)
		(width 0.10795)
		(layer "F.Cu")
		(net "FM_CPU1_PROCHOT_LVT3_N")
	)
	(segment
		(start 392.241024 -45.657262)
		(end 391.414 -46.484286)
		(width 0.10795)
		(layer "F.Cu")
		(net "FM_CPU1_PROCHOT_LVT3_N")
	)
	(segment
		(start 389.966454 -56.819546)
		(end 389.285988 -57.500012)
		(width 0.10795)
		(layer "F.Cu")
		(net "FM_CPU1_PROCHOT_LVT3_N")
	)
	(segment
		(start 376.004582 -61.12637)
		(end 375.106692 -61.12637)
		(width 0.10795)
		(layer "F.Cu")
		(net "FM_CPU1_PROCHOT_LVT3_N")
	)
	(segment
		(start 400.719036 -42.01668)
		(end 398.647412 -42.01668)
		(width 0.10795)
		(layer "F.Cu")
		(net "FM_CPU1_PROCHOT_LVT3_N")
	)
	(segment
		(start 398.647412 -42.01668)
		(end 398.002506 -42.661586)
		(width 0.10795)
		(layer "F.Cu")
		(net "FM_CPU1_PROCHOT_LVT3_N")
	)
	(segment
		(start 375.106692 -61.12637)
		(end 374.711722 -60.7314)
		(width 0.10795)
		(layer "F.Cu")
		(net "FM_CPU1_PROCHOT_LVT3_N")
	)
	(segment
		(start 370.008912 -60.7314)
		(end 368.992912 -61.7474)
		(width 0.10795)
		(layer "F.Cu")
		(net "FM_CPU1_PROCHOT_LVT3_N")
	)
	(segment
		(start 378.761752 -58.3692)
		(end 378.221494 -58.909458)
		(width 0.10795)
		(layer "F.Cu")
		(net "FM_CPU1_PROCHOT_LVT3_N")
	)
	(segment
		(start 402.590254 -41.402508)
		(end 402.615146 -41.4274)
		(width 0.10795)
		(layer "F.Cu")
		(net "FM_CPU1_PROCHOT_LVT3_N")
	)
	(segment
		(start 391.414 -46.484286)
		(end 391.414 -51.92014)
		(width 0.10795)
		(layer "F.Cu")
		(net "FM_CPU1_PROCHOT_LVT3_N")
	)
	(segment
		(start 380.646432 -58.135266)
		(end 380.412498 -58.3692)
		(width 0.10795)
		(layer "F.Cu")
		(net "FM_CPU1_PROCHOT_LVT3_N")
	)
	(segment
		(start 400.943064 -41.792652)
		(end 400.719036 -42.01668)
		(width 0.10795)
		(layer "F.Cu")
		(net "FM_CPU1_PROCHOT_LVT3_N")
	)
	(segment
		(start 389.966454 -53.367686)
		(end 389.966454 -56.819546)
		(width 0.10795)
		(layer "F.Cu")
		(net "FM_CPU1_PROCHOT_LVT3_N")
	)
	(via
		(at 378.221494 -58.909458)
		(size 0.762)
		(drill 0.381)
		(layers "F.Cu" "B.Cu")
		(net "FM_CPU1_PROCHOT_LVT3_N")
	)
	(via
		(at 368.992912 -61.799724)
		(size 0.508)
		(drill 0.254)
		(layers "F.Cu" "B.Cu")
		(net "FM_CPU1_PROCHOT_LVT3_N")
	)
	(via
		(at 370.476526 -48.804322)
		(size 0.508)
		(drill 0.254)
		(layers "F.Cu" "B.Cu")
		(net "FM_CPU1_PROCHOT_LVT3_N")
	)
	(segment
		(start 366.494822 -48.133762)
		(end 366.494314 -48.13427)
		(width 0.10795)
		(layer "B.Cu")
		(net "FM_CPU1_PROCHOT_LVT3_N")
	)
	(segment
		(start 360.555794 -47.815754)
		(end 360.555794 -47.258986)
		(width 0.10795)
		(layer "B.Cu")
		(net "FM_CPU1_PROCHOT_LVT3_N")
	)
	(segment
		(start 366.494314 -48.13427)
		(end 366.48898 -48.13427)
		(width 0.10795)
		(layer "B.Cu")
		(net "FM_CPU1_PROCHOT_LVT3_N")
	)
	(segment
		(start 361.054904 -48.314864)
		(end 360.555794 -47.815754)
		(width 0.10795)
		(layer "B.Cu")
		(net "FM_CPU1_PROCHOT_LVT3_N")
	)
	(segment
		(start 361.449874 -48.314864)
		(end 361.054904 -48.314864)
		(width 0.10795)
		(layer "B.Cu")
		(net "FM_CPU1_PROCHOT_LVT3_N")
	)
	(segment
		(start 369.153186 -48.804322)
		(end 368.482626 -48.133762)
		(width 0.10795)
		(layer "B.Cu")
		(net "FM_CPU1_PROCHOT_LVT3_N")
	)
	(segment
		(start 368.482626 -48.133762)
		(end 366.494822 -48.133762)
		(width 0.10795)
		(layer "B.Cu")
		(net "FM_CPU1_PROCHOT_LVT3_N")
	)
	(segment
		(start 362.011214 -48.876204)
		(end 361.449874 -48.314864)
		(width 0.10795)
		(layer "B.Cu")
		(net "FM_CPU1_PROCHOT_LVT3_N")
	)
	(segment
		(start 365.747046 -48.876204)
		(end 362.011214 -48.876204)
		(width 0.10795)
		(layer "B.Cu")
		(net "FM_CPU1_PROCHOT_LVT3_N")
	)
	(segment
		(start 366.48898 -48.13427)
		(end 365.747046 -48.876204)
		(width 0.10795)
		(layer "B.Cu")
		(net "FM_CPU1_PROCHOT_LVT3_N")
	)
	(segment
		(start 370.476526 -48.804322)
		(end 369.153186 -48.804322)
		(width 0.10795)
		(layer "B.Cu")
		(net "FM_CPU1_PROCHOT_LVT3_N")
	)
	(segment
		(start 367.986056 -51.791616)
		(end 368.024156 -51.829716)
		(width 0.089408)
		(layer "In9.Cu")
		(net "FM_CPU1_PROCHOT_LVT3_N")
	)
	(segment
		(start 367.438686 -51.791616)
		(end 367.986056 -51.791616)
		(width 0.089408)
		(layer "In9.Cu")
		(net "FM_CPU1_PROCHOT_LVT3_N")
	)
	(segment
		(start 368.992912 -61.799724)
		(end 369.189 -61.603636)
		(width 0.089408)
		(layer "In9.Cu")
		(net "FM_CPU1_PROCHOT_LVT3_N")
	)
	(segment
		(start 369.189 -61.603636)
		(end 369.189 -54.2544)
		(width 0.089408)
		(layer "In9.Cu")
		(net "FM_CPU1_PROCHOT_LVT3_N")
	)
	(segment
		(start 369.189 -54.2544)
		(end 367.288064 -52.353464)
		(width 0.089408)
		(layer "In9.Cu")
		(net "FM_CPU1_PROCHOT_LVT3_N")
	)
	(segment
		(start 368.024156 -51.829716)
		(end 368.387884 -51.829716)
		(width 0.089408)
		(layer "In9.Cu")
		(net "FM_CPU1_PROCHOT_LVT3_N")
	)
	(segment
		(start 368.387884 -51.829716)
		(end 370.549424 -49.668176)
		(width 0.089408)
		(layer "In9.Cu")
		(net "FM_CPU1_PROCHOT_LVT3_N")
	)
	(segment
		(start 367.288064 -51.942238)
		(end 367.438686 -51.791616)
		(width 0.089408)
		(layer "In9.Cu")
		(net "FM_CPU1_PROCHOT_LVT3_N")
	)
	(segment
		(start 367.288064 -52.353464)
		(end 367.288064 -51.942238)
		(width 0.089408)
		(layer "In9.Cu")
		(net "FM_CPU1_PROCHOT_LVT3_N")
	)
	(segment
		(start 370.549424 -49.668176)
		(end 370.549424 -48.87722)
		(width 0.089408)
		(layer "In9.Cu")
		(net "FM_CPU1_PROCHOT_LVT3_N")
	)
	(segment
		(start 370.549424 -48.87722)
		(end 370.476526 -48.804322)
		(width 0.089408)
		(layer "In9.Cu")
		(net "FM_CPU1_PROCHOT_LVT3_N")
	)
	(segment
		(start 410.290264 -37.734748)
		(end 410.690314 -38.134798)
		(width 0.10795)
		(layer "F.Cu")
		(net "FM_CPU1_FIVR_FAULT_LVT3_R_N")
	)
	(via
		(at 405.714708 -41.181528)
		(size 0.6604)
		(drill 0.3302)
		(layers "F.Cu" "B.Cu")
		(net "FM_CPU1_FIVR_FAULT_LVT3_R_N")
	)
	(via
		(at 410.690314 -38.134798)
		(size 0.4572)
		(drill 0.2032)
		(layers "F.Cu" "B.Cu")
		(net "FM_CPU1_FIVR_FAULT_LVT3_R_N")
	)
	(segment
		(start 404.481792 -42.321988)
		(end 405.08682 -41.71696)
		(width 0.10795)
		(layer "B.Cu")
		(net "FM_CPU1_FIVR_FAULT_LVT3_R_N")
	)
	(segment
		(start 407.874216 -39.567866)
		(end 408.109928 -39.332154)
		(width 0.10795)
		(layer "B.Cu")
		(net "FM_CPU1_FIVR_FAULT_LVT3_R_N")
	)
	(segment
		(start 403.509988 -42.321988)
		(end 404.481792 -42.321988)
		(width 0.10795)
		(layer "B.Cu")
		(net "FM_CPU1_FIVR_FAULT_LVT3_R_N")
	)
	(segment
		(start 407.560272 -40.207692)
		(end 407.874216 -39.893748)
		(width 0.10795)
		(layer "B.Cu")
		(net "FM_CPU1_FIVR_FAULT_LVT3_R_N")
	)
	(segment
		(start 408.109928 -39.332154)
		(end 408.469846 -39.332154)
		(width 0.10795)
		(layer "B.Cu")
		(net "FM_CPU1_FIVR_FAULT_LVT3_R_N")
	)
	(segment
		(start 405.08682 -41.71696)
		(end 405.179276 -41.71696)
		(width 0.10795)
		(layer "B.Cu")
		(net "FM_CPU1_FIVR_FAULT_LVT3_R_N")
	)
	(segment
		(start 405.179276 -41.71696)
		(end 405.714708 -41.181528)
		(width 0.10795)
		(layer "B.Cu")
		(net "FM_CPU1_FIVR_FAULT_LVT3_R_N")
	)
	(segment
		(start 405.714708 -41.181528)
		(end 406.230836 -40.6654)
		(width 0.10795)
		(layer "B.Cu")
		(net "FM_CPU1_FIVR_FAULT_LVT3_R_N")
	)
	(segment
		(start 407.874216 -39.893748)
		(end 407.874216 -39.567866)
		(width 0.10795)
		(layer "B.Cu")
		(net "FM_CPU1_FIVR_FAULT_LVT3_R_N")
	)
	(segment
		(start 408.699208 -39.102792)
		(end 408.699208 -38.696392)
		(width 0.10795)
		(layer "B.Cu")
		(net "FM_CPU1_FIVR_FAULT_LVT3_R_N")
	)
	(segment
		(start 408.8638 -38.5318)
		(end 410.293312 -38.5318)
		(width 0.10795)
		(layer "B.Cu")
		(net "FM_CPU1_FIVR_FAULT_LVT3_R_N")
	)
	(segment
		(start 410.293312 -38.5318)
		(end 410.690314 -38.134798)
		(width 0.10795)
		(layer "B.Cu")
		(net "FM_CPU1_FIVR_FAULT_LVT3_R_N")
	)
	(segment
		(start 403.352 -42.164)
		(end 403.509988 -42.321988)
		(width 0.10795)
		(layer "B.Cu")
		(net "FM_CPU1_FIVR_FAULT_LVT3_R_N")
	)
	(segment
		(start 406.230836 -40.6654)
		(end 406.6794 -40.6654)
		(width 0.10795)
		(layer "B.Cu")
		(net "FM_CPU1_FIVR_FAULT_LVT3_R_N")
	)
	(segment
		(start 402.3995 -42.164)
		(end 403.352 -42.164)
		(width 0.10795)
		(layer "B.Cu")
		(net "FM_CPU1_FIVR_FAULT_LVT3_R_N")
	)
	(segment
		(start 408.699208 -38.696392)
		(end 408.8638 -38.5318)
		(width 0.10795)
		(layer "B.Cu")
		(net "FM_CPU1_FIVR_FAULT_LVT3_R_N")
	)
	(segment
		(start 408.469846 -39.332154)
		(end 408.699208 -39.102792)
		(width 0.10795)
		(layer "B.Cu")
		(net "FM_CPU1_FIVR_FAULT_LVT3_R_N")
	)
	(segment
		(start 406.6794 -40.6654)
		(end 407.137108 -40.207692)
		(width 0.10795)
		(layer "B.Cu")
		(net "FM_CPU1_FIVR_FAULT_LVT3_R_N")
	)
	(segment
		(start 407.137108 -40.207692)
		(end 407.560272 -40.207692)
		(width 0.10795)
		(layer "B.Cu")
		(net "FM_CPU1_FIVR_FAULT_LVT3_R_N")
	)
	(segment
		(start 368.745262 -72.695308)
		(end 369.145058 -73.095104)
		(width 0.1016)
		(layer "F.Cu")
		(net "FM_CPU1_FIVR_FAULT_LVT3")
	)
	(via
		(at 366.70361 -64.457326)
		(size 0.6604)
		(drill 0.3302)
		(layers "F.Cu" "B.Cu")
		(net "FM_CPU1_FIVR_FAULT_LVT3")
	)
	(via
		(at 368.745262 -72.695308)
		(size 0.4572)
		(drill 0.2032)
		(layers "F.Cu" "B.Cu")
		(net "FM_CPU1_FIVR_FAULT_LVT3")
	)
	(segment
		(start 366.944656 -71.935086)
		(end 367.349278 -72.339708)
		(width 0.10795)
		(layer "B.Cu")
		(net "FM_CPU1_FIVR_FAULT_LVT3")
	)
	(segment
		(start 367.349278 -72.339708)
		(end 367.349278 -72.640698)
		(width 0.10795)
		(layer "B.Cu")
		(net "FM_CPU1_FIVR_FAULT_LVT3")
	)
	(segment
		(start 366.522 -63.70828)
		(end 366.6998 -63.88608)
		(width 0.10795)
		(layer "B.Cu")
		(net "FM_CPU1_FIVR_FAULT_LVT3")
	)
	(segment
		(start 367.349278 -72.640698)
		(end 367.786666 -73.078086)
		(width 0.10795)
		(layer "B.Cu")
		(net "FM_CPU1_FIVR_FAULT_LVT3")
	)
	(segment
		(start 365.844074 -66.693034)
		(end 365.844074 -71.285354)
		(width 0.10795)
		(layer "B.Cu")
		(net "FM_CPU1_FIVR_FAULT_LVT3")
	)
	(segment
		(start 366.6998 -65.837308)
		(end 365.844074 -66.693034)
		(width 0.10795)
		(layer "B.Cu")
		(net "FM_CPU1_FIVR_FAULT_LVT3")
	)
	(segment
		(start 368.13744 -73.078086)
		(end 368.520218 -72.695308)
		(width 0.10795)
		(layer "B.Cu")
		(net "FM_CPU1_FIVR_FAULT_LVT3")
	)
	(segment
		(start 366.522 -63.1825)
		(end 366.522 -63.70828)
		(width 0.10795)
		(layer "B.Cu")
		(net "FM_CPU1_FIVR_FAULT_LVT3")
	)
	(segment
		(start 368.520218 -72.695308)
		(end 368.745262 -72.695308)
		(width 0.10795)
		(layer "B.Cu")
		(net "FM_CPU1_FIVR_FAULT_LVT3")
	)
	(segment
		(start 365.844074 -71.285354)
		(end 366.493806 -71.935086)
		(width 0.10795)
		(layer "B.Cu")
		(net "FM_CPU1_FIVR_FAULT_LVT3")
	)
	(segment
		(start 366.6998 -64.457326)
		(end 366.6998 -65.837308)
		(width 0.10795)
		(layer "B.Cu")
		(net "FM_CPU1_FIVR_FAULT_LVT3")
	)
	(segment
		(start 367.786666 -73.078086)
		(end 368.13744 -73.078086)
		(width 0.10795)
		(layer "B.Cu")
		(net "FM_CPU1_FIVR_FAULT_LVT3")
	)
	(segment
		(start 366.6998 -64.457326)
		(end 366.70361 -64.457326)
		(width 0.10795)
		(layer "B.Cu")
		(net "FM_CPU1_FIVR_FAULT_LVT3")
	)
	(segment
		(start 366.6998 -63.88608)
		(end 366.6998 -64.457326)
		(width 0.10795)
		(layer "B.Cu")
		(net "FM_CPU1_FIVR_FAULT_LVT3")
	)
	(segment
		(start 366.493806 -71.935086)
		(end 366.944656 -71.935086)
		(width 0.10795)
		(layer "B.Cu")
		(net "FM_CPU1_FIVR_FAULT_LVT3")
	)
	(segment
		(start 392.295888 -75.137518)
		(end 393.196318 -75.137518)
		(width 0.10795)
		(layer "F.Cu")
		(net "FM_CPU0_THERMTRIP_LVT3_R_N")
	)
	(segment
		(start 393.8778 -75.819)
		(end 394.6525 -75.819)
		(width 0.10795)
		(layer "F.Cu")
		(net "FM_CPU0_THERMTRIP_LVT3_R_N")
	)
	(segment
		(start 393.196318 -75.137518)
		(end 393.8778 -75.819)
		(width 0.10795)
		(layer "F.Cu")
		(net "FM_CPU0_THERMTRIP_LVT3_R_N")
	)
	(segment
		(start 396.113 -75.946)
		(end 395.986 -75.819)
		(width 0.10795)
		(layer "F.Cu")
		(net "FM_CPU0_THERMTRIP_LVT3_N")
	)
	(segment
		(start 395.986 -75.819)
		(end 395.5415 -75.819)
		(width 0.10795)
		(layer "F.Cu")
		(net "FM_CPU0_THERMTRIP_LVT3_N")
	)
	(segment
		(start 397.226028 -78.329282)
		(end 396.113 -77.216254)
		(width 0.10795)
		(layer "F.Cu")
		(net "FM_CPU0_THERMTRIP_LVT3_N")
	)
	(segment
		(start 396.113 -77.216254)
		(end 396.113 -75.946)
		(width 0.10795)
		(layer "F.Cu")
		(net "FM_CPU0_THERMTRIP_LVT3_N")
	)
	(segment
		(start 397.3576 -78.329282)
		(end 397.226028 -78.329282)
		(width 0.10795)
		(layer "F.Cu")
		(net "FM_CPU0_THERMTRIP_LVT3_N")
	)
	(segment
		(start 367.145316 -78.294738)
		(end 367.545112 -77.894942)
		(width 0.1016)
		(layer "F.Cu")
		(net "FM_CPU0_THERMTRIP_LVT3_N")
	)
	(via
		(at 367.145316 -78.294738)
		(size 0.4572)
		(drill 0.2032)
		(layers "F.Cu" "B.Cu")
		(net "FM_CPU0_THERMTRIP_LVT3_N")
	)
	(via
		(at 397.3576 -78.329282)
		(size 0.508)
		(drill 0.254)
		(layers "F.Cu" "B.Cu")
		(net "FM_CPU0_THERMTRIP_LVT3_N")
	)
	(segment
		(start 386.884418 -79.645764)
		(end 390.000998 -79.645764)
		(width 0.089408)
		(layer "In4.Cu")
		(net "FM_CPU0_THERMTRIP_LVT3_N")
	)
	(segment
		(start 390.000998 -79.645764)
		(end 390.809226 -78.837536)
		(width 0.089408)
		(layer "In4.Cu")
		(net "FM_CPU0_THERMTRIP_LVT3_N")
	)
	(segment
		(start 380.329694 -81.56448)
		(end 381.047498 -80.846676)
		(width 0.089408)
		(layer "In4.Cu")
		(net "FM_CPU0_THERMTRIP_LVT3_N")
	)
	(segment
		(start 370.499894 -78.721458)
		(end 370.771928 -78.993492)
		(width 0.089408)
		(layer "In4.Cu")
		(net "FM_CPU0_THERMTRIP_LVT3_N")
	)
	(segment
		(start 367.145316 -78.294738)
		(end 367.572036 -78.721458)
		(width 0.089408)
		(layer "In4.Cu")
		(net "FM_CPU0_THERMTRIP_LVT3_N")
	)
	(segment
		(start 392.577574 -77.76845)
		(end 395.106652 -77.76845)
		(width 0.089408)
		(layer "In4.Cu")
		(net "FM_CPU0_THERMTRIP_LVT3_N")
	)
	(segment
		(start 382.735074 -81.33334)
		(end 384.172714 -79.8957)
		(width 0.089408)
		(layer "In4.Cu")
		(net "FM_CPU0_THERMTRIP_LVT3_N")
	)
	(segment
		(start 397.3576 -78.060804)
		(end 397.3576 -78.329282)
		(width 0.089408)
		(layer "In4.Cu")
		(net "FM_CPU0_THERMTRIP_LVT3_N")
	)
	(segment
		(start 384.172714 -79.290418)
		(end 384.93319 -78.529942)
		(width 0.089408)
		(layer "In4.Cu")
		(net "FM_CPU0_THERMTRIP_LVT3_N")
	)
	(segment
		(start 367.572036 -78.721458)
		(end 370.499894 -78.721458)
		(width 0.089408)
		(layer "In4.Cu")
		(net "FM_CPU0_THERMTRIP_LVT3_N")
	)
	(segment
		(start 372.320312 -79.468218)
		(end 373.390922 -80.538828)
		(width 0.089408)
		(layer "In4.Cu")
		(net "FM_CPU0_THERMTRIP_LVT3_N")
	)
	(segment
		(start 395.50594 -77.369162)
		(end 396.665958 -77.369162)
		(width 0.089408)
		(layer "In4.Cu")
		(net "FM_CPU0_THERMTRIP_LVT3_N")
	)
	(segment
		(start 381.865886 -81.33334)
		(end 382.735074 -81.33334)
		(width 0.089408)
		(layer "In4.Cu")
		(net "FM_CPU0_THERMTRIP_LVT3_N")
	)
	(segment
		(start 392.450066 -77.895958)
		(end 392.577574 -77.76845)
		(width 0.089408)
		(layer "In4.Cu")
		(net "FM_CPU0_THERMTRIP_LVT3_N")
	)
	(segment
		(start 391.907776 -77.895958)
		(end 392.450066 -77.895958)
		(width 0.089408)
		(layer "In4.Cu")
		(net "FM_CPU0_THERMTRIP_LVT3_N")
	)
	(segment
		(start 390.809226 -78.837536)
		(end 390.966198 -78.837536)
		(width 0.089408)
		(layer "In4.Cu")
		(net "FM_CPU0_THERMTRIP_LVT3_N")
	)
	(segment
		(start 390.966198 -78.837536)
		(end 391.907776 -77.895958)
		(width 0.089408)
		(layer "In4.Cu")
		(net "FM_CPU0_THERMTRIP_LVT3_N")
	)
	(segment
		(start 370.771928 -79.249524)
		(end 370.990622 -79.468218)
		(width 0.089408)
		(layer "In4.Cu")
		(net "FM_CPU0_THERMTRIP_LVT3_N")
	)
	(segment
		(start 396.665958 -77.369162)
		(end 397.3576 -78.060804)
		(width 0.089408)
		(layer "In4.Cu")
		(net "FM_CPU0_THERMTRIP_LVT3_N")
	)
	(segment
		(start 395.106652 -77.76845)
		(end 395.50594 -77.369162)
		(width 0.089408)
		(layer "In4.Cu")
		(net "FM_CPU0_THERMTRIP_LVT3_N")
	)
	(segment
		(start 373.390922 -80.538828)
		(end 374.555258 -80.538828)
		(width 0.089408)
		(layer "In4.Cu")
		(net "FM_CPU0_THERMTRIP_LVT3_N")
	)
	(segment
		(start 384.93319 -78.529942)
		(end 385.768596 -78.529942)
		(width 0.089408)
		(layer "In4.Cu")
		(net "FM_CPU0_THERMTRIP_LVT3_N")
	)
	(segment
		(start 385.768596 -78.529942)
		(end 386.884418 -79.645764)
		(width 0.089408)
		(layer "In4.Cu")
		(net "FM_CPU0_THERMTRIP_LVT3_N")
	)
	(segment
		(start 370.771928 -78.993492)
		(end 370.771928 -79.249524)
		(width 0.089408)
		(layer "In4.Cu")
		(net "FM_CPU0_THERMTRIP_LVT3_N")
	)
	(segment
		(start 381.379222 -80.846676)
		(end 381.865886 -81.33334)
		(width 0.089408)
		(layer "In4.Cu")
		(net "FM_CPU0_THERMTRIP_LVT3_N")
	)
	(segment
		(start 374.555258 -80.538828)
		(end 375.58091 -81.56448)
		(width 0.089408)
		(layer "In4.Cu")
		(net "FM_CPU0_THERMTRIP_LVT3_N")
	)
	(segment
		(start 384.172714 -79.8957)
		(end 384.172714 -79.290418)
		(width 0.089408)
		(layer "In4.Cu")
		(net "FM_CPU0_THERMTRIP_LVT3_N")
	)
	(segment
		(start 375.58091 -81.56448)
		(end 380.329694 -81.56448)
		(width 0.089408)
		(layer "In4.Cu")
		(net "FM_CPU0_THERMTRIP_LVT3_N")
	)
	(segment
		(start 370.990622 -79.468218)
		(end 372.320312 -79.468218)
		(width 0.089408)
		(layer "In4.Cu")
		(net "FM_CPU0_THERMTRIP_LVT3_N")
	)
	(segment
		(start 381.047498 -80.846676)
		(end 381.379222 -80.846676)
		(width 0.089408)
		(layer "In4.Cu")
		(net "FM_CPU0_THERMTRIP_LVT3_N")
	)
	(segment
		(start 393.313158 -75.787758)
		(end 392.295888 -75.787758)
		(width 0.10795)
		(layer "F.Cu")
		(net "FM_CPU_ERR2_LVT3_R_N")
	)
	(segment
		(start 394.6525 -76.581)
		(end 394.1064 -76.581)
		(width 0.10795)
		(layer "F.Cu")
		(net "FM_CPU_ERR2_LVT3_R_N")
	)
	(segment
		(start 394.1064 -76.581)
		(end 393.313158 -75.787758)
		(width 0.10795)
		(layer "F.Cu")
		(net "FM_CPU_ERR2_LVT3_R_N")
	)
	(segment
		(start 402.615146 -42.859198)
		(end 402.961094 -42.51325)
		(width 0.10795)
		(layer "F.Cu")
		(net "FM_CPU0_PROCHOT_LVT3_N")
	)
	(segment
		(start 402.641054 -43.3832)
		(end 402.641054 -43.729148)
		(width 0.10795)
		(layer "F.Cu")
		(net "FM_CPU0_PROCHOT_LVT3_N")
	)
	(segment
		(start 402.615146 -43.357292)
		(end 402.641054 -43.3832)
		(width 0.10795)
		(layer "F.Cu")
		(net "FM_CPU0_PROCHOT_LVT3_N")
	)
	(segment
		(start 403.68855 -42.51325)
		(end 404.3172 -41.8846)
		(width 0.10795)
		(layer "F.Cu")
		(net "FM_CPU0_PROCHOT_LVT3_N")
	)
	(segment
		(start 402.615146 -42.935652)
		(end 402.615146 -42.859198)
		(width 0.10795)
		(layer "F.Cu")
		(net "FM_CPU0_PROCHOT_LVT3_N")
	)
	(segment
		(start 402.961094 -42.51325)
		(end 403.68855 -42.51325)
		(width 0.10795)
		(layer "F.Cu")
		(net "FM_CPU0_PROCHOT_LVT3_N")
	)
	(segment
		(start 402.615146 -42.935652)
		(end 402.615146 -43.357292)
		(width 0.10795)
		(layer "F.Cu")
		(net "FM_CPU0_PROCHOT_LVT3_N")
	)
	(via
		(at 382.440942 -37.171884)
		(size 0.508)
		(drill 0.254)
		(layers "F.Cu" "B.Cu")
		(net "FM_CPU0_PROCHOT_LVT3_N")
	)
	(via
		(at 372.0592 -33.7566)
		(size 0.6604)
		(drill 0.3302)
		(layers "F.Cu" "B.Cu")
		(net "FM_CPU0_PROCHOT_LVT3_N")
	)
	(via
		(at 404.3172 -41.8846)
		(size 0.508)
		(drill 0.254)
		(layers "F.Cu" "B.Cu")
		(net "FM_CPU0_PROCHOT_LVT3_N")
	)
	(segment
		(start 381.61976 -36.863782)
		(end 381.592328 -36.863782)
		(width 0.10795)
		(layer "B.Cu")
		(net "FM_CPU0_PROCHOT_LVT3_N")
	)
	(segment
		(start 372.400576 -34.097976)
		(end 372.0592 -33.7566)
		(width 0.10795)
		(layer "B.Cu")
		(net "FM_CPU0_PROCHOT_LVT3_N")
	)
	(segment
		(start 381.889508 -37.13353)
		(end 381.61976 -36.863782)
		(width 0.10795)
		(layer "B.Cu")
		(net "FM_CPU0_PROCHOT_LVT3_N")
	)
	(segment
		(start 381.943864 -37.215318)
		(end 381.889508 -37.160962)
		(width 0.10795)
		(layer "B.Cu")
		(net "FM_CPU0_PROCHOT_LVT3_N")
	)
	(segment
		(start 359.043478 -44.831)
		(end 359.043478 -40.473122)
		(width 0.10795)
		(layer "B.Cu")
		(net "FM_CPU0_PROCHOT_LVT3_N")
	)
	(segment
		(start 376.574812 -35.0393)
		(end 375.633488 -34.097976)
		(width 0.10795)
		(layer "B.Cu")
		(net "FM_CPU0_PROCHOT_LVT3_N")
	)
	(segment
		(start 366.208056 -33.308544)
		(end 371.611144 -33.308544)
		(width 0.10795)
		(layer "B.Cu")
		(net "FM_CPU0_PROCHOT_LVT3_N")
	)
	(segment
		(start 375.633488 -34.097976)
		(end 372.400576 -34.097976)
		(width 0.10795)
		(layer "B.Cu")
		(net "FM_CPU0_PROCHOT_LVT3_N")
	)
	(segment
		(start 382.426718 -37.171884)
		(end 382.426718 -37.113464)
		(width 0.10795)
		(layer "B.Cu")
		(net "FM_CPU0_PROCHOT_LVT3_N")
	)
	(segment
		(start 381.592328 -36.863782)
		(end 379.767846 -35.0393)
		(width 0.10795)
		(layer "B.Cu")
		(net "FM_CPU0_PROCHOT_LVT3_N")
	)
	(segment
		(start 360.26598 -45.1358)
		(end 359.348278 -45.1358)
		(width 0.10795)
		(layer "B.Cu")
		(net "FM_CPU0_PROCHOT_LVT3_N")
	)
	(segment
		(start 379.767846 -35.0393)
		(end 376.574812 -35.0393)
		(width 0.10795)
		(layer "B.Cu")
		(net "FM_CPU0_PROCHOT_LVT3_N")
	)
	(segment
		(start 382.440942 -37.171884)
		(end 382.426718 -37.171884)
		(width 0.10795)
		(layer "B.Cu")
		(net "FM_CPU0_PROCHOT_LVT3_N")
	)
	(segment
		(start 381.889508 -37.160962)
		(end 381.889508 -37.13353)
		(width 0.10795)
		(layer "B.Cu")
		(net "FM_CPU0_PROCHOT_LVT3_N")
	)
	(segment
		(start 359.348278 -45.1358)
		(end 359.043478 -44.831)
		(width 0.10795)
		(layer "B.Cu")
		(net "FM_CPU0_PROCHOT_LVT3_N")
	)
	(segment
		(start 382.324864 -37.215318)
		(end 381.943864 -37.215318)
		(width 0.10795)
		(layer "B.Cu")
		(net "FM_CPU0_PROCHOT_LVT3_N")
	)
	(segment
		(start 371.611144 -33.308544)
		(end 372.0592 -33.7566)
		(width 0.10795)
		(layer "B.Cu")
		(net "FM_CPU0_PROCHOT_LVT3_N")
	)
	(segment
		(start 359.043478 -40.473122)
		(end 366.208056 -33.308544)
		(width 0.10795)
		(layer "B.Cu")
		(net "FM_CPU0_PROCHOT_LVT3_N")
	)
	(segment
		(start 360.555794 -44.845986)
		(end 360.26598 -45.1358)
		(width 0.10795)
		(layer "B.Cu")
		(net "FM_CPU0_PROCHOT_LVT3_N")
	)
	(segment
		(start 382.426718 -37.113464)
		(end 382.324864 -37.215318)
		(width 0.10795)
		(layer "B.Cu")
		(net "FM_CPU0_PROCHOT_LVT3_N")
	)
	(segment
		(start 392.85291 -36.81603)
		(end 390.135364 -36.81603)
		(width 0.089408)
		(layer "In4.Cu")
		(net "FM_CPU0_PROCHOT_LVT3_N")
	)
	(segment
		(start 388.152132 -36.307268)
		(end 387.876034 -36.583366)
		(width 0.089408)
		(layer "In4.Cu")
		(net "FM_CPU0_PROCHOT_LVT3_N")
	)
	(segment
		(start 404.3045 -41.8719)
		(end 402.672804 -41.8719)
		(width 0.089408)
		(layer "In4.Cu")
		(net "FM_CPU0_PROCHOT_LVT3_N")
	)
	(segment
		(start 387.876034 -36.583366)
		(end 384.063748 -36.583366)
		(width 0.089408)
		(layer "In4.Cu")
		(net "FM_CPU0_PROCHOT_LVT3_N")
	)
	(segment
		(start 404.3172 -41.8846)
		(end 404.3045 -41.8719)
		(width 0.089408)
		(layer "In4.Cu")
		(net "FM_CPU0_PROCHOT_LVT3_N")
	)
	(segment
		(start 389.626602 -36.307268)
		(end 388.152132 -36.307268)
		(width 0.089408)
		(layer "In4.Cu")
		(net "FM_CPU0_PROCHOT_LVT3_N")
	)
	(segment
		(start 402.672804 -41.8719)
		(end 401.757896 -40.956992)
		(width 0.089408)
		(layer "In4.Cu")
		(net "FM_CPU0_PROCHOT_LVT3_N")
	)
	(segment
		(start 397.970756 -38.227)
		(end 394.26388 -38.227)
		(width 0.089408)
		(layer "In4.Cu")
		(net "FM_CPU0_PROCHOT_LVT3_N")
	)
	(segment
		(start 394.26388 -38.227)
		(end 392.85291 -36.81603)
		(width 0.089408)
		(layer "In4.Cu")
		(net "FM_CPU0_PROCHOT_LVT3_N")
	)
	(segment
		(start 390.135364 -36.81603)
		(end 389.626602 -36.307268)
		(width 0.089408)
		(layer "In4.Cu")
		(net "FM_CPU0_PROCHOT_LVT3_N")
	)
	(segment
		(start 400.700748 -40.956992)
		(end 397.970756 -38.227)
		(width 0.089408)
		(layer "In4.Cu")
		(net "FM_CPU0_PROCHOT_LVT3_N")
	)
	(segment
		(start 382.724914 -36.815268)
		(end 382.426718 -37.113464)
		(width 0.089408)
		(layer "In4.Cu")
		(net "FM_CPU0_PROCHOT_LVT3_N")
	)
	(segment
		(start 384.063748 -36.583366)
		(end 383.831846 -36.815268)
		(width 0.089408)
		(layer "In4.Cu")
		(net "FM_CPU0_PROCHOT_LVT3_N")
	)
	(segment
		(start 382.426718 -37.171884)
		(end 382.440942 -37.171884)
		(width 0.089408)
		(layer "In4.Cu")
		(net "FM_CPU0_PROCHOT_LVT3_N")
	)
	(segment
		(start 401.757896 -40.956992)
		(end 400.700748 -40.956992)
		(width 0.089408)
		(layer "In4.Cu")
		(net "FM_CPU0_PROCHOT_LVT3_N")
	)
	(segment
		(start 382.426718 -37.113464)
		(end 382.426718 -37.171884)
		(width 0.089408)
		(layer "In4.Cu")
		(net "FM_CPU0_PROCHOT_LVT3_N")
	)
	(segment
		(start 383.831846 -36.815268)
		(end 382.724914 -36.815268)
		(width 0.089408)
		(layer "In4.Cu")
		(net "FM_CPU0_PROCHOT_LVT3_N")
	)
	(segment
		(start 408.690064 -40.13454)
		(end 408.690064 -40.134794)
		(width 0.10795)
		(layer "F.Cu")
		(net "FM_CPU0_FIVR_FAULT_LVT3_R_N")
	)
	(segment
		(start 408.690064 -40.134794)
		(end 408.290268 -40.53459)
		(width 0.10795)
		(layer "F.Cu")
		(net "FM_CPU0_FIVR_FAULT_LVT3_R_N")
	)
	(via
		(at 403.7838 -42.926)
		(size 0.6604)
		(drill 0.3302)
		(layers "F.Cu" "B.Cu")
		(net "FM_CPU0_FIVR_FAULT_LVT3_R_N")
	)
	(via
		(at 408.290268 -40.53459)
		(size 0.4572)
		(drill 0.2032)
		(layers "F.Cu" "B.Cu")
		(net "FM_CPU0_FIVR_FAULT_LVT3_R_N")
	)
	(segment
		(start 406.257252 -41.495726)
		(end 407.218388 -40.53459)
		(width 0.10795)
		(layer "B.Cu")
		(net "FM_CPU0_FIVR_FAULT_LVT3_R_N")
	)
	(segment
		(start 403.7838 -42.926)
		(end 405.2316 -42.926)
		(width 0.10795)
		(layer "B.Cu")
		(net "FM_CPU0_FIVR_FAULT_LVT3_R_N")
	)
	(segment
		(start 405.2316 -42.926)
		(end 406.257252 -41.900348)
		(width 0.10795)
		(layer "B.Cu")
		(net "FM_CPU0_FIVR_FAULT_LVT3_R_N")
	)
	(segment
		(start 406.257252 -41.900348)
		(end 406.257252 -41.495726)
		(width 0.10795)
		(layer "B.Cu")
		(net "FM_CPU0_FIVR_FAULT_LVT3_R_N")
	)
	(segment
		(start 402.3995 -42.926)
		(end 403.7838 -42.926)
		(width 0.10795)
		(layer "B.Cu")
		(net "FM_CPU0_FIVR_FAULT_LVT3_R_N")
	)
	(segment
		(start 407.218388 -40.53459)
		(end 408.290268 -40.53459)
		(width 0.10795)
		(layer "B.Cu")
		(net "FM_CPU0_FIVR_FAULT_LVT3_R_N")
	)
	(segment
		(start 396.3416 -78.151482)
		(end 395.787118 -77.597)
		(width 0.10795)
		(layer "F.Cu")
		(net "FM_CPU0_FIVR_FAULT_LVT3")
	)
	(segment
		(start 366.345216 -77.494892)
		(end 366.745012 -77.095096)
		(width 0.1016)
		(layer "F.Cu")
		(net "FM_CPU0_FIVR_FAULT_LVT3")
	)
	(segment
		(start 395.787118 -77.597)
		(end 395.5415 -77.597)
		(width 0.10795)
		(layer "F.Cu")
		(net "FM_CPU0_FIVR_FAULT_LVT3")
	)
	(via
		(at 396.3416 -78.151482)
		(size 0.508)
		(drill 0.254)
		(layers "F.Cu" "B.Cu")
		(net "FM_CPU0_FIVR_FAULT_LVT3")
	)
	(via
		(at 366.345216 -77.494892)
		(size 0.4572)
		(drill 0.2032)
		(layers "F.Cu" "B.Cu")
		(net "FM_CPU0_FIVR_FAULT_LVT3")
	)
	(via
		(at 365.6838 -76.3016)
		(size 0.6604)
		(drill 0.3302)
		(layers "F.Cu" "B.Cu")
		(net "FM_CPU0_FIVR_FAULT_LVT3")
	)
	(segment
		(start 365.6838 -76.3016)
		(end 365.6838 -76.833476)
		(width 0.10795)
		(layer "B.Cu")
		(net "FM_CPU0_FIVR_FAULT_LVT3")
	)
	(segment
		(start 365.6838 -76.833476)
		(end 366.345216 -77.494892)
		(width 0.10795)
		(layer "B.Cu")
		(net "FM_CPU0_FIVR_FAULT_LVT3")
	)
	(segment
		(start 393.656312 -78.736952)
		(end 393.656312 -78.747366)
		(width 0.089408)
		(layer "In4.Cu")
		(net "FM_CPU0_FIVR_FAULT_LVT3")
	)
	(segment
		(start 386.64642 -80.4164)
		(end 387.78688 -80.4164)
		(width 0.089408)
		(layer "In4.Cu")
		(net "FM_CPU0_FIVR_FAULT_LVT3")
	)
	(segment
		(start 393.890754 -78.981808)
		(end 393.901168 -78.981808)
		(width 0.089408)
		(layer "In4.Cu")
		(net "FM_CPU0_FIVR_FAULT_LVT3")
	)
	(segment
		(start 388.054088 -80.683608)
		(end 391.13968 -80.683608)
		(width 0.089408)
		(layer "In4.Cu")
		(net "FM_CPU0_FIVR_FAULT_LVT3")
	)
	(segment
		(start 366.718596 -79.196184)
		(end 367.790476 -80.268064)
		(width 0.089408)
		(layer "In4.Cu")
		(net "FM_CPU0_FIVR_FAULT_LVT3")
	)
	(segment
		(start 370.961666 -81.396332)
		(end 371.161818 -81.19618)
		(width 0.089408)
		(layer "In4.Cu")
		(net "FM_CPU0_FIVR_FAULT_LVT3")
	)
	(segment
		(start 366.345216 -77.494892)
		(end 366.718596 -77.868272)
		(width 0.089408)
		(layer "In4.Cu")
		(net "FM_CPU0_FIVR_FAULT_LVT3")
	)
	(segment
		(start 371.93093 -81.19618)
		(end 372.247414 -80.879696)
		(width 0.089408)
		(layer "In4.Cu")
		(net "FM_CPU0_FIVR_FAULT_LVT3")
	)
	(segment
		(start 369.6462 -80.268064)
		(end 369.9383 -80.560164)
		(width 0.089408)
		(layer "In4.Cu")
		(net "FM_CPU0_FIVR_FAULT_LVT3")
	)
	(segment
		(start 372.724934 -80.879696)
		(end 373.078248 -81.23301)
		(width 0.089408)
		(layer "In4.Cu")
		(net "FM_CPU0_FIVR_FAULT_LVT3")
	)
	(segment
		(start 391.741152 -80.082136)
		(end 391.741152 -78.929484)
		(width 0.089408)
		(layer "In4.Cu")
		(net "FM_CPU0_FIVR_FAULT_LVT3")
	)
	(segment
		(start 391.7442 -78.89875)
		(end 392.079734 -78.563216)
		(width 0.089408)
		(layer "In4.Cu")
		(net "FM_CPU0_FIVR_FAULT_LVT3")
	)
	(segment
		(start 382.710182 -82.169)
		(end 383.771902 -81.10728)
		(width 0.089408)
		(layer "In4.Cu")
		(net "FM_CPU0_FIVR_FAULT_LVT3")
	)
	(segment
		(start 369.9383 -80.931766)
		(end 370.402866 -81.396332)
		(width 0.089408)
		(layer "In4.Cu")
		(net "FM_CPU0_FIVR_FAULT_LVT3")
	)
	(segment
		(start 393.937744 -79.018384)
		(end 395.474698 -79.018384)
		(width 0.089408)
		(layer "In4.Cu")
		(net "FM_CPU0_FIVR_FAULT_LVT3")
	)
	(segment
		(start 371.161818 -81.19618)
		(end 371.93093 -81.19618)
		(width 0.089408)
		(layer "In4.Cu")
		(net "FM_CPU0_FIVR_FAULT_LVT3")
	)
	(segment
		(start 367.790476 -80.268064)
		(end 369.6462 -80.268064)
		(width 0.089408)
		(layer "In4.Cu")
		(net "FM_CPU0_FIVR_FAULT_LVT3")
	)
	(segment
		(start 372.247414 -80.879696)
		(end 372.724934 -80.879696)
		(width 0.089408)
		(layer "In4.Cu")
		(net "FM_CPU0_FIVR_FAULT_LVT3")
	)
	(segment
		(start 366.718596 -77.868272)
		(end 366.718596 -79.196184)
		(width 0.089408)
		(layer "In4.Cu")
		(net "FM_CPU0_FIVR_FAULT_LVT3")
	)
	(segment
		(start 374.46204 -82.169)
		(end 382.710182 -82.169)
		(width 0.089408)
		(layer "In4.Cu")
		(net "FM_CPU0_FIVR_FAULT_LVT3")
	)
	(segment
		(start 393.901168 -78.981808)
		(end 393.937744 -79.018384)
		(width 0.089408)
		(layer "In4.Cu")
		(net "FM_CPU0_FIVR_FAULT_LVT3")
	)
	(segment
		(start 391.7442 -78.926436)
		(end 391.7442 -78.89875)
		(width 0.089408)
		(layer "In4.Cu")
		(net "FM_CPU0_FIVR_FAULT_LVT3")
	)
	(segment
		(start 373.078248 -81.23301)
		(end 373.52605 -81.23301)
		(width 0.089408)
		(layer "In4.Cu")
		(net "FM_CPU0_FIVR_FAULT_LVT3")
	)
	(segment
		(start 385.95554 -81.10728)
		(end 386.64642 -80.4164)
		(width 0.089408)
		(layer "In4.Cu")
		(net "FM_CPU0_FIVR_FAULT_LVT3")
	)
	(segment
		(start 393.656312 -78.747366)
		(end 393.890754 -78.981808)
		(width 0.089408)
		(layer "In4.Cu")
		(net "FM_CPU0_FIVR_FAULT_LVT3")
	)
	(segment
		(start 391.13968 -80.683608)
		(end 391.741152 -80.082136)
		(width 0.089408)
		(layer "In4.Cu")
		(net "FM_CPU0_FIVR_FAULT_LVT3")
	)
	(segment
		(start 393.482576 -78.563216)
		(end 393.656312 -78.736952)
		(width 0.089408)
		(layer "In4.Cu")
		(net "FM_CPU0_FIVR_FAULT_LVT3")
	)
	(segment
		(start 369.9383 -80.560164)
		(end 369.9383 -80.931766)
		(width 0.089408)
		(layer "In4.Cu")
		(net "FM_CPU0_FIVR_FAULT_LVT3")
	)
	(segment
		(start 387.78688 -80.4164)
		(end 388.054088 -80.683608)
		(width 0.089408)
		(layer "In4.Cu")
		(net "FM_CPU0_FIVR_FAULT_LVT3")
	)
	(segment
		(start 373.52605 -81.23301)
		(end 374.46204 -82.169)
		(width 0.089408)
		(layer "In4.Cu")
		(net "FM_CPU0_FIVR_FAULT_LVT3")
	)
	(segment
		(start 395.474698 -79.018384)
		(end 396.3416 -78.151482)
		(width 0.089408)
		(layer "In4.Cu")
		(net "FM_CPU0_FIVR_FAULT_LVT3")
	)
	(segment
		(start 391.741152 -78.929484)
		(end 391.7442 -78.926436)
		(width 0.089408)
		(layer "In4.Cu")
		(net "FM_CPU0_FIVR_FAULT_LVT3")
	)
	(segment
		(start 370.402866 -81.396332)
		(end 370.961666 -81.396332)
		(width 0.089408)
		(layer "In4.Cu")
		(net "FM_CPU0_FIVR_FAULT_LVT3")
	)
	(segment
		(start 392.079734 -78.563216)
		(end 393.482576 -78.563216)
		(width 0.089408)
		(layer "In4.Cu")
		(net "FM_CPU0_FIVR_FAULT_LVT3")
	)
	(segment
		(start 383.771902 -81.10728)
		(end 385.95554 -81.10728)
		(width 0.089408)
		(layer "In4.Cu")
		(net "FM_CPU0_FIVR_FAULT_LVT3")
	)
	(segment
		(start 418.554408 -48.953166)
		(end 418.554408 -50.132996)
		(width 0.10795)
		(layer "F.Cu")
		(net "FM_BMC_ONCTL_N")
	)
	(segment
		(start 374.344692 -69.495162)
		(end 373.944896 -69.894958)
		(width 0.1016)
		(layer "F.Cu")
		(net "FM_BMC_ONCTL_N")
	)
	(via
		(at 374.344692 -69.495162)
		(size 0.4572)
		(drill 0.2032)
		(layers "F.Cu" "B.Cu")
		(net "FM_BMC_ONCTL_N")
	)
	(via
		(at 418.554408 -50.132996)
		(size 0.508)
		(drill 0.254)
		(layers "F.Cu" "B.Cu")
		(net "FM_BMC_ONCTL_N")
	)
	(via
		(at 406.87498 -68.69938)
		(size 0.508)
		(drill 0.254)
		(layers "F.Cu" "B.Cu")
		(net "FM_BMC_ONCTL_N")
	)
	(segment
		(start 407.013156 -62.65291)
		(end 405.2316 -60.871354)
		(width 0.089408)
		(layer "In2.Cu")
		(net "FM_BMC_ONCTL_N")
	)
	(segment
		(start 407.013156 -66.545968)
		(end 407.013156 -62.65291)
		(width 0.089408)
		(layer "In2.Cu")
		(net "FM_BMC_ONCTL_N")
	)
	(segment
		(start 418.44087 -50.132996)
		(end 418.554408 -50.132996)
		(width 0.089408)
		(layer "In2.Cu")
		(net "FM_BMC_ONCTL_N")
	)
	(segment
		(start 406.141682 -67.966082)
		(end 406.141682 -67.417442)
		(width 0.089408)
		(layer "In2.Cu")
		(net "FM_BMC_ONCTL_N")
	)
	(segment
		(start 406.217628 -53.489606)
		(end 408.493722 -51.213512)
		(width 0.089408)
		(layer "In2.Cu")
		(net "FM_BMC_ONCTL_N")
	)
	(segment
		(start 406.217628 -57.991756)
		(end 406.217628 -53.489606)
		(width 0.089408)
		(layer "In2.Cu")
		(net "FM_BMC_ONCTL_N")
	)
	(segment
		(start 406.141682 -67.417442)
		(end 407.013156 -66.545968)
		(width 0.089408)
		(layer "In2.Cu")
		(net "FM_BMC_ONCTL_N")
	)
	(segment
		(start 405.2316 -58.977784)
		(end 406.217628 -57.991756)
		(width 0.089408)
		(layer "In2.Cu")
		(net "FM_BMC_ONCTL_N")
	)
	(segment
		(start 408.493722 -51.213512)
		(end 417.360354 -51.213512)
		(width 0.089408)
		(layer "In2.Cu")
		(net "FM_BMC_ONCTL_N")
	)
	(segment
		(start 406.87498 -68.69938)
		(end 406.141682 -67.966082)
		(width 0.089408)
		(layer "In2.Cu")
		(net "FM_BMC_ONCTL_N")
	)
	(segment
		(start 405.2316 -60.871354)
		(end 405.2316 -58.977784)
		(width 0.089408)
		(layer "In2.Cu")
		(net "FM_BMC_ONCTL_N")
	)
	(segment
		(start 417.360354 -51.213512)
		(end 418.44087 -50.132996)
		(width 0.089408)
		(layer "In2.Cu")
		(net "FM_BMC_ONCTL_N")
	)
	(segment
		(start 374.8786 -69.121782)
		(end 375.389648 -69.121782)
		(width 0.089408)
		(layer "In4.Cu")
		(net "FM_BMC_ONCTL_N")
	)
	(segment
		(start 376.464322 -67.377564)
		(end 376.586242 -67.255644)
		(width 0.089408)
		(layer "In4.Cu")
		(net "FM_BMC_ONCTL_N")
	)
	(segment
		(start 375.389648 -69.121782)
		(end 375.566178 -68.945252)
		(width 0.089408)
		(layer "In4.Cu")
		(net "FM_BMC_ONCTL_N")
	)
	(segment
		(start 377.927108 -67.255644)
		(end 378.034296 -67.362832)
		(width 0.089408)
		(layer "In4.Cu")
		(net "FM_BMC_ONCTL_N")
	)
	(segment
		(start 378.034296 -67.362832)
		(end 379.937264 -67.362832)
		(width 0.089408)
		(layer "In4.Cu")
		(net "FM_BMC_ONCTL_N")
	)
	(segment
		(start 375.566178 -68.945252)
		(end 375.566178 -67.745864)
		(width 0.089408)
		(layer "In4.Cu")
		(net "FM_BMC_ONCTL_N")
	)
	(segment
		(start 397.568674 -68.554346)
		(end 406.4508 -68.554346)
		(width 0.089408)
		(layer "In4.Cu")
		(net "FM_BMC_ONCTL_N")
	)
	(segment
		(start 374.50522 -69.495162)
		(end 374.8786 -69.121782)
		(width 0.089408)
		(layer "In4.Cu")
		(net "FM_BMC_ONCTL_N")
	)
	(segment
		(start 375.934478 -67.377564)
		(end 376.464322 -67.377564)
		(width 0.089408)
		(layer "In4.Cu")
		(net "FM_BMC_ONCTL_N")
	)
	(segment
		(start 374.344692 -69.495162)
		(end 374.50522 -69.495162)
		(width 0.089408)
		(layer "In4.Cu")
		(net "FM_BMC_ONCTL_N")
	)
	(segment
		(start 388.826756 -68.13931)
		(end 391.010648 -65.955418)
		(width 0.089408)
		(layer "In4.Cu")
		(net "FM_BMC_ONCTL_N")
	)
	(segment
		(start 380.713742 -68.13931)
		(end 388.826756 -68.13931)
		(width 0.089408)
		(layer "In4.Cu")
		(net "FM_BMC_ONCTL_N")
	)
	(segment
		(start 391.010648 -65.955418)
		(end 391.327132 -65.955418)
		(width 0.089408)
		(layer "In4.Cu")
		(net "FM_BMC_ONCTL_N")
	)
	(segment
		(start 376.586242 -67.255644)
		(end 377.927108 -67.255644)
		(width 0.089408)
		(layer "In4.Cu")
		(net "FM_BMC_ONCTL_N")
	)
	(segment
		(start 406.4508 -68.554346)
		(end 406.595834 -68.69938)
		(width 0.089408)
		(layer "In4.Cu")
		(net "FM_BMC_ONCTL_N")
	)
	(segment
		(start 391.327386 -65.955672)
		(end 394.97 -65.955672)
		(width 0.089408)
		(layer "In4.Cu")
		(net "FM_BMC_ONCTL_N")
	)
	(segment
		(start 379.937264 -67.362832)
		(end 380.713742 -68.13931)
		(width 0.089408)
		(layer "In4.Cu")
		(net "FM_BMC_ONCTL_N")
	)
	(segment
		(start 391.327132 -65.955418)
		(end 391.327386 -65.955672)
		(width 0.089408)
		(layer "In4.Cu")
		(net "FM_BMC_ONCTL_N")
	)
	(segment
		(start 375.566178 -67.745864)
		(end 375.934478 -67.377564)
		(width 0.089408)
		(layer "In4.Cu")
		(net "FM_BMC_ONCTL_N")
	)
	(segment
		(start 406.595834 -68.69938)
		(end 406.87498 -68.69938)
		(width 0.089408)
		(layer "In4.Cu")
		(net "FM_BMC_ONCTL_N")
	)
	(segment
		(start 394.97 -65.955672)
		(end 397.568674 -68.554346)
		(width 0.089408)
		(layer "In4.Cu")
		(net "FM_BMC_ONCTL_N")
	)
	(segment
		(start 107.049824 -148.773388)
		(end 107.04957 -148.773134)
		(width 0.10795)
		(layer "F.Cu")
		(net "FM_ADR_COMPLETE_KLM_N")
	)
	(segment
		(start 107.04957 -148.773134)
		(end 107.04957 -147.27174)
		(width 0.10795)
		(layer "F.Cu")
		(net "FM_ADR_COMPLETE_KLM_N")
	)
	(segment
		(start 107.04957 -139.171934)
		(end 107.049824 -139.172188)
		(width 0.10795)
		(layer "F.Cu")
		(net "FM_ADR_COMPLETE_KLM_N")
	)
	(segment
		(start 107.04957 -156.87294)
		(end 107.049316 -155.59024)
		(width 0.10795)
		(layer "F.Cu")
		(net "FM_ADR_COMPLETE_KLM_N")
	)
	(segment
		(start 322.131944 -35.567874)
		(end 321.8434 -35.27933)
		(width 0.10795)
		(layer "F.Cu")
		(net "FM_ADR_COMPLETE_KLM_N")
	)
	(segment
		(start 321.8434 -35.27933)
		(end 321.8434 -35.052)
		(width 0.10795)
		(layer "F.Cu")
		(net "FM_ADR_COMPLETE_KLM_N")
	)
	(segment
		(start 107.04957 -137.67054)
		(end 107.04957 -139.171934)
		(width 0.10795)
		(layer "F.Cu")
		(net "FM_ADR_COMPLETE_KLM_N")
	)
	(segment
		(start 322.131944 -36.052252)
		(end 322.131944 -35.567874)
		(width 0.10795)
		(layer "F.Cu")
		(net "FM_ADR_COMPLETE_KLM_N")
	)
	(via
		(at 107.049316 -155.59024)
		(size 0.508)
		(drill 0.254)
		(layers "F.Cu" "B.Cu")
		(net "FM_ADR_COMPLETE_KLM_N")
	)
	(via
		(at 330.551536 -157.002226)
		(size 0.508)
		(drill 0.254)
		(layers "F.Cu" "B.Cu")
		(net "FM_ADR_COMPLETE_KLM_N")
	)
	(via
		(at 331.691742 -78.54823)
		(size 0.508)
		(drill 0.254)
		(layers "F.Cu" "B.Cu")
		(net "FM_ADR_COMPLETE_KLM_N")
	)
	(via
		(at 327.086722 -66.790824)
		(size 0.6604)
		(drill 0.3302)
		(layers "F.Cu" "B.Cu")
		(net "FM_ADR_COMPLETE_KLM_N")
	)
	(via
		(at 322.6816 -150.7744)
		(size 0.508)
		(drill 0.254)
		(layers "F.Cu" "B.Cu")
		(net "FM_ADR_COMPLETE_KLM_N")
	)
	(via
		(at 107.049824 -139.172188)
		(size 0.4572)
		(drill 0.2032)
		(layers "F.Cu" "B.Cu")
		(net "FM_ADR_COMPLETE_KLM_N")
	)
	(via
		(at 322.131944 -36.052252)
		(size 0.508)
		(drill 0.254)
		(layers "F.Cu" "B.Cu")
		(net "FM_ADR_COMPLETE_KLM_N")
	)
	(via
		(at 323.6214 -64.8462)
		(size 0.508)
		(drill 0.254)
		(layers "F.Cu" "B.Cu")
		(net "FM_ADR_COMPLETE_KLM_N")
	)
	(via
		(at 107.049824 -148.773388)
		(size 0.4572)
		(drill 0.2032)
		(layers "F.Cu" "B.Cu")
		(net "FM_ADR_COMPLETE_KLM_N")
	)
	(segment
		(start 106.58602 -130.24485)
		(end 106.58602 -130.249168)
		(width 0.10795)
		(layer "B.Cu")
		(net "FM_ADR_COMPLETE_KLM_N")
	)
	(segment
		(start 99.7712 -140.264896)
		(end 99.866704 -140.3604)
		(width 0.10795)
		(layer "B.Cu")
		(net "FM_ADR_COMPLETE_KLM_N")
	)
	(segment
		(start 100.099114 -150.292054)
		(end 99.794568 -150.5966)
		(width 0.10795)
		(layer "B.Cu")
		(net "FM_ADR_COMPLETE_KLM_N")
	)
	(segment
		(start 100.912168 -155.3972)
		(end 101.5492 -155.3972)
		(width 0.10795)
		(layer "B.Cu")
		(net "FM_ADR_COMPLETE_KLM_N")
	)
	(segment
		(start 330.567538 -76.465938)
		(end 331.286358 -77.184758)
		(width 0.10795)
		(layer "B.Cu")
		(net "FM_ADR_COMPLETE_KLM_N")
	)
	(segment
		(start 106.045 -130.249168)
		(end 105.611168 -130.683)
		(width 0.10795)
		(layer "B.Cu")
		(net "FM_ADR_COMPLETE_KLM_N")
	)
	(segment
		(start 99.7585 -146.276568)
		(end 99.692968 -146.3421)
		(width 0.10795)
		(layer "B.Cu")
		(net "FM_ADR_COMPLETE_KLM_N")
	)
	(segment
		(start 99.692968 -131.5974)
		(end 99.692968 -134.3533)
		(width 0.10795)
		(layer "B.Cu")
		(net "FM_ADR_COMPLETE_KLM_N")
	)
	(segment
		(start 99.695 -139.319)
		(end 99.695 -140.188696)
		(width 0.10795)
		(layer "B.Cu")
		(net "FM_ADR_COMPLETE_KLM_N")
	)
	(segment
		(start 104.417368 -130.2766)
		(end 103.934768 -130.7592)
		(width 0.10795)
		(layer "B.Cu")
		(net "FM_ADR_COMPLETE_KLM_N")
	)
	(segment
		(start 105.611168 -130.683)
		(end 105.153968 -130.683)
		(width 0.10795)
		(layer "B.Cu")
		(net "FM_ADR_COMPLETE_KLM_N")
	)
	(segment
		(start 99.692968 -146.3421)
		(end 99.692968 -148.4757)
		(width 0.10795)
		(layer "B.Cu")
		(net "FM_ADR_COMPLETE_KLM_N")
	)
	(segment
		(start 99.866704 -140.3604)
		(end 100.5586 -140.3604)
		(width 0.10795)
		(layer "B.Cu")
		(net "FM_ADR_COMPLETE_KLM_N")
	)
	(segment
		(start 99.692968 -139.316968)
		(end 99.695 -139.319)
		(width 0.10795)
		(layer "B.Cu")
		(net "FM_ADR_COMPLETE_KLM_N")
	)
	(segment
		(start 107.04957 -139.33805)
		(end 107.04957 -139.171934)
		(width 0.10795)
		(layer "B.Cu")
		(net "FM_ADR_COMPLETE_KLM_N")
	)
	(segment
		(start 105.966768 -154.3558)
		(end 106.398568 -154.3558)
		(width 0.10795)
		(layer "B.Cu")
		(net "FM_ADR_COMPLETE_KLM_N")
	)
	(segment
		(start 107.049316 -155.006548)
		(end 107.049316 -155.59024)
		(width 0.10795)
		(layer "B.Cu")
		(net "FM_ADR_COMPLETE_KLM_N")
	)
	(segment
		(start 106.58602 -130.249168)
		(end 106.045 -130.249168)
		(width 0.10795)
		(layer "B.Cu")
		(net "FM_ADR_COMPLETE_KLM_N")
	)
	(segment
		(start 99.794568 -154.559)
		(end 99.972368 -154.7368)
		(width 0.10795)
		(layer "B.Cu")
		(net "FM_ADR_COMPLETE_KLM_N")
	)
	(segment
		(start 100.457 -150.292054)
		(end 100.6856 -150.063454)
		(width 0.10795)
		(layer "B.Cu")
		(net "FM_ADR_COMPLETE_KLM_N")
	)
	(segment
		(start 100.099114 -150.292054)
		(end 100.457 -150.292054)
		(width 0.10795)
		(layer "B.Cu")
		(net "FM_ADR_COMPLETE_KLM_N")
	)
	(segment
		(start 106.398568 -154.3558)
		(end 107.049316 -155.006548)
		(width 0.10795)
		(layer "B.Cu")
		(net "FM_ADR_COMPLETE_KLM_N")
	)
	(segment
		(start 99.695 -140.188696)
		(end 99.7712 -140.264896)
		(width 0.10795)
		(layer "B.Cu")
		(net "FM_ADR_COMPLETE_KLM_N")
	)
	(segment
		(start 107.04957 -139.171934)
		(end 107.04957 -137.877296)
		(width 0.10795)
		(layer "B.Cu")
		(net "FM_ADR_COMPLETE_KLM_N")
	)
	(segment
		(start 101.7651 -155.1813)
		(end 102.144068 -155.1813)
		(width 0.10795)
		(layer "B.Cu")
		(net "FM_ADR_COMPLETE_KLM_N")
	)
	(segment
		(start 99.695 -149.88794)
		(end 100.099114 -150.292054)
		(width 0.10795)
		(layer "B.Cu")
		(net "FM_ADR_COMPLETE_KLM_N")
	)
	(segment
		(start 101.5492 -155.3972)
		(end 101.7651 -155.1813)
		(width 0.10795)
		(layer "B.Cu")
		(net "FM_ADR_COMPLETE_KLM_N")
	)
	(segment
		(start 107.04957 -148.773134)
		(end 107.04957 -147.478496)
		(width 0.10795)
		(layer "B.Cu")
		(net "FM_ADR_COMPLETE_KLM_N")
	)
	(segment
		(start 100.6856 -150.063454)
		(end 100.6856 -149.352)
		(width 0.10795)
		(layer "B.Cu")
		(net "FM_ADR_COMPLETE_KLM_N")
	)
	(segment
		(start 107.049824 -148.773388)
		(end 107.04957 -148.773134)
		(width 0.10795)
		(layer "B.Cu")
		(net "FM_ADR_COMPLETE_KLM_N")
	)
	(segment
		(start 100.251768 -154.7368)
		(end 100.912168 -155.3972)
		(width 0.10795)
		(layer "B.Cu")
		(net "FM_ADR_COMPLETE_KLM_N")
	)
	(segment
		(start 99.692968 -143.7005)
		(end 99.7585 -143.766032)
		(width 0.10795)
		(layer "B.Cu")
		(net "FM_ADR_COMPLETE_KLM_N")
	)
	(segment
		(start 99.692968 -141.3002)
		(end 99.692968 -143.7005)
		(width 0.10795)
		(layer "B.Cu")
		(net "FM_ADR_COMPLETE_KLM_N")
	)
	(segment
		(start 330.198984 -75.311254)
		(end 330.567538 -75.679808)
		(width 0.10795)
		(layer "B.Cu")
		(net "FM_ADR_COMPLETE_KLM_N")
	)
	(segment
		(start 99.7712 -134.431532)
		(end 99.7712 -136.319768)
		(width 0.10795)
		(layer "B.Cu")
		(net "FM_ADR_COMPLETE_KLM_N")
	)
	(segment
		(start 99.692968 -136.398)
		(end 99.692968 -139.316968)
		(width 0.10795)
		(layer "B.Cu")
		(net "FM_ADR_COMPLETE_KLM_N")
	)
	(segment
		(start 330.567538 -75.679808)
		(end 330.567538 -76.465938)
		(width 0.10795)
		(layer "B.Cu")
		(net "FM_ADR_COMPLETE_KLM_N")
	)
	(segment
		(start 99.972368 -154.7368)
		(end 100.251768 -154.7368)
		(width 0.10795)
		(layer "B.Cu")
		(net "FM_ADR_COMPLETE_KLM_N")
	)
	(segment
		(start 331.286358 -78.142846)
		(end 331.691742 -78.54823)
		(width 0.10795)
		(layer "B.Cu")
		(net "FM_ADR_COMPLETE_KLM_N")
	)
	(segment
		(start 327.086722 -66.790824)
		(end 330.198984 -69.903086)
		(width 0.10795)
		(layer "B.Cu")
		(net "FM_ADR_COMPLETE_KLM_N")
	)
	(segment
		(start 101.369368 -130.4036)
		(end 100.886768 -130.4036)
		(width 0.10795)
		(layer "B.Cu")
		(net "FM_ADR_COMPLETE_KLM_N")
	)
	(segment
		(start 103.375968 -130.7592)
		(end 102.944168 -130.3274)
		(width 0.10795)
		(layer "B.Cu")
		(net "FM_ADR_COMPLETE_KLM_N")
	)
	(segment
		(start 103.909368 -155.0924)
		(end 104.239568 -155.4226)
		(width 0.10795)
		(layer "B.Cu")
		(net "FM_ADR_COMPLETE_KLM_N")
	)
	(segment
		(start 99.7712 -136.319768)
		(end 99.692968 -136.398)
		(width 0.10795)
		(layer "B.Cu")
		(net "FM_ADR_COMPLETE_KLM_N")
	)
	(segment
		(start 100.6856 -149.352)
		(end 100.838 -149.1996)
		(width 0.10795)
		(layer "B.Cu")
		(net "FM_ADR_COMPLETE_KLM_N")
	)
	(segment
		(start 102.207568 -130.7084)
		(end 101.674168 -130.7084)
		(width 0.10795)
		(layer "B.Cu")
		(net "FM_ADR_COMPLETE_KLM_N")
	)
	(segment
		(start 99.7712 -141.221968)
		(end 99.692968 -141.3002)
		(width 0.10795)
		(layer "B.Cu")
		(net "FM_ADR_COMPLETE_KLM_N")
	)
	(segment
		(start 101.674168 -130.7084)
		(end 101.369368 -130.4036)
		(width 0.10795)
		(layer "B.Cu")
		(net "FM_ADR_COMPLETE_KLM_N")
	)
	(segment
		(start 102.944168 -130.3274)
		(end 102.588568 -130.3274)
		(width 0.10795)
		(layer "B.Cu")
		(net "FM_ADR_COMPLETE_KLM_N")
	)
	(segment
		(start 99.692968 -148.4757)
		(end 99.695 -148.477732)
		(width 0.10795)
		(layer "B.Cu")
		(net "FM_ADR_COMPLETE_KLM_N")
	)
	(segment
		(start 99.7585 -143.766032)
		(end 99.7585 -146.276568)
		(width 0.10795)
		(layer "B.Cu")
		(net "FM_ADR_COMPLETE_KLM_N")
	)
	(segment
		(start 106.76382 -139.6238)
		(end 107.04957 -139.33805)
		(width 0.10795)
		(layer "B.Cu")
		(net "FM_ADR_COMPLETE_KLM_N")
	)
	(segment
		(start 100.711 -139.8016)
		(end 100.8888 -139.6238)
		(width 0.10795)
		(layer "B.Cu")
		(net "FM_ADR_COMPLETE_KLM_N")
	)
	(segment
		(start 330.198984 -69.903086)
		(end 330.198984 -75.311254)
		(width 0.10795)
		(layer "B.Cu")
		(net "FM_ADR_COMPLETE_KLM_N")
	)
	(segment
		(start 102.144068 -155.1813)
		(end 102.308152 -155.345384)
		(width 0.10795)
		(layer "B.Cu")
		(net "FM_ADR_COMPLETE_KLM_N")
	)
	(segment
		(start 325.142098 -64.8462)
		(end 327.086722 -66.790824)
		(width 0.10795)
		(layer "B.Cu")
		(net "FM_ADR_COMPLETE_KLM_N")
	)
	(segment
		(start 106.623612 -149.1996)
		(end 107.049824 -148.773388)
		(width 0.10795)
		(layer "B.Cu")
		(net "FM_ADR_COMPLETE_KLM_N")
	)
	(segment
		(start 323.6214 -64.8462)
		(end 325.142098 -64.8462)
		(width 0.10795)
		(layer "B.Cu")
		(net "FM_ADR_COMPLETE_KLM_N")
	)
	(segment
		(start 100.711 -140.208)
		(end 100.711 -139.8016)
		(width 0.10795)
		(layer "B.Cu")
		(net "FM_ADR_COMPLETE_KLM_N")
	)
	(segment
		(start 102.308152 -155.345384)
		(end 103.224584 -155.345384)
		(width 0.10795)
		(layer "B.Cu")
		(net "FM_ADR_COMPLETE_KLM_N")
	)
	(segment
		(start 99.695 -148.477732)
		(end 99.695 -149.88794)
		(width 0.10795)
		(layer "B.Cu")
		(net "FM_ADR_COMPLETE_KLM_N")
	)
	(segment
		(start 100.838 -149.1996)
		(end 106.623612 -149.1996)
		(width 0.10795)
		(layer "B.Cu")
		(net "FM_ADR_COMPLETE_KLM_N")
	)
	(segment
		(start 104.722168 -155.4226)
		(end 105.382568 -154.7622)
		(width 0.10795)
		(layer "B.Cu")
		(net "FM_ADR_COMPLETE_KLM_N")
	)
	(segment
		(start 105.153968 -130.683)
		(end 104.747568 -130.2766)
		(width 0.10795)
		(layer "B.Cu")
		(net "FM_ADR_COMPLETE_KLM_N")
	)
	(segment
		(start 331.286358 -77.184758)
		(end 331.286358 -78.142846)
		(width 0.10795)
		(layer "B.Cu")
		(net "FM_ADR_COMPLETE_KLM_N")
	)
	(segment
		(start 102.588568 -130.3274)
		(end 102.207568 -130.7084)
		(width 0.10795)
		(layer "B.Cu")
		(net "FM_ADR_COMPLETE_KLM_N")
	)
	(segment
		(start 100.5586 -140.3604)
		(end 100.711 -140.208)
		(width 0.10795)
		(layer "B.Cu")
		(net "FM_ADR_COMPLETE_KLM_N")
	)
	(segment
		(start 103.224584 -155.345384)
		(end 103.477568 -155.0924)
		(width 0.10795)
		(layer "B.Cu")
		(net "FM_ADR_COMPLETE_KLM_N")
	)
	(segment
		(start 99.692968 -134.3533)
		(end 99.7712 -134.431532)
		(width 0.10795)
		(layer "B.Cu")
		(net "FM_ADR_COMPLETE_KLM_N")
	)
	(segment
		(start 100.8888 -139.6238)
		(end 106.76382 -139.6238)
		(width 0.10795)
		(layer "B.Cu")
		(net "FM_ADR_COMPLETE_KLM_N")
	)
	(segment
		(start 104.239568 -155.4226)
		(end 104.722168 -155.4226)
		(width 0.10795)
		(layer "B.Cu")
		(net "FM_ADR_COMPLETE_KLM_N")
	)
	(segment
		(start 99.794568 -150.5966)
		(end 99.794568 -154.559)
		(width 0.10795)
		(layer "B.Cu")
		(net "FM_ADR_COMPLETE_KLM_N")
	)
	(segment
		(start 107.04957 -128.276096)
		(end 107.04957 -129.7813)
		(width 0.10795)
		(layer "B.Cu")
		(net "FM_ADR_COMPLETE_KLM_N")
	)
	(segment
		(start 105.382568 -154.7622)
		(end 105.560368 -154.7622)
		(width 0.10795)
		(layer "B.Cu")
		(net "FM_ADR_COMPLETE_KLM_N")
	)
	(segment
		(start 104.747568 -130.2766)
		(end 104.417368 -130.2766)
		(width 0.10795)
		(layer "B.Cu")
		(net "FM_ADR_COMPLETE_KLM_N")
	)
	(segment
		(start 107.049824 -139.172188)
		(end 107.04957 -139.171934)
		(width 0.10795)
		(layer "B.Cu")
		(net "FM_ADR_COMPLETE_KLM_N")
	)
	(segment
		(start 103.477568 -155.0924)
		(end 103.909368 -155.0924)
		(width 0.10795)
		(layer "B.Cu")
		(net "FM_ADR_COMPLETE_KLM_N")
	)
	(segment
		(start 107.04957 -129.7813)
		(end 106.58602 -130.24485)
		(width 0.10795)
		(layer "B.Cu")
		(net "FM_ADR_COMPLETE_KLM_N")
	)
	(segment
		(start 105.560368 -154.7622)
		(end 105.966768 -154.3558)
		(width 0.10795)
		(layer "B.Cu")
		(net "FM_ADR_COMPLETE_KLM_N")
	)
	(segment
		(start 100.886768 -130.4036)
		(end 99.692968 -131.5974)
		(width 0.10795)
		(layer "B.Cu")
		(net "FM_ADR_COMPLETE_KLM_N")
	)
	(segment
		(start 99.7712 -140.264896)
		(end 99.7712 -141.221968)
		(width 0.10795)
		(layer "B.Cu")
		(net "FM_ADR_COMPLETE_KLM_N")
	)
	(segment
		(start 103.934768 -130.7592)
		(end 103.375968 -130.7592)
		(width 0.10795)
		(layer "B.Cu")
		(net "FM_ADR_COMPLETE_KLM_N")
	)
	(segment
		(start 325.912226 -157.002226)
		(end 324.4469 -155.5369)
		(width 0.089408)
		(layer "In2.Cu")
		(net "FM_ADR_COMPLETE_KLM_N")
	)
	(segment
		(start 324.4469 -155.5369)
		(end 324.4469 -152.5397)
		(width 0.089408)
		(layer "In2.Cu")
		(net "FM_ADR_COMPLETE_KLM_N")
	)
	(segment
		(start 324.4469 -152.5397)
		(end 322.6816 -150.7744)
		(width 0.089408)
		(layer "In2.Cu")
		(net "FM_ADR_COMPLETE_KLM_N")
	)
	(segment
		(start 330.551536 -157.002226)
		(end 325.912226 -157.002226)
		(width 0.089408)
		(layer "In2.Cu")
		(net "FM_ADR_COMPLETE_KLM_N")
	)
	(segment
		(start 322.191888 -91.173554)
		(end 329.177396 -84.187792)
		(width 0.089408)
		(layer "In4.Cu")
		(net "FM_ADR_COMPLETE_KLM_N")
	)
	(segment
		(start 324.127368 -124.855732)
		(end 324.169532 -124.813568)
		(width 0.089408)
		(layer "In4.Cu")
		(net "FM_ADR_COMPLETE_KLM_N")
	)
	(segment
		(start 323.342 -130.048)
		(end 323.342 -129.235962)
		(width 0.089408)
		(layer "In4.Cu")
		(net "FM_ADR_COMPLETE_KLM_N")
	)
	(segment
		(start 325.41845 -125.5014)
		(end 324.378066 -125.5014)
		(width 0.089408)
		(layer "In4.Cu")
		(net "FM_ADR_COMPLETE_KLM_N")
	)
	(segment
		(start 323.342 -129.235962)
		(end 324.689724 -127.888238)
		(width 0.089408)
		(layer "In4.Cu")
		(net "FM_ADR_COMPLETE_KLM_N")
	)
	(segment
		(start 324.689724 -127.319024)
		(end 325.763636 -126.245112)
		(width 0.089408)
		(layer "In4.Cu")
		(net "FM_ADR_COMPLETE_KLM_N")
	)
	(segment
		(start 320.949574 -140.82268)
		(end 322.237608 -139.534646)
		(width 0.089408)
		(layer "In4.Cu")
		(net "FM_ADR_COMPLETE_KLM_N")
	)
	(segment
		(start 322.191888 -99.176332)
		(end 322.191888 -91.611196)
		(width 0.089408)
		(layer "In4.Cu")
		(net "FM_ADR_COMPLETE_KLM_N")
	)
	(segment
		(start 324.169532 -124.813568)
		(end 324.169532 -119.376952)
		(width 0.089408)
		(layer "In4.Cu")
		(net "FM_ADR_COMPLETE_KLM_N")
	)
	(segment
		(start 331.691742 -79.574644)
		(end 331.691742 -78.54823)
		(width 0.089408)
		(layer "In4.Cu")
		(net "FM_ADR_COMPLETE_KLM_N")
	)
	(segment
		(start 324.689724 -127.888238)
		(end 324.689724 -127.319024)
		(width 0.089408)
		(layer "In4.Cu")
		(net "FM_ADR_COMPLETE_KLM_N")
	)
	(segment
		(start 323.5198 -118.72722)
		(end 323.5198 -116.848128)
		(width 0.089408)
		(layer "In4.Cu")
		(net "FM_ADR_COMPLETE_KLM_N")
	)
	(segment
		(start 322.191634 -91.328494)
		(end 322.191888 -91.327986)
		(width 0.089408)
		(layer "In4.Cu")
		(net "FM_ADR_COMPLETE_KLM_N")
	)
	(segment
		(start 322.191634 -91.610942)
		(end 322.191634 -91.328494)
		(width 0.089408)
		(layer "In4.Cu")
		(net "FM_ADR_COMPLETE_KLM_N")
	)
	(segment
		(start 322.191888 -91.327986)
		(end 322.191888 -91.173554)
		(width 0.089408)
		(layer "In4.Cu")
		(net "FM_ADR_COMPLETE_KLM_N")
	)
	(segment
		(start 323.105272 -130.284728)
		(end 323.342 -130.048)
		(width 0.089408)
		(layer "In4.Cu")
		(net "FM_ADR_COMPLETE_KLM_N")
	)
	(segment
		(start 324.378066 -125.5014)
		(end 324.127368 -125.250702)
		(width 0.089408)
		(layer "In4.Cu")
		(net "FM_ADR_COMPLETE_KLM_N")
	)
	(segment
		(start 329.177396 -82.08899)
		(end 331.691742 -79.574644)
		(width 0.089408)
		(layer "In4.Cu")
		(net "FM_ADR_COMPLETE_KLM_N")
	)
	(segment
		(start 322.191888 -91.611196)
		(end 322.191634 -91.610942)
		(width 0.089408)
		(layer "In4.Cu")
		(net "FM_ADR_COMPLETE_KLM_N")
	)
	(segment
		(start 324.127368 -125.250702)
		(end 324.127368 -124.855732)
		(width 0.089408)
		(layer "In4.Cu")
		(net "FM_ADR_COMPLETE_KLM_N")
	)
	(segment
		(start 323.105272 -135.577072)
		(end 323.105272 -130.284728)
		(width 0.089408)
		(layer "In4.Cu")
		(net "FM_ADR_COMPLETE_KLM_N")
	)
	(segment
		(start 321.812666 -99.555554)
		(end 322.191888 -99.176332)
		(width 0.089408)
		(layer "In4.Cu")
		(net "FM_ADR_COMPLETE_KLM_N")
	)
	(segment
		(start 322.237608 -136.444736)
		(end 323.105272 -135.577072)
		(width 0.089408)
		(layer "In4.Cu")
		(net "FM_ADR_COMPLETE_KLM_N")
	)
	(segment
		(start 321.812666 -115.140994)
		(end 321.812666 -99.555554)
		(width 0.089408)
		(layer "In4.Cu")
		(net "FM_ADR_COMPLETE_KLM_N")
	)
	(segment
		(start 322.237608 -139.534646)
		(end 322.237608 -136.444736)
		(width 0.089408)
		(layer "In4.Cu")
		(net "FM_ADR_COMPLETE_KLM_N")
	)
	(segment
		(start 325.763636 -125.846586)
		(end 325.41845 -125.5014)
		(width 0.089408)
		(layer "In4.Cu")
		(net "FM_ADR_COMPLETE_KLM_N")
	)
	(segment
		(start 322.6816 -150.7744)
		(end 320.949574 -149.042374)
		(width 0.089408)
		(layer "In4.Cu")
		(net "FM_ADR_COMPLETE_KLM_N")
	)
	(segment
		(start 320.949574 -149.042374)
		(end 320.949574 -140.82268)
		(width 0.089408)
		(layer "In4.Cu")
		(net "FM_ADR_COMPLETE_KLM_N")
	)
	(segment
		(start 324.169532 -119.376952)
		(end 323.5198 -118.72722)
		(width 0.089408)
		(layer "In4.Cu")
		(net "FM_ADR_COMPLETE_KLM_N")
	)
	(segment
		(start 329.177396 -84.187792)
		(end 329.177396 -82.08899)
		(width 0.089408)
		(layer "In4.Cu")
		(net "FM_ADR_COMPLETE_KLM_N")
	)
	(segment
		(start 323.5198 -116.848128)
		(end 321.812666 -115.140994)
		(width 0.089408)
		(layer "In4.Cu")
		(net "FM_ADR_COMPLETE_KLM_N")
	)
	(segment
		(start 325.763636 -126.245112)
		(end 325.763636 -125.846586)
		(width 0.089408)
		(layer "In4.Cu")
		(net "FM_ADR_COMPLETE_KLM_N")
	)
	(segment
		(start 322.131944 -36.052252)
		(end 322.131944 -37.002212)
		(width 0.089408)
		(layer "In9.Cu")
		(net "FM_ADR_COMPLETE_KLM_N")
	)
	(segment
		(start 280.31694 -157.858968)
		(end 279.785572 -157.3276)
		(width 0.089408)
		(layer "In9.Cu")
		(net "FM_ADR_COMPLETE_KLM_N")
	)
	(segment
		(start 183.769 -156.21)
		(end 182.304436 -154.745436)
		(width 0.089408)
		(layer "In9.Cu")
		(net "FM_ADR_COMPLETE_KLM_N")
	)
	(segment
		(start 324.180708 -39.050976)
		(end 324.180708 -43.335448)
		(width 0.089408)
		(layer "In9.Cu")
		(net "FM_ADR_COMPLETE_KLM_N")
	)
	(segment
		(start 107.049316 -155.189428)
		(end 107.049316 -155.59024)
		(width 0.089408)
		(layer "In9.Cu")
		(net "FM_ADR_COMPLETE_KLM_N")
	)
	(segment
		(start 322.131944 -37.002212)
		(end 324.180708 -39.050976)
		(width 0.089408)
		(layer "In9.Cu")
		(net "FM_ADR_COMPLETE_KLM_N")
	)
	(segment
		(start 186.433968 -156.21)
		(end 183.769 -156.21)
		(width 0.089408)
		(layer "In9.Cu")
		(net "FM_ADR_COMPLETE_KLM_N")
	)
	(segment
		(start 167.805862 -149.162008)
		(end 164.505132 -152.462738)
		(width 0.089408)
		(layer "In9.Cu")
		(net "FM_ADR_COMPLETE_KLM_N")
	)
	(segment
		(start 321.742308 -64.8462)
		(end 323.6214 -64.8462)
		(width 0.089408)
		(layer "In9.Cu")
		(net "FM_ADR_COMPLETE_KLM_N")
	)
	(segment
		(start 313.256676 -51.684428)
		(end 313.256676 -56.360568)
		(width 0.089408)
		(layer "In9.Cu")
		(net "FM_ADR_COMPLETE_KLM_N")
	)
	(segment
		(start 264.5664 -157.3276)
		(end 264.270998 -157.623002)
		(width 0.089408)
		(layer "In9.Cu")
		(net "FM_ADR_COMPLETE_KLM_N")
	)
	(segment
		(start 324.180708 -43.335448)
		(end 320.77533 -46.740826)
		(width 0.089408)
		(layer "In9.Cu")
		(net "FM_ADR_COMPLETE_KLM_N")
	)
	(segment
		(start 318.200278 -46.740826)
		(end 313.256676 -51.684428)
		(width 0.089408)
		(layer "In9.Cu")
		(net "FM_ADR_COMPLETE_KLM_N")
	)
	(segment
		(start 181.348634 -151.572468)
		(end 180.835046 -151.05888)
		(width 0.089408)
		(layer "In9.Cu")
		(net "FM_ADR_COMPLETE_KLM_N")
	)
	(segment
		(start 164.505132 -152.462738)
		(end 159.928052 -152.462738)
		(width 0.089408)
		(layer "In9.Cu")
		(net "FM_ADR_COMPLETE_KLM_N")
	)
	(segment
		(start 159.928052 -152.462738)
		(end 159.278066 -153.112724)
		(width 0.089408)
		(layer "In9.Cu")
		(net "FM_ADR_COMPLETE_KLM_N")
	)
	(segment
		(start 159.278066 -153.112724)
		(end 109.12602 -153.112724)
		(width 0.089408)
		(layer "In9.Cu")
		(net "FM_ADR_COMPLETE_KLM_N")
	)
	(segment
		(start 279.785572 -157.3276)
		(end 264.5664 -157.3276)
		(width 0.089408)
		(layer "In9.Cu")
		(net "FM_ADR_COMPLETE_KLM_N")
	)
	(segment
		(start 181.348634 -152.617424)
		(end 181.348634 -151.572468)
		(width 0.089408)
		(layer "In9.Cu")
		(net "FM_ADR_COMPLETE_KLM_N")
	)
	(segment
		(start 178.364896 -151.05888)
		(end 176.468024 -149.162008)
		(width 0.089408)
		(layer "In9.Cu")
		(net "FM_ADR_COMPLETE_KLM_N")
	)
	(segment
		(start 313.256676 -56.360568)
		(end 321.742308 -64.8462)
		(width 0.089408)
		(layer "In9.Cu")
		(net "FM_ADR_COMPLETE_KLM_N")
	)
	(segment
		(start 264.270998 -157.623002)
		(end 187.84697 -157.623002)
		(width 0.089408)
		(layer "In9.Cu")
		(net "FM_ADR_COMPLETE_KLM_N")
	)
	(segment
		(start 180.835046 -151.05888)
		(end 178.364896 -151.05888)
		(width 0.089408)
		(layer "In9.Cu")
		(net "FM_ADR_COMPLETE_KLM_N")
	)
	(segment
		(start 182.304436 -153.573226)
		(end 181.348634 -152.617424)
		(width 0.089408)
		(layer "In9.Cu")
		(net "FM_ADR_COMPLETE_KLM_N")
	)
	(segment
		(start 330.551536 -157.002226)
		(end 329.694794 -157.858968)
		(width 0.089408)
		(layer "In9.Cu")
		(net "FM_ADR_COMPLETE_KLM_N")
	)
	(segment
		(start 182.304436 -154.745436)
		(end 182.304436 -153.573226)
		(width 0.089408)
		(layer "In9.Cu")
		(net "FM_ADR_COMPLETE_KLM_N")
	)
	(segment
		(start 176.468024 -149.162008)
		(end 167.805862 -149.162008)
		(width 0.089408)
		(layer "In9.Cu")
		(net "FM_ADR_COMPLETE_KLM_N")
	)
	(segment
		(start 187.84697 -157.623002)
		(end 186.433968 -156.21)
		(width 0.089408)
		(layer "In9.Cu")
		(net "FM_ADR_COMPLETE_KLM_N")
	)
	(segment
		(start 109.12602 -153.112724)
		(end 107.049316 -155.189428)
		(width 0.089408)
		(layer "In9.Cu")
		(net "FM_ADR_COMPLETE_KLM_N")
	)
	(segment
		(start 320.77533 -46.740826)
		(end 318.200278 -46.740826)
		(width 0.089408)
		(layer "In9.Cu")
		(net "FM_ADR_COMPLETE_KLM_N")
	)
	(segment
		(start 329.694794 -157.858968)
		(end 280.31694 -157.858968)
		(width 0.089408)
		(layer "In9.Cu")
		(net "FM_ADR_COMPLETE_KLM_N")
	)
	(segment
		(start 321.252088 -34.33572)
		(end 320.55816 -34.33572)
		(width 0.10795)
		(layer "F.Cu")
		(net "FM_ADR_COMPLETE_GHJ_N")
	)
	(segment
		(start 107.04957 -0.821182)
		(end 107.049316 0.461518)
		(width 0.10795)
		(layer "F.Cu")
		(net "FM_ADR_COMPLETE_GHJ_N")
	)
	(segment
		(start 107.04957 -18.734532)
		(end 107.04957 -20.023582)
		(width 0.10795)
		(layer "F.Cu")
		(net "FM_ADR_COMPLETE_GHJ_N")
	)
	(segment
		(start 320.55816 -34.33572)
		(end 320.227198 -34.004758)
		(width 0.10795)
		(layer "F.Cu")
		(net "FM_ADR_COMPLETE_GHJ_N")
	)
	(segment
		(start 99.794568 -14.457172)
		(end 100.200968 -14.050772)
		(width 0.10795)
		(layer "F.Cu")
		(net "FM_ADR_COMPLETE_GHJ_N")
	)
	(segment
		(start 107.04957 -11.917934)
		(end 107.04957 -10.422382)
		(width 0.10795)
		(layer "F.Cu")
		(net "FM_ADR_COMPLETE_GHJ_N")
	)
	(segment
		(start 107.049824 -18.734278)
		(end 106.546142 -18.230596)
		(width 0.10795)
		(layer "F.Cu")
		(net "FM_ADR_COMPLETE_GHJ_N")
	)
	(segment
		(start 107.049824 -18.734278)
		(end 107.04957 -18.734532)
		(width 0.10795)
		(layer "F.Cu")
		(net "FM_ADR_COMPLETE_GHJ_N")
	)
	(segment
		(start 99.794568 -17.552416)
		(end 99.794568 -14.457172)
		(width 0.10795)
		(layer "F.Cu")
		(net "FM_ADR_COMPLETE_GHJ_N")
	)
	(segment
		(start 100.200968 -14.050772)
		(end 100.200968 -13.8938)
		(width 0.10795)
		(layer "F.Cu")
		(net "FM_ADR_COMPLETE_GHJ_N")
	)
	(segment
		(start 321.8434 -34.163)
		(end 321.424808 -34.163)
		(width 0.10795)
		(layer "F.Cu")
		(net "FM_ADR_COMPLETE_GHJ_N")
	)
	(segment
		(start 321.424808 -34.163)
		(end 321.252088 -34.33572)
		(width 0.10795)
		(layer "F.Cu")
		(net "FM_ADR_COMPLETE_GHJ_N")
	)
	(segment
		(start 100.472748 -18.230596)
		(end 99.794568 -17.552416)
		(width 0.10795)
		(layer "F.Cu")
		(net "FM_ADR_COMPLETE_GHJ_N")
	)
	(segment
		(start 106.546142 -18.230596)
		(end 100.472748 -18.230596)
		(width 0.10795)
		(layer "F.Cu")
		(net "FM_ADR_COMPLETE_GHJ_N")
	)
	(via
		(at 107.04957 -2.316734)
		(size 0.4572)
		(drill 0.2032)
		(layers "F.Cu" "B.Cu")
		(net "FM_ADR_COMPLETE_GHJ_N")
	)
	(via
		(at 329.799188 -18.796)
		(size 0.508)
		(drill 0.254)
		(layers "F.Cu" "B.Cu")
		(net "FM_ADR_COMPLETE_GHJ_N")
	)
	(via
		(at 107.049316 0.461518)
		(size 0.508)
		(drill 0.254)
		(layers "F.Cu" "B.Cu")
		(net "FM_ADR_COMPLETE_GHJ_N")
	)
	(via
		(at 100.200968 -13.8938)
		(size 0.508)
		(drill 0.254)
		(layers "F.Cu" "B.Cu")
		(net "FM_ADR_COMPLETE_GHJ_N")
	)
	(via
		(at 107.049824 -18.734278)
		(size 0.4572)
		(drill 0.2032)
		(layers "F.Cu" "B.Cu")
		(net "FM_ADR_COMPLETE_GHJ_N")
	)
	(via
		(at 107.04957 -11.917934)
		(size 0.4572)
		(drill 0.2032)
		(layers "F.Cu" "B.Cu")
		(net "FM_ADR_COMPLETE_GHJ_N")
	)
	(via
		(at 166.828978 5.245608)
		(size 0.508)
		(drill 0.254)
		(layers "F.Cu" "B.Cu")
		(net "FM_ADR_COMPLETE_GHJ_N")
	)
	(via
		(at 320.227198 -34.004758)
		(size 0.508)
		(drill 0.254)
		(layers "F.Cu" "B.Cu")
		(net "FM_ADR_COMPLETE_GHJ_N")
	)
	(segment
		(start 108.0516 1.778)
		(end 108.5088 1.3208)
		(width 0.10795)
		(layer "B.Cu")
		(net "FM_ADR_COMPLETE_GHJ_N")
	)
	(segment
		(start 99.273868 -11.2649)
		(end 99.695 -11.686032)
		(width 0.10795)
		(layer "B.Cu")
		(net "FM_ADR_COMPLETE_GHJ_N")
	)
	(segment
		(start 114.2111 1.5113)
		(end 117.3099 1.5113)
		(width 0.10795)
		(layer "B.Cu")
		(net "FM_ADR_COMPLETE_GHJ_N")
	)
	(segment
		(start 107.04957 -1.021842)
		(end 107.04957 -2.316734)
		(width 0.10795)
		(layer "B.Cu")
		(net "FM_ADR_COMPLETE_GHJ_N")
	)
	(segment
		(start 109.0168 1.3208)
		(end 109.347 1.651)
		(width 0.10795)
		(layer "B.Cu")
		(net "FM_ADR_COMPLETE_GHJ_N")
	)
	(segment
		(start 105.153968 1.3208)
		(end 104.798368 1.6764)
		(width 0.10795)
		(layer "B.Cu")
		(net "FM_ADR_COMPLETE_GHJ_N")
	)
	(segment
		(start 109.347 1.651)
		(end 109.9058 1.651)
		(width 0.10795)
		(layer "B.Cu")
		(net "FM_ADR_COMPLETE_GHJ_N")
	)
	(segment
		(start 99.273868 -10.6807)
		(end 99.273868 -11.2649)
		(width 0.10795)
		(layer "B.Cu")
		(net "FM_ADR_COMPLETE_GHJ_N")
	)
	(segment
		(start 105.611168 1.3208)
		(end 105.153968 1.3208)
		(width 0.10795)
		(layer "B.Cu")
		(net "FM_ADR_COMPLETE_GHJ_N")
	)
	(segment
		(start 99.718368 -10.2362)
		(end 99.273868 -10.6807)
		(width 0.10795)
		(layer "B.Cu")
		(net "FM_ADR_COMPLETE_GHJ_N")
	)
	(segment
		(start 99.695 -13.387832)
		(end 100.200968 -13.8938)
		(width 0.10795)
		(layer "B.Cu")
		(net "FM_ADR_COMPLETE_GHJ_N")
	)
	(segment
		(start 101.724968 1.27)
		(end 101.394768 1.6002)
		(width 0.10795)
		(layer "B.Cu")
		(net "FM_ADR_COMPLETE_GHJ_N")
	)
	(segment
		(start 117.58168 1.78308)
		(end 117.58168 3.07848)
		(width 0.10795)
		(layer "B.Cu")
		(net "FM_ADR_COMPLETE_GHJ_N")
	)
	(segment
		(start 107.049316 0.461518)
		(end 106.7054 0.805434)
		(width 0.10795)
		(layer "B.Cu")
		(net "FM_ADR_COMPLETE_GHJ_N")
	)
	(segment
		(start 100.696522 -13.599922)
		(end 100.402644 -13.8938)
		(width 0.10795)
		(layer "B.Cu")
		(net "FM_ADR_COMPLETE_GHJ_N")
	)
	(segment
		(start 102.639368 1.7018)
		(end 102.207568 1.27)
		(width 0.10795)
		(layer "B.Cu")
		(net "FM_ADR_COMPLETE_GHJ_N")
	)
	(segment
		(start 166.646352 5.062982)
		(end 166.828978 5.245608)
		(width 0.10795)
		(layer "B.Cu")
		(net "FM_ADR_COMPLETE_GHJ_N")
	)
	(segment
		(start 119.566182 5.062982)
		(end 166.646352 5.062982)
		(width 0.10795)
		(layer "B.Cu")
		(net "FM_ADR_COMPLETE_GHJ_N")
	)
	(segment
		(start 100.402644 -13.8938)
		(end 100.200968 -13.8938)
		(width 0.10795)
		(layer "B.Cu")
		(net "FM_ADR_COMPLETE_GHJ_N")
	)
	(segment
		(start 110.5662 1.27)
		(end 111.1504 0.6858)
		(width 0.10795)
		(layer "B.Cu")
		(net "FM_ADR_COMPLETE_GHJ_N")
	)
	(segment
		(start 102.207568 1.27)
		(end 101.724968 1.27)
		(width 0.10795)
		(layer "B.Cu")
		(net "FM_ADR_COMPLETE_GHJ_N")
	)
	(segment
		(start 100.696522 -12.511278)
		(end 100.696522 -13.599922)
		(width 0.10795)
		(layer "B.Cu")
		(net "FM_ADR_COMPLETE_GHJ_N")
	)
	(segment
		(start 102.994968 1.7018)
		(end 102.639368 1.7018)
		(width 0.10795)
		(layer "B.Cu")
		(net "FM_ADR_COMPLETE_GHJ_N")
	)
	(segment
		(start 111.1504 0.6858)
		(end 111.633 0.6858)
		(width 0.10795)
		(layer "B.Cu")
		(net "FM_ADR_COMPLETE_GHJ_N")
	)
	(segment
		(start 104.341168 1.6764)
		(end 103.934768 1.27)
		(width 0.10795)
		(layer "B.Cu")
		(net "FM_ADR_COMPLETE_GHJ_N")
	)
	(segment
		(start 100.683568 1.6002)
		(end 99.718368 0.635)
		(width 0.10795)
		(layer "B.Cu")
		(net "FM_ADR_COMPLETE_GHJ_N")
	)
	(segment
		(start 107.04957 -11.917934)
		(end 107.049824 -11.918188)
		(width 0.10795)
		(layer "B.Cu")
		(net "FM_ADR_COMPLETE_GHJ_N")
	)
	(segment
		(start 108.5088 1.3208)
		(end 109.0168 1.3208)
		(width 0.10795)
		(layer "B.Cu")
		(net "FM_ADR_COMPLETE_GHJ_N")
	)
	(segment
		(start 113.9698 1.27)
		(end 114.2111 1.5113)
		(width 0.10795)
		(layer "B.Cu")
		(net "FM_ADR_COMPLETE_GHJ_N")
	)
	(segment
		(start 99.695 -11.686032)
		(end 99.695 -13.387832)
		(width 0.10795)
		(layer "B.Cu")
		(net "FM_ADR_COMPLETE_GHJ_N")
	)
	(segment
		(start 104.798368 1.6764)
		(end 104.341168 1.6764)
		(width 0.10795)
		(layer "B.Cu")
		(net "FM_ADR_COMPLETE_GHJ_N")
	)
	(segment
		(start 111.633 0.6858)
		(end 112.5474 1.6002)
		(width 0.10795)
		(layer "B.Cu")
		(net "FM_ADR_COMPLETE_GHJ_N")
	)
	(segment
		(start 107.04957 -18.734532)
		(end 107.049824 -18.734278)
		(width 0.10795)
		(layer "B.Cu")
		(net "FM_ADR_COMPLETE_GHJ_N")
	)
	(segment
		(start 107.04957 -20.224242)
		(end 107.04957 -18.734532)
		(width 0.10795)
		(layer "B.Cu")
		(net "FM_ADR_COMPLETE_GHJ_N")
	)
	(segment
		(start 106.598212 -12.3698)
		(end 100.838 -12.3698)
		(width 0.10795)
		(layer "B.Cu")
		(net "FM_ADR_COMPLETE_GHJ_N")
	)
	(segment
		(start 100.838 -12.3698)
		(end 100.696522 -12.511278)
		(width 0.10795)
		(layer "B.Cu")
		(net "FM_ADR_COMPLETE_GHJ_N")
	)
	(segment
		(start 106.7054 0.805434)
		(end 106.7054 1.369568)
		(width 0.10795)
		(layer "B.Cu")
		(net "FM_ADR_COMPLETE_GHJ_N")
	)
	(segment
		(start 101.394768 1.6002)
		(end 100.683568 1.6002)
		(width 0.10795)
		(layer "B.Cu")
		(net "FM_ADR_COMPLETE_GHJ_N")
	)
	(segment
		(start 106.398568 1.6764)
		(end 105.966768 1.6764)
		(width 0.10795)
		(layer "B.Cu")
		(net "FM_ADR_COMPLETE_GHJ_N")
	)
	(segment
		(start 107.04957 -10.623042)
		(end 107.04957 -11.917934)
		(width 0.10795)
		(layer "B.Cu")
		(net "FM_ADR_COMPLETE_GHJ_N")
	)
	(segment
		(start 99.718368 0.635)
		(end 99.718368 -10.2362)
		(width 0.10795)
		(layer "B.Cu")
		(net "FM_ADR_COMPLETE_GHJ_N")
	)
	(segment
		(start 103.426768 1.27)
		(end 102.994968 1.7018)
		(width 0.10795)
		(layer "B.Cu")
		(net "FM_ADR_COMPLETE_GHJ_N")
	)
	(segment
		(start 117.3099 1.5113)
		(end 117.58168 1.78308)
		(width 0.10795)
		(layer "B.Cu")
		(net "FM_ADR_COMPLETE_GHJ_N")
	)
	(segment
		(start 113.2078 1.6002)
		(end 113.538 1.27)
		(width 0.10795)
		(layer "B.Cu")
		(net "FM_ADR_COMPLETE_GHJ_N")
	)
	(segment
		(start 105.966768 1.6764)
		(end 105.611168 1.3208)
		(width 0.10795)
		(layer "B.Cu")
		(net "FM_ADR_COMPLETE_GHJ_N")
	)
	(segment
		(start 110.2868 1.27)
		(end 110.5662 1.27)
		(width 0.10795)
		(layer "B.Cu")
		(net "FM_ADR_COMPLETE_GHJ_N")
	)
	(segment
		(start 107.3404 0.752602)
		(end 107.3404 1.3208)
		(width 0.10795)
		(layer "B.Cu")
		(net "FM_ADR_COMPLETE_GHJ_N")
	)
	(segment
		(start 107.049824 -11.918188)
		(end 106.598212 -12.3698)
		(width 0.10795)
		(layer "B.Cu")
		(net "FM_ADR_COMPLETE_GHJ_N")
	)
	(segment
		(start 106.7054 1.369568)
		(end 106.398568 1.6764)
		(width 0.10795)
		(layer "B.Cu")
		(net "FM_ADR_COMPLETE_GHJ_N")
	)
	(segment
		(start 107.049316 0.461518)
		(end 107.3404 0.752602)
		(width 0.10795)
		(layer "B.Cu")
		(net "FM_ADR_COMPLETE_GHJ_N")
	)
	(segment
		(start 117.58168 3.07848)
		(end 119.566182 5.062982)
		(width 0.10795)
		(layer "B.Cu")
		(net "FM_ADR_COMPLETE_GHJ_N")
	)
	(segment
		(start 113.538 1.27)
		(end 113.9698 1.27)
		(width 0.10795)
		(layer "B.Cu")
		(net "FM_ADR_COMPLETE_GHJ_N")
	)
	(segment
		(start 107.3404 1.3208)
		(end 107.7976 1.778)
		(width 0.10795)
		(layer "B.Cu")
		(net "FM_ADR_COMPLETE_GHJ_N")
	)
	(segment
		(start 107.7976 1.778)
		(end 108.0516 1.778)
		(width 0.10795)
		(layer "B.Cu")
		(net "FM_ADR_COMPLETE_GHJ_N")
	)
	(segment
		(start 103.934768 1.27)
		(end 103.426768 1.27)
		(width 0.10795)
		(layer "B.Cu")
		(net "FM_ADR_COMPLETE_GHJ_N")
	)
	(segment
		(start 109.9058 1.651)
		(end 110.2868 1.27)
		(width 0.10795)
		(layer "B.Cu")
		(net "FM_ADR_COMPLETE_GHJ_N")
	)
	(segment
		(start 112.5474 1.6002)
		(end 113.2078 1.6002)
		(width 0.10795)
		(layer "B.Cu")
		(net "FM_ADR_COMPLETE_GHJ_N")
	)
	(segment
		(start 321.67322 -34.33318)
		(end 323.3928 -32.6136)
		(width 0.089408)
		(layer "In2.Cu")
		(net "FM_ADR_COMPLETE_GHJ_N")
	)
	(segment
		(start 107.04957 0.442468)
		(end 107.04957 -2.316734)
		(width 0.089408)
		(layer "In2.Cu")
		(net "FM_ADR_COMPLETE_GHJ_N")
	)
	(segment
		(start 329.2856 -22.7838)
		(end 329.2856 -19.309588)
		(width 0.089408)
		(layer "In2.Cu")
		(net "FM_ADR_COMPLETE_GHJ_N")
	)
	(segment
		(start 323.3928 -27.3558)
		(end 326.4408 -24.3078)
		(width 0.089408)
		(layer "In2.Cu")
		(net "FM_ADR_COMPLETE_GHJ_N")
	)
	(segment
		(start 107.049316 0.461518)
		(end 107.049316 0.442722)
		(width 0.089408)
		(layer "In2.Cu")
		(net "FM_ADR_COMPLETE_GHJ_N")
	)
	(segment
		(start 320.55562 -34.33318)
		(end 321.67322 -34.33318)
		(width 0.089408)
		(layer "In2.Cu")
		(net "FM_ADR_COMPLETE_GHJ_N")
	)
	(segment
		(start 326.4408 -24.3078)
		(end 327.7616 -24.3078)
		(width 0.089408)
		(layer "In2.Cu")
		(net "FM_ADR_COMPLETE_GHJ_N")
	)
	(segment
		(start 320.227198 -34.004758)
		(end 320.55562 -34.33318)
		(width 0.089408)
		(layer "In2.Cu")
		(net "FM_ADR_COMPLETE_GHJ_N")
	)
	(segment
		(start 329.2856 -19.309588)
		(end 329.799188 -18.796)
		(width 0.089408)
		(layer "In2.Cu")
		(net "FM_ADR_COMPLETE_GHJ_N")
	)
	(segment
		(start 323.3928 -32.6136)
		(end 323.3928 -27.3558)
		(width 0.089408)
		(layer "In2.Cu")
		(net "FM_ADR_COMPLETE_GHJ_N")
	)
	(segment
		(start 107.049316 0.442722)
		(end 107.04957 0.442468)
		(width 0.089408)
		(layer "In2.Cu")
		(net "FM_ADR_COMPLETE_GHJ_N")
	)
	(segment
		(start 327.7616 -24.3078)
		(end 329.2856 -22.7838)
		(width 0.089408)
		(layer "In2.Cu")
		(net "FM_ADR_COMPLETE_GHJ_N")
	)
	(segment
		(start 167.08755 4.987036)
		(end 166.828978 5.245608)
		(width 0.089408)
		(layer "In4.Cu")
		(net "FM_ADR_COMPLETE_GHJ_N")
	)
	(segment
		(start 179.3621 0.2667)
		(end 179.3621 -0.0889)
		(width 0.089408)
		(layer "In4.Cu")
		(net "FM_ADR_COMPLETE_GHJ_N")
	)
	(segment
		(start 179.7304 0.635)
		(end 179.3621 0.2667)
		(width 0.089408)
		(layer "In4.Cu")
		(net "FM_ADR_COMPLETE_GHJ_N")
	)
	(segment
		(start 329.336908 -16.078708)
		(end 329.006708 -15.748508)
		(width 0.089408)
		(layer "In4.Cu")
		(net "FM_ADR_COMPLETE_GHJ_N")
	)
	(segment
		(start 328.689208 -4.463288)
		(end 329.057 -4.095496)
		(width 0.089408)
		(layer "In4.Cu")
		(net "FM_ADR_COMPLETE_GHJ_N")
	)
	(segment
		(start 325.209408 0.774192)
		(end 325.209408 3.48996)
		(width 0.089408)
		(layer "In4.Cu")
		(net "FM_ADR_COMPLETE_GHJ_N")
	)
	(segment
		(start 179.3621 -0.0889)
		(end 177.224944 -2.226056)
		(width 0.089408)
		(layer "In4.Cu")
		(net "FM_ADR_COMPLETE_GHJ_N")
	)
	(segment
		(start 168.516808 0.794004)
		(end 168.516808 0.993648)
		(width 0.089408)
		(layer "In4.Cu")
		(net "FM_ADR_COMPLETE_GHJ_N")
	)
	(segment
		(start 177.224944 -2.226056)
		(end 173.752256 -2.226056)
		(width 0.089408)
		(layer "In4.Cu")
		(net "FM_ADR_COMPLETE_GHJ_N")
	)
	(segment
		(start 328.689208 -6.170168)
		(end 328.689208 -4.463288)
		(width 0.089408)
		(layer "In4.Cu")
		(net "FM_ADR_COMPLETE_GHJ_N")
	)
	(segment
		(start 179.7304 3.719322)
		(end 179.7304 0.635)
		(width 0.089408)
		(layer "In4.Cu")
		(net "FM_ADR_COMPLETE_GHJ_N")
	)
	(segment
		(start 167.753792 1.410208)
		(end 167.08755 2.07645)
		(width 0.089408)
		(layer "In4.Cu")
		(net "FM_ADR_COMPLETE_GHJ_N")
	)
	(segment
		(start 325.209408 3.48996)
		(end 325.291704 3.572256)
		(width 0.089408)
		(layer "In4.Cu")
		(net "FM_ADR_COMPLETE_GHJ_N")
	)
	(segment
		(start 329.006708 -15.748508)
		(end 329.006708 -6.487668)
		(width 0.089408)
		(layer "In4.Cu")
		(net "FM_ADR_COMPLETE_GHJ_N")
	)
	(segment
		(start 329.057 -4.095496)
		(end 329.057 -1.9558)
		(width 0.089408)
		(layer "In4.Cu")
		(net "FM_ADR_COMPLETE_GHJ_N")
	)
	(segment
		(start 327.4314 -0.3302)
		(end 326.3138 -0.3302)
		(width 0.089408)
		(layer "In4.Cu")
		(net "FM_ADR_COMPLETE_GHJ_N")
	)
	(segment
		(start 329.006708 -6.487668)
		(end 328.689208 -6.170168)
		(width 0.089408)
		(layer "In4.Cu")
		(net "FM_ADR_COMPLETE_GHJ_N")
	)
	(segment
		(start 325.291704 3.572256)
		(end 325.291704 4.273296)
		(width 0.089408)
		(layer "In4.Cu")
		(net "FM_ADR_COMPLETE_GHJ_N")
	)
	(segment
		(start 329.057 -1.9558)
		(end 327.4314 -0.3302)
		(width 0.089408)
		(layer "In4.Cu")
		(net "FM_ADR_COMPLETE_GHJ_N")
	)
	(segment
		(start 325.291704 4.273296)
		(end 324.066916 5.498084)
		(width 0.089408)
		(layer "In4.Cu")
		(net "FM_ADR_COMPLETE_GHJ_N")
	)
	(segment
		(start 170.530012 -1.2192)
		(end 168.516808 0.794004)
		(width 0.089408)
		(layer "In4.Cu")
		(net "FM_ADR_COMPLETE_GHJ_N")
	)
	(segment
		(start 168.516808 0.993648)
		(end 168.100248 1.410208)
		(width 0.089408)
		(layer "In4.Cu")
		(net "FM_ADR_COMPLETE_GHJ_N")
	)
	(segment
		(start 329.799188 -18.796)
		(end 329.774296 -18.796)
		(width 0.089408)
		(layer "In4.Cu")
		(net "FM_ADR_COMPLETE_GHJ_N")
	)
	(segment
		(start 173.752256 -2.226056)
		(end 172.7454 -1.2192)
		(width 0.089408)
		(layer "In4.Cu")
		(net "FM_ADR_COMPLETE_GHJ_N")
	)
	(segment
		(start 172.7454 -1.2192)
		(end 170.530012 -1.2192)
		(width 0.089408)
		(layer "In4.Cu")
		(net "FM_ADR_COMPLETE_GHJ_N")
	)
	(segment
		(start 167.08755 2.07645)
		(end 167.08755 4.987036)
		(width 0.089408)
		(layer "In4.Cu")
		(net "FM_ADR_COMPLETE_GHJ_N")
	)
	(segment
		(start 329.774296 -18.796)
		(end 329.336908 -18.358612)
		(width 0.089408)
		(layer "In4.Cu")
		(net "FM_ADR_COMPLETE_GHJ_N")
	)
	(segment
		(start 168.100248 1.410208)
		(end 167.753792 1.410208)
		(width 0.089408)
		(layer "In4.Cu")
		(net "FM_ADR_COMPLETE_GHJ_N")
	)
	(segment
		(start 181.509162 5.498084)
		(end 179.7304 3.719322)
		(width 0.089408)
		(layer "In4.Cu")
		(net "FM_ADR_COMPLETE_GHJ_N")
	)
	(segment
		(start 329.336908 -18.358612)
		(end 329.336908 -16.078708)
		(width 0.089408)
		(layer "In4.Cu")
		(net "FM_ADR_COMPLETE_GHJ_N")
	)
	(segment
		(start 326.3138 -0.3302)
		(end 325.209408 0.774192)
		(width 0.089408)
		(layer "In4.Cu")
		(net "FM_ADR_COMPLETE_GHJ_N")
	)
	(segment
		(start 324.066916 5.498084)
		(end 181.509162 5.498084)
		(width 0.089408)
		(layer "In4.Cu")
		(net "FM_ADR_COMPLETE_GHJ_N")
	)
	(segment
		(start 272.05051 -156.87294)
		(end 272.049748 -155.59024)
		(width 0.10795)
		(layer "F.Cu")
		(net "FM_ADR_COMPLETE_DEF_N")
	)
	(segment
		(start 272.05051 -148.773134)
		(end 272.050256 -148.773388)
		(width 0.10795)
		(layer "F.Cu")
		(net "FM_ADR_COMPLETE_DEF_N")
	)
	(segment
		(start 272.05051 -139.171934)
		(end 272.050256 -139.172188)
		(width 0.10795)
		(layer "F.Cu")
		(net "FM_ADR_COMPLETE_DEF_N")
	)
	(segment
		(start 324.612 -35.814)
		(end 324.612 -37.02812)
		(width 0.10795)
		(layer "F.Cu")
		(net "FM_ADR_COMPLETE_DEF_N")
	)
	(segment
		(start 272.05051 -147.27174)
		(end 272.05051 -148.773134)
		(width 0.10795)
		(layer "F.Cu")
		(net "FM_ADR_COMPLETE_DEF_N")
	)
	(segment
		(start 272.05051 -137.67054)
		(end 272.05051 -139.171934)
		(width 0.10795)
		(layer "F.Cu")
		(net "FM_ADR_COMPLETE_DEF_N")
	)
	(via
		(at 329.25893 -156.361384)
		(size 0.508)
		(drill 0.254)
		(layers "F.Cu" "B.Cu")
		(net "FM_ADR_COMPLETE_DEF_N")
	)
	(via
		(at 272.049748 -155.59024)
		(size 0.508)
		(drill 0.254)
		(layers "F.Cu" "B.Cu")
		(net "FM_ADR_COMPLETE_DEF_N")
	)
	(via
		(at 330.708 -71.7042)
		(size 0.6604)
		(drill 0.3302)
		(layers "F.Cu" "B.Cu")
		(net "FM_ADR_COMPLETE_DEF_N")
	)
	(via
		(at 324.612 -37.02812)
		(size 0.508)
		(drill 0.254)
		(layers "F.Cu" "B.Cu")
		(net "FM_ADR_COMPLETE_DEF_N")
	)
	(via
		(at 272.050256 -139.172188)
		(size 0.4572)
		(drill 0.2032)
		(layers "F.Cu" "B.Cu")
		(net "FM_ADR_COMPLETE_DEF_N")
	)
	(via
		(at 324.606412 -124.859034)
		(size 0.508)
		(drill 0.254)
		(layers "F.Cu" "B.Cu")
		(net "FM_ADR_COMPLETE_DEF_N")
	)
	(via
		(at 272.050256 -148.773388)
		(size 0.4572)
		(drill 0.2032)
		(layers "F.Cu" "B.Cu")
		(net "FM_ADR_COMPLETE_DEF_N")
	)
	(via
		(at 322.174616 -62.561216)
		(size 0.508)
		(drill 0.254)
		(layers "F.Cu" "B.Cu")
		(net "FM_ADR_COMPLETE_DEF_N")
	)
	(via
		(at 331.7113 -77.879194)
		(size 0.508)
		(drill 0.254)
		(layers "F.Cu" "B.Cu")
		(net "FM_ADR_COMPLETE_DEF_N")
	)
	(segment
		(start 265.108436 -140.589)
		(end 265.684 -140.013436)
		(width 0.10795)
		(layer "B.Cu")
		(net "FM_ADR_COMPLETE_DEF_N")
	)
	(segment
		(start 265.684 -149.987)
		(end 265.684 -149.352)
		(width 0.10795)
		(layer "B.Cu")
		(net "FM_ADR_COMPLETE_DEF_N")
	)
	(segment
		(start 330.708 -74.449178)
		(end 331.396848 -75.138026)
		(width 0.10795)
		(layer "B.Cu")
		(net "FM_ADR_COMPLETE_DEF_N")
	)
	(segment
		(start 265.684 -139.857734)
		(end 265.883136 -139.658598)
		(width 0.10795)
		(layer "B.Cu")
		(net "FM_ADR_COMPLETE_DEF_N")
	)
	(segment
		(start 271.663922 -130.2512)
		(end 271.0434 -130.2512)
		(width 0.10795)
		(layer "B.Cu")
		(net "FM_ADR_COMPLETE_DEF_N")
	)
	(segment
		(start 264.7823 -134.4041)
		(end 264.7823 -136.3599)
		(width 0.10795)
		(layer "B.Cu")
		(net "FM_ADR_COMPLETE_DEF_N")
	)
	(segment
		(start 272.05051 -147.478496)
		(end 272.05051 -148.773134)
		(width 0.10795)
		(layer "B.Cu")
		(net "FM_ADR_COMPLETE_DEF_N")
	)
	(segment
		(start 272.050256 -139.172188)
		(end 272.05051 -139.171934)
		(width 0.10795)
		(layer "B.Cu")
		(net "FM_ADR_COMPLETE_DEF_N")
	)
	(segment
		(start 315.616844 -157.692344)
		(end 314.599066 -156.674566)
		(width 0.10795)
		(layer "B.Cu")
		(net "FM_ADR_COMPLETE_DEF_N")
	)
	(segment
		(start 331.7113 -76.368148)
		(end 331.7113 -77.879194)
		(width 0.10795)
		(layer "B.Cu")
		(net "FM_ADR_COMPLETE_DEF_N")
	)
	(segment
		(start 276.886924 -155.167076)
		(end 276.479 -155.575)
		(width 0.10795)
		(layer "B.Cu")
		(net "FM_ADR_COMPLETE_DEF_N")
	)
	(segment
		(start 264.6934 -141.004036)
		(end 264.6934 -143.7259)
		(width 0.10795)
		(layer "B.Cu")
		(net "FM_ADR_COMPLETE_DEF_N")
	)
	(segment
		(start 279.5778 -154.5844)
		(end 279.022556 -155.139644)
		(width 0.10795)
		(layer "B.Cu")
		(net "FM_ADR_COMPLETE_DEF_N")
	)
	(segment
		(start 264.7823 -136.3599)
		(end 264.6934 -136.4488)
		(width 0.10795)
		(layer "B.Cu")
		(net "FM_ADR_COMPLETE_DEF_N")
	)
	(segment
		(start 267.589 -154.432)
		(end 267.208 -154.813)
		(width 0.10795)
		(layer "B.Cu")
		(net "FM_ADR_COMPLETE_DEF_N")
	)
	(segment
		(start 264.795 -143.8275)
		(end 264.795 -146.1008)
		(width 0.10795)
		(layer "B.Cu")
		(net "FM_ADR_COMPLETE_DEF_N")
	)
	(segment
		(start 265.684 -140.013436)
		(end 265.684 -139.857734)
		(width 0.10795)
		(layer "B.Cu")
		(net "FM_ADR_COMPLETE_DEF_N")
	)
	(segment
		(start 272.049748 -155.59024)
		(end 272.049748 -155.082748)
		(width 0.10795)
		(layer "B.Cu")
		(net "FM_ADR_COMPLETE_DEF_N")
	)
	(segment
		(start 270.637 -154.813)
		(end 270.004794 -154.813)
		(width 0.10795)
		(layer "B.Cu")
		(net "FM_ADR_COMPLETE_DEF_N")
	)
	(segment
		(start 329.25893 -156.361384)
		(end 326.721216 -156.361384)
		(width 0.10795)
		(layer "B.Cu")
		(net "FM_ADR_COMPLETE_DEF_N")
	)
	(segment
		(start 268.478 -154.813)
		(end 268.097 -154.432)
		(width 0.10795)
		(layer "B.Cu")
		(net "FM_ADR_COMPLETE_DEF_N")
	)
	(segment
		(start 276.479 -155.575)
		(end 276.098 -155.575)
		(width 0.10795)
		(layer "B.Cu")
		(net "FM_ADR_COMPLETE_DEF_N")
	)
	(segment
		(start 264.6934 -131.5974)
		(end 264.6934 -134.3152)
		(width 0.10795)
		(layer "B.Cu")
		(net "FM_ADR_COMPLETE_DEF_N")
	)
	(segment
		(start 276.098 -155.575)
		(end 274.955 -154.432)
		(width 0.10795)
		(layer "B.Cu")
		(net "FM_ADR_COMPLETE_DEF_N")
	)
	(segment
		(start 264.795 -146.1008)
		(end 264.541 -146.3548)
		(width 0.10795)
		(layer "B.Cu")
		(net "FM_ADR_COMPLETE_DEF_N")
	)
	(segment
		(start 270.6116 -130.683)
		(end 270.1544 -130.683)
		(width 0.10795)
		(layer "B.Cu")
		(net "FM_ADR_COMPLETE_DEF_N")
	)
	(segment
		(start 272.074386 -155.614878)
		(end 272.049748 -155.59024)
		(width 0.10795)
		(layer "B.Cu")
		(net "FM_ADR_COMPLETE_DEF_N")
	)
	(segment
		(start 322.267834 -62.654434)
		(end 322.174616 -62.561216)
		(width 0.10795)
		(layer "B.Cu")
		(net "FM_ADR_COMPLETE_DEF_N")
	)
	(segment
		(start 269.623794 -154.432)
		(end 269.367 -154.432)
		(width 0.10795)
		(layer "B.Cu")
		(net "FM_ADR_COMPLETE_DEF_N")
	)
	(segment
		(start 272.05051 -128.276096)
		(end 272.050002 -128.276604)
		(width 0.10795)
		(layer "B.Cu")
		(net "FM_ADR_COMPLETE_DEF_N")
	)
	(segment
		(start 268.3764 -130.7592)
		(end 267.9446 -130.3274)
		(width 0.10795)
		(layer "B.Cu")
		(net "FM_ADR_COMPLETE_DEF_N")
	)
	(segment
		(start 265.108436 -140.589)
		(end 264.6934 -141.004036)
		(width 0.10795)
		(layer "B.Cu")
		(net "FM_ADR_COMPLETE_DEF_N")
	)
	(segment
		(start 264.69594 -148.702268)
		(end 264.69594 -149.888448)
		(width 0.10795)
		(layer "B.Cu")
		(net "FM_ADR_COMPLETE_DEF_N")
	)
	(segment
		(start 269.748 -130.2766)
		(end 269.4178 -130.2766)
		(width 0.10795)
		(layer "B.Cu")
		(net "FM_ADR_COMPLETE_DEF_N")
	)
	(segment
		(start 277.868888 -155.3718)
		(end 277.664164 -155.167076)
		(width 0.10795)
		(layer "B.Cu")
		(net "FM_ADR_COMPLETE_DEF_N")
	)
	(segment
		(start 264.541 -148.547328)
		(end 264.69594 -148.702268)
		(width 0.10795)
		(layer "B.Cu")
		(net "FM_ADR_COMPLETE_DEF_N")
	)
	(segment
		(start 264.6934 -134.3152)
		(end 264.7823 -134.4041)
		(width 0.10795)
		(layer "B.Cu")
		(net "FM_ADR_COMPLETE_DEF_N")
	)
	(segment
		(start 270.004794 -154.813)
		(end 269.623794 -154.432)
		(width 0.10795)
		(layer "B.Cu")
		(net "FM_ADR_COMPLETE_DEF_N")
	)
	(segment
		(start 331.396848 -75.51928)
		(end 331.306932 -75.609196)
		(width 0.10795)
		(layer "B.Cu")
		(net "FM_ADR_COMPLETE_DEF_N")
	)
	(segment
		(start 265.938 -154.432)
		(end 265.557 -154.813)
		(width 0.10795)
		(layer "B.Cu")
		(net "FM_ADR_COMPLETE_DEF_N")
	)
	(segment
		(start 267.208 -130.7084)
		(end 266.6746 -130.7084)
		(width 0.10795)
		(layer "B.Cu")
		(net "FM_ADR_COMPLETE_DEF_N")
	)
	(segment
		(start 266.7 -154.813)
		(end 266.319 -154.432)
		(width 0.10795)
		(layer "B.Cu")
		(net "FM_ADR_COMPLETE_DEF_N")
	)
	(segment
		(start 314.599066 -156.674566)
		(end 283.496766 -156.674566)
		(width 0.10795)
		(layer "B.Cu")
		(net "FM_ADR_COMPLETE_DEF_N")
	)
	(segment
		(start 271.018 -154.432)
		(end 270.637 -154.813)
		(width 0.10795)
		(layer "B.Cu")
		(net "FM_ADR_COMPLETE_DEF_N")
	)
	(segment
		(start 282.5242 -155.702)
		(end 282.5242 -154.7114)
		(width 0.10795)
		(layer "B.Cu")
		(net "FM_ADR_COMPLETE_DEF_N")
	)
	(segment
		(start 271.563846 -139.658598)
		(end 272.050256 -139.172188)
		(width 0.10795)
		(layer "B.Cu")
		(net "FM_ADR_COMPLETE_DEF_N")
	)
	(segment
		(start 325.126604 -64.116966)
		(end 324.41769 -64.116966)
		(width 0.10795)
		(layer "B.Cu")
		(net "FM_ADR_COMPLETE_DEF_N")
	)
	(segment
		(start 331.396848 -75.138026)
		(end 331.396848 -75.51928)
		(width 0.10795)
		(layer "B.Cu")
		(net "FM_ADR_COMPLETE_DEF_N")
	)
	(segment
		(start 267.9446 -130.3274)
		(end 267.589 -130.3274)
		(width 0.10795)
		(layer "B.Cu")
		(net "FM_ADR_COMPLETE_DEF_N")
	)
	(segment
		(start 282.5242 -154.7114)
		(end 282.3972 -154.5844)
		(width 0.10795)
		(layer "B.Cu")
		(net "FM_ADR_COMPLETE_DEF_N")
	)
	(segment
		(start 271.598644 -149.225)
		(end 272.050256 -148.773388)
		(width 0.10795)
		(layer "B.Cu")
		(net "FM_ADR_COMPLETE_DEF_N")
	)
	(segment
		(start 272.050002 -129.86512)
		(end 271.663922 -130.2512)
		(width 0.10795)
		(layer "B.Cu")
		(net "FM_ADR_COMPLETE_DEF_N")
	)
	(segment
		(start 270.1544 -130.683)
		(end 269.748 -130.2766)
		(width 0.10795)
		(layer "B.Cu")
		(net "FM_ADR_COMPLETE_DEF_N")
	)
	(segment
		(start 268.097 -154.432)
		(end 267.589 -154.432)
		(width 0.10795)
		(layer "B.Cu")
		(net "FM_ADR_COMPLETE_DEF_N")
	)
	(segment
		(start 264.541 -146.3548)
		(end 264.541 -148.547328)
		(width 0.10795)
		(layer "B.Cu")
		(net "FM_ADR_COMPLETE_DEF_N")
	)
	(segment
		(start 278.2316 -155.3718)
		(end 277.868888 -155.3718)
		(width 0.10795)
		(layer "B.Cu")
		(net "FM_ADR_COMPLETE_DEF_N")
	)
	(segment
		(start 268.9352 -130.7592)
		(end 268.3764 -130.7592)
		(width 0.10795)
		(layer "B.Cu")
		(net "FM_ADR_COMPLETE_DEF_N")
	)
	(segment
		(start 266.6746 -130.7084)
		(end 266.3698 -130.4036)
		(width 0.10795)
		(layer "B.Cu")
		(net "FM_ADR_COMPLETE_DEF_N")
	)
	(segment
		(start 264.6934 -143.7259)
		(end 264.795 -143.8275)
		(width 0.10795)
		(layer "B.Cu")
		(net "FM_ADR_COMPLETE_DEF_N")
	)
	(segment
		(start 272.049748 -155.082748)
		(end 271.399 -154.432)
		(width 0.10795)
		(layer "B.Cu")
		(net "FM_ADR_COMPLETE_DEF_N")
	)
	(segment
		(start 277.664164 -155.167076)
		(end 276.886924 -155.167076)
		(width 0.10795)
		(layer "B.Cu")
		(net "FM_ADR_COMPLETE_DEF_N")
	)
	(segment
		(start 264.795 -150.5966)
		(end 265.099546 -150.292054)
		(width 0.10795)
		(layer "B.Cu")
		(net "FM_ADR_COMPLETE_DEF_N")
	)
	(segment
		(start 283.496766 -156.674566)
		(end 282.5242 -155.702)
		(width 0.10795)
		(layer "B.Cu")
		(net "FM_ADR_COMPLETE_DEF_N")
	)
	(segment
		(start 269.4178 -130.2766)
		(end 268.9352 -130.7592)
		(width 0.10795)
		(layer "B.Cu")
		(net "FM_ADR_COMPLETE_DEF_N")
	)
	(segment
		(start 265.378946 -150.292054)
		(end 265.684 -149.987)
		(width 0.10795)
		(layer "B.Cu")
		(net "FM_ADR_COMPLETE_DEF_N")
	)
	(segment
		(start 272.05051 -148.773134)
		(end 272.050256 -148.773388)
		(width 0.10795)
		(layer "B.Cu")
		(net "FM_ADR_COMPLETE_DEF_N")
	)
	(segment
		(start 272.883122 -155.614878)
		(end 272.074386 -155.614878)
		(width 0.10795)
		(layer "B.Cu")
		(net "FM_ADR_COMPLETE_DEF_N")
	)
	(segment
		(start 265.684 -149.352)
		(end 265.811 -149.225)
		(width 0.10795)
		(layer "B.Cu")
		(net "FM_ADR_COMPLETE_DEF_N")
	)
	(segment
		(start 264.795 -140.275564)
		(end 265.108436 -140.589)
		(width 0.10795)
		(layer "B.Cu")
		(net "FM_ADR_COMPLETE_DEF_N")
	)
	(segment
		(start 264.6934 -138.9761)
		(end 264.795 -139.0777)
		(width 0.10795)
		(layer "B.Cu")
		(net "FM_ADR_COMPLETE_DEF_N")
	)
	(segment
		(start 330.708 -71.7042)
		(end 330.708 -69.698362)
		(width 0.10795)
		(layer "B.Cu")
		(net "FM_ADR_COMPLETE_DEF_N")
	)
	(segment
		(start 272.050002 -128.276604)
		(end 272.050002 -129.86512)
		(width 0.10795)
		(layer "B.Cu")
		(net "FM_ADR_COMPLETE_DEF_N")
	)
	(segment
		(start 267.208 -154.813)
		(end 266.7 -154.813)
		(width 0.10795)
		(layer "B.Cu")
		(net "FM_ADR_COMPLETE_DEF_N")
	)
	(segment
		(start 326.721216 -156.361384)
		(end 325.390256 -157.692344)
		(width 0.10795)
		(layer "B.Cu")
		(net "FM_ADR_COMPLETE_DEF_N")
	)
	(segment
		(start 264.926318 -154.813)
		(end 264.795 -154.681682)
		(width 0.10795)
		(layer "B.Cu")
		(net "FM_ADR_COMPLETE_DEF_N")
	)
	(segment
		(start 282.3972 -154.5844)
		(end 279.5778 -154.5844)
		(width 0.10795)
		(layer "B.Cu")
		(net "FM_ADR_COMPLETE_DEF_N")
	)
	(segment
		(start 273.558 -154.94)
		(end 272.883122 -155.614878)
		(width 0.10795)
		(layer "B.Cu")
		(net "FM_ADR_COMPLETE_DEF_N")
	)
	(segment
		(start 266.3698 -130.4036)
		(end 265.8872 -130.4036)
		(width 0.10795)
		(layer "B.Cu")
		(net "FM_ADR_COMPLETE_DEF_N")
	)
	(segment
		(start 265.8872 -130.4036)
		(end 264.6934 -131.5974)
		(width 0.10795)
		(layer "B.Cu")
		(net "FM_ADR_COMPLETE_DEF_N")
	)
	(segment
		(start 265.883136 -139.658598)
		(end 271.563846 -139.658598)
		(width 0.10795)
		(layer "B.Cu")
		(net "FM_ADR_COMPLETE_DEF_N")
	)
	(segment
		(start 271.399 -154.432)
		(end 271.018 -154.432)
		(width 0.10795)
		(layer "B.Cu")
		(net "FM_ADR_COMPLETE_DEF_N")
	)
	(segment
		(start 325.390256 -157.692344)
		(end 315.616844 -157.692344)
		(width 0.10795)
		(layer "B.Cu")
		(net "FM_ADR_COMPLETE_DEF_N")
	)
	(segment
		(start 265.811 -149.225)
		(end 271.598644 -149.225)
		(width 0.10795)
		(layer "B.Cu")
		(net "FM_ADR_COMPLETE_DEF_N")
	)
	(segment
		(start 271.0434 -130.2512)
		(end 270.6116 -130.683)
		(width 0.10795)
		(layer "B.Cu")
		(net "FM_ADR_COMPLETE_DEF_N")
	)
	(segment
		(start 330.708 -71.7042)
		(end 330.708 -74.449178)
		(width 0.10795)
		(layer "B.Cu")
		(net "FM_ADR_COMPLETE_DEF_N")
	)
	(segment
		(start 272.05051 -139.171934)
		(end 272.05051 -137.877296)
		(width 0.10795)
		(layer "B.Cu")
		(net "FM_ADR_COMPLETE_DEF_N")
	)
	(segment
		(start 278.463756 -155.139644)
		(end 278.2316 -155.3718)
		(width 0.10795)
		(layer "B.Cu")
		(net "FM_ADR_COMPLETE_DEF_N")
	)
	(segment
		(start 274.32 -154.432)
		(end 273.812 -154.94)
		(width 0.10795)
		(layer "B.Cu")
		(net "FM_ADR_COMPLETE_DEF_N")
	)
	(segment
		(start 274.955 -154.432)
		(end 274.32 -154.432)
		(width 0.10795)
		(layer "B.Cu")
		(net "FM_ADR_COMPLETE_DEF_N")
	)
	(segment
		(start 264.795 -154.681682)
		(end 264.795 -150.5966)
		(width 0.10795)
		(layer "B.Cu")
		(net "FM_ADR_COMPLETE_DEF_N")
	)
	(segment
		(start 331.306932 -75.96378)
		(end 331.7113 -76.368148)
		(width 0.10795)
		(layer "B.Cu")
		(net "FM_ADR_COMPLETE_DEF_N")
	)
	(segment
		(start 264.6934 -136.4488)
		(end 264.6934 -138.9761)
		(width 0.10795)
		(layer "B.Cu")
		(net "FM_ADR_COMPLETE_DEF_N")
	)
	(segment
		(start 269.367 -154.432)
		(end 268.986 -154.813)
		(width 0.10795)
		(layer "B.Cu")
		(net "FM_ADR_COMPLETE_DEF_N")
	)
	(segment
		(start 322.955158 -62.654434)
		(end 322.267834 -62.654434)
		(width 0.10795)
		(layer "B.Cu")
		(net "FM_ADR_COMPLETE_DEF_N")
	)
	(segment
		(start 267.589 -130.3274)
		(end 267.208 -130.7084)
		(width 0.10795)
		(layer "B.Cu")
		(net "FM_ADR_COMPLETE_DEF_N")
	)
	(segment
		(start 268.986 -154.813)
		(end 268.478 -154.813)
		(width 0.10795)
		(layer "B.Cu")
		(net "FM_ADR_COMPLETE_DEF_N")
	)
	(segment
		(start 265.557 -154.813)
		(end 264.926318 -154.813)
		(width 0.10795)
		(layer "B.Cu")
		(net "FM_ADR_COMPLETE_DEF_N")
	)
	(segment
		(start 279.022556 -155.139644)
		(end 278.463756 -155.139644)
		(width 0.10795)
		(layer "B.Cu")
		(net "FM_ADR_COMPLETE_DEF_N")
	)
	(segment
		(start 324.41769 -64.116966)
		(end 322.955158 -62.654434)
		(width 0.10795)
		(layer "B.Cu")
		(net "FM_ADR_COMPLETE_DEF_N")
	)
	(segment
		(start 330.708 -69.698362)
		(end 325.126604 -64.116966)
		(width 0.10795)
		(layer "B.Cu")
		(net "FM_ADR_COMPLETE_DEF_N")
	)
	(segment
		(start 266.319 -154.432)
		(end 265.938 -154.432)
		(width 0.10795)
		(layer "B.Cu")
		(net "FM_ADR_COMPLETE_DEF_N")
	)
	(segment
		(start 264.795 -139.0777)
		(end 264.795 -140.275564)
		(width 0.10795)
		(layer "B.Cu")
		(net "FM_ADR_COMPLETE_DEF_N")
	)
	(segment
		(start 331.306932 -75.609196)
		(end 331.306932 -75.96378)
		(width 0.10795)
		(layer "B.Cu")
		(net "FM_ADR_COMPLETE_DEF_N")
	)
	(segment
		(start 265.099546 -150.292054)
		(end 265.378946 -150.292054)
		(width 0.10795)
		(layer "B.Cu")
		(net "FM_ADR_COMPLETE_DEF_N")
	)
	(segment
		(start 264.69594 -149.888448)
		(end 265.099546 -150.292054)
		(width 0.10795)
		(layer "B.Cu")
		(net "FM_ADR_COMPLETE_DEF_N")
	)
	(segment
		(start 273.812 -154.94)
		(end 273.558 -154.94)
		(width 0.10795)
		(layer "B.Cu")
		(net "FM_ADR_COMPLETE_DEF_N")
	)
	(segment
		(start 322.961 -134.349998)
		(end 322.961 -140.49248)
		(width 0.089408)
		(layer "In2.Cu")
		(net "FM_ADR_COMPLETE_DEF_N")
	)
	(segment
		(start 324.606412 -124.859034)
		(end 324.608698 -124.859034)
		(width 0.089408)
		(layer "In2.Cu")
		(net "FM_ADR_COMPLETE_DEF_N")
	)
	(segment
		(start 324.608698 -124.859034)
		(end 324.608698 -124.856748)
		(width 0.089408)
		(layer "In2.Cu")
		(net "FM_ADR_COMPLETE_DEF_N")
	)
	(segment
		(start 329.416664 -155.507182)
		(end 329.61072 -155.701238)
		(width 0.089408)
		(layer "In2.Cu")
		(net "FM_ADR_COMPLETE_DEF_N")
	)
	(segment
		(start 322.961 -140.49248)
		(end 324.14718 -141.67866)
		(width 0.089408)
		(layer "In2.Cu")
		(net "FM_ADR_COMPLETE_DEF_N")
	)
	(segment
		(start 321.933062 -133.32206)
		(end 322.961 -134.349998)
		(width 0.089408)
		(layer "In2.Cu")
		(net "FM_ADR_COMPLETE_DEF_N")
	)
	(segment
		(start 320.46926 -133.32206)
		(end 321.933062 -133.32206)
		(width 0.089408)
		(layer "In2.Cu")
		(net "FM_ADR_COMPLETE_DEF_N")
	)
	(segment
		(start 320.07302 -132.92582)
		(end 320.46926 -133.32206)
		(width 0.089408)
		(layer "In2.Cu")
		(net "FM_ADR_COMPLETE_DEF_N")
	)
	(segment
		(start 324.14718 -141.67866)
		(end 324.14718 -150.449534)
		(width 0.089408)
		(layer "In2.Cu")
		(net "FM_ADR_COMPLETE_DEF_N")
	)
	(segment
		(start 324.608698 -124.856748)
		(end 324.362826 -124.856748)
		(width 0.089408)
		(layer "In2.Cu")
		(net "FM_ADR_COMPLETE_DEF_N")
	)
	(segment
		(start 326.486774 -152.789128)
		(end 327.744328 -152.789128)
		(width 0.089408)
		(layer "In2.Cu")
		(net "FM_ADR_COMPLETE_DEF_N")
	)
	(segment
		(start 329.416664 -154.461464)
		(end 329.416664 -155.507182)
		(width 0.089408)
		(layer "In2.Cu")
		(net "FM_ADR_COMPLETE_DEF_N")
	)
	(segment
		(start 324.303898 -124.79782)
		(end 320.63182 -124.79782)
		(width 0.089408)
		(layer "In2.Cu")
		(net "FM_ADR_COMPLETE_DEF_N")
	)
	(segment
		(start 327.744328 -152.789128)
		(end 329.416664 -154.461464)
		(width 0.089408)
		(layer "In2.Cu")
		(net "FM_ADR_COMPLETE_DEF_N")
	)
	(segment
		(start 324.14718 -150.449534)
		(end 326.486774 -152.789128)
		(width 0.089408)
		(layer "In2.Cu")
		(net "FM_ADR_COMPLETE_DEF_N")
	)
	(segment
		(start 320.63182 -124.79782)
		(end 319.4304 -125.99924)
		(width 0.089408)
		(layer "In2.Cu")
		(net "FM_ADR_COMPLETE_DEF_N")
	)
	(segment
		(start 319.4304 -125.99924)
		(end 319.4304 -128.23698)
		(width 0.089408)
		(layer "In2.Cu")
		(net "FM_ADR_COMPLETE_DEF_N")
	)
	(segment
		(start 329.61072 -156.009594)
		(end 329.25893 -156.361384)
		(width 0.089408)
		(layer "In2.Cu")
		(net "FM_ADR_COMPLETE_DEF_N")
	)
	(segment
		(start 319.4304 -128.23698)
		(end 320.07302 -128.8796)
		(width 0.089408)
		(layer "In2.Cu")
		(net "FM_ADR_COMPLETE_DEF_N")
	)
	(segment
		(start 329.61072 -155.701238)
		(end 329.61072 -156.009594)
		(width 0.089408)
		(layer "In2.Cu")
		(net "FM_ADR_COMPLETE_DEF_N")
	)
	(segment
		(start 324.362826 -124.856748)
		(end 324.303898 -124.79782)
		(width 0.089408)
		(layer "In2.Cu")
		(net "FM_ADR_COMPLETE_DEF_N")
	)
	(segment
		(start 320.07302 -128.8796)
		(end 320.07302 -132.92582)
		(width 0.089408)
		(layer "In2.Cu")
		(net "FM_ADR_COMPLETE_DEF_N")
	)
	(segment
		(start 324.608698 -124.859034)
		(end 324.606412 -124.859034)
		(width 0.089408)
		(layer "In4.Cu")
		(net "FM_ADR_COMPLETE_DEF_N")
	)
	(segment
		(start 329.53198 -84.13242)
		(end 322.382896 -91.281504)
		(width 0.089408)
		(layer "In4.Cu")
		(net "FM_ADR_COMPLETE_DEF_N")
	)
	(segment
		(start 329.53198 -82.344006)
		(end 329.53198 -84.13242)
		(width 0.089408)
		(layer "In4.Cu")
		(net "FM_ADR_COMPLETE_DEF_N")
	)
	(segment
		(start 324.608698 -124.856748)
		(end 324.608698 -124.859034)
		(width 0.089408)
		(layer "In4.Cu")
		(net "FM_ADR_COMPLETE_DEF_N")
	)
	(segment
		(start 324.40245 -119.32031)
		(end 324.40245 -124.6505)
		(width 0.089408)
		(layer "In4.Cu")
		(net "FM_ADR_COMPLETE_DEF_N")
	)
	(segment
		(start 324.40245 -124.6505)
		(end 324.608698 -124.856748)
		(width 0.089408)
		(layer "In4.Cu")
		(net "FM_ADR_COMPLETE_DEF_N")
	)
	(segment
		(start 323.721222 -116.779294)
		(end 323.721222 -118.639082)
		(width 0.089408)
		(layer "In4.Cu")
		(net "FM_ADR_COMPLETE_DEF_N")
	)
	(segment
		(start 332.14437 -78.312264)
		(end 332.14437 -79.731616)
		(width 0.089408)
		(layer "In4.Cu")
		(net "FM_ADR_COMPLETE_DEF_N")
	)
	(segment
		(start 332.14437 -79.731616)
		(end 329.53198 -82.344006)
		(width 0.089408)
		(layer "In4.Cu")
		(net "FM_ADR_COMPLETE_DEF_N")
	)
	(segment
		(start 322.382896 -99.25558)
		(end 322.18249 -99.455986)
		(width 0.089408)
		(layer "In4.Cu")
		(net "FM_ADR_COMPLETE_DEF_N")
	)
	(segment
		(start 331.7113 -77.879194)
		(end 332.14437 -78.312264)
		(width 0.089408)
		(layer "In4.Cu")
		(net "FM_ADR_COMPLETE_DEF_N")
	)
	(segment
		(start 322.18249 -99.455986)
		(end 322.18249 -115.240562)
		(width 0.089408)
		(layer "In4.Cu")
		(net "FM_ADR_COMPLETE_DEF_N")
	)
	(segment
		(start 322.382896 -91.531948)
		(end 322.382896 -99.25558)
		(width 0.089408)
		(layer "In4.Cu")
		(net "FM_ADR_COMPLETE_DEF_N")
	)
	(segment
		(start 322.18249 -115.240562)
		(end 323.721222 -116.779294)
		(width 0.089408)
		(layer "In4.Cu")
		(net "FM_ADR_COMPLETE_DEF_N")
	)
	(segment
		(start 322.382642 -91.531694)
		(end 322.382896 -91.531948)
		(width 0.089408)
		(layer "In4.Cu")
		(net "FM_ADR_COMPLETE_DEF_N")
	)
	(segment
		(start 323.721222 -118.639082)
		(end 324.40245 -119.32031)
		(width 0.089408)
		(layer "In4.Cu")
		(net "FM_ADR_COMPLETE_DEF_N")
	)
	(segment
		(start 322.382642 -91.373706)
		(end 322.382642 -91.531694)
		(width 0.089408)
		(layer "In4.Cu")
		(net "FM_ADR_COMPLETE_DEF_N")
	)
	(segment
		(start 322.382896 -91.281504)
		(end 322.382896 -91.373198)
		(width 0.089408)
		(layer "In4.Cu")
		(net "FM_ADR_COMPLETE_DEF_N")
	)
	(segment
		(start 322.382896 -91.373198)
		(end 322.382642 -91.373706)
		(width 0.089408)
		(layer "In4.Cu")
		(net "FM_ADR_COMPLETE_DEF_N")
	)
	(segment
		(start 322.174616 -62.561216)
		(end 319.954656 -62.561216)
		(width 0.089408)
		(layer "In9.Cu")
		(net "FM_ADR_COMPLETE_DEF_N")
	)
	(segment
		(start 325.177658 -37.392356)
		(end 324.813422 -37.02812)
		(width 0.089408)
		(layer "In9.Cu")
		(net "FM_ADR_COMPLETE_DEF_N")
	)
	(segment
		(start 324.51167 -39.575994)
		(end 325.177658 -38.910006)
		(width 0.089408)
		(layer "In9.Cu")
		(net "FM_ADR_COMPLETE_DEF_N")
	)
	(segment
		(start 318.366648 -47.079408)
		(end 321.001644 -47.079408)
		(width 0.089408)
		(layer "In9.Cu")
		(net "FM_ADR_COMPLETE_DEF_N")
	)
	(segment
		(start 313.677808 -51.768248)
		(end 318.366648 -47.079408)
		(width 0.089408)
		(layer "In9.Cu")
		(net "FM_ADR_COMPLETE_DEF_N")
	)
	(segment
		(start 313.677808 -56.284368)
		(end 313.677808 -51.768248)
		(width 0.089408)
		(layer "In9.Cu")
		(net "FM_ADR_COMPLETE_DEF_N")
	)
	(segment
		(start 324.813422 -37.02812)
		(end 324.612 -37.02812)
		(width 0.089408)
		(layer "In9.Cu")
		(net "FM_ADR_COMPLETE_DEF_N")
	)
	(segment
		(start 321.001644 -47.079408)
		(end 324.51167 -43.569382)
		(width 0.089408)
		(layer "In9.Cu")
		(net "FM_ADR_COMPLETE_DEF_N")
	)
	(segment
		(start 325.177658 -38.910006)
		(end 325.177658 -37.392356)
		(width 0.089408)
		(layer "In9.Cu")
		(net "FM_ADR_COMPLETE_DEF_N")
	)
	(segment
		(start 324.51167 -43.569382)
		(end 324.51167 -39.575994)
		(width 0.089408)
		(layer "In9.Cu")
		(net "FM_ADR_COMPLETE_DEF_N")
	)
	(segment
		(start 319.954656 -62.561216)
		(end 313.677808 -56.284368)
		(width 0.089408)
		(layer "In9.Cu")
		(net "FM_ADR_COMPLETE_DEF_N")
	)
	(segment
		(start 272.050256 -18.734278)
		(end 272.050002 -18.734532)
		(width 0.10795)
		(layer "F.Cu")
		(net "FM_ADR_COMPLETE_ABC_N")
	)
	(segment
		(start 324.496938 -33.718246)
		(end 324.612 -33.833308)
		(width 0.10795)
		(layer "F.Cu")
		(net "FM_ADR_COMPLETE_ABC_N")
	)
	(segment
		(start 272.050002 -10.422382)
		(end 272.050002 -11.917934)
		(width 0.10795)
		(layer "F.Cu")
		(net "FM_ADR_COMPLETE_ABC_N")
	)
	(segment
		(start 272.05051 -10.422382)
		(end 272.050002 -10.422382)
		(width 0.10795)
		(layer "F.Cu")
		(net "FM_ADR_COMPLETE_ABC_N")
	)
	(segment
		(start 265.2014 -13.8938)
		(end 264.795 -14.3002)
		(width 0.10795)
		(layer "F.Cu")
		(net "FM_ADR_COMPLETE_ABC_N")
	)
	(segment
		(start 272.05051 -0.821182)
		(end 272.049748 0.461518)
		(width 0.10795)
		(layer "F.Cu")
		(net "FM_ADR_COMPLETE_ABC_N")
	)
	(segment
		(start 272.050002 -18.734532)
		(end 272.050002 -20.023582)
		(width 0.10795)
		(layer "F.Cu")
		(net "FM_ADR_COMPLETE_ABC_N")
	)
	(segment
		(start 272.050002 -11.917934)
		(end 272.050256 -11.918188)
		(width 0.10795)
		(layer "F.Cu")
		(net "FM_ADR_COMPLETE_ABC_N")
	)
	(segment
		(start 264.795 -18.001488)
		(end 265.024108 -18.230596)
		(width 0.10795)
		(layer "F.Cu")
		(net "FM_ADR_COMPLETE_ABC_N")
	)
	(segment
		(start 324.612 -33.833308)
		(end 324.612 -34.163)
		(width 0.10795)
		(layer "F.Cu")
		(net "FM_ADR_COMPLETE_ABC_N")
	)
	(segment
		(start 272.050002 -20.023582)
		(end 272.05051 -20.023582)
		(width 0.10795)
		(layer "F.Cu")
		(net "FM_ADR_COMPLETE_ABC_N")
	)
	(segment
		(start 271.546574 -18.230596)
		(end 272.050256 -18.734278)
		(width 0.10795)
		(layer "F.Cu")
		(net "FM_ADR_COMPLETE_ABC_N")
	)
	(segment
		(start 264.795 -14.3002)
		(end 264.795 -18.001488)
		(width 0.10795)
		(layer "F.Cu")
		(net "FM_ADR_COMPLETE_ABC_N")
	)
	(segment
		(start 321.193668 -33.718246)
		(end 324.496938 -33.718246)
		(width 0.10795)
		(layer "F.Cu")
		(net "FM_ADR_COMPLETE_ABC_N")
	)
	(segment
		(start 265.024108 -18.230596)
		(end 271.546574 -18.230596)
		(width 0.10795)
		(layer "F.Cu")
		(net "FM_ADR_COMPLETE_ABC_N")
	)
	(segment
		(start 321.004692 -33.907222)
		(end 321.193668 -33.718246)
		(width 0.10795)
		(layer "F.Cu")
		(net "FM_ADR_COMPLETE_ABC_N")
	)
	(via
		(at 272.050256 -2.316988)
		(size 0.4572)
		(drill 0.2032)
		(layers "F.Cu" "B.Cu")
		(net "FM_ADR_COMPLETE_ABC_N")
	)
	(via
		(at 272.050256 -18.734278)
		(size 0.4572)
		(drill 0.2032)
		(layers "F.Cu" "B.Cu")
		(net "FM_ADR_COMPLETE_ABC_N")
	)
	(via
		(at 272.050256 -11.918188)
		(size 0.4572)
		(drill 0.2032)
		(layers "F.Cu" "B.Cu")
		(net "FM_ADR_COMPLETE_ABC_N")
	)
	(via
		(at 272.049748 0.461518)
		(size 0.508)
		(drill 0.254)
		(layers "F.Cu" "B.Cu")
		(net "FM_ADR_COMPLETE_ABC_N")
	)
	(via
		(at 321.004692 -33.907222)
		(size 0.508)
		(drill 0.254)
		(layers "F.Cu" "B.Cu")
		(net "FM_ADR_COMPLETE_ABC_N")
	)
	(via
		(at 265.2014 -13.8938)
		(size 0.508)
		(drill 0.254)
		(layers "F.Cu" "B.Cu")
		(net "FM_ADR_COMPLETE_ABC_N")
	)
	(segment
		(start 264.7188 0.635)
		(end 264.7188 -10.2362)
		(width 0.10795)
		(layer "B.Cu")
		(net "FM_ADR_COMPLETE_ABC_N")
	)
	(segment
		(start 265.9126 -12.3698)
		(end 271.598644 -12.3698)
		(width 0.10795)
		(layer "B.Cu")
		(net "FM_ADR_COMPLETE_ABC_N")
	)
	(segment
		(start 264.7188 -10.2362)
		(end 264.2743 -10.6807)
		(width 0.10795)
		(layer "B.Cu")
		(net "FM_ADR_COMPLETE_ABC_N")
	)
	(segment
		(start 269.7988 1.6764)
		(end 269.3416 1.6764)
		(width 0.10795)
		(layer "B.Cu")
		(net "FM_ADR_COMPLETE_ABC_N")
	)
	(segment
		(start 272.05051 -20.224242)
		(end 272.050002 -20.224242)
		(width 0.10795)
		(layer "B.Cu")
		(net "FM_ADR_COMPLETE_ABC_N")
	)
	(segment
		(start 272.050002 -1.021842)
		(end 272.050002 -2.316734)
		(width 0.10795)
		(layer "B.Cu")
		(net "FM_ADR_COMPLETE_ABC_N")
	)
	(segment
		(start 266.7254 1.27)
		(end 266.3952 1.6002)
		(width 0.10795)
		(layer "B.Cu")
		(net "FM_ADR_COMPLETE_ABC_N")
	)
	(segment
		(start 272.050002 -10.623042)
		(end 272.05051 -10.623042)
		(width 0.10795)
		(layer "B.Cu")
		(net "FM_ADR_COMPLETE_ABC_N")
	)
	(segment
		(start 270.6116 1.3208)
		(end 270.1544 1.3208)
		(width 0.10795)
		(layer "B.Cu")
		(net "FM_ADR_COMPLETE_ABC_N")
	)
	(segment
		(start 268.4272 1.27)
		(end 267.9954 1.7018)
		(width 0.10795)
		(layer "B.Cu")
		(net "FM_ADR_COMPLETE_ABC_N")
	)
	(segment
		(start 271.598644 -12.3698)
		(end 272.050256 -11.918188)
		(width 0.10795)
		(layer "B.Cu")
		(net "FM_ADR_COMPLETE_ABC_N")
	)
	(segment
		(start 267.6398 1.7018)
		(end 267.208 1.27)
		(width 0.10795)
		(layer "B.Cu")
		(net "FM_ADR_COMPLETE_ABC_N")
	)
	(segment
		(start 265.7348 -13.562076)
		(end 265.7348 -12.5476)
		(width 0.10795)
		(layer "B.Cu")
		(net "FM_ADR_COMPLETE_ABC_N")
	)
	(segment
		(start 264.795 -13.4874)
		(end 265.2014 -13.8938)
		(width 0.10795)
		(layer "B.Cu")
		(net "FM_ADR_COMPLETE_ABC_N")
	)
	(segment
		(start 267.9954 1.7018)
		(end 267.6398 1.7018)
		(width 0.10795)
		(layer "B.Cu")
		(net "FM_ADR_COMPLETE_ABC_N")
	)
	(segment
		(start 270.1544 1.3208)
		(end 269.7988 1.6764)
		(width 0.10795)
		(layer "B.Cu")
		(net "FM_ADR_COMPLETE_ABC_N")
	)
	(segment
		(start 272.049748 0.461518)
		(end 272.049748 1.025652)
		(width 0.10795)
		(layer "B.Cu")
		(net "FM_ADR_COMPLETE_ABC_N")
	)
	(segment
		(start 272.050256 -11.918188)
		(end 272.050002 -11.917934)
		(width 0.10795)
		(layer "B.Cu")
		(net "FM_ADR_COMPLETE_ABC_N")
	)
	(segment
		(start 269.3416 1.6764)
		(end 268.9352 1.27)
		(width 0.10795)
		(layer "B.Cu")
		(net "FM_ADR_COMPLETE_ABC_N")
	)
	(segment
		(start 266.3952 1.6002)
		(end 265.684 1.6002)
		(width 0.10795)
		(layer "B.Cu")
		(net "FM_ADR_COMPLETE_ABC_N")
	)
	(segment
		(start 265.7348 -12.5476)
		(end 265.9126 -12.3698)
		(width 0.10795)
		(layer "B.Cu")
		(net "FM_ADR_COMPLETE_ABC_N")
	)
	(segment
		(start 272.05051 -1.021842)
		(end 272.050002 -1.021842)
		(width 0.10795)
		(layer "B.Cu")
		(net "FM_ADR_COMPLETE_ABC_N")
	)
	(segment
		(start 268.9352 1.27)
		(end 268.4272 1.27)
		(width 0.10795)
		(layer "B.Cu")
		(net "FM_ADR_COMPLETE_ABC_N")
	)
	(segment
		(start 267.208 1.27)
		(end 266.7254 1.27)
		(width 0.10795)
		(layer "B.Cu")
		(net "FM_ADR_COMPLETE_ABC_N")
	)
	(segment
		(start 265.2014 -13.8938)
		(end 265.403076 -13.8938)
		(width 0.10795)
		(layer "B.Cu")
		(net "FM_ADR_COMPLETE_ABC_N")
	)
	(segment
		(start 264.2743 -11.2649)
		(end 264.795 -11.7856)
		(width 0.10795)
		(layer "B.Cu")
		(net "FM_ADR_COMPLETE_ABC_N")
	)
	(segment
		(start 265.684 1.6002)
		(end 264.7188 0.635)
		(width 0.10795)
		(layer "B.Cu")
		(net "FM_ADR_COMPLETE_ABC_N")
	)
	(segment
		(start 264.795 -11.7856)
		(end 264.795 -13.4874)
		(width 0.10795)
		(layer "B.Cu")
		(net "FM_ADR_COMPLETE_ABC_N")
	)
	(segment
		(start 272.049748 1.025652)
		(end 271.399 1.6764)
		(width 0.10795)
		(layer "B.Cu")
		(net "FM_ADR_COMPLETE_ABC_N")
	)
	(segment
		(start 264.2743 -10.6807)
		(end 264.2743 -11.2649)
		(width 0.10795)
		(layer "B.Cu")
		(net "FM_ADR_COMPLETE_ABC_N")
	)
	(segment
		(start 272.050002 -20.224242)
		(end 272.050002 -18.734532)
		(width 0.10795)
		(layer "B.Cu")
		(net "FM_ADR_COMPLETE_ABC_N")
	)
	(segment
		(start 272.050002 -11.917934)
		(end 272.050002 -10.623042)
		(width 0.10795)
		(layer "B.Cu")
		(net "FM_ADR_COMPLETE_ABC_N")
	)
	(segment
		(start 265.403076 -13.8938)
		(end 265.7348 -13.562076)
		(width 0.10795)
		(layer "B.Cu")
		(net "FM_ADR_COMPLETE_ABC_N")
	)
	(segment
		(start 272.050002 -2.316734)
		(end 272.050256 -2.316988)
		(width 0.10795)
		(layer "B.Cu")
		(net "FM_ADR_COMPLETE_ABC_N")
	)
	(segment
		(start 272.050002 -18.734532)
		(end 272.050256 -18.734278)
		(width 0.10795)
		(layer "B.Cu")
		(net "FM_ADR_COMPLETE_ABC_N")
	)
	(segment
		(start 271.399 1.6764)
		(end 270.9672 1.6764)
		(width 0.10795)
		(layer "B.Cu")
		(net "FM_ADR_COMPLETE_ABC_N")
	)
	(segment
		(start 270.9672 1.6764)
		(end 270.6116 1.3208)
		(width 0.10795)
		(layer "B.Cu")
		(net "FM_ADR_COMPLETE_ABC_N")
	)
	(segment
		(start 321.214496 -31.388304)
		(end 321.214496 -30.949138)
		(width 0.089408)
		(layer "In2.Cu")
		(net "FM_ADR_COMPLETE_ABC_N")
	)
	(segment
		(start 322.384166 -30.318456)
		(end 322.9864 -29.716222)
		(width 0.089408)
		(layer "In2.Cu")
		(net "FM_ADR_COMPLETE_ABC_N")
	)
	(segment
		(start 321.214496 -30.949138)
		(end 321.845178 -30.318456)
		(width 0.089408)
		(layer "In2.Cu")
		(net "FM_ADR_COMPLETE_ABC_N")
	)
	(segment
		(start 323.0118 -8.980424)
		(end 323.0118 1.841754)
		(width 0.089408)
		(layer "In2.Cu")
		(net "FM_ADR_COMPLETE_ABC_N")
	)
	(segment
		(start 321.2084 -31.3944)
		(end 321.214496 -31.388304)
		(width 0.089408)
		(layer "In2.Cu")
		(net "FM_ADR_COMPLETE_ABC_N")
	)
	(segment
		(start 271.6276 0.883666)
		(end 272.049748 0.461518)
		(width 0.089408)
		(layer "In2.Cu")
		(net "FM_ADR_COMPLETE_ABC_N")
	)
	(segment
		(start 321.2084 -32.600392)
		(end 321.2084 -31.3944)
		(width 0.089408)
		(layer "In2.Cu")
		(net "FM_ADR_COMPLETE_ABC_N")
	)
	(segment
		(start 321.938396 2.915158)
		(end 272.434558 2.915158)
		(width 0.089408)
		(layer "In2.Cu")
		(net "FM_ADR_COMPLETE_ABC_N")
	)
	(segment
		(start 321.004692 -33.907222)
		(end 321.004692 -32.8041)
		(width 0.089408)
		(layer "In2.Cu")
		(net "FM_ADR_COMPLETE_ABC_N")
	)
	(segment
		(start 323.39026 -16.642334)
		(end 320.940176 -14.19225)
		(width 0.089408)
		(layer "In2.Cu")
		(net "FM_ADR_COMPLETE_ABC_N")
	)
	(segment
		(start 320.940176 -11.052048)
		(end 323.0118 -8.980424)
		(width 0.089408)
		(layer "In2.Cu")
		(net "FM_ADR_COMPLETE_ABC_N")
	)
	(segment
		(start 322.9864 -27.1526)
		(end 323.39026 -26.74874)
		(width 0.089408)
		(layer "In2.Cu")
		(net "FM_ADR_COMPLETE_ABC_N")
	)
	(segment
		(start 320.940176 -14.19225)
		(end 320.940176 -11.052048)
		(width 0.089408)
		(layer "In2.Cu")
		(net "FM_ADR_COMPLETE_ABC_N")
	)
	(segment
		(start 321.845178 -30.318456)
		(end 322.384166 -30.318456)
		(width 0.089408)
		(layer "In2.Cu")
		(net "FM_ADR_COMPLETE_ABC_N")
	)
	(segment
		(start 321.004692 -32.8041)
		(end 321.2084 -32.600392)
		(width 0.089408)
		(layer "In2.Cu")
		(net "FM_ADR_COMPLETE_ABC_N")
	)
	(segment
		(start 323.39026 -26.74874)
		(end 323.39026 -16.642334)
		(width 0.089408)
		(layer "In2.Cu")
		(net "FM_ADR_COMPLETE_ABC_N")
	)
	(segment
		(start 271.6276 2.1082)
		(end 271.6276 0.883666)
		(width 0.089408)
		(layer "In2.Cu")
		(net "FM_ADR_COMPLETE_ABC_N")
	)
	(segment
		(start 272.434558 2.915158)
		(end 271.6276 2.1082)
		(width 0.089408)
		(layer "In2.Cu")
		(net "FM_ADR_COMPLETE_ABC_N")
	)
	(segment
		(start 272.049748 0.461518)
		(end 272.049748 -2.31648)
		(width 0.089408)
		(layer "In2.Cu")
		(net "FM_ADR_COMPLETE_ABC_N")
	)
	(segment
		(start 323.0118 1.841754)
		(end 321.938396 2.915158)
		(width 0.089408)
		(layer "In2.Cu")
		(net "FM_ADR_COMPLETE_ABC_N")
	)
	(segment
		(start 272.049748 -2.31648)
		(end 272.050256 -2.316988)
		(width 0.089408)
		(layer "In2.Cu")
		(net "FM_ADR_COMPLETE_ABC_N")
	)
	(segment
		(start 322.9864 -29.716222)
		(end 322.9864 -27.1526)
		(width 0.089408)
		(layer "In2.Cu")
		(net "FM_ADR_COMPLETE_ABC_N")
	)
	(segment
		(start 123.363228 -66.800984)
		(end 122.791728 -66.800984)
		(width 0.1016)
		(layer "F.Cu")
		(net "TP_CPU1_RSVD_208")
	)
	(via
		(at 122.791728 -66.800984)
		(size 0.508)
		(drill 0.254)
		(layers "F.Cu" "B.Cu")
		(net "TP_CPU1_RSVD_208")
	)
	(segment
		(start 69.466206 -52.618386)
		(end 68.894706 -52.618386)
		(width 0.10795)
		(layer "F.Cu")
		(net "TP_CPU1_RSVD_273")
	)
	(via
		(at 68.894706 -52.618386)
		(size 0.508)
		(drill 0.254)
		(layers "F.Cu" "B.Cu")
		(net "TP_CPU1_RSVD_273")
	)
	(segment
		(start 124.221748 -66.305938)
		(end 123.650248 -66.305938)
		(width 0.1016)
		(layer "F.Cu")
		(net "TP_CPU1_RSVD_214")
	)
	(via
		(at 123.650248 -66.305938)
		(size 0.508)
		(drill 0.254)
		(layers "F.Cu" "B.Cu")
		(net "TP_CPU1_RSVD_214")
	)
	(segment
		(start 70.324726 -52.12334)
		(end 69.753226 -52.12334)
		(width 0.10795)
		(layer "F.Cu")
		(net "TP_CPU1_RSVD_276")
	)
	(via
		(at 69.753226 -52.12334)
		(size 0.508)
		(drill 0.254)
		(layers "F.Cu" "B.Cu")
		(net "TP_CPU1_RSVD_276")
	)
	(segment
		(start 287.79216 -66.800984)
		(end 288.36366 -66.800984)
		(width 0.10795)
		(layer "F.Cu")
		(net "TP_CPU0_RSVD_208")
	)
	(via
		(at 287.79216 -66.800984)
		(size 0.508)
		(drill 0.254)
		(layers "F.Cu" "B.Cu")
		(net "TP_CPU0_RSVD_208")
	)
	(segment
		(start 234.466638 -52.618386)
		(end 233.895138 -52.618386)
		(width 0.10795)
		(layer "F.Cu")
		(net "TP_CPU0_RSVD_273")
	)
	(via
		(at 233.895138 -52.618386)
		(size 0.508)
		(drill 0.254)
		(layers "F.Cu" "B.Cu")
		(net "TP_CPU0_RSVD_273")
	)
	(via
		(at 232.526078 -52.618386)
		(size 0.6604)
		(drill 0.3302)
		(layers "F.Cu" "B.Cu")
		(net "TP_CPU0_RSVD_273")
	)
	(segment
		(start 232.526078 -52.618386)
		(end 233.895138 -52.618386)
		(width 0.10795)
		(layer "B.Cu")
		(net "TP_CPU0_RSVD_273")
	)
	(segment
		(start 289.22218 -66.305938)
		(end 288.65068 -66.305938)
		(width 0.10795)
		(layer "F.Cu")
		(net "TP_CPU0_RSVD_214")
	)
	(via
		(at 288.65068 -66.305938)
		(size 0.508)
		(drill 0.254)
		(layers "F.Cu" "B.Cu")
		(net "TP_CPU0_RSVD_214")
	)
	(segment
		(start 235.325158 -52.12334)
		(end 234.753658 -52.12334)
		(width 0.10795)
		(layer "F.Cu")
		(net "TP_CPU0_RSVD_276")
	)
	(via
		(at 234.753658 -52.12334)
		(size 0.508)
		(drill 0.254)
		(layers "F.Cu" "B.Cu")
		(net "TP_CPU0_RSVD_276")
	)
	(segment
		(start 101.230684 -61.038486)
		(end 100.659184 -61.038486)
		(width 0.10795)
		(layer "F.Cu")
		(net "TP_CPU1_RSVD_254")
	)
	(via
		(at 100.659184 -61.038486)
		(size 0.508)
		(drill 0.254)
		(layers "F.Cu" "B.Cu")
		(net "TP_CPU1_RSVD_254")
	)
	(segment
		(start 101.230684 -62.029086)
		(end 100.659184 -62.029086)
		(width 0.10795)
		(layer "F.Cu")
		(net "TP_CPU1_RSVD_245")
	)
	(via
		(at 100.659184 -62.029086)
		(size 0.508)
		(drill 0.254)
		(layers "F.Cu" "B.Cu")
		(net "TP_CPU1_RSVD_245")
	)
	(segment
		(start 134.523734 -80.174338)
		(end 135.095234 -80.174338)
		(width 0.10795)
		(layer "F.Cu")
		(net "TP_CPU1_RSVD_123")
	)
	(via
		(at 135.095234 -80.174338)
		(size 0.508)
		(drill 0.254)
		(layers "F.Cu" "B.Cu")
		(net "TP_CPU1_RSVD_123")
	)
	(segment
		(start 137.957814 -82.155284)
		(end 138.529314 -82.155284)
		(width 0.10795)
		(layer "F.Cu")
		(net "TP_CPU1_RSVD_111")
	)
	(via
		(at 138.529314 -82.155284)
		(size 0.508)
		(drill 0.254)
		(layers "F.Cu" "B.Cu")
		(net "TP_CPU1_RSVD_111")
	)
	(segment
		(start 138.816334 -81.659984)
		(end 139.387834 -81.659984)
		(width 0.10795)
		(layer "F.Cu")
		(net "TP_CPU1_RSVD_113")
	)
	(via
		(at 139.387834 -81.659984)
		(size 0.508)
		(drill 0.254)
		(layers "F.Cu" "B.Cu")
		(net "TP_CPU1_RSVD_113")
	)
	(segment
		(start 124.221748 -71.258938)
		(end 124.793248 -71.258938)
		(width 0.10795)
		(layer "F.Cu")
		(net "TP_CPU1_RSVD_175")
	)
	(via
		(at 124.793248 -71.258938)
		(size 0.508)
		(drill 0.254)
		(layers "F.Cu" "B.Cu")
		(net "TP_CPU1_RSVD_175")
	)
	(segment
		(start 129.085848 -72.744584)
		(end 128.514348 -72.744584)
		(width 0.10795)
		(layer "F.Cu")
		(net "TP_CPU1_RSVD_155")
	)
	(via
		(at 129.085848 -72.744584)
		(size 0.508)
		(drill 0.254)
		(layers "F.Cu" "B.Cu")
		(net "TP_CPU1_RSVD_155")
	)
	(segment
		(start 125.080268 -71.753984)
		(end 125.651768 -71.753984)
		(width 0.10795)
		(layer "F.Cu")
		(net "TP_CPU1_RSVD_166")
	)
	(via
		(at 125.651768 -71.753984)
		(size 0.508)
		(drill 0.254)
		(layers "F.Cu" "B.Cu")
		(net "TP_CPU1_RSVD_166")
	)
	(segment
		(start 127.655828 -72.249538)
		(end 128.227328 -72.249538)
		(width 0.10795)
		(layer "F.Cu")
		(net "TP_CPU1_RSVD_161")
	)
	(via
		(at 128.227328 -72.249538)
		(size 0.508)
		(drill 0.254)
		(layers "F.Cu" "B.Cu")
		(net "TP_CPU1_RSVD_161")
	)
	(segment
		(start 127.655828 -73.240138)
		(end 128.227328 -73.240138)
		(width 0.10795)
		(layer "F.Cu")
		(net "TP_CPU1_RSVD_149")
	)
	(via
		(at 128.227328 -73.240138)
		(size 0.508)
		(drill 0.254)
		(layers "F.Cu" "B.Cu")
		(net "TP_CPU1_RSVD_149")
	)
	(segment
		(start 128.514348 -71.753984)
		(end 129.085848 -71.753984)
		(width 0.10795)
		(layer "F.Cu")
		(net "TP_CPU1_RSVD_167")
	)
	(via
		(at 129.085848 -71.753984)
		(size 0.508)
		(drill 0.254)
		(layers "F.Cu" "B.Cu")
		(net "TP_CPU1_RSVD_167")
	)
	(segment
		(start 131.089908 -72.249538)
		(end 131.661408 -72.249538)
		(width 0.10795)
		(layer "F.Cu")
		(net "TP_CPU1_RSVD_162")
	)
	(via
		(at 131.661408 -72.249538)
		(size 0.508)
		(drill 0.254)
		(layers "F.Cu" "B.Cu")
		(net "TP_CPU1_RSVD_162")
	)
	(segment
		(start 127.655828 -74.230738)
		(end 128.227328 -74.230738)
		(width 0.10795)
		(layer "F.Cu")
		(net "TP_CPU1_RSVD_145")
	)
	(via
		(at 128.227328 -74.230738)
		(size 0.508)
		(drill 0.254)
		(layers "F.Cu" "B.Cu")
		(net "TP_CPU1_RSVD_145")
	)
	(segment
		(start 125.938788 -74.230738)
		(end 126.510288 -74.230738)
		(width 0.10795)
		(layer "F.Cu")
		(net "TP_CPU1_RSVD_144")
	)
	(via
		(at 126.510288 -74.230738)
		(size 0.508)
		(drill 0.254)
		(layers "F.Cu" "B.Cu")
		(net "TP_CPU1_RSVD_144")
	)
	(segment
		(start 131.948174 -71.753984)
		(end 132.519674 -71.753984)
		(width 0.10795)
		(layer "F.Cu")
		(net "TP_CPU1_RSVD_169")
	)
	(via
		(at 132.519674 -71.753984)
		(size 0.508)
		(drill 0.254)
		(layers "F.Cu" "B.Cu")
		(net "TP_CPU1_RSVD_169")
	)
	(segment
		(start 125.080268 -73.735184)
		(end 125.651768 -73.735184)
		(width 0.10795)
		(layer "F.Cu")
		(net "TP_CPU1_RSVD_146")
	)
	(via
		(at 125.651768 -73.735184)
		(size 0.508)
		(drill 0.254)
		(layers "F.Cu" "B.Cu")
		(net "TP_CPU1_RSVD_146")
	)
	(segment
		(start 126.797308 -72.744584)
		(end 127.368808 -72.744584)
		(width 0.10795)
		(layer "F.Cu")
		(net "TP_CPU1_RSVD_154")
	)
	(via
		(at 127.368808 -72.744584)
		(size 0.508)
		(drill 0.254)
		(layers "F.Cu" "B.Cu")
		(net "TP_CPU1_RSVD_154")
	)
	(segment
		(start 125.938788 -73.240138)
		(end 126.510288 -73.240138)
		(width 0.10795)
		(layer "F.Cu")
		(net "TP_CPU1_RSVD_148")
	)
	(via
		(at 126.510288 -73.240138)
		(size 0.508)
		(drill 0.254)
		(layers "F.Cu" "B.Cu")
		(net "TP_CPU1_RSVD_148")
	)
	(segment
		(start 125.938788 -72.249538)
		(end 126.510288 -72.249538)
		(width 0.10795)
		(layer "F.Cu")
		(net "TP_CPU1_RSVD_160")
	)
	(via
		(at 126.510288 -72.249538)
		(size 0.508)
		(drill 0.254)
		(layers "F.Cu" "B.Cu")
		(net "TP_CPU1_RSVD_160")
	)
	(segment
		(start 124.221748 -72.249538)
		(end 124.793248 -72.249538)
		(width 0.10795)
		(layer "F.Cu")
		(net "TP_CPU1_RSVD_159")
	)
	(via
		(at 124.793248 -72.249538)
		(size 0.508)
		(drill 0.254)
		(layers "F.Cu" "B.Cu")
		(net "TP_CPU1_RSVD_159")
	)
	(segment
		(start 124.221748 -73.240138)
		(end 124.793248 -73.240138)
		(width 0.10795)
		(layer "F.Cu")
		(net "TP_CPU1_RSVD_147")
	)
	(via
		(at 124.793248 -73.240138)
		(size 0.508)
		(drill 0.254)
		(layers "F.Cu" "B.Cu")
		(net "TP_CPU1_RSVD_147")
	)
	(segment
		(start 130.231388 -71.753984)
		(end 130.802888 -71.753984)
		(width 0.10795)
		(layer "F.Cu")
		(net "TP_CPU1_RSVD_168")
	)
	(via
		(at 130.802888 -71.753984)
		(size 0.508)
		(drill 0.254)
		(layers "F.Cu" "B.Cu")
		(net "TP_CPU1_RSVD_168")
	)
	(segment
		(start 134.523734 -84.136738)
		(end 135.095234 -84.136738)
		(width 0.10795)
		(layer "F.Cu")
		(net "TP_CPU1_RSVD_99")
	)
	(via
		(at 135.095234 -84.136738)
		(size 0.4826)
		(drill 0.254)
		(layers "F.Cu" "B.Cu")
		(net "TP_CPU1_RSVD_99")
	)
	(segment
		(start 126.797308 -85.622384)
		(end 127.368808 -85.622384)
		(width 0.10795)
		(layer "F.Cu")
		(net "TP_CPU1_RSVD_85")
	)
	(via
		(at 127.368808 -85.622384)
		(size 0.4826)
		(drill 0.254)
		(layers "F.Cu" "B.Cu")
		(net "TP_CPU1_RSVD_85")
	)
	(segment
		(start 131.948174 -68.782184)
		(end 132.519674 -68.782184)
		(width 0.1016)
		(layer "F.Cu")
		(net "TP_CPU1_RSVD_189")
	)
	(via
		(at 132.519674 -68.782184)
		(size 0.508)
		(drill 0.254)
		(layers "F.Cu" "B.Cu")
		(net "TP_CPU1_RSVD_189")
	)
	(segment
		(start 126.797308 -63.829184)
		(end 127.368808 -63.829184)
		(width 0.1016)
		(layer "F.Cu")
		(net "TP_CPU1_RSVD_246")
	)
	(via
		(at 127.368808 -63.829184)
		(size 0.508)
		(drill 0.254)
		(layers "F.Cu" "B.Cu")
		(net "TP_CPU1_RSVD_246")
	)
	(segment
		(start 126.797308 -64.819784)
		(end 127.368808 -64.819784)
		(width 0.1016)
		(layer "F.Cu")
		(net "TP_CPU1_RSVD_232")
	)
	(via
		(at 127.368808 -64.819784)
		(size 0.508)
		(drill 0.254)
		(layers "F.Cu" "B.Cu")
		(net "TP_CPU1_RSVD_232")
	)
	(segment
		(start 130.231388 -64.819784)
		(end 130.802888 -64.819784)
		(width 0.10795)
		(layer "F.Cu")
		(net "TP_CPU1_RSVD_233")
	)
	(via
		(at 130.802888 -64.819784)
		(size 0.508)
		(drill 0.254)
		(layers "F.Cu" "B.Cu")
		(net "TP_CPU1_RSVD_233")
	)
	(segment
		(start 129.372868 -68.287138)
		(end 129.944368 -68.287138)
		(width 0.10795)
		(layer "F.Cu")
		(net "TP_CPU1_TEST_6")
	)
	(via
		(at 129.944368 -68.287138)
		(size 0.508)
		(drill 0.254)
		(layers "F.Cu" "B.Cu")
		(net "TP_CPU1_TEST_6")
	)
	(segment
		(start 122.504708 -84.136738)
		(end 123.076208 -84.136738)
		(width 0.10795)
		(layer "F.Cu")
		(net "TP_CPU1_RSVD_97")
	)
	(via
		(at 123.076208 -84.136738)
		(size 0.508)
		(drill 0.254)
		(layers "F.Cu" "B.Cu")
		(net "TP_CPU1_RSVD_97")
	)
	(segment
		(start 121.646188 -84.631784)
		(end 122.217688 -84.631784)
		(width 0.10795)
		(layer "F.Cu")
		(net "TP_CPU1_RSVD_91")
	)
	(via
		(at 122.217688 -84.631784)
		(size 0.508)
		(drill 0.254)
		(layers "F.Cu" "B.Cu")
		(net "TP_CPU1_RSVD_91")
	)
	(segment
		(start 121.646188 -80.669384)
		(end 122.217688 -80.669384)
		(width 0.10795)
		(layer "F.Cu")
		(net "TP_CPU1_RSVD_119")
	)
	(via
		(at 122.217688 -80.669384)
		(size 0.508)
		(drill 0.254)
		(layers "F.Cu" "B.Cu")
		(net "TP_CPU1_RSVD_119")
	)
	(segment
		(start 123.075954 -81.164938)
		(end 123.076208 -81.164684)
		(width 0.10795)
		(layer "F.Cu")
		(net "TP_CPU1_RSVD_117")
	)
	(segment
		(start 122.504708 -81.164938)
		(end 123.075954 -81.164938)
		(width 0.10795)
		(layer "F.Cu")
		(net "TP_CPU1_RSVD_117")
	)
	(via
		(at 123.076208 -81.164684)
		(size 0.508)
		(drill 0.254)
		(layers "F.Cu" "B.Cu")
		(net "TP_CPU1_RSVD_117")
	)
	(segment
		(start 124.221748 -80.174338)
		(end 124.793248 -80.174338)
		(width 0.10795)
		(layer "F.Cu")
		(net "TP_CPU1_RSVD_121")
	)
	(via
		(at 124.793248 -80.174338)
		(size 0.508)
		(drill 0.254)
		(layers "F.Cu" "B.Cu")
		(net "TP_CPU1_RSVD_121")
	)
	(segment
		(start 121.646188 -82.650584)
		(end 122.217688 -82.650584)
		(width 0.10795)
		(layer "F.Cu")
		(net "TP_CPU1_RSVD_108")
	)
	(via
		(at 122.217688 -82.650584)
		(size 0.508)
		(drill 0.254)
		(layers "F.Cu" "B.Cu")
		(net "TP_CPU1_RSVD_108")
	)
	(segment
		(start 123.363228 -79.678784)
		(end 123.934728 -79.678784)
		(width 0.10795)
		(layer "F.Cu")
		(net "TP_CPU1_RSVD_124")
	)
	(via
		(at 123.934728 -79.678784)
		(size 0.508)
		(drill 0.254)
		(layers "F.Cu" "B.Cu")
		(net "TP_CPU1_RSVD_124")
	)
	(segment
		(start 121.646188 -81.659984)
		(end 122.217688 -81.659984)
		(width 0.10795)
		(layer "F.Cu")
		(net "TP_CPU1_RSVD_114")
	)
	(via
		(at 122.217688 -81.659984)
		(size 0.508)
		(drill 0.254)
		(layers "F.Cu" "B.Cu")
		(net "TP_CPU1_RSVD_114")
	)
	(segment
		(start 266.231116 -61.038486)
		(end 265.659616 -61.038486)
		(width 0.10795)
		(layer "F.Cu")
		(net "TP_CPU0_RSVD_254")
	)
	(via
		(at 265.659616 -61.038486)
		(size 0.508)
		(drill 0.254)
		(layers "F.Cu" "B.Cu")
		(net "TP_CPU0_RSVD_254")
	)
	(segment
		(start 266.231116 -62.029086)
		(end 265.659616 -62.029086)
		(width 0.10795)
		(layer "F.Cu")
		(net "TP_CPU0_RSVD_245")
	)
	(via
		(at 265.659616 -62.029086)
		(size 0.508)
		(drill 0.254)
		(layers "F.Cu" "B.Cu")
		(net "TP_CPU0_RSVD_245")
	)
	(segment
		(start 300.095666 -80.174338)
		(end 299.524166 -80.174338)
		(width 0.10795)
		(layer "F.Cu")
		(net "TP_CPU0_RSVD_123")
	)
	(via
		(at 300.095666 -80.174338)
		(size 0.508)
		(drill 0.254)
		(layers "F.Cu" "B.Cu")
		(net "TP_CPU0_RSVD_123")
	)
	(segment
		(start 303.529746 -82.155284)
		(end 302.958246 -82.155284)
		(width 0.10795)
		(layer "F.Cu")
		(net "TP_CPU0_RSVD_111")
	)
	(via
		(at 303.529746 -82.155284)
		(size 0.508)
		(drill 0.254)
		(layers "F.Cu" "B.Cu")
		(net "TP_CPU0_RSVD_111")
	)
	(segment
		(start 303.816766 -81.659984)
		(end 304.388266 -81.659984)
		(width 0.10795)
		(layer "F.Cu")
		(net "TP_CPU0_RSVD_113")
	)
	(via
		(at 304.388266 -81.659984)
		(size 0.508)
		(drill 0.254)
		(layers "F.Cu" "B.Cu")
		(net "TP_CPU0_RSVD_113")
	)
	(segment
		(start 289.22218 -71.258938)
		(end 289.79368 -71.258938)
		(width 0.10795)
		(layer "F.Cu")
		(net "TP_CPU0_RSVD_175")
	)
	(via
		(at 289.79368 -71.258938)
		(size 0.508)
		(drill 0.254)
		(layers "F.Cu" "B.Cu")
		(net "TP_CPU0_RSVD_175")
	)
	(segment
		(start 293.51478 -72.744584)
		(end 294.08628 -72.744584)
		(width 0.10795)
		(layer "F.Cu")
		(net "TP_CPU0_RSVD_155")
	)
	(via
		(at 294.08628 -72.744584)
		(size 0.508)
		(drill 0.254)
		(layers "F.Cu" "B.Cu")
		(net "TP_CPU0_RSVD_155")
	)
	(segment
		(start 290.0807 -71.753984)
		(end 290.6522 -71.753984)
		(width 0.10795)
		(layer "F.Cu")
		(net "TP_CPU0_RSVD_166")
	)
	(via
		(at 290.6522 -71.753984)
		(size 0.508)
		(drill 0.254)
		(layers "F.Cu" "B.Cu")
		(net "TP_CPU0_RSVD_166")
	)
	(segment
		(start 292.65626 -72.249538)
		(end 293.22776 -72.249538)
		(width 0.10795)
		(layer "F.Cu")
		(net "TP_CPU0_RSVD_161")
	)
	(via
		(at 293.22776 -72.249538)
		(size 0.508)
		(drill 0.254)
		(layers "F.Cu" "B.Cu")
		(net "TP_CPU0_RSVD_161")
	)
	(segment
		(start 293.22776 -73.240138)
		(end 292.65626 -73.240138)
		(width 0.10795)
		(layer "F.Cu")
		(net "TP_CPU0_RSVD_149")
	)
	(via
		(at 293.22776 -73.240138)
		(size 0.508)
		(drill 0.254)
		(layers "F.Cu" "B.Cu")
		(net "TP_CPU0_RSVD_149")
	)
	(segment
		(start 293.51478 -71.753984)
		(end 294.08628 -71.753984)
		(width 0.10795)
		(layer "F.Cu")
		(net "TP_CPU0_RSVD_167")
	)
	(via
		(at 294.08628 -71.753984)
		(size 0.508)
		(drill 0.254)
		(layers "F.Cu" "B.Cu")
		(net "TP_CPU0_RSVD_167")
	)
	(segment
		(start 296.66184 -72.249538)
		(end 296.09034 -72.249538)
		(width 0.10795)
		(layer "F.Cu")
		(net "TP_CPU0_RSVD_162")
	)
	(via
		(at 296.66184 -72.249538)
		(size 0.508)
		(drill 0.254)
		(layers "F.Cu" "B.Cu")
		(net "TP_CPU0_RSVD_162")
	)
	(segment
		(start 292.65626 -74.230738)
		(end 293.22776 -74.230738)
		(width 0.10795)
		(layer "F.Cu")
		(net "TP_CPU0_RSVD_145")
	)
	(via
		(at 293.22776 -74.230738)
		(size 0.508)
		(drill 0.254)
		(layers "F.Cu" "B.Cu")
		(net "TP_CPU0_RSVD_145")
	)
	(segment
		(start 290.93922 -74.230738)
		(end 291.51072 -74.230738)
		(width 0.10795)
		(layer "F.Cu")
		(net "TP_CPU0_RSVD_144")
	)
	(via
		(at 291.51072 -74.230738)
		(size 0.508)
		(drill 0.254)
		(layers "F.Cu" "B.Cu")
		(net "TP_CPU0_RSVD_144")
	)
	(segment
		(start 296.948606 -71.753984)
		(end 297.520106 -71.753984)
		(width 0.10795)
		(layer "F.Cu")
		(net "TP_CPU0_RSVD_169")
	)
	(via
		(at 297.520106 -71.753984)
		(size 0.508)
		(drill 0.254)
		(layers "F.Cu" "B.Cu")
		(net "TP_CPU0_RSVD_169")
	)
	(segment
		(start 290.0807 -73.735184)
		(end 290.6522 -73.735184)
		(width 0.10795)
		(layer "F.Cu")
		(net "TP_CPU0_RSVD_146")
	)
	(via
		(at 290.6522 -73.735184)
		(size 0.508)
		(drill 0.254)
		(layers "F.Cu" "B.Cu")
		(net "TP_CPU0_RSVD_146")
	)
	(segment
		(start 296.66184 -71.258938)
		(end 296.09034 -71.258938)
		(width 0.10795)
		(layer "F.Cu")
		(net "TP_CPU0_RSVD_178")
	)
	(via
		(at 296.66184 -71.258938)
		(size 0.508)
		(drill 0.254)
		(layers "F.Cu" "B.Cu")
		(net "TP_CPU0_RSVD_178")
	)
	(segment
		(start 291.79774 -72.744584)
		(end 292.36924 -72.744584)
		(width 0.10795)
		(layer "F.Cu")
		(net "TP_CPU0_RSVD_154")
	)
	(via
		(at 292.36924 -72.744584)
		(size 0.508)
		(drill 0.254)
		(layers "F.Cu" "B.Cu")
		(net "TP_CPU0_RSVD_154")
	)
	(segment
		(start 290.93922 -73.240138)
		(end 291.51072 -73.240138)
		(width 0.10795)
		(layer "F.Cu")
		(net "TP_CPU0_RSVD_148")
	)
	(via
		(at 291.51072 -73.240138)
		(size 0.508)
		(drill 0.254)
		(layers "F.Cu" "B.Cu")
		(net "TP_CPU0_RSVD_148")
	)
	(segment
		(start 290.93922 -72.249538)
		(end 291.51072 -72.249538)
		(width 0.10795)
		(layer "F.Cu")
		(net "TP_CPU0_RSVD_160")
	)
	(via
		(at 291.51072 -72.249538)
		(size 0.508)
		(drill 0.254)
		(layers "F.Cu" "B.Cu")
		(net "TP_CPU0_RSVD_160")
	)
	(segment
		(start 289.22218 -72.249538)
		(end 289.79368 -72.249538)
		(width 0.10795)
		(layer "F.Cu")
		(net "TP_CPU0_RSVD_159")
	)
	(via
		(at 289.79368 -72.249538)
		(size 0.508)
		(drill 0.254)
		(layers "F.Cu" "B.Cu")
		(net "TP_CPU0_RSVD_159")
	)
	(segment
		(start 289.22218 -73.240138)
		(end 289.79368 -73.240138)
		(width 0.10795)
		(layer "F.Cu")
		(net "TP_CPU0_RSVD_147")
	)
	(via
		(at 289.79368 -73.240138)
		(size 0.508)
		(drill 0.254)
		(layers "F.Cu" "B.Cu")
		(net "TP_CPU0_RSVD_147")
	)
	(segment
		(start 292.65626 -71.258938)
		(end 293.22776 -71.258938)
		(width 0.10795)
		(layer "F.Cu")
		(net "TP_CPU0_RSVD_176")
	)
	(via
		(at 293.22776 -71.258938)
		(size 0.508)
		(drill 0.254)
		(layers "F.Cu" "B.Cu")
		(net "TP_CPU0_RSVD_176")
	)
	(segment
		(start 295.23182 -71.753984)
		(end 295.80332 -71.753984)
		(width 0.10795)
		(layer "F.Cu")
		(net "TP_CPU0_RSVD_168")
	)
	(via
		(at 295.80332 -71.753984)
		(size 0.508)
		(drill 0.254)
		(layers "F.Cu" "B.Cu")
		(net "TP_CPU0_RSVD_168")
	)
	(segment
		(start 291.79774 -85.622384)
		(end 292.36924 -85.622384)
		(width 0.10795)
		(layer "F.Cu")
		(net "TP_CPU0_RSVD_85")
	)
	(via
		(at 292.36924 -85.622384)
		(size 0.508)
		(drill 0.254)
		(layers "F.Cu" "B.Cu")
		(net "TP_CPU0_RSVD_85")
	)
	(segment
		(start 299.524166 -84.136738)
		(end 300.095666 -84.136738)
		(width 0.10795)
		(layer "F.Cu")
		(net "TP_CPU0_RSVD_99")
	)
	(via
		(at 300.095666 -84.136738)
		(size 0.508)
		(drill 0.254)
		(layers "F.Cu" "B.Cu")
		(net "TP_CPU0_RSVD_99")
	)
	(segment
		(start 296.948606 -68.782184)
		(end 297.520106 -68.782184)
		(width 0.10795)
		(layer "F.Cu")
		(net "TP_CPU0_RSVD_189")
	)
	(via
		(at 297.520106 -68.782184)
		(size 0.508)
		(drill 0.254)
		(layers "F.Cu" "B.Cu")
		(net "TP_CPU0_RSVD_189")
	)
	(segment
		(start 291.79774 -63.829184)
		(end 292.36924 -63.829184)
		(width 0.10795)
		(layer "F.Cu")
		(net "TP_CPU0_RSVD_246")
	)
	(via
		(at 292.36924 -63.829184)
		(size 0.508)
		(drill 0.254)
		(layers "F.Cu" "B.Cu")
		(net "TP_CPU0_RSVD_246")
	)
	(segment
		(start 291.79774 -64.819784)
		(end 292.36924 -64.819784)
		(width 0.10795)
		(layer "F.Cu")
		(net "TP_CPU0_RSVD_232")
	)
	(via
		(at 292.36924 -64.819784)
		(size 0.508)
		(drill 0.254)
		(layers "F.Cu" "B.Cu")
		(net "TP_CPU0_RSVD_232")
	)
	(segment
		(start 295.23182 -64.819784)
		(end 295.80332 -64.819784)
		(width 0.10795)
		(layer "F.Cu")
		(net "TP_CPU0_RSVD_233")
	)
	(via
		(at 295.80332 -64.819784)
		(size 0.508)
		(drill 0.254)
		(layers "F.Cu" "B.Cu")
		(net "TP_CPU0_RSVD_233")
	)
	(segment
		(start 294.3733 -68.287138)
		(end 294.9448 -68.287138)
		(width 0.10795)
		(layer "F.Cu")
		(net "TP_CPU0_TEST_6")
	)
	(via
		(at 294.9448 -68.287138)
		(size 0.508)
		(drill 0.254)
		(layers "F.Cu" "B.Cu")
		(net "TP_CPU0_TEST_6")
	)
	(segment
		(start 287.50514 -84.136738)
		(end 288.07664 -84.136738)
		(width 0.10795)
		(layer "F.Cu")
		(net "TP_CPU0_RSVD_97")
	)
	(via
		(at 288.07664 -84.136738)
		(size 0.508)
		(drill 0.254)
		(layers "F.Cu" "B.Cu")
		(net "TP_CPU0_RSVD_97")
	)
	(segment
		(start 287.21812 -84.631784)
		(end 286.64662 -84.631784)
		(width 0.10795)
		(layer "F.Cu")
		(net "TP_CPU0_RSVD_91")
	)
	(via
		(at 287.21812 -84.631784)
		(size 0.508)
		(drill 0.254)
		(layers "F.Cu" "B.Cu")
		(net "TP_CPU0_RSVD_91")
	)
	(segment
		(start 287.21812 -80.669384)
		(end 286.64662 -80.669384)
		(width 0.10795)
		(layer "F.Cu")
		(net "TP_CPU0_RSVD_119")
	)
	(via
		(at 287.21812 -80.669384)
		(size 0.508)
		(drill 0.254)
		(layers "F.Cu" "B.Cu")
		(net "TP_CPU0_RSVD_119")
	)
	(segment
		(start 287.50514 -81.164938)
		(end 288.07664 -81.164938)
		(width 0.10795)
		(layer "F.Cu")
		(net "TP_CPU0_RSVD_117")
	)
	(via
		(at 288.07664 -81.164938)
		(size 0.508)
		(drill 0.254)
		(layers "F.Cu" "B.Cu")
		(net "TP_CPU0_RSVD_117")
	)
	(segment
		(start 289.22218 -80.174338)
		(end 289.79368 -80.174338)
		(width 0.10795)
		(layer "F.Cu")
		(net "TP_CPU0_RSVD_121")
	)
	(via
		(at 289.79368 -80.174338)
		(size 0.508)
		(drill 0.254)
		(layers "F.Cu" "B.Cu")
		(net "TP_CPU0_RSVD_121")
	)
	(segment
		(start 287.21812 -82.650584)
		(end 286.64662 -82.650584)
		(width 0.10795)
		(layer "F.Cu")
		(net "TP_CPU0_RSVD_108")
	)
	(via
		(at 287.21812 -82.650584)
		(size 0.508)
		(drill 0.254)
		(layers "F.Cu" "B.Cu")
		(net "TP_CPU0_RSVD_108")
	)
	(segment
		(start 288.36366 -79.678784)
		(end 288.93516 -79.678784)
		(width 0.10795)
		(layer "F.Cu")
		(net "TP_CPU0_RSVD_124")
	)
	(via
		(at 288.93516 -79.678784)
		(size 0.508)
		(drill 0.254)
		(layers "F.Cu" "B.Cu")
		(net "TP_CPU0_RSVD_124")
	)
	(segment
		(start 287.21812 -81.659984)
		(end 286.64662 -81.659984)
		(width 0.10795)
		(layer "F.Cu")
		(net "TP_CPU0_RSVD_114")
	)
	(via
		(at 287.21812 -81.659984)
		(size 0.508)
		(drill 0.254)
		(layers "F.Cu" "B.Cu")
		(net "TP_CPU0_RSVD_114")
	)
	(segment
		(start 304.675286 -88.099138)
		(end 305.246786 -88.099138)
		(width 0.1143)
		(layer "F.Cu")
		(net "DMI_CPU0_PCH_TX_DP<3>")
	)
	(segment
		(start 364.617 -115.189)
		(end 363.7026 -115.189)
		(width 0.1143)
		(layer "F.Cu")
		(net "DMI_CPU0_PCH_TX_DP<3>")
	)
	(via
		(at 363.7026 -115.189)
		(size 0.508)
		(drill 0.254)
		(layers "F.Cu" "B.Cu")
		(net "DMI_CPU0_PCH_TX_DP<3>")
	)
	(via
		(at 305.246786 -88.099138)
		(size 0.508)
		(drill 0.254)
		(layers "F.Cu" "B.Cu")
		(net "DMI_CPU0_PCH_TX_DP<3>")
	)
	(segment
		(start 360.308652 -106.26852)
		(end 359.739184 -105.025952)
		(width 0.1143)
		(layer "In11.Cu")
		(net "DMI_CPU0_PCH_TX_DP<3>")
	)
	(segment
		(start 355.025198 -101.261164)
		(end 354.469954 -98.48596)
		(width 0.1143)
		(layer "In11.Cu")
		(net "DMI_CPU0_PCH_TX_DP<3>")
	)
	(segment
		(start 363.855 -115.0366)
		(end 363.855 -114.73815)
		(width 0.1143)
		(layer "In11.Cu")
		(net "DMI_CPU0_PCH_TX_DP<3>")
	)
	(segment
		(start 352.862896 -86.21268)
		(end 350.353122 -86.721696)
		(width 0.1143)
		(layer "In11.Cu")
		(net "DMI_CPU0_PCH_TX_DP<3>")
	)
	(segment
		(start 306.394104 -87.699088)
		(end 306.127404 -87.699088)
		(width 0.0889)
		(layer "In11.Cu")
		(net "DMI_CPU0_PCH_TX_DP<3>")
	)
	(segment
		(start 332.339442 -86.91499)
		(end 319.051178 -89.572846)
		(width 0.1143)
		(layer "In11.Cu")
		(net "DMI_CPU0_PCH_TX_DP<3>")
	)
	(segment
		(start 304.95367 -87.929974)
		(end 305.246786 -88.099138)
		(width 0.0889)
		(layer "In11.Cu")
		(net "DMI_CPU0_PCH_TX_DP<3>")
	)
	(segment
		(start 308.483 -88.3666)
		(end 308.460902 -88.3666)
		(width 0.0889)
		(layer "In11.Cu")
		(net "DMI_CPU0_PCH_TX_DP<3>")
	)
	(segment
		(start 354.617274 -87.06485)
		(end 353.54133 -86.35238)
		(width 0.1143)
		(layer "In11.Cu")
		(net "DMI_CPU0_PCH_TX_DP<3>")
	)
	(segment
		(start 304.926238 -87.826088)
		(end 304.925984 -87.826342)
		(width 0.0889)
		(layer "In11.Cu")
		(net "DMI_CPU0_PCH_TX_DP<3>")
	)
	(segment
		(start 306.038504 -87.787988)
		(end 305.771804 -87.787988)
		(width 0.0889)
		(layer "In11.Cu")
		(net "DMI_CPU0_PCH_TX_DP<3>")
	)
	(segment
		(start 344.470228 -88.198198)
		(end 343.85758 -87.789766)
		(width 0.1143)
		(layer "In11.Cu")
		(net "DMI_CPU0_PCH_TX_DP<3>")
	)
	(segment
		(start 306.483004 -87.787988)
		(end 306.394104 -87.699088)
		(width 0.0889)
		(layer "In11.Cu")
		(net "DMI_CPU0_PCH_TX_DP<3>")
	)
	(segment
		(start 307.722016 -88.3158)
		(end 307.105304 -87.699088)
		(width 0.0889)
		(layer "In11.Cu")
		(net "DMI_CPU0_PCH_TX_DP<3>")
	)
	(segment
		(start 355.110542 -91.057222)
		(end 355.482398 -89.201498)
		(width 0.1143)
		(layer "In11.Cu")
		(net "DMI_CPU0_PCH_TX_DP<3>")
	)
	(segment
		(start 305.771804 -87.787988)
		(end 305.682904 -87.699088)
		(width 0.0889)
		(layer "In11.Cu")
		(net "DMI_CPU0_PCH_TX_DP<3>")
	)
	(segment
		(start 319.051178 -89.572846)
		(end 313.216544 -88.3666)
		(width 0.1143)
		(layer "In11.Cu")
		(net "DMI_CPU0_PCH_TX_DP<3>")
	)
	(segment
		(start 359.704894 -109.287056)
		(end 360.167682 -106.97337)
		(width 0.1143)
		(layer "In11.Cu")
		(net "DMI_CPU0_PCH_TX_DP<3>")
	)
	(segment
		(start 353.920552 -93.928692)
		(end 355.110542 -91.057222)
		(width 0.1143)
		(layer "In11.Cu")
		(net "DMI_CPU0_PCH_TX_DP<3>")
	)
	(segment
		(start 353.54133 -86.35238)
		(end 352.862896 -86.21268)
		(width 0.1143)
		(layer "In11.Cu")
		(net "DMI_CPU0_PCH_TX_DP<3>")
	)
	(segment
		(start 354.469954 -98.48596)
		(end 354.650802 -97.58172)
		(width 0.1143)
		(layer "In11.Cu")
		(net "DMI_CPU0_PCH_TX_DP<3>")
	)
	(segment
		(start 308.410102 -88.3158)
		(end 307.722016 -88.3158)
		(width 0.0889)
		(layer "In11.Cu")
		(net "DMI_CPU0_PCH_TX_DP<3>")
	)
	(segment
		(start 360.167682 -106.97337)
		(end 360.308652 -106.26852)
		(width 0.1143)
		(layer "In11.Cu")
		(net "DMI_CPU0_PCH_TX_DP<3>")
	)
	(segment
		(start 355.114352 -101.706172)
		(end 355.025198 -101.261164)
		(width 0.1143)
		(layer "In11.Cu")
		(net "DMI_CPU0_PCH_TX_DP<3>")
	)
	(segment
		(start 305.682904 -87.699088)
		(end 305.2318 -87.699088)
		(width 0.0889)
		(layer "In11.Cu")
		(net "DMI_CPU0_PCH_TX_DP<3>")
	)
	(segment
		(start 308.460902 -88.3666)
		(end 308.410102 -88.3158)
		(width 0.0889)
		(layer "In11.Cu")
		(net "DMI_CPU0_PCH_TX_DP<3>")
	)
	(segment
		(start 341.559134 -87.330026)
		(end 341.55888 -87.330026)
		(width 0.1143)
		(layer "In11.Cu")
		(net "DMI_CPU0_PCH_TX_DP<3>")
	)
	(segment
		(start 343.85758 -87.789766)
		(end 341.559134 -87.330026)
		(width 0.1143)
		(layer "In11.Cu")
		(net "DMI_CPU0_PCH_TX_DP<3>")
	)
	(segment
		(start 363.7661 -114.64925)
		(end 362.835698 -114.64925)
		(width 0.1143)
		(layer "In11.Cu")
		(net "DMI_CPU0_PCH_TX_DP<3>")
	)
	(segment
		(start 359.739184 -105.025952)
		(end 355.114352 -101.706172)
		(width 0.1143)
		(layer "In11.Cu")
		(net "DMI_CPU0_PCH_TX_DP<3>")
	)
	(segment
		(start 341.55888 -87.330026)
		(end 339.259926 -86.870032)
		(width 0.1143)
		(layer "In11.Cu")
		(net "DMI_CPU0_PCH_TX_DP<3>")
	)
	(segment
		(start 313.216544 -88.3666)
		(end 308.483 -88.3666)
		(width 0.1143)
		(layer "In11.Cu")
		(net "DMI_CPU0_PCH_TX_DP<3>")
	)
	(segment
		(start 363.7026 -115.189)
		(end 363.855 -115.0366)
		(width 0.1143)
		(layer "In11.Cu")
		(net "DMI_CPU0_PCH_TX_DP<3>")
	)
	(segment
		(start 347.930216 -88.169496)
		(end 346.901008 -87.964518)
		(width 0.1143)
		(layer "In11.Cu")
		(net "DMI_CPU0_PCH_TX_DP<3>")
	)
	(segment
		(start 354.650802 -97.58172)
		(end 353.920552 -93.928692)
		(width 0.1143)
		(layer "In11.Cu")
		(net "DMI_CPU0_PCH_TX_DP<3>")
	)
	(segment
		(start 304.925984 -87.826342)
		(end 304.95367 -87.929974)
		(width 0.0889)
		(layer "In11.Cu")
		(net "DMI_CPU0_PCH_TX_DP<3>")
	)
	(segment
		(start 345.10091 -88.324436)
		(end 344.470228 -88.198198)
		(width 0.1143)
		(layer "In11.Cu")
		(net "DMI_CPU0_PCH_TX_DP<3>")
	)
	(segment
		(start 363.855 -114.73815)
		(end 363.7661 -114.64925)
		(width 0.1143)
		(layer "In11.Cu")
		(net "DMI_CPU0_PCH_TX_DP<3>")
	)
	(segment
		(start 350.353122 -86.721696)
		(end 348.267528 -88.101932)
		(width 0.1143)
		(layer "In11.Cu")
		(net "DMI_CPU0_PCH_TX_DP<3>")
	)
	(segment
		(start 306.838604 -87.699088)
		(end 306.749704 -87.787988)
		(width 0.0889)
		(layer "In11.Cu")
		(net "DMI_CPU0_PCH_TX_DP<3>")
	)
	(segment
		(start 361.686856 -114.41938)
		(end 360.32186 -112.371886)
		(width 0.1143)
		(layer "In11.Cu")
		(net "DMI_CPU0_PCH_TX_DP<3>")
	)
	(segment
		(start 355.482398 -89.201498)
		(end 354.617274 -87.06485)
		(width 0.1143)
		(layer "In11.Cu")
		(net "DMI_CPU0_PCH_TX_DP<3>")
	)
	(segment
		(start 362.835698 -114.64925)
		(end 361.686856 -114.41938)
		(width 0.1143)
		(layer "In11.Cu")
		(net "DMI_CPU0_PCH_TX_DP<3>")
	)
	(segment
		(start 348.267528 -88.101932)
		(end 347.930216 -88.169496)
		(width 0.1143)
		(layer "In11.Cu")
		(net "DMI_CPU0_PCH_TX_DP<3>")
	)
	(segment
		(start 360.32186 -112.371886)
		(end 359.704894 -109.287056)
		(width 0.1143)
		(layer "In11.Cu")
		(net "DMI_CPU0_PCH_TX_DP<3>")
	)
	(segment
		(start 307.105304 -87.699088)
		(end 306.838604 -87.699088)
		(width 0.0889)
		(layer "In11.Cu")
		(net "DMI_CPU0_PCH_TX_DP<3>")
	)
	(segment
		(start 336.920078 -87.831168)
		(end 332.339442 -86.91499)
		(width 0.1143)
		(layer "In11.Cu")
		(net "DMI_CPU0_PCH_TX_DP<3>")
	)
	(segment
		(start 339.259926 -86.870032)
		(end 336.920078 -87.831168)
		(width 0.1143)
		(layer "In11.Cu")
		(net "DMI_CPU0_PCH_TX_DP<3>")
	)
	(segment
		(start 306.127404 -87.699088)
		(end 306.038504 -87.787988)
		(width 0.0889)
		(layer "In11.Cu")
		(net "DMI_CPU0_PCH_TX_DP<3>")
	)
	(segment
		(start 306.749704 -87.787988)
		(end 306.483004 -87.787988)
		(width 0.0889)
		(layer "In11.Cu")
		(net "DMI_CPU0_PCH_TX_DP<3>")
	)
	(segment
		(start 346.901008 -87.964518)
		(end 345.10091 -88.324436)
		(width 0.1143)
		(layer "In11.Cu")
		(net "DMI_CPU0_PCH_TX_DP<3>")
	)
	(arc
		(start 305.2318 -87.699088)
		(mid 305.066326 -87.732052)
		(end 304.926238 -87.826088)
		(width 0.0889)
		(layer "In11.Cu")
		(net "DMI_CPU0_PCH_TX_DP<3>")
	)
	(segment
		(start 305.533806 -86.612984)
		(end 306.105306 -86.612984)
		(width 0.1143)
		(layer "F.Cu")
		(net "DMI_CPU0_PCH_TX_DP<2>")
	)
	(segment
		(start 367.665 -113.792)
		(end 368.554 -113.792)
		(width 0.1143)
		(layer "F.Cu")
		(net "DMI_CPU0_PCH_TX_DP<2>")
	)
	(via
		(at 367.665 -113.792)
		(size 0.508)
		(drill 0.254)
		(layers "F.Cu" "B.Cu")
		(net "DMI_CPU0_PCH_TX_DP<2>")
	)
	(via
		(at 306.105306 -86.612984)
		(size 0.508)
		(drill 0.254)
		(layers "F.Cu" "B.Cu")
		(net "DMI_CPU0_PCH_TX_DP<2>")
	)
	(segment
		(start 343.625424 -86.450932)
		(end 342.40978 -86.69401)
		(width 0.1143)
		(layer "In11.Cu")
		(net "DMI_CPU0_PCH_TX_DP<2>")
	)
	(segment
		(start 310.717184 -87.24773)
		(end 310.670702 -87.201248)
		(width 0.0889)
		(layer "In11.Cu")
		(net "DMI_CPU0_PCH_TX_DP<2>")
	)
	(segment
		(start 360.45775 -109.258862)
		(end 360.458004 -109.258862)
		(width 0.1143)
		(layer "In11.Cu")
		(net "DMI_CPU0_PCH_TX_DP<2>")
	)
	(segment
		(start 310.670702 -87.201248)
		(end 310.670702 -87.200994)
		(width 0.0889)
		(layer "In11.Cu")
		(net "DMI_CPU0_PCH_TX_DP<2>")
	)
	(segment
		(start 309.232046 -87.200994)
		(end 309.185564 -87.154512)
		(width 0.0889)
		(layer "In11.Cu")
		(net "DMI_CPU0_PCH_TX_DP<2>")
	)
	(segment
		(start 307.819298 -86.708234)
		(end 307.600096 -86.708234)
		(width 0.0889)
		(layer "In11.Cu")
		(net "DMI_CPU0_PCH_TX_DP<2>")
	)
	(segment
		(start 367.665 -113.32845)
		(end 367.5761 -113.23955)
		(width 0.1143)
		(layer "In11.Cu")
		(net "DMI_CPU0_PCH_TX_DP<2>")
	)
	(segment
		(start 311.076848 -87.154512)
		(end 311.030366 -87.200994)
		(width 0.0889)
		(layer "In11.Cu")
		(net "DMI_CPU0_PCH_TX_DP<2>")
	)
	(segment
		(start 345.670886 -87.08136)
		(end 343.644728 -86.447122)
		(width 0.1143)
		(layer "In11.Cu")
		(net "DMI_CPU0_PCH_TX_DP<2>")
	)
	(segment
		(start 308.466236 -87.154512)
		(end 308.265576 -87.154512)
		(width 0.0889)
		(layer "In11.Cu")
		(net "DMI_CPU0_PCH_TX_DP<2>")
	)
	(segment
		(start 337.81619 -85.775546)
		(end 335.21015 -86.679532)
		(width 0.1143)
		(layer "In11.Cu")
		(net "DMI_CPU0_PCH_TX_DP<2>")
	)
	(segment
		(start 309.278528 -87.24773)
		(end 309.232046 -87.201248)
		(width 0.0889)
		(layer "In11.Cu")
		(net "DMI_CPU0_PCH_TX_DP<2>")
	)
	(segment
		(start 310.670702 -87.200994)
		(end 310.62422 -87.154512)
		(width 0.0889)
		(layer "In11.Cu")
		(net "DMI_CPU0_PCH_TX_DP<2>")
	)
	(segment
		(start 360.458004 -109.258862)
		(end 361.026456 -106.415586)
		(width 0.1143)
		(layer "In11.Cu")
		(net "DMI_CPU0_PCH_TX_DP<2>")
	)
	(segment
		(start 308.512718 -87.200994)
		(end 308.466236 -87.154512)
		(width 0.0889)
		(layer "In11.Cu")
		(net "DMI_CPU0_PCH_TX_DP<2>")
	)
	(segment
		(start 332.621382 -86.161626)
		(end 320.511678 -88.584024)
		(width 0.1143)
		(layer "In11.Cu")
		(net "DMI_CPU0_PCH_TX_DP<2>")
	)
	(segment
		(start 307.509672 -86.798658)
		(end 307.242972 -86.798658)
		(width 0.0889)
		(layer "In11.Cu")
		(net "DMI_CPU0_PCH_TX_DP<2>")
	)
	(segment
		(start 310.311038 -87.201248)
		(end 310.264556 -87.24773)
		(width 0.0889)
		(layer "In11.Cu")
		(net "DMI_CPU0_PCH_TX_DP<2>")
	)
	(segment
		(start 355.171248 -98.248216)
		(end 355.340666 -97.400618)
		(width 0.1143)
		(layer "In11.Cu")
		(net "DMI_CPU0_PCH_TX_DP<2>")
	)
	(segment
		(start 310.264556 -87.24773)
		(end 309.997856 -87.24773)
		(width 0.0889)
		(layer "In11.Cu")
		(net "DMI_CPU0_PCH_TX_DP<2>")
	)
	(segment
		(start 355.10089 -86.53526)
		(end 353.743768 -85.636862)
		(width 0.1143)
		(layer "In11.Cu")
		(net "DMI_CPU0_PCH_TX_DP<2>")
	)
	(segment
		(start 307.152548 -86.708234)
		(end 306.921662 -86.708234)
		(width 0.0889)
		(layer "In11.Cu")
		(net "DMI_CPU0_PCH_TX_DP<2>")
	)
	(segment
		(start 311.030366 -87.200994)
		(end 311.030366 -87.201248)
		(width 0.0889)
		(layer "In11.Cu")
		(net "DMI_CPU0_PCH_TX_DP<2>")
	)
	(segment
		(start 309.545228 -87.24773)
		(end 309.278528 -87.24773)
		(width 0.0889)
		(layer "In11.Cu")
		(net "DMI_CPU0_PCH_TX_DP<2>")
	)
	(segment
		(start 354.76434 -93.742256)
		(end 355.772974 -91.30919)
		(width 0.1143)
		(layer "In11.Cu")
		(net "DMI_CPU0_PCH_TX_DP<2>")
	)
	(segment
		(start 355.791008 -101.348794)
		(end 355.773482 -101.261164)
		(width 0.1143)
		(layer "In11.Cu")
		(net "DMI_CPU0_PCH_TX_DP<2>")
	)
	(segment
		(start 311.519824 -87.205312)
		(end 311.469024 -87.154512)
		(width 0.0889)
		(layer "In11.Cu")
		(net "DMI_CPU0_PCH_TX_DP<2>")
	)
	(segment
		(start 310.311038 -87.200994)
		(end 310.311038 -87.201248)
		(width 0.0889)
		(layer "In11.Cu")
		(net "DMI_CPU0_PCH_TX_DP<2>")
	)
	(segment
		(start 362.987336 -113.23955)
		(end 361.791504 -113.00079)
		(width 0.1143)
		(layer "In11.Cu")
		(net "DMI_CPU0_PCH_TX_DP<2>")
	)
	(segment
		(start 361.060746 -106.242866)
		(end 360.30154 -104.586278)
		(width 0.1143)
		(layer "In11.Cu")
		(net "DMI_CPU0_PCH_TX_DP<2>")
	)
	(segment
		(start 361.061 -106.242866)
		(end 361.060746 -106.242866)
		(width 0.1143)
		(layer "In11.Cu")
		(net "DMI_CPU0_PCH_TX_DP<2>")
	)
	(segment
		(start 309.59171 -87.201248)
		(end 309.545228 -87.24773)
		(width 0.0889)
		(layer "In11.Cu")
		(net "DMI_CPU0_PCH_TX_DP<2>")
	)
	(segment
		(start 310.983884 -87.24773)
		(end 310.717184 -87.24773)
		(width 0.0889)
		(layer "In11.Cu")
		(net "DMI_CPU0_PCH_TX_DP<2>")
	)
	(segment
		(start 308.5592 -87.24773)
		(end 308.512718 -87.201248)
		(width 0.0889)
		(layer "In11.Cu")
		(net "DMI_CPU0_PCH_TX_DP<2>")
	)
	(segment
		(start 306.125626 -86.213188)
		(end 306.087272 -86.213188)
		(width 0.0889)
		(layer "In11.Cu")
		(net "DMI_CPU0_PCH_TX_DP<2>")
	)
	(segment
		(start 349.010478 -86.713822)
		(end 348.337378 -86.848188)
		(width 0.1143)
		(layer "In11.Cu")
		(net "DMI_CPU0_PCH_TX_DP<2>")
	)
	(segment
		(start 367.5761 -113.23955)
		(end 362.987336 -113.23955)
		(width 0.1143)
		(layer "In11.Cu")
		(net "DMI_CPU0_PCH_TX_DP<2>")
	)
	(segment
		(start 342.40978 -86.69401)
		(end 338.064602 -85.82533)
		(width 0.1143)
		(layer "In11.Cu")
		(net "DMI_CPU0_PCH_TX_DP<2>")
	)
	(segment
		(start 348.337378 -86.848188)
		(end 347.784166 -86.746588)
		(width 0.1143)
		(layer "In11.Cu")
		(net "DMI_CPU0_PCH_TX_DP<2>")
	)
	(segment
		(start 335.21015 -86.679532)
		(end 332.621382 -86.161626)
		(width 0.1143)
		(layer "In11.Cu")
		(net "DMI_CPU0_PCH_TX_DP<2>")
	)
	(segment
		(start 310.35752 -87.154512)
		(end 310.311038 -87.200994)
		(width 0.0889)
		(layer "In11.Cu")
		(net "DMI_CPU0_PCH_TX_DP<2>")
	)
	(segment
		(start 355.772974 -91.30919)
		(end 356.196392 -89.180162)
		(width 0.1143)
		(layer "In11.Cu")
		(net "DMI_CPU0_PCH_TX_DP<2>")
	)
	(segment
		(start 343.644728 -86.447122)
		(end 343.625424 -86.450932)
		(width 0.1143)
		(layer "In11.Cu")
		(net "DMI_CPU0_PCH_TX_DP<2>")
	)
	(segment
		(start 355.773482 -101.261164)
		(end 355.171248 -98.248216)
		(width 0.1143)
		(layer "In11.Cu")
		(net "DMI_CPU0_PCH_TX_DP<2>")
	)
	(segment
		(start 308.918864 -87.154512)
		(end 308.872382 -87.200994)
		(width 0.0889)
		(layer "In11.Cu")
		(net "DMI_CPU0_PCH_TX_DP<2>")
	)
	(segment
		(start 360.167682 -104.490266)
		(end 355.791008 -101.348794)
		(width 0.1143)
		(layer "In11.Cu")
		(net "DMI_CPU0_PCH_TX_DP<2>")
	)
	(segment
		(start 361.791504 -113.00079)
		(end 360.92257 -111.697008)
		(width 0.1143)
		(layer "In11.Cu")
		(net "DMI_CPU0_PCH_TX_DP<2>")
	)
	(segment
		(start 311.469024 -87.154512)
		(end 311.076848 -87.154512)
		(width 0.0889)
		(layer "In11.Cu")
		(net "DMI_CPU0_PCH_TX_DP<2>")
	)
	(segment
		(start 360.30154 -104.586278)
		(end 360.167682 -104.490266)
		(width 0.1143)
		(layer "In11.Cu")
		(net "DMI_CPU0_PCH_TX_DP<2>")
	)
	(segment
		(start 361.026456 -106.415586)
		(end 361.061 -106.242866)
		(width 0.1143)
		(layer "In11.Cu")
		(net "DMI_CPU0_PCH_TX_DP<2>")
	)
	(segment
		(start 308.872382 -87.200994)
		(end 308.872382 -87.201248)
		(width 0.0889)
		(layer "In11.Cu")
		(net "DMI_CPU0_PCH_TX_DP<2>")
	)
	(segment
		(start 308.8259 -87.24773)
		(end 308.5592 -87.24773)
		(width 0.0889)
		(layer "In11.Cu")
		(net "DMI_CPU0_PCH_TX_DP<2>")
	)
	(segment
		(start 338.064602 -85.82533)
		(end 337.81619 -85.775546)
		(width 0.1143)
		(layer "In11.Cu")
		(net "DMI_CPU0_PCH_TX_DP<2>")
	)
	(segment
		(start 306.495958 -86.479126)
		(end 306.438808 -86.392258)
		(width 0.0889)
		(layer "In11.Cu")
		(net "DMI_CPU0_PCH_TX_DP<2>")
	)
	(segment
		(start 310.62422 -87.154512)
		(end 310.35752 -87.154512)
		(width 0.0889)
		(layer "In11.Cu")
		(net "DMI_CPU0_PCH_TX_DP<2>")
	)
	(segment
		(start 356.196392 -89.180162)
		(end 355.10089 -86.53526)
		(width 0.1143)
		(layer "In11.Cu")
		(net "DMI_CPU0_PCH_TX_DP<2>")
	)
	(segment
		(start 308.872382 -87.201248)
		(end 308.8259 -87.24773)
		(width 0.0889)
		(layer "In11.Cu")
		(net "DMI_CPU0_PCH_TX_DP<2>")
	)
	(segment
		(start 307.600096 -86.708234)
		(end 307.509672 -86.798658)
		(width 0.0889)
		(layer "In11.Cu")
		(net "DMI_CPU0_PCH_TX_DP<2>")
	)
	(segment
		(start 355.340666 -97.400618)
		(end 354.76434 -93.742256)
		(width 0.1143)
		(layer "In11.Cu")
		(net "DMI_CPU0_PCH_TX_DP<2>")
	)
	(segment
		(start 309.638192 -87.154512)
		(end 309.59171 -87.200994)
		(width 0.0889)
		(layer "In11.Cu")
		(net "DMI_CPU0_PCH_TX_DP<2>")
	)
	(segment
		(start 309.59171 -87.200994)
		(end 309.59171 -87.201248)
		(width 0.0889)
		(layer "In11.Cu")
		(net "DMI_CPU0_PCH_TX_DP<2>")
	)
	(segment
		(start 349.822008 -86.176358)
		(end 349.010478 -86.713822)
		(width 0.1143)
		(layer "In11.Cu")
		(net "DMI_CPU0_PCH_TX_DP<2>")
	)
	(segment
		(start 309.951374 -87.201248)
		(end 309.951374 -87.200994)
		(width 0.0889)
		(layer "In11.Cu")
		(net "DMI_CPU0_PCH_TX_DP<2>")
	)
	(segment
		(start 305.81219 -86.782148)
		(end 306.105306 -86.612984)
		(width 0.0889)
		(layer "In11.Cu")
		(net "DMI_CPU0_PCH_TX_DP<2>")
	)
	(segment
		(start 309.997856 -87.24773)
		(end 309.951374 -87.201248)
		(width 0.0889)
		(layer "In11.Cu")
		(net "DMI_CPU0_PCH_TX_DP<2>")
	)
	(segment
		(start 347.784166 -86.746588)
		(end 345.670886 -87.08136)
		(width 0.1143)
		(layer "In11.Cu")
		(net "DMI_CPU0_PCH_TX_DP<2>")
	)
	(segment
		(start 308.512718 -87.201248)
		(end 308.512718 -87.200994)
		(width 0.0889)
		(layer "In11.Cu")
		(net "DMI_CPU0_PCH_TX_DP<2>")
	)
	(segment
		(start 360.92257 -111.697008)
		(end 360.446574 -109.316012)
		(width 0.1143)
		(layer "In11.Cu")
		(net "DMI_CPU0_PCH_TX_DP<2>")
	)
	(segment
		(start 360.446574 -109.316012)
		(end 360.45775 -109.258862)
		(width 0.1143)
		(layer "In11.Cu")
		(net "DMI_CPU0_PCH_TX_DP<2>")
	)
	(segment
		(start 307.242972 -86.798658)
		(end 307.152548 -86.708234)
		(width 0.0889)
		(layer "In11.Cu")
		(net "DMI_CPU0_PCH_TX_DP<2>")
	)
	(segment
		(start 313.42076 -87.205312)
		(end 311.541922 -87.205312)
		(width 0.1143)
		(layer "In11.Cu")
		(net "DMI_CPU0_PCH_TX_DP<2>")
	)
	(segment
		(start 353.10953 -85.507068)
		(end 349.822008 -86.176358)
		(width 0.1143)
		(layer "In11.Cu")
		(net "DMI_CPU0_PCH_TX_DP<2>")
	)
	(segment
		(start 309.951374 -87.200994)
		(end 309.904892 -87.154512)
		(width 0.0889)
		(layer "In11.Cu")
		(net "DMI_CPU0_PCH_TX_DP<2>")
	)
	(segment
		(start 311.030366 -87.201248)
		(end 310.983884 -87.24773)
		(width 0.0889)
		(layer "In11.Cu")
		(net "DMI_CPU0_PCH_TX_DP<2>")
	)
	(segment
		(start 311.541922 -87.205312)
		(end 311.519824 -87.205312)
		(width 0.0889)
		(layer "In11.Cu")
		(net "DMI_CPU0_PCH_TX_DP<2>")
	)
	(segment
		(start 367.665 -113.792)
		(end 367.665 -113.32845)
		(width 0.1143)
		(layer "In11.Cu")
		(net "DMI_CPU0_PCH_TX_DP<2>")
	)
	(segment
		(start 305.73345 -86.760812)
		(end 305.81219 -86.782148)
		(width 0.0889)
		(layer "In11.Cu")
		(net "DMI_CPU0_PCH_TX_DP<2>")
	)
	(segment
		(start 309.904892 -87.154512)
		(end 309.638192 -87.154512)
		(width 0.0889)
		(layer "In11.Cu")
		(net "DMI_CPU0_PCH_TX_DP<2>")
	)
	(segment
		(start 309.232046 -87.201248)
		(end 309.232046 -87.200994)
		(width 0.0889)
		(layer "In11.Cu")
		(net "DMI_CPU0_PCH_TX_DP<2>")
	)
	(segment
		(start 309.185564 -87.154512)
		(end 308.918864 -87.154512)
		(width 0.0889)
		(layer "In11.Cu")
		(net "DMI_CPU0_PCH_TX_DP<2>")
	)
	(segment
		(start 320.511678 -88.584024)
		(end 313.42076 -87.205312)
		(width 0.1143)
		(layer "In11.Cu")
		(net "DMI_CPU0_PCH_TX_DP<2>")
	)
	(segment
		(start 353.743768 -85.636862)
		(end 353.10953 -85.507068)
		(width 0.1143)
		(layer "In11.Cu")
		(net "DMI_CPU0_PCH_TX_DP<2>")
	)
	(segment
		(start 308.265576 -87.154512)
		(end 307.819298 -86.708234)
		(width 0.0889)
		(layer "In11.Cu")
		(net "DMI_CPU0_PCH_TX_DP<2>")
	)
	(arc
		(start 306.438808 -86.392258)
		(mid 306.303602 -86.265305)
		(end 306.125626 -86.213188)
		(width 0.0889)
		(layer "In11.Cu")
		(net "DMI_CPU0_PCH_TX_DP<2>")
	)
	(arc
		(start 306.087272 -86.213188)
		(mid 305.76937 -86.395849)
		(end 305.73345 -86.760812)
		(width 0.0889)
		(layer "In11.Cu")
		(net "DMI_CPU0_PCH_TX_DP<2>")
	)
	(arc
		(start 306.921662 -86.708234)
		(mid 306.679918 -86.647372)
		(end 306.495958 -86.479126)
		(width 0.0889)
		(layer "In11.Cu")
		(net "DMI_CPU0_PCH_TX_DP<2>")
	)
	(segment
		(start 363.728 -112.395)
		(end 363.7026 -112.4204)
		(width 0.1143)
		(layer "F.Cu")
		(net "DMI_CPU0_PCH_TX_DP<1>")
	)
	(segment
		(start 364.617 -112.395)
		(end 363.728 -112.395)
		(width 0.1143)
		(layer "F.Cu")
		(net "DMI_CPU0_PCH_TX_DP<1>")
	)
	(segment
		(start 304.675286 -86.117938)
		(end 305.246786 -86.117938)
		(width 0.1143)
		(layer "F.Cu")
		(net "DMI_CPU0_PCH_TX_DP<1>")
	)
	(via
		(at 363.7026 -112.4204)
		(size 0.508)
		(drill 0.254)
		(layers "F.Cu" "B.Cu")
		(net "DMI_CPU0_PCH_TX_DP<1>")
	)
	(via
		(at 305.246786 -86.117938)
		(size 0.508)
		(drill 0.254)
		(layers "F.Cu" "B.Cu")
		(net "DMI_CPU0_PCH_TX_DP<1>")
	)
	(segment
		(start 356.87508 -89.116154)
		(end 355.623368 -86.093046)
		(width 0.1143)
		(layer "In11.Cu")
		(net "DMI_CPU0_PCH_TX_DP<1>")
	)
	(segment
		(start 347.983048 -85.36305)
		(end 347.049344 -85.549486)
		(width 0.1143)
		(layer "In11.Cu")
		(net "DMI_CPU0_PCH_TX_DP<1>")
	)
	(segment
		(start 363.855 -111.98225)
		(end 363.753146 -111.880396)
		(width 0.1143)
		(layer "In11.Cu")
		(net "DMI_CPU0_PCH_TX_DP<1>")
	)
	(segment
		(start 361.218988 -109.034072)
		(end 361.742736 -106.415332)
		(width 0.1143)
		(layer "In11.Cu")
		(net "DMI_CPU0_PCH_TX_DP<1>")
	)
	(segment
		(start 348.843346 -85.720682)
		(end 347.983048 -85.36305)
		(width 0.1143)
		(layer "In11.Cu")
		(net "DMI_CPU0_PCH_TX_DP<1>")
	)
	(segment
		(start 345.12631 -85.165946)
		(end 344.620088 -84.829142)
		(width 0.1143)
		(layer "In11.Cu")
		(net "DMI_CPU0_PCH_TX_DP<1>")
	)
	(segment
		(start 355.845618 -98.204274)
		(end 356.057962 -97.142808)
		(width 0.1143)
		(layer "In11.Cu")
		(net "DMI_CPU0_PCH_TX_DP<1>")
	)
	(segment
		(start 356.39502 -100.952046)
		(end 356.37216 -100.839016)
		(width 0.1143)
		(layer "In11.Cu")
		(net "DMI_CPU0_PCH_TX_DP<1>")
	)
	(segment
		(start 353.250754 -84.824316)
		(end 348.843346 -85.720682)
		(width 0.1143)
		(layer "In11.Cu")
		(net "DMI_CPU0_PCH_TX_DP<1>")
	)
	(segment
		(start 356.37216 -100.839016)
		(end 356.372414 -100.839016)
		(width 0.1143)
		(layer "In11.Cu")
		(net "DMI_CPU0_PCH_TX_DP<1>")
	)
	(segment
		(start 356.372414 -100.839016)
		(end 355.845618 -98.204274)
		(width 0.1143)
		(layer "In11.Cu")
		(net "DMI_CPU0_PCH_TX_DP<1>")
	)
	(segment
		(start 308.659276 -85.983572)
		(end 308.637178 -85.983572)
		(width 0.0889)
		(layer "In11.Cu")
		(net "DMI_CPU0_PCH_TX_DP<1>")
	)
	(segment
		(start 356.057962 -97.142808)
		(end 355.505004 -93.632528)
		(width 0.1143)
		(layer "In11.Cu")
		(net "DMI_CPU0_PCH_TX_DP<1>")
	)
	(segment
		(start 347.049344 -85.549486)
		(end 345.12631 -85.165946)
		(width 0.1143)
		(layer "In11.Cu")
		(net "DMI_CPU0_PCH_TX_DP<1>")
	)
	(segment
		(start 308.586378 -85.932772)
		(end 307.938678 -85.932772)
		(width 0.0889)
		(layer "In11.Cu")
		(net "DMI_CPU0_PCH_TX_DP<1>")
	)
	(segment
		(start 361.742736 -106.415332)
		(end 361.77347 -106.261154)
		(width 0.1143)
		(layer "In11.Cu")
		(net "DMI_CPU0_PCH_TX_DP<1>")
	)
	(segment
		(start 356.40772 -91.454478)
		(end 356.87508 -89.116154)
		(width 0.1143)
		(layer "In11.Cu")
		(net "DMI_CPU0_PCH_TX_DP<1>")
	)
	(segment
		(start 320.690748 -87.86241)
		(end 311.037478 -85.983572)
		(width 0.1143)
		(layer "In11.Cu")
		(net "DMI_CPU0_PCH_TX_DP<1>")
	)
	(segment
		(start 344.620088 -84.829142)
		(end 340.240874 -83.952842)
		(width 0.1143)
		(layer "In11.Cu")
		(net "DMI_CPU0_PCH_TX_DP<1>")
	)
	(segment
		(start 353.903026 -84.954872)
		(end 353.250754 -84.824316)
		(width 0.1143)
		(layer "In11.Cu")
		(net "DMI_CPU0_PCH_TX_DP<1>")
	)
	(segment
		(start 307.938678 -85.932772)
		(end 307.723794 -85.717888)
		(width 0.0889)
		(layer "In11.Cu")
		(net "DMI_CPU0_PCH_TX_DP<1>")
	)
	(segment
		(start 360.785664 -104.104186)
		(end 356.39502 -100.952046)
		(width 0.1143)
		(layer "In11.Cu")
		(net "DMI_CPU0_PCH_TX_DP<1>")
	)
	(segment
		(start 355.623368 -86.093046)
		(end 353.903026 -84.954872)
		(width 0.1143)
		(layer "In11.Cu")
		(net "DMI_CPU0_PCH_TX_DP<1>")
	)
	(segment
		(start 361.77347 -106.261154)
		(end 360.785664 -104.104186)
		(width 0.1143)
		(layer "In11.Cu")
		(net "DMI_CPU0_PCH_TX_DP<1>")
	)
	(segment
		(start 305.246786 -85.806788)
		(end 305.246786 -86.117938)
		(width 0.0889)
		(layer "In11.Cu")
		(net "DMI_CPU0_PCH_TX_DP<1>")
	)
	(segment
		(start 307.723794 -85.717888)
		(end 305.335686 -85.717888)
		(width 0.0889)
		(layer "In11.Cu")
		(net "DMI_CPU0_PCH_TX_DP<1>")
	)
	(segment
		(start 355.505004 -93.632528)
		(end 356.40772 -91.454478)
		(width 0.1143)
		(layer "In11.Cu")
		(net "DMI_CPU0_PCH_TX_DP<1>")
	)
	(segment
		(start 363.7026 -112.4204)
		(end 363.855 -112.268)
		(width 0.1143)
		(layer "In11.Cu")
		(net "DMI_CPU0_PCH_TX_DP<1>")
	)
	(segment
		(start 363.855 -112.268)
		(end 363.855 -111.98225)
		(width 0.1143)
		(layer "In11.Cu")
		(net "DMI_CPU0_PCH_TX_DP<1>")
	)
	(segment
		(start 340.240874 -83.952842)
		(end 320.690748 -87.86241)
		(width 0.1143)
		(layer "In11.Cu")
		(net "DMI_CPU0_PCH_TX_DP<1>")
	)
	(segment
		(start 305.335686 -85.717888)
		(end 305.246786 -85.806788)
		(width 0.0889)
		(layer "In11.Cu")
		(net "DMI_CPU0_PCH_TX_DP<1>")
	)
	(segment
		(start 363.753146 -111.880396)
		(end 362.154724 -111.880396)
		(width 0.1143)
		(layer "In11.Cu")
		(net "DMI_CPU0_PCH_TX_DP<1>")
	)
	(segment
		(start 362.154724 -111.880396)
		(end 361.63123 -111.095028)
		(width 0.1143)
		(layer "In11.Cu")
		(net "DMI_CPU0_PCH_TX_DP<1>")
	)
	(segment
		(start 311.037478 -85.983572)
		(end 308.659276 -85.983572)
		(width 0.1143)
		(layer "In11.Cu")
		(net "DMI_CPU0_PCH_TX_DP<1>")
	)
	(segment
		(start 308.637178 -85.983572)
		(end 308.586378 -85.932772)
		(width 0.0889)
		(layer "In11.Cu")
		(net "DMI_CPU0_PCH_TX_DP<1>")
	)
	(segment
		(start 361.63123 -111.095028)
		(end 361.218988 -109.034072)
		(width 0.1143)
		(layer "In11.Cu")
		(net "DMI_CPU0_PCH_TX_DP<1>")
	)
	(segment
		(start 304.388266 -84.631784)
		(end 303.816766 -84.631784)
		(width 0.1143)
		(layer "F.Cu")
		(net "DMI_CPU0_PCH_TX_DP<0>")
	)
	(segment
		(start 367.792 -110.998)
		(end 368.554 -110.998)
		(width 0.1143)
		(layer "F.Cu")
		(net "DMI_CPU0_PCH_TX_DP<0>")
	)
	(via
		(at 367.792 -110.998)
		(size 0.508)
		(drill 0.254)
		(layers "F.Cu" "B.Cu")
		(net "DMI_CPU0_PCH_TX_DP<0>")
	)
	(via
		(at 304.388266 -84.631784)
		(size 0.508)
		(drill 0.254)
		(layers "F.Cu" "B.Cu")
		(net "DMI_CPU0_PCH_TX_DP<0>")
	)
	(segment
		(start 356.986332 -100.580444)
		(end 356.51821 -98.241358)
		(width 0.1143)
		(layer "In11.Cu")
		(net "DMI_CPU0_PCH_TX_DP<0>")
	)
	(segment
		(start 308.864 -85.2805)
		(end 308.841902 -85.2805)
		(width 0.0889)
		(layer "In11.Cu")
		(net "DMI_CPU0_PCH_TX_DP<0>")
	)
	(segment
		(start 365.326168 -110.44555)
		(end 364.1344 -109.680502)
		(width 0.1143)
		(layer "In11.Cu")
		(net "DMI_CPU0_PCH_TX_DP<0>")
	)
	(segment
		(start 305.264312 -84.727288)
		(end 305.229006 -84.727288)
		(width 0.0889)
		(layer "In11.Cu")
		(net "DMI_CPU0_PCH_TX_DP<0>")
	)
	(segment
		(start 305.681634 -85.080094)
		(end 305.593496 -84.927186)
		(width 0.0889)
		(layer "In11.Cu")
		(net "DMI_CPU0_PCH_TX_DP<0>")
	)
	(segment
		(start 320.806572 -87.151718)
		(end 311.449974 -85.2805)
		(width 0.1143)
		(layer "In11.Cu")
		(net "DMI_CPU0_PCH_TX_DP<0>")
	)
	(segment
		(start 353.766628 -82.96656)
		(end 352.776028 -83.163918)
		(width 0.1143)
		(layer "In11.Cu")
		(net "DMI_CPU0_PCH_TX_DP<0>")
	)
	(segment
		(start 345.934792 -83.486752)
		(end 343.808558 -83.911948)
		(width 0.1143)
		(layer "In11.Cu")
		(net "DMI_CPU0_PCH_TX_DP<0>")
	)
	(segment
		(start 356.8954 -86.550246)
		(end 356.549706 -84.8233)
		(width 0.1143)
		(layer "In11.Cu")
		(net "DMI_CPU0_PCH_TX_DP<0>")
	)
	(segment
		(start 358.45369 -101.648006)
		(end 356.986332 -100.580444)
		(width 0.1143)
		(layer "In11.Cu")
		(net "DMI_CPU0_PCH_TX_DP<0>")
	)
	(segment
		(start 350.939354 -84.094828)
		(end 348.07906 -83.522312)
		(width 0.1143)
		(layer "In11.Cu")
		(net "DMI_CPU0_PCH_TX_DP<0>")
	)
	(segment
		(start 356.51821 -98.241358)
		(end 356.77729 -96.94672)
		(width 0.1143)
		(layer "In11.Cu")
		(net "DMI_CPU0_PCH_TX_DP<0>")
	)
	(segment
		(start 351.569274 -83.96859)
		(end 350.939354 -84.094828)
		(width 0.1143)
		(layer "In11.Cu")
		(net "DMI_CPU0_PCH_TX_DP<0>")
	)
	(segment
		(start 343.808558 -83.911948)
		(end 343.625424 -83.875372)
		(width 0.1143)
		(layer "In11.Cu")
		(net "DMI_CPU0_PCH_TX_DP<0>")
	)
	(segment
		(start 348.07906 -83.522312)
		(end 347.096334 -83.718908)
		(width 0.1143)
		(layer "In11.Cu")
		(net "DMI_CPU0_PCH_TX_DP<0>")
	)
	(segment
		(start 354.687378 -83.15071)
		(end 353.766628 -82.96656)
		(width 0.1143)
		(layer "In11.Cu")
		(net "DMI_CPU0_PCH_TX_DP<0>")
	)
	(segment
		(start 304.681382 -84.462874)
		(end 304.388266 -84.631784)
		(width 0.0889)
		(layer "In11.Cu")
		(net "DMI_CPU0_PCH_TX_DP<0>")
	)
	(segment
		(start 356.03307 -84.048092)
		(end 354.687378 -83.15071)
		(width 0.1143)
		(layer "In11.Cu")
		(net "DMI_CPU0_PCH_TX_DP<0>")
	)
	(segment
		(start 367.792 -110.998)
		(end 367.792 -110.540546)
		(width 0.1143)
		(layer "In11.Cu")
		(net "DMI_CPU0_PCH_TX_DP<0>")
	)
	(segment
		(start 305.94046 -85.2297)
		(end 305.681634 -85.080094)
		(width 0.0889)
		(layer "In11.Cu")
		(net "DMI_CPU0_PCH_TX_DP<0>")
	)
	(segment
		(start 311.449974 -85.2805)
		(end 308.864 -85.2805)
		(width 0.1143)
		(layer "In11.Cu")
		(net "DMI_CPU0_PCH_TX_DP<0>")
	)
	(segment
		(start 357.670354 -88.463374)
		(end 356.8954 -86.550246)
		(width 0.1143)
		(layer "In11.Cu")
		(net "DMI_CPU0_PCH_TX_DP<0>")
	)
	(segment
		(start 356.25659 -93.640656)
		(end 356.988364 -91.87561)
		(width 0.1143)
		(layer "In11.Cu")
		(net "DMI_CPU0_PCH_TX_DP<0>")
	)
	(segment
		(start 367.792 -110.540546)
		(end 367.697004 -110.44555)
		(width 0.1143)
		(layer "In11.Cu")
		(net "DMI_CPU0_PCH_TX_DP<0>")
	)
	(segment
		(start 364.1344 -109.680502)
		(end 364.106968 -109.662976)
		(width 0.1143)
		(layer "In11.Cu")
		(net "DMI_CPU0_PCH_TX_DP<0>")
	)
	(segment
		(start 304.77079 -84.487004)
		(end 304.681382 -84.462874)
		(width 0.0889)
		(layer "In11.Cu")
		(net "DMI_CPU0_PCH_TX_DP<0>")
	)
	(segment
		(start 361.40644 -103.76789)
		(end 358.45369 -101.648006)
		(width 0.1143)
		(layer "In11.Cu")
		(net "DMI_CPU0_PCH_TX_DP<0>")
	)
	(segment
		(start 352.776028 -83.163918)
		(end 351.569274 -83.96859)
		(width 0.1143)
		(layer "In11.Cu")
		(net "DMI_CPU0_PCH_TX_DP<0>")
	)
	(segment
		(start 308.791102 -85.2297)
		(end 305.94046 -85.2297)
		(width 0.0889)
		(layer "In11.Cu")
		(net "DMI_CPU0_PCH_TX_DP<0>")
	)
	(segment
		(start 364.106968 -109.662976)
		(end 361.40644 -103.76789)
		(width 0.1143)
		(layer "In11.Cu")
		(net "DMI_CPU0_PCH_TX_DP<0>")
	)
	(segment
		(start 356.77729 -96.94672)
		(end 356.25659 -93.640656)
		(width 0.1143)
		(layer "In11.Cu")
		(net "DMI_CPU0_PCH_TX_DP<0>")
	)
	(segment
		(start 343.625424 -83.875372)
		(end 340.412324 -83.231736)
		(width 0.1143)
		(layer "In11.Cu")
		(net "DMI_CPU0_PCH_TX_DP<0>")
	)
	(segment
		(start 367.697004 -110.44555)
		(end 365.326168 -110.44555)
		(width 0.1143)
		(layer "In11.Cu")
		(net "DMI_CPU0_PCH_TX_DP<0>")
	)
	(segment
		(start 308.841902 -85.2805)
		(end 308.791102 -85.2297)
		(width 0.0889)
		(layer "In11.Cu")
		(net "DMI_CPU0_PCH_TX_DP<0>")
	)
	(segment
		(start 356.549706 -84.8233)
		(end 356.03307 -84.048092)
		(width 0.1143)
		(layer "In11.Cu")
		(net "DMI_CPU0_PCH_TX_DP<0>")
	)
	(segment
		(start 356.988364 -91.87561)
		(end 357.670354 -88.463374)
		(width 0.1143)
		(layer "In11.Cu")
		(net "DMI_CPU0_PCH_TX_DP<0>")
	)
	(segment
		(start 347.096334 -83.718908)
		(end 345.934792 -83.486752)
		(width 0.1143)
		(layer "In11.Cu")
		(net "DMI_CPU0_PCH_TX_DP<0>")
	)
	(segment
		(start 340.412324 -83.231736)
		(end 320.806572 -87.151718)
		(width 0.1143)
		(layer "In11.Cu")
		(net "DMI_CPU0_PCH_TX_DP<0>")
	)
	(arc
		(start 305.229006 -84.727288)
		(mid 304.972184 -84.659987)
		(end 304.77079 -84.487004)
		(width 0.0889)
		(layer "In11.Cu")
		(net "DMI_CPU0_PCH_TX_DP<0>")
	)
	(arc
		(start 305.593496 -84.927186)
		(mid 305.454503 -84.785106)
		(end 305.264312 -84.727288)
		(width 0.0889)
		(layer "In11.Cu")
		(net "DMI_CPU0_PCH_TX_DP<0>")
	)
	(segment
		(start 303.816766 -87.603584)
		(end 304.388266 -87.603584)
		(width 0.1143)
		(layer "F.Cu")
		(net "DMI_CPU0_PCH_TX_DN<3>")
	)
	(segment
		(start 364.617 -113.792)
		(end 363.7026 -113.792)
		(width 0.1143)
		(layer "F.Cu")
		(net "DMI_CPU0_PCH_TX_DN<3>")
	)
	(via
		(at 363.7026 -113.792)
		(size 0.508)
		(drill 0.254)
		(layers "F.Cu" "B.Cu")
		(net "DMI_CPU0_PCH_TX_DN<3>")
	)
	(via
		(at 304.388266 -87.603584)
		(size 0.508)
		(drill 0.254)
		(layers "F.Cu" "B.Cu")
		(net "DMI_CPU0_PCH_TX_DN<3>")
	)
	(segment
		(start 360.596942 -112.25784)
		(end 360.596942 -112.257586)
		(width 0.1143)
		(layer "In11.Cu")
		(net "DMI_CPU0_PCH_TX_DN<3>")
	)
	(segment
		(start 344.584274 -87.923116)
		(end 343.971626 -87.514684)
		(width 0.1143)
		(layer "In11.Cu")
		(net "DMI_CPU0_PCH_TX_DN<3>")
	)
	(segment
		(start 363.7534 -114.35715)
		(end 362.864908 -114.35715)
		(width 0.1143)
		(layer "In11.Cu")
		(net "DMI_CPU0_PCH_TX_DN<3>")
	)
	(segment
		(start 355.391466 -91.14282)
		(end 355.397308 -91.114372)
		(width 0.1143)
		(layer "In11.Cu")
		(net "DMI_CPU0_PCH_TX_DN<3>")
	)
	(segment
		(start 362.864908 -114.35715)
		(end 361.862878 -114.15649)
		(width 0.1143)
		(layer "In11.Cu")
		(net "DMI_CPU0_PCH_TX_DN<3>")
	)
	(segment
		(start 345.10091 -88.026494)
		(end 344.584274 -87.923116)
		(width 0.1143)
		(layer "In11.Cu")
		(net "DMI_CPU0_PCH_TX_DN<3>")
	)
	(segment
		(start 347.415104 -87.768938)
		(end 347.415104 -87.768684)
		(width 0.1143)
		(layer "In11.Cu")
		(net "DMI_CPU0_PCH_TX_DN<3>")
	)
	(segment
		(start 353.65563 -86.077552)
		(end 352.863404 -85.914484)
		(width 0.1143)
		(layer "In11.Cu")
		(net "DMI_CPU0_PCH_TX_DN<3>")
	)
	(segment
		(start 360.002836 -109.287056)
		(end 360.167682 -108.462826)
		(width 0.1143)
		(layer "In11.Cu")
		(net "DMI_CPU0_PCH_TX_DN<3>")
	)
	(segment
		(start 336.890868 -87.52713)
		(end 332.339442 -86.617048)
		(width 0.1143)
		(layer "In11.Cu")
		(net "DMI_CPU0_PCH_TX_DN<3>")
	)
	(segment
		(start 359.97261 -104.833674)
		(end 355.378258 -101.535992)
		(width 0.1143)
		(layer "In11.Cu")
		(net "DMI_CPU0_PCH_TX_DN<3>")
	)
	(segment
		(start 348.15399 -87.826596)
		(end 347.929962 -87.871554)
		(width 0.1143)
		(layer "In11.Cu")
		(net "DMI_CPU0_PCH_TX_DN<3>")
	)
	(segment
		(start 360.167682 -108.462826)
		(end 360.57713 -106.41584)
		(width 0.1143)
		(layer "In11.Cu")
		(net "DMI_CPU0_PCH_TX_DN<3>")
	)
	(segment
		(start 313.275472 -88.080342)
		(end 313.26963 -88.0745)
		(width 0.1143)
		(layer "In11.Cu")
		(net "DMI_CPU0_PCH_TX_DN<3>")
	)
	(segment
		(start 343.971626 -87.514684)
		(end 339.230716 -86.565994)
		(width 0.1143)
		(layer "In11.Cu")
		(net "DMI_CPU0_PCH_TX_DN<3>")
	)
	(segment
		(start 355.397308 -91.114372)
		(end 355.397054 -91.114372)
		(width 0.1143)
		(layer "In11.Cu")
		(net "DMI_CPU0_PCH_TX_DN<3>")
	)
	(segment
		(start 355.378258 -101.535992)
		(end 355.32314 -101.261164)
		(width 0.1143)
		(layer "In11.Cu")
		(net "DMI_CPU0_PCH_TX_DN<3>")
	)
	(segment
		(start 363.855 -114.25555)
		(end 363.7534 -114.35715)
		(width 0.1143)
		(layer "In11.Cu")
		(net "DMI_CPU0_PCH_TX_DN<3>")
	)
	(segment
		(start 355.786182 -89.17305)
		(end 354.854256 -86.871048)
		(width 0.1143)
		(layer "In11.Cu")
		(net "DMI_CPU0_PCH_TX_DN<3>")
	)
	(segment
		(start 319.052194 -89.27465)
		(end 313.275472 -88.080342)
		(width 0.1143)
		(layer "In11.Cu")
		(net "DMI_CPU0_PCH_TX_DN<3>")
	)
	(segment
		(start 355.397054 -91.114372)
		(end 355.786182 -89.17305)
		(width 0.1143)
		(layer "In11.Cu")
		(net "DMI_CPU0_PCH_TX_DN<3>")
	)
	(segment
		(start 307.184298 -87.508588)
		(end 305.232054 -87.508588)
		(width 0.0889)
		(layer "In11.Cu")
		(net "DMI_CPU0_PCH_TX_DN<3>")
	)
	(segment
		(start 339.230716 -86.565994)
		(end 336.890868 -87.52713)
		(width 0.1143)
		(layer "In11.Cu")
		(net "DMI_CPU0_PCH_TX_DN<3>")
	)
	(segment
		(start 304.791364 -87.691468)
		(end 304.738786 -87.743792)
		(width 0.0889)
		(layer "In11.Cu")
		(net "DMI_CPU0_PCH_TX_DN<3>")
	)
	(segment
		(start 354.854256 -86.871048)
		(end 354.240592 -86.464648)
		(width 0.1143)
		(layer "In11.Cu")
		(net "DMI_CPU0_PCH_TX_DN<3>")
	)
	(segment
		(start 360.596942 -112.257586)
		(end 360.002836 -109.287056)
		(width 0.1143)
		(layer "In11.Cu")
		(net "DMI_CPU0_PCH_TX_DN<3>")
	)
	(segment
		(start 361.862878 -114.15649)
		(end 360.596942 -112.25784)
		(width 0.1143)
		(layer "In11.Cu")
		(net "DMI_CPU0_PCH_TX_DN<3>")
	)
	(segment
		(start 350.23933 -86.446614)
		(end 348.15399 -87.826596)
		(width 0.1143)
		(layer "In11.Cu")
		(net "DMI_CPU0_PCH_TX_DN<3>")
	)
	(segment
		(start 360.167682 -105.259378)
		(end 359.97261 -104.833674)
		(width 0.1143)
		(layer "In11.Cu")
		(net "DMI_CPU0_PCH_TX_DN<3>")
	)
	(segment
		(start 355.32314 -101.261164)
		(end 354.767896 -98.48596)
		(width 0.1143)
		(layer "In11.Cu")
		(net "DMI_CPU0_PCH_TX_DN<3>")
	)
	(segment
		(start 354.240592 -86.464902)
		(end 353.65563 -86.077552)
		(width 0.1143)
		(layer "In11.Cu")
		(net "DMI_CPU0_PCH_TX_DN<3>")
	)
	(segment
		(start 352.863404 -85.914484)
		(end 350.23933 -86.446614)
		(width 0.1143)
		(layer "In11.Cu")
		(net "DMI_CPU0_PCH_TX_DN<3>")
	)
	(segment
		(start 360.57713 -106.41584)
		(end 360.613706 -106.23296)
		(width 0.1143)
		(layer "In11.Cu")
		(net "DMI_CPU0_PCH_TX_DN<3>")
	)
	(segment
		(start 347.929962 -87.871554)
		(end 347.415104 -87.768938)
		(width 0.1143)
		(layer "In11.Cu")
		(net "DMI_CPU0_PCH_TX_DN<3>")
	)
	(segment
		(start 360.613706 -106.23296)
		(end 360.167682 -105.259378)
		(width 0.1143)
		(layer "In11.Cu")
		(net "DMI_CPU0_PCH_TX_DN<3>")
	)
	(segment
		(start 354.767896 -98.48596)
		(end 354.948744 -97.58172)
		(width 0.1143)
		(layer "In11.Cu")
		(net "DMI_CPU0_PCH_TX_DN<3>")
	)
	(segment
		(start 347.415104 -87.768684)
		(end 346.901008 -87.666576)
		(width 0.1143)
		(layer "In11.Cu")
		(net "DMI_CPU0_PCH_TX_DN<3>")
	)
	(segment
		(start 332.339442 -86.617048)
		(end 319.052194 -89.27465)
		(width 0.1143)
		(layer "In11.Cu")
		(net "DMI_CPU0_PCH_TX_DN<3>")
	)
	(segment
		(start 308.483 -88.0745)
		(end 308.460902 -88.0745)
		(width 0.0889)
		(layer "In11.Cu")
		(net "DMI_CPU0_PCH_TX_DN<3>")
	)
	(segment
		(start 363.855 -113.9444)
		(end 363.855 -114.25555)
		(width 0.1143)
		(layer "In11.Cu")
		(net "DMI_CPU0_PCH_TX_DN<3>")
	)
	(segment
		(start 308.410102 -88.1253)
		(end 307.80101 -88.1253)
		(width 0.0889)
		(layer "In11.Cu")
		(net "DMI_CPU0_PCH_TX_DN<3>")
	)
	(segment
		(start 304.738786 -87.743792)
		(end 304.665634 -87.763604)
		(width 0.0889)
		(layer "In11.Cu")
		(net "DMI_CPU0_PCH_TX_DN<3>")
	)
	(segment
		(start 307.80101 -88.1253)
		(end 307.184298 -87.508588)
		(width 0.0889)
		(layer "In11.Cu")
		(net "DMI_CPU0_PCH_TX_DN<3>")
	)
	(segment
		(start 354.22459 -93.95841)
		(end 355.391466 -91.14282)
		(width 0.1143)
		(layer "In11.Cu")
		(net "DMI_CPU0_PCH_TX_DN<3>")
	)
	(segment
		(start 354.948744 -97.58172)
		(end 354.22459 -93.95841)
		(width 0.1143)
		(layer "In11.Cu")
		(net "DMI_CPU0_PCH_TX_DN<3>")
	)
	(segment
		(start 304.665634 -87.763604)
		(end 304.388266 -87.603584)
		(width 0.0889)
		(layer "In11.Cu")
		(net "DMI_CPU0_PCH_TX_DN<3>")
	)
	(segment
		(start 354.240592 -86.464648)
		(end 354.240592 -86.464902)
		(width 0.1143)
		(layer "In11.Cu")
		(net "DMI_CPU0_PCH_TX_DN<3>")
	)
	(segment
		(start 308.460902 -88.0745)
		(end 308.410102 -88.1253)
		(width 0.0889)
		(layer "In11.Cu")
		(net "DMI_CPU0_PCH_TX_DN<3>")
	)
	(segment
		(start 346.901008 -87.666576)
		(end 345.10091 -88.026494)
		(width 0.1143)
		(layer "In11.Cu")
		(net "DMI_CPU0_PCH_TX_DN<3>")
	)
	(segment
		(start 363.7026 -113.792)
		(end 363.855 -113.9444)
		(width 0.1143)
		(layer "In11.Cu")
		(net "DMI_CPU0_PCH_TX_DN<3>")
	)
	(segment
		(start 313.26963 -88.0745)
		(end 308.483 -88.0745)
		(width 0.1143)
		(layer "In11.Cu")
		(net "DMI_CPU0_PCH_TX_DN<3>")
	)
	(arc
		(start 305.232054 -87.508588)
		(mid 304.993459 -87.556039)
		(end 304.791364 -87.691468)
		(width 0.0889)
		(layer "In11.Cu")
		(net "DMI_CPU0_PCH_TX_DN<3>")
	)
	(segment
		(start 304.675286 -87.108538)
		(end 305.246786 -87.108538)
		(width 0.1143)
		(layer "F.Cu")
		(net "DMI_CPU0_PCH_TX_DN<2>")
	)
	(segment
		(start 367.7158 -112.395)
		(end 368.554 -112.395)
		(width 0.1143)
		(layer "F.Cu")
		(net "DMI_CPU0_PCH_TX_DN<2>")
	)
	(via
		(at 305.246786 -87.108538)
		(size 0.508)
		(drill 0.254)
		(layers "F.Cu" "B.Cu")
		(net "DMI_CPU0_PCH_TX_DN<2>")
	)
	(via
		(at 367.7158 -112.395)
		(size 0.508)
		(drill 0.254)
		(layers "F.Cu" "B.Cu")
		(net "DMI_CPU0_PCH_TX_DN<2>")
	)
	(segment
		(start 367.6015 -112.94745)
		(end 363.016292 -112.94745)
		(width 0.1143)
		(layer "In11.Cu")
		(net "DMI_CPU0_PCH_TX_DN<2>")
	)
	(segment
		(start 360.971084 -110.44936)
		(end 360.971084 -110.449106)
		(width 0.1143)
		(layer "In11.Cu")
		(net "DMI_CPU0_PCH_TX_DN<2>")
	)
	(segment
		(start 356.053898 -91.394534)
		(end 356.500176 -89.15019)
		(width 0.1143)
		(layer "In11.Cu")
		(net "DMI_CPU0_PCH_TX_DN<2>")
	)
	(segment
		(start 367.7158 -112.395)
		(end 367.7158 -112.83315)
		(width 0.1143)
		(layer "In11.Cu")
		(net "DMI_CPU0_PCH_TX_DN<2>")
	)
	(segment
		(start 332.621382 -85.863684)
		(end 320.510916 -88.286082)
		(width 0.1143)
		(layer "In11.Cu")
		(net "DMI_CPU0_PCH_TX_DN<2>")
	)
	(segment
		(start 355.336602 -86.34095)
		(end 353.857814 -85.362034)
		(width 0.1143)
		(layer "In11.Cu")
		(net "DMI_CPU0_PCH_TX_DN<2>")
	)
	(segment
		(start 313.471052 -86.913212)
		(end 311.541922 -86.913212)
		(width 0.1143)
		(layer "In11.Cu")
		(net "DMI_CPU0_PCH_TX_DN<2>")
	)
	(segment
		(start 361.197652 -111.582962)
		(end 360.971084 -110.44936)
		(width 0.1143)
		(layer "In11.Cu")
		(net "DMI_CPU0_PCH_TX_DN<2>")
	)
	(segment
		(start 353.109784 -85.208872)
		(end 349.707962 -85.901276)
		(width 0.1143)
		(layer "In11.Cu")
		(net "DMI_CPU0_PCH_TX_DN<2>")
	)
	(segment
		(start 361.967526 -112.7379)
		(end 361.197652 -111.582962)
		(width 0.1143)
		(layer "In11.Cu")
		(net "DMI_CPU0_PCH_TX_DN<2>")
	)
	(segment
		(start 347.787722 -86.45017)
		(end 345.69273 -86.781894)
		(width 0.1143)
		(layer "In11.Cu")
		(net "DMI_CPU0_PCH_TX_DN<2>")
	)
	(segment
		(start 349.707962 -85.901276)
		(end 348.89694 -86.438486)
		(width 0.1143)
		(layer "In11.Cu")
		(net "DMI_CPU0_PCH_TX_DN<2>")
	)
	(segment
		(start 355.46919 -98.248216)
		(end 355.637338 -97.406714)
		(width 0.1143)
		(layer "In11.Cu")
		(net "DMI_CPU0_PCH_TX_DN<2>")
	)
	(segment
		(start 348.89694 -86.438486)
		(end 348.335092 -86.550754)
		(width 0.1143)
		(layer "In11.Cu")
		(net "DMI_CPU0_PCH_TX_DN<2>")
	)
	(segment
		(start 308.34457 -86.964012)
		(end 307.898292 -86.517734)
		(width 0.0889)
		(layer "In11.Cu")
		(net "DMI_CPU0_PCH_TX_DN<2>")
	)
	(segment
		(start 361.366054 -106.207306)
		(end 360.534966 -104.394)
		(width 0.1143)
		(layer "In11.Cu")
		(net "DMI_CPU0_PCH_TX_DN<2>")
	)
	(segment
		(start 305.563778 -86.849966)
		(end 305.539902 -86.939374)
		(width 0.0889)
		(layer "In11.Cu")
		(net "DMI_CPU0_PCH_TX_DN<2>")
	)
	(segment
		(start 343.66073 -86.145878)
		(end 342.40978 -86.396068)
		(width 0.1143)
		(layer "In11.Cu")
		(net "DMI_CPU0_PCH_TX_DN<2>")
	)
	(segment
		(start 311.519824 -86.913212)
		(end 311.469024 -86.964012)
		(width 0.0889)
		(layer "In11.Cu")
		(net "DMI_CPU0_PCH_TX_DN<2>")
	)
	(segment
		(start 356.054914 -101.178614)
		(end 355.46919 -98.248216)
		(width 0.1143)
		(layer "In11.Cu")
		(net "DMI_CPU0_PCH_TX_DN<2>")
	)
	(segment
		(start 360.744516 -109.316012)
		(end 361.324398 -106.415332)
		(width 0.1143)
		(layer "In11.Cu")
		(net "DMI_CPU0_PCH_TX_DN<2>")
	)
	(segment
		(start 360.534966 -104.394)
		(end 356.054914 -101.178614)
		(width 0.1143)
		(layer "In11.Cu")
		(net "DMI_CPU0_PCH_TX_DN<2>")
	)
	(segment
		(start 306.655216 -86.374224)
		(end 306.598066 -86.287356)
		(width 0.0889)
		(layer "In11.Cu")
		(net "DMI_CPU0_PCH_TX_DN<2>")
	)
	(segment
		(start 367.7158 -112.83315)
		(end 367.6015 -112.94745)
		(width 0.1143)
		(layer "In11.Cu")
		(net "DMI_CPU0_PCH_TX_DN<2>")
	)
	(segment
		(start 355.637338 -97.406714)
		(end 355.065838 -93.77807)
		(width 0.1143)
		(layer "In11.Cu")
		(net "DMI_CPU0_PCH_TX_DN<2>")
	)
	(segment
		(start 306.130198 -86.022688)
		(end 306.080414 -86.022688)
		(width 0.0889)
		(layer "In11.Cu")
		(net "DMI_CPU0_PCH_TX_DN<2>")
	)
	(segment
		(start 311.469024 -86.964012)
		(end 308.34457 -86.964012)
		(width 0.0889)
		(layer "In11.Cu")
		(net "DMI_CPU0_PCH_TX_DN<2>")
	)
	(segment
		(start 356.500176 -89.15019)
		(end 355.336602 -86.34095)
		(width 0.1143)
		(layer "In11.Cu")
		(net "DMI_CPU0_PCH_TX_DN<2>")
	)
	(segment
		(start 355.065838 -93.77807)
		(end 356.053898 -91.394534)
		(width 0.1143)
		(layer "In11.Cu")
		(net "DMI_CPU0_PCH_TX_DN<2>")
	)
	(segment
		(start 335.189576 -86.377272)
		(end 332.621382 -85.863684)
		(width 0.1143)
		(layer "In11.Cu")
		(net "DMI_CPU0_PCH_TX_DN<2>")
	)
	(segment
		(start 342.40978 -86.396068)
		(end 337.795616 -85.473286)
		(width 0.1143)
		(layer "In11.Cu")
		(net "DMI_CPU0_PCH_TX_DN<2>")
	)
	(segment
		(start 353.857814 -85.362034)
		(end 353.109784 -85.208872)
		(width 0.1143)
		(layer "In11.Cu")
		(net "DMI_CPU0_PCH_TX_DN<2>")
	)
	(segment
		(start 363.016292 -112.94745)
		(end 361.967526 -112.7379)
		(width 0.1143)
		(layer "In11.Cu")
		(net "DMI_CPU0_PCH_TX_DN<2>")
	)
	(segment
		(start 320.510916 -88.286082)
		(end 313.476386 -86.918546)
		(width 0.1143)
		(layer "In11.Cu")
		(net "DMI_CPU0_PCH_TX_DN<2>")
	)
	(segment
		(start 307.898292 -86.517734)
		(end 306.921408 -86.517734)
		(width 0.0889)
		(layer "In11.Cu")
		(net "DMI_CPU0_PCH_TX_DN<2>")
	)
	(segment
		(start 313.476386 -86.918546)
		(end 313.471052 -86.913212)
		(width 0.1143)
		(layer "In11.Cu")
		(net "DMI_CPU0_PCH_TX_DN<2>")
	)
	(segment
		(start 345.69273 -86.781894)
		(end 343.66073 -86.145878)
		(width 0.1143)
		(layer "In11.Cu")
		(net "DMI_CPU0_PCH_TX_DN<2>")
	)
	(segment
		(start 311.541922 -86.913212)
		(end 311.519824 -86.913212)
		(width 0.0889)
		(layer "In11.Cu")
		(net "DMI_CPU0_PCH_TX_DN<2>")
	)
	(segment
		(start 305.539902 -86.939374)
		(end 305.246786 -87.108538)
		(width 0.0889)
		(layer "In11.Cu")
		(net "DMI_CPU0_PCH_TX_DN<2>")
	)
	(segment
		(start 348.335092 -86.550754)
		(end 347.787722 -86.45017)
		(width 0.1143)
		(layer "In11.Cu")
		(net "DMI_CPU0_PCH_TX_DN<2>")
	)
	(segment
		(start 361.324398 -106.415332)
		(end 361.366054 -106.207306)
		(width 0.1143)
		(layer "In11.Cu")
		(net "DMI_CPU0_PCH_TX_DN<2>")
	)
	(segment
		(start 360.971084 -110.449106)
		(end 360.744516 -109.316012)
		(width 0.1143)
		(layer "In11.Cu")
		(net "DMI_CPU0_PCH_TX_DN<2>")
	)
	(segment
		(start 337.795616 -85.473286)
		(end 335.189576 -86.377272)
		(width 0.1143)
		(layer "In11.Cu")
		(net "DMI_CPU0_PCH_TX_DN<2>")
	)
	(arc
		(start 306.598066 -86.287356)
		(mid 306.396044 -86.098593)
		(end 306.130198 -86.022688)
		(width 0.0889)
		(layer "In11.Cu")
		(net "DMI_CPU0_PCH_TX_DN<2>")
	)
	(arc
		(start 306.080414 -86.022688)
		(mid 305.603921 -86.300055)
		(end 305.563778 -86.849966)
		(width 0.0889)
		(layer "In11.Cu")
		(net "DMI_CPU0_PCH_TX_DN<2>")
	)
	(arc
		(start 306.921408 -86.517734)
		(mid 306.77024 -86.479509)
		(end 306.655216 -86.374224)
		(width 0.0889)
		(layer "In11.Cu")
		(net "DMI_CPU0_PCH_TX_DN<2>")
	)
	(segment
		(start 363.728 -110.998)
		(end 363.7026 -111.0234)
		(width 0.1143)
		(layer "F.Cu")
		(net "DMI_CPU0_PCH_TX_DN<1>")
	)
	(segment
		(start 364.617 -110.998)
		(end 363.728 -110.998)
		(width 0.1143)
		(layer "F.Cu")
		(net "DMI_CPU0_PCH_TX_DN<1>")
	)
	(segment
		(start 305.246786 -85.127338)
		(end 304.675286 -85.127338)
		(width 0.1143)
		(layer "F.Cu")
		(net "DMI_CPU0_PCH_TX_DN<1>")
	)
	(via
		(at 305.246786 -85.127338)
		(size 0.508)
		(drill 0.254)
		(layers "F.Cu" "B.Cu")
		(net "DMI_CPU0_PCH_TX_DN<1>")
	)
	(via
		(at 363.7026 -111.0234)
		(size 0.508)
		(drill 0.254)
		(layers "F.Cu" "B.Cu")
		(net "DMI_CPU0_PCH_TX_DN<1>")
	)
	(segment
		(start 340.240874 -83.6549)
		(end 320.689986 -87.564468)
		(width 0.1143)
		(layer "In11.Cu")
		(net "DMI_CPU0_PCH_TX_DN<1>")
	)
	(segment
		(start 361.51693 -109.034072)
		(end 362.040678 -106.415078)
		(width 0.1143)
		(layer "In11.Cu")
		(net "DMI_CPU0_PCH_TX_DN<1>")
	)
	(segment
		(start 348.01302 -85.059012)
		(end 347.049344 -85.251544)
		(width 0.1143)
		(layer "In11.Cu")
		(net "DMI_CPU0_PCH_TX_DN<1>")
	)
	(segment
		(start 363.855 -111.46155)
		(end 363.728254 -111.588296)
		(width 0.1143)
		(layer "In11.Cu")
		(net "DMI_CPU0_PCH_TX_DN<1>")
	)
	(segment
		(start 344.734134 -84.553806)
		(end 340.240874 -83.6549)
		(width 0.1143)
		(layer "In11.Cu")
		(net "DMI_CPU0_PCH_TX_DN<1>")
	)
	(segment
		(start 320.689986 -87.564468)
		(end 311.065672 -85.691472)
		(width 0.1143)
		(layer "In11.Cu")
		(net "DMI_CPU0_PCH_TX_DN<1>")
	)
	(segment
		(start 348.87281 -85.41639)
		(end 348.01302 -85.059012)
		(width 0.1143)
		(layer "In11.Cu")
		(net "DMI_CPU0_PCH_TX_DN<1>")
	)
	(segment
		(start 356.688644 -91.539822)
		(end 356.694486 -91.511628)
		(width 0.1143)
		(layer "In11.Cu")
		(net "DMI_CPU0_PCH_TX_DN<1>")
	)
	(segment
		(start 356.354888 -97.148904)
		(end 355.806502 -93.668342)
		(width 0.1143)
		(layer "In11.Cu")
		(net "DMI_CPU0_PCH_TX_DN<1>")
	)
	(segment
		(start 356.694232 -91.511628)
		(end 357.179118 -89.086436)
		(width 0.1143)
		(layer "In11.Cu")
		(net "DMI_CPU0_PCH_TX_DN<1>")
	)
	(segment
		(start 363.7026 -111.0234)
		(end 363.855 -111.1758)
		(width 0.1143)
		(layer "In11.Cu")
		(net "DMI_CPU0_PCH_TX_DN<1>")
	)
	(segment
		(start 362.0897 -106.249724)
		(end 361.171236 -104.244394)
		(width 0.1143)
		(layer "In11.Cu")
		(net "DMI_CPU0_PCH_TX_DN<1>")
	)
	(segment
		(start 361.171236 -104.244394)
		(end 361.01909 -103.912162)
		(width 0.1143)
		(layer "In11.Cu")
		(net "DMI_CPU0_PCH_TX_DN<1>")
	)
	(segment
		(start 308.659276 -85.691472)
		(end 308.637178 -85.691472)
		(width 0.0889)
		(layer "In11.Cu")
		(net "DMI_CPU0_PCH_TX_DN<1>")
	)
	(segment
		(start 361.906312 -110.980982)
		(end 361.51693 -109.034072)
		(width 0.1143)
		(layer "In11.Cu")
		(net "DMI_CPU0_PCH_TX_DN<1>")
	)
	(segment
		(start 361.01909 -103.912162)
		(end 356.658926 -100.781866)
		(width 0.1143)
		(layer "In11.Cu")
		(net "DMI_CPU0_PCH_TX_DN<1>")
	)
	(segment
		(start 356.694486 -91.511628)
		(end 356.694232 -91.511628)
		(width 0.1143)
		(layer "In11.Cu")
		(net "DMI_CPU0_PCH_TX_DN<1>")
	)
	(segment
		(start 357.179118 -89.086436)
		(end 355.85908 -85.898736)
		(width 0.1143)
		(layer "In11.Cu")
		(net "DMI_CPU0_PCH_TX_DN<1>")
	)
	(segment
		(start 355.806502 -93.668342)
		(end 356.688644 -91.539822)
		(width 0.1143)
		(layer "In11.Cu")
		(net "DMI_CPU0_PCH_TX_DN<1>")
	)
	(segment
		(start 362.040678 -106.415078)
		(end 362.055156 -106.342942)
		(width 0.1143)
		(layer "In11.Cu")
		(net "DMI_CPU0_PCH_TX_DN<1>")
	)
	(segment
		(start 345.240102 -84.89061)
		(end 344.734134 -84.553806)
		(width 0.1143)
		(layer "In11.Cu")
		(net "DMI_CPU0_PCH_TX_DN<1>")
	)
	(segment
		(start 363.728254 -111.588296)
		(end 362.311188 -111.588296)
		(width 0.1143)
		(layer "In11.Cu")
		(net "DMI_CPU0_PCH_TX_DN<1>")
	)
	(segment
		(start 362.311188 -111.588296)
		(end 361.906312 -110.980982)
		(width 0.1143)
		(layer "In11.Cu")
		(net "DMI_CPU0_PCH_TX_DN<1>")
	)
	(segment
		(start 354.016564 -84.679536)
		(end 353.250246 -84.52612)
		(width 0.1143)
		(layer "In11.Cu")
		(net "DMI_CPU0_PCH_TX_DN<1>")
	)
	(segment
		(start 353.250246 -84.52612)
		(end 348.87281 -85.41639)
		(width 0.1143)
		(layer "In11.Cu")
		(net "DMI_CPU0_PCH_TX_DN<1>")
	)
	(segment
		(start 311.065672 -85.691472)
		(end 308.659276 -85.691472)
		(width 0.1143)
		(layer "In11.Cu")
		(net "DMI_CPU0_PCH_TX_DN<1>")
	)
	(segment
		(start 308.637178 -85.691472)
		(end 308.586378 -85.742272)
		(width 0.0889)
		(layer "In11.Cu")
		(net "DMI_CPU0_PCH_TX_DN<1>")
	)
	(segment
		(start 308.586378 -85.742272)
		(end 308.017672 -85.742272)
		(width 0.0889)
		(layer "In11.Cu")
		(net "DMI_CPU0_PCH_TX_DN<1>")
	)
	(segment
		(start 355.85908 -85.898736)
		(end 354.016564 -84.679536)
		(width 0.1143)
		(layer "In11.Cu")
		(net "DMI_CPU0_PCH_TX_DN<1>")
	)
	(segment
		(start 362.055156 -106.342942)
		(end 362.0897 -106.249724)
		(width 0.1143)
		(layer "In11.Cu")
		(net "DMI_CPU0_PCH_TX_DN<1>")
	)
	(segment
		(start 308.017672 -85.742272)
		(end 307.802788 -85.527388)
		(width 0.0889)
		(layer "In11.Cu")
		(net "DMI_CPU0_PCH_TX_DN<1>")
	)
	(segment
		(start 356.14356 -98.204274)
		(end 356.354888 -97.148904)
		(width 0.1143)
		(layer "In11.Cu")
		(net "DMI_CPU0_PCH_TX_DN<1>")
	)
	(segment
		(start 356.658926 -100.781866)
		(end 356.14356 -98.204274)
		(width 0.1143)
		(layer "In11.Cu")
		(net "DMI_CPU0_PCH_TX_DN<1>")
	)
	(segment
		(start 307.802788 -85.527388)
		(end 305.335686 -85.527388)
		(width 0.0889)
		(layer "In11.Cu")
		(net "DMI_CPU0_PCH_TX_DN<1>")
	)
	(segment
		(start 347.049344 -85.251544)
		(end 345.240102 -84.89061)
		(width 0.1143)
		(layer "In11.Cu")
		(net "DMI_CPU0_PCH_TX_DN<1>")
	)
	(segment
		(start 305.246786 -85.438488)
		(end 305.246786 -85.127338)
		(width 0.0889)
		(layer "In11.Cu")
		(net "DMI_CPU0_PCH_TX_DN<1>")
	)
	(segment
		(start 305.335686 -85.527388)
		(end 305.246786 -85.438488)
		(width 0.0889)
		(layer "In11.Cu")
		(net "DMI_CPU0_PCH_TX_DN<1>")
	)
	(segment
		(start 363.855 -111.1758)
		(end 363.855 -111.46155)
		(width 0.1143)
		(layer "In11.Cu")
		(net "DMI_CPU0_PCH_TX_DN<1>")
	)
	(segment
		(start 367.792 -109.601)
		(end 368.554 -109.601)
		(width 0.1143)
		(layer "F.Cu")
		(net "DMI_CPU0_PCH_TX_DN<0>")
	)
	(segment
		(start 304.675286 -84.136738)
		(end 305.246786 -84.136738)
		(width 0.1143)
		(layer "F.Cu")
		(net "DMI_CPU0_PCH_TX_DN<0>")
	)
	(via
		(at 367.792 -109.601)
		(size 0.508)
		(drill 0.254)
		(layers "F.Cu" "B.Cu")
		(net "DMI_CPU0_PCH_TX_DN<0>")
	)
	(via
		(at 305.246786 -84.136738)
		(size 0.508)
		(drill 0.254)
		(layers "F.Cu" "B.Cu")
		(net "DMI_CPU0_PCH_TX_DN<0>")
	)
	(segment
		(start 307.15712 -85.0392)
		(end 306.89042 -85.0392)
		(width 0.0889)
		(layer "In11.Cu")
		(net "DMI_CPU0_PCH_TX_DN<0>")
	)
	(segment
		(start 305.268122 -84.536788)
		(end 305.23561 -84.536788)
		(width 0.0889)
		(layer "In11.Cu")
		(net "DMI_CPU0_PCH_TX_DN<0>")
	)
	(segment
		(start 357.074216 -96.952816)
		(end 356.558088 -93.67647)
		(width 0.1143)
		(layer "In11.Cu")
		(net "DMI_CPU0_PCH_TX_DN<0>")
	)
	(segment
		(start 306.799488 -84.948268)
		(end 306.532788 -84.948268)
		(width 0.0889)
		(layer "In11.Cu")
		(net "DMI_CPU0_PCH_TX_DN<0>")
	)
	(segment
		(start 304.932588 -84.384388)
		(end 304.95367 -84.305648)
		(width 0.0889)
		(layer "In11.Cu")
		(net "DMI_CPU0_PCH_TX_DN<0>")
	)
	(segment
		(start 347.096334 -83.420966)
		(end 345.934792 -83.18881)
		(width 0.1143)
		(layer "In11.Cu")
		(net "DMI_CPU0_PCH_TX_DN<0>")
	)
	(segment
		(start 306.441856 -85.0392)
		(end 305.991768 -85.0392)
		(width 0.0889)
		(layer "In11.Cu")
		(net "DMI_CPU0_PCH_TX_DN<0>")
	)
	(segment
		(start 308.841902 -84.9884)
		(end 308.791102 -85.0392)
		(width 0.0889)
		(layer "In11.Cu")
		(net "DMI_CPU0_PCH_TX_DN<0>")
	)
	(segment
		(start 307.248052 -84.948268)
		(end 307.15712 -85.0392)
		(width 0.0889)
		(layer "In11.Cu")
		(net "DMI_CPU0_PCH_TX_DN<0>")
	)
	(segment
		(start 305.991768 -85.0392)
		(end 305.821334 -84.940648)
		(width 0.0889)
		(layer "In11.Cu")
		(net "DMI_CPU0_PCH_TX_DN<0>")
	)
	(segment
		(start 356.823518 -98.205036)
		(end 356.823518 -98.20529)
		(width 0.1143)
		(layer "In11.Cu")
		(net "DMI_CPU0_PCH_TX_DN<0>")
	)
	(segment
		(start 351.455228 -83.693508)
		(end 350.939354 -83.796886)
		(width 0.1143)
		(layer "In11.Cu")
		(net "DMI_CPU0_PCH_TX_DN<0>")
	)
	(segment
		(start 356.824788 -84.709254)
		(end 356.24389 -83.837272)
		(width 0.1143)
		(layer "In11.Cu")
		(net "DMI_CPU0_PCH_TX_DN<0>")
	)
	(segment
		(start 366.500664 -110.15345)
		(end 366.418622 -110.071408)
		(width 0.1143)
		(layer "In11.Cu")
		(net "DMI_CPU0_PCH_TX_DN<0>")
	)
	(segment
		(start 367.792 -109.601)
		(end 367.792 -110.06455)
		(width 0.1143)
		(layer "In11.Cu")
		(net "DMI_CPU0_PCH_TX_DN<0>")
	)
	(segment
		(start 340.412324 -82.933794)
		(end 320.806572 -86.853776)
		(width 0.1143)
		(layer "In11.Cu")
		(net "DMI_CPU0_PCH_TX_DN<0>")
	)
	(segment
		(start 311.47893 -84.9884)
		(end 308.864 -84.9884)
		(width 0.1143)
		(layer "In11.Cu")
		(net "DMI_CPU0_PCH_TX_DN<0>")
	)
	(segment
		(start 364.336838 -109.463078)
		(end 361.640374 -103.57612)
		(width 0.1143)
		(layer "In11.Cu")
		(net "DMI_CPU0_PCH_TX_DN<0>")
	)
	(segment
		(start 305.821334 -84.940648)
		(end 305.758596 -84.831936)
		(width 0.0889)
		(layer "In11.Cu")
		(net "DMI_CPU0_PCH_TX_DN<0>")
	)
	(segment
		(start 356.823518 -98.20529)
		(end 357.074216 -96.952816)
		(width 0.1143)
		(layer "In11.Cu")
		(net "DMI_CPU0_PCH_TX_DN<0>")
	)
	(segment
		(start 307.605684 -85.0392)
		(end 307.514752 -84.948268)
		(width 0.0889)
		(layer "In11.Cu")
		(net "DMI_CPU0_PCH_TX_DN<0>")
	)
	(segment
		(start 308.864 -84.9884)
		(end 308.841902 -84.9884)
		(width 0.0889)
		(layer "In11.Cu")
		(net "DMI_CPU0_PCH_TX_DN<0>")
	)
	(segment
		(start 353.766882 -82.668618)
		(end 352.661982 -82.888582)
		(width 0.1143)
		(layer "In11.Cu")
		(net "DMI_CPU0_PCH_TX_DN<0>")
	)
	(segment
		(start 306.89042 -85.0392)
		(end 306.799488 -84.948268)
		(width 0.0889)
		(layer "In11.Cu")
		(net "DMI_CPU0_PCH_TX_DN<0>")
	)
	(segment
		(start 365.993934 -110.15345)
		(end 365.41202 -110.15345)
		(width 0.1143)
		(layer "In11.Cu")
		(net "DMI_CPU0_PCH_TX_DN<0>")
	)
	(segment
		(start 307.514752 -84.948268)
		(end 307.248052 -84.948268)
		(width 0.0889)
		(layer "In11.Cu")
		(net "DMI_CPU0_PCH_TX_DN<0>")
	)
	(segment
		(start 367.792 -110.06455)
		(end 367.7031 -110.15345)
		(width 0.1143)
		(layer "In11.Cu")
		(net "DMI_CPU0_PCH_TX_DN<0>")
	)
	(segment
		(start 343.809066 -83.613752)
		(end 343.625424 -83.576922)
		(width 0.1143)
		(layer "In11.Cu")
		(net "DMI_CPU0_PCH_TX_DN<0>")
	)
	(segment
		(start 356.558088 -93.67647)
		(end 357.116634 -92.329)
		(width 0.1143)
		(layer "In11.Cu")
		(net "DMI_CPU0_PCH_TX_DN<0>")
	)
	(segment
		(start 352.661982 -82.888582)
		(end 351.455228 -83.693508)
		(width 0.1143)
		(layer "In11.Cu")
		(net "DMI_CPU0_PCH_TX_DN<0>")
	)
	(segment
		(start 366.075976 -110.071408)
		(end 365.993934 -110.15345)
		(width 0.1143)
		(layer "In11.Cu")
		(net "DMI_CPU0_PCH_TX_DN<0>")
	)
	(segment
		(start 364.337092 -109.463332)
		(end 364.336838 -109.463078)
		(width 0.1143)
		(layer "In11.Cu")
		(net "DMI_CPU0_PCH_TX_DN<0>")
	)
	(segment
		(start 345.934792 -83.18881)
		(end 343.809066 -83.613752)
		(width 0.1143)
		(layer "In11.Cu")
		(net "DMI_CPU0_PCH_TX_DN<0>")
	)
	(segment
		(start 365.41202 -110.15345)
		(end 364.337092 -109.463332)
		(width 0.1143)
		(layer "In11.Cu")
		(net "DMI_CPU0_PCH_TX_DN<0>")
	)
	(segment
		(start 356.24389 -83.837272)
		(end 354.801424 -82.875628)
		(width 0.1143)
		(layer "In11.Cu")
		(net "DMI_CPU0_PCH_TX_DN<0>")
	)
	(segment
		(start 306.532788 -84.948268)
		(end 306.441856 -85.0392)
		(width 0.0889)
		(layer "In11.Cu")
		(net "DMI_CPU0_PCH_TX_DN<0>")
	)
	(segment
		(start 357.176578 -86.465918)
		(end 356.824788 -84.709254)
		(width 0.1143)
		(layer "In11.Cu")
		(net "DMI_CPU0_PCH_TX_DN<0>")
	)
	(segment
		(start 354.801424 -82.875628)
		(end 353.766882 -82.668618)
		(width 0.1143)
		(layer "In11.Cu")
		(net "DMI_CPU0_PCH_TX_DN<0>")
	)
	(segment
		(start 361.640374 -103.57612)
		(end 358.624886 -101.411278)
		(width 0.1143)
		(layer "In11.Cu")
		(net "DMI_CPU0_PCH_TX_DN<0>")
	)
	(segment
		(start 367.7031 -110.15345)
		(end 366.500664 -110.15345)
		(width 0.1143)
		(layer "In11.Cu")
		(net "DMI_CPU0_PCH_TX_DN<0>")
	)
	(segment
		(start 348.07906 -83.22437)
		(end 347.096334 -83.420966)
		(width 0.1143)
		(layer "In11.Cu")
		(net "DMI_CPU0_PCH_TX_DN<0>")
	)
	(segment
		(start 366.418622 -110.071408)
		(end 366.075976 -110.071408)
		(width 0.1143)
		(layer "In11.Cu")
		(net "DMI_CPU0_PCH_TX_DN<0>")
	)
	(segment
		(start 304.95367 -84.305648)
		(end 305.246786 -84.136738)
		(width 0.0889)
		(layer "In11.Cu")
		(net "DMI_CPU0_PCH_TX_DN<0>")
	)
	(segment
		(start 358.624886 -101.411278)
		(end 357.250492 -100.41128)
		(width 0.1143)
		(layer "In11.Cu")
		(net "DMI_CPU0_PCH_TX_DN<0>")
	)
	(segment
		(start 356.816406 -98.24085)
		(end 356.823518 -98.205036)
		(width 0.1143)
		(layer "In11.Cu")
		(net "DMI_CPU0_PCH_TX_DN<0>")
	)
	(segment
		(start 357.269288 -91.960954)
		(end 357.974138 -88.434672)
		(width 0.1143)
		(layer "In11.Cu")
		(net "DMI_CPU0_PCH_TX_DN<0>")
	)
	(segment
		(start 357.974138 -88.434672)
		(end 357.176578 -86.465918)
		(width 0.1143)
		(layer "In11.Cu")
		(net "DMI_CPU0_PCH_TX_DN<0>")
	)
	(segment
		(start 357.250492 -100.41128)
		(end 356.816406 -98.24085)
		(width 0.1143)
		(layer "In11.Cu")
		(net "DMI_CPU0_PCH_TX_DN<0>")
	)
	(segment
		(start 350.939354 -83.796886)
		(end 348.07906 -83.22437)
		(width 0.1143)
		(layer "In11.Cu")
		(net "DMI_CPU0_PCH_TX_DN<0>")
	)
	(segment
		(start 343.625424 -83.576922)
		(end 340.412324 -82.933794)
		(width 0.1143)
		(layer "In11.Cu")
		(net "DMI_CPU0_PCH_TX_DN<0>")
	)
	(segment
		(start 308.791102 -85.0392)
		(end 307.605684 -85.0392)
		(width 0.0889)
		(layer "In11.Cu")
		(net "DMI_CPU0_PCH_TX_DN<0>")
	)
	(segment
		(start 357.116634 -92.329)
		(end 357.269288 -91.960954)
		(width 0.1143)
		(layer "In11.Cu")
		(net "DMI_CPU0_PCH_TX_DN<0>")
	)
	(segment
		(start 320.806572 -86.853776)
		(end 311.47893 -84.9884)
		(width 0.1143)
		(layer "In11.Cu")
		(net "DMI_CPU0_PCH_TX_DN<0>")
	)
	(arc
		(start 305.758596 -84.831936)
		(mid 305.551483 -84.621006)
		(end 305.268122 -84.536788)
		(width 0.0889)
		(layer "In11.Cu")
		(net "DMI_CPU0_PCH_TX_DN<0>")
	)
	(arc
		(start 305.23561 -84.536788)
		(mid 305.067173 -84.494255)
		(end 304.932588 -84.384388)
		(width 0.0889)
		(layer "In11.Cu")
		(net "DMI_CPU0_PCH_TX_DN<0>")
	)
	(segment
		(start 368.65179 -114.687096)
		(end 368.550444 -114.58575)
		(width 0.0889)
		(layer "F.Cu")
		(net "DMI_CPU0_PCH_TX_C_DP<3>")
	)
	(segment
		(start 371.794532 -113.759742)
		(end 371.616732 -113.759742)
		(width 0.0889)
		(layer "F.Cu")
		(net "DMI_CPU0_PCH_TX_C_DP<3>")
	)
	(segment
		(start 374.674892 -113.848642)
		(end 374.585992 -113.759742)
		(width 0.0889)
		(layer "F.Cu")
		(net "DMI_CPU0_PCH_TX_C_DP<3>")
	)
	(segment
		(start 369.667028 -114.58575)
		(end 369.489228 -114.58575)
		(width 0.0889)
		(layer "F.Cu")
		(net "DMI_CPU0_PCH_TX_C_DP<3>")
	)
	(segment
		(start 373.190262 -113.861088)
		(end 373.012462 -113.861088)
		(width 0.0889)
		(layer "F.Cu")
		(net "DMI_CPU0_PCH_TX_C_DP<3>")
	)
	(segment
		(start 372.073678 -113.861088)
		(end 371.895878 -113.861088)
		(width 0.0889)
		(layer "F.Cu")
		(net "DMI_CPU0_PCH_TX_C_DP<3>")
	)
	(segment
		(start 373.469408 -113.759742)
		(end 373.291608 -113.759742)
		(width 0.0889)
		(layer "F.Cu")
		(net "DMI_CPU0_PCH_TX_C_DP<3>")
	)
	(segment
		(start 368.181382 -114.58575)
		(end 368.155982 -114.61115)
		(width 0.0889)
		(layer "F.Cu")
		(net "DMI_CPU0_PCH_TX_C_DP<3>")
	)
	(segment
		(start 368.550444 -114.58575)
		(end 368.181382 -114.58575)
		(width 0.0889)
		(layer "F.Cu")
		(net "DMI_CPU0_PCH_TX_C_DP<3>")
	)
	(segment
		(start 369.803934 -114.448844)
		(end 369.667028 -114.58575)
		(width 0.0889)
		(layer "F.Cu")
		(net "DMI_CPU0_PCH_TX_C_DP<3>")
	)
	(segment
		(start 369.387882 -114.687096)
		(end 369.210082 -114.687096)
		(width 0.0889)
		(layer "F.Cu")
		(net "DMI_CPU0_PCH_TX_C_DP<3>")
	)
	(segment
		(start 369.108736 -114.58575)
		(end 368.930936 -114.58575)
		(width 0.0889)
		(layer "F.Cu")
		(net "DMI_CPU0_PCH_TX_C_DP<3>")
	)
	(segment
		(start 373.8499 -113.759742)
		(end 373.748554 -113.861088)
		(width 0.0889)
		(layer "F.Cu")
		(net "DMI_CPU0_PCH_TX_C_DP<3>")
	)
	(segment
		(start 371.515386 -113.861088)
		(end 371.337586 -113.861088)
		(width 0.0889)
		(layer "F.Cu")
		(net "DMI_CPU0_PCH_TX_C_DP<3>")
	)
	(segment
		(start 369.210082 -114.687096)
		(end 369.108736 -114.58575)
		(width 0.0889)
		(layer "F.Cu")
		(net "DMI_CPU0_PCH_TX_C_DP<3>")
	)
	(segment
		(start 372.175024 -113.759742)
		(end 372.073678 -113.861088)
		(width 0.0889)
		(layer "F.Cu")
		(net "DMI_CPU0_PCH_TX_C_DP<3>")
	)
	(segment
		(start 370.779294 -113.861088)
		(end 370.677948 -113.759742)
		(width 0.0889)
		(layer "F.Cu")
		(net "DMI_CPU0_PCH_TX_C_DP<3>")
	)
	(segment
		(start 371.05844 -113.759742)
		(end 370.957094 -113.861088)
		(width 0.0889)
		(layer "F.Cu")
		(net "DMI_CPU0_PCH_TX_C_DP<3>")
	)
	(segment
		(start 373.291608 -113.759742)
		(end 373.190262 -113.861088)
		(width 0.0889)
		(layer "F.Cu")
		(net "DMI_CPU0_PCH_TX_C_DP<3>")
	)
	(segment
		(start 374.0277 -113.759742)
		(end 373.8499 -113.759742)
		(width 0.0889)
		(layer "F.Cu")
		(net "DMI_CPU0_PCH_TX_C_DP<3>")
	)
	(segment
		(start 373.748554 -113.861088)
		(end 373.570754 -113.861088)
		(width 0.0889)
		(layer "F.Cu")
		(net "DMI_CPU0_PCH_TX_C_DP<3>")
	)
	(segment
		(start 372.352824 -113.759742)
		(end 372.175024 -113.759742)
		(width 0.0889)
		(layer "F.Cu")
		(net "DMI_CPU0_PCH_TX_C_DP<3>")
	)
	(segment
		(start 370.07292 -114.179858)
		(end 370.07292 -114.323114)
		(width 0.0889)
		(layer "F.Cu")
		(net "DMI_CPU0_PCH_TX_C_DP<3>")
	)
	(segment
		(start 368.82959 -114.687096)
		(end 368.65179 -114.687096)
		(width 0.0889)
		(layer "F.Cu")
		(net "DMI_CPU0_PCH_TX_C_DP<3>")
	)
	(segment
		(start 372.45417 -113.861088)
		(end 372.352824 -113.759742)
		(width 0.0889)
		(layer "F.Cu")
		(net "DMI_CPU0_PCH_TX_C_DP<3>")
	)
	(segment
		(start 368.930936 -114.58575)
		(end 368.82959 -114.687096)
		(width 0.0889)
		(layer "F.Cu")
		(net "DMI_CPU0_PCH_TX_C_DP<3>")
	)
	(segment
		(start 367.792 -114.61115)
		(end 366.08385 -114.61115)
		(width 0.1143)
		(layer "F.Cu")
		(net "DMI_CPU0_PCH_TX_C_DP<3>")
	)
	(segment
		(start 370.677948 -113.759742)
		(end 370.493036 -113.759742)
		(width 0.0889)
		(layer "F.Cu")
		(net "DMI_CPU0_PCH_TX_C_DP<3>")
	)
	(segment
		(start 373.570754 -113.861088)
		(end 373.469408 -113.759742)
		(width 0.0889)
		(layer "F.Cu")
		(net "DMI_CPU0_PCH_TX_C_DP<3>")
	)
	(segment
		(start 374.129046 -113.861088)
		(end 374.0277 -113.759742)
		(width 0.0889)
		(layer "F.Cu")
		(net "DMI_CPU0_PCH_TX_C_DP<3>")
	)
	(segment
		(start 370.07292 -114.323114)
		(end 369.94719 -114.448844)
		(width 0.0889)
		(layer "F.Cu")
		(net "DMI_CPU0_PCH_TX_C_DP<3>")
	)
	(segment
		(start 370.957094 -113.861088)
		(end 370.779294 -113.861088)
		(width 0.0889)
		(layer "F.Cu")
		(net "DMI_CPU0_PCH_TX_C_DP<3>")
	)
	(segment
		(start 371.895878 -113.861088)
		(end 371.794532 -113.759742)
		(width 0.0889)
		(layer "F.Cu")
		(net "DMI_CPU0_PCH_TX_C_DP<3>")
	)
	(segment
		(start 372.911116 -113.759742)
		(end 372.733316 -113.759742)
		(width 0.0889)
		(layer "F.Cu")
		(net "DMI_CPU0_PCH_TX_C_DP<3>")
	)
	(segment
		(start 372.63197 -113.861088)
		(end 372.45417 -113.861088)
		(width 0.0889)
		(layer "F.Cu")
		(net "DMI_CPU0_PCH_TX_C_DP<3>")
	)
	(segment
		(start 369.489228 -114.58575)
		(end 369.387882 -114.687096)
		(width 0.0889)
		(layer "F.Cu")
		(net "DMI_CPU0_PCH_TX_C_DP<3>")
	)
	(segment
		(start 368.133884 -114.61115)
		(end 367.792 -114.61115)
		(width 0.1143)
		(layer "F.Cu")
		(net "DMI_CPU0_PCH_TX_C_DP<3>")
	)
	(segment
		(start 371.23624 -113.759742)
		(end 371.05844 -113.759742)
		(width 0.0889)
		(layer "F.Cu")
		(net "DMI_CPU0_PCH_TX_C_DP<3>")
	)
	(segment
		(start 374.408192 -113.759742)
		(end 374.306846 -113.861088)
		(width 0.0889)
		(layer "F.Cu")
		(net "DMI_CPU0_PCH_TX_C_DP<3>")
	)
	(segment
		(start 374.674892 -113.854992)
		(end 374.674892 -113.848642)
		(width 0.0889)
		(layer "F.Cu")
		(net "DMI_CPU0_PCH_TX_C_DP<3>")
	)
	(segment
		(start 371.616732 -113.759742)
		(end 371.515386 -113.861088)
		(width 0.0889)
		(layer "F.Cu")
		(net "DMI_CPU0_PCH_TX_C_DP<3>")
	)
	(segment
		(start 371.337586 -113.861088)
		(end 371.23624 -113.759742)
		(width 0.0889)
		(layer "F.Cu")
		(net "DMI_CPU0_PCH_TX_C_DP<3>")
	)
	(segment
		(start 370.493036 -113.759742)
		(end 370.07292 -114.179858)
		(width 0.0889)
		(layer "F.Cu")
		(net "DMI_CPU0_PCH_TX_C_DP<3>")
	)
	(segment
		(start 369.94719 -114.448844)
		(end 369.803934 -114.448844)
		(width 0.0889)
		(layer "F.Cu")
		(net "DMI_CPU0_PCH_TX_C_DP<3>")
	)
	(segment
		(start 368.155982 -114.61115)
		(end 368.133884 -114.61115)
		(width 0.0889)
		(layer "F.Cu")
		(net "DMI_CPU0_PCH_TX_C_DP<3>")
	)
	(segment
		(start 372.733316 -113.759742)
		(end 372.63197 -113.861088)
		(width 0.0889)
		(layer "F.Cu")
		(net "DMI_CPU0_PCH_TX_C_DP<3>")
	)
	(segment
		(start 366.08385 -114.61115)
		(end 365.506 -115.189)
		(width 0.1143)
		(layer "F.Cu")
		(net "DMI_CPU0_PCH_TX_C_DP<3>")
	)
	(segment
		(start 374.306846 -113.861088)
		(end 374.129046 -113.861088)
		(width 0.0889)
		(layer "F.Cu")
		(net "DMI_CPU0_PCH_TX_C_DP<3>")
	)
	(segment
		(start 373.012462 -113.861088)
		(end 372.911116 -113.759742)
		(width 0.0889)
		(layer "F.Cu")
		(net "DMI_CPU0_PCH_TX_C_DP<3>")
	)
	(segment
		(start 374.585992 -113.759742)
		(end 374.408192 -113.759742)
		(width 0.0889)
		(layer "F.Cu")
		(net "DMI_CPU0_PCH_TX_C_DP<3>")
	)
	(via
		(at 367.792 -114.61115)
		(size 0.508)
		(drill 0.254)
		(layers "F.Cu" "B.Cu")
		(net "DMI_CPU0_PCH_TX_C_DP<3>")
	)
	(segment
		(start 375.089928 -113.35512)
		(end 375.066052 -113.331244)
		(width 0.0889)
		(layer "F.Cu")
		(net "DMI_CPU0_PCH_TX_C_DP<2>")
	)
	(segment
		(start 371.238272 -113.087404)
		(end 371.060472 -113.087404)
		(width 0.0889)
		(layer "F.Cu")
		(net "DMI_CPU0_PCH_TX_C_DP<2>")
	)
	(segment
		(start 373.787162 -113.250218)
		(end 373.609362 -113.250218)
		(width 0.0889)
		(layer "F.Cu")
		(net "DMI_CPU0_PCH_TX_C_DP<2>")
	)
	(segment
		(start 372.454932 -113.188496)
		(end 372.35384 -113.087404)
		(width 0.0889)
		(layer "F.Cu")
		(net "DMI_CPU0_PCH_TX_C_DP<2>")
	)
	(segment
		(start 374.167146 -113.250218)
		(end 374.066054 -113.35131)
		(width 0.0889)
		(layer "F.Cu")
		(net "DMI_CPU0_PCH_TX_C_DP<2>")
	)
	(segment
		(start 369.6081 -113.087404)
		(end 369.443 -113.252504)
		(width 0.0889)
		(layer "F.Cu")
		(net "DMI_CPU0_PCH_TX_C_DP<2>")
	)
	(segment
		(start 372.911624 -113.087404)
		(end 372.733824 -113.087404)
		(width 0.0889)
		(layer "F.Cu")
		(net "DMI_CPU0_PCH_TX_C_DP<2>")
	)
	(segment
		(start 370.95938 -113.188496)
		(end 370.78158 -113.188496)
		(width 0.0889)
		(layer "F.Cu")
		(net "DMI_CPU0_PCH_TX_C_DP<2>")
	)
	(segment
		(start 374.42902 -113.331244)
		(end 374.347994 -113.250218)
		(width 0.0889)
		(layer "F.Cu")
		(net "DMI_CPU0_PCH_TX_C_DP<2>")
	)
	(segment
		(start 370.367814 -113.188496)
		(end 370.190014 -113.188496)
		(width 0.0889)
		(layer "F.Cu")
		(net "DMI_CPU0_PCH_TX_C_DP<2>")
	)
	(segment
		(start 374.066054 -113.35131)
		(end 373.888254 -113.35131)
		(width 0.0889)
		(layer "F.Cu")
		(net "DMI_CPU0_PCH_TX_C_DP<2>")
	)
	(segment
		(start 371.339364 -113.188496)
		(end 371.238272 -113.087404)
		(width 0.0889)
		(layer "F.Cu")
		(net "DMI_CPU0_PCH_TX_C_DP<2>")
	)
	(segment
		(start 371.618256 -113.087404)
		(end 371.517164 -113.188496)
		(width 0.0889)
		(layer "F.Cu")
		(net "DMI_CPU0_PCH_TX_C_DP<2>")
	)
	(segment
		(start 371.897148 -113.188496)
		(end 371.796056 -113.087404)
		(width 0.0889)
		(layer "F.Cu")
		(net "DMI_CPU0_PCH_TX_C_DP<2>")
	)
	(segment
		(start 374.347994 -113.250218)
		(end 374.167146 -113.250218)
		(width 0.0889)
		(layer "F.Cu")
		(net "DMI_CPU0_PCH_TX_C_DP<2>")
	)
	(segment
		(start 373.33047 -113.35131)
		(end 373.229378 -113.250218)
		(width 0.0889)
		(layer "F.Cu")
		(net "DMI_CPU0_PCH_TX_C_DP<2>")
	)
	(segment
		(start 371.517164 -113.188496)
		(end 371.339364 -113.188496)
		(width 0.0889)
		(layer "F.Cu")
		(net "DMI_CPU0_PCH_TX_C_DP<2>")
	)
	(segment
		(start 371.060472 -113.087404)
		(end 370.95938 -113.188496)
		(width 0.0889)
		(layer "F.Cu")
		(net "DMI_CPU0_PCH_TX_C_DP<2>")
	)
	(segment
		(start 373.609362 -113.250218)
		(end 373.50827 -113.35131)
		(width 0.0889)
		(layer "F.Cu")
		(net "DMI_CPU0_PCH_TX_C_DP<2>")
	)
	(segment
		(start 372.733824 -113.087404)
		(end 372.632732 -113.188496)
		(width 0.0889)
		(layer "F.Cu")
		(net "DMI_CPU0_PCH_TX_C_DP<2>")
	)
	(segment
		(start 372.17604 -113.087404)
		(end 372.074948 -113.188496)
		(width 0.0889)
		(layer "F.Cu")
		(net "DMI_CPU0_PCH_TX_C_DP<2>")
	)
	(segment
		(start 370.680488 -113.087404)
		(end 370.468906 -113.087404)
		(width 0.0889)
		(layer "F.Cu")
		(net "DMI_CPU0_PCH_TX_C_DP<2>")
	)
	(segment
		(start 370.088922 -113.087404)
		(end 369.6081 -113.087404)
		(width 0.0889)
		(layer "F.Cu")
		(net "DMI_CPU0_PCH_TX_C_DP<2>")
	)
	(segment
		(start 371.796056 -113.087404)
		(end 371.618256 -113.087404)
		(width 0.0889)
		(layer "F.Cu")
		(net "DMI_CPU0_PCH_TX_C_DP<2>")
	)
	(segment
		(start 373.50827 -113.35131)
		(end 373.33047 -113.35131)
		(width 0.0889)
		(layer "F.Cu")
		(net "DMI_CPU0_PCH_TX_C_DP<2>")
	)
	(segment
		(start 373.229378 -113.250218)
		(end 373.074438 -113.250218)
		(width 0.0889)
		(layer "F.Cu")
		(net "DMI_CPU0_PCH_TX_C_DP<2>")
	)
	(segment
		(start 372.074948 -113.188496)
		(end 371.897148 -113.188496)
		(width 0.0889)
		(layer "F.Cu")
		(net "DMI_CPU0_PCH_TX_C_DP<2>")
	)
	(segment
		(start 370.190014 -113.188496)
		(end 370.088922 -113.087404)
		(width 0.0889)
		(layer "F.Cu")
		(net "DMI_CPU0_PCH_TX_C_DP<2>")
	)
	(segment
		(start 370.468906 -113.087404)
		(end 370.367814 -113.188496)
		(width 0.0889)
		(layer "F.Cu")
		(net "DMI_CPU0_PCH_TX_C_DP<2>")
	)
	(segment
		(start 373.888254 -113.35131)
		(end 373.787162 -113.250218)
		(width 0.0889)
		(layer "F.Cu")
		(net "DMI_CPU0_PCH_TX_C_DP<2>")
	)
	(segment
		(start 373.074438 -113.250218)
		(end 372.911624 -113.087404)
		(width 0.0889)
		(layer "F.Cu")
		(net "DMI_CPU0_PCH_TX_C_DP<2>")
	)
	(segment
		(start 372.35384 -113.087404)
		(end 372.17604 -113.087404)
		(width 0.0889)
		(layer "F.Cu")
		(net "DMI_CPU0_PCH_TX_C_DP<2>")
	)
	(segment
		(start 369.443 -113.252504)
		(end 369.443 -113.792)
		(width 0.0889)
		(layer "F.Cu")
		(net "DMI_CPU0_PCH_TX_C_DP<2>")
	)
	(segment
		(start 370.78158 -113.188496)
		(end 370.680488 -113.087404)
		(width 0.0889)
		(layer "F.Cu")
		(net "DMI_CPU0_PCH_TX_C_DP<2>")
	)
	(segment
		(start 375.066052 -113.331244)
		(end 374.42902 -113.331244)
		(width 0.0889)
		(layer "F.Cu")
		(net "DMI_CPU0_PCH_TX_C_DP<2>")
	)
	(segment
		(start 372.632732 -113.188496)
		(end 372.454932 -113.188496)
		(width 0.0889)
		(layer "F.Cu")
		(net "DMI_CPU0_PCH_TX_C_DP<2>")
	)
	(segment
		(start 374.315736 -112.842802)
		(end 374.137936 -112.842802)
		(width 0.0889)
		(layer "F.Cu")
		(net "DMI_CPU0_PCH_TX_C_DP<1>")
	)
	(segment
		(start 374.137936 -112.842802)
		(end 374.048528 -112.753394)
		(width 0.0889)
		(layer "F.Cu")
		(net "DMI_CPU0_PCH_TX_C_DP<1>")
	)
	(segment
		(start 370.932456 -112.275874)
		(end 370.806726 -112.150144)
		(width 0.0889)
		(layer "F.Cu")
		(net "DMI_CPU0_PCH_TX_C_DP<1>")
	)
	(segment
		(start 372.318788 -112.558068)
		(end 372.140988 -112.558068)
		(width 0.0889)
		(layer "F.Cu")
		(net "DMI_CPU0_PCH_TX_C_DP<1>")
	)
	(segment
		(start 370.806726 -112.150144)
		(end 370.806726 -112.006888)
		(width 0.0889)
		(layer "F.Cu")
		(net "DMI_CPU0_PCH_TX_C_DP<1>")
	)
	(segment
		(start 371.266974 -112.467136)
		(end 371.075712 -112.275874)
		(width 0.0889)
		(layer "F.Cu")
		(net "DMI_CPU0_PCH_TX_C_DP<1>")
	)
	(segment
		(start 372.140988 -112.558068)
		(end 372.050056 -112.467136)
		(width 0.0889)
		(layer "F.Cu")
		(net "DMI_CPU0_PCH_TX_C_DP<1>")
	)
	(segment
		(start 370.311934 -111.867442)
		(end 370.134134 -111.867442)
		(width 0.0889)
		(layer "F.Cu")
		(net "DMI_CPU0_PCH_TX_C_DP<1>")
	)
	(segment
		(start 369.475258 -111.76635)
		(end 369.243356 -111.76635)
		(width 0.0889)
		(layer "F.Cu")
		(net "DMI_CPU0_PCH_TX_C_DP<1>")
	)
	(segment
		(start 372.58752 -112.467136)
		(end 372.40972 -112.467136)
		(width 0.0889)
		(layer "F.Cu")
		(net "DMI_CPU0_PCH_TX_C_DP<1>")
	)
	(segment
		(start 369.75415 -111.867442)
		(end 369.57635 -111.867442)
		(width 0.0889)
		(layer "F.Cu")
		(net "DMI_CPU0_PCH_TX_C_DP<1>")
	)
	(segment
		(start 369.142264 -111.867442)
		(end 368.964464 -111.867442)
		(width 0.0889)
		(layer "F.Cu")
		(net "DMI_CPU0_PCH_TX_C_DP<1>")
	)
	(segment
		(start 373.364252 -112.753394)
		(end 373.077994 -112.467136)
		(width 0.0889)
		(layer "F.Cu")
		(net "DMI_CPU0_PCH_TX_C_DP<1>")
	)
	(segment
		(start 368.964464 -111.867442)
		(end 368.863372 -111.76635)
		(width 0.0889)
		(layer "F.Cu")
		(net "DMI_CPU0_PCH_TX_C_DP<1>")
	)
	(segment
		(start 374.405144 -112.753394)
		(end 374.315736 -112.842802)
		(width 0.0889)
		(layer "F.Cu")
		(net "DMI_CPU0_PCH_TX_C_DP<1>")
	)
	(segment
		(start 374.674892 -112.854994)
		(end 374.573292 -112.753394)
		(width 0.0889)
		(layer "F.Cu")
		(net "DMI_CPU0_PCH_TX_C_DP<1>")
	)
	(segment
		(start 366.10925 -111.79175)
		(end 367.7412 -111.79175)
		(width 0.1143)
		(layer "F.Cu")
		(net "DMI_CPU0_PCH_TX_C_DP<1>")
	)
	(segment
		(start 365.506 -112.395)
		(end 366.10925 -111.79175)
		(width 0.1143)
		(layer "F.Cu")
		(net "DMI_CPU0_PCH_TX_C_DP<1>")
	)
	(segment
		(start 369.855242 -111.76635)
		(end 369.75415 -111.867442)
		(width 0.0889)
		(layer "F.Cu")
		(net "DMI_CPU0_PCH_TX_C_DP<1>")
	)
	(segment
		(start 368.554508 -111.867442)
		(end 368.376708 -111.867442)
		(width 0.0889)
		(layer "F.Cu")
		(net "DMI_CPU0_PCH_TX_C_DP<1>")
	)
	(segment
		(start 371.781324 -112.558068)
		(end 371.603524 -112.558068)
		(width 0.0889)
		(layer "F.Cu")
		(net "DMI_CPU0_PCH_TX_C_DP<1>")
	)
	(segment
		(start 373.870728 -112.753394)
		(end 373.78132 -112.842802)
		(width 0.0889)
		(layer "F.Cu")
		(net "DMI_CPU0_PCH_TX_C_DP<1>")
	)
	(segment
		(start 368.054128 -111.79175)
		(end 367.7412 -111.79175)
		(width 0.1143)
		(layer "F.Cu")
		(net "DMI_CPU0_PCH_TX_C_DP<1>")
	)
	(segment
		(start 371.872256 -112.467136)
		(end 371.781324 -112.558068)
		(width 0.0889)
		(layer "F.Cu")
		(net "DMI_CPU0_PCH_TX_C_DP<1>")
	)
	(segment
		(start 369.57635 -111.867442)
		(end 369.475258 -111.76635)
		(width 0.0889)
		(layer "F.Cu")
		(net "DMI_CPU0_PCH_TX_C_DP<1>")
	)
	(segment
		(start 370.033042 -111.76635)
		(end 369.855242 -111.76635)
		(width 0.0889)
		(layer "F.Cu")
		(net "DMI_CPU0_PCH_TX_C_DP<1>")
	)
	(segment
		(start 371.512592 -112.467136)
		(end 371.266974 -112.467136)
		(width 0.0889)
		(layer "F.Cu")
		(net "DMI_CPU0_PCH_TX_C_DP<1>")
	)
	(segment
		(start 370.806726 -112.006888)
		(end 370.566188 -111.76635)
		(width 0.0889)
		(layer "F.Cu")
		(net "DMI_CPU0_PCH_TX_C_DP<1>")
	)
	(segment
		(start 368.6556 -111.76635)
		(end 368.554508 -111.867442)
		(width 0.0889)
		(layer "F.Cu")
		(net "DMI_CPU0_PCH_TX_C_DP<1>")
	)
	(segment
		(start 368.863372 -111.76635)
		(end 368.6556 -111.76635)
		(width 0.0889)
		(layer "F.Cu")
		(net "DMI_CPU0_PCH_TX_C_DP<1>")
	)
	(segment
		(start 372.947184 -112.467136)
		(end 372.856252 -112.558068)
		(width 0.0889)
		(layer "F.Cu")
		(net "DMI_CPU0_PCH_TX_C_DP<1>")
	)
	(segment
		(start 370.134134 -111.867442)
		(end 370.033042 -111.76635)
		(width 0.0889)
		(layer "F.Cu")
		(net "DMI_CPU0_PCH_TX_C_DP<1>")
	)
	(segment
		(start 372.678452 -112.558068)
		(end 372.58752 -112.467136)
		(width 0.0889)
		(layer "F.Cu")
		(net "DMI_CPU0_PCH_TX_C_DP<1>")
	)
	(segment
		(start 368.101626 -111.76635)
		(end 368.076226 -111.79175)
		(width 0.0889)
		(layer "F.Cu")
		(net "DMI_CPU0_PCH_TX_C_DP<1>")
	)
	(segment
		(start 373.514112 -112.753394)
		(end 373.364252 -112.753394)
		(width 0.0889)
		(layer "F.Cu")
		(net "DMI_CPU0_PCH_TX_C_DP<1>")
	)
	(segment
		(start 371.603524 -112.558068)
		(end 371.512592 -112.467136)
		(width 0.0889)
		(layer "F.Cu")
		(net "DMI_CPU0_PCH_TX_C_DP<1>")
	)
	(segment
		(start 374.573292 -112.753394)
		(end 374.405144 -112.753394)
		(width 0.0889)
		(layer "F.Cu")
		(net "DMI_CPU0_PCH_TX_C_DP<1>")
	)
	(segment
		(start 370.566188 -111.76635)
		(end 370.413026 -111.76635)
		(width 0.0889)
		(layer "F.Cu")
		(net "DMI_CPU0_PCH_TX_C_DP<1>")
	)
	(segment
		(start 372.40972 -112.467136)
		(end 372.318788 -112.558068)
		(width 0.0889)
		(layer "F.Cu")
		(net "DMI_CPU0_PCH_TX_C_DP<1>")
	)
	(segment
		(start 374.048528 -112.753394)
		(end 373.870728 -112.753394)
		(width 0.0889)
		(layer "F.Cu")
		(net "DMI_CPU0_PCH_TX_C_DP<1>")
	)
	(segment
		(start 373.78132 -112.842802)
		(end 373.60352 -112.842802)
		(width 0.0889)
		(layer "F.Cu")
		(net "DMI_CPU0_PCH_TX_C_DP<1>")
	)
	(segment
		(start 373.077994 -112.467136)
		(end 372.947184 -112.467136)
		(width 0.0889)
		(layer "F.Cu")
		(net "DMI_CPU0_PCH_TX_C_DP<1>")
	)
	(segment
		(start 368.376708 -111.867442)
		(end 368.275616 -111.76635)
		(width 0.0889)
		(layer "F.Cu")
		(net "DMI_CPU0_PCH_TX_C_DP<1>")
	)
	(segment
		(start 370.413026 -111.76635)
		(end 370.311934 -111.867442)
		(width 0.0889)
		(layer "F.Cu")
		(net "DMI_CPU0_PCH_TX_C_DP<1>")
	)
	(segment
		(start 372.050056 -112.467136)
		(end 371.872256 -112.467136)
		(width 0.0889)
		(layer "F.Cu")
		(net "DMI_CPU0_PCH_TX_C_DP<1>")
	)
	(segment
		(start 373.60352 -112.842802)
		(end 373.514112 -112.753394)
		(width 0.0889)
		(layer "F.Cu")
		(net "DMI_CPU0_PCH_TX_C_DP<1>")
	)
	(segment
		(start 369.243356 -111.76635)
		(end 369.142264 -111.867442)
		(width 0.0889)
		(layer "F.Cu")
		(net "DMI_CPU0_PCH_TX_C_DP<1>")
	)
	(segment
		(start 368.076226 -111.79175)
		(end 368.054128 -111.79175)
		(width 0.0889)
		(layer "F.Cu")
		(net "DMI_CPU0_PCH_TX_C_DP<1>")
	)
	(segment
		(start 368.275616 -111.76635)
		(end 368.101626 -111.76635)
		(width 0.0889)
		(layer "F.Cu")
		(net "DMI_CPU0_PCH_TX_C_DP<1>")
	)
	(segment
		(start 371.075712 -112.275874)
		(end 370.932456 -112.275874)
		(width 0.0889)
		(layer "F.Cu")
		(net "DMI_CPU0_PCH_TX_C_DP<1>")
	)
	(segment
		(start 372.856252 -112.558068)
		(end 372.678452 -112.558068)
		(width 0.0889)
		(layer "F.Cu")
		(net "DMI_CPU0_PCH_TX_C_DP<1>")
	)
	(via
		(at 367.7412 -111.79175)
		(size 0.508)
		(drill 0.254)
		(layers "F.Cu" "B.Cu")
		(net "DMI_CPU0_PCH_TX_C_DP<1>")
	)
	(segment
		(start 372.706392 -111.83366)
		(end 372.605046 -111.935006)
		(width 0.0889)
		(layer "F.Cu")
		(net "DMI_CPU0_PCH_TX_C_DP<0>")
	)
	(segment
		(start 372.18366 -111.83366)
		(end 372.082314 -111.935006)
		(width 0.0889)
		(layer "F.Cu")
		(net "DMI_CPU0_PCH_TX_C_DP<0>")
	)
	(segment
		(start 373.229124 -111.83366)
		(end 373.127778 -111.935006)
		(width 0.0889)
		(layer "F.Cu")
		(net "DMI_CPU0_PCH_TX_C_DP<0>")
	)
	(segment
		(start 370.141754 -110.3884)
		(end 370.052854 -110.2995)
		(width 0.0889)
		(layer "F.Cu")
		(net "DMI_CPU0_PCH_TX_C_DP<0>")
	)
	(segment
		(start 373.782844 -112.22736)
		(end 373.64035 -112.22736)
		(width 0.0889)
		(layer "F.Cu")
		(net "DMI_CPU0_PCH_TX_C_DP<0>")
	)
	(segment
		(start 370.772182 -110.973616)
		(end 370.629434 -110.973616)
		(width 0.0889)
		(layer "F.Cu")
		(net "DMI_CPU0_PCH_TX_C_DP<0>")
	)
	(segment
		(start 371.259608 -111.461042)
		(end 371.1448 -111.346234)
		(width 0.0889)
		(layer "F.Cu")
		(net "DMI_CPU0_PCH_TX_C_DP<0>")
	)
	(segment
		(start 371.632226 -111.83366)
		(end 371.517418 -111.718852)
		(width 0.0889)
		(layer "F.Cu")
		(net "DMI_CPU0_PCH_TX_C_DP<0>")
	)
	(segment
		(start 371.37467 -111.718852)
		(end 371.259608 -111.60379)
		(width 0.0889)
		(layer "F.Cu")
		(net "DMI_CPU0_PCH_TX_C_DP<0>")
	)
	(segment
		(start 371.922294 -111.935006)
		(end 371.820948 -111.83366)
		(width 0.0889)
		(layer "F.Cu")
		(net "DMI_CPU0_PCH_TX_C_DP<0>")
	)
	(segment
		(start 372.967758 -111.935006)
		(end 372.866412 -111.83366)
		(width 0.0889)
		(layer "F.Cu")
		(net "DMI_CPU0_PCH_TX_C_DP<0>")
	)
	(segment
		(start 370.052854 -110.2995)
		(end 369.579398 -110.2995)
		(width 0.0889)
		(layer "F.Cu")
		(net "DMI_CPU0_PCH_TX_C_DP<0>")
	)
	(segment
		(start 370.256816 -110.600998)
		(end 370.141754 -110.485936)
		(width 0.0889)
		(layer "F.Cu")
		(net "DMI_CPU0_PCH_TX_C_DP<0>")
	)
	(segment
		(start 370.514372 -110.715806)
		(end 370.399564 -110.600998)
		(width 0.0889)
		(layer "F.Cu")
		(net "DMI_CPU0_PCH_TX_C_DP<0>")
	)
	(segment
		(start 370.514372 -110.858554)
		(end 370.514372 -110.715806)
		(width 0.0889)
		(layer "F.Cu")
		(net "DMI_CPU0_PCH_TX_C_DP<0>")
	)
	(segment
		(start 373.64035 -112.22736)
		(end 373.51462 -112.101884)
		(width 0.0889)
		(layer "F.Cu")
		(net "DMI_CPU0_PCH_TX_C_DP<0>")
	)
	(segment
		(start 375.089928 -112.355122)
		(end 373.910606 -112.355122)
		(width 0.0889)
		(layer "F.Cu")
		(net "DMI_CPU0_PCH_TX_C_DP<0>")
	)
	(segment
		(start 370.88699 -111.088424)
		(end 370.772182 -110.973616)
		(width 0.0889)
		(layer "F.Cu")
		(net "DMI_CPU0_PCH_TX_C_DP<0>")
	)
	(segment
		(start 373.51462 -111.959136)
		(end 373.389144 -111.83366)
		(width 0.0889)
		(layer "F.Cu")
		(net "DMI_CPU0_PCH_TX_C_DP<0>")
	)
	(segment
		(start 371.1448 -111.346234)
		(end 371.002052 -111.346234)
		(width 0.0889)
		(layer "F.Cu")
		(net "DMI_CPU0_PCH_TX_C_DP<0>")
	)
	(segment
		(start 371.517418 -111.718852)
		(end 371.37467 -111.718852)
		(width 0.0889)
		(layer "F.Cu")
		(net "DMI_CPU0_PCH_TX_C_DP<0>")
	)
	(segment
		(start 370.88699 -111.231172)
		(end 370.88699 -111.088424)
		(width 0.0889)
		(layer "F.Cu")
		(net "DMI_CPU0_PCH_TX_C_DP<0>")
	)
	(segment
		(start 372.082314 -111.935006)
		(end 371.922294 -111.935006)
		(width 0.0889)
		(layer "F.Cu")
		(net "DMI_CPU0_PCH_TX_C_DP<0>")
	)
	(segment
		(start 372.866412 -111.83366)
		(end 372.706392 -111.83366)
		(width 0.0889)
		(layer "F.Cu")
		(net "DMI_CPU0_PCH_TX_C_DP<0>")
	)
	(segment
		(start 372.445026 -111.935006)
		(end 372.34368 -111.83366)
		(width 0.0889)
		(layer "F.Cu")
		(net "DMI_CPU0_PCH_TX_C_DP<0>")
	)
	(segment
		(start 370.629434 -110.973616)
		(end 370.514372 -110.858554)
		(width 0.0889)
		(layer "F.Cu")
		(net "DMI_CPU0_PCH_TX_C_DP<0>")
	)
	(segment
		(start 370.399564 -110.600998)
		(end 370.256816 -110.600998)
		(width 0.0889)
		(layer "F.Cu")
		(net "DMI_CPU0_PCH_TX_C_DP<0>")
	)
	(segment
		(start 369.579398 -110.2995)
		(end 369.443 -110.435898)
		(width 0.0889)
		(layer "F.Cu")
		(net "DMI_CPU0_PCH_TX_C_DP<0>")
	)
	(segment
		(start 370.141754 -110.485936)
		(end 370.141754 -110.3884)
		(width 0.0889)
		(layer "F.Cu")
		(net "DMI_CPU0_PCH_TX_C_DP<0>")
	)
	(segment
		(start 373.51462 -112.101884)
		(end 373.51462 -111.959136)
		(width 0.0889)
		(layer "F.Cu")
		(net "DMI_CPU0_PCH_TX_C_DP<0>")
	)
	(segment
		(start 371.002052 -111.346234)
		(end 370.88699 -111.231172)
		(width 0.0889)
		(layer "F.Cu")
		(net "DMI_CPU0_PCH_TX_C_DP<0>")
	)
	(segment
		(start 369.443 -110.435898)
		(end 369.443 -110.998)
		(width 0.0889)
		(layer "F.Cu")
		(net "DMI_CPU0_PCH_TX_C_DP<0>")
	)
	(segment
		(start 371.259608 -111.60379)
		(end 371.259608 -111.461042)
		(width 0.0889)
		(layer "F.Cu")
		(net "DMI_CPU0_PCH_TX_C_DP<0>")
	)
	(segment
		(start 373.127778 -111.935006)
		(end 372.967758 -111.935006)
		(width 0.0889)
		(layer "F.Cu")
		(net "DMI_CPU0_PCH_TX_C_DP<0>")
	)
	(segment
		(start 372.605046 -111.935006)
		(end 372.445026 -111.935006)
		(width 0.0889)
		(layer "F.Cu")
		(net "DMI_CPU0_PCH_TX_C_DP<0>")
	)
	(segment
		(start 371.820948 -111.83366)
		(end 371.632226 -111.83366)
		(width 0.0889)
		(layer "F.Cu")
		(net "DMI_CPU0_PCH_TX_C_DP<0>")
	)
	(segment
		(start 373.910606 -112.355122)
		(end 373.782844 -112.22736)
		(width 0.0889)
		(layer "F.Cu")
		(net "DMI_CPU0_PCH_TX_C_DP<0>")
	)
	(segment
		(start 373.389144 -111.83366)
		(end 373.229124 -111.83366)
		(width 0.0889)
		(layer "F.Cu")
		(net "DMI_CPU0_PCH_TX_C_DP<0>")
	)
	(segment
		(start 372.34368 -111.83366)
		(end 372.18366 -111.83366)
		(width 0.0889)
		(layer "F.Cu")
		(net "DMI_CPU0_PCH_TX_C_DP<0>")
	)
	(segment
		(start 366.08385 -114.36985)
		(end 365.506 -113.792)
		(width 0.1143)
		(layer "F.Cu")
		(net "DMI_CPU0_PCH_TX_C_DN<3>")
	)
	(segment
		(start 374.769888 -113.569242)
		(end 370.414042 -113.569242)
		(width 0.0889)
		(layer "F.Cu")
		(net "DMI_CPU0_PCH_TX_C_DN<3>")
	)
	(segment
		(start 369.588034 -114.39525)
		(end 368.181382 -114.39525)
		(width 0.0889)
		(layer "F.Cu")
		(net "DMI_CPU0_PCH_TX_C_DN<3>")
	)
	(segment
		(start 370.414042 -113.569242)
		(end 369.588034 -114.39525)
		(width 0.0889)
		(layer "F.Cu")
		(net "DMI_CPU0_PCH_TX_C_DN<3>")
	)
	(segment
		(start 368.181382 -114.39525)
		(end 368.155982 -114.36985)
		(width 0.0889)
		(layer "F.Cu")
		(net "DMI_CPU0_PCH_TX_C_DN<3>")
	)
	(segment
		(start 375.504964 -113.854992)
		(end 374.769888 -113.569242)
		(width 0.0889)
		(layer "F.Cu")
		(net "DMI_CPU0_PCH_TX_C_DN<3>")
	)
	(segment
		(start 368.155982 -114.36985)
		(end 368.133884 -114.36985)
		(width 0.0889)
		(layer "F.Cu")
		(net "DMI_CPU0_PCH_TX_C_DN<3>")
	)
	(segment
		(start 368.133884 -114.36985)
		(end 366.522 -114.36985)
		(width 0.1143)
		(layer "F.Cu")
		(net "DMI_CPU0_PCH_TX_C_DN<3>")
	)
	(segment
		(start 366.522 -114.36985)
		(end 366.08385 -114.36985)
		(width 0.1143)
		(layer "F.Cu")
		(net "DMI_CPU0_PCH_TX_C_DN<3>")
	)
	(via
		(at 366.522 -114.36985)
		(size 0.508)
		(drill 0.254)
		(layers "F.Cu" "B.Cu")
		(net "DMI_CPU0_PCH_TX_C_DN<3>")
	)
	(segment
		(start 374.508014 -113.140744)
		(end 374.426988 -113.059718)
		(width 0.0889)
		(layer "F.Cu")
		(net "DMI_CPU0_PCH_TX_C_DN<2>")
	)
	(segment
		(start 373.153432 -113.059718)
		(end 372.990618 -112.896904)
		(width 0.0889)
		(layer "F.Cu")
		(net "DMI_CPU0_PCH_TX_C_DN<2>")
	)
	(segment
		(start 372.990618 -112.896904)
		(end 369.705128 -112.896904)
		(width 0.0889)
		(layer "F.Cu")
		(net "DMI_CPU0_PCH_TX_C_DN<2>")
	)
	(segment
		(start 374.426988 -113.059718)
		(end 373.153432 -113.059718)
		(width 0.0889)
		(layer "F.Cu")
		(net "DMI_CPU0_PCH_TX_C_DN<2>")
	)
	(segment
		(start 369.443 -112.634776)
		(end 369.443 -112.395)
		(width 0.0889)
		(layer "F.Cu")
		(net "DMI_CPU0_PCH_TX_C_DN<2>")
	)
	(segment
		(start 374.784366 -113.140744)
		(end 374.508014 -113.140744)
		(width 0.0889)
		(layer "F.Cu")
		(net "DMI_CPU0_PCH_TX_C_DN<2>")
	)
	(segment
		(start 375.266204 -113.097056)
		(end 375.21261 -113.043462)
		(width 0.0889)
		(layer "F.Cu")
		(net "DMI_CPU0_PCH_TX_C_DN<2>")
	)
	(segment
		(start 375.019316 -113.043462)
		(end 374.784366 -113.140744)
		(width 0.0889)
		(layer "F.Cu")
		(net "DMI_CPU0_PCH_TX_C_DN<2>")
	)
	(segment
		(start 369.705128 -112.896904)
		(end 369.443 -112.634776)
		(width 0.0889)
		(layer "F.Cu")
		(net "DMI_CPU0_PCH_TX_C_DN<2>")
	)
	(segment
		(start 375.92 -113.35512)
		(end 375.266204 -113.097056)
		(width 0.0889)
		(layer "F.Cu")
		(net "DMI_CPU0_PCH_TX_C_DN<2>")
	)
	(segment
		(start 375.21261 -113.043462)
		(end 375.019316 -113.043462)
		(width 0.0889)
		(layer "F.Cu")
		(net "DMI_CPU0_PCH_TX_C_DN<2>")
	)
	(segment
		(start 368.076226 -111.55045)
		(end 368.101626 -111.57585)
		(width 0.0889)
		(layer "F.Cu")
		(net "DMI_CPU0_PCH_TX_C_DN<1>")
	)
	(segment
		(start 373.443246 -112.562894)
		(end 374.83796 -112.562894)
		(width 0.0889)
		(layer "F.Cu")
		(net "DMI_CPU0_PCH_TX_C_DN<1>")
	)
	(segment
		(start 365.506 -110.998)
		(end 366.05845 -111.55045)
		(width 0.1143)
		(layer "F.Cu")
		(net "DMI_CPU0_PCH_TX_C_DN<1>")
	)
	(segment
		(start 368.054128 -111.55045)
		(end 368.076226 -111.55045)
		(width 0.0889)
		(layer "F.Cu")
		(net "DMI_CPU0_PCH_TX_C_DN<1>")
	)
	(segment
		(start 366.4712 -111.55045)
		(end 368.054128 -111.55045)
		(width 0.1143)
		(layer "F.Cu")
		(net "DMI_CPU0_PCH_TX_C_DN<1>")
	)
	(segment
		(start 374.91162 -112.636554)
		(end 375.504964 -112.854994)
		(width 0.0889)
		(layer "F.Cu")
		(net "DMI_CPU0_PCH_TX_C_DN<1>")
	)
	(segment
		(start 373.156988 -112.276636)
		(end 373.443246 -112.562894)
		(width 0.0889)
		(layer "F.Cu")
		(net "DMI_CPU0_PCH_TX_C_DN<1>")
	)
	(segment
		(start 370.645182 -111.57585)
		(end 371.345968 -112.276636)
		(width 0.0889)
		(layer "F.Cu")
		(net "DMI_CPU0_PCH_TX_C_DN<1>")
	)
	(segment
		(start 366.05845 -111.55045)
		(end 366.4712 -111.55045)
		(width 0.1143)
		(layer "F.Cu")
		(net "DMI_CPU0_PCH_TX_C_DN<1>")
	)
	(segment
		(start 368.101626 -111.57585)
		(end 370.645182 -111.57585)
		(width 0.0889)
		(layer "F.Cu")
		(net "DMI_CPU0_PCH_TX_C_DN<1>")
	)
	(segment
		(start 374.83796 -112.562894)
		(end 374.91162 -112.636554)
		(width 0.0889)
		(layer "F.Cu")
		(net "DMI_CPU0_PCH_TX_C_DN<1>")
	)
	(segment
		(start 371.345968 -112.276636)
		(end 373.156988 -112.276636)
		(width 0.0889)
		(layer "F.Cu")
		(net "DMI_CPU0_PCH_TX_C_DN<1>")
	)
	(via
		(at 366.4712 -111.55045)
		(size 0.508)
		(drill 0.254)
		(layers "F.Cu" "B.Cu")
		(net "DMI_CPU0_PCH_TX_C_DN<1>")
	)
	(segment
		(start 369.443 -109.883956)
		(end 369.443 -109.601)
		(width 0.0889)
		(layer "F.Cu")
		(net "DMI_CPU0_PCH_TX_C_DN<0>")
	)
	(segment
		(start 370.17706 -110.109)
		(end 369.668044 -110.109)
		(width 0.0889)
		(layer "F.Cu")
		(net "DMI_CPU0_PCH_TX_C_DN<0>")
	)
	(segment
		(start 371.71122 -111.64316)
		(end 370.17706 -110.109)
		(width 0.0889)
		(layer "F.Cu")
		(net "DMI_CPU0_PCH_TX_C_DN<0>")
	)
	(segment
		(start 375.92 -112.355122)
		(end 375.311924 -112.129316)
		(width 0.0889)
		(layer "F.Cu")
		(net "DMI_CPU0_PCH_TX_C_DN<0>")
	)
	(segment
		(start 373.9896 -112.164622)
		(end 373.468138 -111.64316)
		(width 0.0889)
		(layer "F.Cu")
		(net "DMI_CPU0_PCH_TX_C_DN<0>")
	)
	(segment
		(start 375.311924 -112.129316)
		(end 375.19229 -112.04067)
		(width 0.0889)
		(layer "F.Cu")
		(net "DMI_CPU0_PCH_TX_C_DN<0>")
	)
	(segment
		(start 373.468138 -111.64316)
		(end 371.71122 -111.64316)
		(width 0.0889)
		(layer "F.Cu")
		(net "DMI_CPU0_PCH_TX_C_DN<0>")
	)
	(segment
		(start 375.19229 -112.04067)
		(end 374.98401 -112.04067)
		(width 0.0889)
		(layer "F.Cu")
		(net "DMI_CPU0_PCH_TX_C_DN<0>")
	)
	(segment
		(start 374.98401 -112.04067)
		(end 374.749314 -112.164622)
		(width 0.0889)
		(layer "F.Cu")
		(net "DMI_CPU0_PCH_TX_C_DN<0>")
	)
	(segment
		(start 374.749314 -112.164622)
		(end 373.9896 -112.164622)
		(width 0.0889)
		(layer "F.Cu")
		(net "DMI_CPU0_PCH_TX_C_DN<0>")
	)
	(segment
		(start 369.668044 -110.109)
		(end 369.443 -109.883956)
		(width 0.0889)
		(layer "F.Cu")
		(net "DMI_CPU0_PCH_TX_C_DN<0>")
	)
	(segment
		(start 379.81255 -117.58168)
		(end 380.30785 -117.811804)
		(width 0.1143)
		(layer "F.Cu")
		(net "DMI_CPU0_PCH_RX_DP<3>")
	)
	(via
		(at 374.97131 -111.025686)
		(size 0.508)
		(drill 0.254)
		(layers "F.Cu" "B.Cu")
		(net "DMI_CPU0_PCH_RX_DP<3>")
	)
	(via
		(at 380.30785 -117.811804)
		(size 0.508)
		(drill 0.254)
		(layers "F.Cu" "B.Cu")
		(net "DMI_CPU0_PCH_RX_DP<3>")
	)
	(segment
		(start 371.631972 -110.795562)
		(end 371.573806 -110.853728)
		(width 0.1143)
		(layer "B.Cu")
		(net "DMI_CPU0_PCH_RX_DP<3>")
	)
	(segment
		(start 373.4689 -110.795562)
		(end 373.410734 -110.853728)
		(width 0.1143)
		(layer "B.Cu")
		(net "DMI_CPU0_PCH_RX_DP<3>")
	)
	(segment
		(start 372.951502 -110.737142)
		(end 372.608602 -110.737142)
		(width 0.1143)
		(layer "B.Cu")
		(net "DMI_CPU0_PCH_RX_DP<3>")
	)
	(segment
		(start 373.928132 -110.795562)
		(end 373.928132 -110.795308)
		(width 0.1143)
		(layer "B.Cu")
		(net "DMI_CPU0_PCH_RX_DP<3>")
	)
	(segment
		(start 374.387364 -110.795562)
		(end 374.329198 -110.853728)
		(width 0.1143)
		(layer "B.Cu")
		(net "DMI_CPU0_PCH_RX_DP<3>")
	)
	(segment
		(start 372.49227 -110.853728)
		(end 372.14937 -110.853728)
		(width 0.1143)
		(layer "B.Cu")
		(net "DMI_CPU0_PCH_RX_DP<3>")
	)
	(segment
		(start 380.507748 -114.724434)
		(end 380.558294 -114.695224)
		(width 0.0889)
		(layer "B.Cu")
		(net "DMI_CPU0_PCH_RX_DP<3>")
	)
	(segment
		(start 371.17274 -110.795562)
		(end 371.17274 -110.795308)
		(width 0.1143)
		(layer "B.Cu")
		(net "DMI_CPU0_PCH_RX_DP<3>")
	)
	(segment
		(start 373.009668 -110.795308)
		(end 372.951502 -110.737142)
		(width 0.1143)
		(layer "B.Cu")
		(net "DMI_CPU0_PCH_RX_DP<3>")
	)
	(segment
		(start 371.230906 -110.853728)
		(end 371.17274 -110.795562)
		(width 0.1143)
		(layer "B.Cu")
		(net "DMI_CPU0_PCH_RX_DP<3>")
	)
	(segment
		(start 376.272806 -112.9665)
		(end 375.3231 -112.016794)
		(width 0.0889)
		(layer "B.Cu")
		(net "DMI_CPU0_PCH_RX_DP<3>")
	)
	(segment
		(start 375.2977 -111.352076)
		(end 374.97131 -111.025686)
		(width 0.1143)
		(layer "B.Cu")
		(net "DMI_CPU0_PCH_RX_DP<3>")
	)
	(segment
		(start 380.2126 -113.540794)
		(end 380.2126 -113.508028)
		(width 0.0889)
		(layer "B.Cu")
		(net "DMI_CPU0_PCH_RX_DP<3>")
	)
	(segment
		(start 375.2977 -111.687102)
		(end 375.2977 -111.352076)
		(width 0.1143)
		(layer "B.Cu")
		(net "DMI_CPU0_PCH_RX_DP<3>")
	)
	(segment
		(start 373.410734 -110.853728)
		(end 373.067834 -110.853728)
		(width 0.1143)
		(layer "B.Cu")
		(net "DMI_CPU0_PCH_RX_DP<3>")
	)
	(segment
		(start 371.114574 -110.737142)
		(end 370.498624 -110.737142)
		(width 0.1143)
		(layer "B.Cu")
		(net "DMI_CPU0_PCH_RX_DP<3>")
	)
	(segment
		(start 371.573806 -110.853728)
		(end 371.230906 -110.853728)
		(width 0.1143)
		(layer "B.Cu")
		(net "DMI_CPU0_PCH_RX_DP<3>")
	)
	(segment
		(start 374.44553 -110.737142)
		(end 374.387364 -110.795308)
		(width 0.1143)
		(layer "B.Cu")
		(net "DMI_CPU0_PCH_RX_DP<3>")
	)
	(segment
		(start 370.498624 -110.737142)
		(end 369.828826 -110.459774)
		(width 0.1143)
		(layer "B.Cu")
		(net "DMI_CPU0_PCH_RX_DP<3>")
	)
	(segment
		(start 373.928132 -110.795308)
		(end 373.869966 -110.737142)
		(width 0.1143)
		(layer "B.Cu")
		(net "DMI_CPU0_PCH_RX_DP<3>")
	)
	(segment
		(start 372.033038 -110.737142)
		(end 371.690138 -110.737142)
		(width 0.1143)
		(layer "B.Cu")
		(net "DMI_CPU0_PCH_RX_DP<3>")
	)
	(segment
		(start 378.621798 -113.172494)
		(end 378.472446 -113.2586)
		(width 0.0889)
		(layer "B.Cu")
		(net "DMI_CPU0_PCH_RX_DP<3>")
	)
	(segment
		(start 373.009668 -110.795562)
		(end 373.009668 -110.795308)
		(width 0.1143)
		(layer "B.Cu")
		(net "DMI_CPU0_PCH_RX_DP<3>")
	)
	(segment
		(start 375.3231 -111.7346)
		(end 375.2977 -111.7092)
		(width 0.0889)
		(layer "B.Cu")
		(net "DMI_CPU0_PCH_RX_DP<3>")
	)
	(segment
		(start 374.329198 -110.853728)
		(end 373.986298 -110.853728)
		(width 0.1143)
		(layer "B.Cu")
		(net "DMI_CPU0_PCH_RX_DP<3>")
	)
	(segment
		(start 376.958098 -113.17224)
		(end 376.752358 -112.9665)
		(width 0.0889)
		(layer "B.Cu")
		(net "DMI_CPU0_PCH_RX_DP<3>")
	)
	(segment
		(start 373.4689 -110.795308)
		(end 373.4689 -110.795562)
		(width 0.1143)
		(layer "B.Cu")
		(net "DMI_CPU0_PCH_RX_DP<3>")
	)
	(segment
		(start 372.091204 -110.795308)
		(end 372.033038 -110.737142)
		(width 0.1143)
		(layer "B.Cu")
		(net "DMI_CPU0_PCH_RX_DP<3>")
	)
	(segment
		(start 373.869966 -110.737142)
		(end 373.527066 -110.737142)
		(width 0.1143)
		(layer "B.Cu")
		(net "DMI_CPU0_PCH_RX_DP<3>")
	)
	(segment
		(start 372.14937 -110.853728)
		(end 372.091204 -110.795562)
		(width 0.1143)
		(layer "B.Cu")
		(net "DMI_CPU0_PCH_RX_DP<3>")
	)
	(segment
		(start 369.443 -110.5408)
		(end 369.443 -110.998)
		(width 0.1143)
		(layer "B.Cu")
		(net "DMI_CPU0_PCH_RX_DP<3>")
	)
	(segment
		(start 376.752358 -112.9665)
		(end 376.272806 -112.9665)
		(width 0.0889)
		(layer "B.Cu")
		(net "DMI_CPU0_PCH_RX_DP<3>")
	)
	(segment
		(start 372.608602 -110.737142)
		(end 372.550436 -110.795308)
		(width 0.1143)
		(layer "B.Cu")
		(net "DMI_CPU0_PCH_RX_DP<3>")
	)
	(segment
		(start 369.524026 -110.459774)
		(end 369.443 -110.5408)
		(width 0.1143)
		(layer "B.Cu")
		(net "DMI_CPU0_PCH_RX_DP<3>")
	)
	(segment
		(start 373.527066 -110.737142)
		(end 373.4689 -110.795308)
		(width 0.1143)
		(layer "B.Cu")
		(net "DMI_CPU0_PCH_RX_DP<3>")
	)
	(segment
		(start 373.986298 -110.853728)
		(end 373.928132 -110.795562)
		(width 0.1143)
		(layer "B.Cu")
		(net "DMI_CPU0_PCH_RX_DP<3>")
	)
	(segment
		(start 373.067834 -110.853728)
		(end 373.009668 -110.795562)
		(width 0.1143)
		(layer "B.Cu")
		(net "DMI_CPU0_PCH_RX_DP<3>")
	)
	(segment
		(start 374.387364 -110.795308)
		(end 374.387364 -110.795562)
		(width 0.1143)
		(layer "B.Cu")
		(net "DMI_CPU0_PCH_RX_DP<3>")
	)
	(segment
		(start 377.044712 -113.2586)
		(end 376.958352 -113.17224)
		(width 0.0889)
		(layer "B.Cu")
		(net "DMI_CPU0_PCH_RX_DP<3>")
	)
	(segment
		(start 380.30785 -117.811804)
		(end 380.47676 -117.518688)
		(width 0.0889)
		(layer "B.Cu")
		(net "DMI_CPU0_PCH_RX_DP<3>")
	)
	(segment
		(start 375.2977 -111.7092)
		(end 375.2977 -111.687102)
		(width 0.0889)
		(layer "B.Cu")
		(net "DMI_CPU0_PCH_RX_DP<3>")
	)
	(segment
		(start 374.682766 -110.737142)
		(end 374.44553 -110.737142)
		(width 0.1143)
		(layer "B.Cu")
		(net "DMI_CPU0_PCH_RX_DP<3>")
	)
	(segment
		(start 380.2126 -115.257834)
		(end 380.2126 -115.214654)
		(width 0.0889)
		(layer "B.Cu")
		(net "DMI_CPU0_PCH_RX_DP<3>")
	)
	(segment
		(start 372.550436 -110.795562)
		(end 372.49227 -110.853728)
		(width 0.1143)
		(layer "B.Cu")
		(net "DMI_CPU0_PCH_RX_DP<3>")
	)
	(segment
		(start 371.690138 -110.737142)
		(end 371.631972 -110.795308)
		(width 0.1143)
		(layer "B.Cu")
		(net "DMI_CPU0_PCH_RX_DP<3>")
	)
	(segment
		(start 378.472446 -113.2586)
		(end 377.044712 -113.2586)
		(width 0.0889)
		(layer "B.Cu")
		(net "DMI_CPU0_PCH_RX_DP<3>")
	)
	(segment
		(start 369.828826 -110.459774)
		(end 369.524026 -110.459774)
		(width 0.1143)
		(layer "B.Cu")
		(net "DMI_CPU0_PCH_RX_DP<3>")
	)
	(segment
		(start 371.631972 -110.795308)
		(end 371.631972 -110.795562)
		(width 0.1143)
		(layer "B.Cu")
		(net "DMI_CPU0_PCH_RX_DP<3>")
	)
	(segment
		(start 376.958352 -113.17224)
		(end 376.958098 -113.17224)
		(width 0.0889)
		(layer "B.Cu")
		(net "DMI_CPU0_PCH_RX_DP<3>")
	)
	(segment
		(start 378.622052 -113.172494)
		(end 378.621798 -113.172494)
		(width 0.0889)
		(layer "B.Cu")
		(net "DMI_CPU0_PCH_RX_DP<3>")
	)
	(segment
		(start 380.7079 -116.10594)
		(end 380.7079 -116.083588)
		(width 0.0889)
		(layer "B.Cu")
		(net "DMI_CPU0_PCH_RX_DP<3>")
	)
	(segment
		(start 371.17274 -110.795308)
		(end 371.114574 -110.737142)
		(width 0.1143)
		(layer "B.Cu")
		(net "DMI_CPU0_PCH_RX_DP<3>")
	)
	(segment
		(start 372.550436 -110.795308)
		(end 372.550436 -110.795562)
		(width 0.1143)
		(layer "B.Cu")
		(net "DMI_CPU0_PCH_RX_DP<3>")
	)
	(segment
		(start 375.3231 -112.016794)
		(end 375.3231 -111.7346)
		(width 0.0889)
		(layer "B.Cu")
		(net "DMI_CPU0_PCH_RX_DP<3>")
	)
	(segment
		(start 380.51359 -114.034062)
		(end 380.50216 -114.027204)
		(width 0.0889)
		(layer "B.Cu")
		(net "DMI_CPU0_PCH_RX_DP<3>")
	)
	(segment
		(start 374.97131 -111.025686)
		(end 374.682766 -110.737142)
		(width 0.1143)
		(layer "B.Cu")
		(net "DMI_CPU0_PCH_RX_DP<3>")
	)
	(segment
		(start 380.47676 -117.518688)
		(end 380.45263 -117.42928)
		(width 0.0889)
		(layer "B.Cu")
		(net "DMI_CPU0_PCH_RX_DP<3>")
	)
	(segment
		(start 372.091204 -110.795562)
		(end 372.091204 -110.795308)
		(width 0.1143)
		(layer "B.Cu")
		(net "DMI_CPU0_PCH_RX_DP<3>")
	)
	(segment
		(start 380.2126 -116.974874)
		(end 380.2126 -116.931694)
		(width 0.0889)
		(layer "B.Cu")
		(net "DMI_CPU0_PCH_RX_DP<3>")
	)
	(arc
		(start 380.507748 -116.441474)
		(mid 380.651552 -116.299791)
		(end 380.7079 -116.10594)
		(width 0.0889)
		(layer "B.Cu")
		(net "DMI_CPU0_PCH_RX_DP<3>")
	)
	(arc
		(start 380.7079 -116.083588)
		(mid 380.65155 -115.889738)
		(end 380.507748 -115.748054)
		(width 0.0889)
		(layer "B.Cu")
		(net "DMI_CPU0_PCH_RX_DP<3>")
	)
	(arc
		(start 380.2126 -116.931694)
		(mid 380.296881 -116.648477)
		(end 380.507748 -116.441474)
		(width 0.0889)
		(layer "B.Cu")
		(net "DMI_CPU0_PCH_RX_DP<3>")
	)
	(arc
		(start 380.2126 -113.508028)
		(mid 380.007898 -113.169913)
		(end 379.612652 -113.172494)
		(width 0.0889)
		(layer "B.Cu")
		(net "DMI_CPU0_PCH_RX_DP<3>")
	)
	(arc
		(start 379.612652 -113.172494)
		(mid 379.31725 -113.251625)
		(end 379.021848 -113.172494)
		(width 0.0889)
		(layer "B.Cu")
		(net "DMI_CPU0_PCH_RX_DP<3>")
	)
	(arc
		(start 380.2126 -115.214654)
		(mid 380.296881 -114.931437)
		(end 380.507748 -114.724434)
		(width 0.0889)
		(layer "B.Cu")
		(net "DMI_CPU0_PCH_RX_DP<3>")
	)
	(arc
		(start 380.558294 -114.695224)
		(mid 380.66493 -114.56752)
		(end 380.711202 -114.407696)
		(width 0.0889)
		(layer "B.Cu")
		(net "DMI_CPU0_PCH_RX_DP<3>")
	)
	(arc
		(start 379.021848 -113.172494)
		(mid 378.82195 -113.118995)
		(end 378.622052 -113.172494)
		(width 0.0889)
		(layer "B.Cu")
		(net "DMI_CPU0_PCH_RX_DP<3>")
	)
	(arc
		(start 380.711202 -114.407696)
		(mid 380.666093 -114.192504)
		(end 380.51359 -114.034062)
		(width 0.0889)
		(layer "B.Cu")
		(net "DMI_CPU0_PCH_RX_DP<3>")
	)
	(arc
		(start 380.50216 -114.027204)
		(mid 380.2953 -113.82097)
		(end 380.2126 -113.540794)
		(width 0.0889)
		(layer "B.Cu")
		(net "DMI_CPU0_PCH_RX_DP<3>")
	)
	(arc
		(start 380.507748 -115.748054)
		(mid 380.296884 -115.54105)
		(end 380.2126 -115.257834)
		(width 0.0889)
		(layer "B.Cu")
		(net "DMI_CPU0_PCH_RX_DP<3>")
	)
	(arc
		(start 380.45263 -117.42928)
		(mid 380.280636 -117.229535)
		(end 380.2126 -116.974874)
		(width 0.0889)
		(layer "B.Cu")
		(net "DMI_CPU0_PCH_RX_DP<3>")
	)
	(segment
		(start 379.81255 -116.953284)
		(end 379.31725 -116.72316)
		(width 0.1143)
		(layer "F.Cu")
		(net "DMI_CPU0_PCH_RX_DP<2>")
	)
	(via
		(at 370.3574 -111.5822)
		(size 0.508)
		(drill 0.254)
		(layers "F.Cu" "B.Cu")
		(net "DMI_CPU0_PCH_RX_DP<2>")
	)
	(via
		(at 379.81255 -116.953284)
		(size 0.508)
		(drill 0.254)
		(layers "F.Cu" "B.Cu")
		(net "DMI_CPU0_PCH_RX_DP<2>")
	)
	(segment
		(start 365.656368 -111.5822)
		(end 370.3574 -111.5822)
		(width 0.1143)
		(layer "B.Cu")
		(net "DMI_CPU0_PCH_RX_DP<2>")
	)
	(segment
		(start 379.616716 -115.585494)
		(end 379.624336 -115.589812)
		(width 0.0889)
		(layer "B.Cu")
		(net "DMI_CPU0_PCH_RX_DP<2>")
	)
	(segment
		(start 372.082314 -112.378236)
		(end 374.645936 -112.378236)
		(width 0.0889)
		(layer "B.Cu")
		(net "DMI_CPU0_PCH_RX_DP<2>")
	)
	(segment
		(start 371.8052 -112.352836)
		(end 372.034816 -112.352836)
		(width 0.1143)
		(layer "B.Cu")
		(net "DMI_CPU0_PCH_RX_DP<2>")
	)
	(segment
		(start 378.031248 -113.865914)
		(end 378.075444 -113.840514)
		(width 0.0889)
		(layer "B.Cu")
		(net "DMI_CPU0_PCH_RX_DP<2>")
	)
	(segment
		(start 379.64364 -116.660168)
		(end 379.81255 -116.953284)
		(width 0.0889)
		(layer "B.Cu")
		(net "DMI_CPU0_PCH_RX_DP<2>")
	)
	(segment
		(start 374.645936 -112.378236)
		(end 376.074686 -113.806986)
		(width 0.0889)
		(layer "B.Cu")
		(net "DMI_CPU0_PCH_RX_DP<2>")
	)
	(segment
		(start 379.685042 -116.597938)
		(end 379.64364 -116.660168)
		(width 0.0889)
		(layer "B.Cu")
		(net "DMI_CPU0_PCH_RX_DP<2>")
	)
	(segment
		(start 379.9078 -116.073174)
		(end 379.9078 -116.105686)
		(width 0.0889)
		(layer "B.Cu")
		(net "DMI_CPU0_PCH_RX_DP<2>")
	)
	(segment
		(start 365.506 -110.998)
		(end 365.506 -111.431832)
		(width 0.1143)
		(layer "B.Cu")
		(net "DMI_CPU0_PCH_RX_DP<2>")
	)
	(segment
		(start 376.074686 -113.806986)
		(end 377.411488 -113.806986)
		(width 0.0889)
		(layer "B.Cu")
		(net "DMI_CPU0_PCH_RX_DP<2>")
	)
	(segment
		(start 379.757178 -116.513864)
		(end 379.685042 -116.597938)
		(width 0.0889)
		(layer "B.Cu")
		(net "DMI_CPU0_PCH_RX_DP<2>")
	)
	(segment
		(start 372.034816 -112.352836)
		(end 372.056914 -112.352836)
		(width 0.0889)
		(layer "B.Cu")
		(net "DMI_CPU0_PCH_RX_DP<2>")
	)
	(segment
		(start 371.034564 -111.5822)
		(end 371.8052 -112.352836)
		(width 0.1143)
		(layer "B.Cu")
		(net "DMI_CPU0_PCH_RX_DP<2>")
	)
	(segment
		(start 370.3574 -111.5822)
		(end 371.034564 -111.5822)
		(width 0.1143)
		(layer "B.Cu")
		(net "DMI_CPU0_PCH_RX_DP<2>")
	)
	(segment
		(start 365.506 -111.431832)
		(end 365.656368 -111.5822)
		(width 0.1143)
		(layer "B.Cu")
		(net "DMI_CPU0_PCH_RX_DP<2>")
	)
	(segment
		(start 379.612398 -114.889534)
		(end 379.612144 -114.889788)
		(width 0.0889)
		(layer "B.Cu")
		(net "DMI_CPU0_PCH_RX_DP<2>")
	)
	(segment
		(start 378.075444 -113.840514)
		(end 378.080778 -113.840514)
		(width 0.0889)
		(layer "B.Cu")
		(net "DMI_CPU0_PCH_RX_DP<2>")
	)
	(segment
		(start 372.056914 -112.352836)
		(end 372.082314 -112.378236)
		(width 0.0889)
		(layer "B.Cu")
		(net "DMI_CPU0_PCH_RX_DP<2>")
	)
	(arc
		(start 377.411488 -113.806986)
		(mid 377.525356 -113.82196)
		(end 377.631452 -113.865914)
		(width 0.0889)
		(layer "B.Cu")
		(net "DMI_CPU0_PCH_RX_DP<2>")
	)
	(arc
		(start 378.080778 -113.840514)
		(mid 378.354368 -113.787572)
		(end 378.621798 -113.865914)
		(width 0.0889)
		(layer "B.Cu")
		(net "DMI_CPU0_PCH_RX_DP<2>")
	)
	(arc
		(start 379.612144 -114.889788)
		(mid 379.604086 -114.89452)
		(end 379.596142 -114.89944)
		(width 0.0889)
		(layer "B.Cu")
		(net "DMI_CPU0_PCH_RX_DP<2>")
	)
	(arc
		(start 379.596142 -114.89944)
		(mid 379.41216 -115.248265)
		(end 379.616716 -115.585494)
		(width 0.0889)
		(layer "B.Cu")
		(net "DMI_CPU0_PCH_RX_DP<2>")
	)
	(arc
		(start 379.022102 -113.865914)
		(mid 379.82906 -114.082576)
		(end 379.612398 -114.889534)
		(width 0.0889)
		(layer "B.Cu")
		(net "DMI_CPU0_PCH_RX_DP<2>")
	)
	(arc
		(start 377.631452 -113.865914)
		(mid 377.83135 -113.919413)
		(end 378.031248 -113.865914)
		(width 0.0889)
		(layer "B.Cu")
		(net "DMI_CPU0_PCH_RX_DP<2>")
	)
	(arc
		(start 379.9078 -116.105686)
		(mid 379.869061 -116.323266)
		(end 379.757178 -116.513864)
		(width 0.0889)
		(layer "B.Cu")
		(net "DMI_CPU0_PCH_RX_DP<2>")
	)
	(arc
		(start 379.624336 -115.589812)
		(mid 379.831661 -115.793016)
		(end 379.9078 -116.073174)
		(width 0.0889)
		(layer "B.Cu")
		(net "DMI_CPU0_PCH_RX_DP<2>")
	)
	(arc
		(start 378.621798 -113.865914)
		(mid 378.82195 -113.91954)
		(end 379.022102 -113.865914)
		(width 0.0889)
		(layer "B.Cu")
		(net "DMI_CPU0_PCH_RX_DP<2>")
	)
	(segment
		(start 377.83135 -115.86464)
		(end 378.32665 -116.094764)
		(width 0.1143)
		(layer "F.Cu")
		(net "DMI_CPU0_PCH_RX_DP<1>")
	)
	(via
		(at 378.32665 -116.094764)
		(size 0.508)
		(drill 0.254)
		(layers "F.Cu" "B.Cu")
		(net "DMI_CPU0_PCH_RX_DP<1>")
	)
	(segment
		(start 378.474224 -115.722908)
		(end 378.481082 -115.7478)
		(width 0.0889)
		(layer "B.Cu")
		(net "DMI_CPU0_PCH_RX_DP<1>")
	)
	(segment
		(start 375.834148 -116.0145)
		(end 376.05843 -116.0145)
		(width 0.0889)
		(layer "B.Cu")
		(net "DMI_CPU0_PCH_RX_DP<1>")
	)
	(segment
		(start 373.180102 -114.915188)
		(end 375.834148 -116.0145)
		(width 0.0889)
		(layer "B.Cu")
		(net "DMI_CPU0_PCH_RX_DP<1>")
	)
	(segment
		(start 367.53292 -114.940588)
		(end 367.8682 -114.940588)
		(width 0.1143)
		(layer "B.Cu")
		(net "DMI_CPU0_PCH_RX_DP<1>")
	)
	(segment
		(start 376.05843 -116.0145)
		(end 376.148854 -116.104924)
		(width 0.0889)
		(layer "B.Cu")
		(net "DMI_CPU0_PCH_RX_DP<1>")
	)
	(segment
		(start 365.506 -114.7064)
		(end 365.6076 -114.6048)
		(width 0.1143)
		(layer "B.Cu")
		(net "DMI_CPU0_PCH_RX_DP<1>")
	)
	(segment
		(start 367.890298 -114.940588)
		(end 367.915698 -114.915188)
		(width 0.0889)
		(layer "B.Cu")
		(net "DMI_CPU0_PCH_RX_DP<1>")
	)
	(segment
		(start 376.148854 -116.104924)
		(end 376.415554 -116.104924)
		(width 0.0889)
		(layer "B.Cu")
		(net "DMI_CPU0_PCH_RX_DP<1>")
	)
	(segment
		(start 367.915698 -114.915188)
		(end 373.180102 -114.915188)
		(width 0.0889)
		(layer "B.Cu")
		(net "DMI_CPU0_PCH_RX_DP<1>")
	)
	(segment
		(start 365.506 -115.189)
		(end 365.506 -114.7064)
		(width 0.1143)
		(layer "B.Cu")
		(net "DMI_CPU0_PCH_RX_DP<1>")
	)
	(segment
		(start 376.505978 -116.0145)
		(end 377.304046 -116.0145)
		(width 0.0889)
		(layer "B.Cu")
		(net "DMI_CPU0_PCH_RX_DP<1>")
	)
	(segment
		(start 367.8682 -114.940588)
		(end 367.890298 -114.940588)
		(width 0.0889)
		(layer "B.Cu")
		(net "DMI_CPU0_PCH_RX_DP<1>")
	)
	(segment
		(start 378.49556 -115.801648)
		(end 378.32665 -116.094764)
		(width 0.0889)
		(layer "B.Cu")
		(net "DMI_CPU0_PCH_RX_DP<1>")
	)
	(segment
		(start 366.722152 -114.6048)
		(end 367.53292 -114.940588)
		(width 0.1143)
		(layer "B.Cu")
		(net "DMI_CPU0_PCH_RX_DP<1>")
	)
	(segment
		(start 377.481846 -115.8367)
		(end 377.795028 -115.8367)
		(width 0.0889)
		(layer "B.Cu")
		(net "DMI_CPU0_PCH_RX_DP<1>")
	)
	(segment
		(start 365.6076 -114.6048)
		(end 366.722152 -114.6048)
		(width 0.1143)
		(layer "B.Cu")
		(net "DMI_CPU0_PCH_RX_DP<1>")
	)
	(segment
		(start 378.126498 -115.748054)
		(end 378.126752 -115.748054)
		(width 0.0889)
		(layer "B.Cu")
		(net "DMI_CPU0_PCH_RX_DP<1>")
	)
	(segment
		(start 377.304046 -116.0145)
		(end 377.481846 -115.8367)
		(width 0.0889)
		(layer "B.Cu")
		(net "DMI_CPU0_PCH_RX_DP<1>")
	)
	(segment
		(start 376.415554 -116.104924)
		(end 376.505978 -116.0145)
		(width 0.0889)
		(layer "B.Cu")
		(net "DMI_CPU0_PCH_RX_DP<1>")
	)
	(segment
		(start 378.481082 -115.7478)
		(end 378.49556 -115.801648)
		(width 0.0889)
		(layer "B.Cu")
		(net "DMI_CPU0_PCH_RX_DP<1>")
	)
	(arc
		(start 377.926346 -115.823492)
		(mid 378.029473 -115.79387)
		(end 378.126498 -115.748054)
		(width 0.0889)
		(layer "B.Cu")
		(net "DMI_CPU0_PCH_RX_DP<1>")
	)
	(arc
		(start 378.126752 -115.748054)
		(mid 378.297601 -115.69572)
		(end 378.474224 -115.722908)
		(width 0.0889)
		(layer "B.Cu")
		(net "DMI_CPU0_PCH_RX_DP<1>")
	)
	(arc
		(start 377.795028 -115.8367)
		(mid 377.861016 -115.833366)
		(end 377.926346 -115.823492)
		(width 0.0889)
		(layer "B.Cu")
		(net "DMI_CPU0_PCH_RX_DP<1>")
	)
	(segment
		(start 378.822204 -114.1476)
		(end 379.31725 -114.377724)
		(width 0.1143)
		(layer "F.Cu")
		(net "DMI_CPU0_PCH_RX_DP<0>")
	)
	(segment
		(start 378.82195 -114.1476)
		(end 378.822204 -114.1476)
		(width 0.1143)
		(layer "F.Cu")
		(net "DMI_CPU0_PCH_RX_DP<0>")
	)
	(via
		(at 370.400834 -113.41608)
		(size 0.508)
		(drill 0.254)
		(layers "F.Cu" "B.Cu")
		(net "DMI_CPU0_PCH_RX_DP<0>")
	)
	(via
		(at 379.31725 -114.377724)
		(size 0.508)
		(drill 0.254)
		(layers "F.Cu" "B.Cu")
		(net "DMI_CPU0_PCH_RX_DP<0>")
	)
	(segment
		(start 378.032518 -114.890042)
		(end 378.013722 -114.879374)
		(width 0.0889)
		(layer "B.Cu")
		(net "DMI_CPU0_PCH_RX_DP<0>")
	)
	(segment
		(start 373.9134 -113.665)
		(end 371.001798 -113.665)
		(width 0.1143)
		(layer "B.Cu")
		(net "DMI_CPU0_PCH_RX_DP<0>")
	)
	(segment
		(start 378.979176 -114.377724)
		(end 378.914152 -114.442748)
		(width 0.0889)
		(layer "B.Cu")
		(net "DMI_CPU0_PCH_RX_DP<0>")
	)
	(segment
		(start 374.1166 -113.6396)
		(end 373.960898 -113.6396)
		(width 0.0889)
		(layer "B.Cu")
		(net "DMI_CPU0_PCH_RX_DP<0>")
	)
	(segment
		(start 375.48312 -115.00612)
		(end 374.1166 -113.6396)
		(width 0.0889)
		(layer "B.Cu")
		(net "DMI_CPU0_PCH_RX_DP<0>")
	)
	(segment
		(start 378.013722 -114.879374)
		(end 378.012198 -114.878612)
		(width 0.0889)
		(layer "B.Cu")
		(net "DMI_CPU0_PCH_RX_DP<0>")
	)
	(segment
		(start 378.080524 -114.914934)
		(end 378.080524 -114.91468)
		(width 0.0889)
		(layer "B.Cu")
		(net "DMI_CPU0_PCH_RX_DP<0>")
	)
	(segment
		(start 377.649994 -114.878866)
		(end 377.630944 -114.889788)
		(width 0.0889)
		(layer "B.Cu")
		(net "DMI_CPU0_PCH_RX_DP<0>")
	)
	(segment
		(start 370.400834 -113.41608)
		(end 369.928648 -113.2205)
		(width 0.1143)
		(layer "B.Cu")
		(net "DMI_CPU0_PCH_RX_DP<0>")
	)
	(segment
		(start 379.31725 -114.377724)
		(end 378.979176 -114.377724)
		(width 0.0889)
		(layer "B.Cu")
		(net "DMI_CPU0_PCH_RX_DP<0>")
	)
	(segment
		(start 369.928648 -113.2205)
		(end 369.5573 -113.2205)
		(width 0.1143)
		(layer "B.Cu")
		(net "DMI_CPU0_PCH_RX_DP<0>")
	)
	(segment
		(start 373.960898 -113.6396)
		(end 373.935498 -113.665)
		(width 0.0889)
		(layer "B.Cu")
		(net "DMI_CPU0_PCH_RX_DP<0>")
	)
	(segment
		(start 377.650502 -114.878612)
		(end 377.649994 -114.878866)
		(width 0.0889)
		(layer "B.Cu")
		(net "DMI_CPU0_PCH_RX_DP<0>")
	)
	(segment
		(start 377.195842 -115.00612)
		(end 375.48312 -115.00612)
		(width 0.0889)
		(layer "B.Cu")
		(net "DMI_CPU0_PCH_RX_DP<0>")
	)
	(segment
		(start 369.443 -113.3348)
		(end 369.443 -113.792)
		(width 0.1143)
		(layer "B.Cu")
		(net "DMI_CPU0_PCH_RX_DP<0>")
	)
	(segment
		(start 373.935498 -113.665)
		(end 373.9134 -113.665)
		(width 0.0889)
		(layer "B.Cu")
		(net "DMI_CPU0_PCH_RX_DP<0>")
	)
	(segment
		(start 371.001798 -113.665)
		(end 370.400834 -113.41608)
		(width 0.1143)
		(layer "B.Cu")
		(net "DMI_CPU0_PCH_RX_DP<0>")
	)
	(segment
		(start 369.5573 -113.2205)
		(end 369.443 -113.3348)
		(width 0.1143)
		(layer "B.Cu")
		(net "DMI_CPU0_PCH_RX_DP<0>")
	)
	(arc
		(start 378.914152 -114.442748)
		(mid 378.618027 -114.892006)
		(end 378.080524 -114.914934)
		(width 0.0889)
		(layer "B.Cu")
		(net "DMI_CPU0_PCH_RX_DP<0>")
	)
	(arc
		(start 377.630944 -114.889788)
		(mid 377.421047 -114.976574)
		(end 377.195842 -115.00612)
		(width 0.0889)
		(layer "B.Cu")
		(net "DMI_CPU0_PCH_RX_DP<0>")
	)
	(arc
		(start 378.080524 -114.91468)
		(mid 378.056239 -114.90291)
		(end 378.032518 -114.890042)
		(width 0.0889)
		(layer "B.Cu")
		(net "DMI_CPU0_PCH_RX_DP<0>")
	)
	(arc
		(start 378.012198 -114.878612)
		(mid 377.83135 -114.830214)
		(end 377.650502 -114.878612)
		(width 0.0889)
		(layer "B.Cu")
		(net "DMI_CPU0_PCH_RX_DP<0>")
	)
	(segment
		(start 380.30785 -116.72316)
		(end 380.80315 -116.953284)
		(width 0.1143)
		(layer "F.Cu")
		(net "DMI_CPU0_PCH_RX_DN<3>")
	)
	(via
		(at 380.80315 -116.953284)
		(size 0.508)
		(drill 0.254)
		(layers "F.Cu" "B.Cu")
		(net "DMI_CPU0_PCH_RX_DN<3>")
	)
	(segment
		(start 374.782842 -110.495842)
		(end 375.539 -111.252)
		(width 0.1143)
		(layer "B.Cu")
		(net "DMI_CPU0_PCH_RX_DN<3>")
	)
	(segment
		(start 369.443 -109.601)
		(end 369.443 -110.080552)
		(width 0.1143)
		(layer "B.Cu")
		(net "DMI_CPU0_PCH_RX_DN<3>")
	)
	(segment
		(start 380.4031 -115.225068)
		(end 380.4031 -115.24742)
		(width 0.0889)
		(layer "B.Cu")
		(net "DMI_CPU0_PCH_RX_DN<3>")
	)
	(segment
		(start 378.421392 -113.0681)
		(end 378.526548 -113.007394)
		(width 0.0889)
		(layer "B.Cu")
		(net "DMI_CPU0_PCH_RX_DN<3>")
	)
	(segment
		(start 380.664466 -114.854228)
		(end 380.603252 -114.88928)
		(width 0.0889)
		(layer "B.Cu")
		(net "DMI_CPU0_PCH_RX_DN<3>")
	)
	(segment
		(start 380.63424 -117.2464)
		(end 380.80315 -116.953284)
		(width 0.0889)
		(layer "B.Cu")
		(net "DMI_CPU0_PCH_RX_DN<3>")
	)
	(segment
		(start 377.615958 -113.022126)
		(end 377.661678 -112.976406)
		(width 0.0889)
		(layer "B.Cu")
		(net "DMI_CPU0_PCH_RX_DN<3>")
	)
	(segment
		(start 380.599188 -113.86312)
		(end 380.599696 -113.863374)
		(width 0.0889)
		(layer "B.Cu")
		(net "DMI_CPU0_PCH_RX_DN<3>")
	)
	(segment
		(start 378.019818 -113.0681)
		(end 378.421392 -113.0681)
		(width 0.0889)
		(layer "B.Cu")
		(net "DMI_CPU0_PCH_RX_DN<3>")
	)
	(segment
		(start 375.5136 -111.9378)
		(end 375.748804 -112.173004)
		(width 0.0889)
		(layer "B.Cu")
		(net "DMI_CPU0_PCH_RX_DN<3>")
	)
	(segment
		(start 377.974098 -113.02238)
		(end 378.019818 -113.0681)
		(width 0.0889)
		(layer "B.Cu")
		(net "DMI_CPU0_PCH_RX_DN<3>")
	)
	(segment
		(start 375.539 -111.687102)
		(end 375.539 -111.7092)
		(width 0.0889)
		(layer "B.Cu")
		(net "DMI_CPU0_PCH_RX_DN<3>")
	)
	(segment
		(start 376.3518 -112.776)
		(end 376.834654 -112.776)
		(width 0.0889)
		(layer "B.Cu")
		(net "DMI_CPU0_PCH_RX_DN<3>")
	)
	(segment
		(start 377.123706 -113.0681)
		(end 377.570238 -113.0681)
		(width 0.0889)
		(layer "B.Cu")
		(net "DMI_CPU0_PCH_RX_DN<3>")
	)
	(segment
		(start 377.570238 -113.0681)
		(end 377.615958 -113.02238)
		(width 0.0889)
		(layer "B.Cu")
		(net "DMI_CPU0_PCH_RX_DN<3>")
	)
	(segment
		(start 380.4031 -116.942108)
		(end 380.4031 -116.96446)
		(width 0.0889)
		(layer "B.Cu")
		(net "DMI_CPU0_PCH_RX_DN<3>")
	)
	(segment
		(start 380.4031 -113.505488)
		(end 380.4031 -113.53673)
		(width 0.0889)
		(layer "B.Cu")
		(net "DMI_CPU0_PCH_RX_DN<3>")
	)
	(segment
		(start 375.875804 -112.173004)
		(end 376.064526 -112.361726)
		(width 0.0889)
		(layer "B.Cu")
		(net "DMI_CPU0_PCH_RX_DN<3>")
	)
	(segment
		(start 379.517402 -113.00714)
		(end 379.517402 -113.007394)
		(width 0.0889)
		(layer "B.Cu")
		(net "DMI_CPU0_PCH_RX_DN<3>")
	)
	(segment
		(start 375.539 -111.252)
		(end 375.539 -111.687102)
		(width 0.1143)
		(layer "B.Cu")
		(net "DMI_CPU0_PCH_RX_DN<3>")
	)
	(segment
		(start 380.603252 -114.88928)
		(end 380.603252 -114.889534)
		(width 0.0889)
		(layer "B.Cu")
		(net "DMI_CPU0_PCH_RX_DN<3>")
	)
	(segment
		(start 376.064526 -112.488726)
		(end 376.3518 -112.776)
		(width 0.0889)
		(layer "B.Cu")
		(net "DMI_CPU0_PCH_RX_DN<3>")
	)
	(segment
		(start 377.974098 -113.022126)
		(end 377.974098 -113.02238)
		(width 0.0889)
		(layer "B.Cu")
		(net "DMI_CPU0_PCH_RX_DN<3>")
	)
	(segment
		(start 375.5136 -111.7346)
		(end 375.5136 -111.9378)
		(width 0.0889)
		(layer "B.Cu")
		(net "DMI_CPU0_PCH_RX_DN<3>")
	)
	(segment
		(start 375.748804 -112.173004)
		(end 375.875804 -112.173004)
		(width 0.0889)
		(layer "B.Cu")
		(net "DMI_CPU0_PCH_RX_DN<3>")
	)
	(segment
		(start 375.539 -111.7092)
		(end 375.5136 -111.7346)
		(width 0.0889)
		(layer "B.Cu")
		(net "DMI_CPU0_PCH_RX_DN<3>")
	)
	(segment
		(start 377.928378 -112.976406)
		(end 377.974098 -113.022126)
		(width 0.0889)
		(layer "B.Cu")
		(net "DMI_CPU0_PCH_RX_DN<3>")
	)
	(segment
		(start 376.866404 -112.810798)
		(end 377.123706 -113.0681)
		(width 0.0889)
		(layer "B.Cu")
		(net "DMI_CPU0_PCH_RX_DN<3>")
	)
	(segment
		(start 376.866404 -112.80775)
		(end 376.866404 -112.810798)
		(width 0.0889)
		(layer "B.Cu")
		(net "DMI_CPU0_PCH_RX_DN<3>")
	)
	(segment
		(start 380.5555 -117.267482)
		(end 380.63424 -117.2464)
		(width 0.0889)
		(layer "B.Cu")
		(net "DMI_CPU0_PCH_RX_DN<3>")
	)
	(segment
		(start 376.834654 -112.776)
		(end 376.866404 -112.80775)
		(width 0.0889)
		(layer "B.Cu")
		(net "DMI_CPU0_PCH_RX_DN<3>")
	)
	(segment
		(start 380.8984 -116.073174)
		(end 380.8984 -116.116354)
		(width 0.0889)
		(layer "B.Cu")
		(net "DMI_CPU0_PCH_RX_DN<3>")
	)
	(segment
		(start 369.876832 -110.218474)
		(end 370.54663 -110.495842)
		(width 0.1143)
		(layer "B.Cu")
		(net "DMI_CPU0_PCH_RX_DN<3>")
	)
	(segment
		(start 377.615958 -113.02238)
		(end 377.615958 -113.022126)
		(width 0.0889)
		(layer "B.Cu")
		(net "DMI_CPU0_PCH_RX_DN<3>")
	)
	(segment
		(start 370.54663 -110.495842)
		(end 374.782842 -110.495842)
		(width 0.1143)
		(layer "B.Cu")
		(net "DMI_CPU0_PCH_RX_DN<3>")
	)
	(segment
		(start 376.064526 -112.361726)
		(end 376.064526 -112.488726)
		(width 0.0889)
		(layer "B.Cu")
		(net "DMI_CPU0_PCH_RX_DN<3>")
	)
	(segment
		(start 379.517148 -113.007394)
		(end 379.517402 -113.00714)
		(width 0.0889)
		(layer "B.Cu")
		(net "DMI_CPU0_PCH_RX_DN<3>")
	)
	(segment
		(start 369.580922 -110.218474)
		(end 369.876832 -110.218474)
		(width 0.1143)
		(layer "B.Cu")
		(net "DMI_CPU0_PCH_RX_DN<3>")
	)
	(segment
		(start 380.599696 -113.863374)
		(end 380.610618 -113.869724)
		(width 0.0889)
		(layer "B.Cu")
		(net "DMI_CPU0_PCH_RX_DN<3>")
	)
	(segment
		(start 369.443 -110.080552)
		(end 369.580922 -110.218474)
		(width 0.1143)
		(layer "B.Cu")
		(net "DMI_CPU0_PCH_RX_DN<3>")
	)
	(segment
		(start 377.661678 -112.976406)
		(end 377.928378 -112.976406)
		(width 0.0889)
		(layer "B.Cu")
		(net "DMI_CPU0_PCH_RX_DN<3>")
	)
	(arc
		(start 380.4031 -116.96446)
		(mid 380.445633 -117.132897)
		(end 380.5555 -117.267482)
		(width 0.0889)
		(layer "B.Cu")
		(net "DMI_CPU0_PCH_RX_DN<3>")
	)
	(arc
		(start 380.4031 -113.53673)
		(mid 380.4598 -113.724746)
		(end 380.599188 -113.86312)
		(width 0.0889)
		(layer "B.Cu")
		(net "DMI_CPU0_PCH_RX_DN<3>")
	)
	(arc
		(start 380.610618 -113.869724)
		(mid 380.835212 -114.103973)
		(end 380.901448 -114.421666)
		(width 0.0889)
		(layer "B.Cu")
		(net "DMI_CPU0_PCH_RX_DN<3>")
	)
	(arc
		(start 380.901448 -114.421666)
		(mid 380.829891 -114.663666)
		(end 380.664466 -114.854228)
		(width 0.0889)
		(layer "B.Cu")
		(net "DMI_CPU0_PCH_RX_DN<3>")
	)
	(arc
		(start 380.8984 -116.116354)
		(mid 380.814119 -116.399571)
		(end 380.603252 -116.606574)
		(width 0.0889)
		(layer "B.Cu")
		(net "DMI_CPU0_PCH_RX_DN<3>")
	)
	(arc
		(start 380.4031 -115.24742)
		(mid 380.45945 -115.44127)
		(end 380.603252 -115.582954)
		(width 0.0889)
		(layer "B.Cu")
		(net "DMI_CPU0_PCH_RX_DN<3>")
	)
	(arc
		(start 378.526548 -113.007394)
		(mid 378.82195 -112.928263)
		(end 379.117352 -113.007394)
		(width 0.0889)
		(layer "B.Cu")
		(net "DMI_CPU0_PCH_RX_DN<3>")
	)
	(arc
		(start 380.603252 -114.889534)
		(mid 380.459448 -115.031217)
		(end 380.4031 -115.225068)
		(width 0.0889)
		(layer "B.Cu")
		(net "DMI_CPU0_PCH_RX_DN<3>")
	)
	(arc
		(start 379.517402 -113.007394)
		(mid 380.102127 -113.004222)
		(end 380.4031 -113.505488)
		(width 0.0889)
		(layer "B.Cu")
		(net "DMI_CPU0_PCH_RX_DN<3>")
	)
	(arc
		(start 379.117352 -113.007394)
		(mid 379.31725 -113.060893)
		(end 379.517148 -113.007394)
		(width 0.0889)
		(layer "B.Cu")
		(net "DMI_CPU0_PCH_RX_DN<3>")
	)
	(arc
		(start 380.603252 -115.582954)
		(mid 380.814116 -115.789958)
		(end 380.8984 -116.073174)
		(width 0.0889)
		(layer "B.Cu")
		(net "DMI_CPU0_PCH_RX_DN<3>")
	)
	(arc
		(start 380.603252 -116.606574)
		(mid 380.459448 -116.748257)
		(end 380.4031 -116.942108)
		(width 0.0889)
		(layer "B.Cu")
		(net "DMI_CPU0_PCH_RX_DN<3>")
	)
	(segment
		(start 378.82195 -115.86464)
		(end 379.31725 -116.094764)
		(width 0.1143)
		(layer "F.Cu")
		(net "DMI_CPU0_PCH_RX_DN<2>")
	)
	(via
		(at 379.31725 -116.094764)
		(size 0.508)
		(drill 0.254)
		(layers "F.Cu" "B.Cu")
		(net "DMI_CPU0_PCH_RX_DN<2>")
	)
	(via
		(at 366.432084 -111.8235)
		(size 0.508)
		(drill 0.254)
		(layers "F.Cu" "B.Cu")
		(net "DMI_CPU0_PCH_RX_DN<2>")
	)
	(segment
		(start 372.589298 -112.568736)
		(end 372.082314 -112.568736)
		(width 0.0889)
		(layer "B.Cu")
		(net "DMI_CPU0_PCH_RX_DN<2>")
	)
	(segment
		(start 375.995692 -113.997486)
		(end 375.839228 -113.841022)
		(width 0.0889)
		(layer "B.Cu")
		(net "DMI_CPU0_PCH_RX_DN<2>")
	)
	(segment
		(start 379.495304 -114.73688)
		(end 379.517148 -114.724434)
		(width 0.0889)
		(layer "B.Cu")
		(net "DMI_CPU0_PCH_RX_DN<2>")
	)
	(segment
		(start 371.705124 -112.594136)
		(end 370.934488 -111.8235)
		(width 0.1143)
		(layer "B.Cu")
		(net "DMI_CPU0_PCH_RX_DN<2>")
	)
	(segment
		(start 379.31725 -116.094764)
		(end 379.485906 -116.387626)
		(width 0.0889)
		(layer "B.Cu")
		(net "DMI_CPU0_PCH_RX_DN<2>")
	)
	(segment
		(start 373.037862 -112.568736)
		(end 372.94693 -112.659668)
		(width 0.0889)
		(layer "B.Cu")
		(net "DMI_CPU0_PCH_RX_DN<2>")
	)
	(segment
		(start 376.13844 -113.997486)
		(end 375.995692 -113.997486)
		(width 0.0889)
		(layer "B.Cu")
		(net "DMI_CPU0_PCH_RX_DN<2>")
	)
	(segment
		(start 375.520966 -113.6523)
		(end 375.520966 -113.52276)
		(width 0.0889)
		(layer "B.Cu")
		(net "DMI_CPU0_PCH_RX_DN<2>")
	)
	(segment
		(start 375.839228 -113.841022)
		(end 375.709688 -113.841022)
		(width 0.0889)
		(layer "B.Cu")
		(net "DMI_CPU0_PCH_RX_DN<2>")
	)
	(segment
		(start 365.506 -112.395)
		(end 365.506 -111.9505)
		(width 0.1143)
		(layer "B.Cu")
		(net "DMI_CPU0_PCH_RX_DN<2>")
	)
	(segment
		(start 374.566942 -112.568736)
		(end 374.46839 -112.568736)
		(width 0.0889)
		(layer "B.Cu")
		(net "DMI_CPU0_PCH_RX_DN<2>")
	)
	(segment
		(start 375.709688 -113.841022)
		(end 375.520966 -113.6523)
		(width 0.0889)
		(layer "B.Cu")
		(net "DMI_CPU0_PCH_RX_DN<2>")
	)
	(segment
		(start 373.395494 -112.659668)
		(end 373.304562 -112.568736)
		(width 0.0889)
		(layer "B.Cu")
		(net "DMI_CPU0_PCH_RX_DN<2>")
	)
	(segment
		(start 375.332244 -113.334038)
		(end 375.202704 -113.334038)
		(width 0.0889)
		(layer "B.Cu")
		(net "DMI_CPU0_PCH_RX_DN<2>")
	)
	(segment
		(start 375.202704 -113.334038)
		(end 375.013982 -113.145316)
		(width 0.0889)
		(layer "B.Cu")
		(net "DMI_CPU0_PCH_RX_DN<2>")
	)
	(segment
		(start 372.056914 -112.594136)
		(end 372.034816 -112.594136)
		(width 0.0889)
		(layer "B.Cu")
		(net "DMI_CPU0_PCH_RX_DN<2>")
	)
	(segment
		(start 373.753126 -112.568736)
		(end 373.662194 -112.659668)
		(width 0.0889)
		(layer "B.Cu")
		(net "DMI_CPU0_PCH_RX_DN<2>")
	)
	(segment
		(start 365.506 -111.9505)
		(end 365.633 -111.8235)
		(width 0.1143)
		(layer "B.Cu")
		(net "DMI_CPU0_PCH_RX_DN<2>")
	)
	(segment
		(start 374.019826 -112.568736)
		(end 373.753126 -112.568736)
		(width 0.0889)
		(layer "B.Cu")
		(net "DMI_CPU0_PCH_RX_DN<2>")
	)
	(segment
		(start 375.013982 -113.145316)
		(end 375.013982 -113.015776)
		(width 0.0889)
		(layer "B.Cu")
		(net "DMI_CPU0_PCH_RX_DN<2>")
	)
	(segment
		(start 375.013982 -113.015776)
		(end 374.566942 -112.568736)
		(width 0.0889)
		(layer "B.Cu")
		(net "DMI_CPU0_PCH_RX_DN<2>")
	)
	(segment
		(start 372.94693 -112.659668)
		(end 372.68023 -112.659668)
		(width 0.0889)
		(layer "B.Cu")
		(net "DMI_CPU0_PCH_RX_DN<2>")
	)
	(segment
		(start 373.662194 -112.659668)
		(end 373.395494 -112.659668)
		(width 0.0889)
		(layer "B.Cu")
		(net "DMI_CPU0_PCH_RX_DN<2>")
	)
	(segment
		(start 379.7173 -116.10594)
		(end 379.7173 -116.08181)
		(width 0.0889)
		(layer "B.Cu")
		(net "DMI_CPU0_PCH_RX_DN<2>")
	)
	(segment
		(start 372.034816 -112.594136)
		(end 371.705124 -112.594136)
		(width 0.1143)
		(layer "B.Cu")
		(net "DMI_CPU0_PCH_RX_DN<2>")
	)
	(segment
		(start 372.082314 -112.568736)
		(end 372.056914 -112.594136)
		(width 0.0889)
		(layer "B.Cu")
		(net "DMI_CPU0_PCH_RX_DN<2>")
	)
	(segment
		(start 376.494548 -114.086894)
		(end 376.227848 -114.086894)
		(width 0.0889)
		(layer "B.Cu")
		(net "DMI_CPU0_PCH_RX_DN<2>")
	)
	(segment
		(start 373.304562 -112.568736)
		(end 373.037862 -112.568736)
		(width 0.0889)
		(layer "B.Cu")
		(net "DMI_CPU0_PCH_RX_DN<2>")
	)
	(segment
		(start 379.485906 -116.387626)
		(end 379.588776 -116.415058)
		(width 0.0889)
		(layer "B.Cu")
		(net "DMI_CPU0_PCH_RX_DN<2>")
	)
	(segment
		(start 379.493272 -114.738912)
		(end 379.495304 -114.73688)
		(width 0.0889)
		(layer "B.Cu")
		(net "DMI_CPU0_PCH_RX_DN<2>")
	)
	(segment
		(start 376.583956 -113.997486)
		(end 376.494548 -114.086894)
		(width 0.0889)
		(layer "B.Cu")
		(net "DMI_CPU0_PCH_RX_DN<2>")
	)
	(segment
		(start 378.126752 -114.031014)
		(end 378.126498 -114.031014)
		(width 0.0889)
		(layer "B.Cu")
		(net "DMI_CPU0_PCH_RX_DN<2>")
	)
	(segment
		(start 375.520966 -113.52276)
		(end 375.332244 -113.334038)
		(width 0.0889)
		(layer "B.Cu")
		(net "DMI_CPU0_PCH_RX_DN<2>")
	)
	(segment
		(start 365.633 -111.8235)
		(end 366.432084 -111.8235)
		(width 0.1143)
		(layer "B.Cu")
		(net "DMI_CPU0_PCH_RX_DN<2>")
	)
	(segment
		(start 376.227848 -114.086894)
		(end 376.13844 -113.997486)
		(width 0.0889)
		(layer "B.Cu")
		(net "DMI_CPU0_PCH_RX_DN<2>")
	)
	(segment
		(start 372.68023 -112.659668)
		(end 372.589298 -112.568736)
		(width 0.0889)
		(layer "B.Cu")
		(net "DMI_CPU0_PCH_RX_DN<2>")
	)
	(segment
		(start 374.377458 -112.659668)
		(end 374.110758 -112.659668)
		(width 0.0889)
		(layer "B.Cu")
		(net "DMI_CPU0_PCH_RX_DN<2>")
	)
	(segment
		(start 374.110758 -112.659668)
		(end 374.019826 -112.568736)
		(width 0.0889)
		(layer "B.Cu")
		(net "DMI_CPU0_PCH_RX_DN<2>")
	)
	(segment
		(start 377.411234 -113.997486)
		(end 376.583956 -113.997486)
		(width 0.0889)
		(layer "B.Cu")
		(net "DMI_CPU0_PCH_RX_DN<2>")
	)
	(segment
		(start 374.46839 -112.568736)
		(end 374.377458 -112.659668)
		(width 0.0889)
		(layer "B.Cu")
		(net "DMI_CPU0_PCH_RX_DN<2>")
	)
	(segment
		(start 370.934488 -111.8235)
		(end 366.432084 -111.8235)
		(width 0.1143)
		(layer "B.Cu")
		(net "DMI_CPU0_PCH_RX_DN<2>")
	)
	(arc
		(start 378.126498 -114.031014)
		(mid 377.83135 -114.110019)
		(end 377.536202 -114.031014)
		(width 0.0889)
		(layer "B.Cu")
		(net "DMI_CPU0_PCH_RX_DN<2>")
	)
	(arc
		(start 379.117352 -114.031014)
		(mid 378.82195 -114.110145)
		(end 378.526548 -114.031014)
		(width 0.0889)
		(layer "B.Cu")
		(net "DMI_CPU0_PCH_RX_DN<2>")
	)
	(arc
		(start 378.526548 -114.031014)
		(mid 378.345363 -113.978068)
		(end 378.160026 -114.013996)
		(width 0.0889)
		(layer "B.Cu")
		(net "DMI_CPU0_PCH_RX_DN<2>")
	)
	(arc
		(start 379.523752 -115.751864)
		(mid 379.221568 -115.254017)
		(end 379.493272 -114.738912)
		(width 0.0889)
		(layer "B.Cu")
		(net "DMI_CPU0_PCH_RX_DN<2>")
	)
	(arc
		(start 377.536202 -114.031014)
		(mid 377.475923 -114.006041)
		(end 377.411234 -113.997486)
		(width 0.0889)
		(layer "B.Cu")
		(net "DMI_CPU0_PCH_RX_DN<2>")
	)
	(arc
		(start 379.588776 -116.415058)
		(mid 379.683942 -116.273347)
		(end 379.7173 -116.10594)
		(width 0.0889)
		(layer "B.Cu")
		(net "DMI_CPU0_PCH_RX_DN<2>")
	)
	(arc
		(start 379.517148 -114.724434)
		(mid 379.66396 -114.177826)
		(end 379.117352 -114.031014)
		(width 0.0889)
		(layer "B.Cu")
		(net "DMI_CPU0_PCH_RX_DN<2>")
	)
	(arc
		(start 378.160026 -114.013996)
		(mid 378.143189 -114.022114)
		(end 378.126752 -114.031014)
		(width 0.0889)
		(layer "B.Cu")
		(net "DMI_CPU0_PCH_RX_DN<2>")
	)
	(arc
		(start 379.7173 -116.08181)
		(mid 379.665338 -115.890555)
		(end 379.523752 -115.751864)
		(width 0.0889)
		(layer "B.Cu")
		(net "DMI_CPU0_PCH_RX_DN<2>")
	)
	(segment
		(start 378.32665 -115.00612)
		(end 378.82195 -115.236244)
		(width 0.1143)
		(layer "F.Cu")
		(net "DMI_CPU0_PCH_RX_DN<1>")
	)
	(via
		(at 378.82195 -115.236244)
		(size 0.508)
		(drill 0.254)
		(layers "F.Cu" "B.Cu")
		(net "DMI_CPU0_PCH_RX_DN<1>")
	)
	(via
		(at 366.310926 -114.3635)
		(size 0.508)
		(drill 0.254)
		(layers "F.Cu" "B.Cu")
		(net "DMI_CPU0_PCH_RX_DN<1>")
	)
	(segment
		(start 367.8682 -114.699288)
		(end 367.580926 -114.699288)
		(width 0.1143)
		(layer "B.Cu")
		(net "DMI_CPU0_PCH_RX_DN<1>")
	)
	(segment
		(start 377.402852 -115.6462)
		(end 377.225052 -115.824)
		(width 0.0889)
		(layer "B.Cu")
		(net "DMI_CPU0_PCH_RX_DN<1>")
	)
	(segment
		(start 378.65304 -115.52936)
		(end 378.563632 -115.553236)
		(width 0.0889)
		(layer "B.Cu")
		(net "DMI_CPU0_PCH_RX_DN<1>")
	)
	(segment
		(start 367.580926 -114.699288)
		(end 366.770158 -114.3635)
		(width 0.1143)
		(layer "B.Cu")
		(net "DMI_CPU0_PCH_RX_DN<1>")
	)
	(segment
		(start 378.82195 -115.236244)
		(end 378.65304 -115.52936)
		(width 0.0889)
		(layer "B.Cu")
		(net "DMI_CPU0_PCH_RX_DN<1>")
	)
	(segment
		(start 365.633 -114.3635)
		(end 365.506 -114.2365)
		(width 0.1143)
		(layer "B.Cu")
		(net "DMI_CPU0_PCH_RX_DN<1>")
	)
	(segment
		(start 377.225052 -115.824)
		(end 375.872248 -115.824)
		(width 0.0889)
		(layer "B.Cu")
		(net "DMI_CPU0_PCH_RX_DN<1>")
	)
	(segment
		(start 367.890298 -114.699288)
		(end 367.8682 -114.699288)
		(width 0.0889)
		(layer "B.Cu")
		(net "DMI_CPU0_PCH_RX_DN<1>")
	)
	(segment
		(start 375.872248 -115.824)
		(end 373.218202 -114.724688)
		(width 0.0889)
		(layer "B.Cu")
		(net "DMI_CPU0_PCH_RX_DN<1>")
	)
	(segment
		(start 366.770158 -114.3635)
		(end 366.310926 -114.3635)
		(width 0.1143)
		(layer "B.Cu")
		(net "DMI_CPU0_PCH_RX_DN<1>")
	)
	(segment
		(start 377.794774 -115.6462)
		(end 377.402852 -115.6462)
		(width 0.0889)
		(layer "B.Cu")
		(net "DMI_CPU0_PCH_RX_DN<1>")
	)
	(segment
		(start 367.915698 -114.724688)
		(end 367.890298 -114.699288)
		(width 0.0889)
		(layer "B.Cu")
		(net "DMI_CPU0_PCH_RX_DN<1>")
	)
	(segment
		(start 373.218202 -114.724688)
		(end 367.915698 -114.724688)
		(width 0.0889)
		(layer "B.Cu")
		(net "DMI_CPU0_PCH_RX_DN<1>")
	)
	(segment
		(start 366.310926 -114.3635)
		(end 365.633 -114.3635)
		(width 0.1143)
		(layer "B.Cu")
		(net "DMI_CPU0_PCH_RX_DN<1>")
	)
	(segment
		(start 365.506 -114.2365)
		(end 365.506 -113.792)
		(width 0.1143)
		(layer "B.Cu")
		(net "DMI_CPU0_PCH_RX_DN<1>")
	)
	(arc
		(start 378.031248 -115.582954)
		(mid 377.962038 -115.615512)
		(end 377.8885 -115.636548)
		(width 0.0889)
		(layer "B.Cu")
		(net "DMI_CPU0_PCH_RX_DN<1>")
	)
	(arc
		(start 377.8885 -115.636548)
		(mid 377.841878 -115.643712)
		(end 377.794774 -115.6462)
		(width 0.0889)
		(layer "B.Cu")
		(net "DMI_CPU0_PCH_RX_DN<1>")
	)
	(arc
		(start 378.563632 -115.553236)
		(mid 378.293907 -115.504676)
		(end 378.031248 -115.582954)
		(width 0.0889)
		(layer "B.Cu")
		(net "DMI_CPU0_PCH_RX_DN<1>")
	)
	(segment
		(start 377.83135 -114.1476)
		(end 378.32665 -114.377724)
		(width 0.1143)
		(layer "F.Cu")
		(net "DMI_CPU0_PCH_RX_DN<0>")
	)
	(via
		(at 373.575072 -113.4237)
		(size 0.508)
		(drill 0.254)
		(layers "F.Cu" "B.Cu")
		(net "DMI_CPU0_PCH_RX_DN<0>")
	)
	(via
		(at 378.32665 -114.377724)
		(size 0.508)
		(drill 0.254)
		(layers "F.Cu" "B.Cu")
		(net "DMI_CPU0_PCH_RX_DN<0>")
	)
	(segment
		(start 374.69953 -113.953036)
		(end 374.195594 -113.4491)
		(width 0.0889)
		(layer "B.Cu")
		(net "DMI_CPU0_PCH_RX_DN<0>")
	)
	(segment
		(start 377.196096 -114.81562)
		(end 376.2248 -114.81562)
		(width 0.0889)
		(layer "B.Cu")
		(net "DMI_CPU0_PCH_RX_DN<0>")
	)
	(segment
		(start 375.418604 -114.67211)
		(end 375.418604 -114.528346)
		(width 0.0889)
		(layer "B.Cu")
		(net "DMI_CPU0_PCH_RX_DN<0>")
	)
	(segment
		(start 375.130822 -114.384328)
		(end 374.987312 -114.240818)
		(width 0.0889)
		(layer "B.Cu")
		(net "DMI_CPU0_PCH_RX_DN<0>")
	)
	(segment
		(start 371.049804 -113.4237)
		(end 369.976654 -112.9792)
		(width 0.1143)
		(layer "B.Cu")
		(net "DMI_CPU0_PCH_RX_DN<0>")
	)
	(segment
		(start 374.987312 -114.240818)
		(end 374.987312 -114.097054)
		(width 0.0889)
		(layer "B.Cu")
		(net "DMI_CPU0_PCH_RX_DN<0>")
	)
	(segment
		(start 378.32665 -114.377724)
		(end 378.664724 -114.377724)
		(width 0.0889)
		(layer "B.Cu")
		(net "DMI_CPU0_PCH_RX_DN<0>")
	)
	(segment
		(start 378.126752 -114.724434)
		(end 378.107448 -114.713512)
		(width 0.0889)
		(layer "B.Cu")
		(net "DMI_CPU0_PCH_RX_DN<0>")
	)
	(segment
		(start 375.562114 -114.81562)
		(end 375.418604 -114.67211)
		(width 0.0889)
		(layer "B.Cu")
		(net "DMI_CPU0_PCH_RX_DN<0>")
	)
	(segment
		(start 378.664724 -114.377724)
		(end 378.722636 -114.435636)
		(width 0.0889)
		(layer "B.Cu")
		(net "DMI_CPU0_PCH_RX_DN<0>")
	)
	(segment
		(start 373.960898 -113.4491)
		(end 373.935498 -113.4237)
		(width 0.0889)
		(layer "B.Cu")
		(net "DMI_CPU0_PCH_RX_DN<0>")
	)
	(segment
		(start 374.987312 -114.097054)
		(end 374.843548 -113.953036)
		(width 0.0889)
		(layer "B.Cu")
		(net "DMI_CPU0_PCH_RX_DN<0>")
	)
	(segment
		(start 369.443 -112.852454)
		(end 369.443 -112.395)
		(width 0.1143)
		(layer "B.Cu")
		(net "DMI_CPU0_PCH_RX_DN<0>")
	)
	(segment
		(start 375.8184 -114.81562)
		(end 375.562114 -114.81562)
		(width 0.0889)
		(layer "B.Cu")
		(net "DMI_CPU0_PCH_RX_DN<0>")
	)
	(segment
		(start 373.9134 -113.4237)
		(end 373.575072 -113.4237)
		(width 0.1143)
		(layer "B.Cu")
		(net "DMI_CPU0_PCH_RX_DN<0>")
	)
	(segment
		(start 375.92 -114.71402)
		(end 375.8184 -114.81562)
		(width 0.0889)
		(layer "B.Cu")
		(net "DMI_CPU0_PCH_RX_DN<0>")
	)
	(segment
		(start 376.2248 -114.81562)
		(end 376.1232 -114.71402)
		(width 0.0889)
		(layer "B.Cu")
		(net "DMI_CPU0_PCH_RX_DN<0>")
	)
	(segment
		(start 376.1232 -114.71402)
		(end 375.92 -114.71402)
		(width 0.0889)
		(layer "B.Cu")
		(net "DMI_CPU0_PCH_RX_DN<0>")
	)
	(segment
		(start 377.555252 -114.713512)
		(end 377.536202 -114.724434)
		(width 0.0889)
		(layer "B.Cu")
		(net "DMI_CPU0_PCH_RX_DN<0>")
	)
	(segment
		(start 374.195594 -113.4491)
		(end 373.960898 -113.4491)
		(width 0.0889)
		(layer "B.Cu")
		(net "DMI_CPU0_PCH_RX_DN<0>")
	)
	(segment
		(start 369.976654 -112.9792)
		(end 369.569746 -112.9792)
		(width 0.1143)
		(layer "B.Cu")
		(net "DMI_CPU0_PCH_RX_DN<0>")
	)
	(segment
		(start 369.569746 -112.9792)
		(end 369.443 -112.852454)
		(width 0.1143)
		(layer "B.Cu")
		(net "DMI_CPU0_PCH_RX_DN<0>")
	)
	(segment
		(start 375.418604 -114.528346)
		(end 375.27484 -114.384328)
		(width 0.0889)
		(layer "B.Cu")
		(net "DMI_CPU0_PCH_RX_DN<0>")
	)
	(segment
		(start 373.935498 -113.4237)
		(end 373.9134 -113.4237)
		(width 0.0889)
		(layer "B.Cu")
		(net "DMI_CPU0_PCH_RX_DN<0>")
	)
	(segment
		(start 375.27484 -114.384328)
		(end 375.130822 -114.384328)
		(width 0.0889)
		(layer "B.Cu")
		(net "DMI_CPU0_PCH_RX_DN<0>")
	)
	(segment
		(start 374.843548 -113.953036)
		(end 374.69953 -113.953036)
		(width 0.0889)
		(layer "B.Cu")
		(net "DMI_CPU0_PCH_RX_DN<0>")
	)
	(segment
		(start 373.575072 -113.4237)
		(end 371.049804 -113.4237)
		(width 0.1143)
		(layer "B.Cu")
		(net "DMI_CPU0_PCH_RX_DN<0>")
	)
	(arc
		(start 377.536202 -114.724434)
		(mid 377.372158 -114.792443)
		(end 377.196096 -114.81562)
		(width 0.0889)
		(layer "B.Cu")
		(net "DMI_CPU0_PCH_RX_DN<0>")
	)
	(arc
		(start 378.160026 -114.741452)
		(mid 378.143189 -114.733334)
		(end 378.126752 -114.724434)
		(width 0.0889)
		(layer "B.Cu")
		(net "DMI_CPU0_PCH_RX_DN<0>")
	)
	(arc
		(start 378.722636 -114.435636)
		(mid 378.517814 -114.729313)
		(end 378.160026 -114.741452)
		(width 0.0889)
		(layer "B.Cu")
		(net "DMI_CPU0_PCH_RX_DN<0>")
	)
	(arc
		(start 378.107448 -114.713512)
		(mid 377.83135 -114.639609)
		(end 377.555252 -114.713512)
		(width 0.0889)
		(layer "B.Cu")
		(net "DMI_CPU0_PCH_RX_DN<0>")
	)
	(segment
		(start 298.665646 -89.584784)
		(end 299.237146 -89.584784)
		(width 0.1143)
		(layer "F.Cu")
		(net "DMI_CPU0_PCH_RX_C_DP<3>")
	)
	(via
		(at 299.237146 -89.584784)
		(size 0.508)
		(drill 0.254)
		(layers "F.Cu" "B.Cu")
		(net "DMI_CPU0_PCH_RX_C_DP<3>")
	)
	(via
		(at 360.81081 -94.89059)
		(size 0.508)
		(drill 0.254)
		(layers "F.Cu" "B.Cu")
		(net "DMI_CPU0_PCH_RX_C_DP<3>")
	)
	(segment
		(start 368.4397 -110.42015)
		(end 368.554 -110.53445)
		(width 0.1143)
		(layer "B.Cu")
		(net "DMI_CPU0_PCH_RX_C_DP<3>")
	)
	(segment
		(start 363.482636 -109.063536)
		(end 364.102142 -109.992414)
		(width 0.1143)
		(layer "B.Cu")
		(net "DMI_CPU0_PCH_RX_C_DP<3>")
	)
	(segment
		(start 363.48797 -101.261164)
		(end 363.106208 -103.169212)
		(width 0.1143)
		(layer "B.Cu")
		(net "DMI_CPU0_PCH_RX_C_DP<3>")
	)
	(segment
		(start 363.661452 -105.945178)
		(end 363.301534 -107.742482)
		(width 0.1143)
		(layer "B.Cu")
		(net "DMI_CPU0_PCH_RX_C_DP<3>")
	)
	(segment
		(start 363.301534 -107.742482)
		(end 363.260132 -107.950508)
		(width 0.1143)
		(layer "B.Cu")
		(net "DMI_CPU0_PCH_RX_C_DP<3>")
	)
	(segment
		(start 363.865668 -99.372928)
		(end 363.48797 -101.261164)
		(width 0.1143)
		(layer "B.Cu")
		(net "DMI_CPU0_PCH_RX_C_DP<3>")
	)
	(segment
		(start 363.106208 -103.169212)
		(end 363.661452 -105.945178)
		(width 0.1143)
		(layer "B.Cu")
		(net "DMI_CPU0_PCH_RX_C_DP<3>")
	)
	(segment
		(start 360.81081 -94.553786)
		(end 360.987086 -94.37751)
		(width 0.1143)
		(layer "B.Cu")
		(net "DMI_CPU0_PCH_RX_C_DP<3>")
	)
	(segment
		(start 368.554 -110.53445)
		(end 368.554 -110.998)
		(width 0.1143)
		(layer "B.Cu")
		(net "DMI_CPU0_PCH_RX_C_DP<3>")
	)
	(segment
		(start 366.554258 -110.42015)
		(end 368.4397 -110.42015)
		(width 0.1143)
		(layer "B.Cu")
		(net "DMI_CPU0_PCH_RX_C_DP<3>")
	)
	(segment
		(start 363.260132 -107.950508)
		(end 363.482636 -109.063536)
		(width 0.1143)
		(layer "B.Cu")
		(net "DMI_CPU0_PCH_RX_C_DP<3>")
	)
	(segment
		(start 364.102142 -109.992414)
		(end 366.554258 -110.42015)
		(width 0.1143)
		(layer "B.Cu")
		(net "DMI_CPU0_PCH_RX_C_DP<3>")
	)
	(segment
		(start 360.81081 -94.89059)
		(end 360.81081 -94.553786)
		(width 0.1143)
		(layer "B.Cu")
		(net "DMI_CPU0_PCH_RX_C_DP<3>")
	)
	(segment
		(start 361.39882 -94.37751)
		(end 363.49559 -97.522538)
		(width 0.1143)
		(layer "B.Cu")
		(net "DMI_CPU0_PCH_RX_C_DP<3>")
	)
	(segment
		(start 363.49559 -97.522538)
		(end 363.865668 -99.372928)
		(width 0.1143)
		(layer "B.Cu")
		(net "DMI_CPU0_PCH_RX_C_DP<3>")
	)
	(segment
		(start 360.987086 -94.37751)
		(end 361.39882 -94.37751)
		(width 0.1143)
		(layer "B.Cu")
		(net "DMI_CPU0_PCH_RX_C_DP<3>")
	)
	(segment
		(start 301.79772 -83.736688)
		(end 301.830486 -83.736688)
		(width 0.0889)
		(layer "In11.Cu")
		(net "DMI_CPU0_PCH_RX_C_DP<3>")
	)
	(segment
		(start 359.851452 -92.548964)
		(end 359.3211 -93.079316)
		(width 0.1143)
		(layer "In11.Cu")
		(net "DMI_CPU0_PCH_RX_C_DP<3>")
	)
	(segment
		(start 303.51476 -82.746088)
		(end 303.5427 -82.746088)
		(width 0.0889)
		(layer "In11.Cu")
		(net "DMI_CPU0_PCH_RX_C_DP<3>")
	)
	(segment
		(start 341.279988 -74.450448)
		(end 342.494362 -74.207878)
		(width 0.1143)
		(layer "In11.Cu")
		(net "DMI_CPU0_PCH_RX_C_DP<3>")
	)
	(segment
		(start 300.94301 -84.231734)
		(end 300.975776 -84.231734)
		(width 0.0889)
		(layer "In11.Cu")
		(net "DMI_CPU0_PCH_RX_C_DP<3>")
	)
	(segment
		(start 338.326984 -75.67549)
		(end 341.279988 -74.450448)
		(width 0.1143)
		(layer "In11.Cu")
		(net "DMI_CPU0_PCH_RX_C_DP<3>")
	)
	(segment
		(start 361.76585 -77.40015)
		(end 361.84205 -77.78115)
		(width 0.1143)
		(layer "In11.Cu")
		(net "DMI_CPU0_PCH_RX_C_DP<3>")
	)
	(segment
		(start 361.834684 -77.818234)
		(end 361.546648 -79.258668)
		(width 0.1143)
		(layer "In11.Cu")
		(net "DMI_CPU0_PCH_RX_C_DP<3>")
	)
	(segment
		(start 359.537 -94.063058)
		(end 359.873042 -94.398846)
		(width 0.1143)
		(layer "In11.Cu")
		(net "DMI_CPU0_PCH_RX_C_DP<3>")
	)
	(segment
		(start 360.853228 -82.72526)
		(end 361.168442 -84.302346)
		(width 0.1143)
		(layer "In11.Cu")
		(net "DMI_CPU0_PCH_RX_C_DP<3>")
	)
	(segment
		(start 360.805476 -75.135232)
		(end 361.530138 -76.222098)
		(width 0.1143)
		(layer "In11.Cu")
		(net "DMI_CPU0_PCH_RX_C_DP<3>")
	)
	(segment
		(start 359.396792 -93.816424)
		(end 359.396538 -93.816424)
		(width 0.1143)
		(layer "In11.Cu")
		(net "DMI_CPU0_PCH_RX_C_DP<3>")
	)
	(segment
		(start 361.32262 -90.73896)
		(end 360.167682 -92.470224)
		(width 0.1143)
		(layer "In11.Cu")
		(net "DMI_CPU0_PCH_RX_C_DP<3>")
	)
	(segment
		(start 299.748956 -88.299036)
		(end 299.74413 -88.2904)
		(width 0.0889)
		(layer "In11.Cu")
		(net "DMI_CPU0_PCH_RX_C_DP<3>")
	)
	(segment
		(start 359.3211 -93.63456)
		(end 359.396792 -93.816424)
		(width 0.1143)
		(layer "In11.Cu")
		(net "DMI_CPU0_PCH_RX_C_DP<3>")
	)
	(segment
		(start 360.623866 -94.398846)
		(end 360.81081 -94.58579)
		(width 0.1143)
		(layer "In11.Cu")
		(net "DMI_CPU0_PCH_RX_C_DP<3>")
	)
	(segment
		(start 342.494362 -74.207878)
		(end 345.457018 -74.800206)
		(width 0.1143)
		(layer "In11.Cu")
		(net "DMI_CPU0_PCH_RX_C_DP<3>")
	)
	(segment
		(start 361.053634 -84.873846)
		(end 361.774486 -88.476582)
		(width 0.1143)
		(layer "In11.Cu")
		(net "DMI_CPU0_PCH_RX_C_DP<3>")
	)
	(segment
		(start 361.167934 -84.3026)
		(end 361.053634 -84.873846)
		(width 0.1143)
		(layer "In11.Cu")
		(net "DMI_CPU0_PCH_RX_C_DP<3>")
	)
	(segment
		(start 305.225196 -82.745834)
		(end 308.0512 -82.745834)
		(width 0.0889)
		(layer "In11.Cu")
		(net "DMI_CPU0_PCH_RX_C_DP<3>")
	)
	(segment
		(start 302.66005 -83.241134)
		(end 302.692816 -83.241134)
		(width 0.0889)
		(layer "In11.Cu")
		(net "DMI_CPU0_PCH_RX_C_DP<3>")
	)
	(segment
		(start 358.641142 -74.702162)
		(end 360.805476 -75.135232)
		(width 0.1143)
		(layer "In11.Cu")
		(net "DMI_CPU0_PCH_RX_C_DP<3>")
	)
	(segment
		(start 359.472484 -93.998542)
		(end 359.537 -94.063058)
		(width 0.1143)
		(layer "In11.Cu")
		(net "DMI_CPU0_PCH_RX_C_DP<3>")
	)
	(segment
		(start 352.307398 -74.96175)
		(end 354.262944 -74.57059)
		(width 0.1143)
		(layer "In11.Cu")
		(net "DMI_CPU0_PCH_RX_C_DP<3>")
	)
	(segment
		(start 299.22597 -85.222334)
		(end 299.258736 -85.222334)
		(width 0.0889)
		(layer "In11.Cu")
		(net "DMI_CPU0_PCH_RX_C_DP<3>")
	)
	(segment
		(start 300.08068 -84.727288)
		(end 300.113446 -84.727288)
		(width 0.0889)
		(layer "In11.Cu")
		(net "DMI_CPU0_PCH_RX_C_DP<3>")
	)
	(segment
		(start 361.168442 -84.302346)
		(end 361.167934 -84.3026)
		(width 0.1143)
		(layer "In11.Cu")
		(net "DMI_CPU0_PCH_RX_C_DP<3>")
	)
	(segment
		(start 361.837478 -77.803248)
		(end 361.83697 -77.806804)
		(width 0.1143)
		(layer "In11.Cu")
		(net "DMI_CPU0_PCH_RX_C_DP<3>")
	)
	(segment
		(start 359.3211 -93.079316)
		(end 359.3211 -93.63456)
		(width 0.1143)
		(layer "In11.Cu")
		(net "DMI_CPU0_PCH_RX_C_DP<3>")
	)
	(segment
		(start 360.81081 -94.58579)
		(end 360.81081 -94.89059)
		(width 0.1143)
		(layer "In11.Cu")
		(net "DMI_CPU0_PCH_RX_C_DP<3>")
	)
	(segment
		(start 348.476824 -74.19594)
		(end 352.307398 -74.96175)
		(width 0.1143)
		(layer "In11.Cu")
		(net "DMI_CPU0_PCH_RX_C_DP<3>")
	)
	(segment
		(start 361.546648 -79.258668)
		(end 360.853228 -82.72526)
		(width 0.1143)
		(layer "In11.Cu")
		(net "DMI_CPU0_PCH_RX_C_DP<3>")
	)
	(segment
		(start 361.774486 -88.476582)
		(end 361.32262 -90.73896)
		(width 0.1143)
		(layer "In11.Cu")
		(net "DMI_CPU0_PCH_RX_C_DP<3>")
	)
	(segment
		(start 335.927954 -79.274924)
		(end 338.326984 -75.67549)
		(width 0.1143)
		(layer "In11.Cu")
		(net "DMI_CPU0_PCH_RX_C_DP<3>")
	)
	(segment
		(start 354.262944 -74.57059)
		(end 356.779576 -75.074272)
		(width 0.1143)
		(layer "In11.Cu")
		(net "DMI_CPU0_PCH_RX_C_DP<3>")
	)
	(segment
		(start 304.37709 -82.250534)
		(end 304.399442 -82.250534)
		(width 0.0889)
		(layer "In11.Cu")
		(net "DMI_CPU0_PCH_RX_C_DP<3>")
	)
	(segment
		(start 298.890436 -86.413086)
		(end 298.896786 -86.402418)
		(width 0.0889)
		(layer "In11.Cu")
		(net "DMI_CPU0_PCH_RX_C_DP<3>")
	)
	(segment
		(start 359.396538 -93.816424)
		(end 359.472484 -93.998542)
		(width 0.1143)
		(layer "In11.Cu")
		(net "DMI_CPU0_PCH_RX_C_DP<3>")
	)
	(segment
		(start 308.0512 -82.745834)
		(end 308.102 -82.796634)
		(width 0.0889)
		(layer "In11.Cu")
		(net "DMI_CPU0_PCH_RX_C_DP<3>")
	)
	(segment
		(start 299.755306 -88.309704)
		(end 299.748956 -88.299036)
		(width 0.0889)
		(layer "In11.Cu")
		(net "DMI_CPU0_PCH_RX_C_DP<3>")
	)
	(segment
		(start 345.457018 -74.800206)
		(end 348.476824 -74.19594)
		(width 0.1143)
		(layer "In11.Cu")
		(net "DMI_CPU0_PCH_RX_C_DP<3>")
	)
	(segment
		(start 321.168268 -84.802472)
		(end 330.40828 -82.954368)
		(width 0.1143)
		(layer "In11.Cu")
		(net "DMI_CPU0_PCH_RX_C_DP<3>")
	)
	(segment
		(start 308.124098 -82.796634)
		(end 311.137808 -82.796634)
		(width 0.1143)
		(layer "In11.Cu")
		(net "DMI_CPU0_PCH_RX_C_DP<3>")
	)
	(segment
		(start 361.83697 -77.806804)
		(end 361.834684 -77.818234)
		(width 0.1143)
		(layer "In11.Cu")
		(net "DMI_CPU0_PCH_RX_C_DP<3>")
	)
	(segment
		(start 360.167682 -92.470224)
		(end 360.155744 -92.488004)
		(width 0.1143)
		(layer "In11.Cu")
		(net "DMI_CPU0_PCH_RX_C_DP<3>")
	)
	(segment
		(start 361.530138 -76.222098)
		(end 361.76585 -77.40015)
		(width 0.1143)
		(layer "In11.Cu")
		(net "DMI_CPU0_PCH_RX_C_DP<3>")
	)
	(segment
		(start 359.873042 -94.398846)
		(end 360.623866 -94.398846)
		(width 0.1143)
		(layer "In11.Cu")
		(net "DMI_CPU0_PCH_RX_C_DP<3>")
	)
	(segment
		(start 361.84205 -77.78115)
		(end 361.839002 -77.795882)
		(width 0.1143)
		(layer "In11.Cu")
		(net "DMI_CPU0_PCH_RX_C_DP<3>")
	)
	(segment
		(start 299.237146 -89.24671)
		(end 299.30217 -89.181686)
		(width 0.0889)
		(layer "In11.Cu")
		(net "DMI_CPU0_PCH_RX_C_DP<3>")
	)
	(segment
		(start 308.102 -82.796634)
		(end 308.124098 -82.796634)
		(width 0.0889)
		(layer "In11.Cu")
		(net "DMI_CPU0_PCH_RX_C_DP<3>")
	)
	(segment
		(start 330.40828 -82.954368)
		(end 335.927954 -79.274924)
		(width 0.1143)
		(layer "In11.Cu")
		(net "DMI_CPU0_PCH_RX_C_DP<3>")
	)
	(segment
		(start 361.839002 -77.795882)
		(end 361.837986 -77.800962)
		(width 0.1143)
		(layer "In11.Cu")
		(net "DMI_CPU0_PCH_RX_C_DP<3>")
	)
	(segment
		(start 299.237146 -89.584784)
		(end 299.237146 -89.24671)
		(width 0.0889)
		(layer "In11.Cu")
		(net "DMI_CPU0_PCH_RX_C_DP<3>")
	)
	(segment
		(start 299.254926 -87.013034)
		(end 299.22216 -87.013034)
		(width 0.0889)
		(layer "In11.Cu")
		(net "DMI_CPU0_PCH_RX_C_DP<3>")
	)
	(segment
		(start 360.155744 -92.488004)
		(end 359.851452 -92.548964)
		(width 0.1143)
		(layer "In11.Cu")
		(net "DMI_CPU0_PCH_RX_C_DP<3>")
	)
	(segment
		(start 311.137808 -82.796634)
		(end 321.168268 -84.802472)
		(width 0.1143)
		(layer "In11.Cu")
		(net "DMI_CPU0_PCH_RX_C_DP<3>")
	)
	(segment
		(start 298.88561 -86.421722)
		(end 298.890436 -86.413086)
		(width 0.0889)
		(layer "In11.Cu")
		(net "DMI_CPU0_PCH_RX_C_DP<3>")
	)
	(segment
		(start 356.779576 -75.074272)
		(end 358.641142 -74.702162)
		(width 0.1143)
		(layer "In11.Cu")
		(net "DMI_CPU0_PCH_RX_C_DP<3>")
	)
	(segment
		(start 361.837986 -77.800962)
		(end 361.837478 -77.803248)
		(width 0.1143)
		(layer "In11.Cu")
		(net "DMI_CPU0_PCH_RX_C_DP<3>")
	)
	(arc
		(start 299.748956 -84.927186)
		(mid 299.889035 -84.78445)
		(end 300.08068 -84.727288)
		(width 0.0889)
		(layer "In11.Cu")
		(net "DMI_CPU0_PCH_RX_C_DP<3>")
	)
	(arc
		(start 298.890436 -85.822536)
		(mid 298.887688 -85.427069)
		(end 299.22597 -85.222334)
		(width 0.0889)
		(layer "In11.Cu")
		(net "DMI_CPU0_PCH_RX_C_DP<3>")
	)
	(arc
		(start 300.113446 -84.727288)
		(mid 300.39887 -84.643821)
		(end 300.607476 -84.431886)
		(width 0.0889)
		(layer "In11.Cu")
		(net "DMI_CPU0_PCH_RX_C_DP<3>")
	)
	(arc
		(start 304.399442 -82.250534)
		(mid 304.593292 -82.306884)
		(end 304.734976 -82.450686)
		(width 0.0889)
		(layer "In11.Cu")
		(net "DMI_CPU0_PCH_RX_C_DP<3>")
	)
	(arc
		(start 299.74413 -88.2904)
		(mid 299.695375 -88.094048)
		(end 299.748956 -87.898986)
		(width 0.0889)
		(layer "In11.Cu")
		(net "DMI_CPU0_PCH_RX_C_DP<3>")
	)
	(arc
		(start 299.22216 -87.013034)
		(mid 298.889242 -86.811043)
		(end 298.88561 -86.421722)
		(width 0.0889)
		(layer "In11.Cu")
		(net "DMI_CPU0_PCH_RX_C_DP<3>")
	)
	(arc
		(start 304.041556 -82.450686)
		(mid 304.183239 -82.306882)
		(end 304.37709 -82.250534)
		(width 0.0889)
		(layer "In11.Cu")
		(net "DMI_CPU0_PCH_RX_C_DP<3>")
	)
	(arc
		(start 300.607476 -84.431886)
		(mid 300.749159 -84.288082)
		(end 300.94301 -84.231734)
		(width 0.0889)
		(layer "In11.Cu")
		(net "DMI_CPU0_PCH_RX_C_DP<3>")
	)
	(arc
		(start 302.324516 -83.441286)
		(mid 302.466199 -83.297482)
		(end 302.66005 -83.241134)
		(width 0.0889)
		(layer "In11.Cu")
		(net "DMI_CPU0_PCH_RX_C_DP<3>")
	)
	(arc
		(start 303.5427 -82.746088)
		(mid 303.830845 -82.663769)
		(end 304.041556 -82.450686)
		(width 0.0889)
		(layer "In11.Cu")
		(net "DMI_CPU0_PCH_RX_C_DP<3>")
	)
	(arc
		(start 299.258736 -85.222334)
		(mid 299.541953 -85.138053)
		(end 299.748956 -84.927186)
		(width 0.0889)
		(layer "In11.Cu")
		(net "DMI_CPU0_PCH_RX_C_DP<3>")
	)
	(arc
		(start 301.830486 -83.736688)
		(mid 302.11591 -83.653221)
		(end 302.324516 -83.441286)
		(width 0.0889)
		(layer "In11.Cu")
		(net "DMI_CPU0_PCH_RX_C_DP<3>")
	)
	(arc
		(start 298.896786 -86.402418)
		(mid 298.969584 -86.111655)
		(end 298.890436 -85.822536)
		(width 0.0889)
		(layer "In11.Cu")
		(net "DMI_CPU0_PCH_RX_C_DP<3>")
	)
	(arc
		(start 300.975776 -84.231734)
		(mid 301.258993 -84.147453)
		(end 301.465996 -83.936586)
		(width 0.0889)
		(layer "In11.Cu")
		(net "DMI_CPU0_PCH_RX_C_DP<3>")
	)
	(arc
		(start 301.465996 -83.936586)
		(mid 301.606075 -83.79385)
		(end 301.79772 -83.736688)
		(width 0.0889)
		(layer "In11.Cu")
		(net "DMI_CPU0_PCH_RX_C_DP<3>")
	)
	(arc
		(start 302.692816 -83.241134)
		(mid 302.976033 -83.156853)
		(end 303.183036 -82.945986)
		(width 0.0889)
		(layer "In11.Cu")
		(net "DMI_CPU0_PCH_RX_C_DP<3>")
	)
	(arc
		(start 299.30217 -89.181686)
		(mid 299.761647 -88.866737)
		(end 299.755306 -88.309704)
		(width 0.0889)
		(layer "In11.Cu")
		(net "DMI_CPU0_PCH_RX_C_DP<3>")
	)
	(arc
		(start 299.748956 -87.898986)
		(mid 299.753285 -87.315814)
		(end 299.254926 -87.013034)
		(width 0.0889)
		(layer "In11.Cu")
		(net "DMI_CPU0_PCH_RX_C_DP<3>")
	)
	(arc
		(start 304.734976 -82.450686)
		(mid 304.94198 -82.66155)
		(end 305.225196 -82.745834)
		(width 0.0889)
		(layer "In11.Cu")
		(net "DMI_CPU0_PCH_RX_C_DP<3>")
	)
	(arc
		(start 303.183036 -82.945986)
		(mid 303.323115 -82.80325)
		(end 303.51476 -82.746088)
		(width 0.0889)
		(layer "In11.Cu")
		(net "DMI_CPU0_PCH_RX_C_DP<3>")
	)
	(segment
		(start 298.665646 -87.603584)
		(end 299.237146 -87.603584)
		(width 0.1143)
		(layer "F.Cu")
		(net "DMI_CPU0_PCH_RX_C_DP<2>")
	)
	(via
		(at 299.237146 -87.603584)
		(size 0.508)
		(drill 0.254)
		(layers "F.Cu" "B.Cu")
		(net "DMI_CPU0_PCH_RX_C_DP<2>")
	)
	(via
		(at 360.69905 -96.10725)
		(size 0.508)
		(drill 0.254)
		(layers "F.Cu" "B.Cu")
		(net "DMI_CPU0_PCH_RX_C_DP<2>")
	)
	(segment
		(start 362.464858 -111.111284)
		(end 362.596176 -111.388398)
		(width 0.1143)
		(layer "B.Cu")
		(net "DMI_CPU0_PCH_RX_C_DP<2>")
	)
	(segment
		(start 362.30941 -102.914704)
		(end 362.851954 -105.62717)
		(width 0.1143)
		(layer "B.Cu")
		(net "DMI_CPU0_PCH_RX_C_DP<2>")
	)
	(segment
		(start 362.596176 -111.388398)
		(end 362.809028 -111.60125)
		(width 0.1143)
		(layer "B.Cu")
		(net "DMI_CPU0_PCH_RX_C_DP<2>")
	)
	(segment
		(start 364.4773 -111.60125)
		(end 364.617 -111.46155)
		(width 0.1143)
		(layer "B.Cu")
		(net "DMI_CPU0_PCH_RX_C_DP<2>")
	)
	(segment
		(start 361.992926 -97.123504)
		(end 361.992926 -97.123758)
		(width 0.1143)
		(layer "B.Cu")
		(net "DMI_CPU0_PCH_RX_C_DP<2>")
	)
	(segment
		(start 361.992926 -97.123758)
		(end 363.041438 -99.255072)
		(width 0.1143)
		(layer "B.Cu")
		(net "DMI_CPU0_PCH_RX_C_DP<2>")
	)
	(segment
		(start 362.640118 -101.261164)
		(end 362.30941 -102.914704)
		(width 0.1143)
		(layer "B.Cu")
		(net "DMI_CPU0_PCH_RX_C_DP<2>")
	)
	(segment
		(start 360.81335 -96.6216)
		(end 361.255564 -96.6216)
		(width 0.1143)
		(layer "B.Cu")
		(net "DMI_CPU0_PCH_RX_C_DP<2>")
	)
	(segment
		(start 361.255564 -96.6216)
		(end 361.962446 -97.061782)
		(width 0.1143)
		(layer "B.Cu")
		(net "DMI_CPU0_PCH_RX_C_DP<2>")
	)
	(segment
		(start 360.69905 -96.10725)
		(end 360.69905 -96.5073)
		(width 0.1143)
		(layer "B.Cu")
		(net "DMI_CPU0_PCH_RX_C_DP<2>")
	)
	(segment
		(start 361.962446 -97.061782)
		(end 361.992926 -97.123504)
		(width 0.1143)
		(layer "B.Cu")
		(net "DMI_CPU0_PCH_RX_C_DP<2>")
	)
	(segment
		(start 360.69905 -96.5073)
		(end 360.81335 -96.6216)
		(width 0.1143)
		(layer "B.Cu")
		(net "DMI_CPU0_PCH_RX_C_DP<2>")
	)
	(segment
		(start 362.461556 -111.109252)
		(end 362.464858 -111.111284)
		(width 0.1143)
		(layer "B.Cu")
		(net "DMI_CPU0_PCH_RX_C_DP<2>")
	)
	(segment
		(start 364.617 -111.46155)
		(end 364.617 -110.998)
		(width 0.1143)
		(layer "B.Cu")
		(net "DMI_CPU0_PCH_RX_C_DP<2>")
	)
	(segment
		(start 363.041438 -99.255072)
		(end 362.640118 -101.261164)
		(width 0.1143)
		(layer "B.Cu")
		(net "DMI_CPU0_PCH_RX_C_DP<2>")
	)
	(segment
		(start 362.108496 -109.34446)
		(end 362.461556 -111.109252)
		(width 0.1143)
		(layer "B.Cu")
		(net "DMI_CPU0_PCH_RX_C_DP<2>")
	)
	(segment
		(start 362.809028 -111.60125)
		(end 364.4773 -111.60125)
		(width 0.1143)
		(layer "B.Cu")
		(net "DMI_CPU0_PCH_RX_C_DP<2>")
	)
	(segment
		(start 362.851954 -105.62717)
		(end 362.108496 -109.34446)
		(width 0.1143)
		(layer "B.Cu")
		(net "DMI_CPU0_PCH_RX_C_DP<2>")
	)
	(segment
		(start 331.769212 -81.18983)
		(end 332.054454 -80.999584)
		(width 0.1143)
		(layer "In11.Cu")
		(net "DMI_CPU0_PCH_RX_C_DP<2>")
	)
	(segment
		(start 337.717892 -75.400154)
		(end 337.727544 -75.379072)
		(width 0.1143)
		(layer "In11.Cu")
		(net "DMI_CPU0_PCH_RX_C_DP<2>")
	)
	(segment
		(start 338.787486 -73.555098)
		(end 339.707474 -73.370694)
		(width 0.1143)
		(layer "In11.Cu")
		(net "DMI_CPU0_PCH_RX_C_DP<2>")
	)
	(segment
		(start 332.614778 -80.626204)
		(end 332.90002 -80.435958)
		(width 0.1143)
		(layer "In11.Cu")
		(net "DMI_CPU0_PCH_RX_C_DP<2>")
	)
	(segment
		(start 334.590644 -79.30896)
		(end 334.636618 -79.080106)
		(width 0.1143)
		(layer "In11.Cu")
		(net "DMI_CPU0_PCH_RX_C_DP<2>")
	)
	(segment
		(start 299.22597 -84.231734)
		(end 299.258736 -84.231734)
		(width 0.0889)
		(layer "In11.Cu")
		(net "DMI_CPU0_PCH_RX_C_DP<2>")
	)
	(segment
		(start 332.90002 -80.435958)
		(end 332.945994 -80.207104)
		(width 0.1143)
		(layer "In11.Cu")
		(net "DMI_CPU0_PCH_RX_C_DP<2>")
	)
	(segment
		(start 362.07065 -75.686158)
		(end 362.3056 -76.8604)
		(width 0.1143)
		(layer "In11.Cu")
		(net "DMI_CPU0_PCH_RX_C_DP<2>")
	)
	(segment
		(start 335.150714 -78.935834)
		(end 335.435956 -78.745588)
		(width 0.1143)
		(layer "In11.Cu")
		(net "DMI_CPU0_PCH_RX_C_DP<2>")
	)
	(segment
		(start 307.587396 -81.858104)
		(end 307.854096 -81.858104)
		(width 0.0889)
		(layer "In11.Cu")
		(net "DMI_CPU0_PCH_RX_C_DP<2>")
	)
	(segment
		(start 298.400216 -87.508588)
		(end 298.36745 -87.508588)
		(width 0.0889)
		(layer "In11.Cu")
		(net "DMI_CPU0_PCH_RX_C_DP<2>")
	)
	(segment
		(start 361.729528 -92.208604)
		(end 362.350558 -95.312484)
		(width 0.1143)
		(layer "In11.Cu")
		(net "DMI_CPU0_PCH_RX_C_DP<2>")
	)
	(segment
		(start 298.038266 -85.337904)
		(end 298.031916 -85.327236)
		(width 0.0889)
		(layer "In11.Cu")
		(net "DMI_CPU0_PCH_RX_C_DP<2>")
	)
	(segment
		(start 334.076548 -79.453232)
		(end 334.305402 -79.499206)
		(width 0.1143)
		(layer "In11.Cu")
		(net "DMI_CPU0_PCH_RX_C_DP<2>")
	)
	(segment
		(start 332.100428 -80.77073)
		(end 332.38567 -80.580484)
		(width 0.1143)
		(layer "In11.Cu")
		(net "DMI_CPU0_PCH_RX_C_DP<2>")
	)
	(segment
		(start 352.32848 -74.20864)
		(end 354.21443 -73.83145)
		(width 0.1143)
		(layer "In11.Cu")
		(net "DMI_CPU0_PCH_RX_C_DP<2>")
	)
	(segment
		(start 306.876196 -81.858104)
		(end 307.142896 -81.858104)
		(width 0.0889)
		(layer "In11.Cu")
		(net "DMI_CPU0_PCH_RX_C_DP<2>")
	)
	(segment
		(start 309.632096 -81.947004)
		(end 309.720996 -81.858104)
		(width 0.0889)
		(layer "In11.Cu")
		(net "DMI_CPU0_PCH_RX_C_DP<2>")
	)
	(segment
		(start 345.397328 -74.047604)
		(end 348.460314 -73.434956)
		(width 0.1143)
		(layer "In11.Cu")
		(net "DMI_CPU0_PCH_RX_C_DP<2>")
	)
	(segment
		(start 309.276496 -81.858104)
		(end 309.365396 -81.947004)
		(width 0.0889)
		(layer "In11.Cu")
		(net "DMI_CPU0_PCH_RX_C_DP<2>")
	)
	(segment
		(start 332.38567 -80.58023)
		(end 332.614778 -80.626204)
		(width 0.1143)
		(layer "In11.Cu")
		(net "DMI_CPU0_PCH_RX_C_DP<2>")
	)
	(segment
		(start 308.920896 -81.947004)
		(end 309.009796 -81.858104)
		(width 0.0889)
		(layer "In11.Cu")
		(net "DMI_CPU0_PCH_RX_C_DP<2>")
	)
	(segment
		(start 361.693206 -75.120246)
		(end 362.07065 -75.686158)
		(width 0.1143)
		(layer "In11.Cu")
		(net "DMI_CPU0_PCH_RX_C_DP<2>")
	)
	(segment
		(start 362.350558 -95.312484)
		(end 361.663742 -96.3422)
		(width 0.1143)
		(layer "In11.Cu")
		(net "DMI_CPU0_PCH_RX_C_DP<2>")
	)
	(segment
		(start 309.720996 -81.858104)
		(end 310.238902 -81.858104)
		(width 0.0889)
		(layer "In11.Cu")
		(net "DMI_CPU0_PCH_RX_C_DP<2>")
	)
	(segment
		(start 334.636618 -79.080106)
		(end 334.92186 -78.88986)
		(width 0.1143)
		(layer "In11.Cu")
		(net "DMI_CPU0_PCH_RX_C_DP<2>")
	)
	(segment
		(start 311.099454 -81.908904)
		(end 321.403726 -83.969098)
		(width 0.1143)
		(layer "In11.Cu")
		(net "DMI_CPU0_PCH_RX_C_DP<2>")
	)
	(segment
		(start 362.50118 -77.837792)
		(end 361.536742 -82.660236)
		(width 0.1143)
		(layer "In11.Cu")
		(net "DMI_CPU0_PCH_RX_C_DP<2>")
	)
	(segment
		(start 307.942996 -81.947004)
		(end 308.209696 -81.947004)
		(width 0.0889)
		(layer "In11.Cu")
		(net "DMI_CPU0_PCH_RX_C_DP<2>")
	)
	(segment
		(start 335.767172 -78.326488)
		(end 337.717892 -75.400154)
		(width 0.1143)
		(layer "In11.Cu")
		(net "DMI_CPU0_PCH_RX_C_DP<2>")
	)
	(segment
		(start 298.031916 -86.317836)
		(end 298.02709 -86.3092)
		(width 0.0889)
		(layer "In11.Cu")
		(net "DMI_CPU0_PCH_RX_C_DP<2>")
	)
	(segment
		(start 362.158788 -90.062304)
		(end 361.729528 -92.208604)
		(width 0.1143)
		(layer "In11.Cu")
		(net "DMI_CPU0_PCH_RX_C_DP<2>")
	)
	(segment
		(start 298.94403 -87.772748)
		(end 298.854622 -87.748618)
		(width 0.0889)
		(layer "In11.Cu")
		(net "DMI_CPU0_PCH_RX_C_DP<2>")
	)
	(segment
		(start 305.182778 -81.245964)
		(end 305.449478 -81.245964)
		(width 0.0889)
		(layer "In11.Cu")
		(net "DMI_CPU0_PCH_RX_C_DP<2>")
	)
	(segment
		(start 305.538378 -81.334864)
		(end 305.805078 -81.334864)
		(width 0.0889)
		(layer "In11.Cu")
		(net "DMI_CPU0_PCH_RX_C_DP<2>")
	)
	(segment
		(start 305.093878 -81.334864)
		(end 305.182778 -81.245964)
		(width 0.0889)
		(layer "In11.Cu")
		(net "DMI_CPU0_PCH_RX_C_DP<2>")
	)
	(segment
		(start 308.298596 -81.858104)
		(end 308.565296 -81.858104)
		(width 0.0889)
		(layer "In11.Cu")
		(net "DMI_CPU0_PCH_RX_C_DP<2>")
	)
	(segment
		(start 321.403726 -83.969098)
		(end 329.830176 -82.283554)
		(width 0.1143)
		(layer "In11.Cu")
		(net "DMI_CPU0_PCH_RX_C_DP<2>")
	)
	(segment
		(start 333.231236 -80.016858)
		(end 333.46009 -80.062578)
		(width 0.1143)
		(layer "In11.Cu")
		(net "DMI_CPU0_PCH_RX_C_DP<2>")
	)
	(segment
		(start 332.38567 -80.580484)
		(end 332.38567 -80.58023)
		(width 0.1143)
		(layer "In11.Cu")
		(net "DMI_CPU0_PCH_RX_C_DP<2>")
	)
	(segment
		(start 356.940866 -74.377042)
		(end 358.686354 -74.028046)
		(width 0.1143)
		(layer "In11.Cu")
		(net "DMI_CPU0_PCH_RX_C_DP<2>")
	)
	(segment
		(start 308.565296 -81.858104)
		(end 308.654196 -81.947004)
		(width 0.0889)
		(layer "In11.Cu")
		(net "DMI_CPU0_PCH_RX_C_DP<2>")
	)
	(segment
		(start 362.588048 -87.916258)
		(end 362.158788 -90.062304)
		(width 0.1143)
		(layer "In11.Cu")
		(net "DMI_CPU0_PCH_RX_C_DP<2>")
	)
	(segment
		(start 307.498496 -81.947004)
		(end 307.587396 -81.858104)
		(width 0.0889)
		(layer "In11.Cu")
		(net "DMI_CPU0_PCH_RX_C_DP<2>")
	)
	(segment
		(start 309.009796 -81.858104)
		(end 309.276496 -81.858104)
		(width 0.0889)
		(layer "In11.Cu")
		(net "DMI_CPU0_PCH_RX_C_DP<2>")
	)
	(segment
		(start 360.83875 -96.6724)
		(end 360.69905 -96.5327)
		(width 0.1143)
		(layer "In11.Cu")
		(net "DMI_CPU0_PCH_RX_C_DP<2>")
	)
	(segment
		(start 310.289702 -81.908904)
		(end 311.099454 -81.908904)
		(width 0.1143)
		(layer "In11.Cu")
		(net "DMI_CPU0_PCH_RX_C_DP<2>")
	)
	(segment
		(start 362.3056 -76.8604)
		(end 362.50118 -77.837792)
		(width 0.1143)
		(layer "In11.Cu")
		(net "DMI_CPU0_PCH_RX_C_DP<2>")
	)
	(segment
		(start 361.333542 -96.6724)
		(end 360.83875 -96.6724)
		(width 0.1143)
		(layer "In11.Cu")
		(net "DMI_CPU0_PCH_RX_C_DP<2>")
	)
	(segment
		(start 300.08068 -83.736688)
		(end 300.113446 -83.736688)
		(width 0.0889)
		(layer "In11.Cu")
		(net "DMI_CPU0_PCH_RX_C_DP<2>")
	)
	(segment
		(start 362.094018 -85.4456)
		(end 362.093764 -85.446108)
		(width 0.1143)
		(layer "In11.Cu")
		(net "DMI_CPU0_PCH_RX_C_DP<2>")
	)
	(segment
		(start 331.540104 -81.143856)
		(end 331.769212 -81.18983)
		(width 0.1143)
		(layer "In11.Cu")
		(net "DMI_CPU0_PCH_RX_C_DP<2>")
	)
	(segment
		(start 300.94301 -83.241134)
		(end 300.975776 -83.241134)
		(width 0.0889)
		(layer "In11.Cu")
		(net "DMI_CPU0_PCH_RX_C_DP<2>")
	)
	(segment
		(start 332.054454 -80.999584)
		(end 332.100428 -80.77073)
		(width 0.1143)
		(layer "In11.Cu")
		(net "DMI_CPU0_PCH_RX_C_DP<2>")
	)
	(segment
		(start 340.76767 -73.582784)
		(end 341.919814 -73.352152)
		(width 0.1143)
		(layer "In11.Cu")
		(net "DMI_CPU0_PCH_RX_C_DP<2>")
	)
	(segment
		(start 358.686354 -74.028046)
		(end 361.316016 -74.554334)
		(width 0.1143)
		(layer "In11.Cu")
		(net "DMI_CPU0_PCH_RX_C_DP<2>")
	)
	(segment
		(start 354.21443 -73.83145)
		(end 356.940866 -74.377042)
		(width 0.1143)
		(layer "In11.Cu")
		(net "DMI_CPU0_PCH_RX_C_DP<2>")
	)
	(segment
		(start 304.827178 -81.334864)
		(end 305.093878 -81.334864)
		(width 0.0889)
		(layer "In11.Cu")
		(net "DMI_CPU0_PCH_RX_C_DP<2>")
	)
	(segment
		(start 298.36364 -84.727288)
		(end 298.396406 -84.727288)
		(width 0.0889)
		(layer "In11.Cu")
		(net "DMI_CPU0_PCH_RX_C_DP<2>")
	)
	(segment
		(start 298.038266 -86.328504)
		(end 298.031916 -86.317836)
		(width 0.0889)
		(layer "In11.Cu")
		(net "DMI_CPU0_PCH_RX_C_DP<2>")
	)
	(segment
		(start 333.745332 -79.872332)
		(end 333.791306 -79.643478)
		(width 0.1143)
		(layer "In11.Cu")
		(net "DMI_CPU0_PCH_RX_C_DP<2>")
	)
	(segment
		(start 360.69905 -96.5327)
		(end 360.69905 -96.10725)
		(width 0.1143)
		(layer "In11.Cu")
		(net "DMI_CPU0_PCH_RX_C_DP<2>")
	)
	(segment
		(start 335.435956 -78.745588)
		(end 335.48193 -78.516734)
		(width 0.1143)
		(layer "In11.Cu")
		(net "DMI_CPU0_PCH_RX_C_DP<2>")
	)
	(segment
		(start 307.231796 -81.947004)
		(end 307.498496 -81.947004)
		(width 0.0889)
		(layer "In11.Cu")
		(net "DMI_CPU0_PCH_RX_C_DP<2>")
	)
	(segment
		(start 308.209696 -81.947004)
		(end 308.298596 -81.858104)
		(width 0.0889)
		(layer "In11.Cu")
		(net "DMI_CPU0_PCH_RX_C_DP<2>")
	)
	(segment
		(start 333.46009 -80.062578)
		(end 333.745332 -79.872332)
		(width 0.1143)
		(layer "In11.Cu")
		(net "DMI_CPU0_PCH_RX_C_DP<2>")
	)
	(segment
		(start 302.66005 -82.250534)
		(end 302.692816 -82.250534)
		(width 0.0889)
		(layer "In11.Cu")
		(net "DMI_CPU0_PCH_RX_C_DP<2>")
	)
	(segment
		(start 306.264056 -81.245964)
		(end 306.876196 -81.858104)
		(width 0.0889)
		(layer "In11.Cu")
		(net "DMI_CPU0_PCH_RX_C_DP<2>")
	)
	(segment
		(start 304.738278 -81.245964)
		(end 304.827178 -81.334864)
		(width 0.0889)
		(layer "In11.Cu")
		(net "DMI_CPU0_PCH_RX_C_DP<2>")
	)
	(segment
		(start 304.04181 -81.460086)
		(end 304.164492 -81.245964)
		(width 0.0889)
		(layer "In11.Cu")
		(net "DMI_CPU0_PCH_RX_C_DP<2>")
	)
	(segment
		(start 333.791306 -79.643478)
		(end 334.076548 -79.453232)
		(width 0.1143)
		(layer "In11.Cu")
		(net "DMI_CPU0_PCH_RX_C_DP<2>")
	)
	(segment
		(start 341.919814 -73.352152)
		(end 345.397328 -74.047604)
		(width 0.1143)
		(layer "In11.Cu")
		(net "DMI_CPU0_PCH_RX_C_DP<2>")
	)
	(segment
		(start 337.727544 -75.379072)
		(end 338.460588 -73.772776)
		(width 0.1143)
		(layer "In11.Cu")
		(net "DMI_CPU0_PCH_RX_C_DP<2>")
	)
	(segment
		(start 307.142896 -81.858104)
		(end 307.231796 -81.947004)
		(width 0.0889)
		(layer "In11.Cu")
		(net "DMI_CPU0_PCH_RX_C_DP<2>")
	)
	(segment
		(start 362.093764 -85.446108)
		(end 362.588048 -87.916258)
		(width 0.1143)
		(layer "In11.Cu")
		(net "DMI_CPU0_PCH_RX_C_DP<2>")
	)
	(segment
		(start 298.031916 -85.327236)
		(end 298.02709 -85.3186)
		(width 0.0889)
		(layer "In11.Cu")
		(net "DMI_CPU0_PCH_RX_C_DP<2>")
	)
	(segment
		(start 339.707474 -73.370694)
		(end 340.76767 -73.582784)
		(width 0.1143)
		(layer "In11.Cu")
		(net "DMI_CPU0_PCH_RX_C_DP<2>")
	)
	(segment
		(start 309.365396 -81.947004)
		(end 309.632096 -81.947004)
		(width 0.0889)
		(layer "In11.Cu")
		(net "DMI_CPU0_PCH_RX_C_DP<2>")
	)
	(segment
		(start 307.854096 -81.858104)
		(end 307.942996 -81.947004)
		(width 0.0889)
		(layer "In11.Cu")
		(net "DMI_CPU0_PCH_RX_C_DP<2>")
	)
	(segment
		(start 303.511712 -81.755488)
		(end 303.5173 -81.755234)
		(width 0.0889)
		(layer "In11.Cu")
		(net "DMI_CPU0_PCH_RX_C_DP<2>")
	)
	(segment
		(start 332.945994 -80.207104)
		(end 333.231236 -80.016858)
		(width 0.1143)
		(layer "In11.Cu")
		(net "DMI_CPU0_PCH_RX_C_DP<2>")
	)
	(segment
		(start 334.305402 -79.499206)
		(end 334.590644 -79.30896)
		(width 0.1143)
		(layer "In11.Cu")
		(net "DMI_CPU0_PCH_RX_C_DP<2>")
	)
	(segment
		(start 299.237146 -87.603584)
		(end 298.94403 -87.772748)
		(width 0.0889)
		(layer "In11.Cu")
		(net "DMI_CPU0_PCH_RX_C_DP<2>")
	)
	(segment
		(start 361.693206 -75.119992)
		(end 361.693206 -75.120246)
		(width 0.1143)
		(layer "In11.Cu")
		(net "DMI_CPU0_PCH_RX_C_DP<2>")
	)
	(segment
		(start 335.48193 -78.516734)
		(end 335.767172 -78.326488)
		(width 0.1143)
		(layer "In11.Cu")
		(net "DMI_CPU0_PCH_RX_C_DP<2>")
	)
	(segment
		(start 334.92186 -78.88986)
		(end 335.150714 -78.935834)
		(width 0.1143)
		(layer "In11.Cu")
		(net "DMI_CPU0_PCH_RX_C_DP<2>")
	)
	(segment
		(start 305.893978 -81.245964)
		(end 306.264056 -81.245964)
		(width 0.0889)
		(layer "In11.Cu")
		(net "DMI_CPU0_PCH_RX_C_DP<2>")
	)
	(segment
		(start 305.805078 -81.334864)
		(end 305.893978 -81.245964)
		(width 0.0889)
		(layer "In11.Cu")
		(net "DMI_CPU0_PCH_RX_C_DP<2>")
	)
	(segment
		(start 348.460314 -73.434956)
		(end 352.32848 -74.20864)
		(width 0.1143)
		(layer "In11.Cu")
		(net "DMI_CPU0_PCH_RX_C_DP<2>")
	)
	(segment
		(start 304.164492 -81.245964)
		(end 304.738278 -81.245964)
		(width 0.0889)
		(layer "In11.Cu")
		(net "DMI_CPU0_PCH_RX_C_DP<2>")
	)
	(segment
		(start 361.316016 -74.554334)
		(end 361.693206 -75.119992)
		(width 0.1143)
		(layer "In11.Cu")
		(net "DMI_CPU0_PCH_RX_C_DP<2>")
	)
	(segment
		(start 361.663742 -96.3422)
		(end 361.333542 -96.6724)
		(width 0.1143)
		(layer "In11.Cu")
		(net "DMI_CPU0_PCH_RX_C_DP<2>")
	)
	(segment
		(start 329.830176 -82.283554)
		(end 331.540104 -81.143856)
		(width 0.1143)
		(layer "In11.Cu")
		(net "DMI_CPU0_PCH_RX_C_DP<2>")
	)
	(segment
		(start 301.79772 -82.746088)
		(end 301.82566 -82.746088)
		(width 0.0889)
		(layer "In11.Cu")
		(net "DMI_CPU0_PCH_RX_C_DP<2>")
	)
	(segment
		(start 303.5173 -81.755234)
		(end 303.551844 -81.755234)
		(width 0.0889)
		(layer "In11.Cu")
		(net "DMI_CPU0_PCH_RX_C_DP<2>")
	)
	(segment
		(start 308.654196 -81.947004)
		(end 308.920896 -81.947004)
		(width 0.0889)
		(layer "In11.Cu")
		(net "DMI_CPU0_PCH_RX_C_DP<2>")
	)
	(segment
		(start 338.460588 -73.772776)
		(end 338.787486 -73.555098)
		(width 0.1143)
		(layer "In11.Cu")
		(net "DMI_CPU0_PCH_RX_C_DP<2>")
	)
	(segment
		(start 310.238902 -81.858104)
		(end 310.289702 -81.908904)
		(width 0.0889)
		(layer "In11.Cu")
		(net "DMI_CPU0_PCH_RX_C_DP<2>")
	)
	(segment
		(start 305.449478 -81.245964)
		(end 305.538378 -81.334864)
		(width 0.0889)
		(layer "In11.Cu")
		(net "DMI_CPU0_PCH_RX_C_DP<2>")
	)
	(segment
		(start 361.536742 -82.660236)
		(end 362.094018 -85.4456)
		(width 0.1143)
		(layer "In11.Cu")
		(net "DMI_CPU0_PCH_RX_C_DP<2>")
	)
	(arc
		(start 301.82566 -82.746088)
		(mid 302.113805 -82.663769)
		(end 302.324516 -82.450686)
		(width 0.0889)
		(layer "In11.Cu")
		(net "DMI_CPU0_PCH_RX_C_DP<2>")
	)
	(arc
		(start 302.692816 -82.250534)
		(mid 302.976033 -82.166253)
		(end 303.183036 -81.955386)
		(width 0.0889)
		(layer "In11.Cu")
		(net "DMI_CPU0_PCH_RX_C_DP<2>")
	)
	(arc
		(start 298.027852 -87.30107)
		(mid 297.978386 -87.104188)
		(end 298.031916 -86.908386)
		(width 0.0889)
		(layer "In11.Cu")
		(net "DMI_CPU0_PCH_RX_C_DP<2>")
	)
	(arc
		(start 298.02709 -85.3186)
		(mid 298.030837 -84.929344)
		(end 298.36364 -84.727288)
		(width 0.0889)
		(layer "In11.Cu")
		(net "DMI_CPU0_PCH_RX_C_DP<2>")
	)
	(arc
		(start 302.324516 -82.450686)
		(mid 302.466199 -82.306882)
		(end 302.66005 -82.250534)
		(width 0.0889)
		(layer "In11.Cu")
		(net "DMI_CPU0_PCH_RX_C_DP<2>")
	)
	(arc
		(start 298.02709 -86.3092)
		(mid 297.978335 -86.112848)
		(end 298.031916 -85.917786)
		(width 0.0889)
		(layer "In11.Cu")
		(net "DMI_CPU0_PCH_RX_C_DP<2>")
	)
	(arc
		(start 300.607476 -83.441286)
		(mid 300.749159 -83.297482)
		(end 300.94301 -83.241134)
		(width 0.0889)
		(layer "In11.Cu")
		(net "DMI_CPU0_PCH_RX_C_DP<2>")
	)
	(arc
		(start 300.975776 -83.241134)
		(mid 301.258993 -83.156853)
		(end 301.465996 -82.945986)
		(width 0.0889)
		(layer "In11.Cu")
		(net "DMI_CPU0_PCH_RX_C_DP<2>")
	)
	(arc
		(start 299.258736 -84.231734)
		(mid 299.541953 -84.147453)
		(end 299.748956 -83.936586)
		(width 0.0889)
		(layer "In11.Cu")
		(net "DMI_CPU0_PCH_RX_C_DP<2>")
	)
	(arc
		(start 299.748956 -83.936586)
		(mid 299.889035 -83.79385)
		(end 300.08068 -83.736688)
		(width 0.0889)
		(layer "In11.Cu")
		(net "DMI_CPU0_PCH_RX_C_DP<2>")
	)
	(arc
		(start 298.890436 -84.431886)
		(mid 299.032119 -84.288082)
		(end 299.22597 -84.231734)
		(width 0.0889)
		(layer "In11.Cu")
		(net "DMI_CPU0_PCH_RX_C_DP<2>")
	)
	(arc
		(start 298.36745 -87.508588)
		(mid 298.169999 -87.450064)
		(end 298.027852 -87.30107)
		(width 0.0889)
		(layer "In11.Cu")
		(net "DMI_CPU0_PCH_RX_C_DP<2>")
	)
	(arc
		(start 300.113446 -83.736688)
		(mid 300.39887 -83.653221)
		(end 300.607476 -83.441286)
		(width 0.0889)
		(layer "In11.Cu")
		(net "DMI_CPU0_PCH_RX_C_DP<2>")
	)
	(arc
		(start 298.031916 -86.908386)
		(mid 298.111138 -86.619268)
		(end 298.038266 -86.328504)
		(width 0.0889)
		(layer "In11.Cu")
		(net "DMI_CPU0_PCH_RX_C_DP<2>")
	)
	(arc
		(start 298.396406 -84.727288)
		(mid 298.68183 -84.643821)
		(end 298.890436 -84.431886)
		(width 0.0889)
		(layer "In11.Cu")
		(net "DMI_CPU0_PCH_RX_C_DP<2>")
	)
	(arc
		(start 303.183036 -81.955386)
		(mid 303.32178 -81.813353)
		(end 303.511712 -81.755488)
		(width 0.0889)
		(layer "In11.Cu")
		(net "DMI_CPU0_PCH_RX_C_DP<2>")
	)
	(arc
		(start 298.854622 -87.748618)
		(mid 298.654877 -87.576624)
		(end 298.400216 -87.508588)
		(width 0.0889)
		(layer "In11.Cu")
		(net "DMI_CPU0_PCH_RX_C_DP<2>")
	)
	(arc
		(start 303.551844 -81.755234)
		(mid 303.834888 -81.670873)
		(end 304.04181 -81.460086)
		(width 0.0889)
		(layer "In11.Cu")
		(net "DMI_CPU0_PCH_RX_C_DP<2>")
	)
	(arc
		(start 298.031916 -85.917786)
		(mid 298.111138 -85.628668)
		(end 298.038266 -85.337904)
		(width 0.0889)
		(layer "In11.Cu")
		(net "DMI_CPU0_PCH_RX_C_DP<2>")
	)
	(arc
		(start 301.465996 -82.945986)
		(mid 301.606075 -82.80325)
		(end 301.79772 -82.746088)
		(width 0.0889)
		(layer "In11.Cu")
		(net "DMI_CPU0_PCH_RX_C_DP<2>")
	)
	(segment
		(start 299.524166 -87.108538)
		(end 300.095666 -87.108538)
		(width 0.1143)
		(layer "F.Cu")
		(net "DMI_CPU0_PCH_RX_C_DP<1>")
	)
	(via
		(at 300.095666 -87.108538)
		(size 0.508)
		(drill 0.254)
		(layers "F.Cu" "B.Cu")
		(net "DMI_CPU0_PCH_RX_C_DP<1>")
	)
	(via
		(at 359.08869 -100.660708)
		(size 0.508)
		(drill 0.254)
		(layers "F.Cu" "B.Cu")
		(net "DMI_CPU0_PCH_RX_C_DP<1>")
	)
	(segment
		(start 360.459274 -105.663238)
		(end 359.84815 -102.607618)
		(width 0.1143)
		(layer "B.Cu")
		(net "DMI_CPU0_PCH_RX_C_DP<1>")
	)
	(segment
		(start 359.08869 -100.33381)
		(end 359.08869 -100.660708)
		(width 0.1143)
		(layer "B.Cu")
		(net "DMI_CPU0_PCH_RX_C_DP<1>")
	)
	(segment
		(start 364.617 -115.189)
		(end 364.617 -114.72545)
		(width 0.1143)
		(layer "B.Cu")
		(net "DMI_CPU0_PCH_RX_C_DP<1>")
	)
	(segment
		(start 364.617 -114.72545)
		(end 364.5027 -114.61115)
		(width 0.1143)
		(layer "B.Cu")
		(net "DMI_CPU0_PCH_RX_C_DP<1>")
	)
	(segment
		(start 359.275634 -100.146866)
		(end 359.08869 -100.33381)
		(width 0.1143)
		(layer "B.Cu")
		(net "DMI_CPU0_PCH_RX_C_DP<1>")
	)
	(segment
		(start 364.5027 -114.61115)
		(end 362.633006 -114.61115)
		(width 0.1143)
		(layer "B.Cu")
		(net "DMI_CPU0_PCH_RX_C_DP<1>")
	)
	(segment
		(start 360.308652 -106.41584)
		(end 360.459274 -105.663238)
		(width 0.1143)
		(layer "B.Cu")
		(net "DMI_CPU0_PCH_RX_C_DP<1>")
	)
	(segment
		(start 362.633006 -114.61115)
		(end 360.797094 -113.203482)
		(width 0.1143)
		(layer "B.Cu")
		(net "DMI_CPU0_PCH_RX_C_DP<1>")
	)
	(segment
		(start 359.443782 -100.146866)
		(end 359.275634 -100.146866)
		(width 0.1143)
		(layer "B.Cu")
		(net "DMI_CPU0_PCH_RX_C_DP<1>")
	)
	(segment
		(start 360.167682 -107.12069)
		(end 360.308652 -106.41584)
		(width 0.1143)
		(layer "B.Cu")
		(net "DMI_CPU0_PCH_RX_C_DP<1>")
	)
	(segment
		(start 359.84815 -102.607618)
		(end 360.09834 -101.35616)
		(width 0.1143)
		(layer "B.Cu")
		(net "DMI_CPU0_PCH_RX_C_DP<1>")
	)
	(segment
		(start 360.09834 -101.35616)
		(end 360.070908 -101.261164)
		(width 0.1143)
		(layer "B.Cu")
		(net "DMI_CPU0_PCH_RX_C_DP<1>")
	)
	(segment
		(start 360.797094 -113.203482)
		(end 359.629202 -109.812582)
		(width 0.1143)
		(layer "B.Cu")
		(net "DMI_CPU0_PCH_RX_C_DP<1>")
	)
	(segment
		(start 359.932478 -100.779834)
		(end 359.443782 -100.146866)
		(width 0.1143)
		(layer "B.Cu")
		(net "DMI_CPU0_PCH_RX_C_DP<1>")
	)
	(segment
		(start 359.629202 -109.812582)
		(end 360.167682 -107.12069)
		(width 0.1143)
		(layer "B.Cu")
		(net "DMI_CPU0_PCH_RX_C_DP<1>")
	)
	(segment
		(start 360.070908 -101.261164)
		(end 359.932478 -100.779834)
		(width 0.1143)
		(layer "B.Cu")
		(net "DMI_CPU0_PCH_RX_C_DP<1>")
	)
	(segment
		(start 358.035606 -84.162138)
		(end 358.638856 -85.067394)
		(width 0.1143)
		(layer "In11.Cu")
		(net "DMI_CPU0_PCH_RX_C_DP<1>")
	)
	(segment
		(start 307.310536 -84.271612)
		(end 307.310536 -84.271866)
		(width 0.0889)
		(layer "In11.Cu")
		(net "DMI_CPU0_PCH_RX_C_DP<1>")
	)
	(segment
		(start 359.017062 -86.957916)
		(end 358.201214 -91.038426)
		(width 0.1143)
		(layer "In11.Cu")
		(net "DMI_CPU0_PCH_RX_C_DP<1>")
	)
	(segment
		(start 307.622448 -84.317078)
		(end 307.66766 -84.271866)
		(width 0.0889)
		(layer "In11.Cu")
		(net "DMI_CPU0_PCH_RX_C_DP<1>")
	)
	(segment
		(start 306.596288 -84.271866)
		(end 306.6415 -84.317078)
		(width 0.0889)
		(layer "In11.Cu")
		(net "DMI_CPU0_PCH_RX_C_DP<1>")
	)
	(segment
		(start 305.733958 -83.795616)
		(end 305.79314 -83.736434)
		(width 0.0889)
		(layer "In11.Cu")
		(net "DMI_CPU0_PCH_RX_C_DP<1>")
	)
	(segment
		(start 308.218332 -84.2772)
		(end 308.24043 -84.2772)
		(width 0.0889)
		(layer "In11.Cu")
		(net "DMI_CPU0_PCH_RX_C_DP<1>")
	)
	(segment
		(start 353.614736 -82.110072)
		(end 355.536246 -82.494374)
		(width 0.1143)
		(layer "In11.Cu")
		(net "DMI_CPU0_PCH_RX_C_DP<1>")
	)
	(segment
		(start 358.52354 -100.095558)
		(end 359.08869 -100.660708)
		(width 0.1143)
		(layer "In11.Cu")
		(net "DMI_CPU0_PCH_RX_C_DP<1>")
	)
	(segment
		(start 351.343722 -83.14563)
		(end 352.589338 -82.315304)
		(width 0.1143)
		(layer "In11.Cu")
		(net "DMI_CPU0_PCH_RX_C_DP<1>")
	)
	(segment
		(start 307.265324 -84.2264)
		(end 307.310536 -84.271612)
		(width 0.0889)
		(layer "In11.Cu")
		(net "DMI_CPU0_PCH_RX_C_DP<1>")
	)
	(segment
		(start 306.953412 -84.271612)
		(end 306.998624 -84.2264)
		(width 0.0889)
		(layer "In11.Cu")
		(net "DMI_CPU0_PCH_RX_C_DP<1>")
	)
	(segment
		(start 355.536246 -82.494374)
		(end 358.035606 -84.162138)
		(width 0.1143)
		(layer "In11.Cu")
		(net "DMI_CPU0_PCH_RX_C_DP<1>")
	)
	(segment
		(start 305.467258 -83.795616)
		(end 305.733958 -83.795616)
		(width 0.0889)
		(layer "In11.Cu")
		(net "DMI_CPU0_PCH_RX_C_DP<1>")
	)
	(segment
		(start 304.041556 -85.422486)
		(end 304.047906 -85.411818)
		(width 0.0889)
		(layer "In11.Cu")
		(net "DMI_CPU0_PCH_RX_C_DP<1>")
	)
	(segment
		(start 310.87949 -84.2772)
		(end 320.994278 -86.300564)
		(width 0.1143)
		(layer "In11.Cu")
		(net "DMI_CPU0_PCH_RX_C_DP<1>")
	)
	(segment
		(start 307.66766 -84.271612)
		(end 307.712872 -84.2264)
		(width 0.0889)
		(layer "In11.Cu")
		(net "DMI_CPU0_PCH_RX_C_DP<1>")
	)
	(segment
		(start 351.343722 -83.145884)
		(end 351.343722 -83.14563)
		(width 0.1143)
		(layer "In11.Cu")
		(net "DMI_CPU0_PCH_RX_C_DP<1>")
	)
	(segment
		(start 307.66766 -84.271866)
		(end 307.66766 -84.271612)
		(width 0.0889)
		(layer "In11.Cu")
		(net "DMI_CPU0_PCH_RX_C_DP<1>")
	)
	(segment
		(start 300.095666 -87.108538)
		(end 299.80255 -86.939374)
		(width 0.0889)
		(layer "In11.Cu")
		(net "DMI_CPU0_PCH_RX_C_DP<1>")
	)
	(segment
		(start 303.51476 -85.717888)
		(end 303.547526 -85.717888)
		(width 0.0889)
		(layer "In11.Cu")
		(net "DMI_CPU0_PCH_RX_C_DP<1>")
	)
	(segment
		(start 347.277436 -82.874358)
		(end 348.098364 -82.71002)
		(width 0.1143)
		(layer "In11.Cu")
		(net "DMI_CPU0_PCH_RX_C_DP<1>")
	)
	(segment
		(start 304.37709 -84.231734)
		(end 304.409856 -84.231734)
		(width 0.0889)
		(layer "In11.Cu")
		(net "DMI_CPU0_PCH_RX_C_DP<1>")
	)
	(segment
		(start 357.700072 -96.598232)
		(end 357.397812 -98.109532)
		(width 0.1143)
		(layer "In11.Cu")
		(net "DMI_CPU0_PCH_RX_C_DP<1>")
	)
	(segment
		(start 306.551076 -84.2264)
		(end 306.596288 -84.271612)
		(width 0.0889)
		(layer "In11.Cu")
		(net "DMI_CPU0_PCH_RX_C_DP<1>")
	)
	(segment
		(start 358.638856 -85.067394)
		(end 359.017062 -86.957916)
		(width 0.1143)
		(layer "In11.Cu")
		(net "DMI_CPU0_PCH_RX_C_DP<1>")
	)
	(segment
		(start 348.098364 -82.71002)
		(end 350.86671 -83.26374)
		(width 0.1143)
		(layer "In11.Cu")
		(net "DMI_CPU0_PCH_RX_C_DP<1>")
	)
	(segment
		(start 351.295716 -83.177634)
		(end 351.343722 -83.145884)
		(width 0.1143)
		(layer "In11.Cu")
		(net "DMI_CPU0_PCH_RX_C_DP<1>")
	)
	(segment
		(start 320.994278 -86.300564)
		(end 340.574376 -82.384392)
		(width 0.1143)
		(layer "In11.Cu")
		(net "DMI_CPU0_PCH_RX_C_DP<1>")
	)
	(segment
		(start 300.08068 -86.708488)
		(end 300.110652 -86.708488)
		(width 0.0889)
		(layer "In11.Cu")
		(net "DMI_CPU0_PCH_RX_C_DP<1>")
	)
	(segment
		(start 305.79314 -83.736434)
		(end 305.902614 -83.736434)
		(width 0.0889)
		(layer "In11.Cu")
		(net "DMI_CPU0_PCH_RX_C_DP<1>")
	)
	(segment
		(start 306.953412 -84.271866)
		(end 306.953412 -84.271612)
		(width 0.0889)
		(layer "In11.Cu")
		(net "DMI_CPU0_PCH_RX_C_DP<1>")
	)
	(segment
		(start 300.932596 -87.203534)
		(end 300.975776 -87.203534)
		(width 0.0889)
		(layer "In11.Cu")
		(net "DMI_CPU0_PCH_RX_C_DP<1>")
	)
	(segment
		(start 306.596288 -84.271612)
		(end 306.596288 -84.271866)
		(width 0.0889)
		(layer "In11.Cu")
		(net "DMI_CPU0_PCH_RX_C_DP<1>")
	)
	(segment
		(start 307.355748 -84.317078)
		(end 307.622448 -84.317078)
		(width 0.0889)
		(layer "In11.Cu")
		(net "DMI_CPU0_PCH_RX_C_DP<1>")
	)
	(segment
		(start 305.408076 -83.736434)
		(end 305.467258 -83.795616)
		(width 0.0889)
		(layer "In11.Cu")
		(net "DMI_CPU0_PCH_RX_C_DP<1>")
	)
	(segment
		(start 306.6415 -84.317078)
		(end 306.9082 -84.317078)
		(width 0.0889)
		(layer "In11.Cu")
		(net "DMI_CPU0_PCH_RX_C_DP<1>")
	)
	(segment
		(start 340.574376 -82.384392)
		(end 343.576148 -82.984594)
		(width 0.1143)
		(layer "In11.Cu")
		(net "DMI_CPU0_PCH_RX_C_DP<1>")
	)
	(segment
		(start 306.39258 -84.2264)
		(end 306.551076 -84.2264)
		(width 0.0889)
		(layer "In11.Cu")
		(net "DMI_CPU0_PCH_RX_C_DP<1>")
	)
	(segment
		(start 305.902614 -83.736434)
		(end 306.39258 -84.2264)
		(width 0.0889)
		(layer "In11.Cu")
		(net "DMI_CPU0_PCH_RX_C_DP<1>")
	)
	(segment
		(start 358.076246 -100.095558)
		(end 358.52354 -100.095558)
		(width 0.1143)
		(layer "In11.Cu")
		(net "DMI_CPU0_PCH_RX_C_DP<1>")
	)
	(segment
		(start 301.79772 -86.708488)
		(end 301.830486 -86.708488)
		(width 0.0889)
		(layer "In11.Cu")
		(net "DMI_CPU0_PCH_RX_C_DP<1>")
	)
	(segment
		(start 302.66005 -86.212934)
		(end 302.692816 -86.212934)
		(width 0.0889)
		(layer "In11.Cu")
		(net "DMI_CPU0_PCH_RX_C_DP<1>")
	)
	(segment
		(start 350.86671 -83.26374)
		(end 351.295716 -83.177634)
		(width 0.1143)
		(layer "In11.Cu")
		(net "DMI_CPU0_PCH_RX_C_DP<1>")
	)
	(segment
		(start 352.589338 -82.315304)
		(end 353.614736 -82.110072)
		(width 0.1143)
		(layer "In11.Cu")
		(net "DMI_CPU0_PCH_RX_C_DP<1>")
	)
	(segment
		(start 305.053746 -83.736434)
		(end 305.408076 -83.736434)
		(width 0.0889)
		(layer "In11.Cu")
		(net "DMI_CPU0_PCH_RX_C_DP<1>")
	)
	(segment
		(start 307.712872 -84.2264)
		(end 308.167532 -84.2264)
		(width 0.0889)
		(layer "In11.Cu")
		(net "DMI_CPU0_PCH_RX_C_DP<1>")
	)
	(segment
		(start 343.576148 -82.984594)
		(end 345.703652 -82.559398)
		(width 0.1143)
		(layer "In11.Cu")
		(net "DMI_CPU0_PCH_RX_C_DP<1>")
	)
	(segment
		(start 357.724964 -99.744276)
		(end 358.076246 -100.095558)
		(width 0.1143)
		(layer "In11.Cu")
		(net "DMI_CPU0_PCH_RX_C_DP<1>")
	)
	(segment
		(start 306.9082 -84.317078)
		(end 306.953412 -84.271866)
		(width 0.0889)
		(layer "In11.Cu")
		(net "DMI_CPU0_PCH_RX_C_DP<1>")
	)
	(segment
		(start 357.112316 -93.660722)
		(end 357.700072 -96.598232)
		(width 0.1143)
		(layer "In11.Cu")
		(net "DMI_CPU0_PCH_RX_C_DP<1>")
	)
	(segment
		(start 358.201214 -91.038426)
		(end 357.112316 -93.660722)
		(width 0.1143)
		(layer "In11.Cu")
		(net "DMI_CPU0_PCH_RX_C_DP<1>")
	)
	(segment
		(start 345.703652 -82.559398)
		(end 347.277436 -82.874358)
		(width 0.1143)
		(layer "In11.Cu")
		(net "DMI_CPU0_PCH_RX_C_DP<1>")
	)
	(segment
		(start 306.998624 -84.2264)
		(end 307.265324 -84.2264)
		(width 0.0889)
		(layer "In11.Cu")
		(net "DMI_CPU0_PCH_RX_C_DP<1>")
	)
	(segment
		(start 299.80255 -86.939374)
		(end 299.781468 -86.860634)
		(width 0.0889)
		(layer "In11.Cu")
		(net "DMI_CPU0_PCH_RX_C_DP<1>")
	)
	(segment
		(start 304.900076 -83.936586)
		(end 304.964084 -83.826096)
		(width 0.0889)
		(layer "In11.Cu")
		(net "DMI_CPU0_PCH_RX_C_DP<1>")
	)
	(segment
		(start 307.310536 -84.271866)
		(end 307.355748 -84.317078)
		(width 0.0889)
		(layer "In11.Cu")
		(net "DMI_CPU0_PCH_RX_C_DP<1>")
	)
	(segment
		(start 304.964084 -83.826096)
		(end 305.053746 -83.736434)
		(width 0.0889)
		(layer "In11.Cu")
		(net "DMI_CPU0_PCH_RX_C_DP<1>")
	)
	(segment
		(start 357.397812 -98.109532)
		(end 357.724964 -99.744276)
		(width 0.1143)
		(layer "In11.Cu")
		(net "DMI_CPU0_PCH_RX_C_DP<1>")
	)
	(segment
		(start 308.167532 -84.2264)
		(end 308.218332 -84.2772)
		(width 0.0889)
		(layer "In11.Cu")
		(net "DMI_CPU0_PCH_RX_C_DP<1>")
	)
	(segment
		(start 308.24043 -84.2772)
		(end 310.87949 -84.2772)
		(width 0.1143)
		(layer "In11.Cu")
		(net "DMI_CPU0_PCH_RX_C_DP<1>")
	)
	(arc
		(start 304.041556 -84.831936)
		(mid 304.038808 -84.436469)
		(end 304.37709 -84.231734)
		(width 0.0889)
		(layer "In11.Cu")
		(net "DMI_CPU0_PCH_RX_C_DP<1>")
	)
	(arc
		(start 300.110652 -86.708488)
		(mid 300.302294 -86.765654)
		(end 300.442376 -86.908386)
		(width 0.0889)
		(layer "In11.Cu")
		(net "DMI_CPU0_PCH_RX_C_DP<1>")
	)
	(arc
		(start 302.692816 -86.212934)
		(mid 302.976033 -86.128653)
		(end 303.183036 -85.917786)
		(width 0.0889)
		(layer "In11.Cu")
		(net "DMI_CPU0_PCH_RX_C_DP<1>")
	)
	(arc
		(start 300.442376 -86.908386)
		(mid 300.64938 -87.11925)
		(end 300.932596 -87.203534)
		(width 0.0889)
		(layer "In11.Cu")
		(net "DMI_CPU0_PCH_RX_C_DP<1>")
	)
	(arc
		(start 302.324516 -86.413086)
		(mid 302.466199 -86.269282)
		(end 302.66005 -86.212934)
		(width 0.0889)
		(layer "In11.Cu")
		(net "DMI_CPU0_PCH_RX_C_DP<1>")
	)
	(arc
		(start 301.830486 -86.708488)
		(mid 302.11591 -86.625021)
		(end 302.324516 -86.413086)
		(width 0.0889)
		(layer "In11.Cu")
		(net "DMI_CPU0_PCH_RX_C_DP<1>")
	)
	(arc
		(start 299.781468 -86.860634)
		(mid 299.914349 -86.751651)
		(end 300.08068 -86.708488)
		(width 0.0889)
		(layer "In11.Cu")
		(net "DMI_CPU0_PCH_RX_C_DP<1>")
	)
	(arc
		(start 301.465996 -86.908386)
		(mid 301.606075 -86.76565)
		(end 301.79772 -86.708488)
		(width 0.0889)
		(layer "In11.Cu")
		(net "DMI_CPU0_PCH_RX_C_DP<1>")
	)
	(arc
		(start 300.975776 -87.203534)
		(mid 301.258993 -87.119253)
		(end 301.465996 -86.908386)
		(width 0.0889)
		(layer "In11.Cu")
		(net "DMI_CPU0_PCH_RX_C_DP<1>")
	)
	(arc
		(start 304.409856 -84.231734)
		(mid 304.693073 -84.147453)
		(end 304.900076 -83.936586)
		(width 0.0889)
		(layer "In11.Cu")
		(net "DMI_CPU0_PCH_RX_C_DP<1>")
	)
	(arc
		(start 303.183036 -85.917786)
		(mid 303.323115 -85.77505)
		(end 303.51476 -85.717888)
		(width 0.0889)
		(layer "In11.Cu")
		(net "DMI_CPU0_PCH_RX_C_DP<1>")
	)
	(arc
		(start 304.047906 -85.411818)
		(mid 304.120704 -85.121055)
		(end 304.041556 -84.831936)
		(width 0.0889)
		(layer "In11.Cu")
		(net "DMI_CPU0_PCH_RX_C_DP<1>")
	)
	(arc
		(start 303.547526 -85.717888)
		(mid 303.83295 -85.634421)
		(end 304.041556 -85.422486)
		(width 0.0889)
		(layer "In11.Cu")
		(net "DMI_CPU0_PCH_RX_C_DP<1>")
	)
	(segment
		(start 299.524166 -86.117938)
		(end 300.095666 -86.117938)
		(width 0.1143)
		(layer "F.Cu")
		(net "DMI_CPU0_PCH_RX_C_DP<0>")
	)
	(via
		(at 300.095666 -86.117938)
		(size 0.508)
		(drill 0.254)
		(layers "F.Cu" "B.Cu")
		(net "DMI_CPU0_PCH_RX_C_DP<0>")
	)
	(via
		(at 360.69905 -99.924108)
		(size 0.508)
		(drill 0.254)
		(layers "F.Cu" "B.Cu")
		(net "DMI_CPU0_PCH_RX_C_DP<0>")
	)
	(segment
		(start 361.47248 -112.058958)
		(end 362.641896 -113.22812)
		(width 0.1143)
		(layer "B.Cu")
		(net "DMI_CPU0_PCH_RX_C_DP<0>")
	)
	(segment
		(start 368.554 -113.332514)
		(end 368.554 -113.792)
		(width 0.1143)
		(layer "B.Cu")
		(net "DMI_CPU0_PCH_RX_C_DP<0>")
	)
	(segment
		(start 360.795824 -99.456494)
		(end 361.239816 -99.456494)
		(width 0.1143)
		(layer "B.Cu")
		(net "DMI_CPU0_PCH_RX_C_DP<0>")
	)
	(segment
		(start 360.787442 -109.883194)
		(end 361.47248 -112.058958)
		(width 0.1143)
		(layer "B.Cu")
		(net "DMI_CPU0_PCH_RX_C_DP<0>")
	)
	(segment
		(start 360.69905 -99.553268)
		(end 360.795824 -99.456494)
		(width 0.1143)
		(layer "B.Cu")
		(net "DMI_CPU0_PCH_RX_C_DP<0>")
	)
	(segment
		(start 361.503214 -105.638092)
		(end 361.37215 -106.415332)
		(width 0.1143)
		(layer "B.Cu")
		(net "DMI_CPU0_PCH_RX_C_DP<0>")
	)
	(segment
		(start 361.584494 -99.957636)
		(end 361.32389 -101.261164)
		(width 0.1143)
		(layer "B.Cu")
		(net "DMI_CPU0_PCH_RX_C_DP<0>")
	)
	(segment
		(start 360.990642 -102.926896)
		(end 361.503214 -105.638092)
		(width 0.1143)
		(layer "B.Cu")
		(net "DMI_CPU0_PCH_RX_C_DP<0>")
	)
	(segment
		(start 368.449606 -113.22812)
		(end 368.554 -113.332514)
		(width 0.1143)
		(layer "B.Cu")
		(net "DMI_CPU0_PCH_RX_C_DP<0>")
	)
	(segment
		(start 361.239816 -99.456494)
		(end 361.393994 -99.578668)
		(width 0.1143)
		(layer "B.Cu")
		(net "DMI_CPU0_PCH_RX_C_DP<0>")
	)
	(segment
		(start 362.641896 -113.22812)
		(end 368.449606 -113.22812)
		(width 0.1143)
		(layer "B.Cu")
		(net "DMI_CPU0_PCH_RX_C_DP<0>")
	)
	(segment
		(start 361.37215 -106.415332)
		(end 360.787442 -109.883194)
		(width 0.1143)
		(layer "B.Cu")
		(net "DMI_CPU0_PCH_RX_C_DP<0>")
	)
	(segment
		(start 360.69905 -99.924108)
		(end 360.69905 -99.553268)
		(width 0.1143)
		(layer "B.Cu")
		(net "DMI_CPU0_PCH_RX_C_DP<0>")
	)
	(segment
		(start 361.393994 -99.578668)
		(end 361.584494 -99.957636)
		(width 0.1143)
		(layer "B.Cu")
		(net "DMI_CPU0_PCH_RX_C_DP<0>")
	)
	(segment
		(start 361.32389 -101.261164)
		(end 360.990642 -102.926896)
		(width 0.1143)
		(layer "B.Cu")
		(net "DMI_CPU0_PCH_RX_C_DP<0>")
	)
	(segment
		(start 341.29853 -75.185016)
		(end 338.918042 -76.171806)
		(width 0.1143)
		(layer "In11.Cu")
		(net "DMI_CPU0_PCH_RX_C_DP<0>")
	)
	(segment
		(start 303.17821 -84.328)
		(end 303.183036 -84.336636)
		(width 0.0889)
		(layer "In11.Cu")
		(net "DMI_CPU0_PCH_RX_C_DP<0>")
	)
	(segment
		(start 308.374542 -83.4898)
		(end 306.464716 -83.4898)
		(width 0.0889)
		(layer "In11.Cu")
		(net "DMI_CPU0_PCH_RX_C_DP<0>")
	)
	(segment
		(start 360.472736 -75.817984)
		(end 358.4702 -75.41768)
		(width 0.1143)
		(layer "In11.Cu")
		(net "DMI_CPU0_PCH_RX_C_DP<0>")
	)
	(segment
		(start 348.2975 -75.00874)
		(end 345.455748 -75.577192)
		(width 0.1143)
		(layer "In11.Cu")
		(net "DMI_CPU0_PCH_RX_C_DP<0>")
	)
	(segment
		(start 360.49585 -84.339684)
		(end 360.189272 -82.80527)
		(width 0.1143)
		(layer "In11.Cu")
		(net "DMI_CPU0_PCH_RX_C_DP<0>")
	)
	(segment
		(start 338.918042 -76.171552)
		(end 336.480658 -79.828136)
		(width 0.1143)
		(layer "In11.Cu")
		(net "DMI_CPU0_PCH_RX_C_DP<0>")
	)
	(segment
		(start 303.183036 -84.336636)
		(end 303.189386 -84.347304)
		(width 0.0889)
		(layer "In11.Cu")
		(net "DMI_CPU0_PCH_RX_C_DP<0>")
	)
	(segment
		(start 311.331356 -83.5406)
		(end 308.44744 -83.5406)
		(width 0.1143)
		(layer "In11.Cu")
		(net "DMI_CPU0_PCH_RX_C_DP<0>")
	)
	(segment
		(start 345.455748 -75.577192)
		(end 342.396572 -74.965306)
		(width 0.1143)
		(layer "In11.Cu")
		(net "DMI_CPU0_PCH_RX_C_DP<0>")
	)
	(segment
		(start 358.238806 -94.123764)
		(end 358.4067 -93.285818)
		(width 0.1143)
		(layer "In11.Cu")
		(net "DMI_CPU0_PCH_RX_C_DP<0>")
	)
	(segment
		(start 356.742492 -75.76312)
		(end 354.417884 -75.298046)
		(width 0.1143)
		(layer "In11.Cu")
		(net "DMI_CPU0_PCH_RX_C_DP<0>")
	)
	(segment
		(start 321.317874 -85.537802)
		(end 311.331356 -83.5406)
		(width 0.1143)
		(layer "In11.Cu")
		(net "DMI_CPU0_PCH_RX_C_DP<0>")
	)
	(segment
		(start 342.396572 -74.965306)
		(end 341.29853 -75.185016)
		(width 0.1143)
		(layer "In11.Cu")
		(net "DMI_CPU0_PCH_RX_C_DP<0>")
	)
	(segment
		(start 354.417884 -75.298046)
		(end 352.081338 -75.765406)
		(width 0.1143)
		(layer "In11.Cu")
		(net "DMI_CPU0_PCH_RX_C_DP<0>")
	)
	(segment
		(start 360.69905 -99.924108)
		(end 360.69905 -99.586796)
		(width 0.1143)
		(layer "In11.Cu")
		(net "DMI_CPU0_PCH_RX_C_DP<0>")
	)
	(segment
		(start 330.74229 -83.653122)
		(end 321.317874 -85.537802)
		(width 0.1143)
		(layer "In11.Cu")
		(net "DMI_CPU0_PCH_RX_C_DP<0>")
	)
	(segment
		(start 306.21605 -83.241134)
		(end 304.37709 -83.241134)
		(width 0.0889)
		(layer "In11.Cu")
		(net "DMI_CPU0_PCH_RX_C_DP<0>")
	)
	(segment
		(start 301.830486 -85.717888)
		(end 301.79772 -85.717888)
		(width 0.0889)
		(layer "In11.Cu")
		(net "DMI_CPU0_PCH_RX_C_DP<0>")
	)
	(segment
		(start 308.425342 -83.5406)
		(end 308.374542 -83.4898)
		(width 0.0889)
		(layer "In11.Cu")
		(net "DMI_CPU0_PCH_RX_C_DP<0>")
	)
	(segment
		(start 359.076498 -98.309684)
		(end 358.238806 -94.123764)
		(width 0.1143)
		(layer "In11.Cu")
		(net "DMI_CPU0_PCH_RX_C_DP<0>")
	)
	(segment
		(start 336.480658 -79.828136)
		(end 330.74229 -83.653122)
		(width 0.1143)
		(layer "In11.Cu")
		(net "DMI_CPU0_PCH_RX_C_DP<0>")
	)
	(segment
		(start 361.081828 -88.287098)
		(end 360.39425 -84.847938)
		(width 0.1143)
		(layer "In11.Cu")
		(net "DMI_CPU0_PCH_RX_C_DP<0>")
	)
	(segment
		(start 360.189272 -82.80527)
		(end 361.146598 -78.019402)
		(width 0.1143)
		(layer "In11.Cu")
		(net "DMI_CPU0_PCH_RX_C_DP<0>")
	)
	(segment
		(start 360.534712 -99.422458)
		(end 360.044746 -99.422458)
		(width 0.1143)
		(layer "In11.Cu")
		(net "DMI_CPU0_PCH_RX_C_DP<0>")
	)
	(segment
		(start 338.918042 -76.171806)
		(end 338.918042 -76.171552)
		(width 0.1143)
		(layer "In11.Cu")
		(net "DMI_CPU0_PCH_RX_C_DP<0>")
	)
	(segment
		(start 300.346872 -85.972904)
		(end 300.095666 -86.117938)
		(width 0.0889)
		(layer "In11.Cu")
		(net "DMI_CPU0_PCH_RX_C_DP<0>")
	)
	(segment
		(start 359.05059 -92.319602)
		(end 359.681526 -91.897962)
		(width 0.1143)
		(layer "In11.Cu")
		(net "DMI_CPU0_PCH_RX_C_DP<0>")
	)
	(segment
		(start 360.921046 -76.490576)
		(end 360.472736 -75.817984)
		(width 0.1143)
		(layer "In11.Cu")
		(net "DMI_CPU0_PCH_RX_C_DP<0>")
	)
	(segment
		(start 358.4067 -93.285818)
		(end 359.05059 -92.319602)
		(width 0.1143)
		(layer "In11.Cu")
		(net "DMI_CPU0_PCH_RX_C_DP<0>")
	)
	(segment
		(start 303.547526 -83.736688)
		(end 303.51476 -83.736688)
		(width 0.0889)
		(layer "In11.Cu")
		(net "DMI_CPU0_PCH_RX_C_DP<0>")
	)
	(segment
		(start 359.681526 -91.897962)
		(end 360.649266 -90.446352)
		(width 0.1143)
		(layer "In11.Cu")
		(net "DMI_CPU0_PCH_RX_C_DP<0>")
	)
	(segment
		(start 360.39425 -84.847938)
		(end 360.49585 -84.339684)
		(width 0.1143)
		(layer "In11.Cu")
		(net "DMI_CPU0_PCH_RX_C_DP<0>")
	)
	(segment
		(start 358.4702 -75.41768)
		(end 356.742492 -75.76312)
		(width 0.1143)
		(layer "In11.Cu")
		(net "DMI_CPU0_PCH_RX_C_DP<0>")
	)
	(segment
		(start 352.081338 -75.765406)
		(end 348.2975 -75.00874)
		(width 0.1143)
		(layer "In11.Cu")
		(net "DMI_CPU0_PCH_RX_C_DP<0>")
	)
	(segment
		(start 300.975776 -86.212934)
		(end 300.932596 -86.212934)
		(width 0.0889)
		(layer "In11.Cu")
		(net "DMI_CPU0_PCH_RX_C_DP<0>")
	)
	(segment
		(start 306.464716 -83.4898)
		(end 306.21605 -83.241134)
		(width 0.0889)
		(layer "In11.Cu")
		(net "DMI_CPU0_PCH_RX_C_DP<0>")
	)
	(segment
		(start 359.365804 -98.743516)
		(end 359.076498 -98.309684)
		(width 0.1143)
		(layer "In11.Cu")
		(net "DMI_CPU0_PCH_RX_C_DP<0>")
	)
	(segment
		(start 361.146598 -78.019402)
		(end 361.18673 -77.81925)
		(width 0.1143)
		(layer "In11.Cu")
		(net "DMI_CPU0_PCH_RX_C_DP<0>")
	)
	(segment
		(start 302.692816 -85.222334)
		(end 302.66005 -85.222334)
		(width 0.0889)
		(layer "In11.Cu")
		(net "DMI_CPU0_PCH_RX_C_DP<0>")
	)
	(segment
		(start 300.47819 -85.972904)
		(end 300.346872 -85.972904)
		(width 0.0889)
		(layer "In11.Cu")
		(net "DMI_CPU0_PCH_RX_C_DP<0>")
	)
	(segment
		(start 360.044746 -99.422458)
		(end 359.365804 -98.743516)
		(width 0.1143)
		(layer "In11.Cu")
		(net "DMI_CPU0_PCH_RX_C_DP<0>")
	)
	(segment
		(start 360.69905 -99.586796)
		(end 360.534712 -99.422458)
		(width 0.1143)
		(layer "In11.Cu")
		(net "DMI_CPU0_PCH_RX_C_DP<0>")
	)
	(segment
		(start 360.649266 -90.446352)
		(end 361.081828 -88.287098)
		(width 0.1143)
		(layer "In11.Cu")
		(net "DMI_CPU0_PCH_RX_C_DP<0>")
	)
	(segment
		(start 361.18673 -77.81925)
		(end 360.921046 -76.490576)
		(width 0.1143)
		(layer "In11.Cu")
		(net "DMI_CPU0_PCH_RX_C_DP<0>")
	)
	(segment
		(start 308.44744 -83.5406)
		(end 308.425342 -83.5406)
		(width 0.0889)
		(layer "In11.Cu")
		(net "DMI_CPU0_PCH_RX_C_DP<0>")
	)
	(arc
		(start 304.37709 -83.241134)
		(mid 304.18324 -83.297484)
		(end 304.041556 -83.441286)
		(width 0.0889)
		(layer "In11.Cu")
		(net "DMI_CPU0_PCH_RX_C_DP<0>")
	)
	(arc
		(start 301.79772 -85.717888)
		(mid 301.606078 -85.775054)
		(end 301.465996 -85.917786)
		(width 0.0889)
		(layer "In11.Cu")
		(net "DMI_CPU0_PCH_RX_C_DP<0>")
	)
	(arc
		(start 302.66005 -85.222334)
		(mid 302.4662 -85.278684)
		(end 302.324516 -85.422486)
		(width 0.0889)
		(layer "In11.Cu")
		(net "DMI_CPU0_PCH_RX_C_DP<0>")
	)
	(arc
		(start 302.324516 -85.422486)
		(mid 302.115908 -85.634418)
		(end 301.830486 -85.717888)
		(width 0.0889)
		(layer "In11.Cu")
		(net "DMI_CPU0_PCH_RX_C_DP<0>")
	)
	(arc
		(start 300.932596 -86.212934)
		(mid 300.677931 -86.144905)
		(end 300.47819 -85.972904)
		(width 0.0889)
		(layer "In11.Cu")
		(net "DMI_CPU0_PCH_RX_C_DP<0>")
	)
	(arc
		(start 303.51476 -83.736688)
		(mid 303.181842 -83.938679)
		(end 303.17821 -84.328)
		(width 0.0889)
		(layer "In11.Cu")
		(net "DMI_CPU0_PCH_RX_C_DP<0>")
	)
	(arc
		(start 303.189386 -84.347304)
		(mid 303.185355 -84.923486)
		(end 302.692816 -85.222334)
		(width 0.0889)
		(layer "In11.Cu")
		(net "DMI_CPU0_PCH_RX_C_DP<0>")
	)
	(arc
		(start 301.465996 -85.917786)
		(mid 301.258992 -86.12865)
		(end 300.975776 -86.212934)
		(width 0.0889)
		(layer "In11.Cu")
		(net "DMI_CPU0_PCH_RX_C_DP<0>")
	)
	(arc
		(start 304.041556 -83.441286)
		(mid 303.832948 -83.653218)
		(end 303.547526 -83.736688)
		(width 0.0889)
		(layer "In11.Cu")
		(net "DMI_CPU0_PCH_RX_C_DP<0>")
	)
	(segment
		(start 298.665646 -88.594184)
		(end 299.237146 -88.594184)
		(width 0.1143)
		(layer "F.Cu")
		(net "DMI_CPU0_PCH_RX_C_DN<3>")
	)
	(via
		(at 363.62513 -107.356402)
		(size 0.1016)
		(drill 0.0508)
		(layers "F.Cu" "B.Cu")
		(net "DMI_CPU0_PCH_RX_C_DN<3>")
	)
	(via
		(at 299.237146 -88.594184)
		(size 0.508)
		(drill 0.254)
		(layers "F.Cu" "B.Cu")
		(net "DMI_CPU0_PCH_RX_C_DN<3>")
	)
	(via
		(at 360.81081 -93.62059)
		(size 0.508)
		(drill 0.254)
		(layers "F.Cu" "B.Cu")
		(net "DMI_CPU0_PCH_RX_C_DN<3>")
	)
	(segment
		(start 363.538262 -107.78998)
		(end 363.506258 -107.950508)
		(width 0.1143)
		(layer "B.Cu")
		(net "DMI_CPU0_PCH_RX_C_DN<3>")
	)
	(segment
		(start 363.506258 -107.950508)
		(end 363.709966 -108.969302)
		(width 0.1143)
		(layer "B.Cu")
		(net "DMI_CPU0_PCH_RX_C_DN<3>")
	)
	(segment
		(start 366.57534 -110.17885)
		(end 368.4397 -110.17885)
		(width 0.1143)
		(layer "B.Cu")
		(net "DMI_CPU0_PCH_RX_C_DN<3>")
	)
	(segment
		(start 368.554 -110.06455)
		(end 368.554 -109.601)
		(width 0.1143)
		(layer "B.Cu")
		(net "DMI_CPU0_PCH_RX_C_DN<3>")
	)
	(segment
		(start 360.81081 -93.9673)
		(end 360.97972 -94.13621)
		(width 0.1143)
		(layer "B.Cu")
		(net "DMI_CPU0_PCH_RX_C_DN<3>")
	)
	(segment
		(start 363.352334 -103.169212)
		(end 363.907578 -105.945178)
		(width 0.1143)
		(layer "B.Cu")
		(net "DMI_CPU0_PCH_RX_C_DN<3>")
	)
	(segment
		(start 363.62513 -107.356402)
		(end 363.538262 -107.78998)
		(width 0.1143)
		(layer "B.Cu")
		(net "DMI_CPU0_PCH_RX_C_DN<3>")
	)
	(segment
		(start 360.97972 -94.13621)
		(end 361.528106 -94.13621)
		(width 0.1143)
		(layer "B.Cu")
		(net "DMI_CPU0_PCH_RX_C_DN<3>")
	)
	(segment
		(start 364.111794 -99.372928)
		(end 363.734096 -101.261164)
		(width 0.1143)
		(layer "B.Cu")
		(net "DMI_CPU0_PCH_RX_C_DN<3>")
	)
	(segment
		(start 363.72292 -97.428304)
		(end 364.111794 -99.372928)
		(width 0.1143)
		(layer "B.Cu")
		(net "DMI_CPU0_PCH_RX_C_DN<3>")
	)
	(segment
		(start 364.245652 -109.77245)
		(end 366.57534 -110.17885)
		(width 0.1143)
		(layer "B.Cu")
		(net "DMI_CPU0_PCH_RX_C_DN<3>")
	)
	(segment
		(start 361.528106 -94.13621)
		(end 363.72292 -97.428304)
		(width 0.1143)
		(layer "B.Cu")
		(net "DMI_CPU0_PCH_RX_C_DN<3>")
	)
	(segment
		(start 363.734096 -101.261164)
		(end 363.352334 -103.169212)
		(width 0.1143)
		(layer "B.Cu")
		(net "DMI_CPU0_PCH_RX_C_DN<3>")
	)
	(segment
		(start 363.709966 -108.969302)
		(end 364.245652 -109.77245)
		(width 0.1143)
		(layer "B.Cu")
		(net "DMI_CPU0_PCH_RX_C_DN<3>")
	)
	(segment
		(start 360.81081 -93.62059)
		(end 360.81081 -93.9673)
		(width 0.1143)
		(layer "B.Cu")
		(net "DMI_CPU0_PCH_RX_C_DN<3>")
	)
	(segment
		(start 368.4397 -110.17885)
		(end 368.554 -110.06455)
		(width 0.1143)
		(layer "B.Cu")
		(net "DMI_CPU0_PCH_RX_C_DN<3>")
	)
	(segment
		(start 363.907578 -105.945178)
		(end 363.62513 -107.356402)
		(width 0.1143)
		(layer "B.Cu")
		(net "DMI_CPU0_PCH_RX_C_DN<3>")
	)
	(segment
		(start 345.457018 -74.502264)
		(end 342.494362 -73.909936)
		(width 0.1143)
		(layer "In11.Cu")
		(net "DMI_CPU0_PCH_RX_C_DN<3>")
	)
	(segment
		(start 354.262944 -74.272648)
		(end 352.307398 -74.663808)
		(width 0.1143)
		(layer "In11.Cu")
		(net "DMI_CPU0_PCH_RX_C_DN<3>")
	)
	(segment
		(start 299.252132 -85.031834)
		(end 299.219366 -85.031834)
		(width 0.0889)
		(layer "In11.Cu")
		(net "DMI_CPU0_PCH_RX_C_DN<3>")
	)
	(segment
		(start 308.0512 -82.555334)
		(end 305.23561 -82.555334)
		(width 0.0889)
		(layer "In11.Cu")
		(net "DMI_CPU0_PCH_RX_C_DN<3>")
	)
	(segment
		(start 302.686212 -83.050634)
		(end 302.653446 -83.050634)
		(width 0.0889)
		(layer "In11.Cu")
		(net "DMI_CPU0_PCH_RX_C_DN<3>")
	)
	(segment
		(start 321.168268 -84.50453)
		(end 311.194958 -82.510122)
		(width 0.1143)
		(layer "In11.Cu")
		(net "DMI_CPU0_PCH_RX_C_DN<3>")
	)
	(segment
		(start 362.072428 -88.476582)
		(end 361.351576 -84.873846)
		(width 0.1143)
		(layer "In11.Cu")
		(net "DMI_CPU0_PCH_RX_C_DN<3>")
	)
	(segment
		(start 308.102 -82.504534)
		(end 308.0512 -82.555334)
		(width 0.0889)
		(layer "In11.Cu")
		(net "DMI_CPU0_PCH_RX_C_DN<3>")
	)
	(segment
		(start 303.540922 -82.555334)
		(end 303.516792 -82.555334)
		(width 0.0889)
		(layer "In11.Cu")
		(net "DMI_CPU0_PCH_RX_C_DN<3>")
	)
	(segment
		(start 359.6132 -93.200474)
		(end 359.995724 -92.818204)
		(width 0.1143)
		(layer "In11.Cu")
		(net "DMI_CPU0_PCH_RX_C_DN<3>")
	)
	(segment
		(start 362.136182 -77.800708)
		(end 362.139992 -77.78115)
		(width 0.1143)
		(layer "In11.Cu")
		(net "DMI_CPU0_PCH_RX_C_DN<3>")
	)
	(segment
		(start 362.132372 -77.81925)
		(end 362.13923 -77.814678)
		(width 0.1143)
		(layer "In11.Cu")
		(net "DMI_CPU0_PCH_RX_C_DN<3>")
	)
	(segment
		(start 360.81081 -93.62059)
		(end 360.81081 -93.932502)
		(width 0.1143)
		(layer "In11.Cu")
		(net "DMI_CPU0_PCH_RX_C_DN<3>")
	)
	(segment
		(start 338.064602 -75.54214)
		(end 335.717134 -79.064104)
		(width 0.1143)
		(layer "In11.Cu")
		(net "DMI_CPU0_PCH_RX_C_DN<3>")
	)
	(segment
		(start 362.124752 -77.85735)
		(end 362.132372 -77.81925)
		(width 0.1143)
		(layer "In11.Cu")
		(net "DMI_CPU0_PCH_RX_C_DN<3>")
	)
	(segment
		(start 298.725336 -86.317836)
		(end 298.718986 -86.328504)
		(width 0.0889)
		(layer "In11.Cu")
		(net "DMI_CPU0_PCH_RX_C_DN<3>")
	)
	(segment
		(start 360.636566 -94.106746)
		(end 359.9942 -94.106746)
		(width 0.1143)
		(layer "In11.Cu")
		(net "DMI_CPU0_PCH_RX_C_DN<3>")
	)
	(segment
		(start 304.409856 -82.060034)
		(end 304.366676 -82.060034)
		(width 0.0889)
		(layer "In11.Cu")
		(net "DMI_CPU0_PCH_RX_C_DN<3>")
	)
	(segment
		(start 360.981498 -74.872342)
		(end 358.641142 -74.40422)
		(width 0.1143)
		(layer "In11.Cu")
		(net "DMI_CPU0_PCH_RX_C_DN<3>")
	)
	(segment
		(start 299.237146 -88.932258)
		(end 299.237146 -88.594184)
		(width 0.0889)
		(layer "In11.Cu")
		(net "DMI_CPU0_PCH_RX_C_DN<3>")
	)
	(segment
		(start 338.132928 -75.439524)
		(end 338.064602 -75.54214)
		(width 0.1143)
		(layer "In11.Cu")
		(net "DMI_CPU0_PCH_RX_C_DN<3>")
	)
	(segment
		(start 335.717134 -79.064104)
		(end 330.294234 -82.679286)
		(width 0.1143)
		(layer "In11.Cu")
		(net "DMI_CPU0_PCH_RX_C_DN<3>")
	)
	(segment
		(start 301.823882 -83.546188)
		(end 301.791116 -83.546188)
		(width 0.0889)
		(layer "In11.Cu")
		(net "DMI_CPU0_PCH_RX_C_DN<3>")
	)
	(segment
		(start 360.331766 -92.750894)
		(end 361.597956 -90.853006)
		(width 0.1143)
		(layer "In11.Cu")
		(net "DMI_CPU0_PCH_RX_C_DN<3>")
	)
	(segment
		(start 299.295058 -88.99017)
		(end 299.237146 -88.932258)
		(width 0.0889)
		(layer "In11.Cu")
		(net "DMI_CPU0_PCH_RX_C_DN<3>")
	)
	(segment
		(start 299.577506 -88.383618)
		(end 299.583856 -88.394286)
		(width 0.0889)
		(layer "In11.Cu")
		(net "DMI_CPU0_PCH_RX_C_DN<3>")
	)
	(segment
		(start 362.139992 -77.78115)
		(end 362.014008 -77.151992)
		(width 0.1143)
		(layer "In11.Cu")
		(net "DMI_CPU0_PCH_RX_C_DN<3>")
	)
	(segment
		(start 330.294234 -82.679286)
		(end 321.168268 -84.50453)
		(width 0.1143)
		(layer "In11.Cu")
		(net "DMI_CPU0_PCH_RX_C_DN<3>")
	)
	(segment
		(start 308.124098 -82.504534)
		(end 308.102 -82.504534)
		(width 0.0889)
		(layer "In11.Cu")
		(net "DMI_CPU0_PCH_RX_C_DN<3>")
	)
	(segment
		(start 362.014008 -77.151992)
		(end 361.80522 -76.108052)
		(width 0.1143)
		(layer "In11.Cu")
		(net "DMI_CPU0_PCH_RX_C_DN<3>")
	)
	(segment
		(start 299.583856 -88.394286)
		(end 299.588682 -88.402922)
		(width 0.0889)
		(layer "In11.Cu")
		(net "DMI_CPU0_PCH_RX_C_DN<3>")
	)
	(segment
		(start 361.466384 -84.302092)
		(end 361.15117 -82.72526)
		(width 0.1143)
		(layer "In11.Cu")
		(net "DMI_CPU0_PCH_RX_C_DN<3>")
	)
	(segment
		(start 352.307398 -74.663808)
		(end 348.476824 -73.897998)
		(width 0.1143)
		(layer "In11.Cu")
		(net "DMI_CPU0_PCH_RX_C_DN<3>")
	)
	(segment
		(start 360.167682 -92.78366)
		(end 360.331766 -92.750894)
		(width 0.1143)
		(layer "In11.Cu")
		(net "DMI_CPU0_PCH_RX_C_DN<3>")
	)
	(segment
		(start 362.12399 -77.861668)
		(end 362.124752 -77.85735)
		(width 0.1143)
		(layer "In11.Cu")
		(net "DMI_CPU0_PCH_RX_C_DN<3>")
	)
	(segment
		(start 359.6132 -93.575886)
		(end 359.6132 -93.200474)
		(width 0.1143)
		(layer "In11.Cu")
		(net "DMI_CPU0_PCH_RX_C_DN<3>")
	)
	(segment
		(start 361.83316 -79.316072)
		(end 362.120942 -77.8764)
		(width 0.1143)
		(layer "In11.Cu")
		(net "DMI_CPU0_PCH_RX_C_DN<3>")
	)
	(segment
		(start 362.13923 -77.814424)
		(end 362.136182 -77.800708)
		(width 0.1143)
		(layer "In11.Cu")
		(net "DMI_CPU0_PCH_RX_C_DN<3>")
	)
	(segment
		(start 362.13923 -77.814678)
		(end 362.13923 -77.814424)
		(width 0.1143)
		(layer "In11.Cu")
		(net "DMI_CPU0_PCH_RX_C_DN<3>")
	)
	(segment
		(start 311.18937 -82.504534)
		(end 308.124098 -82.504534)
		(width 0.1143)
		(layer "In11.Cu")
		(net "DMI_CPU0_PCH_RX_C_DN<3>")
	)
	(segment
		(start 358.641142 -74.40422)
		(end 356.779576 -74.77633)
		(width 0.1143)
		(layer "In11.Cu")
		(net "DMI_CPU0_PCH_RX_C_DN<3>")
	)
	(segment
		(start 359.9942 -94.106746)
		(end 359.720134 -93.83268)
		(width 0.1143)
		(layer "In11.Cu")
		(net "DMI_CPU0_PCH_RX_C_DN<3>")
	)
	(segment
		(start 359.995724 -92.818204)
		(end 360.167682 -92.78366)
		(width 0.1143)
		(layer "In11.Cu")
		(net "DMI_CPU0_PCH_RX_C_DN<3>")
	)
	(segment
		(start 298.730162 -86.3092)
		(end 298.725336 -86.317836)
		(width 0.0889)
		(layer "In11.Cu")
		(net "DMI_CPU0_PCH_RX_C_DN<3>")
	)
	(segment
		(start 356.779576 -74.77633)
		(end 354.262944 -74.272648)
		(width 0.1143)
		(layer "In11.Cu")
		(net "DMI_CPU0_PCH_RX_C_DN<3>")
	)
	(segment
		(start 300.106842 -84.536788)
		(end 300.074076 -84.536788)
		(width 0.0889)
		(layer "In11.Cu")
		(net "DMI_CPU0_PCH_RX_C_DN<3>")
	)
	(segment
		(start 360.81081 -93.932502)
		(end 360.636566 -94.106746)
		(width 0.1143)
		(layer "In11.Cu")
		(net "DMI_CPU0_PCH_RX_C_DN<3>")
	)
	(segment
		(start 341.194644 -74.169524)
		(end 338.132928 -75.439524)
		(width 0.1143)
		(layer "In11.Cu")
		(net "DMI_CPU0_PCH_RX_C_DN<3>")
	)
	(segment
		(start 311.194958 -82.510122)
		(end 311.18937 -82.504534)
		(width 0.1143)
		(layer "In11.Cu")
		(net "DMI_CPU0_PCH_RX_C_DN<3>")
	)
	(segment
		(start 359.720134 -93.83268)
		(end 359.6132 -93.575886)
		(width 0.1143)
		(layer "In11.Cu")
		(net "DMI_CPU0_PCH_RX_C_DN<3>")
	)
	(segment
		(start 299.215556 -87.203534)
		(end 299.248322 -87.203534)
		(width 0.0889)
		(layer "In11.Cu")
		(net "DMI_CPU0_PCH_RX_C_DN<3>")
	)
	(segment
		(start 361.80522 -76.108052)
		(end 360.981498 -74.872342)
		(width 0.1143)
		(layer "In11.Cu")
		(net "DMI_CPU0_PCH_RX_C_DN<3>")
	)
	(segment
		(start 300.969172 -84.041234)
		(end 300.936406 -84.041234)
		(width 0.0889)
		(layer "In11.Cu")
		(net "DMI_CPU0_PCH_RX_C_DN<3>")
	)
	(segment
		(start 361.15117 -82.72526)
		(end 361.83316 -79.316072)
		(width 0.1143)
		(layer "In11.Cu")
		(net "DMI_CPU0_PCH_RX_C_DN<3>")
	)
	(segment
		(start 348.476824 -73.897998)
		(end 345.457018 -74.502264)
		(width 0.1143)
		(layer "In11.Cu")
		(net "DMI_CPU0_PCH_RX_C_DN<3>")
	)
	(segment
		(start 361.597956 -90.853006)
		(end 362.072428 -88.476582)
		(width 0.1143)
		(layer "In11.Cu")
		(net "DMI_CPU0_PCH_RX_C_DN<3>")
	)
	(segment
		(start 361.351576 -84.873846)
		(end 361.466384 -84.302092)
		(width 0.1143)
		(layer "In11.Cu")
		(net "DMI_CPU0_PCH_RX_C_DN<3>")
	)
	(segment
		(start 362.120942 -77.8764)
		(end 362.12399 -77.861668)
		(width 0.1143)
		(layer "In11.Cu")
		(net "DMI_CPU0_PCH_RX_C_DN<3>")
	)
	(segment
		(start 342.494362 -73.909936)
		(end 341.194644 -74.169524)
		(width 0.1143)
		(layer "In11.Cu")
		(net "DMI_CPU0_PCH_RX_C_DN<3>")
	)
	(arc
		(start 301.791116 -83.546188)
		(mid 301.507899 -83.630469)
		(end 301.300896 -83.841336)
		(width 0.0889)
		(layer "In11.Cu")
		(net "DMI_CPU0_PCH_RX_C_DN<3>")
	)
	(arc
		(start 299.583856 -84.831936)
		(mid 299.443777 -84.974672)
		(end 299.252132 -85.031834)
		(width 0.0889)
		(layer "In11.Cu")
		(net "DMI_CPU0_PCH_RX_C_DN<3>")
	)
	(arc
		(start 299.219366 -85.031834)
		(mid 298.721115 -85.334674)
		(end 298.725336 -85.917786)
		(width 0.0889)
		(layer "In11.Cu")
		(net "DMI_CPU0_PCH_RX_C_DN<3>")
	)
	(arc
		(start 303.017936 -82.850736)
		(mid 302.877857 -82.993472)
		(end 302.686212 -83.050634)
		(width 0.0889)
		(layer "In11.Cu")
		(net "DMI_CPU0_PCH_RX_C_DN<3>")
	)
	(arc
		(start 300.074076 -84.536788)
		(mid 299.790859 -84.621069)
		(end 299.583856 -84.831936)
		(width 0.0889)
		(layer "In11.Cu")
		(net "DMI_CPU0_PCH_RX_C_DN<3>")
	)
	(arc
		(start 303.516792 -82.555334)
		(mid 303.228647 -82.637653)
		(end 303.017936 -82.850736)
		(width 0.0889)
		(layer "In11.Cu")
		(net "DMI_CPU0_PCH_RX_C_DN<3>")
	)
	(arc
		(start 303.876456 -82.355182)
		(mid 303.734773 -82.498986)
		(end 303.540922 -82.555334)
		(width 0.0889)
		(layer "In11.Cu")
		(net "DMI_CPU0_PCH_RX_C_DN<3>")
	)
	(arc
		(start 304.900076 -82.355182)
		(mid 304.693072 -82.144318)
		(end 304.409856 -82.060034)
		(width 0.0889)
		(layer "In11.Cu")
		(net "DMI_CPU0_PCH_RX_C_DN<3>")
	)
	(arc
		(start 299.583856 -87.803736)
		(mid 299.504634 -88.092854)
		(end 299.577506 -88.383618)
		(width 0.0889)
		(layer "In11.Cu")
		(net "DMI_CPU0_PCH_RX_C_DN<3>")
	)
	(arc
		(start 300.442376 -84.336636)
		(mid 300.300693 -84.48044)
		(end 300.106842 -84.536788)
		(width 0.0889)
		(layer "In11.Cu")
		(net "DMI_CPU0_PCH_RX_C_DN<3>")
	)
	(arc
		(start 300.936406 -84.041234)
		(mid 300.650982 -84.124701)
		(end 300.442376 -84.336636)
		(width 0.0889)
		(layer "In11.Cu")
		(net "DMI_CPU0_PCH_RX_C_DN<3>")
	)
	(arc
		(start 304.366676 -82.060034)
		(mid 304.083459 -82.144315)
		(end 303.876456 -82.355182)
		(width 0.0889)
		(layer "In11.Cu")
		(net "DMI_CPU0_PCH_RX_C_DN<3>")
	)
	(arc
		(start 299.248322 -87.203534)
		(mid 299.586491 -87.408332)
		(end 299.583856 -87.803736)
		(width 0.0889)
		(layer "In11.Cu")
		(net "DMI_CPU0_PCH_RX_C_DN<3>")
	)
	(arc
		(start 298.725336 -85.917786)
		(mid 298.778806 -86.112849)
		(end 298.730162 -86.3092)
		(width 0.0889)
		(layer "In11.Cu")
		(net "DMI_CPU0_PCH_RX_C_DN<3>")
	)
	(arc
		(start 302.653446 -83.050634)
		(mid 302.368022 -83.134101)
		(end 302.159416 -83.346036)
		(width 0.0889)
		(layer "In11.Cu")
		(net "DMI_CPU0_PCH_RX_C_DN<3>")
	)
	(arc
		(start 305.23561 -82.555334)
		(mid 305.04176 -82.498984)
		(end 304.900076 -82.355182)
		(width 0.0889)
		(layer "In11.Cu")
		(net "DMI_CPU0_PCH_RX_C_DN<3>")
	)
	(arc
		(start 301.300896 -83.841336)
		(mid 301.160817 -83.984072)
		(end 300.969172 -84.041234)
		(width 0.0889)
		(layer "In11.Cu")
		(net "DMI_CPU0_PCH_RX_C_DN<3>")
	)
	(arc
		(start 298.718986 -86.328504)
		(mid 298.723017 -86.904686)
		(end 299.215556 -87.203534)
		(width 0.0889)
		(layer "In11.Cu")
		(net "DMI_CPU0_PCH_RX_C_DN<3>")
	)
	(arc
		(start 299.588682 -88.402922)
		(mid 299.595094 -88.773158)
		(end 299.295058 -88.99017)
		(width 0.0889)
		(layer "In11.Cu")
		(net "DMI_CPU0_PCH_RX_C_DN<3>")
	)
	(arc
		(start 302.159416 -83.346036)
		(mid 302.017733 -83.48984)
		(end 301.823882 -83.546188)
		(width 0.0889)
		(layer "In11.Cu")
		(net "DMI_CPU0_PCH_RX_C_DN<3>")
	)
	(segment
		(start 297.807126 -88.099138)
		(end 298.378626 -88.099138)
		(width 0.1143)
		(layer "F.Cu")
		(net "DMI_CPU0_PCH_RX_C_DN<2>")
	)
	(via
		(at 298.378626 -88.099138)
		(size 0.508)
		(drill 0.254)
		(layers "F.Cu" "B.Cu")
		(net "DMI_CPU0_PCH_RX_C_DN<2>")
	)
	(via
		(at 360.69905 -97.37725)
		(size 0.508)
		(drill 0.254)
		(layers "F.Cu" "B.Cu")
		(net "DMI_CPU0_PCH_RX_C_DN<2>")
	)
	(segment
		(start 361.776264 -97.230184)
		(end 361.186476 -96.8629)
		(width 0.1143)
		(layer "B.Cu")
		(net "DMI_CPU0_PCH_RX_C_DN<2>")
	)
	(segment
		(start 362.393992 -101.261164)
		(end 362.788708 -99.288092)
		(width 0.1143)
		(layer "B.Cu")
		(net "DMI_CPU0_PCH_RX_C_DN<2>")
	)
	(segment
		(start 364.5027 -111.84255)
		(end 362.708952 -111.84255)
		(width 0.1143)
		(layer "B.Cu")
		(net "DMI_CPU0_PCH_RX_C_DN<2>")
	)
	(segment
		(start 360.81335 -96.8629)
		(end 360.69905 -96.9772)
		(width 0.1143)
		(layer "B.Cu")
		(net "DMI_CPU0_PCH_RX_C_DN<2>")
	)
	(segment
		(start 362.228892 -111.17707)
		(end 361.86237 -109.34446)
		(width 0.1143)
		(layer "B.Cu")
		(net "DMI_CPU0_PCH_RX_C_DN<2>")
	)
	(segment
		(start 361.86237 -109.34446)
		(end 362.605828 -105.62717)
		(width 0.1143)
		(layer "B.Cu")
		(net "DMI_CPU0_PCH_RX_C_DN<2>")
	)
	(segment
		(start 364.617 -112.395)
		(end 364.617 -111.95685)
		(width 0.1143)
		(layer "B.Cu")
		(net "DMI_CPU0_PCH_RX_C_DN<2>")
	)
	(segment
		(start 362.708952 -111.84255)
		(end 362.39577 -111.529622)
		(width 0.1143)
		(layer "B.Cu")
		(net "DMI_CPU0_PCH_RX_C_DN<2>")
	)
	(segment
		(start 362.063284 -102.914704)
		(end 362.393992 -101.261164)
		(width 0.1143)
		(layer "B.Cu")
		(net "DMI_CPU0_PCH_RX_C_DN<2>")
	)
	(segment
		(start 362.39577 -111.529622)
		(end 362.228892 -111.17707)
		(width 0.1143)
		(layer "B.Cu")
		(net "DMI_CPU0_PCH_RX_C_DN<2>")
	)
	(segment
		(start 361.186476 -96.8629)
		(end 360.81335 -96.8629)
		(width 0.1143)
		(layer "B.Cu")
		(net "DMI_CPU0_PCH_RX_C_DN<2>")
	)
	(segment
		(start 362.605828 -105.62717)
		(end 362.063284 -102.914704)
		(width 0.1143)
		(layer "B.Cu")
		(net "DMI_CPU0_PCH_RX_C_DN<2>")
	)
	(segment
		(start 360.69905 -96.9772)
		(end 360.69905 -97.37725)
		(width 0.1143)
		(layer "B.Cu")
		(net "DMI_CPU0_PCH_RX_C_DN<2>")
	)
	(segment
		(start 364.617 -111.95685)
		(end 364.5027 -111.84255)
		(width 0.1143)
		(layer "B.Cu")
		(net "DMI_CPU0_PCH_RX_C_DN<2>")
	)
	(segment
		(start 362.788708 -99.288092)
		(end 361.776264 -97.230184)
		(width 0.1143)
		(layer "B.Cu")
		(net "DMI_CPU0_PCH_RX_C_DN<2>")
	)
	(segment
		(start 362.400342 -85.486494)
		(end 362.400088 -85.487002)
		(width 0.1143)
		(layer "In11.Cu")
		(net "DMI_CPU0_PCH_RX_C_DN<2>")
	)
	(segment
		(start 304.054002 -81.055464)
		(end 306.34305 -81.055464)
		(width 0.0889)
		(layer "In11.Cu")
		(net "DMI_CPU0_PCH_RX_C_DN<2>")
	)
	(segment
		(start 362.88599 -87.916258)
		(end 362.02747 -92.208604)
		(width 0.1143)
		(layer "In11.Cu")
		(net "DMI_CPU0_PCH_RX_C_DN<2>")
	)
	(segment
		(start 299.219366 -84.041234)
		(end 299.252132 -84.041234)
		(width 0.0889)
		(layer "In11.Cu")
		(net "DMI_CPU0_PCH_RX_C_DN<2>")
	)
	(segment
		(start 329.71613 -82.008472)
		(end 335.556352 -78.115668)
		(width 0.1143)
		(layer "In11.Cu")
		(net "DMI_CPU0_PCH_RX_C_DN<2>")
	)
	(segment
		(start 297.871642 -85.431122)
		(end 297.866816 -85.422486)
		(width 0.0889)
		(layer "In11.Cu")
		(net "DMI_CPU0_PCH_RX_C_DN<2>")
	)
	(segment
		(start 301.799752 -82.555334)
		(end 301.823882 -82.555334)
		(width 0.0889)
		(layer "In11.Cu")
		(net "DMI_CPU0_PCH_RX_C_DN<2>")
	)
	(segment
		(start 361.985306 -75.031346)
		(end 361.985306 -75.0316)
		(width 0.1143)
		(layer "In11.Cu")
		(net "DMI_CPU0_PCH_RX_C_DN<2>")
	)
	(segment
		(start 306.95519 -81.667604)
		(end 310.238902 -81.667604)
		(width 0.0889)
		(layer "In11.Cu")
		(net "DMI_CPU0_PCH_RX_C_DN<2>")
	)
	(segment
		(start 298.378626 -88.099138)
		(end 298.671742 -87.929974)
		(width 0.0889)
		(layer "In11.Cu")
		(net "DMI_CPU0_PCH_RX_C_DN<2>")
	)
	(segment
		(start 303.876456 -81.364836)
		(end 304.054002 -81.055464)
		(width 0.0889)
		(layer "In11.Cu")
		(net "DMI_CPU0_PCH_RX_C_DN<2>")
	)
	(segment
		(start 300.074076 -83.546188)
		(end 300.106842 -83.546188)
		(width 0.0889)
		(layer "In11.Cu")
		(net "DMI_CPU0_PCH_RX_C_DN<2>")
	)
	(segment
		(start 356.940866 -74.0791)
		(end 358.686354 -73.730104)
		(width 0.1143)
		(layer "In11.Cu")
		(net "DMI_CPU0_PCH_RX_C_DN<2>")
	)
	(segment
		(start 310.289702 -81.616804)
		(end 311.12841 -81.616804)
		(width 0.1143)
		(layer "In11.Cu")
		(net "DMI_CPU0_PCH_RX_C_DN<2>")
	)
	(segment
		(start 337.461352 -75.257406)
		(end 338.229448 -73.575672)
		(width 0.1143)
		(layer "In11.Cu")
		(net "DMI_CPU0_PCH_RX_C_DN<2>")
	)
	(segment
		(start 302.649636 -82.060034)
		(end 302.682402 -82.060034)
		(width 0.0889)
		(layer "In11.Cu")
		(net "DMI_CPU0_PCH_RX_C_DN<2>")
	)
	(segment
		(start 338.229448 -73.575672)
		(end 338.67344 -73.279762)
		(width 0.1143)
		(layer "In11.Cu")
		(net "DMI_CPU0_PCH_RX_C_DN<2>")
	)
	(segment
		(start 335.556352 -78.115668)
		(end 337.461352 -75.258168)
		(width 0.1143)
		(layer "In11.Cu")
		(net "DMI_CPU0_PCH_RX_C_DN<2>")
	)
	(segment
		(start 340.76767 -73.284842)
		(end 341.919814 -73.05421)
		(width 0.1143)
		(layer "In11.Cu")
		(net "DMI_CPU0_PCH_RX_C_DN<2>")
	)
	(segment
		(start 362.553758 -76.612242)
		(end 362.799122 -77.837792)
		(width 0.1143)
		(layer "In11.Cu")
		(net "DMI_CPU0_PCH_RX_C_DN<2>")
	)
	(segment
		(start 362.660946 -95.373952)
		(end 361.890818 -96.528382)
		(width 0.1143)
		(layer "In11.Cu")
		(net "DMI_CPU0_PCH_RX_C_DN<2>")
	)
	(segment
		(start 362.400088 -85.487002)
		(end 362.88599 -87.916258)
		(width 0.1143)
		(layer "In11.Cu")
		(net "DMI_CPU0_PCH_RX_C_DN<2>")
	)
	(segment
		(start 360.83875 -96.9645)
		(end 360.69905 -97.1042)
		(width 0.1143)
		(layer "In11.Cu")
		(net "DMI_CPU0_PCH_RX_C_DN<2>")
	)
	(segment
		(start 361.834684 -82.660236)
		(end 362.400342 -85.486494)
		(width 0.1143)
		(layer "In11.Cu")
		(net "DMI_CPU0_PCH_RX_C_DN<2>")
	)
	(segment
		(start 358.686354 -73.730104)
		(end 361.492038 -74.291444)
		(width 0.1143)
		(layer "In11.Cu")
		(net "DMI_CPU0_PCH_RX_C_DN<2>")
	)
	(segment
		(start 338.730082 -73.268586)
		(end 339.707474 -73.072752)
		(width 0.1143)
		(layer "In11.Cu")
		(net "DMI_CPU0_PCH_RX_C_DN<2>")
	)
	(segment
		(start 361.890818 -96.528382)
		(end 361.4547 -96.9645)
		(width 0.1143)
		(layer "In11.Cu")
		(net "DMI_CPU0_PCH_RX_C_DN<2>")
	)
	(segment
		(start 338.730082 -73.268332)
		(end 338.730082 -73.268586)
		(width 0.1143)
		(layer "In11.Cu")
		(net "DMI_CPU0_PCH_RX_C_DN<2>")
	)
	(segment
		(start 297.866816 -85.422486)
		(end 297.860466 -85.411818)
		(width 0.0889)
		(layer "In11.Cu")
		(net "DMI_CPU0_PCH_RX_C_DN<2>")
	)
	(segment
		(start 361.492038 -74.291444)
		(end 361.985306 -75.031346)
		(width 0.1143)
		(layer "In11.Cu")
		(net "DMI_CPU0_PCH_RX_C_DN<2>")
	)
	(segment
		(start 362.345732 -75.572112)
		(end 362.553758 -76.612242)
		(width 0.1143)
		(layer "In11.Cu")
		(net "DMI_CPU0_PCH_RX_C_DN<2>")
	)
	(segment
		(start 361.985306 -75.0316)
		(end 362.345732 -75.572112)
		(width 0.1143)
		(layer "In11.Cu")
		(net "DMI_CPU0_PCH_RX_C_DN<2>")
	)
	(segment
		(start 338.67344 -73.279762)
		(end 338.730082 -73.268332)
		(width 0.1143)
		(layer "In11.Cu")
		(net "DMI_CPU0_PCH_RX_C_DN<2>")
	)
	(segment
		(start 298.671742 -87.929974)
		(end 298.692824 -87.851234)
		(width 0.0889)
		(layer "In11.Cu")
		(net "DMI_CPU0_PCH_RX_C_DN<2>")
	)
	(segment
		(start 311.12841 -81.616804)
		(end 321.403726 -83.671156)
		(width 0.1143)
		(layer "In11.Cu")
		(net "DMI_CPU0_PCH_RX_C_DN<2>")
	)
	(segment
		(start 362.799122 -77.837792)
		(end 361.834684 -82.660236)
		(width 0.1143)
		(layer "In11.Cu")
		(net "DMI_CPU0_PCH_RX_C_DN<2>")
	)
	(segment
		(start 297.866816 -87.403686)
		(end 297.860466 -87.393018)
		(width 0.0889)
		(layer "In11.Cu")
		(net "DMI_CPU0_PCH_RX_C_DN<2>")
	)
	(segment
		(start 337.461352 -75.258168)
		(end 337.461606 -75.257406)
		(width 0.1143)
		(layer "In11.Cu")
		(net "DMI_CPU0_PCH_RX_C_DN<2>")
	)
	(segment
		(start 361.4547 -96.9645)
		(end 360.83875 -96.9645)
		(width 0.1143)
		(layer "In11.Cu")
		(net "DMI_CPU0_PCH_RX_C_DN<2>")
	)
	(segment
		(start 345.397328 -73.749662)
		(end 348.460314 -73.137014)
		(width 0.1143)
		(layer "In11.Cu")
		(net "DMI_CPU0_PCH_RX_C_DN<2>")
	)
	(segment
		(start 297.871642 -86.421722)
		(end 297.866816 -86.413086)
		(width 0.0889)
		(layer "In11.Cu")
		(net "DMI_CPU0_PCH_RX_C_DN<2>")
	)
	(segment
		(start 300.936406 -83.050634)
		(end 300.969172 -83.050634)
		(width 0.0889)
		(layer "In11.Cu")
		(net "DMI_CPU0_PCH_RX_C_DN<2>")
	)
	(segment
		(start 339.707474 -73.072752)
		(end 340.76767 -73.284842)
		(width 0.1143)
		(layer "In11.Cu")
		(net "DMI_CPU0_PCH_RX_C_DN<2>")
	)
	(segment
		(start 297.866816 -86.413086)
		(end 297.860466 -86.402418)
		(width 0.0889)
		(layer "In11.Cu")
		(net "DMI_CPU0_PCH_RX_C_DN<2>")
	)
	(segment
		(start 321.403726 -83.671156)
		(end 329.71613 -82.008472)
		(width 0.1143)
		(layer "In11.Cu")
		(net "DMI_CPU0_PCH_RX_C_DN<2>")
	)
	(segment
		(start 354.21443 -73.533508)
		(end 356.940866 -74.0791)
		(width 0.1143)
		(layer "In11.Cu")
		(net "DMI_CPU0_PCH_RX_C_DN<2>")
	)
	(segment
		(start 352.32848 -73.910698)
		(end 354.21443 -73.533508)
		(width 0.1143)
		(layer "In11.Cu")
		(net "DMI_CPU0_PCH_RX_C_DN<2>")
	)
	(segment
		(start 341.919814 -73.05421)
		(end 345.397328 -73.749662)
		(width 0.1143)
		(layer "In11.Cu")
		(net "DMI_CPU0_PCH_RX_C_DN<2>")
	)
	(segment
		(start 337.461606 -75.257406)
		(end 337.461352 -75.257406)
		(width 0.1143)
		(layer "In11.Cu")
		(net "DMI_CPU0_PCH_RX_C_DN<2>")
	)
	(segment
		(start 310.238902 -81.667604)
		(end 310.289702 -81.616804)
		(width 0.0889)
		(layer "In11.Cu")
		(net "DMI_CPU0_PCH_RX_C_DN<2>")
	)
	(segment
		(start 298.393612 -87.699088)
		(end 298.360846 -87.699088)
		(width 0.0889)
		(layer "In11.Cu")
		(net "DMI_CPU0_PCH_RX_C_DN<2>")
	)
	(segment
		(start 348.460314 -73.137014)
		(end 352.32848 -73.910698)
		(width 0.1143)
		(layer "In11.Cu")
		(net "DMI_CPU0_PCH_RX_C_DN<2>")
	)
	(segment
		(start 360.69905 -97.1042)
		(end 360.69905 -97.37725)
		(width 0.1143)
		(layer "In11.Cu")
		(net "DMI_CPU0_PCH_RX_C_DN<2>")
	)
	(segment
		(start 303.508156 -81.564734)
		(end 303.54778 -81.564734)
		(width 0.0889)
		(layer "In11.Cu")
		(net "DMI_CPU0_PCH_RX_C_DN<2>")
	)
	(segment
		(start 298.357036 -84.536788)
		(end 298.389802 -84.536788)
		(width 0.0889)
		(layer "In11.Cu")
		(net "DMI_CPU0_PCH_RX_C_DN<2>")
	)
	(segment
		(start 362.02747 -92.208604)
		(end 362.660946 -95.373952)
		(width 0.1143)
		(layer "In11.Cu")
		(net "DMI_CPU0_PCH_RX_C_DN<2>")
	)
	(segment
		(start 306.34305 -81.055464)
		(end 306.95519 -81.667604)
		(width 0.0889)
		(layer "In11.Cu")
		(net "DMI_CPU0_PCH_RX_C_DN<2>")
	)
	(arc
		(start 302.682402 -82.060034)
		(mid 302.876252 -82.003684)
		(end 303.017936 -81.859882)
		(width 0.0889)
		(layer "In11.Cu")
		(net "DMI_CPU0_PCH_RX_C_DN<2>")
	)
	(arc
		(start 299.252132 -84.041234)
		(mid 299.443774 -83.984068)
		(end 299.583856 -83.841336)
		(width 0.0889)
		(layer "In11.Cu")
		(net "DMI_CPU0_PCH_RX_C_DN<2>")
	)
	(arc
		(start 298.389802 -84.536788)
		(mid 298.583652 -84.480438)
		(end 298.725336 -84.336636)
		(width 0.0889)
		(layer "In11.Cu")
		(net "DMI_CPU0_PCH_RX_C_DN<2>")
	)
	(arc
		(start 298.725336 -84.336636)
		(mid 298.933944 -84.124704)
		(end 299.219366 -84.041234)
		(width 0.0889)
		(layer "In11.Cu")
		(net "DMI_CPU0_PCH_RX_C_DN<2>")
	)
	(arc
		(start 300.442376 -83.346036)
		(mid 300.650984 -83.134104)
		(end 300.936406 -83.050634)
		(width 0.0889)
		(layer "In11.Cu")
		(net "DMI_CPU0_PCH_RX_C_DN<2>")
	)
	(arc
		(start 297.860466 -86.402418)
		(mid 297.787668 -86.111655)
		(end 297.866816 -85.822536)
		(width 0.0889)
		(layer "In11.Cu")
		(net "DMI_CPU0_PCH_RX_C_DN<2>")
	)
	(arc
		(start 300.969172 -83.050634)
		(mid 301.160814 -82.993468)
		(end 301.300896 -82.850736)
		(width 0.0889)
		(layer "In11.Cu")
		(net "DMI_CPU0_PCH_RX_C_DN<2>")
	)
	(arc
		(start 299.583856 -83.841336)
		(mid 299.79086 -83.630472)
		(end 300.074076 -83.546188)
		(width 0.0889)
		(layer "In11.Cu")
		(net "DMI_CPU0_PCH_RX_C_DN<2>")
	)
	(arc
		(start 297.866816 -86.813136)
		(mid 297.920286 -86.618073)
		(end 297.871642 -86.421722)
		(width 0.0889)
		(layer "In11.Cu")
		(net "DMI_CPU0_PCH_RX_C_DN<2>")
	)
	(arc
		(start 297.866816 -85.822536)
		(mid 297.920286 -85.627473)
		(end 297.871642 -85.431122)
		(width 0.0889)
		(layer "In11.Cu")
		(net "DMI_CPU0_PCH_RX_C_DN<2>")
	)
	(arc
		(start 298.692824 -87.851234)
		(mid 298.559943 -87.742251)
		(end 298.393612 -87.699088)
		(width 0.0889)
		(layer "In11.Cu")
		(net "DMI_CPU0_PCH_RX_C_DN<2>")
	)
	(arc
		(start 297.860466 -85.411818)
		(mid 297.864497 -84.835636)
		(end 298.357036 -84.536788)
		(width 0.0889)
		(layer "In11.Cu")
		(net "DMI_CPU0_PCH_RX_C_DN<2>")
	)
	(arc
		(start 303.017936 -81.859882)
		(mid 303.22494 -81.649018)
		(end 303.508156 -81.564734)
		(width 0.0889)
		(layer "In11.Cu")
		(net "DMI_CPU0_PCH_RX_C_DN<2>")
	)
	(arc
		(start 301.300896 -82.850736)
		(mid 301.511609 -82.637657)
		(end 301.799752 -82.555334)
		(width 0.0889)
		(layer "In11.Cu")
		(net "DMI_CPU0_PCH_RX_C_DN<2>")
	)
	(arc
		(start 302.159416 -82.355182)
		(mid 302.36642 -82.144318)
		(end 302.649636 -82.060034)
		(width 0.0889)
		(layer "In11.Cu")
		(net "DMI_CPU0_PCH_RX_C_DN<2>")
	)
	(arc
		(start 301.823882 -82.555334)
		(mid 302.017732 -82.498984)
		(end 302.159416 -82.355182)
		(width 0.0889)
		(layer "In11.Cu")
		(net "DMI_CPU0_PCH_RX_C_DN<2>")
	)
	(arc
		(start 303.54778 -81.564734)
		(mid 303.737709 -81.506864)
		(end 303.876456 -81.364836)
		(width 0.0889)
		(layer "In11.Cu")
		(net "DMI_CPU0_PCH_RX_C_DN<2>")
	)
	(arc
		(start 297.860466 -87.393018)
		(mid 297.787668 -87.102255)
		(end 297.866816 -86.813136)
		(width 0.0889)
		(layer "In11.Cu")
		(net "DMI_CPU0_PCH_RX_C_DN<2>")
	)
	(arc
		(start 300.106842 -83.546188)
		(mid 300.300692 -83.489838)
		(end 300.442376 -83.346036)
		(width 0.0889)
		(layer "In11.Cu")
		(net "DMI_CPU0_PCH_RX_C_DN<2>")
	)
	(arc
		(start 298.360846 -87.699088)
		(mid 298.075422 -87.615621)
		(end 297.866816 -87.403686)
		(width 0.0889)
		(layer "In11.Cu")
		(net "DMI_CPU0_PCH_RX_C_DN<2>")
	)
	(segment
		(start 298.665646 -86.612984)
		(end 299.237146 -86.612984)
		(width 0.1143)
		(layer "F.Cu")
		(net "DMI_CPU0_PCH_RX_C_DN<1>")
	)
	(via
		(at 299.237146 -86.612984)
		(size 0.508)
		(drill 0.254)
		(layers "F.Cu" "B.Cu")
		(net "DMI_CPU0_PCH_RX_C_DN<1>")
	)
	(via
		(at 359.08869 -99.390708)
		(size 0.508)
		(drill 0.254)
		(layers "F.Cu" "B.Cu")
		(net "DMI_CPU0_PCH_RX_C_DN<1>")
	)
	(segment
		(start 364.5027 -114.36985)
		(end 362.715048 -114.36985)
		(width 0.1143)
		(layer "B.Cu")
		(net "DMI_CPU0_PCH_RX_C_DN<1>")
	)
	(segment
		(start 360.322368 -101.261164)
		(end 360.167682 -100.724462)
		(width 0.1143)
		(layer "B.Cu")
		(net "DMI_CPU0_PCH_RX_C_DN<1>")
	)
	(segment
		(start 362.715048 -114.36985)
		(end 361.001818 -113.056162)
		(width 0.1143)
		(layer "B.Cu")
		(net "DMI_CPU0_PCH_RX_C_DN<1>")
	)
	(segment
		(start 359.5624 -99.905566)
		(end 359.286302 -99.905566)
		(width 0.1143)
		(layer "B.Cu")
		(net "DMI_CPU0_PCH_RX_C_DN<1>")
	)
	(segment
		(start 360.554778 -106.41584)
		(end 360.7054 -105.663238)
		(width 0.1143)
		(layer "B.Cu")
		(net "DMI_CPU0_PCH_RX_C_DN<1>")
	)
	(segment
		(start 360.15168 -100.668836)
		(end 359.5624 -99.905566)
		(width 0.1143)
		(layer "B.Cu")
		(net "DMI_CPU0_PCH_RX_C_DN<1>")
	)
	(segment
		(start 360.167682 -102.240842)
		(end 360.346752 -101.345746)
		(width 0.1143)
		(layer "B.Cu")
		(net "DMI_CPU0_PCH_RX_C_DN<1>")
	)
	(segment
		(start 359.286302 -99.905566)
		(end 359.08869 -99.707954)
		(width 0.1143)
		(layer "B.Cu")
		(net "DMI_CPU0_PCH_RX_C_DN<1>")
	)
	(segment
		(start 361.001818 -113.056162)
		(end 359.878884 -109.795818)
		(width 0.1143)
		(layer "B.Cu")
		(net "DMI_CPU0_PCH_RX_C_DN<1>")
	)
	(segment
		(start 359.878884 -109.795818)
		(end 360.554778 -106.41584)
		(width 0.1143)
		(layer "B.Cu")
		(net "DMI_CPU0_PCH_RX_C_DN<1>")
	)
	(segment
		(start 364.617 -114.25555)
		(end 364.5027 -114.36985)
		(width 0.1143)
		(layer "B.Cu")
		(net "DMI_CPU0_PCH_RX_C_DN<1>")
	)
	(segment
		(start 360.167682 -100.724462)
		(end 360.15168 -100.668836)
		(width 0.1143)
		(layer "B.Cu")
		(net "DMI_CPU0_PCH_RX_C_DN<1>")
	)
	(segment
		(start 364.617 -113.792)
		(end 364.617 -114.25555)
		(width 0.1143)
		(layer "B.Cu")
		(net "DMI_CPU0_PCH_RX_C_DN<1>")
	)
	(segment
		(start 360.094276 -102.607618)
		(end 360.167682 -102.240842)
		(width 0.1143)
		(layer "B.Cu")
		(net "DMI_CPU0_PCH_RX_C_DN<1>")
	)
	(segment
		(start 359.08869 -99.707954)
		(end 359.08869 -99.390708)
		(width 0.1143)
		(layer "B.Cu")
		(net "DMI_CPU0_PCH_RX_C_DN<1>")
	)
	(segment
		(start 360.7054 -105.663238)
		(end 360.094276 -102.607618)
		(width 0.1143)
		(layer "B.Cu")
		(net "DMI_CPU0_PCH_RX_C_DN<1>")
	)
	(segment
		(start 360.346752 -101.345746)
		(end 360.322368 -101.261164)
		(width 0.1143)
		(layer "B.Cu")
		(net "DMI_CPU0_PCH_RX_C_DN<1>")
	)
	(segment
		(start 310.931052 -83.9851)
		(end 310.93664 -83.990688)
		(width 0.1143)
		(layer "In11.Cu")
		(net "DMI_CPU0_PCH_RX_C_DN<1>")
	)
	(segment
		(start 320.994278 -86.002622)
		(end 340.574376 -82.08645)
		(width 0.1143)
		(layer "In11.Cu")
		(net "DMI_CPU0_PCH_RX_C_DN<1>")
	)
	(segment
		(start 345.703652 -82.261456)
		(end 347.277436 -82.576416)
		(width 0.1143)
		(layer "In11.Cu")
		(net "DMI_CPU0_PCH_RX_C_DN<1>")
	)
	(segment
		(start 352.475292 -82.040222)
		(end 353.614736 -81.81213)
		(width 0.1143)
		(layer "In11.Cu")
		(net "DMI_CPU0_PCH_RX_C_DN<1>")
	)
	(segment
		(start 351.18167 -82.902552)
		(end 352.475292 -82.040222)
		(width 0.1143)
		(layer "In11.Cu")
		(net "DMI_CPU0_PCH_RX_C_DN<1>")
	)
	(segment
		(start 357.998014 -96.598232)
		(end 357.695754 -98.109532)
		(width 0.1143)
		(layer "In11.Cu")
		(net "DMI_CPU0_PCH_RX_C_DN<1>")
	)
	(segment
		(start 299.237146 -86.612984)
		(end 299.530262 -86.782148)
		(width 0.0889)
		(layer "In11.Cu")
		(net "DMI_CPU0_PCH_RX_C_DN<1>")
	)
	(segment
		(start 357.994204 -99.600258)
		(end 358.197404 -99.803458)
		(width 0.1143)
		(layer "In11.Cu")
		(net "DMI_CPU0_PCH_RX_C_DN<1>")
	)
	(segment
		(start 358.913938 -84.953348)
		(end 359.315004 -86.957916)
		(width 0.1143)
		(layer "In11.Cu")
		(net "DMI_CPU0_PCH_RX_C_DN<1>")
	)
	(segment
		(start 300.9392 -87.013034)
		(end 300.969172 -87.013034)
		(width 0.0889)
		(layer "In11.Cu")
		(net "DMI_CPU0_PCH_RX_C_DN<1>")
	)
	(segment
		(start 310.93664 -83.990688)
		(end 320.994278 -86.002622)
		(width 0.1143)
		(layer "In11.Cu")
		(net "DMI_CPU0_PCH_RX_C_DN<1>")
	)
	(segment
		(start 353.614736 -81.81213)
		(end 355.650292 -82.219292)
		(width 0.1143)
		(layer "In11.Cu")
		(net "DMI_CPU0_PCH_RX_C_DN<1>")
	)
	(segment
		(start 304.370486 -84.041234)
		(end 304.405792 -84.041234)
		(width 0.0889)
		(layer "In11.Cu")
		(net "DMI_CPU0_PCH_RX_C_DN<1>")
	)
	(segment
		(start 358.197404 -99.803458)
		(end 358.67594 -99.803458)
		(width 0.1143)
		(layer "In11.Cu")
		(net "DMI_CPU0_PCH_RX_C_DN<1>")
	)
	(segment
		(start 303.508156 -85.527388)
		(end 303.540922 -85.527388)
		(width 0.0889)
		(layer "In11.Cu")
		(net "DMI_CPU0_PCH_RX_C_DN<1>")
	)
	(segment
		(start 303.876456 -85.327236)
		(end 303.881282 -85.3186)
		(width 0.0889)
		(layer "In11.Cu")
		(net "DMI_CPU0_PCH_RX_C_DN<1>")
	)
	(segment
		(start 340.574376 -82.08645)
		(end 343.576148 -82.686652)
		(width 0.1143)
		(layer "In11.Cu")
		(net "DMI_CPU0_PCH_RX_C_DN<1>")
	)
	(segment
		(start 358.246426 -83.951572)
		(end 358.913938 -84.953348)
		(width 0.1143)
		(layer "In11.Cu")
		(net "DMI_CPU0_PCH_RX_C_DN<1>")
	)
	(segment
		(start 357.416354 -93.690694)
		(end 357.998014 -96.598232)
		(width 0.1143)
		(layer "In11.Cu")
		(net "DMI_CPU0_PCH_RX_C_DN<1>")
	)
	(segment
		(start 358.482138 -91.124024)
		(end 357.416354 -93.690694)
		(width 0.1143)
		(layer "In11.Cu")
		(net "DMI_CPU0_PCH_RX_C_DN<1>")
	)
	(segment
		(start 308.167532 -84.0359)
		(end 308.218332 -83.9851)
		(width 0.0889)
		(layer "In11.Cu")
		(net "DMI_CPU0_PCH_RX_C_DN<1>")
	)
	(segment
		(start 306.471574 -84.0359)
		(end 308.167532 -84.0359)
		(width 0.0889)
		(layer "In11.Cu")
		(net "DMI_CPU0_PCH_RX_C_DN<1>")
	)
	(segment
		(start 350.86671 -82.965798)
		(end 351.18167 -82.902552)
		(width 0.1143)
		(layer "In11.Cu")
		(net "DMI_CPU0_PCH_RX_C_DN<1>")
	)
	(segment
		(start 343.576148 -82.686652)
		(end 345.703652 -82.261456)
		(width 0.1143)
		(layer "In11.Cu")
		(net "DMI_CPU0_PCH_RX_C_DN<1>")
	)
	(segment
		(start 358.67594 -99.803458)
		(end 359.08869 -99.390708)
		(width 0.1143)
		(layer "In11.Cu")
		(net "DMI_CPU0_PCH_RX_C_DN<1>")
	)
	(segment
		(start 300.074076 -86.517988)
		(end 300.117256 -86.517988)
		(width 0.0889)
		(layer "In11.Cu")
		(net "DMI_CPU0_PCH_RX_C_DN<1>")
	)
	(segment
		(start 347.277436 -82.576416)
		(end 348.098364 -82.412078)
		(width 0.1143)
		(layer "In11.Cu")
		(net "DMI_CPU0_PCH_RX_C_DN<1>")
	)
	(segment
		(start 302.653446 -86.022434)
		(end 302.686212 -86.022434)
		(width 0.0889)
		(layer "In11.Cu")
		(net "DMI_CPU0_PCH_RX_C_DN<1>")
	)
	(segment
		(start 348.098364 -82.412078)
		(end 350.86671 -82.965798)
		(width 0.1143)
		(layer "In11.Cu")
		(net "DMI_CPU0_PCH_RX_C_DN<1>")
	)
	(segment
		(start 304.974752 -83.545934)
		(end 305.981608 -83.545934)
		(width 0.0889)
		(layer "In11.Cu")
		(net "DMI_CPU0_PCH_RX_C_DN<1>")
	)
	(segment
		(start 305.981608 -83.545934)
		(end 306.471574 -84.0359)
		(width 0.0889)
		(layer "In11.Cu")
		(net "DMI_CPU0_PCH_RX_C_DN<1>")
	)
	(segment
		(start 355.650292 -82.219292)
		(end 358.246426 -83.951572)
		(width 0.1143)
		(layer "In11.Cu")
		(net "DMI_CPU0_PCH_RX_C_DN<1>")
	)
	(segment
		(start 308.24043 -83.9851)
		(end 310.931052 -83.9851)
		(width 0.1143)
		(layer "In11.Cu")
		(net "DMI_CPU0_PCH_RX_C_DN<1>")
	)
	(segment
		(start 301.791116 -86.517988)
		(end 301.823882 -86.517988)
		(width 0.0889)
		(layer "In11.Cu")
		(net "DMI_CPU0_PCH_RX_C_DN<1>")
	)
	(segment
		(start 304.811176 -83.70951)
		(end 304.974752 -83.545934)
		(width 0.0889)
		(layer "In11.Cu")
		(net "DMI_CPU0_PCH_RX_C_DN<1>")
	)
	(segment
		(start 357.695754 -98.109532)
		(end 357.994204 -99.600258)
		(width 0.1143)
		(layer "In11.Cu")
		(net "DMI_CPU0_PCH_RX_C_DN<1>")
	)
	(segment
		(start 359.315004 -86.957916)
		(end 358.482138 -91.124024)
		(width 0.1143)
		(layer "In11.Cu")
		(net "DMI_CPU0_PCH_RX_C_DN<1>")
	)
	(segment
		(start 304.734976 -83.841336)
		(end 304.811176 -83.70951)
		(width 0.0889)
		(layer "In11.Cu")
		(net "DMI_CPU0_PCH_RX_C_DN<1>")
	)
	(segment
		(start 299.530262 -86.782148)
		(end 299.61967 -86.758018)
		(width 0.0889)
		(layer "In11.Cu")
		(net "DMI_CPU0_PCH_RX_C_DN<1>")
	)
	(segment
		(start 308.218332 -83.9851)
		(end 308.24043 -83.9851)
		(width 0.0889)
		(layer "In11.Cu")
		(net "DMI_CPU0_PCH_RX_C_DN<1>")
	)
	(arc
		(start 303.540922 -85.527388)
		(mid 303.734772 -85.471038)
		(end 303.876456 -85.327236)
		(width 0.0889)
		(layer "In11.Cu")
		(net "DMI_CPU0_PCH_RX_C_DN<1>")
	)
	(arc
		(start 300.117256 -86.517988)
		(mid 300.400473 -86.602269)
		(end 300.607476 -86.813136)
		(width 0.0889)
		(layer "In11.Cu")
		(net "DMI_CPU0_PCH_RX_C_DN<1>")
	)
	(arc
		(start 299.61967 -86.758018)
		(mid 299.819415 -86.586024)
		(end 300.074076 -86.517988)
		(width 0.0889)
		(layer "In11.Cu")
		(net "DMI_CPU0_PCH_RX_C_DN<1>")
	)
	(arc
		(start 301.823882 -86.517988)
		(mid 302.017732 -86.461638)
		(end 302.159416 -86.317836)
		(width 0.0889)
		(layer "In11.Cu")
		(net "DMI_CPU0_PCH_RX_C_DN<1>")
	)
	(arc
		(start 300.607476 -86.813136)
		(mid 300.747555 -86.955872)
		(end 300.9392 -87.013034)
		(width 0.0889)
		(layer "In11.Cu")
		(net "DMI_CPU0_PCH_RX_C_DN<1>")
	)
	(arc
		(start 302.159416 -86.317836)
		(mid 302.368024 -86.105904)
		(end 302.653446 -86.022434)
		(width 0.0889)
		(layer "In11.Cu")
		(net "DMI_CPU0_PCH_RX_C_DN<1>")
	)
	(arc
		(start 300.969172 -87.013034)
		(mid 301.160814 -86.955868)
		(end 301.300896 -86.813136)
		(width 0.0889)
		(layer "In11.Cu")
		(net "DMI_CPU0_PCH_RX_C_DN<1>")
	)
	(arc
		(start 303.876456 -84.927186)
		(mid 303.872127 -84.344014)
		(end 304.370486 -84.041234)
		(width 0.0889)
		(layer "In11.Cu")
		(net "DMI_CPU0_PCH_RX_C_DN<1>")
	)
	(arc
		(start 304.405792 -84.041234)
		(mid 304.596034 -83.983499)
		(end 304.734976 -83.841336)
		(width 0.0889)
		(layer "In11.Cu")
		(net "DMI_CPU0_PCH_RX_C_DN<1>")
	)
	(arc
		(start 303.017936 -85.822536)
		(mid 303.22494 -85.611672)
		(end 303.508156 -85.527388)
		(width 0.0889)
		(layer "In11.Cu")
		(net "DMI_CPU0_PCH_RX_C_DN<1>")
	)
	(arc
		(start 303.881282 -85.3186)
		(mid 303.930037 -85.122248)
		(end 303.876456 -84.927186)
		(width 0.0889)
		(layer "In11.Cu")
		(net "DMI_CPU0_PCH_RX_C_DN<1>")
	)
	(arc
		(start 301.300896 -86.813136)
		(mid 301.5079 -86.602272)
		(end 301.791116 -86.517988)
		(width 0.0889)
		(layer "In11.Cu")
		(net "DMI_CPU0_PCH_RX_C_DN<1>")
	)
	(arc
		(start 302.686212 -86.022434)
		(mid 302.877854 -85.965268)
		(end 303.017936 -85.822536)
		(width 0.0889)
		(layer "In11.Cu")
		(net "DMI_CPU0_PCH_RX_C_DN<1>")
	)
	(segment
		(start 300.382686 -85.622384)
		(end 300.954186 -85.622384)
		(width 0.1143)
		(layer "F.Cu")
		(net "DMI_CPU0_PCH_RX_C_DN<0>")
	)
	(via
		(at 360.69905 -98.654108)
		(size 0.508)
		(drill 0.254)
		(layers "F.Cu" "B.Cu")
		(net "DMI_CPU0_PCH_RX_C_DN<0>")
	)
	(via
		(at 300.954186 -85.622384)
		(size 0.508)
		(drill 0.254)
		(layers "F.Cu" "B.Cu")
		(net "DMI_CPU0_PCH_RX_C_DN<0>")
	)
	(segment
		(start 361.617006 -106.415332)
		(end 361.035092 -109.866176)
		(width 0.1143)
		(layer "B.Cu")
		(net "DMI_CPU0_PCH_RX_C_DN<0>")
	)
	(segment
		(start 368.415062 -112.98682)
		(end 368.554 -112.847882)
		(width 0.1143)
		(layer "B.Cu")
		(net "DMI_CPU0_PCH_RX_C_DN<0>")
	)
	(segment
		(start 361.570016 -101.261164)
		(end 361.236514 -102.928166)
		(width 0.1143)
		(layer "B.Cu")
		(net "DMI_CPU0_PCH_RX_C_DN<0>")
	)
	(segment
		(start 368.554 -112.847882)
		(end 368.554 -112.395)
		(width 0.1143)
		(layer "B.Cu")
		(net "DMI_CPU0_PCH_RX_C_DN<0>")
	)
	(segment
		(start 361.685078 -111.929926)
		(end 362.741972 -112.98682)
		(width 0.1143)
		(layer "B.Cu")
		(net "DMI_CPU0_PCH_RX_C_DN<0>")
	)
	(segment
		(start 361.236514 -102.928166)
		(end 361.748578 -105.635552)
		(width 0.1143)
		(layer "B.Cu")
		(net "DMI_CPU0_PCH_RX_C_DN<0>")
	)
	(segment
		(start 360.69905 -98.654108)
		(end 360.69905 -99.054158)
		(width 0.1143)
		(layer "B.Cu")
		(net "DMI_CPU0_PCH_RX_C_DN<0>")
	)
	(segment
		(start 361.585764 -99.422458)
		(end 361.60964 -99.469956)
		(width 0.1143)
		(layer "B.Cu")
		(net "DMI_CPU0_PCH_RX_C_DN<0>")
	)
	(segment
		(start 361.748578 -105.635552)
		(end 361.617006 -106.415332)
		(width 0.1143)
		(layer "B.Cu")
		(net "DMI_CPU0_PCH_RX_C_DN<0>")
	)
	(segment
		(start 360.69905 -99.054158)
		(end 360.860086 -99.215194)
		(width 0.1143)
		(layer "B.Cu")
		(net "DMI_CPU0_PCH_RX_C_DN<0>")
	)
	(segment
		(start 361.32389 -99.215194)
		(end 361.585764 -99.422458)
		(width 0.1143)
		(layer "B.Cu")
		(net "DMI_CPU0_PCH_RX_C_DN<0>")
	)
	(segment
		(start 361.035092 -109.866176)
		(end 361.685078 -111.929926)
		(width 0.1143)
		(layer "B.Cu")
		(net "DMI_CPU0_PCH_RX_C_DN<0>")
	)
	(segment
		(start 361.837478 -99.9236)
		(end 361.570016 -101.261164)
		(width 0.1143)
		(layer "B.Cu")
		(net "DMI_CPU0_PCH_RX_C_DN<0>")
	)
	(segment
		(start 362.741972 -112.98682)
		(end 368.415062 -112.98682)
		(width 0.1143)
		(layer "B.Cu")
		(net "DMI_CPU0_PCH_RX_C_DN<0>")
	)
	(segment
		(start 360.860086 -99.215194)
		(end 361.32389 -99.215194)
		(width 0.1143)
		(layer "B.Cu")
		(net "DMI_CPU0_PCH_RX_C_DN<0>")
	)
	(segment
		(start 361.60964 -99.469956)
		(end 361.60964 -99.47021)
		(width 0.1143)
		(layer "B.Cu")
		(net "DMI_CPU0_PCH_RX_C_DN<0>")
	)
	(segment
		(start 361.60964 -99.47021)
		(end 361.837478 -99.9236)
		(width 0.1143)
		(layer "B.Cu")
		(net "DMI_CPU0_PCH_RX_C_DN<0>")
	)
	(segment
		(start 302.686212 -85.031834)
		(end 302.653446 -85.031834)
		(width 0.0889)
		(layer "In11.Cu")
		(net "DMI_CPU0_PCH_RX_C_DN<0>")
	)
	(segment
		(start 307.534056 -83.20278)
		(end 307.437536 -83.2993)
		(width 0.0889)
		(layer "In11.Cu")
		(net "DMI_CPU0_PCH_RX_C_DN<0>")
	)
	(segment
		(start 301.823882 -85.527388)
		(end 301.791116 -85.527388)
		(width 0.0889)
		(layer "In11.Cu")
		(net "DMI_CPU0_PCH_RX_C_DN<0>")
	)
	(segment
		(start 354.417884 -75.000104)
		(end 352.081338 -75.467464)
		(width 0.1143)
		(layer "In11.Cu")
		(net "DMI_CPU0_PCH_RX_C_DN<0>")
	)
	(segment
		(start 303.540922 -83.546188)
		(end 303.508156 -83.546188)
		(width 0.0889)
		(layer "In11.Cu")
		(net "DMI_CPU0_PCH_RX_C_DN<0>")
	)
	(segment
		(start 360.584242 -99.130358)
		(end 360.165904 -99.130358)
		(width 0.1143)
		(layer "In11.Cu")
		(net "DMI_CPU0_PCH_RX_C_DN<0>")
	)
	(segment
		(start 306.295044 -83.050634)
		(end 304.370486 -83.050634)
		(width 0.0889)
		(layer "In11.Cu")
		(net "DMI_CPU0_PCH_RX_C_DN<0>")
	)
	(segment
		(start 311.382918 -83.2485)
		(end 308.44744 -83.2485)
		(width 0.1143)
		(layer "In11.Cu")
		(net "DMI_CPU0_PCH_RX_C_DN<0>")
	)
	(segment
		(start 352.081338 -75.467464)
		(end 348.2975 -74.710798)
		(width 0.1143)
		(layer "In11.Cu")
		(net "DMI_CPU0_PCH_RX_C_DN<0>")
	)
	(segment
		(start 360.165904 -99.130358)
		(end 359.59288 -98.557334)
		(width 0.1143)
		(layer "In11.Cu")
		(net "DMI_CPU0_PCH_RX_C_DN<0>")
	)
	(segment
		(start 306.711096 -83.2993)
		(end 306.54371 -83.2993)
		(width 0.0889)
		(layer "In11.Cu")
		(net "DMI_CPU0_PCH_RX_C_DN<0>")
	)
	(segment
		(start 360.692192 -84.847938)
		(end 360.793792 -84.339684)
		(width 0.1143)
		(layer "In11.Cu")
		(net "DMI_CPU0_PCH_RX_C_DN<0>")
	)
	(segment
		(start 358.4702 -75.119738)
		(end 356.742492 -75.465178)
		(width 0.1143)
		(layer "In11.Cu")
		(net "DMI_CPU0_PCH_RX_C_DN<0>")
	)
	(segment
		(start 336.269838 -79.617316)
		(end 330.628244 -83.37804)
		(width 0.1143)
		(layer "In11.Cu")
		(net "DMI_CPU0_PCH_RX_C_DN<0>")
	)
	(segment
		(start 361.37977 -88.287098)
		(end 360.692192 -84.847938)
		(width 0.1143)
		(layer "In11.Cu")
		(net "DMI_CPU0_PCH_RX_C_DN<0>")
	)
	(segment
		(start 361.461812 -77.704188)
		(end 361.196382 -76.37653)
		(width 0.1143)
		(layer "In11.Cu")
		(net "DMI_CPU0_PCH_RX_C_DN<0>")
	)
	(segment
		(start 360.69905 -99.01555)
		(end 360.584242 -99.130358)
		(width 0.1143)
		(layer "In11.Cu")
		(net "DMI_CPU0_PCH_RX_C_DN<0>")
	)
	(segment
		(start 306.54371 -83.2993)
		(end 306.295044 -83.050634)
		(width 0.0889)
		(layer "In11.Cu")
		(net "DMI_CPU0_PCH_RX_C_DN<0>")
	)
	(segment
		(start 360.487214 -82.805524)
		(end 361.484672 -77.81925)
		(width 0.1143)
		(layer "In11.Cu")
		(net "DMI_CPU0_PCH_RX_C_DN<0>")
	)
	(segment
		(start 303.011586 -84.421218)
		(end 303.017936 -84.431886)
		(width 0.0889)
		(layer "In11.Cu")
		(net "DMI_CPU0_PCH_RX_C_DN<0>")
	)
	(segment
		(start 308.44744 -83.2485)
		(end 308.425342 -83.2485)
		(width 0.0889)
		(layer "In11.Cu")
		(net "DMI_CPU0_PCH_RX_C_DN<0>")
	)
	(segment
		(start 307.074316 -83.20278)
		(end 306.807616 -83.20278)
		(width 0.0889)
		(layer "In11.Cu")
		(net "DMI_CPU0_PCH_RX_C_DN<0>")
	)
	(segment
		(start 361.484672 -77.81925)
		(end 361.461812 -77.704188)
		(width 0.1143)
		(layer "In11.Cu")
		(net "DMI_CPU0_PCH_RX_C_DN<0>")
	)
	(segment
		(start 360.924348 -90.560398)
		(end 361.37977 -88.287098)
		(width 0.1143)
		(layer "In11.Cu")
		(net "DMI_CPU0_PCH_RX_C_DN<0>")
	)
	(segment
		(start 307.897276 -83.2993)
		(end 307.800756 -83.20278)
		(width 0.0889)
		(layer "In11.Cu")
		(net "DMI_CPU0_PCH_RX_C_DN<0>")
	)
	(segment
		(start 358.536748 -94.123764)
		(end 358.681782 -93.399864)
		(width 0.1143)
		(layer "In11.Cu")
		(net "DMI_CPU0_PCH_RX_C_DN<0>")
	)
	(segment
		(start 311.388506 -83.254088)
		(end 311.382918 -83.2485)
		(width 0.1143)
		(layer "In11.Cu")
		(net "DMI_CPU0_PCH_RX_C_DN<0>")
	)
	(segment
		(start 356.742492 -75.465178)
		(end 354.417884 -75.000104)
		(width 0.1143)
		(layer "In11.Cu")
		(net "DMI_CPU0_PCH_RX_C_DN<0>")
	)
	(segment
		(start 308.425342 -83.2485)
		(end 308.374542 -83.2993)
		(width 0.0889)
		(layer "In11.Cu")
		(net "DMI_CPU0_PCH_RX_C_DN<0>")
	)
	(segment
		(start 300.66107 -85.791548)
		(end 300.736 -85.748368)
		(width 0.0889)
		(layer "In11.Cu")
		(net "DMI_CPU0_PCH_RX_C_DN<0>")
	)
	(segment
		(start 345.455748 -75.27925)
		(end 342.396572 -74.667364)
		(width 0.1143)
		(layer "In11.Cu")
		(net "DMI_CPU0_PCH_RX_C_DN<0>")
	)
	(segment
		(start 348.2975 -74.710798)
		(end 345.455748 -75.27925)
		(width 0.1143)
		(layer "In11.Cu")
		(net "DMI_CPU0_PCH_RX_C_DN<0>")
	)
	(segment
		(start 308.374542 -83.2993)
		(end 307.897276 -83.2993)
		(width 0.0889)
		(layer "In11.Cu")
		(net "DMI_CPU0_PCH_RX_C_DN<0>")
	)
	(segment
		(start 303.017936 -84.431886)
		(end 303.022762 -84.440522)
		(width 0.0889)
		(layer "In11.Cu")
		(net "DMI_CPU0_PCH_RX_C_DN<0>")
	)
	(segment
		(start 360.793792 -84.339684)
		(end 360.487214 -82.805524)
		(width 0.1143)
		(layer "In11.Cu")
		(net "DMI_CPU0_PCH_RX_C_DN<0>")
	)
	(segment
		(start 342.396572 -74.667364)
		(end 341.213186 -74.904092)
		(width 0.1143)
		(layer "In11.Cu")
		(net "DMI_CPU0_PCH_RX_C_DN<0>")
	)
	(segment
		(start 338.72424 -75.935586)
		(end 336.269838 -79.617316)
		(width 0.1143)
		(layer "In11.Cu")
		(net "DMI_CPU0_PCH_RX_C_DN<0>")
	)
	(segment
		(start 358.681782 -93.399864)
		(end 359.26141 -92.530168)
		(width 0.1143)
		(layer "In11.Cu")
		(net "DMI_CPU0_PCH_RX_C_DN<0>")
	)
	(segment
		(start 359.35158 -98.195638)
		(end 358.536748 -94.123764)
		(width 0.1143)
		(layer "In11.Cu")
		(net "DMI_CPU0_PCH_RX_C_DN<0>")
	)
	(segment
		(start 360.648758 -75.555094)
		(end 358.4702 -75.119738)
		(width 0.1143)
		(layer "In11.Cu")
		(net "DMI_CPU0_PCH_RX_C_DN<0>")
	)
	(segment
		(start 307.800756 -83.20278)
		(end 307.534056 -83.20278)
		(width 0.0889)
		(layer "In11.Cu")
		(net "DMI_CPU0_PCH_RX_C_DN<0>")
	)
	(segment
		(start 321.317874 -85.23986)
		(end 311.388506 -83.254088)
		(width 0.1143)
		(layer "In11.Cu")
		(net "DMI_CPU0_PCH_RX_C_DN<0>")
	)
	(segment
		(start 359.26141 -92.530168)
		(end 359.892346 -92.108528)
		(width 0.1143)
		(layer "In11.Cu")
		(net "DMI_CPU0_PCH_RX_C_DN<0>")
	)
	(segment
		(start 361.196382 -76.37653)
		(end 360.648758 -75.555094)
		(width 0.1143)
		(layer "In11.Cu")
		(net "DMI_CPU0_PCH_RX_C_DN<0>")
	)
	(segment
		(start 359.892346 -92.108528)
		(end 360.924348 -90.560398)
		(width 0.1143)
		(layer "In11.Cu")
		(net "DMI_CPU0_PCH_RX_C_DN<0>")
	)
	(segment
		(start 300.639988 -85.870288)
		(end 300.66107 -85.791548)
		(width 0.0889)
		(layer "In11.Cu")
		(net "DMI_CPU0_PCH_RX_C_DN<0>")
	)
	(segment
		(start 341.213186 -74.904092)
		(end 338.72424 -75.935586)
		(width 0.1143)
		(layer "In11.Cu")
		(net "DMI_CPU0_PCH_RX_C_DN<0>")
	)
	(segment
		(start 330.628244 -83.37804)
		(end 321.317874 -85.23986)
		(width 0.1143)
		(layer "In11.Cu")
		(net "DMI_CPU0_PCH_RX_C_DN<0>")
	)
	(segment
		(start 300.969172 -86.022434)
		(end 300.9392 -86.022434)
		(width 0.0889)
		(layer "In11.Cu")
		(net "DMI_CPU0_PCH_RX_C_DN<0>")
	)
	(segment
		(start 307.170836 -83.2993)
		(end 307.074316 -83.20278)
		(width 0.0889)
		(layer "In11.Cu")
		(net "DMI_CPU0_PCH_RX_C_DN<0>")
	)
	(segment
		(start 306.807616 -83.20278)
		(end 306.711096 -83.2993)
		(width 0.0889)
		(layer "In11.Cu")
		(net "DMI_CPU0_PCH_RX_C_DN<0>")
	)
	(segment
		(start 307.437536 -83.2993)
		(end 307.170836 -83.2993)
		(width 0.0889)
		(layer "In11.Cu")
		(net "DMI_CPU0_PCH_RX_C_DN<0>")
	)
	(segment
		(start 359.59288 -98.557334)
		(end 359.35158 -98.195638)
		(width 0.1143)
		(layer "In11.Cu")
		(net "DMI_CPU0_PCH_RX_C_DN<0>")
	)
	(segment
		(start 300.736 -85.748368)
		(end 300.954186 -85.622384)
		(width 0.0889)
		(layer "In11.Cu")
		(net "DMI_CPU0_PCH_RX_C_DN<0>")
	)
	(segment
		(start 360.69905 -98.654108)
		(end 360.69905 -99.01555)
		(width 0.1143)
		(layer "In11.Cu")
		(net "DMI_CPU0_PCH_RX_C_DN<0>")
	)
	(arc
		(start 303.508156 -83.546188)
		(mid 303.015766 -83.845121)
		(end 303.011586 -84.421218)
		(width 0.0889)
		(layer "In11.Cu")
		(net "DMI_CPU0_PCH_RX_C_DN<0>")
	)
	(arc
		(start 302.653446 -85.031834)
		(mid 302.368022 -85.115301)
		(end 302.159416 -85.327236)
		(width 0.0889)
		(layer "In11.Cu")
		(net "DMI_CPU0_PCH_RX_C_DN<0>")
	)
	(arc
		(start 301.791116 -85.527388)
		(mid 301.507899 -85.611669)
		(end 301.300896 -85.822536)
		(width 0.0889)
		(layer "In11.Cu")
		(net "DMI_CPU0_PCH_RX_C_DN<0>")
	)
	(arc
		(start 300.9392 -86.022434)
		(mid 300.772906 -85.9792)
		(end 300.639988 -85.870288)
		(width 0.0889)
		(layer "In11.Cu")
		(net "DMI_CPU0_PCH_RX_C_DN<0>")
	)
	(arc
		(start 303.876456 -83.346036)
		(mid 303.734773 -83.48984)
		(end 303.540922 -83.546188)
		(width 0.0889)
		(layer "In11.Cu")
		(net "DMI_CPU0_PCH_RX_C_DN<0>")
	)
	(arc
		(start 304.370486 -83.050634)
		(mid 304.085062 -83.134101)
		(end 303.876456 -83.346036)
		(width 0.0889)
		(layer "In11.Cu")
		(net "DMI_CPU0_PCH_RX_C_DN<0>")
	)
	(arc
		(start 301.300896 -85.822536)
		(mid 301.160817 -85.965272)
		(end 300.969172 -86.022434)
		(width 0.0889)
		(layer "In11.Cu")
		(net "DMI_CPU0_PCH_RX_C_DN<0>")
	)
	(arc
		(start 303.022762 -84.440522)
		(mid 303.019015 -84.829778)
		(end 302.686212 -85.031834)
		(width 0.0889)
		(layer "In11.Cu")
		(net "DMI_CPU0_PCH_RX_C_DN<0>")
	)
	(arc
		(start 302.159416 -85.327236)
		(mid 302.017733 -85.47104)
		(end 301.823882 -85.527388)
		(width 0.0889)
		(layer "In11.Cu")
		(net "DMI_CPU0_PCH_RX_C_DN<0>")
	)
	(segment
		(start 400.574256 -115.745768)
		(end 400.952208 -115.745768)
		(width 0.0889)
		(layer "F.Cu")
		(net "CLK_48M_USB_BMC")
	)
	(segment
		(start 401.636484 -115.55349)
		(end 401.7137 -115.476274)
		(width 0.0889)
		(layer "F.Cu")
		(net "CLK_48M_USB_BMC")
	)
	(segment
		(start 403.489414 -115.55349)
		(end 403.632924 -115.697)
		(width 0.10795)
		(layer "F.Cu")
		(net "CLK_48M_USB_BMC")
	)
	(segment
		(start 400.952208 -115.745768)
		(end 401.144486 -115.55349)
		(width 0.0889)
		(layer "F.Cu")
		(net "CLK_48M_USB_BMC")
	)
	(segment
		(start 402.121116 -115.55349)
		(end 402.286216 -115.55349)
		(width 0.0889)
		(layer "F.Cu")
		(net "CLK_48M_USB_BMC")
	)
	(segment
		(start 400.465036 -115.854988)
		(end 400.574256 -115.745768)
		(width 0.0889)
		(layer "F.Cu")
		(net "CLK_48M_USB_BMC")
	)
	(segment
		(start 401.144486 -115.55349)
		(end 401.636484 -115.55349)
		(width 0.0889)
		(layer "F.Cu")
		(net "CLK_48M_USB_BMC")
	)
	(segment
		(start 401.7137 -115.476274)
		(end 402.0439 -115.476274)
		(width 0.0889)
		(layer "F.Cu")
		(net "CLK_48M_USB_BMC")
	)
	(segment
		(start 402.286216 -115.55349)
		(end 403.489414 -115.55349)
		(width 0.10795)
		(layer "F.Cu")
		(net "CLK_48M_USB_BMC")
	)
	(segment
		(start 402.0439 -115.476274)
		(end 402.121116 -115.55349)
		(width 0.0889)
		(layer "F.Cu")
		(net "CLK_48M_USB_BMC")
	)
	(segment
		(start 403.632924 -115.697)
		(end 403.987 -115.697)
		(width 0.10795)
		(layer "F.Cu")
		(net "CLK_48M_USB_BMC")
	)
	(segment
		(start 126.797308 -68.782184)
		(end 127.368808 -68.782184)
		(width 0.1016)
		(layer "F.Cu")
		(net "H_PMSYNC_CLK_24M_CPU1")
	)
	(via
		(at 127.368808 -68.782184)
		(size 0.508)
		(drill 0.254)
		(layers "F.Cu" "B.Cu")
		(net "H_PMSYNC_CLK_24M_CPU1")
	)
	(segment
		(start 128.974088 -68.292472)
		(end 129.28346 -68.292472)
		(width 0.10795)
		(layer "B.Cu")
		(net "H_PMSYNC_CLK_24M_CPU1")
	)
	(segment
		(start 129.777998 -67.797934)
		(end 129.777998 -67.677538)
		(width 0.10795)
		(layer "B.Cu")
		(net "H_PMSYNC_CLK_24M_CPU1")
	)
	(segment
		(start 128.541018 -68.725542)
		(end 128.974088 -68.292472)
		(width 0.10795)
		(layer "B.Cu")
		(net "H_PMSYNC_CLK_24M_CPU1")
	)
	(segment
		(start 127.368808 -68.782184)
		(end 127.42545 -68.725542)
		(width 0.10795)
		(layer "B.Cu")
		(net "H_PMSYNC_CLK_24M_CPU1")
	)
	(segment
		(start 127.42545 -68.725542)
		(end 128.541018 -68.725542)
		(width 0.10795)
		(layer "B.Cu")
		(net "H_PMSYNC_CLK_24M_CPU1")
	)
	(segment
		(start 129.28346 -68.292472)
		(end 129.777998 -67.797934)
		(width 0.10795)
		(layer "B.Cu")
		(net "H_PMSYNC_CLK_24M_CPU1")
	)
	(segment
		(start 291.79774 -68.782184)
		(end 292.36924 -68.782184)
		(width 0.1016)
		(layer "F.Cu")
		(net "H_PMSYNC_CLK_24M_CPU0")
	)
	(via
		(at 292.36924 -68.782184)
		(size 0.508)
		(drill 0.254)
		(layers "F.Cu" "B.Cu")
		(net "H_PMSYNC_CLK_24M_CPU0")
	)
	(segment
		(start 292.36924 -68.782184)
		(end 292.729412 -68.422012)
		(width 0.10795)
		(layer "B.Cu")
		(net "H_PMSYNC_CLK_24M_CPU0")
	)
	(segment
		(start 293.334186 -67.7672)
		(end 293.6494 -67.451986)
		(width 0.10795)
		(layer "B.Cu")
		(net "H_PMSYNC_CLK_24M_CPU0")
	)
	(segment
		(start 292.729412 -68.052188)
		(end 293.0144 -67.7672)
		(width 0.10795)
		(layer "B.Cu")
		(net "H_PMSYNC_CLK_24M_CPU0")
	)
	(segment
		(start 293.6494 -67.3862)
		(end 293.87292 -67.16268)
		(width 0.10795)
		(layer "B.Cu")
		(net "H_PMSYNC_CLK_24M_CPU0")
	)
	(segment
		(start 293.0144 -67.7672)
		(end 293.334186 -67.7672)
		(width 0.10795)
		(layer "B.Cu")
		(net "H_PMSYNC_CLK_24M_CPU0")
	)
	(segment
		(start 293.6494 -67.451986)
		(end 293.6494 -67.3862)
		(width 0.10795)
		(layer "B.Cu")
		(net "H_PMSYNC_CLK_24M_CPU0")
	)
	(segment
		(start 292.729412 -68.422012)
		(end 292.729412 -68.052188)
		(width 0.10795)
		(layer "B.Cu")
		(net "H_PMSYNC_CLK_24M_CPU0")
	)
	(segment
		(start 459.246478 -144.81175)
		(end 459.246478 -144.963896)
		(width 0.127)
		(layer "F.Cu")
		(net "CLK_100M_PCH_XDP_DP")
	)
	(segment
		(start 372.822978 -110.381796)
		(end 371.79504 -110.381796)
		(width 0.0889)
		(layer "F.Cu")
		(net "CLK_100M_PCH_XDP_DP")
	)
	(segment
		(start 458.500988 -145.33372)
		(end 458.287374 -145.33372)
		(width 0.127)
		(layer "F.Cu")
		(net "CLK_100M_PCH_XDP_DP")
	)
	(segment
		(start 374.83161 -110.569248)
		(end 374.518174 -110.569248)
		(width 0.0889)
		(layer "F.Cu")
		(net "CLK_100M_PCH_XDP_DP")
	)
	(segment
		(start 459.178406 -145.031968)
		(end 458.80274 -145.031968)
		(width 0.127)
		(layer "F.Cu")
		(net "CLK_100M_PCH_XDP_DP")
	)
	(segment
		(start 373.16918 -110.727998)
		(end 372.822978 -110.381796)
		(width 0.0889)
		(layer "F.Cu")
		(net "CLK_100M_PCH_XDP_DP")
	)
	(segment
		(start 371.79504 -110.381796)
		(end 371.381274 -109.96803)
		(width 0.0889)
		(layer "F.Cu")
		(net "CLK_100M_PCH_XDP_DP")
	)
	(segment
		(start 374.518174 -110.569248)
		(end 374.359424 -110.727998)
		(width 0.0889)
		(layer "F.Cu")
		(net "CLK_100M_PCH_XDP_DP")
	)
	(segment
		(start 374.359424 -110.727998)
		(end 373.16918 -110.727998)
		(width 0.0889)
		(layer "F.Cu")
		(net "CLK_100M_PCH_XDP_DP")
	)
	(segment
		(start 374.894856 -110.627668)
		(end 374.89003 -110.627668)
		(width 0.0889)
		(layer "F.Cu")
		(net "CLK_100M_PCH_XDP_DP")
	)
	(segment
		(start 458.173582 -145.219928)
		(end 457.252324 -145.219928)
		(width 0.127)
		(layer "F.Cu")
		(net "CLK_100M_PCH_XDP_DP")
	)
	(segment
		(start 458.287374 -145.33372)
		(end 458.173582 -145.219928)
		(width 0.127)
		(layer "F.Cu")
		(net "CLK_100M_PCH_XDP_DP")
	)
	(segment
		(start 458.80274 -145.031968)
		(end 458.500988 -145.33372)
		(width 0.127)
		(layer "F.Cu")
		(net "CLK_100M_PCH_XDP_DP")
	)
	(segment
		(start 374.89003 -110.627668)
		(end 374.83161 -110.569248)
		(width 0.0889)
		(layer "F.Cu")
		(net "CLK_100M_PCH_XDP_DP")
	)
	(segment
		(start 459.246478 -144.963896)
		(end 459.178406 -145.031968)
		(width 0.127)
		(layer "F.Cu")
		(net "CLK_100M_PCH_XDP_DP")
	)
	(segment
		(start 371.381274 -109.96803)
		(end 371.381274 -109.944154)
		(width 0.0889)
		(layer "F.Cu")
		(net "CLK_100M_PCH_XDP_DP")
	)
	(segment
		(start 374.897142 -110.629954)
		(end 374.894856 -110.627668)
		(width 0.0889)
		(layer "F.Cu")
		(net "CLK_100M_PCH_XDP_DP")
	)
	(segment
		(start 375.504964 -110.854998)
		(end 374.897142 -110.629954)
		(width 0.0889)
		(layer "F.Cu")
		(net "CLK_100M_PCH_XDP_DP")
	)
	(via
		(at 459.246478 -144.81175)
		(size 0.508)
		(drill 0.254)
		(layers "F.Cu" "B.Cu")
		(net "CLK_100M_PCH_XDP_DP")
	)
	(via
		(at 371.381274 -109.944154)
		(size 0.508)
		(drill 0.254)
		(layers "F.Cu" "B.Cu")
		(net "CLK_100M_PCH_XDP_DP")
	)
	(via
		(at 348.495112 -116.36375)
		(size 0.508)
		(drill 0.254)
		(layers "F.Cu" "B.Cu")
		(net "CLK_100M_PCH_XDP_DP")
	)
	(segment
		(start 366.105186 -140.031978)
		(end 370.177568 -140.031978)
		(width 0.1143)
		(layer "In4.Cu")
		(net "CLK_100M_PCH_XDP_DP")
	)
	(segment
		(start 458.43063 -142.02283)
		(end 458.6732 -142.2654)
		(width 0.1143)
		(layer "In4.Cu")
		(net "CLK_100M_PCH_XDP_DP")
	)
	(segment
		(start 435.510432 -138.7221)
		(end 438.38368 -138.7221)
		(width 0.1143)
		(layer "In4.Cu")
		(net "CLK_100M_PCH_XDP_DP")
	)
	(segment
		(start 431.668682 -140.53185)
		(end 431.833782 -140.36675)
		(width 0.1143)
		(layer "In4.Cu")
		(net "CLK_100M_PCH_XDP_DP")
	)
	(segment
		(start 439.29681 -137.80897)
		(end 441.457334 -137.80897)
		(width 0.1143)
		(layer "In4.Cu")
		(net "CLK_100M_PCH_XDP_DP")
	)
	(segment
		(start 448.667886 -136.792462)
		(end 448.910202 -136.550146)
		(width 0.1143)
		(layer "In4.Cu")
		(net "CLK_100M_PCH_XDP_DP")
	)
	(segment
		(start 453.523858 -137.9982)
		(end 455.2315 -139.705842)
		(width 0.1143)
		(layer "In4.Cu")
		(net "CLK_100M_PCH_XDP_DP")
	)
	(segment
		(start 356.0699 -130.113024)
		(end 359.916476 -133.9596)
		(width 0.1143)
		(layer "In4.Cu")
		(net "CLK_100M_PCH_XDP_DP")
	)
	(segment
		(start 458.43063 -141.789404)
		(end 458.43063 -142.02283)
		(width 0.1143)
		(layer "In4.Cu")
		(net "CLK_100M_PCH_XDP_DP")
	)
	(segment
		(start 348.495112 -116.36375)
		(end 348.867984 -116.36375)
		(width 0.1143)
		(layer "In4.Cu")
		(net "CLK_100M_PCH_XDP_DP")
	)
	(segment
		(start 397.682974 -140.155676)
		(end 398.73428 -141.206982)
		(width 0.1143)
		(layer "In4.Cu")
		(net "CLK_100M_PCH_XDP_DP")
	)
	(segment
		(start 442.473334 -137.80897)
		(end 442.638434 -137.64387)
		(width 0.1143)
		(layer "In4.Cu")
		(net "CLK_100M_PCH_XDP_DP")
	)
	(segment
		(start 352.555048 -129.558542)
		(end 354.374958 -129.558542)
		(width 0.1143)
		(layer "In4.Cu")
		(net "CLK_100M_PCH_XDP_DP")
	)
	(segment
		(start 347.32087 -115.986052)
		(end 347.32087 -121.036842)
		(width 0.1143)
		(layer "In4.Cu")
		(net "CLK_100M_PCH_XDP_DP")
	)
	(segment
		(start 443.59957 -137.80897)
		(end 444.2079 -138.4173)
		(width 0.1143)
		(layer "In4.Cu")
		(net "CLK_100M_PCH_XDP_DP")
	)
	(segment
		(start 458.8383 -142.7734)
		(end 458.8383 -143.1163)
		(width 0.1143)
		(layer "In4.Cu")
		(net "CLK_100M_PCH_XDP_DP")
	)
	(segment
		(start 449.143628 -136.550146)
		(end 449.386198 -136.307576)
		(width 0.1143)
		(layer "In4.Cu")
		(net "CLK_100M_PCH_XDP_DP")
	)
	(segment
		(start 451.477634 -136.307576)
		(end 453.168258 -137.9982)
		(width 0.1143)
		(layer "In4.Cu")
		(net "CLK_100M_PCH_XDP_DP")
	)
	(segment
		(start 455.2315 -140.721842)
		(end 455.416158 -140.9065)
		(width 0.1143)
		(layer "In4.Cu")
		(net "CLK_100M_PCH_XDP_DP")
	)
	(segment
		(start 431.833782 -140.36675)
		(end 432.176682 -140.36675)
		(width 0.1143)
		(layer "In4.Cu")
		(net "CLK_100M_PCH_XDP_DP")
	)
	(segment
		(start 433.357782 -140.53185)
		(end 433.700682 -140.53185)
		(width 0.1143)
		(layer "In4.Cu")
		(net "CLK_100M_PCH_XDP_DP")
	)
	(segment
		(start 432.176682 -140.36675)
		(end 432.341782 -140.53185)
		(width 0.1143)
		(layer "In4.Cu")
		(net "CLK_100M_PCH_XDP_DP")
	)
	(segment
		(start 441.457334 -137.80897)
		(end 441.622434 -137.64387)
		(width 0.1143)
		(layer "In4.Cu")
		(net "CLK_100M_PCH_XDP_DP")
	)
	(segment
		(start 447.949574 -137.7442)
		(end 447.949574 -137.510774)
		(width 0.1143)
		(layer "In4.Cu")
		(net "CLK_100M_PCH_XDP_DP")
	)
	(segment
		(start 408.792172 -140.620496)
		(end 408.953208 -140.620496)
		(width 0.1143)
		(layer "In4.Cu")
		(net "CLK_100M_PCH_XDP_DP")
	)
	(segment
		(start 354.92944 -130.113024)
		(end 356.0699 -130.113024)
		(width 0.1143)
		(layer "In4.Cu")
		(net "CLK_100M_PCH_XDP_DP")
	)
	(segment
		(start 458.6732 -144.9324)
		(end 458.7875 -145.0467)
		(width 0.1143)
		(layer "In4.Cu")
		(net "CLK_100M_PCH_XDP_DP")
	)
	(segment
		(start 459.011528 -145.0467)
		(end 459.246478 -144.81175)
		(width 0.1143)
		(layer "In4.Cu")
		(net "CLK_100M_PCH_XDP_DP")
	)
	(segment
		(start 406.11425 -141.730476)
		(end 408.792172 -140.620496)
		(width 0.1143)
		(layer "In4.Cu")
		(net "CLK_100M_PCH_XDP_DP")
	)
	(segment
		(start 384.46964 -139.57427)
		(end 384.848354 -139.195556)
		(width 0.1143)
		(layer "In4.Cu")
		(net "CLK_100M_PCH_XDP_DP")
	)
	(segment
		(start 458.6732 -144.5895)
		(end 458.6732 -144.9324)
		(width 0.1143)
		(layer "In4.Cu")
		(net "CLK_100M_PCH_XDP_DP")
	)
	(segment
		(start 370.635276 -139.57427)
		(end 384.46964 -139.57427)
		(width 0.1143)
		(layer "In4.Cu")
		(net "CLK_100M_PCH_XDP_DP")
	)
	(segment
		(start 442.638434 -137.64387)
		(end 442.981334 -137.64387)
		(width 0.1143)
		(layer "In4.Cu")
		(net "CLK_100M_PCH_XDP_DP")
	)
	(segment
		(start 455.2315 -139.705842)
		(end 455.2315 -140.721842)
		(width 0.1143)
		(layer "In4.Cu")
		(net "CLK_100M_PCH_XDP_DP")
	)
	(segment
		(start 348.791784 -115.765326)
		(end 347.541596 -115.765326)
		(width 0.1143)
		(layer "In4.Cu")
		(net "CLK_100M_PCH_XDP_DP")
	)
	(segment
		(start 458.6732 -143.2814)
		(end 458.6732 -143.9164)
		(width 0.1143)
		(layer "In4.Cu")
		(net "CLK_100M_PCH_XDP_DP")
	)
	(segment
		(start 448.910202 -136.550146)
		(end 449.143628 -136.550146)
		(width 0.1143)
		(layer "In4.Cu")
		(net "CLK_100M_PCH_XDP_DP")
	)
	(segment
		(start 359.916476 -133.9596)
		(end 364.358936 -133.9596)
		(width 0.1143)
		(layer "In4.Cu")
		(net "CLK_100M_PCH_XDP_DP")
	)
	(segment
		(start 432.849782 -140.36675)
		(end 433.192682 -140.36675)
		(width 0.1143)
		(layer "In4.Cu")
		(net "CLK_100M_PCH_XDP_DP")
	)
	(segment
		(start 457.954888 -141.547088)
		(end 458.188314 -141.547088)
		(width 0.1143)
		(layer "In4.Cu")
		(net "CLK_100M_PCH_XDP_DP")
	)
	(segment
		(start 453.168258 -137.9982)
		(end 453.523858 -137.9982)
		(width 0.1143)
		(layer "In4.Cu")
		(net "CLK_100M_PCH_XDP_DP")
	)
	(segment
		(start 458.7875 -145.0467)
		(end 459.011528 -145.0467)
		(width 0.1143)
		(layer "In4.Cu")
		(net "CLK_100M_PCH_XDP_DP")
	)
	(segment
		(start 420.563294 -139.86637)
		(end 421.228774 -140.53185)
		(width 0.1143)
		(layer "In4.Cu")
		(net "CLK_100M_PCH_XDP_DP")
	)
	(segment
		(start 448.19189 -137.268458)
		(end 448.425316 -137.268458)
		(width 0.1143)
		(layer "In4.Cu")
		(net "CLK_100M_PCH_XDP_DP")
	)
	(segment
		(start 448.667886 -137.025888)
		(end 448.667886 -136.792462)
		(width 0.1143)
		(layer "In4.Cu")
		(net "CLK_100M_PCH_XDP_DP")
	)
	(segment
		(start 442.130434 -137.80897)
		(end 442.473334 -137.80897)
		(width 0.1143)
		(layer "In4.Cu")
		(net "CLK_100M_PCH_XDP_DP")
	)
	(segment
		(start 455.416158 -140.9065)
		(end 456.2983 -140.9065)
		(width 0.1143)
		(layer "In4.Cu")
		(net "CLK_100M_PCH_XDP_DP")
	)
	(segment
		(start 456.2983 -140.9065)
		(end 456.4634 -140.7414)
		(width 0.1143)
		(layer "In4.Cu")
		(net "CLK_100M_PCH_XDP_DP")
	)
	(segment
		(start 458.188314 -141.547088)
		(end 458.43063 -141.789404)
		(width 0.1143)
		(layer "In4.Cu")
		(net "CLK_100M_PCH_XDP_DP")
	)
	(segment
		(start 441.622434 -137.64387)
		(end 441.965334 -137.64387)
		(width 0.1143)
		(layer "In4.Cu")
		(net "CLK_100M_PCH_XDP_DP")
	)
	(segment
		(start 458.6732 -142.2654)
		(end 458.6732 -142.6083)
		(width 0.1143)
		(layer "In4.Cu")
		(net "CLK_100M_PCH_XDP_DP")
	)
	(segment
		(start 354.374958 -129.558542)
		(end 354.92944 -130.113024)
		(width 0.1143)
		(layer "In4.Cu")
		(net "CLK_100M_PCH_XDP_DP")
	)
	(segment
		(start 456.9714 -140.9065)
		(end 457.3143 -140.9065)
		(width 0.1143)
		(layer "In4.Cu")
		(net "CLK_100M_PCH_XDP_DP")
	)
	(segment
		(start 364.97387 -138.900662)
		(end 366.105186 -140.031978)
		(width 0.1143)
		(layer "In4.Cu")
		(net "CLK_100M_PCH_XDP_DP")
	)
	(segment
		(start 456.8063 -140.7414)
		(end 456.9714 -140.9065)
		(width 0.1143)
		(layer "In4.Cu")
		(net "CLK_100M_PCH_XDP_DP")
	)
	(segment
		(start 432.684682 -140.53185)
		(end 432.849782 -140.36675)
		(width 0.1143)
		(layer "In4.Cu")
		(net "CLK_100M_PCH_XDP_DP")
	)
	(segment
		(start 384.848354 -139.195556)
		(end 392.639804 -139.195556)
		(width 0.1143)
		(layer "In4.Cu")
		(net "CLK_100M_PCH_XDP_DP")
	)
	(segment
		(start 398.73428 -141.206982)
		(end 402.058124 -141.206982)
		(width 0.1143)
		(layer "In4.Cu")
		(net "CLK_100M_PCH_XDP_DP")
	)
	(segment
		(start 438.38368 -138.7221)
		(end 439.29681 -137.80897)
		(width 0.1143)
		(layer "In4.Cu")
		(net "CLK_100M_PCH_XDP_DP")
	)
	(segment
		(start 349.276162 -122.992134)
		(end 349.276162 -126.279656)
		(width 0.1143)
		(layer "In4.Cu")
		(net "CLK_100M_PCH_XDP_DP")
	)
	(segment
		(start 458.8383 -144.0815)
		(end 458.8383 -144.4244)
		(width 0.1143)
		(layer "In4.Cu")
		(net "CLK_100M_PCH_XDP_DP")
	)
	(segment
		(start 364.97387 -134.574534)
		(end 364.97387 -138.900662)
		(width 0.1143)
		(layer "In4.Cu")
		(net "CLK_100M_PCH_XDP_DP")
	)
	(segment
		(start 458.8383 -144.4244)
		(end 458.6732 -144.5895)
		(width 0.1143)
		(layer "In4.Cu")
		(net "CLK_100M_PCH_XDP_DP")
	)
	(segment
		(start 447.949574 -137.510774)
		(end 448.19189 -137.268458)
		(width 0.1143)
		(layer "In4.Cu")
		(net "CLK_100M_PCH_XDP_DP")
	)
	(segment
		(start 433.700682 -140.53185)
		(end 435.510432 -138.7221)
		(width 0.1143)
		(layer "In4.Cu")
		(net "CLK_100M_PCH_XDP_DP")
	)
	(segment
		(start 421.228774 -140.53185)
		(end 431.668682 -140.53185)
		(width 0.1143)
		(layer "In4.Cu")
		(net "CLK_100M_PCH_XDP_DP")
	)
	(segment
		(start 458.6732 -142.6083)
		(end 458.8383 -142.7734)
		(width 0.1143)
		(layer "In4.Cu")
		(net "CLK_100M_PCH_XDP_DP")
	)
	(segment
		(start 348.982284 -115.955826)
		(end 348.791784 -115.765326)
		(width 0.1143)
		(layer "In4.Cu")
		(net "CLK_100M_PCH_XDP_DP")
	)
	(segment
		(start 402.581618 -141.730476)
		(end 406.11425 -141.730476)
		(width 0.1143)
		(layer "In4.Cu")
		(net "CLK_100M_PCH_XDP_DP")
	)
	(segment
		(start 458.6732 -143.9164)
		(end 458.8383 -144.0815)
		(width 0.1143)
		(layer "In4.Cu")
		(net "CLK_100M_PCH_XDP_DP")
	)
	(segment
		(start 393.599924 -140.155676)
		(end 397.682974 -140.155676)
		(width 0.1143)
		(layer "In4.Cu")
		(net "CLK_100M_PCH_XDP_DP")
	)
	(segment
		(start 392.639804 -139.195556)
		(end 393.599924 -140.155676)
		(width 0.1143)
		(layer "In4.Cu")
		(net "CLK_100M_PCH_XDP_DP")
	)
	(segment
		(start 410.773372 -139.86637)
		(end 420.563294 -139.86637)
		(width 0.1143)
		(layer "In4.Cu")
		(net "CLK_100M_PCH_XDP_DP")
	)
	(segment
		(start 347.541596 -115.765326)
		(end 347.32087 -115.986052)
		(width 0.1143)
		(layer "In4.Cu")
		(net "CLK_100M_PCH_XDP_DP")
	)
	(segment
		(start 457.3143 -140.9065)
		(end 457.954888 -141.547088)
		(width 0.1143)
		(layer "In4.Cu")
		(net "CLK_100M_PCH_XDP_DP")
	)
	(segment
		(start 348.982284 -116.24945)
		(end 348.982284 -115.955826)
		(width 0.1143)
		(layer "In4.Cu")
		(net "CLK_100M_PCH_XDP_DP")
	)
	(segment
		(start 370.177568 -140.031978)
		(end 370.635276 -139.57427)
		(width 0.1143)
		(layer "In4.Cu")
		(net "CLK_100M_PCH_XDP_DP")
	)
	(segment
		(start 443.146434 -137.80897)
		(end 443.59957 -137.80897)
		(width 0.1143)
		(layer "In4.Cu")
		(net "CLK_100M_PCH_XDP_DP")
	)
	(segment
		(start 448.425316 -137.268458)
		(end 448.667886 -137.025888)
		(width 0.1143)
		(layer "In4.Cu")
		(net "CLK_100M_PCH_XDP_DP")
	)
	(segment
		(start 433.192682 -140.36675)
		(end 433.357782 -140.53185)
		(width 0.1143)
		(layer "In4.Cu")
		(net "CLK_100M_PCH_XDP_DP")
	)
	(segment
		(start 458.8383 -143.1163)
		(end 458.6732 -143.2814)
		(width 0.1143)
		(layer "In4.Cu")
		(net "CLK_100M_PCH_XDP_DP")
	)
	(segment
		(start 444.2079 -138.4173)
		(end 447.276474 -138.4173)
		(width 0.1143)
		(layer "In4.Cu")
		(net "CLK_100M_PCH_XDP_DP")
	)
	(segment
		(start 364.358936 -133.9596)
		(end 364.97387 -134.574534)
		(width 0.1143)
		(layer "In4.Cu")
		(net "CLK_100M_PCH_XDP_DP")
	)
	(segment
		(start 408.953208 -140.620496)
		(end 410.773372 -139.86637)
		(width 0.1143)
		(layer "In4.Cu")
		(net "CLK_100M_PCH_XDP_DP")
	)
	(segment
		(start 447.276474 -138.4173)
		(end 447.949574 -137.7442)
		(width 0.1143)
		(layer "In4.Cu")
		(net "CLK_100M_PCH_XDP_DP")
	)
	(segment
		(start 456.4634 -140.7414)
		(end 456.8063 -140.7414)
		(width 0.1143)
		(layer "In4.Cu")
		(net "CLK_100M_PCH_XDP_DP")
	)
	(segment
		(start 347.32087 -121.036842)
		(end 349.276162 -122.992134)
		(width 0.1143)
		(layer "In4.Cu")
		(net "CLK_100M_PCH_XDP_DP")
	)
	(segment
		(start 402.058124 -141.206982)
		(end 402.581618 -141.730476)
		(width 0.1143)
		(layer "In4.Cu")
		(net "CLK_100M_PCH_XDP_DP")
	)
	(segment
		(start 348.867984 -116.36375)
		(end 348.982284 -116.24945)
		(width 0.1143)
		(layer "In4.Cu")
		(net "CLK_100M_PCH_XDP_DP")
	)
	(segment
		(start 441.965334 -137.64387)
		(end 442.130434 -137.80897)
		(width 0.1143)
		(layer "In4.Cu")
		(net "CLK_100M_PCH_XDP_DP")
	)
	(segment
		(start 349.276162 -126.279656)
		(end 352.555048 -129.558542)
		(width 0.1143)
		(layer "In4.Cu")
		(net "CLK_100M_PCH_XDP_DP")
	)
	(segment
		(start 432.341782 -140.53185)
		(end 432.684682 -140.53185)
		(width 0.1143)
		(layer "In4.Cu")
		(net "CLK_100M_PCH_XDP_DP")
	)
	(segment
		(start 449.386198 -136.307576)
		(end 451.477634 -136.307576)
		(width 0.1143)
		(layer "In4.Cu")
		(net "CLK_100M_PCH_XDP_DP")
	)
	(segment
		(start 442.981334 -137.64387)
		(end 443.146434 -137.80897)
		(width 0.1143)
		(layer "In4.Cu")
		(net "CLK_100M_PCH_XDP_DP")
	)
	(segment
		(start 369.50015 -114.70005)
		(end 371.157246 -113.042954)
		(width 0.1143)
		(layer "In11.Cu")
		(net "CLK_100M_PCH_XDP_DP")
	)
	(segment
		(start 368.713004 -114.70005)
		(end 369.50015 -114.70005)
		(width 0.1143)
		(layer "In11.Cu")
		(net "CLK_100M_PCH_XDP_DP")
	)
	(segment
		(start 371.157246 -110.168182)
		(end 371.381274 -109.944154)
		(width 0.1143)
		(layer "In11.Cu")
		(net "CLK_100M_PCH_XDP_DP")
	)
	(segment
		(start 349.353632 -117.153944)
		(end 366.25911 -117.153944)
		(width 0.1143)
		(layer "In11.Cu")
		(net "CLK_100M_PCH_XDP_DP")
	)
	(segment
		(start 348.869762 -116.36375)
		(end 348.984062 -116.47805)
		(width 0.1143)
		(layer "In11.Cu")
		(net "CLK_100M_PCH_XDP_DP")
	)
	(segment
		(start 348.984062 -116.784374)
		(end 349.353632 -117.153944)
		(width 0.1143)
		(layer "In11.Cu")
		(net "CLK_100M_PCH_XDP_DP")
	)
	(segment
		(start 348.984062 -116.47805)
		(end 348.984062 -116.784374)
		(width 0.1143)
		(layer "In11.Cu")
		(net "CLK_100M_PCH_XDP_DP")
	)
	(segment
		(start 366.25911 -117.153944)
		(end 368.713004 -114.70005)
		(width 0.1143)
		(layer "In11.Cu")
		(net "CLK_100M_PCH_XDP_DP")
	)
	(segment
		(start 371.157246 -113.042954)
		(end 371.157246 -110.168182)
		(width 0.1143)
		(layer "In11.Cu")
		(net "CLK_100M_PCH_XDP_DP")
	)
	(segment
		(start 348.495112 -116.36375)
		(end 348.869762 -116.36375)
		(width 0.1143)
		(layer "In11.Cu")
		(net "CLK_100M_PCH_XDP_DP")
	)
	(segment
		(start 371.31879 -110.572296)
		(end 370.707412 -109.960918)
		(width 0.0889)
		(layer "F.Cu")
		(net "CLK_100M_PCH_XDP_DN")
	)
	(segment
		(start 372.477284 -110.572296)
		(end 372.388384 -110.661196)
		(width 0.0889)
		(layer "F.Cu")
		(net "CLK_100M_PCH_XDP_DN")
	)
	(segment
		(start 458.62748 -145.63852)
		(end 458.37348 -145.63852)
		(width 0.127)
		(layer "F.Cu")
		(net "CLK_100M_PCH_XDP_DN")
	)
	(segment
		(start 372.032784 -110.572296)
		(end 371.31879 -110.572296)
		(width 0.0889)
		(layer "F.Cu")
		(net "CLK_100M_PCH_XDP_DN")
	)
	(segment
		(start 459.174596 -145.336768)
		(end 458.929232 -145.336768)
		(width 0.127)
		(layer "F.Cu")
		(net "CLK_100M_PCH_XDP_DN")
	)
	(segment
		(start 372.743984 -110.572296)
		(end 372.477284 -110.572296)
		(width 0.0889)
		(layer "F.Cu")
		(net "CLK_100M_PCH_XDP_DN")
	)
	(segment
		(start 373.801386 -110.918498)
		(end 373.712486 -111.007398)
		(width 0.0889)
		(layer "F.Cu")
		(net "CLK_100M_PCH_XDP_DN")
	)
	(segment
		(start 374.438418 -110.918498)
		(end 373.801386 -110.918498)
		(width 0.0889)
		(layer "F.Cu")
		(net "CLK_100M_PCH_XDP_DN")
	)
	(segment
		(start 458.2922 -145.7198)
		(end 457.252324 -145.7198)
		(width 0.127)
		(layer "F.Cu")
		(net "CLK_100M_PCH_XDP_DN")
	)
	(segment
		(start 372.388384 -110.661196)
		(end 372.121684 -110.661196)
		(width 0.0889)
		(layer "F.Cu")
		(net "CLK_100M_PCH_XDP_DN")
	)
	(segment
		(start 373.090186 -110.918498)
		(end 372.743984 -110.572296)
		(width 0.0889)
		(layer "F.Cu")
		(net "CLK_100M_PCH_XDP_DN")
	)
	(segment
		(start 374.501918 -110.854998)
		(end 374.438418 -110.918498)
		(width 0.0889)
		(layer "F.Cu")
		(net "CLK_100M_PCH_XDP_DN")
	)
	(segment
		(start 373.356886 -110.918498)
		(end 373.090186 -110.918498)
		(width 0.0889)
		(layer "F.Cu")
		(net "CLK_100M_PCH_XDP_DN")
	)
	(segment
		(start 374.674892 -110.854998)
		(end 374.501918 -110.854998)
		(width 0.0889)
		(layer "F.Cu")
		(net "CLK_100M_PCH_XDP_DN")
	)
	(segment
		(start 458.37348 -145.63852)
		(end 458.2922 -145.7198)
		(width 0.127)
		(layer "F.Cu")
		(net "CLK_100M_PCH_XDP_DN")
	)
	(segment
		(start 373.712486 -111.007398)
		(end 373.445786 -111.007398)
		(width 0.0889)
		(layer "F.Cu")
		(net "CLK_100M_PCH_XDP_DN")
	)
	(segment
		(start 459.246478 -145.57375)
		(end 459.246478 -145.40865)
		(width 0.127)
		(layer "F.Cu")
		(net "CLK_100M_PCH_XDP_DN")
	)
	(segment
		(start 370.707412 -109.960918)
		(end 370.707412 -109.944154)
		(width 0.0889)
		(layer "F.Cu")
		(net "CLK_100M_PCH_XDP_DN")
	)
	(segment
		(start 373.445786 -111.007398)
		(end 373.356886 -110.918498)
		(width 0.0889)
		(layer "F.Cu")
		(net "CLK_100M_PCH_XDP_DN")
	)
	(segment
		(start 372.121684 -110.661196)
		(end 372.032784 -110.572296)
		(width 0.0889)
		(layer "F.Cu")
		(net "CLK_100M_PCH_XDP_DN")
	)
	(segment
		(start 458.929232 -145.336768)
		(end 458.62748 -145.63852)
		(width 0.127)
		(layer "F.Cu")
		(net "CLK_100M_PCH_XDP_DN")
	)
	(segment
		(start 459.246478 -145.40865)
		(end 459.174596 -145.336768)
		(width 0.127)
		(layer "F.Cu")
		(net "CLK_100M_PCH_XDP_DN")
	)
	(via
		(at 459.246478 -145.57375)
		(size 0.508)
		(drill 0.254)
		(layers "F.Cu" "B.Cu")
		(net "CLK_100M_PCH_XDP_DN")
	)
	(via
		(at 349.765112 -116.36375)
		(size 0.508)
		(drill 0.254)
		(layers "F.Cu" "B.Cu")
		(net "CLK_100M_PCH_XDP_DN")
	)
	(via
		(at 370.707412 -109.944154)
		(size 0.508)
		(drill 0.254)
		(layers "F.Cu" "B.Cu")
		(net "CLK_100M_PCH_XDP_DN")
	)
	(segment
		(start 370.298726 -140.324078)
		(end 370.756434 -139.86637)
		(width 0.1143)
		(layer "In4.Cu")
		(net "CLK_100M_PCH_XDP_DN")
	)
	(segment
		(start 392.518646 -139.487656)
		(end 393.478766 -140.447776)
		(width 0.1143)
		(layer "In4.Cu")
		(net "CLK_100M_PCH_XDP_DN")
	)
	(segment
		(start 433.82184 -140.82395)
		(end 435.63159 -139.0142)
		(width 0.1143)
		(layer "In4.Cu")
		(net "CLK_100M_PCH_XDP_DN")
	)
	(segment
		(start 393.478766 -140.447776)
		(end 397.561816 -140.447776)
		(width 0.1143)
		(layer "In4.Cu")
		(net "CLK_100M_PCH_XDP_DN")
	)
	(segment
		(start 354.2538 -129.850642)
		(end 354.808282 -130.405124)
		(width 0.1143)
		(layer "In4.Cu")
		(net "CLK_100M_PCH_XDP_DN")
	)
	(segment
		(start 355.948742 -130.405124)
		(end 359.795318 -134.2517)
		(width 0.1143)
		(layer "In4.Cu")
		(net "CLK_100M_PCH_XDP_DN")
	)
	(segment
		(start 384.969512 -139.487656)
		(end 392.518646 -139.487656)
		(width 0.1143)
		(layer "In4.Cu")
		(net "CLK_100M_PCH_XDP_DN")
	)
	(segment
		(start 408.850338 -140.912596)
		(end 409.011374 -140.912596)
		(width 0.1143)
		(layer "In4.Cu")
		(net "CLK_100M_PCH_XDP_DN")
	)
	(segment
		(start 458.3811 -142.386558)
		(end 458.3811 -145.053558)
		(width 0.1143)
		(layer "In4.Cu")
		(net "CLK_100M_PCH_XDP_DN")
	)
	(segment
		(start 443.478412 -138.10107)
		(end 444.086742 -138.7094)
		(width 0.1143)
		(layer "In4.Cu")
		(net "CLK_100M_PCH_XDP_DN")
	)
	(segment
		(start 348.984062 -123.113292)
		(end 348.984062 -126.400814)
		(width 0.1143)
		(layer "In4.Cu")
		(net "CLK_100M_PCH_XDP_DN")
	)
	(segment
		(start 349.274384 -115.834668)
		(end 348.912942 -115.473226)
		(width 0.1143)
		(layer "In4.Cu")
		(net "CLK_100M_PCH_XDP_DN")
	)
	(segment
		(start 439.417968 -138.10107)
		(end 443.478412 -138.10107)
		(width 0.1143)
		(layer "In4.Cu")
		(net "CLK_100M_PCH_XDP_DN")
	)
	(segment
		(start 364.68177 -139.02182)
		(end 365.984028 -140.324078)
		(width 0.1143)
		(layer "In4.Cu")
		(net "CLK_100M_PCH_XDP_DN")
	)
	(segment
		(start 455.295 -141.1986)
		(end 457.193142 -141.1986)
		(width 0.1143)
		(layer "In4.Cu")
		(net "CLK_100M_PCH_XDP_DN")
	)
	(segment
		(start 365.984028 -140.324078)
		(end 370.298726 -140.324078)
		(width 0.1143)
		(layer "In4.Cu")
		(net "CLK_100M_PCH_XDP_DN")
	)
	(segment
		(start 384.590798 -139.86637)
		(end 384.969512 -139.487656)
		(width 0.1143)
		(layer "In4.Cu")
		(net "CLK_100M_PCH_XDP_DN")
	)
	(segment
		(start 457.193142 -141.1986)
		(end 458.3811 -142.386558)
		(width 0.1143)
		(layer "In4.Cu")
		(net "CLK_100M_PCH_XDP_DN")
	)
	(segment
		(start 447.397632 -138.7094)
		(end 449.507356 -136.599676)
		(width 0.1143)
		(layer "In4.Cu")
		(net "CLK_100M_PCH_XDP_DN")
	)
	(segment
		(start 410.831538 -140.15847)
		(end 420.442136 -140.15847)
		(width 0.1143)
		(layer "In4.Cu")
		(net "CLK_100M_PCH_XDP_DN")
	)
	(segment
		(start 459.011528 -145.3388)
		(end 459.246478 -145.57375)
		(width 0.1143)
		(layer "In4.Cu")
		(net "CLK_100M_PCH_XDP_DN")
	)
	(segment
		(start 420.442136 -140.15847)
		(end 421.107616 -140.82395)
		(width 0.1143)
		(layer "In4.Cu")
		(net "CLK_100M_PCH_XDP_DN")
	)
	(segment
		(start 402.46046 -142.022576)
		(end 406.172416 -142.022576)
		(width 0.1143)
		(layer "In4.Cu")
		(net "CLK_100M_PCH_XDP_DN")
	)
	(segment
		(start 453.0471 -138.2903)
		(end 453.4027 -138.2903)
		(width 0.1143)
		(layer "In4.Cu")
		(net "CLK_100M_PCH_XDP_DN")
	)
	(segment
		(start 401.936966 -141.499082)
		(end 402.46046 -142.022576)
		(width 0.1143)
		(layer "In4.Cu")
		(net "CLK_100M_PCH_XDP_DN")
	)
	(segment
		(start 454.9394 -140.843)
		(end 455.295 -141.1986)
		(width 0.1143)
		(layer "In4.Cu")
		(net "CLK_100M_PCH_XDP_DN")
	)
	(segment
		(start 398.613122 -141.499082)
		(end 401.936966 -141.499082)
		(width 0.1143)
		(layer "In4.Cu")
		(net "CLK_100M_PCH_XDP_DN")
	)
	(segment
		(start 397.561816 -140.447776)
		(end 398.613122 -141.499082)
		(width 0.1143)
		(layer "In4.Cu")
		(net "CLK_100M_PCH_XDP_DN")
	)
	(segment
		(start 364.68177 -134.695692)
		(end 364.68177 -139.02182)
		(width 0.1143)
		(layer "In4.Cu")
		(net "CLK_100M_PCH_XDP_DN")
	)
	(segment
		(start 347.420438 -115.473226)
		(end 347.02877 -115.864894)
		(width 0.1143)
		(layer "In4.Cu")
		(net "CLK_100M_PCH_XDP_DN")
	)
	(segment
		(start 435.63159 -139.0142)
		(end 438.504838 -139.0142)
		(width 0.1143)
		(layer "In4.Cu")
		(net "CLK_100M_PCH_XDP_DN")
	)
	(segment
		(start 444.086742 -138.7094)
		(end 447.397632 -138.7094)
		(width 0.1143)
		(layer "In4.Cu")
		(net "CLK_100M_PCH_XDP_DN")
	)
	(segment
		(start 349.274384 -116.24945)
		(end 349.274384 -115.834668)
		(width 0.1143)
		(layer "In4.Cu")
		(net "CLK_100M_PCH_XDP_DN")
	)
	(segment
		(start 347.02877 -115.864894)
		(end 347.02877 -121.158)
		(width 0.1143)
		(layer "In4.Cu")
		(net "CLK_100M_PCH_XDP_DN")
	)
	(segment
		(start 359.795318 -134.2517)
		(end 364.237778 -134.2517)
		(width 0.1143)
		(layer "In4.Cu")
		(net "CLK_100M_PCH_XDP_DN")
	)
	(segment
		(start 421.107616 -140.82395)
		(end 433.82184 -140.82395)
		(width 0.1143)
		(layer "In4.Cu")
		(net "CLK_100M_PCH_XDP_DN")
	)
	(segment
		(start 347.02877 -121.158)
		(end 348.984062 -123.113292)
		(width 0.1143)
		(layer "In4.Cu")
		(net "CLK_100M_PCH_XDP_DN")
	)
	(segment
		(start 458.666342 -145.3388)
		(end 459.011528 -145.3388)
		(width 0.1143)
		(layer "In4.Cu")
		(net "CLK_100M_PCH_XDP_DN")
	)
	(segment
		(start 349.765112 -116.36375)
		(end 349.388684 -116.36375)
		(width 0.1143)
		(layer "In4.Cu")
		(net "CLK_100M_PCH_XDP_DN")
	)
	(segment
		(start 348.912942 -115.473226)
		(end 347.420438 -115.473226)
		(width 0.1143)
		(layer "In4.Cu")
		(net "CLK_100M_PCH_XDP_DN")
	)
	(segment
		(start 352.43389 -129.850642)
		(end 354.2538 -129.850642)
		(width 0.1143)
		(layer "In4.Cu")
		(net "CLK_100M_PCH_XDP_DN")
	)
	(segment
		(start 451.356476 -136.599676)
		(end 453.0471 -138.2903)
		(width 0.1143)
		(layer "In4.Cu")
		(net "CLK_100M_PCH_XDP_DN")
	)
	(segment
		(start 364.237778 -134.2517)
		(end 364.68177 -134.695692)
		(width 0.1143)
		(layer "In4.Cu")
		(net "CLK_100M_PCH_XDP_DN")
	)
	(segment
		(start 409.011374 -140.912596)
		(end 410.831538 -140.15847)
		(width 0.1143)
		(layer "In4.Cu")
		(net "CLK_100M_PCH_XDP_DN")
	)
	(segment
		(start 406.172416 -142.022576)
		(end 408.850338 -140.912596)
		(width 0.1143)
		(layer "In4.Cu")
		(net "CLK_100M_PCH_XDP_DN")
	)
	(segment
		(start 348.984062 -126.400814)
		(end 352.43389 -129.850642)
		(width 0.1143)
		(layer "In4.Cu")
		(net "CLK_100M_PCH_XDP_DN")
	)
	(segment
		(start 370.756434 -139.86637)
		(end 384.590798 -139.86637)
		(width 0.1143)
		(layer "In4.Cu")
		(net "CLK_100M_PCH_XDP_DN")
	)
	(segment
		(start 453.4027 -138.2903)
		(end 454.9394 -139.827)
		(width 0.1143)
		(layer "In4.Cu")
		(net "CLK_100M_PCH_XDP_DN")
	)
	(segment
		(start 354.808282 -130.405124)
		(end 355.948742 -130.405124)
		(width 0.1143)
		(layer "In4.Cu")
		(net "CLK_100M_PCH_XDP_DN")
	)
	(segment
		(start 454.9394 -139.827)
		(end 454.9394 -140.843)
		(width 0.1143)
		(layer "In4.Cu")
		(net "CLK_100M_PCH_XDP_DN")
	)
	(segment
		(start 449.507356 -136.599676)
		(end 451.356476 -136.599676)
		(width 0.1143)
		(layer "In4.Cu")
		(net "CLK_100M_PCH_XDP_DN")
	)
	(segment
		(start 438.504838 -139.0142)
		(end 439.417968 -138.10107)
		(width 0.1143)
		(layer "In4.Cu")
		(net "CLK_100M_PCH_XDP_DN")
	)
	(segment
		(start 349.388684 -116.36375)
		(end 349.274384 -116.24945)
		(width 0.1143)
		(layer "In4.Cu")
		(net "CLK_100M_PCH_XDP_DN")
	)
	(segment
		(start 458.3811 -145.053558)
		(end 458.666342 -145.3388)
		(width 0.1143)
		(layer "In4.Cu")
		(net "CLK_100M_PCH_XDP_DN")
	)
	(segment
		(start 361.207558 -116.696744)
		(end 361.550458 -116.696744)
		(width 0.1143)
		(layer "In11.Cu")
		(net "CLK_100M_PCH_XDP_DN")
	)
	(segment
		(start 370.865146 -110.101888)
		(end 370.707412 -109.944154)
		(width 0.1143)
		(layer "In11.Cu")
		(net "CLK_100M_PCH_XDP_DN")
	)
	(segment
		(start 352.65614 -116.861844)
		(end 355.206046 -116.861844)
		(width 0.1143)
		(layer "In11.Cu")
		(net "CLK_100M_PCH_XDP_DN")
	)
	(segment
		(start 361.550458 -116.696744)
		(end 361.715558 -116.861844)
		(width 0.1143)
		(layer "In11.Cu")
		(net "CLK_100M_PCH_XDP_DN")
	)
	(segment
		(start 351.13214 -116.696744)
		(end 351.47504 -116.696744)
		(width 0.1143)
		(layer "In11.Cu")
		(net "CLK_100M_PCH_XDP_DN")
	)
	(segment
		(start 350.96704 -116.861844)
		(end 351.13214 -116.696744)
		(width 0.1143)
		(layer "In11.Cu")
		(net "CLK_100M_PCH_XDP_DN")
	)
	(segment
		(start 355.371146 -116.696744)
		(end 355.714046 -116.696744)
		(width 0.1143)
		(layer "In11.Cu")
		(net "CLK_100M_PCH_XDP_DN")
	)
	(segment
		(start 349.276162 -116.47805)
		(end 349.276162 -116.663216)
		(width 0.1143)
		(layer "In11.Cu")
		(net "CLK_100M_PCH_XDP_DN")
	)
	(segment
		(start 362.058458 -116.861844)
		(end 362.223558 -116.696744)
		(width 0.1143)
		(layer "In11.Cu")
		(net "CLK_100M_PCH_XDP_DN")
	)
	(segment
		(start 362.223558 -116.696744)
		(end 362.566458 -116.696744)
		(width 0.1143)
		(layer "In11.Cu")
		(net "CLK_100M_PCH_XDP_DN")
	)
	(segment
		(start 361.715558 -116.861844)
		(end 362.058458 -116.861844)
		(width 0.1143)
		(layer "In11.Cu")
		(net "CLK_100M_PCH_XDP_DN")
	)
	(segment
		(start 352.14814 -116.696744)
		(end 352.49104 -116.696744)
		(width 0.1143)
		(layer "In11.Cu")
		(net "CLK_100M_PCH_XDP_DN")
	)
	(segment
		(start 359.010458 -116.861844)
		(end 359.175558 -116.696744)
		(width 0.1143)
		(layer "In11.Cu")
		(net "CLK_100M_PCH_XDP_DN")
	)
	(segment
		(start 355.714046 -116.696744)
		(end 355.879146 -116.861844)
		(width 0.1143)
		(layer "In11.Cu")
		(net "CLK_100M_PCH_XDP_DN")
	)
	(segment
		(start 351.47504 -116.696744)
		(end 351.64014 -116.861844)
		(width 0.1143)
		(layer "In11.Cu")
		(net "CLK_100M_PCH_XDP_DN")
	)
	(segment
		(start 352.49104 -116.696744)
		(end 352.65614 -116.861844)
		(width 0.1143)
		(layer "In11.Cu")
		(net "CLK_100M_PCH_XDP_DN")
	)
	(segment
		(start 359.683558 -116.861844)
		(end 360.026458 -116.861844)
		(width 0.1143)
		(layer "In11.Cu")
		(net "CLK_100M_PCH_XDP_DN")
	)
	(segment
		(start 351.98304 -116.861844)
		(end 352.14814 -116.696744)
		(width 0.1143)
		(layer "In11.Cu")
		(net "CLK_100M_PCH_XDP_DN")
	)
	(segment
		(start 355.879146 -116.861844)
		(end 359.010458 -116.861844)
		(width 0.1143)
		(layer "In11.Cu")
		(net "CLK_100M_PCH_XDP_DN")
	)
	(segment
		(start 359.175558 -116.696744)
		(end 359.518458 -116.696744)
		(width 0.1143)
		(layer "In11.Cu")
		(net "CLK_100M_PCH_XDP_DN")
	)
	(segment
		(start 360.534458 -116.696744)
		(end 360.699558 -116.861844)
		(width 0.1143)
		(layer "In11.Cu")
		(net "CLK_100M_PCH_XDP_DN")
	)
	(segment
		(start 360.699558 -116.861844)
		(end 361.042458 -116.861844)
		(width 0.1143)
		(layer "In11.Cu")
		(net "CLK_100M_PCH_XDP_DN")
	)
	(segment
		(start 360.191558 -116.696744)
		(end 360.534458 -116.696744)
		(width 0.1143)
		(layer "In11.Cu")
		(net "CLK_100M_PCH_XDP_DN")
	)
	(segment
		(start 351.64014 -116.861844)
		(end 351.98304 -116.861844)
		(width 0.1143)
		(layer "In11.Cu")
		(net "CLK_100M_PCH_XDP_DN")
	)
	(segment
		(start 369.378992 -114.40795)
		(end 370.865146 -112.921796)
		(width 0.1143)
		(layer "In11.Cu")
		(net "CLK_100M_PCH_XDP_DN")
	)
	(segment
		(start 370.865146 -112.921796)
		(end 370.865146 -110.101888)
		(width 0.1143)
		(layer "In11.Cu")
		(net "CLK_100M_PCH_XDP_DN")
	)
	(segment
		(start 349.47479 -116.861844)
		(end 350.96704 -116.861844)
		(width 0.1143)
		(layer "In11.Cu")
		(net "CLK_100M_PCH_XDP_DN")
	)
	(segment
		(start 349.276162 -116.663216)
		(end 349.47479 -116.861844)
		(width 0.1143)
		(layer "In11.Cu")
		(net "CLK_100M_PCH_XDP_DN")
	)
	(segment
		(start 355.206046 -116.861844)
		(end 355.371146 -116.696744)
		(width 0.1143)
		(layer "In11.Cu")
		(net "CLK_100M_PCH_XDP_DN")
	)
	(segment
		(start 349.390462 -116.36375)
		(end 349.276162 -116.47805)
		(width 0.1143)
		(layer "In11.Cu")
		(net "CLK_100M_PCH_XDP_DN")
	)
	(segment
		(start 359.518458 -116.696744)
		(end 359.683558 -116.861844)
		(width 0.1143)
		(layer "In11.Cu")
		(net "CLK_100M_PCH_XDP_DN")
	)
	(segment
		(start 368.591846 -114.40795)
		(end 369.378992 -114.40795)
		(width 0.1143)
		(layer "In11.Cu")
		(net "CLK_100M_PCH_XDP_DN")
	)
	(segment
		(start 349.765112 -116.36375)
		(end 349.390462 -116.36375)
		(width 0.1143)
		(layer "In11.Cu")
		(net "CLK_100M_PCH_XDP_DN")
	)
	(segment
		(start 362.566458 -116.696744)
		(end 362.731558 -116.861844)
		(width 0.1143)
		(layer "In11.Cu")
		(net "CLK_100M_PCH_XDP_DN")
	)
	(segment
		(start 366.137952 -116.861844)
		(end 368.591846 -114.40795)
		(width 0.1143)
		(layer "In11.Cu")
		(net "CLK_100M_PCH_XDP_DN")
	)
	(segment
		(start 361.042458 -116.861844)
		(end 361.207558 -116.696744)
		(width 0.1143)
		(layer "In11.Cu")
		(net "CLK_100M_PCH_XDP_DN")
	)
	(segment
		(start 362.731558 -116.861844)
		(end 366.137952 -116.861844)
		(width 0.1143)
		(layer "In11.Cu")
		(net "CLK_100M_PCH_XDP_DN")
	)
	(segment
		(start 360.026458 -116.861844)
		(end 360.191558 -116.696744)
		(width 0.1143)
		(layer "In11.Cu")
		(net "CLK_100M_PCH_XDP_DN")
	)
	(segment
		(start 162.5727 -85.1408)
		(end 162.102546 -85.1408)
		(width 0.1143)
		(layer "F.Cu")
		(net "CLK_100M_CPU1_BCLK2_DP")
	)
	(segment
		(start 161.970974 -85.272372)
		(end 161.970974 -85.69706)
		(width 0.1143)
		(layer "F.Cu")
		(net "CLK_100M_CPU1_BCLK2_DP")
	)
	(segment
		(start 162.102546 -85.1408)
		(end 161.970974 -85.272372)
		(width 0.1143)
		(layer "F.Cu")
		(net "CLK_100M_CPU1_BCLK2_DP")
	)
	(segment
		(start 162.687 -85.598)
		(end 162.687 -85.2551)
		(width 0.1143)
		(layer "F.Cu")
		(net "CLK_100M_CPU1_BCLK2_DP")
	)
	(segment
		(start 121.359168 -89.089738)
		(end 120.787668 -89.089738)
		(width 0.1143)
		(layer "F.Cu")
		(net "CLK_100M_CPU1_BCLK2_DP")
	)
	(segment
		(start 162.687 -85.2551)
		(end 162.5727 -85.1408)
		(width 0.1143)
		(layer "F.Cu")
		(net "CLK_100M_CPU1_BCLK2_DP")
	)
	(via
		(at 161.970974 -85.69706)
		(size 0.508)
		(drill 0.254)
		(layers "F.Cu" "B.Cu")
		(net "CLK_100M_CPU1_BCLK2_DP")
	)
	(via
		(at 121.359168 -89.089738)
		(size 0.508)
		(drill 0.254)
		(layers "F.Cu" "B.Cu")
		(net "CLK_100M_CPU1_BCLK2_DP")
	)
	(segment
		(start 162.413188 -85.098128)
		(end 162.91306 -85.598)
		(width 0.1143)
		(layer "B.Cu")
		(net "CLK_100M_CPU1_BCLK2_DP")
	)
	(segment
		(start 162.145726 -85.098128)
		(end 162.413188 -85.098128)
		(width 0.1143)
		(layer "B.Cu")
		(net "CLK_100M_CPU1_BCLK2_DP")
	)
	(segment
		(start 161.970974 -85.69706)
		(end 161.970974 -85.27288)
		(width 0.1143)
		(layer "B.Cu")
		(net "CLK_100M_CPU1_BCLK2_DP")
	)
	(segment
		(start 161.970974 -85.27288)
		(end 162.145726 -85.098128)
		(width 0.1143)
		(layer "B.Cu")
		(net "CLK_100M_CPU1_BCLK2_DP")
	)
	(segment
		(start 132.494782 -89.184734)
		(end 132.541264 -89.184734)
		(width 0.0889)
		(layer "In4.Cu")
		(net "CLK_100M_CPU1_BCLK2_DP")
	)
	(segment
		(start 122.196098 -89.184734)
		(end 122.239278 -89.184734)
		(width 0.0889)
		(layer "In4.Cu")
		(net "CLK_100M_CPU1_BCLK2_DP")
	)
	(segment
		(start 147.2946 -92.658438)
		(end 147.4089 -92.772738)
		(width 0.1143)
		(layer "In4.Cu")
		(net "CLK_100M_CPU1_BCLK2_DP")
	)
	(segment
		(start 148.5138 -101.27869)
		(end 148.5138 -97.053654)
		(width 0.1143)
		(layer "In4.Cu")
		(net "CLK_100M_CPU1_BCLK2_DP")
	)
	(segment
		(start 161.970974 -85.33892)
		(end 161.970974 -85.69706)
		(width 0.1143)
		(layer "In4.Cu")
		(net "CLK_100M_CPU1_BCLK2_DP")
	)
	(segment
		(start 147.694142 -101.57841)
		(end 148.21408 -101.57841)
		(width 0.1143)
		(layer "In4.Cu")
		(net "CLK_100M_CPU1_BCLK2_DP")
	)
	(segment
		(start 158.8262 -97.733358)
		(end 158.8262 -85.598)
		(width 0.1143)
		(layer "In4.Cu")
		(net "CLK_100M_CPU1_BCLK2_DP")
	)
	(segment
		(start 159.3469 -85.598)
		(end 159.3469 -97.34169)
		(width 0.1143)
		(layer "In4.Cu")
		(net "CLK_100M_CPU1_BCLK2_DP")
	)
	(segment
		(start 141.093698 -88.194134)
		(end 143.525494 -88.194134)
		(width 0.0889)
		(layer "In4.Cu")
		(net "CLK_100M_CPU1_BCLK2_DP")
	)
	(segment
		(start 123.061222 -88.689688)
		(end 123.091194 -88.689688)
		(width 0.0889)
		(layer "In4.Cu")
		(net "CLK_100M_CPU1_BCLK2_DP")
	)
	(segment
		(start 146.079718 -101.695758)
		(end 146.599656 -101.695758)
		(width 0.1143)
		(layer "In4.Cu")
		(net "CLK_100M_CPU1_BCLK2_DP")
	)
	(segment
		(start 143.525494 -88.194134)
		(end 143.576294 -88.244934)
		(width 0.0889)
		(layer "In4.Cu")
		(net "CLK_100M_CPU1_BCLK2_DP")
	)
	(segment
		(start 147.00631 -102.930452)
		(end 147.291552 -103.215694)
		(width 0.1143)
		(layer "In4.Cu")
		(net "CLK_100M_CPU1_BCLK2_DP")
	)
	(segment
		(start 146.8882 -101.407214)
		(end 146.8882 -92.772738)
		(width 0.1143)
		(layer "In4.Cu")
		(net "CLK_100M_CPU1_BCLK2_DP")
	)
	(segment
		(start 160.6296 -85.4075)
		(end 160.8455 -85.1916)
		(width 0.1143)
		(layer "In4.Cu")
		(net "CLK_100M_CPU1_BCLK2_DP")
	)
	(segment
		(start 159.406844 -98.30308)
		(end 158.993078 -98.30308)
		(width 0.1143)
		(layer "In4.Cu")
		(net "CLK_100M_CPU1_BCLK2_DP")
	)
	(segment
		(start 154.839162 -101.711506)
		(end 154.839162 -101.996494)
		(width 0.1143)
		(layer "In4.Cu")
		(net "CLK_100M_CPU1_BCLK2_DP")
	)
	(segment
		(start 149.0345 -97.053654)
		(end 149.0345 -100.696268)
		(width 0.1143)
		(layer "In4.Cu")
		(net "CLK_100M_CPU1_BCLK2_DP")
	)
	(segment
		(start 148.5138 -97.053654)
		(end 148.6281 -96.939354)
		(width 0.1143)
		(layer "In4.Cu")
		(net "CLK_100M_CPU1_BCLK2_DP")
	)
	(segment
		(start 158.8262 -85.598)
		(end 158.9405 -85.4837)
		(width 0.1143)
		(layer "In4.Cu")
		(net "CLK_100M_CPU1_BCLK2_DP")
	)
	(segment
		(start 147.0025 -92.658438)
		(end 147.2946 -92.658438)
		(width 0.1143)
		(layer "In4.Cu")
		(net "CLK_100M_CPU1_BCLK2_DP")
	)
	(segment
		(start 131.646422 -88.689688)
		(end 131.661408 -88.689688)
		(width 0.0889)
		(layer "In4.Cu")
		(net "CLK_100M_CPU1_BCLK2_DP")
	)
	(segment
		(start 143.598392 -88.244934)
		(end 144.905476 -88.244934)
		(width 0.1143)
		(layer "In4.Cu")
		(net "CLK_100M_CPU1_BCLK2_DP")
	)
	(segment
		(start 148.9202 -96.939354)
		(end 149.0345 -97.053654)
		(width 0.1143)
		(layer "In4.Cu")
		(net "CLK_100M_CPU1_BCLK2_DP")
	)
	(segment
		(start 145.7833 -101.39934)
		(end 146.079718 -101.695758)
		(width 0.1143)
		(layer "In4.Cu")
		(net "CLK_100M_CPU1_BCLK2_DP")
	)
	(segment
		(start 129.064258 -89.184734)
		(end 129.107438 -89.184734)
		(width 0.0889)
		(layer "In4.Cu")
		(net "CLK_100M_CPU1_BCLK2_DP")
	)
	(segment
		(start 156.164026 -100.395532)
		(end 158.8262 -97.733358)
		(width 0.1143)
		(layer "In4.Cu")
		(net "CLK_100M_CPU1_BCLK2_DP")
	)
	(segment
		(start 143.576294 -88.244934)
		(end 143.598392 -88.244934)
		(width 0.0889)
		(layer "In4.Cu")
		(net "CLK_100M_CPU1_BCLK2_DP")
	)
	(segment
		(start 128.212342 -88.689688)
		(end 128.242314 -88.689688)
		(width 0.0889)
		(layer "In4.Cu")
		(net "CLK_100M_CPU1_BCLK2_DP")
	)
	(segment
		(start 156.356558 -100.749608)
		(end 156.164026 -100.557076)
		(width 0.1143)
		(layer "In4.Cu")
		(net "CLK_100M_CPU1_BCLK2_DP")
	)
	(segment
		(start 146.8882 -92.772738)
		(end 147.0025 -92.658438)
		(width 0.1143)
		(layer "In4.Cu")
		(net "CLK_100M_CPU1_BCLK2_DP")
	)
	(segment
		(start 154.724862 -102.110794)
		(end 147.291552 -102.110794)
		(width 0.1143)
		(layer "In4.Cu")
		(net "CLK_100M_CPU1_BCLK2_DP")
	)
	(segment
		(start 125.630178 -89.184734)
		(end 125.673358 -89.184734)
		(width 0.0889)
		(layer "In4.Cu")
		(net "CLK_100M_CPU1_BCLK2_DP")
	)
	(segment
		(start 144.905476 -88.244934)
		(end 145.7833 -89.122758)
		(width 0.1143)
		(layer "In4.Cu")
		(net "CLK_100M_CPU1_BCLK2_DP")
	)
	(segment
		(start 160.8455 -85.1916)
		(end 161.823654 -85.1916)
		(width 0.1143)
		(layer "In4.Cu")
		(net "CLK_100M_CPU1_BCLK2_DP")
	)
	(segment
		(start 124.778262 -88.689688)
		(end 124.808234 -88.689688)
		(width 0.0889)
		(layer "In4.Cu")
		(net "CLK_100M_CPU1_BCLK2_DP")
	)
	(segment
		(start 149.928326 -101.590094)
		(end 154.71775 -101.590094)
		(width 0.1143)
		(layer "In4.Cu")
		(net "CLK_100M_CPU1_BCLK2_DP")
	)
	(segment
		(start 148.21408 -101.57841)
		(end 148.5138 -101.27869)
		(width 0.1143)
		(layer "In4.Cu")
		(net "CLK_100M_CPU1_BCLK2_DP")
	)
	(segment
		(start 159.774636 -99.0854)
		(end 159.774636 -98.670872)
		(width 0.1143)
		(layer "In4.Cu")
		(net "CLK_100M_CPU1_BCLK2_DP")
	)
	(segment
		(start 159.632142 -97.626932)
		(end 160.305242 -97.626932)
		(width 0.1143)
		(layer "In4.Cu")
		(net "CLK_100M_CPU1_BCLK2_DP")
	)
	(segment
		(start 154.71775 -101.590094)
		(end 154.839162 -101.711506)
		(width 0.1143)
		(layer "In4.Cu")
		(net "CLK_100M_CPU1_BCLK2_DP")
	)
	(segment
		(start 147.291552 -102.110794)
		(end 147.00631 -102.396036)
		(width 0.1143)
		(layer "In4.Cu")
		(net "CLK_100M_CPU1_BCLK2_DP")
	)
	(segment
		(start 146.599656 -101.695758)
		(end 146.8882 -101.407214)
		(width 0.1143)
		(layer "In4.Cu")
		(net "CLK_100M_CPU1_BCLK2_DP")
	)
	(segment
		(start 140.231368 -88.689688)
		(end 140.264134 -88.689688)
		(width 0.0889)
		(layer "In4.Cu")
		(net "CLK_100M_CPU1_BCLK2_DP")
	)
	(segment
		(start 155.644342 -103.215694)
		(end 159.774636 -99.0854)
		(width 0.1143)
		(layer "In4.Cu")
		(net "CLK_100M_CPU1_BCLK2_DP")
	)
	(segment
		(start 133.363208 -88.689688)
		(end 133.39318 -88.689688)
		(width 0.0889)
		(layer "In4.Cu")
		(net "CLK_100M_CPU1_BCLK2_DP")
	)
	(segment
		(start 138.514328 -88.689688)
		(end 138.5443 -88.689688)
		(width 0.0889)
		(layer "In4.Cu")
		(net "CLK_100M_CPU1_BCLK2_DP")
	)
	(segment
		(start 147.4089 -101.293168)
		(end 147.694142 -101.57841)
		(width 0.1143)
		(layer "In4.Cu")
		(net "CLK_100M_CPU1_BCLK2_DP")
	)
	(segment
		(start 132.004562 -88.883998)
		(end 132.007864 -88.88984)
		(width 0.0889)
		(layer "In4.Cu")
		(net "CLK_100M_CPU1_BCLK2_DP")
	)
	(segment
		(start 159.774636 -98.670872)
		(end 159.406844 -98.30308)
		(width 0.1143)
		(layer "In4.Cu")
		(net "CLK_100M_CPU1_BCLK2_DP")
	)
	(segment
		(start 147.291552 -103.215694)
		(end 155.644342 -103.215694)
		(width 0.1143)
		(layer "In4.Cu")
		(net "CLK_100M_CPU1_BCLK2_DP")
	)
	(segment
		(start 130.781298 -89.184734)
		(end 130.824478 -89.184734)
		(width 0.0889)
		(layer "In4.Cu")
		(net "CLK_100M_CPU1_BCLK2_DP")
	)
	(segment
		(start 139.366244 -89.184734)
		(end 139.409424 -89.184734)
		(width 0.0889)
		(layer "In4.Cu")
		(net "CLK_100M_CPU1_BCLK2_DP")
	)
	(segment
		(start 160.305242 -97.626932)
		(end 160.6296 -97.302574)
		(width 0.1143)
		(layer "In4.Cu")
		(net "CLK_100M_CPU1_BCLK2_DP")
	)
	(segment
		(start 160.6296 -97.302574)
		(end 160.6296 -85.4075)
		(width 0.1143)
		(layer "In4.Cu")
		(net "CLK_100M_CPU1_BCLK2_DP")
	)
	(segment
		(start 159.2326 -85.4837)
		(end 159.3469 -85.598)
		(width 0.1143)
		(layer "In4.Cu")
		(net "CLK_100M_CPU1_BCLK2_DP")
	)
	(segment
		(start 156.54655 -100.749608)
		(end 156.356558 -100.749608)
		(width 0.1143)
		(layer "In4.Cu")
		(net "CLK_100M_CPU1_BCLK2_DP")
	)
	(segment
		(start 154.839162 -101.996494)
		(end 154.724862 -102.110794)
		(width 0.1143)
		(layer "In4.Cu")
		(net "CLK_100M_CPU1_BCLK2_DP")
	)
	(segment
		(start 135.932164 -89.184734)
		(end 135.975344 -89.184734)
		(width 0.0889)
		(layer "In4.Cu")
		(net "CLK_100M_CPU1_BCLK2_DP")
	)
	(segment
		(start 147.4089 -92.772738)
		(end 147.4089 -101.293168)
		(width 0.1143)
		(layer "In4.Cu")
		(net "CLK_100M_CPU1_BCLK2_DP")
	)
	(segment
		(start 134.215124 -89.184734)
		(end 134.258304 -89.184734)
		(width 0.0889)
		(layer "In4.Cu")
		(net "CLK_100M_CPU1_BCLK2_DP")
	)
	(segment
		(start 156.164026 -100.557076)
		(end 156.164026 -100.395532)
		(width 0.1143)
		(layer "In4.Cu")
		(net "CLK_100M_CPU1_BCLK2_DP")
	)
	(segment
		(start 148.6281 -96.939354)
		(end 148.9202 -96.939354)
		(width 0.1143)
		(layer "In4.Cu")
		(net "CLK_100M_CPU1_BCLK2_DP")
	)
	(segment
		(start 137.649204 -89.184734)
		(end 137.692384 -89.184734)
		(width 0.0889)
		(layer "In4.Cu")
		(net "CLK_100M_CPU1_BCLK2_DP")
	)
	(segment
		(start 158.9405 -85.4837)
		(end 159.2326 -85.4837)
		(width 0.1143)
		(layer "In4.Cu")
		(net "CLK_100M_CPU1_BCLK2_DP")
	)
	(segment
		(start 161.823654 -85.1916)
		(end 161.970974 -85.33892)
		(width 0.1143)
		(layer "In4.Cu")
		(net "CLK_100M_CPU1_BCLK2_DP")
	)
	(segment
		(start 129.929382 -88.689688)
		(end 129.959354 -88.689688)
		(width 0.0889)
		(layer "In4.Cu")
		(net "CLK_100M_CPU1_BCLK2_DP")
	)
	(segment
		(start 147.00631 -102.396036)
		(end 147.00631 -102.930452)
		(width 0.1143)
		(layer "In4.Cu")
		(net "CLK_100M_CPU1_BCLK2_DP")
	)
	(segment
		(start 158.993078 -98.30308)
		(end 156.54655 -100.749608)
		(width 0.1143)
		(layer "In4.Cu")
		(net "CLK_100M_CPU1_BCLK2_DP")
	)
	(segment
		(start 149.0345 -100.696268)
		(end 149.928326 -101.590094)
		(width 0.1143)
		(layer "In4.Cu")
		(net "CLK_100M_CPU1_BCLK2_DP")
	)
	(segment
		(start 159.3469 -97.34169)
		(end 159.632142 -97.626932)
		(width 0.1143)
		(layer "In4.Cu")
		(net "CLK_100M_CPU1_BCLK2_DP")
	)
	(segment
		(start 145.7833 -89.122758)
		(end 145.7833 -101.39934)
		(width 0.1143)
		(layer "In4.Cu")
		(net "CLK_100M_CPU1_BCLK2_DP")
	)
	(segment
		(start 123.913138 -89.184734)
		(end 123.956318 -89.184734)
		(width 0.0889)
		(layer "In4.Cu")
		(net "CLK_100M_CPU1_BCLK2_DP")
	)
	(arc
		(start 133.724904 -88.889586)
		(mid 133.931908 -89.10045)
		(end 134.215124 -89.184734)
		(width 0.0889)
		(layer "In4.Cu")
		(net "CLK_100M_CPU1_BCLK2_DP")
	)
	(arc
		(start 140.758164 -88.394286)
		(mid 140.899847 -88.250482)
		(end 141.093698 -88.194134)
		(width 0.0889)
		(layer "In4.Cu")
		(net "CLK_100M_CPU1_BCLK2_DP")
	)
	(arc
		(start 123.956318 -89.184734)
		(mid 124.239535 -89.100453)
		(end 124.446538 -88.889586)
		(width 0.0889)
		(layer "In4.Cu")
		(net "CLK_100M_CPU1_BCLK2_DP")
	)
	(arc
		(start 129.107438 -89.184734)
		(mid 129.390655 -89.100453)
		(end 129.597658 -88.889586)
		(width 0.0889)
		(layer "In4.Cu")
		(net "CLK_100M_CPU1_BCLK2_DP")
	)
	(arc
		(start 132.541264 -89.184734)
		(mid 132.824481 -89.100453)
		(end 133.031484 -88.889586)
		(width 0.0889)
		(layer "In4.Cu")
		(net "CLK_100M_CPU1_BCLK2_DP")
	)
	(arc
		(start 127.880618 -88.889586)
		(mid 128.020697 -88.74685)
		(end 128.212342 -88.689688)
		(width 0.0889)
		(layer "In4.Cu")
		(net "CLK_100M_CPU1_BCLK2_DP")
	)
	(arc
		(start 137.158984 -88.889586)
		(mid 137.365988 -89.10045)
		(end 137.649204 -89.184734)
		(width 0.0889)
		(layer "In4.Cu")
		(net "CLK_100M_CPU1_BCLK2_DP")
	)
	(arc
		(start 135.441944 -88.889586)
		(mid 135.648948 -89.10045)
		(end 135.932164 -89.184734)
		(width 0.0889)
		(layer "In4.Cu")
		(net "CLK_100M_CPU1_BCLK2_DP")
	)
	(arc
		(start 131.661408 -88.689688)
		(mid 131.858569 -88.741647)
		(end 132.004562 -88.883998)
		(width 0.0889)
		(layer "In4.Cu")
		(net "CLK_100M_CPU1_BCLK2_DP")
	)
	(arc
		(start 128.574038 -88.889586)
		(mid 128.781042 -89.10045)
		(end 129.064258 -89.184734)
		(width 0.0889)
		(layer "In4.Cu")
		(net "CLK_100M_CPU1_BCLK2_DP")
	)
	(arc
		(start 123.091194 -88.689688)
		(mid 123.282836 -88.746854)
		(end 123.422918 -88.889586)
		(width 0.0889)
		(layer "In4.Cu")
		(net "CLK_100M_CPU1_BCLK2_DP")
	)
	(arc
		(start 134.748524 -88.889586)
		(mid 135.095234 -88.689402)
		(end 135.441944 -88.889586)
		(width 0.0889)
		(layer "In4.Cu")
		(net "CLK_100M_CPU1_BCLK2_DP")
	)
	(arc
		(start 140.264134 -88.689688)
		(mid 140.549558 -88.606221)
		(end 140.758164 -88.394286)
		(width 0.0889)
		(layer "In4.Cu")
		(net "CLK_100M_CPU1_BCLK2_DP")
	)
	(arc
		(start 130.291078 -88.889586)
		(mid 130.498082 -89.10045)
		(end 130.781298 -89.184734)
		(width 0.0889)
		(layer "In4.Cu")
		(net "CLK_100M_CPU1_BCLK2_DP")
	)
	(arc
		(start 125.139958 -88.889586)
		(mid 125.346962 -89.10045)
		(end 125.630178 -89.184734)
		(width 0.0889)
		(layer "In4.Cu")
		(net "CLK_100M_CPU1_BCLK2_DP")
	)
	(arc
		(start 123.422918 -88.889586)
		(mid 123.629922 -89.10045)
		(end 123.913138 -89.184734)
		(width 0.0889)
		(layer "In4.Cu")
		(net "CLK_100M_CPU1_BCLK2_DP")
	)
	(arc
		(start 129.959354 -88.689688)
		(mid 130.150996 -88.746854)
		(end 130.291078 -88.889586)
		(width 0.0889)
		(layer "In4.Cu")
		(net "CLK_100M_CPU1_BCLK2_DP")
	)
	(arc
		(start 134.258304 -89.184734)
		(mid 134.541521 -89.100453)
		(end 134.748524 -88.889586)
		(width 0.0889)
		(layer "In4.Cu")
		(net "CLK_100M_CPU1_BCLK2_DP")
	)
	(arc
		(start 122.239278 -89.184734)
		(mid 122.522495 -89.100453)
		(end 122.729498 -88.889586)
		(width 0.0889)
		(layer "In4.Cu")
		(net "CLK_100M_CPU1_BCLK2_DP")
	)
	(arc
		(start 131.314698 -88.889586)
		(mid 131.454777 -88.74685)
		(end 131.646422 -88.689688)
		(width 0.0889)
		(layer "In4.Cu")
		(net "CLK_100M_CPU1_BCLK2_DP")
	)
	(arc
		(start 132.007864 -88.88984)
		(mid 132.213485 -89.099763)
		(end 132.494782 -89.184734)
		(width 0.0889)
		(layer "In4.Cu")
		(net "CLK_100M_CPU1_BCLK2_DP")
	)
	(arc
		(start 138.876024 -88.889586)
		(mid 139.083028 -89.10045)
		(end 139.366244 -89.184734)
		(width 0.0889)
		(layer "In4.Cu")
		(net "CLK_100M_CPU1_BCLK2_DP")
	)
	(arc
		(start 122.729498 -88.889586)
		(mid 122.869577 -88.74685)
		(end 123.061222 -88.689688)
		(width 0.0889)
		(layer "In4.Cu")
		(net "CLK_100M_CPU1_BCLK2_DP")
	)
	(arc
		(start 124.446538 -88.889586)
		(mid 124.586617 -88.74685)
		(end 124.778262 -88.689688)
		(width 0.0889)
		(layer "In4.Cu")
		(net "CLK_100M_CPU1_BCLK2_DP")
	)
	(arc
		(start 137.692384 -89.184734)
		(mid 137.975601 -89.100453)
		(end 138.182604 -88.889586)
		(width 0.0889)
		(layer "In4.Cu")
		(net "CLK_100M_CPU1_BCLK2_DP")
	)
	(arc
		(start 138.5443 -88.689688)
		(mid 138.735942 -88.746854)
		(end 138.876024 -88.889586)
		(width 0.0889)
		(layer "In4.Cu")
		(net "CLK_100M_CPU1_BCLK2_DP")
	)
	(arc
		(start 139.899644 -88.889586)
		(mid 140.039723 -88.74685)
		(end 140.231368 -88.689688)
		(width 0.0889)
		(layer "In4.Cu")
		(net "CLK_100M_CPU1_BCLK2_DP")
	)
	(arc
		(start 126.163578 -88.889586)
		(mid 126.510288 -88.689402)
		(end 126.856998 -88.889586)
		(width 0.0889)
		(layer "In4.Cu")
		(net "CLK_100M_CPU1_BCLK2_DP")
	)
	(arc
		(start 121.92762 -89.109296)
		(mid 122.057346 -89.163076)
		(end 122.196098 -89.184734)
		(width 0.0889)
		(layer "In4.Cu")
		(net "CLK_100M_CPU1_BCLK2_DP")
	)
	(arc
		(start 130.824478 -89.184734)
		(mid 131.107695 -89.100453)
		(end 131.314698 -88.889586)
		(width 0.0889)
		(layer "In4.Cu")
		(net "CLK_100M_CPU1_BCLK2_DP")
	)
	(arc
		(start 129.597658 -88.889586)
		(mid 129.737737 -88.74685)
		(end 129.929382 -88.689688)
		(width 0.0889)
		(layer "In4.Cu")
		(net "CLK_100M_CPU1_BCLK2_DP")
	)
	(arc
		(start 128.242314 -88.689688)
		(mid 128.433956 -88.746854)
		(end 128.574038 -88.889586)
		(width 0.0889)
		(layer "In4.Cu")
		(net "CLK_100M_CPU1_BCLK2_DP")
	)
	(arc
		(start 139.409424 -89.184734)
		(mid 139.692641 -89.100453)
		(end 139.899644 -88.889586)
		(width 0.0889)
		(layer "In4.Cu")
		(net "CLK_100M_CPU1_BCLK2_DP")
	)
	(arc
		(start 136.465564 -88.889586)
		(mid 136.812274 -88.689402)
		(end 137.158984 -88.889586)
		(width 0.0889)
		(layer "In4.Cu")
		(net "CLK_100M_CPU1_BCLK2_DP")
	)
	(arc
		(start 133.031484 -88.889586)
		(mid 133.171563 -88.74685)
		(end 133.363208 -88.689688)
		(width 0.0889)
		(layer "In4.Cu")
		(net "CLK_100M_CPU1_BCLK2_DP")
	)
	(arc
		(start 124.808234 -88.689688)
		(mid 124.999876 -88.746854)
		(end 125.139958 -88.889586)
		(width 0.0889)
		(layer "In4.Cu")
		(net "CLK_100M_CPU1_BCLK2_DP")
	)
	(arc
		(start 133.39318 -88.689688)
		(mid 133.584822 -88.746854)
		(end 133.724904 -88.889586)
		(width 0.0889)
		(layer "In4.Cu")
		(net "CLK_100M_CPU1_BCLK2_DP")
	)
	(arc
		(start 126.856998 -88.889586)
		(mid 127.368808 -89.185125)
		(end 127.880618 -88.889586)
		(width 0.0889)
		(layer "In4.Cu")
		(net "CLK_100M_CPU1_BCLK2_DP")
	)
	(arc
		(start 121.359168 -89.089738)
		(mid 121.645787 -89.030265)
		(end 121.92762 -89.109296)
		(width 0.0889)
		(layer "In4.Cu")
		(net "CLK_100M_CPU1_BCLK2_DP")
	)
	(arc
		(start 135.975344 -89.184734)
		(mid 136.258561 -89.100453)
		(end 136.465564 -88.889586)
		(width 0.0889)
		(layer "In4.Cu")
		(net "CLK_100M_CPU1_BCLK2_DP")
	)
	(arc
		(start 138.182604 -88.889586)
		(mid 138.322683 -88.74685)
		(end 138.514328 -88.689688)
		(width 0.0889)
		(layer "In4.Cu")
		(net "CLK_100M_CPU1_BCLK2_DP")
	)
	(arc
		(start 125.673358 -89.184734)
		(mid 125.956575 -89.100453)
		(end 126.163578 -88.889586)
		(width 0.0889)
		(layer "In4.Cu")
		(net "CLK_100M_CPU1_BCLK2_DP")
	)
	(segment
		(start 162.5727 -84.870544)
		(end 162.099498 -84.870544)
		(width 0.1143)
		(layer "F.Cu")
		(net "CLK_100M_CPU1_BCLK2_DN")
	)
	(segment
		(start 161.970974 -84.74202)
		(end 161.970974 -84.42706)
		(width 0.1143)
		(layer "F.Cu")
		(net "CLK_100M_CPU1_BCLK2_DN")
	)
	(segment
		(start 122.217688 -88.594184)
		(end 121.646188 -88.594184)
		(width 0.1143)
		(layer "F.Cu")
		(net "CLK_100M_CPU1_BCLK2_DN")
	)
	(segment
		(start 162.687 -84.328)
		(end 162.687 -84.756244)
		(width 0.1143)
		(layer "F.Cu")
		(net "CLK_100M_CPU1_BCLK2_DN")
	)
	(segment
		(start 162.687 -84.756244)
		(end 162.5727 -84.870544)
		(width 0.1143)
		(layer "F.Cu")
		(net "CLK_100M_CPU1_BCLK2_DN")
	)
	(segment
		(start 162.099498 -84.870544)
		(end 161.970974 -84.74202)
		(width 0.1143)
		(layer "F.Cu")
		(net "CLK_100M_CPU1_BCLK2_DN")
	)
	(via
		(at 161.970974 -84.42706)
		(size 0.508)
		(drill 0.254)
		(layers "F.Cu" "B.Cu")
		(net "CLK_100M_CPU1_BCLK2_DN")
	)
	(via
		(at 122.217688 -88.594184)
		(size 0.508)
		(drill 0.254)
		(layers "F.Cu" "B.Cu")
		(net "CLK_100M_CPU1_BCLK2_DN")
	)
	(segment
		(start 162.384232 -84.856828)
		(end 162.91306 -84.328)
		(width 0.1143)
		(layer "B.Cu")
		(net "CLK_100M_CPU1_BCLK2_DN")
	)
	(segment
		(start 161.970974 -84.716874)
		(end 162.110928 -84.856828)
		(width 0.1143)
		(layer "B.Cu")
		(net "CLK_100M_CPU1_BCLK2_DN")
	)
	(segment
		(start 161.970974 -84.42706)
		(end 161.970974 -84.716874)
		(width 0.1143)
		(layer "B.Cu")
		(net "CLK_100M_CPU1_BCLK2_DN")
	)
	(segment
		(start 162.110928 -84.856828)
		(end 162.384232 -84.856828)
		(width 0.1143)
		(layer "B.Cu")
		(net "CLK_100M_CPU1_BCLK2_DN")
	)
	(segment
		(start 147.415758 -92.366338)
		(end 147.701 -92.65158)
		(width 0.1143)
		(layer "In4.Cu")
		(net "CLK_100M_CPU1_BCLK2_DN")
	)
	(segment
		(start 158.819342 -85.1916)
		(end 159.353758 -85.1916)
		(width 0.1143)
		(layer "In4.Cu")
		(net "CLK_100M_CPU1_BCLK2_DN")
	)
	(segment
		(start 147.41271 -102.402894)
		(end 147.29841 -102.517194)
		(width 0.1143)
		(layer "In4.Cu")
		(net "CLK_100M_CPU1_BCLK2_DN")
	)
	(segment
		(start 129.922778 -88.499188)
		(end 129.965958 -88.499188)
		(width 0.0889)
		(layer "In4.Cu")
		(net "CLK_100M_CPU1_BCLK2_DN")
	)
	(segment
		(start 159.353758 -85.1916)
		(end 159.639 -85.476842)
		(width 0.1143)
		(layer "In4.Cu")
		(net "CLK_100M_CPU1_BCLK2_DN")
	)
	(segment
		(start 133.356604 -88.499188)
		(end 133.399784 -88.499188)
		(width 0.0889)
		(layer "In4.Cu")
		(net "CLK_100M_CPU1_BCLK2_DN")
	)
	(segment
		(start 131.639818 -88.499188)
		(end 131.6863 -88.499188)
		(width 0.0889)
		(layer "In4.Cu")
		(net "CLK_100M_CPU1_BCLK2_DN")
	)
	(segment
		(start 134.221728 -88.994234)
		(end 134.2517 -88.994234)
		(width 0.0889)
		(layer "In4.Cu")
		(net "CLK_100M_CPU1_BCLK2_DN")
	)
	(segment
		(start 146.200876 -101.403658)
		(end 146.478498 -101.403658)
		(width 0.1143)
		(layer "In4.Cu")
		(net "CLK_100M_CPU1_BCLK2_DN")
	)
	(segment
		(start 160.3375 -85.286342)
		(end 160.724342 -84.8995)
		(width 0.1143)
		(layer "In4.Cu")
		(net "CLK_100M_CPU1_BCLK2_DN")
	)
	(segment
		(start 141.087094 -88.003634)
		(end 141.353794 -88.003634)
		(width 0.0889)
		(layer "In4.Cu")
		(net "CLK_100M_CPU1_BCLK2_DN")
	)
	(segment
		(start 149.3266 -96.932496)
		(end 149.3266 -100.57511)
		(width 0.1143)
		(layer "In4.Cu")
		(net "CLK_100M_CPU1_BCLK2_DN")
	)
	(segment
		(start 160.184084 -97.334832)
		(end 160.3375 -97.181416)
		(width 0.1143)
		(layer "In4.Cu")
		(net "CLK_100M_CPU1_BCLK2_DN")
	)
	(segment
		(start 142.064994 -88.003634)
		(end 142.153894 -87.914734)
		(width 0.0889)
		(layer "In4.Cu")
		(net "CLK_100M_CPU1_BCLK2_DN")
	)
	(segment
		(start 158.5341 -85.476842)
		(end 158.819342 -85.1916)
		(width 0.1143)
		(layer "In4.Cu")
		(net "CLK_100M_CPU1_BCLK2_DN")
	)
	(segment
		(start 146.5961 -92.65158)
		(end 146.881342 -92.366338)
		(width 0.1143)
		(layer "In4.Cu")
		(net "CLK_100M_CPU1_BCLK2_DN")
	)
	(segment
		(start 159.639 -97.220532)
		(end 159.7533 -97.334832)
		(width 0.1143)
		(layer "In4.Cu")
		(net "CLK_100M_CPU1_BCLK2_DN")
	)
	(segment
		(start 140.224764 -88.499188)
		(end 140.25753 -88.499188)
		(width 0.0889)
		(layer "In4.Cu")
		(net "CLK_100M_CPU1_BCLK2_DN")
	)
	(segment
		(start 155.131262 -101.590348)
		(end 155.131262 -102.117652)
		(width 0.1143)
		(layer "In4.Cu")
		(net "CLK_100M_CPU1_BCLK2_DN")
	)
	(segment
		(start 142.420594 -87.914734)
		(end 142.509494 -88.003634)
		(width 0.0889)
		(layer "In4.Cu")
		(net "CLK_100M_CPU1_BCLK2_DN")
	)
	(segment
		(start 143.525494 -88.003634)
		(end 143.576294 -87.952834)
		(width 0.0889)
		(layer "In4.Cu")
		(net "CLK_100M_CPU1_BCLK2_DN")
	)
	(segment
		(start 148.2217 -101.157532)
		(end 148.2217 -96.932496)
		(width 0.1143)
		(layer "In4.Cu")
		(net "CLK_100M_CPU1_BCLK2_DN")
	)
	(segment
		(start 149.041358 -96.647254)
		(end 149.3266 -96.932496)
		(width 0.1143)
		(layer "In4.Cu")
		(net "CLK_100M_CPU1_BCLK2_DN")
	)
	(segment
		(start 132.519674 -88.994234)
		(end 132.53466 -88.994234)
		(width 0.0889)
		(layer "In4.Cu")
		(net "CLK_100M_CPU1_BCLK2_DN")
	)
	(segment
		(start 141.798294 -88.003634)
		(end 142.064994 -88.003634)
		(width 0.0889)
		(layer "In4.Cu")
		(net "CLK_100M_CPU1_BCLK2_DN")
	)
	(segment
		(start 123.919742 -88.994234)
		(end 123.949714 -88.994234)
		(width 0.0889)
		(layer "In4.Cu")
		(net "CLK_100M_CPU1_BCLK2_DN")
	)
	(segment
		(start 154.838908 -101.297994)
		(end 155.131262 -101.590348)
		(width 0.1143)
		(layer "In4.Cu")
		(net "CLK_100M_CPU1_BCLK2_DN")
	)
	(segment
		(start 155.131262 -102.117652)
		(end 154.84602 -102.402894)
		(width 0.1143)
		(layer "In4.Cu")
		(net "CLK_100M_CPU1_BCLK2_DN")
	)
	(segment
		(start 148.2217 -96.932496)
		(end 148.506942 -96.647254)
		(width 0.1143)
		(layer "In4.Cu")
		(net "CLK_100M_CPU1_BCLK2_DN")
	)
	(segment
		(start 141.442694 -87.914734)
		(end 141.709394 -87.914734)
		(width 0.0889)
		(layer "In4.Cu")
		(net "CLK_100M_CPU1_BCLK2_DN")
	)
	(segment
		(start 155.871926 -100.274374)
		(end 158.5341 -97.6122)
		(width 0.1143)
		(layer "In4.Cu")
		(net "CLK_100M_CPU1_BCLK2_DN")
	)
	(segment
		(start 139.372848 -88.994234)
		(end 139.40282 -88.994234)
		(width 0.0889)
		(layer "In4.Cu")
		(net "CLK_100M_CPU1_BCLK2_DN")
	)
	(segment
		(start 149.3266 -100.57511)
		(end 150.049484 -101.297994)
		(width 0.1143)
		(layer "In4.Cu")
		(net "CLK_100M_CPU1_BCLK2_DN")
	)
	(segment
		(start 122.217688 -88.594184)
		(end 121.924572 -88.763348)
		(width 0.0889)
		(layer "In4.Cu")
		(net "CLK_100M_CPU1_BCLK2_DN")
	)
	(segment
		(start 148.506942 -96.647254)
		(end 149.041358 -96.647254)
		(width 0.1143)
		(layer "In4.Cu")
		(net "CLK_100M_CPU1_BCLK2_DN")
	)
	(segment
		(start 146.478498 -101.403658)
		(end 146.5961 -101.286056)
		(width 0.1143)
		(layer "In4.Cu")
		(net "CLK_100M_CPU1_BCLK2_DN")
	)
	(segment
		(start 147.8153 -101.28631)
		(end 148.092922 -101.28631)
		(width 0.1143)
		(layer "In4.Cu")
		(net "CLK_100M_CPU1_BCLK2_DN")
	)
	(segment
		(start 142.153894 -87.914734)
		(end 142.420594 -87.914734)
		(width 0.0889)
		(layer "In4.Cu")
		(net "CLK_100M_CPU1_BCLK2_DN")
	)
	(segment
		(start 142.509494 -88.003634)
		(end 143.525494 -88.003634)
		(width 0.0889)
		(layer "In4.Cu")
		(net "CLK_100M_CPU1_BCLK2_DN")
	)
	(segment
		(start 159.639 -85.476842)
		(end 159.639 -97.220532)
		(width 0.1143)
		(layer "In4.Cu")
		(net "CLK_100M_CPU1_BCLK2_DN")
	)
	(segment
		(start 123.054618 -88.499188)
		(end 123.097798 -88.499188)
		(width 0.0889)
		(layer "In4.Cu")
		(net "CLK_100M_CPU1_BCLK2_DN")
	)
	(segment
		(start 159.113982 -98.595434)
		(end 156.667708 -101.041708)
		(width 0.1143)
		(layer "In4.Cu")
		(net "CLK_100M_CPU1_BCLK2_DN")
	)
	(segment
		(start 146.5961 -101.286056)
		(end 146.5961 -92.65158)
		(width 0.1143)
		(layer "In4.Cu")
		(net "CLK_100M_CPU1_BCLK2_DN")
	)
	(segment
		(start 146.0754 -101.278182)
		(end 146.200876 -101.403658)
		(width 0.1143)
		(layer "In4.Cu")
		(net "CLK_100M_CPU1_BCLK2_DN")
	)
	(segment
		(start 160.3375 -97.181416)
		(end 160.3375 -85.286342)
		(width 0.1143)
		(layer "In4.Cu")
		(net "CLK_100M_CPU1_BCLK2_DN")
	)
	(segment
		(start 148.092922 -101.28631)
		(end 148.2217 -101.157532)
		(width 0.1143)
		(layer "In4.Cu")
		(net "CLK_100M_CPU1_BCLK2_DN")
	)
	(segment
		(start 141.353794 -88.003634)
		(end 141.442694 -87.914734)
		(width 0.0889)
		(layer "In4.Cu")
		(net "CLK_100M_CPU1_BCLK2_DN")
	)
	(segment
		(start 155.871926 -100.678234)
		(end 155.871926 -100.274374)
		(width 0.1143)
		(layer "In4.Cu")
		(net "CLK_100M_CPU1_BCLK2_DN")
	)
	(segment
		(start 121.924572 -88.763348)
		(end 121.90349 -88.842088)
		(width 0.0889)
		(layer "In4.Cu")
		(net "CLK_100M_CPU1_BCLK2_DN")
	)
	(segment
		(start 161.970974 -84.77758)
		(end 161.970974 -84.42706)
		(width 0.1143)
		(layer "In4.Cu")
		(net "CLK_100M_CPU1_BCLK2_DN")
	)
	(segment
		(start 158.5341 -97.6122)
		(end 158.5341 -85.476842)
		(width 0.1143)
		(layer "In4.Cu")
		(net "CLK_100M_CPU1_BCLK2_DN")
	)
	(segment
		(start 156.667708 -101.041708)
		(end 156.2354 -101.041708)
		(width 0.1143)
		(layer "In4.Cu")
		(net "CLK_100M_CPU1_BCLK2_DN")
	)
	(segment
		(start 138.507724 -88.499188)
		(end 138.550904 -88.499188)
		(width 0.0889)
		(layer "In4.Cu")
		(net "CLK_100M_CPU1_BCLK2_DN")
	)
	(segment
		(start 130.787902 -88.994234)
		(end 130.817874 -88.994234)
		(width 0.0889)
		(layer "In4.Cu")
		(net "CLK_100M_CPU1_BCLK2_DN")
	)
	(segment
		(start 146.881342 -92.366338)
		(end 147.415758 -92.366338)
		(width 0.1143)
		(layer "In4.Cu")
		(net "CLK_100M_CPU1_BCLK2_DN")
	)
	(segment
		(start 145.026634 -87.952834)
		(end 146.0754 -89.0016)
		(width 0.1143)
		(layer "In4.Cu")
		(net "CLK_100M_CPU1_BCLK2_DN")
	)
	(segment
		(start 124.771658 -88.499188)
		(end 124.814838 -88.499188)
		(width 0.0889)
		(layer "In4.Cu")
		(net "CLK_100M_CPU1_BCLK2_DN")
	)
	(segment
		(start 147.29841 -102.517194)
		(end 147.29841 -102.809294)
		(width 0.1143)
		(layer "In4.Cu")
		(net "CLK_100M_CPU1_BCLK2_DN")
	)
	(segment
		(start 129.070862 -88.994234)
		(end 129.100834 -88.994234)
		(width 0.0889)
		(layer "In4.Cu")
		(net "CLK_100M_CPU1_BCLK2_DN")
	)
	(segment
		(start 159.7533 -97.334832)
		(end 160.184084 -97.334832)
		(width 0.1143)
		(layer "In4.Cu")
		(net "CLK_100M_CPU1_BCLK2_DN")
	)
	(segment
		(start 122.202702 -88.994234)
		(end 122.232674 -88.994234)
		(width 0.0889)
		(layer "In4.Cu")
		(net "CLK_100M_CPU1_BCLK2_DN")
	)
	(segment
		(start 159.482536 -98.964242)
		(end 159.482536 -98.79203)
		(width 0.1143)
		(layer "In4.Cu")
		(net "CLK_100M_CPU1_BCLK2_DN")
	)
	(segment
		(start 147.701 -92.65158)
		(end 147.701 -101.17201)
		(width 0.1143)
		(layer "In4.Cu")
		(net "CLK_100M_CPU1_BCLK2_DN")
	)
	(segment
		(start 128.205738 -88.499188)
		(end 128.248918 -88.499188)
		(width 0.0889)
		(layer "In4.Cu")
		(net "CLK_100M_CPU1_BCLK2_DN")
	)
	(segment
		(start 150.049484 -101.297994)
		(end 154.838908 -101.297994)
		(width 0.1143)
		(layer "In4.Cu")
		(net "CLK_100M_CPU1_BCLK2_DN")
	)
	(segment
		(start 147.41271 -102.923594)
		(end 155.523184 -102.923594)
		(width 0.1143)
		(layer "In4.Cu")
		(net "CLK_100M_CPU1_BCLK2_DN")
	)
	(segment
		(start 147.701 -101.17201)
		(end 147.8153 -101.28631)
		(width 0.1143)
		(layer "In4.Cu")
		(net "CLK_100M_CPU1_BCLK2_DN")
	)
	(segment
		(start 137.655808 -88.994234)
		(end 137.68578 -88.994234)
		(width 0.0889)
		(layer "In4.Cu")
		(net "CLK_100M_CPU1_BCLK2_DN")
	)
	(segment
		(start 132.173218 -88.794082)
		(end 132.17652 -88.799924)
		(width 0.0889)
		(layer "In4.Cu")
		(net "CLK_100M_CPU1_BCLK2_DN")
	)
	(segment
		(start 147.29841 -102.809294)
		(end 147.41271 -102.923594)
		(width 0.1143)
		(layer "In4.Cu")
		(net "CLK_100M_CPU1_BCLK2_DN")
	)
	(segment
		(start 155.523184 -102.923594)
		(end 159.482536 -98.964242)
		(width 0.1143)
		(layer "In4.Cu")
		(net "CLK_100M_CPU1_BCLK2_DN")
	)
	(segment
		(start 135.938768 -88.994234)
		(end 135.96874 -88.994234)
		(width 0.0889)
		(layer "In4.Cu")
		(net "CLK_100M_CPU1_BCLK2_DN")
	)
	(segment
		(start 143.598392 -87.952834)
		(end 145.026634 -87.952834)
		(width 0.1143)
		(layer "In4.Cu")
		(net "CLK_100M_CPU1_BCLK2_DN")
	)
	(segment
		(start 154.84602 -102.402894)
		(end 147.41271 -102.402894)
		(width 0.1143)
		(layer "In4.Cu")
		(net "CLK_100M_CPU1_BCLK2_DN")
	)
	(segment
		(start 161.849054 -84.8995)
		(end 161.970974 -84.77758)
		(width 0.1143)
		(layer "In4.Cu")
		(net "CLK_100M_CPU1_BCLK2_DN")
	)
	(segment
		(start 141.709394 -87.914734)
		(end 141.798294 -88.003634)
		(width 0.0889)
		(layer "In4.Cu")
		(net "CLK_100M_CPU1_BCLK2_DN")
	)
	(segment
		(start 159.28594 -98.595434)
		(end 159.113982 -98.595434)
		(width 0.1143)
		(layer "In4.Cu")
		(net "CLK_100M_CPU1_BCLK2_DN")
	)
	(segment
		(start 156.2354 -101.041708)
		(end 155.871926 -100.678234)
		(width 0.1143)
		(layer "In4.Cu")
		(net "CLK_100M_CPU1_BCLK2_DN")
	)
	(segment
		(start 146.0754 -89.0016)
		(end 146.0754 -101.278182)
		(width 0.1143)
		(layer "In4.Cu")
		(net "CLK_100M_CPU1_BCLK2_DN")
	)
	(segment
		(start 159.482536 -98.79203)
		(end 159.28594 -98.595434)
		(width 0.1143)
		(layer "In4.Cu")
		(net "CLK_100M_CPU1_BCLK2_DN")
	)
	(segment
		(start 160.724342 -84.8995)
		(end 161.849054 -84.8995)
		(width 0.1143)
		(layer "In4.Cu")
		(net "CLK_100M_CPU1_BCLK2_DN")
	)
	(segment
		(start 125.636782 -88.994234)
		(end 125.666754 -88.994234)
		(width 0.0889)
		(layer "In4.Cu")
		(net "CLK_100M_CPU1_BCLK2_DN")
	)
	(segment
		(start 143.576294 -87.952834)
		(end 143.598392 -87.952834)
		(width 0.0889)
		(layer "In4.Cu")
		(net "CLK_100M_CPU1_BCLK2_DN")
	)
	(arc
		(start 134.2517 -88.994234)
		(mid 134.443342 -88.937068)
		(end 134.583424 -88.794336)
		(width 0.0889)
		(layer "In4.Cu")
		(net "CLK_100M_CPU1_BCLK2_DN")
	)
	(arc
		(start 137.324084 -88.794336)
		(mid 137.464163 -88.937072)
		(end 137.655808 -88.994234)
		(width 0.0889)
		(layer "In4.Cu")
		(net "CLK_100M_CPU1_BCLK2_DN")
	)
	(arc
		(start 122.564398 -88.794336)
		(mid 122.771402 -88.583472)
		(end 123.054618 -88.499188)
		(width 0.0889)
		(layer "In4.Cu")
		(net "CLK_100M_CPU1_BCLK2_DN")
	)
	(arc
		(start 132.866384 -88.794336)
		(mid 133.073388 -88.583472)
		(end 133.356604 -88.499188)
		(width 0.0889)
		(layer "In4.Cu")
		(net "CLK_100M_CPU1_BCLK2_DN")
	)
	(arc
		(start 123.588018 -88.794336)
		(mid 123.728097 -88.937072)
		(end 123.919742 -88.994234)
		(width 0.0889)
		(layer "In4.Cu")
		(net "CLK_100M_CPU1_BCLK2_DN")
	)
	(arc
		(start 131.6863 -88.499188)
		(mid 131.9676 -88.584154)
		(end 132.173218 -88.794082)
		(width 0.0889)
		(layer "In4.Cu")
		(net "CLK_100M_CPU1_BCLK2_DN")
	)
	(arc
		(start 132.53466 -88.994234)
		(mid 132.726302 -88.937068)
		(end 132.866384 -88.794336)
		(width 0.0889)
		(layer "In4.Cu")
		(net "CLK_100M_CPU1_BCLK2_DN")
	)
	(arc
		(start 127.715518 -88.794336)
		(mid 127.922522 -88.583472)
		(end 128.205738 -88.499188)
		(width 0.0889)
		(layer "In4.Cu")
		(net "CLK_100M_CPU1_BCLK2_DN")
	)
	(arc
		(start 129.100834 -88.994234)
		(mid 129.292476 -88.937068)
		(end 129.432558 -88.794336)
		(width 0.0889)
		(layer "In4.Cu")
		(net "CLK_100M_CPU1_BCLK2_DN")
	)
	(arc
		(start 125.666754 -88.994234)
		(mid 125.858396 -88.937068)
		(end 125.998478 -88.794336)
		(width 0.0889)
		(layer "In4.Cu")
		(net "CLK_100M_CPU1_BCLK2_DN")
	)
	(arc
		(start 124.814838 -88.499188)
		(mid 125.098055 -88.583469)
		(end 125.305058 -88.794336)
		(width 0.0889)
		(layer "In4.Cu")
		(net "CLK_100M_CPU1_BCLK2_DN")
	)
	(arc
		(start 123.949714 -88.994234)
		(mid 124.141356 -88.937068)
		(end 124.281438 -88.794336)
		(width 0.0889)
		(layer "In4.Cu")
		(net "CLK_100M_CPU1_BCLK2_DN")
	)
	(arc
		(start 138.017504 -88.794336)
		(mid 138.224508 -88.583472)
		(end 138.507724 -88.499188)
		(width 0.0889)
		(layer "In4.Cu")
		(net "CLK_100M_CPU1_BCLK2_DN")
	)
	(arc
		(start 139.734544 -88.794336)
		(mid 139.941548 -88.583472)
		(end 140.224764 -88.499188)
		(width 0.0889)
		(layer "In4.Cu")
		(net "CLK_100M_CPU1_BCLK2_DN")
	)
	(arc
		(start 128.248918 -88.499188)
		(mid 128.532135 -88.583469)
		(end 128.739138 -88.794336)
		(width 0.0889)
		(layer "In4.Cu")
		(net "CLK_100M_CPU1_BCLK2_DN")
	)
	(arc
		(start 129.965958 -88.499188)
		(mid 130.249175 -88.583469)
		(end 130.456178 -88.794336)
		(width 0.0889)
		(layer "In4.Cu")
		(net "CLK_100M_CPU1_BCLK2_DN")
	)
	(arc
		(start 125.305058 -88.794336)
		(mid 125.445137 -88.937072)
		(end 125.636782 -88.994234)
		(width 0.0889)
		(layer "In4.Cu")
		(net "CLK_100M_CPU1_BCLK2_DN")
	)
	(arc
		(start 125.998478 -88.794336)
		(mid 126.510288 -88.498797)
		(end 127.022098 -88.794336)
		(width 0.0889)
		(layer "In4.Cu")
		(net "CLK_100M_CPU1_BCLK2_DN")
	)
	(arc
		(start 135.96874 -88.994234)
		(mid 136.160382 -88.937068)
		(end 136.300464 -88.794336)
		(width 0.0889)
		(layer "In4.Cu")
		(net "CLK_100M_CPU1_BCLK2_DN")
	)
	(arc
		(start 135.607044 -88.794336)
		(mid 135.747123 -88.937072)
		(end 135.938768 -88.994234)
		(width 0.0889)
		(layer "In4.Cu")
		(net "CLK_100M_CPU1_BCLK2_DN")
	)
	(arc
		(start 128.739138 -88.794336)
		(mid 128.879217 -88.937072)
		(end 129.070862 -88.994234)
		(width 0.0889)
		(layer "In4.Cu")
		(net "CLK_100M_CPU1_BCLK2_DN")
	)
	(arc
		(start 138.550904 -88.499188)
		(mid 138.834121 -88.583469)
		(end 139.041124 -88.794336)
		(width 0.0889)
		(layer "In4.Cu")
		(net "CLK_100M_CPU1_BCLK2_DN")
	)
	(arc
		(start 134.583424 -88.794336)
		(mid 135.095234 -88.498797)
		(end 135.607044 -88.794336)
		(width 0.0889)
		(layer "In4.Cu")
		(net "CLK_100M_CPU1_BCLK2_DN")
	)
	(arc
		(start 122.232674 -88.994234)
		(mid 122.424316 -88.937068)
		(end 122.564398 -88.794336)
		(width 0.0889)
		(layer "In4.Cu")
		(net "CLK_100M_CPU1_BCLK2_DN")
	)
	(arc
		(start 123.097798 -88.499188)
		(mid 123.381015 -88.583469)
		(end 123.588018 -88.794336)
		(width 0.0889)
		(layer "In4.Cu")
		(net "CLK_100M_CPU1_BCLK2_DN")
	)
	(arc
		(start 139.40282 -88.994234)
		(mid 139.594462 -88.937068)
		(end 139.734544 -88.794336)
		(width 0.0889)
		(layer "In4.Cu")
		(net "CLK_100M_CPU1_BCLK2_DN")
	)
	(arc
		(start 130.456178 -88.794336)
		(mid 130.596257 -88.937072)
		(end 130.787902 -88.994234)
		(width 0.0889)
		(layer "In4.Cu")
		(net "CLK_100M_CPU1_BCLK2_DN")
	)
	(arc
		(start 130.817874 -88.994234)
		(mid 131.009516 -88.937068)
		(end 131.149598 -88.794336)
		(width 0.0889)
		(layer "In4.Cu")
		(net "CLK_100M_CPU1_BCLK2_DN")
	)
	(arc
		(start 129.432558 -88.794336)
		(mid 129.639562 -88.583472)
		(end 129.922778 -88.499188)
		(width 0.0889)
		(layer "In4.Cu")
		(net "CLK_100M_CPU1_BCLK2_DN")
	)
	(arc
		(start 140.25753 -88.499188)
		(mid 140.45138 -88.442838)
		(end 140.593064 -88.299036)
		(width 0.0889)
		(layer "In4.Cu")
		(net "CLK_100M_CPU1_BCLK2_DN")
	)
	(arc
		(start 124.281438 -88.794336)
		(mid 124.488442 -88.583472)
		(end 124.771658 -88.499188)
		(width 0.0889)
		(layer "In4.Cu")
		(net "CLK_100M_CPU1_BCLK2_DN")
	)
	(arc
		(start 139.041124 -88.794336)
		(mid 139.181203 -88.937072)
		(end 139.372848 -88.994234)
		(width 0.0889)
		(layer "In4.Cu")
		(net "CLK_100M_CPU1_BCLK2_DN")
	)
	(arc
		(start 137.68578 -88.994234)
		(mid 137.877422 -88.937068)
		(end 138.017504 -88.794336)
		(width 0.0889)
		(layer "In4.Cu")
		(net "CLK_100M_CPU1_BCLK2_DN")
	)
	(arc
		(start 133.399784 -88.499188)
		(mid 133.683001 -88.583469)
		(end 133.890004 -88.794336)
		(width 0.0889)
		(layer "In4.Cu")
		(net "CLK_100M_CPU1_BCLK2_DN")
	)
	(arc
		(start 131.149598 -88.794336)
		(mid 131.356602 -88.583472)
		(end 131.639818 -88.499188)
		(width 0.0889)
		(layer "In4.Cu")
		(net "CLK_100M_CPU1_BCLK2_DN")
	)
	(arc
		(start 127.022098 -88.794336)
		(mid 127.368808 -88.99452)
		(end 127.715518 -88.794336)
		(width 0.0889)
		(layer "In4.Cu")
		(net "CLK_100M_CPU1_BCLK2_DN")
	)
	(arc
		(start 133.890004 -88.794336)
		(mid 134.030083 -88.937072)
		(end 134.221728 -88.994234)
		(width 0.0889)
		(layer "In4.Cu")
		(net "CLK_100M_CPU1_BCLK2_DN")
	)
	(arc
		(start 136.300464 -88.794336)
		(mid 136.812274 -88.498797)
		(end 137.324084 -88.794336)
		(width 0.0889)
		(layer "In4.Cu")
		(net "CLK_100M_CPU1_BCLK2_DN")
	)
	(arc
		(start 121.90349 -88.842088)
		(mid 122.036371 -88.951071)
		(end 122.202702 -88.994234)
		(width 0.0889)
		(layer "In4.Cu")
		(net "CLK_100M_CPU1_BCLK2_DN")
	)
	(arc
		(start 140.593064 -88.299036)
		(mid 140.801672 -88.087104)
		(end 141.087094 -88.003634)
		(width 0.0889)
		(layer "In4.Cu")
		(net "CLK_100M_CPU1_BCLK2_DN")
	)
	(arc
		(start 132.17652 -88.799924)
		(mid 132.322486 -88.942323)
		(end 132.519674 -88.994234)
		(width 0.0889)
		(layer "In4.Cu")
		(net "CLK_100M_CPU1_BCLK2_DN")
	)
	(segment
		(start 120.500902 -87.603584)
		(end 119.929402 -87.603584)
		(width 0.1143)
		(layer "F.Cu")
		(net "CLK_100M_CPU1_BCLK1_DP")
	)
	(segment
		(start 165.626796 -89.017856)
		(end 165.626796 -87.924132)
		(width 0.1143)
		(layer "F.Cu")
		(net "CLK_100M_CPU1_BCLK1_DP")
	)
	(segment
		(start 165.626796 -87.924132)
		(end 165.793928 -87.757)
		(width 0.1143)
		(layer "F.Cu")
		(net "CLK_100M_CPU1_BCLK1_DP")
	)
	(segment
		(start 166.165276 -89.206324)
		(end 165.815264 -89.206324)
		(width 0.1143)
		(layer "F.Cu")
		(net "CLK_100M_CPU1_BCLK1_DP")
	)
	(segment
		(start 165.793928 -87.757)
		(end 166.116 -87.757)
		(width 0.1143)
		(layer "F.Cu")
		(net "CLK_100M_CPU1_BCLK1_DP")
	)
	(segment
		(start 165.815264 -89.206324)
		(end 165.626796 -89.017856)
		(width 0.1143)
		(layer "F.Cu")
		(net "CLK_100M_CPU1_BCLK1_DP")
	)
	(via
		(at 166.165276 -89.206324)
		(size 0.508)
		(drill 0.254)
		(layers "F.Cu" "B.Cu")
		(net "CLK_100M_CPU1_BCLK1_DP")
	)
	(via
		(at 120.500902 -87.603584)
		(size 0.508)
		(drill 0.254)
		(layers "F.Cu" "B.Cu")
		(net "CLK_100M_CPU1_BCLK1_DP")
	)
	(segment
		(start 165.620192 -87.986362)
		(end 165.620192 -88.979502)
		(width 0.1143)
		(layer "B.Cu")
		(net "CLK_100M_CPU1_BCLK1_DP")
	)
	(segment
		(start 165.847014 -89.206324)
		(end 166.165276 -89.206324)
		(width 0.1143)
		(layer "B.Cu")
		(net "CLK_100M_CPU1_BCLK1_DP")
	)
	(segment
		(start 165.620192 -88.979502)
		(end 165.847014 -89.206324)
		(width 0.1143)
		(layer "B.Cu")
		(net "CLK_100M_CPU1_BCLK1_DP")
	)
	(segment
		(start 166.116 -87.757)
		(end 165.849554 -87.757)
		(width 0.1143)
		(layer "B.Cu")
		(net "CLK_100M_CPU1_BCLK1_DP")
	)
	(segment
		(start 165.849554 -87.757)
		(end 165.620192 -87.986362)
		(width 0.1143)
		(layer "B.Cu")
		(net "CLK_100M_CPU1_BCLK1_DP")
	)
	(segment
		(start 165.67785 -97.422208)
		(end 165.67785 -89.69375)
		(width 0.1143)
		(layer "In4.Cu")
		(net "CLK_100M_CPU1_BCLK1_DP")
	)
	(segment
		(start 157.065726 -103.17353)
		(end 161.913316 -98.32594)
		(width 0.1143)
		(layer "In4.Cu")
		(net "CLK_100M_CPU1_BCLK1_DP")
	)
	(segment
		(start 145.270982 -104.639618)
		(end 144.98574 -104.92486)
		(width 0.1143)
		(layer "In4.Cu")
		(net "CLK_100M_CPU1_BCLK1_DP")
	)
	(segment
		(start 162.6362 -89.3445)
		(end 162.7505 -89.4588)
		(width 0.1143)
		(layer "In4.Cu")
		(net "CLK_100M_CPU1_BCLK1_DP")
	)
	(segment
		(start 145.262854 -104.118918)
		(end 155.038044 -104.118918)
		(width 0.1143)
		(layer "In4.Cu")
		(net "CLK_100M_CPU1_BCLK1_DP")
	)
	(segment
		(start 164.4015 -97.435162)
		(end 164.74313 -97.776792)
		(width 0.1143)
		(layer "In4.Cu")
		(net "CLK_100M_CPU1_BCLK1_DP")
	)
	(segment
		(start 132.494782 -90.175334)
		(end 132.541264 -90.175334)
		(width 0.0889)
		(layer "In4.Cu")
		(net "CLK_100M_CPU1_BCLK1_DP")
	)
	(segment
		(start 157.475174 -103.500682)
		(end 157.231588 -103.500682)
		(width 0.1143)
		(layer "In4.Cu")
		(net "CLK_100M_CPU1_BCLK1_DP")
	)
	(segment
		(start 129.064258 -90.175334)
		(end 129.107438 -90.175334)
		(width 0.0889)
		(layer "In4.Cu")
		(net "CLK_100M_CPU1_BCLK1_DP")
	)
	(segment
		(start 162.862006 -99.677982)
		(end 162.862006 -99.27463)
		(width 0.1143)
		(layer "In4.Cu")
		(net "CLK_100M_CPU1_BCLK1_DP")
	)
	(segment
		(start 155.866846 -105.744518)
		(end 156.855922 -104.755442)
		(width 0.1143)
		(layer "In4.Cu")
		(net "CLK_100M_CPU1_BCLK1_DP")
	)
	(segment
		(start 144.033748 -102.889812)
		(end 145.262854 -104.118918)
		(width 0.1143)
		(layer "In4.Cu")
		(net "CLK_100M_CPU1_BCLK1_DP")
	)
	(segment
		(start 164.2872 -89.7382)
		(end 164.4015 -89.8525)
		(width 0.1143)
		(layer "In4.Cu")
		(net "CLK_100M_CPU1_BCLK1_DP")
	)
	(segment
		(start 127.347218 -90.175334)
		(end 127.390398 -90.175334)
		(width 0.0889)
		(layer "In4.Cu")
		(net "CLK_100M_CPU1_BCLK1_DP")
	)
	(segment
		(start 129.929382 -89.680288)
		(end 129.959354 -89.680288)
		(width 0.0889)
		(layer "In4.Cu")
		(net "CLK_100M_CPU1_BCLK1_DP")
	)
	(segment
		(start 125.630178 -90.175334)
		(end 125.673358 -90.175334)
		(width 0.0889)
		(layer "In4.Cu")
		(net "CLK_100M_CPU1_BCLK1_DP")
	)
	(segment
		(start 164.0205 -89.7382)
		(end 164.2872 -89.7382)
		(width 0.1143)
		(layer "In4.Cu")
		(net "CLK_100M_CPU1_BCLK1_DP")
	)
	(segment
		(start 143.956024 -89.184734)
		(end 144.084548 -89.313258)
		(width 0.0889)
		(layer "In4.Cu")
		(net "CLK_100M_CPU1_BCLK1_DP")
	)
	(segment
		(start 137.649204 -90.175334)
		(end 137.692384 -90.175334)
		(width 0.0889)
		(layer "In4.Cu")
		(net "CLK_100M_CPU1_BCLK1_DP")
	)
	(segment
		(start 162.7505 -89.4588)
		(end 162.7505 -97.568258)
		(width 0.1143)
		(layer "In4.Cu")
		(net "CLK_100M_CPU1_BCLK1_DP")
	)
	(segment
		(start 162.027616 -89.3445)
		(end 162.6362 -89.3445)
		(width 0.1143)
		(layer "In4.Cu")
		(net "CLK_100M_CPU1_BCLK1_DP")
	)
	(segment
		(start 164.74313 -97.776792)
		(end 165.323266 -97.776792)
		(width 0.1143)
		(layer "In4.Cu")
		(net "CLK_100M_CPU1_BCLK1_DP")
	)
	(segment
		(start 136.797288 -89.680288)
		(end 136.82726 -89.680288)
		(width 0.0889)
		(layer "In4.Cu")
		(net "CLK_100M_CPU1_BCLK1_DP")
	)
	(segment
		(start 135.080248 -89.680288)
		(end 135.11022 -89.680288)
		(width 0.0889)
		(layer "In4.Cu")
		(net "CLK_100M_CPU1_BCLK1_DP")
	)
	(segment
		(start 144.98574 -105.459276)
		(end 145.270982 -105.744518)
		(width 0.1143)
		(layer "In4.Cu")
		(net "CLK_100M_CPU1_BCLK1_DP")
	)
	(segment
		(start 140.231368 -89.680288)
		(end 140.264134 -89.680288)
		(width 0.0889)
		(layer "In4.Cu")
		(net "CLK_100M_CPU1_BCLK1_DP")
	)
	(segment
		(start 157.065726 -103.33482)
		(end 157.065726 -103.17353)
		(width 0.1143)
		(layer "In4.Cu")
		(net "CLK_100M_CPU1_BCLK1_DP")
	)
	(segment
		(start 162.862006 -99.27463)
		(end 162.483292 -98.895916)
		(width 0.1143)
		(layer "In4.Cu")
		(net "CLK_100M_CPU1_BCLK1_DP")
	)
	(segment
		(start 156.855922 -104.755442)
		(end 157.784546 -104.755442)
		(width 0.1143)
		(layer "In4.Cu")
		(net "CLK_100M_CPU1_BCLK1_DP")
	)
	(segment
		(start 162.483292 -98.895916)
		(end 162.07994 -98.895916)
		(width 0.1143)
		(layer "In4.Cu")
		(net "CLK_100M_CPU1_BCLK1_DP")
	)
	(segment
		(start 144.084548 -89.313258)
		(end 144.084548 -89.653364)
		(width 0.0889)
		(layer "In4.Cu")
		(net "CLK_100M_CPU1_BCLK1_DP")
	)
	(segment
		(start 121.341388 -89.680288)
		(end 121.374154 -89.680288)
		(width 0.0889)
		(layer "In4.Cu")
		(net "CLK_100M_CPU1_BCLK1_DP")
	)
	(segment
		(start 132.004562 -89.874598)
		(end 132.007864 -89.88044)
		(width 0.0889)
		(layer "In4.Cu")
		(net "CLK_100M_CPU1_BCLK1_DP")
	)
	(segment
		(start 138.514328 -89.680288)
		(end 138.5443 -89.680288)
		(width 0.0889)
		(layer "In4.Cu")
		(net "CLK_100M_CPU1_BCLK1_DP")
	)
	(segment
		(start 155.1559 -104.236774)
		(end 155.1559 -104.525318)
		(width 0.1143)
		(layer "In4.Cu")
		(net "CLK_100M_CPU1_BCLK1_DP")
	)
	(segment
		(start 165.67785 -89.69375)
		(end 166.165276 -89.206324)
		(width 0.1143)
		(layer "In4.Cu")
		(net "CLK_100M_CPU1_BCLK1_DP")
	)
	(segment
		(start 128.212342 -89.680288)
		(end 128.242314 -89.680288)
		(width 0.0889)
		(layer "In4.Cu")
		(net "CLK_100M_CPU1_BCLK1_DP")
	)
	(segment
		(start 161.913316 -98.32594)
		(end 161.913316 -89.4588)
		(width 0.1143)
		(layer "In4.Cu")
		(net "CLK_100M_CPU1_BCLK1_DP")
	)
	(segment
		(start 164.4015 -89.8525)
		(end 164.4015 -97.435162)
		(width 0.1143)
		(layer "In4.Cu")
		(net "CLK_100M_CPU1_BCLK1_DP")
	)
	(segment
		(start 157.231588 -103.500682)
		(end 157.065726 -103.33482)
		(width 0.1143)
		(layer "In4.Cu")
		(net "CLK_100M_CPU1_BCLK1_DP")
	)
	(segment
		(start 144.084548 -89.653364)
		(end 144.033748 -89.704164)
		(width 0.0889)
		(layer "In4.Cu")
		(net "CLK_100M_CPU1_BCLK1_DP")
	)
	(segment
		(start 126.495302 -89.680288)
		(end 126.525274 -89.680288)
		(width 0.0889)
		(layer "In4.Cu")
		(net "CLK_100M_CPU1_BCLK1_DP")
	)
	(segment
		(start 124.778262 -89.680288)
		(end 124.808234 -89.680288)
		(width 0.0889)
		(layer "In4.Cu")
		(net "CLK_100M_CPU1_BCLK1_DP")
	)
	(segment
		(start 142.84198 -89.184734)
		(end 143.956024 -89.184734)
		(width 0.0889)
		(layer "In4.Cu")
		(net "CLK_100M_CPU1_BCLK1_DP")
	)
	(segment
		(start 162.7505 -97.568258)
		(end 163.035742 -97.8535)
		(width 0.1143)
		(layer "In4.Cu")
		(net "CLK_100M_CPU1_BCLK1_DP")
	)
	(segment
		(start 163.620958 -97.8535)
		(end 163.9062 -97.568258)
		(width 0.1143)
		(layer "In4.Cu")
		(net "CLK_100M_CPU1_BCLK1_DP")
	)
	(segment
		(start 155.038044 -104.118918)
		(end 155.1559 -104.236774)
		(width 0.1143)
		(layer "In4.Cu")
		(net "CLK_100M_CPU1_BCLK1_DP")
	)
	(segment
		(start 145.270982 -105.744518)
		(end 155.866846 -105.744518)
		(width 0.1143)
		(layer "In4.Cu")
		(net "CLK_100M_CPU1_BCLK1_DP")
	)
	(segment
		(start 141.945614 -89.680288)
		(end 142.164308 -89.680288)
		(width 0.0889)
		(layer "In4.Cu")
		(net "CLK_100M_CPU1_BCLK1_DP")
	)
	(segment
		(start 144.033748 -89.726262)
		(end 144.033748 -102.889812)
		(width 0.1143)
		(layer "In4.Cu")
		(net "CLK_100M_CPU1_BCLK1_DP")
	)
	(segment
		(start 163.9062 -89.8525)
		(end 164.0205 -89.7382)
		(width 0.1143)
		(layer "In4.Cu")
		(net "CLK_100M_CPU1_BCLK1_DP")
	)
	(segment
		(start 163.035742 -97.8535)
		(end 163.620958 -97.8535)
		(width 0.1143)
		(layer "In4.Cu")
		(net "CLK_100M_CPU1_BCLK1_DP")
	)
	(segment
		(start 144.033748 -89.704164)
		(end 144.033748 -89.726262)
		(width 0.0889)
		(layer "In4.Cu")
		(net "CLK_100M_CPU1_BCLK1_DP")
	)
	(segment
		(start 123.061222 -89.680288)
		(end 123.091194 -89.680288)
		(width 0.0889)
		(layer "In4.Cu")
		(net "CLK_100M_CPU1_BCLK1_DP")
	)
	(segment
		(start 162.07994 -98.895916)
		(end 157.475174 -103.500682)
		(width 0.1143)
		(layer "In4.Cu")
		(net "CLK_100M_CPU1_BCLK1_DP")
	)
	(segment
		(start 135.932164 -90.175334)
		(end 135.975344 -90.175334)
		(width 0.0889)
		(layer "In4.Cu")
		(net "CLK_100M_CPU1_BCLK1_DP")
	)
	(segment
		(start 139.366244 -90.175334)
		(end 139.409424 -90.175334)
		(width 0.0889)
		(layer "In4.Cu")
		(net "CLK_100M_CPU1_BCLK1_DP")
	)
	(segment
		(start 155.1559 -104.525318)
		(end 155.0416 -104.639618)
		(width 0.1143)
		(layer "In4.Cu")
		(net "CLK_100M_CPU1_BCLK1_DP")
	)
	(segment
		(start 133.363208 -89.680288)
		(end 133.39318 -89.680288)
		(width 0.0889)
		(layer "In4.Cu")
		(net "CLK_100M_CPU1_BCLK1_DP")
	)
	(segment
		(start 122.196098 -90.175334)
		(end 122.239278 -90.175334)
		(width 0.0889)
		(layer "In4.Cu")
		(net "CLK_100M_CPU1_BCLK1_DP")
	)
	(segment
		(start 123.913138 -90.175334)
		(end 123.956318 -90.175334)
		(width 0.0889)
		(layer "In4.Cu")
		(net "CLK_100M_CPU1_BCLK1_DP")
	)
	(segment
		(start 161.913316 -89.4588)
		(end 162.027616 -89.3445)
		(width 0.1143)
		(layer "In4.Cu")
		(net "CLK_100M_CPU1_BCLK1_DP")
	)
	(segment
		(start 120.838468 -88.379046)
		(end 120.847358 -88.394286)
		(width 0.0889)
		(layer "In4.Cu")
		(net "CLK_100M_CPU1_BCLK1_DP")
	)
	(segment
		(start 130.781298 -90.175334)
		(end 130.824478 -90.175334)
		(width 0.0889)
		(layer "In4.Cu")
		(net "CLK_100M_CPU1_BCLK1_DP")
	)
	(segment
		(start 165.323266 -97.776792)
		(end 165.67785 -97.422208)
		(width 0.1143)
		(layer "In4.Cu")
		(net "CLK_100M_CPU1_BCLK1_DP")
	)
	(segment
		(start 134.215124 -90.175334)
		(end 134.258304 -90.175334)
		(width 0.0889)
		(layer "In4.Cu")
		(net "CLK_100M_CPU1_BCLK1_DP")
	)
	(segment
		(start 157.784546 -104.755442)
		(end 162.862006 -99.677982)
		(width 0.1143)
		(layer "In4.Cu")
		(net "CLK_100M_CPU1_BCLK1_DP")
	)
	(segment
		(start 120.500902 -87.603584)
		(end 120.639332 -87.742014)
		(width 0.0889)
		(layer "In4.Cu")
		(net "CLK_100M_CPU1_BCLK1_DP")
	)
	(segment
		(start 144.98574 -104.92486)
		(end 144.98574 -105.459276)
		(width 0.1143)
		(layer "In4.Cu")
		(net "CLK_100M_CPU1_BCLK1_DP")
	)
	(segment
		(start 155.0416 -104.639618)
		(end 145.270982 -104.639618)
		(width 0.1143)
		(layer "In4.Cu")
		(net "CLK_100M_CPU1_BCLK1_DP")
	)
	(segment
		(start 163.9062 -97.568258)
		(end 163.9062 -89.8525)
		(width 0.1143)
		(layer "In4.Cu")
		(net "CLK_100M_CPU1_BCLK1_DP")
	)
	(arc
		(start 126.163578 -89.880186)
		(mid 126.303657 -89.73745)
		(end 126.495302 -89.680288)
		(width 0.0889)
		(layer "In4.Cu")
		(net "CLK_100M_CPU1_BCLK1_DP")
	)
	(arc
		(start 120.847358 -88.394286)
		(mid 120.900891 -88.594184)
		(end 120.847358 -88.794082)
		(width 0.0889)
		(layer "In4.Cu")
		(net "CLK_100M_CPU1_BCLK1_DP")
	)
	(arc
		(start 120.639332 -87.742014)
		(mid 120.738847 -87.894427)
		(end 120.768618 -88.073992)
		(width 0.0889)
		(layer "In4.Cu")
		(net "CLK_100M_CPU1_BCLK1_DP")
	)
	(arc
		(start 131.314698 -89.880186)
		(mid 131.454937 -89.737563)
		(end 131.646676 -89.680542)
		(width 0.0889)
		(layer "In4.Cu")
		(net "CLK_100M_CPU1_BCLK1_DP")
	)
	(arc
		(start 138.5443 -89.680288)
		(mid 138.735942 -89.737454)
		(end 138.876024 -89.880186)
		(width 0.0889)
		(layer "In4.Cu")
		(net "CLK_100M_CPU1_BCLK1_DP")
	)
	(arc
		(start 125.139958 -89.880186)
		(mid 125.346962 -90.09105)
		(end 125.630178 -90.175334)
		(width 0.0889)
		(layer "In4.Cu")
		(net "CLK_100M_CPU1_BCLK1_DP")
	)
	(arc
		(start 128.574038 -89.880186)
		(mid 128.781042 -90.09105)
		(end 129.064258 -90.175334)
		(width 0.0889)
		(layer "In4.Cu")
		(net "CLK_100M_CPU1_BCLK1_DP")
	)
	(arc
		(start 141.092936 -89.184734)
		(mid 141.104874 -89.184556)
		(end 141.116812 -89.184734)
		(width 0.0889)
		(layer "In4.Cu")
		(net "CLK_100M_CPU1_BCLK1_DP")
	)
	(arc
		(start 131.678172 -89.680542)
		(mid 131.865869 -89.73637)
		(end 132.004562 -89.874598)
		(width 0.0889)
		(layer "In4.Cu")
		(net "CLK_100M_CPU1_BCLK1_DP")
	)
	(arc
		(start 129.959354 -89.680288)
		(mid 130.150996 -89.737454)
		(end 130.291078 -89.880186)
		(width 0.0889)
		(layer "In4.Cu")
		(net "CLK_100M_CPU1_BCLK1_DP")
	)
	(arc
		(start 130.291078 -89.880186)
		(mid 130.498082 -90.09105)
		(end 130.781298 -90.175334)
		(width 0.0889)
		(layer "In4.Cu")
		(net "CLK_100M_CPU1_BCLK1_DP")
	)
	(arc
		(start 123.422918 -89.880186)
		(mid 123.629922 -90.09105)
		(end 123.913138 -90.175334)
		(width 0.0889)
		(layer "In4.Cu")
		(net "CLK_100M_CPU1_BCLK1_DP")
	)
	(arc
		(start 122.729498 -89.880186)
		(mid 122.869577 -89.73745)
		(end 123.061222 -89.680288)
		(width 0.0889)
		(layer "In4.Cu")
		(net "CLK_100M_CPU1_BCLK1_DP")
	)
	(arc
		(start 133.724904 -89.880186)
		(mid 133.931908 -90.09105)
		(end 134.215124 -90.175334)
		(width 0.0889)
		(layer "In4.Cu")
		(net "CLK_100M_CPU1_BCLK1_DP")
	)
	(arc
		(start 136.465564 -89.880186)
		(mid 136.605643 -89.73745)
		(end 136.797288 -89.680288)
		(width 0.0889)
		(layer "In4.Cu")
		(net "CLK_100M_CPU1_BCLK1_DP")
	)
	(arc
		(start 137.692384 -90.175334)
		(mid 137.975601 -90.091053)
		(end 138.182604 -89.880186)
		(width 0.0889)
		(layer "In4.Cu")
		(net "CLK_100M_CPU1_BCLK1_DP")
	)
	(arc
		(start 129.107438 -90.175334)
		(mid 129.390655 -90.091053)
		(end 129.597658 -89.880186)
		(width 0.0889)
		(layer "In4.Cu")
		(net "CLK_100M_CPU1_BCLK1_DP")
	)
	(arc
		(start 124.446538 -89.880186)
		(mid 124.586617 -89.73745)
		(end 124.778262 -89.680288)
		(width 0.0889)
		(layer "In4.Cu")
		(net "CLK_100M_CPU1_BCLK1_DP")
	)
	(arc
		(start 141.451584 -89.384886)
		(mid 141.660192 -89.596818)
		(end 141.945614 -89.680288)
		(width 0.0889)
		(layer "In4.Cu")
		(net "CLK_100M_CPU1_BCLK1_DP")
	)
	(arc
		(start 133.031484 -89.880186)
		(mid 133.171563 -89.73745)
		(end 133.363208 -89.680288)
		(width 0.0889)
		(layer "In4.Cu")
		(net "CLK_100M_CPU1_BCLK1_DP")
	)
	(arc
		(start 136.82726 -89.680288)
		(mid 137.018902 -89.737454)
		(end 137.158984 -89.880186)
		(width 0.0889)
		(layer "In4.Cu")
		(net "CLK_100M_CPU1_BCLK1_DP")
	)
	(arc
		(start 134.748524 -89.880186)
		(mid 134.888603 -89.73745)
		(end 135.080248 -89.680288)
		(width 0.0889)
		(layer "In4.Cu")
		(net "CLK_100M_CPU1_BCLK1_DP")
	)
	(arc
		(start 131.646676 -89.680542)
		(mid 131.662424 -89.680232)
		(end 131.678172 -89.680542)
		(width 0.0889)
		(layer "In4.Cu")
		(net "CLK_100M_CPU1_BCLK1_DP")
	)
	(arc
		(start 139.409424 -90.175334)
		(mid 139.692641 -90.091053)
		(end 139.899644 -89.880186)
		(width 0.0889)
		(layer "In4.Cu")
		(net "CLK_100M_CPU1_BCLK1_DP")
	)
	(arc
		(start 132.007864 -89.88044)
		(mid 132.213485 -90.090363)
		(end 132.494782 -90.175334)
		(width 0.0889)
		(layer "In4.Cu")
		(net "CLK_100M_CPU1_BCLK1_DP")
	)
	(arc
		(start 142.164308 -89.680288)
		(mid 142.368096 -89.564429)
		(end 142.514828 -89.381584)
		(width 0.0889)
		(layer "In4.Cu")
		(net "CLK_100M_CPU1_BCLK1_DP")
	)
	(arc
		(start 141.116812 -89.184734)
		(mid 141.310238 -89.241261)
		(end 141.451584 -89.384886)
		(width 0.0889)
		(layer "In4.Cu")
		(net "CLK_100M_CPU1_BCLK1_DP")
	)
	(arc
		(start 139.899644 -89.880186)
		(mid 140.039723 -89.73745)
		(end 140.231368 -89.680288)
		(width 0.0889)
		(layer "In4.Cu")
		(net "CLK_100M_CPU1_BCLK1_DP")
	)
	(arc
		(start 122.239278 -90.175334)
		(mid 122.522495 -90.091053)
		(end 122.729498 -89.880186)
		(width 0.0889)
		(layer "In4.Cu")
		(net "CLK_100M_CPU1_BCLK1_DP")
	)
	(arc
		(start 140.758164 -89.384886)
		(mid 140.89952 -89.241277)
		(end 141.092936 -89.184734)
		(width 0.0889)
		(layer "In4.Cu")
		(net "CLK_100M_CPU1_BCLK1_DP")
	)
	(arc
		(start 124.808234 -89.680288)
		(mid 124.999876 -89.737454)
		(end 125.139958 -89.880186)
		(width 0.0889)
		(layer "In4.Cu")
		(net "CLK_100M_CPU1_BCLK1_DP")
	)
	(arc
		(start 123.091194 -89.680288)
		(mid 123.282836 -89.737454)
		(end 123.422918 -89.880186)
		(width 0.0889)
		(layer "In4.Cu")
		(net "CLK_100M_CPU1_BCLK1_DP")
	)
	(arc
		(start 127.880618 -89.880186)
		(mid 128.020697 -89.73745)
		(end 128.212342 -89.680288)
		(width 0.0889)
		(layer "In4.Cu")
		(net "CLK_100M_CPU1_BCLK1_DP")
	)
	(arc
		(start 128.242314 -89.680288)
		(mid 128.433956 -89.737454)
		(end 128.574038 -89.880186)
		(width 0.0889)
		(layer "In4.Cu")
		(net "CLK_100M_CPU1_BCLK1_DP")
	)
	(arc
		(start 120.847358 -88.794082)
		(mid 120.84303 -89.377258)
		(end 121.341388 -89.680288)
		(width 0.0889)
		(layer "In4.Cu")
		(net "CLK_100M_CPU1_BCLK1_DP")
	)
	(arc
		(start 132.541264 -90.175334)
		(mid 132.824481 -90.091053)
		(end 133.031484 -89.880186)
		(width 0.0889)
		(layer "In4.Cu")
		(net "CLK_100M_CPU1_BCLK1_DP")
	)
	(arc
		(start 140.264134 -89.680288)
		(mid 140.549558 -89.596821)
		(end 140.758164 -89.384886)
		(width 0.0889)
		(layer "In4.Cu")
		(net "CLK_100M_CPU1_BCLK1_DP")
	)
	(arc
		(start 138.876024 -89.880186)
		(mid 139.083028 -90.09105)
		(end 139.366244 -90.175334)
		(width 0.0889)
		(layer "In4.Cu")
		(net "CLK_100M_CPU1_BCLK1_DP")
	)
	(arc
		(start 135.11022 -89.680288)
		(mid 135.301862 -89.737454)
		(end 135.441944 -89.880186)
		(width 0.0889)
		(layer "In4.Cu")
		(net "CLK_100M_CPU1_BCLK1_DP")
	)
	(arc
		(start 121.374154 -89.680288)
		(mid 121.565796 -89.737454)
		(end 121.705878 -89.880186)
		(width 0.0889)
		(layer "In4.Cu")
		(net "CLK_100M_CPU1_BCLK1_DP")
	)
	(arc
		(start 126.525274 -89.680288)
		(mid 126.716916 -89.737454)
		(end 126.856998 -89.880186)
		(width 0.0889)
		(layer "In4.Cu")
		(net "CLK_100M_CPU1_BCLK1_DP")
	)
	(arc
		(start 120.768618 -88.073992)
		(mid 120.783022 -88.231214)
		(end 120.838468 -88.379046)
		(width 0.0889)
		(layer "In4.Cu")
		(net "CLK_100M_CPU1_BCLK1_DP")
	)
	(arc
		(start 142.514828 -89.381584)
		(mid 142.651083 -89.237761)
		(end 142.84198 -89.184734)
		(width 0.0889)
		(layer "In4.Cu")
		(net "CLK_100M_CPU1_BCLK1_DP")
	)
	(arc
		(start 126.856998 -89.880186)
		(mid 127.064002 -90.09105)
		(end 127.347218 -90.175334)
		(width 0.0889)
		(layer "In4.Cu")
		(net "CLK_100M_CPU1_BCLK1_DP")
	)
	(arc
		(start 133.39318 -89.680288)
		(mid 133.584822 -89.737454)
		(end 133.724904 -89.880186)
		(width 0.0889)
		(layer "In4.Cu")
		(net "CLK_100M_CPU1_BCLK1_DP")
	)
	(arc
		(start 130.824478 -90.175334)
		(mid 131.107695 -90.091053)
		(end 131.314698 -89.880186)
		(width 0.0889)
		(layer "In4.Cu")
		(net "CLK_100M_CPU1_BCLK1_DP")
	)
	(arc
		(start 123.956318 -90.175334)
		(mid 124.239535 -90.091053)
		(end 124.446538 -89.880186)
		(width 0.0889)
		(layer "In4.Cu")
		(net "CLK_100M_CPU1_BCLK1_DP")
	)
	(arc
		(start 127.390398 -90.175334)
		(mid 127.673615 -90.091053)
		(end 127.880618 -89.880186)
		(width 0.0889)
		(layer "In4.Cu")
		(net "CLK_100M_CPU1_BCLK1_DP")
	)
	(arc
		(start 137.158984 -89.880186)
		(mid 137.365988 -90.09105)
		(end 137.649204 -90.175334)
		(width 0.0889)
		(layer "In4.Cu")
		(net "CLK_100M_CPU1_BCLK1_DP")
	)
	(arc
		(start 125.673358 -90.175334)
		(mid 125.956575 -90.091053)
		(end 126.163578 -89.880186)
		(width 0.0889)
		(layer "In4.Cu")
		(net "CLK_100M_CPU1_BCLK1_DP")
	)
	(arc
		(start 135.975344 -90.175334)
		(mid 136.258561 -90.091053)
		(end 136.465564 -89.880186)
		(width 0.0889)
		(layer "In4.Cu")
		(net "CLK_100M_CPU1_BCLK1_DP")
	)
	(arc
		(start 138.182604 -89.880186)
		(mid 138.322683 -89.73745)
		(end 138.514328 -89.680288)
		(width 0.0889)
		(layer "In4.Cu")
		(net "CLK_100M_CPU1_BCLK1_DP")
	)
	(arc
		(start 134.258304 -90.175334)
		(mid 134.541521 -90.091053)
		(end 134.748524 -89.880186)
		(width 0.0889)
		(layer "In4.Cu")
		(net "CLK_100M_CPU1_BCLK1_DP")
	)
	(arc
		(start 135.441944 -89.880186)
		(mid 135.648948 -90.09105)
		(end 135.932164 -90.175334)
		(width 0.0889)
		(layer "In4.Cu")
		(net "CLK_100M_CPU1_BCLK1_DP")
	)
	(arc
		(start 129.597658 -89.880186)
		(mid 129.737737 -89.73745)
		(end 129.929382 -89.680288)
		(width 0.0889)
		(layer "In4.Cu")
		(net "CLK_100M_CPU1_BCLK1_DP")
	)
	(arc
		(start 121.705878 -89.880186)
		(mid 121.912882 -90.09105)
		(end 122.196098 -90.175334)
		(width 0.0889)
		(layer "In4.Cu")
		(net "CLK_100M_CPU1_BCLK1_DP")
	)
	(segment
		(start 121.359168 -88.099138)
		(end 120.787668 -88.099138)
		(width 0.1143)
		(layer "F.Cu")
		(net "CLK_100M_CPU1_BCLK1_DN")
	)
	(segment
		(start 165.197028 -89.206324)
		(end 165.385496 -89.017856)
		(width 0.1143)
		(layer "F.Cu")
		(net "CLK_100M_CPU1_BCLK1_DN")
	)
	(segment
		(start 164.895276 -89.206324)
		(end 165.197028 -89.206324)
		(width 0.1143)
		(layer "F.Cu")
		(net "CLK_100M_CPU1_BCLK1_DN")
	)
	(segment
		(start 165.192202 -87.757)
		(end 164.846 -87.757)
		(width 0.1143)
		(layer "F.Cu")
		(net "CLK_100M_CPU1_BCLK1_DN")
	)
	(segment
		(start 165.385496 -89.017856)
		(end 165.385496 -87.950294)
		(width 0.1143)
		(layer "F.Cu")
		(net "CLK_100M_CPU1_BCLK1_DN")
	)
	(segment
		(start 165.385496 -87.950294)
		(end 165.192202 -87.757)
		(width 0.1143)
		(layer "F.Cu")
		(net "CLK_100M_CPU1_BCLK1_DN")
	)
	(via
		(at 121.359168 -88.099138)
		(size 0.508)
		(drill 0.254)
		(layers "F.Cu" "B.Cu")
		(net "CLK_100M_CPU1_BCLK1_DN")
	)
	(via
		(at 164.895276 -89.206324)
		(size 0.508)
		(drill 0.254)
		(layers "F.Cu" "B.Cu")
		(net "CLK_100M_CPU1_BCLK1_DN")
	)
	(segment
		(start 165.378892 -88.006174)
		(end 165.378892 -89.012014)
		(width 0.1143)
		(layer "B.Cu")
		(net "CLK_100M_CPU1_BCLK1_DN")
	)
	(segment
		(start 165.378892 -89.012014)
		(end 165.184582 -89.206324)
		(width 0.1143)
		(layer "B.Cu")
		(net "CLK_100M_CPU1_BCLK1_DN")
	)
	(segment
		(start 165.184582 -89.206324)
		(end 164.895276 -89.206324)
		(width 0.1143)
		(layer "B.Cu")
		(net "CLK_100M_CPU1_BCLK1_DN")
	)
	(segment
		(start 164.846 -87.757)
		(end 165.129718 -87.757)
		(width 0.1143)
		(layer "B.Cu")
		(net "CLK_100M_CPU1_BCLK1_DN")
	)
	(segment
		(start 165.129718 -87.757)
		(end 165.378892 -88.006174)
		(width 0.1143)
		(layer "B.Cu")
		(net "CLK_100M_CPU1_BCLK1_DN")
	)
	(segment
		(start 162.362642 -99.188524)
		(end 162.20059 -99.188524)
		(width 0.1143)
		(layer "In4.Cu")
		(net "CLK_100M_CPU1_BCLK1_DN")
	)
	(segment
		(start 144.035018 -88.994234)
		(end 144.275048 -89.234264)
		(width 0.0889)
		(layer "In4.Cu")
		(net "CLK_100M_CPU1_BCLK1_DN")
	)
	(segment
		(start 162.757358 -89.0524)
		(end 163.0426 -89.337642)
		(width 0.1143)
		(layer "In4.Cu")
		(net "CLK_100M_CPU1_BCLK1_DN")
	)
	(segment
		(start 144.325848 -94.88805)
		(end 144.325848 -98.704654)
		(width 0.1143)
		(layer "In4.Cu")
		(net "CLK_100M_CPU1_BCLK1_DN")
	)
	(segment
		(start 121.359168 -89.489788)
		(end 121.380758 -89.489788)
		(width 0.0889)
		(layer "In4.Cu")
		(net "CLK_100M_CPU1_BCLK1_DN")
	)
	(segment
		(start 163.4998 -97.5614)
		(end 163.6141 -97.4471)
		(width 0.1143)
		(layer "In4.Cu")
		(net "CLK_100M_CPU1_BCLK1_DN")
	)
	(segment
		(start 144.325848 -91.16695)
		(end 144.490948 -91.33205)
		(width 0.1143)
		(layer "In4.Cu")
		(net "CLK_100M_CPU1_BCLK1_DN")
	)
	(segment
		(start 136.790684 -89.489788)
		(end 136.833864 -89.489788)
		(width 0.0889)
		(layer "In4.Cu")
		(net "CLK_100M_CPU1_BCLK1_DN")
	)
	(segment
		(start 144.325848 -100.393754)
		(end 144.325848 -100.736654)
		(width 0.1143)
		(layer "In4.Cu")
		(net "CLK_100M_CPU1_BCLK1_DN")
	)
	(segment
		(start 164.6936 -97.314004)
		(end 164.864288 -97.484692)
		(width 0.1143)
		(layer "In4.Cu")
		(net "CLK_100M_CPU1_BCLK1_DN")
	)
	(segment
		(start 155.159202 -103.826818)
		(end 155.448 -104.115616)
		(width 0.1143)
		(layer "In4.Cu")
		(net "CLK_100M_CPU1_BCLK1_DN")
	)
	(segment
		(start 144.490948 -94.38005)
		(end 144.490948 -94.72295)
		(width 0.1143)
		(layer "In4.Cu")
		(net "CLK_100M_CPU1_BCLK1_DN")
	)
	(segment
		(start 124.771658 -89.489788)
		(end 124.814838 -89.489788)
		(width 0.0889)
		(layer "In4.Cu")
		(net "CLK_100M_CPU1_BCLK1_DN")
	)
	(segment
		(start 164.408358 -89.4461)
		(end 164.6936 -89.731342)
		(width 0.1143)
		(layer "In4.Cu")
		(net "CLK_100M_CPU1_BCLK1_DN")
	)
	(segment
		(start 138.507724 -89.489788)
		(end 138.550904 -89.489788)
		(width 0.0889)
		(layer "In4.Cu")
		(net "CLK_100M_CPU1_BCLK1_DN")
	)
	(segment
		(start 144.325848 -93.19895)
		(end 144.490948 -93.36405)
		(width 0.1143)
		(layer "In4.Cu")
		(net "CLK_100M_CPU1_BCLK1_DN")
	)
	(segment
		(start 145.27784 -105.046018)
		(end 145.27784 -105.338118)
		(width 0.1143)
		(layer "In4.Cu")
		(net "CLK_100M_CPU1_BCLK1_DN")
	)
	(segment
		(start 144.490948 -94.72295)
		(end 144.325848 -94.88805)
		(width 0.1143)
		(layer "In4.Cu")
		(net "CLK_100M_CPU1_BCLK1_DN")
	)
	(segment
		(start 144.490948 -91.33205)
		(end 144.490948 -91.67495)
		(width 0.1143)
		(layer "In4.Cu")
		(net "CLK_100M_CPU1_BCLK1_DN")
	)
	(segment
		(start 144.490948 -91.67495)
		(end 144.325848 -91.84005)
		(width 0.1143)
		(layer "In4.Cu")
		(net "CLK_100M_CPU1_BCLK1_DN")
	)
	(segment
		(start 165.38575 -89.696798)
		(end 164.895276 -89.206324)
		(width 0.1143)
		(layer "In4.Cu")
		(net "CLK_100M_CPU1_BCLK1_DN")
	)
	(segment
		(start 144.490948 -99.212654)
		(end 144.325848 -99.377754)
		(width 0.1143)
		(layer "In4.Cu")
		(net "CLK_100M_CPU1_BCLK1_DN")
	)
	(segment
		(start 121.012712 -88.299036)
		(end 121.021602 -88.314276)
		(width 0.0889)
		(layer "In4.Cu")
		(net "CLK_100M_CPU1_BCLK1_DN")
	)
	(segment
		(start 144.490948 -93.70695)
		(end 144.325848 -93.87205)
		(width 0.1143)
		(layer "In4.Cu")
		(net "CLK_100M_CPU1_BCLK1_DN")
	)
	(segment
		(start 163.0426 -97.4471)
		(end 163.1569 -97.5614)
		(width 0.1143)
		(layer "In4.Cu")
		(net "CLK_100M_CPU1_BCLK1_DN")
	)
	(segment
		(start 122.202702 -89.984834)
		(end 122.232674 -89.984834)
		(width 0.0889)
		(layer "In4.Cu")
		(net "CLK_100M_CPU1_BCLK1_DN")
	)
	(segment
		(start 144.490948 -101.244654)
		(end 144.325848 -101.409754)
		(width 0.1143)
		(layer "In4.Cu")
		(net "CLK_100M_CPU1_BCLK1_DN")
	)
	(segment
		(start 123.054618 -89.489788)
		(end 123.097798 -89.489788)
		(width 0.0889)
		(layer "In4.Cu")
		(net "CLK_100M_CPU1_BCLK1_DN")
	)
	(segment
		(start 141.952218 -89.489788)
		(end 142.129764 -89.489788)
		(width 0.0889)
		(layer "In4.Cu")
		(net "CLK_100M_CPU1_BCLK1_DN")
	)
	(segment
		(start 141.087094 -88.994234)
		(end 141.122654 -88.994234)
		(width 0.0889)
		(layer "In4.Cu")
		(net "CLK_100M_CPU1_BCLK1_DN")
	)
	(segment
		(start 144.490948 -93.36405)
		(end 144.490948 -93.70695)
		(width 0.1143)
		(layer "In4.Cu")
		(net "CLK_100M_CPU1_BCLK1_DN")
	)
	(segment
		(start 140.224764 -89.489788)
		(end 140.25753 -89.489788)
		(width 0.0889)
		(layer "In4.Cu")
		(net "CLK_100M_CPU1_BCLK1_DN")
	)
	(segment
		(start 135.073644 -89.489788)
		(end 135.116824 -89.489788)
		(width 0.0889)
		(layer "In4.Cu")
		(net "CLK_100M_CPU1_BCLK1_DN")
	)
	(segment
		(start 144.325848 -99.377754)
		(end 144.325848 -99.720654)
		(width 0.1143)
		(layer "In4.Cu")
		(net "CLK_100M_CPU1_BCLK1_DN")
	)
	(segment
		(start 137.655808 -89.984834)
		(end 137.68578 -89.984834)
		(width 0.0889)
		(layer "In4.Cu")
		(net "CLK_100M_CPU1_BCLK1_DN")
	)
	(segment
		(start 125.636782 -89.984834)
		(end 125.666754 -89.984834)
		(width 0.0889)
		(layer "In4.Cu")
		(net "CLK_100M_CPU1_BCLK1_DN")
	)
	(segment
		(start 164.6936 -89.731342)
		(end 164.6936 -97.314004)
		(width 0.1143)
		(layer "In4.Cu")
		(net "CLK_100M_CPU1_BCLK1_DN")
	)
	(segment
		(start 156.734764 -104.463342)
		(end 157.663388 -104.463342)
		(width 0.1143)
		(layer "In4.Cu")
		(net "CLK_100M_CPU1_BCLK1_DN")
	)
	(segment
		(start 132.173218 -89.784682)
		(end 132.17652 -89.790524)
		(width 0.0889)
		(layer "In4.Cu")
		(net "CLK_100M_CPU1_BCLK1_DN")
	)
	(segment
		(start 156.773626 -103.052372)
		(end 161.621216 -98.204782)
		(width 0.1143)
		(layer "In4.Cu")
		(net "CLK_100M_CPU1_BCLK1_DN")
	)
	(segment
		(start 135.938768 -89.984834)
		(end 135.96874 -89.984834)
		(width 0.0889)
		(layer "In4.Cu")
		(net "CLK_100M_CPU1_BCLK1_DN")
	)
	(segment
		(start 144.490948 -100.228654)
		(end 144.325848 -100.393754)
		(width 0.1143)
		(layer "In4.Cu")
		(net "CLK_100M_CPU1_BCLK1_DN")
	)
	(segment
		(start 144.275048 -89.234264)
		(end 144.275048 -89.653364)
		(width 0.0889)
		(layer "In4.Cu")
		(net "CLK_100M_CPU1_BCLK1_DN")
	)
	(segment
		(start 161.906458 -89.0524)
		(end 162.757358 -89.0524)
		(width 0.1143)
		(layer "In4.Cu")
		(net "CLK_100M_CPU1_BCLK1_DN")
	)
	(segment
		(start 155.162758 -104.931718)
		(end 145.39214 -104.931718)
		(width 0.1143)
		(layer "In4.Cu")
		(net "CLK_100M_CPU1_BCLK1_DN")
	)
	(segment
		(start 134.221728 -89.984834)
		(end 134.2517 -89.984834)
		(width 0.0889)
		(layer "In4.Cu")
		(net "CLK_100M_CPU1_BCLK1_DN")
	)
	(segment
		(start 131.639818 -89.489788)
		(end 131.6863 -89.489788)
		(width 0.0889)
		(layer "In4.Cu")
		(net "CLK_100M_CPU1_BCLK1_DN")
	)
	(segment
		(start 142.84198 -88.994234)
		(end 144.035018 -88.994234)
		(width 0.0889)
		(layer "In4.Cu")
		(net "CLK_100M_CPU1_BCLK1_DN")
	)
	(segment
		(start 126.488698 -89.489788)
		(end 126.531878 -89.489788)
		(width 0.0889)
		(layer "In4.Cu")
		(net "CLK_100M_CPU1_BCLK1_DN")
	)
	(segment
		(start 145.39214 -105.452418)
		(end 155.745688 -105.452418)
		(width 0.1143)
		(layer "In4.Cu")
		(net "CLK_100M_CPU1_BCLK1_DN")
	)
	(segment
		(start 145.384012 -103.826818)
		(end 155.159202 -103.826818)
		(width 0.1143)
		(layer "In4.Cu")
		(net "CLK_100M_CPU1_BCLK1_DN")
	)
	(segment
		(start 144.325848 -92.85605)
		(end 144.325848 -93.19895)
		(width 0.1143)
		(layer "In4.Cu")
		(net "CLK_100M_CPU1_BCLK1_DN")
	)
	(segment
		(start 162.569398 -99.39528)
		(end 162.362642 -99.188524)
		(width 0.1143)
		(layer "In4.Cu")
		(net "CLK_100M_CPU1_BCLK1_DN")
	)
	(segment
		(start 144.325848 -102.768654)
		(end 145.384012 -103.826818)
		(width 0.1143)
		(layer "In4.Cu")
		(net "CLK_100M_CPU1_BCLK1_DN")
	)
	(segment
		(start 123.919742 -89.984834)
		(end 123.949714 -89.984834)
		(width 0.0889)
		(layer "In4.Cu")
		(net "CLK_100M_CPU1_BCLK1_DN")
	)
	(segment
		(start 162.20059 -99.188524)
		(end 157.596332 -103.792782)
		(width 0.1143)
		(layer "In4.Cu")
		(net "CLK_100M_CPU1_BCLK1_DN")
	)
	(segment
		(start 121.359168 -88.099138)
		(end 121.066306 -87.930228)
		(width 0.0889)
		(layer "In4.Cu")
		(net "CLK_100M_CPU1_BCLK1_DN")
	)
	(segment
		(start 144.325848 -92.18295)
		(end 144.490948 -92.34805)
		(width 0.1143)
		(layer "In4.Cu")
		(net "CLK_100M_CPU1_BCLK1_DN")
	)
	(segment
		(start 144.325848 -93.87205)
		(end 144.325848 -94.21495)
		(width 0.1143)
		(layer "In4.Cu")
		(net "CLK_100M_CPU1_BCLK1_DN")
	)
	(segment
		(start 144.325848 -94.21495)
		(end 144.490948 -94.38005)
		(width 0.1143)
		(layer "In4.Cu")
		(net "CLK_100M_CPU1_BCLK1_DN")
	)
	(segment
		(start 129.070862 -89.984834)
		(end 129.100834 -89.984834)
		(width 0.0889)
		(layer "In4.Cu")
		(net "CLK_100M_CPU1_BCLK1_DN")
	)
	(segment
		(start 145.39214 -104.931718)
		(end 145.27784 -105.046018)
		(width 0.1143)
		(layer "In4.Cu")
		(net "CLK_100M_CPU1_BCLK1_DN")
	)
	(segment
		(start 161.621216 -98.204782)
		(end 161.621216 -89.337642)
		(width 0.1143)
		(layer "In4.Cu")
		(net "CLK_100M_CPU1_BCLK1_DN")
	)
	(segment
		(start 163.6141 -97.4471)
		(end 163.6141 -89.731342)
		(width 0.1143)
		(layer "In4.Cu")
		(net "CLK_100M_CPU1_BCLK1_DN")
	)
	(segment
		(start 145.27784 -105.338118)
		(end 145.39214 -105.452418)
		(width 0.1143)
		(layer "In4.Cu")
		(net "CLK_100M_CPU1_BCLK1_DN")
	)
	(segment
		(start 144.325848 -98.704654)
		(end 144.490948 -98.869754)
		(width 0.1143)
		(layer "In4.Cu")
		(net "CLK_100M_CPU1_BCLK1_DN")
	)
	(segment
		(start 144.490948 -99.885754)
		(end 144.490948 -100.228654)
		(width 0.1143)
		(layer "In4.Cu")
		(net "CLK_100M_CPU1_BCLK1_DN")
	)
	(segment
		(start 130.787902 -89.984834)
		(end 130.817874 -89.984834)
		(width 0.0889)
		(layer "In4.Cu")
		(net "CLK_100M_CPU1_BCLK1_DN")
	)
	(segment
		(start 144.325848 -89.704164)
		(end 144.325848 -89.726262)
		(width 0.0889)
		(layer "In4.Cu")
		(net "CLK_100M_CPU1_BCLK1_DN")
	)
	(segment
		(start 165.38575 -97.30105)
		(end 165.38575 -89.696798)
		(width 0.1143)
		(layer "In4.Cu")
		(net "CLK_100M_CPU1_BCLK1_DN")
	)
	(segment
		(start 165.202108 -97.484692)
		(end 165.38575 -97.30105)
		(width 0.1143)
		(layer "In4.Cu")
		(net "CLK_100M_CPU1_BCLK1_DN")
	)
	(segment
		(start 144.490948 -92.69095)
		(end 144.325848 -92.85605)
		(width 0.1143)
		(layer "In4.Cu")
		(net "CLK_100M_CPU1_BCLK1_DN")
	)
	(segment
		(start 121.066306 -87.930228)
		(end 120.987566 -87.951564)
		(width 0.0889)
		(layer "In4.Cu")
		(net "CLK_100M_CPU1_BCLK1_DN")
	)
	(segment
		(start 163.6141 -89.731342)
		(end 163.899342 -89.4461)
		(width 0.1143)
		(layer "In4.Cu")
		(net "CLK_100M_CPU1_BCLK1_DN")
	)
	(segment
		(start 144.325848 -91.84005)
		(end 144.325848 -92.18295)
		(width 0.1143)
		(layer "In4.Cu")
		(net "CLK_100M_CPU1_BCLK1_DN")
	)
	(segment
		(start 127.353822 -89.984834)
		(end 127.383794 -89.984834)
		(width 0.0889)
		(layer "In4.Cu")
		(net "CLK_100M_CPU1_BCLK1_DN")
	)
	(segment
		(start 144.325848 -101.409754)
		(end 144.325848 -102.768654)
		(width 0.1143)
		(layer "In4.Cu")
		(net "CLK_100M_CPU1_BCLK1_DN")
	)
	(segment
		(start 163.1569 -97.5614)
		(end 163.4998 -97.5614)
		(width 0.1143)
		(layer "In4.Cu")
		(net "CLK_100M_CPU1_BCLK1_DN")
	)
	(segment
		(start 163.899342 -89.4461)
		(end 164.408358 -89.4461)
		(width 0.1143)
		(layer "In4.Cu")
		(net "CLK_100M_CPU1_BCLK1_DN")
	)
	(segment
		(start 144.490948 -100.901754)
		(end 144.490948 -101.244654)
		(width 0.1143)
		(layer "In4.Cu")
		(net "CLK_100M_CPU1_BCLK1_DN")
	)
	(segment
		(start 155.448 -104.646476)
		(end 155.162758 -104.931718)
		(width 0.1143)
		(layer "In4.Cu")
		(net "CLK_100M_CPU1_BCLK1_DN")
	)
	(segment
		(start 128.205738 -89.489788)
		(end 128.248918 -89.489788)
		(width 0.0889)
		(layer "In4.Cu")
		(net "CLK_100M_CPU1_BCLK1_DN")
	)
	(segment
		(start 163.0426 -89.337642)
		(end 163.0426 -97.4471)
		(width 0.1143)
		(layer "In4.Cu")
		(net "CLK_100M_CPU1_BCLK1_DN")
	)
	(segment
		(start 161.621216 -89.337642)
		(end 161.906458 -89.0524)
		(width 0.1143)
		(layer "In4.Cu")
		(net "CLK_100M_CPU1_BCLK1_DN")
	)
	(segment
		(start 133.356604 -89.489788)
		(end 133.399784 -89.489788)
		(width 0.0889)
		(layer "In4.Cu")
		(net "CLK_100M_CPU1_BCLK1_DN")
	)
	(segment
		(start 156.773626 -103.455978)
		(end 156.773626 -103.052372)
		(width 0.1143)
		(layer "In4.Cu")
		(net "CLK_100M_CPU1_BCLK1_DN")
	)
	(segment
		(start 144.490948 -98.869754)
		(end 144.490948 -99.212654)
		(width 0.1143)
		(layer "In4.Cu")
		(net "CLK_100M_CPU1_BCLK1_DN")
	)
	(segment
		(start 157.11043 -103.792782)
		(end 156.773626 -103.455978)
		(width 0.1143)
		(layer "In4.Cu")
		(net "CLK_100M_CPU1_BCLK1_DN")
	)
	(segment
		(start 139.372848 -89.984834)
		(end 139.40282 -89.984834)
		(width 0.0889)
		(layer "In4.Cu")
		(net "CLK_100M_CPU1_BCLK1_DN")
	)
	(segment
		(start 162.569398 -99.557332)
		(end 162.569398 -99.39528)
		(width 0.1143)
		(layer "In4.Cu")
		(net "CLK_100M_CPU1_BCLK1_DN")
	)
	(segment
		(start 144.325848 -100.736654)
		(end 144.490948 -100.901754)
		(width 0.1143)
		(layer "In4.Cu")
		(net "CLK_100M_CPU1_BCLK1_DN")
	)
	(segment
		(start 144.325848 -89.726262)
		(end 144.325848 -91.16695)
		(width 0.1143)
		(layer "In4.Cu")
		(net "CLK_100M_CPU1_BCLK1_DN")
	)
	(segment
		(start 155.745688 -105.452418)
		(end 156.734764 -104.463342)
		(width 0.1143)
		(layer "In4.Cu")
		(net "CLK_100M_CPU1_BCLK1_DN")
	)
	(segment
		(start 144.490948 -92.34805)
		(end 144.490948 -92.69095)
		(width 0.1143)
		(layer "In4.Cu")
		(net "CLK_100M_CPU1_BCLK1_DN")
	)
	(segment
		(start 157.663388 -104.463342)
		(end 162.569398 -99.557332)
		(width 0.1143)
		(layer "In4.Cu")
		(net "CLK_100M_CPU1_BCLK1_DN")
	)
	(segment
		(start 129.922778 -89.489788)
		(end 129.965958 -89.489788)
		(width 0.0889)
		(layer "In4.Cu")
		(net "CLK_100M_CPU1_BCLK1_DN")
	)
	(segment
		(start 164.864288 -97.484692)
		(end 165.202108 -97.484692)
		(width 0.1143)
		(layer "In4.Cu")
		(net "CLK_100M_CPU1_BCLK1_DN")
	)
	(segment
		(start 155.448 -104.115616)
		(end 155.448 -104.646476)
		(width 0.1143)
		(layer "In4.Cu")
		(net "CLK_100M_CPU1_BCLK1_DN")
	)
	(segment
		(start 157.596332 -103.792782)
		(end 157.11043 -103.792782)
		(width 0.1143)
		(layer "In4.Cu")
		(net "CLK_100M_CPU1_BCLK1_DN")
	)
	(segment
		(start 144.275048 -89.653364)
		(end 144.325848 -89.704164)
		(width 0.0889)
		(layer "In4.Cu")
		(net "CLK_100M_CPU1_BCLK1_DN")
	)
	(segment
		(start 144.325848 -99.720654)
		(end 144.490948 -99.885754)
		(width 0.1143)
		(layer "In4.Cu")
		(net "CLK_100M_CPU1_BCLK1_DN")
	)
	(arc
		(start 138.550904 -89.489788)
		(mid 138.834121 -89.574069)
		(end 139.041124 -89.784936)
		(width 0.0889)
		(layer "In4.Cu")
		(net "CLK_100M_CPU1_BCLK1_DN")
	)
	(arc
		(start 122.564398 -89.784936)
		(mid 122.771402 -89.574072)
		(end 123.054618 -89.489788)
		(width 0.0889)
		(layer "In4.Cu")
		(net "CLK_100M_CPU1_BCLK1_DN")
	)
	(arc
		(start 132.534406 -89.984834)
		(mid 132.726189 -89.927725)
		(end 132.866384 -89.784936)
		(width 0.0889)
		(layer "In4.Cu")
		(net "CLK_100M_CPU1_BCLK1_DN")
	)
	(arc
		(start 133.399784 -89.489788)
		(mid 133.683001 -89.574069)
		(end 133.890004 -89.784936)
		(width 0.0889)
		(layer "In4.Cu")
		(net "CLK_100M_CPU1_BCLK1_DN")
	)
	(arc
		(start 123.949714 -89.984834)
		(mid 124.141356 -89.927668)
		(end 124.281438 -89.784936)
		(width 0.0889)
		(layer "In4.Cu")
		(net "CLK_100M_CPU1_BCLK1_DN")
	)
	(arc
		(start 142.346426 -89.29243)
		(mid 142.552798 -89.074519)
		(end 142.84198 -88.994234)
		(width 0.0889)
		(layer "In4.Cu")
		(net "CLK_100M_CPU1_BCLK1_DN")
	)
	(arc
		(start 132.866384 -89.784936)
		(mid 133.073388 -89.574072)
		(end 133.356604 -89.489788)
		(width 0.0889)
		(layer "In4.Cu")
		(net "CLK_100M_CPU1_BCLK1_DN")
	)
	(arc
		(start 128.248918 -89.489788)
		(mid 128.532135 -89.574069)
		(end 128.739138 -89.784936)
		(width 0.0889)
		(layer "In4.Cu")
		(net "CLK_100M_CPU1_BCLK1_DN")
	)
	(arc
		(start 122.232674 -89.984834)
		(mid 122.424316 -89.927668)
		(end 122.564398 -89.784936)
		(width 0.0889)
		(layer "In4.Cu")
		(net "CLK_100M_CPU1_BCLK1_DN")
	)
	(arc
		(start 127.383794 -89.984834)
		(mid 127.575436 -89.927668)
		(end 127.715518 -89.784936)
		(width 0.0889)
		(layer "In4.Cu")
		(net "CLK_100M_CPU1_BCLK1_DN")
	)
	(arc
		(start 138.017504 -89.784936)
		(mid 138.224508 -89.574072)
		(end 138.507724 -89.489788)
		(width 0.0889)
		(layer "In4.Cu")
		(net "CLK_100M_CPU1_BCLK1_DN")
	)
	(arc
		(start 137.324084 -89.784936)
		(mid 137.464163 -89.927672)
		(end 137.655808 -89.984834)
		(width 0.0889)
		(layer "In4.Cu")
		(net "CLK_100M_CPU1_BCLK1_DN")
	)
	(arc
		(start 134.2517 -89.984834)
		(mid 134.443342 -89.927668)
		(end 134.583424 -89.784936)
		(width 0.0889)
		(layer "In4.Cu")
		(net "CLK_100M_CPU1_BCLK1_DN")
	)
	(arc
		(start 125.998478 -89.784936)
		(mid 126.205482 -89.574072)
		(end 126.488698 -89.489788)
		(width 0.0889)
		(layer "In4.Cu")
		(net "CLK_100M_CPU1_BCLK1_DN")
	)
	(arc
		(start 135.607044 -89.784936)
		(mid 135.747123 -89.927672)
		(end 135.938768 -89.984834)
		(width 0.0889)
		(layer "In4.Cu")
		(net "CLK_100M_CPU1_BCLK1_DN")
	)
	(arc
		(start 131.149598 -89.784936)
		(mid 131.356602 -89.574072)
		(end 131.639818 -89.489788)
		(width 0.0889)
		(layer "In4.Cu")
		(net "CLK_100M_CPU1_BCLK1_DN")
	)
	(arc
		(start 132.17652 -89.790524)
		(mid 132.315217 -89.928807)
		(end 132.50291 -89.984834)
		(width 0.0889)
		(layer "In4.Cu")
		(net "CLK_100M_CPU1_BCLK1_DN")
	)
	(arc
		(start 132.50291 -89.984834)
		(mid 132.518658 -89.985144)
		(end 132.534406 -89.984834)
		(width 0.0889)
		(layer "In4.Cu")
		(net "CLK_100M_CPU1_BCLK1_DN")
	)
	(arc
		(start 136.833864 -89.489788)
		(mid 137.117081 -89.574069)
		(end 137.324084 -89.784936)
		(width 0.0889)
		(layer "In4.Cu")
		(net "CLK_100M_CPU1_BCLK1_DN")
	)
	(arc
		(start 134.583424 -89.784936)
		(mid 134.790428 -89.574072)
		(end 135.073644 -89.489788)
		(width 0.0889)
		(layer "In4.Cu")
		(net "CLK_100M_CPU1_BCLK1_DN")
	)
	(arc
		(start 133.890004 -89.784936)
		(mid 134.030083 -89.927672)
		(end 134.221728 -89.984834)
		(width 0.0889)
		(layer "In4.Cu")
		(net "CLK_100M_CPU1_BCLK1_DN")
	)
	(arc
		(start 124.281438 -89.784936)
		(mid 124.488442 -89.574072)
		(end 124.771658 -89.489788)
		(width 0.0889)
		(layer "In4.Cu")
		(net "CLK_100M_CPU1_BCLK1_DN")
	)
	(arc
		(start 130.456178 -89.784936)
		(mid 130.596257 -89.927672)
		(end 130.787902 -89.984834)
		(width 0.0889)
		(layer "In4.Cu")
		(net "CLK_100M_CPU1_BCLK1_DN")
	)
	(arc
		(start 125.666754 -89.984834)
		(mid 125.858396 -89.927668)
		(end 125.998478 -89.784936)
		(width 0.0889)
		(layer "In4.Cu")
		(net "CLK_100M_CPU1_BCLK1_DN")
	)
	(arc
		(start 130.817874 -89.984834)
		(mid 131.009516 -89.927668)
		(end 131.149598 -89.784936)
		(width 0.0889)
		(layer "In4.Cu")
		(net "CLK_100M_CPU1_BCLK1_DN")
	)
	(arc
		(start 137.68578 -89.984834)
		(mid 137.877422 -89.927668)
		(end 138.017504 -89.784936)
		(width 0.0889)
		(layer "In4.Cu")
		(net "CLK_100M_CPU1_BCLK1_DN")
	)
	(arc
		(start 123.097798 -89.489788)
		(mid 123.381015 -89.574069)
		(end 123.588018 -89.784936)
		(width 0.0889)
		(layer "In4.Cu")
		(net "CLK_100M_CPU1_BCLK1_DN")
	)
	(arc
		(start 120.987566 -87.951564)
		(mid 120.968104 -88.015667)
		(end 120.959626 -88.08212)
		(width 0.0889)
		(layer "In4.Cu")
		(net "CLK_100M_CPU1_BCLK1_DN")
	)
	(arc
		(start 125.305058 -89.784936)
		(mid 125.445137 -89.927672)
		(end 125.636782 -89.984834)
		(width 0.0889)
		(layer "In4.Cu")
		(net "CLK_100M_CPU1_BCLK1_DN")
	)
	(arc
		(start 139.041124 -89.784936)
		(mid 139.181203 -89.927672)
		(end 139.372848 -89.984834)
		(width 0.0889)
		(layer "In4.Cu")
		(net "CLK_100M_CPU1_BCLK1_DN")
	)
	(arc
		(start 121.012712 -88.88984)
		(mid 121.012795 -89.289781)
		(end 121.359168 -89.489788)
		(width 0.0889)
		(layer "In4.Cu")
		(net "CLK_100M_CPU1_BCLK1_DN")
	)
	(arc
		(start 120.959626 -88.08212)
		(mid 120.970695 -88.194369)
		(end 121.012712 -88.299036)
		(width 0.0889)
		(layer "In4.Cu")
		(net "CLK_100M_CPU1_BCLK1_DN")
	)
	(arc
		(start 131.6863 -89.489788)
		(mid 131.9676 -89.574754)
		(end 132.173218 -89.784682)
		(width 0.0889)
		(layer "In4.Cu")
		(net "CLK_100M_CPU1_BCLK1_DN")
	)
	(arc
		(start 135.96874 -89.984834)
		(mid 136.160382 -89.927668)
		(end 136.300464 -89.784936)
		(width 0.0889)
		(layer "In4.Cu")
		(net "CLK_100M_CPU1_BCLK1_DN")
	)
	(arc
		(start 121.380758 -89.489788)
		(mid 121.663975 -89.574069)
		(end 121.870978 -89.784936)
		(width 0.0889)
		(layer "In4.Cu")
		(net "CLK_100M_CPU1_BCLK1_DN")
	)
	(arc
		(start 123.588018 -89.784936)
		(mid 123.728097 -89.927672)
		(end 123.919742 -89.984834)
		(width 0.0889)
		(layer "In4.Cu")
		(net "CLK_100M_CPU1_BCLK1_DN")
	)
	(arc
		(start 140.593064 -89.289636)
		(mid 140.801672 -89.077704)
		(end 141.087094 -88.994234)
		(width 0.0889)
		(layer "In4.Cu")
		(net "CLK_100M_CPU1_BCLK1_DN")
	)
	(arc
		(start 129.100834 -89.984834)
		(mid 129.292476 -89.927668)
		(end 129.432558 -89.784936)
		(width 0.0889)
		(layer "In4.Cu")
		(net "CLK_100M_CPU1_BCLK1_DN")
	)
	(arc
		(start 135.116824 -89.489788)
		(mid 135.400041 -89.574069)
		(end 135.607044 -89.784936)
		(width 0.0889)
		(layer "In4.Cu")
		(net "CLK_100M_CPU1_BCLK1_DN")
	)
	(arc
		(start 126.531878 -89.489788)
		(mid 126.815095 -89.574069)
		(end 127.022098 -89.784936)
		(width 0.0889)
		(layer "In4.Cu")
		(net "CLK_100M_CPU1_BCLK1_DN")
	)
	(arc
		(start 139.734544 -89.784936)
		(mid 139.941548 -89.574072)
		(end 140.224764 -89.489788)
		(width 0.0889)
		(layer "In4.Cu")
		(net "CLK_100M_CPU1_BCLK1_DN")
	)
	(arc
		(start 141.616684 -89.289636)
		(mid 141.758367 -89.43344)
		(end 141.952218 -89.489788)
		(width 0.0889)
		(layer "In4.Cu")
		(net "CLK_100M_CPU1_BCLK1_DN")
	)
	(arc
		(start 128.739138 -89.784936)
		(mid 128.879217 -89.927672)
		(end 129.070862 -89.984834)
		(width 0.0889)
		(layer "In4.Cu")
		(net "CLK_100M_CPU1_BCLK1_DN")
	)
	(arc
		(start 129.432558 -89.784936)
		(mid 129.639562 -89.574072)
		(end 129.922778 -89.489788)
		(width 0.0889)
		(layer "In4.Cu")
		(net "CLK_100M_CPU1_BCLK1_DN")
	)
	(arc
		(start 121.870978 -89.784936)
		(mid 122.011057 -89.927672)
		(end 122.202702 -89.984834)
		(width 0.0889)
		(layer "In4.Cu")
		(net "CLK_100M_CPU1_BCLK1_DN")
	)
	(arc
		(start 127.715518 -89.784936)
		(mid 127.922522 -89.574072)
		(end 128.205738 -89.489788)
		(width 0.0889)
		(layer "In4.Cu")
		(net "CLK_100M_CPU1_BCLK1_DN")
	)
	(arc
		(start 140.25753 -89.489788)
		(mid 140.45138 -89.433438)
		(end 140.593064 -89.289636)
		(width 0.0889)
		(layer "In4.Cu")
		(net "CLK_100M_CPU1_BCLK1_DN")
	)
	(arc
		(start 139.40282 -89.984834)
		(mid 139.594462 -89.927668)
		(end 139.734544 -89.784936)
		(width 0.0889)
		(layer "In4.Cu")
		(net "CLK_100M_CPU1_BCLK1_DN")
	)
	(arc
		(start 142.129764 -89.489788)
		(mid 142.255251 -89.409955)
		(end 142.346426 -89.29243)
		(width 0.0889)
		(layer "In4.Cu")
		(net "CLK_100M_CPU1_BCLK1_DN")
	)
	(arc
		(start 141.122654 -88.994234)
		(mid 141.408078 -89.077701)
		(end 141.616684 -89.289636)
		(width 0.0889)
		(layer "In4.Cu")
		(net "CLK_100M_CPU1_BCLK1_DN")
	)
	(arc
		(start 127.022098 -89.784936)
		(mid 127.162177 -89.927672)
		(end 127.353822 -89.984834)
		(width 0.0889)
		(layer "In4.Cu")
		(net "CLK_100M_CPU1_BCLK1_DN")
	)
	(arc
		(start 136.300464 -89.784936)
		(mid 136.507468 -89.574072)
		(end 136.790684 -89.489788)
		(width 0.0889)
		(layer "In4.Cu")
		(net "CLK_100M_CPU1_BCLK1_DN")
	)
	(arc
		(start 129.965958 -89.489788)
		(mid 130.249175 -89.574069)
		(end 130.456178 -89.784936)
		(width 0.0889)
		(layer "In4.Cu")
		(net "CLK_100M_CPU1_BCLK1_DN")
	)
	(arc
		(start 124.814838 -89.489788)
		(mid 125.098055 -89.574069)
		(end 125.305058 -89.784936)
		(width 0.0889)
		(layer "In4.Cu")
		(net "CLK_100M_CPU1_BCLK1_DN")
	)
	(arc
		(start 121.021602 -88.314276)
		(mid 121.091999 -88.603227)
		(end 121.012712 -88.88984)
		(width 0.0889)
		(layer "In4.Cu")
		(net "CLK_100M_CPU1_BCLK1_DN")
	)
	(segment
		(start 168.17848 -88.0618)
		(end 168.48328 -87.757)
		(width 0.1143)
		(layer "F.Cu")
		(net "CLK_100M_CPU1_BCLK0_DP")
	)
	(segment
		(start 168.446704 -89.206324)
		(end 168.17848 -88.9381)
		(width 0.1143)
		(layer "F.Cu")
		(net "CLK_100M_CPU1_BCLK0_DP")
	)
	(segment
		(start 168.48328 -87.757)
		(end 168.656 -87.757)
		(width 0.1143)
		(layer "F.Cu")
		(net "CLK_100M_CPU1_BCLK0_DP")
	)
	(segment
		(start 168.705276 -89.206324)
		(end 168.446704 -89.206324)
		(width 0.1143)
		(layer "F.Cu")
		(net "CLK_100M_CPU1_BCLK0_DP")
	)
	(segment
		(start 123.076208 -70.268084)
		(end 122.504708 -70.268084)
		(width 0.1143)
		(layer "F.Cu")
		(net "CLK_100M_CPU1_BCLK0_DP")
	)
	(segment
		(start 168.17848 -88.9381)
		(end 168.17848 -88.0618)
		(width 0.1143)
		(layer "F.Cu")
		(net "CLK_100M_CPU1_BCLK0_DP")
	)
	(via
		(at 123.076208 -70.268084)
		(size 0.508)
		(drill 0.254)
		(layers "F.Cu" "B.Cu")
		(net "CLK_100M_CPU1_BCLK0_DP")
	)
	(via
		(at 168.705276 -89.206324)
		(size 0.508)
		(drill 0.254)
		(layers "F.Cu" "B.Cu")
		(net "CLK_100M_CPU1_BCLK0_DP")
	)
	(segment
		(start 168.389554 -87.757)
		(end 168.160192 -87.986362)
		(width 0.1143)
		(layer "B.Cu")
		(net "CLK_100M_CPU1_BCLK0_DP")
	)
	(segment
		(start 168.160192 -87.986362)
		(end 168.160192 -88.942926)
		(width 0.1143)
		(layer "B.Cu")
		(net "CLK_100M_CPU1_BCLK0_DP")
	)
	(segment
		(start 168.160192 -88.942926)
		(end 168.42359 -89.206324)
		(width 0.1143)
		(layer "B.Cu")
		(net "CLK_100M_CPU1_BCLK0_DP")
	)
	(segment
		(start 168.42359 -89.206324)
		(end 168.705276 -89.206324)
		(width 0.1143)
		(layer "B.Cu")
		(net "CLK_100M_CPU1_BCLK0_DP")
	)
	(segment
		(start 168.656 -87.757)
		(end 168.389554 -87.757)
		(width 0.1143)
		(layer "B.Cu")
		(net "CLK_100M_CPU1_BCLK0_DP")
	)
	(segment
		(start 125.673358 -71.353934)
		(end 125.630178 -71.353934)
		(width 0.0889)
		(layer "In4.Cu")
		(net "CLK_100M_CPU1_BCLK0_DP")
	)
	(segment
		(start 147.753324 -70.362826)
		(end 147.645882 -70.470268)
		(width 0.1143)
		(layer "In4.Cu")
		(net "CLK_100M_CPU1_BCLK0_DP")
	)
	(segment
		(start 151.31034 -70.357746)
		(end 151.01824 -70.357746)
		(width 0.1143)
		(layer "In4.Cu")
		(net "CLK_100M_CPU1_BCLK0_DP")
	)
	(segment
		(start 147.645882 -76.388214)
		(end 147.36064 -76.673456)
		(width 0.1143)
		(layer "In4.Cu")
		(net "CLK_100M_CPU1_BCLK0_DP")
	)
	(segment
		(start 154.148282 -70.922134)
		(end 154.148282 -76.388214)
		(width 0.1143)
		(layer "In4.Cu")
		(net "CLK_100M_CPU1_BCLK0_DP")
	)
	(segment
		(start 154.26944 -70.800976)
		(end 154.148282 -70.922134)
		(width 0.1143)
		(layer "In4.Cu")
		(net "CLK_100M_CPU1_BCLK0_DP")
	)
	(segment
		(start 146.436842 -70.40499)
		(end 146.131534 -70.40499)
		(width 0.1143)
		(layer "In4.Cu")
		(net "CLK_100M_CPU1_BCLK0_DP")
	)
	(segment
		(start 151.01824 -70.357746)
		(end 150.897082 -70.478904)
		(width 0.1143)
		(layer "In4.Cu")
		(net "CLK_100M_CPU1_BCLK0_DP")
	)
	(segment
		(start 153.86304 -76.673456)
		(end 153.328624 -76.673456)
		(width 0.1143)
		(layer "In4.Cu")
		(net "CLK_100M_CPU1_BCLK0_DP")
	)
	(segment
		(start 149.792182 -70.489826)
		(end 149.660102 -70.357746)
		(width 0.1143)
		(layer "In4.Cu")
		(net "CLK_100M_CPU1_BCLK0_DP")
	)
	(segment
		(start 156.294582 -76.388214)
		(end 156.294582 -74.000614)
		(width 0.1143)
		(layer "In4.Cu")
		(net "CLK_100M_CPU1_BCLK0_DP")
	)
	(segment
		(start 126.525274 -70.858888)
		(end 126.495302 -70.858888)
		(width 0.0889)
		(layer "In4.Cu")
		(net "CLK_100M_CPU1_BCLK0_DP")
	)
	(segment
		(start 166.5859 -88.157812)
		(end 166.324788 -87.8967)
		(width 0.1143)
		(layer "In4.Cu")
		(net "CLK_100M_CPU1_BCLK0_DP")
	)
	(segment
		(start 132.541264 -71.353934)
		(end 132.494782 -71.353934)
		(width 0.0889)
		(layer "In4.Cu")
		(net "CLK_100M_CPU1_BCLK0_DP")
	)
	(segment
		(start 146.020282 -76.388214)
		(end 145.73504 -76.673456)
		(width 0.1143)
		(layer "In4.Cu")
		(net "CLK_100M_CPU1_BCLK0_DP")
	)
	(segment
		(start 158.399226 -78.44282)
		(end 158.093664 -78.137258)
		(width 0.1143)
		(layer "In4.Cu")
		(net "CLK_100M_CPU1_BCLK0_DP")
	)
	(segment
		(start 154.527758 -70.800976)
		(end 154.26944 -70.800976)
		(width 0.1143)
		(layer "In4.Cu")
		(net "CLK_100M_CPU1_BCLK0_DP")
	)
	(segment
		(start 153.043382 -70.475602)
		(end 152.925526 -70.357746)
		(width 0.1143)
		(layer "In4.Cu")
		(net "CLK_100M_CPU1_BCLK0_DP")
	)
	(segment
		(start 137.68197 -70.363334)
		(end 137.659618 -70.363334)
		(width 0.0889)
		(layer "In4.Cu")
		(net "CLK_100M_CPU1_BCLK0_DP")
	)
	(segment
		(start 150.897082 -76.388214)
		(end 150.61184 -76.673456)
		(width 0.1143)
		(layer "In4.Cu")
		(net "CLK_100M_CPU1_BCLK0_DP")
	)
	(segment
		(start 154.148282 -76.388214)
		(end 153.86304 -76.673456)
		(width 0.1143)
		(layer "In4.Cu")
		(net "CLK_100M_CPU1_BCLK0_DP")
	)
	(segment
		(start 139.409424 -71.353934)
		(end 139.366244 -71.353934)
		(width 0.0889)
		(layer "In4.Cu")
		(net "CLK_100M_CPU1_BCLK0_DP")
	)
	(segment
		(start 153.328624 -76.673456)
		(end 153.043382 -76.388214)
		(width 0.1143)
		(layer "In4.Cu")
		(net "CLK_100M_CPU1_BCLK0_DP")
	)
	(segment
		(start 142.58544 -71.849488)
		(end 141.836902 -71.849488)
		(width 0.0889)
		(layer "In4.Cu")
		(net "CLK_100M_CPU1_BCLK0_DP")
	)
	(segment
		(start 162.86988 -86.822026)
		(end 162.86988 -75.983338)
		(width 0.1143)
		(layer "In4.Cu")
		(net "CLK_100M_CPU1_BCLK0_DP")
	)
	(segment
		(start 149.271482 -70.462648)
		(end 149.271482 -76.388214)
		(width 0.1143)
		(layer "In4.Cu")
		(net "CLK_100M_CPU1_BCLK0_DP")
	)
	(segment
		(start 140.26134 -70.858888)
		(end 140.231368 -70.858888)
		(width 0.0889)
		(layer "In4.Cu")
		(net "CLK_100M_CPU1_BCLK0_DP")
	)
	(segment
		(start 135.108188 -70.858888)
		(end 135.080248 -70.858888)
		(width 0.0889)
		(layer "In4.Cu")
		(net "CLK_100M_CPU1_BCLK0_DP")
	)
	(segment
		(start 149.376384 -70.357746)
		(end 149.271482 -70.462648)
		(width 0.1143)
		(layer "In4.Cu")
		(net "CLK_100M_CPU1_BCLK0_DP")
	)
	(segment
		(start 124.808234 -70.858888)
		(end 124.775468 -70.858888)
		(width 0.0889)
		(layer "In4.Cu")
		(net "CLK_100M_CPU1_BCLK0_DP")
	)
	(segment
		(start 148.166582 -70.50786)
		(end 148.021548 -70.362826)
		(width 0.1143)
		(layer "In4.Cu")
		(net "CLK_100M_CPU1_BCLK0_DP")
	)
	(segment
		(start 159.312864 -75.5777)
		(end 159.198564 -75.692)
		(width 0.1143)
		(layer "In4.Cu")
		(net "CLK_100M_CPU1_BCLK0_DP")
	)
	(segment
		(start 155.773882 -74.03465)
		(end 155.773882 -76.388214)
		(width 0.1143)
		(layer "In4.Cu")
		(net "CLK_100M_CPU1_BCLK0_DP")
	)
	(segment
		(start 152.522682 -76.388214)
		(end 152.23744 -76.673456)
		(width 0.1143)
		(layer "In4.Cu")
		(net "CLK_100M_CPU1_BCLK0_DP")
	)
	(segment
		(start 168.241726 -89.320624)
		(end 168.241726 -89.844118)
		(width 0.1143)
		(layer "In4.Cu")
		(net "CLK_100M_CPU1_BCLK0_DP")
	)
	(segment
		(start 130.824478 -71.353934)
		(end 130.781298 -71.353934)
		(width 0.0889)
		(layer "In4.Cu")
		(net "CLK_100M_CPU1_BCLK0_DP")
	)
	(segment
		(start 152.23744 -76.673456)
		(end 151.703024 -76.673456)
		(width 0.1143)
		(layer "In4.Cu")
		(net "CLK_100M_CPU1_BCLK0_DP")
	)
	(segment
		(start 149.660102 -70.357746)
		(end 149.376384 -70.357746)
		(width 0.1143)
		(layer "In4.Cu")
		(net "CLK_100M_CPU1_BCLK0_DP")
	)
	(segment
		(start 156.180282 -73.886314)
		(end 155.922218 -73.886314)
		(width 0.1143)
		(layer "In4.Cu")
		(net "CLK_100M_CPU1_BCLK0_DP")
	)
	(segment
		(start 166.5859 -88.926416)
		(end 166.5859 -88.157812)
		(width 0.1143)
		(layer "In4.Cu")
		(net "CLK_100M_CPU1_BCLK0_DP")
	)
	(segment
		(start 157.729682 -76.673456)
		(end 156.579824 -76.673456)
		(width 0.1143)
		(layer "In4.Cu")
		(net "CLK_100M_CPU1_BCLK0_DP")
	)
	(segment
		(start 155.922218 -73.886314)
		(end 155.773882 -74.03465)
		(width 0.1143)
		(layer "In4.Cu")
		(net "CLK_100M_CPU1_BCLK0_DP")
	)
	(segment
		(start 166.7383 -89.750646)
		(end 166.7383 -89.078816)
		(width 0.1143)
		(layer "In4.Cu")
		(net "CLK_100M_CPU1_BCLK0_DP")
	)
	(segment
		(start 133.39318 -70.858888)
		(end 133.363208 -70.858888)
		(width 0.0889)
		(layer "In4.Cu")
		(net "CLK_100M_CPU1_BCLK0_DP")
	)
	(segment
		(start 150.61184 -76.673456)
		(end 150.077424 -76.673456)
		(width 0.1143)
		(layer "In4.Cu")
		(net "CLK_100M_CPU1_BCLK0_DP")
	)
	(segment
		(start 138.5443 -70.858888)
		(end 138.51636 -70.858888)
		(width 0.0889)
		(layer "In4.Cu")
		(net "CLK_100M_CPU1_BCLK0_DP")
	)
	(segment
		(start 153.043382 -76.388214)
		(end 153.043382 -70.475602)
		(width 0.1143)
		(layer "In4.Cu")
		(net "CLK_100M_CPU1_BCLK0_DP")
	)
	(segment
		(start 134.258304 -71.353934)
		(end 134.215124 -71.353934)
		(width 0.0889)
		(layer "In4.Cu")
		(net "CLK_100M_CPU1_BCLK0_DP")
	)
	(segment
		(start 148.98624 -76.673456)
		(end 148.451824 -76.673456)
		(width 0.1143)
		(layer "In4.Cu")
		(net "CLK_100M_CPU1_BCLK0_DP")
	)
	(segment
		(start 166.324788 -87.8967)
		(end 163.944554 -87.8967)
		(width 0.1143)
		(layer "In4.Cu")
		(net "CLK_100M_CPU1_BCLK0_DP")
	)
	(segment
		(start 148.166582 -76.388214)
		(end 148.166582 -70.50786)
		(width 0.1143)
		(layer "In4.Cu")
		(net "CLK_100M_CPU1_BCLK0_DP")
	)
	(segment
		(start 168.705276 -89.206324)
		(end 168.356026 -89.206324)
		(width 0.1143)
		(layer "In4.Cu")
		(net "CLK_100M_CPU1_BCLK0_DP")
	)
	(segment
		(start 132.007864 -71.05904)
		(end 132.004562 -71.053198)
		(width 0.0889)
		(layer "In4.Cu")
		(net "CLK_100M_CPU1_BCLK0_DP")
	)
	(segment
		(start 151.703024 -76.673456)
		(end 151.417782 -76.388214)
		(width 0.1143)
		(layer "In4.Cu")
		(net "CLK_100M_CPU1_BCLK0_DP")
	)
	(segment
		(start 151.417782 -70.465188)
		(end 151.31034 -70.357746)
		(width 0.1143)
		(layer "In4.Cu")
		(net "CLK_100M_CPU1_BCLK0_DP")
	)
	(segment
		(start 123.945904 -70.363334)
		(end 123.913138 -70.363334)
		(width 0.0889)
		(layer "In4.Cu")
		(net "CLK_100M_CPU1_BCLK0_DP")
	)
	(segment
		(start 154.954224 -76.673456)
		(end 154.668982 -76.388214)
		(width 0.1143)
		(layer "In4.Cu")
		(net "CLK_100M_CPU1_BCLK0_DP")
	)
	(segment
		(start 127.390398 -71.353934)
		(end 127.347218 -71.353934)
		(width 0.0889)
		(layer "In4.Cu")
		(net "CLK_100M_CPU1_BCLK0_DP")
	)
	(segment
		(start 150.077424 -76.673456)
		(end 149.792182 -76.388214)
		(width 0.1143)
		(layer "In4.Cu")
		(net "CLK_100M_CPU1_BCLK0_DP")
	)
	(segment
		(start 146.540982 -70.50913)
		(end 146.436842 -70.40499)
		(width 0.1143)
		(layer "In4.Cu")
		(net "CLK_100M_CPU1_BCLK0_DP")
	)
	(segment
		(start 148.451824 -76.673456)
		(end 148.166582 -76.388214)
		(width 0.1143)
		(layer "In4.Cu")
		(net "CLK_100M_CPU1_BCLK0_DP")
	)
	(segment
		(start 146.131534 -70.40499)
		(end 146.020282 -70.516242)
		(width 0.1143)
		(layer "In4.Cu")
		(net "CLK_100M_CPU1_BCLK0_DP")
	)
	(segment
		(start 129.959354 -70.858888)
		(end 129.929382 -70.858888)
		(width 0.0889)
		(layer "In4.Cu")
		(net "CLK_100M_CPU1_BCLK0_DP")
	)
	(segment
		(start 162.86988 -75.983338)
		(end 162.464242 -75.5777)
		(width 0.1143)
		(layer "In4.Cu")
		(net "CLK_100M_CPU1_BCLK0_DP")
	)
	(segment
		(start 147.36064 -76.673456)
		(end 146.826224 -76.673456)
		(width 0.1143)
		(layer "In4.Cu")
		(net "CLK_100M_CPU1_BCLK0_DP")
	)
	(segment
		(start 158.093664 -77.037438)
		(end 157.729682 -76.673456)
		(width 0.1143)
		(layer "In4.Cu")
		(net "CLK_100M_CPU1_BCLK0_DP")
	)
	(segment
		(start 128.242314 -70.858888)
		(end 128.212342 -70.858888)
		(width 0.0889)
		(layer "In4.Cu")
		(net "CLK_100M_CPU1_BCLK0_DP")
	)
	(segment
		(start 167.91686 -90.168984)
		(end 167.156638 -90.168984)
		(width 0.1143)
		(layer "In4.Cu")
		(net "CLK_100M_CPU1_BCLK0_DP")
	)
	(segment
		(start 167.156638 -90.168984)
		(end 166.7383 -89.750646)
		(width 0.1143)
		(layer "In4.Cu")
		(net "CLK_100M_CPU1_BCLK0_DP")
	)
	(segment
		(start 149.792182 -76.388214)
		(end 149.792182 -70.489826)
		(width 0.1143)
		(layer "In4.Cu")
		(net "CLK_100M_CPU1_BCLK0_DP")
	)
	(segment
		(start 143.528288 -71.900288)
		(end 142.658338 -71.900288)
		(width 0.1143)
		(layer "In4.Cu")
		(net "CLK_100M_CPU1_BCLK0_DP")
	)
	(segment
		(start 136.825228 -70.858888)
		(end 136.79932 -70.858888)
		(width 0.0889)
		(layer "In4.Cu")
		(net "CLK_100M_CPU1_BCLK0_DP")
	)
	(segment
		(start 154.668982 -70.9422)
		(end 154.527758 -70.800976)
		(width 0.1143)
		(layer "In4.Cu")
		(net "CLK_100M_CPU1_BCLK0_DP")
	)
	(segment
		(start 159.198564 -75.692)
		(end 159.198564 -78.157578)
		(width 0.1143)
		(layer "In4.Cu")
		(net "CLK_100M_CPU1_BCLK0_DP")
	)
	(segment
		(start 155.773882 -76.388214)
		(end 155.48864 -76.673456)
		(width 0.1143)
		(layer "In4.Cu")
		(net "CLK_100M_CPU1_BCLK0_DP")
	)
	(segment
		(start 146.540982 -76.388214)
		(end 146.540982 -70.50913)
		(width 0.1143)
		(layer "In4.Cu")
		(net "CLK_100M_CPU1_BCLK0_DP")
	)
	(segment
		(start 143.724376 -72.096376)
		(end 143.528288 -71.900288)
		(width 0.1143)
		(layer "In4.Cu")
		(net "CLK_100M_CPU1_BCLK0_DP")
	)
	(segment
		(start 123.076208 -69.93001)
		(end 123.076208 -70.268084)
		(width 0.0889)
		(layer "In4.Cu")
		(net "CLK_100M_CPU1_BCLK0_DP")
	)
	(segment
		(start 135.96493 -70.363334)
		(end 135.942578 -70.363334)
		(width 0.0889)
		(layer "In4.Cu")
		(net "CLK_100M_CPU1_BCLK0_DP")
	)
	(segment
		(start 149.271482 -76.388214)
		(end 148.98624 -76.673456)
		(width 0.1143)
		(layer "In4.Cu")
		(net "CLK_100M_CPU1_BCLK0_DP")
	)
	(segment
		(start 147.645882 -70.470268)
		(end 147.645882 -76.388214)
		(width 0.1143)
		(layer "In4.Cu")
		(net "CLK_100M_CPU1_BCLK0_DP")
	)
	(segment
		(start 152.925526 -70.357746)
		(end 152.62733 -70.357746)
		(width 0.1143)
		(layer "In4.Cu")
		(net "CLK_100M_CPU1_BCLK0_DP")
	)
	(segment
		(start 144.01546 -76.673456)
		(end 143.724376 -76.382372)
		(width 0.1143)
		(layer "In4.Cu")
		(net "CLK_100M_CPU1_BCLK0_DP")
	)
	(segment
		(start 123.13412 -69.872098)
		(end 123.076208 -69.93001)
		(width 0.0889)
		(layer "In4.Cu")
		(net "CLK_100M_CPU1_BCLK0_DP")
	)
	(segment
		(start 151.417782 -76.388214)
		(end 151.417782 -70.465188)
		(width 0.1143)
		(layer "In4.Cu")
		(net "CLK_100M_CPU1_BCLK0_DP")
	)
	(segment
		(start 168.241726 -89.844118)
		(end 167.91686 -90.168984)
		(width 0.1143)
		(layer "In4.Cu")
		(net "CLK_100M_CPU1_BCLK0_DP")
	)
	(segment
		(start 142.658338 -71.900288)
		(end 142.63624 -71.900288)
		(width 0.0889)
		(layer "In4.Cu")
		(net "CLK_100M_CPU1_BCLK0_DP")
	)
	(segment
		(start 156.579824 -76.673456)
		(end 156.294582 -76.388214)
		(width 0.1143)
		(layer "In4.Cu")
		(net "CLK_100M_CPU1_BCLK0_DP")
	)
	(segment
		(start 156.294582 -74.000614)
		(end 156.180282 -73.886314)
		(width 0.1143)
		(layer "In4.Cu")
		(net "CLK_100M_CPU1_BCLK0_DP")
	)
	(segment
		(start 159.198564 -78.157578)
		(end 158.913322 -78.44282)
		(width 0.1143)
		(layer "In4.Cu")
		(net "CLK_100M_CPU1_BCLK0_DP")
	)
	(segment
		(start 152.62733 -70.357746)
		(end 152.522682 -70.462394)
		(width 0.1143)
		(layer "In4.Cu")
		(net "CLK_100M_CPU1_BCLK0_DP")
	)
	(segment
		(start 129.107438 -71.353934)
		(end 129.064258 -71.353934)
		(width 0.0889)
		(layer "In4.Cu")
		(net "CLK_100M_CPU1_BCLK0_DP")
	)
	(segment
		(start 163.944554 -87.8967)
		(end 162.86988 -86.822026)
		(width 0.1143)
		(layer "In4.Cu")
		(net "CLK_100M_CPU1_BCLK0_DP")
	)
	(segment
		(start 146.826224 -76.673456)
		(end 146.540982 -76.388214)
		(width 0.1143)
		(layer "In4.Cu")
		(net "CLK_100M_CPU1_BCLK0_DP")
	)
	(segment
		(start 146.020282 -70.516242)
		(end 146.020282 -76.388214)
		(width 0.1143)
		(layer "In4.Cu")
		(net "CLK_100M_CPU1_BCLK0_DP")
	)
	(segment
		(start 148.021548 -70.362826)
		(end 147.753324 -70.362826)
		(width 0.1143)
		(layer "In4.Cu")
		(net "CLK_100M_CPU1_BCLK0_DP")
	)
	(segment
		(start 168.356026 -89.206324)
		(end 168.241726 -89.320624)
		(width 0.1143)
		(layer "In4.Cu")
		(net "CLK_100M_CPU1_BCLK0_DP")
	)
	(segment
		(start 166.7383 -89.078816)
		(end 166.5859 -88.926416)
		(width 0.1143)
		(layer "In4.Cu")
		(net "CLK_100M_CPU1_BCLK0_DP")
	)
	(segment
		(start 142.63624 -71.900288)
		(end 142.58544 -71.849488)
		(width 0.0889)
		(layer "In4.Cu")
		(net "CLK_100M_CPU1_BCLK0_DP")
	)
	(segment
		(start 155.48864 -76.673456)
		(end 154.954224 -76.673456)
		(width 0.1143)
		(layer "In4.Cu")
		(net "CLK_100M_CPU1_BCLK0_DP")
	)
	(segment
		(start 162.464242 -75.5777)
		(end 159.312864 -75.5777)
		(width 0.1143)
		(layer "In4.Cu")
		(net "CLK_100M_CPU1_BCLK0_DP")
	)
	(segment
		(start 143.724376 -76.382372)
		(end 143.724376 -72.096376)
		(width 0.1143)
		(layer "In4.Cu")
		(net "CLK_100M_CPU1_BCLK0_DP")
	)
	(segment
		(start 158.093664 -78.137258)
		(end 158.093664 -77.037438)
		(width 0.1143)
		(layer "In4.Cu")
		(net "CLK_100M_CPU1_BCLK0_DP")
	)
	(segment
		(start 152.522682 -70.462394)
		(end 152.522682 -76.388214)
		(width 0.1143)
		(layer "In4.Cu")
		(net "CLK_100M_CPU1_BCLK0_DP")
	)
	(segment
		(start 141.271244 -71.353934)
		(end 141.083284 -71.353934)
		(width 0.0889)
		(layer "In4.Cu")
		(net "CLK_100M_CPU1_BCLK0_DP")
	)
	(segment
		(start 150.897082 -70.478904)
		(end 150.897082 -76.388214)
		(width 0.1143)
		(layer "In4.Cu")
		(net "CLK_100M_CPU1_BCLK0_DP")
	)
	(segment
		(start 145.73504 -76.673456)
		(end 144.01546 -76.673456)
		(width 0.1143)
		(layer "In4.Cu")
		(net "CLK_100M_CPU1_BCLK0_DP")
	)
	(segment
		(start 158.913322 -78.44282)
		(end 158.399226 -78.44282)
		(width 0.1143)
		(layer "In4.Cu")
		(net "CLK_100M_CPU1_BCLK0_DP")
	)
	(segment
		(start 154.668982 -76.388214)
		(end 154.668982 -70.9422)
		(width 0.1143)
		(layer "In4.Cu")
		(net "CLK_100M_CPU1_BCLK0_DP")
	)
	(arc
		(start 141.487906 -71.551292)
		(mid 141.396792 -71.4337)
		(end 141.271244 -71.353934)
		(width 0.0889)
		(layer "In4.Cu")
		(net "CLK_100M_CPU1_BCLK0_DP")
	)
	(arc
		(start 128.212342 -70.858888)
		(mid 128.0207 -70.916054)
		(end 127.880618 -71.058786)
		(width 0.0889)
		(layer "In4.Cu")
		(net "CLK_100M_CPU1_BCLK0_DP")
	)
	(arc
		(start 128.574038 -71.058786)
		(mid 128.433959 -70.91605)
		(end 128.242314 -70.858888)
		(width 0.0889)
		(layer "In4.Cu")
		(net "CLK_100M_CPU1_BCLK0_DP")
	)
	(arc
		(start 139.366244 -71.353934)
		(mid 139.083027 -71.269653)
		(end 138.876024 -71.058786)
		(width 0.0889)
		(layer "In4.Cu")
		(net "CLK_100M_CPU1_BCLK0_DP")
	)
	(arc
		(start 133.031484 -71.058786)
		(mid 132.82448 -71.26965)
		(end 132.541264 -71.353934)
		(width 0.0889)
		(layer "In4.Cu")
		(net "CLK_100M_CPU1_BCLK0_DP")
	)
	(arc
		(start 125.139958 -71.058786)
		(mid 124.999879 -70.91605)
		(end 124.808234 -70.858888)
		(width 0.0889)
		(layer "In4.Cu")
		(net "CLK_100M_CPU1_BCLK0_DP")
	)
	(arc
		(start 131.652518 -70.858888)
		(mid 131.457401 -70.914555)
		(end 131.314698 -71.058786)
		(width 0.0889)
		(layer "In4.Cu")
		(net "CLK_100M_CPU1_BCLK0_DP")
	)
	(arc
		(start 137.659618 -70.363334)
		(mid 137.465768 -70.419684)
		(end 137.324084 -70.563486)
		(width 0.0889)
		(layer "In4.Cu")
		(net "CLK_100M_CPU1_BCLK0_DP")
	)
	(arc
		(start 127.880618 -71.058786)
		(mid 127.673614 -71.26965)
		(end 127.390398 -71.353934)
		(width 0.0889)
		(layer "In4.Cu")
		(net "CLK_100M_CPU1_BCLK0_DP")
	)
	(arc
		(start 124.775468 -70.858888)
		(mid 124.490044 -70.775421)
		(end 124.281438 -70.563486)
		(width 0.0889)
		(layer "In4.Cu")
		(net "CLK_100M_CPU1_BCLK0_DP")
	)
	(arc
		(start 138.876024 -71.058786)
		(mid 138.735945 -70.91605)
		(end 138.5443 -70.858888)
		(width 0.0889)
		(layer "In4.Cu")
		(net "CLK_100M_CPU1_BCLK0_DP")
	)
	(arc
		(start 126.856998 -71.058786)
		(mid 126.716919 -70.91605)
		(end 126.525274 -70.858888)
		(width 0.0889)
		(layer "In4.Cu")
		(net "CLK_100M_CPU1_BCLK0_DP")
	)
	(arc
		(start 141.836902 -71.849488)
		(mid 141.634004 -71.733628)
		(end 141.487906 -71.551292)
		(width 0.0889)
		(layer "In4.Cu")
		(net "CLK_100M_CPU1_BCLK0_DP")
	)
	(arc
		(start 133.363208 -70.858888)
		(mid 133.171566 -70.916054)
		(end 133.031484 -71.058786)
		(width 0.0889)
		(layer "In4.Cu")
		(net "CLK_100M_CPU1_BCLK0_DP")
	)
	(arc
		(start 140.593064 -71.058786)
		(mid 140.452985 -70.91605)
		(end 140.26134 -70.858888)
		(width 0.0889)
		(layer "In4.Cu")
		(net "CLK_100M_CPU1_BCLK0_DP")
	)
	(arc
		(start 139.899644 -71.058786)
		(mid 139.69264 -71.26965)
		(end 139.409424 -71.353934)
		(width 0.0889)
		(layer "In4.Cu")
		(net "CLK_100M_CPU1_BCLK0_DP")
	)
	(arc
		(start 129.929382 -70.858888)
		(mid 129.73774 -70.916054)
		(end 129.597658 -71.058786)
		(width 0.0889)
		(layer "In4.Cu")
		(net "CLK_100M_CPU1_BCLK0_DP")
	)
	(arc
		(start 123.422918 -70.068186)
		(mid 123.301027 -69.93699)
		(end 123.13412 -69.872098)
		(width 0.0889)
		(layer "In4.Cu")
		(net "CLK_100M_CPU1_BCLK0_DP")
	)
	(arc
		(start 123.913138 -70.363334)
		(mid 123.629921 -70.279053)
		(end 123.422918 -70.068186)
		(width 0.0889)
		(layer "In4.Cu")
		(net "CLK_100M_CPU1_BCLK0_DP")
	)
	(arc
		(start 129.064258 -71.353934)
		(mid 128.781041 -71.269653)
		(end 128.574038 -71.058786)
		(width 0.0889)
		(layer "In4.Cu")
		(net "CLK_100M_CPU1_BCLK0_DP")
	)
	(arc
		(start 136.300464 -70.563486)
		(mid 136.158781 -70.419682)
		(end 135.96493 -70.363334)
		(width 0.0889)
		(layer "In4.Cu")
		(net "CLK_100M_CPU1_BCLK0_DP")
	)
	(arc
		(start 130.291078 -71.058786)
		(mid 130.150999 -70.91605)
		(end 129.959354 -70.858888)
		(width 0.0889)
		(layer "In4.Cu")
		(net "CLK_100M_CPU1_BCLK0_DP")
	)
	(arc
		(start 134.748524 -71.058786)
		(mid 134.54152 -71.26965)
		(end 134.258304 -71.353934)
		(width 0.0889)
		(layer "In4.Cu")
		(net "CLK_100M_CPU1_BCLK0_DP")
	)
	(arc
		(start 136.79932 -70.858888)
		(mid 136.511175 -70.776569)
		(end 136.300464 -70.563486)
		(width 0.0889)
		(layer "In4.Cu")
		(net "CLK_100M_CPU1_BCLK0_DP")
	)
	(arc
		(start 135.607044 -70.563486)
		(mid 135.396331 -70.776565)
		(end 135.108188 -70.858888)
		(width 0.0889)
		(layer "In4.Cu")
		(net "CLK_100M_CPU1_BCLK0_DP")
	)
	(arc
		(start 131.314698 -71.058786)
		(mid 131.107694 -71.26965)
		(end 130.824478 -71.353934)
		(width 0.0889)
		(layer "In4.Cu")
		(net "CLK_100M_CPU1_BCLK0_DP")
	)
	(arc
		(start 127.347218 -71.353934)
		(mid 127.064001 -71.269653)
		(end 126.856998 -71.058786)
		(width 0.0889)
		(layer "In4.Cu")
		(net "CLK_100M_CPU1_BCLK0_DP")
	)
	(arc
		(start 138.51636 -70.858888)
		(mid 138.228215 -70.776569)
		(end 138.017504 -70.563486)
		(width 0.0889)
		(layer "In4.Cu")
		(net "CLK_100M_CPU1_BCLK0_DP")
	)
	(arc
		(start 135.942578 -70.363334)
		(mid 135.748728 -70.419684)
		(end 135.607044 -70.563486)
		(width 0.0889)
		(layer "In4.Cu")
		(net "CLK_100M_CPU1_BCLK0_DP")
	)
	(arc
		(start 126.163578 -71.058786)
		(mid 125.956574 -71.26965)
		(end 125.673358 -71.353934)
		(width 0.0889)
		(layer "In4.Cu")
		(net "CLK_100M_CPU1_BCLK0_DP")
	)
	(arc
		(start 141.083284 -71.353934)
		(mid 140.800067 -71.269653)
		(end 140.593064 -71.058786)
		(width 0.0889)
		(layer "In4.Cu")
		(net "CLK_100M_CPU1_BCLK0_DP")
	)
	(arc
		(start 125.630178 -71.353934)
		(mid 125.346961 -71.269653)
		(end 125.139958 -71.058786)
		(width 0.0889)
		(layer "In4.Cu")
		(net "CLK_100M_CPU1_BCLK0_DP")
	)
	(arc
		(start 126.495302 -70.858888)
		(mid 126.30366 -70.916054)
		(end 126.163578 -71.058786)
		(width 0.0889)
		(layer "In4.Cu")
		(net "CLK_100M_CPU1_BCLK0_DP")
	)
	(arc
		(start 140.231368 -70.858888)
		(mid 140.039726 -70.916054)
		(end 139.899644 -71.058786)
		(width 0.0889)
		(layer "In4.Cu")
		(net "CLK_100M_CPU1_BCLK0_DP")
	)
	(arc
		(start 131.673346 -70.858888)
		(mid 131.662932 -70.858752)
		(end 131.652518 -70.858888)
		(width 0.0889)
		(layer "In4.Cu")
		(net "CLK_100M_CPU1_BCLK0_DP")
	)
	(arc
		(start 135.080248 -70.858888)
		(mid 134.888606 -70.916054)
		(end 134.748524 -71.058786)
		(width 0.0889)
		(layer "In4.Cu")
		(net "CLK_100M_CPU1_BCLK0_DP")
	)
	(arc
		(start 137.324084 -70.563486)
		(mid 137.113371 -70.776565)
		(end 136.825228 -70.858888)
		(width 0.0889)
		(layer "In4.Cu")
		(net "CLK_100M_CPU1_BCLK0_DP")
	)
	(arc
		(start 130.781298 -71.353934)
		(mid 130.498081 -71.269653)
		(end 130.291078 -71.058786)
		(width 0.0889)
		(layer "In4.Cu")
		(net "CLK_100M_CPU1_BCLK0_DP")
	)
	(arc
		(start 129.597658 -71.058786)
		(mid 129.390654 -71.26965)
		(end 129.107438 -71.353934)
		(width 0.0889)
		(layer "In4.Cu")
		(net "CLK_100M_CPU1_BCLK0_DP")
	)
	(arc
		(start 138.017504 -70.563486)
		(mid 137.875821 -70.419682)
		(end 137.68197 -70.363334)
		(width 0.0889)
		(layer "In4.Cu")
		(net "CLK_100M_CPU1_BCLK0_DP")
	)
	(arc
		(start 124.281438 -70.563486)
		(mid 124.139755 -70.419682)
		(end 123.945904 -70.363334)
		(width 0.0889)
		(layer "In4.Cu")
		(net "CLK_100M_CPU1_BCLK0_DP")
	)
	(arc
		(start 134.215124 -71.353934)
		(mid 133.931907 -71.269653)
		(end 133.724904 -71.058786)
		(width 0.0889)
		(layer "In4.Cu")
		(net "CLK_100M_CPU1_BCLK0_DP")
	)
	(arc
		(start 133.724904 -71.058786)
		(mid 133.584825 -70.91605)
		(end 133.39318 -70.858888)
		(width 0.0889)
		(layer "In4.Cu")
		(net "CLK_100M_CPU1_BCLK0_DP")
	)
	(arc
		(start 132.004562 -71.053198)
		(mid 131.863789 -70.913689)
		(end 131.673346 -70.858888)
		(width 0.0889)
		(layer "In4.Cu")
		(net "CLK_100M_CPU1_BCLK0_DP")
	)
	(arc
		(start 132.494782 -71.353934)
		(mid 132.213482 -71.268968)
		(end 132.007864 -71.05904)
		(width 0.0889)
		(layer "In4.Cu")
		(net "CLK_100M_CPU1_BCLK0_DP")
	)
	(segment
		(start 123.076208 -69.277738)
		(end 122.504708 -69.277738)
		(width 0.1143)
		(layer "F.Cu")
		(net "CLK_100M_CPU1_BCLK0_DN")
	)
	(segment
		(start 167.709596 -89.206324)
		(end 167.93718 -88.97874)
		(width 0.1143)
		(layer "F.Cu")
		(net "CLK_100M_CPU1_BCLK0_DN")
	)
	(segment
		(start 167.63238 -87.757)
		(end 167.386 -87.757)
		(width 0.1143)
		(layer "F.Cu")
		(net "CLK_100M_CPU1_BCLK0_DN")
	)
	(segment
		(start 167.93718 -88.97874)
		(end 167.93718 -88.0618)
		(width 0.1143)
		(layer "F.Cu")
		(net "CLK_100M_CPU1_BCLK0_DN")
	)
	(segment
		(start 167.562276 -89.206324)
		(end 167.709596 -89.206324)
		(width 0.1143)
		(layer "F.Cu")
		(net "CLK_100M_CPU1_BCLK0_DN")
	)
	(segment
		(start 167.93718 -88.0618)
		(end 167.63238 -87.757)
		(width 0.1143)
		(layer "F.Cu")
		(net "CLK_100M_CPU1_BCLK0_DN")
	)
	(via
		(at 123.076208 -69.277738)
		(size 0.508)
		(drill 0.254)
		(layers "F.Cu" "B.Cu")
		(net "CLK_100M_CPU1_BCLK0_DN")
	)
	(via
		(at 167.562276 -89.206324)
		(size 0.508)
		(drill 0.254)
		(layers "F.Cu" "B.Cu")
		(net "CLK_100M_CPU1_BCLK0_DN")
	)
	(segment
		(start 167.386 -87.757)
		(end 167.738806 -87.757)
		(width 0.1143)
		(layer "B.Cu")
		(net "CLK_100M_CPU1_BCLK0_DN")
	)
	(segment
		(start 167.738806 -87.757)
		(end 167.918892 -87.937086)
		(width 0.1143)
		(layer "B.Cu")
		(net "CLK_100M_CPU1_BCLK0_DN")
	)
	(segment
		(start 167.918892 -87.937086)
		(end 167.918892 -89.055702)
		(width 0.1143)
		(layer "B.Cu")
		(net "CLK_100M_CPU1_BCLK0_DN")
	)
	(segment
		(start 167.76827 -89.206324)
		(end 167.562276 -89.206324)
		(width 0.1143)
		(layer "B.Cu")
		(net "CLK_100M_CPU1_BCLK0_DN")
	)
	(segment
		(start 167.918892 -89.055702)
		(end 167.76827 -89.206324)
		(width 0.1143)
		(layer "B.Cu")
		(net "CLK_100M_CPU1_BCLK0_DN")
	)
	(segment
		(start 158.792164 -78.15072)
		(end 158.520384 -78.15072)
		(width 0.1143)
		(layer "In4.Cu")
		(net "CLK_100M_CPU1_BCLK0_DN")
	)
	(segment
		(start 151.709882 -70.34403)
		(end 151.431498 -70.065646)
		(width 0.1143)
		(layer "In4.Cu")
		(net "CLK_100M_CPU1_BCLK0_DN")
	)
	(segment
		(start 142.658338 -71.608188)
		(end 142.63624 -71.608188)
		(width 0.0889)
		(layer "In4.Cu")
		(net "CLK_100M_CPU1_BCLK0_DN")
	)
	(segment
		(start 148.865082 -76.381356)
		(end 148.572982 -76.381356)
		(width 0.1143)
		(layer "In4.Cu")
		(net "CLK_100M_CPU1_BCLK0_DN")
	)
	(segment
		(start 145.613882 -76.381356)
		(end 144.136618 -76.381356)
		(width 0.1143)
		(layer "In4.Cu")
		(net "CLK_100M_CPU1_BCLK0_DN")
	)
	(segment
		(start 167.949626 -89.72296)
		(end 167.795702 -89.876884)
		(width 0.1143)
		(layer "In4.Cu")
		(net "CLK_100M_CPU1_BCLK0_DN")
	)
	(segment
		(start 153.741882 -76.381356)
		(end 153.449782 -76.381356)
		(width 0.1143)
		(layer "In4.Cu")
		(net "CLK_100M_CPU1_BCLK0_DN")
	)
	(segment
		(start 144.016476 -76.261214)
		(end 144.016476 -75.918314)
		(width 0.1143)
		(layer "In4.Cu")
		(net "CLK_100M_CPU1_BCLK0_DN")
	)
	(segment
		(start 152.230582 -70.341236)
		(end 152.230582 -76.267056)
		(width 0.1143)
		(layer "In4.Cu")
		(net "CLK_100M_CPU1_BCLK0_DN")
	)
	(segment
		(start 163.163758 -86.35619)
		(end 163.163758 -86.194646)
		(width 0.1143)
		(layer "In4.Cu")
		(net "CLK_100M_CPU1_BCLK0_DN")
	)
	(segment
		(start 139.40282 -71.163434)
		(end 139.372848 -71.163434)
		(width 0.0889)
		(layer "In4.Cu")
		(net "CLK_100M_CPU1_BCLK0_DN")
	)
	(segment
		(start 146.833082 -76.267056)
		(end 146.833082 -70.387972)
		(width 0.1143)
		(layer "In4.Cu")
		(net "CLK_100M_CPU1_BCLK0_DN")
	)
	(segment
		(start 132.173726 -70.964044)
		(end 132.173218 -70.963282)
		(width 0.0889)
		(layer "In4.Cu")
		(net "CLK_100M_CPU1_BCLK0_DN")
	)
	(segment
		(start 161.223706 -75.2856)
		(end 161.058606 -75.1205)
		(width 0.1143)
		(layer "In4.Cu")
		(net "CLK_100M_CPU1_BCLK0_DN")
	)
	(segment
		(start 132.17652 -70.969124)
		(end 132.174234 -70.96506)
		(width 0.0889)
		(layer "In4.Cu")
		(net "CLK_100M_CPU1_BCLK0_DN")
	)
	(segment
		(start 155.80106 -73.594214)
		(end 155.481782 -73.913492)
		(width 0.1143)
		(layer "In4.Cu")
		(net "CLK_100M_CPU1_BCLK0_DN")
	)
	(segment
		(start 158.520384 -78.15072)
		(end 158.385764 -78.0161)
		(width 0.1143)
		(layer "In4.Cu")
		(net "CLK_100M_CPU1_BCLK0_DN")
	)
	(segment
		(start 127.383794 -71.163434)
		(end 127.353822 -71.163434)
		(width 0.0889)
		(layer "In4.Cu")
		(net "CLK_100M_CPU1_BCLK0_DN")
	)
	(segment
		(start 154.961082 -70.821042)
		(end 154.648916 -70.508876)
		(width 0.1143)
		(layer "In4.Cu")
		(net "CLK_100M_CPU1_BCLK0_DN")
	)
	(segment
		(start 158.385764 -78.0161)
		(end 158.385764 -76.91628)
		(width 0.1143)
		(layer "In4.Cu")
		(net "CLK_100M_CPU1_BCLK0_DN")
	)
	(segment
		(start 167.795702 -89.876884)
		(end 167.277796 -89.876884)
		(width 0.1143)
		(layer "In4.Cu")
		(net "CLK_100M_CPU1_BCLK0_DN")
	)
	(segment
		(start 148.142706 -70.070726)
		(end 147.632166 -70.070726)
		(width 0.1143)
		(layer "In4.Cu")
		(net "CLK_100M_CPU1_BCLK0_DN")
	)
	(segment
		(start 144.181576 -75.410314)
		(end 144.016476 -75.245214)
		(width 0.1143)
		(layer "In4.Cu")
		(net "CLK_100M_CPU1_BCLK0_DN")
	)
	(segment
		(start 129.965958 -70.668388)
		(end 129.922778 -70.668388)
		(width 0.0889)
		(layer "In4.Cu")
		(net "CLK_100M_CPU1_BCLK0_DN")
	)
	(segment
		(start 159.191706 -75.2856)
		(end 158.906464 -75.570842)
		(width 0.1143)
		(layer "In4.Cu")
		(net "CLK_100M_CPU1_BCLK0_DN")
	)
	(segment
		(start 155.367482 -76.381356)
		(end 155.075382 -76.381356)
		(width 0.1143)
		(layer "In4.Cu")
		(net "CLK_100M_CPU1_BCLK0_DN")
	)
	(segment
		(start 166.445946 -87.6046)
		(end 164.065712 -87.6046)
		(width 0.1143)
		(layer "In4.Cu")
		(net "CLK_100M_CPU1_BCLK0_DN")
	)
	(segment
		(start 144.016476 -75.918314)
		(end 144.181576 -75.753214)
		(width 0.1143)
		(layer "In4.Cu")
		(net "CLK_100M_CPU1_BCLK0_DN")
	)
	(segment
		(start 160.550606 -75.2856)
		(end 160.207706 -75.2856)
		(width 0.1143)
		(layer "In4.Cu")
		(net "CLK_100M_CPU1_BCLK0_DN")
	)
	(segment
		(start 146.558 -70.11289)
		(end 146.010376 -70.11289)
		(width 0.1143)
		(layer "In4.Cu")
		(net "CLK_100M_CPU1_BCLK0_DN")
	)
	(segment
		(start 144.181576 -74.394314)
		(end 144.016476 -74.229214)
		(width 0.1143)
		(layer "In4.Cu")
		(net "CLK_100M_CPU1_BCLK0_DN")
	)
	(segment
		(start 148.458682 -76.267056)
		(end 148.458682 -70.386702)
		(width 0.1143)
		(layer "In4.Cu")
		(net "CLK_100M_CPU1_BCLK0_DN")
	)
	(segment
		(start 153.856182 -70.800976)
		(end 153.856182 -76.267056)
		(width 0.1143)
		(layer "In4.Cu")
		(net "CLK_100M_CPU1_BCLK0_DN")
	)
	(segment
		(start 153.335482 -76.267056)
		(end 153.335482 -70.354444)
		(width 0.1143)
		(layer "In4.Cu")
		(net "CLK_100M_CPU1_BCLK0_DN")
	)
	(segment
		(start 150.198582 -76.381356)
		(end 150.084282 -76.267056)
		(width 0.1143)
		(layer "In4.Cu")
		(net "CLK_100M_CPU1_BCLK0_DN")
	)
	(segment
		(start 150.897082 -70.065646)
		(end 150.604982 -70.357746)
		(width 0.1143)
		(layer "In4.Cu")
		(net "CLK_100M_CPU1_BCLK0_DN")
	)
	(segment
		(start 130.817874 -71.163434)
		(end 130.787902 -71.163434)
		(width 0.0889)
		(layer "In4.Cu")
		(net "CLK_100M_CPU1_BCLK0_DN")
	)
	(segment
		(start 158.385764 -76.91628)
		(end 157.85084 -76.381356)
		(width 0.1143)
		(layer "In4.Cu")
		(net "CLK_100M_CPU1_BCLK0_DN")
	)
	(segment
		(start 156.586682 -76.267056)
		(end 156.586682 -73.879456)
		(width 0.1143)
		(layer "In4.Cu")
		(net "CLK_100M_CPU1_BCLK0_DN")
	)
	(segment
		(start 149.78126 -70.065646)
		(end 149.255226 -70.065646)
		(width 0.1143)
		(layer "In4.Cu")
		(net "CLK_100M_CPU1_BCLK0_DN")
	)
	(segment
		(start 166.878 -88.036654)
		(end 166.445946 -87.6046)
		(width 0.1143)
		(layer "In4.Cu")
		(net "CLK_100M_CPU1_BCLK0_DN")
	)
	(segment
		(start 144.181576 -73.721214)
		(end 144.181576 -73.378314)
		(width 0.1143)
		(layer "In4.Cu")
		(net "CLK_100M_CPU1_BCLK0_DN")
	)
	(segment
		(start 144.016476 -71.975218)
		(end 143.649446 -71.608188)
		(width 0.1143)
		(layer "In4.Cu")
		(net "CLK_100M_CPU1_BCLK0_DN")
	)
	(segment
		(start 144.016476 -75.245214)
		(end 144.016476 -74.902314)
		(width 0.1143)
		(layer "In4.Cu")
		(net "CLK_100M_CPU1_BCLK0_DN")
	)
	(segment
		(start 152.116282 -76.381356)
		(end 151.824182 -76.381356)
		(width 0.1143)
		(layer "In4.Cu")
		(net "CLK_100M_CPU1_BCLK0_DN")
	)
	(segment
		(start 159.699706 -75.1205)
		(end 159.534606 -75.2856)
		(width 0.1143)
		(layer "In4.Cu")
		(net "CLK_100M_CPU1_BCLK0_DN")
	)
	(segment
		(start 151.824182 -76.381356)
		(end 151.709882 -76.267056)
		(width 0.1143)
		(layer "In4.Cu")
		(net "CLK_100M_CPU1_BCLK0_DN")
	)
	(segment
		(start 154.648916 -70.508876)
		(end 154.148282 -70.508876)
		(width 0.1143)
		(layer "In4.Cu")
		(net "CLK_100M_CPU1_BCLK0_DN")
	)
	(segment
		(start 149.255226 -70.065646)
		(end 148.979382 -70.34149)
		(width 0.1143)
		(layer "In4.Cu")
		(net "CLK_100M_CPU1_BCLK0_DN")
	)
	(segment
		(start 156.700982 -76.381356)
		(end 156.586682 -76.267056)
		(width 0.1143)
		(layer "In4.Cu")
		(net "CLK_100M_CPU1_BCLK0_DN")
	)
	(segment
		(start 150.604982 -76.267056)
		(end 150.490682 -76.381356)
		(width 0.1143)
		(layer "In4.Cu")
		(net "CLK_100M_CPU1_BCLK0_DN")
	)
	(segment
		(start 164.065712 -87.6046)
		(end 163.16198 -86.700868)
		(width 0.1143)
		(layer "In4.Cu")
		(net "CLK_100M_CPU1_BCLK0_DN")
	)
	(segment
		(start 134.2517 -71.163434)
		(end 134.221728 -71.163434)
		(width 0.0889)
		(layer "In4.Cu")
		(net "CLK_100M_CPU1_BCLK0_DN")
	)
	(segment
		(start 163.16198 -75.86218)
		(end 162.5854 -75.2856)
		(width 0.1143)
		(layer "In4.Cu")
		(net "CLK_100M_CPU1_BCLK0_DN")
	)
	(segment
		(start 147.239482 -76.381356)
		(end 146.947382 -76.381356)
		(width 0.1143)
		(layer "In4.Cu")
		(net "CLK_100M_CPU1_BCLK0_DN")
	)
	(segment
		(start 159.534606 -75.2856)
		(end 159.191706 -75.2856)
		(width 0.1143)
		(layer "In4.Cu")
		(net "CLK_100M_CPU1_BCLK0_DN")
	)
	(segment
		(start 136.82345 -70.668134)
		(end 136.801098 -70.668134)
		(width 0.0889)
		(layer "In4.Cu")
		(net "CLK_100M_CPU1_BCLK0_DN")
	)
	(segment
		(start 160.207706 -75.2856)
		(end 160.042606 -75.1205)
		(width 0.1143)
		(layer "In4.Cu")
		(net "CLK_100M_CPU1_BCLK0_DN")
	)
	(segment
		(start 157.85084 -76.381356)
		(end 156.700982 -76.381356)
		(width 0.1143)
		(layer "In4.Cu")
		(net "CLK_100M_CPU1_BCLK0_DN")
	)
	(segment
		(start 147.353782 -70.34911)
		(end 147.353782 -76.267056)
		(width 0.1143)
		(layer "In4.Cu")
		(net "CLK_100M_CPU1_BCLK0_DN")
	)
	(segment
		(start 144.016476 -74.229214)
		(end 144.016476 -73.886314)
		(width 0.1143)
		(layer "In4.Cu")
		(net "CLK_100M_CPU1_BCLK0_DN")
	)
	(segment
		(start 124.811536 -70.668388)
		(end 124.782072 -70.668388)
		(width 0.0889)
		(layer "In4.Cu")
		(net "CLK_100M_CPU1_BCLK0_DN")
	)
	(segment
		(start 155.075382 -76.381356)
		(end 154.961082 -76.267056)
		(width 0.1143)
		(layer "In4.Cu")
		(net "CLK_100M_CPU1_BCLK0_DN")
	)
	(segment
		(start 142.58544 -71.658988)
		(end 141.873224 -71.658988)
		(width 0.0889)
		(layer "In4.Cu")
		(net "CLK_100M_CPU1_BCLK0_DN")
	)
	(segment
		(start 132.174234 -70.96506)
		(end 132.173726 -70.964044)
		(width 0.0889)
		(layer "In4.Cu")
		(net "CLK_100M_CPU1_BCLK0_DN")
	)
	(segment
		(start 160.042606 -75.1205)
		(end 159.699706 -75.1205)
		(width 0.1143)
		(layer "In4.Cu")
		(net "CLK_100M_CPU1_BCLK0_DN")
	)
	(segment
		(start 167.277796 -89.876884)
		(end 167.0304 -89.629488)
		(width 0.1143)
		(layer "In4.Cu")
		(net "CLK_100M_CPU1_BCLK0_DN")
	)
	(segment
		(start 144.181576 -75.753214)
		(end 144.181576 -75.410314)
		(width 0.1143)
		(layer "In4.Cu")
		(net "CLK_100M_CPU1_BCLK0_DN")
	)
	(segment
		(start 148.979382 -76.267056)
		(end 148.865082 -76.381356)
		(width 0.1143)
		(layer "In4.Cu")
		(net "CLK_100M_CPU1_BCLK0_DN")
	)
	(segment
		(start 126.531878 -70.668388)
		(end 126.488698 -70.668388)
		(width 0.0889)
		(layer "In4.Cu")
		(net "CLK_100M_CPU1_BCLK0_DN")
	)
	(segment
		(start 143.649446 -71.608188)
		(end 142.658338 -71.608188)
		(width 0.1143)
		(layer "In4.Cu")
		(net "CLK_100M_CPU1_BCLK0_DN")
	)
	(segment
		(start 167.949626 -89.40292)
		(end 167.949626 -89.72296)
		(width 0.1143)
		(layer "In4.Cu")
		(net "CLK_100M_CPU1_BCLK0_DN")
	)
	(segment
		(start 153.335482 -70.354444)
		(end 153.046684 -70.065646)
		(width 0.1143)
		(layer "In4.Cu")
		(net "CLK_100M_CPU1_BCLK0_DN")
	)
	(segment
		(start 152.506172 -70.065646)
		(end 152.230582 -70.341236)
		(width 0.1143)
		(layer "In4.Cu")
		(net "CLK_100M_CPU1_BCLK0_DN")
	)
	(segment
		(start 144.016476 -73.886314)
		(end 144.181576 -73.721214)
		(width 0.1143)
		(layer "In4.Cu")
		(net "CLK_100M_CPU1_BCLK0_DN")
	)
	(segment
		(start 135.975344 -70.172834)
		(end 135.932164 -70.172834)
		(width 0.0889)
		(layer "In4.Cu")
		(net "CLK_100M_CPU1_BCLK0_DN")
	)
	(segment
		(start 146.833082 -70.387972)
		(end 146.558 -70.11289)
		(width 0.1143)
		(layer "In4.Cu")
		(net "CLK_100M_CPU1_BCLK0_DN")
	)
	(segment
		(start 151.709882 -76.267056)
		(end 151.709882 -70.34403)
		(width 0.1143)
		(layer "In4.Cu")
		(net "CLK_100M_CPU1_BCLK0_DN")
	)
	(segment
		(start 147.632166 -70.070726)
		(end 147.353782 -70.34911)
		(width 0.1143)
		(layer "In4.Cu")
		(net "CLK_100M_CPU1_BCLK0_DN")
	)
	(segment
		(start 142.63624 -71.608188)
		(end 142.58544 -71.658988)
		(width 0.0889)
		(layer "In4.Cu")
		(net "CLK_100M_CPU1_BCLK0_DN")
	)
	(segment
		(start 160.715706 -75.1205)
		(end 160.550606 -75.2856)
		(width 0.1143)
		(layer "In4.Cu")
		(net "CLK_100M_CPU1_BCLK0_DN")
	)
	(segment
		(start 144.181576 -74.737214)
		(end 144.181576 -74.394314)
		(width 0.1143)
		(layer "In4.Cu")
		(net "CLK_100M_CPU1_BCLK0_DN")
	)
	(segment
		(start 153.449782 -76.381356)
		(end 153.335482 -76.267056)
		(width 0.1143)
		(layer "In4.Cu")
		(net "CLK_100M_CPU1_BCLK0_DN")
	)
	(segment
		(start 153.856182 -76.267056)
		(end 153.741882 -76.381356)
		(width 0.1143)
		(layer "In4.Cu")
		(net "CLK_100M_CPU1_BCLK0_DN")
	)
	(segment
		(start 150.490682 -76.381356)
		(end 150.198582 -76.381356)
		(width 0.1143)
		(layer "In4.Cu")
		(net "CLK_100M_CPU1_BCLK0_DN")
	)
	(segment
		(start 148.458682 -70.386702)
		(end 148.142706 -70.070726)
		(width 0.1143)
		(layer "In4.Cu")
		(net "CLK_100M_CPU1_BCLK0_DN")
	)
	(segment
		(start 163.16198 -86.700868)
		(end 163.16198 -86.357968)
		(width 0.1143)
		(layer "In4.Cu")
		(net "CLK_100M_CPU1_BCLK0_DN")
	)
	(segment
		(start 167.562276 -89.206324)
		(end 167.75303 -89.206324)
		(width 0.1143)
		(layer "In4.Cu")
		(net "CLK_100M_CPU1_BCLK0_DN")
	)
	(segment
		(start 158.906464 -75.570842)
		(end 158.906464 -78.03642)
		(width 0.1143)
		(layer "In4.Cu")
		(net "CLK_100M_CPU1_BCLK0_DN")
	)
	(segment
		(start 163.16198 -86.192868)
		(end 163.16198 -75.86218)
		(width 0.1143)
		(layer "In4.Cu")
		(net "CLK_100M_CPU1_BCLK0_DN")
	)
	(segment
		(start 156.586682 -73.879456)
		(end 156.30144 -73.594214)
		(width 0.1143)
		(layer "In4.Cu")
		(net "CLK_100M_CPU1_BCLK0_DN")
	)
	(segment
		(start 148.572982 -76.381356)
		(end 148.458682 -76.267056)
		(width 0.1143)
		(layer "In4.Cu")
		(net "CLK_100M_CPU1_BCLK0_DN")
	)
	(segment
		(start 132.176012 -70.969124)
		(end 132.17652 -70.969124)
		(width 0.0889)
		(layer "In4.Cu")
		(net "CLK_100M_CPU1_BCLK0_DN")
	)
	(segment
		(start 144.016476 -74.902314)
		(end 144.181576 -74.737214)
		(width 0.1143)
		(layer "In4.Cu")
		(net "CLK_100M_CPU1_BCLK0_DN")
	)
	(segment
		(start 145.728182 -76.267056)
		(end 145.613882 -76.381356)
		(width 0.1143)
		(layer "In4.Cu")
		(net "CLK_100M_CPU1_BCLK0_DN")
	)
	(segment
		(start 161.058606 -75.1205)
		(end 160.715706 -75.1205)
		(width 0.1143)
		(layer "In4.Cu")
		(net "CLK_100M_CPU1_BCLK0_DN")
	)
	(segment
		(start 131.679188 -70.668134)
		(end 131.648454 -70.668134)
		(width 0.0889)
		(layer "In4.Cu")
		(net "CLK_100M_CPU1_BCLK0_DN")
	)
	(segment
		(start 144.016476 -73.213214)
		(end 144.016476 -71.975218)
		(width 0.1143)
		(layer "In4.Cu")
		(net "CLK_100M_CPU1_BCLK0_DN")
	)
	(segment
		(start 141.307566 -71.163434)
		(end 141.089888 -71.163434)
		(width 0.0889)
		(layer "In4.Cu")
		(net "CLK_100M_CPU1_BCLK0_DN")
	)
	(segment
		(start 150.084282 -70.368668)
		(end 149.78126 -70.065646)
		(width 0.1143)
		(layer "In4.Cu")
		(net "CLK_100M_CPU1_BCLK0_DN")
	)
	(segment
		(start 155.481782 -76.267056)
		(end 155.367482 -76.381356)
		(width 0.1143)
		(layer "In4.Cu")
		(net "CLK_100M_CPU1_BCLK0_DN")
	)
	(segment
		(start 132.534406 -71.163434)
		(end 132.499354 -71.163434)
		(width 0.0889)
		(layer "In4.Cu")
		(net "CLK_100M_CPU1_BCLK0_DN")
	)
	(segment
		(start 154.148282 -70.508876)
		(end 153.856182 -70.800976)
		(width 0.1143)
		(layer "In4.Cu")
		(net "CLK_100M_CPU1_BCLK0_DN")
	)
	(segment
		(start 150.084282 -76.267056)
		(end 150.084282 -70.368668)
		(width 0.1143)
		(layer "In4.Cu")
		(net "CLK_100M_CPU1_BCLK0_DN")
	)
	(segment
		(start 137.692384 -70.172834)
		(end 137.649204 -70.172834)
		(width 0.0889)
		(layer "In4.Cu")
		(net "CLK_100M_CPU1_BCLK0_DN")
	)
	(segment
		(start 162.5854 -75.2856)
		(end 161.223706 -75.2856)
		(width 0.1143)
		(layer "In4.Cu")
		(net "CLK_100M_CPU1_BCLK0_DN")
	)
	(segment
		(start 147.353782 -76.267056)
		(end 147.239482 -76.381356)
		(width 0.1143)
		(layer "In4.Cu")
		(net "CLK_100M_CPU1_BCLK0_DN")
	)
	(segment
		(start 125.666754 -71.163434)
		(end 125.636782 -71.163434)
		(width 0.0889)
		(layer "In4.Cu")
		(net "CLK_100M_CPU1_BCLK0_DN")
	)
	(segment
		(start 158.906464 -78.03642)
		(end 158.792164 -78.15072)
		(width 0.1143)
		(layer "In4.Cu")
		(net "CLK_100M_CPU1_BCLK0_DN")
	)
	(segment
		(start 163.163758 -86.194646)
		(end 163.16198 -86.192868)
		(width 0.1143)
		(layer "In4.Cu")
		(net "CLK_100M_CPU1_BCLK0_DN")
	)
	(segment
		(start 151.431498 -70.065646)
		(end 150.897082 -70.065646)
		(width 0.1143)
		(layer "In4.Cu")
		(net "CLK_100M_CPU1_BCLK0_DN")
	)
	(segment
		(start 135.10641 -70.668134)
		(end 135.08228 -70.668134)
		(width 0.0889)
		(layer "In4.Cu")
		(net "CLK_100M_CPU1_BCLK0_DN")
	)
	(segment
		(start 128.248918 -70.668388)
		(end 128.205738 -70.668388)
		(width 0.0889)
		(layer "In4.Cu")
		(net "CLK_100M_CPU1_BCLK0_DN")
	)
	(segment
		(start 123.140978 -69.680582)
		(end 123.076208 -69.615812)
		(width 0.0889)
		(layer "In4.Cu")
		(net "CLK_100M_CPU1_BCLK0_DN")
	)
	(segment
		(start 146.947382 -76.381356)
		(end 146.833082 -76.267056)
		(width 0.1143)
		(layer "In4.Cu")
		(net "CLK_100M_CPU1_BCLK0_DN")
	)
	(segment
		(start 153.046684 -70.065646)
		(end 152.506172 -70.065646)
		(width 0.1143)
		(layer "In4.Cu")
		(net "CLK_100M_CPU1_BCLK0_DN")
	)
	(segment
		(start 154.961082 -76.267056)
		(end 154.961082 -70.821042)
		(width 0.1143)
		(layer "In4.Cu")
		(net "CLK_100M_CPU1_BCLK0_DN")
	)
	(segment
		(start 144.181576 -73.378314)
		(end 144.016476 -73.213214)
		(width 0.1143)
		(layer "In4.Cu")
		(net "CLK_100M_CPU1_BCLK0_DN")
	)
	(segment
		(start 152.230582 -76.267056)
		(end 152.116282 -76.381356)
		(width 0.1143)
		(layer "In4.Cu")
		(net "CLK_100M_CPU1_BCLK0_DN")
	)
	(segment
		(start 145.728182 -70.395084)
		(end 145.728182 -76.267056)
		(width 0.1143)
		(layer "In4.Cu")
		(net "CLK_100M_CPU1_BCLK0_DN")
	)
	(segment
		(start 167.0304 -88.957658)
		(end 166.878 -88.805258)
		(width 0.1143)
		(layer "In4.Cu")
		(net "CLK_100M_CPU1_BCLK0_DN")
	)
	(segment
		(start 129.100834 -71.163434)
		(end 129.070862 -71.163434)
		(width 0.0889)
		(layer "In4.Cu")
		(net "CLK_100M_CPU1_BCLK0_DN")
	)
	(segment
		(start 155.481782 -73.913492)
		(end 155.481782 -76.267056)
		(width 0.1143)
		(layer "In4.Cu")
		(net "CLK_100M_CPU1_BCLK0_DN")
	)
	(segment
		(start 163.16198 -86.357968)
		(end 163.163758 -86.35619)
		(width 0.1143)
		(layer "In4.Cu")
		(net "CLK_100M_CPU1_BCLK0_DN")
	)
	(segment
		(start 148.979382 -70.34149)
		(end 148.979382 -76.267056)
		(width 0.1143)
		(layer "In4.Cu")
		(net "CLK_100M_CPU1_BCLK0_DN")
	)
	(segment
		(start 156.30144 -73.594214)
		(end 155.80106 -73.594214)
		(width 0.1143)
		(layer "In4.Cu")
		(net "CLK_100M_CPU1_BCLK0_DN")
	)
	(segment
		(start 138.542268 -70.668134)
		(end 138.518138 -70.668134)
		(width 0.0889)
		(layer "In4.Cu")
		(net "CLK_100M_CPU1_BCLK0_DN")
	)
	(segment
		(start 150.604982 -70.357746)
		(end 150.604982 -76.267056)
		(width 0.1143)
		(layer "In4.Cu")
		(net "CLK_100M_CPU1_BCLK0_DN")
	)
	(segment
		(start 123.952508 -70.172834)
		(end 123.923552 -70.172834)
		(width 0.0889)
		(layer "In4.Cu")
		(net "CLK_100M_CPU1_BCLK0_DN")
	)
	(segment
		(start 144.136618 -76.381356)
		(end 144.016476 -76.261214)
		(width 0.1143)
		(layer "In4.Cu")
		(net "CLK_100M_CPU1_BCLK0_DN")
	)
	(segment
		(start 166.878 -88.805258)
		(end 166.878 -88.036654)
		(width 0.1143)
		(layer "In4.Cu")
		(net "CLK_100M_CPU1_BCLK0_DN")
	)
	(segment
		(start 123.076208 -69.615812)
		(end 123.076208 -69.277738)
		(width 0.0889)
		(layer "In4.Cu")
		(net "CLK_100M_CPU1_BCLK0_DN")
	)
	(segment
		(start 146.010376 -70.11289)
		(end 145.728182 -70.395084)
		(width 0.1143)
		(layer "In4.Cu")
		(net "CLK_100M_CPU1_BCLK0_DN")
	)
	(segment
		(start 167.0304 -89.629488)
		(end 167.0304 -88.957658)
		(width 0.1143)
		(layer "In4.Cu")
		(net "CLK_100M_CPU1_BCLK0_DN")
	)
	(segment
		(start 167.75303 -89.206324)
		(end 167.949626 -89.40292)
		(width 0.1143)
		(layer "In4.Cu")
		(net "CLK_100M_CPU1_BCLK0_DN")
	)
	(arc
		(start 139.041124 -70.963536)
		(mid 138.830411 -70.750457)
		(end 138.542268 -70.668134)
		(width 0.0889)
		(layer "In4.Cu")
		(net "CLK_100M_CPU1_BCLK0_DN")
	)
	(arc
		(start 124.782072 -70.668388)
		(mid 124.588222 -70.612038)
		(end 124.446538 -70.468236)
		(width 0.0889)
		(layer "In4.Cu")
		(net "CLK_100M_CPU1_BCLK0_DN")
	)
	(arc
		(start 132.499354 -71.163434)
		(mid 132.313367 -71.106736)
		(end 132.176012 -70.969124)
		(width 0.0889)
		(layer "In4.Cu")
		(net "CLK_100M_CPU1_BCLK0_DN")
	)
	(arc
		(start 126.488698 -70.668388)
		(mid 126.205481 -70.752669)
		(end 125.998478 -70.963536)
		(width 0.0889)
		(layer "In4.Cu")
		(net "CLK_100M_CPU1_BCLK0_DN")
	)
	(arc
		(start 140.268452 -70.668388)
		(mid 140.246354 -70.667975)
		(end 140.224256 -70.668388)
		(width 0.0889)
		(layer "In4.Cu")
		(net "CLK_100M_CPU1_BCLK0_DN")
	)
	(arc
		(start 124.814838 -70.668388)
		(mid 124.813187 -70.668386)
		(end 124.811536 -70.668388)
		(width 0.0889)
		(layer "In4.Cu")
		(net "CLK_100M_CPU1_BCLK0_DN")
	)
	(arc
		(start 125.998478 -70.963536)
		(mid 125.858399 -71.106272)
		(end 125.666754 -71.163434)
		(width 0.0889)
		(layer "In4.Cu")
		(net "CLK_100M_CPU1_BCLK0_DN")
	)
	(arc
		(start 132.866384 -70.963536)
		(mid 132.726196 -71.106338)
		(end 132.534406 -71.163434)
		(width 0.0889)
		(layer "In4.Cu")
		(net "CLK_100M_CPU1_BCLK0_DN")
	)
	(arc
		(start 123.161806 -69.683376)
		(mid 123.151404 -69.681888)
		(end 123.140978 -69.680582)
		(width 0.0889)
		(layer "In4.Cu")
		(net "CLK_100M_CPU1_BCLK0_DN")
	)
	(arc
		(start 127.022098 -70.963536)
		(mid 126.815094 -70.752672)
		(end 126.531878 -70.668388)
		(width 0.0889)
		(layer "In4.Cu")
		(net "CLK_100M_CPU1_BCLK0_DN")
	)
	(arc
		(start 133.890004 -70.963536)
		(mid 133.683217 -70.752803)
		(end 133.400292 -70.668388)
		(width 0.0889)
		(layer "In4.Cu")
		(net "CLK_100M_CPU1_BCLK0_DN")
	)
	(arc
		(start 141.873224 -71.658988)
		(mid 141.747737 -71.579155)
		(end 141.656562 -71.46163)
		(width 0.0889)
		(layer "In4.Cu")
		(net "CLK_100M_CPU1_BCLK0_DN")
	)
	(arc
		(start 137.649204 -70.172834)
		(mid 137.365987 -70.257115)
		(end 137.158984 -70.467982)
		(width 0.0889)
		(layer "In4.Cu")
		(net "CLK_100M_CPU1_BCLK0_DN")
	)
	(arc
		(start 128.739138 -70.963536)
		(mid 128.532134 -70.752672)
		(end 128.248918 -70.668388)
		(width 0.0889)
		(layer "In4.Cu")
		(net "CLK_100M_CPU1_BCLK0_DN")
	)
	(arc
		(start 140.758164 -70.963536)
		(mid 140.551377 -70.752803)
		(end 140.268452 -70.668388)
		(width 0.0889)
		(layer "In4.Cu")
		(net "CLK_100M_CPU1_BCLK0_DN")
	)
	(arc
		(start 129.922778 -70.668388)
		(mid 129.639561 -70.752669)
		(end 129.432558 -70.963536)
		(width 0.0889)
		(layer "In4.Cu")
		(net "CLK_100M_CPU1_BCLK0_DN")
	)
	(arc
		(start 131.648454 -70.668134)
		(mid 131.360309 -70.750453)
		(end 131.149598 -70.963536)
		(width 0.0889)
		(layer "In4.Cu")
		(net "CLK_100M_CPU1_BCLK0_DN")
	)
	(arc
		(start 127.353822 -71.163434)
		(mid 127.16218 -71.106268)
		(end 127.022098 -70.963536)
		(width 0.0889)
		(layer "In4.Cu")
		(net "CLK_100M_CPU1_BCLK0_DN")
	)
	(arc
		(start 130.787902 -71.163434)
		(mid 130.59626 -71.106268)
		(end 130.456178 -70.963536)
		(width 0.0889)
		(layer "In4.Cu")
		(net "CLK_100M_CPU1_BCLK0_DN")
	)
	(arc
		(start 128.205738 -70.668388)
		(mid 127.922521 -70.752669)
		(end 127.715518 -70.963536)
		(width 0.0889)
		(layer "In4.Cu")
		(net "CLK_100M_CPU1_BCLK0_DN")
	)
	(arc
		(start 129.070862 -71.163434)
		(mid 128.87922 -71.106268)
		(end 128.739138 -70.963536)
		(width 0.0889)
		(layer "In4.Cu")
		(net "CLK_100M_CPU1_BCLK0_DN")
	)
	(arc
		(start 130.456178 -70.963536)
		(mid 130.249174 -70.752672)
		(end 129.965958 -70.668388)
		(width 0.0889)
		(layer "In4.Cu")
		(net "CLK_100M_CPU1_BCLK0_DN")
	)
	(arc
		(start 139.734544 -70.963536)
		(mid 139.594465 -71.106272)
		(end 139.40282 -71.163434)
		(width 0.0889)
		(layer "In4.Cu")
		(net "CLK_100M_CPU1_BCLK0_DN")
	)
	(arc
		(start 127.715518 -70.963536)
		(mid 127.575439 -71.106272)
		(end 127.383794 -71.163434)
		(width 0.0889)
		(layer "In4.Cu")
		(net "CLK_100M_CPU1_BCLK0_DN")
	)
	(arc
		(start 133.400292 -70.668388)
		(mid 133.378194 -70.667975)
		(end 133.356096 -70.668388)
		(width 0.0889)
		(layer "In4.Cu")
		(net "CLK_100M_CPU1_BCLK0_DN")
	)
	(arc
		(start 123.923552 -70.172834)
		(mid 123.729702 -70.116484)
		(end 123.588018 -69.972682)
		(width 0.0889)
		(layer "In4.Cu")
		(net "CLK_100M_CPU1_BCLK0_DN")
	)
	(arc
		(start 137.158984 -70.467982)
		(mid 137.017301 -70.611786)
		(end 136.82345 -70.668134)
		(width 0.0889)
		(layer "In4.Cu")
		(net "CLK_100M_CPU1_BCLK0_DN")
	)
	(arc
		(start 139.372848 -71.163434)
		(mid 139.181206 -71.106268)
		(end 139.041124 -70.963536)
		(width 0.0889)
		(layer "In4.Cu")
		(net "CLK_100M_CPU1_BCLK0_DN")
	)
	(arc
		(start 124.446538 -70.468236)
		(mid 124.23793 -70.256304)
		(end 123.952508 -70.172834)
		(width 0.0889)
		(layer "In4.Cu")
		(net "CLK_100M_CPU1_BCLK0_DN")
	)
	(arc
		(start 140.224256 -70.668388)
		(mid 139.94132 -70.752784)
		(end 139.734544 -70.963536)
		(width 0.0889)
		(layer "In4.Cu")
		(net "CLK_100M_CPU1_BCLK0_DN")
	)
	(arc
		(start 138.182604 -70.467982)
		(mid 137.9756 -70.257118)
		(end 137.692384 -70.172834)
		(width 0.0889)
		(layer "In4.Cu")
		(net "CLK_100M_CPU1_BCLK0_DN")
	)
	(arc
		(start 132.173218 -70.963282)
		(mid 131.964548 -70.751525)
		(end 131.679188 -70.668134)
		(width 0.0889)
		(layer "In4.Cu")
		(net "CLK_100M_CPU1_BCLK0_DN")
	)
	(arc
		(start 136.465564 -70.467982)
		(mid 136.25856 -70.257118)
		(end 135.975344 -70.172834)
		(width 0.0889)
		(layer "In4.Cu")
		(net "CLK_100M_CPU1_BCLK0_DN")
	)
	(arc
		(start 135.08228 -70.668134)
		(mid 134.794135 -70.750453)
		(end 134.583424 -70.963536)
		(width 0.0889)
		(layer "In4.Cu")
		(net "CLK_100M_CPU1_BCLK0_DN")
	)
	(arc
		(start 125.305058 -70.963536)
		(mid 125.098054 -70.752672)
		(end 124.814838 -70.668388)
		(width 0.0889)
		(layer "In4.Cu")
		(net "CLK_100M_CPU1_BCLK0_DN")
	)
	(arc
		(start 129.432558 -70.963536)
		(mid 129.292479 -71.106272)
		(end 129.100834 -71.163434)
		(width 0.0889)
		(layer "In4.Cu")
		(net "CLK_100M_CPU1_BCLK0_DN")
	)
	(arc
		(start 135.441944 -70.467982)
		(mid 135.300261 -70.611786)
		(end 135.10641 -70.668134)
		(width 0.0889)
		(layer "In4.Cu")
		(net "CLK_100M_CPU1_BCLK0_DN")
	)
	(arc
		(start 135.932164 -70.172834)
		(mid 135.648947 -70.257115)
		(end 135.441944 -70.467982)
		(width 0.0889)
		(layer "In4.Cu")
		(net "CLK_100M_CPU1_BCLK0_DN")
	)
	(arc
		(start 133.356096 -70.668388)
		(mid 133.07316 -70.752784)
		(end 132.866384 -70.963536)
		(width 0.0889)
		(layer "In4.Cu")
		(net "CLK_100M_CPU1_BCLK0_DN")
	)
	(arc
		(start 136.801098 -70.668134)
		(mid 136.607248 -70.611784)
		(end 136.465564 -70.467982)
		(width 0.0889)
		(layer "In4.Cu")
		(net "CLK_100M_CPU1_BCLK0_DN")
	)
	(arc
		(start 125.636782 -71.163434)
		(mid 125.44514 -71.106268)
		(end 125.305058 -70.963536)
		(width 0.0889)
		(layer "In4.Cu")
		(net "CLK_100M_CPU1_BCLK0_DN")
	)
	(arc
		(start 123.588018 -69.972682)
		(mid 123.408095 -69.779143)
		(end 123.161806 -69.683376)
		(width 0.0889)
		(layer "In4.Cu")
		(net "CLK_100M_CPU1_BCLK0_DN")
	)
	(arc
		(start 134.583424 -70.963536)
		(mid 134.443345 -71.106272)
		(end 134.2517 -71.163434)
		(width 0.0889)
		(layer "In4.Cu")
		(net "CLK_100M_CPU1_BCLK0_DN")
	)
	(arc
		(start 138.518138 -70.668134)
		(mid 138.324288 -70.611784)
		(end 138.182604 -70.467982)
		(width 0.0889)
		(layer "In4.Cu")
		(net "CLK_100M_CPU1_BCLK0_DN")
	)
	(arc
		(start 131.149598 -70.963536)
		(mid 131.009519 -71.106272)
		(end 130.817874 -71.163434)
		(width 0.0889)
		(layer "In4.Cu")
		(net "CLK_100M_CPU1_BCLK0_DN")
	)
	(arc
		(start 141.656562 -71.46163)
		(mid 141.510462 -71.279296)
		(end 141.307566 -71.163434)
		(width 0.0889)
		(layer "In4.Cu")
		(net "CLK_100M_CPU1_BCLK0_DN")
	)
	(arc
		(start 134.221728 -71.163434)
		(mid 134.030086 -71.106268)
		(end 133.890004 -70.963536)
		(width 0.0889)
		(layer "In4.Cu")
		(net "CLK_100M_CPU1_BCLK0_DN")
	)
	(arc
		(start 141.089888 -71.163434)
		(mid 140.898246 -71.106268)
		(end 140.758164 -70.963536)
		(width 0.0889)
		(layer "In4.Cu")
		(net "CLK_100M_CPU1_BCLK0_DN")
	)
	(segment
		(start 177.170334 -81.82229)
		(end 177.170334 -81.407)
		(width 0.1143)
		(layer "F.Cu")
		(net "CLK_100M_CPU0_BCLK2_DP")
	)
	(segment
		(start 176.398682 -81.92135)
		(end 177.071274 -81.92135)
		(width 0.1143)
		(layer "F.Cu")
		(net "CLK_100M_CPU0_BCLK2_DP")
	)
	(segment
		(start 176.276 -81.407)
		(end 176.276 -81.798668)
		(width 0.1143)
		(layer "F.Cu")
		(net "CLK_100M_CPU0_BCLK2_DP")
	)
	(segment
		(start 177.071274 -81.92135)
		(end 177.170334 -81.82229)
		(width 0.1143)
		(layer "F.Cu")
		(net "CLK_100M_CPU0_BCLK2_DP")
	)
	(segment
		(start 286.3596 -89.089738)
		(end 285.7881 -89.089738)
		(width 0.1143)
		(layer "F.Cu")
		(net "CLK_100M_CPU0_BCLK2_DP")
	)
	(segment
		(start 176.276 -81.798668)
		(end 176.398682 -81.92135)
		(width 0.1143)
		(layer "F.Cu")
		(net "CLK_100M_CPU0_BCLK2_DP")
	)
	(via
		(at 286.3596 -89.089738)
		(size 0.508)
		(drill 0.254)
		(layers "F.Cu" "B.Cu")
		(net "CLK_100M_CPU0_BCLK2_DP")
	)
	(via
		(at 177.170334 -81.407)
		(size 0.508)
		(drill 0.254)
		(layers "F.Cu" "B.Cu")
		(net "CLK_100M_CPU0_BCLK2_DP")
	)
	(segment
		(start 177.170334 -81.68005)
		(end 177.170334 -81.407)
		(width 0.1143)
		(layer "B.Cu")
		(net "CLK_100M_CPU0_BCLK2_DP")
	)
	(segment
		(start 176.25568 -81.407)
		(end 176.738026 -81.889346)
		(width 0.1143)
		(layer "B.Cu")
		(net "CLK_100M_CPU0_BCLK2_DP")
	)
	(segment
		(start 176.961038 -81.889346)
		(end 177.170334 -81.68005)
		(width 0.1143)
		(layer "B.Cu")
		(net "CLK_100M_CPU0_BCLK2_DP")
	)
	(segment
		(start 176.738026 -81.889346)
		(end 176.961038 -81.889346)
		(width 0.1143)
		(layer "B.Cu")
		(net "CLK_100M_CPU0_BCLK2_DP")
	)
	(segment
		(start 280.792428 -102.260146)
		(end 280.792428 -102.385876)
		(width 0.0889)
		(layer "In9.Cu")
		(net "CLK_100M_CPU0_BCLK2_DP")
	)
	(segment
		(start 267.033248 -104.0384)
		(end 265.736578 -102.74173)
		(width 0.1143)
		(layer "In9.Cu")
		(net "CLK_100M_CPU0_BCLK2_DP")
	)
	(segment
		(start 194.793108 -103.046784)
		(end 193.40957 -103.046784)
		(width 0.1143)
		(layer "In9.Cu")
		(net "CLK_100M_CPU0_BCLK2_DP")
	)
	(segment
		(start 286.711136 -96.2152)
		(end 286.70631 -96.223836)
		(width 0.0889)
		(layer "In9.Cu")
		(net "CLK_100M_CPU0_BCLK2_DP")
	)
	(segment
		(start 286.711136 -90.2716)
		(end 286.70631 -90.280236)
		(width 0.0889)
		(layer "In9.Cu")
		(net "CLK_100M_CPU0_BCLK2_DP")
	)
	(segment
		(start 230.877618 -102.48519)
		(end 231.16286 -102.199948)
		(width 0.1143)
		(layer "In9.Cu")
		(net "CLK_100M_CPU0_BCLK2_DP")
	)
	(segment
		(start 286.370776 -98.405188)
		(end 286.334708 -98.405188)
		(width 0.0889)
		(layer "In9.Cu")
		(net "CLK_100M_CPU0_BCLK2_DP")
	)
	(segment
		(start 286.70631 -96.223836)
		(end 286.69996 -96.234504)
		(width 0.0889)
		(layer "In9.Cu")
		(net "CLK_100M_CPU0_BCLK2_DP")
	)
	(segment
		(start 189.43574 -102.23754)
		(end 180.349906 -93.151706)
		(width 0.1143)
		(layer "In9.Cu")
		(net "CLK_100M_CPU0_BCLK2_DP")
	)
	(segment
		(start 285.84779 -98.700082)
		(end 285.844488 -98.705924)
		(width 0.0889)
		(layer "In9.Cu")
		(net "CLK_100M_CPU0_BCLK2_DP")
	)
	(segment
		(start 279.06853 -104.0384)
		(end 277.106888 -104.0384)
		(width 0.1143)
		(layer "In9.Cu")
		(net "CLK_100M_CPU0_BCLK2_DP")
	)
	(segment
		(start 210.602576 -106.0704)
		(end 203.349606 -106.0704)
		(width 0.1143)
		(layer "In9.Cu")
		(net "CLK_100M_CPU0_BCLK2_DP")
	)
	(segment
		(start 281.48407 -101.568504)
		(end 281.295348 -101.757226)
		(width 0.0889)
		(layer "In9.Cu")
		(net "CLK_100M_CPU0_BCLK2_DP")
	)
	(segment
		(start 282.301188 -100.877116)
		(end 282.11272 -101.065584)
		(width 0.0889)
		(layer "In9.Cu")
		(net "CLK_100M_CPU0_BCLK2_DP")
	)
	(segment
		(start 177.808382 -81.88325)
		(end 177.284634 -81.88325)
		(width 0.1143)
		(layer "In9.Cu")
		(net "CLK_100M_CPU0_BCLK2_DP")
	)
	(segment
		(start 286.711136 -93.2434)
		(end 286.70631 -93.252036)
		(width 0.0889)
		(layer "In9.Cu")
		(net "CLK_100M_CPU0_BCLK2_DP")
	)
	(segment
		(start 286.69996 -94.822518)
		(end 286.70631 -94.833186)
		(width 0.0889)
		(layer "In9.Cu")
		(net "CLK_100M_CPU0_BCLK2_DP")
	)
	(segment
		(start 286.711136 -89.281)
		(end 286.70631 -89.289636)
		(width 0.0889)
		(layer "In9.Cu")
		(net "CLK_100M_CPU0_BCLK2_DP")
	)
	(segment
		(start 231.16286 -101.665532)
		(end 230.877618 -101.38029)
		(width 0.1143)
		(layer "In9.Cu")
		(net "CLK_100M_CPU0_BCLK2_DP")
	)
	(segment
		(start 228.117146 -102.59949)
		(end 228.231446 -102.48519)
		(width 0.1143)
		(layer "In9.Cu")
		(net "CLK_100M_CPU0_BCLK2_DP")
	)
	(segment
		(start 286.70631 -93.252036)
		(end 286.69996 -93.262704)
		(width 0.0889)
		(layer "In9.Cu")
		(net "CLK_100M_CPU0_BCLK2_DP")
	)
	(segment
		(start 247.3198 -100.6602)
		(end 246.96039 -101.019356)
		(width 0.1143)
		(layer "In9.Cu")
		(net "CLK_100M_CPU0_BCLK2_DP")
	)
	(segment
		(start 276.433788 -104.0384)
		(end 276.090888 -104.0384)
		(width 0.1143)
		(layer "In9.Cu")
		(net "CLK_100M_CPU0_BCLK2_DP")
	)
	(segment
		(start 282.11272 -101.065584)
		(end 281.98699 -101.065584)
		(width 0.0889)
		(layer "In9.Cu")
		(net "CLK_100M_CPU0_BCLK2_DP")
	)
	(segment
		(start 281.98699 -101.065584)
		(end 281.798268 -101.254306)
		(width 0.0889)
		(layer "In9.Cu")
		(net "CLK_100M_CPU0_BCLK2_DP")
	)
	(segment
		(start 282.413964 -100.681536)
		(end 282.301188 -100.877116)
		(width 0.0889)
		(layer "In9.Cu")
		(net "CLK_100M_CPU0_BCLK2_DP")
	)
	(segment
		(start 275.925788 -103.8733)
		(end 275.582888 -103.8733)
		(width 0.1143)
		(layer "In9.Cu")
		(net "CLK_100M_CPU0_BCLK2_DP")
	)
	(segment
		(start 281.798268 -101.254306)
		(end 281.798268 -101.380036)
		(width 0.0889)
		(layer "In9.Cu")
		(net "CLK_100M_CPU0_BCLK2_DP")
	)
	(segment
		(start 246.96039 -101.019356)
		(end 242.163092 -103.00589)
		(width 0.1143)
		(layer "In9.Cu")
		(net "CLK_100M_CPU0_BCLK2_DP")
	)
	(segment
		(start 276.090888 -104.0384)
		(end 275.925788 -103.8733)
		(width 0.1143)
		(layer "In9.Cu")
		(net "CLK_100M_CPU0_BCLK2_DP")
	)
	(segment
		(start 286.70631 -89.289636)
		(end 286.69996 -89.300304)
		(width 0.0889)
		(layer "In9.Cu")
		(net "CLK_100M_CPU0_BCLK2_DP")
	)
	(segment
		(start 285.501334 -98.900234)
		(end 285.483554 -98.900234)
		(width 0.0889)
		(layer "In9.Cu")
		(net "CLK_100M_CPU0_BCLK2_DP")
	)
	(segment
		(start 231.16286 -102.199948)
		(end 231.16286 -101.665532)
		(width 0.1143)
		(layer "In9.Cu")
		(net "CLK_100M_CPU0_BCLK2_DP")
	)
	(segment
		(start 286.3596 -89.089738)
		(end 286.652716 -88.920574)
		(width 0.0889)
		(layer "In9.Cu")
		(net "CLK_100M_CPU0_BCLK2_DP")
	)
	(segment
		(start 227.339144 -101.38029)
		(end 226.231958 -102.487222)
		(width 0.1143)
		(layer "In9.Cu")
		(net "CLK_100M_CPU0_BCLK2_DP")
	)
	(segment
		(start 280.792428 -102.385876)
		(end 280.398728 -102.779576)
		(width 0.0889)
		(layer "In9.Cu")
		(net "CLK_100M_CPU0_BCLK2_DP")
	)
	(segment
		(start 177.284634 -81.88325)
		(end 177.170334 -81.76895)
		(width 0.1143)
		(layer "In9.Cu")
		(net "CLK_100M_CPU0_BCLK2_DP")
	)
	(segment
		(start 195.594224 -103.8479)
		(end 194.793108 -103.046784)
		(width 0.1143)
		(layer "In9.Cu")
		(net "CLK_100M_CPU0_BCLK2_DP")
	)
	(segment
		(start 286.711136 -97.2058)
		(end 286.70631 -97.214436)
		(width 0.0889)
		(layer "In9.Cu")
		(net "CLK_100M_CPU0_BCLK2_DP")
	)
	(segment
		(start 196.703442 -103.8479)
		(end 195.594224 -103.8479)
		(width 0.1143)
		(layer "In9.Cu")
		(net "CLK_100M_CPU0_BCLK2_DP")
	)
	(segment
		(start 281.295348 -101.882956)
		(end 281.10688 -102.071424)
		(width 0.0889)
		(layer "In9.Cu")
		(net "CLK_100M_CPU0_BCLK2_DP")
	)
	(segment
		(start 280.98115 -102.071424)
		(end 280.792428 -102.260146)
		(width 0.0889)
		(layer "In9.Cu")
		(net "CLK_100M_CPU0_BCLK2_DP")
	)
	(segment
		(start 286.70631 -97.214436)
		(end 286.69996 -97.225104)
		(width 0.0889)
		(layer "In9.Cu")
		(net "CLK_100M_CPU0_BCLK2_DP")
	)
	(segment
		(start 275.417788 -104.0384)
		(end 267.033248 -104.0384)
		(width 0.1143)
		(layer "In9.Cu")
		(net "CLK_100M_CPU0_BCLK2_DP")
	)
	(segment
		(start 281.798268 -101.380036)
		(end 281.6098 -101.568504)
		(width 0.0889)
		(layer "In9.Cu")
		(net "CLK_100M_CPU0_BCLK2_DP")
	)
	(segment
		(start 286.711136 -91.2622)
		(end 286.70631 -91.270836)
		(width 0.0889)
		(layer "In9.Cu")
		(net "CLK_100M_CPU0_BCLK2_DP")
	)
	(segment
		(start 228.231446 -102.48519)
		(end 230.877618 -102.48519)
		(width 0.1143)
		(layer "In9.Cu")
		(net "CLK_100M_CPU0_BCLK2_DP")
	)
	(segment
		(start 276.598888 -103.8733)
		(end 276.433788 -104.0384)
		(width 0.1143)
		(layer "In9.Cu")
		(net "CLK_100M_CPU0_BCLK2_DP")
	)
	(segment
		(start 281.10688 -102.071424)
		(end 280.98115 -102.071424)
		(width 0.0889)
		(layer "In9.Cu")
		(net "CLK_100M_CPU0_BCLK2_DP")
	)
	(segment
		(start 280.3271 -102.779576)
		(end 280.311606 -102.79507)
		(width 0.0889)
		(layer "In9.Cu")
		(net "CLK_100M_CPU0_BCLK2_DP")
	)
	(segment
		(start 286.652716 -88.920574)
		(end 286.731456 -88.94191)
		(width 0.0889)
		(layer "In9.Cu")
		(net "CLK_100M_CPU0_BCLK2_DP")
	)
	(segment
		(start 192.600326 -102.23754)
		(end 189.43574 -102.23754)
		(width 0.1143)
		(layer "In9.Cu")
		(net "CLK_100M_CPU0_BCLK2_DP")
	)
	(segment
		(start 280.311606 -102.79507)
		(end 279.06853 -104.0384)
		(width 0.1143)
		(layer "In9.Cu")
		(net "CLK_100M_CPU0_BCLK2_DP")
	)
	(segment
		(start 284.65399 -99.395788)
		(end 284.621224 -99.395788)
		(width 0.0889)
		(layer "In9.Cu")
		(net "CLK_100M_CPU0_BCLK2_DP")
	)
	(segment
		(start 230.877618 -101.38029)
		(end 227.339144 -101.38029)
		(width 0.1143)
		(layer "In9.Cu")
		(net "CLK_100M_CPU0_BCLK2_DP")
	)
	(segment
		(start 281.295348 -101.757226)
		(end 281.295348 -101.882956)
		(width 0.0889)
		(layer "In9.Cu")
		(net "CLK_100M_CPU0_BCLK2_DP")
	)
	(segment
		(start 197.475602 -103.07574)
		(end 196.703442 -103.8479)
		(width 0.1143)
		(layer "In9.Cu")
		(net "CLK_100M_CPU0_BCLK2_DP")
	)
	(segment
		(start 177.170334 -81.76895)
		(end 177.170334 -81.407)
		(width 0.1143)
		(layer "In9.Cu")
		(net "CLK_100M_CPU0_BCLK2_DP")
	)
	(segment
		(start 283.79928 -99.890834)
		(end 283.766514 -99.890834)
		(width 0.0889)
		(layer "In9.Cu")
		(net "CLK_100M_CPU0_BCLK2_DP")
	)
	(segment
		(start 180.349906 -84.424774)
		(end 177.808382 -81.88325)
		(width 0.1143)
		(layer "In9.Cu")
		(net "CLK_100M_CPU0_BCLK2_DP")
	)
	(segment
		(start 228.231446 -103.00589)
		(end 228.117146 -102.89159)
		(width 0.1143)
		(layer "In9.Cu")
		(net "CLK_100M_CPU0_BCLK2_DP")
	)
	(segment
		(start 281.6098 -101.568504)
		(end 281.48407 -101.568504)
		(width 0.0889)
		(layer "In9.Cu")
		(net "CLK_100M_CPU0_BCLK2_DP")
	)
	(segment
		(start 265.736578 -102.74173)
		(end 252.946154 -102.74173)
		(width 0.1143)
		(layer "In9.Cu")
		(net "CLK_100M_CPU0_BCLK2_DP")
	)
	(segment
		(start 200.354946 -103.07574)
		(end 197.475602 -103.07574)
		(width 0.1143)
		(layer "In9.Cu")
		(net "CLK_100M_CPU0_BCLK2_DP")
	)
	(segment
		(start 286.70631 -90.280236)
		(end 286.69996 -90.290904)
		(width 0.0889)
		(layer "In9.Cu")
		(net "CLK_100M_CPU0_BCLK2_DP")
	)
	(segment
		(start 286.711136 -92.2528)
		(end 286.70631 -92.261436)
		(width 0.0889)
		(layer "In9.Cu")
		(net "CLK_100M_CPU0_BCLK2_DP")
	)
	(segment
		(start 252.946154 -102.74173)
		(end 250.864624 -100.6602)
		(width 0.1143)
		(layer "In9.Cu")
		(net "CLK_100M_CPU0_BCLK2_DP")
	)
	(segment
		(start 226.231958 -102.487222)
		(end 210.602576 -106.0704)
		(width 0.1143)
		(layer "In9.Cu")
		(net "CLK_100M_CPU0_BCLK2_DP")
	)
	(segment
		(start 275.582888 -103.8733)
		(end 275.417788 -104.0384)
		(width 0.1143)
		(layer "In9.Cu")
		(net "CLK_100M_CPU0_BCLK2_DP")
	)
	(segment
		(start 242.163092 -103.00589)
		(end 228.231446 -103.00589)
		(width 0.1143)
		(layer "In9.Cu")
		(net "CLK_100M_CPU0_BCLK2_DP")
	)
	(segment
		(start 277.106888 -104.0384)
		(end 276.941788 -103.8733)
		(width 0.1143)
		(layer "In9.Cu")
		(net "CLK_100M_CPU0_BCLK2_DP")
	)
	(segment
		(start 228.117146 -102.89159)
		(end 228.117146 -102.59949)
		(width 0.1143)
		(layer "In9.Cu")
		(net "CLK_100M_CPU0_BCLK2_DP")
	)
	(segment
		(start 203.349606 -106.0704)
		(end 200.354946 -103.07574)
		(width 0.1143)
		(layer "In9.Cu")
		(net "CLK_100M_CPU0_BCLK2_DP")
	)
	(segment
		(start 286.70631 -91.270836)
		(end 286.69996 -91.281504)
		(width 0.0889)
		(layer "In9.Cu")
		(net "CLK_100M_CPU0_BCLK2_DP")
	)
	(segment
		(start 276.941788 -103.8733)
		(end 276.598888 -103.8733)
		(width 0.1143)
		(layer "In9.Cu")
		(net "CLK_100M_CPU0_BCLK2_DP")
	)
	(segment
		(start 193.40957 -103.046784)
		(end 192.600326 -102.23754)
		(width 0.1143)
		(layer "In9.Cu")
		(net "CLK_100M_CPU0_BCLK2_DP")
	)
	(segment
		(start 250.864624 -100.6602)
		(end 247.3198 -100.6602)
		(width 0.1143)
		(layer "In9.Cu")
		(net "CLK_100M_CPU0_BCLK2_DP")
	)
	(segment
		(start 280.398728 -102.779576)
		(end 280.3271 -102.779576)
		(width 0.0889)
		(layer "In9.Cu")
		(net "CLK_100M_CPU0_BCLK2_DP")
	)
	(segment
		(start 286.70631 -92.261436)
		(end 286.69996 -92.272104)
		(width 0.0889)
		(layer "In9.Cu")
		(net "CLK_100M_CPU0_BCLK2_DP")
	)
	(segment
		(start 282.943808 -100.386134)
		(end 282.907994 -100.386134)
		(width 0.0889)
		(layer "In9.Cu")
		(net "CLK_100M_CPU0_BCLK2_DP")
	)
	(segment
		(start 180.349906 -93.151706)
		(end 180.349906 -84.424774)
		(width 0.1143)
		(layer "In9.Cu")
		(net "CLK_100M_CPU0_BCLK2_DP")
	)
	(segment
		(start 286.711136 -94.234)
		(end 286.70631 -94.242636)
		(width 0.0889)
		(layer "In9.Cu")
		(net "CLK_100M_CPU0_BCLK2_DP")
	)
	(arc
		(start 286.69996 -90.290904)
		(mid 286.627162 -90.581667)
		(end 286.70631 -90.870786)
		(width 0.0889)
		(layer "In9.Cu")
		(net "CLK_100M_CPU0_BCLK2_DP")
	)
	(arc
		(start 286.70631 -93.842586)
		(mid 286.75978 -94.037649)
		(end 286.711136 -94.234)
		(width 0.0889)
		(layer "In9.Cu")
		(net "CLK_100M_CPU0_BCLK2_DP")
	)
	(arc
		(start 286.70631 -92.851986)
		(mid 286.75978 -93.047049)
		(end 286.711136 -93.2434)
		(width 0.0889)
		(layer "In9.Cu")
		(net "CLK_100M_CPU0_BCLK2_DP")
	)
	(arc
		(start 286.70631 -91.861386)
		(mid 286.75978 -92.056449)
		(end 286.711136 -92.2528)
		(width 0.0889)
		(layer "In9.Cu")
		(net "CLK_100M_CPU0_BCLK2_DP")
	)
	(arc
		(start 284.989524 -99.195636)
		(mid 284.847841 -99.33944)
		(end 284.65399 -99.395788)
		(width 0.0889)
		(layer "In9.Cu")
		(net "CLK_100M_CPU0_BCLK2_DP")
	)
	(arc
		(start 286.69996 -92.272104)
		(mid 286.627162 -92.562867)
		(end 286.70631 -92.851986)
		(width 0.0889)
		(layer "In9.Cu")
		(net "CLK_100M_CPU0_BCLK2_DP")
	)
	(arc
		(start 286.70631 -90.870786)
		(mid 286.75978 -91.065849)
		(end 286.711136 -91.2622)
		(width 0.0889)
		(layer "In9.Cu")
		(net "CLK_100M_CPU0_BCLK2_DP")
	)
	(arc
		(start 286.70631 -94.242636)
		(mid 286.627088 -94.531754)
		(end 286.69996 -94.822518)
		(width 0.0889)
		(layer "In9.Cu")
		(net "CLK_100M_CPU0_BCLK2_DP")
	)
	(arc
		(start 284.621224 -99.395788)
		(mid 284.338007 -99.480069)
		(end 284.131004 -99.690936)
		(width 0.0889)
		(layer "In9.Cu")
		(net "CLK_100M_CPU0_BCLK2_DP")
	)
	(arc
		(start 286.70631 -89.880186)
		(mid 286.75978 -90.075249)
		(end 286.711136 -90.2716)
		(width 0.0889)
		(layer "In9.Cu")
		(net "CLK_100M_CPU0_BCLK2_DP")
	)
	(arc
		(start 286.69996 -97.225104)
		(mid 286.627162 -97.515867)
		(end 286.70631 -97.804986)
		(width 0.0889)
		(layer "In9.Cu")
		(net "CLK_100M_CPU0_BCLK2_DP")
	)
	(arc
		(start 284.131004 -99.690936)
		(mid 283.990925 -99.833672)
		(end 283.79928 -99.890834)
		(width 0.0889)
		(layer "In9.Cu")
		(net "CLK_100M_CPU0_BCLK2_DP")
	)
	(arc
		(start 285.483554 -98.900234)
		(mid 285.19813 -98.983701)
		(end 284.989524 -99.195636)
		(width 0.0889)
		(layer "In9.Cu")
		(net "CLK_100M_CPU0_BCLK2_DP")
	)
	(arc
		(start 282.907994 -100.386134)
		(mid 282.62257 -100.469601)
		(end 282.413964 -100.681536)
		(width 0.0889)
		(layer "In9.Cu")
		(net "CLK_100M_CPU0_BCLK2_DP")
	)
	(arc
		(start 286.69996 -93.262704)
		(mid 286.627162 -93.553467)
		(end 286.70631 -93.842586)
		(width 0.0889)
		(layer "In9.Cu")
		(net "CLK_100M_CPU0_BCLK2_DP")
	)
	(arc
		(start 286.334708 -98.405188)
		(mid 286.053408 -98.490154)
		(end 285.84779 -98.700082)
		(width 0.0889)
		(layer "In9.Cu")
		(net "CLK_100M_CPU0_BCLK2_DP")
	)
	(arc
		(start 286.69996 -91.281504)
		(mid 286.627162 -91.572267)
		(end 286.70631 -91.861386)
		(width 0.0889)
		(layer "In9.Cu")
		(net "CLK_100M_CPU0_BCLK2_DP")
	)
	(arc
		(start 283.766514 -99.890834)
		(mid 283.48109 -99.974301)
		(end 283.272484 -100.186236)
		(width 0.0889)
		(layer "In9.Cu")
		(net "CLK_100M_CPU0_BCLK2_DP")
	)
	(arc
		(start 286.70631 -96.814386)
		(mid 286.75978 -97.009449)
		(end 286.711136 -97.2058)
		(width 0.0889)
		(layer "In9.Cu")
		(net "CLK_100M_CPU0_BCLK2_DP")
	)
	(arc
		(start 286.731456 -88.94191)
		(mid 286.759026 -89.113713)
		(end 286.711136 -89.281)
		(width 0.0889)
		(layer "In9.Cu")
		(net "CLK_100M_CPU0_BCLK2_DP")
	)
	(arc
		(start 286.70631 -95.823786)
		(mid 286.75978 -96.018849)
		(end 286.711136 -96.2152)
		(width 0.0889)
		(layer "In9.Cu")
		(net "CLK_100M_CPU0_BCLK2_DP")
	)
	(arc
		(start 285.844488 -98.705924)
		(mid 285.698522 -98.848323)
		(end 285.501334 -98.900234)
		(width 0.0889)
		(layer "In9.Cu")
		(net "CLK_100M_CPU0_BCLK2_DP")
	)
	(arc
		(start 286.69996 -96.234504)
		(mid 286.627162 -96.525267)
		(end 286.70631 -96.814386)
		(width 0.0889)
		(layer "In9.Cu")
		(net "CLK_100M_CPU0_BCLK2_DP")
	)
	(arc
		(start 286.70631 -95.232982)
		(mid 286.627179 -95.528384)
		(end 286.70631 -95.823786)
		(width 0.0889)
		(layer "In9.Cu")
		(net "CLK_100M_CPU0_BCLK2_DP")
	)
	(arc
		(start 286.70631 -97.804986)
		(mid 286.709058 -98.200453)
		(end 286.370776 -98.405188)
		(width 0.0889)
		(layer "In9.Cu")
		(net "CLK_100M_CPU0_BCLK2_DP")
	)
	(arc
		(start 286.69996 -89.300304)
		(mid 286.627162 -89.591067)
		(end 286.70631 -89.880186)
		(width 0.0889)
		(layer "In9.Cu")
		(net "CLK_100M_CPU0_BCLK2_DP")
	)
	(arc
		(start 286.70631 -94.833186)
		(mid 286.759809 -95.033084)
		(end 286.70631 -95.232982)
		(width 0.0889)
		(layer "In9.Cu")
		(net "CLK_100M_CPU0_BCLK2_DP")
	)
	(arc
		(start 283.272484 -100.186236)
		(mid 283.13374 -100.328269)
		(end 282.943808 -100.386134)
		(width 0.0889)
		(layer "In9.Cu")
		(net "CLK_100M_CPU0_BCLK2_DP")
	)
	(segment
		(start 176.276 -82.267552)
		(end 176.380902 -82.16265)
		(width 0.1143)
		(layer "F.Cu")
		(net "CLK_100M_CPU0_BCLK2_DN")
	)
	(segment
		(start 177.071274 -82.16265)
		(end 177.170334 -82.26171)
		(width 0.1143)
		(layer "F.Cu")
		(net "CLK_100M_CPU0_BCLK2_DN")
	)
	(segment
		(start 177.170334 -82.26171)
		(end 177.170334 -82.677)
		(width 0.1143)
		(layer "F.Cu")
		(net "CLK_100M_CPU0_BCLK2_DN")
	)
	(segment
		(start 287.21812 -88.594184)
		(end 286.64662 -88.594184)
		(width 0.1143)
		(layer "F.Cu")
		(net "CLK_100M_CPU0_BCLK2_DN")
	)
	(segment
		(start 176.276 -82.677)
		(end 176.276 -82.267552)
		(width 0.1143)
		(layer "F.Cu")
		(net "CLK_100M_CPU0_BCLK2_DN")
	)
	(segment
		(start 176.380902 -82.16265)
		(end 177.071274 -82.16265)
		(width 0.1143)
		(layer "F.Cu")
		(net "CLK_100M_CPU0_BCLK2_DN")
	)
	(via
		(at 287.21812 -88.594184)
		(size 0.508)
		(drill 0.254)
		(layers "F.Cu" "B.Cu")
		(net "CLK_100M_CPU0_BCLK2_DN")
	)
	(via
		(at 177.170334 -82.677)
		(size 0.508)
		(drill 0.254)
		(layers "F.Cu" "B.Cu")
		(net "CLK_100M_CPU0_BCLK2_DN")
	)
	(segment
		(start 176.738534 -82.194146)
		(end 176.929034 -82.194146)
		(width 0.1143)
		(layer "B.Cu")
		(net "CLK_100M_CPU0_BCLK2_DN")
	)
	(segment
		(start 177.170334 -82.435446)
		(end 177.170334 -82.677)
		(width 0.1143)
		(layer "B.Cu")
		(net "CLK_100M_CPU0_BCLK2_DN")
	)
	(segment
		(start 176.25568 -82.677)
		(end 176.738534 -82.194146)
		(width 0.1143)
		(layer "B.Cu")
		(net "CLK_100M_CPU0_BCLK2_DN")
	)
	(segment
		(start 176.929034 -82.194146)
		(end 177.170334 -82.435446)
		(width 0.1143)
		(layer "B.Cu")
		(net "CLK_100M_CPU0_BCLK2_DN")
	)
	(segment
		(start 266.91209 -104.3305)
		(end 265.61542 -103.03383)
		(width 0.1143)
		(layer "In9.Cu")
		(net "CLK_100M_CPU0_BCLK2_DN")
	)
	(segment
		(start 227.460556 -101.67239)
		(end 226.379278 -102.753414)
		(width 0.1143)
		(layer "In9.Cu")
		(net "CLK_100M_CPU0_BCLK2_DN")
	)
	(segment
		(start 193.288412 -103.338884)
		(end 192.479168 -102.52964)
		(width 0.1143)
		(layer "In9.Cu")
		(net "CLK_100M_CPU0_BCLK2_DN")
	)
	(segment
		(start 286.87141 -97.309686)
		(end 286.866584 -97.318322)
		(width 0.0889)
		(layer "In9.Cu")
		(net "CLK_100M_CPU0_BCLK2_DN")
	)
	(segment
		(start 283.805884 -100.081334)
		(end 283.773118 -100.081334)
		(width 0.0889)
		(layer "In9.Cu")
		(net "CLK_100M_CPU0_BCLK2_DN")
	)
	(segment
		(start 180.057806 -93.272864)
		(end 180.057806 -84.545932)
		(width 0.1143)
		(layer "In9.Cu")
		(net "CLK_100M_CPU0_BCLK2_DN")
	)
	(segment
		(start 286.87141 -92.356686)
		(end 286.866584 -92.365322)
		(width 0.0889)
		(layer "In9.Cu")
		(net "CLK_100M_CPU0_BCLK2_DN")
	)
	(segment
		(start 177.687224 -82.17535)
		(end 177.284888 -82.17535)
		(width 0.1143)
		(layer "In9.Cu")
		(net "CLK_100M_CPU0_BCLK2_DN")
	)
	(segment
		(start 279.189688 -104.3305)
		(end 266.91209 -104.3305)
		(width 0.1143)
		(layer "In9.Cu")
		(net "CLK_100M_CPU0_BCLK2_DN")
	)
	(segment
		(start 250.743466 -100.9523)
		(end 247.440958 -100.9523)
		(width 0.1143)
		(layer "In9.Cu")
		(net "CLK_100M_CPU0_BCLK2_DN")
	)
	(segment
		(start 228.110288 -103.29799)
		(end 227.825046 -103.012748)
		(width 0.1143)
		(layer "In9.Cu")
		(net "CLK_100M_CPU0_BCLK2_DN")
	)
	(segment
		(start 197.59676 -103.36784)
		(end 196.8246 -104.14)
		(width 0.1143)
		(layer "In9.Cu")
		(net "CLK_100M_CPU0_BCLK2_DN")
	)
	(segment
		(start 177.170334 -82.289904)
		(end 177.170334 -82.677)
		(width 0.1143)
		(layer "In9.Cu")
		(net "CLK_100M_CPU0_BCLK2_DN")
	)
	(segment
		(start 282.579064 -100.776786)
		(end 282.453842 -100.99421)
		(width 0.0889)
		(layer "In9.Cu")
		(net "CLK_100M_CPU0_BCLK2_DN")
	)
	(segment
		(start 286.87776 -93.336618)
		(end 286.87141 -93.347286)
		(width 0.0889)
		(layer "In9.Cu")
		(net "CLK_100M_CPU0_BCLK2_DN")
	)
	(segment
		(start 286.87141 -93.347286)
		(end 286.866584 -93.355922)
		(width 0.0889)
		(layer "In9.Cu")
		(net "CLK_100M_CPU0_BCLK2_DN")
	)
	(segment
		(start 280.533856 -102.986332)
		(end 280.518362 -103.001826)
		(width 0.0889)
		(layer "In9.Cu")
		(net "CLK_100M_CPU0_BCLK2_DN")
	)
	(segment
		(start 286.37738 -98.595688)
		(end 286.3596 -98.595688)
		(width 0.0889)
		(layer "In9.Cu")
		(net "CLK_100M_CPU0_BCLK2_DN")
	)
	(segment
		(start 282.453842 -100.99421)
		(end 280.533856 -102.914196)
		(width 0.0889)
		(layer "In9.Cu")
		(net "CLK_100M_CPU0_BCLK2_DN")
	)
	(segment
		(start 286.87776 -90.364818)
		(end 286.87141 -90.375486)
		(width 0.0889)
		(layer "In9.Cu")
		(net "CLK_100M_CPU0_BCLK2_DN")
	)
	(segment
		(start 180.057806 -84.545932)
		(end 177.687224 -82.17535)
		(width 0.1143)
		(layer "In9.Cu")
		(net "CLK_100M_CPU0_BCLK2_DN")
	)
	(segment
		(start 247.125744 -101.26726)
		(end 242.221258 -103.29799)
		(width 0.1143)
		(layer "In9.Cu")
		(net "CLK_100M_CPU0_BCLK2_DN")
	)
	(segment
		(start 226.379278 -102.753414)
		(end 210.63585 -106.3625)
		(width 0.1143)
		(layer "In9.Cu")
		(net "CLK_100M_CPU0_BCLK2_DN")
	)
	(segment
		(start 286.87141 -96.319086)
		(end 286.866584 -96.327722)
		(width 0.0889)
		(layer "In9.Cu")
		(net "CLK_100M_CPU0_BCLK2_DN")
	)
	(segment
		(start 242.221258 -103.29799)
		(end 228.110288 -103.29799)
		(width 0.1143)
		(layer "In9.Cu")
		(net "CLK_100M_CPU0_BCLK2_DN")
	)
	(segment
		(start 286.87776 -96.308418)
		(end 286.87141 -96.319086)
		(width 0.0889)
		(layer "In9.Cu")
		(net "CLK_100M_CPU0_BCLK2_DN")
	)
	(segment
		(start 252.824996 -103.03383)
		(end 250.743466 -100.9523)
		(width 0.1143)
		(layer "In9.Cu")
		(net "CLK_100M_CPU0_BCLK2_DN")
	)
	(segment
		(start 285.526226 -99.090734)
		(end 285.490158 -99.090734)
		(width 0.0889)
		(layer "In9.Cu")
		(net "CLK_100M_CPU0_BCLK2_DN")
	)
	(segment
		(start 280.518362 -103.001826)
		(end 279.189688 -104.3305)
		(width 0.1143)
		(layer "In9.Cu")
		(net "CLK_100M_CPU0_BCLK2_DN")
	)
	(segment
		(start 286.87141 -90.375486)
		(end 286.866584 -90.384122)
		(width 0.0889)
		(layer "In9.Cu")
		(net "CLK_100M_CPU0_BCLK2_DN")
	)
	(segment
		(start 286.87776 -92.346018)
		(end 286.87141 -92.356686)
		(width 0.0889)
		(layer "In9.Cu")
		(net "CLK_100M_CPU0_BCLK2_DN")
	)
	(segment
		(start 177.284888 -82.17535)
		(end 177.170334 -82.289904)
		(width 0.1143)
		(layer "In9.Cu")
		(net "CLK_100M_CPU0_BCLK2_DN")
	)
	(segment
		(start 286.87141 -89.384886)
		(end 286.866584 -89.393522)
		(width 0.0889)
		(layer "In9.Cu")
		(net "CLK_100M_CPU0_BCLK2_DN")
	)
	(segment
		(start 286.87141 -91.366086)
		(end 286.866584 -91.374722)
		(width 0.0889)
		(layer "In9.Cu")
		(net "CLK_100M_CPU0_BCLK2_DN")
	)
	(segment
		(start 230.75646 -101.67239)
		(end 227.460556 -101.67239)
		(width 0.1143)
		(layer "In9.Cu")
		(net "CLK_100M_CPU0_BCLK2_DN")
	)
	(segment
		(start 286.87776 -97.299018)
		(end 286.87141 -97.309686)
		(width 0.0889)
		(layer "In9.Cu")
		(net "CLK_100M_CPU0_BCLK2_DN")
	)
	(segment
		(start 280.533856 -102.914196)
		(end 280.533856 -102.986332)
		(width 0.0889)
		(layer "In9.Cu")
		(net "CLK_100M_CPU0_BCLK2_DN")
	)
	(segment
		(start 230.87076 -102.07879)
		(end 230.87076 -101.78669)
		(width 0.1143)
		(layer "In9.Cu")
		(net "CLK_100M_CPU0_BCLK2_DN")
	)
	(segment
		(start 282.943554 -100.576888)
		(end 282.90774 -100.576888)
		(width 0.0889)
		(layer "In9.Cu")
		(net "CLK_100M_CPU0_BCLK2_DN")
	)
	(segment
		(start 286.87141 -94.737936)
		(end 286.87776 -94.748604)
		(width 0.0889)
		(layer "In9.Cu")
		(net "CLK_100M_CPU0_BCLK2_DN")
	)
	(segment
		(start 230.87076 -101.78669)
		(end 230.75646 -101.67239)
		(width 0.1143)
		(layer "In9.Cu")
		(net "CLK_100M_CPU0_BCLK2_DN")
	)
	(segment
		(start 195.473066 -104.14)
		(end 194.67195 -103.338884)
		(width 0.1143)
		(layer "In9.Cu")
		(net "CLK_100M_CPU0_BCLK2_DN")
	)
	(segment
		(start 194.67195 -103.338884)
		(end 193.288412 -103.338884)
		(width 0.1143)
		(layer "In9.Cu")
		(net "CLK_100M_CPU0_BCLK2_DN")
	)
	(segment
		(start 203.228448 -106.3625)
		(end 200.233788 -103.36784)
		(width 0.1143)
		(layer "In9.Cu")
		(net "CLK_100M_CPU0_BCLK2_DN")
	)
	(segment
		(start 265.61542 -103.03383)
		(end 252.824996 -103.03383)
		(width 0.1143)
		(layer "In9.Cu")
		(net "CLK_100M_CPU0_BCLK2_DN")
	)
	(segment
		(start 227.825046 -103.012748)
		(end 227.825046 -102.478332)
		(width 0.1143)
		(layer "In9.Cu")
		(net "CLK_100M_CPU0_BCLK2_DN")
	)
	(segment
		(start 286.016446 -98.789998)
		(end 286.013144 -98.79584)
		(width 0.0889)
		(layer "In9.Cu")
		(net "CLK_100M_CPU0_BCLK2_DN")
	)
	(segment
		(start 227.825046 -102.478332)
		(end 228.110288 -102.19309)
		(width 0.1143)
		(layer "In9.Cu")
		(net "CLK_100M_CPU0_BCLK2_DN")
	)
	(segment
		(start 287.21812 -88.594184)
		(end 286.925004 -88.763348)
		(width 0.0889)
		(layer "In9.Cu")
		(net "CLK_100M_CPU0_BCLK2_DN")
	)
	(segment
		(start 200.233788 -103.36784)
		(end 197.59676 -103.36784)
		(width 0.1143)
		(layer "In9.Cu")
		(net "CLK_100M_CPU0_BCLK2_DN")
	)
	(segment
		(start 196.8246 -104.14)
		(end 195.473066 -104.14)
		(width 0.1143)
		(layer "In9.Cu")
		(net "CLK_100M_CPU0_BCLK2_DN")
	)
	(segment
		(start 286.87776 -89.374218)
		(end 286.87141 -89.384886)
		(width 0.0889)
		(layer "In9.Cu")
		(net "CLK_100M_CPU0_BCLK2_DN")
	)
	(segment
		(start 286.925004 -88.763348)
		(end 286.901128 -88.852756)
		(width 0.0889)
		(layer "In9.Cu")
		(net "CLK_100M_CPU0_BCLK2_DN")
	)
	(segment
		(start 228.110288 -102.19309)
		(end 230.75646 -102.19309)
		(width 0.1143)
		(layer "In9.Cu")
		(net "CLK_100M_CPU0_BCLK2_DN")
	)
	(segment
		(start 286.87776 -91.355418)
		(end 286.87141 -91.366086)
		(width 0.0889)
		(layer "In9.Cu")
		(net "CLK_100M_CPU0_BCLK2_DN")
	)
	(segment
		(start 210.63585 -106.3625)
		(end 203.228448 -106.3625)
		(width 0.1143)
		(layer "In9.Cu")
		(net "CLK_100M_CPU0_BCLK2_DN")
	)
	(segment
		(start 192.479168 -102.52964)
		(end 189.314582 -102.52964)
		(width 0.1143)
		(layer "In9.Cu")
		(net "CLK_100M_CPU0_BCLK2_DN")
	)
	(segment
		(start 284.660594 -99.586288)
		(end 284.627828 -99.586288)
		(width 0.0889)
		(layer "In9.Cu")
		(net "CLK_100M_CPU0_BCLK2_DN")
	)
	(segment
		(start 230.75646 -102.19309)
		(end 230.87076 -102.07879)
		(width 0.1143)
		(layer "In9.Cu")
		(net "CLK_100M_CPU0_BCLK2_DN")
	)
	(segment
		(start 247.440958 -100.9523)
		(end 247.125744 -101.26726)
		(width 0.1143)
		(layer "In9.Cu")
		(net "CLK_100M_CPU0_BCLK2_DN")
	)
	(segment
		(start 189.314582 -102.52964)
		(end 180.057806 -93.272864)
		(width 0.1143)
		(layer "In9.Cu")
		(net "CLK_100M_CPU0_BCLK2_DN")
	)
	(segment
		(start 286.87141 -95.328486)
		(end 286.866584 -95.337122)
		(width 0.0889)
		(layer "In9.Cu")
		(net "CLK_100M_CPU0_BCLK2_DN")
	)
	(arc
		(start 286.866584 -90.384122)
		(mid 286.817829 -90.580474)
		(end 286.87141 -90.775536)
		(width 0.0889)
		(layer "In9.Cu")
		(net "CLK_100M_CPU0_BCLK2_DN")
	)
	(arc
		(start 284.296104 -99.786186)
		(mid 284.0891 -99.99705)
		(end 283.805884 -100.081334)
		(width 0.0889)
		(layer "In9.Cu")
		(net "CLK_100M_CPU0_BCLK2_DN")
	)
	(arc
		(start 284.627828 -99.586288)
		(mid 284.436186 -99.643454)
		(end 284.296104 -99.786186)
		(width 0.0889)
		(layer "In9.Cu")
		(net "CLK_100M_CPU0_BCLK2_DN")
	)
	(arc
		(start 286.013144 -98.79584)
		(mid 285.807523 -99.005763)
		(end 285.526226 -99.090734)
		(width 0.0889)
		(layer "In9.Cu")
		(net "CLK_100M_CPU0_BCLK2_DN")
	)
	(arc
		(start 286.87141 -95.728536)
		(mid 286.950632 -96.017654)
		(end 286.87776 -96.308418)
		(width 0.0889)
		(layer "In9.Cu")
		(net "CLK_100M_CPU0_BCLK2_DN")
	)
	(arc
		(start 286.87141 -94.33814)
		(mid 286.817911 -94.538038)
		(end 286.87141 -94.737936)
		(width 0.0889)
		(layer "In9.Cu")
		(net "CLK_100M_CPU0_BCLK2_DN")
	)
	(arc
		(start 286.87141 -89.784936)
		(mid 286.950632 -90.074054)
		(end 286.87776 -90.364818)
		(width 0.0889)
		(layer "In9.Cu")
		(net "CLK_100M_CPU0_BCLK2_DN")
	)
	(arc
		(start 286.87141 -96.719136)
		(mid 286.950632 -97.008254)
		(end 286.87776 -97.299018)
		(width 0.0889)
		(layer "In9.Cu")
		(net "CLK_100M_CPU0_BCLK2_DN")
	)
	(arc
		(start 286.866584 -89.393522)
		(mid 286.817829 -89.589874)
		(end 286.87141 -89.784936)
		(width 0.0889)
		(layer "In9.Cu")
		(net "CLK_100M_CPU0_BCLK2_DN")
	)
	(arc
		(start 286.866584 -91.374722)
		(mid 286.817829 -91.571074)
		(end 286.87141 -91.766136)
		(width 0.0889)
		(layer "In9.Cu")
		(net "CLK_100M_CPU0_BCLK2_DN")
	)
	(arc
		(start 286.866584 -92.365322)
		(mid 286.817829 -92.561674)
		(end 286.87141 -92.756736)
		(width 0.0889)
		(layer "In9.Cu")
		(net "CLK_100M_CPU0_BCLK2_DN")
	)
	(arc
		(start 286.866584 -96.327722)
		(mid 286.817829 -96.524074)
		(end 286.87141 -96.719136)
		(width 0.0889)
		(layer "In9.Cu")
		(net "CLK_100M_CPU0_BCLK2_DN")
	)
	(arc
		(start 286.866584 -97.318322)
		(mid 286.817829 -97.514674)
		(end 286.87141 -97.709736)
		(width 0.0889)
		(layer "In9.Cu")
		(net "CLK_100M_CPU0_BCLK2_DN")
	)
	(arc
		(start 286.3596 -98.595688)
		(mid 286.162439 -98.647647)
		(end 286.016446 -98.789998)
		(width 0.0889)
		(layer "In9.Cu")
		(net "CLK_100M_CPU0_BCLK2_DN")
	)
	(arc
		(start 286.866584 -93.355922)
		(mid 286.817829 -93.552274)
		(end 286.87141 -93.747336)
		(width 0.0889)
		(layer "In9.Cu")
		(net "CLK_100M_CPU0_BCLK2_DN")
	)
	(arc
		(start 286.901128 -88.852756)
		(mid 286.95014 -89.116205)
		(end 286.87776 -89.374218)
		(width 0.0889)
		(layer "In9.Cu")
		(net "CLK_100M_CPU0_BCLK2_DN")
	)
	(arc
		(start 286.87141 -97.709736)
		(mid 286.875739 -98.292908)
		(end 286.37738 -98.595688)
		(width 0.0889)
		(layer "In9.Cu")
		(net "CLK_100M_CPU0_BCLK2_DN")
	)
	(arc
		(start 286.866584 -95.337122)
		(mid 286.817829 -95.533474)
		(end 286.87141 -95.728536)
		(width 0.0889)
		(layer "In9.Cu")
		(net "CLK_100M_CPU0_BCLK2_DN")
	)
	(arc
		(start 286.87776 -94.748604)
		(mid 286.950558 -95.039367)
		(end 286.87141 -95.328486)
		(width 0.0889)
		(layer "In9.Cu")
		(net "CLK_100M_CPU0_BCLK2_DN")
	)
	(arc
		(start 286.87141 -91.766136)
		(mid 286.950632 -92.055254)
		(end 286.87776 -92.346018)
		(width 0.0889)
		(layer "In9.Cu")
		(net "CLK_100M_CPU0_BCLK2_DN")
	)
	(arc
		(start 285.490158 -99.090734)
		(mid 285.296308 -99.147084)
		(end 285.154624 -99.290886)
		(width 0.0889)
		(layer "In9.Cu")
		(net "CLK_100M_CPU0_BCLK2_DN")
	)
	(arc
		(start 285.154624 -99.290886)
		(mid 284.946016 -99.502818)
		(end 284.660594 -99.586288)
		(width 0.0889)
		(layer "In9.Cu")
		(net "CLK_100M_CPU0_BCLK2_DN")
	)
	(arc
		(start 286.87141 -90.775536)
		(mid 286.950632 -91.064654)
		(end 286.87776 -91.355418)
		(width 0.0889)
		(layer "In9.Cu")
		(net "CLK_100M_CPU0_BCLK2_DN")
	)
	(arc
		(start 286.87141 -92.756736)
		(mid 286.950632 -93.045854)
		(end 286.87776 -93.336618)
		(width 0.0889)
		(layer "In9.Cu")
		(net "CLK_100M_CPU0_BCLK2_DN")
	)
	(arc
		(start 286.87141 -93.747336)
		(mid 286.950541 -94.042738)
		(end 286.87141 -94.33814)
		(width 0.0889)
		(layer "In9.Cu")
		(net "CLK_100M_CPU0_BCLK2_DN")
	)
	(arc
		(start 283.773118 -100.081334)
		(mid 283.579268 -100.137684)
		(end 283.437584 -100.281486)
		(width 0.0889)
		(layer "In9.Cu")
		(net "CLK_100M_CPU0_BCLK2_DN")
	)
	(arc
		(start 283.437584 -100.281486)
		(mid 283.228976 -100.493418)
		(end 282.943554 -100.576888)
		(width 0.0889)
		(layer "In9.Cu")
		(net "CLK_100M_CPU0_BCLK2_DN")
	)
	(arc
		(start 282.90774 -100.576888)
		(mid 282.717811 -100.634758)
		(end 282.579064 -100.776786)
		(width 0.0889)
		(layer "In9.Cu")
		(net "CLK_100M_CPU0_BCLK2_DN")
	)
	(segment
		(start 178.054 -77.978)
		(end 178.054 -78.867)
		(width 0.1143)
		(layer "F.Cu")
		(net "CLK_100M_CPU0_BCLK1_DP")
	)
	(segment
		(start 178.918616 -79.307436)
		(end 178.800252 -79.4258)
		(width 0.1143)
		(layer "F.Cu")
		(net "CLK_100M_CPU0_BCLK1_DP")
	)
	(segment
		(start 178.918616 -78.96225)
		(end 178.918616 -79.307436)
		(width 0.1143)
		(layer "F.Cu")
		(net "CLK_100M_CPU0_BCLK1_DP")
	)
	(segment
		(start 285.501334 -87.603584)
		(end 284.929834 -87.603584)
		(width 0.1143)
		(layer "F.Cu")
		(net "CLK_100M_CPU0_BCLK1_DP")
	)
	(segment
		(start 178.054 -78.9051)
		(end 178.054 -78.867)
		(width 0.1143)
		(layer "F.Cu")
		(net "CLK_100M_CPU0_BCLK1_DP")
	)
	(segment
		(start 178.800252 -79.4258)
		(end 178.5747 -79.4258)
		(width 0.1143)
		(layer "F.Cu")
		(net "CLK_100M_CPU0_BCLK1_DP")
	)
	(segment
		(start 178.5747 -79.4258)
		(end 178.054 -78.9051)
		(width 0.1143)
		(layer "F.Cu")
		(net "CLK_100M_CPU0_BCLK1_DP")
	)
	(via
		(at 285.501334 -87.603584)
		(size 0.508)
		(drill 0.254)
		(layers "F.Cu" "B.Cu")
		(net "CLK_100M_CPU0_BCLK1_DP")
	)
	(via
		(at 178.918616 -78.96225)
		(size 0.508)
		(drill 0.254)
		(layers "F.Cu" "B.Cu")
		(net "CLK_100M_CPU0_BCLK1_DP")
	)
	(segment
		(start 276.352508 -101.755956)
		(end 275.428964 -102.6795)
		(width 0.1143)
		(layer "In9.Cu")
		(net "CLK_100M_CPU0_BCLK1_DP")
	)
	(segment
		(start 285.501334 -87.603584)
		(end 285.794196 -87.772494)
		(width 0.0889)
		(layer "In9.Cu")
		(net "CLK_100M_CPU0_BCLK1_DP")
	)
	(segment
		(start 213.46795 -104.53624)
		(end 204.352906 -104.53624)
		(width 0.1143)
		(layer "In9.Cu")
		(net "CLK_100M_CPU0_BCLK1_DP")
	)
	(segment
		(start 283.79928 -98.900234)
		(end 283.766514 -98.900234)
		(width 0.0889)
		(layer "In9.Cu")
		(net "CLK_100M_CPU0_BCLK1_DP")
	)
	(segment
		(start 195.108322 -102.195122)
		(end 193.702178 -102.195122)
		(width 0.1143)
		(layer "In9.Cu")
		(net "CLK_100M_CPU0_BCLK1_DP")
	)
	(segment
		(start 189.758066 -101.416866)
		(end 182.232046 -93.890846)
		(width 0.1143)
		(layer "In9.Cu")
		(net "CLK_100M_CPU0_BCLK1_DP")
	)
	(segment
		(start 228.869494 -100.364544)
		(end 228.869494 -100.072444)
		(width 0.1143)
		(layer "In9.Cu")
		(net "CLK_100M_CPU0_BCLK1_DP")
	)
	(segment
		(start 285.84144 -94.327472)
		(end 285.84779 -94.33814)
		(width 0.0889)
		(layer "In9.Cu")
		(net "CLK_100M_CPU0_BCLK1_DP")
	)
	(segment
		(start 273.346164 -102.6795)
		(end 267.6271 -102.6795)
		(width 0.1143)
		(layer "In9.Cu")
		(net "CLK_100M_CPU0_BCLK1_DP")
	)
	(segment
		(start 231.500172 -100.478844)
		(end 228.983794 -100.478844)
		(width 0.1143)
		(layer "In9.Cu")
		(net "CLK_100M_CPU0_BCLK1_DP")
	)
	(segment
		(start 285.84779 -94.737936)
		(end 285.84144 -94.748604)
		(width 0.0889)
		(layer "In9.Cu")
		(net "CLK_100M_CPU0_BCLK1_DP")
	)
	(segment
		(start 228.869494 -100.072444)
		(end 228.983794 -99.958144)
		(width 0.1143)
		(layer "In9.Cu")
		(net "CLK_100M_CPU0_BCLK1_DP")
	)
	(segment
		(start 274.908264 -102.5144)
		(end 274.552664 -102.5144)
		(width 0.1143)
		(layer "In9.Cu")
		(net "CLK_100M_CPU0_BCLK1_DP")
	)
	(segment
		(start 276.368002 -101.740462)
		(end 276.352508 -101.755956)
		(width 0.0889)
		(layer "In9.Cu")
		(net "CLK_100M_CPU0_BCLK1_DP")
	)
	(segment
		(start 285.501334 -97.909634)
		(end 285.483554 -97.909634)
		(width 0.0889)
		(layer "In9.Cu")
		(net "CLK_100M_CPU0_BCLK1_DP")
	)
	(segment
		(start 201.847958 -103.3399)
		(end 200.796398 -102.28834)
		(width 0.1143)
		(layer "In9.Cu")
		(net "CLK_100M_CPU0_BCLK1_DP")
	)
	(segment
		(start 239.88268 -102.215696)
		(end 233.237024 -102.215696)
		(width 0.1143)
		(layer "In9.Cu")
		(net "CLK_100M_CPU0_BCLK1_DP")
	)
	(segment
		(start 231.043988 -98.853244)
		(end 228.35362 -98.853244)
		(width 0.1143)
		(layer "In9.Cu")
		(net "CLK_100M_CPU0_BCLK1_DP")
	)
	(segment
		(start 278.073612 -101.376988)
		(end 276.803612 -101.376988)
		(width 0.0889)
		(layer "In9.Cu")
		(net "CLK_100M_CPU0_BCLK1_DP")
	)
	(segment
		(start 179.383436 -79.42707)
		(end 178.918616 -78.96225)
		(width 0.1143)
		(layer "In9.Cu")
		(net "CLK_100M_CPU0_BCLK1_DP")
	)
	(segment
		(start 285.8389 -92.341446)
		(end 285.84779 -92.356686)
		(width 0.0889)
		(layer "In9.Cu")
		(net "CLK_100M_CPU0_BCLK1_DP")
	)
	(segment
		(start 203.156566 -103.3399)
		(end 201.847958 -103.3399)
		(width 0.1143)
		(layer "In9.Cu")
		(net "CLK_100M_CPU0_BCLK1_DP")
	)
	(segment
		(start 273.511264 -102.5144)
		(end 273.346164 -102.6795)
		(width 0.1143)
		(layer "In9.Cu")
		(net "CLK_100M_CPU0_BCLK1_DP")
	)
	(segment
		(start 197.120256 -102.28834)
		(end 196.449696 -102.9589)
		(width 0.1143)
		(layer "In9.Cu")
		(net "CLK_100M_CPU0_BCLK1_DP")
	)
	(segment
		(start 228.983794 -99.958144)
		(end 231.043988 -99.958144)
		(width 0.1143)
		(layer "In9.Cu")
		(net "CLK_100M_CPU0_BCLK1_DP")
	)
	(segment
		(start 274.552664 -102.5144)
		(end 274.387564 -102.6795)
		(width 0.1143)
		(layer "In9.Cu")
		(net "CLK_100M_CPU0_BCLK1_DP")
	)
	(segment
		(start 285.8389 -93.332046)
		(end 285.84779 -93.347286)
		(width 0.0889)
		(layer "In9.Cu")
		(net "CLK_100M_CPU0_BCLK1_DP")
	)
	(segment
		(start 282.08224 -99.890834)
		(end 282.067508 -99.890834)
		(width 0.0889)
		(layer "In9.Cu")
		(net "CLK_100M_CPU0_BCLK1_DP")
	)
	(segment
		(start 285.8389 -88.379046)
		(end 285.84779 -88.394286)
		(width 0.0889)
		(layer "In9.Cu")
		(net "CLK_100M_CPU0_BCLK1_DP")
	)
	(segment
		(start 182.232046 -93.890846)
		(end 182.232046 -81.715356)
		(width 0.1143)
		(layer "In9.Cu")
		(net "CLK_100M_CPU0_BCLK1_DP")
	)
	(segment
		(start 281.093418 -99.891088)
		(end 280.598118 -100.386388)
		(width 0.0889)
		(layer "In9.Cu")
		(net "CLK_100M_CPU0_BCLK1_DP")
	)
	(segment
		(start 193.702178 -102.195122)
		(end 192.923922 -101.416866)
		(width 0.1143)
		(layer "In9.Cu")
		(net "CLK_100M_CPU0_BCLK1_DP")
	)
	(segment
		(start 273.866864 -102.5144)
		(end 273.511264 -102.5144)
		(width 0.1143)
		(layer "In9.Cu")
		(net "CLK_100M_CPU0_BCLK1_DP")
	)
	(segment
		(start 253.510542 -101.092)
		(end 252.342142 -99.9236)
		(width 0.1143)
		(layer "In9.Cu")
		(net "CLK_100M_CPU0_BCLK1_DP")
	)
	(segment
		(start 231.32923 -99.138486)
		(end 231.043988 -98.853244)
		(width 0.1143)
		(layer "In9.Cu")
		(net "CLK_100M_CPU0_BCLK1_DP")
	)
	(segment
		(start 204.352906 -104.53624)
		(end 203.156566 -103.3399)
		(width 0.1143)
		(layer "In9.Cu")
		(net "CLK_100M_CPU0_BCLK1_DP")
	)
	(segment
		(start 182.232046 -81.715356)
		(end 179.94376 -79.42707)
		(width 0.1143)
		(layer "In9.Cu")
		(net "CLK_100M_CPU0_BCLK1_DP")
	)
	(segment
		(start 285.794196 -87.772494)
		(end 285.818072 -87.861902)
		(width 0.0889)
		(layer "In9.Cu")
		(net "CLK_100M_CPU0_BCLK1_DP")
	)
	(segment
		(start 285.8389 -96.303846)
		(end 285.84779 -96.319086)
		(width 0.0889)
		(layer "In9.Cu")
		(net "CLK_100M_CPU0_BCLK1_DP")
	)
	(segment
		(start 274.031964 -102.6795)
		(end 273.866864 -102.5144)
		(width 0.1143)
		(layer "In9.Cu")
		(net "CLK_100M_CPU0_BCLK1_DP")
	)
	(segment
		(start 200.796398 -102.28834)
		(end 197.120256 -102.28834)
		(width 0.1143)
		(layer "In9.Cu")
		(net "CLK_100M_CPU0_BCLK1_DP")
	)
	(segment
		(start 280.598118 -100.386388)
		(end 279.064212 -100.386388)
		(width 0.0889)
		(layer "In9.Cu")
		(net "CLK_100M_CPU0_BCLK1_DP")
	)
	(segment
		(start 179.94376 -79.42707)
		(end 179.383436 -79.42707)
		(width 0.1143)
		(layer "In9.Cu")
		(net "CLK_100M_CPU0_BCLK1_DP")
	)
	(segment
		(start 275.428964 -102.6795)
		(end 275.073364 -102.6795)
		(width 0.1143)
		(layer "In9.Cu")
		(net "CLK_100M_CPU0_BCLK1_DP")
	)
	(segment
		(start 275.073364 -102.6795)
		(end 274.908264 -102.5144)
		(width 0.1143)
		(layer "In9.Cu")
		(net "CLK_100M_CPU0_BCLK1_DP")
	)
	(segment
		(start 267.6271 -102.6795)
		(end 266.0396 -101.092)
		(width 0.1143)
		(layer "In9.Cu")
		(net "CLK_100M_CPU0_BCLK1_DP")
	)
	(segment
		(start 282.93695 -99.395788)
		(end 282.904184 -99.395788)
		(width 0.0889)
		(layer "In9.Cu")
		(net "CLK_100M_CPU0_BCLK1_DP")
	)
	(segment
		(start 246.761254 -99.9236)
		(end 246.050054 -100.6348)
		(width 0.1143)
		(layer "In9.Cu")
		(net "CLK_100M_CPU0_BCLK1_DP")
	)
	(segment
		(start 192.923922 -101.416866)
		(end 189.758066 -101.416866)
		(width 0.1143)
		(layer "In9.Cu")
		(net "CLK_100M_CPU0_BCLK1_DP")
	)
	(segment
		(start 276.803612 -101.376988)
		(end 276.440138 -101.740462)
		(width 0.0889)
		(layer "In9.Cu")
		(net "CLK_100M_CPU0_BCLK1_DP")
	)
	(segment
		(start 246.050054 -100.6348)
		(end 243.707158 -100.6348)
		(width 0.1143)
		(layer "In9.Cu")
		(net "CLK_100M_CPU0_BCLK1_DP")
	)
	(segment
		(start 228.983794 -100.478844)
		(end 228.869494 -100.364544)
		(width 0.1143)
		(layer "In9.Cu")
		(net "CLK_100M_CPU0_BCLK1_DP")
	)
	(segment
		(start 225.60153 -101.60508)
		(end 213.46795 -104.53624)
		(width 0.1143)
		(layer "In9.Cu")
		(net "CLK_100M_CPU0_BCLK1_DP")
	)
	(segment
		(start 285.8389 -89.369646)
		(end 285.84779 -89.384886)
		(width 0.0889)
		(layer "In9.Cu")
		(net "CLK_100M_CPU0_BCLK1_DP")
	)
	(segment
		(start 252.342142 -99.9236)
		(end 246.761254 -99.9236)
		(width 0.1143)
		(layer "In9.Cu")
		(net "CLK_100M_CPU0_BCLK1_DP")
	)
	(segment
		(start 243.707158 -100.6348)
		(end 239.88268 -102.215696)
		(width 0.1143)
		(layer "In9.Cu")
		(net "CLK_100M_CPU0_BCLK1_DP")
	)
	(segment
		(start 276.440138 -101.740462)
		(end 276.368002 -101.740462)
		(width 0.0889)
		(layer "In9.Cu")
		(net "CLK_100M_CPU0_BCLK1_DP")
	)
	(segment
		(start 231.32923 -99.672902)
		(end 231.32923 -99.138486)
		(width 0.1143)
		(layer "In9.Cu")
		(net "CLK_100M_CPU0_BCLK1_DP")
	)
	(segment
		(start 285.8389 -91.350846)
		(end 285.84779 -91.366086)
		(width 0.0889)
		(layer "In9.Cu")
		(net "CLK_100M_CPU0_BCLK1_DP")
	)
	(segment
		(start 284.65399 -98.405188)
		(end 284.621224 -98.405188)
		(width 0.0889)
		(layer "In9.Cu")
		(net "CLK_100M_CPU0_BCLK1_DP")
	)
	(segment
		(start 233.237024 -102.215696)
		(end 231.500172 -100.478844)
		(width 0.1143)
		(layer "In9.Cu")
		(net "CLK_100M_CPU0_BCLK1_DP")
	)
	(segment
		(start 231.043988 -99.958144)
		(end 231.32923 -99.672902)
		(width 0.1143)
		(layer "In9.Cu")
		(net "CLK_100M_CPU0_BCLK1_DP")
	)
	(segment
		(start 282.067508 -99.890834)
		(end 282.067254 -99.891088)
		(width 0.0889)
		(layer "In9.Cu")
		(net "CLK_100M_CPU0_BCLK1_DP")
	)
	(segment
		(start 279.064212 -100.386388)
		(end 278.073612 -101.376988)
		(width 0.0889)
		(layer "In9.Cu")
		(net "CLK_100M_CPU0_BCLK1_DP")
	)
	(segment
		(start 282.067254 -99.891088)
		(end 281.093418 -99.891088)
		(width 0.0889)
		(layer "In9.Cu")
		(net "CLK_100M_CPU0_BCLK1_DP")
	)
	(segment
		(start 285.8389 -97.294446)
		(end 285.84779 -97.309686)
		(width 0.0889)
		(layer "In9.Cu")
		(net "CLK_100M_CPU0_BCLK1_DP")
	)
	(segment
		(start 266.0396 -101.092)
		(end 253.510542 -101.092)
		(width 0.1143)
		(layer "In9.Cu")
		(net "CLK_100M_CPU0_BCLK1_DP")
	)
	(segment
		(start 228.35362 -98.853244)
		(end 225.60153 -101.60508)
		(width 0.1143)
		(layer "In9.Cu")
		(net "CLK_100M_CPU0_BCLK1_DP")
	)
	(segment
		(start 196.449696 -102.9589)
		(end 195.8721 -102.9589)
		(width 0.1143)
		(layer "In9.Cu")
		(net "CLK_100M_CPU0_BCLK1_DP")
	)
	(segment
		(start 195.8721 -102.9589)
		(end 195.108322 -102.195122)
		(width 0.1143)
		(layer "In9.Cu")
		(net "CLK_100M_CPU0_BCLK1_DP")
	)
	(segment
		(start 285.8389 -90.360246)
		(end 285.84779 -90.375486)
		(width 0.0889)
		(layer "In9.Cu")
		(net "CLK_100M_CPU0_BCLK1_DP")
	)
	(segment
		(start 274.387564 -102.6795)
		(end 274.031964 -102.6795)
		(width 0.1143)
		(layer "In9.Cu")
		(net "CLK_100M_CPU0_BCLK1_DP")
	)
	(arc
		(start 285.84779 -97.309686)
		(mid 285.847707 -97.709627)
		(end 285.501334 -97.909634)
		(width 0.0889)
		(layer "In9.Cu")
		(net "CLK_100M_CPU0_BCLK1_DP")
	)
	(arc
		(start 285.84779 -88.394286)
		(mid 285.901323 -88.594184)
		(end 285.84779 -88.794082)
		(width 0.0889)
		(layer "In9.Cu")
		(net "CLK_100M_CPU0_BCLK1_DP")
	)
	(arc
		(start 285.84779 -93.747082)
		(mid 285.768441 -94.036454)
		(end 285.84144 -94.327472)
		(width 0.0889)
		(layer "In9.Cu")
		(net "CLK_100M_CPU0_BCLK1_DP")
	)
	(arc
		(start 284.621224 -98.405188)
		(mid 284.338007 -98.489469)
		(end 284.131004 -98.700336)
		(width 0.0889)
		(layer "In9.Cu")
		(net "CLK_100M_CPU0_BCLK1_DP")
	)
	(arc
		(start 285.84779 -91.366086)
		(mid 285.901323 -91.565984)
		(end 285.84779 -91.765882)
		(width 0.0889)
		(layer "In9.Cu")
		(net "CLK_100M_CPU0_BCLK1_DP")
	)
	(arc
		(start 285.84144 -94.748604)
		(mid 285.768642 -95.039367)
		(end 285.84779 -95.328486)
		(width 0.0889)
		(layer "In9.Cu")
		(net "CLK_100M_CPU0_BCLK1_DP")
	)
	(arc
		(start 285.818072 -87.861902)
		(mid 285.768842 -88.122881)
		(end 285.8389 -88.379046)
		(width 0.0889)
		(layer "In9.Cu")
		(net "CLK_100M_CPU0_BCLK1_DP")
	)
	(arc
		(start 285.84779 -89.784682)
		(mid 285.768601 -90.071297)
		(end 285.8389 -90.360246)
		(width 0.0889)
		(layer "In9.Cu")
		(net "CLK_100M_CPU0_BCLK1_DP")
	)
	(arc
		(start 284.989524 -98.205036)
		(mid 284.847841 -98.34884)
		(end 284.65399 -98.405188)
		(width 0.0889)
		(layer "In9.Cu")
		(net "CLK_100M_CPU0_BCLK1_DP")
	)
	(arc
		(start 285.84779 -95.328486)
		(mid 285.901323 -95.528384)
		(end 285.84779 -95.728282)
		(width 0.0889)
		(layer "In9.Cu")
		(net "CLK_100M_CPU0_BCLK1_DP")
	)
	(arc
		(start 283.766514 -98.900234)
		(mid 283.48109 -98.983701)
		(end 283.272484 -99.195636)
		(width 0.0889)
		(layer "In9.Cu")
		(net "CLK_100M_CPU0_BCLK1_DP")
	)
	(arc
		(start 285.84779 -90.775282)
		(mid 285.768601 -91.061897)
		(end 285.8389 -91.350846)
		(width 0.0889)
		(layer "In9.Cu")
		(net "CLK_100M_CPU0_BCLK1_DP")
	)
	(arc
		(start 285.84779 -88.794082)
		(mid 285.768601 -89.080697)
		(end 285.8389 -89.369646)
		(width 0.0889)
		(layer "In9.Cu")
		(net "CLK_100M_CPU0_BCLK1_DP")
	)
	(arc
		(start 282.904184 -99.395788)
		(mid 282.620967 -99.480069)
		(end 282.413964 -99.690936)
		(width 0.0889)
		(layer "In9.Cu")
		(net "CLK_100M_CPU0_BCLK1_DP")
	)
	(arc
		(start 285.84779 -92.356686)
		(mid 285.901323 -92.556584)
		(end 285.84779 -92.756482)
		(width 0.0889)
		(layer "In9.Cu")
		(net "CLK_100M_CPU0_BCLK1_DP")
	)
	(arc
		(start 285.84779 -95.728282)
		(mid 285.768601 -96.014897)
		(end 285.8389 -96.303846)
		(width 0.0889)
		(layer "In9.Cu")
		(net "CLK_100M_CPU0_BCLK1_DP")
	)
	(arc
		(start 285.84779 -90.375486)
		(mid 285.901323 -90.575384)
		(end 285.84779 -90.775282)
		(width 0.0889)
		(layer "In9.Cu")
		(net "CLK_100M_CPU0_BCLK1_DP")
	)
	(arc
		(start 285.84779 -91.765882)
		(mid 285.768601 -92.052497)
		(end 285.8389 -92.341446)
		(width 0.0889)
		(layer "In9.Cu")
		(net "CLK_100M_CPU0_BCLK1_DP")
	)
	(arc
		(start 283.272484 -99.195636)
		(mid 283.130801 -99.33944)
		(end 282.93695 -99.395788)
		(width 0.0889)
		(layer "In9.Cu")
		(net "CLK_100M_CPU0_BCLK1_DP")
	)
	(arc
		(start 285.84779 -94.33814)
		(mid 285.901323 -94.538038)
		(end 285.84779 -94.737936)
		(width 0.0889)
		(layer "In9.Cu")
		(net "CLK_100M_CPU0_BCLK1_DP")
	)
	(arc
		(start 285.84779 -96.718882)
		(mid 285.768601 -97.005497)
		(end 285.8389 -97.294446)
		(width 0.0889)
		(layer "In9.Cu")
		(net "CLK_100M_CPU0_BCLK1_DP")
	)
	(arc
		(start 285.84779 -89.384886)
		(mid 285.901323 -89.584784)
		(end 285.84779 -89.784682)
		(width 0.0889)
		(layer "In9.Cu")
		(net "CLK_100M_CPU0_BCLK1_DP")
	)
	(arc
		(start 285.483554 -97.909634)
		(mid 285.19813 -97.993101)
		(end 284.989524 -98.205036)
		(width 0.0889)
		(layer "In9.Cu")
		(net "CLK_100M_CPU0_BCLK1_DP")
	)
	(arc
		(start 284.131004 -98.700336)
		(mid 283.990925 -98.843072)
		(end 283.79928 -98.900234)
		(width 0.0889)
		(layer "In9.Cu")
		(net "CLK_100M_CPU0_BCLK1_DP")
	)
	(arc
		(start 285.84779 -92.756482)
		(mid 285.768601 -93.043097)
		(end 285.8389 -93.332046)
		(width 0.0889)
		(layer "In9.Cu")
		(net "CLK_100M_CPU0_BCLK1_DP")
	)
	(arc
		(start 282.413964 -99.690936)
		(mid 282.273885 -99.833672)
		(end 282.08224 -99.890834)
		(width 0.0889)
		(layer "In9.Cu")
		(net "CLK_100M_CPU0_BCLK1_DP")
	)
	(arc
		(start 285.84779 -96.319086)
		(mid 285.901323 -96.518984)
		(end 285.84779 -96.718882)
		(width 0.0889)
		(layer "In9.Cu")
		(net "CLK_100M_CPU0_BCLK1_DP")
	)
	(arc
		(start 285.84779 -93.347286)
		(mid 285.901323 -93.547184)
		(end 285.84779 -93.747082)
		(width 0.0889)
		(layer "In9.Cu")
		(net "CLK_100M_CPU0_BCLK1_DP")
	)
	(segment
		(start 178.774852 -79.6671)
		(end 178.918616 -79.810864)
		(width 0.1143)
		(layer "F.Cu")
		(net "CLK_100M_CPU0_BCLK1_DN")
	)
	(segment
		(start 178.054 -80.137)
		(end 178.5239 -79.6671)
		(width 0.1143)
		(layer "F.Cu")
		(net "CLK_100M_CPU0_BCLK1_DN")
	)
	(segment
		(start 178.918616 -79.810864)
		(end 178.918616 -80.23225)
		(width 0.1143)
		(layer "F.Cu")
		(net "CLK_100M_CPU0_BCLK1_DN")
	)
	(segment
		(start 178.054 -81.026)
		(end 178.054 -80.137)
		(width 0.1143)
		(layer "F.Cu")
		(net "CLK_100M_CPU0_BCLK1_DN")
	)
	(segment
		(start 286.3596 -88.099138)
		(end 285.7881 -88.099138)
		(width 0.1143)
		(layer "F.Cu")
		(net "CLK_100M_CPU0_BCLK1_DN")
	)
	(segment
		(start 178.5239 -79.6671)
		(end 178.774852 -79.6671)
		(width 0.1143)
		(layer "F.Cu")
		(net "CLK_100M_CPU0_BCLK1_DN")
	)
	(via
		(at 178.918616 -80.23225)
		(size 0.508)
		(drill 0.254)
		(layers "F.Cu" "B.Cu")
		(net "CLK_100M_CPU0_BCLK1_DN")
	)
	(via
		(at 286.3596 -88.099138)
		(size 0.508)
		(drill 0.254)
		(layers "F.Cu" "B.Cu")
		(net "CLK_100M_CPU0_BCLK1_DN")
	)
	(segment
		(start 286.3596 -88.099138)
		(end 286.066738 -87.930228)
		(width 0.0889)
		(layer "In9.Cu")
		(net "CLK_100M_CPU0_BCLK1_DN")
	)
	(segment
		(start 225.75012 -101.870002)
		(end 219.603574 -103.354632)
		(width 0.1143)
		(layer "In9.Cu")
		(net "CLK_100M_CPU0_BCLK1_DN")
	)
	(segment
		(start 228.577394 -99.951286)
		(end 228.862636 -99.666044)
		(width 0.1143)
		(layer "In9.Cu")
		(net "CLK_100M_CPU0_BCLK1_DN")
	)
	(segment
		(start 276.55901 -101.962966)
		(end 275.550376 -102.9716)
		(width 0.1143)
		(layer "In9.Cu")
		(net "CLK_100M_CPU0_BCLK1_DN")
	)
	(segment
		(start 283.805884 -99.090734)
		(end 283.773118 -99.090734)
		(width 0.0889)
		(layer "In9.Cu")
		(net "CLK_100M_CPU0_BCLK1_DN")
	)
	(segment
		(start 192.802764 -101.708966)
		(end 189.636908 -101.708966)
		(width 0.1143)
		(layer "In9.Cu")
		(net "CLK_100M_CPU0_BCLK1_DN")
	)
	(segment
		(start 196.570854 -103.251)
		(end 195.750942 -103.251)
		(width 0.1143)
		(layer "In9.Cu")
		(net "CLK_100M_CPU0_BCLK1_DN")
	)
	(segment
		(start 179.822602 -79.71917)
		(end 179.431696 -79.71917)
		(width 0.1143)
		(layer "In9.Cu")
		(net "CLK_100M_CPU0_BCLK1_DN")
	)
	(segment
		(start 285.526226 -98.100134)
		(end 285.490158 -98.100134)
		(width 0.0889)
		(layer "In9.Cu")
		(net "CLK_100M_CPU0_BCLK1_DN")
	)
	(segment
		(start 286.013144 -90.280236)
		(end 286.022034 -90.295476)
		(width 0.0889)
		(layer "In9.Cu")
		(net "CLK_100M_CPU0_BCLK1_DN")
	)
	(segment
		(start 286.013144 -93.252036)
		(end 286.022034 -93.267276)
		(width 0.0889)
		(layer "In9.Cu")
		(net "CLK_100M_CPU0_BCLK1_DN")
	)
	(segment
		(start 286.013144 -97.214436)
		(end 286.022034 -97.229676)
		(width 0.0889)
		(layer "In9.Cu")
		(net "CLK_100M_CPU0_BCLK1_DN")
	)
	(segment
		(start 246.171212 -100.9269)
		(end 243.765324 -100.9269)
		(width 0.1143)
		(layer "In9.Cu")
		(net "CLK_100M_CPU0_BCLK1_DN")
	)
	(segment
		(start 231.03713 -99.259644)
		(end 230.92283 -99.145344)
		(width 0.1143)
		(layer "In9.Cu")
		(net "CLK_100M_CPU0_BCLK1_DN")
	)
	(segment
		(start 252.220984 -100.2157)
		(end 246.882412 -100.2157)
		(width 0.1143)
		(layer "In9.Cu")
		(net "CLK_100M_CPU0_BCLK1_DN")
	)
	(segment
		(start 267.505942 -102.9716)
		(end 265.918442 -101.3841)
		(width 0.1143)
		(layer "In9.Cu")
		(net "CLK_100M_CPU0_BCLK1_DN")
	)
	(segment
		(start 286.013144 -96.223836)
		(end 286.022034 -96.239076)
		(width 0.0889)
		(layer "In9.Cu")
		(net "CLK_100M_CPU0_BCLK1_DN")
	)
	(segment
		(start 286.013144 -89.289636)
		(end 286.022034 -89.304876)
		(width 0.0889)
		(layer "In9.Cu")
		(net "CLK_100M_CPU0_BCLK1_DN")
	)
	(segment
		(start 278.152606 -101.567488)
		(end 276.882606 -101.567488)
		(width 0.0889)
		(layer "In9.Cu")
		(net "CLK_100M_CPU0_BCLK1_DN")
	)
	(segment
		(start 276.882606 -101.567488)
		(end 276.574504 -101.87559)
		(width 0.0889)
		(layer "In9.Cu")
		(net "CLK_100M_CPU0_BCLK1_DN")
	)
	(segment
		(start 204.231748 -104.82834)
		(end 203.035408 -103.632)
		(width 0.1143)
		(layer "In9.Cu")
		(net "CLK_100M_CPU0_BCLK1_DN")
	)
	(segment
		(start 219.603574 -103.354632)
		(end 219.60332 -103.354632)
		(width 0.1143)
		(layer "In9.Cu")
		(net "CLK_100M_CPU0_BCLK1_DN")
	)
	(segment
		(start 276.574504 -101.947472)
		(end 276.55901 -101.962966)
		(width 0.0889)
		(layer "In9.Cu")
		(net "CLK_100M_CPU0_BCLK1_DN")
	)
	(segment
		(start 284.660594 -98.595688)
		(end 284.627828 -98.595688)
		(width 0.0889)
		(layer "In9.Cu")
		(net "CLK_100M_CPU0_BCLK1_DN")
	)
	(segment
		(start 239.940846 -102.507796)
		(end 233.115866 -102.507796)
		(width 0.1143)
		(layer "In9.Cu")
		(net "CLK_100M_CPU0_BCLK1_DN")
	)
	(segment
		(start 275.550376 -102.9716)
		(end 267.505942 -102.9716)
		(width 0.1143)
		(layer "In9.Cu")
		(net "CLK_100M_CPU0_BCLK1_DN")
	)
	(segment
		(start 286.013144 -88.299036)
		(end 286.022034 -88.314276)
		(width 0.0889)
		(layer "In9.Cu")
		(net "CLK_100M_CPU0_BCLK1_DN")
	)
	(segment
		(start 228.474778 -99.145344)
		(end 225.75012 -101.870002)
		(width 0.1143)
		(layer "In9.Cu")
		(net "CLK_100M_CPU0_BCLK1_DN")
	)
	(segment
		(start 203.035408 -103.632)
		(end 201.7268 -103.632)
		(width 0.1143)
		(layer "In9.Cu")
		(net "CLK_100M_CPU0_BCLK1_DN")
	)
	(segment
		(start 286.066738 -87.930228)
		(end 285.987998 -87.951564)
		(width 0.0889)
		(layer "In9.Cu")
		(net "CLK_100M_CPU0_BCLK1_DN")
	)
	(segment
		(start 197.241414 -102.58044)
		(end 196.570854 -103.251)
		(width 0.1143)
		(layer "In9.Cu")
		(net "CLK_100M_CPU0_BCLK1_DN")
	)
	(segment
		(start 276.574504 -101.87559)
		(end 276.574504 -101.947472)
		(width 0.0889)
		(layer "In9.Cu")
		(net "CLK_100M_CPU0_BCLK1_DN")
	)
	(segment
		(start 228.862636 -100.770944)
		(end 228.577394 -100.485702)
		(width 0.1143)
		(layer "In9.Cu")
		(net "CLK_100M_CPU0_BCLK1_DN")
	)
	(segment
		(start 286.013144 -91.270836)
		(end 286.022034 -91.286076)
		(width 0.0889)
		(layer "In9.Cu")
		(net "CLK_100M_CPU0_BCLK1_DN")
	)
	(segment
		(start 181.939946 -81.836514)
		(end 179.822602 -79.71917)
		(width 0.1143)
		(layer "In9.Cu")
		(net "CLK_100M_CPU0_BCLK1_DN")
	)
	(segment
		(start 200.67524 -102.58044)
		(end 197.241414 -102.58044)
		(width 0.1143)
		(layer "In9.Cu")
		(net "CLK_100M_CPU0_BCLK1_DN")
	)
	(segment
		(start 231.379014 -100.770944)
		(end 228.862636 -100.770944)
		(width 0.1143)
		(layer "In9.Cu")
		(net "CLK_100M_CPU0_BCLK1_DN")
	)
	(segment
		(start 286.013144 -95.232982)
		(end 286.019494 -95.24365)
		(width 0.0889)
		(layer "In9.Cu")
		(net "CLK_100M_CPU0_BCLK1_DN")
	)
	(segment
		(start 228.577394 -100.485702)
		(end 228.577394 -99.951286)
		(width 0.1143)
		(layer "In9.Cu")
		(net "CLK_100M_CPU0_BCLK1_DN")
	)
	(segment
		(start 282.943554 -99.586288)
		(end 282.910788 -99.586288)
		(width 0.0889)
		(layer "In9.Cu")
		(net "CLK_100M_CPU0_BCLK1_DN")
	)
	(segment
		(start 201.7268 -103.632)
		(end 200.67524 -102.58044)
		(width 0.1143)
		(layer "In9.Cu")
		(net "CLK_100M_CPU0_BCLK1_DN")
	)
	(segment
		(start 179.431696 -79.71917)
		(end 178.918616 -80.23225)
		(width 0.1143)
		(layer "In9.Cu")
		(net "CLK_100M_CPU0_BCLK1_DN")
	)
	(segment
		(start 219.60332 -103.354632)
		(end 213.502748 -104.82834)
		(width 0.1143)
		(layer "In9.Cu")
		(net "CLK_100M_CPU0_BCLK1_DN")
	)
	(segment
		(start 286.019494 -94.822518)
		(end 286.013144 -94.833186)
		(width 0.0889)
		(layer "In9.Cu")
		(net "CLK_100M_CPU0_BCLK1_DN")
	)
	(segment
		(start 233.115866 -102.507796)
		(end 231.379014 -100.770944)
		(width 0.1143)
		(layer "In9.Cu")
		(net "CLK_100M_CPU0_BCLK1_DN")
	)
	(segment
		(start 193.58102 -102.487222)
		(end 192.802764 -101.708966)
		(width 0.1143)
		(layer "In9.Cu")
		(net "CLK_100M_CPU0_BCLK1_DN")
	)
	(segment
		(start 181.939946 -94.012004)
		(end 181.939946 -81.836514)
		(width 0.1143)
		(layer "In9.Cu")
		(net "CLK_100M_CPU0_BCLK1_DN")
	)
	(segment
		(start 286.013144 -92.261436)
		(end 286.022034 -92.276676)
		(width 0.0889)
		(layer "In9.Cu")
		(net "CLK_100M_CPU0_BCLK1_DN")
	)
	(segment
		(start 230.92283 -99.145344)
		(end 228.474778 -99.145344)
		(width 0.1143)
		(layer "In9.Cu")
		(net "CLK_100M_CPU0_BCLK1_DN")
	)
	(segment
		(start 279.143206 -100.576888)
		(end 278.152606 -101.567488)
		(width 0.0889)
		(layer "In9.Cu")
		(net "CLK_100M_CPU0_BCLK1_DN")
	)
	(segment
		(start 265.918442 -101.3841)
		(end 253.389384 -101.3841)
		(width 0.1143)
		(layer "In9.Cu")
		(net "CLK_100M_CPU0_BCLK1_DN")
	)
	(segment
		(start 282.080208 -100.081588)
		(end 281.172412 -100.081588)
		(width 0.0889)
		(layer "In9.Cu")
		(net "CLK_100M_CPU0_BCLK1_DN")
	)
	(segment
		(start 280.677112 -100.576888)
		(end 279.143206 -100.576888)
		(width 0.0889)
		(layer "In9.Cu")
		(net "CLK_100M_CPU0_BCLK1_DN")
	)
	(segment
		(start 195.750942 -103.251)
		(end 194.987164 -102.487222)
		(width 0.1143)
		(layer "In9.Cu")
		(net "CLK_100M_CPU0_BCLK1_DN")
	)
	(segment
		(start 194.987164 -102.487222)
		(end 193.58102 -102.487222)
		(width 0.1143)
		(layer "In9.Cu")
		(net "CLK_100M_CPU0_BCLK1_DN")
	)
	(segment
		(start 228.862636 -99.666044)
		(end 230.92283 -99.666044)
		(width 0.1143)
		(layer "In9.Cu")
		(net "CLK_100M_CPU0_BCLK1_DN")
	)
	(segment
		(start 213.502748 -104.82834)
		(end 204.231748 -104.82834)
		(width 0.1143)
		(layer "In9.Cu")
		(net "CLK_100M_CPU0_BCLK1_DN")
	)
	(segment
		(start 246.882412 -100.2157)
		(end 246.171212 -100.9269)
		(width 0.1143)
		(layer "In9.Cu")
		(net "CLK_100M_CPU0_BCLK1_DN")
	)
	(segment
		(start 253.389384 -101.3841)
		(end 252.220984 -100.2157)
		(width 0.1143)
		(layer "In9.Cu")
		(net "CLK_100M_CPU0_BCLK1_DN")
	)
	(segment
		(start 243.765324 -100.9269)
		(end 239.940846 -102.507796)
		(width 0.1143)
		(layer "In9.Cu")
		(net "CLK_100M_CPU0_BCLK1_DN")
	)
	(segment
		(start 231.03713 -99.551744)
		(end 231.03713 -99.259644)
		(width 0.1143)
		(layer "In9.Cu")
		(net "CLK_100M_CPU0_BCLK1_DN")
	)
	(segment
		(start 230.92283 -99.666044)
		(end 231.03713 -99.551744)
		(width 0.1143)
		(layer "In9.Cu")
		(net "CLK_100M_CPU0_BCLK1_DN")
	)
	(segment
		(start 281.172412 -100.081588)
		(end 280.677112 -100.576888)
		(width 0.0889)
		(layer "In9.Cu")
		(net "CLK_100M_CPU0_BCLK1_DN")
	)
	(segment
		(start 189.636908 -101.708966)
		(end 181.939946 -94.012004)
		(width 0.1143)
		(layer "In9.Cu")
		(net "CLK_100M_CPU0_BCLK1_DN")
	)
	(arc
		(start 282.910788 -99.586288)
		(mid 282.719146 -99.643454)
		(end 282.579064 -99.786186)
		(width 0.0889)
		(layer "In9.Cu")
		(net "CLK_100M_CPU0_BCLK1_DN")
	)
	(arc
		(start 286.013144 -94.242636)
		(mid 286.092366 -94.531754)
		(end 286.019494 -94.822518)
		(width 0.0889)
		(layer "In9.Cu")
		(net "CLK_100M_CPU0_BCLK1_DN")
	)
	(arc
		(start 283.437584 -99.290886)
		(mid 283.228976 -99.502818)
		(end 282.943554 -99.586288)
		(width 0.0889)
		(layer "In9.Cu")
		(net "CLK_100M_CPU0_BCLK1_DN")
	)
	(arc
		(start 284.296104 -98.795586)
		(mid 284.0891 -99.00645)
		(end 283.805884 -99.090734)
		(width 0.0889)
		(layer "In9.Cu")
		(net "CLK_100M_CPU0_BCLK1_DN")
	)
	(arc
		(start 286.013144 -89.88044)
		(mid 285.959611 -90.080338)
		(end 286.013144 -90.280236)
		(width 0.0889)
		(layer "In9.Cu")
		(net "CLK_100M_CPU0_BCLK1_DN")
	)
	(arc
		(start 286.013144 -93.84284)
		(mid 285.959611 -94.042738)
		(end 286.013144 -94.242636)
		(width 0.0889)
		(layer "In9.Cu")
		(net "CLK_100M_CPU0_BCLK1_DN")
	)
	(arc
		(start 285.987998 -87.951564)
		(mid 285.960712 -88.128192)
		(end 286.013144 -88.299036)
		(width 0.0889)
		(layer "In9.Cu")
		(net "CLK_100M_CPU0_BCLK1_DN")
	)
	(arc
		(start 286.013144 -96.81464)
		(mid 285.959611 -97.014538)
		(end 286.013144 -97.214436)
		(width 0.0889)
		(layer "In9.Cu")
		(net "CLK_100M_CPU0_BCLK1_DN")
	)
	(arc
		(start 286.013144 -88.88984)
		(mid 285.959611 -89.089738)
		(end 286.013144 -89.289636)
		(width 0.0889)
		(layer "In9.Cu")
		(net "CLK_100M_CPU0_BCLK1_DN")
	)
	(arc
		(start 286.022034 -93.267276)
		(mid 286.092431 -93.556227)
		(end 286.013144 -93.84284)
		(width 0.0889)
		(layer "In9.Cu")
		(net "CLK_100M_CPU0_BCLK1_DN")
	)
	(arc
		(start 284.627828 -98.595688)
		(mid 284.436186 -98.652854)
		(end 284.296104 -98.795586)
		(width 0.0889)
		(layer "In9.Cu")
		(net "CLK_100M_CPU0_BCLK1_DN")
	)
	(arc
		(start 286.022034 -97.229676)
		(mid 286.015029 -97.802149)
		(end 285.526226 -98.100134)
		(width 0.0889)
		(layer "In9.Cu")
		(net "CLK_100M_CPU0_BCLK1_DN")
	)
	(arc
		(start 286.013144 -94.833186)
		(mid 285.959611 -95.033084)
		(end 286.013144 -95.232982)
		(width 0.0889)
		(layer "In9.Cu")
		(net "CLK_100M_CPU0_BCLK1_DN")
	)
	(arc
		(start 286.013144 -90.87104)
		(mid 285.959611 -91.070938)
		(end 286.013144 -91.270836)
		(width 0.0889)
		(layer "In9.Cu")
		(net "CLK_100M_CPU0_BCLK1_DN")
	)
	(arc
		(start 286.013144 -95.82404)
		(mid 285.959611 -96.023938)
		(end 286.013144 -96.223836)
		(width 0.0889)
		(layer "In9.Cu")
		(net "CLK_100M_CPU0_BCLK1_DN")
	)
	(arc
		(start 286.022034 -91.286076)
		(mid 286.092431 -91.575027)
		(end 286.013144 -91.86164)
		(width 0.0889)
		(layer "In9.Cu")
		(net "CLK_100M_CPU0_BCLK1_DN")
	)
	(arc
		(start 286.022034 -92.276676)
		(mid 286.092431 -92.565627)
		(end 286.013144 -92.85224)
		(width 0.0889)
		(layer "In9.Cu")
		(net "CLK_100M_CPU0_BCLK1_DN")
	)
	(arc
		(start 286.013144 -91.86164)
		(mid 285.959611 -92.061538)
		(end 286.013144 -92.261436)
		(width 0.0889)
		(layer "In9.Cu")
		(net "CLK_100M_CPU0_BCLK1_DN")
	)
	(arc
		(start 285.154624 -98.300286)
		(mid 284.946016 -98.512218)
		(end 284.660594 -98.595688)
		(width 0.0889)
		(layer "In9.Cu")
		(net "CLK_100M_CPU0_BCLK1_DN")
	)
	(arc
		(start 286.013144 -92.85224)
		(mid 285.959611 -93.052138)
		(end 286.013144 -93.252036)
		(width 0.0889)
		(layer "In9.Cu")
		(net "CLK_100M_CPU0_BCLK1_DN")
	)
	(arc
		(start 286.022034 -90.295476)
		(mid 286.092431 -90.584427)
		(end 286.013144 -90.87104)
		(width 0.0889)
		(layer "In9.Cu")
		(net "CLK_100M_CPU0_BCLK1_DN")
	)
	(arc
		(start 286.022034 -88.314276)
		(mid 286.092431 -88.603227)
		(end 286.013144 -88.88984)
		(width 0.0889)
		(layer "In9.Cu")
		(net "CLK_100M_CPU0_BCLK1_DN")
	)
	(arc
		(start 286.022034 -89.304876)
		(mid 286.092431 -89.593827)
		(end 286.013144 -89.88044)
		(width 0.0889)
		(layer "In9.Cu")
		(net "CLK_100M_CPU0_BCLK1_DN")
	)
	(arc
		(start 282.579064 -99.786186)
		(mid 282.368351 -99.999265)
		(end 282.080208 -100.081588)
		(width 0.0889)
		(layer "In9.Cu")
		(net "CLK_100M_CPU0_BCLK1_DN")
	)
	(arc
		(start 286.019494 -95.24365)
		(mid 286.092414 -95.534667)
		(end 286.013144 -95.82404)
		(width 0.0889)
		(layer "In9.Cu")
		(net "CLK_100M_CPU0_BCLK1_DN")
	)
	(arc
		(start 283.773118 -99.090734)
		(mid 283.579268 -99.147084)
		(end 283.437584 -99.290886)
		(width 0.0889)
		(layer "In9.Cu")
		(net "CLK_100M_CPU0_BCLK1_DN")
	)
	(arc
		(start 286.022034 -96.239076)
		(mid 286.092431 -96.528027)
		(end 286.013144 -96.81464)
		(width 0.0889)
		(layer "In9.Cu")
		(net "CLK_100M_CPU0_BCLK1_DN")
	)
	(arc
		(start 285.490158 -98.100134)
		(mid 285.296308 -98.156484)
		(end 285.154624 -98.300286)
		(width 0.0889)
		(layer "In9.Cu")
		(net "CLK_100M_CPU0_BCLK1_DN")
	)
	(segment
		(start 177.06848 -76.288646)
		(end 177.06848 -76.512166)
		(width 0.1143)
		(layer "F.Cu")
		(net "CLK_100M_CPU0_BCLK0_DP")
	)
	(segment
		(start 288.07664 -70.268084)
		(end 287.50514 -70.268084)
		(width 0.1143)
		(layer "F.Cu")
		(net "CLK_100M_CPU0_BCLK0_DP")
	)
	(segment
		(start 176.407826 -76.8223)
		(end 176.276 -76.690474)
		(width 0.1143)
		(layer "F.Cu")
		(net "CLK_100M_CPU0_BCLK0_DP")
	)
	(segment
		(start 176.758346 -76.8223)
		(end 176.407826 -76.8223)
		(width 0.1143)
		(layer "F.Cu")
		(net "CLK_100M_CPU0_BCLK0_DP")
	)
	(segment
		(start 176.276 -76.690474)
		(end 176.276 -76.327)
		(width 0.1143)
		(layer "F.Cu")
		(net "CLK_100M_CPU0_BCLK0_DP")
	)
	(segment
		(start 177.06848 -76.512166)
		(end 176.758346 -76.8223)
		(width 0.1143)
		(layer "F.Cu")
		(net "CLK_100M_CPU0_BCLK0_DP")
	)
	(via
		(at 288.07664 -70.268084)
		(size 0.508)
		(drill 0.254)
		(layers "F.Cu" "B.Cu")
		(net "CLK_100M_CPU0_BCLK0_DP")
	)
	(via
		(at 177.06848 -76.288646)
		(size 0.508)
		(drill 0.254)
		(layers "F.Cu" "B.Cu")
		(net "CLK_100M_CPU0_BCLK0_DP")
	)
	(segment
		(start 176.87036 -76.819506)
		(end 176.641506 -76.819506)
		(width 0.1143)
		(layer "B.Cu")
		(net "CLK_100M_CPU0_BCLK0_DP")
	)
	(segment
		(start 177.06848 -76.288646)
		(end 177.06848 -76.621386)
		(width 0.1143)
		(layer "B.Cu")
		(net "CLK_100M_CPU0_BCLK0_DP")
	)
	(segment
		(start 176.641506 -76.819506)
		(end 176.149 -76.327)
		(width 0.1143)
		(layer "B.Cu")
		(net "CLK_100M_CPU0_BCLK0_DP")
	)
	(segment
		(start 177.06848 -76.621386)
		(end 176.87036 -76.819506)
		(width 0.1143)
		(layer "B.Cu")
		(net "CLK_100M_CPU0_BCLK0_DP")
	)
	(segment
		(start 182.74538 -59.947048)
		(end 182.503064 -60.189364)
		(width 0.1143)
		(layer "In9.Cu")
		(net "CLK_100M_CPU0_BCLK0_DP")
	)
	(segment
		(start 270.706342 -56.494934)
		(end 270.1163 -56.494934)
		(width 0.0889)
		(layer "In9.Cu")
		(net "CLK_100M_CPU0_BCLK0_DP")
	)
	(segment
		(start 274.402804 -58.67654)
		(end 274.399502 -58.670698)
		(width 0.0889)
		(layer "In9.Cu")
		(net "CLK_100M_CPU0_BCLK0_DP")
	)
	(segment
		(start 176.237138 -67.9704)
		(end 176.237138 -70.67677)
		(width 0.1143)
		(layer "In9.Cu")
		(net "CLK_100M_CPU0_BCLK0_DP")
	)
	(segment
		(start 288.07664 -70.268084)
		(end 288.07664 -69.93001)
		(width 0.0889)
		(layer "In9.Cu")
		(net "CLK_100M_CPU0_BCLK0_DP")
	)
	(segment
		(start 279.21839 -61.447934)
		(end 279.185624 -61.447934)
		(width 0.0889)
		(layer "In9.Cu")
		(net "CLK_100M_CPU0_BCLK0_DP")
	)
	(segment
		(start 254.724916 -49.317656)
		(end 248.992644 -49.317656)
		(width 0.1143)
		(layer "In9.Cu")
		(net "CLK_100M_CPU0_BCLK0_DP")
	)
	(segment
		(start 182.74538 -59.713368)
		(end 182.74538 -59.947048)
		(width 0.1143)
		(layer "In9.Cu")
		(net "CLK_100M_CPU0_BCLK0_DP")
	)
	(segment
		(start 273.212814 -57.981088)
		(end 273.180048 -57.981088)
		(width 0.0889)
		(layer "In9.Cu")
		(net "CLK_100M_CPU0_BCLK0_DP")
	)
	(segment
		(start 177.12309 -63.77432)
		(end 177.12309 -64.11722)
		(width 0.1143)
		(layer "In9.Cu")
		(net "CLK_100M_CPU0_BCLK0_DP")
	)
	(segment
		(start 286.086296 -65.410334)
		(end 286.05353 -65.410334)
		(width 0.0889)
		(layer "In9.Cu")
		(net "CLK_100M_CPU0_BCLK0_DP")
	)
	(segment
		(start 258.469638 -48.49749)
		(end 258.304538 -48.66259)
		(width 0.1143)
		(layer "In9.Cu")
		(net "CLK_100M_CPU0_BCLK0_DP")
	)
	(segment
		(start 262.236966 -51.723036)
		(end 262.2042 -51.723036)
		(width 0.0889)
		(layer "In9.Cu")
		(net "CLK_100M_CPU0_BCLK0_DP")
	)
	(segment
		(start 274.056348 -58.476388)
		(end 274.043394 -58.476388)
		(width 0.0889)
		(layer "In9.Cu")
		(net "CLK_100M_CPU0_BCLK0_DP")
	)
	(segment
		(start 182.503064 -60.189364)
		(end 182.269384 -60.189364)
		(width 0.1143)
		(layer "In9.Cu")
		(net "CLK_100M_CPU0_BCLK0_DP")
	)
	(segment
		(start 282.65247 -63.429134)
		(end 282.619704 -63.429134)
		(width 0.0889)
		(layer "In9.Cu")
		(net "CLK_100M_CPU0_BCLK0_DP")
	)
	(segment
		(start 202.412854 -46.9011)
		(end 199.798686 -49.515268)
		(width 0.1143)
		(layer "In9.Cu")
		(net "CLK_100M_CPU0_BCLK0_DP")
	)
	(segment
		(start 274.932648 -58.971688)
		(end 274.893024 -58.971688)
		(width 0.0889)
		(layer "In9.Cu")
		(net "CLK_100M_CPU0_BCLK0_DP")
	)
	(segment
		(start 177.28819 -63.26632)
		(end 177.28819 -63.60922)
		(width 0.1143)
		(layer "In9.Cu")
		(net "CLK_100M_CPU0_BCLK0_DP")
	)
	(segment
		(start 263.099296 -52.21859)
		(end 263.06653 -52.21859)
		(width 0.0889)
		(layer "In9.Cu")
		(net "CLK_100M_CPU0_BCLK0_DP")
	)
	(segment
		(start 285.231586 -64.915288)
		(end 285.19882 -64.915288)
		(width 0.0889)
		(layer "In9.Cu")
		(net "CLK_100M_CPU0_BCLK0_DP")
	)
	(segment
		(start 260.526276 -50.342292)
		(end 260.457188 -50.324004)
		(width 0.0889)
		(layer "In9.Cu")
		(net "CLK_100M_CPU0_BCLK0_DP")
	)
	(segment
		(start 272.350484 -57.485534)
		(end 272.317718 -57.485534)
		(width 0.0889)
		(layer "In9.Cu")
		(net "CLK_100M_CPU0_BCLK0_DP")
	)
	(segment
		(start 264.289286 -52.913788)
		(end 264.285984 -52.907946)
		(width 0.0889)
		(layer "In9.Cu")
		(net "CLK_100M_CPU0_BCLK0_DP")
	)
	(segment
		(start 177.12309 -61.74232)
		(end 177.12309 -62.08522)
		(width 0.1143)
		(layer "In9.Cu")
		(net "CLK_100M_CPU0_BCLK0_DP")
	)
	(segment
		(start 268.877288 -54.727602)
		(end 266.883134 -54.198266)
		(width 0.0889)
		(layer "In9.Cu")
		(net "CLK_100M_CPU0_BCLK0_DP")
	)
	(segment
		(start 284.358334 -64.419734)
		(end 284.336744 -64.419734)
		(width 0.0889)
		(layer "In9.Cu")
		(net "CLK_100M_CPU0_BCLK0_DP")
	)
	(segment
		(start 199.798686 -49.515268)
		(end 194.688968 -49.515268)
		(width 0.1143)
		(layer "In9.Cu")
		(net "CLK_100M_CPU0_BCLK0_DP")
	)
	(segment
		(start 184.2516 -58.207148)
		(end 183.463692 -58.995056)
		(width 0.1143)
		(layer "In9.Cu")
		(net "CLK_100M_CPU0_BCLK0_DP")
	)
	(segment
		(start 178.553364 -61.25591)
		(end 177.6095 -61.25591)
		(width 0.1143)
		(layer "In9.Cu")
		(net "CLK_100M_CPU0_BCLK0_DP")
	)
	(segment
		(start 255.545082 -48.49749)
		(end 254.724916 -49.317656)
		(width 0.1143)
		(layer "In9.Cu")
		(net "CLK_100M_CPU0_BCLK0_DP")
	)
	(segment
		(start 182.987696 -59.471052)
		(end 182.74538 -59.713368)
		(width 0.1143)
		(layer "In9.Cu")
		(net "CLK_100M_CPU0_BCLK0_DP")
	)
	(segment
		(start 256.437638 -48.49749)
		(end 256.272538 -48.66259)
		(width 0.1143)
		(layer "In9.Cu")
		(net "CLK_100M_CPU0_BCLK0_DP")
	)
	(segment
		(start 260.457188 -50.324004)
		(end 260.446012 -50.3047)
		(width 0.0889)
		(layer "In9.Cu")
		(net "CLK_100M_CPU0_BCLK0_DP")
	)
	(segment
		(start 265.674094 -53.704236)
		(end 265.638026 -53.704236)
		(width 0.0889)
		(layer "In9.Cu")
		(net "CLK_100M_CPU0_BCLK0_DP")
	)
	(segment
		(start 175.8442 -76.424282)
		(end 176.25314 -76.833222)
		(width 0.1143)
		(layer "In9.Cu")
		(net "CLK_100M_CPU0_BCLK0_DP")
	)
	(segment
		(start 257.288538 -48.66259)
		(end 256.945638 -48.66259)
		(width 0.1143)
		(layer "In9.Cu")
		(net "CLK_100M_CPU0_BCLK0_DP")
	)
	(segment
		(start 284.70479 -64.619886)
		(end 284.701488 -64.614044)
		(width 0.0889)
		(layer "In9.Cu")
		(net "CLK_100M_CPU0_BCLK0_DP")
	)
	(segment
		(start 260.446012 -50.3047)
		(end 260.324092 -50.094134)
		(width 0.1143)
		(layer "In9.Cu")
		(net "CLK_100M_CPU0_BCLK0_DP")
	)
	(segment
		(start 194.688968 -49.515268)
		(end 194.3608 -49.1871)
		(width 0.1143)
		(layer "In9.Cu")
		(net "CLK_100M_CPU0_BCLK0_DP")
	)
	(segment
		(start 271.495774 -56.990488)
		(end 271.315942 -56.990488)
		(width 0.0889)
		(layer "In9.Cu")
		(net "CLK_100M_CPU0_BCLK0_DP")
	)
	(segment
		(start 275.791168 -59.466988)
		(end 275.755354 -59.466988)
		(width 0.0889)
		(layer "In9.Cu")
		(net "CLK_100M_CPU0_BCLK0_DP")
	)
	(segment
		(start 176.237138 -70.67677)
		(end 177.3555 -71.795132)
		(width 0.1143)
		(layer "In9.Cu")
		(net "CLK_100M_CPU0_BCLK0_DP")
	)
	(segment
		(start 260.872732 -50.942748)
		(end 260.526276 -50.342292)
		(width 0.0889)
		(layer "In9.Cu")
		(net "CLK_100M_CPU0_BCLK0_DP")
	)
	(segment
		(start 177.28819 -65.64122)
		(end 177.12309 -65.80632)
		(width 0.1143)
		(layer "In9.Cu")
		(net "CLK_100M_CPU0_BCLK0_DP")
	)
	(segment
		(start 177.28819 -62.59322)
		(end 177.12309 -62.75832)
		(width 0.1143)
		(layer "In9.Cu")
		(net "CLK_100M_CPU0_BCLK0_DP")
	)
	(segment
		(start 257.796538 -48.49749)
		(end 257.453638 -48.49749)
		(width 0.1143)
		(layer "In9.Cu")
		(net "CLK_100M_CPU0_BCLK0_DP")
	)
	(segment
		(start 269.46225 -55.717948)
		(end 268.877288 -54.727602)
		(width 0.0889)
		(layer "In9.Cu")
		(net "CLK_100M_CPU0_BCLK0_DP")
	)
	(segment
		(start 263.94283 -52.713636)
		(end 263.92124 -52.713636)
		(width 0.0889)
		(layer "In9.Cu")
		(net "CLK_100M_CPU0_BCLK0_DP")
	)
	(segment
		(start 264.816082 -53.20919)
		(end 264.783316 -53.20919)
		(width 0.0889)
		(layer "In9.Cu")
		(net "CLK_100M_CPU0_BCLK0_DP")
	)
	(segment
		(start 175.8442 -75.54214)
		(end 175.8442 -76.424282)
		(width 0.1143)
		(layer "In9.Cu")
		(net "CLK_100M_CPU0_BCLK0_DP")
	)
	(segment
		(start 181.613048 -60.8457)
		(end 178.963574 -60.8457)
		(width 0.1143)
		(layer "In9.Cu")
		(net "CLK_100M_CPU0_BCLK0_DP")
	)
	(segment
		(start 177.6095 -61.25591)
		(end 177.12309 -61.74232)
		(width 0.1143)
		(layer "In9.Cu")
		(net "CLK_100M_CPU0_BCLK0_DP")
	)
	(segment
		(start 177.28819 -63.60922)
		(end 177.12309 -63.77432)
		(width 0.1143)
		(layer "In9.Cu")
		(net "CLK_100M_CPU0_BCLK0_DP")
	)
	(segment
		(start 283.5148 -63.924688)
		(end 283.482034 -63.924688)
		(width 0.0889)
		(layer "In9.Cu")
		(net "CLK_100M_CPU0_BCLK0_DP")
	)
	(segment
		(start 177.3555 -74.03084)
		(end 175.8442 -75.54214)
		(width 0.1143)
		(layer "In9.Cu")
		(net "CLK_100M_CPU0_BCLK0_DP")
	)
	(segment
		(start 177.12309 -65.13322)
		(end 177.28819 -65.29832)
		(width 0.1143)
		(layer "In9.Cu")
		(net "CLK_100M_CPU0_BCLK0_DP")
	)
	(segment
		(start 266.883134 -54.198266)
		(end 266.515596 -54.198266)
		(width 0.0889)
		(layer "In9.Cu")
		(net "CLK_100M_CPU0_BCLK0_DP")
	)
	(segment
		(start 177.28819 -65.29832)
		(end 177.28819 -65.64122)
		(width 0.1143)
		(layer "In9.Cu")
		(net "CLK_100M_CPU0_BCLK0_DP")
	)
	(segment
		(start 177.12309 -62.75832)
		(end 177.12309 -63.10122)
		(width 0.1143)
		(layer "In9.Cu")
		(net "CLK_100M_CPU0_BCLK0_DP")
	)
	(segment
		(start 241.931444 -48.113696)
		(end 208.65846 -48.113696)
		(width 0.1143)
		(layer "In9.Cu")
		(net "CLK_100M_CPU0_BCLK0_DP")
	)
	(segment
		(start 276.64664 -59.962288)
		(end 276.6187 -59.962288)
		(width 0.0889)
		(layer "In9.Cu")
		(net "CLK_100M_CPU0_BCLK0_DP")
	)
	(segment
		(start 278.36368 -60.952888)
		(end 278.330914 -60.952888)
		(width 0.0889)
		(layer "In9.Cu")
		(net "CLK_100M_CPU0_BCLK0_DP")
	)
	(segment
		(start 194.3608 -49.1871)
		(end 188.08827 -49.1871)
		(width 0.1143)
		(layer "In9.Cu")
		(net "CLK_100M_CPU0_BCLK0_DP")
	)
	(segment
		(start 177.12309 -64.79032)
		(end 177.12309 -65.13322)
		(width 0.1143)
		(layer "In9.Cu")
		(net "CLK_100M_CPU0_BCLK0_DP")
	)
	(segment
		(start 183.463692 -59.228482)
		(end 183.221122 -59.471052)
		(width 0.1143)
		(layer "In9.Cu")
		(net "CLK_100M_CPU0_BCLK0_DP")
	)
	(segment
		(start 177.12309 -65.80632)
		(end 177.12309 -67.084448)
		(width 0.1143)
		(layer "In9.Cu")
		(net "CLK_100M_CPU0_BCLK0_DP")
	)
	(segment
		(start 177.3555 -71.795132)
		(end 177.3555 -74.03084)
		(width 0.1143)
		(layer "In9.Cu")
		(net "CLK_100M_CPU0_BCLK0_DP")
	)
	(segment
		(start 261.382256 -51.22799)
		(end 261.353554 -51.22799)
		(width 0.0889)
		(layer "In9.Cu")
		(net "CLK_100M_CPU0_BCLK0_DP")
	)
	(segment
		(start 270.1163 -56.494934)
		(end 269.46225 -55.717948)
		(width 0.0889)
		(layer "In9.Cu")
		(net "CLK_100M_CPU0_BCLK0_DP")
	)
	(segment
		(start 204.790548 -46.9011)
		(end 202.412854 -46.9011)
		(width 0.1143)
		(layer "In9.Cu")
		(net "CLK_100M_CPU0_BCLK0_DP")
	)
	(segment
		(start 205.363826 -47.474378)
		(end 204.790548 -46.9011)
		(width 0.1143)
		(layer "In9.Cu")
		(net "CLK_100M_CPU0_BCLK0_DP")
	)
	(segment
		(start 256.945638 -48.66259)
		(end 256.780538 -48.49749)
		(width 0.1143)
		(layer "In9.Cu")
		(net "CLK_100M_CPU0_BCLK0_DP")
	)
	(segment
		(start 248.992644 -49.317656)
		(end 248.4247 -49.8856)
		(width 0.1143)
		(layer "In9.Cu")
		(net "CLK_100M_CPU0_BCLK0_DP")
	)
	(segment
		(start 177.12309 -67.084448)
		(end 176.237138 -67.9704)
		(width 0.1143)
		(layer "In9.Cu")
		(net "CLK_100M_CPU0_BCLK0_DP")
	)
	(segment
		(start 188.08827 -49.1871)
		(end 184.2516 -53.02377)
		(width 0.1143)
		(layer "In9.Cu")
		(net "CLK_100M_CPU0_BCLK0_DP")
	)
	(segment
		(start 177.12309 -63.10122)
		(end 177.28819 -63.26632)
		(width 0.1143)
		(layer "In9.Cu")
		(net "CLK_100M_CPU0_BCLK0_DP")
	)
	(segment
		(start 280.08072 -61.943488)
		(end 280.047954 -61.943488)
		(width 0.0889)
		(layer "In9.Cu")
		(net "CLK_100M_CPU0_BCLK0_DP")
	)
	(segment
		(start 183.221122 -59.471052)
		(end 182.987696 -59.471052)
		(width 0.1143)
		(layer "In9.Cu")
		(net "CLK_100M_CPU0_BCLK0_DP")
	)
	(segment
		(start 177.12309 -64.11722)
		(end 177.28819 -64.28232)
		(width 0.1143)
		(layer "In9.Cu")
		(net "CLK_100M_CPU0_BCLK0_DP")
	)
	(segment
		(start 288.07664 -69.93001)
		(end 288.011616 -69.864986)
		(width 0.0889)
		(layer "In9.Cu")
		(net "CLK_100M_CPU0_BCLK0_DP")
	)
	(segment
		(start 281.79776 -62.934088)
		(end 281.764994 -62.934088)
		(width 0.0889)
		(layer "In9.Cu")
		(net "CLK_100M_CPU0_BCLK0_DP")
	)
	(segment
		(start 287.56483 -69.572886)
		(end 286.41548 -67.581018)
		(width 0.0889)
		(layer "In9.Cu")
		(net "CLK_100M_CPU0_BCLK0_DP")
	)
	(segment
		(start 260.324092 -50.094134)
		(end 258.727448 -48.49749)
		(width 0.1143)
		(layer "In9.Cu")
		(net "CLK_100M_CPU0_BCLK0_DP")
	)
	(segment
		(start 258.727448 -48.49749)
		(end 258.469638 -48.49749)
		(width 0.1143)
		(layer "In9.Cu")
		(net "CLK_100M_CPU0_BCLK0_DP")
	)
	(segment
		(start 183.463692 -58.995056)
		(end 183.463692 -59.228482)
		(width 0.1143)
		(layer "In9.Cu")
		(net "CLK_100M_CPU0_BCLK0_DP")
	)
	(segment
		(start 184.2516 -53.02377)
		(end 184.2516 -58.207148)
		(width 0.1143)
		(layer "In9.Cu")
		(net "CLK_100M_CPU0_BCLK0_DP")
	)
	(segment
		(start 177.28819 -64.28232)
		(end 177.28819 -64.62522)
		(width 0.1143)
		(layer "In9.Cu")
		(net "CLK_100M_CPU0_BCLK0_DP")
	)
	(segment
		(start 257.453638 -48.49749)
		(end 257.288538 -48.66259)
		(width 0.1143)
		(layer "In9.Cu")
		(net "CLK_100M_CPU0_BCLK0_DP")
	)
	(segment
		(start 178.963574 -60.8457)
		(end 178.553364 -61.25591)
		(width 0.1143)
		(layer "In9.Cu")
		(net "CLK_100M_CPU0_BCLK0_DP")
	)
	(segment
		(start 258.304538 -48.66259)
		(end 257.961638 -48.66259)
		(width 0.1143)
		(layer "In9.Cu")
		(net "CLK_100M_CPU0_BCLK0_DP")
	)
	(segment
		(start 256.272538 -48.66259)
		(end 255.929638 -48.66259)
		(width 0.1143)
		(layer "In9.Cu")
		(net "CLK_100M_CPU0_BCLK0_DP")
	)
	(segment
		(start 176.25314 -76.833222)
		(end 176.523904 -76.833222)
		(width 0.1143)
		(layer "In9.Cu")
		(net "CLK_100M_CPU0_BCLK0_DP")
	)
	(segment
		(start 208.65846 -48.113696)
		(end 208.019142 -47.474378)
		(width 0.1143)
		(layer "In9.Cu")
		(net "CLK_100M_CPU0_BCLK0_DP")
	)
	(segment
		(start 256.780538 -48.49749)
		(end 256.437638 -48.49749)
		(width 0.1143)
		(layer "In9.Cu")
		(net "CLK_100M_CPU0_BCLK0_DP")
	)
	(segment
		(start 286.42183 -66.601086)
		(end 286.41548 -66.590418)
		(width 0.0889)
		(layer "In9.Cu")
		(net "CLK_100M_CPU0_BCLK0_DP")
	)
	(segment
		(start 182.269384 -60.189364)
		(end 181.613048 -60.8457)
		(width 0.1143)
		(layer "In9.Cu")
		(net "CLK_100M_CPU0_BCLK0_DP")
	)
	(segment
		(start 255.929638 -48.66259)
		(end 255.764538 -48.49749)
		(width 0.1143)
		(layer "In9.Cu")
		(net "CLK_100M_CPU0_BCLK0_DP")
	)
	(segment
		(start 248.4247 -49.8856)
		(end 243.703348 -49.8856)
		(width 0.1143)
		(layer "In9.Cu")
		(net "CLK_100M_CPU0_BCLK0_DP")
	)
	(segment
		(start 176.523904 -76.833222)
		(end 177.06848 -76.288646)
		(width 0.1143)
		(layer "In9.Cu")
		(net "CLK_100M_CPU0_BCLK0_DP")
	)
	(segment
		(start 177.28819 -62.25032)
		(end 177.28819 -62.59322)
		(width 0.1143)
		(layer "In9.Cu")
		(net "CLK_100M_CPU0_BCLK0_DP")
	)
	(segment
		(start 257.961638 -48.66259)
		(end 257.796538 -48.49749)
		(width 0.1143)
		(layer "In9.Cu")
		(net "CLK_100M_CPU0_BCLK0_DP")
	)
	(segment
		(start 255.764538 -48.49749)
		(end 255.545082 -48.49749)
		(width 0.1143)
		(layer "In9.Cu")
		(net "CLK_100M_CPU0_BCLK0_DP")
	)
	(segment
		(start 208.019142 -47.474378)
		(end 205.363826 -47.474378)
		(width 0.1143)
		(layer "In9.Cu")
		(net "CLK_100M_CPU0_BCLK0_DP")
	)
	(segment
		(start 280.93543 -62.438534)
		(end 280.902664 -62.438534)
		(width 0.0889)
		(layer "In9.Cu")
		(net "CLK_100M_CPU0_BCLK0_DP")
	)
	(segment
		(start 243.703348 -49.8856)
		(end 241.931444 -48.113696)
		(width 0.1143)
		(layer "In9.Cu")
		(net "CLK_100M_CPU0_BCLK0_DP")
	)
	(segment
		(start 177.28819 -64.62522)
		(end 177.12309 -64.79032)
		(width 0.1143)
		(layer "In9.Cu")
		(net "CLK_100M_CPU0_BCLK0_DP")
	)
	(segment
		(start 286.426656 -66.609722)
		(end 286.42183 -66.601086)
		(width 0.0889)
		(layer "In9.Cu")
		(net "CLK_100M_CPU0_BCLK0_DP")
	)
	(segment
		(start 177.12309 -62.08522)
		(end 177.28819 -62.25032)
		(width 0.1143)
		(layer "In9.Cu")
		(net "CLK_100M_CPU0_BCLK0_DP")
	)
	(segment
		(start 277.50135 -60.457334)
		(end 277.468584 -60.457334)
		(width 0.0889)
		(layer "In9.Cu")
		(net "CLK_100M_CPU0_BCLK0_DP")
	)
	(arc
		(start 266.515596 -54.198266)
		(mid 266.221516 -54.119659)
		(end 266.006326 -53.904388)
		(width 0.0889)
		(layer "In9.Cu")
		(net "CLK_100M_CPU0_BCLK0_DP")
	)
	(arc
		(start 273.180048 -57.981088)
		(mid 272.894624 -57.897621)
		(end 272.686018 -57.685686)
		(width 0.0889)
		(layer "In9.Cu")
		(net "CLK_100M_CPU0_BCLK0_DP")
	)
	(arc
		(start 285.19882 -64.915288)
		(mid 284.913396 -64.831821)
		(end 284.70479 -64.619886)
		(width 0.0889)
		(layer "In9.Cu")
		(net "CLK_100M_CPU0_BCLK0_DP")
	)
	(arc
		(start 279.553924 -61.648086)
		(mid 279.412241 -61.504282)
		(end 279.21839 -61.447934)
		(width 0.0889)
		(layer "In9.Cu")
		(net "CLK_100M_CPU0_BCLK0_DP")
	)
	(arc
		(start 263.92124 -52.713636)
		(mid 263.638023 -52.629355)
		(end 263.43102 -52.418488)
		(width 0.0889)
		(layer "In9.Cu")
		(net "CLK_100M_CPU0_BCLK0_DP")
	)
	(arc
		(start 285.56331 -65.115186)
		(mid 285.423231 -64.97245)
		(end 285.231586 -64.915288)
		(width 0.0889)
		(layer "In9.Cu")
		(net "CLK_100M_CPU0_BCLK0_DP")
	)
	(arc
		(start 275.755354 -59.466988)
		(mid 275.46993 -59.383521)
		(end 275.261324 -59.171586)
		(width 0.0889)
		(layer "In9.Cu")
		(net "CLK_100M_CPU0_BCLK0_DP")
	)
	(arc
		(start 284.701488 -64.614044)
		(mid 284.555522 -64.471645)
		(end 284.358334 -64.419734)
		(width 0.0889)
		(layer "In9.Cu")
		(net "CLK_100M_CPU0_BCLK0_DP")
	)
	(arc
		(start 282.129484 -63.133986)
		(mid 281.989405 -62.99125)
		(end 281.79776 -62.934088)
		(width 0.0889)
		(layer "In9.Cu")
		(net "CLK_100M_CPU0_BCLK0_DP")
	)
	(arc
		(start 282.619704 -63.429134)
		(mid 282.336487 -63.344853)
		(end 282.129484 -63.133986)
		(width 0.0889)
		(layer "In9.Cu")
		(net "CLK_100M_CPU0_BCLK0_DP")
	)
	(arc
		(start 271.827498 -57.190386)
		(mid 271.687419 -57.04765)
		(end 271.495774 -56.990488)
		(width 0.0889)
		(layer "In9.Cu")
		(net "CLK_100M_CPU0_BCLK0_DP")
	)
	(arc
		(start 263.06653 -52.21859)
		(mid 262.781106 -52.135123)
		(end 262.5725 -51.923188)
		(width 0.0889)
		(layer "In9.Cu")
		(net "CLK_100M_CPU0_BCLK0_DP")
	)
	(arc
		(start 286.41548 -66.590418)
		(mid 286.342682 -66.299655)
		(end 286.42183 -66.010536)
		(width 0.0889)
		(layer "In9.Cu")
		(net "CLK_100M_CPU0_BCLK0_DP")
	)
	(arc
		(start 272.686018 -57.685686)
		(mid 272.544335 -57.541882)
		(end 272.350484 -57.485534)
		(width 0.0889)
		(layer "In9.Cu")
		(net "CLK_100M_CPU0_BCLK0_DP")
	)
	(arc
		(start 264.285984 -52.907946)
		(mid 264.140018 -52.765547)
		(end 263.94283 -52.713636)
		(width 0.0889)
		(layer "In9.Cu")
		(net "CLK_100M_CPU0_BCLK0_DP")
	)
	(arc
		(start 273.544538 -58.180986)
		(mid 273.404459 -58.03825)
		(end 273.212814 -57.981088)
		(width 0.0889)
		(layer "In9.Cu")
		(net "CLK_100M_CPU0_BCLK0_DP")
	)
	(arc
		(start 274.893024 -58.971688)
		(mid 274.609807 -58.887407)
		(end 274.402804 -58.67654)
		(width 0.0889)
		(layer "In9.Cu")
		(net "CLK_100M_CPU0_BCLK0_DP")
	)
	(arc
		(start 281.764994 -62.934088)
		(mid 281.47957 -62.850621)
		(end 281.270964 -62.638686)
		(width 0.0889)
		(layer "In9.Cu")
		(net "CLK_100M_CPU0_BCLK0_DP")
	)
	(arc
		(start 264.783316 -53.20919)
		(mid 264.497892 -53.125723)
		(end 264.289286 -52.913788)
		(width 0.0889)
		(layer "In9.Cu")
		(net "CLK_100M_CPU0_BCLK0_DP")
	)
	(arc
		(start 277.836884 -60.657486)
		(mid 277.695201 -60.513682)
		(end 277.50135 -60.457334)
		(width 0.0889)
		(layer "In9.Cu")
		(net "CLK_100M_CPU0_BCLK0_DP")
	)
	(arc
		(start 274.399502 -58.670698)
		(mid 274.253536 -58.528299)
		(end 274.056348 -58.476388)
		(width 0.0889)
		(layer "In9.Cu")
		(net "CLK_100M_CPU0_BCLK0_DP")
	)
	(arc
		(start 278.695404 -61.152786)
		(mid 278.555325 -61.01005)
		(end 278.36368 -60.952888)
		(width 0.0889)
		(layer "In9.Cu")
		(net "CLK_100M_CPU0_BCLK0_DP")
	)
	(arc
		(start 280.902664 -62.438534)
		(mid 280.619447 -62.354253)
		(end 280.412444 -62.143386)
		(width 0.0889)
		(layer "In9.Cu")
		(net "CLK_100M_CPU0_BCLK0_DP")
	)
	(arc
		(start 282.988004 -63.629286)
		(mid 282.846321 -63.485482)
		(end 282.65247 -63.429134)
		(width 0.0889)
		(layer "In9.Cu")
		(net "CLK_100M_CPU0_BCLK0_DP")
	)
	(arc
		(start 283.846524 -64.124586)
		(mid 283.706445 -63.98185)
		(end 283.5148 -63.924688)
		(width 0.0889)
		(layer "In9.Cu")
		(net "CLK_100M_CPU0_BCLK0_DP")
	)
	(arc
		(start 279.185624 -61.447934)
		(mid 278.902407 -61.363653)
		(end 278.695404 -61.152786)
		(width 0.0889)
		(layer "In9.Cu")
		(net "CLK_100M_CPU0_BCLK0_DP")
	)
	(arc
		(start 274.043394 -58.476388)
		(mid 273.755249 -58.394069)
		(end 273.544538 -58.180986)
		(width 0.0889)
		(layer "In9.Cu")
		(net "CLK_100M_CPU0_BCLK0_DP")
	)
	(arc
		(start 288.011616 -69.864986)
		(mid 287.753346 -69.772278)
		(end 287.56483 -69.572886)
		(width 0.0889)
		(layer "In9.Cu")
		(net "CLK_100M_CPU0_BCLK0_DP")
	)
	(arc
		(start 283.482034 -63.924688)
		(mid 283.19661 -63.841221)
		(end 282.988004 -63.629286)
		(width 0.0889)
		(layer "In9.Cu")
		(net "CLK_100M_CPU0_BCLK0_DP")
	)
	(arc
		(start 276.6187 -59.962288)
		(mid 276.330555 -59.879969)
		(end 276.119844 -59.666886)
		(width 0.0889)
		(layer "In9.Cu")
		(net "CLK_100M_CPU0_BCLK0_DP")
	)
	(arc
		(start 262.5725 -51.923188)
		(mid 262.430817 -51.779384)
		(end 262.236966 -51.723036)
		(width 0.0889)
		(layer "In9.Cu")
		(net "CLK_100M_CPU0_BCLK0_DP")
	)
	(arc
		(start 271.315942 -56.990488)
		(mid 271.09896 -56.879658)
		(end 270.942308 -56.693054)
		(width 0.0889)
		(layer "In9.Cu")
		(net "CLK_100M_CPU0_BCLK0_DP")
	)
	(arc
		(start 286.42183 -67.001136)
		(mid 286.4753 -66.806073)
		(end 286.426656 -66.609722)
		(width 0.0889)
		(layer "In9.Cu")
		(net "CLK_100M_CPU0_BCLK0_DP")
	)
	(arc
		(start 265.147806 -53.409088)
		(mid 265.007727 -53.266352)
		(end 264.816082 -53.20919)
		(width 0.0889)
		(layer "In9.Cu")
		(net "CLK_100M_CPU0_BCLK0_DP")
	)
	(arc
		(start 275.261324 -59.171586)
		(mid 275.12258 -59.029553)
		(end 274.932648 -58.971688)
		(width 0.0889)
		(layer "In9.Cu")
		(net "CLK_100M_CPU0_BCLK0_DP")
	)
	(arc
		(start 263.43102 -52.418488)
		(mid 263.290941 -52.275752)
		(end 263.099296 -52.21859)
		(width 0.0889)
		(layer "In9.Cu")
		(net "CLK_100M_CPU0_BCLK0_DP")
	)
	(arc
		(start 261.353554 -51.22799)
		(mid 261.075813 -51.148316)
		(end 260.872732 -50.942748)
		(width 0.0889)
		(layer "In9.Cu")
		(net "CLK_100M_CPU0_BCLK0_DP")
	)
	(arc
		(start 278.330914 -60.952888)
		(mid 278.04549 -60.869421)
		(end 277.836884 -60.657486)
		(width 0.0889)
		(layer "In9.Cu")
		(net "CLK_100M_CPU0_BCLK0_DP")
	)
	(arc
		(start 270.942308 -56.693054)
		(mid 270.843062 -56.571666)
		(end 270.706342 -56.494934)
		(width 0.0889)
		(layer "In9.Cu")
		(net "CLK_100M_CPU0_BCLK0_DP")
	)
	(arc
		(start 281.270964 -62.638686)
		(mid 281.129281 -62.494882)
		(end 280.93543 -62.438534)
		(width 0.0889)
		(layer "In9.Cu")
		(net "CLK_100M_CPU0_BCLK0_DP")
	)
	(arc
		(start 266.006326 -53.904388)
		(mid 265.866058 -53.761432)
		(end 265.674094 -53.704236)
		(width 0.0889)
		(layer "In9.Cu")
		(net "CLK_100M_CPU0_BCLK0_DP")
	)
	(arc
		(start 277.468584 -60.457334)
		(mid 277.185367 -60.373053)
		(end 276.978364 -60.162186)
		(width 0.0889)
		(layer "In9.Cu")
		(net "CLK_100M_CPU0_BCLK0_DP")
	)
	(arc
		(start 286.05353 -65.410334)
		(mid 285.770313 -65.326053)
		(end 285.56331 -65.115186)
		(width 0.0889)
		(layer "In9.Cu")
		(net "CLK_100M_CPU0_BCLK0_DP")
	)
	(arc
		(start 286.41548 -67.581018)
		(mid 286.342682 -67.290255)
		(end 286.42183 -67.001136)
		(width 0.0889)
		(layer "In9.Cu")
		(net "CLK_100M_CPU0_BCLK0_DP")
	)
	(arc
		(start 265.638026 -53.704236)
		(mid 265.354809 -53.619955)
		(end 265.147806 -53.409088)
		(width 0.0889)
		(layer "In9.Cu")
		(net "CLK_100M_CPU0_BCLK0_DP")
	)
	(arc
		(start 261.71398 -51.427888)
		(mid 261.573901 -51.285152)
		(end 261.382256 -51.22799)
		(width 0.0889)
		(layer "In9.Cu")
		(net "CLK_100M_CPU0_BCLK0_DP")
	)
	(arc
		(start 262.2042 -51.723036)
		(mid 261.920983 -51.638755)
		(end 261.71398 -51.427888)
		(width 0.0889)
		(layer "In9.Cu")
		(net "CLK_100M_CPU0_BCLK0_DP")
	)
	(arc
		(start 286.42183 -66.010536)
		(mid 286.424578 -65.615069)
		(end 286.086296 -65.410334)
		(width 0.0889)
		(layer "In9.Cu")
		(net "CLK_100M_CPU0_BCLK0_DP")
	)
	(arc
		(start 280.412444 -62.143386)
		(mid 280.272365 -62.00065)
		(end 280.08072 -61.943488)
		(width 0.0889)
		(layer "In9.Cu")
		(net "CLK_100M_CPU0_BCLK0_DP")
	)
	(arc
		(start 272.317718 -57.485534)
		(mid 272.034501 -57.401253)
		(end 271.827498 -57.190386)
		(width 0.0889)
		(layer "In9.Cu")
		(net "CLK_100M_CPU0_BCLK0_DP")
	)
	(arc
		(start 284.336744 -64.419734)
		(mid 284.053527 -64.335453)
		(end 283.846524 -64.124586)
		(width 0.0889)
		(layer "In9.Cu")
		(net "CLK_100M_CPU0_BCLK0_DP")
	)
	(arc
		(start 276.119844 -59.666886)
		(mid 275.9811 -59.524853)
		(end 275.791168 -59.466988)
		(width 0.0889)
		(layer "In9.Cu")
		(net "CLK_100M_CPU0_BCLK0_DP")
	)
	(arc
		(start 280.047954 -61.943488)
		(mid 279.76253 -61.860021)
		(end 279.553924 -61.648086)
		(width 0.0889)
		(layer "In9.Cu")
		(net "CLK_100M_CPU0_BCLK0_DP")
	)
	(arc
		(start 276.978364 -60.162186)
		(mid 276.838285 -60.01945)
		(end 276.64664 -59.962288)
		(width 0.0889)
		(layer "In9.Cu")
		(net "CLK_100M_CPU0_BCLK0_DP")
	)
	(segment
		(start 288.07664 -69.277738)
		(end 287.50514 -69.277738)
		(width 0.1143)
		(layer "F.Cu")
		(net "CLK_100M_CPU0_BCLK0_DN")
	)
	(segment
		(start 177.06848 -77.399134)
		(end 176.732946 -77.0636)
		(width 0.1143)
		(layer "F.Cu")
		(net "CLK_100M_CPU0_BCLK0_DN")
	)
	(segment
		(start 177.06848 -77.558646)
		(end 177.06848 -77.399134)
		(width 0.1143)
		(layer "F.Cu")
		(net "CLK_100M_CPU0_BCLK0_DN")
	)
	(segment
		(start 176.276 -77.187552)
		(end 176.276 -77.597)
		(width 0.1143)
		(layer "F.Cu")
		(net "CLK_100M_CPU0_BCLK0_DN")
	)
	(segment
		(start 176.399952 -77.0636)
		(end 176.276 -77.187552)
		(width 0.1143)
		(layer "F.Cu")
		(net "CLK_100M_CPU0_BCLK0_DN")
	)
	(segment
		(start 176.732946 -77.0636)
		(end 176.399952 -77.0636)
		(width 0.1143)
		(layer "F.Cu")
		(net "CLK_100M_CPU0_BCLK0_DN")
	)
	(via
		(at 177.06848 -77.558646)
		(size 0.508)
		(drill 0.254)
		(layers "F.Cu" "B.Cu")
		(net "CLK_100M_CPU0_BCLK0_DN")
	)
	(via
		(at 288.07664 -69.277738)
		(size 0.508)
		(drill 0.254)
		(layers "F.Cu" "B.Cu")
		(net "CLK_100M_CPU0_BCLK0_DN")
	)
	(segment
		(start 176.885092 -77.060806)
		(end 177.06848 -77.244194)
		(width 0.1143)
		(layer "B.Cu")
		(net "CLK_100M_CPU0_BCLK0_DN")
	)
	(segment
		(start 176.149 -77.597)
		(end 176.685194 -77.060806)
		(width 0.1143)
		(layer "B.Cu")
		(net "CLK_100M_CPU0_BCLK0_DN")
	)
	(segment
		(start 176.685194 -77.060806)
		(end 176.885092 -77.060806)
		(width 0.1143)
		(layer "B.Cu")
		(net "CLK_100M_CPU0_BCLK0_DN")
	)
	(segment
		(start 177.06848 -77.244194)
		(end 177.06848 -77.558646)
		(width 0.1143)
		(layer "B.Cu")
		(net "CLK_100M_CPU0_BCLK0_DN")
	)
	(segment
		(start 267.993622 -54.203854)
		(end 267.735812 -54.135274)
		(width 0.0889)
		(layer "In9.Cu")
		(net "CLK_100M_CPU0_BCLK0_DN")
	)
	(segment
		(start 278.370284 -60.762388)
		(end 278.337518 -60.762388)
		(width 0.0889)
		(layer "In9.Cu")
		(net "CLK_100M_CPU0_BCLK0_DN")
	)
	(segment
		(start 277.507954 -60.266834)
		(end 277.475188 -60.266834)
		(width 0.0889)
		(layer "In9.Cu")
		(net "CLK_100M_CPU0_BCLK0_DN")
	)
	(segment
		(start 272.357088 -57.295034)
		(end 272.324322 -57.295034)
		(width 0.0889)
		(layer "In9.Cu")
		(net "CLK_100M_CPU0_BCLK0_DN")
	)
	(segment
		(start 176.83099 -61.621162)
		(end 176.83099 -66.96329)
		(width 0.1143)
		(layer "In9.Cu")
		(net "CLK_100M_CPU0_BCLK0_DN")
	)
	(segment
		(start 286.59328 -66.516504)
		(end 286.58693 -66.505836)
		(width 0.0889)
		(layer "In9.Cu")
		(net "CLK_100M_CPU0_BCLK0_DN")
	)
	(segment
		(start 176.83099 -66.96329)
		(end 175.945038 -67.849242)
		(width 0.1143)
		(layer "In9.Cu")
		(net "CLK_100M_CPU0_BCLK0_DN")
	)
	(segment
		(start 267.735812 -54.135274)
		(end 267.6271 -54.19852)
		(width 0.0889)
		(layer "In9.Cu")
		(net "CLK_100M_CPU0_BCLK0_DN")
	)
	(segment
		(start 264.457942 -52.82438)
		(end 264.45464 -52.818538)
		(width 0.0889)
		(layer "In9.Cu")
		(net "CLK_100M_CPU0_BCLK0_DN")
	)
	(segment
		(start 175.5521 -75.420982)
		(end 175.5521 -76.54544)
		(width 0.1143)
		(layer "In9.Cu")
		(net "CLK_100M_CPU0_BCLK0_DN")
	)
	(segment
		(start 261.38886 -51.03749)
		(end 261.356094 -51.03749)
		(width 0.0889)
		(layer "In9.Cu")
		(net "CLK_100M_CPU0_BCLK0_DN")
	)
	(segment
		(start 284.376114 -64.229234)
		(end 284.343348 -64.229234)
		(width 0.0889)
		(layer "In9.Cu")
		(net "CLK_100M_CPU0_BCLK0_DN")
	)
	(segment
		(start 205.484984 -47.182278)
		(end 204.911706 -46.609)
		(width 0.1143)
		(layer "In9.Cu")
		(net "CLK_100M_CPU0_BCLK0_DN")
	)
	(segment
		(start 243.824506 -49.5935)
		(end 242.052602 -47.821596)
		(width 0.1143)
		(layer "In9.Cu")
		(net "CLK_100M_CPU0_BCLK0_DN")
	)
	(segment
		(start 281.804364 -62.743588)
		(end 281.771598 -62.743588)
		(width 0.0889)
		(layer "In9.Cu")
		(net "CLK_100M_CPU0_BCLK0_DN")
	)
	(segment
		(start 176.131982 -77.125322)
		(end 176.635156 -77.125322)
		(width 0.1143)
		(layer "In9.Cu")
		(net "CLK_100M_CPU0_BCLK0_DN")
	)
	(segment
		(start 287.72993 -69.477636)
		(end 286.582104 -67.4878)
		(width 0.0889)
		(layer "In9.Cu")
		(net "CLK_100M_CPU0_BCLK0_DN")
	)
	(segment
		(start 271.502378 -56.799988)
		(end 271.345914 -56.799988)
		(width 0.0889)
		(layer "In9.Cu")
		(net "CLK_100M_CPU0_BCLK0_DN")
	)
	(segment
		(start 177.488342 -60.96381)
		(end 176.83099 -61.621162)
		(width 0.1143)
		(layer "In9.Cu")
		(net "CLK_100M_CPU0_BCLK0_DN")
	)
	(segment
		(start 260.558026 -49.914556)
		(end 258.848606 -48.20539)
		(width 0.1143)
		(layer "In9.Cu")
		(net "CLK_100M_CPU0_BCLK0_DN")
	)
	(segment
		(start 260.698996 -50.15865)
		(end 260.558026 -49.914556)
		(width 0.1143)
		(layer "In9.Cu")
		(net "CLK_100M_CPU0_BCLK0_DN")
	)
	(segment
		(start 261.037832 -50.847498)
		(end 260.691376 -50.247042)
		(width 0.0889)
		(layer "In9.Cu")
		(net "CLK_100M_CPU0_BCLK0_DN")
	)
	(segment
		(start 286.0929 -65.219834)
		(end 286.060134 -65.219834)
		(width 0.0889)
		(layer "In9.Cu")
		(net "CLK_100M_CPU0_BCLK0_DN")
	)
	(segment
		(start 274.932394 -58.780934)
		(end 274.902422 -58.780934)
		(width 0.0889)
		(layer "In9.Cu")
		(net "CLK_100M_CPU0_BCLK0_DN")
	)
	(segment
		(start 284.873446 -64.530478)
		(end 284.870144 -64.524636)
		(width 0.0889)
		(layer "In9.Cu")
		(net "CLK_100M_CPU0_BCLK0_DN")
	)
	(segment
		(start 262.24357 -51.532536)
		(end 262.210804 -51.532536)
		(width 0.0889)
		(layer "In9.Cu")
		(net "CLK_100M_CPU0_BCLK0_DN")
	)
	(segment
		(start 283.521404 -63.734188)
		(end 283.488638 -63.734188)
		(width 0.0889)
		(layer "In9.Cu")
		(net "CLK_100M_CPU0_BCLK0_DN")
	)
	(segment
		(start 183.9595 -52.902612)
		(end 183.9595 -58.08599)
		(width 0.1143)
		(layer "In9.Cu")
		(net "CLK_100M_CPU0_BCLK0_DN")
	)
	(segment
		(start 269.61846 -55.607204)
		(end 269.482824 -55.377588)
		(width 0.0889)
		(layer "In9.Cu")
		(net "CLK_100M_CPU0_BCLK0_DN")
	)
	(segment
		(start 268.056614 -54.312566)
		(end 267.993622 -54.203854)
		(width 0.0889)
		(layer "In9.Cu")
		(net "CLK_100M_CPU0_BCLK0_DN")
	)
	(segment
		(start 263.1059 -52.02809)
		(end 263.073134 -52.02809)
		(width 0.0889)
		(layer "In9.Cu")
		(net "CLK_100M_CPU0_BCLK0_DN")
	)
	(segment
		(start 279.224994 -61.257434)
		(end 279.192228 -61.257434)
		(width 0.0889)
		(layer "In9.Cu")
		(net "CLK_100M_CPU0_BCLK0_DN")
	)
	(segment
		(start 266.908026 -54.007766)
		(end 266.515342 -54.007766)
		(width 0.0889)
		(layer "In9.Cu")
		(net "CLK_100M_CPU0_BCLK0_DN")
	)
	(segment
		(start 286.58693 -66.505836)
		(end 286.582104 -66.4972)
		(width 0.0889)
		(layer "In9.Cu")
		(net "CLK_100M_CPU0_BCLK0_DN")
	)
	(segment
		(start 194.810126 -49.223168)
		(end 194.481958 -48.895)
		(width 0.1143)
		(layer "In9.Cu")
		(net "CLK_100M_CPU0_BCLK0_DN")
	)
	(segment
		(start 273.219418 -57.790588)
		(end 273.186652 -57.790588)
		(width 0.0889)
		(layer "In9.Cu")
		(net "CLK_100M_CPU0_BCLK0_DN")
	)
	(segment
		(start 175.945038 -67.849242)
		(end 175.945038 -70.797928)
		(width 0.1143)
		(layer "In9.Cu")
		(net "CLK_100M_CPU0_BCLK0_DN")
	)
	(segment
		(start 268.743938 -54.494938)
		(end 268.680946 -54.386226)
		(width 0.0889)
		(layer "In9.Cu")
		(net "CLK_100M_CPU0_BCLK0_DN")
	)
	(segment
		(start 177.0634 -73.909682)
		(end 175.5521 -75.420982)
		(width 0.1143)
		(layer "In9.Cu")
		(net "CLK_100M_CPU0_BCLK0_DN")
	)
	(segment
		(start 254.603758 -49.025556)
		(end 248.871486 -49.025556)
		(width 0.1143)
		(layer "In9.Cu")
		(net "CLK_100M_CPU0_BCLK0_DN")
	)
	(segment
		(start 269.514066 -55.255922)
		(end 269.37843 -55.026306)
		(width 0.0889)
		(layer "In9.Cu")
		(net "CLK_100M_CPU0_BCLK0_DN")
	)
	(segment
		(start 204.911706 -46.609)
		(end 202.291696 -46.609)
		(width 0.1143)
		(layer "In9.Cu")
		(net "CLK_100M_CPU0_BCLK0_DN")
	)
	(segment
		(start 199.677528 -49.223168)
		(end 194.810126 -49.223168)
		(width 0.1143)
		(layer "In9.Cu")
		(net "CLK_100M_CPU0_BCLK0_DN")
	)
	(segment
		(start 175.945038 -70.797928)
		(end 177.0634 -71.91629)
		(width 0.1143)
		(layer "In9.Cu")
		(net "CLK_100M_CPU0_BCLK0_DN")
	)
	(segment
		(start 288.07664 -69.277738)
		(end 288.07664 -69.615812)
		(width 0.0889)
		(layer "In9.Cu")
		(net "CLK_100M_CPU0_BCLK0_DN")
	)
	(segment
		(start 202.291696 -46.609)
		(end 199.677528 -49.223168)
		(width 0.1143)
		(layer "In9.Cu")
		(net "CLK_100M_CPU0_BCLK0_DN")
	)
	(segment
		(start 276.644608 -59.771534)
		(end 276.620478 -59.771534)
		(width 0.0889)
		(layer "In9.Cu")
		(net "CLK_100M_CPU0_BCLK0_DN")
	)
	(segment
		(start 268.680946 -54.386226)
		(end 268.423136 -54.317646)
		(width 0.0889)
		(layer "In9.Cu")
		(net "CLK_100M_CPU0_BCLK0_DN")
	)
	(segment
		(start 269.37843 -55.026306)
		(end 269.256764 -54.99481)
		(width 0.0889)
		(layer "In9.Cu")
		(net "CLK_100M_CPU0_BCLK0_DN")
	)
	(segment
		(start 194.481958 -48.895)
		(end 187.967112 -48.895)
		(width 0.1143)
		(layer "In9.Cu")
		(net "CLK_100M_CPU0_BCLK0_DN")
	)
	(segment
		(start 242.052602 -47.821596)
		(end 208.779618 -47.821596)
		(width 0.1143)
		(layer "In9.Cu")
		(net "CLK_100M_CPU0_BCLK0_DN")
	)
	(segment
		(start 280.942034 -62.248034)
		(end 280.909268 -62.248034)
		(width 0.0889)
		(layer "In9.Cu")
		(net "CLK_100M_CPU0_BCLK0_DN")
	)
	(segment
		(start 260.710172 -50.177954)
		(end 260.698996 -50.15865)
		(width 0.0889)
		(layer "In9.Cu")
		(net "CLK_100M_CPU0_BCLK0_DN")
	)
	(segment
		(start 263.96061 -52.523136)
		(end 263.927844 -52.523136)
		(width 0.0889)
		(layer "In9.Cu")
		(net "CLK_100M_CPU0_BCLK0_DN")
	)
	(segment
		(start 288.07664 -69.615812)
		(end 288.018728 -69.673724)
		(width 0.0889)
		(layer "In9.Cu")
		(net "CLK_100M_CPU0_BCLK0_DN")
	)
	(segment
		(start 181.49189 -60.5536)
		(end 178.842416 -60.5536)
		(width 0.1143)
		(layer "In9.Cu")
		(net "CLK_100M_CPU0_BCLK0_DN")
	)
	(segment
		(start 282.659074 -63.238634)
		(end 282.626308 -63.238634)
		(width 0.0889)
		(layer "In9.Cu")
		(net "CLK_100M_CPU0_BCLK0_DN")
	)
	(segment
		(start 268.423136 -54.317646)
		(end 268.314424 -54.380892)
		(width 0.0889)
		(layer "In9.Cu")
		(net "CLK_100M_CPU0_BCLK0_DN")
	)
	(segment
		(start 265.677396 -53.513736)
		(end 265.64463 -53.513736)
		(width 0.0889)
		(layer "In9.Cu")
		(net "CLK_100M_CPU0_BCLK0_DN")
	)
	(segment
		(start 270.736314 -56.304434)
		(end 270.2052 -56.304434)
		(width 0.0889)
		(layer "In9.Cu")
		(net "CLK_100M_CPU0_BCLK0_DN")
	)
	(segment
		(start 268.314424 -54.380892)
		(end 268.056614 -54.312566)
		(width 0.0889)
		(layer "In9.Cu")
		(net "CLK_100M_CPU0_BCLK0_DN")
	)
	(segment
		(start 208.1403 -47.182278)
		(end 205.484984 -47.182278)
		(width 0.1143)
		(layer "In9.Cu")
		(net "CLK_100M_CPU0_BCLK0_DN")
	)
	(segment
		(start 269.256764 -54.99481)
		(end 269.001748 -54.563264)
		(width 0.0889)
		(layer "In9.Cu")
		(net "CLK_100M_CPU0_BCLK0_DN")
	)
	(segment
		(start 264.822686 -53.01869)
		(end 264.801096 -53.01869)
		(width 0.0889)
		(layer "In9.Cu")
		(net "CLK_100M_CPU0_BCLK0_DN")
	)
	(segment
		(start 248.303542 -49.5935)
		(end 243.824506 -49.5935)
		(width 0.1143)
		(layer "In9.Cu")
		(net "CLK_100M_CPU0_BCLK0_DN")
	)
	(segment
		(start 270.2052 -56.304434)
		(end 269.61846 -55.607204)
		(width 0.0889)
		(layer "In9.Cu")
		(net "CLK_100M_CPU0_BCLK0_DN")
	)
	(segment
		(start 183.9595 -58.08599)
		(end 181.49189 -60.5536)
		(width 0.1143)
		(layer "In9.Cu")
		(net "CLK_100M_CPU0_BCLK0_DN")
	)
	(segment
		(start 260.691376 -50.247042)
		(end 260.710172 -50.177954)
		(width 0.0889)
		(layer "In9.Cu")
		(net "CLK_100M_CPU0_BCLK0_DN")
	)
	(segment
		(start 208.779618 -47.821596)
		(end 208.1403 -47.182278)
		(width 0.1143)
		(layer "In9.Cu")
		(net "CLK_100M_CPU0_BCLK0_DN")
	)
	(segment
		(start 178.432206 -60.96381)
		(end 177.488342 -60.96381)
		(width 0.1143)
		(layer "In9.Cu")
		(net "CLK_100M_CPU0_BCLK0_DN")
	)
	(segment
		(start 177.0634 -71.91629)
		(end 177.0634 -73.909682)
		(width 0.1143)
		(layer "In9.Cu")
		(net "CLK_100M_CPU0_BCLK0_DN")
	)
	(segment
		(start 175.5521 -76.54544)
		(end 176.131982 -77.125322)
		(width 0.1143)
		(layer "In9.Cu")
		(net "CLK_100M_CPU0_BCLK0_DN")
	)
	(segment
		(start 269.482824 -55.377588)
		(end 269.514066 -55.255922)
		(width 0.0889)
		(layer "In9.Cu")
		(net "CLK_100M_CPU0_BCLK0_DN")
	)
	(segment
		(start 267.6271 -54.19852)
		(end 266.908026 -54.007766)
		(width 0.0889)
		(layer "In9.Cu")
		(net "CLK_100M_CPU0_BCLK0_DN")
	)
	(segment
		(start 178.842416 -60.5536)
		(end 178.432206 -60.96381)
		(width 0.1143)
		(layer "In9.Cu")
		(net "CLK_100M_CPU0_BCLK0_DN")
	)
	(segment
		(start 280.087324 -61.752988)
		(end 280.054558 -61.752988)
		(width 0.0889)
		(layer "In9.Cu")
		(net "CLK_100M_CPU0_BCLK0_DN")
	)
	(segment
		(start 275.794724 -59.276234)
		(end 275.7551 -59.276234)
		(width 0.0889)
		(layer "In9.Cu")
		(net "CLK_100M_CPU0_BCLK0_DN")
	)
	(segment
		(start 255.423924 -48.20539)
		(end 254.603758 -49.025556)
		(width 0.1143)
		(layer "In9.Cu")
		(net "CLK_100M_CPU0_BCLK0_DN")
	)
	(segment
		(start 269.001748 -54.563264)
		(end 268.743938 -54.494938)
		(width 0.0889)
		(layer "In9.Cu")
		(net "CLK_100M_CPU0_BCLK0_DN")
	)
	(segment
		(start 258.848606 -48.20539)
		(end 255.423924 -48.20539)
		(width 0.1143)
		(layer "In9.Cu")
		(net "CLK_100M_CPU0_BCLK0_DN")
	)
	(segment
		(start 285.23819 -64.724788)
		(end 285.2166 -64.724788)
		(width 0.0889)
		(layer "In9.Cu")
		(net "CLK_100M_CPU0_BCLK0_DN")
	)
	(segment
		(start 187.967112 -48.895)
		(end 183.9595 -52.902612)
		(width 0.1143)
		(layer "In9.Cu")
		(net "CLK_100M_CPU0_BCLK0_DN")
	)
	(segment
		(start 248.871486 -49.025556)
		(end 248.303542 -49.5935)
		(width 0.1143)
		(layer "In9.Cu")
		(net "CLK_100M_CPU0_BCLK0_DN")
	)
	(segment
		(start 274.069302 -58.285634)
		(end 274.041362 -58.285634)
		(width 0.0889)
		(layer "In9.Cu")
		(net "CLK_100M_CPU0_BCLK0_DN")
	)
	(segment
		(start 176.635156 -77.125322)
		(end 177.06848 -77.558646)
		(width 0.1143)
		(layer "In9.Cu")
		(net "CLK_100M_CPU0_BCLK0_DN")
	)
	(arc
		(start 288.018728 -69.673724)
		(mid 287.851827 -69.608824)
		(end 287.72993 -69.477636)
		(width 0.0889)
		(layer "In9.Cu")
		(net "CLK_100M_CPU0_BCLK0_DN")
	)
	(arc
		(start 278.337518 -60.762388)
		(mid 278.143668 -60.706038)
		(end 278.001984 -60.562236)
		(width 0.0889)
		(layer "In9.Cu")
		(net "CLK_100M_CPU0_BCLK0_DN")
	)
	(arc
		(start 271.109948 -56.601868)
		(mid 270.953273 -56.415294)
		(end 270.736314 -56.304434)
		(width 0.0889)
		(layer "In9.Cu")
		(net "CLK_100M_CPU0_BCLK0_DN")
	)
	(arc
		(start 261.356094 -51.03749)
		(mid 261.17219 -50.983986)
		(end 261.037832 -50.847498)
		(width 0.0889)
		(layer "In9.Cu")
		(net "CLK_100M_CPU0_BCLK0_DN")
	)
	(arc
		(start 275.426424 -59.076336)
		(mid 275.217816 -58.864404)
		(end 274.932394 -58.780934)
		(width 0.0889)
		(layer "In9.Cu")
		(net "CLK_100M_CPU0_BCLK0_DN")
	)
	(arc
		(start 285.72841 -65.019936)
		(mid 285.521406 -64.809072)
		(end 285.23819 -64.724788)
		(width 0.0889)
		(layer "In9.Cu")
		(net "CLK_100M_CPU0_BCLK0_DN")
	)
	(arc
		(start 279.192228 -61.257434)
		(mid 279.000586 -61.200268)
		(end 278.860504 -61.057536)
		(width 0.0889)
		(layer "In9.Cu")
		(net "CLK_100M_CPU0_BCLK0_DN")
	)
	(arc
		(start 272.851118 -57.590436)
		(mid 272.64251 -57.378504)
		(end 272.357088 -57.295034)
		(width 0.0889)
		(layer "In9.Cu")
		(net "CLK_100M_CPU0_BCLK0_DN")
	)
	(arc
		(start 277.475188 -60.266834)
		(mid 277.283546 -60.209668)
		(end 277.143464 -60.066936)
		(width 0.0889)
		(layer "In9.Cu")
		(net "CLK_100M_CPU0_BCLK0_DN")
	)
	(arc
		(start 281.771598 -62.743588)
		(mid 281.577748 -62.687238)
		(end 281.436064 -62.543436)
		(width 0.0889)
		(layer "In9.Cu")
		(net "CLK_100M_CPU0_BCLK0_DN")
	)
	(arc
		(start 275.7551 -59.276234)
		(mid 275.565171 -59.218364)
		(end 275.426424 -59.076336)
		(width 0.0889)
		(layer "In9.Cu")
		(net "CLK_100M_CPU0_BCLK0_DN")
	)
	(arc
		(start 276.620478 -59.771534)
		(mid 276.426628 -59.715184)
		(end 276.284944 -59.571382)
		(width 0.0889)
		(layer "In9.Cu")
		(net "CLK_100M_CPU0_BCLK0_DN")
	)
	(arc
		(start 278.860504 -61.057536)
		(mid 278.6535 -60.846672)
		(end 278.370284 -60.762388)
		(width 0.0889)
		(layer "In9.Cu")
		(net "CLK_100M_CPU0_BCLK0_DN")
	)
	(arc
		(start 271.992598 -57.095136)
		(mid 271.785594 -56.884272)
		(end 271.502378 -56.799988)
		(width 0.0889)
		(layer "In9.Cu")
		(net "CLK_100M_CPU0_BCLK0_DN")
	)
	(arc
		(start 277.143464 -60.066936)
		(mid 276.932751 -59.853857)
		(end 276.644608 -59.771534)
		(width 0.0889)
		(layer "In9.Cu")
		(net "CLK_100M_CPU0_BCLK0_DN")
	)
	(arc
		(start 284.011624 -64.029336)
		(mid 283.80462 -63.818472)
		(end 283.521404 -63.734188)
		(width 0.0889)
		(layer "In9.Cu")
		(net "CLK_100M_CPU0_BCLK0_DN")
	)
	(arc
		(start 282.626308 -63.238634)
		(mid 282.434666 -63.181468)
		(end 282.294584 -63.038736)
		(width 0.0889)
		(layer "In9.Cu")
		(net "CLK_100M_CPU0_BCLK0_DN")
	)
	(arc
		(start 278.001984 -60.562236)
		(mid 277.793376 -60.350304)
		(end 277.507954 -60.266834)
		(width 0.0889)
		(layer "In9.Cu")
		(net "CLK_100M_CPU0_BCLK0_DN")
	)
	(arc
		(start 274.902422 -58.780934)
		(mid 274.709319 -58.724415)
		(end 274.568158 -58.581036)
		(width 0.0889)
		(layer "In9.Cu")
		(net "CLK_100M_CPU0_BCLK0_DN")
	)
	(arc
		(start 261.87908 -51.332638)
		(mid 261.672076 -51.121774)
		(end 261.38886 -51.03749)
		(width 0.0889)
		(layer "In9.Cu")
		(net "CLK_100M_CPU0_BCLK0_DN")
	)
	(arc
		(start 263.927844 -52.523136)
		(mid 263.736202 -52.46597)
		(end 263.59612 -52.323238)
		(width 0.0889)
		(layer "In9.Cu")
		(net "CLK_100M_CPU0_BCLK0_DN")
	)
	(arc
		(start 271.345914 -56.799988)
		(mid 271.209245 -56.723195)
		(end 271.109948 -56.601868)
		(width 0.0889)
		(layer "In9.Cu")
		(net "CLK_100M_CPU0_BCLK0_DN")
	)
	(arc
		(start 262.7376 -51.827938)
		(mid 262.528992 -51.616006)
		(end 262.24357 -51.532536)
		(width 0.0889)
		(layer "In9.Cu")
		(net "CLK_100M_CPU0_BCLK0_DN")
	)
	(arc
		(start 283.488638 -63.734188)
		(mid 283.294788 -63.677838)
		(end 283.153104 -63.534036)
		(width 0.0889)
		(layer "In9.Cu")
		(net "CLK_100M_CPU0_BCLK0_DN")
	)
	(arc
		(start 286.582104 -66.4972)
		(mid 286.533349 -66.300848)
		(end 286.58693 -66.105786)
		(width 0.0889)
		(layer "In9.Cu")
		(net "CLK_100M_CPU0_BCLK0_DN")
	)
	(arc
		(start 263.59612 -52.323238)
		(mid 263.389116 -52.112374)
		(end 263.1059 -52.02809)
		(width 0.0889)
		(layer "In9.Cu")
		(net "CLK_100M_CPU0_BCLK0_DN")
	)
	(arc
		(start 286.58693 -66.105786)
		(mid 286.591259 -65.522614)
		(end 286.0929 -65.219834)
		(width 0.0889)
		(layer "In9.Cu")
		(net "CLK_100M_CPU0_BCLK0_DN")
	)
	(arc
		(start 280.909268 -62.248034)
		(mid 280.717626 -62.190868)
		(end 280.577544 -62.048136)
		(width 0.0889)
		(layer "In9.Cu")
		(net "CLK_100M_CPU0_BCLK0_DN")
	)
	(arc
		(start 263.073134 -52.02809)
		(mid 262.879284 -51.97174)
		(end 262.7376 -51.827938)
		(width 0.0889)
		(layer "In9.Cu")
		(net "CLK_100M_CPU0_BCLK0_DN")
	)
	(arc
		(start 286.58693 -67.096386)
		(mid 286.666152 -66.807268)
		(end 286.59328 -66.516504)
		(width 0.0889)
		(layer "In9.Cu")
		(net "CLK_100M_CPU0_BCLK0_DN")
	)
	(arc
		(start 265.64463 -53.513736)
		(mid 265.452988 -53.45657)
		(end 265.312906 -53.313838)
		(width 0.0889)
		(layer "In9.Cu")
		(net "CLK_100M_CPU0_BCLK0_DN")
	)
	(arc
		(start 262.210804 -51.532536)
		(mid 262.019162 -51.47537)
		(end 261.87908 -51.332638)
		(width 0.0889)
		(layer "In9.Cu")
		(net "CLK_100M_CPU0_BCLK0_DN")
	)
	(arc
		(start 279.719024 -61.552836)
		(mid 279.510416 -61.340904)
		(end 279.224994 -61.257434)
		(width 0.0889)
		(layer "In9.Cu")
		(net "CLK_100M_CPU0_BCLK0_DN")
	)
	(arc
		(start 280.577544 -62.048136)
		(mid 280.37054 -61.837272)
		(end 280.087324 -61.752988)
		(width 0.0889)
		(layer "In9.Cu")
		(net "CLK_100M_CPU0_BCLK0_DN")
	)
	(arc
		(start 284.870144 -64.524636)
		(mid 284.661536 -64.312704)
		(end 284.376114 -64.229234)
		(width 0.0889)
		(layer "In9.Cu")
		(net "CLK_100M_CPU0_BCLK0_DN")
	)
	(arc
		(start 272.324322 -57.295034)
		(mid 272.13268 -57.237868)
		(end 271.992598 -57.095136)
		(width 0.0889)
		(layer "In9.Cu")
		(net "CLK_100M_CPU0_BCLK0_DN")
	)
	(arc
		(start 266.171426 -53.809138)
		(mid 265.962818 -53.597206)
		(end 265.677396 -53.513736)
		(width 0.0889)
		(layer "In9.Cu")
		(net "CLK_100M_CPU0_BCLK0_DN")
	)
	(arc
		(start 280.054558 -61.752988)
		(mid 279.860708 -61.696638)
		(end 279.719024 -61.552836)
		(width 0.0889)
		(layer "In9.Cu")
		(net "CLK_100M_CPU0_BCLK0_DN")
	)
	(arc
		(start 286.582104 -67.4878)
		(mid 286.533349 -67.291448)
		(end 286.58693 -67.096386)
		(width 0.0889)
		(layer "In9.Cu")
		(net "CLK_100M_CPU0_BCLK0_DN")
	)
	(arc
		(start 273.186652 -57.790588)
		(mid 272.992802 -57.734238)
		(end 272.851118 -57.590436)
		(width 0.0889)
		(layer "In9.Cu")
		(net "CLK_100M_CPU0_BCLK0_DN")
	)
	(arc
		(start 282.294584 -63.038736)
		(mid 282.08758 -62.827872)
		(end 281.804364 -62.743588)
		(width 0.0889)
		(layer "In9.Cu")
		(net "CLK_100M_CPU0_BCLK0_DN")
	)
	(arc
		(start 265.312906 -53.313838)
		(mid 265.105902 -53.102974)
		(end 264.822686 -53.01869)
		(width 0.0889)
		(layer "In9.Cu")
		(net "CLK_100M_CPU0_BCLK0_DN")
	)
	(arc
		(start 284.343348 -64.229234)
		(mid 284.151706 -64.172068)
		(end 284.011624 -64.029336)
		(width 0.0889)
		(layer "In9.Cu")
		(net "CLK_100M_CPU0_BCLK0_DN")
	)
	(arc
		(start 276.284944 -59.571382)
		(mid 276.07794 -59.360518)
		(end 275.794724 -59.276234)
		(width 0.0889)
		(layer "In9.Cu")
		(net "CLK_100M_CPU0_BCLK0_DN")
	)
	(arc
		(start 266.515342 -54.007766)
		(mid 266.316803 -53.954517)
		(end 266.171426 -53.809138)
		(width 0.0889)
		(layer "In9.Cu")
		(net "CLK_100M_CPU0_BCLK0_DN")
	)
	(arc
		(start 281.436064 -62.543436)
		(mid 281.227456 -62.331504)
		(end 280.942034 -62.248034)
		(width 0.0889)
		(layer "In9.Cu")
		(net "CLK_100M_CPU0_BCLK0_DN")
	)
	(arc
		(start 285.2166 -64.724788)
		(mid 285.019439 -64.672829)
		(end 284.873446 -64.530478)
		(width 0.0889)
		(layer "In9.Cu")
		(net "CLK_100M_CPU0_BCLK0_DN")
	)
	(arc
		(start 274.568158 -58.581036)
		(mid 274.357445 -58.367957)
		(end 274.069302 -58.285634)
		(width 0.0889)
		(layer "In9.Cu")
		(net "CLK_100M_CPU0_BCLK0_DN")
	)
	(arc
		(start 273.709638 -58.085736)
		(mid 273.502634 -57.874872)
		(end 273.219418 -57.790588)
		(width 0.0889)
		(layer "In9.Cu")
		(net "CLK_100M_CPU0_BCLK0_DN")
	)
	(arc
		(start 264.801096 -53.01869)
		(mid 264.603935 -52.966731)
		(end 264.457942 -52.82438)
		(width 0.0889)
		(layer "In9.Cu")
		(net "CLK_100M_CPU0_BCLK0_DN")
	)
	(arc
		(start 283.153104 -63.534036)
		(mid 282.944496 -63.322104)
		(end 282.659074 -63.238634)
		(width 0.0889)
		(layer "In9.Cu")
		(net "CLK_100M_CPU0_BCLK0_DN")
	)
	(arc
		(start 286.060134 -65.219834)
		(mid 285.868492 -65.162668)
		(end 285.72841 -65.019936)
		(width 0.0889)
		(layer "In9.Cu")
		(net "CLK_100M_CPU0_BCLK0_DN")
	)
	(arc
		(start 274.041362 -58.285634)
		(mid 273.84972 -58.228468)
		(end 273.709638 -58.085736)
		(width 0.0889)
		(layer "In9.Cu")
		(net "CLK_100M_CPU0_BCLK0_DN")
	)
	(arc
		(start 264.45464 -52.818538)
		(mid 264.246032 -52.606606)
		(end 263.96061 -52.523136)
		(width 0.0889)
		(layer "In9.Cu")
		(net "CLK_100M_CPU0_BCLK0_DN")
	)
	(segment
		(start 377.33605 -113.28908)
		(end 377.2662 -113.21923)
		(width 0.254)
		(layer "F.Cu")
		(net "A_PCH_XCLK_BIASREF")
	)
	(segment
		(start 377.2662 -113.21923)
		(end 377.2662 -112.644936)
		(width 0.254)
		(layer "F.Cu")
		(net "A_PCH_XCLK_BIASREF")
	)
	(via
		(at 377.128024 -111.918242)
		(size 0.6604)
		(drill 0.3302)
		(layers "F.Cu" "B.Cu")
		(net "A_PCH_XCLK_BIASREF")
	)
	(via
		(at 377.2662 -112.644936)
		(size 0.508)
		(drill 0.254)
		(layers "F.Cu" "B.Cu")
		(net "A_PCH_XCLK_BIASREF")
	)
	(segment
		(start 376.3772 -111.8616)
		(end 376.0724 -111.5568)
		(width 0.254)
		(layer "B.Cu")
		(net "A_PCH_XCLK_BIASREF")
	)
	(segment
		(start 377.2662 -112.056418)
		(end 377.2662 -112.644936)
		(width 0.254)
		(layer "B.Cu")
		(net "A_PCH_XCLK_BIASREF")
	)
	(segment
		(start 376.0724 -111.5568)
		(end 376.0724 -110.9218)
		(width 0.254)
		(layer "B.Cu")
		(net "A_PCH_XCLK_BIASREF")
	)
	(segment
		(start 377.589288 -110.817914)
		(end 377.589288 -111.264192)
		(width 0.254)
		(layer "B.Cu")
		(net "A_PCH_XCLK_BIASREF")
	)
	(segment
		(start 375.7041 -110.5535)
		(end 375.7041 -110.281212)
		(width 0.254)
		(layer "B.Cu")
		(net "A_PCH_XCLK_BIASREF")
	)
	(segment
		(start 376.0724 -110.9218)
		(end 375.7041 -110.5535)
		(width 0.254)
		(layer "B.Cu")
		(net "A_PCH_XCLK_BIASREF")
	)
	(segment
		(start 377.071382 -111.8616)
		(end 376.3772 -111.8616)
		(width 0.254)
		(layer "B.Cu")
		(net "A_PCH_XCLK_BIASREF")
	)
	(segment
		(start 377.128024 -111.918242)
		(end 377.2662 -112.056418)
		(width 0.254)
		(layer "B.Cu")
		(net "A_PCH_XCLK_BIASREF")
	)
	(segment
		(start 377.589288 -111.264192)
		(end 377.128024 -111.725456)
		(width 0.254)
		(layer "B.Cu")
		(net "A_PCH_XCLK_BIASREF")
	)
	(segment
		(start 377.128024 -111.918242)
		(end 377.071382 -111.8616)
		(width 0.254)
		(layer "B.Cu")
		(net "A_PCH_XCLK_BIASREF")
	)
	(segment
		(start 377.128024 -111.725456)
		(end 377.128024 -111.918242)
		(width 0.254)
		(layer "B.Cu")
		(net "A_PCH_XCLK_BIASREF")
	)
	(segment
		(start 114.258852 -84.3661)
		(end 115.1128 -85.220048)
		(width 0.2032)
		(layer "F.Cu")
		(net "A_CPU1_KLM_RCOMP2")
	)
	(segment
		(start 111.5314 -84.1502)
		(end 111.7473 -84.3661)
		(width 0.2032)
		(layer "F.Cu")
		(net "A_CPU1_KLM_RCOMP2")
	)
	(segment
		(start 111.5314 -83.8962)
		(end 111.5314 -84.1502)
		(width 0.2032)
		(layer "F.Cu")
		(net "A_CPU1_KLM_RCOMP2")
	)
	(segment
		(start 115.1128 -85.220048)
		(end 115.1128 -85.2297)
		(width 0.2032)
		(layer "F.Cu")
		(net "A_CPU1_KLM_RCOMP2")
	)
	(segment
		(start 111.7473 -84.3661)
		(end 114.258852 -84.3661)
		(width 0.2032)
		(layer "F.Cu")
		(net "A_CPU1_KLM_RCOMP2")
	)
	(segment
		(start 99.513898 -90.756486)
		(end 98.942398 -90.756486)
		(width 0.2032)
		(layer "F.Cu")
		(net "A_CPU1_KLM_RCOMP2")
	)
	(via
		(at 115.1128 -85.2297)
		(size 0.508)
		(drill 0.254)
		(layers "F.Cu" "B.Cu")
		(net "A_CPU1_KLM_RCOMP2")
	)
	(via
		(at 98.942398 -90.756486)
		(size 0.508)
		(drill 0.254)
		(layers "F.Cu" "B.Cu")
		(net "A_CPU1_KLM_RCOMP2")
	)
	(segment
		(start 99.949762 -90.756486)
		(end 98.942398 -90.756486)
		(width 0.2032)
		(layer "In9.Cu")
		(net "A_CPU1_KLM_RCOMP2")
	)
	(segment
		(start 113.177066 -89.83853)
		(end 113.229898 -89.891362)
		(width 0.2032)
		(layer "In9.Cu")
		(net "A_CPU1_KLM_RCOMP2")
	)
	(segment
		(start 108.252514 -92.02166)
		(end 107.836716 -91.605862)
		(width 0.2032)
		(layer "In9.Cu")
		(net "A_CPU1_KLM_RCOMP2")
	)
	(segment
		(start 108.670852 -92.02166)
		(end 108.252514 -92.02166)
		(width 0.2032)
		(layer "In9.Cu")
		(net "A_CPU1_KLM_RCOMP2")
	)
	(segment
		(start 100.484686 -91.29141)
		(end 99.949762 -90.756486)
		(width 0.2032)
		(layer "In9.Cu")
		(net "A_CPU1_KLM_RCOMP2")
	)
	(segment
		(start 111.726726 -91.110308)
		(end 111.31042 -91.526614)
		(width 0.2032)
		(layer "In9.Cu")
		(net "A_CPU1_KLM_RCOMP2")
	)
	(segment
		(start 107.836716 -91.605862)
		(end 105.60939 -91.605862)
		(width 0.2032)
		(layer "In9.Cu")
		(net "A_CPU1_KLM_RCOMP2")
	)
	(segment
		(start 113.524792 -89.129108)
		(end 113.443766 -89.129108)
		(width 0.2032)
		(layer "In9.Cu")
		(net "A_CPU1_KLM_RCOMP2")
	)
	(segment
		(start 112.599724 -90.536014)
		(end 112.02543 -91.110308)
		(width 0.2032)
		(layer "In9.Cu")
		(net "A_CPU1_KLM_RCOMP2")
	)
	(segment
		(start 115.1128 -85.2297)
		(end 115.181126 -85.298026)
		(width 0.2032)
		(layer "In9.Cu")
		(net "A_CPU1_KLM_RCOMP2")
	)
	(segment
		(start 111.31042 -91.526614)
		(end 110.882938 -91.526614)
		(width 0.2032)
		(layer "In9.Cu")
		(net "A_CPU1_KLM_RCOMP2")
	)
	(segment
		(start 110.387892 -92.02166)
		(end 109.94517 -92.02166)
		(width 0.2032)
		(layer "In9.Cu")
		(net "A_CPU1_KLM_RCOMP2")
	)
	(segment
		(start 113.229898 -89.891362)
		(end 113.229898 -90.269314)
		(width 0.2032)
		(layer "In9.Cu")
		(net "A_CPU1_KLM_RCOMP2")
	)
	(segment
		(start 102.187248 -92.202762)
		(end 101.77145 -91.786964)
		(width 0.2032)
		(layer "In9.Cu")
		(net "A_CPU1_KLM_RCOMP2")
	)
	(segment
		(start 103.805736 -91.770708)
		(end 103.373682 -92.202762)
		(width 0.2032)
		(layer "In9.Cu")
		(net "A_CPU1_KLM_RCOMP2")
	)
	(segment
		(start 112.963198 -90.536014)
		(end 112.599724 -90.536014)
		(width 0.2032)
		(layer "In9.Cu")
		(net "A_CPU1_KLM_RCOMP2")
	)
	(segment
		(start 115.233958 -87.419942)
		(end 113.524792 -89.129108)
		(width 0.2032)
		(layer "In9.Cu")
		(net "A_CPU1_KLM_RCOMP2")
	)
	(segment
		(start 113.443766 -89.129108)
		(end 113.177066 -89.395808)
		(width 0.2032)
		(layer "In9.Cu")
		(net "A_CPU1_KLM_RCOMP2")
	)
	(segment
		(start 113.229898 -90.269314)
		(end 112.963198 -90.536014)
		(width 0.2032)
		(layer "In9.Cu")
		(net "A_CPU1_KLM_RCOMP2")
	)
	(segment
		(start 109.08665 -91.605862)
		(end 108.670852 -92.02166)
		(width 0.2032)
		(layer "In9.Cu")
		(net "A_CPU1_KLM_RCOMP2")
	)
	(segment
		(start 105.60939 -91.605862)
		(end 105.444544 -91.770708)
		(width 0.2032)
		(layer "In9.Cu")
		(net "A_CPU1_KLM_RCOMP2")
	)
	(segment
		(start 109.529372 -91.605862)
		(end 109.08665 -91.605862)
		(width 0.2032)
		(layer "In9.Cu")
		(net "A_CPU1_KLM_RCOMP2")
	)
	(segment
		(start 110.882938 -91.526614)
		(end 110.387892 -92.02166)
		(width 0.2032)
		(layer "In9.Cu")
		(net "A_CPU1_KLM_RCOMP2")
	)
	(segment
		(start 115.181126 -86.726014)
		(end 115.233958 -86.778846)
		(width 0.2032)
		(layer "In9.Cu")
		(net "A_CPU1_KLM_RCOMP2")
	)
	(segment
		(start 115.233958 -86.778846)
		(end 115.233958 -87.419942)
		(width 0.2032)
		(layer "In9.Cu")
		(net "A_CPU1_KLM_RCOMP2")
	)
	(segment
		(start 100.84816 -91.29141)
		(end 100.484686 -91.29141)
		(width 0.2032)
		(layer "In9.Cu")
		(net "A_CPU1_KLM_RCOMP2")
	)
	(segment
		(start 113.177066 -89.395808)
		(end 113.177066 -89.83853)
		(width 0.2032)
		(layer "In9.Cu")
		(net "A_CPU1_KLM_RCOMP2")
	)
	(segment
		(start 112.02543 -91.110308)
		(end 111.726726 -91.110308)
		(width 0.2032)
		(layer "In9.Cu")
		(net "A_CPU1_KLM_RCOMP2")
	)
	(segment
		(start 103.373682 -92.202762)
		(end 102.187248 -92.202762)
		(width 0.2032)
		(layer "In9.Cu")
		(net "A_CPU1_KLM_RCOMP2")
	)
	(segment
		(start 101.77145 -91.786964)
		(end 101.343714 -91.786964)
		(width 0.2032)
		(layer "In9.Cu")
		(net "A_CPU1_KLM_RCOMP2")
	)
	(segment
		(start 101.343714 -91.786964)
		(end 100.84816 -91.29141)
		(width 0.2032)
		(layer "In9.Cu")
		(net "A_CPU1_KLM_RCOMP2")
	)
	(segment
		(start 105.444544 -91.770708)
		(end 103.805736 -91.770708)
		(width 0.2032)
		(layer "In9.Cu")
		(net "A_CPU1_KLM_RCOMP2")
	)
	(segment
		(start 115.181126 -85.298026)
		(end 115.181126 -86.726014)
		(width 0.2032)
		(layer "In9.Cu")
		(net "A_CPU1_KLM_RCOMP2")
	)
	(segment
		(start 109.94517 -92.02166)
		(end 109.529372 -91.605862)
		(width 0.2032)
		(layer "In9.Cu")
		(net "A_CPU1_KLM_RCOMP2")
	)
	(segment
		(start 110.7694 -83.9724)
		(end 110.7694 -83.8962)
		(width 0.2032)
		(layer "F.Cu")
		(net "A_CPU1_KLM_RCOMP1")
	)
	(segment
		(start 114.4778 -85.2297)
		(end 114.060224 -84.812124)
		(width 0.2032)
		(layer "F.Cu")
		(net "A_CPU1_KLM_RCOMP1")
	)
	(segment
		(start 114.060224 -84.812124)
		(end 111.609124 -84.812124)
		(width 0.2032)
		(layer "F.Cu")
		(net "A_CPU1_KLM_RCOMP1")
	)
	(segment
		(start 111.609124 -84.812124)
		(end 110.7694 -83.9724)
		(width 0.2032)
		(layer "F.Cu")
		(net "A_CPU1_KLM_RCOMP1")
	)
	(segment
		(start 101.230684 -90.756486)
		(end 100.659184 -90.756486)
		(width 0.2032)
		(layer "F.Cu")
		(net "A_CPU1_KLM_RCOMP1")
	)
	(via
		(at 100.659184 -90.756486)
		(size 0.508)
		(drill 0.254)
		(layers "F.Cu" "B.Cu")
		(net "A_CPU1_KLM_RCOMP1")
	)
	(via
		(at 114.4778 -85.2297)
		(size 0.508)
		(drill 0.254)
		(layers "F.Cu" "B.Cu")
		(net "A_CPU1_KLM_RCOMP1")
	)
	(segment
		(start 106.059478 -90.796364)
		(end 102.980998 -90.796364)
		(width 0.2032)
		(layer "In9.Cu")
		(net "A_CPU1_KLM_RCOMP1")
	)
	(segment
		(start 114.108738 -87.983314)
		(end 113.781332 -87.983314)
		(width 0.2032)
		(layer "In9.Cu")
		(net "A_CPU1_KLM_RCOMP1")
	)
	(segment
		(start 112.4585 -89.306146)
		(end 112.4585 -89.686638)
		(width 0.2032)
		(layer "In9.Cu")
		(net "A_CPU1_KLM_RCOMP1")
	)
	(segment
		(start 113.781332 -87.983314)
		(end 112.4585 -89.306146)
		(width 0.2032)
		(layer "In9.Cu")
		(net "A_CPU1_KLM_RCOMP1")
	)
	(segment
		(start 102.187248 -91.212162)
		(end 101.731572 -90.756486)
		(width 0.2032)
		(layer "In9.Cu")
		(net "A_CPU1_KLM_RCOMP1")
	)
	(segment
		(start 108.670852 -91.03106)
		(end 108.277914 -91.03106)
		(width 0.2032)
		(layer "In9.Cu")
		(net "A_CPU1_KLM_RCOMP1")
	)
	(segment
		(start 108.277914 -91.03106)
		(end 107.862116 -90.615262)
		(width 0.2032)
		(layer "In9.Cu")
		(net "A_CPU1_KLM_RCOMP1")
	)
	(segment
		(start 102.980998 -90.796364)
		(end 102.5652 -91.212162)
		(width 0.2032)
		(layer "In9.Cu")
		(net "A_CPU1_KLM_RCOMP1")
	)
	(segment
		(start 106.24058 -90.615262)
		(end 106.059478 -90.796364)
		(width 0.2032)
		(layer "In9.Cu")
		(net "A_CPU1_KLM_RCOMP1")
	)
	(segment
		(start 112.02543 -90.119708)
		(end 111.726726 -90.119708)
		(width 0.2032)
		(layer "In9.Cu")
		(net "A_CPU1_KLM_RCOMP1")
	)
	(segment
		(start 111.726726 -90.119708)
		(end 111.231172 -90.615262)
		(width 0.2032)
		(layer "In9.Cu")
		(net "A_CPU1_KLM_RCOMP1")
	)
	(segment
		(start 109.529372 -90.615262)
		(end 109.08665 -90.615262)
		(width 0.2032)
		(layer "In9.Cu")
		(net "A_CPU1_KLM_RCOMP1")
	)
	(segment
		(start 101.731572 -90.756486)
		(end 100.659184 -90.756486)
		(width 0.2032)
		(layer "In9.Cu")
		(net "A_CPU1_KLM_RCOMP1")
	)
	(segment
		(start 114.322606 -87.22106)
		(end 114.375438 -87.273892)
		(width 0.2032)
		(layer "In9.Cu")
		(net "A_CPU1_KLM_RCOMP1")
	)
	(segment
		(start 110.387892 -91.03106)
		(end 109.94517 -91.03106)
		(width 0.2032)
		(layer "In9.Cu")
		(net "A_CPU1_KLM_RCOMP1")
	)
	(segment
		(start 110.80369 -90.615262)
		(end 110.387892 -91.03106)
		(width 0.2032)
		(layer "In9.Cu")
		(net "A_CPU1_KLM_RCOMP1")
	)
	(segment
		(start 109.08665 -90.615262)
		(end 108.670852 -91.03106)
		(width 0.2032)
		(layer "In9.Cu")
		(net "A_CPU1_KLM_RCOMP1")
	)
	(segment
		(start 114.322606 -85.384894)
		(end 114.322606 -87.22106)
		(width 0.2032)
		(layer "In9.Cu")
		(net "A_CPU1_KLM_RCOMP1")
	)
	(segment
		(start 112.4585 -89.686638)
		(end 112.02543 -90.119708)
		(width 0.2032)
		(layer "In9.Cu")
		(net "A_CPU1_KLM_RCOMP1")
	)
	(segment
		(start 114.375438 -87.716614)
		(end 114.108738 -87.983314)
		(width 0.2032)
		(layer "In9.Cu")
		(net "A_CPU1_KLM_RCOMP1")
	)
	(segment
		(start 107.862116 -90.615262)
		(end 106.24058 -90.615262)
		(width 0.2032)
		(layer "In9.Cu")
		(net "A_CPU1_KLM_RCOMP1")
	)
	(segment
		(start 111.231172 -90.615262)
		(end 110.80369 -90.615262)
		(width 0.2032)
		(layer "In9.Cu")
		(net "A_CPU1_KLM_RCOMP1")
	)
	(segment
		(start 114.375438 -87.273892)
		(end 114.375438 -87.716614)
		(width 0.2032)
		(layer "In9.Cu")
		(net "A_CPU1_KLM_RCOMP1")
	)
	(segment
		(start 114.4778 -85.2297)
		(end 114.322606 -85.384894)
		(width 0.2032)
		(layer "In9.Cu")
		(net "A_CPU1_KLM_RCOMP1")
	)
	(segment
		(start 109.94517 -91.03106)
		(end 109.529372 -90.615262)
		(width 0.2032)
		(layer "In9.Cu")
		(net "A_CPU1_KLM_RCOMP1")
	)
	(segment
		(start 102.5652 -91.212162)
		(end 102.187248 -91.212162)
		(width 0.2032)
		(layer "In9.Cu")
		(net "A_CPU1_KLM_RCOMP1")
	)
	(segment
		(start 110.0074 -83.9724)
		(end 110.0074 -83.8962)
		(width 0.2032)
		(layer "F.Cu")
		(net "A_CPU1_KLM_RCOMP0")
	)
	(segment
		(start 113.7412 -85.3186)
		(end 113.6396 -85.217)
		(width 0.2032)
		(layer "F.Cu")
		(net "A_CPU1_KLM_RCOMP0")
	)
	(segment
		(start 100.372164 -90.26144)
		(end 99.800664 -90.26144)
		(width 0.2032)
		(layer "F.Cu")
		(net "A_CPU1_KLM_RCOMP0")
	)
	(segment
		(start 113.6396 -85.217)
		(end 111.252 -85.217)
		(width 0.2032)
		(layer "F.Cu")
		(net "A_CPU1_KLM_RCOMP0")
	)
	(segment
		(start 111.252 -85.217)
		(end 110.0074 -83.9724)
		(width 0.2032)
		(layer "F.Cu")
		(net "A_CPU1_KLM_RCOMP0")
	)
	(via
		(at 99.800664 -90.26144)
		(size 0.508)
		(drill 0.254)
		(layers "F.Cu" "B.Cu")
		(net "A_CPU1_KLM_RCOMP0")
	)
	(via
		(at 113.7412 -85.3186)
		(size 0.508)
		(drill 0.254)
		(layers "F.Cu" "B.Cu")
		(net "A_CPU1_KLM_RCOMP0")
	)
	(segment
		(start 113.8428 -86.233508)
		(end 111.747046 -88.329262)
		(width 0.2032)
		(layer "In9.Cu")
		(net "A_CPU1_KLM_RCOMP0")
	)
	(segment
		(start 101.263958 -89.805764)
		(end 100.84816 -90.221562)
		(width 0.2032)
		(layer "In9.Cu")
		(net "A_CPU1_KLM_RCOMP0")
	)
	(segment
		(start 99.840542 -90.221562)
		(end 99.800664 -90.26144)
		(width 0.2032)
		(layer "In9.Cu")
		(net "A_CPU1_KLM_RCOMP0")
	)
	(segment
		(start 107.253278 -89.805764)
		(end 102.980998 -89.805764)
		(width 0.2032)
		(layer "In9.Cu")
		(net "A_CPU1_KLM_RCOMP0")
	)
	(segment
		(start 100.84816 -90.221562)
		(end 99.840542 -90.221562)
		(width 0.2032)
		(layer "In9.Cu")
		(net "A_CPU1_KLM_RCOMP0")
	)
	(segment
		(start 107.877102 -89.624662)
		(end 107.43438 -89.624662)
		(width 0.2032)
		(layer "In9.Cu")
		(net "A_CPU1_KLM_RCOMP0")
	)
	(segment
		(start 108.2929 -90.04046)
		(end 107.877102 -89.624662)
		(width 0.2032)
		(layer "In9.Cu")
		(net "A_CPU1_KLM_RCOMP0")
	)
	(segment
		(start 102.980998 -89.805764)
		(end 102.5652 -90.221562)
		(width 0.2032)
		(layer "In9.Cu")
		(net "A_CPU1_KLM_RCOMP0")
	)
	(segment
		(start 109.594142 -89.624662)
		(end 109.15142 -89.624662)
		(width 0.2032)
		(layer "In9.Cu")
		(net "A_CPU1_KLM_RCOMP0")
	)
	(segment
		(start 102.187248 -90.221562)
		(end 101.77145 -89.805764)
		(width 0.2032)
		(layer "In9.Cu")
		(net "A_CPU1_KLM_RCOMP0")
	)
	(segment
		(start 101.77145 -89.805764)
		(end 101.263958 -89.805764)
		(width 0.2032)
		(layer "In9.Cu")
		(net "A_CPU1_KLM_RCOMP0")
	)
	(segment
		(start 113.7412 -85.3186)
		(end 113.8428 -85.4202)
		(width 0.2032)
		(layer "In9.Cu")
		(net "A_CPU1_KLM_RCOMP0")
	)
	(segment
		(start 102.5652 -90.221562)
		(end 102.187248 -90.221562)
		(width 0.2032)
		(layer "In9.Cu")
		(net "A_CPU1_KLM_RCOMP0")
	)
	(segment
		(start 110.387892 -90.04046)
		(end 110.00994 -90.04046)
		(width 0.2032)
		(layer "In9.Cu")
		(net "A_CPU1_KLM_RCOMP0")
	)
	(segment
		(start 111.747046 -88.329262)
		(end 111.747046 -88.681306)
		(width 0.2032)
		(layer "In9.Cu")
		(net "A_CPU1_KLM_RCOMP0")
	)
	(segment
		(start 109.15142 -89.624662)
		(end 108.735622 -90.04046)
		(width 0.2032)
		(layer "In9.Cu")
		(net "A_CPU1_KLM_RCOMP0")
	)
	(segment
		(start 111.747046 -88.681306)
		(end 110.387892 -90.04046)
		(width 0.2032)
		(layer "In9.Cu")
		(net "A_CPU1_KLM_RCOMP0")
	)
	(segment
		(start 110.00994 -90.04046)
		(end 109.594142 -89.624662)
		(width 0.2032)
		(layer "In9.Cu")
		(net "A_CPU1_KLM_RCOMP0")
	)
	(segment
		(start 113.8428 -85.4202)
		(end 113.8428 -86.233508)
		(width 0.2032)
		(layer "In9.Cu")
		(net "A_CPU1_KLM_RCOMP0")
	)
	(segment
		(start 108.735622 -90.04046)
		(end 108.2929 -90.04046)
		(width 0.2032)
		(layer "In9.Cu")
		(net "A_CPU1_KLM_RCOMP0")
	)
	(segment
		(start 107.43438 -89.624662)
		(end 107.253278 -89.805764)
		(width 0.2032)
		(layer "In9.Cu")
		(net "A_CPU1_KLM_RCOMP0")
	)
	(segment
		(start 106.480356 -62.343538)
		(end 107.051856 -62.343538)
		(width 0.254)
		(layer "F.Cu")
		(net "A_CPU1_GHJ_RCOMP2")
	)
	(via
		(at 106.480356 -62.343538)
		(size 0.508)
		(drill 0.254)
		(layers "F.Cu" "B.Cu")
		(net "A_CPU1_GHJ_RCOMP2")
	)
	(via
		(at 117.1956 -69.7484)
		(size 0.6604)
		(drill 0.3302)
		(layers "F.Cu" "B.Cu")
		(net "A_CPU1_GHJ_RCOMP2")
	)
	(segment
		(start 111.442246 -63.789814)
		(end 111.80572 -63.789814)
		(width 0.2032)
		(layer "B.Cu")
		(net "A_CPU1_GHJ_RCOMP2")
	)
	(segment
		(start 116.898166 -69.450966)
		(end 117.1956 -69.7484)
		(width 0.2032)
		(layer "B.Cu")
		(net "A_CPU1_GHJ_RCOMP2")
	)
	(segment
		(start 113.52276 -64.780414)
		(end 114.097054 -65.354708)
		(width 0.2032)
		(layer "B.Cu")
		(net "A_CPU1_GHJ_RCOMP2")
	)
	(segment
		(start 117.238018 -67.107562)
		(end 117.238018 -68.308982)
		(width 0.2032)
		(layer "B.Cu")
		(net "A_CPU1_GHJ_RCOMP2")
	)
	(segment
		(start 114.395758 -65.354708)
		(end 114.891312 -65.850262)
		(width 0.2032)
		(layer "B.Cu")
		(net "A_CPU1_GHJ_RCOMP2")
	)
	(segment
		(start 116.971318 -66.840862)
		(end 117.238018 -67.107562)
		(width 0.2032)
		(layer "B.Cu")
		(net "A_CPU1_GHJ_RCOMP2")
	)
	(segment
		(start 110.946692 -63.29426)
		(end 111.442246 -63.789814)
		(width 0.2032)
		(layer "B.Cu")
		(net "A_CPU1_GHJ_RCOMP2")
	)
	(segment
		(start 116.898166 -68.648834)
		(end 116.898166 -69.450966)
		(width 0.2032)
		(layer "B.Cu")
		(net "A_CPU1_GHJ_RCOMP2")
	)
	(segment
		(start 117.1956 -69.7484)
		(end 117.1956 -71.882)
		(width 0.254)
		(layer "B.Cu")
		(net "A_CPU1_GHJ_RCOMP2")
	)
	(segment
		(start 111.80572 -63.789814)
		(end 112.300766 -64.28486)
		(width 0.2032)
		(layer "B.Cu")
		(net "A_CPU1_GHJ_RCOMP2")
	)
	(segment
		(start 110.583726 -63.29426)
		(end 110.946692 -63.29426)
		(width 0.2032)
		(layer "B.Cu")
		(net "A_CPU1_GHJ_RCOMP2")
	)
	(segment
		(start 115.254278 -65.850262)
		(end 115.749324 -66.345308)
		(width 0.2032)
		(layer "B.Cu")
		(net "A_CPU1_GHJ_RCOMP2")
	)
	(segment
		(start 116.129308 -66.345308)
		(end 116.624862 -66.840862)
		(width 0.2032)
		(layer "B.Cu")
		(net "A_CPU1_GHJ_RCOMP2")
	)
	(segment
		(start 110.154466 -62.865)
		(end 110.583726 -63.29426)
		(width 0.2032)
		(layer "B.Cu")
		(net "A_CPU1_GHJ_RCOMP2")
	)
	(segment
		(start 115.749324 -66.345308)
		(end 116.129308 -66.345308)
		(width 0.2032)
		(layer "B.Cu")
		(net "A_CPU1_GHJ_RCOMP2")
	)
	(segment
		(start 106.480356 -62.343538)
		(end 107.504738 -62.343538)
		(width 0.2032)
		(layer "B.Cu")
		(net "A_CPU1_GHJ_RCOMP2")
	)
	(segment
		(start 114.891312 -65.850262)
		(end 115.254278 -65.850262)
		(width 0.2032)
		(layer "B.Cu")
		(net "A_CPU1_GHJ_RCOMP2")
	)
	(segment
		(start 109.728 -62.865)
		(end 110.154466 -62.865)
		(width 0.2032)
		(layer "B.Cu")
		(net "A_CPU1_GHJ_RCOMP2")
	)
	(segment
		(start 109.16666 -62.30366)
		(end 109.728 -62.865)
		(width 0.2032)
		(layer "B.Cu")
		(net "A_CPU1_GHJ_RCOMP2")
	)
	(segment
		(start 112.663732 -64.28486)
		(end 113.159286 -64.780414)
		(width 0.2032)
		(layer "B.Cu")
		(net "A_CPU1_GHJ_RCOMP2")
	)
	(segment
		(start 107.960414 -61.887862)
		(end 108.451142 -61.887862)
		(width 0.2032)
		(layer "B.Cu")
		(net "A_CPU1_GHJ_RCOMP2")
	)
	(segment
		(start 108.86694 -62.30366)
		(end 109.16666 -62.30366)
		(width 0.2032)
		(layer "B.Cu")
		(net "A_CPU1_GHJ_RCOMP2")
	)
	(segment
		(start 113.159286 -64.780414)
		(end 113.52276 -64.780414)
		(width 0.2032)
		(layer "B.Cu")
		(net "A_CPU1_GHJ_RCOMP2")
	)
	(segment
		(start 107.504738 -62.343538)
		(end 107.960414 -61.887862)
		(width 0.2032)
		(layer "B.Cu")
		(net "A_CPU1_GHJ_RCOMP2")
	)
	(segment
		(start 112.300766 -64.28486)
		(end 112.663732 -64.28486)
		(width 0.2032)
		(layer "B.Cu")
		(net "A_CPU1_GHJ_RCOMP2")
	)
	(segment
		(start 108.451142 -61.887862)
		(end 108.86694 -62.30366)
		(width 0.2032)
		(layer "B.Cu")
		(net "A_CPU1_GHJ_RCOMP2")
	)
	(segment
		(start 114.097054 -65.354708)
		(end 114.395758 -65.354708)
		(width 0.2032)
		(layer "B.Cu")
		(net "A_CPU1_GHJ_RCOMP2")
	)
	(segment
		(start 116.624862 -66.840862)
		(end 116.971318 -66.840862)
		(width 0.2032)
		(layer "B.Cu")
		(net "A_CPU1_GHJ_RCOMP2")
	)
	(segment
		(start 117.238018 -68.308982)
		(end 116.898166 -68.648834)
		(width 0.2032)
		(layer "B.Cu")
		(net "A_CPU1_GHJ_RCOMP2")
	)
	(segment
		(start 105.571036 -61.847984)
		(end 106.193336 -61.847984)
		(width 0.254)
		(layer "F.Cu")
		(net "A_CPU1_GHJ_RCOMP1")
	)
	(via
		(at 105.571036 -61.847984)
		(size 0.508)
		(drill 0.254)
		(layers "F.Cu" "B.Cu")
		(net "A_CPU1_GHJ_RCOMP1")
	)
	(segment
		(start 105.571036 -61.847984)
		(end 106.655616 -61.847984)
		(width 0.2032)
		(layer "B.Cu")
		(net "A_CPU1_GHJ_RCOMP1")
	)
	(segment
		(start 114.36858 -64.28486)
		(end 114.532918 -64.449198)
		(width 0.1778)
		(layer "B.Cu")
		(net "A_CPU1_GHJ_RCOMP1")
	)
	(segment
		(start 116.95684 -65.771014)
		(end 117.451886 -66.26606)
		(width 0.2032)
		(layer "B.Cu")
		(net "A_CPU1_GHJ_RCOMP1")
	)
	(segment
		(start 110.08868 -61.808614)
		(end 110.583726 -62.30366)
		(width 0.2032)
		(layer "B.Cu")
		(net "A_CPU1_GHJ_RCOMP1")
	)
	(segment
		(start 118.096538 -66.612008)
		(end 118.096538 -67.04965)
		(width 0.2032)
		(layer "B.Cu")
		(net "A_CPU1_GHJ_RCOMP1")
	)
	(segment
		(start 116.529104 -65.771014)
		(end 116.95684 -65.771014)
		(width 0.2032)
		(layer "B.Cu")
		(net "A_CPU1_GHJ_RCOMP1")
	)
	(segment
		(start 108.00842 -60.897262)
		(end 108.386372 -60.897262)
		(width 0.2032)
		(layer "B.Cu")
		(net "A_CPU1_GHJ_RCOMP1")
	)
	(segment
		(start 118.096538 -67.04965)
		(end 117.890036 -67.256152)
		(width 0.2032)
		(layer "B.Cu")
		(net "A_CPU1_GHJ_RCOMP1")
	)
	(segment
		(start 112.300766 -63.29426)
		(end 112.663732 -63.29426)
		(width 0.2032)
		(layer "B.Cu")
		(net "A_CPU1_GHJ_RCOMP1")
	)
	(segment
		(start 113.953036 -64.28486)
		(end 114.36858 -64.28486)
		(width 0.1778)
		(layer "B.Cu")
		(net "A_CPU1_GHJ_RCOMP1")
	)
	(segment
		(start 106.655616 -61.847984)
		(end 107.111292 -61.392308)
		(width 0.2032)
		(layer "B.Cu")
		(net "A_CPU1_GHJ_RCOMP1")
	)
	(segment
		(start 111.442246 -62.799214)
		(end 111.80572 -62.799214)
		(width 0.2032)
		(layer "B.Cu")
		(net "A_CPU1_GHJ_RCOMP1")
	)
	(segment
		(start 117.890036 -70.095364)
		(end 117.6655 -70.3199)
		(width 0.2032)
		(layer "B.Cu")
		(net "A_CPU1_GHJ_RCOMP1")
	)
	(segment
		(start 110.583726 -62.30366)
		(end 110.946692 -62.30366)
		(width 0.2032)
		(layer "B.Cu")
		(net "A_CPU1_GHJ_RCOMP1")
	)
	(segment
		(start 117.348 -72.644)
		(end 117.1956 -72.644)
		(width 0.2032)
		(layer "B.Cu")
		(net "A_CPU1_GHJ_RCOMP1")
	)
	(segment
		(start 111.80572 -62.799214)
		(end 112.300766 -63.29426)
		(width 0.2032)
		(layer "B.Cu")
		(net "A_CPU1_GHJ_RCOMP1")
	)
	(segment
		(start 109.287818 -61.371226)
		(end 109.725206 -61.808614)
		(width 0.2032)
		(layer "B.Cu")
		(net "A_CPU1_GHJ_RCOMP1")
	)
	(segment
		(start 115.259612 -64.864996)
		(end 115.749324 -65.354708)
		(width 0.2032)
		(layer "B.Cu")
		(net "A_CPU1_GHJ_RCOMP1")
	)
	(segment
		(start 117.75059 -66.26606)
		(end 118.096538 -66.612008)
		(width 0.2032)
		(layer "B.Cu")
		(net "A_CPU1_GHJ_RCOMP1")
	)
	(segment
		(start 113.159286 -63.789814)
		(end 113.45799 -63.789814)
		(width 0.2032)
		(layer "B.Cu")
		(net "A_CPU1_GHJ_RCOMP1")
	)
	(segment
		(start 113.45799 -63.789814)
		(end 113.953036 -64.28486)
		(width 0.2032)
		(layer "B.Cu")
		(net "A_CPU1_GHJ_RCOMP1")
	)
	(segment
		(start 117.890036 -67.256152)
		(end 117.890036 -70.095364)
		(width 0.2032)
		(layer "B.Cu")
		(net "A_CPU1_GHJ_RCOMP1")
	)
	(segment
		(start 116.112798 -65.354708)
		(end 116.529104 -65.771014)
		(width 0.2032)
		(layer "B.Cu")
		(net "A_CPU1_GHJ_RCOMP1")
	)
	(segment
		(start 115.749324 -65.354708)
		(end 116.112798 -65.354708)
		(width 0.2032)
		(layer "B.Cu")
		(net "A_CPU1_GHJ_RCOMP1")
	)
	(segment
		(start 114.532918 -64.449198)
		(end 114.603022 -64.618362)
		(width 0.1778)
		(layer "B.Cu")
		(net "A_CPU1_GHJ_RCOMP1")
	)
	(segment
		(start 108.860336 -61.371226)
		(end 109.287818 -61.371226)
		(width 0.2032)
		(layer "B.Cu")
		(net "A_CPU1_GHJ_RCOMP1")
	)
	(segment
		(start 117.6655 -70.3199)
		(end 117.6655 -72.3265)
		(width 0.2032)
		(layer "B.Cu")
		(net "A_CPU1_GHJ_RCOMP1")
	)
	(segment
		(start 107.513374 -61.392308)
		(end 108.00842 -60.897262)
		(width 0.2032)
		(layer "B.Cu")
		(net "A_CPU1_GHJ_RCOMP1")
	)
	(segment
		(start 110.946692 -62.30366)
		(end 111.442246 -62.799214)
		(width 0.2032)
		(layer "B.Cu")
		(net "A_CPU1_GHJ_RCOMP1")
	)
	(segment
		(start 109.725206 -61.808614)
		(end 110.08868 -61.808614)
		(width 0.2032)
		(layer "B.Cu")
		(net "A_CPU1_GHJ_RCOMP1")
	)
	(segment
		(start 108.386372 -60.897262)
		(end 108.860336 -61.371226)
		(width 0.2032)
		(layer "B.Cu")
		(net "A_CPU1_GHJ_RCOMP1")
	)
	(segment
		(start 107.111292 -61.392308)
		(end 107.513374 -61.392308)
		(width 0.2032)
		(layer "B.Cu")
		(net "A_CPU1_GHJ_RCOMP1")
	)
	(segment
		(start 112.663732 -63.29426)
		(end 113.159286 -63.789814)
		(width 0.2032)
		(layer "B.Cu")
		(net "A_CPU1_GHJ_RCOMP1")
	)
	(segment
		(start 117.6655 -72.3265)
		(end 117.348 -72.644)
		(width 0.2032)
		(layer "B.Cu")
		(net "A_CPU1_GHJ_RCOMP1")
	)
	(segment
		(start 117.451886 -66.26606)
		(end 117.75059 -66.26606)
		(width 0.2032)
		(layer "B.Cu")
		(net "A_CPU1_GHJ_RCOMP1")
	)
	(segment
		(start 114.603022 -64.618362)
		(end 114.849656 -64.864996)
		(width 0.1778)
		(layer "B.Cu")
		(net "A_CPU1_GHJ_RCOMP1")
	)
	(segment
		(start 114.849656 -64.864996)
		(end 115.259612 -64.864996)
		(width 0.1778)
		(layer "B.Cu")
		(net "A_CPU1_GHJ_RCOMP1")
	)
	(segment
		(start 106.193336 -60.857384)
		(end 105.571036 -60.857384)
		(width 0.254)
		(layer "F.Cu")
		(net "A_CPU1_GHJ_RCOMP0")
	)
	(via
		(at 105.571036 -60.857384)
		(size 0.508)
		(drill 0.254)
		(layers "F.Cu" "B.Cu")
		(net "A_CPU1_GHJ_RCOMP0")
	)
	(via
		(at 118.4402 -70.5358)
		(size 0.6604)
		(drill 0.3302)
		(layers "F.Cu" "B.Cu")
		(net "A_CPU1_GHJ_RCOMP0")
	)
	(segment
		(start 119.895874 -67.897248)
		(end 119.895874 -67.694556)
		(width 0.1778)
		(layer "B.Cu")
		(net "A_CPU1_GHJ_RCOMP0")
	)
	(segment
		(start 112.289336 -62.357)
		(end 111.820198 -61.887862)
		(width 0.2032)
		(layer "B.Cu")
		(net "A_CPU1_GHJ_RCOMP0")
	)
	(segment
		(start 110.598204 -61.392308)
		(end 110.103158 -60.897262)
		(width 0.2032)
		(layer "B.Cu")
		(net "A_CPU1_GHJ_RCOMP0")
	)
	(segment
		(start 117.814852 -65.27546)
		(end 117.451886 -65.27546)
		(width 0.2032)
		(layer "B.Cu")
		(net "A_CPU1_GHJ_RCOMP0")
	)
	(segment
		(start 119.895874 -67.694556)
		(end 119.709184 -67.24396)
		(width 0.1778)
		(layer "B.Cu")
		(net "A_CPU1_GHJ_RCOMP0")
	)
	(segment
		(start 118.6434 -72.027288)
		(end 117.264688 -73.406)
		(width 0.2032)
		(layer "B.Cu")
		(net "A_CPU1_GHJ_RCOMP0")
	)
	(segment
		(start 112.717072 -62.357)
		(end 112.289336 -62.357)
		(width 0.2032)
		(layer "B.Cu")
		(net "A_CPU1_GHJ_RCOMP0")
	)
	(segment
		(start 119.751602 -68.533264)
		(end 119.751602 -68.245228)
		(width 0.1778)
		(layer "B.Cu")
		(net "A_CPU1_GHJ_RCOMP0")
	)
	(segment
		(start 119.813578 -68.97116)
		(end 119.813578 -68.59524)
		(width 0.2032)
		(layer "B.Cu")
		(net "A_CPU1_GHJ_RCOMP0")
	)
	(segment
		(start 107.150916 -60.33643)
		(end 106.629962 -60.857384)
		(width 0.2032)
		(layer "B.Cu")
		(net "A_CPU1_GHJ_RCOMP0")
	)
	(segment
		(start 115.551458 -64.099186)
		(end 115.490752 -63.952882)
		(width 0.1778)
		(layer "B.Cu")
		(net "A_CPU1_GHJ_RCOMP0")
	)
	(segment
		(start 118.4402 -69.835268)
		(end 118.99773 -69.277738)
		(width 0.2032)
		(layer "B.Cu")
		(net "A_CPU1_GHJ_RCOMP0")
	)
	(segment
		(start 119.813578 -68.59524)
		(end 119.751602 -68.533264)
		(width 0.2032)
		(layer "B.Cu")
		(net "A_CPU1_GHJ_RCOMP0")
	)
	(segment
		(start 119.507 -69.277738)
		(end 119.813578 -68.97116)
		(width 0.2032)
		(layer "B.Cu")
		(net "A_CPU1_GHJ_RCOMP0")
	)
	(segment
		(start 114.380772 -63.29426)
		(end 114.017806 -63.29426)
		(width 0.2032)
		(layer "B.Cu")
		(net "A_CPU1_GHJ_RCOMP0")
	)
	(segment
		(start 113.52276 -62.799214)
		(end 113.159286 -62.799214)
		(width 0.2032)
		(layer "B.Cu")
		(net "A_CPU1_GHJ_RCOMP0")
	)
	(segment
		(start 115.321334 -63.783464)
		(end 114.869976 -63.783464)
		(width 0.1778)
		(layer "B.Cu")
		(net "A_CPU1_GHJ_RCOMP0")
	)
	(segment
		(start 113.159286 -62.799214)
		(end 112.717072 -62.357)
		(width 0.2032)
		(layer "B.Cu")
		(net "A_CPU1_GHJ_RCOMP0")
	)
	(segment
		(start 118.389654 -65.850262)
		(end 117.814852 -65.27546)
		(width 0.2032)
		(layer "B.Cu")
		(net "A_CPU1_GHJ_RCOMP0")
	)
	(segment
		(start 119.751602 -68.245228)
		(end 119.895874 -67.897248)
		(width 0.1778)
		(layer "B.Cu")
		(net "A_CPU1_GHJ_RCOMP0")
	)
	(segment
		(start 106.629962 -60.857384)
		(end 105.571036 -60.857384)
		(width 0.2032)
		(layer "B.Cu")
		(net "A_CPU1_GHJ_RCOMP0")
	)
	(segment
		(start 115.81638 -64.364108)
		(end 115.551458 -64.099186)
		(width 0.1778)
		(layer "B.Cu")
		(net "A_CPU1_GHJ_RCOMP0")
	)
	(segment
		(start 107.53344 -60.33643)
		(end 107.150916 -60.33643)
		(width 0.2032)
		(layer "B.Cu")
		(net "A_CPU1_GHJ_RCOMP0")
	)
	(segment
		(start 115.490752 -63.952882)
		(end 115.321334 -63.783464)
		(width 0.1778)
		(layer "B.Cu")
		(net "A_CPU1_GHJ_RCOMP0")
	)
	(segment
		(start 110.961678 -61.392308)
		(end 110.598204 -61.392308)
		(width 0.2032)
		(layer "B.Cu")
		(net "A_CPU1_GHJ_RCOMP0")
	)
	(segment
		(start 119.109236 -67.24396)
		(end 118.914926 -67.04965)
		(width 0.1778)
		(layer "B.Cu")
		(net "A_CPU1_GHJ_RCOMP0")
	)
	(segment
		(start 114.869976 -63.783464)
		(end 114.380772 -63.29426)
		(width 0.2032)
		(layer "B.Cu")
		(net "A_CPU1_GHJ_RCOMP0")
	)
	(segment
		(start 114.017806 -63.29426)
		(end 113.52276 -62.799214)
		(width 0.2032)
		(layer "B.Cu")
		(net "A_CPU1_GHJ_RCOMP0")
	)
	(segment
		(start 118.94566 -66.586608)
		(end 118.94566 -66.0908)
		(width 0.1778)
		(layer "B.Cu")
		(net "A_CPU1_GHJ_RCOMP0")
	)
	(segment
		(start 111.457232 -61.887862)
		(end 110.961678 -61.392308)
		(width 0.2032)
		(layer "B.Cu")
		(net "A_CPU1_GHJ_RCOMP0")
	)
	(segment
		(start 118.94566 -66.0908)
		(end 118.705122 -65.850262)
		(width 0.1778)
		(layer "B.Cu")
		(net "A_CPU1_GHJ_RCOMP0")
	)
	(segment
		(start 110.103158 -60.897262)
		(end 109.760004 -60.897262)
		(width 0.2032)
		(layer "B.Cu")
		(net "A_CPU1_GHJ_RCOMP0")
	)
	(segment
		(start 118.99773 -69.277738)
		(end 119.507 -69.277738)
		(width 0.2032)
		(layer "B.Cu")
		(net "A_CPU1_GHJ_RCOMP0")
	)
	(segment
		(start 109.760004 -60.897262)
		(end 109.25048 -60.387738)
		(width 0.2032)
		(layer "B.Cu")
		(net "A_CPU1_GHJ_RCOMP0")
	)
	(segment
		(start 117.451886 -65.27546)
		(end 117.047518 -64.871092)
		(width 0.2032)
		(layer "B.Cu")
		(net "A_CPU1_GHJ_RCOMP0")
	)
	(segment
		(start 119.709184 -67.24396)
		(end 119.109236 -67.24396)
		(width 0.1778)
		(layer "B.Cu")
		(net "A_CPU1_GHJ_RCOMP0")
	)
	(segment
		(start 116.15166 -64.364108)
		(end 115.81638 -64.364108)
		(width 0.1778)
		(layer "B.Cu")
		(net "A_CPU1_GHJ_RCOMP0")
	)
	(segment
		(start 117.264688 -73.406)
		(end 117.1956 -73.406)
		(width 0.2032)
		(layer "B.Cu")
		(net "A_CPU1_GHJ_RCOMP0")
	)
	(segment
		(start 118.6434 -70.739)
		(end 118.6434 -72.027288)
		(width 0.2032)
		(layer "B.Cu")
		(net "A_CPU1_GHJ_RCOMP0")
	)
	(segment
		(start 116.333016 -64.647318)
		(end 116.261134 -64.473582)
		(width 0.1778)
		(layer "B.Cu")
		(net "A_CPU1_GHJ_RCOMP0")
	)
	(segment
		(start 107.963208 -59.906662)
		(end 107.53344 -60.33643)
		(width 0.2032)
		(layer "B.Cu")
		(net "A_CPU1_GHJ_RCOMP0")
	)
	(segment
		(start 118.4402 -70.5358)
		(end 118.6434 -70.739)
		(width 0.2032)
		(layer "B.Cu")
		(net "A_CPU1_GHJ_RCOMP0")
	)
	(segment
		(start 118.914926 -67.04965)
		(end 118.914926 -66.617342)
		(width 0.1778)
		(layer "B.Cu")
		(net "A_CPU1_GHJ_RCOMP0")
	)
	(segment
		(start 108.420916 -59.906662)
		(end 107.963208 -59.906662)
		(width 0.2032)
		(layer "B.Cu")
		(net "A_CPU1_GHJ_RCOMP0")
	)
	(segment
		(start 108.901992 -60.387738)
		(end 108.420916 -59.906662)
		(width 0.2032)
		(layer "B.Cu")
		(net "A_CPU1_GHJ_RCOMP0")
	)
	(segment
		(start 109.25048 -60.387738)
		(end 108.901992 -60.387738)
		(width 0.2032)
		(layer "B.Cu")
		(net "A_CPU1_GHJ_RCOMP0")
	)
	(segment
		(start 118.4402 -70.5358)
		(end 118.4402 -69.835268)
		(width 0.2032)
		(layer "B.Cu")
		(net "A_CPU1_GHJ_RCOMP0")
	)
	(segment
		(start 116.55679 -64.871092)
		(end 116.333016 -64.647318)
		(width 0.1778)
		(layer "B.Cu")
		(net "A_CPU1_GHJ_RCOMP0")
	)
	(segment
		(start 111.820198 -61.887862)
		(end 111.457232 -61.887862)
		(width 0.2032)
		(layer "B.Cu")
		(net "A_CPU1_GHJ_RCOMP0")
	)
	(segment
		(start 118.705122 -65.850262)
		(end 118.389654 -65.850262)
		(width 0.2032)
		(layer "B.Cu")
		(net "A_CPU1_GHJ_RCOMP0")
	)
	(segment
		(start 116.261134 -64.473582)
		(end 116.15166 -64.364108)
		(width 0.1778)
		(layer "B.Cu")
		(net "A_CPU1_GHJ_RCOMP0")
	)
	(segment
		(start 118.914926 -66.617342)
		(end 118.94566 -66.586608)
		(width 0.1778)
		(layer "B.Cu")
		(net "A_CPU1_GHJ_RCOMP0")
	)
	(segment
		(start 117.047518 -64.871092)
		(end 116.55679 -64.871092)
		(width 0.1778)
		(layer "B.Cu")
		(net "A_CPU1_GHJ_RCOMP0")
	)
	(segment
		(start 264.51433 -90.756486)
		(end 263.94283 -90.756486)
		(width 0.2032)
		(layer "F.Cu")
		(net "A_CPU0_DEF_RCOMP2")
	)
	(segment
		(start 280.80462 -85.55482)
		(end 280.8732 -85.55482)
		(width 0.2032)
		(layer "F.Cu")
		(net "A_CPU0_DEF_RCOMP2")
	)
	(segment
		(start 279.590754 -84.340954)
		(end 280.80462 -85.55482)
		(width 0.2032)
		(layer "F.Cu")
		(net "A_CPU0_DEF_RCOMP2")
	)
	(segment
		(start 277.15972 -83.86064)
		(end 277.640034 -84.340954)
		(width 0.2032)
		(layer "F.Cu")
		(net "A_CPU0_DEF_RCOMP2")
	)
	(segment
		(start 277.640034 -84.340954)
		(end 279.590754 -84.340954)
		(width 0.2032)
		(layer "F.Cu")
		(net "A_CPU0_DEF_RCOMP2")
	)
	(via
		(at 263.94283 -90.756486)
		(size 0.508)
		(drill 0.254)
		(layers "F.Cu" "B.Cu")
		(net "A_CPU0_DEF_RCOMP2")
	)
	(via
		(at 280.8732 -85.55482)
		(size 0.508)
		(drill 0.254)
		(layers "F.Cu" "B.Cu")
		(net "A_CPU0_DEF_RCOMP2")
	)
	(segment
		(start 280.753058 -88.288114)
		(end 280.80589 -88.340946)
		(width 0.2032)
		(layer "In9.Cu")
		(net "A_CPU0_DEF_RCOMP2")
	)
	(segment
		(start 279.665684 -90.615262)
		(end 279.302718 -90.615262)
		(width 0.2032)
		(layer "In9.Cu")
		(net "A_CPU0_DEF_RCOMP2")
	)
	(segment
		(start 268.073886 -92.202762)
		(end 267.18768 -92.202762)
		(width 0.2032)
		(layer "In9.Cu")
		(net "A_CPU0_DEF_RCOMP2")
	)
	(segment
		(start 276.24659 -91.605862)
		(end 275.868638 -91.605862)
		(width 0.2032)
		(layer "In9.Cu")
		(net "A_CPU0_DEF_RCOMP2")
	)
	(segment
		(start 265.467592 -91.272106)
		(end 264.951972 -90.756486)
		(width 0.2032)
		(layer "In9.Cu")
		(net "A_CPU0_DEF_RCOMP2")
	)
	(segment
		(start 275.45284 -92.02166)
		(end 275.025358 -92.02166)
		(width 0.2032)
		(layer "In9.Cu")
		(net "A_CPU0_DEF_RCOMP2")
	)
	(segment
		(start 280.80589 -88.84793)
		(end 280.753058 -88.900762)
		(width 0.2032)
		(layer "In9.Cu")
		(net "A_CPU0_DEF_RCOMP2")
	)
	(segment
		(start 266.408408 -91.786964)
		(end 265.89355 -91.272106)
		(width 0.2032)
		(layer "In9.Cu")
		(net "A_CPU0_DEF_RCOMP2")
	)
	(segment
		(start 280.753058 -87.910162)
		(end 280.753058 -88.288114)
		(width 0.2032)
		(layer "In9.Cu")
		(net "A_CPU0_DEF_RCOMP2")
	)
	(segment
		(start 280.80589 -89.77376)
		(end 280.459942 -90.119708)
		(width 0.2032)
		(layer "In9.Cu")
		(net "A_CPU0_DEF_RCOMP2")
	)
	(segment
		(start 280.80589 -88.340946)
		(end 280.80589 -88.84793)
		(width 0.2032)
		(layer "In9.Cu")
		(net "A_CPU0_DEF_RCOMP2")
	)
	(segment
		(start 280.80589 -89.395808)
		(end 280.80589 -89.77376)
		(width 0.2032)
		(layer "In9.Cu")
		(net "A_CPU0_DEF_RCOMP2")
	)
	(segment
		(start 277.585678 -91.605862)
		(end 277.16988 -92.02166)
		(width 0.2032)
		(layer "In9.Cu")
		(net "A_CPU0_DEF_RCOMP2")
	)
	(segment
		(start 265.89355 -91.272106)
		(end 265.467592 -91.272106)
		(width 0.2032)
		(layer "In9.Cu")
		(net "A_CPU0_DEF_RCOMP2")
	)
	(segment
		(start 272.864072 -92.583)
		(end 271.016984 -92.583)
		(width 0.2032)
		(layer "In9.Cu")
		(net "A_CPU0_DEF_RCOMP2")
	)
	(segment
		(start 264.951972 -90.756486)
		(end 263.94283 -90.756486)
		(width 0.2032)
		(layer "In9.Cu")
		(net "A_CPU0_DEF_RCOMP2")
	)
	(segment
		(start 279.302718 -90.615262)
		(end 278.807672 -91.110308)
		(width 0.2032)
		(layer "In9.Cu")
		(net "A_CPU0_DEF_RCOMP2")
	)
	(segment
		(start 267.18768 -92.202762)
		(end 266.771882 -91.786964)
		(width 0.2032)
		(layer "In9.Cu")
		(net "A_CPU0_DEF_RCOMP2")
	)
	(segment
		(start 278.444198 -91.110308)
		(end 277.948644 -91.605862)
		(width 0.2032)
		(layer "In9.Cu")
		(net "A_CPU0_DEF_RCOMP2")
	)
	(segment
		(start 277.16988 -92.02166)
		(end 276.662388 -92.02166)
		(width 0.2032)
		(layer "In9.Cu")
		(net "A_CPU0_DEF_RCOMP2")
	)
	(segment
		(start 266.771882 -91.786964)
		(end 266.408408 -91.786964)
		(width 0.2032)
		(layer "In9.Cu")
		(net "A_CPU0_DEF_RCOMP2")
	)
	(segment
		(start 274.529804 -92.517214)
		(end 274.2311 -92.517214)
		(width 0.2032)
		(layer "In9.Cu")
		(net "A_CPU0_DEF_RCOMP2")
	)
	(segment
		(start 280.753058 -89.342976)
		(end 280.80589 -89.395808)
		(width 0.2032)
		(layer "In9.Cu")
		(net "A_CPU0_DEF_RCOMP2")
	)
	(segment
		(start 275.868638 -91.605862)
		(end 275.45284 -92.02166)
		(width 0.2032)
		(layer "In9.Cu")
		(net "A_CPU0_DEF_RCOMP2")
	)
	(segment
		(start 281.09291 -86.348062)
		(end 281.09291 -87.57031)
		(width 0.2032)
		(layer "In9.Cu")
		(net "A_CPU0_DEF_RCOMP2")
	)
	(segment
		(start 274.2311 -92.517214)
		(end 273.736054 -93.01226)
		(width 0.2032)
		(layer "In9.Cu")
		(net "A_CPU0_DEF_RCOMP2")
	)
	(segment
		(start 278.807672 -91.110308)
		(end 278.444198 -91.110308)
		(width 0.2032)
		(layer "In9.Cu")
		(net "A_CPU0_DEF_RCOMP2")
	)
	(segment
		(start 277.948644 -91.605862)
		(end 277.585678 -91.605862)
		(width 0.2032)
		(layer "In9.Cu")
		(net "A_CPU0_DEF_RCOMP2")
	)
	(segment
		(start 280.753058 -88.900762)
		(end 280.753058 -89.342976)
		(width 0.2032)
		(layer "In9.Cu")
		(net "A_CPU0_DEF_RCOMP2")
	)
	(segment
		(start 268.516862 -91.759786)
		(end 268.073886 -92.202762)
		(width 0.2032)
		(layer "In9.Cu")
		(net "A_CPU0_DEF_RCOMP2")
	)
	(segment
		(start 280.161238 -90.119708)
		(end 279.665684 -90.615262)
		(width 0.2032)
		(layer "In9.Cu")
		(net "A_CPU0_DEF_RCOMP2")
	)
	(segment
		(start 280.459942 -90.119708)
		(end 280.161238 -90.119708)
		(width 0.2032)
		(layer "In9.Cu")
		(net "A_CPU0_DEF_RCOMP2")
	)
	(segment
		(start 270.19377 -91.759786)
		(end 268.516862 -91.759786)
		(width 0.2032)
		(layer "In9.Cu")
		(net "A_CPU0_DEF_RCOMP2")
	)
	(segment
		(start 271.016984 -92.583)
		(end 270.19377 -91.759786)
		(width 0.2032)
		(layer "In9.Cu")
		(net "A_CPU0_DEF_RCOMP2")
	)
	(segment
		(start 273.736054 -93.01226)
		(end 273.293332 -93.01226)
		(width 0.2032)
		(layer "In9.Cu")
		(net "A_CPU0_DEF_RCOMP2")
	)
	(segment
		(start 273.293332 -93.01226)
		(end 272.864072 -92.583)
		(width 0.2032)
		(layer "In9.Cu")
		(net "A_CPU0_DEF_RCOMP2")
	)
	(segment
		(start 280.8732 -85.55482)
		(end 280.8732 -86.128352)
		(width 0.2032)
		(layer "In9.Cu")
		(net "A_CPU0_DEF_RCOMP2")
	)
	(segment
		(start 275.025358 -92.02166)
		(end 274.529804 -92.517214)
		(width 0.2032)
		(layer "In9.Cu")
		(net "A_CPU0_DEF_RCOMP2")
	)
	(segment
		(start 276.662388 -92.02166)
		(end 276.24659 -91.605862)
		(width 0.2032)
		(layer "In9.Cu")
		(net "A_CPU0_DEF_RCOMP2")
	)
	(segment
		(start 280.8732 -86.128352)
		(end 281.09291 -86.348062)
		(width 0.2032)
		(layer "In9.Cu")
		(net "A_CPU0_DEF_RCOMP2")
	)
	(segment
		(start 281.09291 -87.57031)
		(end 280.753058 -87.910162)
		(width 0.2032)
		(layer "In9.Cu")
		(net "A_CPU0_DEF_RCOMP2")
	)
	(segment
		(start 279.9842 -85.4456)
		(end 279.9842 -85.5218)
		(width 0.2032)
		(layer "F.Cu")
		(net "A_CPU0_DEF_RCOMP1")
	)
	(segment
		(start 277.233634 -84.848954)
		(end 279.387554 -84.848954)
		(width 0.2032)
		(layer "F.Cu")
		(net "A_CPU0_DEF_RCOMP1")
	)
	(segment
		(start 279.387554 -84.848954)
		(end 279.9842 -85.4456)
		(width 0.2032)
		(layer "F.Cu")
		(net "A_CPU0_DEF_RCOMP1")
	)
	(segment
		(start 266.231116 -90.756486)
		(end 265.659616 -90.756486)
		(width 0.2032)
		(layer "F.Cu")
		(net "A_CPU0_DEF_RCOMP1")
	)
	(segment
		(start 276.27072 -83.88604)
		(end 277.233634 -84.848954)
		(width 0.2032)
		(layer "F.Cu")
		(net "A_CPU0_DEF_RCOMP1")
	)
	(via
		(at 279.6794 -84.3788)
		(size 0.6604)
		(drill 0.3302)
		(layers "F.Cu" "B.Cu")
		(net "A_CPU0_DEF_RCOMP1")
	)
	(via
		(at 265.659616 -90.756486)
		(size 0.508)
		(drill 0.254)
		(layers "F.Cu" "B.Cu")
		(net "A_CPU0_DEF_RCOMP1")
	)
	(via
		(at 279.9842 -85.5218)
		(size 0.508)
		(drill 0.254)
		(layers "F.Cu" "B.Cu")
		(net "A_CPU0_DEF_RCOMP1")
	)
	(segment
		(start 279.9842 -85.5218)
		(end 279.9842 -84.6836)
		(width 0.254)
		(layer "B.Cu")
		(net "A_CPU0_DEF_RCOMP1")
	)
	(segment
		(start 279.9842 -84.6836)
		(end 279.6794 -84.3788)
		(width 0.254)
		(layer "B.Cu")
		(net "A_CPU0_DEF_RCOMP1")
	)
	(segment
		(start 279.894538 -88.350852)
		(end 280.23439 -88.011)
		(width 0.2032)
		(layer "In9.Cu")
		(net "A_CPU0_DEF_RCOMP1")
	)
	(segment
		(start 278.444198 -90.119708)
		(end 278.807672 -90.119708)
		(width 0.2032)
		(layer "In9.Cu")
		(net "A_CPU0_DEF_RCOMP1")
	)
	(segment
		(start 277.520908 -90.615262)
		(end 277.948644 -90.615262)
		(width 0.2032)
		(layer "In9.Cu")
		(net "A_CPU0_DEF_RCOMP1")
	)
	(segment
		(start 280.23439 -88.011)
		(end 280.23439 -86.843108)
		(width 0.2032)
		(layer "In9.Cu")
		(net "A_CPU0_DEF_RCOMP1")
	)
	(segment
		(start 280.23439 -86.843108)
		(end 279.9842 -86.592918)
		(width 0.2032)
		(layer "In9.Cu")
		(net "A_CPU0_DEF_RCOMP1")
	)
	(segment
		(start 265.659616 -90.756486)
		(end 266.732004 -90.756486)
		(width 0.2032)
		(layer "In9.Cu")
		(net "A_CPU0_DEF_RCOMP1")
	)
	(segment
		(start 279.94737 -89.278714)
		(end 279.94737 -88.900762)
		(width 0.2032)
		(layer "In9.Cu")
		(net "A_CPU0_DEF_RCOMP1")
	)
	(segment
		(start 274.945602 -91.03106)
		(end 275.45284 -91.03106)
		(width 0.2032)
		(layer "In9.Cu")
		(net "A_CPU0_DEF_RCOMP1")
	)
	(segment
		(start 277.948644 -90.615262)
		(end 278.444198 -90.119708)
		(width 0.2032)
		(layer "In9.Cu")
		(net "A_CPU0_DEF_RCOMP1")
	)
	(segment
		(start 274.151852 -90.615262)
		(end 274.529804 -90.615262)
		(width 0.2032)
		(layer "In9.Cu")
		(net "A_CPU0_DEF_RCOMP1")
	)
	(segment
		(start 276.24659 -90.615262)
		(end 276.662388 -91.03106)
		(width 0.2032)
		(layer "In9.Cu")
		(net "A_CPU0_DEF_RCOMP1")
	)
	(segment
		(start 266.732004 -90.756486)
		(end 267.18768 -91.212162)
		(width 0.2032)
		(layer "In9.Cu")
		(net "A_CPU0_DEF_RCOMP1")
	)
	(segment
		(start 272.846546 -91.5416)
		(end 273.305016 -91.08313)
		(width 0.2032)
		(layer "In9.Cu")
		(net "A_CPU0_DEF_RCOMP1")
	)
	(segment
		(start 274.529804 -90.615262)
		(end 274.945602 -91.03106)
		(width 0.2032)
		(layer "In9.Cu")
		(net "A_CPU0_DEF_RCOMP1")
	)
	(segment
		(start 273.683984 -91.08313)
		(end 274.151852 -90.615262)
		(width 0.2032)
		(layer "In9.Cu")
		(net "A_CPU0_DEF_RCOMP1")
	)
	(segment
		(start 275.45284 -91.03106)
		(end 275.868638 -90.615262)
		(width 0.2032)
		(layer "In9.Cu")
		(net "A_CPU0_DEF_RCOMP1")
	)
	(segment
		(start 271.48663 -90.765884)
		(end 272.262346 -91.5416)
		(width 0.2032)
		(layer "In9.Cu")
		(net "A_CPU0_DEF_RCOMP1")
	)
	(segment
		(start 276.662388 -91.03106)
		(end 277.10511 -91.03106)
		(width 0.2032)
		(layer "In9.Cu")
		(net "A_CPU0_DEF_RCOMP1")
	)
	(segment
		(start 279.94737 -88.900762)
		(end 279.894538 -88.84793)
		(width 0.2032)
		(layer "In9.Cu")
		(net "A_CPU0_DEF_RCOMP1")
	)
	(segment
		(start 269.079472 -90.765884)
		(end 271.48663 -90.765884)
		(width 0.2032)
		(layer "In9.Cu")
		(net "A_CPU0_DEF_RCOMP1")
	)
	(segment
		(start 279.9842 -86.592918)
		(end 279.9842 -85.5218)
		(width 0.2032)
		(layer "In9.Cu")
		(net "A_CPU0_DEF_RCOMP1")
	)
	(segment
		(start 279.894538 -88.84793)
		(end 279.894538 -88.350852)
		(width 0.2032)
		(layer "In9.Cu")
		(net "A_CPU0_DEF_RCOMP1")
	)
	(segment
		(start 279.302718 -89.624662)
		(end 279.601422 -89.624662)
		(width 0.2032)
		(layer "In9.Cu")
		(net "A_CPU0_DEF_RCOMP1")
	)
	(segment
		(start 278.807672 -90.119708)
		(end 279.302718 -89.624662)
		(width 0.2032)
		(layer "In9.Cu")
		(net "A_CPU0_DEF_RCOMP1")
	)
	(segment
		(start 279.601422 -89.624662)
		(end 279.94737 -89.278714)
		(width 0.2032)
		(layer "In9.Cu")
		(net "A_CPU0_DEF_RCOMP1")
	)
	(segment
		(start 273.305016 -91.08313)
		(end 273.683984 -91.08313)
		(width 0.2032)
		(layer "In9.Cu")
		(net "A_CPU0_DEF_RCOMP1")
	)
	(segment
		(start 275.868638 -90.615262)
		(end 276.24659 -90.615262)
		(width 0.2032)
		(layer "In9.Cu")
		(net "A_CPU0_DEF_RCOMP1")
	)
	(segment
		(start 268.633194 -91.212162)
		(end 269.079472 -90.765884)
		(width 0.2032)
		(layer "In9.Cu")
		(net "A_CPU0_DEF_RCOMP1")
	)
	(segment
		(start 272.262346 -91.5416)
		(end 272.846546 -91.5416)
		(width 0.2032)
		(layer "In9.Cu")
		(net "A_CPU0_DEF_RCOMP1")
	)
	(segment
		(start 267.18768 -91.212162)
		(end 268.633194 -91.212162)
		(width 0.2032)
		(layer "In9.Cu")
		(net "A_CPU0_DEF_RCOMP1")
	)
	(segment
		(start 277.10511 -91.03106)
		(end 277.520908 -90.615262)
		(width 0.2032)
		(layer "In9.Cu")
		(net "A_CPU0_DEF_RCOMP1")
	)
	(segment
		(start 265.372596 -90.26144)
		(end 264.801096 -90.26144)
		(width 0.2032)
		(layer "F.Cu")
		(net "A_CPU0_DEF_RCOMP0")
	)
	(segment
		(start 275.48332 -83.985354)
		(end 276.75332 -85.255354)
		(width 0.2032)
		(layer "F.Cu")
		(net "A_CPU0_DEF_RCOMP0")
	)
	(segment
		(start 278.902414 -85.255354)
		(end 279.245314 -85.598254)
		(width 0.2032)
		(layer "F.Cu")
		(net "A_CPU0_DEF_RCOMP0")
	)
	(segment
		(start 276.75332 -85.255354)
		(end 278.902414 -85.255354)
		(width 0.2032)
		(layer "F.Cu")
		(net "A_CPU0_DEF_RCOMP0")
	)
	(segment
		(start 275.48332 -83.88604)
		(end 275.48332 -83.985354)
		(width 0.2032)
		(layer "F.Cu")
		(net "A_CPU0_DEF_RCOMP0")
	)
	(via
		(at 264.801096 -90.26144)
		(size 0.508)
		(drill 0.254)
		(layers "F.Cu" "B.Cu")
		(net "A_CPU0_DEF_RCOMP0")
	)
	(via
		(at 279.245314 -85.598254)
		(size 0.508)
		(drill 0.254)
		(layers "F.Cu" "B.Cu")
		(net "A_CPU0_DEF_RCOMP0")
	)
	(segment
		(start 279.395428 -88.067642)
		(end 279.395428 -87.29345)
		(width 0.2032)
		(layer "In9.Cu")
		(net "A_CPU0_DEF_RCOMP0")
	)
	(segment
		(start 266.707112 -89.805764)
		(end 267.12291 -90.221562)
		(width 0.2032)
		(layer "In9.Cu")
		(net "A_CPU0_DEF_RCOMP0")
	)
	(segment
		(start 264.801096 -90.26144)
		(end 265.873484 -90.26144)
		(width 0.2032)
		(layer "In9.Cu")
		(net "A_CPU0_DEF_RCOMP0")
	)
	(segment
		(start 271.642078 -89.805764)
		(end 272.399252 -90.562938)
		(width 0.2032)
		(layer "In9.Cu")
		(net "A_CPU0_DEF_RCOMP0")
	)
	(segment
		(start 274.529804 -89.624662)
		(end 274.945602 -90.04046)
		(width 0.2032)
		(layer "In9.Cu")
		(net "A_CPU0_DEF_RCOMP0")
	)
	(segment
		(start 277.585678 -89.624662)
		(end 277.838408 -89.624662)
		(width 0.2032)
		(layer "In9.Cu")
		(net "A_CPU0_DEF_RCOMP0")
	)
	(segment
		(start 267.858494 -90.221562)
		(end 268.274292 -89.805764)
		(width 0.2032)
		(layer "In9.Cu")
		(net "A_CPU0_DEF_RCOMP0")
	)
	(segment
		(start 265.873484 -90.26144)
		(end 266.32916 -89.805764)
		(width 0.2032)
		(layer "In9.Cu")
		(net "A_CPU0_DEF_RCOMP0")
	)
	(segment
		(start 279.323038 -87.22106)
		(end 279.323038 -86.843108)
		(width 0.2032)
		(layer "In9.Cu")
		(net "A_CPU0_DEF_RCOMP0")
	)
	(segment
		(start 275.868638 -89.624662)
		(end 276.24659 -89.624662)
		(width 0.2032)
		(layer "In9.Cu")
		(net "A_CPU0_DEF_RCOMP0")
	)
	(segment
		(start 266.32916 -89.805764)
		(end 266.707112 -89.805764)
		(width 0.2032)
		(layer "In9.Cu")
		(net "A_CPU0_DEF_RCOMP0")
	)
	(segment
		(start 273.36369 -90.04046)
		(end 273.736054 -90.04046)
		(width 0.2032)
		(layer "In9.Cu")
		(net "A_CPU0_DEF_RCOMP0")
	)
	(segment
		(start 276.24659 -89.624662)
		(end 276.662388 -90.04046)
		(width 0.2032)
		(layer "In9.Cu")
		(net "A_CPU0_DEF_RCOMP0")
	)
	(segment
		(start 274.151852 -89.624662)
		(end 274.529804 -89.624662)
		(width 0.2032)
		(layer "In9.Cu")
		(net "A_CPU0_DEF_RCOMP0")
	)
	(segment
		(start 277.16988 -90.04046)
		(end 277.585678 -89.624662)
		(width 0.2032)
		(layer "In9.Cu")
		(net "A_CPU0_DEF_RCOMP0")
	)
	(segment
		(start 268.274292 -89.805764)
		(end 271.642078 -89.805764)
		(width 0.2032)
		(layer "In9.Cu")
		(net "A_CPU0_DEF_RCOMP0")
	)
	(segment
		(start 279.395428 -87.29345)
		(end 279.323038 -87.22106)
		(width 0.2032)
		(layer "In9.Cu")
		(net "A_CPU0_DEF_RCOMP0")
	)
	(segment
		(start 274.945602 -90.04046)
		(end 275.45284 -90.04046)
		(width 0.2032)
		(layer "In9.Cu")
		(net "A_CPU0_DEF_RCOMP0")
	)
	(segment
		(start 273.736054 -90.04046)
		(end 274.151852 -89.624662)
		(width 0.2032)
		(layer "In9.Cu")
		(net "A_CPU0_DEF_RCOMP0")
	)
	(segment
		(start 279.323038 -86.843108)
		(end 279.291542 -86.811612)
		(width 0.2032)
		(layer "In9.Cu")
		(net "A_CPU0_DEF_RCOMP0")
	)
	(segment
		(start 277.838408 -89.624662)
		(end 279.395428 -88.067642)
		(width 0.2032)
		(layer "In9.Cu")
		(net "A_CPU0_DEF_RCOMP0")
	)
	(segment
		(start 267.12291 -90.221562)
		(end 267.858494 -90.221562)
		(width 0.2032)
		(layer "In9.Cu")
		(net "A_CPU0_DEF_RCOMP0")
	)
	(segment
		(start 276.662388 -90.04046)
		(end 277.16988 -90.04046)
		(width 0.2032)
		(layer "In9.Cu")
		(net "A_CPU0_DEF_RCOMP0")
	)
	(segment
		(start 279.291542 -86.811612)
		(end 279.291542 -85.644482)
		(width 0.2032)
		(layer "In9.Cu")
		(net "A_CPU0_DEF_RCOMP0")
	)
	(segment
		(start 272.841212 -90.562938)
		(end 273.36369 -90.04046)
		(width 0.2032)
		(layer "In9.Cu")
		(net "A_CPU0_DEF_RCOMP0")
	)
	(segment
		(start 275.45284 -90.04046)
		(end 275.868638 -89.624662)
		(width 0.2032)
		(layer "In9.Cu")
		(net "A_CPU0_DEF_RCOMP0")
	)
	(segment
		(start 272.399252 -90.562938)
		(end 272.841212 -90.562938)
		(width 0.2032)
		(layer "In9.Cu")
		(net "A_CPU0_DEF_RCOMP0")
	)
	(segment
		(start 279.291542 -85.644482)
		(end 279.245314 -85.598254)
		(width 0.2032)
		(layer "In9.Cu")
		(net "A_CPU0_DEF_RCOMP0")
	)
	(segment
		(start 271.480788 -62.343538)
		(end 272.052288 -62.343538)
		(width 0.254)
		(layer "F.Cu")
		(net "A_CPU0_ABC_RCOMP2")
	)
	(via
		(at 282.88996 -69.812408)
		(size 0.6604)
		(drill 0.3302)
		(layers "F.Cu" "B.Cu")
		(net "A_CPU0_ABC_RCOMP2")
	)
	(via
		(at 271.480788 -62.343538)
		(size 0.508)
		(drill 0.254)
		(layers "F.Cu" "B.Cu")
		(net "A_CPU0_ABC_RCOMP2")
	)
	(segment
		(start 279.018238 -65.27546)
		(end 279.381204 -65.27546)
		(width 0.1778)
		(layer "B.Cu")
		(net "A_CPU0_ABC_RCOMP2")
	)
	(segment
		(start 281.529536 -66.761614)
		(end 282.021788 -66.761614)
		(width 0.1778)
		(layer "B.Cu")
		(net "A_CPU0_ABC_RCOMP2")
	)
	(segment
		(start 274.740878 -62.878462)
		(end 275.10359 -62.878462)
		(width 0.1778)
		(layer "B.Cu")
		(net "A_CPU0_ABC_RCOMP2")
	)
	(segment
		(start 282.505658 -68.090542)
		(end 282.88996 -68.474844)
		(width 0.1778)
		(layer "B.Cu")
		(net "A_CPU0_ABC_RCOMP2")
	)
	(segment
		(start 282.505658 -67.492626)
		(end 282.505658 -68.090542)
		(width 0.1778)
		(layer "B.Cu")
		(net "A_CPU0_ABC_RCOMP2")
	)
	(segment
		(start 276.442678 -63.789814)
		(end 276.806152 -63.789814)
		(width 0.1778)
		(layer "B.Cu")
		(net "A_CPU0_ABC_RCOMP2")
	)
	(segment
		(start 273.88185 -62.382908)
		(end 274.245324 -62.382908)
		(width 0.1778)
		(layer "B.Cu")
		(net "A_CPU0_ABC_RCOMP2")
	)
	(segment
		(start 282.88996 -70.644766)
		(end 282.259024 -71.275702)
		(width 0.2032)
		(layer "B.Cu")
		(net "A_CPU0_ABC_RCOMP2")
	)
	(segment
		(start 280.25471 -65.850262)
		(end 280.749756 -66.345308)
		(width 0.1778)
		(layer "B.Cu")
		(net "A_CPU0_ABC_RCOMP2")
	)
	(segment
		(start 282.259024 -71.275702)
		(end 282.259024 -71.867014)
		(width 0.2032)
		(layer "B.Cu")
		(net "A_CPU0_ABC_RCOMP2")
	)
	(segment
		(start 271.480788 -62.343538)
		(end 271.52981 -62.294516)
		(width 0.1778)
		(layer "B.Cu")
		(net "A_CPU0_ABC_RCOMP2")
	)
	(segment
		(start 272.742152 -62.156848)
		(end 272.742152 -62.154562)
		(width 0.1778)
		(layer "B.Cu")
		(net "A_CPU0_ABC_RCOMP2")
	)
	(segment
		(start 275.10359 -62.878462)
		(end 275.519388 -63.29426)
		(width 0.1778)
		(layer "B.Cu")
		(net "A_CPU0_ABC_RCOMP2")
	)
	(segment
		(start 274.245324 -62.382908)
		(end 274.740878 -62.878462)
		(width 0.1778)
		(layer "B.Cu")
		(net "A_CPU0_ABC_RCOMP2")
	)
	(segment
		(start 277.743412 -64.364108)
		(end 278.159718 -64.780414)
		(width 0.1778)
		(layer "B.Cu")
		(net "A_CPU0_ABC_RCOMP2")
	)
	(segment
		(start 282.88996 -68.474844)
		(end 282.88996 -69.812408)
		(width 0.1778)
		(layer "B.Cu")
		(net "A_CPU0_ABC_RCOMP2")
	)
	(segment
		(start 278.523192 -64.780414)
		(end 279.018238 -65.27546)
		(width 0.1778)
		(layer "B.Cu")
		(net "A_CPU0_ABC_RCOMP2")
	)
	(segment
		(start 271.52981 -62.294516)
		(end 272.604484 -62.294516)
		(width 0.1778)
		(layer "B.Cu")
		(net "A_CPU0_ABC_RCOMP2")
	)
	(segment
		(start 279.381204 -65.27546)
		(end 279.956006 -65.850262)
		(width 0.1778)
		(layer "B.Cu")
		(net "A_CPU0_ABC_RCOMP2")
	)
	(segment
		(start 272.604484 -62.294516)
		(end 272.742152 -62.156848)
		(width 0.1778)
		(layer "B.Cu")
		(net "A_CPU0_ABC_RCOMP2")
	)
	(segment
		(start 282.021788 -66.761614)
		(end 282.19527 -66.935096)
		(width 0.1778)
		(layer "B.Cu")
		(net "A_CPU0_ABC_RCOMP2")
	)
	(segment
		(start 282.19527 -66.935096)
		(end 282.404566 -67.248278)
		(width 0.1778)
		(layer "B.Cu")
		(net "A_CPU0_ABC_RCOMP2")
	)
	(segment
		(start 281.11323 -66.345308)
		(end 281.529536 -66.761614)
		(width 0.1778)
		(layer "B.Cu")
		(net "A_CPU0_ABC_RCOMP2")
	)
	(segment
		(start 277.380446 -64.364108)
		(end 277.743412 -64.364108)
		(width 0.1778)
		(layer "B.Cu")
		(net "A_CPU0_ABC_RCOMP2")
	)
	(segment
		(start 280.749756 -66.345308)
		(end 281.11323 -66.345308)
		(width 0.1778)
		(layer "B.Cu")
		(net "A_CPU0_ABC_RCOMP2")
	)
	(segment
		(start 278.159718 -64.780414)
		(end 278.523192 -64.780414)
		(width 0.1778)
		(layer "B.Cu")
		(net "A_CPU0_ABC_RCOMP2")
	)
	(segment
		(start 272.742152 -62.154562)
		(end 273.008852 -61.887862)
		(width 0.1778)
		(layer "B.Cu")
		(net "A_CPU0_ABC_RCOMP2")
	)
	(segment
		(start 275.947124 -63.29426)
		(end 276.442678 -63.789814)
		(width 0.1778)
		(layer "B.Cu")
		(net "A_CPU0_ABC_RCOMP2")
	)
	(segment
		(start 273.008852 -61.887862)
		(end 273.386804 -61.887862)
		(width 0.1778)
		(layer "B.Cu")
		(net "A_CPU0_ABC_RCOMP2")
	)
	(segment
		(start 279.956006 -65.850262)
		(end 280.25471 -65.850262)
		(width 0.1778)
		(layer "B.Cu")
		(net "A_CPU0_ABC_RCOMP2")
	)
	(segment
		(start 282.404566 -67.248278)
		(end 282.505658 -67.492626)
		(width 0.1778)
		(layer "B.Cu")
		(net "A_CPU0_ABC_RCOMP2")
	)
	(segment
		(start 276.806152 -63.789814)
		(end 277.380446 -64.364108)
		(width 0.1778)
		(layer "B.Cu")
		(net "A_CPU0_ABC_RCOMP2")
	)
	(segment
		(start 273.386804 -61.887862)
		(end 273.88185 -62.382908)
		(width 0.1778)
		(layer "B.Cu")
		(net "A_CPU0_ABC_RCOMP2")
	)
	(segment
		(start 275.519388 -63.29426)
		(end 275.947124 -63.29426)
		(width 0.1778)
		(layer "B.Cu")
		(net "A_CPU0_ABC_RCOMP2")
	)
	(segment
		(start 282.88996 -69.812408)
		(end 282.88996 -70.644766)
		(width 0.2032)
		(layer "B.Cu")
		(net "A_CPU0_ABC_RCOMP2")
	)
	(segment
		(start 270.571468 -61.847984)
		(end 271.193768 -61.847984)
		(width 0.254)
		(layer "F.Cu")
		(net "A_CPU0_ABC_RCOMP1")
	)
	(via
		(at 270.571468 -61.847984)
		(size 0.508)
		(drill 0.254)
		(layers "F.Cu" "B.Cu")
		(net "A_CPU0_ABC_RCOMP1")
	)
	(segment
		(start 273.88185 -61.392308)
		(end 274.241006 -61.392308)
		(width 0.1778)
		(layer "B.Cu")
		(net "A_CPU0_ABC_RCOMP1")
	)
	(segment
		(start 273.739102 -61.24956)
		(end 273.88185 -61.392308)
		(width 0.1778)
		(layer "B.Cu")
		(net "A_CPU0_ABC_RCOMP1")
	)
	(segment
		(start 283.599636 -71.894446)
		(end 283.104082 -72.39)
		(width 0.1778)
		(layer "B.Cu")
		(net "A_CPU0_ABC_RCOMP1")
	)
	(segment
		(start 283.390086 -66.840862)
		(end 283.695902 -66.840862)
		(width 0.1778)
		(layer "B.Cu")
		(net "A_CPU0_ABC_RCOMP1")
	)
	(segment
		(start 274.69084 -61.887862)
		(end 275.16836 -61.887862)
		(width 0.1778)
		(layer "B.Cu")
		(net "A_CPU0_ABC_RCOMP1")
	)
	(segment
		(start 281.957272 -65.771014)
		(end 282.531566 -66.345308)
		(width 0.1778)
		(layer "B.Cu")
		(net "A_CPU0_ABC_RCOMP1")
	)
	(segment
		(start 274.241006 -61.392308)
		(end 274.426172 -61.577474)
		(width 0.1778)
		(layer "B.Cu")
		(net "A_CPU0_ABC_RCOMP1")
	)
	(segment
		(start 283.849318 -68.659502)
		(end 283.849318 -69.296534)
		(width 0.1778)
		(layer "B.Cu")
		(net "A_CPU0_ABC_RCOMP1")
	)
	(segment
		(start 273.409156 -60.809886)
		(end 273.661632 -61.062362)
		(width 0.1778)
		(layer "B.Cu")
		(net "A_CPU0_ABC_RCOMP1")
	)
	(segment
		(start 272.502122 -61.392308)
		(end 272.668746 -61.225684)
		(width 0.1778)
		(layer "B.Cu")
		(net "A_CPU0_ABC_RCOMP1")
	)
	(segment
		(start 272.668746 -61.225684)
		(end 272.754344 -61.019182)
		(width 0.1778)
		(layer "B.Cu")
		(net "A_CPU0_ABC_RCOMP1")
	)
	(segment
		(start 272.135092 -61.392308)
		(end 272.502122 -61.392308)
		(width 0.1778)
		(layer "B.Cu")
		(net "A_CPU0_ABC_RCOMP1")
	)
	(segment
		(start 280.473912 -65.133474)
		(end 280.700226 -65.359788)
		(width 0.1778)
		(layer "B.Cu")
		(net "A_CPU0_ABC_RCOMP1")
	)
	(segment
		(start 282.531566 -66.345308)
		(end 282.894532 -66.345308)
		(width 0.1778)
		(layer "B.Cu")
		(net "A_CPU0_ABC_RCOMP1")
	)
	(segment
		(start 275.16836 -61.887862)
		(end 275.584158 -62.30366)
		(width 0.1778)
		(layer "B.Cu")
		(net "A_CPU0_ABC_RCOMP1")
	)
	(segment
		(start 270.571468 -61.847984)
		(end 271.679416 -61.847984)
		(width 0.1778)
		(layer "B.Cu")
		(net "A_CPU0_ABC_RCOMP1")
	)
	(segment
		(start 283.599636 -69.546216)
		(end 283.599636 -71.894446)
		(width 0.1778)
		(layer "B.Cu")
		(net "A_CPU0_ABC_RCOMP1")
	)
	(segment
		(start 275.584158 -62.30366)
		(end 275.947124 -62.30366)
		(width 0.1778)
		(layer "B.Cu")
		(net "A_CPU0_ABC_RCOMP1")
	)
	(segment
		(start 274.426172 -61.577474)
		(end 274.45843 -61.655452)
		(width 0.1778)
		(layer "B.Cu")
		(net "A_CPU0_ABC_RCOMP1")
	)
	(segment
		(start 279.876758 -64.780414)
		(end 280.228802 -64.780414)
		(width 0.1778)
		(layer "B.Cu")
		(net "A_CPU0_ABC_RCOMP1")
	)
	(segment
		(start 273.661632 -61.062362)
		(end 273.739102 -61.24956)
		(width 0.1778)
		(layer "B.Cu")
		(net "A_CPU0_ABC_RCOMP1")
	)
	(segment
		(start 282.894532 -66.345308)
		(end 283.390086 -66.840862)
		(width 0.1778)
		(layer "B.Cu")
		(net "A_CPU0_ABC_RCOMP1")
	)
	(segment
		(start 283.902658 -67.602608)
		(end 283.902658 -67.98056)
		(width 0.1778)
		(layer "B.Cu")
		(net "A_CPU0_ABC_RCOMP1")
	)
	(segment
		(start 272.754344 -61.019182)
		(end 272.96364 -60.809886)
		(width 0.1778)
		(layer "B.Cu")
		(net "A_CPU0_ABC_RCOMP1")
	)
	(segment
		(start 280.397458 -64.94907)
		(end 280.473912 -65.133474)
		(width 0.1778)
		(layer "B.Cu")
		(net "A_CPU0_ABC_RCOMP1")
	)
	(segment
		(start 283.979366 -68.057268)
		(end 283.979366 -68.529454)
		(width 0.1778)
		(layer "B.Cu")
		(net "A_CPU0_ABC_RCOMP1")
	)
	(segment
		(start 281.182572 -65.359788)
		(end 281.593798 -65.771014)
		(width 0.1778)
		(layer "B.Cu")
		(net "A_CPU0_ABC_RCOMP1")
	)
	(segment
		(start 283.972 -67.11696)
		(end 283.972 -67.533266)
		(width 0.1778)
		(layer "B.Cu")
		(net "A_CPU0_ABC_RCOMP1")
	)
	(segment
		(start 277.315676 -63.373508)
		(end 277.67915 -63.373508)
		(width 0.1778)
		(layer "B.Cu")
		(net "A_CPU0_ABC_RCOMP1")
	)
	(segment
		(start 283.972 -67.533266)
		(end 283.902658 -67.602608)
		(width 0.1778)
		(layer "B.Cu")
		(net "A_CPU0_ABC_RCOMP1")
	)
	(segment
		(start 275.947124 -62.30366)
		(end 276.521926 -62.878462)
		(width 0.1778)
		(layer "B.Cu")
		(net "A_CPU0_ABC_RCOMP1")
	)
	(segment
		(start 281.593798 -65.771014)
		(end 281.957272 -65.771014)
		(width 0.1778)
		(layer "B.Cu")
		(net "A_CPU0_ABC_RCOMP1")
	)
	(segment
		(start 279.032716 -64.364108)
		(end 279.460452 -64.364108)
		(width 0.1778)
		(layer "B.Cu")
		(net "A_CPU0_ABC_RCOMP1")
	)
	(segment
		(start 276.521926 -62.878462)
		(end 276.82063 -62.878462)
		(width 0.1778)
		(layer "B.Cu")
		(net "A_CPU0_ABC_RCOMP1")
	)
	(segment
		(start 278.53767 -63.869062)
		(end 279.032716 -64.364108)
		(width 0.1778)
		(layer "B.Cu")
		(net "A_CPU0_ABC_RCOMP1")
	)
	(segment
		(start 283.902658 -67.98056)
		(end 283.979366 -68.057268)
		(width 0.1778)
		(layer "B.Cu")
		(net "A_CPU0_ABC_RCOMP1")
	)
	(segment
		(start 283.979366 -68.529454)
		(end 283.849318 -68.659502)
		(width 0.1778)
		(layer "B.Cu")
		(net "A_CPU0_ABC_RCOMP1")
	)
	(segment
		(start 276.82063 -62.878462)
		(end 277.315676 -63.373508)
		(width 0.1778)
		(layer "B.Cu")
		(net "A_CPU0_ABC_RCOMP1")
	)
	(segment
		(start 280.228802 -64.780414)
		(end 280.397458 -64.94907)
		(width 0.1778)
		(layer "B.Cu")
		(net "A_CPU0_ABC_RCOMP1")
	)
	(segment
		(start 274.45843 -61.655452)
		(end 274.69084 -61.887862)
		(width 0.1778)
		(layer "B.Cu")
		(net "A_CPU0_ABC_RCOMP1")
	)
	(segment
		(start 283.695902 -66.840862)
		(end 283.972 -67.11696)
		(width 0.1778)
		(layer "B.Cu")
		(net "A_CPU0_ABC_RCOMP1")
	)
	(segment
		(start 279.460452 -64.364108)
		(end 279.876758 -64.780414)
		(width 0.1778)
		(layer "B.Cu")
		(net "A_CPU0_ABC_RCOMP1")
	)
	(segment
		(start 283.849318 -69.296534)
		(end 283.599636 -69.546216)
		(width 0.1778)
		(layer "B.Cu")
		(net "A_CPU0_ABC_RCOMP1")
	)
	(segment
		(start 277.67915 -63.373508)
		(end 278.174704 -63.869062)
		(width 0.1778)
		(layer "B.Cu")
		(net "A_CPU0_ABC_RCOMP1")
	)
	(segment
		(start 283.104082 -72.39)
		(end 282.548838 -72.39)
		(width 0.1778)
		(layer "B.Cu")
		(net "A_CPU0_ABC_RCOMP1")
	)
	(segment
		(start 272.96364 -60.809886)
		(end 273.409156 -60.809886)
		(width 0.1778)
		(layer "B.Cu")
		(net "A_CPU0_ABC_RCOMP1")
	)
	(segment
		(start 278.174704 -63.869062)
		(end 278.53767 -63.869062)
		(width 0.1778)
		(layer "B.Cu")
		(net "A_CPU0_ABC_RCOMP1")
	)
	(segment
		(start 282.548838 -72.39)
		(end 282.259024 -72.679814)
		(width 0.1778)
		(layer "B.Cu")
		(net "A_CPU0_ABC_RCOMP1")
	)
	(segment
		(start 280.700226 -65.359788)
		(end 281.182572 -65.359788)
		(width 0.1778)
		(layer "B.Cu")
		(net "A_CPU0_ABC_RCOMP1")
	)
	(segment
		(start 271.679416 -61.847984)
		(end 272.135092 -61.392308)
		(width 0.1778)
		(layer "B.Cu")
		(net "A_CPU0_ABC_RCOMP1")
	)
	(segment
		(start 271.193768 -60.857384)
		(end 270.571468 -60.857384)
		(width 0.254)
		(layer "F.Cu")
		(net "A_CPU0_ABC_RCOMP0")
	)
	(via
		(at 270.571468 -60.857384)
		(size 0.508)
		(drill 0.254)
		(layers "F.Cu" "B.Cu")
		(net "A_CPU0_ABC_RCOMP0")
	)
	(via
		(at 284.861 -69.427852)
		(size 0.6604)
		(drill 0.3302)
		(layers "F.Cu" "B.Cu")
		(net "A_CPU0_ABC_RCOMP0")
	)
	(segment
		(start 276.442678 -61.808614)
		(end 276.806152 -61.808614)
		(width 0.1778)
		(layer "B.Cu")
		(net "A_CPU0_ABC_RCOMP0")
	)
	(segment
		(start 278.588978 -62.865)
		(end 279.018238 -63.29426)
		(width 0.1778)
		(layer "B.Cu")
		(net "A_CPU0_ABC_RCOMP0")
	)
	(segment
		(start 279.379426 -63.29426)
		(end 279.53716 -63.451994)
		(width 0.1778)
		(layer "B.Cu")
		(net "A_CPU0_ABC_RCOMP0")
	)
	(segment
		(start 282.903168 -65.363344)
		(end 283.390086 -65.850262)
		(width 0.1778)
		(layer "B.Cu")
		(net "A_CPU0_ABC_RCOMP0")
	)
	(segment
		(start 277.717504 -62.357)
		(end 278.225504 -62.865)
		(width 0.1778)
		(layer "B.Cu")
		(net "A_CPU0_ABC_RCOMP0")
	)
	(segment
		(start 272.105628 -60.405772)
		(end 272.602452 -60.405772)
		(width 0.1778)
		(layer "B.Cu")
		(net "A_CPU0_ABC_RCOMP0")
	)
	(segment
		(start 277.354538 -62.357)
		(end 277.717504 -62.357)
		(width 0.1778)
		(layer "B.Cu")
		(net "A_CPU0_ABC_RCOMP0")
	)
	(segment
		(start 279.843992 -63.872872)
		(end 280.280872 -63.872872)
		(width 0.1778)
		(layer "B.Cu")
		(net "A_CPU0_ABC_RCOMP0")
	)
	(segment
		(start 284.819598 -67.048888)
		(end 284.760924 -67.107562)
		(width 0.1778)
		(layer "B.Cu")
		(net "A_CPU0_ABC_RCOMP0")
	)
	(segment
		(start 284.814264 -67.538854)
		(end 284.814264 -68.044822)
		(width 0.1778)
		(layer "B.Cu")
		(net "A_CPU0_ABC_RCOMP0")
	)
	(segment
		(start 284.148022 -70.304914)
		(end 283.900372 -70.552564)
		(width 0.2032)
		(layer "B.Cu")
		(net "A_CPU0_ABC_RCOMP0")
	)
	(segment
		(start 275.432266 -61.20892)
		(end 275.615654 -61.392308)
		(width 0.1778)
		(layer "B.Cu")
		(net "A_CPU0_ABC_RCOMP0")
	)
	(segment
		(start 284.861 -68.57619)
		(end 284.861 -69.427852)
		(width 0.1778)
		(layer "B.Cu")
		(net "A_CPU0_ABC_RCOMP0")
	)
	(segment
		(start 274.258786 -60.401708)
		(end 274.66544 -60.808362)
		(width 0.1778)
		(layer "B.Cu")
		(net "A_CPU0_ABC_RCOMP0")
	)
	(segment
		(start 276.026372 -61.392308)
		(end 276.442678 -61.808614)
		(width 0.1778)
		(layer "B.Cu")
		(net "A_CPU0_ABC_RCOMP0")
	)
	(segment
		(start 284.760924 -68.098162)
		(end 284.760924 -68.476114)
		(width 0.1778)
		(layer "B.Cu")
		(net "A_CPU0_ABC_RCOMP0")
	)
	(segment
		(start 283.900372 -72.0217)
		(end 282.429458 -73.492614)
		(width 0.2032)
		(layer "B.Cu")
		(net "A_CPU0_ABC_RCOMP0")
	)
	(segment
		(start 275.344636 -60.9981)
		(end 275.432266 -61.20892)
		(width 0.1778)
		(layer "B.Cu")
		(net "A_CPU0_ABC_RCOMP0")
	)
	(segment
		(start 282.429458 -73.492614)
		(end 282.259024 -73.492614)
		(width 0.2032)
		(layer "B.Cu")
		(net "A_CPU0_ABC_RCOMP0")
	)
	(segment
		(start 275.615654 -61.392308)
		(end 276.026372 -61.392308)
		(width 0.1778)
		(layer "B.Cu")
		(net "A_CPU0_ABC_RCOMP0")
	)
	(segment
		(start 284.861 -69.704204)
		(end 284.26029 -70.304914)
		(width 0.2032)
		(layer "B.Cu")
		(net "A_CPU0_ABC_RCOMP0")
	)
	(segment
		(start 280.69286 -64.28486)
		(end 281.09926 -64.28486)
		(width 0.1778)
		(layer "B.Cu")
		(net "A_CPU0_ABC_RCOMP0")
	)
	(segment
		(start 281.09926 -64.28486)
		(end 281.594814 -64.780414)
		(width 0.1778)
		(layer "B.Cu")
		(net "A_CPU0_ABC_RCOMP0")
	)
	(segment
		(start 279.53716 -63.451994)
		(end 279.618186 -63.647066)
		(width 0.1778)
		(layer "B.Cu")
		(net "A_CPU0_ABC_RCOMP0")
	)
	(segment
		(start 284.814264 -68.044822)
		(end 284.760924 -68.098162)
		(width 0.1778)
		(layer "B.Cu")
		(net "A_CPU0_ABC_RCOMP0")
	)
	(segment
		(start 275.154898 -60.808362)
		(end 275.344636 -60.9981)
		(width 0.1778)
		(layer "B.Cu")
		(net "A_CPU0_ABC_RCOMP0")
	)
	(segment
		(start 283.390086 -65.850262)
		(end 283.684218 -65.850262)
		(width 0.1778)
		(layer "B.Cu")
		(net "A_CPU0_ABC_RCOMP0")
	)
	(segment
		(start 284.760924 -67.485514)
		(end 284.814264 -67.538854)
		(width 0.1778)
		(layer "B.Cu")
		(net "A_CPU0_ABC_RCOMP0")
	)
	(segment
		(start 281.882596 -64.780414)
		(end 282.465526 -65.363344)
		(width 0.1778)
		(layer "B.Cu")
		(net "A_CPU0_ABC_RCOMP0")
	)
	(segment
		(start 284.26029 -70.304914)
		(end 284.148022 -70.304914)
		(width 0.2032)
		(layer "B.Cu")
		(net "A_CPU0_ABC_RCOMP0")
	)
	(segment
		(start 284.760924 -67.107562)
		(end 284.760924 -67.485514)
		(width 0.1778)
		(layer "B.Cu")
		(net "A_CPU0_ABC_RCOMP0")
	)
	(segment
		(start 272.82394 -60.099956)
		(end 273.017742 -59.906154)
		(width 0.1778)
		(layer "B.Cu")
		(net "A_CPU0_ABC_RCOMP0")
	)
	(segment
		(start 284.819598 -66.593212)
		(end 284.819598 -67.048888)
		(width 0.1778)
		(layer "B.Cu")
		(net "A_CPU0_ABC_RCOMP0")
	)
	(segment
		(start 284.861 -69.427852)
		(end 284.861 -69.704204)
		(width 0.2032)
		(layer "B.Cu")
		(net "A_CPU0_ABC_RCOMP0")
	)
	(segment
		(start 278.225504 -62.865)
		(end 278.588978 -62.865)
		(width 0.1778)
		(layer "B.Cu")
		(net "A_CPU0_ABC_RCOMP0")
	)
	(segment
		(start 284.760924 -68.476114)
		(end 284.861 -68.57619)
		(width 0.1778)
		(layer "B.Cu")
		(net "A_CPU0_ABC_RCOMP0")
	)
	(segment
		(start 281.594814 -64.780414)
		(end 281.882596 -64.780414)
		(width 0.1778)
		(layer "B.Cu")
		(net "A_CPU0_ABC_RCOMP0")
	)
	(segment
		(start 276.806152 -61.808614)
		(end 277.354538 -62.357)
		(width 0.1778)
		(layer "B.Cu")
		(net "A_CPU0_ABC_RCOMP0")
	)
	(segment
		(start 272.76425 -60.243974)
		(end 272.82394 -60.099956)
		(width 0.1778)
		(layer "B.Cu")
		(net "A_CPU0_ABC_RCOMP0")
	)
	(segment
		(start 274.66544 -60.808362)
		(end 275.154898 -60.808362)
		(width 0.1778)
		(layer "B.Cu")
		(net "A_CPU0_ABC_RCOMP0")
	)
	(segment
		(start 284.179264 -66.345308)
		(end 284.571694 -66.345308)
		(width 0.1778)
		(layer "B.Cu")
		(net "A_CPU0_ABC_RCOMP0")
	)
	(segment
		(start 271.654016 -60.857384)
		(end 272.105628 -60.405772)
		(width 0.1778)
		(layer "B.Cu")
		(net "A_CPU0_ABC_RCOMP0")
	)
	(segment
		(start 284.571694 -66.345308)
		(end 284.819598 -66.593212)
		(width 0.1778)
		(layer "B.Cu")
		(net "A_CPU0_ABC_RCOMP0")
	)
	(segment
		(start 273.94662 -60.401708)
		(end 274.258786 -60.401708)
		(width 0.1778)
		(layer "B.Cu")
		(net "A_CPU0_ABC_RCOMP0")
	)
	(segment
		(start 273.451066 -59.906154)
		(end 273.94662 -60.401708)
		(width 0.1778)
		(layer "B.Cu")
		(net "A_CPU0_ABC_RCOMP0")
	)
	(segment
		(start 273.017742 -59.906154)
		(end 273.451066 -59.906154)
		(width 0.1778)
		(layer "B.Cu")
		(net "A_CPU0_ABC_RCOMP0")
	)
	(segment
		(start 282.465526 -65.363344)
		(end 282.903168 -65.363344)
		(width 0.1778)
		(layer "B.Cu")
		(net "A_CPU0_ABC_RCOMP0")
	)
	(segment
		(start 279.618186 -63.647066)
		(end 279.843992 -63.872872)
		(width 0.1778)
		(layer "B.Cu")
		(net "A_CPU0_ABC_RCOMP0")
	)
	(segment
		(start 279.018238 -63.29426)
		(end 279.379426 -63.29426)
		(width 0.1778)
		(layer "B.Cu")
		(net "A_CPU0_ABC_RCOMP0")
	)
	(segment
		(start 283.900372 -70.552564)
		(end 283.900372 -72.0217)
		(width 0.2032)
		(layer "B.Cu")
		(net "A_CPU0_ABC_RCOMP0")
	)
	(segment
		(start 272.602452 -60.405772)
		(end 272.76425 -60.243974)
		(width 0.1778)
		(layer "B.Cu")
		(net "A_CPU0_ABC_RCOMP0")
	)
	(segment
		(start 270.571468 -60.857384)
		(end 271.654016 -60.857384)
		(width 0.1778)
		(layer "B.Cu")
		(net "A_CPU0_ABC_RCOMP0")
	)
	(segment
		(start 280.280872 -63.872872)
		(end 280.69286 -64.28486)
		(width 0.1778)
		(layer "B.Cu")
		(net "A_CPU0_ABC_RCOMP0")
	)
	(segment
		(start 283.684218 -65.850262)
		(end 284.179264 -66.345308)
		(width 0.1778)
		(layer "B.Cu")
		(net "A_CPU0_ABC_RCOMP0")
	)
	(segment
		(start 17.9578 -83.908646)
		(end 17.9578 -84.354924)
		(width 0.254)
		(layer "F.Cu")
		(net "AGND_HSC")
	)
	(segment
		(start 15.5702 -83.3374)
		(end 15.5702 -83.4644)
		(width 0.254)
		(layer "F.Cu")
		(net "AGND_HSC")
	)
	(segment
		(start 14.8336 -79.9084)
		(end 14.4145 -80.3275)
		(width 0.254)
		(layer "F.Cu")
		(net "AGND_HSC")
	)
	(segment
		(start 21.34108 -80.899)
		(end 21.336 -80.90408)
		(width 0.254)
		(layer "F.Cu")
		(net "AGND_HSC")
	)
	(segment
		(start 23.749 -72.39)
		(end 24.13 -72.39)
		(width 0.254)
		(layer "F.Cu")
		(net "AGND_HSC")
	)
	(segment
		(start 17.857724 -84.455)
		(end 17.399 -84.455)
		(width 0.254)
		(layer "F.Cu")
		(net "AGND_HSC")
	)
	(segment
		(start 24.384 -72.644)
		(end 24.384 -73.0758)
		(width 0.254)
		(layer "F.Cu")
		(net "AGND_HSC")
	)
	(segment
		(start 14.4145 -80.3275)
		(end 14.097 -80.3275)
		(width 0.254)
		(layer "F.Cu")
		(net "AGND_HSC")
	)
	(segment
		(start 23.114 -72.4662)
		(end 23.114 -71.6788)
		(width 0.254)
		(layer "F.Cu")
		(net "AGND_HSC")
	)
	(segment
		(start 18.923 -80.518)
		(end 19.2786 -80.518)
		(width 0.4064)
		(layer "F.Cu")
		(net "AGND_HSC")
	)
	(segment
		(start 24.114252 -82.392774)
		(end 24.114252 -82.160618)
		(width 0.254)
		(layer "F.Cu")
		(net "AGND_HSC")
	)
	(segment
		(start 13.730478 -84.963)
		(end 13.412216 -84.644738)
		(width 0.254)
		(layer "F.Cu")
		(net "AGND_HSC")
	)
	(segment
		(start 24.13 -72.39)
		(end 24.384 -72.644)
		(width 0.254)
		(layer "F.Cu")
		(net "AGND_HSC")
	)
	(segment
		(start 23.384256 -72.4662)
		(end 23.460456 -72.39)
		(width 0.254)
		(layer "F.Cu")
		(net "AGND_HSC")
	)
	(segment
		(start 15.5956 -83.180428)
		(end 15.5956 -83.312)
		(width 0.254)
		(layer "F.Cu")
		(net "AGND_HSC")
	)
	(segment
		(start 20.447 -69.977)
		(end 19.558 -69.977)
		(width 0.254)
		(layer "F.Cu")
		(net "AGND_HSC")
	)
	(segment
		(start 15.5956 -83.312)
		(end 15.5702 -83.3374)
		(width 0.254)
		(layer "F.Cu")
		(net "AGND_HSC")
	)
	(segment
		(start 23.460456 -72.39)
		(end 23.749 -72.39)
		(width 0.254)
		(layer "F.Cu")
		(net "AGND_HSC")
	)
	(segment
		(start 22.225 -80.899)
		(end 21.34108 -80.899)
		(width 0.254)
		(layer "F.Cu")
		(net "AGND_HSC")
	)
	(segment
		(start 16.099028 -82.677)
		(end 15.5956 -83.180428)
		(width 0.254)
		(layer "F.Cu")
		(net "AGND_HSC")
	)
	(segment
		(start 21.336 -69.977)
		(end 21.336 -69.215)
		(width 0.254)
		(layer "F.Cu")
		(net "AGND_HSC")
	)
	(segment
		(start 14.097 -84.963)
		(end 13.730478 -84.963)
		(width 0.254)
		(layer "F.Cu")
		(net "AGND_HSC")
	)
	(segment
		(start 19.558 -69.7484)
		(end 20.1422 -69.1642)
		(width 0.254)
		(layer "F.Cu")
		(net "AGND_HSC")
	)
	(segment
		(start 23.114 -72.4662)
		(end 23.384256 -72.4662)
		(width 0.254)
		(layer "F.Cu")
		(net "AGND_HSC")
	)
	(segment
		(start 14.097 -82.169)
		(end 13.462 -82.169)
		(width 0.254)
		(layer "F.Cu")
		(net "AGND_HSC")
	)
	(segment
		(start 23.46198 -83.045046)
		(end 24.114252 -82.392774)
		(width 0.254)
		(layer "F.Cu")
		(net "AGND_HSC")
	)
	(segment
		(start 23.114 -75.438)
		(end 23.4696 -75.438)
		(width 0.254)
		(layer "F.Cu")
		(net "AGND_HSC")
	)
	(segment
		(start 23.46198 -83.25358)
		(end 23.46198 -83.045046)
		(width 0.254)
		(layer "F.Cu")
		(net "AGND_HSC")
	)
	(segment
		(start 19.558 -69.977)
		(end 19.558 -69.7484)
		(width 0.254)
		(layer "F.Cu")
		(net "AGND_HSC")
	)
	(segment
		(start 23.4696 -75.438)
		(end 23.7236 -75.184)
		(width 0.254)
		(layer "F.Cu")
		(net "AGND_HSC")
	)
	(segment
		(start 18.669 -69.977)
		(end 19.558 -69.977)
		(width 0.254)
		(layer "F.Cu")
		(net "AGND_HSC")
	)
	(segment
		(start 17.9578 -84.354924)
		(end 17.857724 -84.455)
		(width 0.254)
		(layer "F.Cu")
		(net "AGND_HSC")
	)
	(segment
		(start 21.336 -69.977)
		(end 22.225 -69.977)
		(width 0.254)
		(layer "F.Cu")
		(net "AGND_HSC")
	)
	(segment
		(start 19.2786 -80.518)
		(end 19.6342 -80.1624)
		(width 0.4064)
		(layer "F.Cu")
		(net "AGND_HSC")
	)
	(segment
		(start 21.336 -80.90408)
		(end 21.336 -80.285082)
		(width 0.254)
		(layer "F.Cu")
		(net "AGND_HSC")
	)
	(via
		(at 19.5326 -74.3204)
		(size 0.508)
		(drill 0.254)
		(layers "F.Cu" "B.Cu")
		(net "AGND_HSC")
	)
	(via
		(at 23.749 -72.39)
		(size 0.508)
		(drill 0.254)
		(layers "F.Cu" "B.Cu")
		(net "AGND_HSC")
	)
	(via
		(at 21.336 -80.285082)
		(size 0.508)
		(drill 0.254)
		(layers "F.Cu" "B.Cu")
		(net "AGND_HSC")
	)
	(via
		(at 18.161 -75.692)
		(size 0.508)
		(drill 0.254)
		(layers "F.Cu" "B.Cu")
		(net "AGND_HSC")
	)
	(via
		(at 19.6342 -80.1624)
		(size 0.508)
		(drill 0.254)
		(layers "F.Cu" "B.Cu")
		(net "AGND_HSC")
	)
	(via
		(at 23.749 -73.406)
		(size 0.508)
		(drill 0.254)
		(layers "F.Cu" "B.Cu")
		(net "AGND_HSC")
	)
	(via
		(at 16.764 -74.3458)
		(size 0.508)
		(drill 0.254)
		(layers "F.Cu" "B.Cu")
		(net "AGND_HSC")
	)
	(via
		(at 19.5072 -75.692)
		(size 0.508)
		(drill 0.254)
		(layers "F.Cu" "B.Cu")
		(net "AGND_HSC")
	)
	(via
		(at 12.3952 -74.2696)
		(size 0.508)
		(drill 0.254)
		(layers "F.Cu" "B.Cu")
		(net "AGND_HSC")
	)
	(via
		(at 13.412216 -84.644738)
		(size 0.508)
		(drill 0.254)
		(layers "F.Cu" "B.Cu")
		(net "AGND_HSC")
	)
	(via
		(at 19.5072 -77.0636)
		(size 0.508)
		(drill 0.254)
		(layers "F.Cu" "B.Cu")
		(net "AGND_HSC")
	)
	(via
		(at 17.9578 -83.908646)
		(size 0.508)
		(drill 0.254)
		(layers "F.Cu" "B.Cu")
		(net "AGND_HSC")
	)
	(via
		(at 16.891 -77.0636)
		(size 0.508)
		(drill 0.254)
		(layers "F.Cu" "B.Cu")
		(net "AGND_HSC")
	)
	(via
		(at 21.336 -69.215)
		(size 0.508)
		(drill 0.254)
		(layers "F.Cu" "B.Cu")
		(net "AGND_HSC")
	)
	(via
		(at 14.8336 -79.9084)
		(size 0.508)
		(drill 0.254)
		(layers "F.Cu" "B.Cu")
		(net "AGND_HSC")
	)
	(via
		(at 23.7236 -75.184)
		(size 0.508)
		(drill 0.254)
		(layers "F.Cu" "B.Cu")
		(net "AGND_HSC")
	)
	(via
		(at 15.3416 -90.3605)
		(size 0.508)
		(drill 0.254)
		(layers "F.Cu" "B.Cu")
		(net "AGND_HSC")
	)
	(via
		(at 13.462 -82.169)
		(size 0.508)
		(drill 0.254)
		(layers "F.Cu" "B.Cu")
		(net "AGND_HSC")
	)
	(via
		(at 20.1422 -69.1642)
		(size 0.508)
		(drill 0.254)
		(layers "F.Cu" "B.Cu")
		(net "AGND_HSC")
	)
	(via
		(at 15.5702 -83.4644)
		(size 0.508)
		(drill 0.254)
		(layers "F.Cu" "B.Cu")
		(net "AGND_HSC")
	)
	(via
		(at 12.3952 -73.5584)
		(size 0.508)
		(drill 0.254)
		(layers "F.Cu" "B.Cu")
		(net "AGND_HSC")
	)
	(via
		(at 24.114252 -82.160618)
		(size 0.508)
		(drill 0.254)
		(layers "F.Cu" "B.Cu")
		(net "AGND_HSC")
	)
	(segment
		(start 18.542 -82.423)
		(end 18.542 -83.312)
		(width 0.254)
		(layer "B.Cu")
		(net "AGND_HSC")
	)
	(segment
		(start 17.272 -90.3605)
		(end 16.383 -90.3605)
		(width 0.254)
		(layer "B.Cu")
		(net "AGND_HSC")
	)
	(segment
		(start 24.765 -76.2)
		(end 24.765 -77.089)
		(width 0.254)
		(layer "B.Cu")
		(net "AGND_HSC")
	)
	(segment
		(start 24.511 -75.946)
		(end 24.765 -76.2)
		(width 0.254)
		(layer "B.Cu")
		(net "AGND_HSC")
	)
	(segment
		(start 23.876 -75.819)
		(end 23.876 -75.3364)
		(width 0.254)
		(layer "B.Cu")
		(net "AGND_HSC")
	)
	(segment
		(start 24.003 -75.946)
		(end 24.511 -75.946)
		(width 0.254)
		(layer "B.Cu")
		(net "AGND_HSC")
	)
	(segment
		(start 17.9578 -83.8962)
		(end 18.542 -83.312)
		(width 0.254)
		(layer "B.Cu")
		(net "AGND_HSC")
	)
	(segment
		(start 17.9578 -83.908646)
		(end 17.9578 -83.8962)
		(width 0.254)
		(layer "B.Cu")
		(net "AGND_HSC")
	)
	(segment
		(start 23.876 -75.3364)
		(end 23.7236 -75.184)
		(width 0.254)
		(layer "B.Cu")
		(net "AGND_HSC")
	)
	(segment
		(start 16.383 -90.3605)
		(end 15.3416 -90.3605)
		(width 0.254)
		(layer "B.Cu")
		(net "AGND_HSC")
	)
	(segment
		(start 24.003 -75.946)
		(end 23.876 -75.819)
		(width 0.254)
		(layer "B.Cu")
		(net "AGND_HSC")
	)
	(segment
		(start 15.3416 -90.3605)
		(end 17.432782 -90.3605)
		(width 0.254)
		(layer "In4.Cu")
		(net "AGND_HSC")
	)
	(segment
		(start 17.970246 -83.908646)
		(end 17.9578 -83.908646)
		(width 0.254)
		(layer "In4.Cu")
		(net "AGND_HSC")
	)
	(segment
		(start 17.97558 -83.91398)
		(end 17.970246 -83.908646)
		(width 0.254)
		(layer "In4.Cu")
		(net "AGND_HSC")
	)
	(segment
		(start 19.57959 -86.871556)
		(end 19.57959 -85.823044)
		(width 0.254)
		(layer "In4.Cu")
		(net "AGND_HSC")
	)
	(segment
		(start 19.1262 -88.667082)
		(end 19.1262 -87.324946)
		(width 0.254)
		(layer "In4.Cu")
		(net "AGND_HSC")
	)
	(segment
		(start 19.57959 -85.823044)
		(end 17.97558 -84.219034)
		(width 0.254)
		(layer "In4.Cu")
		(net "AGND_HSC")
	)
	(segment
		(start 17.97558 -84.219034)
		(end 17.97558 -83.91398)
		(width 0.254)
		(layer "In4.Cu")
		(net "AGND_HSC")
	)
	(segment
		(start 19.1262 -87.324946)
		(end 19.57959 -86.871556)
		(width 0.254)
		(layer "In4.Cu")
		(net "AGND_HSC")
	)
	(segment
		(start 17.432782 -90.3605)
		(end 19.1262 -88.667082)
		(width 0.254)
		(layer "In4.Cu")
		(net "AGND_HSC")
	)
	(segment
		(start 378.6886 -39.032688)
		(end 378.421138 -39.30015)
		(width 0.254)
		(layer "F.Cu")
		(net "P3V3")
	)
	(segment
		(start 317.7286 -32.380174)
		(end 317.841376 -32.49295)
		(width 0.254)
		(layer "F.Cu")
		(net "P3V3")
	)
	(segment
		(start 176.9364 -147.6756)
		(end 176.9364 -148.336)
		(width 0.254)
		(layer "F.Cu")
		(net "P3V3")
	)
	(segment
		(start 453.771 -153.543)
		(end 455.803 -155.575)
		(width 0.254)
		(layer "F.Cu")
		(net "P3V3")
	)
	(segment
		(start 176.9364 -148.336)
		(end 175.9712 -149.3012)
		(width 0.254)
		(layer "F.Cu")
		(net "P3V3")
	)
	(segment
		(start 315.317124 -30.852618)
		(end 315.317124 -30.26537)
		(width 0.254)
		(layer "F.Cu")
		(net "P3V3")
	)
	(segment
		(start 175.2346 -5.2832)
		(end 175.0568 -5.461)
		(width 0.4064)
		(layer "F.Cu")
		(net "P3V3")
	)
	(segment
		(start 163.0426 -111.1504)
		(end 162.6362 -111.1504)
		(width 0.254)
		(layer "F.Cu")
		(net "P3V3")
	)
	(segment
		(start 383.358898 -83.328002)
		(end 383.358898 -83.318858)
		(width 0.254)
		(layer "F.Cu")
		(net "P3V3")
	)
	(segment
		(start 383.500122 -83.469226)
		(end 383.358898 -83.328002)
		(width 0.254)
		(layer "F.Cu")
		(net "P3V3")
	)
	(segment
		(start 455.803 -155.575)
		(end 455.701146 -155.575)
		(width 0.254)
		(layer "F.Cu")
		(net "P3V3")
	)
	(segment
		(start 175.0568 -5.461)
		(end 174.5996 -5.461)
		(width 0.4064)
		(layer "F.Cu")
		(net "P3V3")
	)
	(segment
		(start 454.969118 -156.307028)
		(end 454.279 -156.307028)
		(width 0.254)
		(layer "F.Cu")
		(net "P3V3")
	)
	(segment
		(start 420.779194 -124.740416)
		(end 420.081964 -124.740416)
		(width 0.508)
		(layer "F.Cu")
		(net "P3V3")
	)
	(segment
		(start 419.545516 -123.95835)
		(end 419.763448 -123.740418)
		(width 0.508)
		(layer "F.Cu")
		(net "P3V3")
	)
	(segment
		(start 383.358898 -83.318858)
		(end 382.759966 -82.719926)
		(width 0.254)
		(layer "F.Cu")
		(net "P3V3")
	)
	(segment
		(start 151.8158 -31.1658)
		(end 152.4381 -31.1658)
		(width 0.254)
		(layer "F.Cu")
		(net "P3V3")
	)
	(segment
		(start 329.594972 -111.4171)
		(end 329.594972 -111.74095)
		(width 0.254)
		(layer "F.Cu")
		(net "P3V3")
	)
	(segment
		(start 164.615114 -111.76)
		(end 163.6522 -111.76)
		(width 0.254)
		(layer "F.Cu")
		(net "P3V3")
	)
	(segment
		(start 378.421138 -39.884858)
		(end 378.619258 -40.082978)
		(width 0.254)
		(layer "F.Cu")
		(net "P3V3")
	)
	(segment
		(start 388.725918 -83.223608)
		(end 389.399526 -82.55)
		(width 0.254)
		(layer "F.Cu")
		(net "P3V3")
	)
	(segment
		(start 389.399526 -82.55)
		(end 389.439912 -82.55)
		(width 0.254)
		(layer "F.Cu")
		(net "P3V3")
	)
	(segment
		(start 163.6522 -111.76)
		(end 163.0426 -111.1504)
		(width 0.254)
		(layer "F.Cu")
		(net "P3V3")
	)
	(segment
		(start 316.696598 -31.8516)
		(end 316.065916 -31.220918)
		(width 0.254)
		(layer "F.Cu")
		(net "P3V3")
	)
	(segment
		(start 473.827094 -141.608048)
		(end 474.081348 -141.608048)
		(width 0.254)
		(layer "F.Cu")
		(net "P3V3")
	)
	(segment
		(start 317.7286 -31.8516)
		(end 317.7286 -32.380174)
		(width 0.254)
		(layer "F.Cu")
		(net "P3V3")
	)
	(segment
		(start 390.347454 -24.520906)
		(end 391.449306 -24.520906)
		(width 0.254)
		(layer "F.Cu")
		(net "P3V3")
	)
	(segment
		(start 384.21818 -83.48218)
		(end 383.52222 -83.48218)
		(width 0.254)
		(layer "F.Cu")
		(net "P3V3")
	)
	(segment
		(start 392.295888 -78.388718)
		(end 393.706096 -78.388718)
		(width 0.254)
		(layer "F.Cu")
		(net "P3V3")
	)
	(segment
		(start 383.52222 -83.48218)
		(end 383.509266 -83.469226)
		(width 0.254)
		(layer "F.Cu")
		(net "P3V3")
	)
	(segment
		(start 419.545516 -124.203968)
		(end 419.545516 -123.95835)
		(width 0.508)
		(layer "F.Cu")
		(net "P3V3")
	)
	(segment
		(start 389.439912 -82.55)
		(end 389.439912 -81.906364)
		(width 0.254)
		(layer "F.Cu")
		(net "P3V3")
	)
	(segment
		(start 394.20292 -78.727808)
		(end 394.20292 -78.92542)
		(width 0.254)
		(layer "F.Cu")
		(net "P3V3")
	)
	(segment
		(start 175.9712 -149.3012)
		(end 175.26 -149.3012)
		(width 0.254)
		(layer "F.Cu")
		(net "P3V3")
	)
	(segment
		(start 152.146 -25.908)
		(end 152.146 -27.051)
		(width 0.254)
		(layer "F.Cu")
		(net "P3V3")
	)
	(segment
		(start 391.4902 -79.5909)
		(end 391.4902 -78.664054)
		(width 0.254)
		(layer "F.Cu")
		(net "P3V3")
	)
	(segment
		(start 378.6886 -37.2364)
		(end 378.6886 -39.032688)
		(width 0.254)
		(layer "F.Cu")
		(net "P3V3")
	)
	(segment
		(start 391.4902 -78.664054)
		(end 391.765536 -78.388718)
		(width 0.254)
		(layer "F.Cu")
		(net "P3V3")
	)
	(segment
		(start 180.975 -5.406898)
		(end 181.565042 -5.99694)
		(width 0.254)
		(layer "F.Cu")
		(net "P3V3")
	)
	(segment
		(start 388.242302 -83.223608)
		(end 388.725918 -83.223608)
		(width 0.254)
		(layer "F.Cu")
		(net "P3V3")
	)
	(segment
		(start 164.615114 -111.74095)
		(end 164.615114 -111.76)
		(width 0.254)
		(layer "F.Cu")
		(net "P3V3")
	)
	(segment
		(start 455.701146 -155.575)
		(end 454.969118 -156.307028)
		(width 0.254)
		(layer "F.Cu")
		(net "P3V3")
	)
	(segment
		(start 420.081964 -124.740416)
		(end 419.545516 -124.203968)
		(width 0.508)
		(layer "F.Cu")
		(net "P3V3")
	)
	(segment
		(start 382.759966 -82.719926)
		(end 382.490726 -82.719926)
		(width 0.254)
		(layer "F.Cu")
		(net "P3V3")
	)
	(segment
		(start 180.975 -5.334)
		(end 180.975 -5.406898)
		(width 0.254)
		(layer "F.Cu")
		(net "P3V3")
	)
	(segment
		(start 384.5687 -83.18246)
		(end 384.5179 -83.18246)
		(width 0.254)
		(layer "F.Cu")
		(net "P3V3")
	)
	(segment
		(start 316.065916 -31.220918)
		(end 315.685424 -31.220918)
		(width 0.254)
		(layer "F.Cu")
		(net "P3V3")
	)
	(segment
		(start 152.146 -27.051)
		(end 151.3586 -27.8384)
		(width 0.254)
		(layer "F.Cu")
		(net "P3V3")
	)
	(segment
		(start 452.12 -153.543)
		(end 453.771 -153.543)
		(width 0.254)
		(layer "F.Cu")
		(net "P3V3")
	)
	(segment
		(start 391.449306 -24.520906)
		(end 391.6426 -24.7142)
		(width 0.254)
		(layer "F.Cu")
		(net "P3V3")
	)
	(segment
		(start 393.898882 -78.581504)
		(end 394.056616 -78.581504)
		(width 0.254)
		(layer "F.Cu")
		(net "P3V3")
	)
	(segment
		(start 151.3586 -30.7086)
		(end 151.8158 -31.1658)
		(width 0.254)
		(layer "F.Cu")
		(net "P3V3")
	)
	(segment
		(start 393.706096 -78.388718)
		(end 393.898882 -78.581504)
		(width 0.254)
		(layer "F.Cu")
		(net "P3V3")
	)
	(segment
		(start 152.702768 -25.908)
		(end 153.203402 -26.408634)
		(width 0.254)
		(layer "F.Cu")
		(net "P3V3")
	)
	(segment
		(start 329.302872 -111.125)
		(end 329.594972 -111.4171)
		(width 0.254)
		(layer "F.Cu")
		(net "P3V3")
	)
	(segment
		(start 394.056616 -78.581504)
		(end 394.20292 -78.727808)
		(width 0.254)
		(layer "F.Cu")
		(net "P3V3")
	)
	(segment
		(start 396.367 -88.2015)
		(end 396.367 -88.9)
		(width 0.254)
		(layer "F.Cu")
		(net "P3V3")
	)
	(segment
		(start 391.765536 -78.388718)
		(end 392.295888 -78.388718)
		(width 0.254)
		(layer "F.Cu")
		(net "P3V3")
	)
	(segment
		(start 378.421138 -39.30015)
		(end 378.421138 -39.884858)
		(width 0.254)
		(layer "F.Cu")
		(net "P3V3")
	)
	(segment
		(start 151.3586 -27.8384)
		(end 151.3586 -30.7086)
		(width 0.254)
		(layer "F.Cu")
		(net "P3V3")
	)
	(segment
		(start 475.2721 -142.7988)
		(end 475.2721 -143.7259)
		(width 0.254)
		(layer "F.Cu")
		(net "P3V3")
	)
	(segment
		(start 315.685424 -31.220918)
		(end 315.317124 -30.852618)
		(width 0.254)
		(layer "F.Cu")
		(net "P3V3")
	)
	(segment
		(start 474.081348 -141.608048)
		(end 475.0054 -142.5321)
		(width 0.254)
		(layer "F.Cu")
		(net "P3V3")
	)
	(segment
		(start 394.20292 -78.92542)
		(end 394.6525 -79.375)
		(width 0.254)
		(layer "F.Cu")
		(net "P3V3")
	)
	(segment
		(start 380.165102 -43.576494)
		(end 380.165102 -44.412662)
		(width 0.254)
		(layer "F.Cu")
		(net "P3V3")
	)
	(segment
		(start 378.619258 -40.082978)
		(end 378.619258 -42.03065)
		(width 0.254)
		(layer "F.Cu")
		(net "P3V3")
	)
	(segment
		(start 404.241 -81.943448)
		(end 404.241 -82.7405)
		(width 0.254)
		(layer "F.Cu")
		(net "P3V3")
	)
	(segment
		(start 404.39594 -81.788508)
		(end 404.241 -81.943448)
		(width 0.254)
		(layer "F.Cu")
		(net "P3V3")
	)
	(segment
		(start 383.509266 -83.469226)
		(end 383.500122 -83.469226)
		(width 0.254)
		(layer "F.Cu")
		(net "P3V3")
	)
	(segment
		(start 152.146 -25.908)
		(end 152.702768 -25.908)
		(width 0.254)
		(layer "F.Cu")
		(net "P3V3")
	)
	(segment
		(start 384.5179 -83.18246)
		(end 384.21818 -83.48218)
		(width 0.254)
		(layer "F.Cu")
		(net "P3V3")
	)
	(segment
		(start 419.763448 -123.740418)
		(end 420.779194 -123.740418)
		(width 0.508)
		(layer "F.Cu")
		(net "P3V3")
	)
	(segment
		(start 317.7286 -31.8516)
		(end 316.696598 -31.8516)
		(width 0.254)
		(layer "F.Cu")
		(net "P3V3")
	)
	(segment
		(start 475.0054 -142.5321)
		(end 475.2721 -142.7988)
		(width 0.254)
		(layer "F.Cu")
		(net "P3V3")
	)
	(segment
		(start 378.619258 -42.03065)
		(end 380.165102 -43.576494)
		(width 0.254)
		(layer "F.Cu")
		(net "P3V3")
	)
	(via
		(at 183.82361 -5.959348)
		(size 0.508)
		(drill 0.254)
		(layers "F.Cu" "B.Cu")
		(net "P3V3")
	)
	(via
		(at 465.8614 -133.0706)
		(size 0.508)
		(drill 0.254)
		(layers "F.Cu" "B.Cu")
		(net "P3V3")
	)
	(via
		(at 494.6777 -123.2789)
		(size 0.508)
		(drill 0.254)
		(layers "F.Cu" "B.Cu")
		(net "P3V3")
	)
	(via
		(at 380.165102 -44.412662)
		(size 0.508)
		(drill 0.254)
		(layers "F.Cu" "B.Cu")
		(net "P3V3")
	)
	(via
		(at 452.4502 -136.6012)
		(size 0.508)
		(drill 0.254)
		(layers "F.Cu" "B.Cu")
		(net "P3V3")
	)
	(via
		(at 466.120734 -5.469128)
		(size 0.5588)
		(drill 0.3048)
		(layers "F.Cu" "B.Cu")
		(net "P3V3")
	)
	(via
		(at 329.302872 -111.125)
		(size 0.508)
		(drill 0.254)
		(layers "F.Cu" "B.Cu")
		(net "P3V3")
	)
	(via
		(at 391.6172 -25.3238)
		(size 0.508)
		(drill 0.254)
		(layers "F.Cu" "B.Cu")
		(net "P3V3")
	)
	(via
		(at 469.05545 -17.109948)
		(size 0.5588)
		(drill 0.3048)
		(layers "F.Cu" "B.Cu")
		(net "P3V3")
	)
	(via
		(at 468.67191 -18.463768)
		(size 0.5588)
		(drill 0.3048)
		(layers "F.Cu" "B.Cu")
		(net "P3V3")
	)
	(via
		(at 467.0298 -6.766052)
		(size 0.5588)
		(drill 0.3048)
		(layers "F.Cu" "B.Cu")
		(net "P3V3")
	)
	(via
		(at 338.2391 -80.5815)
		(size 0.508)
		(drill 0.254)
		(layers "F.Cu" "B.Cu")
		(net "P3V3")
	)
	(via
		(at 469.053418 -19.076924)
		(size 0.5588)
		(drill 0.3048)
		(layers "F.Cu" "B.Cu")
		(net "P3V3")
	)
	(via
		(at 468.388192 -19.096736)
		(size 0.5588)
		(drill 0.3048)
		(layers "F.Cu" "B.Cu")
		(net "P3V3")
	)
	(via
		(at 391.6426 -24.7142)
		(size 0.508)
		(drill 0.254)
		(layers "F.Cu" "B.Cu")
		(net "P3V3")
	)
	(via
		(at 364.65637 -62.6237)
		(size 0.508)
		(drill 0.254)
		(layers "F.Cu" "B.Cu")
		(net "P3V3")
	)
	(via
		(at 394.056616 -78.581504)
		(size 0.508)
		(drill 0.254)
		(layers "F.Cu" "B.Cu")
		(net "P3V3")
	)
	(via
		(at 431.1142 -18.617184)
		(size 0.508)
		(drill 0.254)
		(layers "F.Cu" "B.Cu")
		(net "P3V3")
	)
	(via
		(at 373.0498 -41.4274)
		(size 0.508)
		(drill 0.254)
		(layers "F.Cu" "B.Cu")
		(net "P3V3")
	)
	(via
		(at 434.3273 -150.5966)
		(size 0.508)
		(drill 0.254)
		(layers "F.Cu" "B.Cu")
		(net "P3V3")
	)
	(via
		(at 184.155334 -144.3228)
		(size 0.6604)
		(drill 0.3302)
		(layers "F.Cu" "B.Cu")
		(net "P3V3")
	)
	(via
		(at 429.0695 -21.844)
		(size 0.508)
		(drill 0.254)
		(layers "F.Cu" "B.Cu")
		(net "P3V3")
	)
	(via
		(at 468.38235 -17.109948)
		(size 0.5588)
		(drill 0.3048)
		(layers "F.Cu" "B.Cu")
		(net "P3V3")
	)
	(via
		(at 466.617558 -19.666966)
		(size 0.5588)
		(drill 0.3048)
		(layers "F.Cu" "B.Cu")
		(net "P3V3")
	)
	(via
		(at 421.886888 -101.967538)
		(size 0.508)
		(drill 0.254)
		(layers "F.Cu" "B.Cu")
		(net "P3V3")
	)
	(via
		(at 467.6775 -19.077178)
		(size 0.5588)
		(drill 0.3048)
		(layers "F.Cu" "B.Cu")
		(net "P3V3")
	)
	(via
		(at 389.439912 -82.55)
		(size 0.508)
		(drill 0.254)
		(layers "F.Cu" "B.Cu")
		(net "P3V3")
	)
	(via
		(at 474.64218 -10.86231)
		(size 0.508)
		(drill 0.254)
		(layers "F.Cu" "B.Cu")
		(net "P3V3")
	)
	(via
		(at 466.938868 -19.053556)
		(size 0.5588)
		(drill 0.3048)
		(layers "F.Cu" "B.Cu")
		(net "P3V3")
	)
	(via
		(at 480.597972 -115.413282)
		(size 0.5588)
		(drill 0.3048)
		(layers "F.Cu" "B.Cu")
		(net "P3V3")
	)
	(via
		(at 465.346034 -5.469128)
		(size 0.5588)
		(drill 0.3048)
		(layers "F.Cu" "B.Cu")
		(net "P3V3")
	)
	(via
		(at 479.0948 -115.38712)
		(size 0.5588)
		(drill 0.3048)
		(layers "F.Cu" "B.Cu")
		(net "P3V3")
	)
	(via
		(at 391.58418 -22.29104)
		(size 0.508)
		(drill 0.254)
		(layers "F.Cu" "B.Cu")
		(net "P3V3")
	)
	(via
		(at 378.6886 -37.2364)
		(size 0.508)
		(drill 0.254)
		(layers "F.Cu" "B.Cu")
		(net "P3V3")
	)
	(via
		(at 175.2346 -5.2832)
		(size 0.508)
		(drill 0.254)
		(layers "F.Cu" "B.Cu")
		(net "P3V3")
	)
	(via
		(at 384.5687 -83.18246)
		(size 0.508)
		(drill 0.254)
		(layers "F.Cu" "B.Cu")
		(net "P3V3")
	)
	(via
		(at 406.96261 -92.451174)
		(size 0.508)
		(drill 0.254)
		(layers "F.Cu" "B.Cu")
		(net "P3V3")
	)
	(via
		(at 414.02 -96.8756)
		(size 0.508)
		(drill 0.254)
		(layers "F.Cu" "B.Cu")
		(net "P3V3")
	)
	(via
		(at 180.9496 -82.3976)
		(size 0.508)
		(drill 0.254)
		(layers "F.Cu" "B.Cu")
		(net "P3V3")
	)
	(via
		(at 466.638894 -17.761204)
		(size 0.5588)
		(drill 0.3048)
		(layers "F.Cu" "B.Cu")
		(net "P3V3")
	)
	(via
		(at 465.523834 -6.811772)
		(size 0.5588)
		(drill 0.3048)
		(layers "F.Cu" "B.Cu")
		(net "P3V3")
	)
	(via
		(at 392.22172 -23.28164)
		(size 0.508)
		(drill 0.254)
		(layers "F.Cu" "B.Cu")
		(net "P3V3")
	)
	(via
		(at 176.9364 -147.6756)
		(size 0.508)
		(drill 0.254)
		(layers "F.Cu" "B.Cu")
		(net "P3V3")
	)
	(via
		(at 168.019476 -8.368284)
		(size 0.508)
		(drill 0.254)
		(layers "F.Cu" "B.Cu")
		(net "P3V3")
	)
	(via
		(at 162.6362 -111.1504)
		(size 0.508)
		(drill 0.254)
		(layers "F.Cu" "B.Cu")
		(net "P3V3")
	)
	(via
		(at 441.506864 -139.252706)
		(size 0.508)
		(drill 0.254)
		(layers "F.Cu" "B.Cu")
		(net "P3V3")
	)
	(via
		(at 181.565042 -5.99694)
		(size 0.508)
		(drill 0.254)
		(layers "F.Cu" "B.Cu")
		(net "P3V3")
	)
	(via
		(at 479.12782 -113.79454)
		(size 0.5588)
		(drill 0.3048)
		(layers "F.Cu" "B.Cu")
		(net "P3V3")
	)
	(via
		(at 467.32571 -17.790668)
		(size 0.5588)
		(drill 0.3048)
		(layers "F.Cu" "B.Cu")
		(net "P3V3")
	)
	(via
		(at 467.35619 -19.690588)
		(size 0.5588)
		(drill 0.3048)
		(layers "F.Cu" "B.Cu")
		(net "P3V3")
	)
	(via
		(at 153.203402 -26.408634)
		(size 0.508)
		(drill 0.254)
		(layers "F.Cu" "B.Cu")
		(net "P3V3")
	)
	(via
		(at 467.99881 -17.790668)
		(size 0.5588)
		(drill 0.3048)
		(layers "F.Cu" "B.Cu")
		(net "P3V3")
	)
	(via
		(at 466.271356 -19.057366)
		(size 0.5588)
		(drill 0.3048)
		(layers "F.Cu" "B.Cu")
		(net "P3V3")
	)
	(via
		(at 399.55724 -21.36648)
		(size 0.508)
		(drill 0.254)
		(layers "F.Cu" "B.Cu")
		(net "P3V3")
	)
	(via
		(at 390.87298 -20.06092)
		(size 0.508)
		(drill 0.254)
		(layers "F.Cu" "B.Cu")
		(net "P3V3")
	)
	(via
		(at 391.664952 -22.912578)
		(size 0.508)
		(drill 0.254)
		(layers "F.Cu" "B.Cu")
		(net "P3V3")
	)
	(via
		(at 420.10584 -142.98422)
		(size 0.508)
		(drill 0.254)
		(layers "F.Cu" "B.Cu")
		(net "P3V3")
	)
	(via
		(at 468.066882 -19.710146)
		(size 0.5588)
		(drill 0.3048)
		(layers "F.Cu" "B.Cu")
		(net "P3V3")
	)
	(via
		(at 498.602 -145.542)
		(size 0.508)
		(drill 0.254)
		(layers "F.Cu" "B.Cu")
		(net "P3V3")
	)
	(via
		(at 478.197926 -115.409472)
		(size 0.5588)
		(drill 0.3048)
		(layers "F.Cu" "B.Cu")
		(net "P3V3")
	)
	(via
		(at 467.99881 -18.463768)
		(size 0.5588)
		(drill 0.3048)
		(layers "F.Cu" "B.Cu")
		(net "P3V3")
	)
	(via
		(at 404.39594 -81.788508)
		(size 0.508)
		(drill 0.254)
		(layers "F.Cu" "B.Cu")
		(net "P3V3")
	)
	(via
		(at 466.8774 -5.461)
		(size 0.5588)
		(drill 0.3048)
		(layers "F.Cu" "B.Cu")
		(net "P3V3")
	)
	(via
		(at 466.323934 -6.811772)
		(size 0.5588)
		(drill 0.3048)
		(layers "F.Cu" "B.Cu")
		(net "P3V3")
	)
	(via
		(at 475.0054 -142.5321)
		(size 0.508)
		(drill 0.254)
		(layers "F.Cu" "B.Cu")
		(net "P3V3")
	)
	(via
		(at 466.630766 -18.421604)
		(size 0.5588)
		(drill 0.3048)
		(layers "F.Cu" "B.Cu")
		(net "P3V3")
	)
	(via
		(at 396.367 -88.9)
		(size 0.508)
		(drill 0.254)
		(layers "F.Cu" "B.Cu")
		(net "P3V3")
	)
	(via
		(at 468.380572 -148.966428)
		(size 0.508)
		(drill 0.254)
		(layers "F.Cu" "B.Cu")
		(net "P3V3")
	)
	(via
		(at 180.406802 3.683)
		(size 0.508)
		(drill 0.254)
		(layers "F.Cu" "B.Cu")
		(net "P3V3")
	)
	(via
		(at 363.642656 -48.314102)
		(size 0.5588)
		(drill 0.3048)
		(layers "F.Cu" "B.Cu")
		(net "P3V3")
	)
	(via
		(at 481.39985 -113.805716)
		(size 0.5588)
		(drill 0.3048)
		(layers "F.Cu" "B.Cu")
		(net "P3V3")
	)
	(via
		(at 389.0518 -39.5224)
		(size 0.508)
		(drill 0.254)
		(layers "F.Cu" "B.Cu")
		(net "P3V3")
	)
	(via
		(at 180.8226 -83.2358)
		(size 0.508)
		(drill 0.254)
		(layers "F.Cu" "B.Cu")
		(net "P3V3")
	)
	(via
		(at 490.636306 -45.312584)
		(size 0.508)
		(drill 0.254)
		(layers "F.Cu" "B.Cu")
		(net "P3V3")
	)
	(via
		(at 373.9388 -61.722)
		(size 0.508)
		(drill 0.254)
		(layers "F.Cu" "B.Cu")
		(net "P3V3")
	)
	(via
		(at 194.691 -26.1366)
		(size 0.508)
		(drill 0.254)
		(layers "F.Cu" "B.Cu")
		(net "P3V3")
	)
	(via
		(at 468.67191 -17.790668)
		(size 0.5588)
		(drill 0.3048)
		(layers "F.Cu" "B.Cu")
		(net "P3V3")
	)
	(via
		(at 341.6427 -69.1769)
		(size 0.508)
		(drill 0.254)
		(layers "F.Cu" "B.Cu")
		(net "P3V3")
	)
	(via
		(at 480.600004 -113.805716)
		(size 0.5588)
		(drill 0.3048)
		(layers "F.Cu" "B.Cu")
		(net "P3V3")
	)
	(via
		(at 391.518902 -39.435786)
		(size 0.508)
		(drill 0.254)
		(layers "F.Cu" "B.Cu")
		(net "P3V3")
	)
	(via
		(at 496.951 -128.89738)
		(size 0.508)
		(drill 0.254)
		(layers "F.Cu" "B.Cu")
		(net "P3V3")
	)
	(via
		(at 391.664952 -23.547578)
		(size 0.508)
		(drill 0.254)
		(layers "F.Cu" "B.Cu")
		(net "P3V3")
	)
	(via
		(at 454.7235 -132.6769)
		(size 0.508)
		(drill 0.254)
		(layers "F.Cu" "B.Cu")
		(net "P3V3")
	)
	(via
		(at 467.32571 -18.463768)
		(size 0.5588)
		(drill 0.3048)
		(layers "F.Cu" "B.Cu")
		(net "P3V3")
	)
	(via
		(at 479.797872 -115.413282)
		(size 0.5588)
		(drill 0.3048)
		(layers "F.Cu" "B.Cu")
		(net "P3V3")
	)
	(via
		(at 171.2722 -124.333)
		(size 0.508)
		(drill 0.254)
		(layers "F.Cu" "B.Cu")
		(net "P3V3")
	)
	(via
		(at 317.841376 -32.49295)
		(size 0.508)
		(drill 0.254)
		(layers "F.Cu" "B.Cu")
		(net "P3V3")
	)
	(via
		(at 479.799904 -113.805716)
		(size 0.5588)
		(drill 0.3048)
		(layers "F.Cu" "B.Cu")
		(net "P3V3")
	)
	(via
		(at 469.72855 -17.109948)
		(size 0.5588)
		(drill 0.3048)
		(layers "F.Cu" "B.Cu")
		(net "P3V3")
	)
	(via
		(at 455.803 -155.575)
		(size 0.508)
		(drill 0.254)
		(layers "F.Cu" "B.Cu")
		(net "P3V3")
	)
	(via
		(at 419.545516 -123.95835)
		(size 0.508)
		(drill 0.254)
		(layers "F.Cu" "B.Cu")
		(net "P3V3")
	)
	(segment
		(start 183.625998 -5.761736)
		(end 183.625998 -5.321808)
		(width 0.4064)
		(layer "B.Cu")
		(net "P3V3")
	)
	(segment
		(start 413.059118 -92.428314)
		(end 413.3215 -92.428314)
		(width 0.254)
		(layer "B.Cu")
		(net "P3V3")
	)
	(segment
		(start 415.340038 -116.703602)
		(end 415.340038 -117.063774)
		(width 0.254)
		(layer "B.Cu")
		(net "P3V3")
	)
	(segment
		(start 416.909504 -107.277916)
		(end 415.340546 -108.846874)
		(width 0.254)
		(layer "B.Cu")
		(net "P3V3")
	)
	(segment
		(start 391.756138 -18.9103)
		(end 393.446 -18.9103)
		(width 0.254)
		(layer "B.Cu")
		(net "P3V3")
	)
	(segment
		(start 435.88432 -15.92072)
		(end 436.372 -16.4084)
		(width 0.254)
		(layer "B.Cu")
		(net "P3V3")
	)
	(segment
		(start 420.10584 -142.98422)
		(end 420.10584 -142.4432)
		(width 0.254)
		(layer "B.Cu")
		(net "P3V3")
	)
	(segment
		(start 176.403 -128.905)
		(end 173.609 -126.111)
		(width 0.508)
		(layer "B.Cu")
		(net "P3V3")
	)
	(segment
		(start 364.321852 -47.220378)
		(end 364.381288 -47.279814)
		(width 0.254)
		(layer "B.Cu")
		(net "P3V3")
	)
	(segment
		(start 495.28476 -124.0663)
		(end 494.3729 -124.0663)
		(width 0.254)
		(layer "B.Cu")
		(net "P3V3")
	)
	(segment
		(start 413.3215 -92.428314)
		(end 413.5755 -92.174314)
		(width 0.254)
		(layer "B.Cu")
		(net "P3V3")
	)
	(segment
		(start 168.0972 -7.366)
		(end 168.6306 -7.366)
		(width 0.254)
		(layer "B.Cu")
		(net "P3V3")
	)
	(segment
		(start 339.875114 -75.217782)
		(end 340.988904 -74.103992)
		(width 0.508)
		(layer "B.Cu")
		(net "P3V3")
	)
	(segment
		(start 174.5234 -146.939)
		(end 176.4284 -146.939)
		(width 0.508)
		(layer "B.Cu")
		(net "P3V3")
	)
	(segment
		(start 490.382306 -46.157388)
		(end 489.773214 -46.157388)
		(width 0.254)
		(layer "B.Cu")
		(net "P3V3")
	)
	(segment
		(start 489.773214 -46.157388)
		(end 489.572046 -46.358556)
		(width 0.254)
		(layer "B.Cu")
		(net "P3V3")
	)
	(segment
		(start 432.6255 -15.92072)
		(end 435.88432 -15.92072)
		(width 0.254)
		(layer "B.Cu")
		(net "P3V3")
	)
	(segment
		(start 174.5234 -146.4691)
		(end 173.863 -145.8087)
		(width 0.508)
		(layer "B.Cu")
		(net "P3V3")
	)
	(segment
		(start 176.403 -139.5476)
		(end 176.403 -128.905)
		(width 0.508)
		(layer "B.Cu")
		(net "P3V3")
	)
	(segment
		(start 417.19881 -119.104918)
		(end 417.19881 -120.95226)
		(width 0.254)
		(layer "B.Cu")
		(net "P3V3")
	)
	(segment
		(start 176.168812 -3.2258)
		(end 176.5554 -3.612388)
		(width 0.4064)
		(layer "B.Cu")
		(net "P3V3")
	)
	(segment
		(start 364.381288 -47.279814)
		(end 364.381288 -48.242728)
		(width 0.254)
		(layer "B.Cu")
		(net "P3V3")
	)
	(segment
		(start 432.6255 -15.92072)
		(end 432.6255 -16.383)
		(width 0.381)
		(layer "B.Cu")
		(net "P3V3")
	)
	(segment
		(start 176.2506 -7.62)
		(end 176.2506 -5.9309)
		(width 0.254)
		(layer "B.Cu")
		(net "P3V3")
	)
	(segment
		(start 337.6422 -79.119476)
		(end 337.6422 -76.2762)
		(width 0.508)
		(layer "B.Cu")
		(net "P3V3")
	)
	(segment
		(start 489.445046 -46.503844)
		(end 489.445046 -46.665388)
		(width 0.254)
		(layer "B.Cu")
		(net "P3V3")
	)
	(segment
		(start 431.609246 -18.122138)
		(end 431.1142 -18.617184)
		(width 0.381)
		(layer "B.Cu")
		(net "P3V3")
	)
	(segment
		(start 338.700618 -75.217782)
		(end 339.875114 -75.217782)
		(width 0.508)
		(layer "B.Cu")
		(net "P3V3")
	)
	(segment
		(start 417.19881 -121.313194)
		(end 417.058602 -121.453402)
		(width 0.254)
		(layer "B.Cu")
		(net "P3V3")
	)
	(segment
		(start 413.059118 -92.428314)
		(end 413.059118 -92.807282)
		(width 0.254)
		(layer "B.Cu")
		(net "P3V3")
	)
	(segment
		(start 385.90474 -83.22056)
		(end 384.6068 -83.22056)
		(width 0.254)
		(layer "B.Cu")
		(net "P3V3")
	)
	(segment
		(start 175.8696 -8.001)
		(end 176.2506 -7.62)
		(width 0.254)
		(layer "B.Cu")
		(net "P3V3")
	)
	(segment
		(start 496.05438 -128.15062)
		(end 496.20424 -128.15062)
		(width 0.254)
		(layer "B.Cu")
		(net "P3V3")
	)
	(segment
		(start 338.2391 -80.5815)
		(end 338.2391 -79.716376)
		(width 0.508)
		(layer "B.Cu")
		(net "P3V3")
	)
	(segment
		(start 182.378604 -145.281396)
		(end 182.378604 -145.167096)
		(width 0.508)
		(layer "B.Cu")
		(net "P3V3")
	)
	(segment
		(start 415.068004 -97.923604)
		(end 415.068004 -102.682802)
		(width 0.254)
		(layer "B.Cu")
		(net "P3V3")
	)
	(segment
		(start 417.199064 -121.312686)
		(end 417.19881 -121.31294)
		(width 0.254)
		(layer "B.Cu")
		(net "P3V3")
	)
	(segment
		(start 495.28476 -123.88596)
		(end 494.6777 -123.2789)
		(width 0.254)
		(layer "B.Cu")
		(net "P3V3")
	)
	(segment
		(start 413.5628 -96.4184)
		(end 413.5628 -94.3356)
		(width 0.254)
		(layer "B.Cu")
		(net "P3V3")
	)
	(segment
		(start 495.28476 -124.0663)
		(end 495.28476 -123.88596)
		(width 0.254)
		(layer "B.Cu")
		(net "P3V3")
	)
	(segment
		(start 176.149 -3.2258)
		(end 176.168812 -3.2258)
		(width 0.4064)
		(layer "B.Cu")
		(net "P3V3")
	)
	(segment
		(start 418.50564 -140.843)
		(end 417.895024 -140.843)
		(width 0.254)
		(layer "B.Cu")
		(net "P3V3")
	)
	(segment
		(start 377.973336 -37.3634)
		(end 378.5616 -37.3634)
		(width 0.254)
		(layer "B.Cu")
		(net "P3V3")
	)
	(segment
		(start 174.5234 -148.55698)
		(end 173.72584 -149.35454)
		(width 0.508)
		(layer "B.Cu")
		(net "P3V3")
	)
	(segment
		(start 399.55724 -21.791676)
		(end 399.55724 -21.36648)
		(width 0.254)
		(layer "B.Cu")
		(net "P3V3")
	)
	(segment
		(start 474.64218 -10.86231)
		(end 474.76918 -10.86231)
		(width 0.254)
		(layer "B.Cu")
		(net "P3V3")
	)
	(segment
		(start 340.988904 -71.822564)
		(end 341.6427 -71.168768)
		(width 0.508)
		(layer "B.Cu")
		(net "P3V3")
	)
	(segment
		(start 380.165102 -44.412662)
		(end 381.367538 -44.412662)
		(width 0.254)
		(layer "B.Cu")
		(net "P3V3")
	)
	(segment
		(start 390.87298 -20.06092)
		(end 390.87298 -19.786346)
		(width 0.254)
		(layer "B.Cu")
		(net "P3V3")
	)
	(segment
		(start 173.863 -145.8087)
		(end 173.863 -142.0876)
		(width 0.508)
		(layer "B.Cu")
		(net "P3V3")
	)
	(segment
		(start 496.20424 -128.15062)
		(end 496.951 -128.89738)
		(width 0.254)
		(layer "B.Cu")
		(net "P3V3")
	)
	(segment
		(start 172.04182 -149.35454)
		(end 171.42968 -148.7424)
		(width 0.508)
		(layer "B.Cu")
		(net "P3V3")
	)
	(segment
		(start 182.378604 -145.167096)
		(end 183.2229 -144.3228)
		(width 0.508)
		(layer "B.Cu")
		(net "P3V3")
	)
	(segment
		(start 168.0972 -8.29056)
		(end 168.0972 -7.366)
		(width 0.254)
		(layer "B.Cu")
		(net "P3V3")
	)
	(segment
		(start 364.65637 -62.6237)
		(end 364.58017 -62.6999)
		(width 0.254)
		(layer "B.Cu")
		(net "P3V3")
	)
	(segment
		(start 183.82361 -5.959348)
		(end 183.625998 -5.761736)
		(width 0.4064)
		(layer "B.Cu")
		(net "P3V3")
	)
	(segment
		(start 416.909504 -104.524302)
		(end 416.909504 -107.277916)
		(width 0.254)
		(layer "B.Cu")
		(net "P3V3")
	)
	(segment
		(start 172.829982 -126.093982)
		(end 171.581572 -126.093982)
		(width 0.4572)
		(layer "B.Cu")
		(net "P3V3")
	)
	(segment
		(start 418.350192 -123.95835)
		(end 419.545516 -123.95835)
		(width 0.254)
		(layer "B.Cu")
		(net "P3V3")
	)
	(segment
		(start 489.445046 -46.665388)
		(end 489.445046 -47.902622)
		(width 0.254)
		(layer "B.Cu")
		(net "P3V3")
	)
	(segment
		(start 168.019476 -8.368284)
		(end 168.0972 -8.29056)
		(width 0.254)
		(layer "B.Cu")
		(net "P3V3")
	)
	(segment
		(start 432.6255 -16.383)
		(end 432.2445 -16.764)
		(width 0.381)
		(layer "B.Cu")
		(net "P3V3")
	)
	(segment
		(start 417.199064 -120.952514)
		(end 417.199064 -121.312686)
		(width 0.254)
		(layer "B.Cu")
		(net "P3V3")
	)
	(segment
		(start 173.72584 -149.35454)
		(end 172.04182 -149.35454)
		(width 0.508)
		(layer "B.Cu")
		(net "P3V3")
	)
	(segment
		(start 428.3075 -22.606)
		(end 428.3075 -21.844)
		(width 0.254)
		(layer "B.Cu")
		(net "P3V3")
	)
	(segment
		(start 171.42968 -148.7424)
		(end 168.61028 -148.7424)
		(width 0.508)
		(layer "B.Cu")
		(net "P3V3")
	)
	(segment
		(start 489.572046 -46.376844)
		(end 489.445046 -46.503844)
		(width 0.254)
		(layer "B.Cu")
		(net "P3V3")
	)
	(segment
		(start 413.059118 -92.807282)
		(end 412.8516 -93.0148)
		(width 0.254)
		(layer "B.Cu")
		(net "P3V3")
	)
	(segment
		(start 442.849 -17.2212)
		(end 443.1157 -16.9545)
		(width 0.254)
		(layer "B.Cu")
		(net "P3V3")
	)
	(segment
		(start 413.9438 -89.636346)
		(end 413.9438 -89.4207)
		(width 0.254)
		(layer "B.Cu")
		(net "P3V3")
	)
	(segment
		(start 377.439936 -36.83)
		(end 377.973336 -37.3634)
		(width 0.254)
		(layer "B.Cu")
		(net "P3V3")
	)
	(segment
		(start 176.2506 -5.9309)
		(end 176.1744 -5.8547)
		(width 0.254)
		(layer "B.Cu")
		(net "P3V3")
	)
	(segment
		(start 431.609246 -17.145)
		(end 431.609246 -17.585182)
		(width 0.381)
		(layer "B.Cu")
		(net "P3V3")
	)
	(segment
		(start 415.340292 -116.703348)
		(end 415.340038 -116.703602)
		(width 0.254)
		(layer "B.Cu")
		(net "P3V3")
	)
	(segment
		(start 412.8516 -93.853)
		(end 413.0294 -94.0308)
		(width 0.254)
		(layer "B.Cu")
		(net "P3V3")
	)
	(segment
		(start 415.340546 -117.064282)
		(end 415.340546 -117.246654)
		(width 0.254)
		(layer "B.Cu")
		(net "P3V3")
	)
	(segment
		(start 490.636306 -45.903388)
		(end 490.382306 -46.157388)
		(width 0.254)
		(layer "B.Cu")
		(net "P3V3")
	)
	(segment
		(start 174.5234 -146.939)
		(end 174.5234 -148.55698)
		(width 0.508)
		(layer "B.Cu")
		(net "P3V3")
	)
	(segment
		(start 490.636306 -45.312584)
		(end 490.636306 -45.903388)
		(width 0.254)
		(layer "B.Cu")
		(net "P3V3")
	)
	(segment
		(start 431.990246 -16.764)
		(end 431.609246 -17.145)
		(width 0.381)
		(layer "B.Cu")
		(net "P3V3")
	)
	(segment
		(start 391.6045 -19.054826)
		(end 391.611612 -19.054826)
		(width 0.254)
		(layer "B.Cu")
		(net "P3V3")
	)
	(segment
		(start 494.75136 -128.2954)
		(end 495.9096 -128.2954)
		(width 0.254)
		(layer "B.Cu")
		(net "P3V3")
	)
	(segment
		(start 183.2229 -144.3228)
		(end 184.155334 -144.3228)
		(width 0.508)
		(layer "B.Cu")
		(net "P3V3")
	)
	(segment
		(start 175.2346 -5.4737)
		(end 175.2346 -5.2832)
		(width 0.4064)
		(layer "B.Cu")
		(net "P3V3")
	)
	(segment
		(start 391.611612 -19.054826)
		(end 391.756138 -18.9103)
		(width 0.254)
		(layer "B.Cu")
		(net "P3V3")
	)
	(segment
		(start 428.3075 -21.844)
		(end 429.0695 -21.844)
		(width 0.254)
		(layer "B.Cu")
		(net "P3V3")
	)
	(segment
		(start 378.5616 -37.3634)
		(end 378.6886 -37.2364)
		(width 0.254)
		(layer "B.Cu")
		(net "P3V3")
	)
	(segment
		(start 436.372 -16.4084)
		(end 439.0644 -16.4084)
		(width 0.254)
		(layer "B.Cu")
		(net "P3V3")
	)
	(segment
		(start 413.5628 -94.3356)
		(end 413.258 -94.0308)
		(width 0.254)
		(layer "B.Cu")
		(net "P3V3")
	)
	(segment
		(start 340.988904 -74.103992)
		(end 340.988904 -71.822564)
		(width 0.508)
		(layer "B.Cu")
		(net "P3V3")
	)
	(segment
		(start 414.02 -96.8756)
		(end 413.5628 -96.4184)
		(width 0.254)
		(layer "B.Cu")
		(net "P3V3")
	)
	(segment
		(start 434.721 -147.911058)
		(end 434.3146 -147.504658)
		(width 0.4064)
		(layer "B.Cu")
		(net "P3V3")
	)
	(segment
		(start 434.721 -150.2029)
		(end 434.721 -147.911058)
		(width 0.4064)
		(layer "B.Cu")
		(net "P3V3")
	)
	(segment
		(start 413.258 -94.0308)
		(end 413.0294 -94.0308)
		(width 0.254)
		(layer "B.Cu")
		(net "P3V3")
	)
	(segment
		(start 417.058602 -122.66676)
		(end 418.350192 -123.95835)
		(width 0.254)
		(layer "B.Cu")
		(net "P3V3")
	)
	(segment
		(start 489.572046 -46.358556)
		(end 489.572046 -46.376844)
		(width 0.254)
		(layer "B.Cu")
		(net "P3V3")
	)
	(segment
		(start 186.309 -152.3238)
		(end 185.2168 -153.416)
		(width 0.508)
		(layer "B.Cu")
		(net "P3V3")
	)
	(segment
		(start 176.127664 -3.204464)
		(end 176.149 -3.2258)
		(width 0.4064)
		(layer "B.Cu")
		(net "P3V3")
	)
	(segment
		(start 169.2656 -8.001)
		(end 175.8696 -8.001)
		(width 0.254)
		(layer "B.Cu")
		(net "P3V3")
	)
	(segment
		(start 415.340038 -117.063774)
		(end 415.340546 -117.064282)
		(width 0.254)
		(layer "B.Cu")
		(net "P3V3")
	)
	(segment
		(start 168.6306 -7.366)
		(end 169.2656 -8.001)
		(width 0.254)
		(layer "B.Cu")
		(net "P3V3")
	)
	(segment
		(start 474.843856 -10.787634)
		(end 475.793816 -10.787634)
		(width 0.254)
		(layer "B.Cu")
		(net "P3V3")
	)
	(segment
		(start 415.068004 -102.682802)
		(end 416.909504 -104.524302)
		(width 0.254)
		(layer "B.Cu")
		(net "P3V3")
	)
	(segment
		(start 171.581572 -126.093982)
		(end 171.2722 -125.78461)
		(width 0.4572)
		(layer "B.Cu")
		(net "P3V3")
	)
	(segment
		(start 415.340546 -116.50853)
		(end 415.340292 -116.508784)
		(width 0.254)
		(layer "B.Cu")
		(net "P3V3")
	)
	(segment
		(start 184.9628 -144.3228)
		(end 185.42 -144.78)
		(width 0.508)
		(layer "B.Cu")
		(net "P3V3")
	)
	(segment
		(start 475.793816 -10.787634)
		(end 476.484696 -11.478514)
		(width 0.254)
		(layer "B.Cu")
		(net "P3V3")
	)
	(segment
		(start 176.9364 -147.6756)
		(end 178.7144 -147.6756)
		(width 0.508)
		(layer "B.Cu")
		(net "P3V3")
	)
	(segment
		(start 176.9364 -147.447)
		(end 176.9364 -147.6756)
		(width 0.508)
		(layer "B.Cu")
		(net "P3V3")
	)
	(segment
		(start 363.71403 -48.242728)
		(end 364.381288 -48.242728)
		(width 0.254)
		(layer "B.Cu")
		(net "P3V3")
	)
	(segment
		(start 180.212746 -146.177254)
		(end 180.965856 -146.177254)
		(width 0.508)
		(layer "B.Cu")
		(net "P3V3")
	)
	(segment
		(start 494.3729 -124.0663)
		(end 494.3729 -123.5837)
		(width 0.254)
		(layer "B.Cu")
		(net "P3V3")
	)
	(segment
		(start 181.864 -145.796)
		(end 182.378604 -145.281396)
		(width 0.508)
		(layer "B.Cu")
		(net "P3V3")
	)
	(segment
		(start 494.3729 -123.5837)
		(end 494.6777 -123.2789)
		(width 0.254)
		(layer "B.Cu")
		(net "P3V3")
	)
	(segment
		(start 186.309 -147.32)
		(end 186.309 -152.3238)
		(width 0.508)
		(layer "B.Cu")
		(net "P3V3")
	)
	(segment
		(start 439.8772 -17.2212)
		(end 442.849 -17.2212)
		(width 0.254)
		(layer "B.Cu")
		(net "P3V3")
	)
	(segment
		(start 184.155334 -144.3228)
		(end 184.9628 -144.3228)
		(width 0.508)
		(layer "B.Cu")
		(net "P3V3")
	)
	(segment
		(start 443.1157 -16.9545)
		(end 443.1157 -15.5702)
		(width 0.254)
		(layer "B.Cu")
		(net "P3V3")
	)
	(segment
		(start 377.2281 -36.83)
		(end 377.439936 -36.83)
		(width 0.254)
		(layer "B.Cu")
		(net "P3V3")
	)
	(segment
		(start 364.4265 -61.381132)
		(end 363.4486 -62.359032)
		(width 0.254)
		(layer "B.Cu")
		(net "P3V3")
	)
	(segment
		(start 384.6068 -83.22056)
		(end 384.5687 -83.18246)
		(width 0.254)
		(layer "B.Cu")
		(net "P3V3")
	)
	(segment
		(start 341.6427 -71.168768)
		(end 341.6427 -69.1769)
		(width 0.508)
		(layer "B.Cu")
		(net "P3V3")
	)
	(segment
		(start 434.3273 -150.5966)
		(end 434.721 -150.2029)
		(width 0.4064)
		(layer "B.Cu")
		(net "P3V3")
	)
	(segment
		(start 415.340292 -116.508784)
		(end 415.340292 -116.703348)
		(width 0.254)
		(layer "B.Cu")
		(net "P3V3")
	)
	(segment
		(start 373.9388 -61.722)
		(end 374.4214 -61.2394)
		(width 0.254)
		(layer "B.Cu")
		(net "P3V3")
	)
	(segment
		(start 414.02 -96.8756)
		(end 415.068004 -97.923604)
		(width 0.254)
		(layer "B.Cu")
		(net "P3V3")
	)
	(segment
		(start 185.42 -144.78)
		(end 185.42 -145.923)
		(width 0.508)
		(layer "B.Cu")
		(net "P3V3")
	)
	(segment
		(start 381.367538 -44.412662)
		(end 381.5842 -44.196)
		(width 0.254)
		(layer "B.Cu")
		(net "P3V3")
	)
	(segment
		(start 381.5842 -44.196)
		(end 382.3335 -44.196)
		(width 0.254)
		(layer "B.Cu")
		(net "P3V3")
	)
	(segment
		(start 337.6422 -76.2762)
		(end 338.700618 -75.217782)
		(width 0.508)
		(layer "B.Cu")
		(net "P3V3")
	)
	(segment
		(start 174.6123 -3.683)
		(end 175.090836 -3.204464)
		(width 0.4064)
		(layer "B.Cu")
		(net "P3V3")
	)
	(segment
		(start 420.10584 -142.4432)
		(end 418.50564 -140.843)
		(width 0.254)
		(layer "B.Cu")
		(net "P3V3")
	)
	(segment
		(start 173.609 -126.111)
		(end 172.847 -126.111)
		(width 0.508)
		(layer "B.Cu")
		(net "P3V3")
	)
	(segment
		(start 185.2168 -153.416)
		(end 184.658 -153.416)
		(width 0.508)
		(layer "B.Cu")
		(net "P3V3")
	)
	(segment
		(start 364.321852 -46.788578)
		(end 364.321852 -47.220378)
		(width 0.254)
		(layer "B.Cu")
		(net "P3V3")
	)
	(segment
		(start 171.2722 -125.78461)
		(end 171.2722 -124.333)
		(width 0.4572)
		(layer "B.Cu")
		(net "P3V3")
	)
	(segment
		(start 413.5755 -90.004646)
		(end 413.9438 -89.636346)
		(width 0.254)
		(layer "B.Cu")
		(net "P3V3")
	)
	(segment
		(start 415.340546 -108.846874)
		(end 415.340546 -116.50853)
		(width 0.254)
		(layer "B.Cu")
		(net "P3V3")
	)
	(segment
		(start 180.406802 3.683)
		(end 180.592222 3.683)
		(width 0.4064)
		(layer "B.Cu")
		(net "P3V3")
	)
	(segment
		(start 432.2445 -16.764)
		(end 431.990246 -16.764)
		(width 0.381)
		(layer "B.Cu")
		(net "P3V3")
	)
	(segment
		(start 185.42 -145.923)
		(end 185.42 -146.431)
		(width 0.508)
		(layer "B.Cu")
		(net "P3V3")
	)
	(segment
		(start 400.667474 -22.221698)
		(end 399.987262 -22.221698)
		(width 0.254)
		(layer "B.Cu")
		(net "P3V3")
	)
	(segment
		(start 173.863 -142.0876)
		(end 176.403 -139.5476)
		(width 0.508)
		(layer "B.Cu")
		(net "P3V3")
	)
	(segment
		(start 413.5755 -92.174314)
		(end 413.5755 -90.004646)
		(width 0.254)
		(layer "B.Cu")
		(net "P3V3")
	)
	(segment
		(start 181.34711 -145.796)
		(end 181.864 -145.796)
		(width 0.508)
		(layer "B.Cu")
		(net "P3V3")
	)
	(segment
		(start 363.4486 -62.359032)
		(end 363.4486 -62.6999)
		(width 0.254)
		(layer "B.Cu")
		(net "P3V3")
	)
	(segment
		(start 181.339998 2.935224)
		(end 181.339998 2.425192)
		(width 0.4064)
		(layer "B.Cu")
		(net "P3V3")
	)
	(segment
		(start 185.42 -146.431)
		(end 186.309 -147.32)
		(width 0.508)
		(layer "B.Cu")
		(net "P3V3")
	)
	(segment
		(start 364.4265 -60.87872)
		(end 364.4265 -61.381132)
		(width 0.254)
		(layer "B.Cu")
		(net "P3V3")
	)
	(segment
		(start 175.6156 -5.8547)
		(end 175.2346 -5.4737)
		(width 0.4064)
		(layer "B.Cu")
		(net "P3V3")
	)
	(segment
		(start 417.058602 -121.453402)
		(end 417.058602 -122.66676)
		(width 0.254)
		(layer "B.Cu")
		(net "P3V3")
	)
	(segment
		(start 373.0498 -44.0309)
		(end 372.9863 -44.0944)
		(width 0.254)
		(layer "B.Cu")
		(net "P3V3")
	)
	(segment
		(start 476.484696 -11.478514)
		(end 476.484696 -12.0015)
		(width 0.254)
		(layer "B.Cu")
		(net "P3V3")
	)
	(segment
		(start 499.2878 -145.9738)
		(end 499.0338 -145.9738)
		(width 0.254)
		(layer "B.Cu")
		(net "P3V3")
	)
	(segment
		(start 338.2391 -79.716376)
		(end 337.6422 -79.119476)
		(width 0.508)
		(layer "B.Cu")
		(net "P3V3")
	)
	(segment
		(start 174.5234 -146.939)
		(end 174.5234 -146.4691)
		(width 0.508)
		(layer "B.Cu")
		(net "P3V3")
	)
	(segment
		(start 489.445046 -47.902622)
		(end 489.417614 -47.930054)
		(width 0.254)
		(layer "B.Cu")
		(net "P3V3")
	)
	(segment
		(start 180.965856 -146.177254)
		(end 181.34711 -145.796)
		(width 0.508)
		(layer "B.Cu")
		(net "P3V3")
	)
	(segment
		(start 175.090836 -3.204464)
		(end 176.127664 -3.204464)
		(width 0.4064)
		(layer "B.Cu")
		(net "P3V3")
	)
	(segment
		(start 399.987262 -22.221698)
		(end 399.55724 -21.791676)
		(width 0.254)
		(layer "B.Cu")
		(net "P3V3")
	)
	(segment
		(start 474.76918 -10.86231)
		(end 474.843856 -10.787634)
		(width 0.254)
		(layer "B.Cu")
		(net "P3V3")
	)
	(segment
		(start 172.847 -126.111)
		(end 172.829982 -126.093982)
		(width 0.4572)
		(layer "B.Cu")
		(net "P3V3")
	)
	(segment
		(start 495.9096 -128.2954)
		(end 496.05438 -128.15062)
		(width 0.254)
		(layer "B.Cu")
		(net "P3V3")
	)
	(segment
		(start 417.19881 -121.31294)
		(end 417.19881 -121.313194)
		(width 0.254)
		(layer "B.Cu")
		(net "P3V3")
	)
	(segment
		(start 382.3335 -44.196)
		(end 382.3335 -44.958)
		(width 0.254)
		(layer "B.Cu")
		(net "P3V3")
	)
	(segment
		(start 417.19881 -120.95226)
		(end 417.199064 -120.952514)
		(width 0.254)
		(layer "B.Cu")
		(net "P3V3")
	)
	(segment
		(start 372.9863 -44.0944)
		(end 372.9863 -44.8818)
		(width 0.254)
		(layer "B.Cu")
		(net "P3V3")
	)
	(segment
		(start 499.0338 -145.9738)
		(end 498.602 -145.542)
		(width 0.254)
		(layer "B.Cu")
		(net "P3V3")
	)
	(segment
		(start 176.5554 -3.612388)
		(end 176.5554 -5.4737)
		(width 0.4064)
		(layer "B.Cu")
		(net "P3V3")
	)
	(segment
		(start 415.340546 -117.246654)
		(end 417.19881 -119.104918)
		(width 0.254)
		(layer "B.Cu")
		(net "P3V3")
	)
	(segment
		(start 434.3146 -147.504658)
		(end 434.132482 -147.504658)
		(width 0.4064)
		(layer "B.Cu")
		(net "P3V3")
	)
	(segment
		(start 176.4284 -146.939)
		(end 176.9364 -147.447)
		(width 0.508)
		(layer "B.Cu")
		(net "P3V3")
	)
	(segment
		(start 176.1744 -5.8547)
		(end 175.6156 -5.8547)
		(width 0.4064)
		(layer "B.Cu")
		(net "P3V3")
	)
	(segment
		(start 439.0644 -16.4084)
		(end 439.8772 -17.2212)
		(width 0.254)
		(layer "B.Cu")
		(net "P3V3")
	)
	(segment
		(start 431.609246 -17.585182)
		(end 431.609246 -18.122138)
		(width 0.381)
		(layer "B.Cu")
		(net "P3V3")
	)
	(segment
		(start 363.642656 -48.314102)
		(end 363.71403 -48.242728)
		(width 0.254)
		(layer "B.Cu")
		(net "P3V3")
	)
	(segment
		(start 180.592222 3.683)
		(end 181.339998 2.935224)
		(width 0.4064)
		(layer "B.Cu")
		(net "P3V3")
	)
	(segment
		(start 390.87298 -19.786346)
		(end 391.6045 -19.054826)
		(width 0.254)
		(layer "B.Cu")
		(net "P3V3")
	)
	(segment
		(start 176.5554 -5.4737)
		(end 176.1744 -5.8547)
		(width 0.4064)
		(layer "B.Cu")
		(net "P3V3")
	)
	(segment
		(start 364.58017 -62.6999)
		(end 363.4486 -62.6999)
		(width 0.254)
		(layer "B.Cu")
		(net "P3V3")
	)
	(segment
		(start 373.0498 -41.4274)
		(end 373.0498 -44.0309)
		(width 0.254)
		(layer "B.Cu")
		(net "P3V3")
	)
	(segment
		(start 412.8516 -93.0148)
		(end 412.8516 -93.853)
		(width 0.254)
		(layer "B.Cu")
		(net "P3V3")
	)
	(segment
		(start 374.4214 -61.2394)
		(end 374.4214 -60.4139)
		(width 0.254)
		(layer "B.Cu")
		(net "P3V3")
	)
	(segment
		(start 178.7144 -147.6756)
		(end 180.212746 -146.177254)
		(width 0.508)
		(layer "B.Cu")
		(net "P3V3")
	)
	(segment
		(start 179.9082 -83.2358)
		(end 180.8226 -83.2358)
		(width 0.4064)
		(layer "In2.Cu")
		(net "P3V3")
	)
	(segment
		(start 454.89368 -156.48432)
		(end 450.512688 -156.48432)
		(width 0.4064)
		(layer "In2.Cu")
		(net "P3V3")
	)
	(segment
		(start 478.13468 -151.57958)
		(end 481.04552 -151.57958)
		(width 0.4064)
		(layer "In2.Cu")
		(net "P3V3")
	)
	(segment
		(start 471.0938 -150.6982)
		(end 477.2533 -150.6982)
		(width 0.4064)
		(layer "In2.Cu")
		(net "P3V3")
	)
	(segment
		(start 432.414172 -141.214856)
		(end 431.511964 -142.117064)
		(width 0.254)
		(layer "In2.Cu")
		(net "P3V3")
	)
	(segment
		(start 474.64218 -10.86231)
		(end 474.66758 -10.88771)
		(width 0.508)
		(layer "In2.Cu")
		(net "P3V3")
	)
	(segment
		(start 498.602 -145.542)
		(end 499.7577 -144.3863)
		(width 0.381)
		(layer "In2.Cu")
		(net "P3V3")
	)
	(segment
		(start 455.803 -155.575)
		(end 454.89368 -156.48432)
		(width 0.4064)
		(layer "In2.Cu")
		(net "P3V3")
	)
	(segment
		(start 499.506748 -146.529044)
		(end 499.506748 -146.446748)
		(width 0.4064)
		(layer "In2.Cu")
		(net "P3V3")
	)
	(segment
		(start 394.901928 -82.694272)
		(end 394.901928 -79.426816)
		(width 0.254)
		(layer "In2.Cu")
		(net "P3V3")
	)
	(segment
		(start 498.1829 -132.560314)
		(end 498.1829 -131.895596)
		(width 0.381)
		(layer "In2.Cu")
		(net "P3V3")
	)
	(segment
		(start 498.2591 -130.20548)
		(end 497.2558 -129.20218)
		(width 0.381)
		(layer "In2.Cu")
		(net "P3V3")
	)
	(segment
		(start 405.483568 -83.010502)
		(end 404.39594 -81.922874)
		(width 0.254)
		(layer "In2.Cu")
		(net "P3V3")
	)
	(segment
		(start 468.380572 -148.966428)
		(end 469.362028 -148.966428)
		(width 0.4064)
		(layer "In2.Cu")
		(net "P3V3")
	)
	(segment
		(start 499.7577 -134.135114)
		(end 498.1829 -132.560314)
		(width 0.381)
		(layer "In2.Cu")
		(net "P3V3")
	)
	(segment
		(start 406.96261 -92.451174)
		(end 406.96261 -92.418662)
		(width 0.254)
		(layer "In2.Cu")
		(net "P3V3")
	)
	(segment
		(start 494.6777 -123.2789)
		(end 494.6777 -126.62408)
		(width 0.4064)
		(layer "In2.Cu")
		(net "P3V3")
	)
	(segment
		(start 176.9618 -96.945704)
		(end 178.9684 -94.939104)
		(width 0.4064)
		(layer "In2.Cu")
		(net "P3V3")
	)
	(segment
		(start 179.5272 -91.186)
		(end 179.5272 -83.6168)
		(width 0.4064)
		(layer "In2.Cu")
		(net "P3V3")
	)
	(segment
		(start 450.512688 -156.48432)
		(end 448.979798 -154.95143)
		(width 0.4064)
		(layer "In2.Cu")
		(net "P3V3")
	)
	(segment
		(start 477.2533 -150.6982)
		(end 478.13468 -151.57958)
		(width 0.4064)
		(layer "In2.Cu")
		(net "P3V3")
	)
	(segment
		(start 468.01024 -151.028146)
		(end 468.01024 -149.33676)
		(width 0.4064)
		(layer "In2.Cu")
		(net "P3V3")
	)
	(segment
		(start 439.332624 -141.214856)
		(end 432.414172 -141.214856)
		(width 0.254)
		(layer "In2.Cu")
		(net "P3V3")
	)
	(segment
		(start 474.66758 -16.270732)
		(end 473.602812 -17.3355)
		(width 0.508)
		(layer "In2.Cu")
		(net "P3V3")
	)
	(segment
		(start 420.572692 -142.517368)
		(end 420.10584 -142.98422)
		(width 0.254)
		(layer "In2.Cu")
		(net "P3V3")
	)
	(segment
		(start 499.557294 -146.57959)
		(end 499.506748 -146.529044)
		(width 0.4064)
		(layer "In2.Cu")
		(net "P3V3")
	)
	(segment
		(start 469.362028 -148.966428)
		(end 471.0938 -150.6982)
		(width 0.4064)
		(layer "In2.Cu")
		(net "P3V3")
	)
	(segment
		(start 481.72751 -152.26157)
		(end 483.57917 -152.26157)
		(width 0.4064)
		(layer "In2.Cu")
		(net "P3V3")
	)
	(segment
		(start 448.979798 -154.95143)
		(end 435.7624 -154.95143)
		(width 0.4064)
		(layer "In2.Cu")
		(net "P3V3")
	)
	(segment
		(start 435.356 -154.54503)
		(end 435.356 -151.2316)
		(width 0.4064)
		(layer "In2.Cu")
		(net "P3V3")
	)
	(segment
		(start 404.39594 -81.922874)
		(end 404.39594 -81.788508)
		(width 0.254)
		(layer "In2.Cu")
		(net "P3V3")
	)
	(segment
		(start 178.9684 -91.7448)
		(end 179.5272 -91.186)
		(width 0.4064)
		(layer "In2.Cu")
		(net "P3V3")
	)
	(segment
		(start 441.506864 -139.252706)
		(end 441.294774 -139.252706)
		(width 0.254)
		(layer "In2.Cu")
		(net "P3V3")
	)
	(segment
		(start 170.688 -123.7488)
		(end 170.688 -117.1702)
		(width 0.4064)
		(layer "In2.Cu")
		(net "P3V3")
	)
	(segment
		(start 435.356 -151.2316)
		(end 434.721 -150.5966)
		(width 0.4064)
		(layer "In2.Cu")
		(net "P3V3")
	)
	(segment
		(start 394.901928 -79.426816)
		(end 394.056616 -78.581504)
		(width 0.254)
		(layer "In2.Cu")
		(net "P3V3")
	)
	(segment
		(start 489.712 -154.7114)
		(end 491.122462 -156.121862)
		(width 0.4064)
		(layer "In2.Cu")
		(net "P3V3")
	)
	(segment
		(start 170.688 -117.1702)
		(end 177.5714 -110.2868)
		(width 0.4064)
		(layer "In2.Cu")
		(net "P3V3")
	)
	(segment
		(start 455.917808 -155.460192)
		(end 463.578194 -155.460192)
		(width 0.4064)
		(layer "In2.Cu")
		(net "P3V3")
	)
	(segment
		(start 177.5714 -102.2096)
		(end 176.9618 -101.6)
		(width 0.4064)
		(layer "In2.Cu")
		(net "P3V3")
	)
	(segment
		(start 499.7577 -144.3863)
		(end 499.7577 -134.135114)
		(width 0.381)
		(layer "In2.Cu")
		(net "P3V3")
	)
	(segment
		(start 405.483568 -90.93962)
		(end 405.483568 -83.010502)
		(width 0.254)
		(layer "In2.Cu")
		(net "P3V3")
	)
	(segment
		(start 435.7624 -154.95143)
		(end 435.356 -154.54503)
		(width 0.4064)
		(layer "In2.Cu")
		(net "P3V3")
	)
	(segment
		(start 499.557294 -153.441146)
		(end 499.557294 -146.57959)
		(width 0.4064)
		(layer "In2.Cu")
		(net "P3V3")
	)
	(segment
		(start 406.96261 -92.418662)
		(end 405.483568 -90.93962)
		(width 0.254)
		(layer "In2.Cu")
		(net "P3V3")
	)
	(segment
		(start 434.721 -150.5966)
		(end 434.3273 -150.5966)
		(width 0.4064)
		(layer "In2.Cu")
		(net "P3V3")
	)
	(segment
		(start 498.2591 -131.819396)
		(end 498.2591 -130.20548)
		(width 0.381)
		(layer "In2.Cu")
		(net "P3V3")
	)
	(segment
		(start 179.5272 -83.6168)
		(end 179.9082 -83.2358)
		(width 0.4064)
		(layer "In2.Cu")
		(net "P3V3")
	)
	(segment
		(start 494.6777 -126.62408)
		(end 496.951 -128.89738)
		(width 0.4064)
		(layer "In2.Cu")
		(net "P3V3")
	)
	(segment
		(start 481.04552 -151.57958)
		(end 481.72751 -152.26157)
		(width 0.4064)
		(layer "In2.Cu")
		(net "P3V3")
	)
	(segment
		(start 178.9684 -94.939104)
		(end 178.9684 -91.7448)
		(width 0.4064)
		(layer "In2.Cu")
		(net "P3V3")
	)
	(segment
		(start 423.437304 -142.117064)
		(end 423.037 -142.517368)
		(width 0.254)
		(layer "In2.Cu")
		(net "P3V3")
	)
	(segment
		(start 423.037 -142.517368)
		(end 420.572692 -142.517368)
		(width 0.254)
		(layer "In2.Cu")
		(net "P3V3")
	)
	(segment
		(start 431.511964 -142.117064)
		(end 423.437304 -142.117064)
		(width 0.254)
		(layer "In2.Cu")
		(net "P3V3")
	)
	(segment
		(start 455.803 -155.575)
		(end 455.917808 -155.460192)
		(width 0.4064)
		(layer "In2.Cu")
		(net "P3V3")
	)
	(segment
		(start 483.57917 -152.26157)
		(end 486.029 -154.7114)
		(width 0.4064)
		(layer "In2.Cu")
		(net "P3V3")
	)
	(segment
		(start 470.794842 -17.3355)
		(end 469.053418 -19.076924)
		(width 0.508)
		(layer "In2.Cu")
		(net "P3V3")
	)
	(segment
		(start 497.2558 -129.20218)
		(end 496.951 -128.89738)
		(width 0.4064)
		(layer "In2.Cu")
		(net "P3V3")
	)
	(segment
		(start 498.1829 -131.895596)
		(end 498.2591 -131.819396)
		(width 0.381)
		(layer "In2.Cu")
		(net "P3V3")
	)
	(segment
		(start 394.3604 -86.8934)
		(end 394.3604 -83.2358)
		(width 0.254)
		(layer "In2.Cu")
		(net "P3V3")
	)
	(segment
		(start 463.578194 -155.460192)
		(end 468.01024 -151.028146)
		(width 0.4064)
		(layer "In2.Cu")
		(net "P3V3")
	)
	(segment
		(start 394.3604 -83.2358)
		(end 394.901928 -82.694272)
		(width 0.254)
		(layer "In2.Cu")
		(net "P3V3")
	)
	(segment
		(start 499.506748 -146.446748)
		(end 498.602 -145.542)
		(width 0.4064)
		(layer "In2.Cu")
		(net "P3V3")
	)
	(segment
		(start 496.876578 -156.121862)
		(end 499.557294 -153.441146)
		(width 0.4064)
		(layer "In2.Cu")
		(net "P3V3")
	)
	(segment
		(start 171.2722 -124.333)
		(end 170.688 -123.7488)
		(width 0.4064)
		(layer "In2.Cu")
		(net "P3V3")
	)
	(segment
		(start 441.294774 -139.252706)
		(end 439.332624 -141.214856)
		(width 0.254)
		(layer "In2.Cu")
		(net "P3V3")
	)
	(segment
		(start 491.122462 -156.121862)
		(end 496.876578 -156.121862)
		(width 0.4064)
		(layer "In2.Cu")
		(net "P3V3")
	)
	(segment
		(start 486.029 -154.7114)
		(end 489.712 -154.7114)
		(width 0.4064)
		(layer "In2.Cu")
		(net "P3V3")
	)
	(segment
		(start 176.9618 -101.6)
		(end 176.9618 -96.945704)
		(width 0.4064)
		(layer "In2.Cu")
		(net "P3V3")
	)
	(segment
		(start 396.367 -88.9)
		(end 394.3604 -86.8934)
		(width 0.254)
		(layer "In2.Cu")
		(net "P3V3")
	)
	(segment
		(start 474.66758 -10.88771)
		(end 474.66758 -16.270732)
		(width 0.508)
		(layer "In2.Cu")
		(net "P3V3")
	)
	(segment
		(start 468.01024 -149.33676)
		(end 468.380572 -148.966428)
		(width 0.4064)
		(layer "In2.Cu")
		(net "P3V3")
	)
	(segment
		(start 177.5714 -110.2868)
		(end 177.5714 -102.2096)
		(width 0.4064)
		(layer "In2.Cu")
		(net "P3V3")
	)
	(segment
		(start 473.602812 -17.3355)
		(end 470.794842 -17.3355)
		(width 0.508)
		(layer "In2.Cu")
		(net "P3V3")
	)
	(segment
		(start 377.696222 -44.3738)
		(end 377.04141 -43.718988)
		(width 0.254)
		(layer "In4.Cu")
		(net "P3V3")
	)
	(segment
		(start 160.062164 -10.014712)
		(end 158.603696 -11.47318)
		(width 0.508)
		(layer "In4.Cu")
		(net "P3V3")
	)
	(segment
		(start 421.877744 -101.958394)
		(end 421.886888 -101.967538)
		(width 0.508)
		(layer "In4.Cu")
		(net "P3V3")
	)
	(segment
		(start 153.203402 -25.654254)
		(end 153.203402 -26.408634)
		(width 0.508)
		(layer "In4.Cu")
		(net "P3V3")
	)
	(segment
		(start 359.630218 -67.140582)
		(end 358.238044 -67.140582)
		(width 0.254)
		(layer "In4.Cu")
		(net "P3V3")
	)
	(segment
		(start 386.559552 -83.18246)
		(end 386.780532 -82.96148)
		(width 0.254)
		(layer "In4.Cu")
		(net "P3V3")
	)
	(segment
		(start 363.915706 -48.041052)
		(end 363.642656 -48.314102)
		(width 0.254)
		(layer "In4.Cu")
		(net "P3V3")
	)
	(segment
		(start 372.545356 -40.922956)
		(end 368.780314 -40.922956)
		(width 0.254)
		(layer "In4.Cu")
		(net "P3V3")
	)
	(segment
		(start 467.2584 -135.0772)
		(end 465.8614 -133.6802)
		(width 0.4064)
		(layer "In4.Cu")
		(net "P3V3")
	)
	(segment
		(start 358.238044 -67.140582)
		(end 357.205026 -68.1736)
		(width 0.254)
		(layer "In4.Cu")
		(net "P3V3")
	)
	(segment
		(start 364.1471 -62.6237)
		(end 359.630218 -67.140582)
		(width 0.254)
		(layer "In4.Cu")
		(net "P3V3")
	)
	(segment
		(start 466.918294 -140.675106)
		(end 467.4616 -140.1318)
		(width 0.4064)
		(layer "In4.Cu")
		(net "P3V3")
	)
	(segment
		(start 165.447472 -8.7884)
		(end 164.22116 -10.014712)
		(width 0.508)
		(layer "In4.Cu")
		(net "P3V3")
	)
	(segment
		(start 392.22172 -23.28164)
		(end 394.638276 -23.28164)
		(width 0.254)
		(layer "In4.Cu")
		(net "P3V3")
	)
	(segment
		(start 414.02 -96.8756)
		(end 417.367974 -96.8756)
		(width 0.508)
		(layer "In4.Cu")
		(net "P3V3")
	)
	(segment
		(start 467.8934 -145.104612)
		(end 466.918294 -144.129506)
		(width 0.4064)
		(layer "In4.Cu")
		(net "P3V3")
	)
	(segment
		(start 412.4452 -95.3008)
		(end 412.4452 -94.007686)
		(width 0.508)
		(layer "In4.Cu")
		(net "P3V3")
	)
	(segment
		(start 164.22116 -10.014712)
		(end 160.062164 -10.014712)
		(width 0.508)
		(layer "In4.Cu")
		(net "P3V3")
	)
	(segment
		(start 156.4132 -24.511)
		(end 154.346656 -24.511)
		(width 0.508)
		(layer "In4.Cu")
		(net "P3V3")
	)
	(segment
		(start 452.4502 -136.6012)
		(end 454.7235 -134.3279)
		(width 0.254)
		(layer "In4.Cu")
		(net "P3V3")
	)
	(segment
		(start 375.594626 -42.816018)
		(end 374.438418 -42.816018)
		(width 0.254)
		(layer "In4.Cu")
		(net "P3V3")
	)
	(segment
		(start 397.657574 -21.36648)
		(end 399.55724 -21.36648)
		(width 0.254)
		(layer "In4.Cu")
		(net "P3V3")
	)
	(segment
		(start 465.8614 -133.6802)
		(end 465.8614 -133.0706)
		(width 0.4064)
		(layer "In4.Cu")
		(net "P3V3")
	)
	(segment
		(start 468.380572 -148.966428)
		(end 467.8934 -148.479256)
		(width 0.4064)
		(layer "In4.Cu")
		(net "P3V3")
	)
	(segment
		(start 384.5687 -83.18246)
		(end 386.559552 -83.18246)
		(width 0.254)
		(layer "In4.Cu")
		(net "P3V3")
	)
	(segment
		(start 417.367974 -96.8756)
		(end 420.9542 -100.461826)
		(width 0.508)
		(layer "In4.Cu")
		(net "P3V3")
	)
	(segment
		(start 421.462454 -101.958394)
		(end 421.877744 -101.958394)
		(width 0.508)
		(layer "In4.Cu")
		(net "P3V3")
	)
	(segment
		(start 389.439912 -82.637376)
		(end 389.439912 -82.55)
		(width 0.254)
		(layer "In4.Cu")
		(net "P3V3")
	)
	(segment
		(start 158.603696 -11.47318)
		(end 158.603696 -22.320504)
		(width 0.508)
		(layer "In4.Cu")
		(net "P3V3")
	)
	(segment
		(start 394.915136 -23.00478)
		(end 396.019274 -23.00478)
		(width 0.254)
		(layer "In4.Cu")
		(net "P3V3")
	)
	(segment
		(start 168.019476 -8.368284)
		(end 167.59936 -8.7884)
		(width 0.508)
		(layer "In4.Cu")
		(net "P3V3")
	)
	(segment
		(start 373.0498 -41.4274)
		(end 372.545356 -40.922956)
		(width 0.254)
		(layer "In4.Cu")
		(net "P3V3")
	)
	(segment
		(start 454.7235 -134.3279)
		(end 454.7235 -132.6769)
		(width 0.254)
		(layer "In4.Cu")
		(net "P3V3")
	)
	(segment
		(start 338.2391 -82.9183)
		(end 338.2391 -80.5815)
		(width 0.508)
		(layer "In4.Cu")
		(net "P3V3")
	)
	(segment
		(start 396.019274 -23.00478)
		(end 397.657574 -21.36648)
		(width 0.254)
		(layer "In4.Cu")
		(net "P3V3")
	)
	(segment
		(start 329.302872 -93.27134)
		(end 335.865724 -86.708488)
		(width 0.508)
		(layer "In4.Cu")
		(net "P3V3")
	)
	(segment
		(start 467.4616 -138.679428)
		(end 467.2584 -138.476228)
		(width 0.4064)
		(layer "In4.Cu")
		(net "P3V3")
	)
	(segment
		(start 467.8934 -148.479256)
		(end 467.8934 -145.104612)
		(width 0.4064)
		(layer "In4.Cu")
		(net "P3V3")
	)
	(segment
		(start 335.865724 -85.291676)
		(end 338.2391 -82.9183)
		(width 0.508)
		(layer "In4.Cu")
		(net "P3V3")
	)
	(segment
		(start 412.4452 -94.007686)
		(end 411.869382 -93.42882)
		(width 0.508)
		(layer "In4.Cu")
		(net "P3V3")
	)
	(segment
		(start 467.4616 -140.1318)
		(end 467.4616 -138.679428)
		(width 0.4064)
		(layer "In4.Cu")
		(net "P3V3")
	)
	(segment
		(start 407.972768 -93.42882)
		(end 406.995122 -92.451174)
		(width 0.508)
		(layer "In4.Cu")
		(net "P3V3")
	)
	(segment
		(start 158.603696 -22.320504)
		(end 156.4132 -24.511)
		(width 0.508)
		(layer "In4.Cu")
		(net "P3V3")
	)
	(segment
		(start 414.02 -96.8756)
		(end 412.4452 -95.3008)
		(width 0.508)
		(layer "In4.Cu")
		(net "P3V3")
	)
	(segment
		(start 374.438418 -42.816018)
		(end 373.0498 -41.4274)
		(width 0.254)
		(layer "In4.Cu")
		(net "P3V3")
	)
	(segment
		(start 365.572294 -46.533054)
		(end 364.064296 -48.041052)
		(width 0.254)
		(layer "In4.Cu")
		(net "P3V3")
	)
	(segment
		(start 167.59936 -8.7884)
		(end 165.447472 -8.7884)
		(width 0.508)
		(layer "In4.Cu")
		(net "P3V3")
	)
	(segment
		(start 335.865724 -86.708488)
		(end 335.865724 -85.291676)
		(width 0.508)
		(layer "In4.Cu")
		(net "P3V3")
	)
	(segment
		(start 467.2584 -138.476228)
		(end 467.2584 -135.0772)
		(width 0.4064)
		(layer "In4.Cu")
		(net "P3V3")
	)
	(segment
		(start 343.807542 -69.1769)
		(end 341.6427 -69.1769)
		(width 0.254)
		(layer "In4.Cu")
		(net "P3V3")
	)
	(segment
		(start 329.302872 -111.125)
		(end 329.302872 -93.27134)
		(width 0.508)
		(layer "In4.Cu")
		(net "P3V3")
	)
	(segment
		(start 380.165102 -44.412662)
		(end 380.12624 -44.3738)
		(width 0.254)
		(layer "In4.Cu")
		(net "P3V3")
	)
	(segment
		(start 357.205026 -68.1736)
		(end 344.810842 -68.1736)
		(width 0.254)
		(layer "In4.Cu")
		(net "P3V3")
	)
	(segment
		(start 367.730024 -41.973246)
		(end 367.730024 -45.484796)
		(width 0.254)
		(layer "In4.Cu")
		(net "P3V3")
	)
	(segment
		(start 466.918294 -144.129506)
		(end 466.918294 -140.675106)
		(width 0.4064)
		(layer "In4.Cu")
		(net "P3V3")
	)
	(segment
		(start 368.780314 -40.922956)
		(end 367.730024 -41.973246)
		(width 0.254)
		(layer "In4.Cu")
		(net "P3V3")
	)
	(segment
		(start 411.869382 -93.42882)
		(end 407.972768 -93.42882)
		(width 0.508)
		(layer "In4.Cu")
		(net "P3V3")
	)
	(segment
		(start 394.638276 -23.28164)
		(end 394.915136 -23.00478)
		(width 0.254)
		(layer "In4.Cu")
		(net "P3V3")
	)
	(segment
		(start 344.810842 -68.1736)
		(end 343.807542 -69.1769)
		(width 0.254)
		(layer "In4.Cu")
		(net "P3V3")
	)
	(segment
		(start 367.730024 -45.484796)
		(end 366.681766 -46.533054)
		(width 0.254)
		(layer "In4.Cu")
		(net "P3V3")
	)
	(segment
		(start 420.9542 -101.45014)
		(end 421.462454 -101.958394)
		(width 0.508)
		(layer "In4.Cu")
		(net "P3V3")
	)
	(segment
		(start 364.65637 -62.6237)
		(end 364.1471 -62.6237)
		(width 0.254)
		(layer "In4.Cu")
		(net "P3V3")
	)
	(segment
		(start 386.780532 -82.96148)
		(end 389.115808 -82.96148)
		(width 0.254)
		(layer "In4.Cu")
		(net "P3V3")
	)
	(segment
		(start 420.9542 -100.461826)
		(end 420.9542 -101.45014)
		(width 0.508)
		(layer "In4.Cu")
		(net "P3V3")
	)
	(segment
		(start 154.346656 -24.511)
		(end 153.203402 -25.654254)
		(width 0.508)
		(layer "In4.Cu")
		(net "P3V3")
	)
	(segment
		(start 406.995122 -92.451174)
		(end 406.96261 -92.451174)
		(width 0.508)
		(layer "In4.Cu")
		(net "P3V3")
	)
	(segment
		(start 366.681766 -46.533054)
		(end 365.572294 -46.533054)
		(width 0.254)
		(layer "In4.Cu")
		(net "P3V3")
	)
	(segment
		(start 389.115808 -82.96148)
		(end 389.439912 -82.637376)
		(width 0.254)
		(layer "In4.Cu")
		(net "P3V3")
	)
	(segment
		(start 377.04141 -43.718988)
		(end 376.497596 -43.718988)
		(width 0.254)
		(layer "In4.Cu")
		(net "P3V3")
	)
	(segment
		(start 376.497596 -43.718988)
		(end 375.594626 -42.816018)
		(width 0.254)
		(layer "In4.Cu")
		(net "P3V3")
	)
	(segment
		(start 364.064296 -48.041052)
		(end 363.915706 -48.041052)
		(width 0.254)
		(layer "In4.Cu")
		(net "P3V3")
	)
	(segment
		(start 380.12624 -44.3738)
		(end 377.696222 -44.3738)
		(width 0.254)
		(layer "In4.Cu")
		(net "P3V3")
	)
	(segment
		(start 373.4054 -60.8076)
		(end 373.9388 -61.341)
		(width 0.508)
		(layer "In6.Cu")
		(net "P3V3")
	)
	(segment
		(start 170.8912 -8.0772)
		(end 169.6466 -8.0772)
		(width 0.508)
		(layer "In6.Cu")
		(net "P3V3")
	)
	(segment
		(start 169.6466 -8.0772)
		(end 169.6212 -8.1026)
		(width 0.508)
		(layer "In6.Cu")
		(net "P3V3")
	)
	(segment
		(start 373.9388 -61.341)
		(end 373.9388 -61.722)
		(width 0.508)
		(layer "In6.Cu")
		(net "P3V3")
	)
	(segment
		(start 364.5916 -60.8076)
		(end 373.4054 -60.8076)
		(width 0.508)
		(layer "In6.Cu")
		(net "P3V3")
	)
	(segment
		(start 440.006486 -135.877808)
		(end 440.006486 -136.188196)
		(width 0.254)
		(layer "In9.Cu")
		(net "P3V3")
	)
	(segment
		(start 440.006486 -136.188196)
		(end 440.006232 -136.18845)
		(width 0.254)
		(layer "In9.Cu")
		(net "P3V3")
	)
	(segment
		(start 440.006232 -137.752074)
		(end 441.506864 -139.252706)
		(width 0.254)
		(layer "In9.Cu")
		(net "P3V3")
	)
	(segment
		(start 424.847004 -130.756406)
		(end 427.759368 -130.756406)
		(width 0.254)
		(layer "In9.Cu")
		(net "P3V3")
	)
	(segment
		(start 419.823138 -124.8283)
		(end 419.823138 -125.73254)
		(width 0.254)
		(layer "In9.Cu")
		(net "P3V3")
	)
	(segment
		(start 437.477662 -133.348984)
		(end 440.006486 -135.877808)
		(width 0.254)
		(layer "In9.Cu")
		(net "P3V3")
	)
	(segment
		(start 419.823138 -125.73254)
		(end 424.847004 -130.756406)
		(width 0.254)
		(layer "In9.Cu")
		(net "P3V3")
	)
	(segment
		(start 430.351946 -133.348984)
		(end 437.477662 -133.348984)
		(width 0.254)
		(layer "In9.Cu")
		(net "P3V3")
	)
	(segment
		(start 469.875108 -147.471892)
		(end 473.354908 -147.471892)
		(width 0.508)
		(layer "In9.Cu")
		(net "P3V3")
	)
	(segment
		(start 473.354908 -147.471892)
		(end 475.0054 -145.8214)
		(width 0.508)
		(layer "In9.Cu")
		(net "P3V3")
	)
	(segment
		(start 427.759368 -130.756406)
		(end 430.351946 -133.348984)
		(width 0.254)
		(layer "In9.Cu")
		(net "P3V3")
	)
	(segment
		(start 475.0054 -145.8214)
		(end 475.0054 -142.5321)
		(width 0.508)
		(layer "In9.Cu")
		(net "P3V3")
	)
	(segment
		(start 419.545516 -124.550678)
		(end 419.823138 -124.8283)
		(width 0.254)
		(layer "In9.Cu")
		(net "P3V3")
	)
	(segment
		(start 419.545516 -123.95835)
		(end 419.545516 -124.550678)
		(width 0.254)
		(layer "In9.Cu")
		(net "P3V3")
	)
	(segment
		(start 440.006232 -136.18845)
		(end 440.006232 -137.752074)
		(width 0.254)
		(layer "In9.Cu")
		(net "P3V3")
	)
	(segment
		(start 468.380572 -148.966428)
		(end 469.875108 -147.471892)
		(width 0.508)
		(layer "In9.Cu")
		(net "P3V3")
	)
	(segment
		(start 462.94294 -131.52374)
		(end 455.87666 -131.52374)
		(width 0.254)
		(layer "In11.Cu")
		(net "P3V3")
	)
	(segment
		(start 449.320158 -137.12063)
		(end 449.320158 -136.73709)
		(width 0.254)
		(layer "In11.Cu")
		(net "P3V3")
	)
	(segment
		(start 463.9056 -132.4864)
		(end 462.94294 -131.52374)
		(width 0.254)
		(layer "In11.Cu")
		(net "P3V3")
	)
	(segment
		(start 185.5978 -78.60792)
		(end 185.5978 -75.7682)
		(width 1.016)
		(layer "In11.Cu")
		(net "P3V3")
	)
	(segment
		(start 198.009764 -50.961036)
		(end 201.4728 -47.498)
		(width 1.016)
		(layer "In11.Cu")
		(net "P3V3")
	)
	(segment
		(start 191.7446 -56.64581)
		(end 191.7446 -54.2544)
		(width 1.016)
		(layer "In11.Cu")
		(net "P3V3")
	)
	(segment
		(start 170.98772 -123.534932)
		(end 170.98772 -123.134628)
		(width 0.254)
		(layer "In11.Cu")
		(net "P3V3")
	)
	(segment
		(start 186.7916 -74.5744)
		(end 186.7916 -67.93738)
		(width 1.016)
		(layer "In11.Cu")
		(net "P3V3")
	)
	(segment
		(start 190.900304 -57.490106)
		(end 191.7446 -56.64581)
		(width 1.016)
		(layer "In11.Cu")
		(net "P3V3")
	)
	(segment
		(start 195.220336 -28.164536)
		(end 194.4116 -27.3558)
		(width 1.016)
		(layer "In11.Cu")
		(net "P3V3")
	)
	(segment
		(start 190.900304 -61.63564)
		(end 190.900304 -57.490106)
		(width 1.016)
		(layer "In11.Cu")
		(net "P3V3")
	)
	(segment
		(start 441.506864 -139.252706)
		(end 442.168534 -139.914376)
		(width 0.254)
		(layer "In11.Cu")
		(net "P3V3")
	)
	(segment
		(start 463.978752 -132.4864)
		(end 463.9056 -132.4864)
		(width 0.254)
		(layer "In11.Cu")
		(net "P3V3")
	)
	(segment
		(start 163.4236 -111.1504)
		(end 162.6362 -111.1504)
		(width 0.254)
		(layer "In11.Cu")
		(net "P3V3")
	)
	(segment
		(start 186.7916 -67.93738)
		(end 188.83884 -65.89014)
		(width 1.016)
		(layer "In11.Cu")
		(net "P3V3")
	)
	(segment
		(start 449.319904 -137.837926)
		(end 449.319904 -137.120884)
		(width 0.254)
		(layer "In11.Cu")
		(net "P3V3")
	)
	(segment
		(start 465.8614 -133.0706)
		(end 464.4898 -133.0706)
		(width 0.254)
		(layer "In11.Cu")
		(net "P3V3")
	)
	(segment
		(start 464.2612 -132.842)
		(end 464.2612 -132.768848)
		(width 0.254)
		(layer "In11.Cu")
		(net "P3V3")
	)
	(segment
		(start 464.4898 -133.0706)
		(end 464.2612 -132.842)
		(width 0.254)
		(layer "In11.Cu")
		(net "P3V3")
	)
	(segment
		(start 452.2978 -136.4488)
		(end 452.4502 -136.6012)
		(width 0.254)
		(layer "In11.Cu")
		(net "P3V3")
	)
	(segment
		(start 171.057824 -123.064524)
		(end 171.057824 -118.784624)
		(width 0.254)
		(layer "In11.Cu")
		(net "P3V3")
	)
	(segment
		(start 188.83884 -63.697104)
		(end 190.900304 -61.63564)
		(width 1.016)
		(layer "In11.Cu")
		(net "P3V3")
	)
	(segment
		(start 442.168534 -139.914376)
		(end 447.243454 -139.914376)
		(width 0.254)
		(layer "In11.Cu")
		(net "P3V3")
	)
	(segment
		(start 449.319904 -137.120884)
		(end 449.320158 -137.12063)
		(width 0.254)
		(layer "In11.Cu")
		(net "P3V3")
	)
	(segment
		(start 171.057824 -118.784624)
		(end 163.4236 -111.1504)
		(width 0.254)
		(layer "In11.Cu")
		(net "P3V3")
	)
	(segment
		(start 195.037964 -50.961036)
		(end 198.009764 -50.961036)
		(width 1.016)
		(layer "In11.Cu")
		(net "P3V3")
	)
	(segment
		(start 185.5978 -75.7682)
		(end 186.7916 -74.5744)
		(width 1.016)
		(layer "In11.Cu")
		(net "P3V3")
	)
	(segment
		(start 455.87666 -131.52374)
		(end 454.7235 -132.6769)
		(width 0.254)
		(layer "In11.Cu")
		(net "P3V3")
	)
	(segment
		(start 182.04434 -82.16138)
		(end 185.5978 -78.60792)
		(width 1.016)
		(layer "In11.Cu")
		(net "P3V3")
	)
	(segment
		(start 191.7446 -54.2544)
		(end 195.037964 -50.961036)
		(width 1.016)
		(layer "In11.Cu")
		(net "P3V3")
	)
	(segment
		(start 449.608448 -136.4488)
		(end 452.2978 -136.4488)
		(width 0.254)
		(layer "In11.Cu")
		(net "P3V3")
	)
	(segment
		(start 449.320158 -136.73709)
		(end 449.608448 -136.4488)
		(width 0.254)
		(layer "In11.Cu")
		(net "P3V3")
	)
	(segment
		(start 195.220336 -39.238936)
		(end 195.220336 -28.164536)
		(width 1.016)
		(layer "In11.Cu")
		(net "P3V3")
	)
	(segment
		(start 201.4728 -45.4914)
		(end 195.220336 -39.238936)
		(width 1.016)
		(layer "In11.Cu")
		(net "P3V3")
	)
	(segment
		(start 447.243454 -139.914376)
		(end 449.319904 -137.837926)
		(width 0.254)
		(layer "In11.Cu")
		(net "P3V3")
	)
	(segment
		(start 201.4728 -47.498)
		(end 201.4728 -45.4914)
		(width 1.016)
		(layer "In11.Cu")
		(net "P3V3")
	)
	(segment
		(start 171.2722 -124.333)
		(end 171.2722 -123.819412)
		(width 0.254)
		(layer "In11.Cu")
		(net "P3V3")
	)
	(segment
		(start 464.2612 -132.768848)
		(end 463.978752 -132.4864)
		(width 0.254)
		(layer "In11.Cu")
		(net "P3V3")
	)
	(segment
		(start 170.98772 -123.134628)
		(end 171.057824 -123.064524)
		(width 0.254)
		(layer "In11.Cu")
		(net "P3V3")
	)
	(segment
		(start 188.83884 -65.89014)
		(end 188.83884 -63.697104)
		(width 1.016)
		(layer "In11.Cu")
		(net "P3V3")
	)
	(segment
		(start 171.2722 -123.819412)
		(end 170.98772 -123.534932)
		(width 0.254)
		(layer "In11.Cu")
		(net "P3V3")
	)
	(segment
		(start 135.771636 -17.2466)
		(end 135.735568 -17.210532)
		(width 0.3556)
		(layer "F.Cu")
		(net "GND")
	)
	(segment
		(start 205.749906 -156.87294)
		(end 205.749906 -155.600146)
		(width 0.4064)
		(layer "F.Cu")
		(net "GND")
	)
	(segment
		(start 45.84954 -152.273)
		(end 45.84954 -152.278842)
		(width 0.4064)
		(layer "F.Cu")
		(net "GND")
	)
	(segment
		(start 286.500316 -142.6718)
		(end 286.499808 -142.677642)
		(width 0.4064)
		(layer "F.Cu")
		(net "GND")
	)
	(segment
		(start 464.600798 -114.189002)
		(end 464.4644 -114.3254)
		(width 0.4064)
		(layer "F.Cu")
		(net "GND")
	)
	(segment
		(start 499.143528 -127.90424)
		(end 498.449854 -127.210566)
		(width 0.508)
		(layer "F.Cu")
		(net "GND")
	)
	(segment
		(start 246.485664 -68.46824)
		(end 245.914164 -68.46824)
		(width 0.254)
		(layer "F.Cu")
		(net "GND")
	)
	(segment
		(start 295.23182 -72.744584)
		(end 295.80332 -72.744584)
		(width 0.254)
		(layer "F.Cu")
		(net "GND")
	)
	(segment
		(start 390.13765 -104.65435)
		(end 390.430512 -104.361488)
		(width 0.12446)
		(layer "F.Cu")
		(net "GND")
	)
	(segment
		(start 401.01901 -28.49499)
		(end 400.812 -28.702)
		(width 0.254)
		(layer "F.Cu")
		(net "GND")
	)
	(segment
		(start 215.949784 -142.677642)
		(end 215.949784 -144.364202)
		(width 0.4064)
		(layer "F.Cu")
		(net "GND")
	)
	(segment
		(start 131.089908 -52.437538)
		(end 131.6609 -52.437538)
		(width 0.254)
		(layer "F.Cu")
		(net "GND")
	)
	(segment
		(start 464.439 -0.85725)
		(end 464.521296 -0.939546)
		(width 0.254)
		(layer "F.Cu")
		(net "GND")
	)
	(segment
		(start 293.51478 -98.500184)
		(end 294.08628 -98.500184)
		(width 0.3048)
		(layer "F.Cu")
		(net "GND")
	)
	(segment
		(start 135.099552 -9.156446)
		(end 135.099552 -10.422382)
		(width 0.4064)
		(layer "F.Cu")
		(net "GND")
	)
	(segment
		(start 231.25049 -3.763518)
		(end 231.249728 -3.762756)
		(width 0.4064)
		(layer "F.Cu")
		(net "GND")
	)
	(segment
		(start 472.6178 -42.0624)
		(end 473.0877 -41.5925)
		(width 0.254)
		(layer "F.Cu")
		(net "GND")
	)
	(segment
		(start 449.520056 -12.954)
		(end 447.831972 -12.954)
		(width 0.254)
		(layer "F.Cu")
		(net "GND")
	)
	(segment
		(start 198.949818 -5.822442)
		(end 198.950326 -5.822442)
		(width 0.3556)
		(layer "F.Cu")
		(net "GND")
	)
	(segment
		(start 107.910376 -94.538038)
		(end 108.481876 -94.538038)
		(width 0.254)
		(layer "F.Cu")
		(net "GND")
	)
	(segment
		(start 84.919312 -55.59044)
		(end 84.347812 -55.59044)
		(width 0.254)
		(layer "F.Cu")
		(net "GND")
	)
	(segment
		(start 244.768624 -70.44944)
		(end 244.197124 -70.44944)
		(width 0.254)
		(layer "F.Cu")
		(net "GND")
	)
	(segment
		(start 301.742602 -11.912092)
		(end 301.800006 -11.854688)
		(width 0.4064)
		(layer "F.Cu")
		(net "GND")
	)
	(segment
		(start 244.3607 -12.954)
		(end 243.63172 -12.954)
		(width 0.4064)
		(layer "F.Cu")
		(net "GND")
	)
	(segment
		(start 71.183246 -54.59984)
		(end 70.611746 -54.59984)
		(width 0.254)
		(layer "F.Cu")
		(net "GND")
	)
	(segment
		(start 227.792534 -146.011646)
		(end 227.792534 -145.998946)
		(width 0.3556)
		(layer "F.Cu")
		(net "GND")
	)
	(segment
		(start 289.22218 -61.352938)
		(end 288.65068 -61.352938)
		(width 0.254)
		(layer "F.Cu")
		(net "GND")
	)
	(segment
		(start 183.541924 -153.021284)
		(end 183.541924 -153.6827)
		(width 0.254)
		(layer "F.Cu")
		(net "GND")
	)
	(segment
		(start 301.812706 -52.437538)
		(end 301.241206 -52.437538)
		(width 0.254)
		(layer "F.Cu")
		(net "GND")
	)
	(segment
		(start 285.649924 -2.314956)
		(end 284.3276 -2.3622)
		(width 0.254)
		(layer "F.Cu")
		(net "GND")
	)
	(segment
		(start 456.198986 -26.589228)
		(end 456.198986 -26.518108)
		(width 0.254)
		(layer "F.Cu")
		(net "GND")
	)
	(segment
		(start 136.240774 -57.390538)
		(end 136.812274 -57.390538)
		(width 0.254)
		(layer "F.Cu")
		(net "GND")
	)
	(segment
		(start 50.099468 -2.314956)
		(end 50.099468 -0.821182)
		(width 0.4064)
		(layer "F.Cu")
		(net "GND")
	)
	(segment
		(start 442.922152 -29.432504)
		(end 442.921898 -29.432504)
		(width 0.3048)
		(layer "F.Cu")
		(net "GND")
	)
	(segment
		(start 196.399912 -18.744946)
		(end 196.399912 -20.023582)
		(width 0.4064)
		(layer "F.Cu")
		(net "GND")
	)
	(segment
		(start 233.113072 -53.60924)
		(end 233.608118 -54.104286)
		(width 0.254)
		(layer "F.Cu")
		(net "GND")
	)
	(segment
		(start 236.183678 -98.18624)
		(end 235.612178 -98.18624)
		(width 0.254)
		(layer "F.Cu")
		(net "GND")
	)
	(segment
		(start 32.094932 -62.320932)
		(end 32.094932 -62.772544)
		(width 0.254)
		(layer "F.Cu")
		(net "GND")
	)
	(segment
		(start 232.950512 3.778758)
		(end 232.950512 1.994916)
		(width 0.4064)
		(layer "F.Cu")
		(net "GND")
	)
	(segment
		(start 124.221748 -86.117938)
		(end 124.793248 -86.117938)
		(width 0.254)
		(layer "F.Cu")
		(net "GND")
	)
	(segment
		(start 400.5961 -126.056136)
		(end 400.487134 -126.165102)
		(width 0.254)
		(layer "F.Cu")
		(net "GND")
	)
	(segment
		(start 300.099984 -11.878056)
		(end 300.099984 -10.422382)
		(width 0.4064)
		(layer "F.Cu")
		(net "GND")
	)
	(segment
		(start 223.599756 -15.423896)
		(end 223.60001 -15.423642)
		(width 0.4064)
		(layer "F.Cu")
		(net "GND")
	)
	(segment
		(start 245.627144 -101.653086)
		(end 246.485664 -102.093014)
		(width 0.254)
		(layer "F.Cu")
		(net "GND")
	)
	(segment
		(start 369.608354 -95.9485)
		(end 369.062 -95.9485)
		(width 0.254)
		(layer "F.Cu")
		(net "GND")
	)
	(segment
		(start 119.331232 -21.5138)
		(end 118.041928 -21.513292)
		(width 0.254)
		(layer "F.Cu")
		(net "GND")
	)
	(segment
		(start 298.399962 -156.87294)
		(end 298.40047 -156.87294)
		(width 0.4064)
		(layer "F.Cu")
		(net "GND")
	)
	(segment
		(start 122.504708 -93.052138)
		(end 123.076208 -93.052138)
		(width 0.254)
		(layer "F.Cu")
		(net "GND")
	)
	(segment
		(start 411.89021 -40.93464)
		(end 411.49016 -41.33469)
		(width 0.254)
		(layer "F.Cu")
		(net "GND")
	)
	(segment
		(start 185.1406 -76.3143)
		(end 185.1406 -76.53274)
		(width 0.508)
		(layer "F.Cu")
		(net "GND")
	)
	(segment
		(start 209.092546 0.406654)
		(end 209.092546 0.457454)
		(width 0.4064)
		(layer "F.Cu")
		(net "GND")
	)
	(segment
		(start 262.3566 -24.638)
		(end 261.747 -24.638)
		(width 0.508)
		(layer "F.Cu")
		(net "GND")
	)
	(segment
		(start 141.10462 -98.500184)
		(end 141.104874 -98.500438)
		(width 0.254)
		(layer "F.Cu")
		(net "GND")
	)
	(segment
		(start 39.049452 -137.67054)
		(end 39.049452 -136.410446)
		(width 0.4064)
		(layer "F.Cu")
		(net "GND")
	)
	(segment
		(start 311.15 -20.023582)
		(end 311.15 -21.455888)
		(width 0.4064)
		(layer "F.Cu")
		(net "GND")
	)
	(segment
		(start 138.816334 -67.791584)
		(end 139.387834 -67.791584)
		(width 0.254)
		(layer "F.Cu")
		(net "GND")
	)
	(segment
		(start 298.40047 -137.67054)
		(end 298.399962 -137.67054)
		(width 0.4064)
		(layer "F.Cu")
		(net "GND")
	)
	(segment
		(start 298.665646 -102.462584)
		(end 299.237146 -102.462584)
		(width 0.3048)
		(layer "F.Cu")
		(net "GND")
	)
	(segment
		(start 171.9326 -124.83338)
		(end 172.3136 -125.21438)
		(width 0.381)
		(layer "F.Cu")
		(net "GND")
	)
	(segment
		(start 151.257 -25.908)
		(end 151.257 -22.972776)
		(width 0.508)
		(layer "F.Cu")
		(net "GND")
	)
	(segment
		(start 66.249296 -133.255766)
		(end 66.249296 -134.861046)
		(width 0.4064)
		(layer "F.Cu")
		(net "GND")
	)
	(segment
		(start 363.885226 -7.789926)
		(end 363.885226 -8.84682)
		(width 0.4064)
		(layer "F.Cu")
		(net "GND")
	)
	(segment
		(start 115.636802 -90.080338)
		(end 116.208302 -90.080338)
		(width 0.254)
		(layer "F.Cu")
		(net "GND")
	)
	(segment
		(start 289.899852 3.778758)
		(end 289.899852 2.092198)
		(width 0.4064)
		(layer "F.Cu")
		(net "GND")
	)
	(segment
		(start 306.050442 -137.67054)
		(end 306.049934 -137.67054)
		(width 0.4064)
		(layer "F.Cu")
		(net "GND")
	)
	(segment
		(start 55.199534 -133.076442)
		(end 55.19928 -133.076696)
		(width 0.4064)
		(layer "F.Cu")
		(net "GND")
	)
	(segment
		(start 289.050476 -20.023582)
		(end 289.049968 -20.023582)
		(width 0.4064)
		(layer "F.Cu")
		(net "GND")
	)
	(segment
		(start 140.199364 -15.423642)
		(end 140.199364 -17.208246)
		(width 0.4064)
		(layer "F.Cu")
		(net "GND")
	)
	(segment
		(start 279.778714 -57.885584)
		(end 279.207214 -57.885584)
		(width 0.254)
		(layer "F.Cu")
		(net "GND")
	)
	(segment
		(start 50.099468 -18.744946)
		(end 50.099468 -20.023582)
		(width 0.4064)
		(layer "F.Cu")
		(net "GND")
	)
	(segment
		(start 282.24988 -153.004774)
		(end 282.0162 -153.238454)
		(width 0.3556)
		(layer "F.Cu")
		(net "GND")
	)
	(segment
		(start 303.529746 -93.052138)
		(end 303.529746 -93.260164)
		(width 0.254)
		(layer "F.Cu")
		(net "GND")
	)
	(segment
		(start 175.27016 -104.65562)
		(end 175.27016 -104.20096)
		(width 0.254)
		(layer "F.Cu")
		(net "GND")
	)
	(segment
		(start 221.899988 -133.076442)
		(end 221.899988 -133.255512)
		(width 0.4064)
		(layer "F.Cu")
		(net "GND")
	)
	(segment
		(start 97.796858 -95.709486)
		(end 97.225358 -95.709486)
		(width 0.254)
		(layer "F.Cu")
		(net "GND")
	)
	(segment
		(start 281.495754 -52.932838)
		(end 281.495754 -51.941984)
		(width 0.2286)
		(layer "F.Cu")
		(net "GND")
	)
	(segment
		(start 278.849836 -137.676382)
		(end 278.849836 -137.67054)
		(width 0.4064)
		(layer "F.Cu")
		(net "GND")
	)
	(segment
		(start 306.049934 -137.67054)
		(end 306.049934 -136.410446)
		(width 0.4064)
		(layer "F.Cu")
		(net "GND")
	)
	(segment
		(start 248.202704 -59.55284)
		(end 247.631204 -59.55284)
		(width 0.254)
		(layer "F.Cu")
		(net "GND")
	)
	(segment
		(start 284.799786 -133.076442)
		(end 284.799786 -133.89102)
		(width 0.3556)
		(layer "F.Cu")
		(net "GND")
	)
	(segment
		(start 233.608118 -89.765886)
		(end 233.036618 -89.765886)
		(width 0.254)
		(layer "F.Cu")
		(net "GND")
	)
	(segment
		(start 205.750414 -147.27174)
		(end 205.749906 -147.27174)
		(width 0.4064)
		(layer "F.Cu")
		(net "GND")
	)
	(segment
		(start 418.5031 -54.573932)
		(end 418.5031 -54.5719)
		(width 0.254)
		(layer "F.Cu")
		(net "GND")
	)
	(segment
		(start 36.499292 -15.423896)
		(end 36.499292 -16.238474)
		(width 0.4064)
		(layer "F.Cu")
		(net "GND")
	)
	(segment
		(start 75.762866 -53.60924)
		(end 76.334366 -53.60924)
		(width 0.254)
		(layer "F.Cu")
		(net "GND")
	)
	(segment
		(start 114.699542 -2.314956)
		(end 114.699542 -0.821182)
		(width 0.4064)
		(layer "F.Cu")
		(net "GND")
	)
	(segment
		(start 132.806694 -64.324738)
		(end 133.378194 -64.324738)
		(width 0.254)
		(layer "F.Cu")
		(net "GND")
	)
	(segment
		(start 240.476278 -81.841086)
		(end 239.904778 -81.841086)
		(width 0.254)
		(layer "F.Cu")
		(net "GND")
	)
	(segment
		(start 61.796168 -153.213054)
		(end 61.796168 -154.0764)
		(width 0.3556)
		(layer "F.Cu")
		(net "GND")
	)
	(segment
		(start 242.300506 3.778758)
		(end 242.300506 1.994916)
		(width 0.4064)
		(layer "F.Cu")
		(net "GND")
	)
	(segment
		(start 299.250354 -15.423642)
		(end 299.249846 -15.423642)
		(width 0.4064)
		(layer "F.Cu")
		(net "GND")
	)
	(segment
		(start 50.099468 -137.67054)
		(end 50.099468 -139.170156)
		(width 0.4064)
		(layer "F.Cu")
		(net "GND")
	)
	(segment
		(start 296.69994 -137.67054)
		(end 296.69994 -136.410446)
		(width 0.4064)
		(layer "F.Cu")
		(net "GND")
	)
	(segment
		(start 376.854466 -92.837)
		(end 376.809 -92.837)
		(width 0.254)
		(layer "F.Cu")
		(net "GND")
	)
	(segment
		(start 399.126964 -101.893116)
		(end 399.634964 -102.855014)
		(width 0.254)
		(layer "F.Cu")
		(net "GND")
	)
	(segment
		(start 308.59984 -144.364202)
		(end 308.501796 -144.462246)
		(width 0.4064)
		(layer "F.Cu")
		(net "GND")
	)
	(segment
		(start 124.89942 3.778758)
		(end 124.89942 2.092198)
		(width 0.4064)
		(layer "F.Cu")
		(net "GND")
	)
	(segment
		(start 223.599756 -5.822696)
		(end 223.599756 -7.607046)
		(width 0.4064)
		(layer "F.Cu")
		(net "GND")
	)
	(segment
		(start 50.949352 3.778758)
		(end 50.949352 2.092198)
		(width 0.4064)
		(layer "F.Cu")
		(net "GND")
	)
	(segment
		(start 143.507968 -3.737356)
		(end 143.599408 -3.828796)
		(width 0.4064)
		(layer "F.Cu")
		(net "GND")
	)
	(segment
		(start 74.617326 -89.27084)
		(end 74.045826 -89.27084)
		(width 0.254)
		(layer "F.Cu")
		(net "GND")
	)
	(segment
		(start 130.231388 -102.462584)
		(end 130.802888 -102.462584)
		(width 0.254)
		(layer "F.Cu")
		(net "GND")
	)
	(segment
		(start 198.949818 3.778758)
		(end 198.949818 3.065018)
		(width 0.3556)
		(layer "F.Cu")
		(net "GND")
	)
	(segment
		(start 80.626712 -79.859886)
		(end 80.055212 -79.859886)
		(width 0.254)
		(layer "F.Cu")
		(net "GND")
	)
	(segment
		(start 46.699424 -146.011646)
		(end 46.699424 -147.27174)
		(width 0.4064)
		(layer "F.Cu")
		(net "GND")
	)
	(segment
		(start 117.353842 -59.371484)
		(end 116.782342 -59.371484)
		(width 0.254)
		(layer "F.Cu")
		(net "GND")
	)
	(segment
		(start 36.499292 -153.093674)
		(end 36.040822 -153.552144)
		(width 0.4064)
		(layer "F.Cu")
		(net "GND")
	)
	(segment
		(start 81.485232 -68.46824)
		(end 80.913732 -68.46824)
		(width 0.254)
		(layer "F.Cu")
		(net "GND")
	)
	(segment
		(start 7.7724 3.048)
		(end 8.001 3.2766)
		(width 0.2032)
		(layer "F.Cu")
		(net "GND")
	)
	(segment
		(start 193.200274 -59.817)
		(end 193.117216 -59.900058)
		(width 0.254)
		(layer "F.Cu")
		(net "GND")
	)
	(segment
		(start 232.950004 -133.076442)
		(end 232.94975 -133.076696)
		(width 0.4064)
		(layer "F.Cu")
		(net "GND")
	)
	(segment
		(start 197.249796 -7.509002)
		(end 197.151752 -7.607046)
		(width 0.4064)
		(layer "F.Cu")
		(net "GND")
	)
	(segment
		(start 116.399564 -10.422382)
		(end 116.399564 -9.156446)
		(width 0.4064)
		(layer "F.Cu")
		(net "GND")
	)
	(segment
		(start 61.149484 -11.878056)
		(end 61.149484 -10.422382)
		(width 0.4064)
		(layer "F.Cu")
		(net "GND")
	)
	(segment
		(start 147.849336 -152.273)
		(end 147.849336 -153.093674)
		(width 0.4064)
		(layer "F.Cu")
		(net "GND")
	)
	(segment
		(start 110.485682 -55.409338)
		(end 109.914182 -55.409338)
		(width 0.254)
		(layer "F.Cu")
		(net "GND")
	)
	(segment
		(start 237.900718 -62.52464)
		(end 237.329218 -62.52464)
		(width 0.254)
		(layer "F.Cu")
		(net "GND")
	)
	(segment
		(start 49.249584 -133.0706)
		(end 49.249584 -133.076442)
		(width 0.4064)
		(layer "F.Cu")
		(net "GND")
	)
	(segment
		(start 301.742602 -18.757646)
		(end 301.800006 -18.81505)
		(width 0.3556)
		(layer "F.Cu")
		(net "GND")
	)
	(segment
		(start 466.09 -146.2405)
		(end 465.5185 -146.2405)
		(width 0.4064)
		(layer "F.Cu")
		(net "GND")
	)
	(segment
		(start 291.79774 -53.923184)
		(end 292.36924 -53.923184)
		(width 0.254)
		(layer "F.Cu")
		(net "GND")
	)
	(segment
		(start 174.631858 -103.562658)
		(end 174.631858 -102.279704)
		(width 0.254)
		(layer "F.Cu")
		(net "GND")
	)
	(segment
		(start 376.7328 -114.41557)
		(end 376.335036 -113.854992)
		(width 0.254)
		(layer "F.Cu")
		(net "GND")
	)
	(segment
		(start 382.64084 -105.15092)
		(end 382.64084 -105.15854)
		(width 0.12446)
		(layer "F.Cu")
		(net "GND")
	)
	(segment
		(start 418.973 -82.281014)
		(end 419.859714 -82.281014)
		(width 0.254)
		(layer "F.Cu")
		(net "GND")
	)
	(segment
		(start 309.450486 -20.023582)
		(end 309.449978 -20.023582)
		(width 0.4064)
		(layer "F.Cu")
		(net "GND")
	)
	(segment
		(start 88.353392 -85.30844)
		(end 87.781892 -85.30844)
		(width 0.254)
		(layer "F.Cu")
		(net "GND")
	)
	(segment
		(start 415.890202 -28.916376)
		(end 416.281108 -28.52547)
		(width 0.254)
		(layer "F.Cu")
		(net "GND")
	)
	(segment
		(start 408.690064 -30.53461)
		(end 408.290014 -30.13456)
		(width 0.254)
		(layer "F.Cu")
		(net "GND")
	)
	(segment
		(start 298.665646 -62.838584)
		(end 299.237146 -62.838584)
		(width 0.254)
		(layer "F.Cu")
		(net "GND")
	)
	(segment
		(start 233.682032 -53.977032)
		(end 233.608118 -54.104286)
		(width 0.254)
		(layer "F.Cu")
		(net "GND")
	)
	(segment
		(start 84.919312 -84.31784)
		(end 84.347812 -84.31784)
		(width 0.254)
		(layer "F.Cu")
		(net "GND")
	)
	(segment
		(start 388.9375 -112.2553)
		(end 389.33755 -111.85525)
		(width 0.1143)
		(layer "F.Cu")
		(net "GND")
	)
	(segment
		(start 248.202704 -96.20504)
		(end 247.631204 -96.20504)
		(width 0.254)
		(layer "F.Cu")
		(net "GND")
	)
	(segment
		(start 158.85922 -124.4854)
		(end 158.83636 -124.46254)
		(width 0.4572)
		(layer "F.Cu")
		(net "GND")
	)
	(segment
		(start 80.626712 -95.709486)
		(end 80.055212 -95.709486)
		(width 0.254)
		(layer "F.Cu")
		(net "GND")
	)
	(segment
		(start 69.64934 -153.965402)
		(end 69.551296 -154.063446)
		(width 0.4064)
		(layer "F.Cu")
		(net "GND")
	)
	(segment
		(start 290.0807 -62.838584)
		(end 290.6522 -62.838584)
		(width 0.254)
		(layer "F.Cu")
		(net "GND")
	)
	(segment
		(start 211.699856 -156.87294)
		(end 211.699856 -155.612846)
		(width 0.4064)
		(layer "F.Cu")
		(net "GND")
	)
	(segment
		(start 378.32665 -96.11868)
		(end 378.82195 -95.888556)
		(width 0.254)
		(layer "F.Cu")
		(net "GND")
	)
	(segment
		(start 113.062512 -52.932584)
		(end 113.061242 -52.932838)
		(width 0.254)
		(layer "F.Cu")
		(net "GND")
	)
	(segment
		(start 476.496634 -134.74573)
		(end 478.004378 -134.74573)
		(width 0.381)
		(layer "F.Cu")
		(net "GND")
	)
	(segment
		(start 274.627594 -52.932838)
		(end 274.070064 -53.8988)
		(width 0.254)
		(layer "F.Cu")
		(net "GND")
	)
	(segment
		(start 70.324726 -63.019686)
		(end 69.753226 -63.019686)
		(width 0.254)
		(layer "F.Cu")
		(net "GND")
	)
	(segment
		(start 225.299778 -142.677642)
		(end 225.299778 -144.364202)
		(width 0.4064)
		(layer "F.Cu")
		(net "GND")
	)
	(segment
		(start 45.84954 -14.410182)
		(end 45.84954 -15.423642)
		(width 0.4064)
		(layer "F.Cu")
		(net "GND")
	)
	(segment
		(start 455.000868 -113.892584)
		(end 454.999852 -113.8936)
		(width 0.4064)
		(layer "F.Cu")
		(net "GND")
	)
	(segment
		(start 451.866 -152.1206)
		(end 451.7136 -152.1206)
		(width 0.254)
		(layer "F.Cu")
		(net "GND")
	)
	(segment
		(start 38.199568 -6.001512)
		(end 38.199568 -5.822442)
		(width 0.4064)
		(layer "F.Cu")
		(net "GND")
	)
	(segment
		(start 390.21385 -120.15724)
		(end 390.70915 -120.387364)
		(width 0.254)
		(layer "F.Cu")
		(net "GND")
	)
	(segment
		(start 239.617758 -55.59044)
		(end 239.046258 -55.59044)
		(width 0.254)
		(layer "F.Cu")
		(net "GND")
	)
	(segment
		(start 235.500418 -147.27174)
		(end 235.49991 -147.27174)
		(width 0.4064)
		(layer "F.Cu")
		(net "GND")
	)
	(segment
		(start 53.499512 -147.27174)
		(end 53.499512 -146.06905)
		(width 0.3556)
		(layer "F.Cu")
		(net "GND")
	)
	(segment
		(start 149.549358 -133.0706)
		(end 149.549358 -134.861046)
		(width 0.4064)
		(layer "F.Cu")
		(net "GND")
	)
	(segment
		(start 60.299346 -5.822442)
		(end 60.299346 -7.509002)
		(width 0.4064)
		(layer "F.Cu")
		(net "GND")
	)
	(segment
		(start 288.36366 -71.753984)
		(end 288.93516 -71.753984)
		(width 0.254)
		(layer "F.Cu")
		(net "GND")
	)
	(segment
		(start 197.250304 -152.273)
		(end 197.249796 -152.278842)
		(width 0.4064)
		(layer "F.Cu")
		(net "GND")
	)
	(segment
		(start 481.151946 -142.620746)
		(end 480.897692 -142.875)
		(width 0.254)
		(layer "F.Cu")
		(net "GND")
	)
	(segment
		(start 201.499724 -16.238474)
		(end 201.499724 -15.423896)
		(width 0.4064)
		(layer "F.Cu")
		(net "GND")
	)
	(segment
		(start 339.852 -11.684)
		(end 340.614 -11.684)
		(width 0.254)
		(layer "F.Cu")
		(net "GND")
	)
	(segment
		(start 77.192886 -90.756486)
		(end 76.621386 -90.756486)
		(width 0.254)
		(layer "F.Cu")
		(net "GND")
	)
	(segment
		(start 301.800006 -20.023582)
		(end 301.800006 -21.455888)
		(width 0.4064)
		(layer "F.Cu")
		(net "GND")
	)
	(segment
		(start 227.850446 -20.023582)
		(end 227.849938 -20.023582)
		(width 0.3556)
		(layer "F.Cu")
		(net "GND")
	)
	(segment
		(start 64.549274 -133.076696)
		(end 64.549274 -133.891274)
		(width 0.4064)
		(layer "F.Cu")
		(net "GND")
	)
	(segment
		(start 38.199568 -133.0706)
		(end 38.199568 -133.255512)
		(width 0.4064)
		(layer "F.Cu")
		(net "GND")
	)
	(segment
		(start 449.33235 -50.515774)
		(end 449.330064 -50.513488)
		(width 0.508)
		(layer "F.Cu")
		(net "GND")
	)
	(segment
		(start 310.299862 -152.996138)
		(end 310.0832 -153.2128)
		(width 0.3556)
		(layer "F.Cu")
		(net "GND")
	)
	(segment
		(start 464.185 -22.225)
		(end 464.693 -22.225)
		(width 0.254)
		(layer "F.Cu")
		(net "GND")
	)
	(segment
		(start 116.361464 -2.314956)
		(end 116.399564 -2.276856)
		(width 0.4064)
		(layer "F.Cu")
		(net "GND")
	)
	(segment
		(start 380.418594 -8.744458)
		(end 380.68504 -8.478012)
		(width 0.4064)
		(layer "F.Cu")
		(net "GND")
	)
	(segment
		(start 472.228418 -141.95044)
		(end 472.228418 -142.0749)
		(width 0.254)
		(layer "F.Cu")
		(net "GND")
	)
	(segment
		(start 243.15039 -0.821182)
		(end 243.149882 -0.821182)
		(width 0.4064)
		(layer "F.Cu")
		(net "GND")
	)
	(segment
		(start 120.787668 -80.174338)
		(end 121.359168 -80.174338)
		(width 0.254)
		(layer "F.Cu")
		(net "GND")
	)
	(segment
		(start 124.221748 -98.005138)
		(end 124.793248 -98.005138)
		(width 0.254)
		(layer "F.Cu")
		(net "GND")
	)
	(segment
		(start 170.307 -73.66)
		(end 169.9768 -73.66)
		(width 0.254)
		(layer "F.Cu")
		(net "GND")
	)
	(segment
		(start 284.799532 -153.093674)
		(end 284.341062 -153.552144)
		(width 0.4064)
		(layer "F.Cu")
		(net "GND")
	)
	(segment
		(start 43.29938 -153.014934)
		(end 43.076368 -153.237946)
		(width 0.3556)
		(layer "F.Cu")
		(net "GND")
	)
	(segment
		(start 236.349794 -5.822442)
		(end 236.349794 -6.550406)
		(width 0.3556)
		(layer "F.Cu")
		(net "GND")
	)
	(segment
		(start 88.353392 -91.25204)
		(end 87.781892 -91.25204)
		(width 0.254)
		(layer "F.Cu")
		(net "GND")
	)
	(segment
		(start 472.940888 -43.7134)
		(end 472.6178 -43.390312)
		(width 0.254)
		(layer "F.Cu")
		(net "GND")
	)
	(segment
		(start 41.501314 -17.208246)
		(end 41.599358 -17.110202)
		(width 0.4064)
		(layer "F.Cu")
		(net "GND")
	)
	(segment
		(start 439.74004 -51.875944)
		(end 439.741056 -51.875944)
		(width 0.4064)
		(layer "F.Cu")
		(net "GND")
	)
	(segment
		(start 253.353824 -68.46824)
		(end 252.782324 -68.46824)
		(width 0.254)
		(layer "F.Cu")
		(net "GND")
	)
	(segment
		(start 123.363228 -94.538038)
		(end 123.934728 -94.538038)
		(width 0.3048)
		(layer "F.Cu")
		(net "GND")
	)
	(segment
		(start 441.801758 -45.560996)
		(end 441.341002 -46.021752)
		(width 0.4064)
		(layer "F.Cu")
		(net "GND")
	)
	(segment
		(start 237.042198 -65.991486)
		(end 236.470698 -65.991486)
		(width 0.254)
		(layer "F.Cu")
		(net "GND")
	)
	(segment
		(start 72.900286 -64.50584)
		(end 72.328786 -64.50584)
		(width 0.254)
		(layer "F.Cu")
		(net "GND")
	)
	(segment
		(start 43.076368 -134.035546)
		(end 43.076368 -134.854188)
		(width 0.3556)
		(layer "F.Cu")
		(net "GND")
	)
	(segment
		(start 61.999368 3.778758)
		(end 61.999368 3.047746)
		(width 0.3556)
		(layer "F.Cu")
		(net "GND")
	)
	(segment
		(start 240.476278 -57.076086)
		(end 239.904778 -57.076086)
		(width 0.254)
		(layer "F.Cu")
		(net "GND")
	)
	(segment
		(start 238.44123 -16.696944)
		(end 238.8997 -16.238474)
		(width 0.4064)
		(layer "F.Cu")
		(net "GND")
	)
	(segment
		(start 209.14995 -136.50595)
		(end 209.092546 -136.448546)
		(width 0.4064)
		(layer "F.Cu")
		(net "GND")
	)
	(segment
		(start 240.599976 3.778758)
		(end 240.599976 3.599688)
		(width 0.4064)
		(layer "F.Cu")
		(net "GND")
	)
	(segment
		(start 96.086168 -2.51968)
		(end 95.451168 -1.88468)
		(width 0.4064)
		(layer "F.Cu")
		(net "GND")
	)
	(segment
		(start 393.289282 -124.206)
		(end 393.68095 -123.821444)
		(width 0.254)
		(layer "F.Cu")
		(net "GND")
	)
	(segment
		(start 43.076368 -16.382746)
		(end 43.29938 -16.159734)
		(width 0.3556)
		(layer "F.Cu")
		(net "GND")
	)
	(segment
		(start 226.7966 -134.010654)
		(end 226.7966 -134.874)
		(width 0.3556)
		(layer "F.Cu")
		(net "GND")
	)
	(segment
		(start 276.344634 -96.518984)
		(end 276.916134 -96.518984)
		(width 0.254)
		(layer "F.Cu")
		(net "GND")
	)
	(segment
		(start 68.607686 -57.076086)
		(end 69.753226 -57.076086)
		(width 0.254)
		(layer "F.Cu")
		(net "GND")
	)
	(segment
		(start 127.392176 -146.011646)
		(end 127.392176 -145.998946)
		(width 0.3556)
		(layer "F.Cu")
		(net "GND")
	)
	(segment
		(start 201.499978 -15.423642)
		(end 201.499978 -14.410182)
		(width 0.4064)
		(layer "F.Cu")
		(net "GND")
	)
	(segment
		(start 307.750464 -0.821182)
		(end 307.749956 -0.821182)
		(width 0.4064)
		(layer "F.Cu")
		(net "GND")
	)
	(segment
		(start 68.799456 -9.143746)
		(end 68.799456 -10.422382)
		(width 0.4064)
		(layer "F.Cu")
		(net "GND")
	)
	(segment
		(start 300.100492 -0.821182)
		(end 300.099984 -0.821182)
		(width 0.4064)
		(layer "F.Cu")
		(net "GND")
	)
	(segment
		(start 4.818888 -6.335776)
		(end 4.482846 -6.671818)
		(width 0.254)
		(layer "F.Cu")
		(net "GND")
	)
	(segment
		(start 129.372868 -55.409338)
		(end 129.944368 -55.409338)
		(width 0.254)
		(layer "F.Cu")
		(net "GND")
	)
	(segment
		(start 94.8436 -150.8252)
		(end 94.8817 -150.7871)
		(width 0.4572)
		(layer "F.Cu")
		(net "GND")
	)
	(segment
		(start 316.249812 -142.677642)
		(end 316.249812 -144.462246)
		(width 0.4064)
		(layer "F.Cu")
		(net "GND")
	)
	(segment
		(start 140.246354 -59.371484)
		(end 141.391894 -59.371484)
		(width 0.254)
		(layer "F.Cu")
		(net "GND")
	)
	(segment
		(start 301.241206 -99.986338)
		(end 301.812706 -99.986338)
		(width 0.254)
		(layer "F.Cu")
		(net "GND")
	)
	(segment
		(start 312.850276 -152.273)
		(end 312.849768 -152.278842)
		(width 0.4064)
		(layer "F.Cu")
		(net "GND")
	)
	(segment
		(start 306.900326 -15.423642)
		(end 306.899818 -15.423642)
		(width 0.4064)
		(layer "F.Cu")
		(net "GND")
	)
	(segment
		(start 197.249796 -3.826256)
		(end 197.249796 -5.822442)
		(width 0.4064)
		(layer "F.Cu")
		(net "GND")
	)
	(segment
		(start 500.09298 -122.35434)
		(end 499.143528 -121.404888)
		(width 0.508)
		(layer "F.Cu")
		(net "GND")
	)
	(segment
		(start 220.200474 -15.423642)
		(end 220.199966 -15.423642)
		(width 0.4064)
		(layer "F.Cu")
		(net "GND")
	)
	(segment
		(start 282.250388 -152.273)
		(end 282.24988 -152.278842)
		(width 0.3556)
		(layer "F.Cu")
		(net "GND")
	)
	(segment
		(start 280.550366 -15.423642)
		(end 280.549858 -15.423642)
		(width 0.4064)
		(layer "F.Cu")
		(net "GND")
	)
	(segment
		(start 278.3332 -140.4874)
		(end 278.0538 -140.208)
		(width 0.4572)
		(layer "F.Cu")
		(net "GND")
	)
	(segment
		(start 208.0768 -134.035546)
		(end 208.0768 -134.854188)
		(width 0.3556)
		(layer "F.Cu")
		(net "GND")
	)
	(segment
		(start 174.8155 -67.056)
		(end 175.42764 -67.056)
		(width 0.4064)
		(layer "F.Cu")
		(net "GND")
	)
	(segment
		(start 392.303 -72.705468)
		(end 392.121644 -72.886824)
		(width 0.508)
		(layer "F.Cu")
		(net "GND")
	)
	(segment
		(start 242.193318 -65.991486)
		(end 241.621818 -65.991486)
		(width 0.254)
		(layer "F.Cu")
		(net "GND")
	)
	(segment
		(start 98.655378 -60.54344)
		(end 98.083878 -60.54344)
		(width 0.254)
		(layer "F.Cu")
		(net "GND")
	)
	(segment
		(start 455.742548 -52.2478)
		(end 455.740008 -51.875944)
		(width 0.4064)
		(layer "F.Cu")
		(net "GND")
	)
	(segment
		(start 293.51478 -91.565984)
		(end 294.08628 -91.565984)
		(width 0.3048)
		(layer "F.Cu")
		(net "GND")
	)
	(segment
		(start 131.948174 -55.904384)
		(end 132.519674 -55.904384)
		(width 0.254)
		(layer "F.Cu")
		(net "GND")
	)
	(segment
		(start 445.00165 -45.560996)
		(end 444.540894 -46.021752)
		(width 0.4064)
		(layer "F.Cu")
		(net "GND")
	)
	(segment
		(start 221.899988 -152.457912)
		(end 221.899734 -152.458166)
		(width 0.4064)
		(layer "F.Cu")
		(net "GND")
	)
	(segment
		(start 34.799524 -155.883102)
		(end 34.74212 -155.825698)
		(width 0.4064)
		(layer "F.Cu")
		(net "GND")
	)
	(segment
		(start 281.495754 -96.518984)
		(end 282.067254 -96.518984)
		(width 0.254)
		(layer "F.Cu")
		(net "GND")
	)
	(segment
		(start 136.799574 -137.67054)
		(end 136.799574 -136.46785)
		(width 0.3556)
		(layer "F.Cu")
		(net "GND")
	)
	(segment
		(start 300.099984 -18.757646)
		(end 300.099984 -20.023582)
		(width 0.4064)
		(layer "F.Cu")
		(net "GND")
	)
	(segment
		(start 124.049536 -10.422382)
		(end 124.049536 -11.916156)
		(width 0.4064)
		(layer "F.Cu")
		(net "GND")
	)
	(segment
		(start 400.465036 -99.85502)
		(end 399.634964 -99.85502)
		(width 0.254)
		(layer "F.Cu")
		(net "GND")
	)
	(segment
		(start 280.637234 -62.343538)
		(end 280.065734 -62.343538)
		(width 0.254)
		(layer "F.Cu")
		(net "GND")
	)
	(segment
		(start 208.299812 -143.413734)
		(end 208.0768 -143.636746)
		(width 0.3556)
		(layer "F.Cu")
		(net "GND")
	)
	(segment
		(start 196.399912 -21.517356)
		(end 196.469 -21.586444)
		(width 0.381)
		(layer "F.Cu")
		(net "GND")
	)
	(segment
		(start 298.399962 -2.314956)
		(end 298.399962 -0.821182)
		(width 0.4064)
		(layer "F.Cu")
		(net "GND")
	)
	(segment
		(start 91.787218 -91.25204)
		(end 91.215718 -91.25204)
		(width 0.254)
		(layer "F.Cu")
		(net "GND")
	)
	(segment
		(start 136.799574 -155.67025)
		(end 136.74217 -155.612846)
		(width 0.3556)
		(layer "F.Cu")
		(net "GND")
	)
	(segment
		(start 311.09285 -32.492696)
		(end 312.102754 -32.492696)
		(width 0.4064)
		(layer "F.Cu")
		(net "GND")
	)
	(segment
		(start 79.768192 -54.59984)
		(end 79.196692 -54.59984)
		(width 0.254)
		(layer "F.Cu")
		(net "GND")
	)
	(segment
		(start 383.878582 -125.441456)
		(end 383.985008 -125.33503)
		(width 0.254)
		(layer "F.Cu")
		(net "GND")
	)
	(segment
		(start 401.576032 -126.165102)
		(end 400.487134 -126.165102)
		(width 0.254)
		(layer "F.Cu")
		(net "GND")
	)
	(segment
		(start 457.551536 -63.371476)
		(end 457.551536 -63.626492)
		(width 0.381)
		(layer "F.Cu")
		(net "GND")
	)
	(segment
		(start 226.149916 -10.422382)
		(end 226.149916 -9.156446)
		(width 0.4064)
		(layer "F.Cu")
		(net "GND")
	)
	(segment
		(start 56.049418 -18.757646)
		(end 56.049418 -20.023582)
		(width 0.4064)
		(layer "F.Cu")
		(net "GND")
	)
	(segment
		(start 101.230684 -56.085486)
		(end 100.659184 -56.085486)
		(width 0.254)
		(layer "F.Cu")
		(net "GND")
	)
	(segment
		(start 31.527496 -69.223382)
		(end 31.527496 -69.564504)
		(width 0.381)
		(layer "F.Cu")
		(net "GND")
	)
	(segment
		(start 206.600298 -152.273)
		(end 206.59979 -152.278842)
		(width 0.4064)
		(layer "F.Cu")
		(net "GND")
	)
	(segment
		(start 251.923804 -98.681286)
		(end 251.636784 -98.18624)
		(width 0.254)
		(layer "F.Cu")
		(net "GND")
	)
	(segment
		(start 116.399564 -21.479256)
		(end 116.361464 -21.517356)
		(width 0.4064)
		(layer "F.Cu")
		(net "GND")
	)
	(segment
		(start 387.24205 -96.11868)
		(end 387.73735 -95.888556)
		(width 0.254)
		(layer "F.Cu")
		(net "GND")
	)
	(segment
		(start 135.099552 -2.276856)
		(end 135.061452 -2.314956)
		(width 0.4064)
		(layer "F.Cu")
		(net "GND")
	)
	(segment
		(start 226.7966 -7.62)
		(end 226.822 -7.6454)
		(width 0.3556)
		(layer "F.Cu")
		(net "GND")
	)
	(segment
		(start 67.099434 -0.821182)
		(end 67.099434 -2.314956)
		(width 0.4064)
		(layer "F.Cu")
		(net "GND")
	)
	(segment
		(start 380.151386 -108.839)
		(end 380.30785 -108.766356)
		(width 0.254)
		(layer "F.Cu")
		(net "GND")
	)
	(segment
		(start 437.721756 -28.2321)
		(end 437.322214 -27.832558)
		(width 0.3048)
		(layer "F.Cu")
		(net "GND")
	)
	(segment
		(start 480.91598 -34.86658)
		(end 480.34702 -34.86658)
		(width 0.254)
		(layer "F.Cu")
		(net "GND")
	)
	(segment
		(start 368.967004 -26.362152)
		(end 368.967004 -26.20137)
		(width 0.254)
		(layer "F.Cu")
		(net "GND")
	)
	(segment
		(start 101.230684 -89.765886)
		(end 100.659184 -89.765886)
		(width 0.254)
		(layer "F.Cu")
		(net "GND")
	)
	(segment
		(start 299.237146 -102.462584)
		(end 299.524166 -102.175564)
		(width 0.254)
		(layer "F.Cu")
		(net "GND")
	)
	(segment
		(start 389.86841 -124.206)
		(end 389.984996 -124.504958)
		(width 0.254)
		(layer "F.Cu")
		(net "GND")
	)
	(segment
		(start 196.273928 -53.564282)
		(end 196.273928 -53.221382)
		(width 0.4064)
		(layer "F.Cu")
		(net "GND")
	)
	(segment
		(start 72.900286 -50.63744)
		(end 72.328786 -50.63744)
		(width 0.254)
		(layer "F.Cu")
		(net "GND")
	)
	(segment
		(start 458.9018 -29.7942)
		(end 459.3336 -29.7942)
		(width 0.381)
		(layer "F.Cu")
		(net "GND")
	)
	(segment
		(start 99.513898 -56.085486)
		(end 98.942398 -56.085486)
		(width 0.254)
		(layer "F.Cu")
		(net "GND")
	)
	(segment
		(start 227.792534 -2.310892)
		(end 227.849938 -2.253488)
		(width 0.4064)
		(layer "F.Cu")
		(net "GND")
	)
	(segment
		(start 311.092596 0.444754)
		(end 311.15 0.38735)
		(width 0.3556)
		(layer "F.Cu")
		(net "GND")
	)
	(segment
		(start 379.81255 -96.9772)
		(end 380.30785 -96.747076)
		(width 0.254)
		(layer "F.Cu")
		(net "GND")
	)
	(segment
		(start 123.199398 -17.208246)
		(end 123.199398 -15.423642)
		(width 0.4064)
		(layer "F.Cu")
		(net "GND")
	)
	(segment
		(start 224.449894 -137.67054)
		(end 224.449894 -136.397746)
		(width 0.4064)
		(layer "F.Cu")
		(net "GND")
	)
	(segment
		(start 68.607686 -93.72854)
		(end 67.959986 -93.72854)
		(width 0.254)
		(layer "F.Cu")
		(net "GND")
	)
	(segment
		(start 136.74217 -18.744946)
		(end 136.74217 -18.757646)
		(width 0.3556)
		(layer "F.Cu")
		(net "GND")
	)
	(segment
		(start 384.1369 -114.6556)
		(end 384.53695 -114.25555)
		(width 0.12446)
		(layer "F.Cu")
		(net "GND")
	)
	(segment
		(start 451.677278 -5.770372)
		(end 451.677278 -4.386072)
		(width 0.254)
		(layer "F.Cu")
		(net "GND")
	)
	(segment
		(start 283.099764 -21.455888)
		(end 283.04236 -21.513292)
		(width 0.4064)
		(layer "F.Cu")
		(net "GND")
	)
	(segment
		(start 217.4494 -153.3906)
		(end 217.4494 -154.079194)
		(width 0.3556)
		(layer "F.Cu")
		(net "GND")
	)
	(segment
		(start 126.797308 -92.556584)
		(end 127.368808 -92.556584)
		(width 0.254)
		(layer "F.Cu")
		(net "GND")
	)
	(segment
		(start 388.209536 -7.12216)
		(end 388.594346 -7.50697)
		(width 0.254)
		(layer "F.Cu")
		(net "GND")
	)
	(segment
		(start 240.599976 -133.076442)
		(end 240.600484 -133.0706)
		(width 0.4064)
		(layer "F.Cu")
		(net "GND")
	)
	(segment
		(start 235.325158 -57.076086)
		(end 234.753658 -57.076086)
		(width 0.3048)
		(layer "F.Cu")
		(net "GND")
	)
	(segment
		(start 415.0868 -2.4638)
		(end 415.673286 -3.050286)
		(width 0.254)
		(layer "F.Cu")
		(net "GND")
	)
	(segment
		(start 428.474886 -7.789672)
		(end 428.474886 -9.247886)
		(width 0.254)
		(layer "F.Cu")
		(net "GND")
	)
	(segment
		(start 44.092114 -18.795746)
		(end 44.149518 -18.85315)
		(width 0.4064)
		(layer "F.Cu")
		(net "GND")
	)
	(segment
		(start 147.849336 -153.093674)
		(end 147.390866 -153.552144)
		(width 0.4064)
		(layer "F.Cu")
		(net "GND")
	)
	(segment
		(start 307.250846 -84.631784)
		(end 306.88788 -84.631784)
		(width 0.254)
		(layer "F.Cu")
		(net "GND")
	)
	(segment
		(start 391.178034 -6.874256)
		(end 392.216386 -6.874256)
		(width 0.254)
		(layer "F.Cu")
		(net "GND")
	)
	(segment
		(start 306.049934 -18.757646)
		(end 306.049934 -20.023582)
		(width 0.4064)
		(layer "F.Cu")
		(net "GND")
	)
	(segment
		(start 303.499774 -5.822442)
		(end 303.499774 -6.637274)
		(width 0.4064)
		(layer "F.Cu")
		(net "GND")
	)
	(segment
		(start 386.93725 -111.854488)
		(end 386.93725 -111.85525)
		(width 0.1143)
		(layer "F.Cu")
		(net "GND")
	)
	(segment
		(start 69.64934 -142.6718)
		(end 69.64934 -144.364202)
		(width 0.4064)
		(layer "F.Cu")
		(net "GND")
	)
	(segment
		(start 56.899302 3.599434)
		(end 56.899302 1.994154)
		(width 0.4064)
		(layer "F.Cu")
		(net "GND")
	)
	(segment
		(start 272.052288 -60.362338)
		(end 271.480788 -60.362338)
		(width 0.254)
		(layer "F.Cu")
		(net "GND")
	)
	(segment
		(start 284.800294 2.964688)
		(end 284.341062 2.505456)
		(width 0.4064)
		(layer "F.Cu")
		(net "GND")
	)
	(segment
		(start 310.30037 3.778758)
		(end 310.299862 3.778758)
		(width 0.3556)
		(layer "F.Cu")
		(net "GND")
	)
	(segment
		(start 217.4494 -143.6116)
		(end 217.4494 -143.7894)
		(width 0.3048)
		(layer "F.Cu")
		(net "GND")
	)
	(segment
		(start 122.217688 -94.538038)
		(end 121.646188 -94.538038)
		(width 0.3048)
		(layer "F.Cu")
		(net "GND")
	)
	(segment
		(start 138.499342 -4.808728)
		(end 138.499342 -5.822442)
		(width 0.4064)
		(layer "F.Cu")
		(net "GND")
	)
	(segment
		(start 296.700448 -147.27174)
		(end 296.69994 -147.27174)
		(width 0.4064)
		(layer "F.Cu")
		(net "GND")
	)
	(segment
		(start 118.212362 -94.538038)
		(end 118.783862 -94.538038)
		(width 0.254)
		(layer "F.Cu")
		(net "GND")
	)
	(segment
		(start 67.749166 -87.28964)
		(end 67.101466 -87.28964)
		(width 0.254)
		(layer "F.Cu")
		(net "GND")
	)
	(segment
		(start 227.792534 0.444754)
		(end 227.792534 0.457454)
		(width 0.3556)
		(layer "F.Cu")
		(net "GND")
	)
	(segment
		(start 114.778282 -63.829184)
		(end 114.206782 -63.829184)
		(width 0.254)
		(layer "F.Cu")
		(net "GND")
	)
	(segment
		(start 204.050392 -20.023582)
		(end 204.049884 -20.023582)
		(width 0.4064)
		(layer "F.Cu")
		(net "GND")
	)
	(segment
		(start 51.79949 -0.821182)
		(end 51.79949 0.444754)
		(width 0.4064)
		(layer "F.Cu")
		(net "GND")
	)
	(segment
		(start 384.76555 -95.888556)
		(end 384.985006 -95.205042)
		(width 0.254)
		(layer "F.Cu")
		(net "GND")
	)
	(segment
		(start 44.149518 -2.253488)
		(end 44.092114 -2.310892)
		(width 0.4064)
		(layer "F.Cu")
		(net "GND")
	)
	(segment
		(start 420.69004 -33.734756)
		(end 421.09009 -34.134806)
		(width 0.1016)
		(layer "F.Cu")
		(net "GND")
	)
	(segment
		(start 235.325158 -86.794086)
		(end 234.753658 -86.794086)
		(width 0.254)
		(layer "F.Cu")
		(net "GND")
	)
	(segment
		(start 473.432632 -35.811968)
		(end 473.253308 -35.991292)
		(width 0.508)
		(layer "F.Cu")
		(net "GND")
	)
	(segment
		(start 398.834864 -117.679724)
		(end 399.13306 -117.97792)
		(width 0.254)
		(layer "F.Cu")
		(net "GND")
	)
	(segment
		(start -0.27432 -13.5509)
		(end -0.27432 -14.5034)
		(width 0.254)
		(layer "F.Cu")
		(net "GND")
	)
	(segment
		(start 379.81255 -105.5624)
		(end 380.30785 -105.332276)
		(width 0.254)
		(layer "F.Cu")
		(net "GND")
	)
	(segment
		(start 217.4494 -16.3576)
		(end 217.649806 -16.157194)
		(width 0.3048)
		(layer "F.Cu")
		(net "GND")
	)
	(segment
		(start 231.25049 -152.273)
		(end 231.249982 -152.278842)
		(width 0.4064)
		(layer "F.Cu")
		(net "GND")
	)
	(segment
		(start 279.699974 -147.277582)
		(end 279.699974 -148.771356)
		(width 0.508)
		(layer "F.Cu")
		(net "GND")
	)
	(segment
		(start 107.910376 -63.829184)
		(end 107.338876 -63.829184)
		(width 0.254)
		(layer "F.Cu")
		(net "GND")
	)
	(segment
		(start 215.950292 -152.273)
		(end 215.949784 -152.278842)
		(width 0.4064)
		(layer "F.Cu")
		(net "GND")
	)
	(segment
		(start 71.349362 -133.804406)
		(end 71.117968 -134.0358)
		(width 0.3556)
		(layer "F.Cu")
		(net "GND")
	)
	(segment
		(start 127.655828 -85.127338)
		(end 128.227328 -85.127338)
		(width 0.254)
		(layer "F.Cu")
		(net "GND")
	)
	(segment
		(start 60.299346 -13.427456)
		(end 60.210446 -13.338556)
		(width 0.4064)
		(layer "F.Cu")
		(net "GND")
	)
	(segment
		(start 388.72795 -119.29872)
		(end 389.22325 -119.528844)
		(width 0.254)
		(layer "F.Cu")
		(net "GND")
	)
	(segment
		(start 401.320508 -96.816672)
		(end 401.361148 -96.816672)
		(width 0.254)
		(layer "F.Cu")
		(net "GND")
	)
	(segment
		(start 113.923318 -11.93165)
		(end 113.849404 -11.857736)
		(width 0.4064)
		(layer "F.Cu")
		(net "GND")
	)
	(segment
		(start 113.919762 -65.315338)
		(end 113.348262 -65.315338)
		(width 0.254)
		(layer "F.Cu")
		(net "GND")
	)
	(segment
		(start 390.737598 -152.678638)
		(end 390.737598 -152.625298)
		(width 0.254)
		(layer "F.Cu")
		(net "GND")
	)
	(segment
		(start 152.099518 -148.782278)
		(end 152.099518 -149.601682)
		(width 0.4064)
		(layer "F.Cu")
		(net "GND")
	)
	(segment
		(start 232.749598 -83.32724)
		(end 232.101898 -83.32724)
		(width 0.254)
		(layer "F.Cu")
		(net "GND")
	)
	(segment
		(start 281.399996 -10.422382)
		(end 281.399996 -9.156446)
		(width 0.4064)
		(layer "F.Cu")
		(net "GND")
	)
	(segment
		(start 287.349946 -20.023582)
		(end 287.349946 -21.517356)
		(width 0.4064)
		(layer "F.Cu")
		(net "GND")
	)
	(segment
		(start 71.349362 -133.0706)
		(end 71.349362 -133.804406)
		(width 0.3556)
		(layer "F.Cu")
		(net "GND")
	)
	(segment
		(start 395.224 -115.03279)
		(end 395.66215 -115.236244)
		(width 0.254)
		(layer "F.Cu")
		(net "GND")
	)
	(segment
		(start 45.849286 -5.822696)
		(end 45.849286 -6.637274)
		(width 0.4064)
		(layer "F.Cu")
		(net "GND")
	)
	(segment
		(start 119.799354 -152.273)
		(end 119.799354 -152.278842)
		(width 0.4064)
		(layer "F.Cu")
		(net "GND")
	)
	(segment
		(start 226.7966 2.844546)
		(end 226.7966 1.9812)
		(width 0.3556)
		(layer "F.Cu")
		(net "GND")
	)
	(segment
		(start 143.599408 -15.423642)
		(end 143.599408 -17.110202)
		(width 0.4064)
		(layer "F.Cu")
		(net "GND")
	)
	(segment
		(start 31.536386 -86.487)
		(end 31.877 -86.487)
		(width 0.254)
		(layer "F.Cu")
		(net "GND")
	)
	(segment
		(start 272.052288 -92.061538)
		(end 272.623788 -92.061538)
		(width 0.254)
		(layer "F.Cu")
		(net "GND")
	)
	(segment
		(start 435.818788 -18.866612)
		(end 436.2069 -18.4785)
		(width 0.254)
		(layer "F.Cu")
		(net "GND")
	)
	(segment
		(start 139.34948 -18.757646)
		(end 139.34948 -20.023582)
		(width 0.4064)
		(layer "F.Cu")
		(net "GND")
	)
	(segment
		(start 197.249796 -152.278842)
		(end 197.249796 -153.965402)
		(width 0.4064)
		(layer "F.Cu")
		(net "GND")
	)
	(segment
		(start 62.792102 -9.156446)
		(end 62.792102 -9.143746)
		(width 0.3556)
		(layer "F.Cu")
		(net "GND")
	)
	(segment
		(start 30.668976 -77.44841)
		(end 30.013656 -77.44841)
		(width 0.508)
		(layer "F.Cu")
		(net "GND")
	)
	(segment
		(start 279.778714 -92.556584)
		(end 280.350214 -92.556584)
		(width 0.254)
		(layer "F.Cu")
		(net "GND")
	)
	(segment
		(start 278.849836 -11.857736)
		(end 278.92375 -11.93165)
		(width 0.4064)
		(layer "F.Cu")
		(net "GND")
	)
	(segment
		(start 119.929402 -101.471984)
		(end 119.642382 -101.967538)
		(width 0.4064)
		(layer "F.Cu")
		(net "GND")
	)
	(segment
		(start 389.044688 -104.361488)
		(end 389.33755 -104.65435)
		(width 0.12446)
		(layer "F.Cu")
		(net "GND")
	)
	(segment
		(start 291.79774 -90.575384)
		(end 292.36924 -90.575384)
		(width 0.254)
		(layer "F.Cu")
		(net "GND")
	)
	(segment
		(start 306.392326 -87.108538)
		(end 306.392326 -87.091266)
		(width 0.254)
		(layer "F.Cu")
		(net "GND")
	)
	(segment
		(start 386.627116 -111.544354)
		(end 386.93725 -111.854488)
		(width 0.1143)
		(layer "F.Cu")
		(net "GND")
	)
	(segment
		(start 66.24955 3.778758)
		(end 66.24955 3.599688)
		(width 0.4064)
		(layer "F.Cu")
		(net "GND")
	)
	(segment
		(start 145.29943 3.061462)
		(end 145.082768 2.8448)
		(width 0.3556)
		(layer "F.Cu")
		(net "GND")
	)
	(segment
		(start 279.778714 -63.829184)
		(end 279.207214 -63.829184)
		(width 0.254)
		(layer "F.Cu")
		(net "GND")
	)
	(segment
		(start 255.018032 -139.9794)
		(end 255.3716 -139.9794)
		(width 0.4064)
		(layer "F.Cu")
		(net "GND")
	)
	(segment
		(start 130.231388 -68.782184)
		(end 130.802888 -68.782184)
		(width 0.254)
		(layer "F.Cu")
		(net "GND")
	)
	(segment
		(start 414.655762 -87.159084)
		(end 413.893762 -87.921084)
		(width 0.3048)
		(layer "F.Cu")
		(net "GND")
	)
	(segment
		(start 300.736 -134.035546)
		(end 300.736 -134.863332)
		(width 0.3556)
		(layer "F.Cu")
		(net "GND")
	)
	(segment
		(start 380.41072 -157.783784)
		(end 380.41072 -157.247336)
		(width 0.254)
		(layer "F.Cu")
		(net "GND")
	)
	(segment
		(start 306.049934 -0.821182)
		(end 306.049934 0.444754)
		(width 0.4064)
		(layer "F.Cu")
		(net "GND")
	)
	(segment
		(start 33.949386 -142.6718)
		(end 33.949386 -143.391382)
		(width 0.3556)
		(layer "F.Cu")
		(net "GND")
	)
	(segment
		(start 120.216168 -54.418738)
		(end 120.787668 -54.418738)
		(width 0.254)
		(layer "F.Cu")
		(net "GND")
	)
	(segment
		(start 491.109 -137.16)
		(end 491.109 -136.293352)
		(width 0.254)
		(layer "F.Cu")
		(net "GND")
	)
	(segment
		(start 142.749524 -0.821182)
		(end 142.749524 0.457454)
		(width 0.4064)
		(layer "F.Cu")
		(net "GND")
	)
	(segment
		(start 294.150288 -5.822442)
		(end 294.14978 -5.822442)
		(width 0.4064)
		(layer "F.Cu")
		(net "GND")
	)
	(segment
		(start 135.949436 3.778758)
		(end 135.949436 3.033522)
		(width 0.3556)
		(layer "F.Cu")
		(net "GND")
	)
	(segment
		(start 126.388368 -134.866126)
		(end 126.421642 -134.8994)
		(width 0.3556)
		(layer "F.Cu")
		(net "GND")
	)
	(segment
		(start 52.649374 -16.157194)
		(end 52.649374 -15.423642)
		(width 0.3048)
		(layer "F.Cu")
		(net "GND")
	)
	(segment
		(start 247.344184 -56.085486)
		(end 246.772684 -56.085486)
		(width 0.254)
		(layer "F.Cu")
		(net "GND")
	)
	(segment
		(start 227.000308 -152.273)
		(end 226.9998 -152.278842)
		(width 0.3556)
		(layer "F.Cu")
		(net "GND")
	)
	(segment
		(start 376.335036 -115.78844)
		(end 376.71121 -115.412266)
		(width 0.254)
		(layer "F.Cu")
		(net "GND")
	)
	(segment
		(start 433.409344 -13.60805)
		(end 434.799232 -13.60805)
		(width 0.254)
		(layer "F.Cu")
		(net "GND")
	)
	(segment
		(start 375.504964 -109.855)
		(end 376.335036 -109.855)
		(width 0.254)
		(layer "F.Cu")
		(net "GND")
	)
	(segment
		(start 278.061674 -52.932838)
		(end 278.062944 -52.932584)
		(width 0.254)
		(layer "F.Cu")
		(net "GND")
	)
	(segment
		(start 8.104378 4.911598)
		(end 7.819644 5.196332)
		(width 0.254)
		(layer "F.Cu")
		(net "GND")
	)
	(segment
		(start 308.59984 -133.076442)
		(end 308.59984 -134.763002)
		(width 0.4064)
		(layer "F.Cu")
		(net "GND")
	)
	(segment
		(start 312.849768 2.963926)
		(end 312.849768 3.778758)
		(width 0.4064)
		(layer "F.Cu")
		(net "GND")
	)
	(segment
		(start 78.909672 -87.784686)
		(end 78.338172 -87.784686)
		(width 0.254)
		(layer "F.Cu")
		(net "GND")
	)
	(segment
		(start 145.082768 -144.461738)
		(end 145.12163 -144.5006)
		(width 0.3556)
		(layer "F.Cu")
		(net "GND")
	)
	(segment
		(start 306.392326 -97.014538)
		(end 307.027326 -97.014538)
		(width 0.254)
		(layer "F.Cu")
		(net "GND")
	)
	(segment
		(start 116.361464 -11.916156)
		(end 116.399564 -11.878056)
		(width 0.4064)
		(layer "F.Cu")
		(net "GND")
	)
	(segment
		(start 183.134 -2.705608)
		(end 183.134 -1.27)
		(width 0.3048)
		(layer "F.Cu")
		(net "GND")
	)
	(segment
		(start 173.6852 -6.313424)
		(end 173.874176 -6.313424)
		(width 0.4064)
		(layer "F.Cu")
		(net "GND")
	)
	(segment
		(start 283.099764 -147.27174)
		(end 283.099764 -146.06905)
		(width 0.3556)
		(layer "F.Cu")
		(net "GND")
	)
	(segment
		(start 306.392326 -71.258938)
		(end 307.040026 -71.258938)
		(width 0.254)
		(layer "F.Cu")
		(net "GND")
	)
	(segment
		(start 295.23182 -59.866784)
		(end 295.80332 -59.866784)
		(width 0.254)
		(layer "F.Cu")
		(net "GND")
	)
	(segment
		(start 81.485232 -81.34604)
		(end 80.913732 -81.34604)
		(width 0.254)
		(layer "F.Cu")
		(net "GND")
	)
	(segment
		(start 69.64934 -133.0706)
		(end 69.64934 -134.763002)
		(width 0.4064)
		(layer "F.Cu")
		(net "GND")
	)
	(segment
		(start 390.93775 -107.05465)
		(end 391.3378 -106.6546)
		(width 0.12446)
		(layer "F.Cu")
		(net "GND")
	)
	(segment
		(start 236.1184 -7.591806)
		(end 236.171994 -7.6454)
		(width 0.3556)
		(layer "F.Cu")
		(net "GND")
	)
	(segment
		(start 243.256054 -140.208)
		(end 244.3353 -140.208)
		(width 0.508)
		(layer "F.Cu")
		(net "GND")
	)
	(segment
		(start 283.212794 -63.829184)
		(end 282.641294 -63.829184)
		(width 0.254)
		(layer "F.Cu")
		(net "GND")
	)
	(segment
		(start 290.71189 -2.314956)
		(end 290.74999 -2.276856)
		(width 0.4064)
		(layer "F.Cu")
		(net "GND")
	)
	(segment
		(start 399.634964 -115.854988)
		(end 400.05 -115.355116)
		(width 0.254)
		(layer "F.Cu")
		(net "GND")
	)
	(segment
		(start 416.290252 -30.134814)
		(end 415.890202 -29.734764)
		(width 0.254)
		(layer "F.Cu")
		(net "GND")
	)
	(segment
		(start 280.549858 3.778758)
		(end 280.549858 2.092198)
		(width 0.4064)
		(layer "F.Cu")
		(net "GND")
	)
	(segment
		(start 279.699974 -147.27174)
		(end 279.699974 -147.277582)
		(width 0.4064)
		(layer "F.Cu")
		(net "GND")
	)
	(segment
		(start 415.956242 -129.740406)
		(end 415.191194 -129.740406)
		(width 0.381)
		(layer "F.Cu")
		(net "GND")
	)
	(segment
		(start 74.617326 -56.58104)
		(end 74.045826 -56.58104)
		(width 0.254)
		(layer "F.Cu")
		(net "GND")
	)
	(segment
		(start 303.529746 -69.277738)
		(end 302.958246 -69.277738)
		(width 0.254)
		(layer "F.Cu")
		(net "GND")
	)
	(segment
		(start 483.398322 -31.684468)
		(end 483.9843 -31.684468)
		(width 0.254)
		(layer "F.Cu")
		(net "GND")
	)
	(segment
		(start 399.050764 -96.524064)
		(end 398.361662 -96.524064)
		(width 0.2032)
		(layer "F.Cu")
		(net "GND")
	)
	(segment
		(start 295.23182 -57.885584)
		(end 295.80332 -57.885584)
		(width 0.254)
		(layer "F.Cu")
		(net "GND")
	)
	(segment
		(start 317.09995 -2.325878)
		(end 317.09995 -3.255518)
		(width 0.4064)
		(layer "F.Cu")
		(net "GND")
	)
	(segment
		(start 278.849836 -154.111452)
		(end 278.727408 -154.23388)
		(width 0.4064)
		(layer "F.Cu")
		(net "GND")
	)
	(segment
		(start 116.495322 -56.894984)
		(end 115.923822 -56.894984)
		(width 0.254)
		(layer "F.Cu")
		(net "GND")
	)
	(segment
		(start 363.085126 -4.389882)
		(end 363.085126 -3.420364)
		(width 0.4572)
		(layer "F.Cu")
		(net "GND")
	)
	(segment
		(start 123.363228 -69.772784)
		(end 123.934728 -69.772784)
		(width 0.254)
		(layer "F.Cu")
		(net "GND")
	)
	(segment
		(start 200.983596 -141.1478)
		(end 201.037952 -141.202156)
		(width 0.254)
		(layer "F.Cu")
		(net "GND")
	)
	(segment
		(start 307.749956 -11.916156)
		(end 307.749956 -10.422382)
		(width 0.4064)
		(layer "F.Cu")
		(net "GND")
	)
	(segment
		(start 360.8324 -132.3086)
		(end 360.8324 -132.9436)
		(width 0.254)
		(layer "F.Cu")
		(net "GND")
	)
	(segment
		(start 83.202272 -63.51524)
		(end 82.630772 -63.51524)
		(width 0.254)
		(layer "F.Cu")
		(net "GND")
	)
	(segment
		(start 78.909672 -91.747086)
		(end 78.338172 -91.747086)
		(width 0.254)
		(layer "F.Cu")
		(net "GND")
	)
	(segment
		(start 469.138 -20.6502)
		(end 469.138 -21.971)
		(width 0.254)
		(layer "F.Cu")
		(net "GND")
	)
	(segment
		(start 415.47288 -49.390808)
		(end 415.47288 -49.421542)
		(width 0.254)
		(layer "F.Cu")
		(net "GND")
	)
	(segment
		(start 36.499546 -5.822442)
		(end 36.499546 -4.808982)
		(width 0.4064)
		(layer "F.Cu")
		(net "GND")
	)
	(segment
		(start 301.800514 -0.821182)
		(end 301.800006 -0.821182)
		(width 0.3556)
		(layer "F.Cu")
		(net "GND")
	)
	(segment
		(start 85.777832 -83.822286)
		(end 85.206332 -83.822286)
		(width 0.254)
		(layer "F.Cu")
		(net "GND")
	)
	(segment
		(start 284.929834 -85.622384)
		(end 285.501334 -85.622384)
		(width 0.254)
		(layer "F.Cu")
		(net "GND")
	)
	(segment
		(start 218.499944 -18.81505)
		(end 218.499944 -20.023582)
		(width 0.3556)
		(layer "F.Cu")
		(net "GND")
	)
	(segment
		(start 68.607686 -86.794086)
		(end 68.036186 -86.794086)
		(width 0.254)
		(layer "F.Cu")
		(net "GND")
	)
	(segment
		(start 283.501592 -52.443634)
		(end 283.499814 -52.437284)
		(width 0.254)
		(layer "F.Cu")
		(net "GND")
	)
	(segment
		(start 39.899336 3.778758)
		(end 39.899336 1.994154)
		(width 0.4064)
		(layer "F.Cu")
		(net "GND")
	)
	(segment
		(start 397.14805 -103.615236)
		(end 397.14805 -102.98684)
		(width 0.254)
		(layer "F.Cu")
		(net "GND")
	)
	(segment
		(start 292.45052 -0.821182)
		(end 292.450012 -0.821182)
		(width 0.4064)
		(layer "F.Cu")
		(net "GND")
	)
	(segment
		(start 305.816254 -52.705)
		(end 306.024026 -52.497228)
		(width 0.254)
		(layer "F.Cu")
		(net "GND")
	)
	(segment
		(start 105.9561 -140.208)
		(end 107.027472 -140.208)
		(width 0.4064)
		(layer "F.Cu")
		(net "GND")
	)
	(segment
		(start 71.183246 -80.35544)
		(end 70.611746 -80.35544)
		(width 0.254)
		(layer "F.Cu")
		(net "GND")
	)
	(segment
		(start 317.949834 3.778758)
		(end 317.949834 2.514854)
		(width 0.4064)
		(layer "F.Cu")
		(net "GND")
	)
	(segment
		(start 199.799956 -19.027902)
		(end 199.799956 -20.023582)
		(width 0.4064)
		(layer "F.Cu")
		(net "GND")
	)
	(segment
		(start 382.98501 -126.165102)
		(end 383.286 -126.466092)
		(width 0.254)
		(layer "F.Cu")
		(net "GND")
	)
	(segment
		(start 94.362778 -98.681286)
		(end 93.791278 -98.681286)
		(width 0.254)
		(layer "F.Cu")
		(net "GND")
	)
	(segment
		(start 416.402012 -53.184298)
		(end 416.402012 -52.738782)
		(width 0.254)
		(layer "F.Cu")
		(net "GND")
	)
	(segment
		(start 291.3888 -153.2128)
		(end 291.3888 -154.068526)
		(width 0.3556)
		(layer "F.Cu")
		(net "GND")
	)
	(segment
		(start 253.353824 -82.33664)
		(end 252.782324 -82.33664)
		(width 0.254)
		(layer "F.Cu")
		(net "GND")
	)
	(segment
		(start 85.777832 -60.047886)
		(end 85.206332 -60.047886)
		(width 0.254)
		(layer "F.Cu")
		(net "GND")
	)
	(segment
		(start 47.549308 -133.255766)
		(end 47.549308 -134.861046)
		(width 0.4064)
		(layer "F.Cu")
		(net "GND")
	)
	(segment
		(start 388.9375 -114.6556)
		(end 389.33755 -114.25555)
		(width 0.12446)
		(layer "F.Cu")
		(net "GND")
	)
	(segment
		(start 79.342488 -140.208)
		(end 78.2574 -140.208)
		(width 0.4064)
		(layer "F.Cu")
		(net "GND")
	)
	(segment
		(start 109.82325 -67.253104)
		(end 109.82325 -67.59575)
		(width 0.254)
		(layer "F.Cu")
		(net "GND")
	)
	(segment
		(start 294.999918 -20.023582)
		(end 294.999918 -21.517356)
		(width 0.4064)
		(layer "F.Cu")
		(net "GND")
	)
	(segment
		(start 353.6188 -100.29063)
		(end 354.23729 -100.29063)
		(width 0.254)
		(layer "F.Cu")
		(net "GND")
	)
	(segment
		(start 306.899818 -5.822442)
		(end 306.899818 -7.607046)
		(width 0.4064)
		(layer "F.Cu")
		(net "GND")
	)
	(segment
		(start 458.201014 -112.205516)
		(end 458.201014 -113.751614)
		(width 0.4064)
		(layer "F.Cu")
		(net "GND")
	)
	(segment
		(start 309.449978 -147.27174)
		(end 309.449978 -146.011646)
		(width 0.4064)
		(layer "F.Cu")
		(net "GND")
	)
	(segment
		(start 251.636784 -62.52464)
		(end 251.065284 -62.52464)
		(width 0.254)
		(layer "F.Cu")
		(net "GND")
	)
	(segment
		(start 299.249846 -133.076442)
		(end 299.249846 -134.763002)
		(width 0.4064)
		(layer "F.Cu")
		(net "GND")
	)
	(segment
		(start 379.985016 -95.205042)
		(end 380.985014 -95.205042)
		(width 0.254)
		(layer "F.Cu")
		(net "GND")
	)
	(segment
		(start 44.092114 -136.448546)
		(end 44.092114 -136.397746)
		(width 0.4064)
		(layer "F.Cu")
		(net "GND")
	)
	(segment
		(start 109.627416 -57.885584)
		(end 109.055916 -57.885584)
		(width 0.254)
		(layer "F.Cu")
		(net "GND")
	)
	(segment
		(start 284.071314 -55.409338)
		(end 283.499814 -55.409338)
		(width 0.254)
		(layer "F.Cu")
		(net "GND")
	)
	(segment
		(start 349.292164 -148.098764)
		(end 349.612712 -148.419312)
		(width 0.254)
		(layer "F.Cu")
		(net "GND")
	)
	(segment
		(start 220.200474 -152.273)
		(end 220.199966 -152.278842)
		(width 0.4064)
		(layer "F.Cu")
		(net "GND")
	)
	(segment
		(start 90.928698 -88.775286)
		(end 90.357198 -88.775286)
		(width 0.254)
		(layer "F.Cu")
		(net "GND")
	)
	(segment
		(start 391.20445 -102.98684)
		(end 391.212832 -102.98303)
		(width 0.254)
		(layer "F.Cu")
		(net "GND")
	)
	(segment
		(start 350.012 -13.843)
		(end 350.647 -13.843)
		(width 0.254)
		(layer "F.Cu")
		(net "GND")
	)
	(segment
		(start 84.060792 -78.869286)
		(end 83.489292 -78.869286)
		(width 0.254)
		(layer "F.Cu")
		(net "GND")
	)
	(segment
		(start 457.252578 -138.719814)
		(end 458.520546 -138.719814)
		(width 0.254)
		(layer "F.Cu")
		(net "GND")
	)
	(segment
		(start 67.749166 -90.26144)
		(end 67.101466 -90.26144)
		(width 0.254)
		(layer "F.Cu")
		(net "GND")
	)
	(segment
		(start 181.0004 -145.2626)
		(end 180.594 -145.669)
		(width 0.254)
		(layer "F.Cu")
		(net "GND")
	)
	(segment
		(start 109.2581 -149.8092)
		(end 110.109 -149.8092)
		(width 0.4064)
		(layer "F.Cu")
		(net "GND")
	)
	(segment
		(start 114.699542 -18.744946)
		(end 114.699542 -20.023582)
		(width 0.4064)
		(layer "F.Cu")
		(net "GND")
	)
	(segment
		(start 144.449546 -147.27174)
		(end 144.449546 -146.011646)
		(width 0.4064)
		(layer "F.Cu")
		(net "GND")
	)
	(segment
		(start 56.049418 -156.87294)
		(end 56.049418 -155.612846)
		(width 0.4064)
		(layer "F.Cu")
		(net "GND")
	)
	(segment
		(start 279.778714 -64.819784)
		(end 279.207214 -64.819784)
		(width 0.254)
		(layer "F.Cu")
		(net "GND")
	)
	(segment
		(start 217.4494 -153.2128)
		(end 217.4494 -153.3906)
		(width 0.3048)
		(layer "F.Cu")
		(net "GND")
	)
	(segment
		(start 217.4494 -134.0104)
		(end 217.4494 -134.1882)
		(width 0.3048)
		(layer "F.Cu")
		(net "GND")
	)
	(segment
		(start 267.089636 -89.27084)
		(end 266.518136 -89.27084)
		(width 0.254)
		(layer "F.Cu")
		(net "GND")
	)
	(segment
		(start 399.634964 -113.854992)
		(end 399.634964 -114.85499)
		(width 0.254)
		(layer "F.Cu")
		(net "GND")
	)
	(segment
		(start 454.877678 -7.789672)
		(end 454.877678 -8.824722)
		(width 0.254)
		(layer "F.Cu")
		(net "GND")
	)
	(segment
		(start 317.09995 -156.87294)
		(end 317.09995 -155.612846)
		(width 0.4064)
		(layer "F.Cu")
		(net "GND")
	)
	(segment
		(start 237.900718 -67.47764)
		(end 237.329218 -67.47764)
		(width 0.254)
		(layer "F.Cu")
		(net "GND")
	)
	(segment
		(start 288.19983 -5.822442)
		(end 288.19983 -7.607046)
		(width 0.4064)
		(layer "F.Cu")
		(net "GND")
	)
	(segment
		(start 288.36366 -93.547184)
		(end 288.93516 -93.547184)
		(width 0.254)
		(layer "F.Cu")
		(net "GND")
	)
	(segment
		(start 291.3888 1.989074)
		(end 291.422074 1.9558)
		(width 0.3556)
		(layer "F.Cu")
		(net "GND")
	)
	(segment
		(start 290.750498 -137.67054)
		(end 290.74999 -137.67054)
		(width 0.4064)
		(layer "F.Cu")
		(net "GND")
	)
	(segment
		(start 448.226942 -45.560996)
		(end 447.74104 -46.046898)
		(width 0.4064)
		(layer "F.Cu")
		(net "GND")
	)
	(segment
		(start 284.929834 -94.538038)
		(end 285.501334 -94.538038)
		(width 0.254)
		(layer "F.Cu")
		(net "GND")
	)
	(segment
		(start 299.249846 -144.364202)
		(end 299.151802 -144.462246)
		(width 0.4064)
		(layer "F.Cu")
		(net "GND")
	)
	(segment
		(start 461.440022 -3.386074)
		(end 461.278478 -3.547618)
		(width 0.254)
		(layer "F.Cu")
		(net "GND")
	)
	(segment
		(start 131.089908 -55.409338)
		(end 131.661408 -55.409338)
		(width 0.254)
		(layer "F.Cu")
		(net "GND")
	)
	(segment
		(start 281.61742 -101.261164)
		(end 281.495754 -101.471984)
		(width 0.254)
		(layer "F.Cu")
		(net "GND")
	)
	(segment
		(start 283.100272 -156.87294)
		(end 283.100272 -155.658058)
		(width 0.3556)
		(layer "F.Cu")
		(net "GND")
	)
	(segment
		(start 400.939 -74.53122)
		(end 400.685 -74.78522)
		(width 0.254)
		(layer "F.Cu")
		(net "GND")
	)
	(segment
		(start 232.950512 -3.763518)
		(end 232.94975 -3.762756)
		(width 0.4064)
		(layer "F.Cu")
		(net "GND")
	)
	(segment
		(start 316.249812 -152.278842)
		(end 316.249812 -154.063446)
		(width 0.4064)
		(layer "F.Cu")
		(net "GND")
	)
	(segment
		(start 261.950454 -127.763524)
		(end 261.747 -127.966978)
		(width 0.4064)
		(layer "F.Cu")
		(net "GND")
	)
	(segment
		(start 53.442108 -18.757646)
		(end 53.499512 -18.81505)
		(width 0.3556)
		(layer "F.Cu")
		(net "GND")
	)
	(segment
		(start 130.231388 -70.763384)
		(end 130.802888 -70.763384)
		(width 0.254)
		(layer "F.Cu")
		(net "GND")
	)
	(segment
		(start 397.750538 -75.050396)
		(end 397.750538 -75.30592)
		(width 0.254)
		(layer "F.Cu")
		(net "GND")
	)
	(segment
		(start 119.929402 -86.612984)
		(end 120.500902 -86.612984)
		(width 0.254)
		(layer "F.Cu")
		(net "GND")
	)
	(segment
		(start 207.449928 -11.878056)
		(end 207.449928 -10.422382)
		(width 0.4064)
		(layer "F.Cu")
		(net "GND")
	)
	(segment
		(start 74.617326 -94.223586)
		(end 74.045826 -94.223586)
		(width 0.254)
		(layer "F.Cu")
		(net "GND")
	)
	(segment
		(start 61.796168 -16.357854)
		(end 61.999368 -16.154654)
		(width 0.3556)
		(layer "F.Cu")
		(net "GND")
	)
	(segment
		(start 284.800294 -152.273)
		(end 284.799786 -152.278842)
		(width 0.4064)
		(layer "F.Cu")
		(net "GND")
	)
	(segment
		(start 72.900286 -62.52464)
		(end 72.328786 -62.52464)
		(width 0.254)
		(layer "F.Cu")
		(net "GND")
	)
	(segment
		(start 232.100374 -20.023582)
		(end 232.099866 -20.023582)
		(width 0.4064)
		(layer "F.Cu")
		(net "GND")
	)
	(segment
		(start 296.69994 -0.821182)
		(end 296.69994 0.444754)
		(width 0.4064)
		(layer "F.Cu")
		(net "GND")
	)
	(segment
		(start 283.099764 -9.21385)
		(end 283.099764 -10.422382)
		(width 0.3556)
		(layer "F.Cu")
		(net "GND")
	)
	(segment
		(start 126.797308 -100.481638)
		(end 127.368808 -100.481638)
		(width 0.254)
		(layer "F.Cu")
		(net "GND")
	)
	(segment
		(start 294.150288 -133.0706)
		(end 294.14978 -133.076442)
		(width 0.4064)
		(layer "F.Cu")
		(net "GND")
	)
	(segment
		(start 209.088482 -11.916156)
		(end 209.092546 -11.912092)
		(width 0.254)
		(layer "F.Cu")
		(net "GND")
	)
	(segment
		(start 112.202722 -98.005138)
		(end 112.774222 -98.005138)
		(width 0.254)
		(layer "F.Cu")
		(net "GND")
	)
	(segment
		(start 290.93922 -81.164938)
		(end 291.51072 -81.164938)
		(width 0.254)
		(layer "F.Cu")
		(net "GND")
	)
	(segment
		(start 61.821568 -17.2466)
		(end 61.796168 -17.2212)
		(width 0.3556)
		(layer "F.Cu")
		(net "GND")
	)
	(segment
		(start 289.22218 -98.005138)
		(end 289.79368 -98.005138)
		(width 0.254)
		(layer "F.Cu")
		(net "GND")
	)
	(segment
		(start 237.042198 -87.784686)
		(end 236.470698 -87.784686)
		(width 0.254)
		(layer "F.Cu")
		(net "GND")
	)
	(segment
		(start 51.79949 -11.878056)
		(end 51.76139 -11.916156)
		(width 0.4064)
		(layer "F.Cu")
		(net "GND")
	)
	(segment
		(start 44.149518 -20.023582)
		(end 44.149518 -21.455888)
		(width 0.4064)
		(layer "F.Cu")
		(net "GND")
	)
	(segment
		(start 411.672786 -7.789672)
		(end 411.672786 -8.849614)
		(width 0.254)
		(layer "F.Cu")
		(net "GND")
	)
	(segment
		(start 393.68095 -115.86464)
		(end 394.17625 -116.094764)
		(width 0.254)
		(layer "F.Cu")
		(net "GND")
	)
	(segment
		(start 400.487134 -126.165102)
		(end 400.467576 -126.18466)
		(width 0.254)
		(layer "F.Cu")
		(net "GND")
	)
	(segment
		(start 300.950376 -133.0706)
		(end 300.949868 -133.076442)
		(width 0.3556)
		(layer "F.Cu")
		(net "GND")
	)
	(segment
		(start 53.442108 0.444754)
		(end 53.442108 0.457454)
		(width 0.3556)
		(layer "F.Cu")
		(net "GND")
	)
	(segment
		(start 381.819404 -158.248858)
		(end 381.819404 -157.539944)
		(width 0.254)
		(layer "F.Cu")
		(net "GND")
	)
	(segment
		(start 275.486114 -63.334138)
		(end 274.914614 -63.334138)
		(width 0.254)
		(layer "F.Cu")
		(net "GND")
	)
	(segment
		(start 109.627416 -52.932838)
		(end 109.627162 -52.932838)
		(width 0.254)
		(layer "F.Cu")
		(net "GND")
	)
	(segment
		(start 272.052288 -61.352938)
		(end 271.480788 -61.352938)
		(width 0.254)
		(layer "F.Cu")
		(net "GND")
	)
	(segment
		(start 116.495322 -67.791584)
		(end 116.495322 -68.363084)
		(width 0.254)
		(layer "F.Cu")
		(net "GND")
	)
	(segment
		(start 76.334366 -83.32724)
		(end 75.762866 -83.32724)
		(width 0.254)
		(layer "F.Cu")
		(net "GND")
	)
	(segment
		(start 386.25145 -116.094764)
		(end 386.25145 -115.71224)
		(width 0.1143)
		(layer "F.Cu")
		(net "GND")
	)
	(segment
		(start 34.74212 -18.970498)
		(end 34.799524 -19.027902)
		(width 0.4064)
		(layer "F.Cu")
		(net "GND")
	)
	(segment
		(start 250.778264 -96.700086)
		(end 250.206764 -96.700086)
		(width 0.254)
		(layer "F.Cu")
		(net "GND")
	)
	(segment
		(start 0.26416 -134.929372)
		(end 0.26416 -135.03656)
		(width 0.254)
		(layer "F.Cu")
		(net "GND")
	)
	(segment
		(start 394.67155 -96.9772)
		(end 394.903706 -96.86925)
		(width 0.254)
		(layer "F.Cu")
		(net "GND")
	)
	(segment
		(start 120.787668 -91.070938)
		(end 121.359168 -91.070938)
		(width 0.254)
		(layer "F.Cu")
		(net "GND")
	)
	(segment
		(start 247.344184 -91.747086)
		(end 246.772684 -91.747086)
		(width 0.254)
		(layer "F.Cu")
		(net "GND")
	)
	(segment
		(start 126.599442 3.778758)
		(end 126.599442 3.055874)
		(width 0.3556)
		(layer "F.Cu")
		(net "GND")
	)
	(segment
		(start 140.533374 -52.932838)
		(end 140.742162 -52.932838)
		(width 0.254)
		(layer "F.Cu")
		(net "GND")
	)
	(segment
		(start 33.754568 -7.628382)
		(end 33.754568 -6.731)
		(width 0.3556)
		(layer "F.Cu")
		(net "GND")
	)
	(segment
		(start 41.599358 -3.826256)
		(end 41.510458 -3.737356)
		(width 0.4064)
		(layer "F.Cu")
		(net "GND")
	)
	(segment
		(start 70.324726 -95.709486)
		(end 69.753226 -95.709486)
		(width 0.254)
		(layer "F.Cu")
		(net "GND")
	)
	(segment
		(start 28.7528 -102.235)
		(end 28.067 -102.235)
		(width 0.4064)
		(layer "F.Cu")
		(net "GND")
	)
	(segment
		(start 287.350454 -0.821182)
		(end 287.349946 -0.821182)
		(width 0.4064)
		(layer "F.Cu")
		(net "GND")
	)
	(segment
		(start 291.599874 -15.423642)
		(end 291.599874 -13.541756)
		(width 0.4064)
		(layer "F.Cu")
		(net "GND")
	)
	(segment
		(start 391.69975 -119.29872)
		(end 392.19505 -119.528844)
		(width 0.254)
		(layer "F.Cu")
		(net "GND")
	)
	(segment
		(start 73.758806 -101.653086)
		(end 73.187306 -101.653086)
		(width 0.254)
		(layer "F.Cu")
		(net "GND")
	)
	(segment
		(start 114.778282 -52.932838)
		(end 114.551968 -53.325014)
		(width 0.254)
		(layer "F.Cu")
		(net "GND")
	)
	(segment
		(start 367.945162 -79.094838)
		(end 368.344958 -78.695042)
		(width 0.254)
		(layer "F.Cu")
		(net "GND")
	)
	(segment
		(start 390.578594 -155.394406)
		(end 390.906 -155.067)
		(width 0.254)
		(layer "F.Cu")
		(net "GND")
	)
	(segment
		(start 364.876334 -105.7021)
		(end 364.604554 -105.97388)
		(width 0.254)
		(layer "F.Cu")
		(net "GND")
	)
	(segment
		(start 235.325158 -59.057286)
		(end 234.753658 -59.057286)
		(width 0.3048)
		(layer "F.Cu")
		(net "GND")
	)
	(segment
		(start 11.249914 -45.310044)
		(end 12.683998 -46.744128)
		(width 0.508)
		(layer "F.Cu")
		(net "GND")
	)
	(segment
		(start 397.7894 -98.626422)
		(end 398.13865 -98.464116)
		(width 0.254)
		(layer "F.Cu")
		(net "GND")
	)
	(segment
		(start 27.242516 -32.522414)
		(end 27.137614 -32.627316)
		(width 0.254)
		(layer "F.Cu")
		(net "GND")
	)
	(segment
		(start 198.950326 -152.273)
		(end 198.949818 -152.278842)
		(width 0.3556)
		(layer "F.Cu")
		(net "GND")
	)
	(segment
		(start 51.79949 -18.757646)
		(end 51.79949 -20.023582)
		(width 0.4064)
		(layer "F.Cu")
		(net "GND")
	)
	(segment
		(start 221.050358 -10.422382)
		(end 221.04985 -10.422382)
		(width 0.4064)
		(layer "F.Cu")
		(net "GND")
	)
	(segment
		(start 20.5232 -98.199956)
		(end 20.5232 -98.7806)
		(width 0.254)
		(layer "F.Cu")
		(net "GND")
	)
	(segment
		(start 61.999368 -6.553454)
		(end 61.796168 -6.756654)
		(width 0.3556)
		(layer "F.Cu")
		(net "GND")
	)
	(segment
		(start 316.249812 -17.208246)
		(end 316.249812 -15.423642)
		(width 0.4064)
		(layer "F.Cu")
		(net "GND")
	)
	(segment
		(start 285.649924 -0.821182)
		(end 285.649924 -2.314956)
		(width 0.4064)
		(layer "F.Cu")
		(net "GND")
	)
	(segment
		(start 79.768192 -80.35544)
		(end 79.196692 -80.35544)
		(width 0.254)
		(layer "F.Cu")
		(net "GND")
	)
	(segment
		(start 305.533806 -78.688438)
		(end 306.197 -78.688438)
		(width 0.254)
		(layer "F.Cu")
		(net "GND")
	)
	(segment
		(start 234.753658 -57.076086)
		(end 233.608118 -57.076086)
		(width 0.254)
		(layer "F.Cu")
		(net "GND")
	)
	(segment
		(start 220.200474 3.778758)
		(end 220.200474 2.964688)
		(width 0.4064)
		(layer "F.Cu")
		(net "GND")
	)
	(segment
		(start 68.799456 -147.27174)
		(end 68.799456 -145.998946)
		(width 0.4064)
		(layer "F.Cu")
		(net "GND")
	)
	(segment
		(start 375.827798 -92.886022)
		(end 375.539 -92.837)
		(width 0.254)
		(layer "F.Cu")
		(net "GND")
	)
	(segment
		(start 73.899268 -133.891274)
		(end 73.440798 -134.349744)
		(width 0.4064)
		(layer "F.Cu")
		(net "GND")
	)
	(segment
		(start 301.241206 -65.315338)
		(end 301.812706 -65.315338)
		(width 0.254)
		(layer "F.Cu")
		(net "GND")
	)
	(segment
		(start 406.690068 -43.734736)
		(end 407.090118 -43.334686)
		(width 0.10795)
		(layer "F.Cu")
		(net "GND")
	)
	(segment
		(start 145.29943 -3.940556)
		(end 145.29943 -5.822442)
		(width 0.4064)
		(layer "F.Cu")
		(net "GND")
	)
	(segment
		(start 291.79774 -99.490784)
		(end 292.36924 -99.490784)
		(width 0.254)
		(layer "F.Cu")
		(net "GND")
	)
	(segment
		(start 110.485682 -62.343538)
		(end 109.914182 -62.343538)
		(width 0.254)
		(layer "F.Cu")
		(net "GND")
	)
	(segment
		(start 226.9998 -6.553454)
		(end 226.7966 -6.756654)
		(width 0.3556)
		(layer "F.Cu")
		(net "GND")
	)
	(segment
		(start 128.514348 -70.763384)
		(end 129.085848 -70.763384)
		(width 0.254)
		(layer "F.Cu")
		(net "GND")
	)
	(segment
		(start 198.061834 -11.916156)
		(end 198.099934 -11.878056)
		(width 0.4064)
		(layer "F.Cu")
		(net "GND")
	)
	(segment
		(start 126.797308 -90.575384)
		(end 127.368808 -90.575384)
		(width 0.254)
		(layer "F.Cu")
		(net "GND")
	)
	(segment
		(start 117.249448 -5.822442)
		(end 117.249448 -6.548374)
		(width 0.3556)
		(layer "F.Cu")
		(net "GND")
	)
	(segment
		(start 281.399996 -137.67054)
		(end 281.399996 -136.410446)
		(width 0.4064)
		(layer "F.Cu")
		(net "GND")
	)
	(segment
		(start 227.849938 -20.023582)
		(end 227.849938 -21.455888)
		(width 0.4064)
		(layer "F.Cu")
		(net "GND")
	)
	(segment
		(start 377.83135 -106.190796)
		(end 378.299726 -106.408474)
		(width 0.254)
		(layer "F.Cu")
		(net "GND")
	)
	(segment
		(start 193.5099 -68.803266)
		(end 193.704464 -68.608702)
		(width 0.254)
		(layer "F.Cu")
		(net "GND")
	)
	(segment
		(start 174.625 -64.63538)
		(end 174.625 -63.831978)
		(width 0.4064)
		(layer "F.Cu")
		(net "GND")
	)
	(segment
		(start 243.586 -150.114)
		(end 243.205 -150.114)
		(width 0.4572)
		(layer "F.Cu")
		(net "GND")
	)
	(segment
		(start 249.061224 -82.83194)
		(end 248.489724 -82.83194)
		(width 0.254)
		(layer "F.Cu")
		(net "GND")
	)
	(segment
		(start 292.450012 -18.81505)
		(end 292.450012 -20.023582)
		(width 0.3556)
		(layer "F.Cu")
		(net "GND")
	)
	(segment
		(start 262.79729 -95.709486)
		(end 262.22579 -95.709486)
		(width 0.254)
		(layer "F.Cu")
		(net "GND")
	)
	(segment
		(start 126.388368 -16.3576)
		(end 126.599442 -16.146526)
		(width 0.3556)
		(layer "F.Cu")
		(net "GND")
	)
	(segment
		(start 388.16026 -114.63274)
		(end 387.73735 -115.05565)
		(width 0.254)
		(layer "F.Cu")
		(net "GND")
	)
	(segment
		(start 178.2826 -67.437)
		(end 178.689 -67.437)
		(width 0.254)
		(layer "F.Cu")
		(net "GND")
	)
	(segment
		(start 130.231388 -80.669384)
		(end 130.802888 -80.669384)
		(width 0.254)
		(layer "F.Cu")
		(net "GND")
	)
	(segment
		(start 196.40042 -156.87294)
		(end 196.399912 -156.87294)
		(width 0.4064)
		(layer "F.Cu")
		(net "GND")
	)
	(segment
		(start 62.792102 -18.757646)
		(end 62.849506 -18.81505)
		(width 0.3556)
		(layer "F.Cu")
		(net "GND")
	)
	(segment
		(start 245.627144 -92.737686)
		(end 245.055644 -92.737686)
		(width 0.254)
		(layer "F.Cu")
		(net "GND")
	)
	(segment
		(start 475.7801 -142.5067)
		(end 475.7801 -142.8623)
		(width 0.254)
		(layer "F.Cu")
		(net "GND")
	)
	(segment
		(start 169.157396 -83.979004)
		(end 169.157396 -85.315298)
		(width 0.254)
		(layer "F.Cu")
		(net "GND")
	)
	(segment
		(start 299.250354 -152.273)
		(end 299.249846 -152.278842)
		(width 0.4064)
		(layer "F.Cu")
		(net "GND")
	)
	(segment
		(start 149.549358 -142.6718)
		(end 149.549358 -144.462246)
		(width 0.4064)
		(layer "F.Cu")
		(net "GND")
	)
	(segment
		(start 131.948174 -90.575384)
		(end 132.519674 -90.575384)
		(width 0.254)
		(layer "F.Cu")
		(net "GND")
	)
	(segment
		(start 289.22218 -76.211938)
		(end 289.79368 -76.211938)
		(width 0.254)
		(layer "F.Cu")
		(net "GND")
	)
	(segment
		(start 21.6662 -85.2805)
		(end 21.6662 -85.2424)
		(width 0.254)
		(layer "F.Cu")
		(net "GND")
	)
	(segment
		(start 114.778282 -94.538038)
		(end 115.349782 -94.538038)
		(width 0.254)
		(layer "F.Cu")
		(net "GND")
	)
	(segment
		(start 67.949318 -133.076696)
		(end 67.949318 -134.861046)
		(width 0.4064)
		(layer "F.Cu")
		(net "GND")
	)
	(segment
		(start 61.999368 -142.6718)
		(end 61.999368 -143.408654)
		(width 0.3556)
		(layer "F.Cu")
		(net "GND")
	)
	(segment
		(start 290.93922 -83.146138)
		(end 291.51072 -83.146138)
		(width 0.254)
		(layer "F.Cu")
		(net "GND")
	)
	(segment
		(start 383.985008 -95.205042)
		(end 382.98501 -95.205042)
		(width 0.254)
		(layer "F.Cu")
		(net "GND")
	)
	(segment
		(start 2.77495 -14.266418)
		(end 2.495042 -13.98651)
		(width 0.4064)
		(layer "F.Cu")
		(net "GND")
	)
	(segment
		(start 142.875 -59.866784)
		(end 142.875 -59.86399)
		(width 0.254)
		(layer "F.Cu")
		(net "GND")
	)
	(segment
		(start 278.920194 -91.070938)
		(end 279.491694 -91.070938)
		(width 0.1016)
		(layer "F.Cu")
		(net "GND")
	)
	(segment
		(start 80.626712 -55.094886)
		(end 80.055212 -55.094886)
		(width 0.254)
		(layer "F.Cu")
		(net "GND")
	)
	(segment
		(start 231.249728 3.599434)
		(end 231.249728 1.994154)
		(width 0.4064)
		(layer "F.Cu")
		(net "GND")
	)
	(segment
		(start 293.51478 -79.678784)
		(end 294.08628 -79.678784)
		(width 0.254)
		(layer "F.Cu")
		(net "GND")
	)
	(segment
		(start 69.466206 -60.54344)
		(end 68.894706 -60.54344)
		(width 0.254)
		(layer "F.Cu")
		(net "GND")
	)
	(segment
		(start 203.199746 -142.856966)
		(end 203.199746 -144.462246)
		(width 0.4064)
		(layer "F.Cu")
		(net "GND")
	)
	(segment
		(start 298.399962 -10.422382)
		(end 298.399962 -9.143746)
		(width 0.4064)
		(layer "F.Cu")
		(net "GND")
	)
	(segment
		(start 261.93877 -91.25204)
		(end 261.36727 -91.25204)
		(width 0.254)
		(layer "F.Cu")
		(net "GND")
	)
	(segment
		(start 385.985004 -124.504958)
		(end 386.74675 -123.821444)
		(width 0.254)
		(layer "F.Cu")
		(net "GND")
	)
	(segment
		(start 223.600518 -15.423642)
		(end 223.60001 -15.423642)
		(width 0.4064)
		(layer "F.Cu")
		(net "GND")
	)
	(segment
		(start 44.149518 -10.422382)
		(end 44.149518 -9.25195)
		(width 0.4064)
		(layer "F.Cu")
		(net "GND")
	)
	(segment
		(start 119.7991 -142.677896)
		(end 119.7991 -143.492474)
		(width 0.4064)
		(layer "F.Cu")
		(net "GND")
	)
	(segment
		(start 235.49991 -147.27174)
		(end 235.49991 -146.049746)
		(width 0.4064)
		(layer "F.Cu")
		(net "GND")
	)
	(segment
		(start 123.363228 -70.763384)
		(end 123.934728 -70.763384)
		(width 0.254)
		(layer "F.Cu")
		(net "GND")
	)
	(segment
		(start 220.199966 -14.410182)
		(end 219.73794 -13.948156)
		(width 0.4064)
		(layer "F.Cu")
		(net "GND")
	)
	(segment
		(start 397.14805 -108.766356)
		(end 396.65275 -108.99648)
		(width 0.254)
		(layer "F.Cu")
		(net "GND")
	)
	(segment
		(start 414.073086 -7.789672)
		(end 414.073086 -9.552686)
		(width 0.254)
		(layer "F.Cu")
		(net "GND")
	)
	(segment
		(start 113.849404 -9.131046)
		(end 113.897156 -9.083294)
		(width 0.4064)
		(layer "F.Cu")
		(net "GND")
	)
	(segment
		(start 106.193336 -51.941984)
		(end 105.571036 -51.941984)
		(width 0.254)
		(layer "F.Cu")
		(net "GND")
	)
	(segment
		(start 48.399446 -10.422382)
		(end 48.399446 -11.916156)
		(width 0.4064)
		(layer "F.Cu")
		(net "GND")
	)
	(segment
		(start 111.344202 -93.547184)
		(end 111.915702 -93.547184)
		(width 0.1651)
		(layer "F.Cu")
		(net "GND")
	)
	(segment
		(start 299.524166 -98.995738)
		(end 300.095666 -98.995738)
		(width 0.254)
		(layer "F.Cu")
		(net "GND")
	)
	(segment
		(start 77.299566 -152.273)
		(end 77.299566 -152.278842)
		(width 0.508)
		(layer "F.Cu")
		(net "GND")
	)
	(segment
		(start 290.71189 -11.916156)
		(end 290.71189 -12.91971)
		(width 0.4064)
		(layer "F.Cu")
		(net "GND")
	)
	(segment
		(start 301.812706 -95.815404)
		(end 301.812706 -96.023938)
		(width 0.254)
		(layer "F.Cu")
		(net "GND")
	)
	(segment
		(start 290.93922 -93.052138)
		(end 291.51072 -93.052138)
		(width 0.3048)
		(layer "F.Cu")
		(net "GND")
	)
	(segment
		(start 306.392326 -70.059804)
		(end 306.105306 -69.772784)
		(width 0.254)
		(layer "F.Cu")
		(net "GND")
	)
	(segment
		(start 221.04985 -10.422382)
		(end 221.04985 -11.916156)
		(width 0.4064)
		(layer "F.Cu")
		(net "GND")
	)
	(segment
		(start 117.015768 -6.782054)
		(end 117.015768 -7.58952)
		(width 0.3556)
		(layer "F.Cu")
		(net "GND")
	)
	(segment
		(start 446.085468 -143.25981)
		(end 446.129918 -143.21536)
		(width 0.254)
		(layer "F.Cu")
		(net "GND")
	)
	(segment
		(start 72.900286 -52.618386)
		(end 72.328786 -52.618386)
		(width 0.254)
		(layer "F.Cu")
		(net "GND")
	)
	(segment
		(start 129.149348 -16.238474)
		(end 128.690878 -16.696944)
		(width 0.4064)
		(layer "F.Cu")
		(net "GND")
	)
	(segment
		(start 230.396288 -2.3114)
		(end 230.399844 -2.314956)
		(width 0.4064)
		(layer "F.Cu")
		(net "GND")
	)
	(segment
		(start 31.39948 -147.27174)
		(end 31.39948 -145.998946)
		(width 0.4064)
		(layer "F.Cu")
		(net "GND")
	)
	(segment
		(start 144.449546 -0.821182)
		(end 144.449546 -2.276856)
		(width 0.4064)
		(layer "F.Cu")
		(net "GND")
	)
	(segment
		(start 423.090086 -36.134548)
		(end 423.089832 -36.134548)
		(width 0.254)
		(layer "F.Cu")
		(net "GND")
	)
	(segment
		(start 48.399446 -20.023582)
		(end 48.399446 -18.757646)
		(width 0.4064)
		(layer "F.Cu")
		(net "GND")
	)
	(segment
		(start 43.29938 -3.940556)
		(end 43.12158 -3.762756)
		(width 0.4064)
		(layer "F.Cu")
		(net "GND")
	)
	(segment
		(start 70.499478 -20.023582)
		(end 70.499478 -21.479256)
		(width 0.4064)
		(layer "F.Cu")
		(net "GND")
	)
	(segment
		(start 126.599442 -143.400526)
		(end 126.388368 -143.6116)
		(width 0.3556)
		(layer "F.Cu")
		(net "GND")
	)
	(segment
		(start 322.0212 -150.7744)
		(end 322.0212 -150.289768)
		(width 0.508)
		(layer "F.Cu")
		(net "GND")
	)
	(segment
		(start 114.699542 -147.27174)
		(end 114.699542 -147.277582)
		(width 0.4064)
		(layer "F.Cu")
		(net "GND")
	)
	(segment
		(start 52.448968 -154.079194)
		(end 52.471574 -154.1018)
		(width 0.3556)
		(layer "F.Cu")
		(net "GND")
	)
	(segment
		(start 91.739212 -12.824968)
		(end 91.52763 -12.613386)
		(width 0.381)
		(layer "F.Cu")
		(net "GND")
	)
	(segment
		(start 67.949572 -5.822442)
		(end 67.949318 -5.822696)
		(width 0.4064)
		(layer "F.Cu")
		(net "GND")
	)
	(segment
		(start 287.21812 -79.678784)
		(end 286.64662 -79.678784)
		(width 0.254)
		(layer "F.Cu")
		(net "GND")
	)
	(segment
		(start 117.249448 -143.403574)
		(end 117.015768 -143.637254)
		(width 0.3556)
		(layer "F.Cu")
		(net "GND")
	)
	(segment
		(start 243.051838 -89.27084)
		(end 242.480338 -89.27084)
		(width 0.254)
		(layer "F.Cu")
		(net "GND")
	)
	(segment
		(start 439.732166 -50.5206)
		(end 439.732166 -50.51679)
		(width 0.508)
		(layer "F.Cu")
		(net "GND")
	)
	(segment
		(start 131.948174 -82.650584)
		(end 132.519674 -82.650584)
		(width 0.254)
		(layer "F.Cu")
		(net "GND")
	)
	(segment
		(start 133.39953 -10.422382)
		(end 133.39953 -11.916156)
		(width 0.4064)
		(layer "F.Cu")
		(net "GND")
	)
	(segment
		(start 305.533806 -77.697584)
		(end 306.181506 -77.697584)
		(width 0.254)
		(layer "F.Cu")
		(net "GND")
	)
	(segment
		(start 458.14996 -52.974748)
		(end 458.143356 -52.2478)
		(width 0.4064)
		(layer "F.Cu")
		(net "GND")
	)
	(segment
		(start 383.3368 -113.0554)
		(end 382.93675 -112.65535)
		(width 0.12446)
		(layer "F.Cu")
		(net "GND")
	)
	(segment
		(start 305.533806 -98.500184)
		(end 305.533806 -98.708718)
		(width 0.254)
		(layer "F.Cu")
		(net "GND")
	)
	(segment
		(start 74.617326 -91.25204)
		(end 74.045826 -91.25204)
		(width 0.254)
		(layer "F.Cu")
		(net "GND")
	)
	(segment
		(start 483.067614 -138.770614)
		(end 483.616 -138.770614)
		(width 0.254)
		(layer "F.Cu")
		(net "GND")
	)
	(segment
		(start 132.806694 -87.108538)
		(end 133.378194 -87.108538)
		(width 0.254)
		(layer "F.Cu")
		(net "GND")
	)
	(segment
		(start 58.599324 -15.423896)
		(end 58.599324 -17.208246)
		(width 0.4064)
		(layer "F.Cu")
		(net "GND")
	)
	(segment
		(start 243.910104 -97.690686)
		(end 243.338604 -97.690686)
		(width 0.254)
		(layer "F.Cu")
		(net "GND")
	)
	(segment
		(start 42.411396 -139.170156)
		(end 42.449496 -139.132056)
		(width 0.4064)
		(layer "F.Cu")
		(net "GND")
	)
	(segment
		(start 384.307842 -35.72002)
		(end 382.97739 -35.72002)
		(width 0.2032)
		(layer "F.Cu")
		(net "GND")
	)
	(segment
		(start 34.799524 -21.455888)
		(end 34.799524 -20.023582)
		(width 0.4064)
		(layer "F.Cu")
		(net "GND")
	)
	(segment
		(start 294.14978 -14.409928)
		(end 293.688008 -13.948156)
		(width 0.4064)
		(layer "F.Cu")
		(net "GND")
	)
	(segment
		(start 119.371618 -53.8988)
		(end 119.357648 -53.923184)
		(width 0.254)
		(layer "F.Cu")
		(net "GND")
	)
	(segment
		(start 284.071314 -89.089738)
		(end 284.642814 -89.089738)
		(width 0.254)
		(layer "F.Cu")
		(net "GND")
	)
	(segment
		(start 367.0554 -109.601)
		(end 367.1062 -109.5502)
		(width 0.254)
		(layer "F.Cu")
		(net "GND")
	)
	(segment
		(start 396.782798 -156.803598)
		(end 397.212058 -157.232858)
		(width 0.2032)
		(layer "F.Cu")
		(net "GND")
	)
	(segment
		(start 488.7722 -145.542)
		(end 489.379768 -145.542)
		(width 0.254)
		(layer "F.Cu")
		(net "GND")
	)
	(segment
		(start 204.899768 -5.822442)
		(end 204.899768 -7.607046)
		(width 0.4064)
		(layer "F.Cu")
		(net "GND")
	)
	(segment
		(start 117.353842 -91.070938)
		(end 117.925342 -91.070938)
		(width 0.254)
		(layer "F.Cu")
		(net "GND")
	)
	(segment
		(start 136.8298 -103.1748)
		(end 136.8425 -103.1748)
		(width 0.4064)
		(layer "F.Cu")
		(net "GND")
	)
	(segment
		(start 378.985272 -113.015776)
		(end 378.659898 -113.015776)
		(width 0.2286)
		(layer "F.Cu")
		(net "GND")
	)
	(segment
		(start 97.796858 -53.113686)
		(end 97.225358 -53.113686)
		(width 0.254)
		(layer "F.Cu")
		(net "GND")
	)
	(segment
		(start 282.0162 -7.58952)
		(end 282.07208 -7.6454)
		(width 0.3556)
		(layer "F.Cu")
		(net "GND")
	)
	(segment
		(start 291.599874 -143.400526)
		(end 291.3888 -143.6116)
		(width 0.3556)
		(layer "F.Cu")
		(net "GND")
	)
	(segment
		(start 294.999918 -147.27174)
		(end 294.999918 -146.011646)
		(width 0.4064)
		(layer "F.Cu")
		(net "GND")
	)
	(segment
		(start 124.89942 2.092198)
		(end 124.801376 1.994154)
		(width 0.4064)
		(layer "F.Cu")
		(net "GND")
	)
	(segment
		(start 234.65028 -5.822442)
		(end 234.649772 -5.822442)
		(width 0.4064)
		(layer "F.Cu")
		(net "GND")
	)
	(segment
		(start 396.65275 -112.43056)
		(end 396.15745 -112.660684)
		(width 0.254)
		(layer "F.Cu")
		(net "GND")
	)
	(segment
		(start 194.134994 -85.107272)
		(end 193.8528 -84.825078)
		(width 0.254)
		(layer "F.Cu")
		(net "GND")
	)
	(segment
		(start 466.200998 -116.993162)
		(end 466.199982 -116.992908)
		(width 0.4064)
		(layer "F.Cu")
		(net "GND")
	)
	(segment
		(start 400.05 -111.355124)
		(end 400.880072 -111.355124)
		(width 0.254)
		(layer "F.Cu")
		(net "GND")
	)
	(segment
		(start 51.79949 -20.023582)
		(end 51.79949 -21.479256)
		(width 0.4064)
		(layer "F.Cu")
		(net "GND")
	)
	(segment
		(start 119.337328 -13.948156)
		(end 119.799354 -14.410182)
		(width 0.4064)
		(layer "F.Cu")
		(net "GND")
	)
	(segment
		(start 83.202272 -87.28964)
		(end 82.630772 -87.28964)
		(width 0.254)
		(layer "F.Cu")
		(net "GND")
	)
	(segment
		(start 233.800396 -10.422382)
		(end 233.799888 -10.422382)
		(width 0.4064)
		(layer "F.Cu")
		(net "GND")
	)
	(segment
		(start -0.30226 -13.52296)
		(end -0.27432 -13.5509)
		(width 0.254)
		(layer "F.Cu")
		(net "GND")
	)
	(segment
		(start 254.789432 -140.208)
		(end 255.018032 -139.9794)
		(width 0.4064)
		(layer "F.Cu")
		(net "GND")
	)
	(segment
		(start 125.938788 -90.080338)
		(end 126.510288 -90.080338)
		(width 0.254)
		(layer "F.Cu")
		(net "GND")
	)
	(segment
		(start 66.24955 -15.602712)
		(end 66.249296 -15.602966)
		(width 0.4064)
		(layer "F.Cu")
		(net "GND")
	)
	(segment
		(start 115.636802 -88.099138)
		(end 116.208302 -88.099138)
		(width 0.254)
		(layer "F.Cu")
		(net "GND")
	)
	(segment
		(start 238.759238 -69.953886)
		(end 238.187738 -69.953886)
		(width 0.254)
		(layer "F.Cu")
		(net "GND")
	)
	(segment
		(start 316.249812 3.778758)
		(end 316.249812 1.994154)
		(width 0.4064)
		(layer "F.Cu")
		(net "GND")
	)
	(segment
		(start 279.778714 -89.584784)
		(end 280.350214 -89.584784)
		(width 0.254)
		(layer "F.Cu")
		(net "GND")
	)
	(segment
		(start 300.100492 -20.023582)
		(end 300.099984 -20.023582)
		(width 0.4064)
		(layer "F.Cu")
		(net "GND")
	)
	(segment
		(start 245.627144 -55.094886)
		(end 245.055644 -55.094886)
		(width 0.254)
		(layer "F.Cu")
		(net "GND")
	)
	(segment
		(start 310.299862 -133.793738)
		(end 310.0832 -134.0104)
		(width 0.3556)
		(layer "F.Cu")
		(net "GND")
	)
	(segment
		(start 86.636352 -88.28024)
		(end 86.064852 -88.28024)
		(width 0.254)
		(layer "F.Cu")
		(net "GND")
	)
	(segment
		(start 301.800006 -146.06905)
		(end 301.742602 -146.011646)
		(width 0.3556)
		(layer "F.Cu")
		(net "GND")
	)
	(segment
		(start 1.917446 -135.789162)
		(end 1.917446 -135.420354)
		(width 0.254)
		(layer "F.Cu")
		(net "GND")
	)
	(segment
		(start 128.514348 -79.678784)
		(end 129.085848 -79.678784)
		(width 0.254)
		(layer "F.Cu")
		(net "GND")
	)
	(segment
		(start 454.942702 -52.2478)
		(end 454.939908 -51.875944)
		(width 0.4064)
		(layer "F.Cu")
		(net "GND")
	)
	(segment
		(start 128.514348 -60.857384)
		(end 129.085848 -60.857384)
		(width 0.254)
		(layer "F.Cu")
		(net "GND")
	)
	(segment
		(start 241.334798 -70.44944)
		(end 240.763298 -70.44944)
		(width 0.254)
		(layer "F.Cu")
		(net "GND")
	)
	(segment
		(start 240.599722 -15.602966)
		(end 240.599976 -15.602712)
		(width 0.4064)
		(layer "F.Cu")
		(net "GND")
	)
	(segment
		(start 277.397464 -3.3528)
		(end 278.07031 -3.3528)
		(width 0.381)
		(layer "F.Cu")
		(net "GND")
	)
	(segment
		(start 375.482866 -126.165102)
		(end 375.482866 -126.344934)
		(width 0.254)
		(layer "F.Cu")
		(net "GND")
	)
	(segment
		(start 418.6936 -54.3814)
		(end 418.6936 -54.353968)
		(width 0.254)
		(layer "F.Cu")
		(net "GND")
	)
	(segment
		(start 68.799456 -0.821182)
		(end 68.799456 0.457454)
		(width 0.4064)
		(layer "F.Cu")
		(net "GND")
	)
	(segment
		(start 305.199796 -152.278842)
		(end 305.199796 -154.063446)
		(width 0.4064)
		(layer "F.Cu")
		(net "GND")
	)
	(segment
		(start 40.749474 -0.821182)
		(end 40.749474 0.457454)
		(width 0.4064)
		(layer "F.Cu")
		(net "GND")
	)
	(segment
		(start 75.475846 -54.104286)
		(end 74.904346 -54.104286)
		(width 0.254)
		(layer "F.Cu")
		(net "GND")
	)
	(segment
		(start 145.082768 -154.062938)
		(end 145.12163 -154.1018)
		(width 0.3556)
		(layer "F.Cu")
		(net "GND")
	)
	(segment
		(start 395.224 -113.31575)
		(end 395.16685 -113.28908)
		(width 0.254)
		(layer "F.Cu")
		(net "GND")
	)
	(segment
		(start 225.299778 -133.076442)
		(end 225.299778 -134.763002)
		(width 0.4064)
		(layer "F.Cu")
		(net "GND")
	)
	(segment
		(start 302.671226 -91.565984)
		(end 302.099726 -91.565984)
		(width 0.3048)
		(layer "F.Cu")
		(net "GND")
	)
	(segment
		(start 272.910808 -61.847984)
		(end 272.339308 -61.847984)
		(width 0.254)
		(layer "F.Cu")
		(net "GND")
	)
	(segment
		(start 145.29943 -133.0706)
		(end 145.29943 -133.793738)
		(width 0.3556)
		(layer "F.Cu")
		(net "GND")
	)
	(segment
		(start 436.921656 -28.2321)
		(end 437.32196 -28.632404)
		(width 0.3048)
		(layer "F.Cu")
		(net "GND")
	)
	(segment
		(start 134.523734 -74.230738)
		(end 135.095234 -74.23023)
		(width 0.254)
		(layer "F.Cu")
		(net "GND")
	)
	(segment
		(start 290.93922 -90.080338)
		(end 291.51072 -90.080338)
		(width 0.254)
		(layer "F.Cu")
		(net "GND")
	)
	(segment
		(start 64.549274 -153.093674)
		(end 64.090804 -153.552144)
		(width 0.4064)
		(layer "F.Cu")
		(net "GND")
	)
	(segment
		(start 266.231116 -95.709486)
		(end 265.659616 -95.709486)
		(width 0.254)
		(layer "F.Cu")
		(net "GND")
	)
	(segment
		(start 32.249364 -133.0706)
		(end 32.249364 -134.763002)
		(width 0.4064)
		(layer "F.Cu")
		(net "GND")
	)
	(segment
		(start -1.958848 -117.14226)
		(end -1.550416 -117.14226)
		(width 0.254)
		(layer "F.Cu")
		(net "GND")
	)
	(segment
		(start 442.921898 -35.032442)
		(end 444.250064 -35.032442)
		(width 0.3048)
		(layer "F.Cu")
		(net "GND")
	)
	(segment
		(start 283.099764 -10.422382)
		(end 283.099764 -11.854688)
		(width 0.4064)
		(layer "F.Cu")
		(net "GND")
	)
	(segment
		(start 130.231388 -59.866784)
		(end 130.802888 -59.866784)
		(width 0.254)
		(layer "F.Cu")
		(net "GND")
	)
	(segment
		(start 455.800968 -116.993162)
		(end 455.800968 -118.615968)
		(width 0.4064)
		(layer "F.Cu")
		(net "GND")
	)
	(segment
		(start 42.449496 -147.27174)
		(end 42.449496 -146.037046)
		(width 0.4064)
		(layer "F.Cu")
		(net "GND")
	)
	(segment
		(start 376.245882 -101.855016)
		(end 376.335036 -101.855016)
		(width 0.254)
		(layer "F.Cu")
		(net "GND")
	)
	(segment
		(start 21.442426 -85.018626)
		(end 21.442426 -84.455)
		(width 0.254)
		(layer "F.Cu")
		(net "GND")
	)
	(segment
		(start 258.50469 -64.50584)
		(end 257.93319 -64.50584)
		(width 0.254)
		(layer "F.Cu")
		(net "GND")
	)
	(segment
		(start 28.7274 -104.5718)
		(end 28.7274 -105.3338)
		(width 0.4064)
		(layer "F.Cu")
		(net "GND")
	)
	(segment
		(start 237.900718 -74.411586)
		(end 237.329218 -74.411586)
		(width 0.254)
		(layer "F.Cu")
		(net "GND")
	)
	(segment
		(start 131.6609 -52.437538)
		(end 131.661408 -52.43703)
		(width 0.254)
		(layer "F.Cu")
		(net "GND")
	)
	(segment
		(start 449.276978 -4.386072)
		(end 449.276978 -5.464048)
		(width 0.254)
		(layer "F.Cu")
		(net "GND")
	)
	(segment
		(start 127.44958 -146.06905)
		(end 127.392176 -146.011646)
		(width 0.3556)
		(layer "F.Cu")
		(net "GND")
	)
	(segment
		(start 53.499512 -21.455888)
		(end 53.442108 -21.513292)
		(width 0.4064)
		(layer "F.Cu")
		(net "GND")
	)
	(segment
		(start 391.73785 -114.25555)
		(end 391.3378 -114.6556)
		(width 0.254)
		(layer "F.Cu")
		(net "GND")
	)
	(segment
		(start 73.899268 2.963926)
		(end 73.440798 2.505456)
		(width 0.4064)
		(layer "F.Cu")
		(net "GND")
	)
	(segment
		(start 62.849506 -18.81505)
		(end 62.849506 -20.023582)
		(width 0.3556)
		(layer "F.Cu")
		(net "GND")
	)
	(segment
		(start 272.027904 -12.954)
		(end 270.956532 -12.954)
		(width 0.381)
		(layer "F.Cu")
		(net "GND")
	)
	(segment
		(start 255.07061 -91.25204)
		(end 254.49911 -91.25204)
		(width 0.254)
		(layer "F.Cu")
		(net "GND")
	)
	(segment
		(start 83.202272 -58.561986)
		(end 82.630772 -58.561986)
		(width 0.254)
		(layer "F.Cu")
		(net "GND")
	)
	(segment
		(start 241.334798 -83.32724)
		(end 240.763298 -83.32724)
		(width 0.254)
		(layer "F.Cu")
		(net "GND")
	)
	(segment
		(start 113.849404 -15.423642)
		(end 113.849404 -17.193006)
		(width 0.4064)
		(layer "F.Cu")
		(net "GND")
	)
	(segment
		(start 279.700482 -20.023582)
		(end 279.699974 -20.023582)
		(width 0.4064)
		(layer "F.Cu")
		(net "GND")
	)
	(segment
		(start 232.950512 -17.207484)
		(end 232.94975 -17.208246)
		(width 0.4064)
		(layer "F.Cu")
		(net "GND")
	)
	(segment
		(start 50.851308 -17.208246)
		(end 50.949352 -17.110202)
		(width 0.4064)
		(layer "F.Cu")
		(net "GND")
	)
	(segment
		(start 151.257 -26.56586)
		(end 149.7711 -28.05176)
		(width 0.508)
		(layer "F.Cu")
		(net "GND")
	)
	(segment
		(start 31.2674 -53.1368)
		(end 31.2674 -53.452014)
		(width 0.4064)
		(layer "F.Cu")
		(net "GND")
	)
	(segment
		(start 350.0628 -148.773896)
		(end 349.943928 -148.655024)
		(width 0.4064)
		(layer "F.Cu")
		(net "GND")
	)
	(segment
		(start 195.21424 -61.713618)
		(end 195.21424 -61.98997)
		(width 0.508)
		(layer "F.Cu")
		(net "GND")
	)
	(segment
		(start 294.3733 -82.155284)
		(end 294.9448 -82.155284)
		(width 0.254)
		(layer "F.Cu")
		(net "GND")
	)
	(segment
		(start 136.240774 -102.958138)
		(end 136.613138 -102.958138)
		(width 0.4064)
		(layer "F.Cu")
		(net "GND")
	)
	(segment
		(start 442.522356 -28.2321)
		(end 442.522356 -28.26385)
		(width 0.3048)
		(layer "F.Cu")
		(net "GND")
	)
	(segment
		(start 90.871548 -13.292582)
		(end 90.871548 -12.613386)
		(width 0.4064)
		(layer "F.Cu")
		(net "GND")
	)
	(segment
		(start 280.550366 -142.6718)
		(end 280.549858 -142.677642)
		(width 0.4064)
		(layer "F.Cu")
		(net "GND")
	)
	(segment
		(start 14.358112 5.155184)
		(end 14.36116 5.158232)
		(width 0.381)
		(layer "F.Cu")
		(net "GND")
	)
	(segment
		(start 55.199534 -5.822442)
		(end 55.19928 -5.822696)
		(width 0.4064)
		(layer "F.Cu")
		(net "GND")
	)
	(segment
		(start 78.909672 -57.076086)
		(end 78.338172 -57.076086)
		(width 0.254)
		(layer "F.Cu")
		(net "GND")
	)
	(segment
		(start 72.1995 -20.023582)
		(end 72.1995 -21.455888)
		(width 0.4064)
		(layer "F.Cu")
		(net "GND")
	)
	(segment
		(start 124.049536 -9.143746)
		(end 124.049536 -10.422382)
		(width 0.4064)
		(layer "F.Cu")
		(net "GND")
	)
	(segment
		(start 125.711458 -12.91971)
		(end 125.711458 -11.916156)
		(width 0.4064)
		(layer "F.Cu")
		(net "GND")
	)
	(segment
		(start 376.744738 -70.295262)
		(end 376.344942 -70.695058)
		(width 0.254)
		(layer "F.Cu")
		(net "GND")
	)
	(segment
		(start 47.549562 -133.255512)
		(end 47.549308 -133.255766)
		(width 0.4064)
		(layer "F.Cu")
		(net "GND")
	)
	(segment
		(start 300.099984 -2.276856)
		(end 300.061884 -2.314956)
		(width 0.4064)
		(layer "F.Cu")
		(net "GND")
	)
	(segment
		(start 110.485682 -91.070938)
		(end 111.057182 -91.070938)
		(width 0.1016)
		(layer "F.Cu")
		(net "GND")
	)
	(segment
		(start 278.849836 -20.023582)
		(end 278.849836 -21.567648)
		(width 0.4064)
		(layer "F.Cu")
		(net "GND")
	)
	(segment
		(start 203.2 -15.602712)
		(end 203.2 -15.423642)
		(width 0.4064)
		(layer "F.Cu")
		(net "GND")
	)
	(segment
		(start 392.1379 -108.2548)
		(end 391.73785 -108.65485)
		(width 0.12446)
		(layer "F.Cu")
		(net "GND")
	)
	(segment
		(start 296.948606 -94.538038)
		(end 297.520106 -94.538038)
		(width 0.3048)
		(layer "F.Cu")
		(net "GND")
	)
	(segment
		(start 36.499292 3.778504)
		(end 36.499292 2.963926)
		(width 0.4064)
		(layer "F.Cu")
		(net "GND")
	)
	(segment
		(start 126.599442 -16.146526)
		(end 126.599442 -15.423642)
		(width 0.3556)
		(layer "F.Cu")
		(net "GND")
	)
	(segment
		(start 379.885194 -4.389882)
		(end 379.885194 -3.420364)
		(width 0.4572)
		(layer "F.Cu")
		(net "GND")
	)
	(segment
		(start 377.485148 -4.389882)
		(end 377.485148 -3.429)
		(width 0.4572)
		(layer "F.Cu")
		(net "GND")
	)
	(segment
		(start 444.492634 -143.25981)
		(end 446.085468 -143.25981)
		(width 0.254)
		(layer "F.Cu")
		(net "GND")
	)
	(segment
		(start 151.24938 -15.423642)
		(end 151.24938 -17.208246)
		(width 0.4064)
		(layer "F.Cu")
		(net "GND")
	)
	(segment
		(start 386.13715 -114.25555)
		(end 386.5372 -113.8555)
		(width 0.254)
		(layer "F.Cu")
		(net "GND")
	)
	(segment
		(start 235.325158 -84.812886)
		(end 234.753658 -84.812886)
		(width 0.254)
		(layer "F.Cu")
		(net "GND")
	)
	(segment
		(start 478.30486 -17.59839)
		(end 477.863916 -17.59839)
		(width 0.254)
		(layer "F.Cu")
		(net "GND")
	)
	(segment
		(start 239.749838 -18.757646)
		(end 239.749838 -20.023582)
		(width 0.4064)
		(layer "F.Cu")
		(net "GND")
	)
	(segment
		(start 388.11454 -114.63274)
		(end 388.16026 -114.63274)
		(width 0.254)
		(layer "F.Cu")
		(net "GND")
	)
	(segment
		(start 321.65798 -31.15818)
		(end 321.65798 -32.42818)
		(width 0.4572)
		(layer "F.Cu")
		(net "GND")
	)
	(segment
		(start 140.742162 -52.932838)
		(end 141.1478 -52.5272)
		(width 0.254)
		(layer "F.Cu")
		(net "GND")
	)
	(segment
		(start 295.849802 -5.822442)
		(end 295.849802 -3.762756)
		(width 0.4064)
		(layer "F.Cu")
		(net "GND")
	)
	(segment
		(start 244.768624 -82.33664)
		(end 244.197124 -82.33664)
		(width 0.254)
		(layer "F.Cu")
		(net "GND")
	)
	(segment
		(start 82.343752 -54.104286)
		(end 82.630772 -53.60924)
		(width 0.254)
		(layer "F.Cu")
		(net "GND")
	)
	(segment
		(start 135.099552 -11.878056)
		(end 135.061452 -11.916156)
		(width 0.4064)
		(layer "F.Cu")
		(net "GND")
	)
	(segment
		(start 201.500486 -152.273)
		(end 201.499978 -152.278842)
		(width 0.4064)
		(layer "F.Cu")
		(net "GND")
	)
	(segment
		(start 116.399564 -2.276856)
		(end 116.399564 -0.821182)
		(width 0.4064)
		(layer "F.Cu")
		(net "GND")
	)
	(segment
		(start 117.640862 -56.894984)
		(end 118.212362 -56.894984)
		(width 0.254)
		(layer "F.Cu")
		(net "GND")
	)
	(segment
		(start 70.324726 -66.982086)
		(end 69.753226 -66.982086)
		(width 0.254)
		(layer "F.Cu")
		(net "GND")
	)
	(segment
		(start 127.655828 -78.193138)
		(end 128.227328 -78.193138)
		(width 0.254)
		(layer "F.Cu")
		(net "GND")
	)
	(segment
		(start 284.37205 -53.8988)
		(end 284.35808 -53.923184)
		(width 0.254)
		(layer "F.Cu")
		(net "GND")
	)
	(segment
		(start 299.524166 -81.164938)
		(end 300.095666 -81.164938)
		(width 0.254)
		(layer "F.Cu")
		(net "GND")
	)
	(segment
		(start 456.70597 -36.522406)
		(end 457.267056 -36.522406)
		(width 0.254)
		(layer "F.Cu")
		(net "GND")
	)
	(segment
		(start 242.193318 -67.972686)
		(end 241.621818 -67.972686)
		(width 0.254)
		(layer "F.Cu")
		(net "GND")
	)
	(segment
		(start 318.6176 -32.419798)
		(end 318.6176 -31.8516)
		(width 0.254)
		(layer "F.Cu")
		(net "GND")
	)
	(segment
		(start 133.39953 -18.744946)
		(end 133.39953 -20.023582)
		(width 0.4064)
		(layer "F.Cu")
		(net "GND")
	)
	(segment
		(start 3.215386 -15.065756)
		(end 3.215386 -14.645386)
		(width 0.254)
		(layer "F.Cu")
		(net "GND")
	)
	(segment
		(start 28.7274 -67.757802)
		(end 28.7274 -68.367402)
		(width 0.254)
		(layer "F.Cu")
		(net "GND")
	)
	(segment
		(start 226.9998 -142.677642)
		(end 226.9998 -143.408654)
		(width 0.3556)
		(layer "F.Cu")
		(net "GND")
	)
	(segment
		(start 134.249414 -144.364202)
		(end 134.15137 -144.462246)
		(width 0.4064)
		(layer "F.Cu")
		(net "GND")
	)
	(segment
		(start 308.59984 -17.110202)
		(end 308.501796 -17.208246)
		(width 0.4064)
		(layer "F.Cu")
		(net "GND")
	)
	(segment
		(start 13.6398 -78.105)
		(end 14.224 -78.105)
		(width 0.254)
		(layer "F.Cu")
		(net "GND")
	)
	(segment
		(start 390.34466 -109.86262)
		(end 390.5377 -110.05566)
		(width 0.12446)
		(layer "F.Cu")
		(net "GND")
	)
	(segment
		(start 138.024616 -11.938)
		(end 139.34948 -11.916156)
		(width 0.254)
		(layer "F.Cu")
		(net "GND")
	)
	(segment
		(start 377.921266 -126.562866)
		(end 378.079 -126.7206)
		(width 0.254)
		(layer "F.Cu")
		(net "GND")
	)
	(segment
		(start 455.000868 -112.205516)
		(end 455.000868 -113.892584)
		(width 0.4064)
		(layer "F.Cu")
		(net "GND")
	)
	(segment
		(start 313.699906 -156.87294)
		(end 313.699906 -155.612846)
		(width 0.4064)
		(layer "F.Cu")
		(net "GND")
	)
	(segment
		(start 301.241206 -54.418738)
		(end 301.812706 -54.418738)
		(width 0.254)
		(layer "F.Cu")
		(net "GND")
	)
	(segment
		(start 437.721756 -29.8323)
		(end 437.721756 -29.832808)
		(width 0.3048)
		(layer "F.Cu")
		(net "GND")
	)
	(segment
		(start 67.949318 -5.822696)
		(end 67.949318 -7.607046)
		(width 0.4064)
		(layer "F.Cu")
		(net "GND")
	)
	(segment
		(start 449.334128 -51.869086)
		(end 449.334128 -50.759868)
		(width 0.508)
		(layer "F.Cu")
		(net "GND")
	)
	(segment
		(start 277.203154 -91.070938)
		(end 277.774654 -91.070938)
		(width 0.254)
		(layer "F.Cu")
		(net "GND")
	)
	(segment
		(start 385.26085 -102.98684)
		(end 385.7498 -103.251)
		(width 0.254)
		(layer "F.Cu")
		(net "GND")
	)
	(segment
		(start 306.050442 -156.87294)
		(end 306.049934 -156.87294)
		(width 0.4064)
		(layer "F.Cu")
		(net "GND")
	)
	(segment
		(start 121.646188 -79.678784)
		(end 122.217688 -79.678784)
		(width 0.254)
		(layer "F.Cu")
		(net "GND")
	)
	(segment
		(start 304.675286 -58.381138)
		(end 305.246786 -58.381138)
		(width 0.254)
		(layer "F.Cu")
		(net "GND")
	)
	(segment
		(start 442.949838 -53.263038)
		(end 442.948822 -52.451)
		(width 0.4064)
		(layer "F.Cu")
		(net "GND")
	)
	(segment
		(start 197.095364 -54.644544)
		(end 197.095364 -54.248558)
		(width 0.254)
		(layer "F.Cu")
		(net "GND")
	)
	(segment
		(start 202.346306 -2.3114)
		(end 202.349862 -2.314956)
		(width 0.254)
		(layer "F.Cu")
		(net "GND")
	)
	(segment
		(start 80.626712 -83.822286)
		(end 80.055212 -83.822286)
		(width 0.254)
		(layer "F.Cu")
		(net "GND")
	)
	(segment
		(start 7.0104 2.286)
		(end 7.0104 1.050798)
		(width 0.2032)
		(layer "F.Cu")
		(net "GND")
	)
	(segment
		(start 311.15 -2.253488)
		(end 311.092596 -2.310892)
		(width 0.4064)
		(layer "F.Cu")
		(net "GND")
	)
	(segment
		(start 383.73685 -105.45445)
		(end 383.3368 -105.0544)
		(width 0.12446)
		(layer "F.Cu")
		(net "GND")
	)
	(segment
		(start 143.599408 -133.0706)
		(end 143.599408 -134.763002)
		(width 0.4064)
		(layer "F.Cu")
		(net "GND")
	)
	(segment
		(start 383.985008 -124.504958)
		(end 384.76555 -123.821444)
		(width 0.254)
		(layer "F.Cu")
		(net "GND")
	)
	(segment
		(start 251.636784 -71.44004)
		(end 251.065284 -71.44004)
		(width 0.254)
		(layer "F.Cu")
		(net "GND")
	)
	(segment
		(start 120.649492 -9.156446)
		(end 120.649492 -10.422382)
		(width 0.4064)
		(layer "F.Cu")
		(net "GND")
	)
	(segment
		(start 310.299862 -142.677642)
		(end 310.299862 -143.394938)
		(width 0.3556)
		(layer "F.Cu")
		(net "GND")
	)
	(segment
		(start 375.504964 -108.855002)
		(end 376.335036 -108.855002)
		(width 0.254)
		(layer "F.Cu")
		(net "GND")
	)
	(segment
		(start 87.494872 -95.709486)
		(end 86.923372 -95.709486)
		(width 0.254)
		(layer "F.Cu")
		(net "GND")
	)
	(segment
		(start 452.533004 -50.6222)
		(end 452.532242 -50.5206)
		(width 0.508)
		(layer "F.Cu")
		(net "GND")
	)
	(segment
		(start 381.29845 -106.42092)
		(end 381.29845 -105.813098)
		(width 0.254)
		(layer "F.Cu")
		(net "GND")
	)
	(segment
		(start 152.099518 -139.181078)
		(end 152.099518 -140.000482)
		(width 0.4064)
		(layer "F.Cu")
		(net "GND")
	)
	(segment
		(start 309.449978 -10.422382)
		(end 309.449978 -9.156446)
		(width 0.4064)
		(layer "F.Cu")
		(net "GND")
	)
	(segment
		(start 226.149916 -155.612846)
		(end 226.149916 -156.87294)
		(width 0.4064)
		(layer "F.Cu")
		(net "GND")
	)
	(segment
		(start 376.335036 -114.85499)
		(end 376.7328 -114.41557)
		(width 0.254)
		(layer "F.Cu")
		(net "GND")
	)
	(segment
		(start 301.241206 -63.334138)
		(end 300.954186 -63.621158)
		(width 0.254)
		(layer "F.Cu")
		(net "GND")
	)
	(segment
		(start 397.2052 -147.071588)
		(end 398.325848 -148.192236)
		(width 0.254)
		(layer "F.Cu")
		(net "GND")
	)
	(segment
		(start 284.799786 -133.89102)
		(end 284.799532 -133.891274)
		(width 0.3556)
		(layer "F.Cu")
		(net "GND")
	)
	(segment
		(start 315.400436 -156.87294)
		(end 315.399928 -156.87294)
		(width 0.4064)
		(layer "F.Cu")
		(net "GND")
	)
	(segment
		(start 383.73685 -104.65435)
		(end 384.0607 -104.9782)
		(width 0.12446)
		(layer "F.Cu")
		(net "GND")
	)
	(segment
		(start 99.513898 -63.019686)
		(end 98.942398 -63.019686)
		(width 0.254)
		(layer "F.Cu")
		(net "GND")
	)
	(segment
		(start 213.400386 -20.023582)
		(end 213.399878 -20.023582)
		(width 0.4064)
		(layer "F.Cu")
		(net "GND")
	)
	(segment
		(start 358.698292 -140.61567)
		(end 358.698292 -141.529054)
		(width 0.2032)
		(layer "F.Cu")
		(net "GND")
	)
	(segment
		(start 321.693032 -13.108432)
		(end 321.693032 -12.954)
		(width 0.4064)
		(layer "F.Cu")
		(net "GND")
	)
	(segment
		(start 117.015768 -7.58952)
		(end 117.071648 -7.6454)
		(width 0.3556)
		(layer "F.Cu")
		(net "GND")
	)
	(segment
		(start 376.335036 -104.85501)
		(end 376.38736 -105.136188)
		(width 0.254)
		(layer "F.Cu")
		(net "GND")
	)
	(segment
		(start 90.070178 -91.25204)
		(end 89.498678 -91.25204)
		(width 0.254)
		(layer "F.Cu")
		(net "GND")
	)
	(segment
		(start 78.051406 -100.167186)
		(end 77.479906 -100.167186)
		(width 0.254)
		(layer "F.Cu")
		(net "GND")
	)
	(segment
		(start 120.649492 -20.023582)
		(end 120.649492 -18.757646)
		(width 0.4064)
		(layer "F.Cu")
		(net "GND")
	)
	(segment
		(start 83.202272 -76.39304)
		(end 82.630772 -76.39304)
		(width 0.254)
		(layer "F.Cu")
		(net "GND")
	)
	(segment
		(start 421.59936 -106.43108)
		(end 421.59936 -107.01528)
		(width 0.254)
		(layer "F.Cu")
		(net "GND")
	)
	(segment
		(start 58.599578 -152.273)
		(end 58.599578 -152.278842)
		(width 0.4064)
		(layer "F.Cu")
		(net "GND")
	)
	(segment
		(start 74.749406 -0.821182)
		(end 74.749406 -2.314956)
		(width 0.4064)
		(layer "F.Cu")
		(net "GND")
	)
	(segment
		(start 140.246354 -55.409338)
		(end 139.674854 -55.409338)
		(width 0.254)
		(layer "F.Cu")
		(net "GND")
	)
	(segment
		(start 251.636784 -61.53404)
		(end 251.065284 -61.53404)
		(width 0.254)
		(layer "F.Cu")
		(net "GND")
	)
	(segment
		(start 41.599358 2.092198)
		(end 41.501314 1.994154)
		(width 0.4064)
		(layer "F.Cu")
		(net "GND")
	)
	(segment
		(start 240.476278 -84.812886)
		(end 239.904778 -84.812886)
		(width 0.254)
		(layer "F.Cu")
		(net "GND")
	)
	(segment
		(start 379.093476 -124.3965)
		(end 378.985018 -124.504958)
		(width 0.254)
		(layer "F.Cu")
		(net "GND")
	)
	(segment
		(start 302.958246 -91.070938)
		(end 302.958246 -91.278964)
		(width 0.254)
		(layer "F.Cu")
		(net "GND")
	)
	(segment
		(start 347.3196 -148.766784)
		(end 347.62567 -148.460714)
		(width 0.4064)
		(layer "F.Cu")
		(net "GND")
	)
	(segment
		(start 33.754568 1.972818)
		(end 33.771586 1.9558)
		(width 0.3556)
		(layer "F.Cu")
		(net "GND")
	)
	(segment
		(start 38.199568 -152.273)
		(end 38.199568 -152.457912)
		(width 0.4064)
		(layer "F.Cu")
		(net "GND")
	)
	(segment
		(start 147.849336 -133.0706)
		(end 147.849336 -133.891274)
		(width 0.4064)
		(layer "F.Cu")
		(net "GND")
	)
	(segment
		(start 404.471886 -9.522714)
		(end 404.4188 -9.5758)
		(width 0.254)
		(layer "F.Cu")
		(net "GND")
	)
	(segment
		(start 232.100374 -10.422382)
		(end 232.099866 -10.422382)
		(width 0.4064)
		(layer "F.Cu")
		(net "GND")
	)
	(segment
		(start 349.292164 -147.689062)
		(end 349.292164 -148.098764)
		(width 0.254)
		(layer "F.Cu")
		(net "GND")
	)
	(segment
		(start 174.9044 -92.7354)
		(end 174.9044 -93.0656)
		(width 0.254)
		(layer "F.Cu")
		(net "GND")
	)
	(segment
		(start 66.24955 -152.457912)
		(end 66.249296 -152.458166)
		(width 0.4064)
		(layer "F.Cu")
		(net "GND")
	)
	(segment
		(start 354.36048 -133.557772)
		(end 354.477574 -133.440678)
		(width 0.508)
		(layer "F.Cu")
		(net "GND")
	)
	(segment
		(start 233.799888 -137.67054)
		(end 233.799888 -136.397746)
		(width 0.4064)
		(layer "F.Cu")
		(net "GND")
	)
	(segment
		(start 36.499292 -6.637274)
		(end 36.499292 -5.822696)
		(width 0.4064)
		(layer "F.Cu")
		(net "GND")
	)
	(segment
		(start 392.121644 -73.605644)
		(end 392.303 -73.787)
		(width 0.508)
		(layer "F.Cu")
		(net "GND")
	)
	(segment
		(start 285.649924 0.444754)
		(end 285.649924 -0.821182)
		(width 0.4064)
		(layer "F.Cu")
		(net "GND")
	)
	(segment
		(start 141.963648 -97.0026)
		(end 142.02791 -97.0026)
		(width 0.254)
		(layer "F.Cu")
		(net "GND")
	)
	(segment
		(start 136.8425 -103.1748)
		(end 136.8425 -103.1621)
		(width 0.4064)
		(layer "F.Cu")
		(net "GND")
	)
	(segment
		(start 306.049934 -20.023582)
		(end 306.049934 -21.517356)
		(width 0.4064)
		(layer "F.Cu")
		(net "GND")
	)
	(segment
		(start 483.540562 -34.822638)
		(end 482.7778 -35.5854)
		(width 0.254)
		(layer "F.Cu")
		(net "GND")
	)
	(segment
		(start 43.076368 -17.201388)
		(end 43.076368 -16.382746)
		(width 0.3556)
		(layer "F.Cu")
		(net "GND")
	)
	(segment
		(start 124.221748 -95.033084)
		(end 124.793248 -95.033084)
		(width 0.3048)
		(layer "F.Cu")
		(net "GND")
	)
	(segment
		(start 75.59929 -6.001766)
		(end 75.59929 -7.607046)
		(width 0.4064)
		(layer "F.Cu")
		(net "GND")
	)
	(segment
		(start 278.061674 -58.876438)
		(end 277.490174 -58.876438)
		(width 0.254)
		(layer "F.Cu")
		(net "GND")
	)
	(segment
		(start 64.549528 -133.076442)
		(end 64.549274 -133.076696)
		(width 0.4064)
		(layer "F.Cu")
		(net "GND")
	)
	(segment
		(start 113.919762 -98.005138)
		(end 114.491262 -98.005138)
		(width 0.254)
		(layer "F.Cu")
		(net "GND")
	)
	(segment
		(start 273.769328 -102.958138)
		(end 273.769328 -103.5812)
		(width 0.254)
		(layer "F.Cu")
		(net "GND")
	)
	(segment
		(start 442.122052 -26.232104)
		(end 442.122052 -26.232612)
		(width 0.3048)
		(layer "F.Cu")
		(net "GND")
	)
	(segment
		(start 198.755 -153.1874)
		(end 198.755 -154.084782)
		(width 0.3556)
		(layer "F.Cu")
		(net "GND")
	)
	(segment
		(start 125.938788 -99.986338)
		(end 126.510288 -99.986338)
		(width 0.254)
		(layer "F.Cu")
		(net "GND")
	)
	(segment
		(start 37.34943 -137.67054)
		(end 37.34943 -136.410446)
		(width 0.4064)
		(layer "F.Cu")
		(net "GND")
	)
	(segment
		(start 381.313944 -105.813098)
		(end 381.313944 -105.815384)
		(width 0.254)
		(layer "F.Cu")
		(net "GND")
	)
	(segment
		(start 209.150458 -137.67054)
		(end 209.14995 -137.67054)
		(width 0.4064)
		(layer "F.Cu")
		(net "GND")
	)
	(segment
		(start 254.212344 -53.113686)
		(end 254.212344 -53.322474)
		(width 0.254)
		(layer "F.Cu")
		(net "GND")
	)
	(segment
		(start 197.249796 -5.822442)
		(end 197.249796 -7.509002)
		(width 0.4064)
		(layer "F.Cu")
		(net "GND")
	)
	(segment
		(start 240.600484 -3.763518)
		(end 240.599722 -3.762756)
		(width 0.4064)
		(layer "F.Cu")
		(net "GND")
	)
	(segment
		(start 300.736 -16.382746)
		(end 300.949868 -16.168878)
		(width 0.3556)
		(layer "F.Cu")
		(net "GND")
	)
	(segment
		(start 242.7478 -25.6032)
		(end 242.287044 -25.142444)
		(width 0.4064)
		(layer "F.Cu")
		(net "GND")
	)
	(segment
		(start 309.449978 -156.87294)
		(end 309.450486 -156.87294)
		(width 0.4064)
		(layer "F.Cu")
		(net "GND")
	)
	(segment
		(start 123.363228 -78.688438)
		(end 123.934728 -78.688438)
		(width 0.254)
		(layer "F.Cu")
		(net "GND")
	)
	(segment
		(start 387.73735 -104.65435)
		(end 388.030212 -104.361488)
		(width 0.12446)
		(layer "F.Cu")
		(net "GND")
	)
	(segment
		(start 223.600518 -133.0706)
		(end 223.60001 -133.076442)
		(width 0.4064)
		(layer "F.Cu")
		(net "GND")
	)
	(segment
		(start 237.20044 -0.821182)
		(end 237.199932 -0.821182)
		(width 0.4064)
		(layer "F.Cu")
		(net "GND")
	)
	(segment
		(start 419.490144 -30.93466)
		(end 419.090094 -31.33471)
		(width 0.254)
		(layer "F.Cu")
		(net "GND")
	)
	(segment
		(start 287.50514 -66.305938)
		(end 286.93364 -66.305938)
		(width 0.254)
		(layer "F.Cu")
		(net "GND")
	)
	(segment
		(start 195.24218 -52.59578)
		(end 194.804538 -52.59578)
		(width 0.4064)
		(layer "F.Cu")
		(net "GND")
	)
	(segment
		(start 378.606558 -124.504958)
		(end 378.985018 -124.504958)
		(width 0.254)
		(layer "F.Cu")
		(net "GND")
	)
	(segment
		(start 116.495322 -58.876438)
		(end 115.923822 -58.876438)
		(width 0.254)
		(layer "F.Cu")
		(net "GND")
	)
	(segment
		(start 60.299346 -15.423642)
		(end 60.299346 -13.427456)
		(width 0.4064)
		(layer "F.Cu")
		(net "GND")
	)
	(segment
		(start 285.649924 -137.67054)
		(end 285.649924 -136.410446)
		(width 0.4064)
		(layer "F.Cu")
		(net "GND")
	)
	(segment
		(start 251.636784 -67.47764)
		(end 251.065284 -67.47764)
		(width 0.254)
		(layer "F.Cu")
		(net "GND")
	)
	(segment
		(start 235.325158 -55.094886)
		(end 234.753658 -55.094886)
		(width 0.3048)
		(layer "F.Cu")
		(net "GND")
	)
	(segment
		(start 307.250846 -69.772784)
		(end 307.898546 -69.772784)
		(width 0.254)
		(layer "F.Cu")
		(net "GND")
	)
	(segment
		(start 293.51478 -56.894984)
		(end 294.08628 -56.894984)
		(width 0.254)
		(layer "F.Cu")
		(net "GND")
	)
	(segment
		(start 106.193336 -56.894984)
		(end 105.571036 -56.894984)
		(width 0.254)
		(layer "F.Cu")
		(net "GND")
	)
	(segment
		(start 294.3733 -61.352938)
		(end 294.9448 -61.352938)
		(width 0.254)
		(layer "F.Cu")
		(net "GND")
	)
	(segment
		(start 40.749474 -10.422382)
		(end 40.749474 -11.916156)
		(width 0.4064)
		(layer "F.Cu")
		(net "GND")
	)
	(segment
		(start 144.449546 -137.67054)
		(end 144.449546 -136.410446)
		(width 0.4064)
		(layer "F.Cu")
		(net "GND")
	)
	(segment
		(start 241.44986 -137.67054)
		(end 241.44986 -136.410446)
		(width 0.4064)
		(layer "F.Cu")
		(net "GND")
	)
	(segment
		(start 77.299566 -13.36421)
		(end 77.299566 -15.423642)
		(width 0.4064)
		(layer "F.Cu")
		(net "GND")
	)
	(segment
		(start 226.9998 -153.009854)
		(end 226.7966 -153.213054)
		(width 0.3556)
		(layer "F.Cu")
		(net "GND")
	)
	(segment
		(start 289.049968 -10.422382)
		(end 289.049968 -11.916156)
		(width 0.4064)
		(layer "F.Cu")
		(net "GND")
	)
	(segment
		(start 256.667 -140.1318)
		(end 256.364994 -139.829794)
		(width 0.4064)
		(layer "F.Cu")
		(net "GND")
	)
	(segment
		(start 244.768624 -74.411586)
		(end 244.197124 -74.411586)
		(width 0.254)
		(layer "F.Cu")
		(net "GND")
	)
	(segment
		(start 216.80043 -137.67054)
		(end 216.799922 -137.67054)
		(width 0.4064)
		(layer "F.Cu")
		(net "GND")
	)
	(segment
		(start 262.79729 -63.019686)
		(end 262.22579 -63.019686)
		(width 0.254)
		(layer "F.Cu")
		(net "GND")
	)
	(segment
		(start 33.771586 -7.6454)
		(end 33.754568 -7.628382)
		(width 0.3556)
		(layer "F.Cu")
		(net "GND")
	)
	(segment
		(start 196.469 -3.321812)
		(end 196.884544 -3.737356)
		(width 0.4064)
		(layer "F.Cu")
		(net "GND")
	)
	(segment
		(start 113.849404 -7.1374)
		(end 113.849404 -5.822442)
		(width 0.4064)
		(layer "F.Cu")
		(net "GND")
	)
	(segment
		(start 305.199796 -133.076442)
		(end 305.199796 -134.861046)
		(width 0.4064)
		(layer "F.Cu")
		(net "GND")
	)
	(segment
		(start 234.649772 -133.076442)
		(end 234.649772 -134.763002)
		(width 0.4064)
		(layer "F.Cu")
		(net "GND")
	)
	(segment
		(start 218.500452 -147.27174)
		(end 218.499944 -147.27174)
		(width 0.3556)
		(layer "F.Cu")
		(net "GND")
	)
	(segment
		(start 68.607686 -65.991486)
		(end 68.036186 -65.991486)
		(width 0.254)
		(layer "F.Cu")
		(net "GND")
	)
	(segment
		(start 402.203412 -124.639832)
		(end 403.106382 -124.639832)
		(width 0.254)
		(layer "F.Cu")
		(net "GND")
	)
	(segment
		(start 203.2 -15.423642)
		(end 203.2 -13.36421)
		(width 0.4064)
		(layer "F.Cu")
		(net "GND")
	)
	(segment
		(start 398.63395 -106.190796)
		(end 399.634964 -105.855008)
		(width 0.254)
		(layer "F.Cu")
		(net "GND")
	)
	(segment
		(start 67.749166 -53.60924)
		(end 68.11264 -53.60924)
		(width 0.254)
		(layer "F.Cu")
		(net "GND")
	)
	(segment
		(start 261.747 -127.966978)
		(end 261.747 -128.462024)
		(width 0.4064)
		(layer "F.Cu")
		(net "GND")
	)
	(segment
		(start 277.397464 -149.8092)
		(end 277.9268 -149.8092)
		(width 0.4064)
		(layer "F.Cu")
		(net "GND")
	)
	(segment
		(start 415.191194 -121.740422)
		(end 414.34639 -121.740422)
		(width 0.254)
		(layer "F.Cu")
		(net "GND")
	)
	(segment
		(start 61.999368 -16.154654)
		(end 61.999368 -15.423642)
		(width 0.3556)
		(layer "F.Cu")
		(net "GND")
	)
	(segment
		(start 280.550366 -152.273)
		(end 280.549858 -152.278842)
		(width 0.4064)
		(layer "F.Cu")
		(net "GND")
	)
	(segment
		(start 300.382686 -51.941984)
		(end 300.954186 -51.941984)
		(width 0.254)
		(layer "F.Cu")
		(net "GND")
	)
	(segment
		(start 43.076368 -144.455388)
		(end 43.12158 -144.5006)
		(width 0.3556)
		(layer "F.Cu")
		(net "GND")
	)
	(segment
		(start 415.673286 -3.050286)
		(end 415.673286 -4.386072)
		(width 0.254)
		(layer "F.Cu")
		(net "GND")
	)
	(segment
		(start 230.400352 -10.422382)
		(end 230.399844 -10.422382)
		(width 0.4064)
		(layer "F.Cu")
		(net "GND")
	)
	(segment
		(start 451.800976 -112.205516)
		(end 451.800976 -113.816384)
		(width 0.4064)
		(layer "F.Cu")
		(net "GND")
	)
	(segment
		(start 445.339978 -51.875944)
		(end 445.340994 -51.875944)
		(width 0.4064)
		(layer "F.Cu")
		(net "GND")
	)
	(segment
		(start 446.1764 -50.4952)
		(end 446.141094 -50.61204)
		(width 0.4064)
		(layer "F.Cu")
		(net "GND")
	)
	(segment
		(start 416.690048 -32.934656)
		(end 416.289998 -33.334706)
		(width 0.254)
		(layer "F.Cu")
		(net "GND")
	)
	(segment
		(start 121.900442 -52.380896)
		(end 121.933208 -52.437538)
		(width 0.254)
		(layer "F.Cu")
		(net "GND")
	)
	(segment
		(start 311.150508 -20.023582)
		(end 311.15 -20.023582)
		(width 0.3556)
		(layer "F.Cu")
		(net "GND")
	)
	(segment
		(start 276.916134 -100.48113)
		(end 276.4663 -101.261164)
		(width 0.254)
		(layer "F.Cu")
		(net "GND")
	)
	(segment
		(start 339.471 -22.833584)
		(end 339.5726 -22.833584)
		(width 0.4064)
		(layer "F.Cu")
		(net "GND")
	)
	(segment
		(start 260.50875 -63.019686)
		(end 261.08025 -63.019686)
		(width 0.254)
		(layer "F.Cu")
		(net "GND")
	)
	(segment
		(start 137.957814 -84.136738)
		(end 138.529314 -84.136738)
		(width 0.254)
		(layer "F.Cu")
		(net "GND")
	)
	(segment
		(start 209.150458 -20.023582)
		(end 209.14995 -20.023582)
		(width 0.4064)
		(layer "F.Cu")
		(net "GND")
	)
	(segment
		(start 85.777832 -99.67214)
		(end 86.636352 -99.17684)
		(width 0.254)
		(layer "F.Cu")
		(net "GND")
	)
	(segment
		(start 81.485232 -96.20504)
		(end 80.913732 -96.20504)
		(width 0.254)
		(layer "F.Cu")
		(net "GND")
	)
	(segment
		(start 77.192886 -98.681286)
		(end 76.621386 -98.681286)
		(width 0.254)
		(layer "F.Cu")
		(net "GND")
	)
	(segment
		(start 285.649924 -147.27174)
		(end 285.649924 -146.011646)
		(width 0.4064)
		(layer "F.Cu")
		(net "GND")
	)
	(segment
		(start 401.391882 -83.6549)
		(end 401.3581 -83.688682)
		(width 0.254)
		(layer "F.Cu")
		(net "GND")
	)
	(segment
		(start 53.499512 -2.253488)
		(end 53.499512 -0.821182)
		(width 0.4064)
		(layer "F.Cu")
		(net "GND")
	)
	(segment
		(start 374.171972 -96.791272)
		(end 374.06072 -96.68002)
		(width 0.254)
		(layer "F.Cu")
		(net "GND")
	)
	(segment
		(start 387.3373 -112.2553)
		(end 386.93725 -111.85525)
		(width 0.1143)
		(layer "F.Cu")
		(net "GND")
	)
	(segment
		(start 216.799922 -10.422382)
		(end 216.799922 -11.878056)
		(width 0.4064)
		(layer "F.Cu")
		(net "GND")
	)
	(segment
		(start 34.799524 -11.854688)
		(end 34.799524 -10.422382)
		(width 0.4064)
		(layer "F.Cu")
		(net "GND")
	)
	(segment
		(start 498.449854 -127.210566)
		(end 497.652294 -127.210566)
		(width 0.508)
		(layer "F.Cu")
		(net "GND")
	)
	(segment
		(start 376.335036 -96.855026)
		(end 376.428 -97.354898)
		(width 0.254)
		(layer "F.Cu")
		(net "GND")
	)
	(segment
		(start 449.349876 -53.262276)
		(end 449.34886 -52.451)
		(width 0.4064)
		(layer "F.Cu")
		(net "GND")
	)
	(segment
		(start 300.382686 -59.866784)
		(end 300.954186 -59.866784)
		(width 0.254)
		(layer "F.Cu")
		(net "GND")
	)
	(segment
		(start 419.1762 -49.463198)
		(end 419.316408 -49.32299)
		(width 0.254)
		(layer "F.Cu")
		(net "GND")
	)
	(segment
		(start 288.19983 -17.208246)
		(end 288.19983 -15.423642)
		(width 0.4064)
		(layer "F.Cu")
		(net "GND")
	)
	(segment
		(start 115.549426 3.778758)
		(end 115.549426 2.092198)
		(width 0.4064)
		(layer "F.Cu")
		(net "GND")
	)
	(segment
		(start 413.490156 -43.334686)
		(end 413.490156 -42.534586)
		(width 0.254)
		(layer "F.Cu")
		(net "GND")
	)
	(segment
		(start 72.900286 -80.35544)
		(end 72.328786 -80.35544)
		(width 0.254)
		(layer "F.Cu")
		(net "GND")
	)
	(segment
		(start 1.27 -119.126)
		(end 1.27 -118.959376)
		(width 0.254)
		(layer "F.Cu")
		(net "GND")
	)
	(segment
		(start 71.183246 -58.561986)
		(end 70.611746 -58.561986)
		(width 0.254)
		(layer "F.Cu")
		(net "GND")
	)
	(segment
		(start 121.499376 -133.0706)
		(end 121.499376 -134.861046)
		(width 0.3556)
		(layer "F.Cu")
		(net "GND")
	)
	(segment
		(start 109.728 -67.691)
		(end 109.728 -68.072)
		(width 0.254)
		(layer "F.Cu")
		(net "GND")
	)
	(segment
		(start 409.272486 -7.789672)
		(end 409.272486 -9.256014)
		(width 0.254)
		(layer "F.Cu")
		(net "GND")
	)
	(segment
		(start 191.349122 -149.778212)
		(end 191.349122 -148.842222)
		(width 0.254)
		(layer "F.Cu")
		(net "GND")
	)
	(segment
		(start 251.636784 -64.50584)
		(end 251.065284 -64.50584)
		(width 0.254)
		(layer "F.Cu")
		(net "GND")
	)
	(segment
		(start 230.400352 -0.821182)
		(end 230.399844 -0.821182)
		(width 0.4064)
		(layer "F.Cu")
		(net "GND")
	)
	(segment
		(start 291.599874 -16.146526)
		(end 291.599874 -15.423642)
		(width 0.3556)
		(layer "F.Cu")
		(net "GND")
	)
	(segment
		(start 138.816334 -100.481638)
		(end 138.816334 -100.689664)
		(width 0.4064)
		(layer "F.Cu")
		(net "GND")
	)
	(segment
		(start 31.39948 -18.744946)
		(end 31.39948 -20.023582)
		(width 0.4064)
		(layer "F.Cu")
		(net "GND")
	)
	(segment
		(start 413.490156 -43.334686)
		(end 413.511492 -43.356022)
		(width 0.254)
		(layer "F.Cu")
		(net "GND")
	)
	(segment
		(start 202.349862 -21.517356)
		(end 202.349862 -20.023582)
		(width 0.4064)
		(layer "F.Cu")
		(net "GND")
	)
	(segment
		(start 135.061452 -11.916156)
		(end 135.061452 -12.993116)
		(width 0.4064)
		(layer "F.Cu")
		(net "GND")
	)
	(segment
		(start 242.287044 -25.142444)
		(end 242.287044 -22.965156)
		(width 0.4064)
		(layer "F.Cu")
		(net "GND")
	)
	(segment
		(start 67.749166 -64.50584)
		(end 67.101466 -64.50584)
		(width 0.254)
		(layer "F.Cu")
		(net "GND")
	)
	(segment
		(start 209.092546 -146.049746)
		(end 209.092546 -145.998946)
		(width 0.4064)
		(layer "F.Cu")
		(net "GND")
	)
	(segment
		(start 150.399496 -2.314956)
		(end 150.399496 -0.821182)
		(width 0.4064)
		(layer "F.Cu")
		(net "GND")
	)
	(segment
		(start 243.910104 -59.057286)
		(end 243.338604 -59.057286)
		(width 0.254)
		(layer "F.Cu")
		(net "GND")
	)
	(segment
		(start 212.549994 -152.278842)
		(end 212.549994 -152.457912)
		(width 0.4064)
		(layer "F.Cu")
		(net "GND")
	)
	(segment
		(start 364.604554 -107.462066)
		(end 364.611666 -107.469178)
		(width 0.254)
		(layer "F.Cu")
		(net "GND")
	)
	(segment
		(start 113.061242 -102.462584)
		(end 112.774222 -101.967538)
		(width 0.254)
		(layer "F.Cu")
		(net "GND")
	)
	(segment
		(start 74.045826 -101.15804)
		(end 74.617326 -101.15804)
		(width 0.254)
		(layer "F.Cu")
		(net "GND")
	)
	(segment
		(start 278.348948 -52.4383)
		(end 278.348694 -52.437284)
		(width 0.254)
		(layer "F.Cu")
		(net "GND")
	)
	(segment
		(start 445.236854 -23.292054)
		(end 445.53378 -23.58898)
		(width 0.254)
		(layer "F.Cu")
		(net "GND")
	)
	(segment
		(start 279.699974 -137.676382)
		(end 279.699974 -137.67054)
		(width 0.4064)
		(layer "F.Cu")
		(net "GND")
	)
	(segment
		(start 127.44958 -9.21385)
		(end 127.392176 -9.156446)
		(width 0.3556)
		(layer "F.Cu")
		(net "GND")
	)
	(segment
		(start 348.774512 -2.219198)
		(end 348.739206 -2.254504)
		(width 0.508)
		(layer "F.Cu")
		(net "GND")
	)
	(segment
		(start 100.372164 -63.51524)
		(end 99.800664 -63.51524)
		(width 0.254)
		(layer "F.Cu")
		(net "GND")
	)
	(segment
		(start 235.49991 -11.878056)
		(end 235.49991 -10.422382)
		(width 0.4064)
		(layer "F.Cu")
		(net "GND")
	)
	(segment
		(start 115.636802 -91.070938)
		(end 116.208302 -91.070938)
		(width 0.254)
		(layer "F.Cu")
		(net "GND")
	)
	(segment
		(start 121.499376 -7.607046)
		(end 121.499376 -5.822442)
		(width 0.4064)
		(layer "F.Cu")
		(net "GND")
	)
	(segment
		(start 72.041766 -95.709486)
		(end 71.470266 -95.709486)
		(width 0.254)
		(layer "F.Cu")
		(net "GND")
	)
	(segment
		(start 307.749956 -155.600146)
		(end 307.749956 -156.87294)
		(width 0.4064)
		(layer "F.Cu")
		(net "GND")
	)
	(segment
		(start 389.71855 -123.821444)
		(end 389.86841 -124.206)
		(width 0.254)
		(layer "F.Cu")
		(net "GND")
	)
	(segment
		(start 199.742552 -155.825698)
		(end 199.742552 -155.600146)
		(width 0.4064)
		(layer "F.Cu")
		(net "GND")
	)
	(segment
		(start 279.778714 -62.838584)
		(end 279.207214 -62.838584)
		(width 0.254)
		(layer "F.Cu")
		(net "GND")
	)
	(segment
		(start 291.79774 -62.838584)
		(end 292.36924 -62.838584)
		(width 0.254)
		(layer "F.Cu")
		(net "GND")
	)
	(segment
		(start 261.747 -24.638)
		(end 262.3566 -25.2476)
		(width 0.4064)
		(layer "F.Cu")
		(net "GND")
	)
	(segment
		(start 297.520106 -52.932838)
		(end 296.948606 -52.932838)
		(width 0.254)
		(layer "F.Cu")
		(net "GND")
	)
	(segment
		(start 465.680552 -46.009052)
		(end 466.141054 -46.469554)
		(width 0.4064)
		(layer "F.Cu")
		(net "GND")
	)
	(segment
		(start 390.70915 -101.039676)
		(end 390.21385 -101.2698)
		(width 0.254)
		(layer "F.Cu")
		(net "GND")
	)
	(segment
		(start 122.217688 -96.518984)
		(end 121.646188 -96.518984)
		(width 0.254)
		(layer "F.Cu")
		(net "GND")
	)
	(segment
		(start 437.32196 -25.432004)
		(end 437.32196 -25.432512)
		(width 0.3048)
		(layer "F.Cu")
		(net "GND")
	)
	(segment
		(start 278.849836 -152.273)
		(end 278.849836 -152.278842)
		(width 0.508)
		(layer "F.Cu")
		(net "GND")
	)
	(segment
		(start 197.160896 -3.737356)
		(end 197.249796 -3.826256)
		(width 0.4064)
		(layer "F.Cu")
		(net "GND")
	)
	(segment
		(start 85.206332 -55.094886)
		(end 85.777832 -55.094886)
		(width 0.254)
		(layer "F.Cu")
		(net "GND")
	)
	(segment
		(start 472.6178 -43.390312)
		(end 472.6178 -42.0624)
		(width 0.254)
		(layer "F.Cu")
		(net "GND")
	)
	(segment
		(start 148.699474 -137.67054)
		(end 148.699474 -136.410446)
		(width 0.4064)
		(layer "F.Cu")
		(net "GND")
	)
	(segment
		(start 233.608118 -86.794086)
		(end 233.036618 -86.794086)
		(width 0.254)
		(layer "F.Cu")
		(net "GND")
	)
	(segment
		(start 73.758806 -92.737686)
		(end 73.187306 -92.737686)
		(width 0.254)
		(layer "F.Cu")
		(net "GND")
	)
	(segment
		(start 305.246786 -58.381138)
		(end 306.392326 -58.381138)
		(width 0.254)
		(layer "F.Cu")
		(net "GND")
	)
	(segment
		(start 243.051838 -96.20504)
		(end 242.480338 -96.20504)
		(width 0.254)
		(layer "F.Cu")
		(net "GND")
	)
	(segment
		(start 321.611244 -3.321812)
		(end 322.5038 -3.321812)
		(width 0.4064)
		(layer "F.Cu")
		(net "GND")
	)
	(segment
		(start 400.05 -111.355124)
		(end 399.634964 -111.854996)
		(width 0.254)
		(layer "F.Cu")
		(net "GND")
	)
	(segment
		(start 214.250524 -15.423642)
		(end 214.250524 -17.207484)
		(width 0.4064)
		(layer "F.Cu")
		(net "GND")
	)
	(segment
		(start 2.140458 -135.192262)
		(end 2.145538 -135.192262)
		(width 0.254)
		(layer "F.Cu")
		(net "GND")
	)
	(segment
		(start 195.549774 -143.946626)
		(end 195.5038 -143.9926)
		(width 0.4064)
		(layer "F.Cu")
		(net "GND")
	)
	(segment
		(start 236.1184 -17.193006)
		(end 236.1184 -16.383)
		(width 0.3556)
		(layer "F.Cu")
		(net "GND")
	)
	(segment
		(start 32.094932 -79.028544)
		(end 32.094932 -78.635352)
		(width 0.254)
		(layer "F.Cu")
		(net "GND")
	)
	(segment
		(start 419.890194 -34.534602)
		(end 420.288212 -34.93262)
		(width 0.254)
		(layer "F.Cu")
		(net "GND")
	)
	(segment
		(start 21.2725 -67.8053)
		(end 21.1582 -67.9196)
		(width 0.254)
		(layer "F.Cu")
		(net "GND")
	)
	(segment
		(start 401.295108 -94.352872)
		(end 401.521168 -94.352872)
		(width 0.254)
		(layer "F.Cu")
		(net "GND")
	)
	(segment
		(start 386.644388 -109.162088)
		(end 386.93725 -109.45495)
		(width 0.12446)
		(layer "F.Cu")
		(net "GND")
	)
	(segment
		(start 284.071314 -67.296538)
		(end 283.499814 -67.296538)
		(width 0.254)
		(layer "F.Cu")
		(net "GND")
	)
	(segment
		(start 22.4155 -67.8053)
		(end 22.459188 -67.848988)
		(width 0.254)
		(layer "F.Cu")
		(net "GND")
	)
	(segment
		(start 294.3733 -80.174338)
		(end 294.9448 -80.174338)
		(width 0.254)
		(layer "F.Cu")
		(net "GND")
	)
	(segment
		(start 38.199314 3.599434)
		(end 38.199314 1.994154)
		(width 0.4064)
		(layer "F.Cu")
		(net "GND")
	)
	(segment
		(start 32.249364 -142.6718)
		(end 32.249364 -144.364202)
		(width 0.4064)
		(layer "F.Cu")
		(net "GND")
	)
	(segment
		(start 396.984982 -126.165102)
		(end 397.4084 -126.58852)
		(width 0.254)
		(layer "F.Cu")
		(net "GND")
	)
	(segment
		(start 69.551296 -7.607046)
		(end 69.64934 -7.509002)
		(width 0.4064)
		(layer "F.Cu")
		(net "GND")
	)
	(segment
		(start 202.349862 -156.87294)
		(end 202.349862 -155.612846)
		(width 0.4064)
		(layer "F.Cu")
		(net "GND")
	)
	(segment
		(start 292.65626 -90.080338)
		(end 293.22776 -90.080338)
		(width 0.254)
		(layer "F.Cu")
		(net "GND")
	)
	(segment
		(start 407.403554 -149.72411)
		(end 406.88006 -150.247604)
		(width 0.3556)
		(layer "F.Cu")
		(net "GND")
	)
	(segment
		(start 215.0999 -139.170156)
		(end 215.0999 -137.67054)
		(width 0.4064)
		(layer "F.Cu")
		(net "GND")
	)
	(segment
		(start 276.344634 -61.847984)
		(end 275.773134 -61.847984)
		(width 0.254)
		(layer "F.Cu")
		(net "GND")
	)
	(segment
		(start 55.19928 2.963926)
		(end 54.74081 2.505456)
		(width 0.4064)
		(layer "F.Cu")
		(net "GND")
	)
	(segment
		(start 356.460298 -139.564618)
		(end 356.84714 -139.564618)
		(width 0.1778)
		(layer "F.Cu")
		(net "GND")
	)
	(segment
		(start 385.75615 -96.9772)
		(end 386.25145 -96.747076)
		(width 0.254)
		(layer "F.Cu")
		(net "GND")
	)
	(segment
		(start 467.742016 -52.2478)
		(end 467.739984 -51.875944)
		(width 0.4064)
		(layer "F.Cu")
		(net "GND")
	)
	(segment
		(start 111.344202 -96.518984)
		(end 111.915702 -96.518984)
		(width 0.254)
		(layer "F.Cu")
		(net "GND")
	)
	(segment
		(start 301.800006 -155.67025)
		(end 301.742602 -155.612846)
		(width 0.3556)
		(layer "F.Cu")
		(net "GND")
	)
	(segment
		(start 395.16685 -115.00612)
		(end 395.224 -115.03279)
		(width 0.254)
		(layer "F.Cu")
		(net "GND")
	)
	(segment
		(start 136.240774 -93.052138)
		(end 136.812274 -93.052138)
		(width 0.254)
		(layer "F.Cu")
		(net "GND")
	)
	(segment
		(start 149.549358 -13.363956)
		(end 149.549358 -15.423642)
		(width 0.4064)
		(layer "F.Cu")
		(net "GND")
	)
	(segment
		(start 109.2581 -3.3528)
		(end 110.111032 -3.3528)
		(width 0.508)
		(layer "F.Cu")
		(net "GND")
	)
	(segment
		(start 321.691 -140.6652)
		(end 322.199 -141.1732)
		(width 0.4064)
		(layer "F.Cu")
		(net "GND")
	)
	(segment
		(start 70.324726 -90.756486)
		(end 69.753226 -90.756486)
		(width 0.254)
		(layer "F.Cu")
		(net "GND")
	)
	(segment
		(start 217.649806 -133.076442)
		(end 217.649806 -133.809994)
		(width 0.3048)
		(layer "F.Cu")
		(net "GND")
	)
	(segment
		(start 71.183246 -100.167186)
		(end 70.611746 -100.167186)
		(width 0.254)
		(layer "F.Cu")
		(net "GND")
	)
	(segment
		(start 79.768192 -56.58104)
		(end 79.196692 -56.58104)
		(width 0.254)
		(layer "F.Cu")
		(net "GND")
	)
	(segment
		(start 392.295888 -74.487278)
		(end 391.120122 -74.487278)
		(width 0.254)
		(layer "F.Cu")
		(net "GND")
	)
	(segment
		(start 70.324726 -54.104286)
		(end 69.753226 -54.104286)
		(width 0.254)
		(layer "F.Cu")
		(net "GND")
	)
	(segment
		(start 291.3888 -7.612126)
		(end 291.422074 -7.6454)
		(width 0.3556)
		(layer "F.Cu")
		(net "GND")
	)
	(segment
		(start 383.286 -126.466092)
		(end 383.286 -126.6825)
		(width 0.254)
		(layer "F.Cu")
		(net "GND")
	)
	(segment
		(start 52.448968 -6.7564)
		(end 52.448968 -6.9342)
		(width 0.3048)
		(layer "F.Cu")
		(net "GND")
	)
	(segment
		(start 34.799524 -156.87294)
		(end 34.799524 -155.883102)
		(width 0.4064)
		(layer "F.Cu")
		(net "GND")
	)
	(segment
		(start 403.47646 -98.14814)
		(end 403.48027 -98.14814)
		(width 0.254)
		(layer "F.Cu")
		(net "GND")
	)
	(segment
		(start 143.599408 -13.427456)
		(end 143.599408 -15.423642)
		(width 0.4064)
		(layer "F.Cu")
		(net "GND")
	)
	(segment
		(start 241.334798 -59.55284)
		(end 240.763298 -59.55284)
		(width 0.254)
		(layer "F.Cu")
		(net "GND")
	)
	(segment
		(start 284.799786 -152.278842)
		(end 284.799532 -152.279096)
		(width 0.4064)
		(layer "F.Cu")
		(net "GND")
	)
	(segment
		(start 436.522114 -28.631642)
		(end 436.921656 -28.2321)
		(width 0.3048)
		(layer "F.Cu")
		(net "GND")
	)
	(segment
		(start 78.909672 -61.038486)
		(end 78.338172 -61.038486)
		(width 0.254)
		(layer "F.Cu")
		(net "GND")
	)
	(segment
		(start 377.544838 -69.495162)
		(end 377.145042 -69.894958)
		(width 0.254)
		(layer "F.Cu")
		(net "GND")
	)
	(segment
		(start 131.089908 -92.061538)
		(end 131.661408 -92.061538)
		(width 0.254)
		(layer "F.Cu")
		(net "GND")
	)
	(segment
		(start 121.646188 -58.876438)
		(end 121.074688 -58.876438)
		(width 0.254)
		(layer "F.Cu")
		(net "GND")
	)
	(segment
		(start 244.768624 -51.62804)
		(end 244.481604 -52.12334)
		(width 0.254)
		(layer "F.Cu")
		(net "GND")
	)
	(segment
		(start 301.800006 -9.21385)
		(end 301.742602 -9.156446)
		(width 0.3556)
		(layer "F.Cu")
		(net "GND")
	)
	(segment
		(start 72.900286 -59.55284)
		(end 72.328786 -59.55284)
		(width 0.254)
		(layer "F.Cu")
		(net "GND")
	)
	(segment
		(start 82.343752 -83.822286)
		(end 81.772252 -83.822286)
		(width 0.254)
		(layer "F.Cu")
		(net "GND")
	)
	(segment
		(start 81.485232 -94.223586)
		(end 80.913732 -94.223586)
		(width 0.254)
		(layer "F.Cu")
		(net "GND")
	)
	(segment
		(start 311.092596 -18.757646)
		(end 311.15 -18.81505)
		(width 0.3556)
		(layer "F.Cu")
		(net "GND")
	)
	(segment
		(start 369.8494 -128.524)
		(end 369.8494 -127.762)
		(width 0.254)
		(layer "F.Cu")
		(net "GND")
	)
	(segment
		(start 301.742602 -9.156446)
		(end 301.742602 -9.143746)
		(width 0.3556)
		(layer "F.Cu")
		(net "GND")
	)
	(segment
		(start 118.099332 -156.87294)
		(end 118.099332 -155.67025)
		(width 0.3556)
		(layer "F.Cu")
		(net "GND")
	)
	(segment
		(start 163.862512 -74.2061)
		(end 163.7792 -74.2061)
		(width 0.4064)
		(layer "F.Cu")
		(net "GND")
	)
	(segment
		(start 70.324726 -99.67214)
		(end 69.753226 -99.67214)
		(width 0.254)
		(layer "F.Cu")
		(net "GND")
	)
	(segment
		(start 115.636802 -98.005138)
		(end 116.208302 -98.005138)
		(width 0.254)
		(layer "F.Cu")
		(net "GND")
	)
	(segment
		(start 232.950004 -152.278842)
		(end 232.94975 -152.279096)
		(width 0.4064)
		(layer "F.Cu")
		(net "GND")
	)
	(segment
		(start 152.099518 -9.156446)
		(end 152.099518 -10.422382)
		(width 0.4064)
		(layer "F.Cu")
		(net "GND")
	)
	(segment
		(start 282.07208 -3.762756)
		(end 282.24988 -3.940556)
		(width 0.4064)
		(layer "F.Cu")
		(net "GND")
	)
	(segment
		(start 377.544838 -79.094838)
		(end 377.145042 -78.695042)
		(width 0.254)
		(layer "F.Cu")
		(net "GND")
	)
	(segment
		(start 237.042198 -100.662486)
		(end 236.470698 -100.662486)
		(width 0.254)
		(layer "F.Cu")
		(net "GND")
	)
	(segment
		(start 443.741048 -45.925486)
		(end 443.741048 -47.481998)
		(width 0.4064)
		(layer "F.Cu")
		(net "GND")
	)
	(segment
		(start 124.221748 -97.014538)
		(end 124.793248 -97.014538)
		(width 0.1651)
		(layer "F.Cu")
		(net "GND")
	)
	(segment
		(start 419.890194 -30.53461)
		(end 419.490144 -30.93466)
		(width 0.254)
		(layer "F.Cu")
		(net "GND")
	)
	(segment
		(start 315.399928 -2.314956)
		(end 315.399928 -0.821182)
		(width 0.4064)
		(layer "F.Cu")
		(net "GND")
	)
	(segment
		(start 116.495322 -63.829184)
		(end 115.923822 -63.829184)
		(width 0.254)
		(layer "F.Cu")
		(net "GND")
	)
	(segment
		(start 53.499512 -146.06905)
		(end 53.442108 -146.011646)
		(width 0.3556)
		(layer "F.Cu")
		(net "GND")
	)
	(segment
		(start 310.0832 -6.7564)
		(end 310.0832 -7.606538)
		(width 0.3556)
		(layer "F.Cu")
		(net "GND")
	)
	(segment
		(start 246.485664 -96.20504)
		(end 245.914164 -96.20504)
		(width 0.254)
		(layer "F.Cu")
		(net "GND")
	)
	(segment
		(start 142.02791 -97.0026)
		(end 142.039848 -97.014538)
		(width 0.254)
		(layer "F.Cu")
		(net "GND")
	)
	(segment
		(start 78.909672 -83.822286)
		(end 78.338172 -83.822286)
		(width 0.254)
		(layer "F.Cu")
		(net "GND")
	)
	(segment
		(start 239.617758 -94.223586)
		(end 239.046258 -94.223586)
		(width 0.254)
		(layer "F.Cu")
		(net "GND")
	)
	(segment
		(start 290.0807 -74.725784)
		(end 290.6522 -74.725784)
		(width 0.254)
		(layer "F.Cu")
		(net "GND")
	)
	(segment
		(start 284.799532 -142.677896)
		(end 284.799532 -143.492474)
		(width 0.4064)
		(layer "F.Cu")
		(net "GND")
	)
	(segment
		(start 231.25049 -142.6718)
		(end 231.249982 -142.677642)
		(width 0.4064)
		(layer "F.Cu")
		(net "GND")
	)
	(segment
		(start 376.428 -98.354896)
		(end 376.335036 -98.855022)
		(width 0.254)
		(layer "F.Cu")
		(net "GND")
	)
	(segment
		(start 252.495304 -82.83194)
		(end 251.923804 -82.83194)
		(width 0.254)
		(layer "F.Cu")
		(net "GND")
	)
	(segment
		(start 41.599358 -142.6718)
		(end 41.599358 -144.364202)
		(width 0.4064)
		(layer "F.Cu")
		(net "GND")
	)
	(segment
		(start 111.344202 -101.471984)
		(end 111.915702 -100.48113)
		(width 0.254)
		(layer "F.Cu")
		(net "GND")
	)
	(segment
		(start 389.7376 -114.6556)
		(end 390.13765 -114.25555)
		(width 0.12446)
		(layer "F.Cu")
		(net "GND")
	)
	(segment
		(start 465.346796 -53.053996)
		(end 465.342224 -52.2478)
		(width 0.4064)
		(layer "F.Cu")
		(net "GND")
	)
	(segment
		(start 134.249414 3.778758)
		(end 134.249414 2.092198)
		(width 0.4064)
		(layer "F.Cu")
		(net "GND")
	)
	(segment
		(start 468.925402 -42.785792)
		(end 468.658194 -43.053)
		(width 0.254)
		(layer "F.Cu")
		(net "GND")
	)
	(segment
		(start 261.93877 -60.54344)
		(end 261.36727 -60.54344)
		(width 0.254)
		(layer "F.Cu")
		(net "GND")
	)
	(segment
		(start 197.249796 3.778758)
		(end 197.249796 2.092198)
		(width 0.4064)
		(layer "F.Cu")
		(net "GND")
	)
	(segment
		(start 225.300286 -133.0706)
		(end 225.299778 -133.076442)
		(width 0.4064)
		(layer "F.Cu")
		(net "GND")
	)
	(segment
		(start 122.504708 -76.211938)
		(end 123.076208 -76.211938)
		(width 0.254)
		(layer "F.Cu")
		(net "GND")
	)
	(segment
		(start 205.750414 -137.67054)
		(end 205.749906 -137.67054)
		(width 0.4064)
		(layer "F.Cu")
		(net "GND")
	)
	(segment
		(start 77.192886 -65.991486)
		(end 76.621386 -65.991486)
		(width 0.254)
		(layer "F.Cu")
		(net "GND")
	)
	(segment
		(start 156.5021 -22.7457)
		(end 157.28188 -22.7457)
		(width 0.4064)
		(layer "F.Cu")
		(net "GND")
	)
	(segment
		(start 217.472006 -17.2466)
		(end 217.4494 -17.223994)
		(width 0.3556)
		(layer "F.Cu")
		(net "GND")
	)
	(segment
		(start 113.849404 -141.137894)
		(end 113.849404 -142.6718)
		(width 0.508)
		(layer "F.Cu")
		(net "GND")
	)
	(segment
		(start 292.450012 -21.455888)
		(end 292.392608 -21.513292)
		(width 0.4064)
		(layer "F.Cu")
		(net "GND")
	)
	(segment
		(start 235.325158 -99.67214)
		(end 234.753658 -99.67214)
		(width 0.254)
		(layer "F.Cu")
		(net "GND")
	)
	(segment
		(start 206.59979 2.092198)
		(end 206.501746 1.994154)
		(width 0.4064)
		(layer "F.Cu")
		(net "GND")
	)
	(segment
		(start 474.523816 -126.366016)
		(end 474.523816 -123.867164)
		(width 0.381)
		(layer "F.Cu")
		(net "GND")
	)
	(segment
		(start 406.872186 -7.789672)
		(end 406.872186 -9.209786)
		(width 0.254)
		(layer "F.Cu")
		(net "GND")
	)
	(segment
		(start 267.089636 -63.51524)
		(end 266.518136 -63.51524)
		(width 0.254)
		(layer "F.Cu")
		(net "GND")
	)
	(segment
		(start 32.249364 3.778758)
		(end 32.249364 2.092198)
		(width 0.4064)
		(layer "F.Cu")
		(net "GND")
	)
	(segment
		(start 136.240774 -73.240138)
		(end 136.812274 -73.240138)
		(width 0.254)
		(layer "F.Cu")
		(net "GND")
	)
	(segment
		(start 282.24988 -3.940556)
		(end 282.24988 -5.822442)
		(width 0.4064)
		(layer "F.Cu")
		(net "GND")
	)
	(segment
		(start 443.800992 -118.615714)
		(end 443.804548 -118.61927)
		(width 0.4064)
		(layer "F.Cu")
		(net "GND")
	)
	(segment
		(start 290.71189 -11.916156)
		(end 290.74999 -11.878056)
		(width 0.4064)
		(layer "F.Cu")
		(net "GND")
	)
	(segment
		(start 50.949352 -152.273)
		(end 50.949352 -153.965402)
		(width 0.4064)
		(layer "F.Cu")
		(net "GND")
	)
	(segment
		(start 288.19983 3.778758)
		(end 288.19983 1.994154)
		(width 0.4064)
		(layer "F.Cu")
		(net "GND")
	)
	(segment
		(start 402.141182 -122.918728)
		(end 403.207982 -123.985528)
		(width 0.254)
		(layer "F.Cu")
		(net "GND")
	)
	(segment
		(start 44.149518 -147.27174)
		(end 44.149518 -146.10715)
		(width 0.4064)
		(layer "F.Cu")
		(net "GND")
	)
	(segment
		(start 248.202704 -61.53404)
		(end 247.631204 -61.53404)
		(width 0.254)
		(layer "F.Cu")
		(net "GND")
	)
	(segment
		(start 53.442108 -136.410446)
		(end 53.442108 -136.397746)
		(width 0.3556)
		(layer "F.Cu")
		(net "GND")
	)
	(segment
		(start 129.372868 -100.976684)
		(end 129.944368 -100.976684)
		(width 0.254)
		(layer "F.Cu")
		(net "GND")
	)
	(segment
		(start 401.271486 -4.386072)
		(end 401.271486 -3.376422)
		(width 0.254)
		(layer "F.Cu")
		(net "GND")
	)
	(segment
		(start 393.68095 -117.58168)
		(end 394.002768 -117.731032)
		(width 0.254)
		(layer "F.Cu")
		(net "GND")
	)
	(segment
		(start 307.749956 -0.821182)
		(end 307.749956 0.457454)
		(width 0.4064)
		(layer "F.Cu")
		(net "GND")
	)
	(segment
		(start 433.0446 -18.533872)
		(end 432.062636 -18.533872)
		(width 0.254)
		(layer "F.Cu")
		(net "GND")
	)
	(segment
		(start 92.645738 -98.681286)
		(end 92.074238 -98.681286)
		(width 0.254)
		(layer "F.Cu")
		(net "GND")
	)
	(segment
		(start 175.0822 -146.6342)
		(end 174.7774 -146.939)
		(width 0.254)
		(layer "F.Cu")
		(net "GND")
	)
	(segment
		(start 197.095364 -70.900544)
		(end 197.095364 -70.501764)
		(width 0.254)
		(layer "F.Cu")
		(net "GND")
	)
	(segment
		(start 33.099502 -139.132056)
		(end 33.099502 -137.67054)
		(width 0.4064)
		(layer "F.Cu")
		(net "GND")
	)
	(segment
		(start 30.525466 -53.42763)
		(end 30.816296 -53.1368)
		(width 0.4064)
		(layer "F.Cu")
		(net "GND")
	)
	(segment
		(start 142.749524 -137.67054)
		(end 142.749524 -136.397746)
		(width 0.4064)
		(layer "F.Cu")
		(net "GND")
	)
	(segment
		(start 119.070882 -65.315338)
		(end 118.499382 -65.315338)
		(width 0.254)
		(layer "F.Cu")
		(net "GND")
	)
	(segment
		(start 119.070882 -98.005138)
		(end 119.642382 -98.005138)
		(width 0.254)
		(layer "F.Cu")
		(net "GND")
	)
	(segment
		(start 239.617758 -93.23324)
		(end 239.046258 -93.23324)
		(width 0.254)
		(layer "F.Cu")
		(net "GND")
	)
	(segment
		(start 415.490152 -34.934652)
		(end 415.890202 -34.534602)
		(width 0.254)
		(layer "F.Cu")
		(net "GND")
	)
	(segment
		(start 407.047954 -148.86432)
		(end 407.403554 -149.21992)
		(width 0.3556)
		(layer "F.Cu")
		(net "GND")
	)
	(segment
		(start 438.088532 -9.8044)
		(end 438.088532 -7.802118)
		(width 0.254)
		(layer "F.Cu")
		(net "GND")
	)
	(segment
		(start 256.7686 -12.9032)
		(end 256.379218 -13.292582)
		(width 0.508)
		(layer "F.Cu")
		(net "GND")
	)
	(segment
		(start 255.071626 -140.490194)
		(end 254.789432 -140.208)
		(width 0.4064)
		(layer "F.Cu")
		(net "GND")
	)
	(segment
		(start 33.061402 -11.916156)
		(end 33.099502 -11.878056)
		(width 0.4064)
		(layer "F.Cu")
		(net "GND")
	)
	(segment
		(start 50.099468 -155.600146)
		(end 50.099468 -156.87294)
		(width 0.4064)
		(layer "F.Cu")
		(net "GND")
	)
	(segment
		(start 27.905964 -87.707216)
		(end 28.11018 -87.503)
		(width 0.254)
		(layer "F.Cu")
		(net "GND")
	)
	(segment
		(start 394.032486 -3.249168)
		(end 394.070586 -3.287268)
		(width 0.254)
		(layer "F.Cu")
		(net "GND")
	)
	(segment
		(start 249.061224 -54.104286)
		(end 248.774204 -54.599332)
		(width 0.254)
		(layer "F.Cu")
		(net "GND")
	)
	(segment
		(start 348.19717 -1.06807)
		(end 348.739206 -1.610106)
		(width 0.254)
		(layer "F.Cu")
		(net "GND")
	)
	(segment
		(start 114.206782 -54.913784)
		(end 114.778282 -54.913784)
		(width 0.254)
		(layer "F.Cu")
		(net "GND")
	)
	(segment
		(start 133.378194 -52.437538)
		(end 132.806694 -52.437538)
		(width 0.254)
		(layer "F.Cu")
		(net "GND")
	)
	(segment
		(start 416.281108 -28.52547)
		(end 415.890202 -28.134564)
		(width 0.254)
		(layer "F.Cu")
		(net "GND")
	)
	(segment
		(start 136.240774 -63.334138)
		(end 136.812274 -63.334138)
		(width 0.254)
		(layer "F.Cu")
		(net "GND")
	)
	(segment
		(start 129.149348 -133.0706)
		(end 129.149348 -133.891274)
		(width 0.4064)
		(layer "F.Cu")
		(net "GND")
	)
	(segment
		(start 282.24988 -143.403574)
		(end 282.0162 -143.637254)
		(width 0.3556)
		(layer "F.Cu")
		(net "GND")
	)
	(segment
		(start 413.490156 -35.334702)
		(end 413.890206 -34.934652)
		(width 0.254)
		(layer "F.Cu")
		(net "GND")
	)
	(segment
		(start 90.167206 -139.829794)
		(end 89.789 -140.208)
		(width 0.4064)
		(layer "F.Cu")
		(net "GND")
	)
	(segment
		(start 380.68504 -7.850124)
		(end 380.68504 -7.789926)
		(width 0.381)
		(layer "F.Cu")
		(net "GND")
	)
	(segment
		(start 292.65626 -64.324738)
		(end 293.22776 -64.324738)
		(width 0.254)
		(layer "F.Cu")
		(net "GND")
	)
	(segment
		(start 235.49991 -136.448546)
		(end 235.46181 -136.410446)
		(width 0.4064)
		(layer "F.Cu")
		(net "GND")
	)
	(segment
		(start 216.799922 -20.023582)
		(end 216.799922 -21.479256)
		(width 0.4064)
		(layer "F.Cu")
		(net "GND")
	)
	(segment
		(start 70.324726 -86.794086)
		(end 69.753226 -86.794086)
		(width 0.254)
		(layer "F.Cu")
		(net "GND")
	)
	(segment
		(start 17.399 -98.7044)
		(end 17.399 -97.917)
		(width 0.381)
		(layer "F.Cu")
		(net "GND")
	)
	(segment
		(start 138.499342 -16.238474)
		(end 138.040872 -16.696944)
		(width 0.4064)
		(layer "F.Cu")
		(net "GND")
	)
	(segment
		(start 461.33258 -50.6222)
		(end 461.332326 -50.5206)
		(width 0.508)
		(layer "F.Cu")
		(net "GND")
	)
	(segment
		(start 130.231388 -94.538038)
		(end 130.802888 -94.538038)
		(width 0.254)
		(layer "F.Cu")
		(net "GND")
	)
	(segment
		(start 125.938788 -100.976684)
		(end 126.510288 -100.976684)
		(width 0.3048)
		(layer "F.Cu")
		(net "GND")
	)
	(segment
		(start 124.89942 -13.731748)
		(end 125.711458 -12.91971)
		(width 0.4064)
		(layer "F.Cu")
		(net "GND")
	)
	(segment
		(start 432.414934 -3.360674)
		(end 432.4096 -3.366008)
		(width 0.254)
		(layer "F.Cu")
		(net "GND")
	)
	(segment
		(start 236.183678 -52.618386)
		(end 235.612178 -52.618386)
		(width 0.254)
		(layer "F.Cu")
		(net "GND")
	)
	(segment
		(start 114.778282 -65.810384)
		(end 114.206782 -65.810384)
		(width 0.254)
		(layer "F.Cu")
		(net "GND")
	)
	(segment
		(start 346.580206 -9.574022)
		(end 346.580206 -9.528302)
		(width 0.254)
		(layer "F.Cu")
		(net "GND")
	)
	(segment
		(start 182.372 -51.5874)
		(end 182.44058 -51.5874)
		(width 0.254)
		(layer "F.Cu")
		(net "GND")
	)
	(segment
		(start 196.273928 -86.101682)
		(end 196.527928 -86.355682)
		(width 0.4064)
		(layer "F.Cu")
		(net "GND")
	)
	(segment
		(start 112.202722 -96.023938)
		(end 112.774222 -96.023938)
		(width 0.254)
		(layer "F.Cu")
		(net "GND")
	)
	(segment
		(start 462.980278 -150.219918)
		(end 463.553556 -150.793196)
		(width 0.254)
		(layer "F.Cu")
		(net "GND")
	)
	(segment
		(start 53.442108 -146.011646)
		(end 53.442108 -145.998946)
		(width 0.3556)
		(layer "F.Cu")
		(net "GND")
	)
	(segment
		(start 206.600298 -5.822442)
		(end 206.59979 -5.822442)
		(width 0.4064)
		(layer "F.Cu")
		(net "GND")
	)
	(segment
		(start 138.499342 -5.822442)
		(end 138.499342 -6.637274)
		(width 0.4064)
		(layer "F.Cu")
		(net "GND")
	)
	(segment
		(start 374.244108 -111.854996)
		(end 374.002046 -111.612934)
		(width 0.254)
		(layer "F.Cu")
		(net "GND")
	)
	(segment
		(start 46.699424 -9.156446)
		(end 46.699424 -10.422382)
		(width 0.4064)
		(layer "F.Cu")
		(net "GND")
	)
	(segment
		(start 175.119538 -63.831978)
		(end 175.14316 -63.8556)
		(width 0.381)
		(layer "F.Cu")
		(net "GND")
	)
	(segment
		(start 92.645738 -56.085486)
		(end 92.074238 -56.085486)
		(width 0.254)
		(layer "F.Cu")
		(net "GND")
	)
	(segment
		(start 205.750414 -10.422382)
		(end 205.749906 -10.422382)
		(width 0.4064)
		(layer "F.Cu")
		(net "GND")
	)
	(segment
		(start 241.44986 -20.023582)
		(end 241.44986 -18.757646)
		(width 0.4064)
		(layer "F.Cu")
		(net "GND")
	)
	(segment
		(start 28.194 -92.3798)
		(end 28.194 -92.7862)
		(width 0.254)
		(layer "F.Cu")
		(net "GND")
	)
	(segment
		(start 405.8158 -2.413)
		(end 405.8158 -2.286)
		(width 0.254)
		(layer "F.Cu")
		(net "GND")
	)
	(segment
		(start 442.948822 -52.451)
		(end 442.945774 -52.2478)
		(width 0.4064)
		(layer "F.Cu")
		(net "GND")
	)
	(segment
		(start 383.77495 -115.86464)
		(end 384.27025 -116.35994)
		(width 0.12446)
		(layer "F.Cu")
		(net "GND")
	)
	(segment
		(start 289.050476 -0.821182)
		(end 289.049968 -0.821182)
		(width 0.4064)
		(layer "F.Cu")
		(net "GND")
	)
	(segment
		(start 2.3114 -143.9926)
		(end 2.54 -143.764)
		(width 0.4064)
		(layer "F.Cu")
		(net "GND")
	)
	(segment
		(start 146.149568 -21.455888)
		(end 146.092164 -21.513292)
		(width 0.4064)
		(layer "F.Cu")
		(net "GND")
	)
	(segment
		(start 484.2764 -27.00528)
		(end 484.345234 -26.936446)
		(width 0.254)
		(layer "F.Cu")
		(net "GND")
	)
	(segment
		(start 78.051406 -98.18624)
		(end 78.338172 -98.681286)
		(width 0.254)
		(layer "F.Cu")
		(net "GND")
	)
	(segment
		(start 56.899556 -13.36421)
		(end 56.899556 -15.423642)
		(width 0.4064)
		(layer "F.Cu")
		(net "GND")
	)
	(segment
		(start 397.64335 -100.41128)
		(end 397.7894 -100.343462)
		(width 0.254)
		(layer "F.Cu")
		(net "GND")
	)
	(segment
		(start 36.499546 -133.0706)
		(end 36.499546 -133.076442)
		(width 0.4064)
		(layer "F.Cu")
		(net "GND")
	)
	(segment
		(start 241.44986 -9.156446)
		(end 241.44986 -10.422382)
		(width 0.4064)
		(layer "F.Cu")
		(net "GND")
	)
	(segment
		(start 151.24938 -5.822442)
		(end 151.24938 -7.607046)
		(width 0.4064)
		(layer "F.Cu")
		(net "GND")
	)
	(segment
		(start 311.15 -10.422382)
		(end 311.15 -9.21385)
		(width 0.3556)
		(layer "F.Cu")
		(net "GND")
	)
	(segment
		(start 303.816766 -64.819784)
		(end 304.388266 -64.819784)
		(width 0.254)
		(layer "F.Cu")
		(net "GND")
	)
	(segment
		(start 58.599324 -13.363956)
		(end 58.599578 -13.36421)
		(width 0.4064)
		(layer "F.Cu")
		(net "GND")
	)
	(segment
		(start 134.249414 2.092198)
		(end 134.15137 1.994154)
		(width 0.4064)
		(layer "F.Cu")
		(net "GND")
	)
	(segment
		(start 423.890186 -43.678348)
		(end 423.726102 -43.842432)
		(width 0.254)
		(layer "F.Cu")
		(net "GND")
	)
	(segment
		(start 73.899268 -6.637274)
		(end 73.440798 -7.095744)
		(width 0.4064)
		(layer "F.Cu")
		(net "GND")
	)
	(segment
		(start 134.523734 -66.305938)
		(end 135.095234 -66.305938)
		(width 0.254)
		(layer "F.Cu")
		(net "GND")
	)
	(segment
		(start 239.749838 -20.023582)
		(end 239.749838 -21.517356)
		(width 0.4064)
		(layer "F.Cu")
		(net "GND")
	)
	(segment
		(start 365.024924 -109.601)
		(end 367.0554 -109.601)
		(width 0.254)
		(layer "F.Cu")
		(net "GND")
	)
	(segment
		(start 399.634964 -100.855018)
		(end 399.634964 -101.855016)
		(width 0.254)
		(layer "F.Cu")
		(net "GND")
	)
	(segment
		(start 230.400352 -137.67054)
		(end 230.399844 -137.67054)
		(width 0.4064)
		(layer "F.Cu")
		(net "GND")
	)
	(segment
		(start 4.565396 -14.685518)
		(end 4.565396 -15.065756)
		(width 0.254)
		(layer "F.Cu")
		(net "GND")
	)
	(segment
		(start 458.7748 -138.974068)
		(end 458.7748 -139.4968)
		(width 0.254)
		(layer "F.Cu")
		(net "GND")
	)
	(segment
		(start 195.92544 -78.232)
		(end 195.904612 -78.211172)
		(width 0.254)
		(layer "F.Cu")
		(net "GND")
	)
	(segment
		(start 452.541132 -51.875944)
		(end 452.542148 -51.875944)
		(width 0.508)
		(layer "F.Cu")
		(net "GND")
	)
	(segment
		(start 296.69994 -147.27174)
		(end 296.69994 -146.011646)
		(width 0.4064)
		(layer "F.Cu")
		(net "GND")
	)
	(segment
		(start 202.349862 -147.27174)
		(end 202.349862 -146.011646)
		(width 0.4064)
		(layer "F.Cu")
		(net "GND")
	)
	(segment
		(start 295.849802 3.778758)
		(end 295.849802 1.994154)
		(width 0.4064)
		(layer "F.Cu")
		(net "GND")
	)
	(segment
		(start 216.80043 -0.821182)
		(end 216.799922 -0.821182)
		(width 0.4064)
		(layer "F.Cu")
		(net "GND")
	)
	(segment
		(start 113.849404 -14.13002)
		(end 113.849404 -15.423642)
		(width 0.4064)
		(layer "F.Cu")
		(net "GND")
	)
	(segment
		(start 14.529816 -1.197864)
		(end 14.748002 -1.41605)
		(width 0.254)
		(layer "F.Cu")
		(net "GND")
	)
	(segment
		(start 84.910168 -3.3528)
		(end 85.761068 -3.3528)
		(width 0.4572)
		(layer "F.Cu")
		(net "GND")
	)
	(segment
		(start 123.199398 -133.0706)
		(end 123.199398 -134.861046)
		(width 0.4064)
		(layer "F.Cu")
		(net "GND")
	)
	(segment
		(start 419.1762 -49.593754)
		(end 419.1762 -49.463198)
		(width 0.254)
		(layer "F.Cu")
		(net "GND")
	)
	(segment
		(start 113.849404 -5.822442)
		(end 113.849404 -4.487164)
		(width 0.4064)
		(layer "F.Cu")
		(net "GND")
	)
	(segment
		(start 398.505426 -95.183706)
		(end 398.759426 -95.267526)
		(width 0.254)
		(layer "F.Cu")
		(net "GND")
	)
	(segment
		(start 47.549562 -3.76301)
		(end 47.549562 -5.822442)
		(width 0.4064)
		(layer "F.Cu")
		(net "GND")
	)
	(segment
		(start 300.949868 -153.024078)
		(end 300.736 -153.237946)
		(width 0.3556)
		(layer "F.Cu")
		(net "GND")
	)
	(segment
		(start 75.475846 -81.841086)
		(end 74.904346 -81.841086)
		(width 0.254)
		(layer "F.Cu")
		(net "GND")
	)
	(segment
		(start 249.919744 -68.46824)
		(end 249.348244 -68.46824)
		(width 0.254)
		(layer "F.Cu")
		(net "GND")
	)
	(segment
		(start 216.80043 -156.87294)
		(end 216.799922 -156.87294)
		(width 0.4064)
		(layer "F.Cu")
		(net "GND")
	)
	(segment
		(start 15.2146 -98.171)
		(end 15.2146 -98.7044)
		(width 0.4064)
		(layer "F.Cu")
		(net "GND")
	)
	(segment
		(start 282.0162 -17.19072)
		(end 282.0162 -16.383254)
		(width 0.3556)
		(layer "F.Cu")
		(net "GND")
	)
	(segment
		(start 278.920194 -65.315338)
		(end 278.348694 -65.315338)
		(width 0.254)
		(layer "F.Cu")
		(net "GND")
	)
	(segment
		(start 197.250304 3.778758)
		(end 197.249796 3.778758)
		(width 0.4064)
		(layer "F.Cu")
		(net "GND")
	)
	(segment
		(start 302.7807 -104.0257)
		(end 302.8188 -104.0257)
		(width 0.2032)
		(layer "F.Cu")
		(net "GND")
	)
	(segment
		(start 129.372868 -80.174338)
		(end 129.944368 -80.174338)
		(width 0.254)
		(layer "F.Cu")
		(net "GND")
	)
	(segment
		(start 42.424096 -146.011646)
		(end 42.411396 -146.011646)
		(width 0.4064)
		(layer "F.Cu")
		(net "GND")
	)
	(segment
		(start 245.627144 -59.057286)
		(end 245.055644 -59.057286)
		(width 0.254)
		(layer "F.Cu")
		(net "GND")
	)
	(segment
		(start 113.849404 -17.193006)
		(end 113.951258 -17.29486)
		(width 0.4064)
		(layer "F.Cu")
		(net "GND")
	)
	(segment
		(start 317.09995 -11.927078)
		(end 317.146432 -11.97356)
		(width 0.4064)
		(layer "F.Cu")
		(net "GND")
	)
	(segment
		(start 294.14978 2.963926)
		(end 293.69131 2.505456)
		(width 0.4064)
		(layer "F.Cu")
		(net "GND")
	)
	(segment
		(start 464.906614 -3.4036)
		(end 464.907376 -3.402838)
		(width 0.4064)
		(layer "F.Cu")
		(net "GND")
	)
	(segment
		(start 220.199712 -6.637274)
		(end 219.741242 -7.095744)
		(width 0.4064)
		(layer "F.Cu")
		(net "GND")
	)
	(segment
		(start 33.771586 -17.2466)
		(end 33.754568 -17.229582)
		(width 0.3556)
		(layer "F.Cu")
		(net "GND")
	)
	(segment
		(start 127.392176 0.444754)
		(end 127.392176 0.457454)
		(width 0.3556)
		(layer "F.Cu")
		(net "GND")
	)
	(segment
		(start 473.253308 -35.991292)
		(end 472.227402 -35.991292)
		(width 0.508)
		(layer "F.Cu")
		(net "GND")
	)
	(segment
		(start 377.7488 -122.7328)
		(end 377.33605 -122.32005)
		(width 0.254)
		(layer "F.Cu")
		(net "GND")
	)
	(segment
		(start 152.099518 -15.423642)
		(end 152.099518 -16.687546)
		(width 0.4064)
		(layer "F.Cu")
		(net "GND")
	)
	(segment
		(start 203.200508 -133.0706)
		(end 203.2 -133.076442)
		(width 0.4064)
		(layer "F.Cu")
		(net "GND")
	)
	(segment
		(start 313.700414 -147.27174)
		(end 313.699906 -147.27174)
		(width 0.4064)
		(layer "F.Cu")
		(net "GND")
	)
	(segment
		(start 287.349946 -9.156446)
		(end 287.349946 -10.422382)
		(width 0.4064)
		(layer "F.Cu")
		(net "GND")
	)
	(segment
		(start 298.665646 -59.866784)
		(end 299.237146 -59.866784)
		(width 0.254)
		(layer "F.Cu")
		(net "GND")
	)
	(segment
		(start 460.600806 -113.777014)
		(end 460.59979 -113.77803)
		(width 0.4064)
		(layer "F.Cu")
		(net "GND")
	)
	(segment
		(start 145.082768 -7.606538)
		(end 145.12163 -7.6454)
		(width 0.3556)
		(layer "F.Cu")
		(net "GND")
	)
	(segment
		(start 289.899852 -133.076442)
		(end 289.899852 -134.763002)
		(width 0.4064)
		(layer "F.Cu")
		(net "GND")
	)
	(segment
		(start 418.213032 -54.864)
		(end 418.5031 -54.573932)
		(width 0.254)
		(layer "F.Cu")
		(net "GND")
	)
	(segment
		(start 194.494404 -85.107272)
		(end 194.134994 -85.107272)
		(width 0.254)
		(layer "F.Cu")
		(net "GND")
	)
	(segment
		(start 124.221748 -88.099138)
		(end 124.793248 -88.099138)
		(width 0.254)
		(layer "F.Cu")
		(net "GND")
	)
	(segment
		(start 226.9998 -16.154654)
		(end 226.9998 -15.423642)
		(width 0.3556)
		(layer "F.Cu")
		(net "GND")
	)
	(segment
		(start 66.249296 3.599434)
		(end 66.249296 1.994154)
		(width 0.4064)
		(layer "F.Cu")
		(net "GND")
	)
	(segment
		(start 116.495322 -65.810384)
		(end 115.923822 -65.810384)
		(width 0.254)
		(layer "F.Cu")
		(net "GND")
	)
	(segment
		(start 164.465 -73.914)
		(end 164.154612 -73.914)
		(width 0.4064)
		(layer "F.Cu")
		(net "GND")
	)
	(segment
		(start 47.549562 3.599688)
		(end 47.549308 3.599434)
		(width 0.4064)
		(layer "F.Cu")
		(net "GND")
	)
	(segment
		(start 47.549562 -5.822442)
		(end 47.549562 -6.001512)
		(width 0.4064)
		(layer "F.Cu")
		(net "GND")
	)
	(segment
		(start 477.1263 -139.3571)
		(end 476.52178 -139.96162)
		(width 0.254)
		(layer "F.Cu")
		(net "GND")
	)
	(segment
		(start 474.51645 -43.7134)
		(end 472.940888 -43.7134)
		(width 0.254)
		(layer "F.Cu")
		(net "GND")
	)
	(segment
		(start 316.25032 3.778758)
		(end 316.249812 3.778758)
		(width 0.4064)
		(layer "F.Cu")
		(net "GND")
	)
	(segment
		(start 283.099764 -0.821182)
		(end 283.099764 0.38735)
		(width 0.3556)
		(layer "F.Cu")
		(net "GND")
	)
	(segment
		(start 396.65275 -107.907836)
		(end 396.65275 -107.27944)
		(width 0.254)
		(layer "F.Cu")
		(net "GND")
	)
	(segment
		(start 238.899954 -152.278842)
		(end 238.8997 -152.279096)
		(width 0.4064)
		(layer "F.Cu")
		(net "GND")
	)
	(segment
		(start 114.778282 -101.471984)
		(end 114.491262 -100.976938)
		(width 0.4064)
		(layer "F.Cu")
		(net "GND")
	)
	(segment
		(start 317.100458 -156.87294)
		(end 317.09995 -156.87294)
		(width 0.4064)
		(layer "F.Cu")
		(net "GND")
	)
	(segment
		(start 252.495304 -78.869286)
		(end 251.923804 -78.869286)
		(width 0.254)
		(layer "F.Cu")
		(net "GND")
	)
	(segment
		(start 440.600846 -116.993162)
		(end 440.600846 -118.615714)
		(width 0.4064)
		(layer "F.Cu")
		(net "GND")
	)
	(segment
		(start 242.300506 -134.860284)
		(end 242.299744 -134.861046)
		(width 0.4064)
		(layer "F.Cu")
		(net "GND")
	)
	(segment
		(start 53.442108 -11.912092)
		(end 53.499512 -11.854688)
		(width 0.4064)
		(layer "F.Cu")
		(net "GND")
	)
	(segment
		(start 287.50514 -93.052138)
		(end 288.07664 -93.052138)
		(width 0.254)
		(layer "F.Cu")
		(net "GND")
	)
	(segment
		(start 74.045826 -50.63744)
		(end 73.758806 -50.141886)
		(width 0.254)
		(layer "F.Cu")
		(net "GND")
	)
	(segment
		(start 32.094932 -70.900544)
		(end 32.094932 -70.448932)
		(width 0.254)
		(layer "F.Cu")
		(net "GND")
	)
	(segment
		(start 61.149484 -21.479256)
		(end 61.111384 -21.517356)
		(width 0.4064)
		(layer "F.Cu")
		(net "GND")
	)
	(segment
		(start 289.22218 -88.099138)
		(end 289.79368 -88.099138)
		(width 0.254)
		(layer "F.Cu")
		(net "GND")
	)
	(segment
		(start 448.54876 -52.451)
		(end 448.545712 -52.2478)
		(width 0.4064)
		(layer "F.Cu")
		(net "GND")
	)
	(segment
		(start 242.193318 -53.113686)
		(end 241.621818 -53.113686)
		(width 0.254)
		(layer "F.Cu")
		(net "GND")
	)
	(segment
		(start 350.1136 -148.825712)
		(end 350.0628 -148.774912)
		(width 0.4064)
		(layer "F.Cu")
		(net "GND")
	)
	(segment
		(start 458.9399 -51.875944)
		(end 458.940916 -51.875944)
		(width 0.508)
		(layer "F.Cu")
		(net "GND")
	)
	(segment
		(start 348.739206 -1.610106)
		(end 348.739206 -2.254504)
		(width 0.254)
		(layer "F.Cu")
		(net "GND")
	)
	(segment
		(start 272.623534 -100.976684)
		(end 272.052288 -100.976684)
		(width 0.254)
		(layer "F.Cu")
		(net "GND")
	)
	(segment
		(start 496.24996 -54.329838)
		(end 495.554254 -54.329838)
		(width 0.254)
		(layer "F.Cu")
		(net "GND")
	)
	(segment
		(start 423.674286 -7.789672)
		(end 423.674286 -9.398)
		(width 0.254)
		(layer "F.Cu")
		(net "GND")
	)
	(segment
		(start 205.749906 -0.821182)
		(end 205.749906 0.457454)
		(width 0.4064)
		(layer "F.Cu")
		(net "GND")
	)
	(segment
		(start 120.787668 -65.315338)
		(end 120.216168 -65.315338)
		(width 0.254)
		(layer "F.Cu")
		(net "GND")
	)
	(segment
		(start 213.399878 -20.023582)
		(end 213.399878 -21.517356)
		(width 0.4064)
		(layer "F.Cu")
		(net "GND")
	)
	(segment
		(start 304.35042 -147.27174)
		(end 304.349912 -147.27174)
		(width 0.4064)
		(layer "F.Cu")
		(net "GND")
	)
	(segment
		(start 38.199314 -142.856966)
		(end 38.199314 -144.462246)
		(width 0.4064)
		(layer "F.Cu")
		(net "GND")
	)
	(segment
		(start 388.6708 -65.1764)
		(end 387.8326 -64.3382)
		(width 0.254)
		(layer "F.Cu")
		(net "GND")
	)
	(segment
		(start 179.578254 -75.68565)
		(end 180.2257 -75.68565)
		(width 0.4064)
		(layer "F.Cu")
		(net "GND")
	)
	(segment
		(start 21.863812 -67.8053)
		(end 22.4155 -67.8053)
		(width 0.254)
		(layer "F.Cu")
		(net "GND")
	)
	(segment
		(start 27.451558 -21.488146)
		(end 27.52979 -21.409914)
		(width 0.508)
		(layer "F.Cu")
		(net "GND")
	)
	(segment
		(start 233.608118 -96.700086)
		(end 232.9434 -96.700086)
		(width 0.254)
		(layer "F.Cu")
		(net "GND")
	)
	(segment
		(start 147.390866 -16.696944)
		(end 147.849336 -16.238474)
		(width 0.4064)
		(layer "F.Cu")
		(net "GND")
	)
	(segment
		(start 76.334366 -96.20504)
		(end 75.762866 -96.20504)
		(width 0.254)
		(layer "F.Cu")
		(net "GND")
	)
	(segment
		(start 442.9506 -53.2638)
		(end 442.949838 -53.263038)
		(width 0.4064)
		(layer "F.Cu")
		(net "GND")
	)
	(segment
		(start 235.325158 -63.019686)
		(end 234.753658 -63.019686)
		(width 0.254)
		(layer "F.Cu")
		(net "GND")
	)
	(segment
		(start 399.188432 -101.893116)
		(end 399.126964 -101.893116)
		(width 0.254)
		(layer "F.Cu")
		(net "GND")
	)
	(segment
		(start 96.938338 -88.28024)
		(end 96.366838 -88.28024)
		(width 0.254)
		(layer "F.Cu")
		(net "GND")
	)
	(segment
		(start 245.627144 -81.841086)
		(end 245.055644 -81.841086)
		(width 0.254)
		(layer "F.Cu")
		(net "GND")
	)
	(segment
		(start 55.199534 -4.808982)
		(end 55.199534 -5.822442)
		(width 0.4064)
		(layer "F.Cu")
		(net "GND")
	)
	(segment
		(start 300.772068 -17.2466)
		(end 300.736 -17.210532)
		(width 0.3556)
		(layer "F.Cu")
		(net "GND")
	)
	(segment
		(start 76.334366 -87.28964)
		(end 75.762866 -87.28964)
		(width 0.254)
		(layer "F.Cu")
		(net "GND")
	)
	(segment
		(start 119.929402 -81.659984)
		(end 119.357902 -81.659984)
		(width 0.254)
		(layer "F.Cu")
		(net "GND")
	)
	(segment
		(start 31.400496 -61.095382)
		(end 31.145734 -61.095382)
		(width 0.508)
		(layer "F.Cu")
		(net "GND")
	)
	(segment
		(start 289.22218 -92.061538)
		(end 289.79368 -92.061538)
		(width 0.254)
		(layer "F.Cu")
		(net "GND")
	)
	(segment
		(start 234.649772 -142.677642)
		(end 234.649772 -144.364202)
		(width 0.4064)
		(layer "F.Cu")
		(net "GND")
	)
	(segment
		(start 147.849336 -16.238474)
		(end 147.849336 -15.423642)
		(width 0.4064)
		(layer "F.Cu")
		(net "GND")
	)
	(segment
		(start 292.45052 -156.87294)
		(end 292.45052 -155.658058)
		(width 0.3556)
		(layer "F.Cu")
		(net "GND")
	)
	(segment
		(start 232.950004 -142.677642)
		(end 232.94975 -142.677896)
		(width 0.4064)
		(layer "F.Cu")
		(net "GND")
	)
	(segment
		(start 243.15039 -10.422382)
		(end 243.149882 -10.422382)
		(width 0.4064)
		(layer "F.Cu")
		(net "GND")
	)
	(segment
		(start 236.350302 -15.423642)
		(end 236.349794 -15.423642)
		(width 0.4064)
		(layer "F.Cu")
		(net "GND")
	)
	(segment
		(start 286.499808 -5.822442)
		(end 286.499808 -7.607046)
		(width 0.4064)
		(layer "F.Cu")
		(net "GND")
	)
	(segment
		(start 480.8728 -140.8684)
		(end 481.151946 -141.147546)
		(width 0.254)
		(layer "F.Cu")
		(net "GND")
	)
	(segment
		(start 291.422074 -17.2466)
		(end 291.3888 -17.213326)
		(width 0.3556)
		(layer "F.Cu")
		(net "GND")
	)
	(segment
		(start 271.480788 -54.418738)
		(end 272.052288 -54.418738)
		(width 0.254)
		(layer "F.Cu")
		(net "GND")
	)
	(segment
		(start 303.500282 -5.822442)
		(end 303.499774 -5.822442)
		(width 0.4064)
		(layer "F.Cu")
		(net "GND")
	)
	(segment
		(start 374.1166 -108.855002)
		(end 373.9896 -108.728002)
		(width 0.254)
		(layer "F.Cu")
		(net "GND")
	)
	(segment
		(start 282.24988 -16.149574)
		(end 282.24988 -15.423642)
		(width 0.3556)
		(layer "F.Cu")
		(net "GND")
	)
	(segment
		(start 286.07512 -65.810384)
		(end 286.64662 -65.810384)
		(width 0.254)
		(layer "F.Cu")
		(net "GND")
	)
	(segment
		(start 278.849836 -147.27174)
		(end 278.849836 -146.008852)
		(width 0.4064)
		(layer "F.Cu")
		(net "GND")
	)
	(segment
		(start 76.334366 -72.43064)
		(end 75.762866 -72.43064)
		(width 0.254)
		(layer "F.Cu")
		(net "GND")
	)
	(segment
		(start 119.799354 -133.89102)
		(end 119.7991 -133.891274)
		(width 0.3556)
		(layer "F.Cu")
		(net "GND")
	)
	(segment
		(start 126.421642 -3.762756)
		(end 126.599442 -3.940556)
		(width 0.4064)
		(layer "F.Cu")
		(net "GND")
	)
	(segment
		(start 244.3353 -149.8092)
		(end 243.8908 -149.8092)
		(width 0.4572)
		(layer "F.Cu")
		(net "GND")
	)
	(segment
		(start 123.363228 -93.547184)
		(end 123.934728 -93.547184)
		(width 0.254)
		(layer "F.Cu")
		(net "GND")
	)
	(segment
		(start 456.1713 -27.432)
		(end 456.1713 -26.616914)
		(width 0.254)
		(layer "F.Cu")
		(net "GND")
	)
	(segment
		(start 204.900276 -15.423642)
		(end 204.899768 -15.423642)
		(width 0.4064)
		(layer "F.Cu")
		(net "GND")
	)
	(segment
		(start 142.55623 -70.0786)
		(end 143.2052 -70.0786)
		(width 0.254)
		(layer "F.Cu")
		(net "GND")
	)
	(segment
		(start 376.639328 -37.61232)
		(end 377.69292 -37.61232)
		(width 0.254)
		(layer "F.Cu")
		(net "GND")
	)
	(segment
		(start 101.230684 -98.681286)
		(end 100.659184 -98.681286)
		(width 0.254)
		(layer "F.Cu")
		(net "GND")
	)
	(segment
		(start 239.617758 -68.46824)
		(end 239.046258 -68.46824)
		(width 0.254)
		(layer "F.Cu")
		(net "GND")
	)
	(segment
		(start 238.759238 -50.141886)
		(end 239.046258 -50.63744)
		(width 0.254)
		(layer "F.Cu")
		(net "GND")
	)
	(segment
		(start 284.929834 -63.829184)
		(end 284.358334 -63.829184)
		(width 0.254)
		(layer "F.Cu")
		(net "GND")
	)
	(segment
		(start 380.80315 -119.29872)
		(end 381.29845 -119.528844)
		(width 0.254)
		(layer "F.Cu")
		(net "GND")
	)
	(segment
		(start 230.399844 -146.011646)
		(end 230.399844 -147.27174)
		(width 0.4064)
		(layer "F.Cu")
		(net "GND")
	)
	(segment
		(start 152.099518 -2.325878)
		(end 152.099518 -3.255518)
		(width 0.4064)
		(layer "F.Cu")
		(net "GND")
	)
	(segment
		(start 117.071648 -3.762756)
		(end 117.249448 -3.940556)
		(width 0.4064)
		(layer "F.Cu")
		(net "GND")
	)
	(segment
		(start 236.183678 -78.37424)
		(end 235.612178 -78.37424)
		(width 0.254)
		(layer "F.Cu")
		(net "GND")
	)
	(segment
		(start 294.3733 -53.427884)
		(end 294.9448 -53.427884)
		(width 0.254)
		(layer "F.Cu")
		(net "GND")
	)
	(segment
		(start 272.052288 -101.967538)
		(end 272.623534 -101.967538)
		(width 0.254)
		(layer "F.Cu")
		(net "GND")
	)
	(segment
		(start 275.486114 -91.070938)
		(end 276.057614 -91.070938)
		(width 0.1016)
		(layer "F.Cu")
		(net "GND")
	)
	(segment
		(start 297.807126 -76.211938)
		(end 298.378626 -76.211938)
		(width 0.254)
		(layer "F.Cu")
		(net "GND")
	)
	(segment
		(start 234.65028 -15.423642)
		(end 234.649772 -15.423642)
		(width 0.4064)
		(layer "F.Cu")
		(net "GND")
	)
	(segment
		(start 97.660968 -24.638)
		(end 98.118168 -25.0952)
		(width 0.4064)
		(layer "F.Cu")
		(net "GND")
	)
	(segment
		(start 75.599544 -5.822442)
		(end 75.599544 -6.001512)
		(width 0.4064)
		(layer "F.Cu")
		(net "GND")
	)
	(segment
		(start 115.636802 -50.3047)
		(end 115.636802 -50.3174)
		(width 0.2286)
		(layer "F.Cu")
		(net "GND")
	)
	(segment
		(start 401.320762 -95.140018)
		(end 401.9169 -95.140018)
		(width 0.254)
		(layer "F.Cu")
		(net "GND")
	)
	(segment
		(start 314.550298 -152.273)
		(end 314.54979 -152.278842)
		(width 0.4064)
		(layer "F.Cu")
		(net "GND")
	)
	(segment
		(start 300.099984 -21.479256)
		(end 300.061884 -21.517356)
		(width 0.4064)
		(layer "F.Cu")
		(net "GND")
	)
	(segment
		(start 67.949572 -142.677642)
		(end 67.949318 -142.677896)
		(width 0.4064)
		(layer "F.Cu")
		(net "GND")
	)
	(segment
		(start 401.295108 -96.791272)
		(end 401.320508 -96.816672)
		(width 0.254)
		(layer "F.Cu")
		(net "GND")
	)
	(segment
		(start 449.40093 -116.993162)
		(end 449.404486 -118.61927)
		(width 0.4064)
		(layer "F.Cu")
		(net "GND")
	)
	(segment
		(start 126.599442 -3.940556)
		(end 126.599442 -5.822442)
		(width 0.4064)
		(layer "F.Cu")
		(net "GND")
	)
	(segment
		(start 136.74217 -146.011646)
		(end 136.74217 -145.998946)
		(width 0.3556)
		(layer "F.Cu")
		(net "GND")
	)
	(segment
		(start 237.042198 -97.690686)
		(end 236.470698 -97.690686)
		(width 0.254)
		(layer "F.Cu")
		(net "GND")
	)
	(segment
		(start 89.211912 -66.982086)
		(end 88.640412 -66.982086)
		(width 0.254)
		(layer "F.Cu")
		(net "GND")
	)
	(segment
		(start 38.199568 3.599688)
		(end 38.199314 3.599434)
		(width 0.4064)
		(layer "F.Cu")
		(net "GND")
	)
	(segment
		(start 30.766004 -77.351382)
		(end 30.668976 -77.44841)
		(width 0.508)
		(layer "F.Cu")
		(net "GND")
	)
	(segment
		(start 68.799456 -156.87294)
		(end 68.799456 -155.549346)
		(width 0.4064)
		(layer "F.Cu")
		(net "GND")
	)
	(segment
		(start 355.656388 -140.76299)
		(end 355.656388 -141.243558)
		(width 0.254)
		(layer "F.Cu")
		(net "GND")
	)
	(segment
		(start 278.849836 -137.67054)
		(end 278.850344 -137.67054)
		(width 0.4064)
		(layer "F.Cu")
		(net "GND")
	)
	(segment
		(start 393.18565 -97.83572)
		(end 393.68095 -97.605596)
		(width 0.254)
		(layer "F.Cu")
		(net "GND")
	)
	(segment
		(start 204.049884 -0.821182)
		(end 204.049884 -2.314956)
		(width 0.4064)
		(layer "F.Cu")
		(net "GND")
	)
	(segment
		(start 123.199398 -152.273)
		(end 123.199398 -154.23642)
		(width 0.4064)
		(layer "F.Cu")
		(net "GND")
	)
	(segment
		(start 238.899954 -4.808982)
		(end 238.899954 -5.822442)
		(width 0.4064)
		(layer "F.Cu")
		(net "GND")
	)
	(segment
		(start 373.14505 -74.69505)
		(end 373.544846 -75.094846)
		(width 0.254)
		(layer "F.Cu")
		(net "GND")
	)
	(segment
		(start 171.7548 -71.5264)
		(end 171.8564 -71.628)
		(width 0.254)
		(layer "F.Cu")
		(net "GND")
	)
	(segment
		(start 135.382254 -81.659984)
		(end 135.953754 -81.659984)
		(width 0.254)
		(layer "F.Cu")
		(net "GND")
	)
	(segment
		(start 299.524166 -70.268084)
		(end 300.095666 -70.268084)
		(width 0.254)
		(layer "F.Cu")
		(net "GND")
	)
	(segment
		(start 286.07512 -58.876438)
		(end 286.64662 -58.876438)
		(width 0.254)
		(layer "F.Cu")
		(net "GND")
	)
	(segment
		(start 464.487514 -143.219932)
		(end 462.980278 -143.219932)
		(width 0.254)
		(layer "F.Cu")
		(net "GND")
	)
	(segment
		(start 118.361968 -52.684172)
		(end 118.218966 -52.93106)
		(width 0.254)
		(layer "F.Cu")
		(net "GND")
	)
	(segment
		(start 119.7991 -143.492474)
		(end 119.34063 -143.950944)
		(width 0.4064)
		(layer "F.Cu")
		(net "GND")
	)
	(segment
		(start 485.452674 -34.822638)
		(end 485.5845 -34.690812)
		(width 0.254)
		(layer "F.Cu")
		(net "GND")
	)
	(segment
		(start 196.399912 -145.998946)
		(end 196.399912 -147.27174)
		(width 0.4064)
		(layer "F.Cu")
		(net "GND")
	)
	(segment
		(start 288.36366 -95.528384)
		(end 288.93516 -95.528384)
		(width 0.254)
		(layer "F.Cu")
		(net "GND")
	)
	(segment
		(start 41.501314 -7.607046)
		(end 41.599358 -7.509002)
		(width 0.4064)
		(layer "F.Cu")
		(net "GND")
	)
	(segment
		(start 240.476278 -94.718886)
		(end 239.904778 -94.718886)
		(width 0.254)
		(layer "F.Cu")
		(net "GND")
	)
	(segment
		(start 227.849938 -136.46785)
		(end 227.792534 -136.410446)
		(width 0.3556)
		(layer "F.Cu")
		(net "GND")
	)
	(segment
		(start 459.00086 -116.993162)
		(end 459.00086 -118.615714)
		(width 0.4064)
		(layer "F.Cu")
		(net "GND")
	)
	(segment
		(start 348.276164 -9.283954)
		(end 348.5896 -9.59739)
		(width 0.254)
		(layer "F.Cu")
		(net "GND")
	)
	(segment
		(start 308.59984 -142.677642)
		(end 308.59984 -144.364202)
		(width 0.4064)
		(layer "F.Cu")
		(net "GND")
	)
	(segment
		(start 113.849404 -21.567648)
		(end 113.94694 -21.665184)
		(width 0.4064)
		(layer "F.Cu")
		(net "GND")
	)
	(segment
		(start 196.30898 -77.216)
		(end 195.904612 -77.620368)
		(width 0.508)
		(layer "F.Cu")
		(net "GND")
	)
	(segment
		(start 246.485664 -102.093014)
		(end 246.485664 -101.15804)
		(width 0.254)
		(layer "F.Cu")
		(net "GND")
	)
	(segment
		(start 399.634964 -99.85502)
		(end 399.634964 -100.855018)
		(width 0.254)
		(layer "F.Cu")
		(net "GND")
	)
	(segment
		(start 290.0807 -90.575384)
		(end 290.6522 -90.575384)
		(width 0.1651)
		(layer "F.Cu")
		(net "GND")
	)
	(segment
		(start 279.699974 -18.744946)
		(end 279.699974 -20.023582)
		(width 0.4064)
		(layer "F.Cu")
		(net "GND")
	)
	(segment
		(start 243.149882 -2.3622)
		(end 243.149882 -0.821182)
		(width 0.4064)
		(layer "F.Cu")
		(net "GND")
	)
	(segment
		(start 307.749956 -137.67054)
		(end 307.749956 -136.397746)
		(width 0.4064)
		(layer "F.Cu")
		(net "GND")
	)
	(segment
		(start 235.325158 -64.010286)
		(end 234.753658 -64.010286)
		(width 0.254)
		(layer "F.Cu")
		(net "GND")
	)
	(segment
		(start 243.051838 -53.60924)
		(end 242.480338 -53.60924)
		(width 0.254)
		(layer "F.Cu")
		(net "GND")
	)
	(segment
		(start 142.250414 -64.819784)
		(end 142.898114 -64.819784)
		(width 0.254)
		(layer "F.Cu")
		(net "GND")
	)
	(segment
		(start 488.1372 -34.3408)
		(end 488.188 -34.29)
		(width 0.254)
		(layer "F.Cu")
		(net "GND")
	)
	(segment
		(start 56.899556 -142.6718)
		(end 56.899556 -142.856712)
		(width 0.4064)
		(layer "F.Cu")
		(net "GND")
	)
	(segment
		(start 120.649492 -21.517356)
		(end 120.649492 -20.023582)
		(width 0.4064)
		(layer "F.Cu")
		(net "GND")
	)
	(segment
		(start 31.39948 -9.139682)
		(end 31.39948 -10.422382)
		(width 0.4064)
		(layer "F.Cu")
		(net "GND")
	)
	(segment
		(start 147.849336 -133.891274)
		(end 147.390866 -134.349744)
		(width 0.4064)
		(layer "F.Cu")
		(net "GND")
	)
	(segment
		(start 389.71855 -116.953284)
		(end 389.71855 -115.86464)
		(width 0.254)
		(layer "F.Cu")
		(net "GND")
	)
	(segment
		(start 69.64934 -13.660628)
		(end 70.461378 -12.84859)
		(width 0.4064)
		(layer "F.Cu")
		(net "GND")
	)
	(segment
		(start 77.299312 -13.363956)
		(end 77.299566 -13.36421)
		(width 0.4064)
		(layer "F.Cu")
		(net "GND")
	)
	(segment
		(start 382.797304 -29.27096)
		(end 383.77622 -29.27096)
		(width 0.254)
		(layer "F.Cu")
		(net "GND")
	)
	(segment
		(start 2.71272 -73.16978)
		(end 2.03073 -72.48779)
		(width 0.254)
		(layer "F.Cu")
		(net "GND")
	)
	(segment
		(start 125.749558 -0.821182)
		(end 125.749558 0.444754)
		(width 0.4064)
		(layer "F.Cu")
		(net "GND")
	)
	(segment
		(start 300.100492 -137.67054)
		(end 300.099984 -137.67054)
		(width 0.4064)
		(layer "F.Cu")
		(net "GND")
	)
	(segment
		(start 371.08511 -7.789926)
		(end 371.08511 -7.850124)
		(width 0.254)
		(layer "F.Cu")
		(net "GND")
	)
	(segment
		(start 90.071194 -140.490194)
		(end 90.814906 -140.490194)
		(width 0.4064)
		(layer "F.Cu")
		(net "GND")
	)
	(segment
		(start 304.35042 -156.87294)
		(end 304.349912 -156.87294)
		(width 0.4064)
		(layer "F.Cu")
		(net "GND")
	)
	(segment
		(start 82.343752 -56.085486)
		(end 81.772252 -56.085486)
		(width 0.254)
		(layer "F.Cu")
		(net "GND")
	)
	(segment
		(start 72.041766 -69.953886)
		(end 71.470266 -69.953886)
		(width 0.254)
		(layer "F.Cu")
		(net "GND")
	)
	(segment
		(start 76.334366 -89.27084)
		(end 75.762866 -89.27084)
		(width 0.254)
		(layer "F.Cu")
		(net "GND")
	)
	(segment
		(start 274.627848 -57.885584)
		(end 274.056348 -57.885584)
		(width 0.254)
		(layer "F.Cu")
		(net "GND")
	)
	(segment
		(start 68.11264 -53.60924)
		(end 68.607686 -54.104286)
		(width 0.254)
		(layer "F.Cu")
		(net "GND")
	)
	(segment
		(start 115.636802 -65.315338)
		(end 115.065302 -65.315338)
		(width 0.254)
		(layer "F.Cu")
		(net "GND")
	)
	(segment
		(start 293.69131 -7.095744)
		(end 294.14978 -6.637274)
		(width 0.4064)
		(layer "F.Cu")
		(net "GND")
	)
	(segment
		(start 317.950342 -152.273)
		(end 317.949834 -152.278842)
		(width 0.4064)
		(layer "F.Cu")
		(net "GND")
	)
	(segment
		(start 249.919744 -76.39304)
		(end 249.348244 -76.39304)
		(width 0.254)
		(layer "F.Cu")
		(net "GND")
	)
	(segment
		(start 287.350454 -147.27174)
		(end 287.349946 -147.27174)
		(width 0.4064)
		(layer "F.Cu")
		(net "GND")
	)
	(segment
		(start 371.08511 -7.850124)
		(end 371.08511 -8.84682)
		(width 0.4064)
		(layer "F.Cu")
		(net "GND")
	)
	(segment
		(start 466.09 -148.9075)
		(end 466.09 -149.311614)
		(width 0.254)
		(layer "F.Cu")
		(net "GND")
	)
	(segment
		(start 141.899386 -5.822442)
		(end 141.899386 -3.762756)
		(width 0.4064)
		(layer "F.Cu")
		(net "GND")
	)
	(segment
		(start 302.099726 -88.594184)
		(end 302.671226 -88.594184)
		(width 0.3048)
		(layer "F.Cu")
		(net "GND")
	)
	(segment
		(start 276.344634 -58.876438)
		(end 275.773134 -58.876438)
		(width 0.254)
		(layer "F.Cu")
		(net "GND")
	)
	(segment
		(start 135.735568 -134.035546)
		(end 135.735568 -134.863332)
		(width 0.3556)
		(layer "F.Cu")
		(net "GND")
	)
	(segment
		(start 199.742552 -2.310892)
		(end 199.799956 -2.253488)
		(width 0.4064)
		(layer "F.Cu")
		(net "GND")
	)
	(segment
		(start 349.292164 -155.613862)
		(end 349.292164 -156.048964)
		(width 0.254)
		(layer "F.Cu")
		(net "GND")
	)
	(segment
		(start 278.920194 -93.052138)
		(end 279.491694 -93.052138)
		(width 0.254)
		(layer "F.Cu")
		(net "GND")
	)
	(segment
		(start 86.636352 -74.411586)
		(end 86.064852 -74.411586)
		(width 0.254)
		(layer "F.Cu")
		(net "GND")
	)
	(segment
		(start 202.349862 -0.821182)
		(end 202.349862 -2.314956)
		(width 0.4064)
		(layer "F.Cu")
		(net "GND")
	)
	(segment
		(start 145.29943 -6.539738)
		(end 145.082768 -6.7564)
		(width 0.3556)
		(layer "F.Cu")
		(net "GND")
	)
	(segment
		(start 304.675286 -57.390538)
		(end 303.529746 -57.390538)
		(width 0.254)
		(layer "F.Cu")
		(net "GND")
	)
	(segment
		(start 243.149882 -155.3464)
		(end 243.149882 -156.87294)
		(width 0.4064)
		(layer "F.Cu")
		(net "GND")
	)
	(segment
		(start 139.674854 -73.240138)
		(end 140.246354 -73.240138)
		(width 0.254)
		(layer "F.Cu")
		(net "GND")
	)
	(segment
		(start 470.20099 -114.393472)
		(end 470.20099 -112.205516)
		(width 0.381)
		(layer "F.Cu")
		(net "GND")
	)
	(segment
		(start 235.325158 -54.104286)
		(end 234.753658 -54.104286)
		(width 0.254)
		(layer "F.Cu")
		(net "GND")
	)
	(segment
		(start 211.6963 -11.9126)
		(end 211.699856 -11.916156)
		(width 0.254)
		(layer "F.Cu")
		(net "GND")
	)
	(segment
		(start 411.09011 -38.534594)
		(end 410.711904 -38.9128)
		(width 0.254)
		(layer "F.Cu")
		(net "GND")
	)
	(segment
		(start 137.670794 -91.565984)
		(end 137.099294 -91.565984)
		(width 0.254)
		(layer "F.Cu")
		(net "GND")
	)
	(segment
		(start 126.599442 -15.423642)
		(end 126.599442 -13.541756)
		(width 0.4064)
		(layer "F.Cu")
		(net "GND")
	)
	(segment
		(start 272.027904 -140.208)
		(end 270.956532 -140.208)
		(width 0.4572)
		(layer "F.Cu")
		(net "GND")
	)
	(segment
		(start 70.324726 -88.775286)
		(end 69.753226 -88.775286)
		(width 0.254)
		(layer "F.Cu")
		(net "GND")
	)
	(segment
		(start 303.62017 -103.040942)
		(end 303.64557 -103.066342)
		(width 0.254)
		(layer "F.Cu")
		(net "GND")
	)
	(segment
		(start 107.910376 -89.584784)
		(end 108.481876 -89.584784)
		(width 0.254)
		(layer "F.Cu")
		(net "GND")
	)
	(segment
		(start 282.250388 -133.0706)
		(end 282.24988 -133.076442)
		(width 0.3556)
		(layer "F.Cu")
		(net "GND")
	)
	(segment
		(start 130.231388 -83.641184)
		(end 130.802888 -83.641184)
		(width 0.254)
		(layer "F.Cu")
		(net "GND")
	)
	(segment
		(start 138.816334 -78.688438)
		(end 139.387834 -78.688438)
		(width 0.254)
		(layer "F.Cu")
		(net "GND")
	)
	(segment
		(start 113.849404 -148.597112)
		(end 113.849404 -147.277582)
		(width 0.508)
		(layer "F.Cu")
		(net "GND")
	)
	(segment
		(start 97.796858 -56.085486)
		(end 97.225358 -56.085486)
		(width 0.254)
		(layer "F.Cu")
		(net "GND")
	)
	(segment
		(start 457.980288 -53.14442)
		(end 458.14996 -52.974748)
		(width 0.4064)
		(layer "F.Cu")
		(net "GND")
	)
	(segment
		(start 239.617758 -54.59984)
		(end 239.046258 -54.59984)
		(width 0.254)
		(layer "F.Cu")
		(net "GND")
	)
	(segment
		(start 382.64084 -105.15854)
		(end 382.93675 -105.45445)
		(width 0.12446)
		(layer "F.Cu")
		(net "GND")
	)
	(segment
		(start 303.500282 -15.423642)
		(end 303.499774 -15.423642)
		(width 0.4064)
		(layer "F.Cu")
		(net "GND")
	)
	(segment
		(start 429.962056 -3.589782)
		(end 429.962056 -3.776218)
		(width 0.254)
		(layer "F.Cu")
		(net "GND")
	)
	(segment
		(start 79.768192 -78.37424)
		(end 79.196692 -78.37424)
		(width 0.254)
		(layer "F.Cu")
		(net "GND")
	)
	(segment
		(start 109.627416 -95.528384)
		(end 110.198916 -95.528384)
		(width 0.1651)
		(layer "F.Cu")
		(net "GND")
	)
	(segment
		(start 304.349912 0.444754)
		(end 304.349912 -0.821182)
		(width 0.4064)
		(layer "F.Cu")
		(net "GND")
	)
	(segment
		(start 281.399996 -147.27174)
		(end 281.399996 -146.011646)
		(width 0.4064)
		(layer "F.Cu")
		(net "GND")
	)
	(segment
		(start 33.754568 -143.5862)
		(end 33.754568 -144.483582)
		(width 0.3556)
		(layer "F.Cu")
		(net "GND")
	)
	(segment
		(start 463.000852 -118.615714)
		(end 463.004408 -118.61927)
		(width 0.4064)
		(layer "F.Cu")
		(net "GND")
	)
	(segment
		(start 48.399446 -155.612846)
		(end 48.399446 -156.87294)
		(width 0.4064)
		(layer "F.Cu")
		(net "GND")
	)
	(segment
		(start 131.089908 -80.174338)
		(end 131.661408 -80.174338)
		(width 0.254)
		(layer "F.Cu")
		(net "GND")
	)
	(segment
		(start 221.899988 -142.856712)
		(end 221.899734 -142.856966)
		(width 0.4064)
		(layer "F.Cu")
		(net "GND")
	)
	(segment
		(start -4.064 -143.672306)
		(end -4.418838 -143.317468)
		(width 0.254)
		(layer "F.Cu")
		(net "GND")
	)
	(segment
		(start 236.171994 -17.2466)
		(end 236.1184 -17.193006)
		(width 0.3556)
		(layer "F.Cu")
		(net "GND")
	)
	(segment
		(start 398.795748 -123.707906)
		(end 398.679162 -123.59132)
		(width 0.254)
		(layer "F.Cu")
		(net "GND")
	)
	(segment
		(start 284.929834 -88.594184)
		(end 285.501334 -88.594184)
		(width 0.254)
		(layer "F.Cu")
		(net "GND")
	)
	(segment
		(start 294.3733 -55.409338)
		(end 294.9448 -55.409338)
		(width 0.254)
		(layer "F.Cu")
		(net "GND")
	)
	(segment
		(start 249.919744 -55.59044)
		(end 249.348244 -55.59044)
		(width 0.254)
		(layer "F.Cu")
		(net "GND")
	)
	(segment
		(start 40.749474 -20.023582)
		(end 40.749474 -18.744946)
		(width 0.4064)
		(layer "F.Cu")
		(net "GND")
	)
	(segment
		(start 454.949814 -58.954924)
		(end 454.949814 -57.596278)
		(width 0.381)
		(layer "F.Cu")
		(net "GND")
	)
	(segment
		(start 136.74217 -136.410446)
		(end 136.74217 -136.397746)
		(width 0.3556)
		(layer "F.Cu")
		(net "GND")
	)
	(segment
		(start 233.608118 -65.991486)
		(end 233.036618 -65.991486)
		(width 0.254)
		(layer "F.Cu")
		(net "GND")
	)
	(segment
		(start 221.04985 -0.821182)
		(end 221.04985 0.444754)
		(width 0.4064)
		(layer "F.Cu")
		(net "GND")
	)
	(segment
		(start 386.93725 -104.65435)
		(end 387.200648 -104.392222)
		(width 0.12446)
		(layer "F.Cu")
		(net "GND")
	)
	(segment
		(start 406.072086 -4.386072)
		(end 406.072086 -2.669286)
		(width 0.254)
		(layer "F.Cu")
		(net "GND")
	)
	(segment
		(start 386.93725 -107.85475)
		(end 386.64388 -108.14812)
		(width 0.254)
		(layer "F.Cu")
		(net "GND")
	)
	(segment
		(start 279.700482 -10.422382)
		(end 279.699974 -10.422382)
		(width 0.4064)
		(layer "F.Cu")
		(net "GND")
	)
	(segment
		(start 146.149568 -136.46785)
		(end 146.092164 -136.410446)
		(width 0.3556)
		(layer "F.Cu")
		(net "GND")
	)
	(segment
		(start 442.522356 -28.26385)
		(end 442.89091 -28.632404)
		(width 0.3048)
		(layer "F.Cu")
		(net "GND")
	)
	(segment
		(start 449.25488 -33.5915)
		(end 445.106806 -33.5915)
		(width 0.3556)
		(layer "F.Cu")
		(net "GND")
	)
	(segment
		(start 284.799532 -152.279096)
		(end 284.799532 -153.093674)
		(width 0.4064)
		(layer "F.Cu")
		(net "GND")
	)
	(segment
		(start 75.59929 -5.822188)
		(end 75.599544 -5.822442)
		(width 0.4064)
		(layer "F.Cu")
		(net "GND")
	)
	(segment
		(start 383.27965 -116.72316)
		(end 383.77495 -116.953284)
		(width 0.254)
		(layer "F.Cu")
		(net "GND")
	)
	(segment
		(start 78.051406 -83.32724)
		(end 77.479906 -83.32724)
		(width 0.254)
		(layer "F.Cu")
		(net "GND")
	)
	(segment
		(start 70.499478 -136.448546)
		(end 70.461378 -136.410446)
		(width 0.4064)
		(layer "F.Cu")
		(net "GND")
	)
	(segment
		(start 286.500316 -133.0706)
		(end 286.499808 -133.076442)
		(width 0.3556)
		(layer "F.Cu")
		(net "GND")
	)
	(segment
		(start 146.149568 0.38735)
		(end 146.092164 0.444754)
		(width 0.3556)
		(layer "F.Cu")
		(net "GND")
	)
	(segment
		(start 241.334798 -62.52464)
		(end 240.763298 -62.52464)
		(width 0.254)
		(layer "F.Cu")
		(net "GND")
	)
	(segment
		(start 60.299346 -7.509002)
		(end 60.201302 -7.607046)
		(width 0.4064)
		(layer "F.Cu")
		(net "GND")
	)
	(segment
		(start 32.249364 -153.965402)
		(end 32.15132 -154.063446)
		(width 0.4064)
		(layer "F.Cu")
		(net "GND")
	)
	(segment
		(start 118.212362 -100.481638)
		(end 117.925342 -99.986338)
		(width 0.254)
		(layer "F.Cu")
		(net "GND")
	)
	(segment
		(start 241.44986 -0.821182)
		(end 241.44986 -2.314956)
		(width 0.4064)
		(layer "F.Cu")
		(net "GND")
	)
	(segment
		(start 310.0832 2.8448)
		(end 310.0832 1.994662)
		(width 0.3556)
		(layer "F.Cu")
		(net "GND")
	)
	(segment
		(start 408.453336 -64.135)
		(end 407.8351 -64.135)
		(width 0.254)
		(layer "F.Cu")
		(net "GND")
	)
	(segment
		(start 308.59984 -134.763002)
		(end 308.501796 -134.861046)
		(width 0.4064)
		(layer "F.Cu")
		(net "GND")
	)
	(segment
		(start 236.1184 -144.447006)
		(end 236.171994 -144.5006)
		(width 0.3556)
		(layer "F.Cu")
		(net "GND")
	)
	(segment
		(start 407.517854 -54.229)
		(end 407.793698 -54.229)
		(width 0.254)
		(layer "F.Cu")
		(net "GND")
	)
	(segment
		(start 244.768624 -72.43064)
		(end 244.197124 -72.43064)
		(width 0.254)
		(layer "F.Cu")
		(net "GND")
	)
	(segment
		(start 151.24938 -142.6718)
		(end 151.24938 -144.462246)
		(width 0.4064)
		(layer "F.Cu")
		(net "GND")
	)
	(segment
		(start 376.335036 -102.855014)
		(end 376.428 -103.354886)
		(width 0.254)
		(layer "F.Cu")
		(net "GND")
	)
	(segment
		(start 229.091236 -16.696944)
		(end 229.549706 -16.238474)
		(width 0.4064)
		(layer "F.Cu")
		(net "GND")
	)
	(segment
		(start 385.985004 -95.205042)
		(end 384.985006 -95.205042)
		(width 0.254)
		(layer "F.Cu")
		(net "GND")
	)
	(segment
		(start 416.690048 -35.334702)
		(end 416.289998 -34.934652)
		(width 0.254)
		(layer "F.Cu")
		(net "GND")
	)
	(segment
		(start 307.750464 -10.422382)
		(end 307.749956 -10.422382)
		(width 0.4064)
		(layer "F.Cu")
		(net "GND")
	)
	(segment
		(start 68.607686 -88.775286)
		(end 68.036186 -88.775286)
		(width 0.254)
		(layer "F.Cu")
		(net "GND")
	)
	(segment
		(start 399.219928 -96.3549)
		(end 399.050764 -96.524064)
		(width 0.2032)
		(layer "F.Cu")
		(net "GND")
	)
	(segment
		(start 119.7991 -15.423896)
		(end 119.799354 -15.423642)
		(width 0.4064)
		(layer "F.Cu")
		(net "GND")
	)
	(segment
		(start 89.211912 -53.322474)
		(end 89.498678 -53.60924)
		(width 0.254)
		(layer "F.Cu")
		(net "GND")
	)
	(segment
		(start 62.849506 0.38735)
		(end 62.849506 -0.821182)
		(width 0.3556)
		(layer "F.Cu")
		(net "GND")
	)
	(segment
		(start 207.449928 -0.821182)
		(end 207.449928 0.444754)
		(width 0.4064)
		(layer "F.Cu")
		(net "GND")
	)
	(segment
		(start 199.742552 -18.744946)
		(end 199.742552 -18.970498)
		(width 0.4064)
		(layer "F.Cu")
		(net "GND")
	)
	(segment
		(start 231.249982 -152.278842)
		(end 231.249982 -152.457912)
		(width 0.4064)
		(layer "F.Cu")
		(net "GND")
	)
	(segment
		(start 466.09 -148.9075)
		(end 465.732368 -148.9075)
		(width 0.254)
		(layer "F.Cu")
		(net "GND")
	)
	(segment
		(start 138.816334 -51.941984)
		(end 138.816334 -51.429666)
		(width 0.254)
		(layer "F.Cu")
		(net "GND")
	)
	(segment
		(start 46.699424 -0.821182)
		(end 46.699424 -2.314956)
		(width 0.4064)
		(layer "F.Cu")
		(net "GND")
	)
	(segment
		(start 290.0807 -91.565984)
		(end 290.6522 -91.565984)
		(width 0.254)
		(layer "F.Cu")
		(net "GND")
	)
	(segment
		(start 291.79774 -73.735184)
		(end 292.36924 -73.735184)
		(width 0.254)
		(layer "F.Cu")
		(net "GND")
	)
	(segment
		(start 449.326 -21.209)
		(end 448.5894 -21.209)
		(width 0.254)
		(layer "F.Cu")
		(net "GND")
	)
	(segment
		(start 85.777832 -64.010286)
		(end 85.206332 -64.010286)
		(width 0.254)
		(layer "F.Cu")
		(net "GND")
	)
	(segment
		(start 353.218242 -146.488912)
		(end 352.802444 -146.90471)
		(width 0.381)
		(layer "F.Cu")
		(net "GND")
	)
	(segment
		(start 72.041766 -56.085486)
		(end 71.470266 -56.085486)
		(width 0.254)
		(layer "F.Cu")
		(net "GND")
	)
	(segment
		(start 288.36366 -70.763384)
		(end 288.93516 -70.763384)
		(width 0.254)
		(layer "F.Cu")
		(net "GND")
	)
	(segment
		(start 306.900326 3.778758)
		(end 306.899818 3.778758)
		(width 0.4064)
		(layer "F.Cu")
		(net "GND")
	)
	(segment
		(start 287.349946 -18.757646)
		(end 287.349946 -20.023582)
		(width 0.4064)
		(layer "F.Cu")
		(net "GND")
	)
	(segment
		(start 232.94975 -133.076696)
		(end 232.94975 -134.861046)
		(width 0.4064)
		(layer "F.Cu")
		(net "GND")
	)
	(segment
		(start 286.499808 -142.677642)
		(end 286.499808 -144.462246)
		(width 0.4064)
		(layer "F.Cu")
		(net "GND")
	)
	(segment
		(start 119.070882 -102.958138)
		(end 118.783862 -103.453184)
		(width 0.4064)
		(layer "F.Cu")
		(net "GND")
	)
	(segment
		(start 224.450402 -20.023582)
		(end 224.449894 -20.023582)
		(width 0.4064)
		(layer "F.Cu")
		(net "GND")
	)
	(segment
		(start 202.349862 -136.410446)
		(end 202.349862 -137.67054)
		(width 0.4064)
		(layer "F.Cu")
		(net "GND")
	)
	(segment
		(start 136.799574 -2.253488)
		(end 136.74217 -2.310892)
		(width 0.4064)
		(layer "F.Cu")
		(net "GND")
	)
	(segment
		(start 253.353824 -87.28964)
		(end 252.782324 -87.28964)
		(width 0.254)
		(layer "F.Cu")
		(net "GND")
	)
	(segment
		(start 118.041928 -18.744946)
		(end 118.041928 -18.757646)
		(width 0.3556)
		(layer "F.Cu")
		(net "GND")
	)
	(segment
		(start 394.67155 -121.01576)
		(end 395.16685 -121.245884)
		(width 0.254)
		(layer "F.Cu")
		(net "GND")
	)
	(segment
		(start 110.485682 -90.080338)
		(end 111.057182 -90.080338)
		(width 0.254)
		(layer "F.Cu")
		(net "GND")
	)
	(segment
		(start 280.549858 -3.826256)
		(end 280.460958 -3.737356)
		(width 0.4064)
		(layer "F.Cu")
		(net "GND")
	)
	(segment
		(start 463.7659 -22.3901)
		(end 464.058 -22.098)
		(width 0.254)
		(layer "F.Cu")
		(net "GND")
	)
	(segment
		(start 399.634964 -96.855026)
		(end 399.219928 -96.3549)
		(width 0.254)
		(layer "F.Cu")
		(net "GND")
	)
	(segment
		(start 394.903706 -96.86925)
		(end 395.16685 -96.747076)
		(width 0.254)
		(layer "F.Cu")
		(net "GND")
	)
	(segment
		(start 390.66724 -152.55494)
		(end 390.66724 -152.008586)
		(width 0.254)
		(layer "F.Cu")
		(net "GND")
	)
	(segment
		(start 284.071314 -62.343538)
		(end 283.499814 -62.343538)
		(width 0.254)
		(layer "F.Cu")
		(net "GND")
	)
	(segment
		(start 93.504258 -60.54344)
		(end 92.932758 -60.54344)
		(width 0.254)
		(layer "F.Cu")
		(net "GND")
	)
	(segment
		(start 415.890202 -30.53461)
		(end 415.890456 -30.53461)
		(width 0.254)
		(layer "F.Cu")
		(net "GND")
	)
	(segment
		(start 238.8997 -133.076696)
		(end 238.8997 -133.891274)
		(width 0.4064)
		(layer "F.Cu")
		(net "GND")
	)
	(segment
		(start 77.299566 -152.273)
		(end 77.299566 -150.23211)
		(width 0.508)
		(layer "F.Cu")
		(net "GND")
	)
	(segment
		(start 76.449428 -147.277582)
		(end 76.449428 -148.771356)
		(width 0.508)
		(layer "F.Cu")
		(net "GND")
	)
	(segment
		(start 312.850276 -15.423642)
		(end 312.849768 -15.423642)
		(width 0.4064)
		(layer "F.Cu")
		(net "GND")
	)
	(segment
		(start 230.399844 -18.757646)
		(end 230.399844 -20.023582)
		(width 0.4064)
		(layer "F.Cu")
		(net "GND")
	)
	(segment
		(start 262.79729 -88.775286)
		(end 262.22579 -88.775286)
		(width 0.254)
		(layer "F.Cu")
		(net "GND")
	)
	(segment
		(start 462.143348 -52.2478)
		(end 462.140046 -51.875944)
		(width 0.4064)
		(layer "F.Cu")
		(net "GND")
	)
	(segment
		(start 294.14978 -16.238474)
		(end 294.14978 -15.423642)
		(width 0.4064)
		(layer "F.Cu")
		(net "GND")
	)
	(segment
		(start 304.388266 -53.923184)
		(end 303.816766 -53.923184)
		(width 0.254)
		(layer "F.Cu")
		(net "GND")
	)
	(segment
		(start 381.782574 -115.231164)
		(end 381.79375 -115.261644)
		(width 0.254)
		(layer "F.Cu")
		(net "GND")
	)
	(segment
		(start 397.558768 -122.065034)
		(end 397.64335 -122.104404)
		(width 0.254)
		(layer "F.Cu")
		(net "GND")
	)
	(segment
		(start 449.33235 -50.5206)
		(end 449.33235 -50.515774)
		(width 0.508)
		(layer "F.Cu")
		(net "GND")
	)
	(segment
		(start 450.940932 -46.021752)
		(end 450.940932 -47.481998)
		(width 0.4064)
		(layer "F.Cu")
		(net "GND")
	)
	(segment
		(start 301.812706 -63.125604)
		(end 301.812706 -63.334138)
		(width 0.254)
		(layer "F.Cu")
		(net "GND")
	)
	(segment
		(start 214.250016 -152.278842)
		(end 214.249762 -152.279096)
		(width 0.4064)
		(layer "F.Cu")
		(net "GND")
	)
	(segment
		(start 41.599358 -144.364202)
		(end 41.501314 -144.462246)
		(width 0.4064)
		(layer "F.Cu")
		(net "GND")
	)
	(segment
		(start 34.74212 0.457454)
		(end 34.74212 0.231902)
		(width 0.4064)
		(layer "F.Cu")
		(net "GND")
	)
	(segment
		(start 392.405616 -84.838032)
		(end 392.405616 -84.860384)
		(width 0.254)
		(layer "F.Cu")
		(net "GND")
	)
	(segment
		(start 317.950342 -133.0706)
		(end 317.949834 -133.076442)
		(width 0.4064)
		(layer "F.Cu")
		(net "GND")
	)
	(segment
		(start 382.797304 -27.770836)
		(end 383.942336 -27.770836)
		(width 0.254)
		(layer "F.Cu")
		(net "GND")
	)
	(segment
		(start 284.929834 -64.819784)
		(end 284.358334 -64.819784)
		(width 0.254)
		(layer "F.Cu")
		(net "GND")
	)
	(segment
		(start 121.646188 -69.772784)
		(end 122.217688 -69.772784)
		(width 0.254)
		(layer "F.Cu")
		(net "GND")
	)
	(segment
		(start 99.513898 -95.709486)
		(end 98.942398 -95.709486)
		(width 0.254)
		(layer "F.Cu")
		(net "GND")
	)
	(segment
		(start 285.7881 -50.8127)
		(end 285.8262 -50.7746)
		(width 0.254)
		(layer "F.Cu")
		(net "GND")
	)
	(segment
		(start 130.231388 -57.885584)
		(end 130.802888 -57.885584)
		(width 0.254)
		(layer "F.Cu")
		(net "GND")
	)
	(segment
		(start 45.849286 -143.492474)
		(end 45.390816 -143.950944)
		(width 0.4064)
		(layer "F.Cu")
		(net "GND")
	)
	(segment
		(start 67.099434 -20.023582)
		(end 67.099434 -21.517356)
		(width 0.4064)
		(layer "F.Cu")
		(net "GND")
	)
	(segment
		(start 272.624042 -101.968046)
		(end 272.910808 -102.462584)
		(width 0.254)
		(layer "F.Cu")
		(net "GND")
	)
	(segment
		(start 239.617758 -90.26144)
		(end 239.046258 -90.26144)
		(width 0.254)
		(layer "F.Cu")
		(net "GND")
	)
	(segment
		(start 229.550468 -133.0706)
		(end 229.54996 -133.076442)
		(width 0.4064)
		(layer "F.Cu")
		(net "GND")
	)
	(segment
		(start 388.021322 -112.141)
		(end 387.73735 -111.857028)
		(width 0.1143)
		(layer "F.Cu")
		(net "GND")
	)
	(segment
		(start 60.299346 -142.6718)
		(end 60.299346 -144.364202)
		(width 0.4064)
		(layer "F.Cu")
		(net "GND")
	)
	(segment
		(start 165.672008 -85.533992)
		(end 164.9984 -86.2076)
		(width 0.254)
		(layer "F.Cu")
		(net "GND")
	)
	(segment
		(start 317.100458 -0.821182)
		(end 317.09995 -0.821182)
		(width 0.4064)
		(layer "F.Cu")
		(net "GND")
	)
	(segment
		(start 130.84937 -15.423642)
		(end 130.84937 -13.363956)
		(width 0.4064)
		(layer "F.Cu")
		(net "GND")
	)
	(segment
		(start 301.241206 -56.399938)
		(end 301.812706 -56.399938)
		(width 0.254)
		(layer "F.Cu")
		(net "GND")
	)
	(segment
		(start 227.849938 -11.854688)
		(end 227.849938 -10.422382)
		(width 0.4064)
		(layer "F.Cu")
		(net "GND")
	)
	(segment
		(start 346.926154 -9.182354)
		(end 346.926154 -8.787638)
		(width 0.254)
		(layer "F.Cu")
		(net "GND")
	)
	(segment
		(start 118.50116 -52.443634)
		(end 118.361968 -52.684172)
		(width 0.254)
		(layer "F.Cu")
		(net "GND")
	)
	(segment
		(start 308.600348 -142.6718)
		(end 308.59984 -142.677642)
		(width 0.4064)
		(layer "F.Cu")
		(net "GND")
	)
	(segment
		(start 130.231388 -96.518984)
		(end 130.802888 -96.518984)
		(width 0.254)
		(layer "F.Cu")
		(net "GND")
	)
	(segment
		(start 53.499512 0.38735)
		(end 53.442108 0.444754)
		(width 0.3556)
		(layer "F.Cu")
		(net "GND")
	)
	(segment
		(start 166.8526 -122.50166)
		(end 166.8526 -122.68962)
		(width 0.254)
		(layer "F.Cu")
		(net "GND")
	)
	(segment
		(start 53.499512 -155.67025)
		(end 53.442108 -155.612846)
		(width 0.3556)
		(layer "F.Cu")
		(net "GND")
	)
	(segment
		(start 273.769328 -98.005138)
		(end 274.340828 -98.005138)
		(width 0.254)
		(layer "F.Cu")
		(net "GND")
	)
	(segment
		(start 61.999368 -152.273)
		(end 61.999368 -153.009854)
		(width 0.3556)
		(layer "F.Cu")
		(net "GND")
	)
	(segment
		(start 455.920602 -144.719802)
		(end 455.676 -144.4752)
		(width 0.254)
		(layer "F.Cu")
		(net "GND")
	)
	(segment
		(start 112.202722 -89.089738)
		(end 112.202722 -88.518238)
		(width 0.381)
		(layer "F.Cu")
		(net "GND")
	)
	(segment
		(start 243.051838 -72.43064)
		(end 242.480338 -72.43064)
		(width 0.254)
		(layer "F.Cu")
		(net "GND")
	)
	(segment
		(start 485.5845 -34.690812)
		(end 485.5845 -33.78454)
		(width 0.254)
		(layer "F.Cu")
		(net "GND")
	)
	(segment
		(start 4.88315 -14.274292)
		(end 4.88315 -14.367764)
		(width 0.254)
		(layer "F.Cu")
		(net "GND")
	)
	(segment
		(start 131.948174 -76.706984)
		(end 132.519674 -76.706984)
		(width 0.254)
		(layer "F.Cu")
		(net "GND")
	)
	(segment
		(start 193.6369 -86.33714)
		(end 193.74104 -86.233)
		(width 0.254)
		(layer "F.Cu")
		(net "GND")
	)
	(segment
		(start 366.2172 -93.3831)
		(end 366.5474 -93.7133)
		(width 0.254)
		(layer "F.Cu")
		(net "GND")
	)
	(segment
		(start 182.890922 -152.370282)
		(end 183.541924 -153.021284)
		(width 0.254)
		(layer "F.Cu")
		(net "GND")
	)
	(segment
		(start 196.743828 -53.897022)
		(end 196.743828 -53.856382)
		(width 0.254)
		(layer "F.Cu")
		(net "GND")
	)
	(segment
		(start 301.241206 -86.117938)
		(end 301.812706 -86.117938)
		(width 0.3048)
		(layer "F.Cu")
		(net "GND")
	)
	(segment
		(start 208.30032 -5.822442)
		(end 208.299812 -5.822442)
		(width 0.3556)
		(layer "F.Cu")
		(net "GND")
	)
	(segment
		(start 235.325158 -67.972686)
		(end 234.753658 -67.972686)
		(width 0.254)
		(layer "F.Cu")
		(net "GND")
	)
	(segment
		(start 379.81255 -113.519204)
		(end 379.31725 -113.28908)
		(width 0.254)
		(layer "F.Cu")
		(net "GND")
	)
	(segment
		(start 240.599722 -17.208246)
		(end 240.599722 -15.602966)
		(width 0.4064)
		(layer "F.Cu")
		(net "GND")
	)
	(segment
		(start 312.391298 2.505456)
		(end 312.849768 2.963926)
		(width 0.4064)
		(layer "F.Cu")
		(net "GND")
	)
	(segment
		(start 394.668248 -118.6688)
		(end 394.67155 -118.670324)
		(width 0.254)
		(layer "F.Cu")
		(net "GND")
	)
	(segment
		(start 87.494872 -66.982086)
		(end 86.923372 -66.982086)
		(width 0.254)
		(layer "F.Cu")
		(net "GND")
	)
	(segment
		(start 78.593696 -150.114)
		(end 78.204568 -150.114)
		(width 0.508)
		(layer "F.Cu")
		(net "GND")
	)
	(segment
		(start 174.7774 -146.939)
		(end 174.371 -146.939)
		(width 0.254)
		(layer "F.Cu")
		(net "GND")
	)
	(segment
		(start 381.20828 -31.62808)
		(end 380.902972 -31.62808)
		(width 0.254)
		(layer "F.Cu")
		(net "GND")
	)
	(segment
		(start 321.437 -130.3528)
		(end 321.558412 -130.474212)
		(width 0.4064)
		(layer "F.Cu")
		(net "GND")
	)
	(segment
		(start 207.449928 -136.435846)
		(end 207.449928 -137.67054)
		(width 0.4064)
		(layer "F.Cu")
		(net "GND")
	)
	(segment
		(start 141.391894 -85.127338)
		(end 141.963394 -85.127338)
		(width 0.254)
		(layer "F.Cu")
		(net "GND")
	)
	(segment
		(start 345.277948 -12.41933)
		(end 345.277948 -12.9159)
		(width 0.2032)
		(layer "F.Cu")
		(net "GND")
	)
	(segment
		(start 260.50875 -53.113686)
		(end 261.08025 -53.113686)
		(width 0.254)
		(layer "F.Cu")
		(net "GND")
	)
	(segment
		(start 111.344202 -99.490784)
		(end 111.915702 -99.490784)
		(width 0.254)
		(layer "F.Cu")
		(net "GND")
	)
	(segment
		(start 107.62361 -101.968046)
		(end 107.910376 -102.462584)
		(width 0.254)
		(layer "F.Cu")
		(net "GND")
	)
	(segment
		(start 168.189402 -64.3509)
		(end 168.189402 -63.890398)
		(width 0.2032)
		(layer "F.Cu")
		(net "GND")
	)
	(segment
		(start 182.1942 -76.3778)
		(end 182.1942 -75.565)
		(width 0.4064)
		(layer "F.Cu")
		(net "GND")
	)
	(segment
		(start 67.949318 -17.208246)
		(end 67.949318 -15.423896)
		(width 0.4064)
		(layer "F.Cu")
		(net "GND")
	)
	(segment
		(start 238.899954 -14.410182)
		(end 238.437928 -13.948156)
		(width 0.4064)
		(layer "F.Cu")
		(net "GND")
	)
	(segment
		(start 376.7836 -111.2774)
		(end 376.460004 -110.9726)
		(width 0.254)
		(layer "F.Cu")
		(net "GND")
	)
	(segment
		(start 455.40549 -34.744406)
		(end 455.40549 -34.0614)
		(width 0.254)
		(layer "F.Cu")
		(net "GND")
	)
	(segment
		(start 49.24933 -15.423896)
		(end 49.249584 -15.423642)
		(width 0.4064)
		(layer "F.Cu")
		(net "GND")
	)
	(segment
		(start 55.19928 -153.093674)
		(end 54.74081 -153.552144)
		(width 0.4064)
		(layer "F.Cu")
		(net "GND")
	)
	(segment
		(start 485.0638 -141.9606)
		(end 486.537 -141.9606)
		(width 0.254)
		(layer "F.Cu")
		(net "GND")
	)
	(segment
		(start 379.81255 -104.473756)
		(end 379.81255 -103.84536)
		(width 0.254)
		(layer "F.Cu")
		(net "GND")
	)
	(segment
		(start 305.533806 -84.631784)
		(end 306.105306 -84.631784)
		(width 0.1016)
		(layer "F.Cu")
		(net "GND")
	)
	(segment
		(start 125.080268 -61.847984)
		(end 125.651768 -61.847984)
		(width 0.254)
		(layer "F.Cu")
		(net "GND")
	)
	(segment
		(start 208.299812 3.778758)
		(end 208.299812 3.042666)
		(width 0.3556)
		(layer "F.Cu")
		(net "GND")
	)
	(segment
		(start 282.0162 -143.637254)
		(end 282.0162 -144.44472)
		(width 0.3556)
		(layer "F.Cu")
		(net "GND")
	)
	(segment
		(start 478.524062 -135.265414)
		(end 479.381058 -135.265414)
		(width 0.381)
		(layer "F.Cu")
		(net "GND")
	)
	(segment
		(start 291.600382 -142.6718)
		(end 291.599874 -142.677642)
		(width 0.3556)
		(layer "F.Cu")
		(net "GND")
	)
	(segment
		(start 81.479136 -52.61229)
		(end 81.479136 -51.617626)
		(width 0.2032)
		(layer "F.Cu")
		(net "GND")
	)
	(segment
		(start 409.18257 -55.617872)
		(end 409.862528 -55.617872)
		(width 0.254)
		(layer "F.Cu")
		(net "GND")
	)
	(segment
		(start 109.627416 -56.894984)
		(end 109.055916 -56.894984)
		(width 0.254)
		(layer "F.Cu")
		(net "GND")
	)
	(segment
		(start 382.98501 -125.33503)
		(end 383.091182 -125.441202)
		(width 0.254)
		(layer "F.Cu")
		(net "GND")
	)
	(segment
		(start 290.0807 -99.490784)
		(end 290.6522 -99.490784)
		(width 0.254)
		(layer "F.Cu")
		(net "GND")
	)
	(segment
		(start 383.091182 -126.05893)
		(end 382.98501 -126.165102)
		(width 0.254)
		(layer "F.Cu")
		(net "GND")
	)
	(segment
		(start 145.082768 -16.3576)
		(end 145.082768 -17.207738)
		(width 0.3556)
		(layer "F.Cu")
		(net "GND")
	)
	(segment
		(start 133.665214 -74.725784)
		(end 134.236714 -74.725784)
		(width 0.254)
		(layer "F.Cu")
		(net "GND")
	)
	(segment
		(start 209.14995 -2.253488)
		(end 209.14995 -0.821182)
		(width 0.4064)
		(layer "F.Cu")
		(net "GND")
	)
	(segment
		(start 227.850446 -0.821182)
		(end 227.849938 -0.821182)
		(width 0.3556)
		(layer "F.Cu")
		(net "GND")
	)
	(segment
		(start 239.617758 -62.52464)
		(end 239.046258 -62.52464)
		(width 0.254)
		(layer "F.Cu")
		(net "GND")
	)
	(segment
		(start 86.636352 -89.27084)
		(end 86.064852 -89.27084)
		(width 0.254)
		(layer "F.Cu")
		(net "GND")
	)
	(segment
		(start 299.524166 -79.183738)
		(end 300.095666 -79.183738)
		(width 0.254)
		(layer "F.Cu")
		(net "GND")
	)
	(segment
		(start 449.334128 -50.759868)
		(end 449.333112 -50.6222)
		(width 0.508)
		(layer "F.Cu")
		(net "GND")
	)
	(segment
		(start 351.235518 -11.1506)
		(end 350.981518 -11.4046)
		(width 0.254)
		(layer "F.Cu")
		(net "GND")
	)
	(segment
		(start 298.399962 -11.916156)
		(end 296.69994 -11.916156)
		(width 0.254)
		(layer "F.Cu")
		(net "GND")
	)
	(segment
		(start 394.17625 -109.13872)
		(end 394.17625 -109.855)
		(width 0.254)
		(layer "F.Cu")
		(net "GND")
	)
	(segment
		(start 121.646188 -87.603584)
		(end 122.217688 -87.603584)
		(width 0.254)
		(layer "F.Cu")
		(net "GND")
	)
	(segment
		(start 387.73735 -102.756716)
		(end 387.24205 -102.98684)
		(width 0.254)
		(layer "F.Cu")
		(net "GND")
	)
	(segment
		(start 460.600806 -112.205516)
		(end 460.600806 -113.777014)
		(width 0.4064)
		(layer "F.Cu")
		(net "GND")
	)
	(segment
		(start 145.082768 1.994662)
		(end 145.12163 1.9558)
		(width 0.3556)
		(layer "F.Cu")
		(net "GND")
	)
	(segment
		(start 399.634964 -109.855)
		(end 398.63395 -109.624876)
		(width 0.254)
		(layer "F.Cu")
		(net "GND")
	)
	(segment
		(start 69.64934 -5.822442)
		(end 69.64934 -4.7371)
		(width 0.4064)
		(layer "F.Cu")
		(net "GND")
	)
	(segment
		(start 119.327168 -11.9634)
		(end 120.602248 -11.9634)
		(width 0.4064)
		(layer "F.Cu")
		(net "GND")
	)
	(segment
		(start 212.549994 -133.076442)
		(end 212.549994 -133.255512)
		(width 0.4064)
		(layer "F.Cu")
		(net "GND")
	)
	(segment
		(start 42.449496 -21.479256)
		(end 42.411396 -21.517356)
		(width 0.4064)
		(layer "F.Cu")
		(net "GND")
	)
	(segment
		(start 259.65023 -88.28024)
		(end 260.22173 -88.28024)
		(width 0.254)
		(layer "F.Cu")
		(net "GND")
	)
	(segment
		(start 31.366968 -139.202668)
		(end 31.39948 -139.170156)
		(width 0.4064)
		(layer "F.Cu")
		(net "GND")
	)
	(segment
		(start 91.742768 -140.208)
		(end 91.460574 -140.490194)
		(width 0.4064)
		(layer "F.Cu")
		(net "GND")
	)
	(segment
		(start 55.19928 -16.238474)
		(end 54.74081 -16.696944)
		(width 0.4064)
		(layer "F.Cu")
		(net "GND")
	)
	(segment
		(start 289.22218 -62.343538)
		(end 288.65068 -62.343538)
		(width 0.254)
		(layer "F.Cu")
		(net "GND")
	)
	(segment
		(start 218.499944 -136.46785)
		(end 218.44254 -136.410446)
		(width 0.3556)
		(layer "F.Cu")
		(net "GND")
	)
	(segment
		(start 421.273986 -7.789672)
		(end 421.273986 -9.62406)
		(width 0.254)
		(layer "F.Cu")
		(net "GND")
	)
	(segment
		(start 234.649772 -134.763002)
		(end 234.551728 -134.861046)
		(width 0.4064)
		(layer "F.Cu")
		(net "GND")
	)
	(segment
		(start 462.078578 -8.866378)
		(end 462.2292 -9.017)
		(width 0.254)
		(layer "F.Cu")
		(net "GND")
	)
	(segment
		(start 119.282972 -13.8938)
		(end 119.337328 -13.948156)
		(width 0.4064)
		(layer "F.Cu")
		(net "GND")
	)
	(segment
		(start 119.7991 -153.093674)
		(end 119.34063 -153.552144)
		(width 0.4064)
		(layer "F.Cu")
		(net "GND")
	)
	(segment
		(start 401.295108 -124.660914)
		(end 401.368768 -124.735844)
		(width 0.254)
		(layer "F.Cu")
		(net "GND")
	)
	(segment
		(start 384.27025 -120.15724)
		(end 384.76555 -120.387364)
		(width 0.254)
		(layer "F.Cu")
		(net "GND")
	)
	(segment
		(start 290.0807 -63.829184)
		(end 290.6522 -63.829184)
		(width 0.254)
		(layer "F.Cu")
		(net "GND")
	)
	(segment
		(start 272.910808 -89.584784)
		(end 273.482308 -89.584784)
		(width 0.254)
		(layer "F.Cu")
		(net "GND")
	)
	(segment
		(start 34.74212 -21.513292)
		(end 34.799524 -21.455888)
		(width 0.4064)
		(layer "F.Cu")
		(net "GND")
	)
	(segment
		(start 118.031768 -13.8938)
		(end 119.282972 -13.8938)
		(width 0.4064)
		(layer "F.Cu")
		(net "GND")
	)
	(segment
		(start -0.254 -143.256)
		(end -1.2192 -143.256)
		(width 0.381)
		(layer "F.Cu")
		(net "GND")
	)
	(segment
		(start 440.206384 -152.614376)
		(end 440.206384 -151.83993)
		(width 0.254)
		(layer "F.Cu")
		(net "GND")
	)
	(segment
		(start 199.799956 0.174498)
		(end 199.742552 0.231902)
		(width 0.4064)
		(layer "F.Cu")
		(net "GND")
	)
	(segment
		(start 375.92 -100.354892)
		(end 376.428 -100.354892)
		(width 0.254)
		(layer "F.Cu")
		(net "GND")
	)
	(segment
		(start 139.0904 -51.1556)
		(end 139.1412 -51.1556)
		(width 0.254)
		(layer "F.Cu")
		(net "GND")
	)
	(segment
		(start 56.899556 -142.856712)
		(end 56.899302 -142.856966)
		(width 0.4064)
		(layer "F.Cu")
		(net "GND")
	)
	(segment
		(start 43.076368 2.001012)
		(end 43.12158 1.9558)
		(width 0.3556)
		(layer "F.Cu")
		(net "GND")
	)
	(segment
		(start 304.675286 -61.352938)
		(end 305.246786 -61.352938)
		(width 0.254)
		(layer "F.Cu")
		(net "GND")
	)
	(segment
		(start 198.099934 -137.67054)
		(end 198.099934 -136.410446)
		(width 0.4064)
		(layer "F.Cu")
		(net "GND")
	)
	(segment
		(start 448.534028 -51.869086)
		(end 448.534028 -50.73904)
		(width 0.508)
		(layer "F.Cu")
		(net "GND")
	)
	(segment
		(start 495.3 -54.075584)
		(end 495.3 -52.804822)
		(width 0.254)
		(layer "F.Cu")
		(net "GND")
	)
	(segment
		(start 199.799956 -136.680702)
		(end 199.742552 -136.623298)
		(width 0.4064)
		(layer "F.Cu")
		(net "GND")
	)
	(segment
		(start 307.749956 -18.744946)
		(end 307.749956 -20.023582)
		(width 0.4064)
		(layer "F.Cu")
		(net "GND")
	)
	(segment
		(start 242.193318 -58.06694)
		(end 241.621818 -58.06694)
		(width 0.254)
		(layer "F.Cu")
		(net "GND")
	)
	(segment
		(start 215.100408 -137.67054)
		(end 215.0999 -137.67054)
		(width 0.4064)
		(layer "F.Cu")
		(net "GND")
	)
	(segment
		(start 385.844288 -112.148112)
		(end 386.13715 -111.85525)
		(width 0.12446)
		(layer "F.Cu")
		(net "GND")
	)
	(segment
		(start 278.9682 -140.4874)
		(end 278.3332 -140.4874)
		(width 0.4572)
		(layer "F.Cu")
		(net "GND")
	)
	(segment
		(start 131.948174 -58.876438)
		(end 132.519674 -58.876438)
		(width 0.254)
		(layer "F.Cu")
		(net "GND")
	)
	(segment
		(start 414.528 -16.383)
		(end 415.2392 -16.383)
		(width 0.254)
		(layer "F.Cu")
		(net "GND")
	)
	(segment
		(start 81.485232 -76.39304)
		(end 80.913732 -76.39304)
		(width 0.254)
		(layer "F.Cu")
		(net "GND")
	)
	(segment
		(start 61.149484 -20.023582)
		(end 61.149484 -21.479256)
		(width 0.4064)
		(layer "F.Cu")
		(net "GND")
	)
	(segment
		(start 462.627218 -45.611796)
		(end 462.940908 -45.925486)
		(width 0.4064)
		(layer "F.Cu")
		(net "GND")
	)
	(segment
		(start 466.2297 -118.58498)
		(end 466.204554 -118.559834)
		(width 0.4064)
		(layer "F.Cu")
		(net "GND")
	)
	(segment
		(start 457.252578 -134.821422)
		(end 457.252578 -135.71982)
		(width 0.254)
		(layer "F.Cu")
		(net "GND")
	)
	(segment
		(start 449.948554 -60.633864)
		(end 449.948554 -60.378848)
		(width 0.381)
		(layer "F.Cu")
		(net "GND")
	)
	(segment
		(start 367.145316 -68.695316)
		(end 367.545112 -69.095112)
		(width 0.254)
		(layer "F.Cu")
		(net "GND")
	)
	(segment
		(start 440.227212 -45.611796)
		(end 440.540902 -45.925486)
		(width 0.4064)
		(layer "F.Cu")
		(net "GND")
	)
	(segment
		(start 71.183246 -76.39304)
		(end 70.611746 -76.39304)
		(width 0.254)
		(layer "F.Cu")
		(net "GND")
	)
	(segment
		(start 117.015768 -153.238454)
		(end 117.015768 -154.04592)
		(width 0.3556)
		(layer "F.Cu")
		(net "GND")
	)
	(segment
		(start 387.73735 -111.85525)
		(end 387.3373 -112.2553)
		(width 0.12446)
		(layer "F.Cu")
		(net "GND")
	)
	(segment
		(start 117.015768 -17.19072)
		(end 117.015768 -16.383254)
		(width 0.3556)
		(layer "F.Cu")
		(net "GND")
	)
	(segment
		(start 453.514968 -2.725166)
		(end 453.514968 -2.74574)
		(width 0.4064)
		(layer "F.Cu")
		(net "GND")
	)
	(segment
		(start 220.199712 -152.279096)
		(end 220.199712 -153.093674)
		(width 0.4064)
		(layer "F.Cu")
		(net "GND")
	)
	(segment
		(start 198.061834 -2.314956)
		(end 198.099934 -2.276856)
		(width 0.4064)
		(layer "F.Cu")
		(net "GND")
	)
	(segment
		(start 140.8176 -91.281758)
		(end 140.8176 -90.9574)
		(width 0.254)
		(layer "F.Cu")
		(net "GND")
	)
	(segment
		(start 419.316408 -49.32299)
		(end 419.316408 -48.953166)
		(width 0.254)
		(layer "F.Cu")
		(net "GND")
	)
	(segment
		(start 296.69994 -2.314956)
		(end 296.69994 -0.821182)
		(width 0.4064)
		(layer "F.Cu")
		(net "GND")
	)
	(segment
		(start 102.947724 -53.113686)
		(end 103.557324 -53.113686)
		(width 0.254)
		(layer "F.Cu")
		(net "GND")
	)
	(segment
		(start 136.74217 -9.156446)
		(end 136.799574 -9.21385)
		(width 0.3556)
		(layer "F.Cu")
		(net "GND")
	)
	(segment
		(start 246.479568 -52.61229)
		(end 246.479568 -51.617626)
		(width 0.2032)
		(layer "F.Cu")
		(net "GND")
	)
	(segment
		(start 399.674334 -92.837)
		(end 399.674334 -93.544898)
		(width 0.254)
		(layer "F.Cu")
		(net "GND")
	)
	(segment
		(start 394.568426 -74.163174)
		(end 393.627102 -74.163174)
		(width 0.254)
		(layer "F.Cu")
		(net "GND")
	)
	(segment
		(start 118.099332 -136.46785)
		(end 118.041928 -136.410446)
		(width 0.3556)
		(layer "F.Cu")
		(net "GND")
	)
	(segment
		(start 272.052288 -51.446938)
		(end 272.052288 -50.694082)
		(width 0.254)
		(layer "F.Cu")
		(net "GND")
	)
	(segment
		(start 299.249846 -134.763002)
		(end 299.151802 -134.861046)
		(width 0.4064)
		(layer "F.Cu")
		(net "GND")
	)
	(segment
		(start 278.849836 -133.076442)
		(end 278.850344 -133.0706)
		(width 0.4064)
		(layer "F.Cu")
		(net "GND")
	)
	(segment
		(start 375.504964 -106.855006)
		(end 376.335036 -106.855006)
		(width 0.254)
		(layer "F.Cu")
		(net "GND")
	)
	(segment
		(start 315.399928 -137.67054)
		(end 315.399928 -136.410446)
		(width 0.4064)
		(layer "F.Cu")
		(net "GND")
	)
	(segment
		(start 207.424528 -18.757646)
		(end 207.411828 -18.757646)
		(width 0.4064)
		(layer "F.Cu")
		(net "GND")
	)
	(segment
		(start 235.325158 -85.803486)
		(end 234.753658 -85.803486)
		(width 0.254)
		(layer "F.Cu")
		(net "GND")
	)
	(segment
		(start 142.250414 -59.866784)
		(end 142.875 -59.866784)
		(width 0.254)
		(layer "F.Cu")
		(net "GND")
	)
	(segment
		(start 75.599544 -15.602712)
		(end 75.59929 -15.602966)
		(width 0.4064)
		(layer "F.Cu")
		(net "GND")
	)
	(segment
		(start 293.51478 -58.876438)
		(end 294.08628 -58.876438)
		(width 0.254)
		(layer "F.Cu")
		(net "GND")
	)
	(segment
		(start 64.549528 -4.808982)
		(end 64.549528 -5.822442)
		(width 0.4064)
		(layer "F.Cu")
		(net "GND")
	)
	(segment
		(start 346.3036 -10.457688)
		(end 346.3036 -10.2108)
		(width 0.254)
		(layer "F.Cu")
		(net "GND")
	)
	(segment
		(start 395.16685 -121.87428)
		(end 395.224 -121.90095)
		(width 0.254)
		(layer "F.Cu")
		(net "GND")
	)
	(segment
		(start 217.4494 -17.223994)
		(end 217.4494 -16.5354)
		(width 0.3556)
		(layer "F.Cu")
		(net "GND")
	)
	(segment
		(start 277.203154 -102.958138)
		(end 277.774654 -102.958138)
		(width 0.254)
		(layer "F.Cu")
		(net "GND")
	)
	(segment
		(start 255.92913 -56.085486)
		(end 255.35763 -56.085486)
		(width 0.254)
		(layer "F.Cu")
		(net "GND")
	)
	(segment
		(start 124.221748 -92.061538)
		(end 124.793248 -92.061538)
		(width 0.254)
		(layer "F.Cu")
		(net "GND")
	)
	(segment
		(start 226.9998 3.047746)
		(end 226.7966 2.844546)
		(width 0.3556)
		(layer "F.Cu")
		(net "GND")
	)
	(segment
		(start 286.500316 -5.822442)
		(end 286.499808 -5.822442)
		(width 0.4064)
		(layer "F.Cu")
		(net "GND")
	)
	(segment
		(start 69.466206 -69.45884)
		(end 68.894706 -69.45884)
		(width 0.254)
		(layer "F.Cu")
		(net "GND")
	)
	(segment
		(start 278.920194 -98.005138)
		(end 279.491694 -98.005138)
		(width 0.254)
		(layer "F.Cu")
		(net "GND")
	)
	(segment
		(start 141.049502 -10.422382)
		(end 141.049502 -9.156446)
		(width 0.4064)
		(layer "F.Cu")
		(net "GND")
	)
	(segment
		(start 210.849718 -153.093674)
		(end 210.391248 -153.552144)
		(width 0.4064)
		(layer "F.Cu")
		(net "GND")
	)
	(segment
		(start 148.699474 -147.27174)
		(end 148.699474 -146.011646)
		(width 0.4064)
		(layer "F.Cu")
		(net "GND")
	)
	(segment
		(start 396.65275 -95.888556)
		(end 396.984982 -95.205042)
		(width 0.254)
		(layer "F.Cu")
		(net "GND")
	)
	(segment
		(start 83.202272 -56.58104)
		(end 82.630772 -56.58104)
		(width 0.254)
		(layer "F.Cu")
		(net "GND")
	)
	(segment
		(start 120.500902 -85.622384)
		(end 119.929402 -85.622384)
		(width 0.254)
		(layer "F.Cu")
		(net "GND")
	)
	(segment
		(start 2.836418 -14.266418)
		(end 2.77495 -14.266418)
		(width 0.254)
		(layer "F.Cu")
		(net "GND")
	)
	(segment
		(start 247.344184 -65.000886)
		(end 246.772684 -65.000886)
		(width 0.254)
		(layer "F.Cu")
		(net "GND")
	)
	(segment
		(start 61.999368 -15.423642)
		(end 61.999368 -13.541756)
		(width 0.4064)
		(layer "F.Cu")
		(net "GND")
	)
	(segment
		(start 141.899386 -152.273)
		(end 141.899386 -154.063446)
		(width 0.4064)
		(layer "F.Cu")
		(net "GND")
	)
	(segment
		(start 73.899268 -143.492474)
		(end 73.440798 -143.950944)
		(width 0.4064)
		(layer "F.Cu")
		(net "GND")
	)
	(segment
		(start 312.849768 -14.409928)
		(end 312.387996 -13.948156)
		(width 0.4064)
		(layer "F.Cu")
		(net "GND")
	)
	(segment
		(start 81.485232 -101.15804)
		(end 81.485232 -102.093014)
		(width 0.254)
		(layer "F.Cu")
		(net "GND")
	)
	(segment
		(start 399.634964 -106.855006)
		(end 399.12925 -107.049316)
		(width 0.254)
		(layer "F.Cu")
		(net "GND")
	)
	(segment
		(start 300.949868 -13.541756)
		(end 300.772068 -13.363956)
		(width 0.4064)
		(layer "F.Cu")
		(net "GND")
	)
	(segment
		(start 452.722234 -6.815328)
		(end 451.677278 -5.770372)
		(width 0.254)
		(layer "F.Cu")
		(net "GND")
	)
	(segment
		(start 118.099332 -146.06905)
		(end 118.041928 -146.011646)
		(width 0.3556)
		(layer "F.Cu")
		(net "GND")
	)
	(segment
		(start 282.354274 -102.958138)
		(end 282.925774 -102.958138)
		(width 0.254)
		(layer "F.Cu")
		(net "GND")
	)
	(segment
		(start 315.400436 -0.821182)
		(end 315.399928 -0.821182)
		(width 0.4064)
		(layer "F.Cu")
		(net "GND")
	)
	(segment
		(start 292.65626 -85.127338)
		(end 293.22776 -85.127338)
		(width 0.254)
		(layer "F.Cu")
		(net "GND")
	)
	(segment
		(start 28.217622 -31.141162)
		(end 27.47899 -31.141162)
		(width 0.254)
		(layer "F.Cu")
		(net "GND")
	)
	(segment
		(start 283.04236 -9.156446)
		(end 283.099764 -9.21385)
		(width 0.3556)
		(layer "F.Cu")
		(net "GND")
	)
	(segment
		(start 90.928698 -65.991486)
		(end 90.357198 -65.991486)
		(width 0.254)
		(layer "F.Cu")
		(net "GND")
	)
	(segment
		(start 475.64802 -33.11398)
		(end 476.4278 -32.3342)
		(width 0.254)
		(layer "F.Cu")
		(net "GND")
	)
	(segment
		(start 203.199746 -15.602966)
		(end 203.2 -15.602712)
		(width 0.4064)
		(layer "F.Cu")
		(net "GND")
	)
	(segment
		(start 75.475846 -63.019686)
		(end 74.904346 -63.019686)
		(width 0.254)
		(layer "F.Cu")
		(net "GND")
	)
	(segment
		(start 418.70122 -38.141402)
		(end 418.70122 -38.14572)
		(width 0.254)
		(layer "F.Cu")
		(net "GND")
	)
	(segment
		(start 129.999486 -18.757646)
		(end 129.999486 -20.023582)
		(width 0.4064)
		(layer "F.Cu")
		(net "GND")
	)
	(segment
		(start 247.344184 -78.869286)
		(end 246.772684 -78.869286)
		(width 0.254)
		(layer "F.Cu")
		(net "GND")
	)
	(segment
		(start 377.108466 -126.165102)
		(end 377.081542 -126.192026)
		(width 0.254)
		(layer "F.Cu")
		(net "GND")
	)
	(segment
		(start 70.461378 -11.916156)
		(end 70.499478 -11.878056)
		(width 0.4064)
		(layer "F.Cu")
		(net "GND")
	)
	(segment
		(start 222.749872 -9.156446)
		(end 222.749872 -10.422382)
		(width 0.4064)
		(layer "F.Cu")
		(net "GND")
	)
	(segment
		(start 413.890206 -36.534598)
		(end 414.290256 -36.134548)
		(width 0.254)
		(layer "F.Cu")
		(net "GND")
	)
	(segment
		(start 206.59979 -7.509002)
		(end 206.501746 -7.607046)
		(width 0.4064)
		(layer "F.Cu")
		(net "GND")
	)
	(segment
		(start 287.349946 0.444754)
		(end 287.349946 -0.821182)
		(width 0.4064)
		(layer "F.Cu")
		(net "GND")
	)
	(segment
		(start 145.29943 3.778758)
		(end 145.29943 3.061462)
		(width 0.3556)
		(layer "F.Cu")
		(net "GND")
	)
	(segment
		(start 439.976006 -41.219374)
		(end 439.976006 -40.5257)
		(width 0.3556)
		(layer "F.Cu")
		(net "GND")
	)
	(segment
		(start 295.000426 -0.821182)
		(end 294.999918 -0.821182)
		(width 0.4064)
		(layer "F.Cu")
		(net "GND")
	)
	(segment
		(start 303.529746 -78.193138)
		(end 302.958246 -78.193138)
		(width 0.254)
		(layer "F.Cu")
		(net "GND")
	)
	(segment
		(start 126.510288 -91.070938)
		(end 125.938788 -91.070938)
		(width 0.254)
		(layer "F.Cu")
		(net "GND")
	)
	(segment
		(start 235.325158 -94.718886)
		(end 234.753658 -94.718886)
		(width 0.254)
		(layer "F.Cu")
		(net "GND")
	)
	(segment
		(start 52.649374 -13.541756)
		(end 52.471574 -13.363956)
		(width 0.4064)
		(layer "F.Cu")
		(net "GND")
	)
	(segment
		(start 498.593618 -44.817538)
		(end 497.396008 -43.619928)
		(width 0.254)
		(layer "F.Cu")
		(net "GND")
	)
	(segment
		(start 50.949352 -133.0706)
		(end 50.949352 -134.763002)
		(width 0.4064)
		(layer "F.Cu")
		(net "GND")
	)
	(segment
		(start 287.50514 -74.230738)
		(end 288.07664 -74.230738)
		(width 0.254)
		(layer "F.Cu")
		(net "GND")
	)
	(segment
		(start 309.411878 -2.314956)
		(end 309.449978 -2.276856)
		(width 0.4064)
		(layer "F.Cu")
		(net "GND")
	)
	(segment
		(start 107.051856 -95.033084)
		(end 107.623356 -95.033084)
		(width 0.254)
		(layer "F.Cu")
		(net "GND")
	)
	(segment
		(start 120.787668 -98.995738)
		(end 121.359168 -98.995738)
		(width 0.254)
		(layer "F.Cu")
		(net "GND")
	)
	(segment
		(start 243.051838 -88.28024)
		(end 242.480338 -88.28024)
		(width 0.254)
		(layer "F.Cu")
		(net "GND")
	)
	(segment
		(start 126.388368 1.989074)
		(end 126.421642 1.9558)
		(width 0.3556)
		(layer "F.Cu")
		(net "GND")
	)
	(segment
		(start 215.0999 -156.87294)
		(end 215.0999 -155.600146)
		(width 0.4064)
		(layer "F.Cu")
		(net "GND")
	)
	(segment
		(start 135.382254 -60.857384)
		(end 135.953754 -60.857384)
		(width 0.254)
		(layer "F.Cu")
		(net "GND")
	)
	(segment
		(start 389.22325 -102.98684)
		(end 389.71855 -102.756716)
		(width 0.254)
		(layer "F.Cu")
		(net "GND")
	)
	(segment
		(start 426.074586 -9.260586)
		(end 426.212 -9.398)
		(width 0.254)
		(layer "F.Cu")
		(net "GND")
	)
	(segment
		(start 442.122052 -27.831796)
		(end 442.122052 -27.832558)
		(width 0.3048)
		(layer "F.Cu")
		(net "GND")
	)
	(segment
		(start 225.299778 -13.427456)
		(end 225.210878 -13.338556)
		(width 0.4064)
		(layer "F.Cu")
		(net "GND")
	)
	(segment
		(start 377.093734 -95.498666)
		(end 376.284998 -95.754952)
		(width 0.254)
		(layer "F.Cu")
		(net "GND")
	)
	(segment
		(start 34.118296 -61.677804)
		(end 33.444942 -62.351158)
		(width 0.254)
		(layer "F.Cu")
		(net "GND")
	)
	(segment
		(start 78.051406 -94.223586)
		(end 77.479906 -94.223586)
		(width 0.254)
		(layer "F.Cu")
		(net "GND")
	)
	(segment
		(start 181.5084 -145.923)
		(end 181.0004 -145.415)
		(width 0.254)
		(layer "F.Cu")
		(net "GND")
	)
	(segment
		(start 198.89343 -69.318124)
		(end 198.89343 -69.864224)
		(width 0.254)
		(layer "F.Cu")
		(net "GND")
	)
	(segment
		(start 120.787668 -73.240138)
		(end 121.359168 -73.240138)
		(width 0.254)
		(layer "F.Cu")
		(net "GND")
	)
	(segment
		(start 392.98499 -124.504958)
		(end 393.289282 -124.206)
		(width 0.254)
		(layer "F.Cu")
		(net "GND")
	)
	(segment
		(start 389.33755 -104.65435)
		(end 389.630412 -104.361488)
		(width 0.12446)
		(layer "F.Cu")
		(net "GND")
	)
	(segment
		(start 292.450012 -10.422382)
		(end 292.450012 -9.21385)
		(width 0.3556)
		(layer "F.Cu")
		(net "GND")
	)
	(segment
		(start 248.202704 -58.561986)
		(end 247.631204 -58.561986)
		(width 0.254)
		(layer "F.Cu")
		(net "GND")
	)
	(segment
		(start 276.344634 -56.894984)
		(end 275.773134 -56.894984)
		(width 0.254)
		(layer "F.Cu")
		(net "GND")
	)
	(segment
		(start 207.450436 -147.27174)
		(end 207.449928 -147.27174)
		(width 0.4064)
		(layer "F.Cu")
		(net "GND")
	)
	(segment
		(start 243.910104 -62.029086)
		(end 243.338604 -62.029086)
		(width 0.254)
		(layer "F.Cu")
		(net "GND")
	)
	(segment
		(start 70.324726 -56.085486)
		(end 69.753226 -56.085486)
		(width 0.254)
		(layer "F.Cu")
		(net "GND")
	)
	(segment
		(start 303.816766 -86.612984)
		(end 304.388266 -86.612984)
		(width 0.3048)
		(layer "F.Cu")
		(net "GND")
	)
	(segment
		(start 416.290252 -38.934644)
		(end 415.890202 -39.334694)
		(width 0.254)
		(layer "F.Cu")
		(net "GND")
	)
	(segment
		(start 441.721748 -29.0322)
		(end 441.722256 -29.0322)
		(width 0.3048)
		(layer "F.Cu")
		(net "GND")
	)
	(segment
		(start 110.485682 -60.362338)
		(end 109.914182 -60.362338)
		(width 0.254)
		(layer "F.Cu")
		(net "GND")
	)
	(segment
		(start 280.549858 -5.822442)
		(end 280.549858 -7.509002)
		(width 0.4064)
		(layer "F.Cu")
		(net "GND")
	)
	(segment
		(start 114.519202 -53.381656)
		(end 114.220752 -53.8988)
		(width 0.254)
		(layer "F.Cu")
		(net "GND")
	)
	(segment
		(start 227.840794 -4.346956)
		(end 227.786438 -4.2926)
		(width 0.254)
		(layer "F.Cu")
		(net "GND")
	)
	(segment
		(start 60.299346 2.092198)
		(end 60.201302 1.994154)
		(width 0.4064)
		(layer "F.Cu")
		(net "GND")
	)
	(segment
		(start 310.122062 -17.2466)
		(end 310.0832 -17.207738)
		(width 0.3556)
		(layer "F.Cu")
		(net "GND")
	)
	(segment
		(start 433.275486 -9.222486)
		(end 433.451 -9.398)
		(width 0.254)
		(layer "F.Cu")
		(net "GND")
	)
	(segment
		(start 457.8096 -29.21)
		(end 458.0636 -28.956)
		(width 0.254)
		(layer "F.Cu")
		(net "GND")
	)
	(segment
		(start 126.797308 -99.490784)
		(end 127.368808 -99.490784)
		(width 0.254)
		(layer "F.Cu")
		(net "GND")
	)
	(segment
		(start 233.608118 -66.982086)
		(end 233.036618 -66.982086)
		(width 0.254)
		(layer "F.Cu")
		(net "GND")
	)
	(segment
		(start 221.899988 -133.255512)
		(end 221.899734 -133.255766)
		(width 0.4064)
		(layer "F.Cu")
		(net "GND")
	)
	(segment
		(start 399.12925 -105.332276)
		(end 399.634964 -104.85501)
		(width 0.254)
		(layer "F.Cu")
		(net "GND")
	)
	(segment
		(start 135.949436 -142.6718)
		(end 135.949436 -143.422878)
		(width 0.3556)
		(layer "F.Cu")
		(net "GND")
	)
	(segment
		(start 432.4096 -3.6068)
		(end 432.475386 -3.672586)
		(width 0.254)
		(layer "F.Cu")
		(net "GND")
	)
	(segment
		(start 148.699474 -10.422382)
		(end 148.699474 -9.156446)
		(width 0.4064)
		(layer "F.Cu")
		(net "GND")
	)
	(segment
		(start 285.7881 -81.164938)
		(end 286.3596 -81.164938)
		(width 0.254)
		(layer "F.Cu")
		(net "GND")
	)
	(segment
		(start 193.761868 -76.053442)
		(end 193.761868 -76.818236)
		(width 0.254)
		(layer "F.Cu")
		(net "GND")
	)
	(segment
		(start 384.1369 -113.0554)
		(end 384.53695 -113.45545)
		(width 0.1143)
		(layer "F.Cu")
		(net "GND")
	)
	(segment
		(start 308.600348 3.778758)
		(end 308.59984 3.778758)
		(width 0.4064)
		(layer "F.Cu")
		(net "GND")
	)
	(segment
		(start 129.149348 -152.273)
		(end 129.149348 -153.093674)
		(width 0.4064)
		(layer "F.Cu")
		(net "GND")
	)
	(segment
		(start 243.051838 -84.31784)
		(end 242.480338 -84.31784)
		(width 0.254)
		(layer "F.Cu")
		(net "GND")
	)
	(segment
		(start 461.278478 -3.547618)
		(end 461.278478 -4.386072)
		(width 0.254)
		(layer "F.Cu")
		(net "GND")
	)
	(segment
		(start 303.816766 -70.763384)
		(end 304.388266 -70.763384)
		(width 0.254)
		(layer "F.Cu")
		(net "GND")
	)
	(segment
		(start 149.549358 3.778758)
		(end 149.549358 1.994154)
		(width 0.4064)
		(layer "F.Cu")
		(net "GND")
	)
	(segment
		(start 210.849718 -133.891274)
		(end 210.391248 -134.349744)
		(width 0.4064)
		(layer "F.Cu")
		(net "GND")
	)
	(segment
		(start 389.7376 -112.2553)
		(end 390.13765 -111.85525)
		(width 0.1143)
		(layer "F.Cu")
		(net "GND")
	)
	(segment
		(start 73.899268 -15.423896)
		(end 73.899268 -16.238474)
		(width 0.4064)
		(layer "F.Cu")
		(net "GND")
	)
	(segment
		(start 280.637234 -66.305938)
		(end 280.065734 -66.305938)
		(width 0.254)
		(layer "F.Cu")
		(net "GND")
	)
	(segment
		(start 221.899734 3.599434)
		(end 221.899734 1.994154)
		(width 0.4064)
		(layer "F.Cu")
		(net "GND")
	)
	(segment
		(start 223.60001 -152.278842)
		(end 223.599756 -152.279096)
		(width 0.4064)
		(layer "F.Cu")
		(net "GND")
	)
	(segment
		(start 261.93877 -88.28024)
		(end 261.36727 -88.28024)
		(width 0.254)
		(layer "F.Cu")
		(net "GND")
	)
	(segment
		(start 463.3849 -22.3901)
		(end 463.7659 -22.3901)
		(width 0.254)
		(layer "F.Cu")
		(net "GND")
	)
	(segment
		(start 397.485108 -125.750066)
		(end 397.485108 -124.919994)
		(width 0.254)
		(layer "F.Cu")
		(net "GND")
	)
	(segment
		(start 196.399912 -156.87294)
		(end 196.399912 -155.600146)
		(width 0.4064)
		(layer "F.Cu")
		(net "GND")
	)
	(segment
		(start 231.249982 -133.255512)
		(end 231.249728 -133.255766)
		(width 0.4064)
		(layer "F.Cu")
		(net "GND")
	)
	(segment
		(start 278.849836 -21.567648)
		(end 278.947372 -21.665184)
		(width 0.4064)
		(layer "F.Cu")
		(net "GND")
	)
	(segment
		(start 252.495304 -84.812886)
		(end 251.923804 -84.812886)
		(width 0.254)
		(layer "F.Cu")
		(net "GND")
	)
	(segment
		(start 137.957814 -67.296538)
		(end 138.529314 -67.296538)
		(width 0.254)
		(layer "F.Cu")
		(net "GND")
	)
	(segment
		(start 335.947512 -25.434036)
		(end 335.773776 -25.2603)
		(width 0.254)
		(layer "F.Cu")
		(net "GND")
	)
	(segment
		(start 150.399496 -10.422382)
		(end 150.399496 -9.156446)
		(width 0.4064)
		(layer "F.Cu")
		(net "GND")
	)
	(segment
		(start 131.948174 -91.565984)
		(end 132.519674 -91.565984)
		(width 0.254)
		(layer "F.Cu")
		(net "GND")
	)
	(segment
		(start 131.699508 -20.023582)
		(end 131.699508 -21.517356)
		(width 0.4064)
		(layer "F.Cu")
		(net "GND")
	)
	(segment
		(start 357.823262 -133.887464)
		(end 357.823262 -133.989572)
		(width 0.381)
		(layer "F.Cu")
		(net "GND")
	)
	(segment
		(start 458.520546 -138.719814)
		(end 458.7748 -138.974068)
		(width 0.254)
		(layer "F.Cu")
		(net "GND")
	)
	(segment
		(start 386.644388 -108.361988)
		(end 386.93725 -108.65485)
		(width 0.12446)
		(layer "F.Cu")
		(net "GND")
	)
	(segment
		(start 278.849836 -17.193006)
		(end 278.849836 -15.423642)
		(width 0.4064)
		(layer "F.Cu")
		(net "GND")
	)
	(segment
		(start 137.099294 -62.838584)
		(end 137.670794 -62.838584)
		(width 0.254)
		(layer "F.Cu")
		(net "GND")
	)
	(segment
		(start 136.799574 -10.422382)
		(end 136.799574 -11.854688)
		(width 0.4064)
		(layer "F.Cu")
		(net "GND")
	)
	(segment
		(start 115.549426 -133.0706)
		(end 115.549426 -134.763002)
		(width 0.4064)
		(layer "F.Cu")
		(net "GND")
	)
	(segment
		(start 129.149348 -5.822442)
		(end 129.149348 -6.637274)
		(width 0.4064)
		(layer "F.Cu")
		(net "GND")
	)
	(segment
		(start 308.59984 -3.828796)
		(end 308.5084 -3.737356)
		(width 0.4064)
		(layer "F.Cu")
		(net "GND")
	)
	(segment
		(start 237.199932 -137.67054)
		(end 237.199932 -136.46785)
		(width 0.3556)
		(layer "F.Cu")
		(net "GND")
	)
	(segment
		(start 135.099552 -10.422382)
		(end 135.099552 -11.878056)
		(width 0.4064)
		(layer "F.Cu")
		(net "GND")
	)
	(segment
		(start 249.9106 -3.3528)
		(end 250.7615 -3.3528)
		(width 0.4572)
		(layer "F.Cu")
		(net "GND")
	)
	(segment
		(start 147.849336 -14.409928)
		(end 147.387564 -13.948156)
		(width 0.4064)
		(layer "F.Cu")
		(net "GND")
	)
	(segment
		(start 398.63395 -116.953284)
		(end 399.634964 -116.854986)
		(width 0.254)
		(layer "F.Cu")
		(net "GND")
	)
	(segment
		(start 124.89942 -152.273)
		(end 124.89942 -153.965402)
		(width 0.4064)
		(layer "F.Cu")
		(net "GND")
	)
	(segment
		(start 462.980278 -144.719802)
		(end 464.416394 -144.719802)
		(width 0.254)
		(layer "F.Cu")
		(net "GND")
	)
	(segment
		(start 115.636802 -50.3174)
		(end 115.64366 -50.324258)
		(width 0.2286)
		(layer "F.Cu")
		(net "GND")
	)
	(segment
		(start 396.984982 -95.205042)
		(end 395.984984 -95.205042)
		(width 0.254)
		(layer "F.Cu")
		(net "GND")
	)
	(segment
		(start 457.350114 -63.170054)
		(end 457.551536 -63.371476)
		(width 0.381)
		(layer "F.Cu")
		(net "GND")
	)
	(segment
		(start 271.193768 -52.932838)
		(end 270.571468 -52.932838)
		(width 0.254)
		(layer "F.Cu")
		(net "GND")
	)
	(segment
		(start 131.948174 -62.838584)
		(end 132.519674 -62.838584)
		(width 0.254)
		(layer "F.Cu")
		(net "GND")
	)
	(segment
		(start 64.549528 -142.677642)
		(end 64.549274 -142.677896)
		(width 0.4064)
		(layer "F.Cu")
		(net "GND")
	)
	(segment
		(start 392.303 -74.480166)
		(end 392.295888 -74.487278)
		(width 0.254)
		(layer "F.Cu")
		(net "GND")
	)
	(segment
		(start 44.092114 -18.744946)
		(end 44.092114 -18.795746)
		(width 0.4064)
		(layer "F.Cu")
		(net "GND")
	)
	(segment
		(start 489.379768 -145.542)
		(end 489.3945 -145.527268)
		(width 0.254)
		(layer "F.Cu")
		(net "GND")
	)
	(segment
		(start 43.076368 2.819654)
		(end 43.076368 2.001012)
		(width 0.3556)
		(layer "F.Cu")
		(net "GND")
	)
	(segment
		(start 119.070882 -89.089738)
		(end 119.642382 -89.089738)
		(width 0.254)
		(layer "F.Cu")
		(net "GND")
	)
	(segment
		(start 461.343248 -52.2478)
		(end 461.339946 -51.875944)
		(width 0.4064)
		(layer "F.Cu")
		(net "GND")
	)
	(segment
		(start 43.29938 -142.6718)
		(end 43.29938 -143.413734)
		(width 0.3556)
		(layer "F.Cu")
		(net "GND")
	)
	(segment
		(start 231.25049 -15.423642)
		(end 231.25049 -13.364718)
		(width 0.4064)
		(layer "F.Cu")
		(net "GND")
	)
	(segment
		(start 476.4786 -43.413934)
		(end 476.4786 -42.8879)
		(width 0.254)
		(layer "F.Cu")
		(net "GND")
	)
	(segment
		(start 278.920194 -89.089738)
		(end 279.491694 -89.089738)
		(width 0.254)
		(layer "F.Cu")
		(net "GND")
	)
	(segment
		(start 220.199966 -152.278842)
		(end 220.199712 -152.279096)
		(width 0.4064)
		(layer "F.Cu")
		(net "GND")
	)
	(segment
		(start 317.09995 -22.69363)
		(end 317.146432 -22.740112)
		(width 0.4064)
		(layer "F.Cu")
		(net "GND")
	)
	(segment
		(start 395.66215 -105.5624)
		(end 396.15745 -105.332276)
		(width 0.254)
		(layer "F.Cu")
		(net "GND")
	)
	(segment
		(start 309.449978 -2.276856)
		(end 309.449978 -0.821182)
		(width 0.4064)
		(layer "F.Cu")
		(net "GND")
	)
	(segment
		(start 33.754568 -134.882382)
		(end 33.771586 -134.8994)
		(width 0.3556)
		(layer "F.Cu")
		(net "GND")
	)
	(segment
		(start 392.02741 -96.825054)
		(end 392.19505 -96.747076)
		(width 0.254)
		(layer "F.Cu")
		(net "GND")
	)
	(segment
		(start 464.478878 -3.81)
		(end 464.885278 -3.4036)
		(width 0.4064)
		(layer "F.Cu")
		(net "GND")
	)
	(segment
		(start 301.241206 -57.390538)
		(end 301.812706 -57.390538)
		(width 0.254)
		(layer "F.Cu")
		(net "GND")
	)
	(segment
		(start 196.469 -21.586444)
		(end 196.469 -22.606)
		(width 0.381)
		(layer "F.Cu")
		(net "GND")
	)
	(segment
		(start 127.655828 -87.108538)
		(end 128.227328 -87.108538)
		(width 0.254)
		(layer "F.Cu")
		(net "GND")
	)
	(segment
		(start 499.143528 -128.610106)
		(end 499.143528 -127.90424)
		(width 0.508)
		(layer "F.Cu")
		(net "GND")
	)
	(segment
		(start 226.9998 -133.076442)
		(end 226.9998 -133.807454)
		(width 0.3556)
		(layer "F.Cu")
		(net "GND")
	)
	(segment
		(start 58.599578 -142.6718)
		(end 58.599578 -142.677642)
		(width 0.4064)
		(layer "F.Cu")
		(net "GND")
	)
	(segment
		(start 305.200304 -152.273)
		(end 305.199796 -152.278842)
		(width 0.4064)
		(layer "F.Cu")
		(net "GND")
	)
	(segment
		(start 476.82658 -16.561054)
		(end 476.82658 -16.122142)
		(width 0.254)
		(layer "F.Cu")
		(net "GND")
	)
	(segment
		(start 84.919312 -86.29904)
		(end 84.347812 -86.29904)
		(width 0.254)
		(layer "F.Cu")
		(net "GND")
	)
	(segment
		(start 145.29943 -152.273)
		(end 145.29943 -152.996138)
		(width 0.3556)
		(layer "F.Cu")
		(net "GND")
	)
	(segment
		(start 305.200304 -15.423642)
		(end 305.199796 -15.423642)
		(width 0.4064)
		(layer "F.Cu")
		(net "GND")
	)
	(segment
		(start 130.231388 -72.744584)
		(end 130.802888 -72.744584)
		(width 0.254)
		(layer "F.Cu")
		(net "GND")
	)
	(segment
		(start 304.675286 -66.305938)
		(end 305.246786 -66.305938)
		(width 0.254)
		(layer "F.Cu")
		(net "GND")
	)
	(segment
		(start 75.59929 -133.255766)
		(end 75.59929 -134.861046)
		(width 0.4064)
		(layer "F.Cu")
		(net "GND")
	)
	(segment
		(start 407.67 -18.8595)
		(end 407.67 -19.3675)
		(width 0.254)
		(layer "F.Cu")
		(net "GND")
	)
	(segment
		(start 137.957814 -91.070938)
		(end 138.529314 -91.070938)
		(width 0.254)
		(layer "F.Cu")
		(net "GND")
	)
	(segment
		(start 33.949386 -152.273)
		(end 33.949386 -152.992582)
		(width 0.3556)
		(layer "F.Cu")
		(net "GND")
	)
	(segment
		(start 243.051838 -58.561986)
		(end 242.480338 -58.561986)
		(width 0.254)
		(layer "F.Cu")
		(net "GND")
	)
	(segment
		(start 143.599408 -3.828796)
		(end 143.599408 -5.822442)
		(width 0.4064)
		(layer "F.Cu")
		(net "GND")
	)
	(segment
		(start 128.514348 -83.641184)
		(end 129.085848 -83.641184)
		(width 0.254)
		(layer "F.Cu")
		(net "GND")
	)
	(segment
		(start 72.900286 -82.33664)
		(end 72.328786 -82.33664)
		(width 0.254)
		(layer "F.Cu")
		(net "GND")
	)
	(segment
		(start 384.76555 -122.104404)
		(end 384.27025 -121.87428)
		(width 0.254)
		(layer "F.Cu")
		(net "GND")
	)
	(segment
		(start 231.25049 -133.0706)
		(end 231.249982 -133.076442)
		(width 0.4064)
		(layer "F.Cu")
		(net "GND")
	)
	(segment
		(start 276.3266 -52.914804)
		(end 276.344634 -52.932838)
		(width 0.254)
		(layer "F.Cu")
		(net "GND")
	)
	(segment
		(start 79.768192 -51.62804)
		(end 79.481172 -52.12334)
		(width 0.254)
		(layer "F.Cu")
		(net "GND")
	)
	(segment
		(start 62.849506 -20.023582)
		(end 62.849506 -21.455888)
		(width 0.4064)
		(layer "F.Cu")
		(net "GND")
	)
	(segment
		(start 240.600484 -7.606284)
		(end 240.599722 -7.607046)
		(width 0.4064)
		(layer "F.Cu")
		(net "GND")
	)
	(segment
		(start 366.2426 -98.5266)
		(end 366.2172 -98.552)
		(width 0.254)
		(layer "F.Cu")
		(net "GND")
	)
	(segment
		(start 385.75615 -122.104404)
		(end 385.26085 -121.87428)
		(width 0.254)
		(layer "F.Cu")
		(net "GND")
	)
	(segment
		(start 352.626676 1.44145)
		(end 352.502724 1.317498)
		(width 0.254)
		(layer "F.Cu")
		(net "GND")
	)
	(segment
		(start 195.549774 -133.076442)
		(end 195.549774 -134.400798)
		(width 0.4064)
		(layer "F.Cu")
		(net "GND")
	)
	(segment
		(start 486.0798 -30.734)
		(end 486.41 -31.0642)
		(width 0.254)
		(layer "F.Cu")
		(net "GND")
	)
	(segment
		(start 207.424528 -155.612846)
		(end 207.411828 -155.612846)
		(width 0.4064)
		(layer "F.Cu")
		(net "GND")
	)
	(segment
		(start 452.540116 -51.875944)
		(end 452.541132 -51.875944)
		(width 0.4064)
		(layer "F.Cu")
		(net "GND")
	)
	(segment
		(start 377.921266 -126.165102)
		(end 377.921266 -126.562866)
		(width 0.254)
		(layer "F.Cu")
		(net "GND")
	)
	(segment
		(start 349.5548 -100.914708)
		(end 349.301054 -100.660962)
		(width 0.381)
		(layer "F.Cu")
		(net "GND")
	)
	(segment
		(start 358.285034 -4.389882)
		(end 358.285034 -3.34518)
		(width 0.4572)
		(layer "F.Cu")
		(net "GND")
	)
	(segment
		(start 58.599578 -152.278842)
		(end 58.599324 -152.279096)
		(width 0.4064)
		(layer "F.Cu")
		(net "GND")
	)
	(segment
		(start 196.177154 -61.205364)
		(end 195.722494 -61.205364)
		(width 0.508)
		(layer "F.Cu")
		(net "GND")
	)
	(segment
		(start 148.699474 -18.757646)
		(end 148.699474 -20.023582)
		(width 0.4064)
		(layer "F.Cu")
		(net "GND")
	)
	(segment
		(start 300.061884 -12.993116)
		(end 299.249846 -13.805154)
		(width 0.4064)
		(layer "F.Cu")
		(net "GND")
	)
	(segment
		(start 56.049418 -10.422382)
		(end 56.049418 -11.916156)
		(width 0.4064)
		(layer "F.Cu")
		(net "GND")
	)
	(segment
		(start 310.0832 -144.461738)
		(end 310.122062 -144.5006)
		(width 0.3556)
		(layer "F.Cu")
		(net "GND")
	)
	(segment
		(start 184.935114 -115.55095)
		(end 184.9374 -115.55095)
		(width 0.254)
		(layer "F.Cu")
		(net "GND")
	)
	(segment
		(start 445.340994 -50.4698)
		(end 445.340994 -51.875944)
		(width 0.508)
		(layer "F.Cu")
		(net "GND")
	)
	(segment
		(start 184.531 -145.796)
		(end 184.7596 -145.5674)
		(width 0.254)
		(layer "F.Cu")
		(net "GND")
	)
	(segment
		(start 280.637234 -55.409338)
		(end 280.065734 -55.409338)
		(width 0.254)
		(layer "F.Cu")
		(net "GND")
	)
	(segment
		(start 442.122052 -25.432004)
		(end 442.122052 -25.432512)
		(width 0.3048)
		(layer "F.Cu")
		(net "GND")
	)
	(segment
		(start 286.500316 3.778758)
		(end 286.499808 3.778758)
		(width 0.4064)
		(layer "F.Cu")
		(net "GND")
	)
	(segment
		(start 415.090102 -36.134548)
		(end 415.490152 -36.534598)
		(width 0.254)
		(layer "F.Cu")
		(net "GND")
	)
	(segment
		(start 69.753226 -55.094886)
		(end 70.324726 -55.094886)
		(width 0.3048)
		(layer "F.Cu")
		(net "GND")
	)
	(segment
		(start 232.099866 0.444754)
		(end 232.099866 -0.821182)
		(width 0.4064)
		(layer "F.Cu")
		(net "GND")
	)
	(segment
		(start 446.73012 -23.58898)
		(end 445.91732 -23.58898)
		(width 0.254)
		(layer "F.Cu")
		(net "GND")
	)
	(segment
		(start 321.591432 -22.740112)
		(end 322.219574 -23.368254)
		(width 0.4064)
		(layer "F.Cu")
		(net "GND")
	)
	(segment
		(start 77.286612 -25.142444)
		(end 77.747368 -25.6032)
		(width 0.4064)
		(layer "F.Cu")
		(net "GND")
	)
	(segment
		(start 255.07061 -60.54344)
		(end 254.49911 -60.54344)
		(width 0.254)
		(layer "F.Cu")
		(net "GND")
	)
	(segment
		(start 237.199932 -2.253488)
		(end 237.199932 -0.821182)
		(width 0.4064)
		(layer "F.Cu")
		(net "GND")
	)
	(segment
		(start 226.9998 -13.541756)
		(end 226.822 -13.363956)
		(width 0.4064)
		(layer "F.Cu")
		(net "GND")
	)
	(segment
		(start 283.04236 -9.143746)
		(end 283.04236 -9.156446)
		(width 0.3556)
		(layer "F.Cu")
		(net "GND")
	)
	(segment
		(start 115.636802 -54.418738)
		(end 115.065302 -54.418738)
		(width 0.254)
		(layer "F.Cu")
		(net "GND")
	)
	(segment
		(start 157.020768 -150.7744)
		(end 157.020768 -149.654768)
		(width 0.4064)
		(layer "F.Cu")
		(net "GND")
	)
	(segment
		(start 135.953754 -51.941984)
		(end 135.382254 -51.941984)
		(width 0.1016)
		(layer "F.Cu")
		(net "GND")
	)
	(segment
		(start 196.691504 -94.481904)
		(end 196.200522 -94.481904)
		(width 0.254)
		(layer "F.Cu")
		(net "GND")
	)
	(segment
		(start 60.201302 -17.208246)
		(end 60.299346 -17.110202)
		(width 0.4064)
		(layer "F.Cu")
		(net "GND")
	)
	(segment
		(start 366.285018 -7.789926)
		(end 366.285018 -8.84682)
		(width 0.4064)
		(layer "F.Cu")
		(net "GND")
	)
	(segment
		(start 62.849506 -21.455888)
		(end 62.792102 -21.513292)
		(width 0.4064)
		(layer "F.Cu")
		(net "GND")
	)
	(segment
		(start 67.949572 -15.423642)
		(end 67.949572 -13.36421)
		(width 0.4064)
		(layer "F.Cu")
		(net "GND")
	)
	(segment
		(start 215.949784 3.778758)
		(end 215.949784 2.092198)
		(width 0.4064)
		(layer "F.Cu")
		(net "GND")
	)
	(segment
		(start 452.550022 -60.847986)
		(end 452.742808 -60.6552)
		(width 0.381)
		(layer "F.Cu")
		(net "GND")
	)
	(segment
		(start 82.343752 -52.12334)
		(end 82.3468 -52.120292)
		(width 0.2032)
		(layer "F.Cu")
		(net "GND")
	)
	(segment
		(start 255.92913 -65.991486)
		(end 255.35763 -65.991486)
		(width 0.254)
		(layer "F.Cu")
		(net "GND")
	)
	(segment
		(start 242.300506 -144.461484)
		(end 242.299744 -144.462246)
		(width 0.508)
		(layer "F.Cu")
		(net "GND")
	)
	(segment
		(start 393.081764 -126.068328)
		(end 392.98499 -126.165102)
		(width 0.254)
		(layer "F.Cu")
		(net "GND")
	)
	(segment
		(start 398.048734 -93.544898)
		(end 398.048734 -92.917518)
		(width 0.254)
		(layer "F.Cu")
		(net "GND")
	)
	(segment
		(start 453.545448 -2.725166)
		(end 453.514968 -2.725166)
		(width 0.4064)
		(layer "F.Cu")
		(net "GND")
	)
	(segment
		(start 275.109432 -149.8092)
		(end 274.258532 -149.8092)
		(width 0.4572)
		(layer "F.Cu")
		(net "GND")
	)
	(segment
		(start 38.199568 -142.856712)
		(end 38.199314 -142.856966)
		(width 0.4064)
		(layer "F.Cu")
		(net "GND")
	)
	(segment
		(start 181.0004 -145.415)
		(end 181.0004 -145.2626)
		(width 0.254)
		(layer "F.Cu")
		(net "GND")
	)
	(segment
		(start 179.61102 -77.63002)
		(end 179.07 -77.089)
		(width 0.254)
		(layer "F.Cu")
		(net "GND")
	)
	(segment
		(start 394.870686 -7.789672)
		(end 394.870686 -9.44372)
		(width 0.254)
		(layer "F.Cu")
		(net "GND")
	)
	(segment
		(start 390.5377 -110.05566)
		(end 390.5377 -110.6551)
		(width 0.12446)
		(layer "F.Cu")
		(net "GND")
	)
	(segment
		(start 214.250524 3.778758)
		(end 214.250524 1.994916)
		(width 0.4064)
		(layer "F.Cu")
		(net "GND")
	)
	(segment
		(start 463.795618 -37.3761)
		(end 464.269582 -37.3761)
		(width 0.4064)
		(layer "F.Cu")
		(net "GND")
	)
	(segment
		(start 146.149568 -155.67025)
		(end 146.092164 -155.612846)
		(width 0.3556)
		(layer "F.Cu")
		(net "GND")
	)
	(segment
		(start 234.649772 -5.822442)
		(end 234.649772 -4.7371)
		(width 0.4064)
		(layer "F.Cu")
		(net "GND")
	)
	(segment
		(start 192.773808 -96.707452)
		(end 192.773808 -97.5614)
		(width 0.254)
		(layer "F.Cu")
		(net "GND")
	)
	(segment
		(start 461.339946 -51.875944)
		(end 461.340962 -51.875944)
		(width 0.4064)
		(layer "F.Cu")
		(net "GND")
	)
	(segment
		(start 240.476278 -89.765886)
		(end 239.904778 -89.765886)
		(width 0.254)
		(layer "F.Cu")
		(net "GND")
	)
	(segment
		(start 388.72795 -100.41128)
		(end 389.22325 -100.181156)
		(width 0.254)
		(layer "F.Cu")
		(net "GND")
	)
	(segment
		(start 450.20103 -116.993162)
		(end 450.20103 -118.615714)
		(width 0.4064)
		(layer "F.Cu")
		(net "GND")
	)
	(segment
		(start 300.061884 -11.916156)
		(end 300.061884 -12.993116)
		(width 0.4064)
		(layer "F.Cu")
		(net "GND")
	)
	(segment
		(start 221.899988 -142.677642)
		(end 221.899988 -142.856712)
		(width 0.4064)
		(layer "F.Cu")
		(net "GND")
	)
	(segment
		(start 59.449462 -137.67054)
		(end 59.449462 -136.397746)
		(width 0.4064)
		(layer "F.Cu")
		(net "GND")
	)
	(segment
		(start 458.728318 -137.219944)
		(end 457.252578 -137.219944)
		(width 0.254)
		(layer "F.Cu")
		(net "GND")
	)
	(segment
		(start 202.349862 -11.916156)
		(end 201.031856 -11.9126)
		(width 0.254)
		(layer "F.Cu")
		(net "GND")
	)
	(segment
		(start 252.495304 -81.841086)
		(end 251.923804 -81.841086)
		(width 0.254)
		(layer "F.Cu")
		(net "GND")
	)
	(segment
		(start 394.984986 -124.504958)
		(end 394.984986 -124.13488)
		(width 0.254)
		(layer "F.Cu")
		(net "GND")
	)
	(segment
		(start 206.59979 -142.677642)
		(end 206.59979 -144.364202)
		(width 0.4064)
		(layer "F.Cu")
		(net "GND")
	)
	(segment
		(start -0.254 -20.0406)
		(end -0.254 -20.701)
		(width 0.254)
		(layer "F.Cu")
		(net "GND")
	)
	(segment
		(start 280.637234 -51.446938)
		(end 280.644092 -51.44008)
		(width 0.2286)
		(layer "F.Cu")
		(net "GND")
	)
	(segment
		(start 60.299346 -153.965402)
		(end 60.201302 -154.063446)
		(width 0.4064)
		(layer "F.Cu")
		(net "GND")
	)
	(segment
		(start 237.20044 -137.67054)
		(end 237.199932 -137.67054)
		(width 0.3556)
		(layer "F.Cu")
		(net "GND")
	)
	(segment
		(start 242.2652 -26.0858)
		(end 242.7478 -25.6032)
		(width 0.4064)
		(layer "F.Cu")
		(net "GND")
	)
	(segment
		(start 246.485664 -97.19564)
		(end 245.914164 -97.19564)
		(width 0.254)
		(layer "F.Cu")
		(net "GND")
	)
	(segment
		(start 375.482866 -126.344934)
		(end 375.1072 -126.7206)
		(width 0.254)
		(layer "F.Cu")
		(net "GND")
	)
	(segment
		(start 446.141094 -50.61204)
		(end 446.141094 -51.875944)
		(width 0.4064)
		(layer "F.Cu")
		(net "GND")
	)
	(segment
		(start 396.15745 -96.11868)
		(end 396.65275 -95.888556)
		(width 0.254)
		(layer "F.Cu")
		(net "GND")
	)
	(segment
		(start 281.495754 -86.612984)
		(end 281.495754 -86.041484)
		(width 0.381)
		(layer "F.Cu")
		(net "GND")
	)
	(segment
		(start 390.60628 -156.591)
		(end 390.824466 -156.372814)
		(width 0.254)
		(layer "F.Cu")
		(net "GND")
	)
	(segment
		(start 193.704464 -68.514722)
		(end 193.704464 -68.608702)
		(width 0.381)
		(layer "F.Cu")
		(net "GND")
	)
	(segment
		(start 378.32665 -120.15724)
		(end 378.546106 -120.259094)
		(width 0.254)
		(layer "F.Cu")
		(net "GND")
	)
	(segment
		(start 457.277978 -7.789672)
		(end 457.277978 -8.661908)
		(width 0.254)
		(layer "F.Cu")
		(net "GND")
	)
	(segment
		(start 299.249846 2.092198)
		(end 299.151802 1.994154)
		(width 0.4064)
		(layer "F.Cu")
		(net "GND")
	)
	(segment
		(start 66.249296 -15.423388)
		(end 66.24955 -15.423642)
		(width 0.4064)
		(layer "F.Cu")
		(net "GND")
	)
	(segment
		(start 119.929402 -62.838584)
		(end 119.357902 -62.838584)
		(width 0.254)
		(layer "F.Cu")
		(net "GND")
	)
	(segment
		(start 222.749872 -137.67054)
		(end 222.749872 -136.410446)
		(width 0.4064)
		(layer "F.Cu")
		(net "GND")
	)
	(segment
		(start 306.900326 -133.0706)
		(end 306.899818 -133.076442)
		(width 0.4064)
		(layer "F.Cu")
		(net "GND")
	)
	(segment
		(start 241.334798 -64.50584)
		(end 240.763298 -64.50584)
		(width 0.254)
		(layer "F.Cu")
		(net "GND")
	)
	(segment
		(start 245.627144 -95.709486)
		(end 245.055644 -95.709486)
		(width 0.254)
		(layer "F.Cu")
		(net "GND")
	)
	(segment
		(start 79.768192 -68.46824)
		(end 79.196692 -68.46824)
		(width 0.254)
		(layer "F.Cu")
		(net "GND")
	)
	(segment
		(start 232.749598 -53.60924)
		(end 233.113072 -53.60924)
		(width 0.254)
		(layer "F.Cu")
		(net "GND")
	)
	(segment
		(start 217.649806 -16.157194)
		(end 217.649806 -15.423642)
		(width 0.3048)
		(layer "F.Cu")
		(net "GND")
	)
	(segment
		(start 113.688368 -140.208)
		(end 112.397032 -140.208)
		(width 0.4064)
		(layer "F.Cu")
		(net "GND")
	)
	(segment
		(start 212.54974 3.599434)
		(end 212.54974 1.994154)
		(width 0.4064)
		(layer "F.Cu")
		(net "GND")
	)
	(segment
		(start 406.172416 -148.436584)
		(end 406.600152 -148.86432)
		(width 0.3556)
		(layer "F.Cu")
		(net "GND")
	)
	(segment
		(start 158.17596 -122.04954)
		(end 157.8864 -121.75998)
		(width 0.4572)
		(layer "F.Cu")
		(net "GND")
	)
	(segment
		(start 347.7641 -148.322284)
		(end 347.7641 -148.297392)
		(width 0.254)
		(layer "F.Cu")
		(net "GND")
	)
	(segment
		(start 390.5377 -106.6546)
		(end 390.93775 -107.05465)
		(width 0.12446)
		(layer "F.Cu")
		(net "GND")
	)
	(segment
		(start 448.53225 -50.490374)
		(end 448.529964 -50.488088)
		(width 0.508)
		(layer "F.Cu")
		(net "GND")
	)
	(segment
		(start 221.04985 -21.517356)
		(end 221.04985 -20.023582)
		(width 0.4064)
		(layer "F.Cu")
		(net "GND")
	)
	(segment
		(start 440.600846 -118.615714)
		(end 440.604402 -118.61927)
		(width 0.4064)
		(layer "F.Cu")
		(net "GND")
	)
	(segment
		(start 285.7881 -87.108538)
		(end 286.3596 -87.108538)
		(width 0.254)
		(layer "F.Cu")
		(net "GND")
	)
	(segment
		(start 210.849972 -142.677642)
		(end 210.849718 -142.677896)
		(width 0.4064)
		(layer "F.Cu")
		(net "GND")
	)
	(segment
		(start 385.33705 -112.65535)
		(end 385.629912 -112.362488)
		(width 0.12446)
		(layer "F.Cu")
		(net "GND")
	)
	(segment
		(start 26.416 -61.58992)
		(end 27.3685 -60.63742)
		(width 0.508)
		(layer "F.Cu")
		(net "GND")
	)
	(segment
		(start 141.199616 -90.575384)
		(end 142.250414 -90.575384)
		(width 0.254)
		(layer "F.Cu")
		(net "GND")
	)
	(segment
		(start 178.870356 -73.85685)
		(end 179.492148 -73.85685)
		(width 0.508)
		(layer "F.Cu")
		(net "GND")
	)
	(segment
		(start 166.4716 -149.098)
		(end 165.8874 -149.098)
		(width 0.254)
		(layer "F.Cu")
		(net "GND")
	)
	(segment
		(start 464.424014 -138.719814)
		(end 464.5152 -138.811)
		(width 0.254)
		(layer "F.Cu")
		(net "GND")
	)
	(segment
		(start 440.206384 -151.83993)
		(end 440.040522 -151.674068)
		(width 0.254)
		(layer "F.Cu")
		(net "GND")
	)
	(segment
		(start 316.25032 -5.822442)
		(end 316.249812 -5.822442)
		(width 0.4064)
		(layer "F.Cu")
		(net "GND")
	)
	(segment
		(start 249.919744 -51.62804)
		(end 249.919744 -50.573432)
		(width 0.2032)
		(layer "F.Cu")
		(net "GND")
	)
	(segment
		(start 30.549342 -15.423642)
		(end 30.549342 -13.929106)
		(width 0.4064)
		(layer "F.Cu")
		(net "GND")
	)
	(segment
		(start 390.21385 -97.83572)
		(end 390.70915 -97.605596)
		(width 0.254)
		(layer "F.Cu")
		(net "GND")
	)
	(segment
		(start 280.460958 -14.1224)
		(end 280.460958 -13.338556)
		(width 0.4064)
		(layer "F.Cu")
		(net "GND")
	)
	(segment
		(start 147.849336 -4.808728)
		(end 147.387564 -4.346956)
		(width 0.4064)
		(layer "F.Cu")
		(net "GND")
	)
	(segment
		(start 126.388368 -6.7564)
		(end 126.388368 -7.612126)
		(width 0.3556)
		(layer "F.Cu")
		(net "GND")
	)
	(segment
		(start 301.812706 -93.052138)
		(end 301.812706 -93.260164)
		(width 0.254)
		(layer "F.Cu")
		(net "GND")
	)
	(segment
		(start 72.041766 -51.132486)
		(end 71.470266 -51.132486)
		(width 0.254)
		(layer "F.Cu")
		(net "GND")
	)
	(segment
		(start 222.749872 -155.612846)
		(end 222.749872 -156.87294)
		(width 0.4064)
		(layer "F.Cu")
		(net "GND")
	)
	(segment
		(start 152.099518 -3.255518)
		(end 152.146 -3.302)
		(width 0.4064)
		(layer "F.Cu")
		(net "GND")
	)
	(segment
		(start 71.171562 -3.762756)
		(end 71.349362 -3.940556)
		(width 0.4064)
		(layer "F.Cu")
		(net "GND")
	)
	(segment
		(start 69.64934 -7.509002)
		(end 69.64934 -5.822442)
		(width 0.4064)
		(layer "F.Cu")
		(net "GND")
	)
	(segment
		(start 305.246786 -55.409338)
		(end 305.533806 -55.122318)
		(width 0.254)
		(layer "F.Cu")
		(net "GND")
	)
	(segment
		(start 211.699856 -136.410446)
		(end 211.699856 -137.67054)
		(width 0.4064)
		(layer "F.Cu")
		(net "GND")
	)
	(segment
		(start 354.36048 -134.853934)
		(end 354.36048 -133.557772)
		(width 0.508)
		(layer "F.Cu")
		(net "GND")
	)
	(segment
		(start 117.640862 -61.847984)
		(end 118.212362 -61.847984)
		(width 0.254)
		(layer "F.Cu")
		(net "GND")
	)
	(segment
		(start 277.203154 -60.362338)
		(end 276.631654 -60.362338)
		(width 0.254)
		(layer "F.Cu")
		(net "GND")
	)
	(segment
		(start 78.051406 -74.411586)
		(end 77.479906 -74.411586)
		(width 0.254)
		(layer "F.Cu")
		(net "GND")
	)
	(segment
		(start 84.919312 -51.62804)
		(end 84.919312 -50.573432)
		(width 0.2032)
		(layer "F.Cu")
		(net "GND")
	)
	(segment
		(start 276.4663 -101.261164)
		(end 276.344634 -101.471984)
		(width 0.254)
		(layer "F.Cu")
		(net "GND")
	)
	(segment
		(start 394.67155 -100.41128)
		(end 394.903706 -100.30333)
		(width 0.254)
		(layer "F.Cu")
		(net "GND")
	)
	(segment
		(start 376.638312 -120.854978)
		(end 377.33605 -120.15724)
		(width 0.254)
		(layer "F.Cu")
		(net "GND")
	)
	(segment
		(start 239.617758 -76.39304)
		(end 239.046258 -76.39304)
		(width 0.254)
		(layer "F.Cu")
		(net "GND")
	)
	(segment
		(start 356.252526 -140.34262)
		(end 356.252526 -139.77239)
		(width 0.1778)
		(layer "F.Cu")
		(net "GND")
	)
	(segment
		(start 389.99668 -110.11408)
		(end 389.99668 -109.93882)
		(width 0.12446)
		(layer "F.Cu")
		(net "GND")
	)
	(segment
		(start 290.0807 -85.622384)
		(end 290.6522 -85.622384)
		(width 0.254)
		(layer "F.Cu")
		(net "GND")
	)
	(segment
		(start 174.8155 -67.945)
		(end 175.277526 -67.945)
		(width 0.4064)
		(layer "F.Cu")
		(net "GND")
	)
	(segment
		(start 102.947724 -56.085486)
		(end 103.557324 -56.085486)
		(width 0.254)
		(layer "F.Cu")
		(net "GND")
	)
	(segment
		(start 130.84937 -152.273)
		(end 130.84937 -154.063446)
		(width 0.4064)
		(layer "F.Cu")
		(net "GND")
	)
	(segment
		(start 379.437646 -104.648)
		(end 379.81255 -104.473756)
		(width 0.254)
		(layer "F.Cu")
		(net "GND")
	)
	(segment
		(start 111.326168 -52.914804)
		(end 111.344202 -52.932838)
		(width 0.254)
		(layer "F.Cu")
		(net "GND")
	)
	(segment
		(start 300.099984 0.444754)
		(end 300.099984 -0.821182)
		(width 0.4064)
		(layer "F.Cu")
		(net "GND")
	)
	(segment
		(start 294.3733 -100.976684)
		(end 294.9448 -100.976684)
		(width 0.3048)
		(layer "F.Cu")
		(net "GND")
	)
	(segment
		(start 49.24933 -5.822696)
		(end 49.249584 -5.822442)
		(width 0.4064)
		(layer "F.Cu")
		(net "GND")
	)
	(segment
		(start 30.2387 -86.505288)
		(end 30.2387 -86.77275)
		(width 0.508)
		(layer "F.Cu")
		(net "GND")
	)
	(segment
		(start 300.099984 -137.67054)
		(end 300.099984 -136.410446)
		(width 0.4064)
		(layer "F.Cu")
		(net "GND")
	)
	(segment
		(start 402.244814 -83.412076)
		(end 402.223986 -83.432904)
		(width 0.254)
		(layer "F.Cu")
		(net "GND")
	)
	(segment
		(start 53.499512 -10.422382)
		(end 53.499512 -9.21385)
		(width 0.3556)
		(layer "F.Cu")
		(net "GND")
	)
	(segment
		(start 119.7991 -5.822696)
		(end 119.7991 -6.637274)
		(width 0.4064)
		(layer "F.Cu")
		(net "GND")
	)
	(segment
		(start 306.963826 -59.371484)
		(end 306.392326 -59.371484)
		(width 0.254)
		(layer "F.Cu")
		(net "GND")
	)
	(segment
		(start 390.93775 -111.85525)
		(end 391.3378 -112.2553)
		(width 0.254)
		(layer "F.Cu")
		(net "GND")
	)
	(segment
		(start 229.549706 -142.677896)
		(end 229.549706 -143.492474)
		(width 0.4064)
		(layer "F.Cu")
		(net "GND")
	)
	(segment
		(start 226.150424 -20.023582)
		(end 226.149916 -20.023582)
		(width 0.4064)
		(layer "F.Cu")
		(net "GND")
	)
	(segment
		(start 284.33776 -4.346956)
		(end 284.799786 -4.808982)
		(width 0.4064)
		(layer "F.Cu")
		(net "GND")
	)
	(segment
		(start 113.849404 -4.487164)
		(end 114.018568 -4.318)
		(width 0.4064)
		(layer "F.Cu")
		(net "GND")
	)
	(segment
		(start 122.504708 -88.099138)
		(end 123.076208 -88.099138)
		(width 0.254)
		(layer "F.Cu")
		(net "GND")
	)
	(segment
		(start 36.499546 -15.423642)
		(end 36.499292 -15.423896)
		(width 0.4064)
		(layer "F.Cu")
		(net "GND")
	)
	(segment
		(start 383.091182 -125.441202)
		(end 383.091182 -126.05893)
		(width 0.254)
		(layer "F.Cu")
		(net "GND")
	)
	(segment
		(start 303.816766 -61.847984)
		(end 304.388266 -61.847984)
		(width 0.254)
		(layer "F.Cu")
		(net "GND")
	)
	(segment
		(start 74.749406 -20.023582)
		(end 74.749406 -21.517356)
		(width 0.4064)
		(layer "F.Cu")
		(net "GND")
	)
	(segment
		(start 466.8774 -0.7366)
		(end 467.106 -0.508)
		(width 0.254)
		(layer "F.Cu")
		(net "GND")
	)
	(segment
		(start 377.108466 -93.091)
		(end 376.854466 -92.837)
		(width 0.254)
		(layer "F.Cu")
		(net "GND")
	)
	(segment
		(start 288.19983 -15.423642)
		(end 288.19983 -13.363956)
		(width 0.4064)
		(layer "F.Cu")
		(net "GND")
	)
	(segment
		(start 398.871186 -3.316986)
		(end 398.8308 -3.2766)
		(width 0.254)
		(layer "F.Cu")
		(net "GND")
	)
	(segment
		(start 382.288542 -115.00612)
		(end 382.53162 -115.26266)
		(width 0.254)
		(layer "F.Cu")
		(net "GND")
	)
	(segment
		(start 275.486114 -55.409338)
		(end 274.914614 -55.409338)
		(width 0.254)
		(layer "F.Cu")
		(net "GND")
	)
	(segment
		(start 478.004378 -134.74573)
		(end 478.524062 -135.265414)
		(width 0.381)
		(layer "F.Cu")
		(net "GND")
	)
	(segment
		(start 217.650314 -5.822442)
		(end 217.649806 -5.822442)
		(width 0.4064)
		(layer "F.Cu")
		(net "GND")
	)
	(segment
		(start 108.768896 -60.362338)
		(end 108.197396 -60.362338)
		(width 0.254)
		(layer "F.Cu")
		(net "GND")
	)
	(segment
		(start 118.041928 -9.156446)
		(end 118.041928 -9.143746)
		(width 0.3556)
		(layer "F.Cu")
		(net "GND")
	)
	(segment
		(start 109.627416 -101.471984)
		(end 109.055916 -101.471984)
		(width 0.254)
		(layer "F.Cu")
		(net "GND")
	)
	(segment
		(start 226.9998 -143.408654)
		(end 226.7966 -143.611854)
		(width 0.3556)
		(layer "F.Cu")
		(net "GND")
	)
	(segment
		(start 286.500316 -152.273)
		(end 286.499808 -152.278842)
		(width 0.4064)
		(layer "F.Cu")
		(net "GND")
	)
	(segment
		(start 213.399878 -137.67054)
		(end 213.399878 -139.170156)
		(width 0.4064)
		(layer "F.Cu")
		(net "GND")
	)
	(segment
		(start 201.499978 -14.410182)
		(end 201.037952 -13.948156)
		(width 0.4064)
		(layer "F.Cu")
		(net "GND")
	)
	(segment
		(start 280.637234 -65.315338)
		(end 280.065734 -65.315338)
		(width 0.254)
		(layer "F.Cu")
		(net "GND")
	)
	(segment
		(start 289.899852 -144.364202)
		(end 289.801808 -144.462246)
		(width 0.4064)
		(layer "F.Cu")
		(net "GND")
	)
	(segment
		(start 241.44986 -156.87294)
		(end 241.450368 -156.87294)
		(width 0.4064)
		(layer "F.Cu")
		(net "GND")
	)
	(segment
		(start 294.999918 -18.757646)
		(end 294.999918 -20.023582)
		(width 0.4064)
		(layer "F.Cu")
		(net "GND")
	)
	(segment
		(start 314.54979 -152.278842)
		(end 314.54979 -154.063446)
		(width 0.4064)
		(layer "F.Cu")
		(net "GND")
	)
	(segment
		(start 199.799956 -21.455888)
		(end 199.742552 -21.513292)
		(width 0.4064)
		(layer "F.Cu")
		(net "GND")
	)
	(segment
		(start 46.699424 -10.422382)
		(end 46.699424 -11.916156)
		(width 0.4064)
		(layer "F.Cu")
		(net "GND")
	)
	(segment
		(start 385.75615 -115.86464)
		(end 386.25145 -116.094764)
		(width 0.254)
		(layer "F.Cu")
		(net "GND")
	)
	(segment
		(start 295.23182 -80.669384)
		(end 295.80332 -80.669384)
		(width 0.254)
		(layer "F.Cu")
		(net "GND")
	)
	(segment
		(start 32.094932 -86.704932)
		(end 32.094932 -87.156544)
		(width 0.254)
		(layer "F.Cu")
		(net "GND")
	)
	(segment
		(start 65.399412 -21.517356)
		(end 65.399412 -20.023582)
		(width 0.4064)
		(layer "F.Cu")
		(net "GND")
	)
	(segment
		(start 120.787668 -78.193138)
		(end 121.358152 -78.193138)
		(width 0.254)
		(layer "F.Cu")
		(net "GND")
	)
	(segment
		(start 129.372868 -52.437538)
		(end 129.944368 -52.437538)
		(width 0.254)
		(layer "F.Cu")
		(net "GND")
	)
	(segment
		(start 82.459068 -3.3528)
		(end 81.582768 -3.3528)
		(width 0.4064)
		(layer "F.Cu")
		(net "GND")
	)
	(segment
		(start 261.27202 -11.65098)
		(end 262.0264 -10.8966)
		(width 0.4064)
		(layer "F.Cu")
		(net "GND")
	)
	(segment
		(start 44.149518 -155.70835)
		(end 44.092114 -155.650946)
		(width 0.4064)
		(layer "F.Cu")
		(net "GND")
	)
	(segment
		(start 207.449928 -18.783046)
		(end 207.424528 -18.757646)
		(width 0.4064)
		(layer "F.Cu")
		(net "GND")
	)
	(segment
		(start 282.104592 -70.332346)
		(end 282.104592 -70.422008)
		(width 0.254)
		(layer "F.Cu")
		(net "GND")
	)
	(segment
		(start 384.27025 -96.11868)
		(end 384.76555 -95.888556)
		(width 0.254)
		(layer "F.Cu")
		(net "GND")
	)
	(segment
		(start 275.111464 -12.954)
		(end 274.258532 -12.954)
		(width 0.381)
		(layer "F.Cu")
		(net "GND")
	)
	(segment
		(start 199.799956 -155.883102)
		(end 199.742552 -155.825698)
		(width 0.4064)
		(layer "F.Cu")
		(net "GND")
	)
	(segment
		(start 280.637234 -97.014538)
		(end 281.208734 -97.014538)
		(width 0.254)
		(layer "F.Cu")
		(net "GND")
	)
	(segment
		(start 107.051856 -61.352938)
		(end 106.480356 -61.352938)
		(width 0.254)
		(layer "F.Cu")
		(net "GND")
	)
	(segment
		(start 367.2205 -136.906)
		(end 367.2205 -136.8298)
		(width 0.4064)
		(layer "F.Cu")
		(net "GND")
	)
	(segment
		(start 86.636352 -79.36484)
		(end 86.064852 -79.36484)
		(width 0.254)
		(layer "F.Cu")
		(net "GND")
	)
	(segment
		(start 436.8292 -17.8308)
		(end 436.499 -18.161)
		(width 0.254)
		(layer "F.Cu")
		(net "GND")
	)
	(segment
		(start 124.221748 -96.023938)
		(end 124.793248 -96.023938)
		(width 0.3048)
		(layer "F.Cu")
		(net "GND")
	)
	(segment
		(start 381.4064 -108.087668)
		(end 381.429514 -108.077)
		(width 0.254)
		(layer "F.Cu")
		(net "GND")
	)
	(segment
		(start 242.299744 -13.363956)
		(end 242.300506 -13.364718)
		(width 0.4064)
		(layer "F.Cu")
		(net "GND")
	)
	(segment
		(start 193.860928 -68.358258)
		(end 193.704464 -68.514722)
		(width 0.381)
		(layer "F.Cu")
		(net "GND")
	)
	(segment
		(start 382.9304 -121.083578)
		(end 383.27965 -121.245884)
		(width 0.254)
		(layer "F.Cu")
		(net "GND")
	)
	(segment
		(start 272.052288 -98.005138)
		(end 272.623788 -98.005138)
		(width 0.254)
		(layer "F.Cu")
		(net "GND")
	)
	(segment
		(start 237.042198 -64.010286)
		(end 236.470698 -64.010286)
		(width 0.254)
		(layer "F.Cu")
		(net "GND")
	)
	(segment
		(start 121.646188 -78.688438)
		(end 122.217688 -78.688438)
		(width 0.254)
		(layer "F.Cu")
		(net "GND")
	)
	(segment
		(start 283.0322 -4.2926)
		(end 284.33776 -4.346956)
		(width 0.254)
		(layer "F.Cu")
		(net "GND")
	)
	(segment
		(start 376.420634 -107.315)
		(end 376.428 -107.355132)
		(width 0.254)
		(layer "F.Cu")
		(net "GND")
	)
	(segment
		(start 43.12158 -17.2466)
		(end 43.076368 -17.201388)
		(width 0.3556)
		(layer "F.Cu")
		(net "GND")
	)
	(segment
		(start 485.452674 -34.822638)
		(end 483.540562 -34.822638)
		(width 0.254)
		(layer "F.Cu")
		(net "GND")
	)
	(segment
		(start 376.385836 -108.1278)
		(end 376.40006 -108.204)
		(width 0.254)
		(layer "F.Cu")
		(net "GND")
	)
	(segment
		(start 302.099726 -81.659984)
		(end 302.671226 -81.659984)
		(width 0.254)
		(layer "F.Cu")
		(net "GND")
	)
	(segment
		(start 414.528 -17.75714)
		(end 413.87014 -18.415)
		(width 0.254)
		(layer "F.Cu")
		(net "GND")
	)
	(segment
		(start 484.2764 -28.0797)
		(end 484.2764 -27.00528)
		(width 0.254)
		(layer "F.Cu")
		(net "GND")
	)
	(segment
		(start 308.600348 -5.822442)
		(end 308.59984 -5.822442)
		(width 0.4064)
		(layer "F.Cu")
		(net "GND")
	)
	(segment
		(start 209.14995 -0.821182)
		(end 209.14995 0.34925)
		(width 0.4064)
		(layer "F.Cu")
		(net "GND")
	)
	(segment
		(start 136.74217 -18.757646)
		(end 136.799574 -18.81505)
		(width 0.3556)
		(layer "F.Cu")
		(net "GND")
	)
	(segment
		(start 481.271834 -35.222434)
		(end 480.91598 -34.86658)
		(width 0.254)
		(layer "F.Cu")
		(net "GND")
	)
	(segment
		(start 477.14916 -34.52876)
		(end 477.2533 -34.6329)
		(width 0.254)
		(layer "F.Cu")
		(net "GND")
	)
	(segment
		(start 292.450012 -9.21385)
		(end 292.392608 -9.156446)
		(width 0.3556)
		(layer "F.Cu")
		(net "GND")
	)
	(segment
		(start 86.636352 -67.47764)
		(end 86.064852 -67.47764)
		(width 0.254)
		(layer "F.Cu")
		(net "GND")
	)
	(segment
		(start 75.475846 -62.029086)
		(end 74.904346 -62.029086)
		(width 0.254)
		(layer "F.Cu")
		(net "GND")
	)
	(segment
		(start 312.849768 -4.808728)
		(end 312.849768 -5.822442)
		(width 0.4064)
		(layer "F.Cu")
		(net "GND")
	)
	(segment
		(start 415.890202 -26.534618)
		(end 415.890202 -27.334718)
		(width 0.254)
		(layer "F.Cu")
		(net "GND")
	)
	(segment
		(start 462.078578 -7.789672)
		(end 462.078578 -8.866378)
		(width 0.254)
		(layer "F.Cu")
		(net "GND")
	)
	(segment
		(start 114.778282 -89.584784)
		(end 115.349782 -89.584784)
		(width 0.254)
		(layer "F.Cu")
		(net "GND")
	)
	(segment
		(start 236.183678 -70.44944)
		(end 235.612178 -70.44944)
		(width 0.254)
		(layer "F.Cu")
		(net "GND")
	)
	(segment
		(start 403.207982 -123.985528)
		(end 403.207982 -124.538232)
		(width 0.254)
		(layer "F.Cu")
		(net "GND")
	)
	(segment
		(start 217.649806 -5.822442)
		(end 217.649806 -3.940556)
		(width 0.4064)
		(layer "F.Cu")
		(net "GND")
	)
	(segment
		(start 123.199398 -5.822442)
		(end 123.199398 -7.607046)
		(width 0.4064)
		(layer "F.Cu")
		(net "GND")
	)
	(segment
		(start 135.735568 -6.781546)
		(end 135.735568 -7.609332)
		(width 0.3556)
		(layer "F.Cu")
		(net "GND")
	)
	(segment
		(start 415.490152 -36.534598)
		(end 415.090102 -36.934648)
		(width 0.254)
		(layer "F.Cu")
		(net "GND")
	)
	(segment
		(start 410.3624 -55.118)
		(end 411.6832 -55.118)
		(width 0.254)
		(layer "F.Cu")
		(net "GND")
	)
	(segment
		(start 127.655828 -97.014538)
		(end 128.227328 -97.014538)
		(width 0.254)
		(layer "F.Cu")
		(net "GND")
	)
	(segment
		(start 488.976162 -148.8948)
		(end 489.153962 -148.717)
		(width 0.254)
		(layer "F.Cu")
		(net "GND")
	)
	(segment
		(start 39.899336 -15.423642)
		(end 39.899336 -17.208246)
		(width 0.4064)
		(layer "F.Cu")
		(net "GND")
	)
	(segment
		(start 32.249364 -144.364202)
		(end 32.15132 -144.462246)
		(width 0.4064)
		(layer "F.Cu")
		(net "GND")
	)
	(segment
		(start 174.24527 -80.21193)
		(end 174.3456 -80.1116)
		(width 0.254)
		(layer "F.Cu")
		(net "GND")
	)
	(segment
		(start 399.634964 -111.854996)
		(end 399.634964 -112.854994)
		(width 0.254)
		(layer "F.Cu")
		(net "GND")
	)
	(segment
		(start 436.121556 -27.432)
		(end 436.521098 -27.032458)
		(width 0.3048)
		(layer "F.Cu")
		(net "GND")
	)
	(segment
		(start 479.806 -143.637)
		(end 479.806 -144.3482)
		(width 0.254)
		(layer "F.Cu")
		(net "GND")
	)
	(segment
		(start 256.78765 -91.25204)
		(end 256.21615 -91.25204)
		(width 0.254)
		(layer "F.Cu")
		(net "GND")
	)
	(segment
		(start 375.885202 -7.789926)
		(end 375.885202 -7.850124)
		(width 0.254)
		(layer "F.Cu")
		(net "GND")
	)
	(segment
		(start 455.7522 -53.2638)
		(end 455.749914 -53.261514)
		(width 0.4064)
		(layer "F.Cu")
		(net "GND")
	)
	(segment
		(start 232.099866 -10.422382)
		(end 232.099866 -11.916156)
		(width 0.4064)
		(layer "F.Cu")
		(net "GND")
	)
	(segment
		(start 285.650432 -20.023582)
		(end 285.649924 -20.023582)
		(width 0.4064)
		(layer "F.Cu")
		(net "GND")
	)
	(segment
		(start 119.929402 -64.819784)
		(end 119.357902 -64.819784)
		(width 0.254)
		(layer "F.Cu")
		(net "GND")
	)
	(segment
		(start 90.928698 -98.681286)
		(end 90.357198 -98.681286)
		(width 0.254)
		(layer "F.Cu")
		(net "GND")
	)
	(segment
		(start 399.13306 -117.97792)
		(end 399.255996 -117.854984)
		(width 0.254)
		(layer "F.Cu")
		(net "GND")
	)
	(segment
		(start 241.44986 -10.422382)
		(end 241.44986 -11.916156)
		(width 0.4064)
		(layer "F.Cu")
		(net "GND")
	)
	(segment
		(start 397.64335 -114.1476)
		(end 397.7894 -114.215418)
		(width 0.254)
		(layer "F.Cu")
		(net "GND")
	)
	(segment
		(start 198.099934 -10.422382)
		(end 198.099934 -9.139682)
		(width 0.4064)
		(layer "F.Cu")
		(net "GND")
	)
	(segment
		(start 69.64934 -152.273)
		(end 69.64934 -153.965402)
		(width 0.4064)
		(layer "F.Cu")
		(net "GND")
	)
	(segment
		(start 229.54996 -14.410182)
		(end 229.087934 -13.948156)
		(width 0.4064)
		(layer "F.Cu")
		(net "GND")
	)
	(segment
		(start 33.949386 -13.541756)
		(end 33.771586 -13.363956)
		(width 0.4064)
		(layer "F.Cu")
		(net "GND")
	)
	(segment
		(start 251.636784 -60.54344)
		(end 251.065284 -60.54344)
		(width 0.254)
		(layer "F.Cu")
		(net "GND")
	)
	(segment
		(start 439.732928 -50.6222)
		(end 439.732166 -50.5206)
		(width 0.508)
		(layer "F.Cu")
		(net "GND")
	)
	(segment
		(start 396.4178 -3.302)
		(end 396.470886 -3.355086)
		(width 0.254)
		(layer "F.Cu")
		(net "GND")
	)
	(segment
		(start 227.849938 -0.821182)
		(end 227.849938 0.38735)
		(width 0.3556)
		(layer "F.Cu")
		(net "GND")
	)
	(segment
		(start 278.2062 -150.0886)
		(end 278.9682 -150.0886)
		(width 0.4064)
		(layer "F.Cu")
		(net "GND")
	)
	(segment
		(start 398.817084 -125.603)
		(end 398.984978 -125.435106)
		(width 0.254)
		(layer "F.Cu")
		(net "GND")
	)
	(segment
		(start 387.604 -86.614)
		(end 387.604 -87.3125)
		(width 0.254)
		(layer "F.Cu")
		(net "GND")
	)
	(segment
		(start 224.449894 -147.27174)
		(end 224.449894 -145.998946)
		(width 0.4064)
		(layer "F.Cu")
		(net "GND")
	)
	(segment
		(start 442.522356 -25.8318)
		(end 442.122052 -26.232104)
		(width 0.3048)
		(layer "F.Cu")
		(net "GND")
	)
	(segment
		(start 217.4494 -144.477994)
		(end 217.472006 -144.5006)
		(width 0.3556)
		(layer "F.Cu")
		(net "GND")
	)
	(segment
		(start 126.388368 -134.0104)
		(end 126.388368 -134.866126)
		(width 0.3556)
		(layer "F.Cu")
		(net "GND")
	)
	(segment
		(start 215.949784 -133.076442)
		(end 215.949784 -134.763002)
		(width 0.4064)
		(layer "F.Cu")
		(net "GND")
	)
	(segment
		(start 428.7393 -47.2821)
		(end 429.407828 -46.613572)
		(width 0.254)
		(layer "F.Cu")
		(net "GND")
	)
	(segment
		(start 77.192886 -50.141886)
		(end 77.192886 -49.991518)
		(width 0.254)
		(layer "F.Cu")
		(net "GND")
	)
	(segment
		(start 39.899336 -133.0706)
		(end 39.899336 -134.861046)
		(width 0.4064)
		(layer "F.Cu")
		(net "GND")
	)
	(segment
		(start 71.349362 -152.273)
		(end 71.349362 -153.006806)
		(width 0.3556)
		(layer "F.Cu")
		(net "GND")
	)
	(segment
		(start 227.792534 -9.156446)
		(end 227.792534 -9.143746)
		(width 0.3556)
		(layer "F.Cu")
		(net "GND")
	)
	(segment
		(start 127.368808 -53.923184)
		(end 127.655828 -53.636164)
		(width 0.254)
		(layer "F.Cu")
		(net "GND")
	)
	(segment
		(start 356.252526 -139.77239)
		(end 356.460298 -139.564618)
		(width 0.1778)
		(layer "F.Cu")
		(net "GND")
	)
	(segment
		(start 293.51478 -80.669384)
		(end 294.08628 -80.669384)
		(width 0.254)
		(layer "F.Cu")
		(net "GND")
	)
	(segment
		(start 57.74944 -156.87294)
		(end 57.74944 -155.612846)
		(width 0.4064)
		(layer "F.Cu")
		(net "GND")
	)
	(segment
		(start 113.849404 -152.278842)
		(end 113.849404 -152.273)
		(width 0.508)
		(layer "F.Cu")
		(net "GND")
	)
	(segment
		(start 395.16685 -112.660684)
		(end 395.66215 -112.43056)
		(width 0.254)
		(layer "F.Cu")
		(net "GND")
	)
	(segment
		(start 4.88315 -14.367764)
		(end 4.565396 -14.685518)
		(width 0.254)
		(layer "F.Cu")
		(net "GND")
	)
	(segment
		(start 165.481 -72.136)
		(end 165.481 -71.5264)
		(width 0.254)
		(layer "F.Cu")
		(net "GND")
	)
	(segment
		(start 218.44254 -136.410446)
		(end 218.44254 -136.397746)
		(width 0.3556)
		(layer "F.Cu")
		(net "GND")
	)
	(segment
		(start 442.597286 -151.350726)
		(end 442.9125 -151.66594)
		(width 0.254)
		(layer "F.Cu")
		(net "GND")
	)
	(segment
		(start 413.490156 -36.934648)
		(end 413.890206 -36.534598)
		(width 0.254)
		(layer "F.Cu")
		(net "GND")
	)
	(segment
		(start 288.36366 -102.462584)
		(end 288.93516 -102.462584)
		(width 0.3048)
		(layer "F.Cu")
		(net "GND")
	)
	(segment
		(start 415.490152 -34.934652)
		(end 415.890202 -35.334702)
		(width 0.254)
		(layer "F.Cu")
		(net "GND")
	)
	(segment
		(start 279.778714 -55.904384)
		(end 279.207214 -55.904384)
		(width 0.254)
		(layer "F.Cu")
		(net "GND")
	)
	(segment
		(start 306.049934 -147.27174)
		(end 306.049934 -146.011646)
		(width 0.4064)
		(layer "F.Cu")
		(net "GND")
	)
	(segment
		(start 382.78435 -96.9772)
		(end 382.9304 -96.909382)
		(width 0.254)
		(layer "F.Cu")
		(net "GND")
	)
	(segment
		(start 278.920194 -62.343538)
		(end 278.348694 -62.343538)
		(width 0.254)
		(layer "F.Cu")
		(net "GND")
	)
	(segment
		(start 73.758806 -69.953886)
		(end 73.187306 -69.953886)
		(width 0.254)
		(layer "F.Cu")
		(net "GND")
	)
	(segment
		(start 39.049452 -2.314956)
		(end 39.049452 -0.821182)
		(width 0.4064)
		(layer "F.Cu")
		(net "GND")
	)
	(segment
		(start 146.092164 -18.744946)
		(end 146.092164 -18.757646)
		(width 0.3556)
		(layer "F.Cu")
		(net "GND")
	)
	(segment
		(start 17.907 -119.040402)
		(end 17.91335 -119.034052)
		(width 0.508)
		(layer "F.Cu")
		(net "GND")
	)
	(segment
		(start 478.200974 -113.773204)
		(end 478.200974 -112.205516)
		(width 0.4064)
		(layer "F.Cu")
		(net "GND")
	)
	(segment
		(start 349.7072 -156.402024)
		(end 349.645224 -156.402024)
		(width 0.254)
		(layer "F.Cu")
		(net "GND")
	)
	(segment
		(start 375.145046 -76.695046)
		(end 374.744996 -76.294996)
		(width 0.254)
		(layer "F.Cu")
		(net "GND")
	)
	(segment
		(start 488.5944 -145.3642)
		(end 488.7722 -145.542)
		(width 0.254)
		(layer "F.Cu")
		(net "GND")
	)
	(segment
		(start 56.899302 -142.856966)
		(end 56.899302 -144.462246)
		(width 0.4064)
		(layer "F.Cu")
		(net "GND")
	)
	(segment
		(start 454.9521 -53.2384)
		(end 454.949814 -53.236114)
		(width 0.4064)
		(layer "F.Cu")
		(net "GND")
	)
	(segment
		(start 462.149952 -53.01615)
		(end 462.143348 -52.2478)
		(width 0.4064)
		(layer "F.Cu")
		(net "GND")
	)
	(segment
		(start 377.83135 -123.821444)
		(end 377.33605 -123.59132)
		(width 0.254)
		(layer "F.Cu")
		(net "GND")
	)
	(segment
		(start 475.5769 -147.4089)
		(end 475.5769 -147.12188)
		(width 0.254)
		(layer "F.Cu")
		(net "GND")
	)
	(segment
		(start 76.334366 -55.59044)
		(end 75.762866 -55.59044)
		(width 0.254)
		(layer "F.Cu")
		(net "GND")
	)
	(segment
		(start 214.249762 -142.677896)
		(end 214.249762 -144.462246)
		(width 0.4064)
		(layer "F.Cu")
		(net "GND")
	)
	(segment
		(start 216.799922 0.444754)
		(end 216.799922 -0.821182)
		(width 0.4064)
		(layer "F.Cu")
		(net "GND")
	)
	(segment
		(start 305.246786 -63.334138)
		(end 304.675286 -63.334138)
		(width 0.254)
		(layer "F.Cu")
		(net "GND")
	)
	(segment
		(start 57.74944 -9.156446)
		(end 57.74944 -10.422382)
		(width 0.4064)
		(layer "F.Cu")
		(net "GND")
	)
	(segment
		(start 213.399878 -18.757646)
		(end 213.399878 -20.023582)
		(width 0.4064)
		(layer "F.Cu")
		(net "GND")
	)
	(segment
		(start 421.004492 -67.8434)
		(end 415.2138 -67.8434)
		(width 0.508)
		(layer "F.Cu")
		(net "GND")
	)
	(segment
		(start 42.449496 -10.422382)
		(end 42.449496 -9.156446)
		(width 0.4064)
		(layer "F.Cu")
		(net "GND")
	)
	(segment
		(start 175.18126 -147.955)
		(end 175.17872 -147.95246)
		(width 0.254)
		(layer "F.Cu")
		(net "GND")
	)
	(segment
		(start 384.76555 -123.821444)
		(end 384.27025 -123.59132)
		(width 0.254)
		(layer "F.Cu")
		(net "GND")
	)
	(segment
		(start 381.79375 -101.039676)
		(end 381.29845 -101.2698)
		(width 0.254)
		(layer "F.Cu")
		(net "GND")
	)
	(segment
		(start 246.485664 -89.27084)
		(end 245.914164 -89.27084)
		(width 0.254)
		(layer "F.Cu")
		(net "GND")
	)
	(segment
		(start 78.909672 -58.06694)
		(end 78.338172 -58.06694)
		(width 0.254)
		(layer "F.Cu")
		(net "GND")
	)
	(segment
		(start 292.450012 -20.023582)
		(end 292.450012 -21.455888)
		(width 0.4064)
		(layer "F.Cu")
		(net "GND")
	)
	(segment
		(start 125.080268 -70.763384)
		(end 125.651768 -70.763384)
		(width 0.254)
		(layer "F.Cu")
		(net "GND")
	)
	(segment
		(start 295.23182 -85.622384)
		(end 295.80332 -85.622384)
		(width 0.3048)
		(layer "F.Cu")
		(net "GND")
	)
	(segment
		(start 266.231116 -56.085486)
		(end 265.659616 -56.085486)
		(width 0.254)
		(layer "F.Cu")
		(net "GND")
	)
	(segment
		(start 454.950068 -63.157354)
		(end 454.757282 -63.35014)
		(width 0.381)
		(layer "F.Cu")
		(net "GND")
	)
	(segment
		(start 396.782798 -156.2481)
		(end 396.782798 -156.803598)
		(width 0.2032)
		(layer "F.Cu")
		(net "GND")
	)
	(segment
		(start 124.049536 -156.87294)
		(end 124.049536 -155.600146)
		(width 0.4064)
		(layer "F.Cu")
		(net "GND")
	)
	(segment
		(start 290.93922 -77.202538)
		(end 291.51072 -77.202538)
		(width 0.254)
		(layer "F.Cu")
		(net "GND")
	)
	(segment
		(start 251.636784 -80.35544)
		(end 251.065284 -80.35544)
		(width 0.254)
		(layer "F.Cu")
		(net "GND")
	)
	(segment
		(start 88.353392 -67.47764)
		(end 87.781892 -67.47764)
		(width 0.254)
		(layer "F.Cu")
		(net "GND")
	)
	(segment
		(start 100.372164 -89.27084)
		(end 99.800664 -89.27084)
		(width 0.254)
		(layer "F.Cu")
		(net "GND")
	)
	(segment
		(start 294.150288 3.778758)
		(end 294.14978 3.778758)
		(width 0.4064)
		(layer "F.Cu")
		(net "GND")
	)
	(segment
		(start 0.18034 -133.07568)
		(end 0.18034 -132.56006)
		(width 0.254)
		(layer "F.Cu")
		(net "GND")
	)
	(segment
		(start 244.768624 -80.35544)
		(end 244.197124 -80.35544)
		(width 0.254)
		(layer "F.Cu")
		(net "GND")
	)
	(segment
		(start 83.202272 -79.36484)
		(end 82.630772 -79.36484)
		(width 0.254)
		(layer "F.Cu")
		(net "GND")
	)
	(segment
		(start 289.22218 -98.995738)
		(end 289.79368 -98.995738)
		(width 0.254)
		(layer "F.Cu")
		(net "GND")
	)
	(segment
		(start 124.221748 -94.042738)
		(end 124.793248 -94.042738)
		(width 0.254)
		(layer "F.Cu")
		(net "GND")
	)
	(segment
		(start 417.83 -55.245)
		(end 418.211 -54.864)
		(width 0.254)
		(layer "F.Cu")
		(net "GND")
	)
	(segment
		(start 287.349946 -137.67054)
		(end 287.349946 -136.410446)
		(width 0.4064)
		(layer "F.Cu")
		(net "GND")
	)
	(segment
		(start 248.202704 -71.44004)
		(end 247.631204 -71.44004)
		(width 0.254)
		(layer "F.Cu")
		(net "GND")
	)
	(segment
		(start 360.684826 -3.420364)
		(end 360.684826 -3.445764)
		(width 0.4572)
		(layer "F.Cu")
		(net "GND")
	)
	(segment
		(start 247.344184 -81.841086)
		(end 246.772684 -81.841086)
		(width 0.254)
		(layer "F.Cu")
		(net "GND")
	)
	(segment
		(start 386.74675 -120.387364)
		(end 386.25145 -120.15724)
		(width 0.254)
		(layer "F.Cu")
		(net "GND")
	)
	(segment
		(start 275.486114 -95.033084)
		(end 276.057614 -95.033084)
		(width 0.1651)
		(layer "F.Cu")
		(net "GND")
	)
	(segment
		(start 232.100374 -0.821182)
		(end 232.099866 -0.821182)
		(width 0.4064)
		(layer "F.Cu")
		(net "GND")
	)
	(segment
		(start 139.34948 -147.27174)
		(end 139.34948 -146.011646)
		(width 0.4064)
		(layer "F.Cu")
		(net "GND")
	)
	(segment
		(start 196.399912 0.457454)
		(end 196.399912 -0.821182)
		(width 0.4064)
		(layer "F.Cu")
		(net "GND")
	)
	(segment
		(start 304.388266 -64.819784)
		(end 304.388266 -65.028318)
		(width 0.254)
		(layer "F.Cu")
		(net "GND")
	)
	(segment
		(start 284.800294 -133.0706)
		(end 284.799786 -133.076442)
		(width 0.3556)
		(layer "F.Cu")
		(net "GND")
	)
	(segment
		(start 286.07512 -61.847984)
		(end 286.64662 -61.847984)
		(width 0.254)
		(layer "F.Cu")
		(net "GND")
	)
	(segment
		(start 78.631288 -12.954)
		(end 78.562454 -12.885166)
		(width 0.4064)
		(layer "F.Cu")
		(net "GND")
	)
	(segment
		(start 386.5372 -113.8555)
		(end 386.93725 -113.45545)
		(width 0.254)
		(layer "F.Cu")
		(net "GND")
	)
	(segment
		(start 427.674786 -4.386072)
		(end 427.674786 -3.71221)
		(width 0.254)
		(layer "F.Cu")
		(net "GND")
	)
	(segment
		(start 383.73685 -112.65535)
		(end 384.1369 -113.0554)
		(width 0.12446)
		(layer "F.Cu")
		(net "GND")
	)
	(segment
		(start 274.627848 -62.838584)
		(end 274.056348 -62.838584)
		(width 0.254)
		(layer "F.Cu")
		(net "GND")
	)
	(segment
		(start 144.411446 -11.916156)
		(end 144.449546 -11.878056)
		(width 0.4064)
		(layer "F.Cu")
		(net "GND")
	)
	(segment
		(start 119.929402 -96.518984)
		(end 120.500902 -96.518984)
		(width 0.254)
		(layer "F.Cu")
		(net "GND")
	)
	(segment
		(start 292.65626 -88.099138)
		(end 293.22776 -88.099138)
		(width 0.254)
		(layer "F.Cu")
		(net "GND")
	)
	(segment
		(start 157.020768 -149.654768)
		(end 156.972 -149.606)
		(width 0.4064)
		(layer "F.Cu")
		(net "GND")
	)
	(segment
		(start 282.354274 -89.089738)
		(end 282.925774 -89.089738)
		(width 0.254)
		(layer "F.Cu")
		(net "GND")
	)
	(segment
		(start 82.343752 -101.508814)
		(end 82.343752 -100.662486)
		(width 0.2032)
		(layer "F.Cu")
		(net "GND")
	)
	(segment
		(start 444.492634 -145.21053)
		(end 444.06947 -145.21053)
		(width 0.254)
		(layer "F.Cu")
		(net "GND")
	)
	(segment
		(start 31.468568 -3.321812)
		(end 31.884112 -3.737356)
		(width 0.4064)
		(layer "F.Cu")
		(net "GND")
	)
	(segment
		(start 424.360848 -17.4244)
		(end 424.0149 -17.770348)
		(width 0.254)
		(layer "F.Cu")
		(net "GND")
	)
	(segment
		(start 84.919312 -74.411586)
		(end 84.347812 -74.411586)
		(width 0.254)
		(layer "F.Cu")
		(net "GND")
	)
	(segment
		(start 120.649492 -10.422382)
		(end 120.649492 -11.916156)
		(width 0.4064)
		(layer "F.Cu")
		(net "GND")
	)
	(segment
		(start 240.476278 -63.019686)
		(end 239.904778 -63.019686)
		(width 0.254)
		(layer "F.Cu")
		(net "GND")
	)
	(segment
		(start 31.468568 -3.321812)
		(end 31.468568 -2.384044)
		(width 0.381)
		(layer "F.Cu")
		(net "GND")
	)
	(segment
		(start 209.150458 -0.821182)
		(end 209.14995 -0.821182)
		(width 0.4064)
		(layer "F.Cu")
		(net "GND")
	)
	(segment
		(start 120.649492 0.444754)
		(end 120.649492 -0.821182)
		(width 0.4064)
		(layer "F.Cu")
		(net "GND")
	)
	(segment
		(start 26.896568 -12.507976)
		(end 26.898092 -12.5095)
		(width 0.4064)
		(layer "F.Cu")
		(net "GND")
	)
	(segment
		(start 249.9106 -149.8092)
		(end 250.7615 -149.8092)
		(width 0.4064)
		(layer "F.Cu")
		(net "GND")
	)
	(segment
		(start 217.649806 -143.411194)
		(end 217.4494 -143.6116)
		(width 0.3048)
		(layer "F.Cu")
		(net "GND")
	)
	(segment
		(start 349.914972 -114.28095)
		(end 350.5454 -113.665)
		(width 0.254)
		(layer "F.Cu")
		(net "GND")
	)
	(segment
		(start 143.599408 -144.364202)
		(end 143.501364 -144.462246)
		(width 0.4064)
		(layer "F.Cu")
		(net "GND")
	)
	(segment
		(start 145.082768 -143.6116)
		(end 145.082768 -144.461738)
		(width 0.3556)
		(layer "F.Cu")
		(net "GND")
	)
	(segment
		(start 215.0999 -145.998946)
		(end 215.0999 -147.27174)
		(width 0.4064)
		(layer "F.Cu")
		(net "GND")
	)
	(segment
		(start 226.149916 -146.011646)
		(end 226.149916 -147.27174)
		(width 0.4064)
		(layer "F.Cu")
		(net "GND")
	)
	(segment
		(start 133.665214 -72.744584)
		(end 134.236714 -72.744584)
		(width 0.254)
		(layer "F.Cu")
		(net "GND")
	)
	(segment
		(start 179.743862 -57.492138)
		(end 180.086 -57.834276)
		(width 0.4064)
		(layer "F.Cu")
		(net "GND")
	)
	(segment
		(start 316.249812 -3.762756)
		(end 316.249812 -5.822442)
		(width 0.4064)
		(layer "F.Cu")
		(net "GND")
	)
	(segment
		(start 275.486114 -98.995738)
		(end 276.057614 -98.995738)
		(width 0.254)
		(layer "F.Cu")
		(net "GND")
	)
	(segment
		(start 230.399844 -10.422382)
		(end 230.399844 -9.156446)
		(width 0.4064)
		(layer "F.Cu")
		(net "GND")
	)
	(segment
		(start 434.243988 -48.308006)
		(end 435.490112 -48.308006)
		(width 0.254)
		(layer "F.Cu")
		(net "GND")
	)
	(segment
		(start 443.322456 -29.0322)
		(end 442.922152 -29.432504)
		(width 0.3048)
		(layer "F.Cu")
		(net "GND")
	)
	(segment
		(start 237.199932 -21.455888)
		(end 237.142528 -21.513292)
		(width 0.4064)
		(layer "F.Cu")
		(net "GND")
	)
	(segment
		(start 33.444942 -62.351158)
		(end 33.444942 -62.772544)
		(width 0.254)
		(layer "F.Cu")
		(net "GND")
	)
	(segment
		(start 135.382254 -74.725784)
		(end 135.953754 -74.725784)
		(width 0.254)
		(layer "F.Cu")
		(net "GND")
	)
	(segment
		(start 142.749524 -18.744946)
		(end 142.749524 -20.023582)
		(width 0.4064)
		(layer "F.Cu")
		(net "GND")
	)
	(segment
		(start 310.299862 -133.076442)
		(end 310.299862 -133.793738)
		(width 0.3556)
		(layer "F.Cu")
		(net "GND")
	)
	(segment
		(start 239.617758 -92.24264)
		(end 239.046258 -92.24264)
		(width 0.254)
		(layer "F.Cu")
		(net "GND")
	)
	(segment
		(start 70.324726 -61.038486)
		(end 69.753226 -61.038486)
		(width 0.254)
		(layer "F.Cu")
		(net "GND")
	)
	(segment
		(start 33.754568 -154.084782)
		(end 33.771586 -154.1018)
		(width 0.3556)
		(layer "F.Cu")
		(net "GND")
	)
	(segment
		(start 262.79729 -98.681286)
		(end 262.22579 -98.681286)
		(width 0.254)
		(layer "F.Cu")
		(net "GND")
	)
	(segment
		(start 230.399844 -11.916156)
		(end 230.399844 -10.422382)
		(width 0.4064)
		(layer "F.Cu")
		(net "GND")
	)
	(segment
		(start 67.749166 -67.47764)
		(end 67.101466 -67.47764)
		(width 0.254)
		(layer "F.Cu")
		(net "GND")
	)
	(segment
		(start 303.816766 -78.688438)
		(end 304.388266 -78.688438)
		(width 0.254)
		(layer "F.Cu")
		(net "GND")
	)
	(segment
		(start 274.627848 -101.471984)
		(end 274.056348 -101.471984)
		(width 0.254)
		(layer "F.Cu")
		(net "GND")
	)
	(segment
		(start 227.000308 -5.822442)
		(end 226.9998 -5.822442)
		(width 0.4064)
		(layer "F.Cu")
		(net "GND")
	)
	(segment
		(start 235.325158 -56.085486)
		(end 234.753658 -56.085486)
		(width 0.254)
		(layer "F.Cu")
		(net "GND")
	)
	(segment
		(start 407.090118 -25.96896)
		(end 407.090118 -26.534618)
		(width 0.254)
		(layer "F.Cu")
		(net "GND")
	)
	(segment
		(start 78.051406 -93.23324)
		(end 77.479906 -93.23324)
		(width 0.254)
		(layer "F.Cu")
		(net "GND")
	)
	(segment
		(start 302.099726 -60.857384)
		(end 302.671226 -60.857384)
		(width 0.254)
		(layer "F.Cu")
		(net "GND")
	)
	(segment
		(start 281.399996 -11.878056)
		(end 281.399996 -10.422382)
		(width 0.4064)
		(layer "F.Cu")
		(net "GND")
	)
	(segment
		(start 369.545108 -71.095108)
		(end 369.944904 -71.494904)
		(width 0.254)
		(layer "F.Cu")
		(net "GND")
	)
	(segment
		(start 202.349862 -137.67054)
		(end 202.349862 -139.170156)
		(width 0.4064)
		(layer "F.Cu")
		(net "GND")
	)
	(segment
		(start 289.22218 -96.023938)
		(end 289.79368 -96.023938)
		(width 0.3048)
		(layer "F.Cu")
		(net "GND")
	)
	(segment
		(start 125.938788 -92.061538)
		(end 126.510288 -92.061538)
		(width 0.254)
		(layer "F.Cu")
		(net "GND")
	)
	(segment
		(start 237.900718 -52.618386)
		(end 237.329218 -52.618386)
		(width 0.254)
		(layer "F.Cu")
		(net "GND")
	)
	(segment
		(start 113.849404 -147.277582)
		(end 113.849404 -147.27174)
		(width 0.4064)
		(layer "F.Cu")
		(net "GND")
	)
	(segment
		(start 278.061674 -102.462584)
		(end 277.774654 -101.967538)
		(width 0.254)
		(layer "F.Cu")
		(net "GND")
	)
	(segment
		(start 289.90036 -152.273)
		(end 289.899852 -152.278842)
		(width 0.4064)
		(layer "F.Cu")
		(net "GND")
	)
	(segment
		(start 391.69975 -115.86464)
		(end 392.02741 -116.016786)
		(width 0.254)
		(layer "F.Cu")
		(net "GND")
	)
	(segment
		(start 215.950292 -142.6718)
		(end 215.949784 -142.677642)
		(width 0.4064)
		(layer "F.Cu")
		(net "GND")
	)
	(segment
		(start 124.89942 -133.0706)
		(end 124.89942 -134.763002)
		(width 0.4064)
		(layer "F.Cu")
		(net "GND")
	)
	(segment
		(start 227.792534 -155.600146)
		(end 227.792534 -155.612846)
		(width 0.3556)
		(layer "F.Cu")
		(net "GND")
	)
	(segment
		(start 31.400496 -78.161134)
		(end 31.318454 -78.243176)
		(width 0.508)
		(layer "F.Cu")
		(net "GND")
	)
	(segment
		(start 411.48 -88.7095)
		(end 411.48 -89.59342)
		(width 0.254)
		(layer "F.Cu")
		(net "GND")
	)
	(segment
		(start 231.249982 -142.856712)
		(end 231.249728 -142.856966)
		(width 0.4064)
		(layer "F.Cu")
		(net "GND")
	)
	(segment
		(start 129.999486 -2.314956)
		(end 128.677416 -2.3622)
		(width 0.254)
		(layer "F.Cu")
		(net "GND")
	)
	(segment
		(start 125.938788 -81.164938)
		(end 126.510288 -81.164938)
		(width 0.254)
		(layer "F.Cu")
		(net "GND")
	)
	(segment
		(start 413.87522 -87.939626)
		(end 413.893762 -87.921084)
		(width 0.3048)
		(layer "F.Cu")
		(net "GND")
	)
	(segment
		(start 222.75038 -147.27174)
		(end 222.749872 -147.27174)
		(width 0.4064)
		(layer "F.Cu")
		(net "GND")
	)
	(segment
		(start 415.490152 -36.534598)
		(end 415.890202 -36.934648)
		(width 0.254)
		(layer "F.Cu")
		(net "GND")
	)
	(segment
		(start 452.550022 -62.00267)
		(end 452.550022 -60.847986)
		(width 0.381)
		(layer "F.Cu")
		(net "GND")
	)
	(segment
		(start 83.202272 -95.21444)
		(end 82.630772 -95.21444)
		(width 0.254)
		(layer "F.Cu")
		(net "GND")
	)
	(segment
		(start 199.800464 -0.821182)
		(end 199.799956 -0.821182)
		(width 0.4064)
		(layer "F.Cu")
		(net "GND")
	)
	(segment
		(start 436.522114 -31.03245)
		(end 436.921656 -30.632908)
		(width 0.3048)
		(layer "F.Cu")
		(net "GND")
	)
	(segment
		(start 374.674892 -96.791272)
		(end 374.171972 -96.791272)
		(width 0.254)
		(layer "F.Cu")
		(net "GND")
	)
	(segment
		(start 31.39948 -21.517356)
		(end 31.39948 -20.023582)
		(width 0.4064)
		(layer "F.Cu")
		(net "GND")
	)
	(segment
		(start 64.549274 -152.279096)
		(end 64.549274 -153.093674)
		(width 0.4064)
		(layer "F.Cu")
		(net "GND")
	)
	(segment
		(start 244.768624 -53.60924)
		(end 244.197124 -53.60924)
		(width 0.254)
		(layer "F.Cu")
		(net "GND")
	)
	(segment
		(start 239.617758 -72.43064)
		(end 239.046258 -72.43064)
		(width 0.254)
		(layer "F.Cu")
		(net "GND")
	)
	(segment
		(start 387.73735 -111.857028)
		(end 387.73735 -111.85525)
		(width 0.1143)
		(layer "F.Cu")
		(net "GND")
	)
	(segment
		(start 278.19731 -3.4798)
		(end 278.8666 -3.4798)
		(width 0.381)
		(layer "F.Cu")
		(net "GND")
	)
	(segment
		(start 272.910808 -52.932838)
		(end 273.198082 -52.438554)
		(width 0.254)
		(layer "F.Cu")
		(net "GND")
	)
	(segment
		(start 203.200508 -152.273)
		(end 203.2 -152.278842)
		(width 0.4064)
		(layer "F.Cu")
		(net "GND")
	)
	(segment
		(start 281.361896 -21.517356)
		(end 281.399996 -21.479256)
		(width 0.4064)
		(layer "F.Cu")
		(net "GND")
	)
	(segment
		(start 175.27016 -104.65562)
		(end 175.58258 -104.65562)
		(width 0.254)
		(layer "F.Cu")
		(net "GND")
	)
	(segment
		(start 235.325158 -62.029086)
		(end 234.753658 -62.029086)
		(width 0.254)
		(layer "F.Cu")
		(net "GND")
	)
	(segment
		(start 455.507344 -141.719808)
		(end 455.50328 -141.723872)
		(width 0.254)
		(layer "F.Cu")
		(net "GND")
	)
	(segment
		(start 296.66184 -58.381138)
		(end 296.09034 -58.381138)
		(width 0.254)
		(layer "F.Cu")
		(net "GND")
	)
	(segment
		(start 198.755 -17.229582)
		(end 198.755 -16.3322)
		(width 0.3556)
		(layer "F.Cu")
		(net "GND")
	)
	(segment
		(start 436.522114 -34.232342)
		(end 436.522114 -34.232596)
		(width 0.3048)
		(layer "F.Cu")
		(net "GND")
	)
	(segment
		(start 77.192886 -58.06694)
		(end 76.621386 -58.06694)
		(width 0.254)
		(layer "F.Cu")
		(net "GND")
	)
	(segment
		(start 71.183246 -64.50584)
		(end 70.611746 -64.50584)
		(width 0.254)
		(layer "F.Cu")
		(net "GND")
	)
	(segment
		(start 76.334366 -67.47764)
		(end 75.762866 -67.47764)
		(width 0.254)
		(layer "F.Cu")
		(net "GND")
	)
	(segment
		(start 133.39953 -11.916156)
		(end 131.699508 -11.916156)
		(width 0.254)
		(layer "F.Cu")
		(net "GND")
	)
	(segment
		(start 248.202704 -85.30844)
		(end 247.631204 -85.30844)
		(width 0.254)
		(layer "F.Cu")
		(net "GND")
	)
	(segment
		(start 417.47059 -51.43881)
		(end 418.180012 -51.43881)
		(width 0.254)
		(layer "F.Cu")
		(net "GND")
	)
	(segment
		(start 225.299778 -17.110202)
		(end 225.299778 -15.423642)
		(width 0.4064)
		(layer "F.Cu")
		(net "GND")
	)
	(segment
		(start 271.193768 -59.866784)
		(end 270.571468 -59.866784)
		(width 0.254)
		(layer "F.Cu")
		(net "GND")
	)
	(segment
		(start 30.566614 -93.715332)
		(end 30.656784 -93.625162)
		(width 0.508)
		(layer "F.Cu")
		(net "GND")
	)
	(segment
		(start 300.382686 -76.706984)
		(end 300.954186 -76.706984)
		(width 0.254)
		(layer "F.Cu")
		(net "GND")
	)
	(segment
		(start 164.5666 -72.644)
		(end 165.0492 -72.644)
		(width 0.254)
		(layer "F.Cu")
		(net "GND")
	)
	(segment
		(start 483.8954 -136.652)
		(end 482.8286 -137.7188)
		(width 0.254)
		(layer "F.Cu")
		(net "GND")
	)
	(segment
		(start 198.949818 -152.278842)
		(end 198.949818 -152.992582)
		(width 0.3556)
		(layer "F.Cu")
		(net "GND")
	)
	(segment
		(start 374.744996 -72.295004)
		(end 375.145046 -71.894954)
		(width 0.254)
		(layer "F.Cu")
		(net "GND")
	)
	(segment
		(start 410.872686 -3.710686)
		(end 410.21 -3.048)
		(width 0.254)
		(layer "F.Cu")
		(net "GND")
	)
	(segment
		(start 239.749838 -2.314956)
		(end 239.749838 -0.821182)
		(width 0.4064)
		(layer "F.Cu")
		(net "GND")
	)
	(segment
		(start 72.900286 -87.28964)
		(end 72.328786 -87.28964)
		(width 0.254)
		(layer "F.Cu")
		(net "GND")
	)
	(segment
		(start 247.344184 -83.822286)
		(end 246.772684 -83.822286)
		(width 0.254)
		(layer "F.Cu")
		(net "GND")
	)
	(segment
		(start 74.617326 -67.47764)
		(end 74.045826 -67.47764)
		(width 0.254)
		(layer "F.Cu")
		(net "GND")
	)
	(segment
		(start 26.602182 -131.40055)
		(end 26.913332 -131.7117)
		(width 0.4064)
		(layer "F.Cu")
		(net "GND")
	)
	(segment
		(start 207.450436 -10.422382)
		(end 207.449928 -10.422382)
		(width 0.4064)
		(layer "F.Cu")
		(net "GND")
	)
	(segment
		(start 193.761868 -76.818236)
		(end 194.054984 -77.111352)
		(width 0.508)
		(layer "F.Cu")
		(net "GND")
	)
	(segment
		(start 442.976 -50.4952)
		(end 442.976 -50.542952)
		(width 0.4064)
		(layer "F.Cu")
		(net "GND")
	)
	(segment
		(start 467.643972 -139.5984)
		(end 467.643972 -138.811)
		(width 0.254)
		(layer "F.Cu")
		(net "GND")
	)
	(segment
		(start 126.797308 -88.594184)
		(end 127.368808 -88.594184)
		(width 0.254)
		(layer "F.Cu")
		(net "GND")
	)
	(segment
		(start 58.599324 -152.279096)
		(end 58.599324 -154.063446)
		(width 0.4064)
		(layer "F.Cu")
		(net "GND")
	)
	(segment
		(start 495.951256 -25.055576)
		(end 495.91976 -25.02408)
		(width 0.254)
		(layer "F.Cu")
		(net "GND")
	)
	(segment
		(start 134.249414 -134.763002)
		(end 134.15137 -134.861046)
		(width 0.4064)
		(layer "F.Cu")
		(net "GND")
	)
	(segment
		(start 294.14978 -4.808728)
		(end 293.688008 -4.346956)
		(width 0.4064)
		(layer "F.Cu")
		(net "GND")
	)
	(segment
		(start 120.787668 -50.8127)
		(end 120.825768 -50.7746)
		(width 0.254)
		(layer "F.Cu")
		(net "GND")
	)
	(segment
		(start 462.940908 -45.925486)
		(end 462.940908 -47.481998)
		(width 0.4064)
		(layer "F.Cu")
		(net "GND")
	)
	(segment
		(start 249.061224 -84.812886)
		(end 248.489724 -84.812886)
		(width 0.254)
		(layer "F.Cu")
		(net "GND")
	)
	(segment
		(start 242.299998 -150.958296)
		(end 242.299998 -152.273)
		(width 0.508)
		(layer "F.Cu")
		(net "GND")
	)
	(segment
		(start 73.899522 -15.423642)
		(end 73.899268 -15.423896)
		(width 0.4064)
		(layer "F.Cu")
		(net "GND")
	)
	(segment
		(start 80.626712 -53.113686)
		(end 80.055212 -53.113686)
		(width 0.254)
		(layer "F.Cu")
		(net "GND")
	)
	(segment
		(start 86.636352 -62.52464)
		(end 86.064852 -62.52464)
		(width 0.254)
		(layer "F.Cu")
		(net "GND")
	)
	(segment
		(start 278.849836 -5.822442)
		(end 278.849836 -7.1374)
		(width 0.4064)
		(layer "F.Cu")
		(net "GND")
	)
	(segment
		(start 466.09 -149.311614)
		(end 466.415374 -149.636988)
		(width 0.254)
		(layer "F.Cu")
		(net "GND")
	)
	(segment
		(start 214.250016 -133.076442)
		(end 214.249762 -133.076696)
		(width 0.4064)
		(layer "F.Cu")
		(net "GND")
	)
	(segment
		(start 399.634964 -97.855024)
		(end 399.634964 -98.855022)
		(width 0.254)
		(layer "F.Cu")
		(net "GND")
	)
	(segment
		(start 299.249846 -142.677642)
		(end 299.249846 -144.364202)
		(width 0.4064)
		(layer "F.Cu")
		(net "GND")
	)
	(segment
		(start 78.909672 -69.953886)
		(end 78.338172 -69.953886)
		(width 0.254)
		(layer "F.Cu")
		(net "GND")
	)
	(segment
		(start 201.499724 -143.492474)
		(end 201.041254 -143.950944)
		(width 0.4064)
		(layer "F.Cu")
		(net "GND")
	)
	(segment
		(start 288.200338 -5.822442)
		(end 288.19983 -5.822442)
		(width 0.4064)
		(layer "F.Cu")
		(net "GND")
	)
	(segment
		(start 64.549274 3.778504)
		(end 64.549274 2.963926)
		(width 0.4064)
		(layer "F.Cu")
		(net "GND")
	)
	(segment
		(start 350.012 -12.827)
		(end 350.647 -12.827)
		(width 0.2032)
		(layer "F.Cu")
		(net "GND")
	)
	(segment
		(start 447.74993 -62.00267)
		(end 447.74993 -60.847986)
		(width 0.381)
		(layer "F.Cu")
		(net "GND")
	)
	(segment
		(start 55.199534 -152.278842)
		(end 55.19928 -152.279096)
		(width 0.4064)
		(layer "F.Cu")
		(net "GND")
	)
	(segment
		(start 112.202722 -59.371484)
		(end 111.631222 -59.371484)
		(width 0.254)
		(layer "F.Cu")
		(net "GND")
	)
	(segment
		(start 119.070882 -67.296538)
		(end 118.499382 -67.296538)
		(width 0.254)
		(layer "F.Cu")
		(net "GND")
	)
	(segment
		(start 114.778282 -96.518984)
		(end 115.349782 -96.518984)
		(width 0.254)
		(layer "F.Cu")
		(net "GND")
	)
	(segment
		(start 379.48489 -93.959934)
		(end 379.48489 -94.790006)
		(width 0.254)
		(layer "F.Cu")
		(net "GND")
	)
	(segment
		(start 49.249584 -152.278842)
		(end 49.24933 -152.279096)
		(width 0.4064)
		(layer "F.Cu")
		(net "GND")
	)
	(segment
		(start 382.498092 -112.866424)
		(end 382.382268 -112.7506)
		(width 0.1143)
		(layer "F.Cu")
		(net "GND")
	)
	(segment
		(start 31.39948 -156.87294)
		(end 31.39948 -155.600146)
		(width 0.4064)
		(layer "F.Cu")
		(net "GND")
	)
	(segment
		(start 306.900326 -5.822442)
		(end 306.899818 -5.822442)
		(width 0.4064)
		(layer "F.Cu")
		(net "GND")
	)
	(segment
		(start 69.56044 -4.6482)
		(end 69.56044 -3.737356)
		(width 0.4064)
		(layer "F.Cu")
		(net "GND")
	)
	(segment
		(start 402.717 -25.654)
		(end 402.134832 -25.654)
		(width 0.254)
		(layer "F.Cu")
		(net "GND")
	)
	(segment
		(start 1.999234 -135.333486)
		(end 2.140458 -135.192262)
		(width 0.254)
		(layer "F.Cu")
		(net "GND")
	)
	(segment
		(start 116.435632 -70.85076)
		(end 116.140992 -71.1454)
		(width 0.254)
		(layer "F.Cu")
		(net "GND")
	)
	(segment
		(start 62.849506 -136.46785)
		(end 62.792102 -136.410446)
		(width 0.3556)
		(layer "F.Cu")
		(net "GND")
	)
	(segment
		(start 448.900296 -19.3675)
		(end 449.1863 -19.653504)
		(width 0.254)
		(layer "F.Cu")
		(net "GND")
	)
	(segment
		(start 135.949436 -5.822442)
		(end 135.949436 -6.567678)
		(width 0.3556)
		(layer "F.Cu")
		(net "GND")
	)
	(segment
		(start 39.049452 -146.011646)
		(end 39.049452 -147.27174)
		(width 0.4064)
		(layer "F.Cu")
		(net "GND")
	)
	(segment
		(start 180.2257 -75.68565)
		(end 180.2257 -76.52385)
		(width 0.4064)
		(layer "F.Cu")
		(net "GND")
	)
	(segment
		(start 138.031474 -21.5138)
		(end 139.34948 -21.517356)
		(width 0.254)
		(layer "F.Cu")
		(net "GND")
	)
	(segment
		(start 33.099502 -147.27174)
		(end 33.099502 -146.011646)
		(width 0.4064)
		(layer "F.Cu")
		(net "GND")
	)
	(segment
		(start 122.504708 -61.352938)
		(end 121.933208 -61.352938)
		(width 0.254)
		(layer "F.Cu")
		(net "GND")
	)
	(segment
		(start 236.1184 -143.637)
		(end 236.1184 -144.447006)
		(width 0.3556)
		(layer "F.Cu")
		(net "GND")
	)
	(segment
		(start 369.5954 -127.762)
		(end 369.2398 -127.4064)
		(width 0.254)
		(layer "F.Cu")
		(net "GND")
	)
	(segment
		(start 300.382686 -97.509584)
		(end 300.954186 -97.509584)
		(width 0.254)
		(layer "F.Cu")
		(net "GND")
	)
	(segment
		(start 373.978932 -158.2166)
		(end 373.702326 -158.493206)
		(width 0.254)
		(layer "F.Cu")
		(net "GND")
	)
	(segment
		(start 459.80096 -118.615714)
		(end 459.804516 -118.61927)
		(width 0.4064)
		(layer "F.Cu")
		(net "GND")
	)
	(segment
		(start 454.201022 -112.205516)
		(end 454.201022 -113.867184)
		(width 0.4064)
		(layer "F.Cu")
		(net "GND")
	)
	(segment
		(start 198.100442 -156.87294)
		(end 198.099934 -156.87294)
		(width 0.4064)
		(layer "F.Cu")
		(net "GND")
	)
	(segment
		(start 238.899954 -142.677642)
		(end 238.8997 -142.677896)
		(width 0.4064)
		(layer "F.Cu")
		(net "GND")
	)
	(segment
		(start 253.353824 -85.30844)
		(end 252.782324 -85.30844)
		(width 0.254)
		(layer "F.Cu")
		(net "GND")
	)
	(segment
		(start 390.70915 -121.01576)
		(end 391.20445 -121.245884)
		(width 0.254)
		(layer "F.Cu")
		(net "GND")
	)
	(segment
		(start 83.202272 -93.23324)
		(end 82.630772 -93.23324)
		(width 0.254)
		(layer "F.Cu")
		(net "GND")
	)
	(segment
		(start 169.157396 -85.315298)
		(end 169.17289 -85.330792)
		(width 0.254)
		(layer "F.Cu")
		(net "GND")
	)
	(segment
		(start 307.8988 -84.631784)
		(end 307.250846 -84.631784)
		(width 0.254)
		(layer "F.Cu")
		(net "GND")
	)
	(segment
		(start 311.092596 -136.410446)
		(end 311.092596 -136.397746)
		(width 0.3556)
		(layer "F.Cu")
		(net "GND")
	)
	(segment
		(start 217.4494 -16.5354)
		(end 217.4494 -16.3576)
		(width 0.3048)
		(layer "F.Cu")
		(net "GND")
	)
	(segment
		(start 135.382254 -78.688438)
		(end 135.953754 -78.688438)
		(width 0.254)
		(layer "F.Cu")
		(net "GND")
	)
	(segment
		(start 114.699542 -137.676382)
		(end 114.699542 -139.170156)
		(width 0.508)
		(layer "F.Cu")
		(net "GND")
	)
	(segment
		(start 237.042198 -85.803486)
		(end 236.470698 -85.803486)
		(width 0.254)
		(layer "F.Cu")
		(net "GND")
	)
	(segment
		(start 241.450368 -20.023582)
		(end 241.44986 -20.023582)
		(width 0.4064)
		(layer "F.Cu")
		(net "GND")
	)
	(segment
		(start 9.093454 -41.5036)
		(end 7.29996 -39.710106)
		(width 0.254)
		(layer "F.Cu")
		(net "GND")
	)
	(segment
		(start 255.07061 -66.48704)
		(end 254.49911 -66.48704)
		(width 0.254)
		(layer "F.Cu")
		(net "GND")
	)
	(segment
		(start 216.80043 -147.27174)
		(end 216.799922 -147.27174)
		(width 0.4064)
		(layer "F.Cu")
		(net "GND")
	)
	(segment
		(start 267.948156 -95.709486)
		(end 267.376656 -95.709486)
		(width 0.254)
		(layer "F.Cu")
		(net "GND")
	)
	(segment
		(start 279.207214 -54.913784)
		(end 279.778714 -54.913784)
		(width 0.254)
		(layer "F.Cu")
		(net "GND")
	)
	(segment
		(start 392.405616 -84.860384)
		(end 392.165078 -85.100922)
		(width 0.254)
		(layer "F.Cu")
		(net "GND")
	)
	(segment
		(start 212.549994 -15.423642)
		(end 212.549994 -13.36421)
		(width 0.4064)
		(layer "F.Cu")
		(net "GND")
	)
	(segment
		(start 127.392176 -2.310892)
		(end 127.44958 -2.253488)
		(width 0.4064)
		(layer "F.Cu")
		(net "GND")
	)
	(segment
		(start 88.353392 -81.34604)
		(end 87.781892 -81.34604)
		(width 0.254)
		(layer "F.Cu")
		(net "GND")
	)
	(segment
		(start 429.651414 -3.359404)
		(end 429.731678 -3.359404)
		(width 0.254)
		(layer "F.Cu")
		(net "GND")
	)
	(segment
		(start 131.089908 -58.381138)
		(end 131.661408 -58.381138)
		(width 0.254)
		(layer "F.Cu")
		(net "GND")
	)
	(segment
		(start 195.550282 -5.822442)
		(end 195.549774 -5.822442)
		(width 0.4064)
		(layer "F.Cu")
		(net "GND")
	)
	(segment
		(start 197.095364 -70.501764)
		(end 196.219826 -69.626226)
		(width 0.254)
		(layer "F.Cu")
		(net "GND")
	)
	(segment
		(start 118.041928 -146.011646)
		(end 118.041928 -145.998946)
		(width 0.3556)
		(layer "F.Cu")
		(net "GND")
	)
	(segment
		(start 285.7881 -97.014538)
		(end 286.3596 -97.014538)
		(width 0.254)
		(layer "F.Cu")
		(net "GND")
	)
	(segment
		(start 131.948174 -52.932838)
		(end 132.519674 -52.932838)
		(width 0.254)
		(layer "F.Cu")
		(net "GND")
	)
	(segment
		(start 289.899852 -3.826256)
		(end 289.810952 -3.737356)
		(width 0.4064)
		(layer "F.Cu")
		(net "GND")
	)
	(segment
		(start 43.12158 -7.6454)
		(end 43.076368 -7.600188)
		(width 0.3556)
		(layer "F.Cu")
		(net "GND")
	)
	(segment
		(start 31.527496 -69.564504)
		(end 31.260796 -69.831204)
		(width 0.381)
		(layer "F.Cu")
		(net "GND")
	)
	(segment
		(start 120.787668 -51.446938)
		(end 120.787668 -50.8127)
		(width 0.254)
		(layer "F.Cu")
		(net "GND")
	)
	(segment
		(start 295.23182 -73.735184)
		(end 295.80332 -73.735184)
		(width 0.254)
		(layer "F.Cu")
		(net "GND")
	)
	(segment
		(start 62.849506 -155.67025)
		(end 62.792102 -155.612846)
		(width 0.3556)
		(layer "F.Cu")
		(net "GND")
	)
	(segment
		(start 279.65654 -101.261164)
		(end 279.778714 -101.471984)
		(width 0.4064)
		(layer "F.Cu")
		(net "GND")
	)
	(segment
		(start 384.27025 -102.98684)
		(end 383.77495 -102.756716)
		(width 0.254)
		(layer "F.Cu")
		(net "GND")
	)
	(segment
		(start 289.049968 -0.821182)
		(end 289.049968 -2.314956)
		(width 0.4064)
		(layer "F.Cu")
		(net "GND")
	)
	(segment
		(start 497.949982 -60.184792)
		(end 498.32006 -60.55487)
		(width 0.254)
		(layer "F.Cu")
		(net "GND")
	)
	(segment
		(start 243.051838 -68.46824)
		(end 242.480338 -68.46824)
		(width 0.254)
		(layer "F.Cu")
		(net "GND")
	)
	(segment
		(start 379.31725 -113.28908)
		(end 379.301248 -113.217198)
		(width 0.2286)
		(layer "F.Cu")
		(net "GND")
	)
	(segment
		(start 129.149348 2.963926)
		(end 128.690878 2.505456)
		(width 0.4064)
		(layer "F.Cu")
		(net "GND")
	)
	(segment
		(start 139.34948 0.444754)
		(end 139.34948 -0.821182)
		(width 0.4064)
		(layer "F.Cu")
		(net "GND")
	)
	(segment
		(start 376.428 -117.355112)
		(end 376.335036 -116.854986)
		(width 0.254)
		(layer "F.Cu")
		(net "GND")
	)
	(segment
		(start 85.777832 -94.718886)
		(end 85.206332 -94.718886)
		(width 0.254)
		(layer "F.Cu")
		(net "GND")
	)
	(segment
		(start 382.78435 -121.01576)
		(end 382.9304 -121.083578)
		(width 0.254)
		(layer "F.Cu")
		(net "GND")
	)
	(segment
		(start 360.684826 -3.445764)
		(end 360.68508 -3.446018)
		(width 0.4572)
		(layer "F.Cu")
		(net "GND")
	)
	(segment
		(start 243.154454 -125.88113)
		(end 242.721384 -126.3142)
		(width 0.4064)
		(layer "F.Cu")
		(net "GND")
	)
	(segment
		(start 77.192886 -93.72854)
		(end 76.621386 -93.72854)
		(width 0.254)
		(layer "F.Cu")
		(net "GND")
	)
	(segment
		(start 30.549342 2.514854)
		(end 30.549342 3.778758)
		(width 0.4064)
		(layer "F.Cu")
		(net "GND")
	)
	(segment
		(start 395.984984 -124.504958)
		(end 394.984986 -124.504958)
		(width 0.254)
		(layer "F.Cu")
		(net "GND")
	)
	(segment
		(start 417.2458 -51.6636)
		(end 417.47059 -51.43881)
		(width 0.254)
		(layer "F.Cu")
		(net "GND")
	)
	(segment
		(start 151.24938 3.778758)
		(end 151.24938 1.994154)
		(width 0.4064)
		(layer "F.Cu")
		(net "GND")
	)
	(segment
		(start 283.212794 -93.547184)
		(end 283.784294 -93.547184)
		(width 0.254)
		(layer "F.Cu")
		(net "GND")
	)
	(segment
		(start 410.872686 -4.386072)
		(end 410.872686 -3.710686)
		(width 0.254)
		(layer "F.Cu")
		(net "GND")
	)
	(segment
		(start 301.800006 -11.854688)
		(end 301.800006 -10.422382)
		(width 0.4064)
		(layer "F.Cu")
		(net "GND")
	)
	(segment
		(start 434.213 -42.2148)
		(end 433.8955 -41.8973)
		(width 0.254)
		(layer "F.Cu")
		(net "GND")
	)
	(segment
		(start 126.797308 -62.838584)
		(end 127.368808 -62.838584)
		(width 0.254)
		(layer "F.Cu")
		(net "GND")
	)
	(segment
		(start 53.442108 -2.310892)
		(end 53.499512 -2.253488)
		(width 0.4064)
		(layer "F.Cu")
		(net "GND")
	)
	(segment
		(start 284.358334 -68.782184)
		(end 284.929834 -68.782184)
		(width 0.254)
		(layer "F.Cu")
		(net "GND")
	)
	(segment
		(start 43.29938 -133.812534)
		(end 43.076368 -134.035546)
		(width 0.3556)
		(layer "F.Cu")
		(net "GND")
	)
	(segment
		(start 47.549562 3.778758)
		(end 47.549562 3.599688)
		(width 0.4064)
		(layer "F.Cu")
		(net "GND")
	)
	(segment
		(start 243.051838 -51.62804)
		(end 243.338604 -51.132486)
		(width 0.254)
		(layer "F.Cu")
		(net "GND")
	)
	(segment
		(start 370.0145 -96.9899)
		(end 370.0145 -96.354646)
		(width 0.254)
		(layer "F.Cu")
		(net "GND")
	)
	(segment
		(start 278.850344 -147.27174)
		(end 278.849836 -147.27174)
		(width 0.4064)
		(layer "F.Cu")
		(net "GND")
	)
	(segment
		(start 119.799354 -5.822442)
		(end 119.799354 -4.808982)
		(width 0.4064)
		(layer "F.Cu")
		(net "GND")
	)
	(segment
		(start 133.665214 -92.556584)
		(end 134.236714 -92.556584)
		(width 0.254)
		(layer "F.Cu")
		(net "GND")
	)
	(segment
		(start 215.0999 0.457454)
		(end 215.0999 -0.821182)
		(width 0.4064)
		(layer "F.Cu")
		(net "GND")
	)
	(segment
		(start 215.949784 -17.110202)
		(end 215.949784 -15.423642)
		(width 0.4064)
		(layer "F.Cu")
		(net "GND")
	)
	(segment
		(start 38.199568 -3.76301)
		(end 38.199314 -3.762756)
		(width 0.4064)
		(layer "F.Cu")
		(net "GND")
	)
	(segment
		(start 300.382686 -83.641184)
		(end 300.954186 -83.641184)
		(width 0.254)
		(layer "F.Cu")
		(net "GND")
	)
	(segment
		(start 286.499808 -152.278842)
		(end 286.499808 -154.063446)
		(width 0.4064)
		(layer "F.Cu")
		(net "GND")
	)
	(segment
		(start 127.44958 -155.67025)
		(end 127.392176 -155.612846)
		(width 0.3556)
		(layer "F.Cu")
		(net "GND")
	)
	(segment
		(start 197.095364 -86.766908)
		(end 197.095364 -87.156544)
		(width 0.254)
		(layer "F.Cu")
		(net "GND")
	)
	(segment
		(start 295.849802 -7.607046)
		(end 295.849802 -5.822442)
		(width 0.4064)
		(layer "F.Cu")
		(net "GND")
	)
	(segment
		(start 47.549308 -142.856966)
		(end 47.549308 -144.462246)
		(width 0.4064)
		(layer "F.Cu")
		(net "GND")
	)
	(segment
		(start 237.142528 -2.310892)
		(end 237.199932 -2.253488)
		(width 0.4064)
		(layer "F.Cu")
		(net "GND")
	)
	(segment
		(start 278.849836 -134.866888)
		(end 278.849836 -133.076442)
		(width 0.4064)
		(layer "F.Cu")
		(net "GND")
	)
	(segment
		(start 222.749872 -21.517356)
		(end 222.749872 -20.023582)
		(width 0.4064)
		(layer "F.Cu")
		(net "GND")
	)
	(segment
		(start 472.42222 -114.4397)
		(end 471.54846 -114.4397)
		(width 0.4064)
		(layer "F.Cu")
		(net "GND")
	)
	(segment
		(start 367.9063 -105.7021)
		(end 364.876334 -105.7021)
		(width 0.254)
		(layer "F.Cu")
		(net "GND")
	)
	(segment
		(start 202.349862 -148.771356)
		(end 202.349862 -147.27174)
		(width 0.4064)
		(layer "F.Cu")
		(net "GND")
	)
	(segment
		(start 217.4494 -6.7564)
		(end 217.649806 -6.555994)
		(width 0.3048)
		(layer "F.Cu")
		(net "GND")
	)
	(segment
		(start 291.79774 -69.772784)
		(end 292.36924 -69.772784)
		(width 0.254)
		(layer "F.Cu")
		(net "GND")
	)
	(segment
		(start 39.899336 -152.273)
		(end 39.899336 -154.063446)
		(width 0.4064)
		(layer "F.Cu")
		(net "GND")
	)
	(segment
		(start 122.349514 -10.422382)
		(end 122.349514 -11.916156)
		(width 0.4064)
		(layer "F.Cu")
		(net "GND")
	)
	(segment
		(start 386.9436 -55.3466)
		(end 385.6609 -55.3466)
		(width 0.254)
		(layer "F.Cu")
		(net "GND")
	)
	(segment
		(start 415.22523 -106.23677)
		(end 417.398454 -106.23677)
		(width 0.254)
		(layer "F.Cu")
		(net "GND")
	)
	(segment
		(start 124.89942 -3.826256)
		(end 124.89942 -5.822442)
		(width 0.4064)
		(layer "F.Cu")
		(net "GND")
	)
	(segment
		(start 313.700414 -20.023582)
		(end 313.699906 -20.023582)
		(width 0.4064)
		(layer "F.Cu")
		(net "GND")
	)
	(segment
		(start 77.299566 3.778758)
		(end 77.299312 3.778504)
		(width 0.4064)
		(layer "F.Cu")
		(net "GND")
	)
	(segment
		(start 417.034218 -52.738782)
		(end 417.2458 -52.5272)
		(width 0.254)
		(layer "F.Cu")
		(net "GND")
	)
	(segment
		(start 116.399564 -156.87294)
		(end 116.399564 -155.612846)
		(width 0.4064)
		(layer "F.Cu")
		(net "GND")
	)
	(segment
		(start 407.461974 -105.664)
		(end 407.9875 -105.664)
		(width 0.254)
		(layer "F.Cu")
		(net "GND")
	)
	(segment
		(start 109.627416 -63.829184)
		(end 109.055916 -63.829184)
		(width 0.254)
		(layer "F.Cu")
		(net "GND")
	)
	(segment
		(start 113.849404 -152.273)
		(end 113.849404 -150.81631)
		(width 0.508)
		(layer "F.Cu")
		(net "GND")
	)
	(segment
		(start 29.71673 -85.983318)
		(end 30.2387 -86.505288)
		(width 0.508)
		(layer "F.Cu")
		(net "GND")
	)
	(segment
		(start 480.5045 -142.875)
		(end 480.5045 -143.256)
		(width 0.254)
		(layer "F.Cu")
		(net "GND")
	)
	(segment
		(start 451.000876 -113.816384)
		(end 450.99986 -113.8174)
		(width 0.4064)
		(layer "F.Cu")
		(net "GND")
	)
	(segment
		(start 85.777832 -91.747086)
		(end 85.206332 -91.747086)
		(width 0.254)
		(layer "F.Cu")
		(net "GND")
	)
	(segment
		(start 117.015768 2.01168)
		(end 117.071648 1.9558)
		(width 0.3556)
		(layer "F.Cu")
		(net "GND")
	)
	(segment
		(start 146.092164 -2.310892)
		(end 146.149568 -2.253488)
		(width 0.4064)
		(layer "F.Cu")
		(net "GND")
	)
	(segment
		(start 289.22218 -100.976684)
		(end 289.79368 -100.976684)
		(width 0.3048)
		(layer "F.Cu")
		(net "GND")
	)
	(segment
		(start 251.923804 -98.681286)
		(end 251.636784 -99.17684)
		(width 0.254)
		(layer "F.Cu")
		(net "GND")
	)
	(segment
		(start 26.8224 -76.7334)
		(end 26.289 -76.7334)
		(width 0.254)
		(layer "F.Cu")
		(net "GND")
	)
	(segment
		(start 170.547538 -147.42922)
		(end 169.11193 -147.42922)
		(width 0.254)
		(layer "F.Cu")
		(net "GND")
	)
	(segment
		(start 491.2106 -121.80062)
		(end 492.47298 -121.80062)
		(width 0.254)
		(layer "F.Cu")
		(net "GND")
	)
	(segment
		(start 239.617758 -59.55284)
		(end 239.046258 -59.55284)
		(width 0.254)
		(layer "F.Cu")
		(net "GND")
	)
	(segment
		(start 145.29943 -5.822442)
		(end 145.29943 -6.539738)
		(width 0.3556)
		(layer "F.Cu")
		(net "GND")
	)
	(segment
		(start 214.250524 -142.6718)
		(end 214.250016 -142.677642)
		(width 0.4064)
		(layer "F.Cu")
		(net "GND")
	)
	(segment
		(start 96.079818 -63.019686)
		(end 95.508318 -63.019686)
		(width 0.254)
		(layer "F.Cu")
		(net "GND")
	)
	(segment
		(start 204.049884 -10.422382)
		(end 204.049884 -11.916156)
		(width 0.4064)
		(layer "F.Cu")
		(net "GND")
	)
	(segment
		(start 295.23182 -84.631784)
		(end 295.80332 -84.631784)
		(width 0.254)
		(layer "F.Cu")
		(net "GND")
	)
	(segment
		(start 78.051406 -84.31784)
		(end 77.479906 -84.31784)
		(width 0.254)
		(layer "F.Cu")
		(net "GND")
	)
	(segment
		(start 289.049968 -9.143746)
		(end 289.049968 -10.422382)
		(width 0.4064)
		(layer "F.Cu")
		(net "GND")
	)
	(segment
		(start 285.649924 -11.916156)
		(end 284.3276 -11.9634)
		(width 0.254)
		(layer "F.Cu")
		(net "GND")
	)
	(segment
		(start 272.910808 -93.547184)
		(end 273.482308 -93.547184)
		(width 0.254)
		(layer "F.Cu")
		(net "GND")
	)
	(segment
		(start 199.742552 -18.970498)
		(end 199.799956 -19.027902)
		(width 0.4064)
		(layer "F.Cu")
		(net "GND")
	)
	(segment
		(start 66.249296 -13.363956)
		(end 66.249296 -15.423388)
		(width 0.4064)
		(layer "F.Cu")
		(net "GND")
	)
	(segment
		(start 99.513898 -89.765886)
		(end 98.942398 -89.765886)
		(width 0.254)
		(layer "F.Cu")
		(net "GND")
	)
	(segment
		(start 374.674892 -123.731528)
		(end 374.674892 -122.918728)
		(width 0.254)
		(layer "F.Cu")
		(net "GND")
	)
	(segment
		(start 136.799574 -146.06905)
		(end 136.74217 -146.011646)
		(width 0.3556)
		(layer "F.Cu")
		(net "GND")
	)
	(segment
		(start 243.910104 -57.076086)
		(end 243.338604 -57.076086)
		(width 0.254)
		(layer "F.Cu")
		(net "GND")
	)
	(segment
		(start 394.67155 -119.29872)
		(end 395.16685 -119.528844)
		(width 0.254)
		(layer "F.Cu")
		(net "GND")
	)
	(segment
		(start 77.299312 -15.423896)
		(end 77.299312 -17.208246)
		(width 0.4064)
		(layer "F.Cu")
		(net "GND")
	)
	(segment
		(start 62.849506 -11.854688)
		(end 62.849506 -10.422382)
		(width 0.4064)
		(layer "F.Cu")
		(net "GND")
	)
	(segment
		(start 141.049502 -156.87294)
		(end 141.049502 -155.612846)
		(width 0.4064)
		(layer "F.Cu")
		(net "GND")
	)
	(segment
		(start 298.665646 -80.669384)
		(end 299.237146 -80.669384)
		(width 0.254)
		(layer "F.Cu")
		(net "GND")
	)
	(segment
		(start 71.117968 -144.447006)
		(end 71.171562 -144.5006)
		(width 0.3556)
		(layer "F.Cu")
		(net "GND")
	)
	(segment
		(start 171.704 -71.5264)
		(end 171.7548 -71.5264)
		(width 0.254)
		(layer "F.Cu")
		(net "GND")
	)
	(segment
		(start 288.200338 -15.423642)
		(end 288.19983 -15.423642)
		(width 0.4064)
		(layer "F.Cu")
		(net "GND")
	)
	(segment
		(start 236.183678 -53.60924)
		(end 235.612178 -53.60924)
		(width 0.254)
		(layer "F.Cu")
		(net "GND")
	)
	(segment
		(start 61.796168 -134.874)
		(end 61.821568 -134.8994)
		(width 0.3556)
		(layer "F.Cu")
		(net "GND")
	)
	(segment
		(start 304.675286 -82.155284)
		(end 305.246786 -82.155284)
		(width 0.254)
		(layer "F.Cu")
		(net "GND")
	)
	(segment
		(start 136.613138 -102.958138)
		(end 136.8298 -103.1748)
		(width 0.4064)
		(layer "F.Cu")
		(net "GND")
	)
	(segment
		(start 70.324726 -85.803486)
		(end 69.753226 -85.803486)
		(width 0.254)
		(layer "F.Cu")
		(net "GND")
	)
	(segment
		(start 268.679168 -149.8092)
		(end 267.794232 -149.8092)
		(width 0.4572)
		(layer "F.Cu")
		(net "GND")
	)
	(segment
		(start 400.465036 -100.855018)
		(end 399.634964 -100.855018)
		(width 0.254)
		(layer "F.Cu")
		(net "GND")
	)
	(segment
		(start 29.02458 -105.918508)
		(end 28.7274 -105.621328)
		(width 0.4064)
		(layer "F.Cu")
		(net "GND")
	)
	(segment
		(start 401.295108 -125.357128)
		(end 401.991576 -125.749558)
		(width 0.254)
		(layer "F.Cu")
		(net "GND")
	)
	(segment
		(start 291.79774 -89.584784)
		(end 292.36924 -89.584784)
		(width 0.254)
		(layer "F.Cu")
		(net "GND")
	)
	(segment
		(start 152.146 -11.97356)
		(end 152.146 -12.954)
		(width 0.4064)
		(layer "F.Cu")
		(net "GND")
	)
	(segment
		(start 90.928698 -95.709486)
		(end 90.357198 -95.709486)
		(width 0.254)
		(layer "F.Cu")
		(net "GND")
	)
	(segment
		(start 254.212344 -56.085486)
		(end 253.640844 -56.085486)
		(width 0.254)
		(layer "F.Cu")
		(net "GND")
	)
	(segment
		(start 420.69004 -36.934648)
		(end 420.28999 -37.334698)
		(width 0.254)
		(layer "F.Cu")
		(net "GND")
	)
	(segment
		(start 210.849972 -4.808982)
		(end 210.849972 -5.822442)
		(width 0.4064)
		(layer "F.Cu")
		(net "GND")
	)
	(segment
		(start 474.523816 -123.867164)
		(end 475.015052 -123.375928)
		(width 0.381)
		(layer "F.Cu")
		(net "GND")
	)
	(segment
		(start 249.061224 -67.972686)
		(end 248.489724 -67.972686)
		(width 0.254)
		(layer "F.Cu")
		(net "GND")
	)
	(segment
		(start 300.099984 -20.023582)
		(end 300.099984 -21.479256)
		(width 0.4064)
		(layer "F.Cu")
		(net "GND")
	)
	(segment
		(start 382.3462 -116.74983)
		(end 382.78435 -116.953284)
		(width 0.254)
		(layer "F.Cu")
		(net "GND")
	)
	(segment
		(start -2.205228 -117.38864)
		(end -1.958848 -117.14226)
		(width 0.254)
		(layer "F.Cu")
		(net "GND")
	)
	(segment
		(start 223.599756 -142.677896)
		(end 223.599756 -144.462246)
		(width 0.4064)
		(layer "F.Cu")
		(net "GND")
	)
	(segment
		(start 303.60874 -2.341626)
		(end 303.43602 -2.347722)
		(width 0.254)
		(layer "F.Cu")
		(net "GND")
	)
	(segment
		(start 288.200338 -152.273)
		(end 288.19983 -152.278842)
		(width 0.4064)
		(layer "F.Cu")
		(net "GND")
	)
	(segment
		(start 306.88788 -84.631784)
		(end 306.392326 -85.127338)
		(width 0.254)
		(layer "F.Cu")
		(net "GND")
	)
	(segment
		(start 290.750498 -10.422382)
		(end 290.74999 -10.422382)
		(width 0.4064)
		(layer "F.Cu")
		(net "GND")
	)
	(segment
		(start 116.495322 -96.518984)
		(end 117.066822 -96.518984)
		(width 0.254)
		(layer "F.Cu")
		(net "GND")
	)
	(segment
		(start 304.35042 -20.023582)
		(end 304.349912 -20.023582)
		(width 0.4064)
		(layer "F.Cu")
		(net "GND")
	)
	(segment
		(start 441.400946 -113.816384)
		(end 441.39993 -113.8174)
		(width 0.4064)
		(layer "F.Cu")
		(net "GND")
	)
	(segment
		(start 284.929834 -55.904384)
		(end 284.358334 -55.904384)
		(width 0.254)
		(layer "F.Cu")
		(net "GND")
	)
	(segment
		(start 124.221748 -65.315338)
		(end 123.650248 -65.315338)
		(width 0.254)
		(layer "F.Cu")
		(net "GND")
	)
	(segment
		(start 282.354274 -59.371484)
		(end 281.782774 -59.371484)
		(width 0.254)
		(layer "F.Cu")
		(net "GND")
	)
	(segment
		(start 76.334366 -50.63744)
		(end 75.762866 -50.63744)
		(width 0.254)
		(layer "F.Cu")
		(net "GND")
	)
	(segment
		(start 237.199932 -10.422382)
		(end 237.199932 -11.854688)
		(width 0.4064)
		(layer "F.Cu")
		(net "GND")
	)
	(segment
		(start 305.533806 -52.932838)
		(end 305.761644 -52.705)
		(width 0.254)
		(layer "F.Cu")
		(net "GND")
	)
	(segment
		(start 62.849506 -137.67054)
		(end 62.849506 -136.46785)
		(width 0.3556)
		(layer "F.Cu")
		(net "GND")
	)
	(segment
		(start 223.600518 -142.6718)
		(end 223.60001 -142.677642)
		(width 0.4064)
		(layer "F.Cu")
		(net "GND")
	)
	(segment
		(start 395.16685 -110.943644)
		(end 395.66215 -110.71352)
		(width 0.254)
		(layer "F.Cu")
		(net "GND")
	)
	(segment
		(start 67.949572 -133.076442)
		(end 67.949318 -133.076696)
		(width 0.4064)
		(layer "F.Cu")
		(net "GND")
	)
	(segment
		(start 283.3624 -52.684172)
		(end 283.501592 -52.443634)
		(width 0.254)
		(layer "F.Cu")
		(net "GND")
	)
	(segment
		(start 306.899818 -3.762756)
		(end 306.899818 -5.822442)
		(width 0.4064)
		(layer "F.Cu")
		(net "GND")
	)
	(segment
		(start 375.089928 -98.354896)
		(end 375.92 -98.354896)
		(width 0.254)
		(layer "F.Cu")
		(net "GND")
	)
	(segment
		(start 294.3733 -81.164938)
		(end 294.9448 -81.164938)
		(width 0.254)
		(layer "F.Cu")
		(net "GND")
	)
	(segment
		(start 243.149882 -147.27174)
		(end 243.15039 -147.27174)
		(width 0.4064)
		(layer "F.Cu")
		(net "GND")
	)
	(segment
		(start 285.650432 -137.67054)
		(end 285.649924 -137.67054)
		(width 0.4064)
		(layer "F.Cu")
		(net "GND")
	)
	(segment
		(start 198.432674 -94.886526)
		(end 198.432674 -95.284544)
		(width 0.254)
		(layer "F.Cu")
		(net "GND")
	)
	(segment
		(start 436.522114 -32.606742)
		(end 436.522114 -32.632396)
		(width 0.3048)
		(layer "F.Cu")
		(net "GND")
	)
	(segment
		(start 72.041766 -85.803486)
		(end 71.470266 -85.803486)
		(width 0.254)
		(layer "F.Cu")
		(net "GND")
	)
	(segment
		(start 394.9192 -157.2514)
		(end 394.9192 -157.71114)
		(width 0.2032)
		(layer "F.Cu")
		(net "GND")
	)
	(segment
		(start 204.899768 -152.278842)
		(end 204.899768 -154.063446)
		(width 0.4064)
		(layer "F.Cu")
		(net "GND")
	)
	(segment
		(start 264.51433 -63.019686)
		(end 263.94283 -63.019686)
		(width 0.254)
		(layer "F.Cu")
		(net "GND")
	)
	(segment
		(start 387.73735 -107.05465)
		(end 387.3373 -106.6546)
		(width 0.254)
		(layer "F.Cu")
		(net "GND")
	)
	(segment
		(start 374.674892 -100.855018)
		(end 374.56491 -100.965)
		(width 0.254)
		(layer "F.Cu")
		(net "GND")
	)
	(segment
		(start 143.599408 -152.273)
		(end 143.599408 -153.965402)
		(width 0.4064)
		(layer "F.Cu")
		(net "GND")
	)
	(segment
		(start 366.54486 -95.9485)
		(end 366.2172 -96.27616)
		(width 0.254)
		(layer "F.Cu")
		(net "GND")
	)
	(segment
		(start 296.948606 -59.866784)
		(end 297.520106 -59.866784)
		(width 0.254)
		(layer "F.Cu")
		(net "GND")
	)
	(segment
		(start 2.54 -143.764)
		(end 2.54 -143.256)
		(width 0.4064)
		(layer "F.Cu")
		(net "GND")
	)
	(segment
		(start 397.7894 -100.343462)
		(end 398.13865 -100.181156)
		(width 0.254)
		(layer "F.Cu")
		(net "GND")
	)
	(segment
		(start 67.949572 -152.278842)
		(end 67.949318 -152.279096)
		(width 0.4064)
		(layer "F.Cu")
		(net "GND")
	)
	(segment
		(start 248.202704 -92.24264)
		(end 247.631204 -92.24264)
		(width 0.254)
		(layer "F.Cu")
		(net "GND")
	)
	(segment
		(start 383.3368 -105.0544)
		(end 383.73685 -104.65435)
		(width 0.12446)
		(layer "F.Cu")
		(net "GND")
	)
	(segment
		(start 433.275486 -7.789672)
		(end 433.275486 -9.222486)
		(width 0.254)
		(layer "F.Cu")
		(net "GND")
	)
	(segment
		(start 385.844288 -112.362488)
		(end 386.13715 -112.65535)
		(width 0.12446)
		(layer "F.Cu")
		(net "GND")
	)
	(segment
		(start -0.500126 -45.310044)
		(end 0.933958 -46.744128)
		(width 0.508)
		(layer "F.Cu")
		(net "GND")
	)
	(segment
		(start 450.461634 -145.21053)
		(end 448.93357 -145.21053)
		(width 0.254)
		(layer "F.Cu")
		(net "GND")
	)
	(segment
		(start 72.142096 -146.011646)
		(end 72.142096 -145.998946)
		(width 0.3556)
		(layer "F.Cu")
		(net "GND")
	)
	(segment
		(start 71.349362 -16.151606)
		(end 71.117968 -16.383)
		(width 0.3556)
		(layer "F.Cu")
		(net "GND")
	)
	(segment
		(start 387.1595 -79.8322)
		(end 388.1755 -79.8322)
		(width 0.254)
		(layer "F.Cu")
		(net "GND")
	)
	(segment
		(start 287.21812 -94.538038)
		(end 286.64662 -94.538038)
		(width 0.3048)
		(layer "F.Cu")
		(net "GND")
	)
	(segment
		(start 84.060792 -82.83194)
		(end 83.489292 -82.83194)
		(width 0.254)
		(layer "F.Cu")
		(net "GND")
	)
	(segment
		(start 67.099434 -11.916156)
		(end 67.099434 -10.422382)
		(width 0.4064)
		(layer "F.Cu")
		(net "GND")
	)
	(segment
		(start 306.049934 -2.314956)
		(end 306.049934 -0.821182)
		(width 0.4064)
		(layer "F.Cu")
		(net "GND")
	)
	(segment
		(start 136.799574 -147.27174)
		(end 136.799574 -146.06905)
		(width 0.3556)
		(layer "F.Cu")
		(net "GND")
	)
	(segment
		(start 138.816334 -72.744584)
		(end 139.387834 -72.744584)
		(width 0.254)
		(layer "F.Cu")
		(net "GND")
	)
	(segment
		(start 75.475846 -58.06694)
		(end 74.904346 -58.06694)
		(width 0.254)
		(layer "F.Cu")
		(net "GND")
	)
	(segment
		(start 303.816766 -51.490626)
		(end 303.816766 -51.941984)
		(width 0.254)
		(layer "F.Cu")
		(net "GND")
	)
	(segment
		(start 184.9374 -114.3)
		(end 184.9374 -115.55095)
		(width 0.254)
		(layer "F.Cu")
		(net "GND")
	)
	(segment
		(start 236.1184 2.009394)
		(end 236.171994 1.9558)
		(width 0.3556)
		(layer "F.Cu")
		(net "GND")
	)
	(segment
		(start 385.33705 -112.65535)
		(end 385.629912 -112.948212)
		(width 0.12446)
		(layer "F.Cu")
		(net "GND")
	)
	(segment
		(start 71.117968 -7.591806)
		(end 71.171562 -7.6454)
		(width 0.3556)
		(layer "F.Cu")
		(net "GND")
	)
	(segment
		(start 124.89942 -15.423642)
		(end 124.89942 -17.110202)
		(width 0.4064)
		(layer "F.Cu")
		(net "GND")
	)
	(segment
		(start 42.411396 -148.771356)
		(end 42.449496 -148.733256)
		(width 0.4064)
		(layer "F.Cu")
		(net "GND")
	)
	(segment
		(start 234.466638 -83.32724)
		(end 233.895138 -83.32724)
		(width 0.254)
		(layer "F.Cu")
		(net "GND")
	)
	(segment
		(start 220.199966 -5.822442)
		(end 220.199712 -5.822696)
		(width 0.4064)
		(layer "F.Cu")
		(net "GND")
	)
	(segment
		(start 226.7966 -17.2212)
		(end 226.7966 -16.357854)
		(width 0.3556)
		(layer "F.Cu")
		(net "GND")
	)
	(segment
		(start 134.523734 -77.202538)
		(end 135.095234 -77.202538)
		(width 0.254)
		(layer "F.Cu")
		(net "GND")
	)
	(segment
		(start 349.0976 -10.2108)
		(end 349.0976 -9.923272)
		(width 0.4064)
		(layer "F.Cu")
		(net "GND")
	)
	(segment
		(start 273.769328 -90.080338)
		(end 274.340828 -90.080338)
		(width 0.254)
		(layer "F.Cu")
		(net "GND")
	)
	(segment
		(start 142.250414 -61.847984)
		(end 142.898114 -61.847984)
		(width 0.254)
		(layer "F.Cu")
		(net "GND")
	)
	(segment
		(start 172.1993 -71.628)
		(end 172.2247 -71.6026)
		(width 0.254)
		(layer "F.Cu")
		(net "GND")
	)
	(segment
		(start 283.04236 -146.011646)
		(end 283.04236 -145.998946)
		(width 0.3556)
		(layer "F.Cu")
		(net "GND")
	)
	(segment
		(start 121.499376 -5.822442)
		(end 121.499376 -3.762756)
		(width 0.4064)
		(layer "F.Cu")
		(net "GND")
	)
	(segment
		(start 112.202722 -64.324738)
		(end 111.631222 -64.324738)
		(width 0.254)
		(layer "F.Cu")
		(net "GND")
	)
	(segment
		(start 369.062 -95.9485)
		(end 366.54486 -95.9485)
		(width 0.254)
		(layer "F.Cu")
		(net "GND")
	)
	(segment
		(start 293.51478 -73.735184)
		(end 294.08628 -73.735184)
		(width 0.254)
		(layer "F.Cu")
		(net "GND")
	)
	(segment
		(start 301.800006 -137.67054)
		(end 301.800006 -136.46785)
		(width 0.3556)
		(layer "F.Cu")
		(net "GND")
	)
	(segment
		(start 45.849286 2.963926)
		(end 45.390816 2.505456)
		(width 0.4064)
		(layer "F.Cu")
		(net "GND")
	)
	(segment
		(start 69.64934 3.778758)
		(end 69.64934 2.092198)
		(width 0.4064)
		(layer "F.Cu")
		(net "GND")
	)
	(segment
		(start 237.900718 -70.44944)
		(end 237.329218 -70.44944)
		(width 0.254)
		(layer "F.Cu")
		(net "GND")
	)
	(segment
		(start 138.816334 -79.678784)
		(end 139.387834 -79.678784)
		(width 0.254)
		(layer "F.Cu")
		(net "GND")
	)
	(segment
		(start 90.071956 -3.635756)
		(end 90.802968 -3.635756)
		(width 0.4064)
		(layer "F.Cu")
		(net "GND")
	)
	(segment
		(start 140.8176 -90.9574)
		(end 141.199616 -90.575384)
		(width 0.254)
		(layer "F.Cu")
		(net "GND")
	)
	(segment
		(start 39.899336 -142.6718)
		(end 39.899336 -144.462246)
		(width 0.4064)
		(layer "F.Cu")
		(net "GND")
	)
	(segment
		(start 283.04236 -18.757646)
		(end 283.099764 -18.81505)
		(width 0.3556)
		(layer "F.Cu")
		(net "GND")
	)
	(segment
		(start 488.188 -34.29)
		(end 488.188 -33.655)
		(width 0.254)
		(layer "F.Cu")
		(net "GND")
	)
	(segment
		(start 199.800464 -147.27174)
		(end 199.799956 -147.27174)
		(width 0.4064)
		(layer "F.Cu")
		(net "GND")
	)
	(segment
		(start 489.86059 -34.687002)
		(end 489.7374 -34.563812)
		(width 0.254)
		(layer "F.Cu")
		(net "GND")
	)
	(segment
		(start 30.020006 -13.929106)
		(end 29.464 -13.3731)
		(width 0.4064)
		(layer "F.Cu")
		(net "GND")
	)
	(segment
		(start 127.44958 -137.67054)
		(end 127.44958 -136.46785)
		(width 0.3556)
		(layer "F.Cu")
		(net "GND")
	)
	(segment
		(start 130.231388 -76.706984)
		(end 130.802888 -76.706984)
		(width 0.254)
		(layer "F.Cu")
		(net "GND")
	)
	(segment
		(start 264.51433 -98.681286)
		(end 263.94283 -98.681286)
		(width 0.254)
		(layer "F.Cu")
		(net "GND")
	)
	(segment
		(start 297.807126 -80.174338)
		(end 298.378626 -80.174338)
		(width 0.254)
		(layer "F.Cu")
		(net "GND")
	)
	(segment
		(start 381.99568 -104.411018)
		(end 382.288542 -104.70388)
		(width 0.12446)
		(layer "F.Cu")
		(net "GND")
	)
	(segment
		(start 175.14316 -63.8556)
		(end 175.35652 -64.06896)
		(width 0.4064)
		(layer "F.Cu")
		(net "GND")
	)
	(segment
		(start 130.231388 -60.857384)
		(end 130.802888 -60.857384)
		(width 0.254)
		(layer "F.Cu")
		(net "GND")
	)
	(segment
		(start 278.849836 -147.277582)
		(end 278.849836 -147.27174)
		(width 0.4064)
		(layer "F.Cu")
		(net "GND")
	)
	(segment
		(start 278.849836 -142.6718)
		(end 278.849836 -142.677642)
		(width 0.508)
		(layer "F.Cu")
		(net "GND")
	)
	(segment
		(start 416.473386 -9.668256)
		(end 416.464242 -9.6774)
		(width 0.254)
		(layer "F.Cu")
		(net "GND")
	)
	(segment
		(start 206.59979 -13.427456)
		(end 206.51089 -13.338556)
		(width 0.4064)
		(layer "F.Cu")
		(net "GND")
	)
	(segment
		(start 243.051838 -63.51524)
		(end 242.480338 -63.51524)
		(width 0.254)
		(layer "F.Cu")
		(net "GND")
	)
	(segment
		(start 206.600298 -142.6718)
		(end 206.59979 -142.677642)
		(width 0.4064)
		(layer "F.Cu")
		(net "GND")
	)
	(segment
		(start 390.984994 -124.504958)
		(end 389.984996 -124.504958)
		(width 0.254)
		(layer "F.Cu")
		(net "GND")
	)
	(segment
		(start 49.24933 -7.607046)
		(end 49.24933 -5.822696)
		(width 0.4064)
		(layer "F.Cu")
		(net "GND")
	)
	(segment
		(start 73.758806 -64.010286)
		(end 73.187306 -64.010286)
		(width 0.254)
		(layer "F.Cu")
		(net "GND")
	)
	(segment
		(start 135.949436 -13.541756)
		(end 135.771636 -13.363956)
		(width 0.4064)
		(layer "F.Cu")
		(net "GND")
	)
	(segment
		(start 178.0286 -67.0814)
		(end 178.0286 -67.183)
		(width 0.254)
		(layer "F.Cu")
		(net "GND")
	)
	(segment
		(start -2.5908 -141.7828)
		(end -2.753868 -141.619732)
		(width 0.254)
		(layer "F.Cu")
		(net "GND")
	)
	(segment
		(start 309.449978 -0.821182)
		(end 309.449978 0.444754)
		(width 0.4064)
		(layer "F.Cu")
		(net "GND")
	)
	(segment
		(start 265.372596 -60.54344)
		(end 264.801096 -60.54344)
		(width 0.254)
		(layer "F.Cu")
		(net "GND")
	)
	(segment
		(start 397.485108 -124.689108)
		(end 397.300958 -124.504958)
		(width 0.254)
		(layer "F.Cu")
		(net "GND")
	)
	(segment
		(start 460.2226 -29.845)
		(end 459.3844 -29.845)
		(width 0.381)
		(layer "F.Cu")
		(net "GND")
	)
	(segment
		(start 141.049502 -18.757646)
		(end 141.049502 -20.023582)
		(width 0.4064)
		(layer "F.Cu")
		(net "GND")
	)
	(segment
		(start 76.449428 -0.821182)
		(end 76.449428 -2.314956)
		(width 0.4064)
		(layer "F.Cu")
		(net "GND")
	)
	(segment
		(start 47.549562 -152.273)
		(end 47.549562 -152.457912)
		(width 0.4064)
		(layer "F.Cu")
		(net "GND")
	)
	(segment
		(start 301.812706 -63.334138)
		(end 301.241206 -63.334138)
		(width 0.254)
		(layer "F.Cu")
		(net "GND")
	)
	(segment
		(start 304.675286 -59.371484)
		(end 305.246786 -59.371484)
		(width 0.254)
		(layer "F.Cu")
		(net "GND")
	)
	(segment
		(start 240.476278 -62.029086)
		(end 239.904778 -62.029086)
		(width 0.254)
		(layer "F.Cu")
		(net "GND")
	)
	(segment
		(start 237.042198 -56.085486)
		(end 236.470698 -56.085486)
		(width 0.254)
		(layer "F.Cu")
		(net "GND")
	)
	(segment
		(start 116.495322 -92.556584)
		(end 117.066822 -92.556584)
		(width 0.254)
		(layer "F.Cu")
		(net "GND")
	)
	(segment
		(start 379.985016 -124.504958)
		(end 379.876558 -124.3965)
		(width 0.254)
		(layer "F.Cu")
		(net "GND")
	)
	(segment
		(start 294.3733 -96.023938)
		(end 294.9448 -96.023938)
		(width 0.254)
		(layer "F.Cu")
		(net "GND")
	)
	(segment
		(start 33.754568 -153.1874)
		(end 33.754568 -154.084782)
		(width 0.3556)
		(layer "F.Cu")
		(net "GND")
	)
	(segment
		(start 312.849768 3.778758)
		(end 312.850276 3.778758)
		(width 0.4064)
		(layer "F.Cu")
		(net "GND")
	)
	(segment
		(start 456.541124 -45.92574)
		(end 456.541124 -47.481998)
		(width 0.4064)
		(layer "F.Cu")
		(net "GND")
	)
	(segment
		(start 151.24938 -133.0706)
		(end 151.24938 -134.861046)
		(width 0.4064)
		(layer "F.Cu")
		(net "GND")
	)
	(segment
		(start 222.749872 -10.422382)
		(end 222.749872 -11.916156)
		(width 0.4064)
		(layer "F.Cu")
		(net "GND")
	)
	(segment
		(start 443.322456 -37.0332)
		(end 442.923168 -37.432488)
		(width 0.3048)
		(layer "F.Cu")
		(net "GND")
	)
	(segment
		(start 349.914972 -115.55095)
		(end 350.5454 -114.935)
		(width 0.254)
		(layer "F.Cu")
		(net "GND")
	)
	(segment
		(start 124.221748 -100.976684)
		(end 124.793248 -100.976684)
		(width 0.3048)
		(layer "F.Cu")
		(net "GND")
	)
	(segment
		(start 71.117968 -154.048206)
		(end 71.171562 -154.1018)
		(width 0.3556)
		(layer "F.Cu")
		(net "GND")
	)
	(segment
		(start 195.550282 3.778758)
		(end 195.549774 3.778758)
		(width 0.4064)
		(layer "F.Cu")
		(net "GND")
	)
	(segment
		(start 415.749994 -48.717962)
		(end 415.72815 -48.717962)
		(width 0.254)
		(layer "F.Cu")
		(net "GND")
	)
	(segment
		(start 46.699424 -21.517356)
		(end 46.699424 -20.023582)
		(width 0.4064)
		(layer "F.Cu")
		(net "GND")
	)
	(segment
		(start 294.999918 -11.916156)
		(end 293.6748 -11.938)
		(width 0.254)
		(layer "F.Cu")
		(net "GND")
	)
	(segment
		(start 115.549426 2.092198)
		(end 115.451382 1.994154)
		(width 0.4064)
		(layer "F.Cu")
		(net "GND")
	)
	(segment
		(start 464.4898 -50.572924)
		(end 464.542124 -50.625248)
		(width 0.508)
		(layer "F.Cu")
		(net "GND")
	)
	(segment
		(start 242.300506 -142.6718)
		(end 242.300506 -144.461484)
		(width 0.508)
		(layer "F.Cu")
		(net "GND")
	)
	(segment
		(start 436.522114 -35.032442)
		(end 436.121556 -35.433)
		(width 0.3048)
		(layer "F.Cu")
		(net "GND")
	)
	(segment
		(start 281.495754 -66.800984)
		(end 280.924254 -66.800984)
		(width 0.254)
		(layer "F.Cu")
		(net "GND")
	)
	(segment
		(start 237.199932 0.38735)
		(end 237.142528 0.444754)
		(width 0.3556)
		(layer "F.Cu")
		(net "GND")
	)
	(segment
		(start 212.54974 -17.208246)
		(end 212.54974 -15.602966)
		(width 0.4064)
		(layer "F.Cu")
		(net "GND")
	)
	(segment
		(start 218.500452 -20.023582)
		(end 218.499944 -20.023582)
		(width 0.3556)
		(layer "F.Cu")
		(net "GND")
	)
	(segment
		(start 243.910104 -91.747086)
		(end 243.338604 -91.747086)
		(width 0.254)
		(layer "F.Cu")
		(net "GND")
	)
	(segment
		(start 195.549774 -152.278842)
		(end 195.549774 -153.598626)
		(width 0.4064)
		(layer "F.Cu")
		(net "GND")
	)
	(segment
		(start 89.211912 -88.775286)
		(end 88.640412 -88.775286)
		(width 0.254)
		(layer "F.Cu")
		(net "GND")
	)
	(segment
		(start 396.65275 -110.71352)
		(end 396.15745 -110.943644)
		(width 0.254)
		(layer "F.Cu")
		(net "GND")
	)
	(segment
		(start 198.100442 -137.67054)
		(end 198.099934 -137.67054)
		(width 0.4064)
		(layer "F.Cu")
		(net "GND")
	)
	(segment
		(start 387.876796 -124.206)
		(end 387.985 -124.504958)
		(width 0.254)
		(layer "F.Cu")
		(net "GND")
	)
	(segment
		(start 291.79774 -88.594184)
		(end 292.36924 -88.594184)
		(width 0.3048)
		(layer "F.Cu")
		(net "GND")
	)
	(segment
		(start 437.275986 -4.386072)
		(end 437.275986 -3.429)
		(width 0.254)
		(layer "F.Cu")
		(net "GND")
	)
	(segment
		(start 28.147518 -71.515478)
		(end 28.147518 -72.03313)
		(width 0.254)
		(layer "F.Cu")
		(net "GND")
	)
	(segment
		(start 306.105306 -69.772784)
		(end 305.533806 -69.772784)
		(width 0.254)
		(layer "F.Cu")
		(net "GND")
	)
	(segment
		(start 414.528 -16.383)
		(end 414.528 -17.75714)
		(width 0.254)
		(layer "F.Cu")
		(net "GND")
	)
	(segment
		(start 36.499546 3.778758)
		(end 36.499292 3.778504)
		(width 0.4064)
		(layer "F.Cu")
		(net "GND")
	)
	(segment
		(start 246.485664 -52.618386)
		(end 246.479568 -52.61229)
		(width 0.2032)
		(layer "F.Cu")
		(net "GND")
	)
	(segment
		(start 5.334 -126.111)
		(end 4.879848 -126.565152)
		(width 0.2032)
		(layer "F.Cu")
		(net "GND")
	)
	(segment
		(start 296.948606 -80.669384)
		(end 297.520106 -80.669384)
		(width 0.254)
		(layer "F.Cu")
		(net "GND")
	)
	(segment
		(start 120.216168 -62.343538)
		(end 120.787668 -62.343538)
		(width 0.254)
		(layer "F.Cu")
		(net "GND")
	)
	(segment
		(start 118.099332 -155.67025)
		(end 118.041928 -155.612846)
		(width 0.3556)
		(layer "F.Cu")
		(net "GND")
	)
	(segment
		(start 462.140046 -51.875944)
		(end 462.141062 -51.875944)
		(width 0.4064)
		(layer "F.Cu")
		(net "GND")
	)
	(segment
		(start 247.347232 -52.120292)
		(end 247.347232 -51.132232)
		(width 0.2032)
		(layer "F.Cu")
		(net "GND")
	)
	(segment
		(start 208.30032 -15.423642)
		(end 208.299812 -15.423642)
		(width 0.3556)
		(layer "F.Cu")
		(net "GND")
	)
	(segment
		(start 129.999486 -0.821182)
		(end 129.999486 -2.314956)
		(width 0.4064)
		(layer "F.Cu")
		(net "GND")
	)
	(segment
		(start 471.000836 -113.892076)
		(end 471.000836 -112.205516)
		(width 0.4064)
		(layer "F.Cu")
		(net "GND")
	)
	(segment
		(start 275.486114 -62.343538)
		(end 274.914614 -62.343538)
		(width 0.254)
		(layer "F.Cu")
		(net "GND")
	)
	(segment
		(start 240.476278 -93.72854)
		(end 239.904778 -93.72854)
		(width 0.254)
		(layer "F.Cu")
		(net "GND")
	)
	(segment
		(start 236.350302 -142.6718)
		(end 236.349794 -142.677642)
		(width 0.3556)
		(layer "F.Cu")
		(net "GND")
	)
	(segment
		(start 221.899988 3.778758)
		(end 221.899988 3.599688)
		(width 0.4064)
		(layer "F.Cu")
		(net "GND")
	)
	(segment
		(start 384.1242 -115.443)
		(end 384.1496 -115.443)
		(width 0.1143)
		(layer "F.Cu")
		(net "GND")
	)
	(segment
		(start 238.759238 -68.963286)
		(end 238.187738 -68.963286)
		(width 0.254)
		(layer "F.Cu")
		(net "GND")
	)
	(segment
		(start 105.9561 -3.3528)
		(end 107.027472 -3.3528)
		(width 0.508)
		(layer "F.Cu")
		(net "GND")
	)
	(segment
		(start 115.549426 -17.110202)
		(end 115.549426 -15.423642)
		(width 0.4064)
		(layer "F.Cu")
		(net "GND")
	)
	(segment
		(start 388.543546 -54.84368)
		(end 387.44652 -54.84368)
		(width 0.254)
		(layer "F.Cu")
		(net "GND")
	)
	(segment
		(start 497.396008 -43.619928)
		(end 496.704874 -43.619928)
		(width 0.254)
		(layer "F.Cu")
		(net "GND")
	)
	(segment
		(start 56.899302 -13.363956)
		(end 56.899556 -13.36421)
		(width 0.4064)
		(layer "F.Cu")
		(net "GND")
	)
	(segment
		(start 278.850344 -5.822442)
		(end 278.849836 -5.822442)
		(width 0.4064)
		(layer "F.Cu")
		(net "GND")
	)
	(segment
		(start 61.149484 -137.67054)
		(end 61.149484 -136.410446)
		(width 0.4064)
		(layer "F.Cu")
		(net "GND")
	)
	(segment
		(start 111.344202 -58.876438)
		(end 110.772702 -58.876438)
		(width 0.254)
		(layer "F.Cu")
		(net "GND")
	)
	(segment
		(start 394.17625 -106.92257)
		(end 394.124688 -106.974132)
		(width 0.254)
		(layer "F.Cu")
		(net "GND")
	)
	(segment
		(start 223.600518 -5.822442)
		(end 223.60001 -5.822442)
		(width 0.4064)
		(layer "F.Cu")
		(net "GND")
	)
	(segment
		(start 244.768624 -97.19564)
		(end 244.197124 -97.19564)
		(width 0.254)
		(layer "F.Cu")
		(net "GND")
	)
	(segment
		(start 226.149916 -20.023582)
		(end 226.149916 -21.479256)
		(width 0.4064)
		(layer "F.Cu")
		(net "GND")
	)
	(segment
		(start 264.51433 -95.709486)
		(end 263.94283 -95.709486)
		(width 0.254)
		(layer "F.Cu")
		(net "GND")
	)
	(segment
		(start 179.07 -77.089)
		(end 178.054 -77.089)
		(width 0.254)
		(layer "F.Cu")
		(net "GND")
	)
	(segment
		(start 66.249296 -142.856966)
		(end 66.249296 -144.462246)
		(width 0.4064)
		(layer "F.Cu")
		(net "GND")
	)
	(segment
		(start 238.8997 -152.279096)
		(end 238.8997 -153.093674)
		(width 0.4064)
		(layer "F.Cu")
		(net "GND")
	)
	(segment
		(start 242.193318 -69.953886)
		(end 241.621818 -69.953886)
		(width 0.254)
		(layer "F.Cu")
		(net "GND")
	)
	(segment
		(start 214.250524 -133.0706)
		(end 214.250016 -133.076442)
		(width 0.4064)
		(layer "F.Cu")
		(net "GND")
	)
	(segment
		(start 156.6926 -12.954)
		(end 157.466792 -12.954)
		(width 0.4064)
		(layer "F.Cu")
		(net "GND")
	)
	(segment
		(start 286.500316 -15.423642)
		(end 286.499808 -15.423642)
		(width 0.4064)
		(layer "F.Cu")
		(net "GND")
	)
	(segment
		(start 137.957814 -93.052138)
		(end 138.529314 -93.052138)
		(width 0.254)
		(layer "F.Cu")
		(net "GND")
	)
	(segment
		(start 278.061674 -56.894984)
		(end 277.490174 -56.894984)
		(width 0.254)
		(layer "F.Cu")
		(net "GND")
	)
	(segment
		(start 107.051856 -59.371484)
		(end 106.480356 -59.371484)
		(width 0.254)
		(layer "F.Cu")
		(net "GND")
	)
	(segment
		(start 206.600298 3.778758)
		(end 206.59979 3.778758)
		(width 0.4064)
		(layer "F.Cu")
		(net "GND")
	)
	(segment
		(start 436.921656 -30.632908)
		(end 436.921656 -30.6324)
		(width 0.3048)
		(layer "F.Cu")
		(net "GND")
	)
	(segment
		(start 75.475846 -97.690686)
		(end 74.904346 -97.690686)
		(width 0.254)
		(layer "F.Cu")
		(net "GND")
	)
	(segment
		(start 220.199712 -16.238474)
		(end 220.199712 -15.423896)
		(width 0.4064)
		(layer "F.Cu")
		(net "GND")
	)
	(segment
		(start 218.500452 -156.87294)
		(end 218.499944 -156.87294)
		(width 0.3556)
		(layer "F.Cu")
		(net "GND")
	)
	(segment
		(start 31.736792 -70.090792)
		(end 31.260796 -70.090792)
		(width 0.254)
		(layer "F.Cu")
		(net "GND")
	)
	(segment
		(start 292.392608 -18.757646)
		(end 292.450012 -18.81505)
		(width 0.3556)
		(layer "F.Cu")
		(net "GND")
	)
	(segment
		(start 53.499512 -20.023582)
		(end 53.499512 -21.455888)
		(width 0.4064)
		(layer "F.Cu")
		(net "GND")
	)
	(segment
		(start 167.4368 -8.001)
		(end 167.3098 -7.874)
		(width 0.254)
		(layer "F.Cu")
		(net "GND")
	)
	(segment
		(start 237.042198 -95.709486)
		(end 236.470698 -95.709486)
		(width 0.254)
		(layer "F.Cu")
		(net "GND")
	)
	(segment
		(start 52.448968 -153.2128)
		(end 52.448968 -153.3906)
		(width 0.3048)
		(layer "F.Cu")
		(net "GND")
	)
	(segment
		(start 61.796168 2.844546)
		(end 61.796168 1.9812)
		(width 0.3556)
		(layer "F.Cu")
		(net "GND")
	)
	(segment
		(start 17.399 -99.20986)
		(end 17.399 -98.7044)
		(width 0.4064)
		(layer "F.Cu")
		(net "GND")
	)
	(segment
		(start 122.504708 -99.986338)
		(end 123.076208 -99.986338)
		(width 0.254)
		(layer "F.Cu")
		(net "GND")
	)
	(segment
		(start 451.000876 -112.205516)
		(end 451.000876 -113.816384)
		(width 0.4064)
		(layer "F.Cu")
		(net "GND")
	)
	(segment
		(start 138.816334 -53.923184)
		(end 139.387834 -53.923184)
		(width 0.254)
		(layer "F.Cu")
		(net "GND")
	)
	(segment
		(start 45.387514 -13.948156)
		(end 45.84954 -14.410182)
		(width 0.4064)
		(layer "F.Cu")
		(net "GND")
	)
	(segment
		(start 64.549274 -16.238474)
		(end 64.090804 -16.696944)
		(width 0.4064)
		(layer "F.Cu")
		(net "GND")
	)
	(segment
		(start 287.50514 -60.362338)
		(end 286.93364 -60.362338)
		(width 0.254)
		(layer "F.Cu")
		(net "GND")
	)
	(segment
		(start 14.748002 -1.41605)
		(end 15.767304 -1.41605)
		(width 0.254)
		(layer "F.Cu")
		(net "GND")
	)
	(segment
		(start 299.249846 3.778758)
		(end 299.249846 2.092198)
		(width 0.4064)
		(layer "F.Cu")
		(net "GND")
	)
	(segment
		(start 123.199398 3.778758)
		(end 123.199398 1.994154)
		(width 0.4064)
		(layer "F.Cu")
		(net "GND")
	)
	(segment
		(start 301.742602 -146.011646)
		(end 301.742602 -145.998946)
		(width 0.3556)
		(layer "F.Cu")
		(net "GND")
	)
	(segment
		(start 265.372596 -89.27084)
		(end 264.801096 -89.27084)
		(width 0.254)
		(layer "F.Cu")
		(net "GND")
	)
	(segment
		(start 196.469 -12.923012)
		(end 196.469 -11.985244)
		(width 0.381)
		(layer "F.Cu")
		(net "GND")
	)
	(segment
		(start 84.919312 -98.18624)
		(end 85.206332 -97.690686)
		(width 0.254)
		(layer "F.Cu")
		(net "GND")
	)
	(segment
		(start 399.209768 -123.414536)
		(end 398.795748 -123.707906)
		(width 0.254)
		(layer "F.Cu")
		(net "GND")
	)
	(segment
		(start 303.529746 -59.371484)
		(end 302.958246 -59.371484)
		(width 0.254)
		(layer "F.Cu")
		(net "GND")
	)
	(segment
		(start 77.264768 -26.0858)
		(end 77.264768 -26.67)
		(width 0.4064)
		(layer "F.Cu")
		(net "GND")
	)
	(segment
		(start 389.89 -125.430026)
		(end 389.89 -126.070106)
		(width 0.254)
		(layer "F.Cu")
		(net "GND")
	)
	(segment
		(start 221.899988 -13.36421)
		(end 221.899734 -13.363956)
		(width 0.4064)
		(layer "F.Cu")
		(net "GND")
	)
	(segment
		(start 52.448968 -16.3576)
		(end 52.649374 -16.157194)
		(width 0.3048)
		(layer "F.Cu")
		(net "GND")
	)
	(segment
		(start 33.949386 -133.0706)
		(end 33.949386 -133.790182)
		(width 0.3556)
		(layer "F.Cu")
		(net "GND")
	)
	(segment
		(start 94.362778 -87.784686)
		(end 93.791278 -87.784686)
		(width 0.254)
		(layer "F.Cu")
		(net "GND")
	)
	(segment
		(start 312.650124 -27.72537)
		(end 312.650124 -27.185112)
		(width 0.254)
		(layer "F.Cu")
		(net "GND")
	)
	(segment
		(start 119.929402 -72.744584)
		(end 119.357902 -72.744584)
		(width 0.254)
		(layer "F.Cu")
		(net "GND")
	)
	(segment
		(start 211.699856 -2.314956)
		(end 211.699856 -0.821182)
		(width 0.4064)
		(layer "F.Cu")
		(net "GND")
	)
	(segment
		(start 289.22218 -53.427884)
		(end 288.65068 -53.427884)
		(width 0.254)
		(layer "F.Cu")
		(net "GND")
	)
	(segment
		(start 235.500418 -0.821182)
		(end 235.49991 -0.821182)
		(width 0.4064)
		(layer "F.Cu")
		(net "GND")
	)
	(segment
		(start 472.938094 -141.608048)
		(end 472.57081 -141.608048)
		(width 0.254)
		(layer "F.Cu")
		(net "GND")
	)
	(segment
		(start 119.7991 2.963926)
		(end 119.34063 2.505456)
		(width 0.4064)
		(layer "F.Cu")
		(net "GND")
	)
	(segment
		(start 382.797304 -35.270948)
		(end 380.982982 -35.270948)
		(width 0.2032)
		(layer "F.Cu")
		(net "GND")
	)
	(segment
		(start 77.299566 -142.6718)
		(end 77.299566 -142.677642)
		(width 0.4064)
		(layer "F.Cu")
		(net "GND")
	)
	(segment
		(start 137.957814 -56.399938)
		(end 138.529314 -56.399938)
		(width 0.254)
		(layer "F.Cu")
		(net "GND")
	)
	(segment
		(start 381.29845 -118.4402)
		(end 381.790448 -118.6688)
		(width 0.254)
		(layer "F.Cu")
		(net "GND")
	)
	(segment
		(start 383.3368 -115.4557)
		(end 383.4765 -115.5954)
		(width 0.12446)
		(layer "F.Cu")
		(net "GND")
	)
	(segment
		(start 238.8997 -15.423896)
		(end 238.899954 -15.423642)
		(width 0.4064)
		(layer "F.Cu")
		(net "GND")
	)
	(segment
		(start 156.944568 -130.3528)
		(end 157.325568 -130.7338)
		(width 0.4064)
		(layer "F.Cu")
		(net "GND")
	)
	(segment
		(start 398.13865 -116.72316)
		(end 398.13865 -116.094764)
		(width 0.254)
		(layer "F.Cu")
		(net "GND")
	)
	(segment
		(start 214.250524 -17.207484)
		(end 214.249762 -17.208246)
		(width 0.4064)
		(layer "F.Cu")
		(net "GND")
	)
	(segment
		(start 217.649806 -152.278842)
		(end 217.649806 -153.012394)
		(width 0.3048)
		(layer "F.Cu")
		(net "GND")
	)
	(segment
		(start 152.099518 -137.67054)
		(end 152.099518 -136.410446)
		(width 0.4064)
		(layer "F.Cu")
		(net "GND")
	)
	(segment
		(start 237.142528 -9.156446)
		(end 237.199932 -9.21385)
		(width 0.3556)
		(layer "F.Cu")
		(net "GND")
	)
	(segment
		(start 226.9998 -5.822442)
		(end 226.9998 -6.553454)
		(width 0.3556)
		(layer "F.Cu")
		(net "GND")
	)
	(segment
		(start 301.742602 -155.612846)
		(end 301.742602 -155.600146)
		(width 0.3556)
		(layer "F.Cu")
		(net "GND")
	)
	(segment
		(start 69.64934 -17.110202)
		(end 69.551296 -17.208246)
		(width 0.4064)
		(layer "F.Cu")
		(net "GND")
	)
	(segment
		(start 113.061242 -100.481638)
		(end 112.774222 -99.986338)
		(width 0.254)
		(layer "F.Cu")
		(net "GND")
	)
	(segment
		(start 278.849836 -15.423642)
		(end 278.850344 -15.423642)
		(width 0.4064)
		(layer "F.Cu")
		(net "GND")
	)
	(segment
		(start 241.334798 -76.39304)
		(end 240.763298 -76.39304)
		(width 0.254)
		(layer "F.Cu")
		(net "GND")
	)
	(segment
		(start 131.089908 -81.164938)
		(end 131.661408 -81.164938)
		(width 0.254)
		(layer "F.Cu")
		(net "GND")
	)
	(segment
		(start 46.699424 -137.67054)
		(end 46.699424 -136.410446)
		(width 0.4064)
		(layer "F.Cu")
		(net "GND")
	)
	(segment
		(start 212.54974 -15.602966)
		(end 212.549994 -15.602712)
		(width 0.4064)
		(layer "F.Cu")
		(net "GND")
	)
	(segment
		(start 78.051406 -58.561986)
		(end 77.479906 -58.561986)
		(width 0.254)
		(layer "F.Cu")
		(net "GND")
	)
	(segment
		(start 196.399912 -0.821182)
		(end 196.399912 -2.314956)
		(width 0.4064)
		(layer "F.Cu")
		(net "GND")
	)
	(segment
		(start 53.499512 -0.821182)
		(end 53.499512 0.38735)
		(width 0.3556)
		(layer "F.Cu")
		(net "GND")
	)
	(segment
		(start 466.141054 -46.469554)
		(end 466.141054 -47.481998)
		(width 0.4064)
		(layer "F.Cu")
		(net "GND")
	)
	(segment
		(start 117.353842 -89.089738)
		(end 117.925342 -89.089738)
		(width 0.254)
		(layer "F.Cu")
		(net "GND")
	)
	(segment
		(start 64.549528 -133.0706)
		(end 64.549528 -133.076442)
		(width 0.4064)
		(layer "F.Cu")
		(net "GND")
	)
	(segment
		(start 42.449496 -139.132056)
		(end 42.449496 -137.67054)
		(width 0.4064)
		(layer "F.Cu")
		(net "GND")
	)
	(segment
		(start 254.212344 -98.681286)
		(end 254.49911 -98.18624)
		(width 0.254)
		(layer "F.Cu")
		(net "GND")
	)
	(segment
		(start 75.59929 -13.363956)
		(end 75.599544 -13.36421)
		(width 0.4064)
		(layer "F.Cu")
		(net "GND")
	)
	(segment
		(start 395.16685 -120.15724)
		(end 395.224 -120.18391)
		(width 0.254)
		(layer "F.Cu")
		(net "GND")
	)
	(segment
		(start 248.202704 -63.51524)
		(end 247.631204 -63.51524)
		(width 0.254)
		(layer "F.Cu")
		(net "GND")
	)
	(segment
		(start 157.466792 -12.954)
		(end 157.49778 -12.923012)
		(width 0.4064)
		(layer "F.Cu")
		(net "GND")
	)
	(segment
		(start 284.799532 -143.492474)
		(end 284.341062 -143.950944)
		(width 0.4064)
		(layer "F.Cu")
		(net "GND")
	)
	(segment
		(start 230.400352 -20.023582)
		(end 230.399844 -20.023582)
		(width 0.4064)
		(layer "F.Cu")
		(net "GND")
	)
	(segment
		(start 348.18828 -11.14933)
		(end 346.995242 -11.14933)
		(width 0.254)
		(layer "F.Cu")
		(net "GND")
	)
	(segment
		(start 446.024 -53.34)
		(end 446.024 -52.959)
		(width 0.4064)
		(layer "F.Cu")
		(net "GND")
	)
	(segment
		(start 82.343752 -65.991486)
		(end 81.772252 -65.991486)
		(width 0.254)
		(layer "F.Cu")
		(net "GND")
	)
	(segment
		(start 386.25145 -115.71224)
		(end 385.977638 -115.438428)
		(width 0.1143)
		(layer "F.Cu")
		(net "GND")
	)
	(segment
		(start 217.649806 -153.012394)
		(end 217.4494 -153.2128)
		(width 0.3048)
		(layer "F.Cu")
		(net "GND")
	)
	(segment
		(start 192.099438 -80.363568)
		(end 192.052956 -80.317086)
		(width 0.254)
		(layer "F.Cu")
		(net "GND")
	)
	(segment
		(start 210.849718 -142.677896)
		(end 210.849718 -143.492474)
		(width 0.4064)
		(layer "F.Cu")
		(net "GND")
	)
	(segment
		(start 300.949868 -133.076442)
		(end 300.949868 -133.821678)
		(width 0.3556)
		(layer "F.Cu")
		(net "GND")
	)
	(segment
		(start 460.082392 -37.067998)
		(end 460.082392 -36.435792)
		(width 0.254)
		(layer "F.Cu")
		(net "GND")
	)
	(segment
		(start 81.485232 -61.53404)
		(end 80.913732 -61.53404)
		(width 0.254)
		(layer "F.Cu")
		(net "GND")
	)
	(segment
		(start 280.550366 -5.822442)
		(end 280.549858 -5.822442)
		(width 0.4064)
		(layer "F.Cu")
		(net "GND")
	)
	(segment
		(start 351.6122 -11.1506)
		(end 351.235518 -11.1506)
		(width 0.254)
		(layer "F.Cu")
		(net "GND")
	)
	(segment
		(start 42.449496 -0.821182)
		(end 42.449496 -2.276856)
		(width 0.4064)
		(layer "F.Cu")
		(net "GND")
	)
	(segment
		(start 141.391894 -99.986338)
		(end 142.039848 -99.986338)
		(width 0.254)
		(layer "F.Cu")
		(net "GND")
	)
	(segment
		(start 415.890202 -28.934664)
		(end 415.890202 -28.916376)
		(width 0.254)
		(layer "F.Cu")
		(net "GND")
	)
	(segment
		(start 127.44958 -10.422382)
		(end 127.44958 -9.21385)
		(width 0.3556)
		(layer "F.Cu")
		(net "GND")
	)
	(segment
		(start 141.391894 -69.277738)
		(end 141.963394 -69.277738)
		(width 0.254)
		(layer "F.Cu")
		(net "GND")
	)
	(segment
		(start 278.070056 -69.969888)
		(end 278.899112 -69.969888)
		(width 0.254)
		(layer "F.Cu")
		(net "GND")
	)
	(segment
		(start 121.646188 -51.941984)
		(end 121.892568 -52.367434)
		(width 0.254)
		(layer "F.Cu")
		(net "GND")
	)
	(segment
		(start 300.736 -6.781546)
		(end 300.736 -7.609332)
		(width 0.3556)
		(layer "F.Cu")
		(net "GND")
	)
	(segment
		(start 349.421704 -1.93802)
		(end 349.140526 -2.219198)
		(width 0.508)
		(layer "F.Cu")
		(net "GND")
	)
	(segment
		(start 77.299566 -5.822442)
		(end 77.299312 -5.822696)
		(width 0.4064)
		(layer "F.Cu")
		(net "GND")
	)
	(segment
		(start 38.199568 -13.36421)
		(end 38.199568 -15.423642)
		(width 0.4064)
		(layer "F.Cu")
		(net "GND")
	)
	(segment
		(start 134.249414 -142.6718)
		(end 134.249414 -144.364202)
		(width 0.4064)
		(layer "F.Cu")
		(net "GND")
	)
	(segment
		(start 202.35037 -156.87294)
		(end 202.349862 -156.87294)
		(width 0.4064)
		(layer "F.Cu")
		(net "GND")
	)
	(segment
		(start 75.59929 -142.856966)
		(end 75.59929 -144.462246)
		(width 0.4064)
		(layer "F.Cu")
		(net "GND")
	)
	(segment
		(start 43.076368 -154.056588)
		(end 43.12158 -154.1018)
		(width 0.3556)
		(layer "F.Cu")
		(net "GND")
	)
	(segment
		(start 137.957814 -53.427884)
		(end 138.529314 -53.427884)
		(width 0.254)
		(layer "F.Cu")
		(net "GND")
	)
	(segment
		(start 303.3395 -102.708456)
		(end 303.62017 -102.989126)
		(width 0.254)
		(layer "F.Cu")
		(net "GND")
	)
	(segment
		(start 84.919312 -76.39304)
		(end 84.347812 -76.39304)
		(width 0.254)
		(layer "F.Cu")
		(net "GND")
	)
	(segment
		(start 130.231388 -56.894984)
		(end 130.802888 -56.894984)
		(width 0.254)
		(layer "F.Cu")
		(net "GND")
	)
	(segment
		(start 443.484 -145.796)
		(end 443.2935 -145.9865)
		(width 0.254)
		(layer "F.Cu")
		(net "GND")
	)
	(segment
		(start 56.899556 -3.76301)
		(end 56.899556 -5.822442)
		(width 0.4064)
		(layer "F.Cu")
		(net "GND")
	)
	(segment
		(start 117.640862 -63.829184)
		(end 118.212362 -63.829184)
		(width 0.254)
		(layer "F.Cu")
		(net "GND")
	)
	(segment
		(start 377.91771 -124.206)
		(end 377.83135 -123.821444)
		(width 0.254)
		(layer "F.Cu")
		(net "GND")
	)
	(segment
		(start 385.33705 -115.05565)
		(end 385.11988 -115.27282)
		(width 0.12446)
		(layer "F.Cu")
		(net "GND")
	)
	(segment
		(start 196.399912 -139.170156)
		(end 196.3674 -139.202668)
		(width 0.4064)
		(layer "F.Cu")
		(net "GND")
	)
	(segment
		(start 367.885218 -4.389882)
		(end 367.885218 -3.437382)
		(width 0.4572)
		(layer "F.Cu")
		(net "GND")
	)
	(segment
		(start 86.064852 -53.608732)
		(end 85.777832 -54.104286)
		(width 0.254)
		(layer "F.Cu")
		(net "GND")
	)
	(segment
		(start 282.250388 -15.423642)
		(end 282.24988 -15.423642)
		(width 0.3556)
		(layer "F.Cu")
		(net "GND")
	)
	(segment
		(start 132.549392 -152.273)
		(end 132.549392 -154.063446)
		(width 0.4064)
		(layer "F.Cu")
		(net "GND")
	)
	(segment
		(start 76.334366 -70.44944)
		(end 75.762866 -70.44944)
		(width 0.254)
		(layer "F.Cu")
		(net "GND")
	)
	(segment
		(start 484.27386 -28.14828)
		(end 484.27386 -28.08224)
		(width 0.254)
		(layer "F.Cu")
		(net "GND")
	)
	(segment
		(start 218.499944 -21.455888)
		(end 218.44254 -21.513292)
		(width 0.4064)
		(layer "F.Cu")
		(net "GND")
	)
	(segment
		(start 8.001 3.2766)
		(end 8.4836 3.2766)
		(width 0.2032)
		(layer "F.Cu")
		(net "GND")
	)
	(segment
		(start 70.324726 -58.06694)
		(end 69.753226 -58.06694)
		(width 0.254)
		(layer "F.Cu")
		(net "GND")
	)
	(segment
		(start 236.1184 -134.0358)
		(end 236.1184 -134.845806)
		(width 0.3556)
		(layer "F.Cu")
		(net "GND")
	)
	(segment
		(start 73.758806 -68.963286)
		(end 73.187306 -68.963286)
		(width 0.254)
		(layer "F.Cu")
		(net "GND")
	)
	(segment
		(start 444.476886 -5.375402)
		(end 444.476886 -4.386072)
		(width 0.254)
		(layer "F.Cu")
		(net "GND")
	)
	(segment
		(start 237.900718 -57.57164)
		(end 237.329218 -57.57164)
		(width 0.254)
		(layer "F.Cu")
		(net "GND")
	)
	(segment
		(start 374.674892 -108.855002)
		(end 374.1166 -108.855002)
		(width 0.254)
		(layer "F.Cu")
		(net "GND")
	)
	(segment
		(start 50.949352 -5.822442)
		(end 50.949352 -7.509002)
		(width 0.4064)
		(layer "F.Cu")
		(net "GND")
	)
	(segment
		(start 68.607686 -61.038486)
		(end 68.036186 -61.038486)
		(width 0.254)
		(layer "F.Cu")
		(net "GND")
	)
	(segment
		(start 225.300286 -5.822442)
		(end 225.299778 -5.822442)
		(width 0.4064)
		(layer "F.Cu")
		(net "GND")
	)
	(segment
		(start 346.580206 -9.528302)
		(end 346.926154 -9.182354)
		(width 0.254)
		(layer "F.Cu")
		(net "GND")
	)
	(segment
		(start 204.899768 -3.762756)
		(end 204.899768 -5.822442)
		(width 0.4064)
		(layer "F.Cu")
		(net "GND")
	)
	(segment
		(start 204.900276 -142.6718)
		(end 204.899768 -142.677642)
		(width 0.4064)
		(layer "F.Cu")
		(net "GND")
	)
	(segment
		(start 42.411396 -18.757646)
		(end 42.424096 -18.757646)
		(width 0.4064)
		(layer "F.Cu")
		(net "GND")
	)
	(segment
		(start 376.20067 -94.274894)
		(end 376.295666 -93.544898)
		(width 0.254)
		(layer "F.Cu")
		(net "GND")
	)
	(segment
		(start 396.15745 -105.332276)
		(end 396.65275 -105.5624)
		(width 0.254)
		(layer "F.Cu")
		(net "GND")
	)
	(segment
		(start 147.849336 -142.6718)
		(end 147.849336 -143.492474)
		(width 0.4064)
		(layer "F.Cu")
		(net "GND")
	)
	(segment
		(start 113.061242 -54.913784)
		(end 112.489742 -54.913784)
		(width 0.254)
		(layer "F.Cu")
		(net "GND")
	)
	(segment
		(start 291.600382 -152.273)
		(end 291.599874 -152.278842)
		(width 0.3556)
		(layer "F.Cu")
		(net "GND")
	)
	(segment
		(start 475.45117 -26.463752)
		(end 475.58706 -26.599642)
		(width 0.254)
		(layer "F.Cu")
		(net "GND")
	)
	(segment
		(start 205.750414 -20.023582)
		(end 205.749906 -20.023582)
		(width 0.4064)
		(layer "F.Cu")
		(net "GND")
	)
	(segment
		(start 1.148588 -13.806932)
		(end 1.356106 -13.599414)
		(width 0.4064)
		(layer "F.Cu")
		(net "GND")
	)
	(segment
		(start 303.816766 -67.791584)
		(end 303.529746 -68.078604)
		(width 0.254)
		(layer "F.Cu")
		(net "GND")
	)
	(segment
		(start 124.89942 -7.509002)
		(end 124.801376 -7.607046)
		(width 0.4064)
		(layer "F.Cu")
		(net "GND")
	)
	(segment
		(start 229.549706 -133.891274)
		(end 229.091236 -134.349744)
		(width 0.4064)
		(layer "F.Cu")
		(net "GND")
	)
	(segment
		(start 272.910808 -54.913784)
		(end 272.339308 -54.913784)
		(width 0.254)
		(layer "F.Cu")
		(net "GND")
	)
	(segment
		(start 403.571456 -100.49002)
		(end 401.98548 -100.49002)
		(width 0.1524)
		(layer "F.Cu")
		(net "GND")
	)
	(segment
		(start 455.741024 -50.523648)
		(end 455.730864 -50.513488)
		(width 0.508)
		(layer "F.Cu")
		(net "GND")
	)
	(segment
		(start 0 -134.665212)
		(end 0.26416 -134.929372)
		(width 0.4064)
		(layer "F.Cu")
		(net "GND")
	)
	(segment
		(start 131.089908 -94.042738)
		(end 131.661408 -94.042738)
		(width 0.254)
		(layer "F.Cu")
		(net "GND")
	)
	(segment
		(start 129.372868 -72.249538)
		(end 129.944368 -72.249538)
		(width 0.254)
		(layer "F.Cu")
		(net "GND")
	)
	(segment
		(start 114.699542 -136.397746)
		(end 114.699542 -137.67054)
		(width 0.4064)
		(layer "F.Cu")
		(net "GND")
	)
	(segment
		(start 137.957814 -98.005138)
		(end 138.529314 -98.005138)
		(width 0.254)
		(layer "F.Cu")
		(net "GND")
	)
	(segment
		(start 145.12163 -13.363956)
		(end 145.29943 -13.541756)
		(width 0.4064)
		(layer "F.Cu")
		(net "GND")
	)
	(segment
		(start 80.626712 -81.841086)
		(end 80.055212 -81.841086)
		(width 0.254)
		(layer "F.Cu")
		(net "GND")
	)
	(segment
		(start 384.76555 -101.039676)
		(end 385.449064 -100.656898)
		(width 0.254)
		(layer "F.Cu")
		(net "GND")
	)
	(segment
		(start 307.749956 -147.27174)
		(end 307.749956 -145.998946)
		(width 0.4064)
		(layer "F.Cu")
		(net "GND")
	)
	(segment
		(start 268.806676 -89.27084)
		(end 269.416276 -89.27084)
		(width 0.254)
		(layer "F.Cu")
		(net "GND")
	)
	(segment
		(start 14.36116 5.158232)
		(end 14.972792 5.158232)
		(width 0.381)
		(layer "F.Cu")
		(net "GND")
	)
	(segment
		(start 116.495322 -94.538038)
		(end 117.066822 -94.538038)
		(width 0.1651)
		(layer "F.Cu")
		(net "GND")
	)
	(segment
		(start 113.061242 -88.594184)
		(end 113.061242 -88.022684)
		(width 0.381)
		(layer "F.Cu")
		(net "GND")
	)
	(segment
		(start 50.099468 -145.998946)
		(end 50.099468 -147.27174)
		(width 0.4064)
		(layer "F.Cu")
		(net "GND")
	)
	(segment
		(start 465.339938 -51.875944)
		(end 465.340954 -51.875944)
		(width 0.4064)
		(layer "F.Cu")
		(net "GND")
	)
	(segment
		(start 128.514348 -55.904384)
		(end 129.085848 -55.904384)
		(width 0.254)
		(layer "F.Cu")
		(net "GND")
	)
	(segment
		(start 373.888 -103.324914)
		(end 373.888 -103.3526)
		(width 0.254)
		(layer "F.Cu")
		(net "GND")
	)
	(segment
		(start 70.461378 -2.314956)
		(end 70.499478 -2.276856)
		(width 0.4064)
		(layer "F.Cu")
		(net "GND")
	)
	(segment
		(start 64.549528 -142.6718)
		(end 64.549528 -142.677642)
		(width 0.4064)
		(layer "F.Cu")
		(net "GND")
	)
	(segment
		(start 296.700448 -10.422382)
		(end 296.69994 -10.422382)
		(width 0.4064)
		(layer "F.Cu")
		(net "GND")
	)
	(segment
		(start 31.400496 -61.095382)
		(end 31.400496 -61.31306)
		(width 0.254)
		(layer "F.Cu")
		(net "GND")
	)
	(segment
		(start 61.111384 -11.916156)
		(end 61.149484 -11.878056)
		(width 0.4064)
		(layer "F.Cu")
		(net "GND")
	)
	(segment
		(start 49.249584 -15.423642)
		(end 49.249584 -13.36421)
		(width 0.4064)
		(layer "F.Cu")
		(net "GND")
	)
	(segment
		(start 295.000426 -156.87294)
		(end 295.000426 -155.613354)
		(width 0.3556)
		(layer "F.Cu")
		(net "GND")
	)
	(segment
		(start 381.29845 -99.55276)
		(end 381.79375 -99.322636)
		(width 0.254)
		(layer "F.Cu")
		(net "GND")
	)
	(segment
		(start 295.849802 -15.423642)
		(end 295.849802 -13.363956)
		(width 0.4064)
		(layer "F.Cu")
		(net "GND")
	)
	(segment
		(start 315.399928 -156.87294)
		(end 315.399928 -155.612846)
		(width 0.4064)
		(layer "F.Cu")
		(net "GND")
	)
	(segment
		(start 236.183678 -99.17684)
		(end 235.612178 -99.17684)
		(width 0.254)
		(layer "F.Cu")
		(net "GND")
	)
	(segment
		(start 480.34702 -34.86658)
		(end 480.15144 -34.671)
		(width 0.254)
		(layer "F.Cu")
		(net "GND")
	)
	(segment
		(start 415.090102 -35.334702)
		(end 415.490152 -34.934652)
		(width 0.254)
		(layer "F.Cu")
		(net "GND")
	)
	(segment
		(start 464.53425 -143.173196)
		(end 464.487514 -143.219932)
		(width 0.254)
		(layer "F.Cu")
		(net "GND")
	)
	(segment
		(start 317.100458 -10.422382)
		(end 317.09995 -10.422382)
		(width 0.4064)
		(layer "F.Cu")
		(net "GND")
	)
	(segment
		(start 131.699508 -2.314956)
		(end 131.699508 -0.821182)
		(width 0.4064)
		(layer "F.Cu")
		(net "GND")
	)
	(segment
		(start 136.240774 -53.427884)
		(end 136.812274 -53.427884)
		(width 0.254)
		(layer "F.Cu")
		(net "GND")
	)
	(segment
		(start 67.099434 -147.27174)
		(end 67.099434 -146.011646)
		(width 0.4064)
		(layer "F.Cu")
		(net "GND")
	)
	(segment
		(start 67.749166 -57.57164)
		(end 67.101466 -57.57164)
		(width 0.254)
		(layer "F.Cu")
		(net "GND")
	)
	(segment
		(start 74.617326 -90.26144)
		(end 74.045826 -90.26144)
		(width 0.254)
		(layer "F.Cu")
		(net "GND")
	)
	(segment
		(start 84.919312 -68.46824)
		(end 84.347812 -68.46824)
		(width 0.254)
		(layer "F.Cu")
		(net "GND")
	)
	(segment
		(start 444.600838 -113.800382)
		(end 444.599822 -113.801398)
		(width 0.4064)
		(layer "F.Cu")
		(net "GND")
	)
	(segment
		(start 375.504964 -111.854996)
		(end 376.335036 -111.854996)
		(width 0.254)
		(layer "F.Cu")
		(net "GND")
	)
	(segment
		(start 399.671286 -7.789672)
		(end 399.671286 -9.44372)
		(width 0.254)
		(layer "F.Cu")
		(net "GND")
	)
	(segment
		(start 47.549562 -6.001512)
		(end 47.549308 -6.001766)
		(width 0.4064)
		(layer "F.Cu")
		(net "GND")
	)
	(segment
		(start 464.058 -22.098)
		(end 464.185 -22.225)
		(width 0.254)
		(layer "F.Cu")
		(net "GND")
	)
	(segment
		(start 378.82195 -101.039676)
		(end 378.32665 -101.2698)
		(width 0.1143)
		(layer "F.Cu")
		(net "GND")
	)
	(segment
		(start 407.1112 -9.4488)
		(end 407.1112 -9.495028)
		(width 0.254)
		(layer "F.Cu")
		(net "GND")
	)
	(segment
		(start 28.601416 -77.216)
		(end 28.702 -77.216)
		(width 0.254)
		(layer "F.Cu")
		(net "GND")
	)
	(segment
		(start 245.627144 -78.869286)
		(end 245.055644 -78.869286)
		(width 0.254)
		(layer "F.Cu")
		(net "GND")
	)
	(segment
		(start 301.800514 -147.27174)
		(end 301.800006 -147.27174)
		(width 0.3556)
		(layer "F.Cu")
		(net "GND")
	)
	(segment
		(start 285.7881 -98.995738)
		(end 286.3596 -98.995738)
		(width 0.254)
		(layer "F.Cu")
		(net "GND")
	)
	(segment
		(start 127.655828 -90.080338)
		(end 128.227328 -90.080338)
		(width 0.254)
		(layer "F.Cu")
		(net "GND")
	)
	(segment
		(start 152.099518 -20.023582)
		(end 152.099518 -21.528278)
		(width 0.4064)
		(layer "F.Cu")
		(net "GND")
	)
	(segment
		(start 299.524166 -68.287138)
		(end 300.095666 -68.287138)
		(width 0.254)
		(layer "F.Cu")
		(net "GND")
	)
	(segment
		(start 390.21385 -102.98684)
		(end 390.70915 -102.756716)
		(width 0.254)
		(layer "F.Cu")
		(net "GND")
	)
	(segment
		(start 241.450368 -0.821182)
		(end 241.44986 -0.821182)
		(width 0.4064)
		(layer "F.Cu")
		(net "GND")
	)
	(segment
		(start 36.499546 -133.076442)
		(end 36.499292 -133.076696)
		(width 0.4064)
		(layer "F.Cu")
		(net "GND")
	)
	(segment
		(start 351.630234 0.76708)
		(end 352.421952 0.76708)
		(width 0.254)
		(layer "F.Cu")
		(net "GND")
	)
	(segment
		(start 303.64557 -103.066342)
		(end 303.67097 -103.066342)
		(width 0.254)
		(layer "F.Cu")
		(net "GND")
	)
	(segment
		(start 213.399878 -11.916156)
		(end 213.399878 -10.422382)
		(width 0.4064)
		(layer "F.Cu")
		(net "GND")
	)
	(segment
		(start 394.081 -107.093766)
		(end 394.124688 -106.974132)
		(width 0.254)
		(layer "F.Cu")
		(net "GND")
	)
	(segment
		(start 124.221748 -74.230738)
		(end 124.793248 -74.23023)
		(width 0.254)
		(layer "F.Cu")
		(net "GND")
	)
	(segment
		(start 80.626712 -56.085486)
		(end 80.055212 -56.085486)
		(width 0.254)
		(layer "F.Cu")
		(net "GND")
	)
	(segment
		(start 67.749166 -83.32724)
		(end 67.101466 -83.32724)
		(width 0.254)
		(layer "F.Cu")
		(net "GND")
	)
	(segment
		(start 240.599976 -142.677642)
		(end 240.599976 -142.856712)
		(width 0.4064)
		(layer "F.Cu")
		(net "GND")
	)
	(segment
		(start 72.142096 -9.156446)
		(end 72.1995 -9.21385)
		(width 0.3556)
		(layer "F.Cu")
		(net "GND")
	)
	(segment
		(start 448.53987 -51.875944)
		(end 448.540886 -51.875944)
		(width 0.4064)
		(layer "F.Cu")
		(net "GND")
	)
	(segment
		(start 286.07512 -56.894984)
		(end 286.64662 -56.894984)
		(width 0.254)
		(layer "F.Cu")
		(net "GND")
	)
	(segment
		(start 71.117968 -153.2382)
		(end 71.117968 -154.048206)
		(width 0.3556)
		(layer "F.Cu")
		(net "GND")
	)
	(segment
		(start 43.076368 -134.854188)
		(end 43.12158 -134.8994)
		(width 0.3556)
		(layer "F.Cu")
		(net "GND")
	)
	(segment
		(start 122.504708 -82.155284)
		(end 123.076208 -82.155284)
		(width 0.254)
		(layer "F.Cu")
		(net "GND")
	)
	(segment
		(start 115.549426 -3.826256)
		(end 115.460526 -3.737356)
		(width 0.4064)
		(layer "F.Cu")
		(net "GND")
	)
	(segment
		(start 255.8034 -3.635756)
		(end 255.8034 -2.975356)
		(width 0.4064)
		(layer "F.Cu")
		(net "GND")
	)
	(segment
		(start 108.768896 -96.023938)
		(end 109.340396 -96.023938)
		(width 0.254)
		(layer "F.Cu")
		(net "GND")
	)
	(segment
		(start 31.400496 -61.31306)
		(end 31.6865 -61.599064)
		(width 0.254)
		(layer "F.Cu")
		(net "GND")
	)
	(segment
		(start 335.773776 -25.2603)
		(end 335.0768 -25.2603)
		(width 0.254)
		(layer "F.Cu")
		(net "GND")
	)
	(segment
		(start 284.929834 -96.518984)
		(end 285.501334 -96.518984)
		(width 0.254)
		(layer "F.Cu")
		(net "GND")
	)
	(segment
		(start 377.69292 -37.61232)
		(end 378.0409 -37.9603)
		(width 0.254)
		(layer "F.Cu")
		(net "GND")
	)
	(segment
		(start 471.54846 -114.4397)
		(end 471.000836 -113.892076)
		(width 0.4064)
		(layer "F.Cu")
		(net "GND")
	)
	(segment
		(start 42.449496 -136.435846)
		(end 42.424096 -136.410446)
		(width 0.4064)
		(layer "F.Cu")
		(net "GND")
	)
	(segment
		(start 292.45052 -137.67054)
		(end 292.450012 -137.67054)
		(width 0.3556)
		(layer "F.Cu")
		(net "GND")
	)
	(segment
		(start 119.929402 -57.885584)
		(end 119.357902 -57.885584)
		(width 0.254)
		(layer "F.Cu")
		(net "GND")
	)
	(segment
		(start 198.061834 -148.771356)
		(end 198.099934 -148.733256)
		(width 0.4064)
		(layer "F.Cu")
		(net "GND")
	)
	(segment
		(start 284.929834 -56.894984)
		(end 284.358334 -56.894984)
		(width 0.254)
		(layer "F.Cu")
		(net "GND")
	)
	(segment
		(start 100.372164 -60.54344)
		(end 99.800664 -60.54344)
		(width 0.254)
		(layer "F.Cu")
		(net "GND")
	)
	(segment
		(start 388.23265 -102.98684)
		(end 387.73735 -102.756716)
		(width 0.254)
		(layer "F.Cu")
		(net "GND")
	)
	(segment
		(start 215.85174 -17.208246)
		(end 215.949784 -17.110202)
		(width 0.4064)
		(layer "F.Cu")
		(net "GND")
	)
	(segment
		(start 193.117216 -60.209938)
		(end 193.750946 -60.843668)
		(width 0.254)
		(layer "F.Cu")
		(net "GND")
	)
	(segment
		(start 0.011684 -6.047486)
		(end 0.271272 -6.307074)
		(width 0.254)
		(layer "F.Cu")
		(net "GND")
	)
	(segment
		(start 393.984988 -124.504958)
		(end 394.285216 -124.206)
		(width 0.254)
		(layer "F.Cu")
		(net "GND")
	)
	(segment
		(start 224.450402 -147.27174)
		(end 224.449894 -147.27174)
		(width 0.4064)
		(layer "F.Cu")
		(net "GND")
	)
	(segment
		(start 27.47899 -31.141162)
		(end 27.1526 -31.467552)
		(width 0.254)
		(layer "F.Cu")
		(net "GND")
	)
	(segment
		(start 239.749838 -10.422382)
		(end 239.749838 -9.156446)
		(width 0.4064)
		(layer "F.Cu")
		(net "GND")
	)
	(segment
		(start 394.984986 -95.205042)
		(end 393.984988 -95.205042)
		(width 0.254)
		(layer "F.Cu")
		(net "GND")
	)
	(segment
		(start 247.4595 -149.8092)
		(end 246.565674 -149.8092)
		(width 0.4064)
		(layer "F.Cu")
		(net "GND")
	)
	(segment
		(start 71.183246 -74.411586)
		(end 70.611746 -74.411586)
		(width 0.254)
		(layer "F.Cu")
		(net "GND")
	)
	(segment
		(start 274.627848 -96.518984)
		(end 275.199348 -96.518984)
		(width 0.254)
		(layer "F.Cu")
		(net "GND")
	)
	(segment
		(start 290.71189 -12.91971)
		(end 289.899852 -13.731748)
		(width 0.4064)
		(layer "F.Cu")
		(net "GND")
	)
	(segment
		(start 242.300506 -13.364718)
		(end 242.300506 -15.423642)
		(width 0.4064)
		(layer "F.Cu")
		(net "GND")
	)
	(segment
		(start 73.899268 3.778504)
		(end 73.899268 2.963926)
		(width 0.4064)
		(layer "F.Cu")
		(net "GND")
	)
	(segment
		(start 353.218242 -146.046444)
		(end 353.218242 -146.488912)
		(width 0.381)
		(layer "F.Cu")
		(net "GND")
	)
	(segment
		(start 123.363228 -95.528384)
		(end 123.934728 -95.528384)
		(width 0.254)
		(layer "F.Cu")
		(net "GND")
	)
	(segment
		(start 76.334366 -78.37424)
		(end 75.762866 -78.37424)
		(width 0.254)
		(layer "F.Cu")
		(net "GND")
	)
	(segment
		(start 252.495304 -70.94474)
		(end 251.923804 -70.94474)
		(width 0.254)
		(layer "F.Cu")
		(net "GND")
	)
	(segment
		(start 415.490152 -34.934652)
		(end 415.090102 -34.534602)
		(width 0.254)
		(layer "F.Cu")
		(net "GND")
	)
	(segment
		(start 84.919312 -79.36484)
		(end 84.347812 -79.36484)
		(width 0.254)
		(layer "F.Cu")
		(net "GND")
	)
	(segment
		(start 201.041254 -16.696944)
		(end 201.499724 -16.238474)
		(width 0.4064)
		(layer "F.Cu")
		(net "GND")
	)
	(segment
		(start 74.617326 -85.30844)
		(end 74.045826 -85.30844)
		(width 0.254)
		(layer "F.Cu")
		(net "GND")
	)
	(segment
		(start 241.44986 -147.27174)
		(end 241.44986 -146.011646)
		(width 0.4064)
		(layer "F.Cu")
		(net "GND")
	)
	(segment
		(start 389.33755 -114.25555)
		(end 389.7376 -114.6556)
		(width 0.12446)
		(layer "F.Cu")
		(net "GND")
	)
	(segment
		(start 2.71272 -73.787)
		(end 2.71272 -73.16978)
		(width 0.254)
		(layer "F.Cu")
		(net "GND")
	)
	(segment
		(start 86.636352 -91.25204)
		(end 86.064852 -91.25204)
		(width 0.254)
		(layer "F.Cu")
		(net "GND")
	)
	(segment
		(start 303.529746 -77.202538)
		(end 302.958246 -77.202538)
		(width 0.254)
		(layer "F.Cu")
		(net "GND")
	)
	(segment
		(start 295.849802 -142.677642)
		(end 295.849802 -144.462246)
		(width 0.4064)
		(layer "F.Cu")
		(net "GND")
	)
	(segment
		(start 285.650432 -10.422382)
		(end 285.649924 -10.422382)
		(width 0.4064)
		(layer "F.Cu")
		(net "GND")
	)
	(segment
		(start 103.678736 -12.954)
		(end 102.7938 -12.954)
		(width 0.381)
		(layer "F.Cu")
		(net "GND")
	)
	(segment
		(start 117.249448 -13.541756)
		(end 117.071648 -13.363956)
		(width 0.4064)
		(layer "F.Cu")
		(net "GND")
	)
	(segment
		(start 296.948606 -62.838584)
		(end 297.520106 -62.838584)
		(width 0.254)
		(layer "F.Cu")
		(net "GND")
	)
	(segment
		(start 418.873686 -7.789672)
		(end 418.873686 -9.693656)
		(width 0.254)
		(layer "F.Cu")
		(net "GND")
	)
	(segment
		(start 293.69131 -16.696944)
		(end 294.14978 -16.238474)
		(width 0.4064)
		(layer "F.Cu")
		(net "GND")
	)
	(segment
		(start 419.73119 -52.260246)
		(end 418.909754 -51.43881)
		(width 0.254)
		(layer "F.Cu")
		(net "GND")
	)
	(segment
		(start 71.349362 -3.940556)
		(end 71.349362 -5.822442)
		(width 0.4064)
		(layer "F.Cu")
		(net "GND")
	)
	(segment
		(start 388.53745 -104.65435)
		(end 388.830312 -104.361488)
		(width 0.12446)
		(layer "F.Cu")
		(net "GND")
	)
	(segment
		(start 116.495322 -101.471984)
		(end 117.066822 -100.48113)
		(width 0.254)
		(layer "F.Cu")
		(net "GND")
	)
	(segment
		(start 235.325158 -92.737686)
		(end 234.753658 -92.737686)
		(width 0.254)
		(layer "F.Cu")
		(net "GND")
	)
	(segment
		(start 297.807126 -90.080338)
		(end 298.378626 -90.080338)
		(width 0.3048)
		(layer "F.Cu")
		(net "GND")
	)
	(segment
		(start 368.972592 -26.362152)
		(end 368.967004 -26.362152)
		(width 0.254)
		(layer "F.Cu")
		(net "GND")
	)
	(segment
		(start 203.200508 -15.423642)
		(end 203.2 -15.423642)
		(width 0.4064)
		(layer "F.Cu")
		(net "GND")
	)
	(segment
		(start 415.191194 -128.740408)
		(end 416.165792 -128.740408)
		(width 0.381)
		(layer "F.Cu")
		(net "GND")
	)
	(segment
		(start 476.2246 -146.47418)
		(end 476.2246 -145.8849)
		(width 0.254)
		(layer "F.Cu")
		(net "GND")
	)
	(segment
		(start 246.485664 -90.26144)
		(end 245.914164 -90.26144)
		(width 0.254)
		(layer "F.Cu")
		(net "GND")
	)
	(segment
		(start 118.041928 -155.612846)
		(end 118.041928 -155.600146)
		(width 0.3556)
		(layer "F.Cu")
		(net "GND")
	)
	(segment
		(start 78.051406 -89.27084)
		(end 77.479906 -89.27084)
		(width 0.254)
		(layer "F.Cu")
		(net "GND")
	)
	(segment
		(start 409.272486 -9.256014)
		(end 409.0543 -9.4742)
		(width 0.254)
		(layer "F.Cu")
		(net "GND")
	)
	(segment
		(start 243.051838 -67.47764)
		(end 242.480338 -67.47764)
		(width 0.254)
		(layer "F.Cu")
		(net "GND")
	)
	(segment
		(start 375.089928 -104.354884)
		(end 375.92 -104.354884)
		(width 0.254)
		(layer "F.Cu")
		(net "GND")
	)
	(segment
		(start 243.051838 -62.52464)
		(end 242.480338 -62.52464)
		(width 0.254)
		(layer "F.Cu")
		(net "GND")
	)
	(segment
		(start 120.787668 -90.080338)
		(end 121.359168 -90.080338)
		(width 0.254)
		(layer "F.Cu")
		(net "GND")
	)
	(segment
		(start 276.344634 -52.077366)
		(end 276.3266 -52.0954)
		(width 0.254)
		(layer "F.Cu")
		(net "GND")
	)
	(segment
		(start 165.672008 -85.330792)
		(end 165.672008 -85.533992)
		(width 0.254)
		(layer "F.Cu")
		(net "GND")
	)
	(segment
		(start 386.5372 -112.2553)
		(end 386.13715 -111.85525)
		(width 0.1143)
		(layer "F.Cu")
		(net "GND")
	)
	(segment
		(start 61.149484 -147.27174)
		(end 61.149484 -146.011646)
		(width 0.4064)
		(layer "F.Cu")
		(net "GND")
	)
	(segment
		(start 152.949402 -133.0706)
		(end 152.949402 -134.340346)
		(width 0.4064)
		(layer "F.Cu")
		(net "GND")
	)
	(segment
		(start 364.604554 -105.97388)
		(end 364.604554 -107.462066)
		(width 0.254)
		(layer "F.Cu")
		(net "GND")
	)
	(segment
		(start 390.62152 -74.98588)
		(end 390.62152 -76.113894)
		(width 0.254)
		(layer "F.Cu")
		(net "GND")
	)
	(segment
		(start 137.957814 -75.221338)
		(end 138.529314 -75.221338)
		(width 0.254)
		(layer "F.Cu")
		(net "GND")
	)
	(segment
		(start 408.556206 -64.03213)
		(end 408.453336 -64.135)
		(width 0.254)
		(layer "F.Cu")
		(net "GND")
	)
	(segment
		(start 285.649924 -10.422382)
		(end 285.649924 -9.156446)
		(width 0.4064)
		(layer "F.Cu")
		(net "GND")
	)
	(segment
		(start 463.800952 -113.798604)
		(end 463.799936 -113.79962)
		(width 0.4064)
		(layer "F.Cu")
		(net "GND")
	)
	(segment
		(start 290.74999 -137.67054)
		(end 290.74999 -136.410446)
		(width 0.4064)
		(layer "F.Cu")
		(net "GND")
	)
	(segment
		(start 272.623534 -101.967538)
		(end 272.624042 -101.968046)
		(width 0.254)
		(layer "F.Cu")
		(net "GND")
	)
	(segment
		(start 144.449546 -20.023582)
		(end 144.449546 -21.479256)
		(width 0.4064)
		(layer "F.Cu")
		(net "GND")
	)
	(segment
		(start 176.054004 -147.67052)
		(end 176.054004 -147.694142)
		(width 0.254)
		(layer "F.Cu")
		(net "GND")
	)
	(segment
		(start 254.212344 -53.322474)
		(end 254.49911 -53.60924)
		(width 0.254)
		(layer "F.Cu")
		(net "GND")
	)
	(segment
		(start 134.160514 -3.737356)
		(end 134.249414 -3.826256)
		(width 0.4064)
		(layer "F.Cu")
		(net "GND")
	)
	(segment
		(start 493.64646 -25.83942)
		(end 494.33226 -25.83942)
		(width 0.254)
		(layer "F.Cu")
		(net "GND")
	)
	(segment
		(start 401.786852 -99.363276)
		(end 402.259292 -99.363276)
		(width 0.254)
		(layer "F.Cu")
		(net "GND")
	)
	(segment
		(start 234.65028 3.778758)
		(end 234.649772 3.778758)
		(width 0.4064)
		(layer "F.Cu")
		(net "GND")
	)
	(segment
		(start 394.124688 -106.974132)
		(end 394.20546 -106.974132)
		(width 0.254)
		(layer "F.Cu")
		(net "GND")
	)
	(segment
		(start 281.400504 -147.27174)
		(end 281.399996 -147.27174)
		(width 0.4064)
		(layer "F.Cu")
		(net "GND")
	)
	(segment
		(start 0.26416 -135.03656)
		(end 0.567436 -135.339836)
		(width 0.254)
		(layer "F.Cu")
		(net "GND")
	)
	(segment
		(start 310.299862 -6.539738)
		(end 310.0832 -6.7564)
		(width 0.3556)
		(layer "F.Cu")
		(net "GND")
	)
	(segment
		(start 276.3266 -52.0954)
		(end 276.3266 -52.914804)
		(width 0.254)
		(layer "F.Cu")
		(net "GND")
	)
	(segment
		(start 383.666746 -24.770842)
		(end 383.959354 -25.06345)
		(width 0.254)
		(layer "F.Cu")
		(net "GND")
	)
	(segment
		(start 290.93922 -100.976684)
		(end 291.51072 -100.976684)
		(width 0.3048)
		(layer "F.Cu")
		(net "GND")
	)
	(segment
		(start 69.466206 -67.47764)
		(end 68.894706 -67.47764)
		(width 0.254)
		(layer "F.Cu")
		(net "GND")
	)
	(segment
		(start 74.617326 -57.57164)
		(end 74.045826 -57.57164)
		(width 0.254)
		(layer "F.Cu")
		(net "GND")
	)
	(segment
		(start 384.893566 -80.941926)
		(end 385.4704 -81.51876)
		(width 0.254)
		(layer "F.Cu")
		(net "GND")
	)
	(segment
		(start 138.529314 -100.976684)
		(end 137.957814 -100.976684)
		(width 0.4064)
		(layer "F.Cu")
		(net "GND")
	)
	(segment
		(start 399.634964 -101.855016)
		(end 399.188432 -101.893116)
		(width 0.254)
		(layer "F.Cu")
		(net "GND")
	)
	(segment
		(start 289.899852 -142.677642)
		(end 289.899852 -144.364202)
		(width 0.4064)
		(layer "F.Cu")
		(net "GND")
	)
	(segment
		(start 231.249982 3.599688)
		(end 231.249728 3.599434)
		(width 0.4064)
		(layer "F.Cu")
		(net "GND")
	)
	(segment
		(start 457.252324 -144.719802)
		(end 455.920602 -144.719802)
		(width 0.254)
		(layer "F.Cu")
		(net "GND")
	)
	(segment
		(start 207.449928 -21.479256)
		(end 207.449928 -20.023582)
		(width 0.4064)
		(layer "F.Cu")
		(net "GND")
	)
	(segment
		(start 300.949868 -152.278842)
		(end 300.949868 -153.024078)
		(width 0.3556)
		(layer "F.Cu")
		(net "GND")
	)
	(segment
		(start 305.533806 -62.838584)
		(end 305.246786 -63.125604)
		(width 0.254)
		(layer "F.Cu")
		(net "GND")
	)
	(segment
		(start 118.041928 -136.410446)
		(end 118.041928 -136.397746)
		(width 0.3556)
		(layer "F.Cu")
		(net "GND")
	)
	(segment
		(start 194.49542 -85.106256)
		(end 194.494404 -85.107272)
		(width 0.254)
		(layer "F.Cu")
		(net "GND")
	)
	(segment
		(start 170.7261 -73.2409)
		(end 170.307 -73.66)
		(width 0.254)
		(layer "F.Cu")
		(net "GND")
	)
	(segment
		(start 72.142096 -136.410446)
		(end 72.142096 -136.397746)
		(width 0.3556)
		(layer "F.Cu")
		(net "GND")
	)
	(segment
		(start 442.923168 -37.432488)
		(end 442.921898 -37.432488)
		(width 0.3048)
		(layer "F.Cu")
		(net "GND")
	)
	(segment
		(start 314.550298 3.778758)
		(end 314.54979 3.778758)
		(width 0.4064)
		(layer "F.Cu")
		(net "GND")
	)
	(segment
		(start 285.7881 -98.005138)
		(end 286.3596 -98.005138)
		(width 0.254)
		(layer "F.Cu")
		(net "GND")
	)
	(segment
		(start 113.919762 -93.052138)
		(end 114.491262 -93.052138)
		(width 0.254)
		(layer "F.Cu")
		(net "GND")
	)
	(segment
		(start 262.636 -24.3586)
		(end 262.3566 -24.638)
		(width 0.508)
		(layer "F.Cu")
		(net "GND")
	)
	(segment
		(start 381.33655 -156.321506)
		(end 381.576072 -156.321506)
		(width 0.254)
		(layer "F.Cu")
		(net "GND")
	)
	(segment
		(start 169.389298 -64.3509)
		(end 169.389298 -63.731902)
		(width 0.2032)
		(layer "F.Cu")
		(net "GND")
	)
	(segment
		(start 395.66215 -114.1476)
		(end 395.66215 -113.519204)
		(width 0.254)
		(layer "F.Cu")
		(net "GND")
	)
	(segment
		(start 74.617326 -50.63744)
		(end 74.904346 -51.132486)
		(width 0.254)
		(layer "F.Cu")
		(net "GND")
	)
	(segment
		(start 114.778282 -55.904384)
		(end 114.206782 -55.904384)
		(width 0.254)
		(layer "F.Cu")
		(net "GND")
	)
	(segment
		(start 184.531 -5.9182)
		(end 184.531 -5.1435)
		(width 0.4064)
		(layer "F.Cu")
		(net "GND")
	)
	(segment
		(start 124.221748 -93.052138)
		(end 124.793248 -93.052138)
		(width 0.254)
		(layer "F.Cu")
		(net "GND")
	)
	(segment
		(start 294.3733 -78.193138)
		(end 294.9448 -78.193138)
		(width 0.254)
		(layer "F.Cu")
		(net "GND")
	)
	(segment
		(start 38.199314 -133.255766)
		(end 38.199314 -134.861046)
		(width 0.4064)
		(layer "F.Cu")
		(net "GND")
	)
	(segment
		(start 398.759426 -95.267526)
		(end 398.876012 -95.498666)
		(width 0.254)
		(layer "F.Cu")
		(net "GND")
	)
	(segment
		(start 72.900286 -76.39304)
		(end 72.328786 -76.39304)
		(width 0.254)
		(layer "F.Cu")
		(net "GND")
	)
	(segment
		(start 382.9304 -100.343462)
		(end 383.27965 -100.181156)
		(width 0.254)
		(layer "F.Cu")
		(net "GND")
	)
	(segment
		(start 128.514348 -84.631784)
		(end 129.085848 -84.631784)
		(width 0.254)
		(layer "F.Cu")
		(net "GND")
	)
	(segment
		(start 53.499512 -156.87294)
		(end 53.499512 -155.67025)
		(width 0.3556)
		(layer "F.Cu")
		(net "GND")
	)
	(segment
		(start 36.499292 -133.076696)
		(end 36.499292 -133.891274)
		(width 0.4064)
		(layer "F.Cu")
		(net "GND")
	)
	(segment
		(start 291.79774 -96.518984)
		(end 292.36924 -96.518984)
		(width 0.254)
		(layer "F.Cu")
		(net "GND")
	)
	(segment
		(start 202.35037 -147.27174)
		(end 202.349862 -147.27174)
		(width 0.4064)
		(layer "F.Cu")
		(net "GND")
	)
	(segment
		(start 123.363228 -100.481638)
		(end 123.934728 -100.481638)
		(width 0.254)
		(layer "F.Cu")
		(net "GND")
	)
	(segment
		(start 483.108254 -31.3944)
		(end 483.398322 -31.684468)
		(width 0.254)
		(layer "F.Cu")
		(net "GND")
	)
	(segment
		(start 122.217688 -91.565984)
		(end 121.646188 -91.565984)
		(width 0.1651)
		(layer "F.Cu")
		(net "GND")
	)
	(segment
		(start 414.073086 -9.552686)
		(end 414.050734 -9.552686)
		(width 0.254)
		(layer "F.Cu")
		(net "GND")
	)
	(segment
		(start 449.25488 -35.8775)
		(end 445.0715 -35.8775)
		(width 0.4064)
		(layer "F.Cu")
		(net "GND")
	)
	(segment
		(start 70.499478 -18.795746)
		(end 70.499478 -20.023582)
		(width 0.4064)
		(layer "F.Cu")
		(net "GND")
	)
	(segment
		(start 114.699542 -147.277582)
		(end 114.699542 -148.771356)
		(width 0.508)
		(layer "F.Cu")
		(net "GND")
	)
	(segment
		(start 292.45052 -20.023582)
		(end 292.450012 -20.023582)
		(width 0.3556)
		(layer "F.Cu")
		(net "GND")
	)
	(segment
		(start 300.954186 -63.621158)
		(end 300.954186 -63.829184)
		(width 0.254)
		(layer "F.Cu")
		(net "GND")
	)
	(segment
		(start 460.541116 -46.011084)
		(end 460.541116 -47.481998)
		(width 0.4064)
		(layer "F.Cu")
		(net "GND")
	)
	(segment
		(start 214.250524 1.994916)
		(end 214.249762 1.994154)
		(width 0.4064)
		(layer "F.Cu")
		(net "GND")
	)
	(segment
		(start 40.749474 -9.143746)
		(end 40.749474 -10.422382)
		(width 0.4064)
		(layer "F.Cu")
		(net "GND")
	)
	(segment
		(start 481.151946 -141.147546)
		(end 481.151946 -141.67866)
		(width 0.254)
		(layer "F.Cu")
		(net "GND")
	)
	(segment
		(start 278.850344 3.778758)
		(end 278.849836 3.778758)
		(width 0.4064)
		(layer "F.Cu")
		(net "GND")
	)
	(segment
		(start 282.354274 -91.070938)
		(end 282.925774 -91.070938)
		(width 0.254)
		(layer "F.Cu")
		(net "GND")
	)
	(segment
		(start 43.076368 -6.781546)
		(end 43.29938 -6.558534)
		(width 0.3556)
		(layer "F.Cu")
		(net "GND")
	)
	(segment
		(start 142.875 -59.86399)
		(end 143.277336 -59.86399)
		(width 0.254)
		(layer "F.Cu")
		(net "GND")
	)
	(segment
		(start 274.919186 -67.21348)
		(end 274.919186 -67.904614)
		(width 0.254)
		(layer "F.Cu")
		(net "GND")
	)
	(segment
		(start 249.919744 -90.26144)
		(end 249.348244 -90.26144)
		(width 0.254)
		(layer "F.Cu")
		(net "GND")
	)
	(segment
		(start 117.353842 -102.958138)
		(end 117.925342 -102.958138)
		(width 0.254)
		(layer "F.Cu")
		(net "GND")
	)
	(segment
		(start 43.29938 3.042666)
		(end 43.076368 2.819654)
		(width 0.3556)
		(layer "F.Cu")
		(net "GND")
	)
	(segment
		(start 399.671286 -9.44372)
		(end 399.662142 -9.452864)
		(width 0.254)
		(layer "F.Cu")
		(net "GND")
	)
	(segment
		(start 283.212794 -61.847984)
		(end 282.641294 -61.847984)
		(width 0.254)
		(layer "F.Cu")
		(net "GND")
	)
	(segment
		(start 45.84954 -133.0706)
		(end 45.84954 -133.076442)
		(width 0.4064)
		(layer "F.Cu")
		(net "GND")
	)
	(segment
		(start 290.0807 -72.744584)
		(end 290.6522 -72.744584)
		(width 0.254)
		(layer "F.Cu")
		(net "GND")
	)
	(segment
		(start 236.1184 2.8194)
		(end 236.1184 2.009394)
		(width 0.3556)
		(layer "F.Cu")
		(net "GND")
	)
	(segment
		(start 288.19983 -142.677642)
		(end 288.19983 -144.462246)
		(width 0.4064)
		(layer "F.Cu")
		(net "GND")
	)
	(segment
		(start 379.31725 -104.70388)
		(end 379.437646 -104.648)
		(width 0.254)
		(layer "F.Cu")
		(net "GND")
	)
	(segment
		(start 480.08286 -17.59839)
		(end 480.539806 -17.59839)
		(width 0.254)
		(layer "F.Cu")
		(net "GND")
	)
	(segment
		(start 137.670794 -88.594184)
		(end 137.099294 -88.594184)
		(width 0.254)
		(layer "F.Cu")
		(net "GND")
	)
	(segment
		(start 109.627162 -52.932838)
		(end 109.069632 -53.8988)
		(width 0.254)
		(layer "F.Cu")
		(net "GND")
	)
	(segment
		(start 311.15 -9.21385)
		(end 311.092596 -9.156446)
		(width 0.3556)
		(layer "F.Cu")
		(net "GND")
	)
	(segment
		(start 377.33605 -106.42092)
		(end 377.361958 -106.408728)
		(width 0.254)
		(layer "F.Cu")
		(net "GND")
	)
	(segment
		(start 134.523734 -79.183738)
		(end 135.095234 -79.183738)
		(width 0.254)
		(layer "F.Cu")
		(net "GND")
	)
	(segment
		(start 373.485156 -7.850124)
		(end 373.485156 -8.84682)
		(width 0.4064)
		(layer "F.Cu")
		(net "GND")
	)
	(segment
		(start 301.800006 -18.81505)
		(end 301.800006 -20.023582)
		(width 0.3556)
		(layer "F.Cu")
		(net "GND")
	)
	(segment
		(start 113.069878 -3.3528)
		(end 113.196878 -3.4798)
		(width 0.381)
		(layer "F.Cu")
		(net "GND")
	)
	(segment
		(start 204.899768 3.778758)
		(end 204.899768 1.994154)
		(width 0.4064)
		(layer "F.Cu")
		(net "GND")
	)
	(segment
		(start 240.476278 -66.982086)
		(end 239.904778 -66.982086)
		(width 0.254)
		(layer "F.Cu")
		(net "GND")
	)
	(segment
		(start 463.29092 -37.067998)
		(end 463.611722 -37.3888)
		(width 0.4064)
		(layer "F.Cu")
		(net "GND")
	)
	(segment
		(start 196.177154 -61.430154)
		(end 196.177154 -61.205364)
		(width 0.254)
		(layer "F.Cu")
		(net "GND")
	)
	(segment
		(start 292.392608 -18.744946)
		(end 292.392608 -18.757646)
		(width 0.3556)
		(layer "F.Cu")
		(net "GND")
	)
	(segment
		(start 300.949868 -3.940556)
		(end 300.949868 -5.822442)
		(width 0.4064)
		(layer "F.Cu")
		(net "GND")
	)
	(segment
		(start 208.299812 -15.423642)
		(end 208.299812 -13.541756)
		(width 0.4064)
		(layer "F.Cu")
		(net "GND")
	)
	(segment
		(start 391.69975 -121.01576)
		(end 392.19505 -121.245884)
		(width 0.254)
		(layer "F.Cu")
		(net "GND")
	)
	(segment
		(start 217.650314 -152.273)
		(end 217.649806 -152.278842)
		(width 0.3048)
		(layer "F.Cu")
		(net "GND")
	)
	(segment
		(start 431.8 -24.130762)
		(end 431.8 -25.908)
		(width 0.254)
		(layer "F.Cu")
		(net "GND")
	)
	(segment
		(start 174.8155 -69.5452)
		(end 174.8155 -68.834)
		(width 0.381)
		(layer "F.Cu")
		(net "GND")
	)
	(segment
		(start 45.849286 -133.891274)
		(end 45.390816 -134.349744)
		(width 0.4064)
		(layer "F.Cu")
		(net "GND")
	)
	(segment
		(start 297.549824 -152.278842)
		(end 297.549824 -154.063446)
		(width 0.4064)
		(layer "F.Cu")
		(net "GND")
	)
	(segment
		(start 221.900496 3.778758)
		(end 221.899988 3.778758)
		(width 0.4064)
		(layer "F.Cu")
		(net "GND")
	)
	(segment
		(start 196.4436 -130.2512)
		(end 196.4436 -129.612644)
		(width 0.4064)
		(layer "F.Cu")
		(net "GND")
	)
	(segment
		(start 37.34943 -10.422382)
		(end 37.34943 -11.916156)
		(width 0.4064)
		(layer "F.Cu")
		(net "GND")
	)
	(segment
		(start 352.9203 -94.5515)
		(end 352.786696 -94.685104)
		(width 0.254)
		(layer "F.Cu")
		(net "GND")
	)
	(segment
		(start 386.13715 -104.65435)
		(end 386.13715 -104.22636)
		(width 0.254)
		(layer "F.Cu")
		(net "GND")
	)
	(segment
		(start 42.424096 -136.410446)
		(end 42.411396 -136.410446)
		(width 0.4064)
		(layer "F.Cu")
		(net "GND")
	)
	(segment
		(start 210.38185 -11.9126)
		(end 211.6963 -11.9126)
		(width 0.254)
		(layer "F.Cu")
		(net "GND")
	)
	(segment
		(start 388.984998 -95.205042)
		(end 389.485124 -94.790006)
		(width 0.254)
		(layer "F.Cu")
		(net "GND")
	)
	(segment
		(start 222.75038 -0.821182)
		(end 222.749872 -0.821182)
		(width 0.4064)
		(layer "F.Cu")
		(net "GND")
	)
	(segment
		(start 463.553556 -150.793196)
		(end 463.553556 -150.79853)
		(width 0.254)
		(layer "F.Cu")
		(net "GND")
	)
	(segment
		(start 32.094932 -78.635352)
		(end 31.702756 -78.243176)
		(width 0.254)
		(layer "F.Cu")
		(net "GND")
	)
	(segment
		(start 464.476338 -140.219938)
		(end 464.5406 -140.2842)
		(width 0.254)
		(layer "F.Cu")
		(net "GND")
	)
	(segment
		(start 43.29938 -143.413734)
		(end 43.076368 -143.636746)
		(width 0.3556)
		(layer "F.Cu")
		(net "GND")
	)
	(segment
		(start 223.60001 -3.76301)
		(end 223.60001 -5.822442)
		(width 0.4064)
		(layer "F.Cu")
		(net "GND")
	)
	(segment
		(start 297.550332 -15.423642)
		(end 297.549824 -15.423642)
		(width 0.4064)
		(layer "F.Cu")
		(net "GND")
	)
	(segment
		(start 442.945774 -52.2478)
		(end 442.939932 -51.875944)
		(width 0.4064)
		(layer "F.Cu")
		(net "GND")
	)
	(segment
		(start 135.382254 -90.575384)
		(end 135.953754 -90.575384)
		(width 0.254)
		(layer "F.Cu")
		(net "GND")
	)
	(segment
		(start 238.900462 -5.822442)
		(end 238.899954 -5.822442)
		(width 0.4064)
		(layer "F.Cu")
		(net "GND")
	)
	(segment
		(start 472.600782 -118.397782)
		(end 472.7702 -118.5672)
		(width 0.4064)
		(layer "F.Cu")
		(net "GND")
	)
	(segment
		(start 289.801808 -17.208246)
		(end 289.899852 -17.110202)
		(width 0.4064)
		(layer "F.Cu")
		(net "GND")
	)
	(segment
		(start 87.494872 -79.859886)
		(end 86.923372 -79.859886)
		(width 0.254)
		(layer "F.Cu")
		(net "GND")
	)
	(segment
		(start 3.132836 -6.663436)
		(end 2.8448 -6.3754)
		(width 0.254)
		(layer "F.Cu")
		(net "GND")
	)
	(segment
		(start 286.499808 -3.762756)
		(end 286.499808 -5.822442)
		(width 0.4064)
		(layer "F.Cu")
		(net "GND")
	)
	(segment
		(start 317.100458 -142.6718)
		(end 317.09995 -142.677642)
		(width 0.4064)
		(layer "F.Cu")
		(net "GND")
	)
	(segment
		(start 18.453862 -120.414288)
		(end 18.453862 -120.410224)
		(width 0.508)
		(layer "F.Cu")
		(net "GND")
	)
	(segment
		(start 458.201014 -113.751614)
		(end 458.216 -113.7666)
		(width 0.4064)
		(layer "F.Cu")
		(net "GND")
	)
	(segment
		(start 263.65581 -91.25204)
		(end 263.08431 -91.25204)
		(width 0.254)
		(layer "F.Cu")
		(net "GND")
	)
	(segment
		(start 298.665646 -92.556584)
		(end 299.237146 -92.556584)
		(width 0.3048)
		(layer "F.Cu")
		(net "GND")
	)
	(segment
		(start 119.070882 -58.381138)
		(end 118.499382 -58.381138)
		(width 0.254)
		(layer "F.Cu")
		(net "GND")
	)
	(segment
		(start 213.399878 -136.410446)
		(end 213.399878 -137.67054)
		(width 0.4064)
		(layer "F.Cu")
		(net "GND")
	)
	(segment
		(start 77.299312 -142.677896)
		(end 77.299312 -144.462246)
		(width 0.4064)
		(layer "F.Cu")
		(net "GND")
	)
	(segment
		(start 394.67155 -112.43056)
		(end 395.16685 -112.660684)
		(width 0.254)
		(layer "F.Cu")
		(net "GND")
	)
	(segment
		(start 312.850276 -142.6718)
		(end 312.849768 -142.677642)
		(width 0.4064)
		(layer "F.Cu")
		(net "GND")
	)
	(segment
		(start 38.199568 -142.6718)
		(end 38.199568 -142.856712)
		(width 0.4064)
		(layer "F.Cu")
		(net "GND")
	)
	(segment
		(start 277.203154 -98.005138)
		(end 277.774654 -98.005138)
		(width 0.254)
		(layer "F.Cu")
		(net "GND")
	)
	(segment
		(start 191.897 -12.5095)
		(end 191.897 -11.8618)
		(width 0.4064)
		(layer "F.Cu")
		(net "GND")
	)
	(segment
		(start 136.74217 0.444754)
		(end 136.74217 0.457454)
		(width 0.3556)
		(layer "F.Cu")
		(net "GND")
	)
	(segment
		(start 126.599442 -133.0706)
		(end 126.599442 -133.799326)
		(width 0.3556)
		(layer "F.Cu")
		(net "GND")
	)
	(segment
		(start 178.943 -75.050396)
		(end 179.578254 -75.68565)
		(width 0.4064)
		(layer "F.Cu")
		(net "GND")
	)
	(segment
		(start 64.549528 3.778758)
		(end 64.549274 3.778504)
		(width 0.4064)
		(layer "F.Cu")
		(net "GND")
	)
	(segment
		(start 375.085102 -3.446018)
		(end 375.085102 -4.389882)
		(width 0.4572)
		(layer "F.Cu")
		(net "GND")
	)
	(segment
		(start 448.545712 -52.2478)
		(end 448.53987 -51.875944)
		(width 0.4064)
		(layer "F.Cu")
		(net "GND")
	)
	(segment
		(start 401.99564 -93.8784)
		(end 401.955 -93.8784)
		(width 0.254)
		(layer "F.Cu")
		(net "GND")
	)
	(segment
		(start 382.397 -124.15266)
		(end 382.78435 -123.821444)
		(width 0.254)
		(layer "F.Cu")
		(net "GND")
	)
	(segment
		(start 389.22325 -123.59132)
		(end 389.71855 -123.821444)
		(width 0.254)
		(layer "F.Cu")
		(net "GND")
	)
	(segment
		(start 43.29938 -5.822442)
		(end 43.29938 -3.940556)
		(width 0.4064)
		(layer "F.Cu")
		(net "GND")
	)
	(segment
		(start 389.89 -126.070106)
		(end 389.984996 -126.165102)
		(width 0.254)
		(layer "F.Cu")
		(net "GND")
	)
	(segment
		(start 201.500486 -5.822442)
		(end 201.500486 -6.636512)
		(width 0.4064)
		(layer "F.Cu")
		(net "GND")
	)
	(segment
		(start 287.50514 -96.023938)
		(end 288.07664 -96.023938)
		(width 0.254)
		(layer "F.Cu")
		(net "GND")
	)
	(segment
		(start 122.349514 -2.314956)
		(end 122.349514 -0.821182)
		(width 0.4064)
		(layer "F.Cu")
		(net "GND")
	)
	(segment
		(start 390.07288 -109.86262)
		(end 390.34466 -109.86262)
		(width 0.12446)
		(layer "F.Cu")
		(net "GND")
	)
	(segment
		(start 217.650314 3.778758)
		(end 217.649806 3.778758)
		(width 0.3048)
		(layer "F.Cu")
		(net "GND")
	)
	(segment
		(start 303.529746 -74.230738)
		(end 302.958246 -74.230738)
		(width 0.254)
		(layer "F.Cu")
		(net "GND")
	)
	(segment
		(start 394.67155 -123.821444)
		(end 394.17625 -123.59132)
		(width 0.254)
		(layer "F.Cu")
		(net "GND")
	)
	(segment
		(start 240.600484 -15.423642)
		(end 240.599976 -15.423642)
		(width 0.4064)
		(layer "F.Cu")
		(net "GND")
	)
	(segment
		(start 498.5512 -37.101272)
		(end 498.5512 -36.4998)
		(width 0.254)
		(layer "F.Cu")
		(net "GND")
	)
	(segment
		(start 115.636802 -58.381138)
		(end 115.065302 -58.381138)
		(width 0.254)
		(layer "F.Cu")
		(net "GND")
	)
	(segment
		(start 230.399844 -155.612846)
		(end 230.399844 -156.87294)
		(width 0.4064)
		(layer "F.Cu")
		(net "GND")
	)
	(segment
		(start 31.468568 -11.985244)
		(end 31.468568 -12.923012)
		(width 0.381)
		(layer "F.Cu")
		(net "GND")
	)
	(segment
		(start 458.878178 -3.545078)
		(end 458.878178 -4.386072)
		(width 0.254)
		(layer "F.Cu")
		(net "GND")
	)
	(segment
		(start 107.623102 -101.967538)
		(end 107.62361 -101.968046)
		(width 0.254)
		(layer "F.Cu")
		(net "GND")
	)
	(segment
		(start 299.524166 -77.202538)
		(end 300.095666 -77.202538)
		(width 0.254)
		(layer "F.Cu")
		(net "GND")
	)
	(segment
		(start 210.849718 -15.423896)
		(end 210.849972 -15.423642)
		(width 0.4064)
		(layer "F.Cu")
		(net "GND")
	)
	(segment
		(start 236.349794 -133.076442)
		(end 236.349794 -133.804406)
		(width 0.3556)
		(layer "F.Cu")
		(net "GND")
	)
	(segment
		(start 106.480356 -54.418738)
		(end 107.051856 -54.418738)
		(width 0.254)
		(layer "F.Cu")
		(net "GND")
	)
	(segment
		(start 77.299566 -142.6718)
		(end 77.299566 -140.63091)
		(width 0.4064)
		(layer "F.Cu")
		(net "GND")
	)
	(segment
		(start 385.545838 -81.594198)
		(end 386.007864 -81.594198)
		(width 0.254)
		(layer "F.Cu")
		(net "GND")
	)
	(segment
		(start 115.549426 -15.423642)
		(end 115.549426 -14.2113)
		(width 0.4064)
		(layer "F.Cu")
		(net "GND")
	)
	(segment
		(start 215.0999 -10.422382)
		(end 215.0999 -11.916156)
		(width 0.4064)
		(layer "F.Cu")
		(net "GND")
	)
	(segment
		(start 131.699508 -18.757646)
		(end 131.699508 -20.023582)
		(width 0.4064)
		(layer "F.Cu")
		(net "GND")
	)
	(segment
		(start 267.794232 -140.208)
		(end 268.679168 -140.208)
		(width 0.4572)
		(layer "F.Cu")
		(net "GND")
	)
	(segment
		(start 287.21812 -89.584784)
		(end 286.64662 -89.584784)
		(width 0.254)
		(layer "F.Cu")
		(net "GND")
	)
	(segment
		(start 300.950376 -142.6718)
		(end 300.949868 -142.677642)
		(width 0.3556)
		(layer "F.Cu")
		(net "GND")
	)
	(segment
		(start 501.2563 -128.610106)
		(end 501.2563 -128.44018)
		(width 0.508)
		(layer "F.Cu")
		(net "GND")
	)
	(segment
		(start 464.542886 -52.2478)
		(end 464.540092 -51.875944)
		(width 0.4064)
		(layer "F.Cu")
		(net "GND")
	)
	(segment
		(start 234.649772 -152.278842)
		(end 234.649772 -153.965402)
		(width 0.4064)
		(layer "F.Cu")
		(net "GND")
	)
	(segment
		(start 37.34943 -2.314956)
		(end 37.34943 -0.821182)
		(width 0.4064)
		(layer "F.Cu")
		(net "GND")
	)
	(segment
		(start 61.999368 -143.408654)
		(end 61.796168 -143.611854)
		(width 0.3556)
		(layer "F.Cu")
		(net "GND")
	)
	(segment
		(start 226.150424 -10.422382)
		(end 226.149916 -10.422382)
		(width 0.4064)
		(layer "F.Cu")
		(net "GND")
	)
	(segment
		(start 128.687576 -4.346956)
		(end 127.382016 -4.2926)
		(width 0.254)
		(layer "F.Cu")
		(net "GND")
	)
	(segment
		(start 283.212794 -102.462584)
		(end 282.925774 -101.967538)
		(width 0.254)
		(layer "F.Cu")
		(net "GND")
	)
	(segment
		(start 133.665214 -59.866784)
		(end 134.236714 -59.866784)
		(width 0.254)
		(layer "F.Cu")
		(net "GND")
	)
	(segment
		(start 459.557374 -63.35014)
		(end 459.557374 -63.626492)
		(width 0.381)
		(layer "F.Cu")
		(net "GND")
	)
	(segment
		(start 184.6072 -154.0256)
		(end 184.658 -154.0764)
		(width 0.254)
		(layer "F.Cu")
		(net "GND")
	)
	(segment
		(start 248.202704 -87.28964)
		(end 247.631204 -87.28964)
		(width 0.254)
		(layer "F.Cu")
		(net "GND")
	)
	(segment
		(start 239.617758 -78.37424)
		(end 239.046258 -78.37424)
		(width 0.254)
		(layer "F.Cu")
		(net "GND")
	)
	(segment
		(start 385.26085 -120.15724)
		(end 385.75615 -120.387364)
		(width 0.254)
		(layer "F.Cu")
		(net "GND")
	)
	(segment
		(start 132.806694 -90.080338)
		(end 133.378194 -90.080338)
		(width 0.254)
		(layer "F.Cu")
		(net "GND")
	)
	(segment
		(start 376.38736 -105.136188)
		(end 376.428 -105.354882)
		(width 0.254)
		(layer "F.Cu")
		(net "GND")
	)
	(segment
		(start 381.29845 -96.11868)
		(end 381.79375 -95.888556)
		(width 0.254)
		(layer "F.Cu")
		(net "GND")
	)
	(segment
		(start 119.929402 -54.913784)
		(end 119.357902 -54.913784)
		(width 0.254)
		(layer "F.Cu")
		(net "GND")
	)
	(segment
		(start 419.1635 -54.8513)
		(end 419.1635 -55.2831)
		(width 0.254)
		(layer "F.Cu")
		(net "GND")
	)
	(segment
		(start 74.617326 -83.32724)
		(end 74.045826 -83.32724)
		(width 0.254)
		(layer "F.Cu")
		(net "GND")
	)
	(segment
		(start 198.061834 -21.517356)
		(end 198.099934 -21.479256)
		(width 0.4064)
		(layer "F.Cu")
		(net "GND")
	)
	(segment
		(start 120.787668 -81.164938)
		(end 121.359168 -81.164938)
		(width 0.254)
		(layer "F.Cu")
		(net "GND")
	)
	(segment
		(start 64.549528 -5.822442)
		(end 64.549274 -5.822696)
		(width 0.4064)
		(layer "F.Cu")
		(net "GND")
	)
	(segment
		(start 129.372868 -86.117938)
		(end 129.944368 -86.117938)
		(width 0.254)
		(layer "F.Cu")
		(net "GND")
	)
	(segment
		(start 209.150458 -10.422382)
		(end 209.14995 -10.422382)
		(width 0.4064)
		(layer "F.Cu")
		(net "GND")
	)
	(segment
		(start 376.42292 -122.38228)
		(end 376.362468 -122.7074)
		(width 0.254)
		(layer "F.Cu")
		(net "GND")
	)
	(segment
		(start 215.949784 2.092198)
		(end 215.85174 1.994154)
		(width 0.4064)
		(layer "F.Cu")
		(net "GND")
	)
	(segment
		(start 289.899852 -15.423642)
		(end 289.90036 -15.423642)
		(width 0.4064)
		(layer "F.Cu")
		(net "GND")
	)
	(segment
		(start 259.36321 -98.681286)
		(end 258.79171 -98.681286)
		(width 0.254)
		(layer "F.Cu")
		(net "GND")
	)
	(segment
		(start 287.21812 -100.481384)
		(end 287.1216 -100.64877)
		(width 0.254)
		(layer "F.Cu")
		(net "GND")
	)
	(segment
		(start 2.145538 -135.192262)
		(end 2.3876 -134.9502)
		(width 0.254)
		(layer "F.Cu")
		(net "GND")
	)
	(segment
		(start 249.919744 -96.20504)
		(end 249.348244 -96.20504)
		(width 0.254)
		(layer "F.Cu")
		(net "GND")
	)
	(segment
		(start 201.499724 -153.093674)
		(end 201.041254 -153.552144)
		(width 0.4064)
		(layer "F.Cu")
		(net "GND")
	)
	(segment
		(start 89.789 -140.208)
		(end 90.071194 -140.490194)
		(width 0.4064)
		(layer "F.Cu")
		(net "GND")
	)
	(segment
		(start 205.750414 -156.87294)
		(end 205.749906 -156.87294)
		(width 0.4064)
		(layer "F.Cu")
		(net "GND")
	)
	(segment
		(start 114.551968 -53.325014)
		(end 114.519202 -53.381656)
		(width 0.254)
		(layer "F.Cu")
		(net "GND")
	)
	(segment
		(start 376.335036 -107.855004)
		(end 376.376438 -108.077)
		(width 0.254)
		(layer "F.Cu")
		(net "GND")
	)
	(segment
		(start 238.759238 -64.010286)
		(end 238.187738 -64.010286)
		(width 0.254)
		(layer "F.Cu")
		(net "GND")
	)
	(segment
		(start 113.849404 -137.67054)
		(end 113.849404 -136.379966)
		(width 0.4064)
		(layer "F.Cu")
		(net "GND")
	)
	(segment
		(start 243.910104 -92.737686)
		(end 243.338604 -92.737686)
		(width 0.254)
		(layer "F.Cu")
		(net "GND")
	)
	(segment
		(start 462.141062 -51.875944)
		(end 462.142078 -51.875944)
		(width 0.508)
		(layer "F.Cu")
		(net "GND")
	)
	(segment
		(start 390.737598 -152.625298)
		(end 390.66724 -152.55494)
		(width 0.254)
		(layer "F.Cu")
		(net "GND")
	)
	(segment
		(start 204.049884 -147.27174)
		(end 204.049884 -148.771356)
		(width 0.4064)
		(layer "F.Cu")
		(net "GND")
	)
	(segment
		(start 278.849836 -9.131046)
		(end 278.897588 -9.083294)
		(width 0.254)
		(layer "F.Cu")
		(net "GND")
	)
	(segment
		(start 88.353392 -82.33664)
		(end 87.781892 -82.33664)
		(width 0.254)
		(layer "F.Cu")
		(net "GND")
	)
	(segment
		(start 221.899988 3.599688)
		(end 221.899734 3.599434)
		(width 0.4064)
		(layer "F.Cu")
		(net "GND")
	)
	(segment
		(start 215.100408 -156.87294)
		(end 215.0999 -156.87294)
		(width 0.4064)
		(layer "F.Cu")
		(net "GND")
	)
	(segment
		(start 369.944904 -77.095096)
		(end 369.545108 -77.494892)
		(width 0.254)
		(layer "F.Cu")
		(net "GND")
	)
	(segment
		(start 80.626712 -59.057286)
		(end 80.055212 -59.057286)
		(width 0.254)
		(layer "F.Cu")
		(net "GND")
	)
	(segment
		(start 198.099934 -21.479256)
		(end 198.099934 -20.023582)
		(width 0.4064)
		(layer "F.Cu")
		(net "GND")
	)
	(segment
		(start 396.984982 -124.504958)
		(end 396.984982 -125.33503)
		(width 0.254)
		(layer "F.Cu")
		(net "GND")
	)
	(segment
		(start 127.392176 -136.410446)
		(end 127.392176 -136.397746)
		(width 0.3556)
		(layer "F.Cu")
		(net "GND")
	)
	(segment
		(start 284.33776 -13.948156)
		(end 284.800294 -14.41069)
		(width 0.4064)
		(layer "F.Cu")
		(net "GND")
	)
	(segment
		(start 140.533374 -84.631784)
		(end 141.104874 -84.631784)
		(width 0.254)
		(layer "F.Cu")
		(net "GND")
	)
	(segment
		(start 419.490144 -30.93466)
		(end 419.090094 -30.53461)
		(width 0.254)
		(layer "F.Cu")
		(net "GND")
	)
	(segment
		(start 289.22218 -65.315338)
		(end 288.65068 -65.315338)
		(width 0.254)
		(layer "F.Cu")
		(net "GND")
	)
	(segment
		(start 446.024 -52.959)
		(end 446.141094 -52.841906)
		(width 0.4064)
		(layer "F.Cu")
		(net "GND")
	)
	(segment
		(start 295.849802 -133.076442)
		(end 295.849802 -134.861046)
		(width 0.4064)
		(layer "F.Cu")
		(net "GND")
	)
	(segment
		(start 218.499944 -20.023582)
		(end 218.499944 -21.455888)
		(width 0.4064)
		(layer "F.Cu")
		(net "GND")
	)
	(segment
		(start 287.79216 -61.847984)
		(end 288.36366 -61.847984)
		(width 0.254)
		(layer "F.Cu")
		(net "GND")
	)
	(segment
		(start 282.24988 3.052826)
		(end 282.0162 2.819146)
		(width 0.3556)
		(layer "F.Cu")
		(net "GND")
	)
	(segment
		(start 295.000426 -20.023582)
		(end 294.999918 -20.023582)
		(width 0.4064)
		(layer "F.Cu")
		(net "GND")
	)
	(segment
		(start 145.082768 -134.0104)
		(end 145.082768 -134.860538)
		(width 0.3556)
		(layer "F.Cu")
		(net "GND")
	)
	(segment
		(start 132.549392 -13.363956)
		(end 132.549392 -15.423642)
		(width 0.4064)
		(layer "F.Cu")
		(net "GND")
	)
	(segment
		(start 397.14805 -111.57204)
		(end 397.64335 -111.802164)
		(width 0.254)
		(layer "F.Cu")
		(net "GND")
	)
	(segment
		(start 277.203154 -99.986338)
		(end 277.774654 -99.986338)
		(width 0.254)
		(layer "F.Cu")
		(net "GND")
	)
	(segment
		(start 376.985022 -94.274894)
		(end 377.108466 -93.544898)
		(width 0.254)
		(layer "F.Cu")
		(net "GND")
	)
	(segment
		(start 388.244588 -104.361488)
		(end 388.53745 -104.65435)
		(width 0.12446)
		(layer "F.Cu")
		(net "GND")
	)
	(segment
		(start 137.957814 -80.174338)
		(end 138.529314 -80.174338)
		(width 0.254)
		(layer "F.Cu")
		(net "GND")
	)
	(segment
		(start 198.755 -144.483582)
		(end 198.772018 -144.5006)
		(width 0.3556)
		(layer "F.Cu")
		(net "GND")
	)
	(segment
		(start 11.249914 -45.310044)
		(end 12.683998 -43.87596)
		(width 0.508)
		(layer "F.Cu")
		(net "GND")
	)
	(segment
		(start 284.071314 -98.005138)
		(end 284.642814 -98.005138)
		(width 0.254)
		(layer "F.Cu")
		(net "GND")
	)
	(segment
		(start 241.334798 -67.47764)
		(end 240.763298 -67.47764)
		(width 0.254)
		(layer "F.Cu")
		(net "GND")
	)
	(segment
		(start 302.958246 -100.976684)
		(end 302.958246 -101.967538)
		(width 0.1524)
		(layer "F.Cu")
		(net "GND")
	)
	(segment
		(start 74.617326 -58.561986)
		(end 74.045826 -58.561986)
		(width 0.254)
		(layer "F.Cu")
		(net "GND")
	)
	(segment
		(start 263.0805 -127.763524)
		(end 261.950454 -127.763524)
		(width 0.4064)
		(layer "F.Cu")
		(net "GND")
	)
	(segment
		(start 303.529746 -67.296538)
		(end 302.958246 -67.296538)
		(width 0.254)
		(layer "F.Cu")
		(net "GND")
	)
	(segment
		(start 423.890186 -43.334686)
		(end 423.890186 -43.678348)
		(width 0.254)
		(layer "F.Cu")
		(net "GND")
	)
	(segment
		(start 61.999368 3.047746)
		(end 61.796168 2.844546)
		(width 0.3556)
		(layer "F.Cu")
		(net "GND")
	)
	(segment
		(start 347.6498 -156.6418)
		(end 347.6498 -156.2862)
		(width 0.254)
		(layer "F.Cu")
		(net "GND")
	)
	(segment
		(start 41.599358 -133.0706)
		(end 41.599358 -134.763002)
		(width 0.4064)
		(layer "F.Cu")
		(net "GND")
	)
	(segment
		(start 297.807126 -55.409338)
		(end 298.378626 -55.409338)
		(width 0.254)
		(layer "F.Cu")
		(net "GND")
	)
	(segment
		(start 289.22218 -93.052138)
		(end 289.79368 -93.052138)
		(width 0.254)
		(layer "F.Cu")
		(net "GND")
	)
	(segment
		(start 301.800514 -20.023582)
		(end 301.800006 -20.023582)
		(width 0.3556)
		(layer "F.Cu")
		(net "GND")
	)
	(segment
		(start 182.4228 -74.93)
		(end 182.1942 -75.1586)
		(width 0.4064)
		(layer "F.Cu")
		(net "GND")
	)
	(segment
		(start 249.061224 -83.822286)
		(end 248.489724 -83.822286)
		(width 0.254)
		(layer "F.Cu")
		(net "GND")
	)
	(segment
		(start 350.62668 -139.01801)
		(end 350.906842 -138.737848)
		(width 0.508)
		(layer "F.Cu")
		(net "GND")
	)
	(segment
		(start 273.769328 -60.362338)
		(end 273.197828 -60.362338)
		(width 0.254)
		(layer "F.Cu")
		(net "GND")
	)
	(segment
		(start 303.499774 -153.093674)
		(end 303.041304 -153.552144)
		(width 0.4064)
		(layer "F.Cu")
		(net "GND")
	)
	(segment
		(start 42.449496 -18.783046)
		(end 42.449496 -20.023582)
		(width 0.4064)
		(layer "F.Cu")
		(net "GND")
	)
	(segment
		(start 196.219826 -69.324474)
		(end 195.58 -69.324474)
		(width 0.508)
		(layer "F.Cu")
		(net "GND")
	)
	(segment
		(start 129.372868 -84.136738)
		(end 129.944368 -84.136738)
		(width 0.254)
		(layer "F.Cu")
		(net "GND")
	)
	(segment
		(start 284.800294 3.778758)
		(end 284.800294 2.964688)
		(width 0.4064)
		(layer "F.Cu")
		(net "GND")
	)
	(segment
		(start 220.199712 -15.423896)
		(end 220.199966 -15.423642)
		(width 0.4064)
		(layer "F.Cu")
		(net "GND")
	)
	(segment
		(start 201.499724 -142.677896)
		(end 201.499724 -143.492474)
		(width 0.4064)
		(layer "F.Cu")
		(net "GND")
	)
	(segment
		(start 34.74212 -18.744946)
		(end 34.74212 -18.970498)
		(width 0.4064)
		(layer "F.Cu")
		(net "GND")
	)
	(segment
		(start 143.0528 -90.575384)
		(end 142.250414 -90.575384)
		(width 0.254)
		(layer "F.Cu")
		(net "GND")
	)
	(segment
		(start 196.40042 -0.821182)
		(end 196.399912 -0.821182)
		(width 0.4064)
		(layer "F.Cu")
		(net "GND")
	)
	(segment
		(start 33.949386 -3.940556)
		(end 33.771586 -3.762756)
		(width 0.4064)
		(layer "F.Cu")
		(net "GND")
	)
	(segment
		(start 42.449496 -155.638246)
		(end 42.424096 -155.612846)
		(width 0.4064)
		(layer "F.Cu")
		(net "GND")
	)
	(segment
		(start 115.636802 -66.305938)
		(end 115.065302 -66.305938)
		(width 0.254)
		(layer "F.Cu")
		(net "GND")
	)
	(segment
		(start 448.5513 -53.2384)
		(end 448.549776 -53.236876)
		(width 0.4064)
		(layer "F.Cu")
		(net "GND")
	)
	(segment
		(start 73.899268 -16.238474)
		(end 73.440798 -16.696944)
		(width 0.4064)
		(layer "F.Cu")
		(net "GND")
	)
	(segment
		(start 304.349912 -18.757646)
		(end 304.349912 -20.023582)
		(width 0.4064)
		(layer "F.Cu")
		(net "GND")
	)
	(segment
		(start 297.550332 3.778758)
		(end 297.549824 3.778758)
		(width 0.4064)
		(layer "F.Cu")
		(net "GND")
	)
	(segment
		(start 61.796168 -143.611854)
		(end 61.796168 -144.4752)
		(width 0.3556)
		(layer "F.Cu")
		(net "GND")
	)
	(segment
		(start 121.933208 -52.437538)
		(end 121.646188 -52.932838)
		(width 0.254)
		(layer "F.Cu")
		(net "GND")
	)
	(segment
		(start 282.0162 -6.782054)
		(end 282.0162 -7.58952)
		(width 0.3556)
		(layer "F.Cu")
		(net "GND")
	)
	(segment
		(start 287.350454 -20.023582)
		(end 287.349946 -20.023582)
		(width 0.4064)
		(layer "F.Cu")
		(net "GND")
	)
	(segment
		(start 246.61876 -12.954)
		(end 246.5832 -12.91844)
		(width 0.4064)
		(layer "F.Cu")
		(net "GND")
	)
	(segment
		(start 82.343752 -69.953886)
		(end 81.772252 -69.953886)
		(width 0.254)
		(layer "F.Cu")
		(net "GND")
	)
	(segment
		(start 350.62668 -139.37742)
		(end 350.62668 -139.9286)
		(width 0.508)
		(layer "F.Cu")
		(net "GND")
	)
	(segment
		(start 381.985012 -124.504958)
		(end 382.1684 -124.34824)
		(width 0.254)
		(layer "F.Cu")
		(net "GND")
	)
	(segment
		(start 283.212794 -100.481638)
		(end 282.925774 -99.986338)
		(width 0.254)
		(layer "F.Cu")
		(net "GND")
	)
	(segment
		(start 301.812706 -56.399938)
		(end 302.958246 -56.399938)
		(width 0.254)
		(layer "F.Cu")
		(net "GND")
	)
	(segment
		(start 445.400938 -113.816384)
		(end 445.399922 -113.8174)
		(width 0.4064)
		(layer "F.Cu")
		(net "GND")
	)
	(segment
		(start 232.0925 -56.58104)
		(end 232.0798 -56.56834)
		(width 0.254)
		(layer "F.Cu")
		(net "GND")
	)
	(segment
		(start 128.687576 -13.948156)
		(end 127.378968 -13.8938)
		(width 0.254)
		(layer "F.Cu")
		(net "GND")
	)
	(segment
		(start 196.219826 -69.626226)
		(end 196.219826 -69.324474)
		(width 0.254)
		(layer "F.Cu")
		(net "GND")
	)
	(segment
		(start 150.399496 -18.757646)
		(end 150.399496 -20.023582)
		(width 0.4064)
		(layer "F.Cu")
		(net "GND")
	)
	(segment
		(start 370.009674 -106.217466)
		(end 370.727986 -106.935778)
		(width 0.254)
		(layer "F.Cu")
		(net "GND")
	)
	(segment
		(start 180.594 -145.669)
		(end 180.594 -145.923)
		(width 0.254)
		(layer "F.Cu")
		(net "GND")
	)
	(segment
		(start 386.93725 -111.85525)
		(end 386.5372 -112.2553)
		(width 0.12446)
		(layer "F.Cu")
		(net "GND")
	)
	(segment
		(start 233.800396 -137.67054)
		(end 233.799888 -137.67054)
		(width 0.4064)
		(layer "F.Cu")
		(net "GND")
	)
	(segment
		(start 413.490156 -32.934656)
		(end 413.890206 -33.334706)
		(width 0.254)
		(layer "F.Cu")
		(net "GND")
	)
	(segment
		(start 447.942716 -60.6552)
		(end 447.942716 -60.378848)
		(width 0.381)
		(layer "F.Cu")
		(net "GND")
	)
	(segment
		(start 456.22718 -45.611796)
		(end 456.541124 -45.92574)
		(width 0.4064)
		(layer "F.Cu")
		(net "GND")
	)
	(segment
		(start 149.7711 -28.05176)
		(end 149.7711 -28.6258)
		(width 0.508)
		(layer "F.Cu")
		(net "GND")
	)
	(segment
		(start 379.81255 -100.41128)
		(end 380.30785 -100.181156)
		(width 0.254)
		(layer "F.Cu")
		(net "GND")
	)
	(segment
		(start 287.21812 -99.490784)
		(end 286.64662 -99.490784)
		(width 0.254)
		(layer "F.Cu")
		(net "GND")
	)
	(segment
		(start 15.494 -97.8916)
		(end 15.494 -97.282)
		(width 0.4064)
		(layer "F.Cu")
		(net "GND")
	)
	(segment
		(start 296.700448 -137.67054)
		(end 296.69994 -137.67054)
		(width 0.4064)
		(layer "F.Cu")
		(net "GND")
	)
	(segment
		(start 305.533806 -55.122318)
		(end 305.533806 -54.913784)
		(width 0.254)
		(layer "F.Cu")
		(net "GND")
	)
	(segment
		(start 96.938338 -91.25204)
		(end 96.366838 -91.25204)
		(width 0.254)
		(layer "F.Cu")
		(net "GND")
	)
	(segment
		(start 179.4002 -81.097628)
		(end 178.582828 -81.915)
		(width 0.254)
		(layer "F.Cu")
		(net "GND")
	)
	(segment
		(start 229.549706 -15.423896)
		(end 229.54996 -15.423642)
		(width 0.4064)
		(layer "F.Cu")
		(net "GND")
	)
	(segment
		(start 79.360268 -149.8092)
		(end 78.898496 -149.8092)
		(width 0.508)
		(layer "F.Cu")
		(net "GND")
	)
	(segment
		(start 208.299812 -6.558534)
		(end 208.299812 -5.822442)
		(width 0.3556)
		(layer "F.Cu")
		(net "GND")
	)
	(segment
		(start 378.344684 -68.695316)
		(end 377.944888 -69.095112)
		(width 0.254)
		(layer "F.Cu")
		(net "GND")
	)
	(segment
		(start 229.549706 -153.093674)
		(end 229.091236 -153.552144)
		(width 0.4064)
		(layer "F.Cu")
		(net "GND")
	)
	(segment
		(start 38.199568 -152.457912)
		(end 38.199314 -152.458166)
		(width 0.4064)
		(layer "F.Cu")
		(net "GND")
	)
	(segment
		(start 66.24955 -6.001512)
		(end 66.249296 -6.001766)
		(width 0.4064)
		(layer "F.Cu")
		(net "GND")
	)
	(segment
		(start 249.061224 -59.057286)
		(end 248.489724 -59.057286)
		(width 0.254)
		(layer "F.Cu")
		(net "GND")
	)
	(segment
		(start 276.344634 -93.547184)
		(end 276.916134 -93.547184)
		(width 0.1651)
		(layer "F.Cu")
		(net "GND")
	)
	(segment
		(start 397.64335 -98.69424)
		(end 397.7894 -98.626422)
		(width 0.254)
		(layer "F.Cu")
		(net "GND")
	)
	(segment
		(start 135.735568 2.819654)
		(end 135.735568 1.991868)
		(width 0.3556)
		(layer "F.Cu")
		(net "GND")
	)
	(segment
		(start 85.777832 -88.775286)
		(end 85.206332 -88.775286)
		(width 0.254)
		(layer "F.Cu")
		(net "GND")
	)
	(segment
		(start 272.910808 -95.528384)
		(end 273.482308 -95.528384)
		(width 0.254)
		(layer "F.Cu")
		(net "GND")
	)
	(segment
		(start 250.778264 -63.019686)
		(end 250.206764 -63.019686)
		(width 0.254)
		(layer "F.Cu")
		(net "GND")
	)
	(segment
		(start 282.354274 -61.352938)
		(end 281.782774 -61.352938)
		(width 0.254)
		(layer "F.Cu")
		(net "GND")
	)
	(segment
		(start 234.466638 -60.54344)
		(end 233.895138 -60.54344)
		(width 0.254)
		(layer "F.Cu")
		(net "GND")
	)
	(segment
		(start 457.252578 -141.719808)
		(end 455.507344 -141.719808)
		(width 0.254)
		(layer "F.Cu")
		(net "GND")
	)
	(segment
		(start 264.51433 -56.085486)
		(end 263.94283 -56.085486)
		(width 0.254)
		(layer "F.Cu")
		(net "GND")
	)
	(segment
		(start 345.408758 -12.28852)
		(end 345.277948 -12.41933)
		(width 0.2032)
		(layer "F.Cu")
		(net "GND")
	)
	(segment
		(start 72.900286 -101.15804)
		(end 72.328786 -101.15804)
		(width 0.254)
		(layer "F.Cu")
		(net "GND")
	)
	(segment
		(start 237.900718 -92.24264)
		(end 237.329218 -92.24264)
		(width 0.254)
		(layer "F.Cu")
		(net "GND")
	)
	(segment
		(start 218.499944 -11.854688)
		(end 218.44254 -11.912092)
		(width 0.4064)
		(layer "F.Cu")
		(net "GND")
	)
	(segment
		(start 82.343752 -65.000886)
		(end 81.772252 -65.000886)
		(width 0.254)
		(layer "F.Cu")
		(net "GND")
	)
	(segment
		(start 468.60079 -118.47195)
		(end 468.71382 -118.58498)
		(width 0.4064)
		(layer "F.Cu")
		(net "GND")
	)
	(segment
		(start 398.63395 -104.473756)
		(end 399.634964 -104.85501)
		(width 0.254)
		(layer "F.Cu")
		(net "GND")
	)
	(segment
		(start 237.900718 -97.19564)
		(end 237.329218 -97.19564)
		(width 0.254)
		(layer "F.Cu")
		(net "GND")
	)
	(segment
		(start 213.400386 -137.67054)
		(end 213.399878 -137.67054)
		(width 0.4064)
		(layer "F.Cu")
		(net "GND")
	)
	(segment
		(start 399.371058 -124.70638)
		(end 398.69872 -124.70638)
		(width 0.254)
		(layer "F.Cu")
		(net "GND")
	)
	(segment
		(start 234.649772 -15.423642)
		(end 234.649772 -17.110202)
		(width 0.4064)
		(layer "F.Cu")
		(net "GND")
	)
	(segment
		(start 445.0715 -35.8775)
		(end 444.9572 -35.9918)
		(width 0.4064)
		(layer "F.Cu")
		(net "GND")
	)
	(segment
		(start 127.44958 -147.27174)
		(end 127.44958 -146.06905)
		(width 0.3556)
		(layer "F.Cu")
		(net "GND")
	)
	(segment
		(start 396.470886 -3.355086)
		(end 396.470886 -4.386072)
		(width 0.254)
		(layer "F.Cu")
		(net "GND")
	)
	(segment
		(start 52.448968 -144.477994)
		(end 52.471574 -144.5006)
		(width 0.3556)
		(layer "F.Cu")
		(net "GND")
	)
	(segment
		(start 112.202722 -91.070938)
		(end 112.774222 -91.070938)
		(width 0.254)
		(layer "F.Cu")
		(net "GND")
	)
	(segment
		(start 454.757282 -63.35014)
		(end 454.757282 -63.626492)
		(width 0.381)
		(layer "F.Cu")
		(net "GND")
	)
	(segment
		(start 249.919744 -92.24264)
		(end 249.348244 -92.24264)
		(width 0.254)
		(layer "F.Cu")
		(net "GND")
	)
	(segment
		(start 397.56334 -130.37566)
		(end 398.73428 -131.5466)
		(width 0.4064)
		(layer "F.Cu")
		(net "GND")
	)
	(segment
		(start 164.4523 -124.5235)
		(end 164.9984 -125.0696)
		(width 0.254)
		(layer "F.Cu")
		(net "GND")
	)
	(segment
		(start 36.499546 -152.278842)
		(end 36.499292 -152.279096)
		(width 0.4064)
		(layer "F.Cu")
		(net "GND")
	)
	(segment
		(start 374.56491 -100.965)
		(end 374.0277 -100.965)
		(width 0.254)
		(layer "F.Cu")
		(net "GND")
	)
	(segment
		(start 236.349794 3.050794)
		(end 236.1184 2.8194)
		(width 0.3556)
		(layer "F.Cu")
		(net "GND")
	)
	(segment
		(start 288.36366 -100.481638)
		(end 288.93516 -100.481638)
		(width 0.254)
		(layer "F.Cu")
		(net "GND")
	)
	(segment
		(start 72.041766 -80.850486)
		(end 71.470266 -80.850486)
		(width 0.254)
		(layer "F.Cu")
		(net "GND")
	)
	(segment
		(start 411.672786 -8.849614)
		(end 411.4927 -9.0297)
		(width 0.254)
		(layer "F.Cu")
		(net "GND")
	)
	(segment
		(start 32.249364 -5.822442)
		(end 32.249364 -7.509002)
		(width 0.4064)
		(layer "F.Cu")
		(net "GND")
	)
	(segment
		(start 300.099984 -10.422382)
		(end 300.099984 -9.156446)
		(width 0.4064)
		(layer "F.Cu")
		(net "GND")
	)
	(segment
		(start 85.777832 -96.700086)
		(end 85.206332 -96.700086)
		(width 0.254)
		(layer "F.Cu")
		(net "GND")
	)
	(segment
		(start 241.44986 -21.517356)
		(end 241.44986 -20.023582)
		(width 0.4064)
		(layer "F.Cu")
		(net "GND")
	)
	(segment
		(start 76.334366 -59.55284)
		(end 75.762866 -59.55284)
		(width 0.254)
		(layer "F.Cu")
		(net "GND")
	)
	(segment
		(start 84.060792 -92.737686)
		(end 83.489292 -92.737686)
		(width 0.254)
		(layer "F.Cu")
		(net "GND")
	)
	(segment
		(start 281.495754 -61.847984)
		(end 280.924254 -61.847984)
		(width 0.254)
		(layer "F.Cu")
		(net "GND")
	)
	(segment
		(start 52.649374 -143.411194)
		(end 52.448968 -143.6116)
		(width 0.3048)
		(layer "F.Cu")
		(net "GND")
	)
	(segment
		(start 310.30037 -5.822442)
		(end 310.299862 -5.822442)
		(width 0.4064)
		(layer "F.Cu")
		(net "GND")
	)
	(segment
		(start 290.93922 -59.371484)
		(end 291.51072 -59.371484)
		(width 0.254)
		(layer "F.Cu")
		(net "GND")
	)
	(segment
		(start 262.79729 -53.113686)
		(end 262.22579 -53.113686)
		(width 0.254)
		(layer "F.Cu")
		(net "GND")
	)
	(segment
		(start 0.946658 -118.636034)
		(end 0.611378 -118.636034)
		(width 0.254)
		(layer "F.Cu")
		(net "GND")
	)
	(segment
		(start 396.984982 -125.33503)
		(end 397.0782 -125.428248)
		(width 0.254)
		(layer "F.Cu")
		(net "GND")
	)
	(segment
		(start 69.466206 -68.46824)
		(end 68.894706 -68.46824)
		(width 0.254)
		(layer "F.Cu")
		(net "GND")
	)
	(segment
		(start 110.485682 -92.061538)
		(end 111.057182 -92.061538)
		(width 0.254)
		(layer "F.Cu")
		(net "GND")
	)
	(segment
		(start 378.82195 -95.888556)
		(end 378.985018 -95.205042)
		(width 0.254)
		(layer "F.Cu")
		(net "GND")
	)
	(segment
		(start 51.79949 -2.276856)
		(end 51.79949 -0.821182)
		(width 0.4064)
		(layer "F.Cu")
		(net "GND")
	)
	(segment
		(start 156.610812 -3.321812)
		(end 157.503368 -3.321812)
		(width 0.4064)
		(layer "F.Cu")
		(net "GND")
	)
	(segment
		(start 133.39953 -137.67054)
		(end 133.39953 -136.397746)
		(width 0.4064)
		(layer "F.Cu")
		(net "GND")
	)
	(segment
		(start 229.087934 -4.346956)
		(end 227.840794 -4.346956)
		(width 0.254)
		(layer "F.Cu")
		(net "GND")
	)
	(segment
		(start 30.843982 -69.223382)
		(end 31.527496 -69.223382)
		(width 0.381)
		(layer "F.Cu")
		(net "GND")
	)
	(segment
		(start -0.500126 -45.310044)
		(end 0.933958 -43.87596)
		(width 0.508)
		(layer "F.Cu")
		(net "GND")
	)
	(segment
		(start 291.79774 -67.791584)
		(end 292.36924 -67.791584)
		(width 0.254)
		(layer "F.Cu")
		(net "GND")
	)
	(segment
		(start 234.560872 -4.6482)
		(end 234.560872 -3.737356)
		(width 0.4064)
		(layer "F.Cu")
		(net "GND")
	)
	(segment
		(start 218.499944 -10.422382)
		(end 218.499944 -11.854688)
		(width 0.4064)
		(layer "F.Cu")
		(net "GND")
	)
	(segment
		(start 113.726976 -154.23388)
		(end 113.849404 -154.111452)
		(width 0.4064)
		(layer "F.Cu")
		(net "GND")
	)
	(segment
		(start 315.399928 -0.821182)
		(end 315.399928 0.444754)
		(width 0.4064)
		(layer "F.Cu")
		(net "GND")
	)
	(segment
		(start 134.249414 -13.805154)
		(end 134.249414 -15.423642)
		(width 0.4064)
		(layer "F.Cu")
		(net "GND")
	)
	(segment
		(start 298.40047 -20.023582)
		(end 298.399962 -20.023582)
		(width 0.4064)
		(layer "F.Cu")
		(net "GND")
	)
	(segment
		(start 54.737508 -4.346956)
		(end 55.199534 -4.808982)
		(width 0.4064)
		(layer "F.Cu")
		(net "GND")
	)
	(segment
		(start 238.900462 -142.6718)
		(end 238.899954 -142.677642)
		(width 0.4064)
		(layer "F.Cu")
		(net "GND")
	)
	(segment
		(start 300.099984 -155.612846)
		(end 300.099984 -156.87294)
		(width 0.4064)
		(layer "F.Cu")
		(net "GND")
	)
	(segment
		(start 122.504708 -98.005138)
		(end 123.076208 -98.005138)
		(width 0.254)
		(layer "F.Cu")
		(net "GND")
	)
	(segment
		(start 84.919312 -61.53404)
		(end 84.347812 -61.53404)
		(width 0.254)
		(layer "F.Cu")
		(net "GND")
	)
	(segment
		(start 65.399412 -147.27174)
		(end 65.399412 -146.011646)
		(width 0.4064)
		(layer "F.Cu")
		(net "GND")
	)
	(segment
		(start 72.041766 -59.057286)
		(end 71.470266 -59.057286)
		(width 0.254)
		(layer "F.Cu")
		(net "GND")
	)
	(segment
		(start 317.09995 -149.813518)
		(end 317.146432 -149.86)
		(width 0.4064)
		(layer "F.Cu")
		(net "GND")
	)
	(segment
		(start 43.076368 -143.636746)
		(end 43.076368 -144.455388)
		(width 0.3556)
		(layer "F.Cu")
		(net "GND")
	)
	(segment
		(start 350.0628 -157.2768)
		(end 350.0628 -156.757624)
		(width 0.4064)
		(layer "F.Cu")
		(net "GND")
	)
	(segment
		(start 18.453862 -120.410224)
		(end 17.907 -119.863362)
		(width 0.508)
		(layer "F.Cu")
		(net "GND")
	)
	(segment
		(start 219.73794 -4.346956)
		(end 220.199966 -4.808982)
		(width 0.4064)
		(layer "F.Cu")
		(net "GND")
	)
	(segment
		(start 129.149348 -153.093674)
		(end 128.690878 -153.552144)
		(width 0.4064)
		(layer "F.Cu")
		(net "GND")
	)
	(segment
		(start 391.3378 -106.6546)
		(end 391.73785 -107.05465)
		(width 0.12446)
		(layer "F.Cu")
		(net "GND")
	)
	(segment
		(start 366.2172 -93.0656)
		(end 366.2172 -93.3831)
		(width 0.254)
		(layer "F.Cu")
		(net "GND")
	)
	(segment
		(start 49.249584 -5.822442)
		(end 49.249584 -3.76301)
		(width 0.4064)
		(layer "F.Cu")
		(net "GND")
	)
	(segment
		(start 381.29845 -108.13796)
		(end 381.4064 -108.087668)
		(width 0.254)
		(layer "F.Cu")
		(net "GND")
	)
	(segment
		(start 263.65581 -63.51524)
		(end 263.08431 -63.51524)
		(width 0.254)
		(layer "F.Cu")
		(net "GND")
	)
	(segment
		(start 129.372868 -81.164938)
		(end 129.944368 -81.164938)
		(width 0.254)
		(layer "F.Cu")
		(net "GND")
	)
	(segment
		(start 95.451168 -1.651)
		(end 95.51924 -1.582928)
		(width 0.254)
		(layer "F.Cu")
		(net "GND")
	)
	(segment
		(start 138.816334 -64.819784)
		(end 139.387834 -64.819784)
		(width 0.254)
		(layer "F.Cu")
		(net "GND")
	)
	(segment
		(start 369.891818 -101.1174)
		(end 370.594382 -100.414836)
		(width 0.254)
		(layer "F.Cu")
		(net "GND")
	)
	(segment
		(start 216.799922 -18.757646)
		(end 216.799922 -20.023582)
		(width 0.4064)
		(layer "F.Cu")
		(net "GND")
	)
	(segment
		(start 317.09995 -10.422382)
		(end 317.09995 -11.927078)
		(width 0.4064)
		(layer "F.Cu")
		(net "GND")
	)
	(segment
		(start 392.470386 -7.128256)
		(end 392.470386 -7.789672)
		(width 0.254)
		(layer "F.Cu")
		(net "GND")
	)
	(segment
		(start 175.14316 -80.1116)
		(end 175.80356 -80.772)
		(width 0.254)
		(layer "F.Cu")
		(net "GND")
	)
	(segment
		(start 58.599324 -3.762756)
		(end 58.599578 -3.76301)
		(width 0.4064)
		(layer "F.Cu")
		(net "GND")
	)
	(segment
		(start 52.471574 -3.762756)
		(end 52.649374 -3.940556)
		(width 0.4064)
		(layer "F.Cu")
		(net "GND")
	)
	(segment
		(start 208.299812 -153.014934)
		(end 208.0768 -153.237946)
		(width 0.3556)
		(layer "F.Cu")
		(net "GND")
	)
	(segment
		(start 392.43 -102.87762)
		(end 392.19505 -102.98684)
		(width 0.254)
		(layer "F.Cu")
		(net "GND")
	)
	(segment
		(start 451.733158 -50.6222)
		(end 451.732396 -50.5206)
		(width 0.508)
		(layer "F.Cu")
		(net "GND")
	)
	(segment
		(start 472.57081 -141.608048)
		(end 472.228418 -141.95044)
		(width 0.254)
		(layer "F.Cu")
		(net "GND")
	)
	(segment
		(start 289.79368 -89.089738)
		(end 289.22218 -89.089738)
		(width 0.254)
		(layer "F.Cu")
		(net "GND")
	)
	(segment
		(start 212.54974 -142.856966)
		(end 212.54974 -144.462246)
		(width 0.4064)
		(layer "F.Cu")
		(net "GND")
	)
	(segment
		(start 248.202704 -76.39304)
		(end 247.631204 -76.39304)
		(width 0.254)
		(layer "F.Cu")
		(net "GND")
	)
	(segment
		(start 246.485664 -74.411586)
		(end 245.914164 -74.411586)
		(width 0.254)
		(layer "F.Cu")
		(net "GND")
	)
	(segment
		(start 238.759238 -91.747086)
		(end 238.187738 -91.747086)
		(width 0.254)
		(layer "F.Cu")
		(net "GND")
	)
	(segment
		(start 220.200474 -5.822442)
		(end 220.199966 -5.822442)
		(width 0.4064)
		(layer "F.Cu")
		(net "GND")
	)
	(segment
		(start 76.334366 -57.57164)
		(end 75.762866 -57.57164)
		(width 0.254)
		(layer "F.Cu")
		(net "GND")
	)
	(segment
		(start 138.816334 -100.689664)
		(end 138.529314 -100.976684)
		(width 0.4064)
		(layer "F.Cu")
		(net "GND")
	)
	(segment
		(start 87.494872 -83.822286)
		(end 86.923372 -83.822286)
		(width 0.254)
		(layer "F.Cu")
		(net "GND")
	)
	(segment
		(start 462.980532 -138.719814)
		(end 464.424014 -138.719814)
		(width 0.254)
		(layer "F.Cu")
		(net "GND")
	)
	(segment
		(start 399.634964 -106.855006)
		(end 399.634964 -105.855008)
		(width 0.254)
		(layer "F.Cu")
		(net "GND")
	)
	(segment
		(start 218.499944 -155.67025)
		(end 218.44254 -155.612846)
		(width 0.3556)
		(layer "F.Cu")
		(net "GND")
	)
	(segment
		(start 224.450402 -10.422382)
		(end 224.449894 -10.422382)
		(width 0.4064)
		(layer "F.Cu")
		(net "GND")
	)
	(segment
		(start 137.099294 -69.772784)
		(end 137.670794 -69.772784)
		(width 0.254)
		(layer "F.Cu")
		(net "GND")
	)
	(segment
		(start 404.471886 -7.789672)
		(end 404.471886 -9.522714)
		(width 0.254)
		(layer "F.Cu")
		(net "GND")
	)
	(segment
		(start 28.194 -92.7862)
		(end 28.448 -93.0402)
		(width 0.254)
		(layer "F.Cu")
		(net "GND")
	)
	(segment
		(start 81.485232 -91.25204)
		(end 80.913732 -91.25204)
		(width 0.254)
		(layer "F.Cu")
		(net "GND")
	)
	(segment
		(start 242.193318 -50.141886)
		(end 242.193318 -49.991518)
		(width 0.254)
		(layer "F.Cu")
		(net "GND")
	)
	(segment
		(start 119.799354 3.778758)
		(end 119.7991 3.778504)
		(width 0.4064)
		(layer "F.Cu")
		(net "GND")
	)
	(segment
		(start 385.977638 -115.438428)
		(end 385.719828 -115.438428)
		(width 0.1143)
		(layer "F.Cu")
		(net "GND")
	)
	(segment
		(start 280.637234 -98.995738)
		(end 281.208734 -98.995738)
		(width 0.254)
		(layer "F.Cu")
		(net "GND")
	)
	(segment
		(start 217.649806 -142.677642)
		(end 217.649806 -143.411194)
		(width 0.3048)
		(layer "F.Cu")
		(net "GND")
	)
	(segment
		(start 237.042198 -92.737686)
		(end 236.470698 -92.737686)
		(width 0.254)
		(layer "F.Cu")
		(net "GND")
	)
	(segment
		(start 243.149882 -139.2428)
		(end 243.15039 -139.242292)
		(width 0.508)
		(layer "F.Cu")
		(net "GND")
	)
	(segment
		(start 301.800006 -136.46785)
		(end 301.742602 -136.410446)
		(width 0.3556)
		(layer "F.Cu")
		(net "GND")
	)
	(segment
		(start 0.567436 -144.534636)
		(end 0 -143.9672)
		(width 0.254)
		(layer "F.Cu")
		(net "GND")
	)
	(segment
		(start 386.644388 -109.747812)
		(end 386.93725 -109.45495)
		(width 0.12446)
		(layer "F.Cu")
		(net "GND")
	)
	(segment
		(start 447.800984 -112.205516)
		(end 447.800984 -113.775236)
		(width 0.4064)
		(layer "F.Cu")
		(net "GND")
	)
	(segment
		(start 134.249414 -3.826256)
		(end 134.249414 -5.822442)
		(width 0.4064)
		(layer "F.Cu")
		(net "GND")
	)
	(segment
		(start 393.68095 -101.039676)
		(end 393.18565 -101.2698)
		(width 0.254)
		(layer "F.Cu")
		(net "GND")
	)
	(segment
		(start 275.486114 -98.005138)
		(end 276.057614 -98.005138)
		(width 0.254)
		(layer "F.Cu")
		(net "GND")
	)
	(segment
		(start 208.0768 -134.854188)
		(end 208.122012 -134.8994)
		(width 0.3556)
		(layer "F.Cu")
		(net "GND")
	)
	(segment
		(start 436.7403 -21.9964)
		(end 436.4228 -21.9964)
		(width 0.254)
		(layer "F.Cu")
		(net "GND")
	)
	(segment
		(start 141.391894 -70.059804)
		(end 141.391894 -70.268084)
		(width 0.254)
		(layer "F.Cu")
		(net "GND")
	)
	(segment
		(start 30.816296 -53.1368)
		(end 31.2674 -53.1368)
		(width 0.4064)
		(layer "F.Cu")
		(net "GND")
	)
	(segment
		(start 126.797308 -69.772784)
		(end 127.368808 -69.772784)
		(width 0.254)
		(layer "F.Cu")
		(net "GND")
	)
	(segment
		(start 235.46181 -11.916156)
		(end 235.49991 -11.878056)
		(width 0.4064)
		(layer "F.Cu")
		(net "GND")
	)
	(segment
		(start 393.6873 -115.240308)
		(end 393.684252 -115.243356)
		(width 0.254)
		(layer "F.Cu")
		(net "GND")
	)
	(segment
		(start 70.499478 -2.276856)
		(end 70.499478 -0.821182)
		(width 0.4064)
		(layer "F.Cu")
		(net "GND")
	)
	(segment
		(start 433.07 -13.947394)
		(end 433.409344 -13.60805)
		(width 0.254)
		(layer "F.Cu")
		(net "GND")
	)
	(segment
		(start 291.79774 -56.894984)
		(end 292.36924 -56.894984)
		(width 0.254)
		(layer "F.Cu")
		(net "GND")
	)
	(segment
		(start 180.9242 -57.8866)
		(end 180.9242 -57.785)
		(width 0.381)
		(layer "F.Cu")
		(net "GND")
	)
	(segment
		(start 48.399446 -2.314956)
		(end 48.399446 -0.821182)
		(width 0.4064)
		(layer "F.Cu")
		(net "GND")
	)
	(segment
		(start 393.18565 -102.98684)
		(end 392.69035 -102.756716)
		(width 0.254)
		(layer "F.Cu")
		(net "GND")
	)
	(segment
		(start 255.92913 -85.803486)
		(end 255.35763 -85.803486)
		(width 0.254)
		(layer "F.Cu")
		(net "GND")
	)
	(segment
		(start 387.484874 -124.919994)
		(end 387.484874 -125.750066)
		(width 0.254)
		(layer "F.Cu")
		(net "GND")
	)
	(segment
		(start 133.39953 -156.87294)
		(end 133.39953 -155.600146)
		(width 0.4064)
		(layer "F.Cu")
		(net "GND")
	)
	(segment
		(start 33.099502 -11.878056)
		(end 33.099502 -10.422382)
		(width 0.4064)
		(layer "F.Cu")
		(net "GND")
	)
	(segment
		(start 286.499808 -15.423642)
		(end 286.499808 -13.363956)
		(width 0.4064)
		(layer "F.Cu")
		(net "GND")
	)
	(segment
		(start 31.400496 -77.351382)
		(end 30.766004 -77.351382)
		(width 0.508)
		(layer "F.Cu")
		(net "GND")
	)
	(segment
		(start 235.325158 -88.775286)
		(end 234.753658 -88.775286)
		(width 0.254)
		(layer "F.Cu")
		(net "GND")
	)
	(segment
		(start 125.080268 -72.744584)
		(end 125.651768 -72.744584)
		(width 0.254)
		(layer "F.Cu")
		(net "GND")
	)
	(segment
		(start 474.218762 -39.805102)
		(end 473.3925 -40.631364)
		(width 0.254)
		(layer "F.Cu")
		(net "GND")
	)
	(segment
		(start 310.122062 -3.762756)
		(end 310.299862 -3.940556)
		(width 0.4064)
		(layer "F.Cu")
		(net "GND")
	)
	(segment
		(start 435.675786 -9.042908)
		(end 435.675786 -7.789672)
		(width 0.254)
		(layer "F.Cu")
		(net "GND")
	)
	(segment
		(start 68.607686 -84.812886)
		(end 68.036186 -84.812886)
		(width 0.254)
		(layer "F.Cu")
		(net "GND")
	)
	(segment
		(start 307.749956 -156.87294)
		(end 307.750464 -156.87294)
		(width 0.4064)
		(layer "F.Cu")
		(net "GND")
	)
	(segment
		(start 377.98502 -125.33503)
		(end 377.98502 -126.101348)
		(width 0.254)
		(layer "F.Cu")
		(net "GND")
	)
	(segment
		(start 221.899988 -6.001512)
		(end 221.899734 -6.001766)
		(width 0.4064)
		(layer "F.Cu")
		(net "GND")
	)
	(segment
		(start 235.49991 -18.795746)
		(end 235.49991 -20.023582)
		(width 0.4064)
		(layer "F.Cu")
		(net "GND")
	)
	(segment
		(start 121.646188 -53.923184)
		(end 121.074688 -53.923184)
		(width 0.254)
		(layer "F.Cu")
		(net "GND")
	)
	(segment
		(start 436.921656 -24.7777)
		(end 436.921656 -25.0317)
		(width 0.3048)
		(layer "F.Cu")
		(net "GND")
	)
	(segment
		(start 290.74999 -18.757646)
		(end 290.74999 -20.023582)
		(width 0.4064)
		(layer "F.Cu")
		(net "GND")
	)
	(segment
		(start 226.7966 -153.213054)
		(end 226.7966 -154.0764)
		(width 0.3556)
		(layer "F.Cu")
		(net "GND")
	)
	(segment
		(start 499.501668 -45.619924)
		(end 496.704874 -45.619924)
		(width 0.254)
		(layer "F.Cu")
		(net "GND")
	)
	(segment
		(start 27.549348 -79.882492)
		(end 27.88158 -79.55026)
		(width 0.254)
		(layer "F.Cu")
		(net "GND")
	)
	(segment
		(start 122.504708 -94.042738)
		(end 123.076208 -94.042738)
		(width 0.3048)
		(layer "F.Cu")
		(net "GND")
	)
	(segment
		(start 447.800984 -113.775236)
		(end 447.799968 -113.776252)
		(width 0.4064)
		(layer "F.Cu")
		(net "GND")
	)
	(segment
		(start 465.003388 -147.719796)
		(end 462.980278 -147.719796)
		(width 0.254)
		(layer "F.Cu")
		(net "GND")
	)
	(segment
		(start 467.74735 -53.20665)
		(end 467.742016 -52.2478)
		(width 0.4064)
		(layer "F.Cu")
		(net "GND")
	)
	(segment
		(start 61.149484 -18.757646)
		(end 61.149484 -20.023582)
		(width 0.4064)
		(layer "F.Cu")
		(net "GND")
	)
	(segment
		(start 277.203154 -64.324738)
		(end 276.631654 -64.324738)
		(width 0.254)
		(layer "F.Cu")
		(net "GND")
	)
	(segment
		(start 34.799524 -136.680702)
		(end 34.74212 -136.623298)
		(width 0.4064)
		(layer "F.Cu")
		(net "GND")
	)
	(segment
		(start 13.843 -90.0684)
		(end 13.2334 -90.0684)
		(width 0.254)
		(layer "F.Cu")
		(net "GND")
	)
	(segment
		(start 66.24955 -5.822442)
		(end 66.24955 -6.001512)
		(width 0.4064)
		(layer "F.Cu")
		(net "GND")
	)
	(segment
		(start 152.099518 -0.821182)
		(end 152.099518 -2.325878)
		(width 0.4064)
		(layer "F.Cu")
		(net "GND")
	)
	(segment
		(start 72.041766 -100.662486)
		(end 71.470266 -100.662486)
		(width 0.254)
		(layer "F.Cu")
		(net "GND")
	)
	(segment
		(start 124.221748 -89.089738)
		(end 124.793248 -89.089738)
		(width 0.254)
		(layer "F.Cu")
		(net "GND")
	)
	(segment
		(start 473.0877 -41.5925)
		(end 473.3925 -41.5925)
		(width 0.254)
		(layer "F.Cu")
		(net "GND")
	)
	(segment
		(start 296.948606 -101.471984)
		(end 297.520106 -101.471984)
		(width 0.3048)
		(layer "F.Cu")
		(net "GND")
	)
	(segment
		(start 410.711904 -38.9128)
		(end 410.6926 -38.9128)
		(width 0.254)
		(layer "F.Cu")
		(net "GND")
	)
	(segment
		(start 113.919762 -96.023938)
		(end 114.491262 -96.023938)
		(width 0.254)
		(layer "F.Cu")
		(net "GND")
	)
	(segment
		(start 241.334798 -92.24264)
		(end 240.763298 -92.24264)
		(width 0.254)
		(layer "F.Cu")
		(net "GND")
	)
	(segment
		(start 144.449546 -21.479256)
		(end 144.411446 -21.517356)
		(width 0.4064)
		(layer "F.Cu")
		(net "GND")
	)
	(segment
		(start 83.202272 -69.45884)
		(end 82.630772 -69.45884)
		(width 0.254)
		(layer "F.Cu")
		(net "GND")
	)
	(segment
		(start 247.344184 -65.991486)
		(end 246.772684 -65.991486)
		(width 0.254)
		(layer "F.Cu")
		(net "GND")
	)
	(segment
		(start 446.605406 -31.3055)
		(end 446.453006 -31.4579)
		(width 0.3556)
		(layer "F.Cu")
		(net "GND")
	)
	(segment
		(start 137.957814 -73.240138)
		(end 138.529314 -73.240138)
		(width 0.254)
		(layer "F.Cu")
		(net "GND")
	)
	(segment
		(start 385.26085 -116.72316)
		(end 385.75615 -116.953284)
		(width 0.254)
		(layer "F.Cu")
		(net "GND")
	)
	(segment
		(start 275.486114 -54.418738)
		(end 274.914614 -54.418738)
		(width 0.254)
		(layer "F.Cu")
		(net "GND")
	)
	(segment
		(start 297.549824 -7.607046)
		(end 297.549824 -5.822442)
		(width 0.4064)
		(layer "F.Cu")
		(net "GND")
	)
	(segment
		(start 277.203154 -93.052138)
		(end 277.774654 -93.052138)
		(width 0.254)
		(layer "F.Cu")
		(net "GND")
	)
	(segment
		(start 385.11988 -115.27282)
		(end 384.75412 -115.27282)
		(width 0.12446)
		(layer "F.Cu")
		(net "GND")
	)
	(segment
		(start 209.092546 -136.448546)
		(end 209.092546 -136.397746)
		(width 0.4064)
		(layer "F.Cu")
		(net "GND")
	)
	(segment
		(start 55.199534 -14.410182)
		(end 55.199534 -15.423642)
		(width 0.4064)
		(layer "F.Cu")
		(net "GND")
	)
	(segment
		(start 129.149348 3.778758)
		(end 129.149348 2.963926)
		(width 0.4064)
		(layer "F.Cu")
		(net "GND")
	)
	(segment
		(start 113.849404 -137.676382)
		(end 113.849404 -137.67054)
		(width 0.4064)
		(layer "F.Cu")
		(net "GND")
	)
	(segment
		(start 67.099434 0.444754)
		(end 67.099434 -0.821182)
		(width 0.4064)
		(layer "F.Cu")
		(net "GND")
	)
	(segment
		(start 314.54979 -17.208246)
		(end 314.54979 -15.423642)
		(width 0.4064)
		(layer "F.Cu")
		(net "GND")
	)
	(segment
		(start 406.072086 -2.669286)
		(end 405.8158 -2.413)
		(width 0.254)
		(layer "F.Cu")
		(net "GND")
	)
	(segment
		(start 85.761068 -149.8092)
		(end 84.910168 -149.8092)
		(width 0.4064)
		(layer "F.Cu")
		(net "GND")
	)
	(segment
		(start 102.947724 -95.709486)
		(end 102.376224 -95.709486)
		(width 0.254)
		(layer "F.Cu")
		(net "GND")
	)
	(segment
		(start 28.7274 -59.617102)
		(end 28.7274 -60.203588)
		(width 0.254)
		(layer "F.Cu")
		(net "GND")
	)
	(segment
		(start 113.919762 -89.089738)
		(end 114.491262 -89.089738)
		(width 0.254)
		(layer "F.Cu")
		(net "GND")
	)
	(segment
		(start 376.335036 -97.855024)
		(end 376.428 -98.354896)
		(width 0.254)
		(layer "F.Cu")
		(net "GND")
	)
	(segment
		(start 402.0566 -83.6549)
		(end 401.391882 -83.6549)
		(width 0.254)
		(layer "F.Cu")
		(net "GND")
	)
	(segment
		(start 384.27025 -97.83572)
		(end 384.76555 -97.605596)
		(width 0.254)
		(layer "F.Cu")
		(net "GND")
	)
	(segment
		(start 28.448 -93.0402)
		(end 28.6004 -93.0402)
		(width 0.254)
		(layer "F.Cu")
		(net "GND")
	)
	(segment
		(start 394.67155 -110.71352)
		(end 395.16685 -110.943644)
		(width 0.254)
		(layer "F.Cu")
		(net "GND")
	)
	(segment
		(start 117.015768 2.819146)
		(end 117.015768 2.01168)
		(width 0.3556)
		(layer "F.Cu")
		(net "GND")
	)
	(segment
		(start 233.799888 -0.821182)
		(end 233.799888 0.457454)
		(width 0.4064)
		(layer "F.Cu")
		(net "GND")
	)
	(segment
		(start 45.84954 -142.6718)
		(end 45.84954 -142.677642)
		(width 0.4064)
		(layer "F.Cu")
		(net "GND")
	)
	(segment
		(start 128.514348 -58.876438)
		(end 129.085848 -58.876438)
		(width 0.254)
		(layer "F.Cu")
		(net "GND")
	)
	(segment
		(start 311.15 -155.67025)
		(end 311.15 -156.87294)
		(width 0.3556)
		(layer "F.Cu")
		(net "GND")
	)
	(segment
		(start 388.984998 -124.504958)
		(end 389.306054 -124.206)
		(width 0.254)
		(layer "F.Cu")
		(net "GND")
	)
	(segment
		(start 126.599442 -142.6718)
		(end 126.599442 -143.400526)
		(width 0.3556)
		(layer "F.Cu")
		(net "GND")
	)
	(segment
		(start 311.150508 -137.67054)
		(end 311.15 -137.67054)
		(width 0.3556)
		(layer "F.Cu")
		(net "GND")
	)
	(segment
		(start 175.793146 -147.955)
		(end 175.18126 -147.955)
		(width 0.254)
		(layer "F.Cu")
		(net "GND")
	)
	(segment
		(start 109.891322 -67.185032)
		(end 109.82325 -67.253104)
		(width 0.254)
		(layer "F.Cu")
		(net "GND")
	)
	(segment
		(start 208.0768 -16.382746)
		(end 208.299812 -16.159734)
		(width 0.3556)
		(layer "F.Cu")
		(net "GND")
	)
	(segment
		(start 246.485664 -57.57164)
		(end 245.914164 -57.57164)
		(width 0.254)
		(layer "F.Cu")
		(net "GND")
	)
	(segment
		(start 239.749838 -155.511246)
		(end 239.749838 -156.87294)
		(width 0.4064)
		(layer "F.Cu")
		(net "GND")
	)
	(segment
		(start 221.900496 -15.423642)
		(end 221.899988 -15.423642)
		(width 0.4064)
		(layer "F.Cu")
		(net "GND")
	)
	(segment
		(start 302.118268 -102.481126)
		(end 302.118268 -103.363268)
		(width 0.2032)
		(layer "F.Cu")
		(net "GND")
	)
	(segment
		(start 207.449928 -2.276856)
		(end 207.449928 -0.821182)
		(width 0.4064)
		(layer "F.Cu")
		(net "GND")
	)
	(segment
		(start 468.4014 -139.954)
		(end 467.999572 -139.954)
		(width 0.254)
		(layer "F.Cu")
		(net "GND")
	)
	(segment
		(start 77.299566 -15.423642)
		(end 77.299312 -15.423896)
		(width 0.4064)
		(layer "F.Cu")
		(net "GND")
	)
	(segment
		(start 225.300286 -152.273)
		(end 225.299778 -152.278842)
		(width 0.4064)
		(layer "F.Cu")
		(net "GND")
	)
	(segment
		(start 240.599976 -15.423642)
		(end 240.599976 -13.36421)
		(width 0.4064)
		(layer "F.Cu")
		(net "GND")
	)
	(segment
		(start 139.674854 -63.334138)
		(end 140.246354 -63.334138)
		(width 0.254)
		(layer "F.Cu")
		(net "GND")
	)
	(segment
		(start 198.099934 -20.023582)
		(end 198.099934 -18.757646)
		(width 0.4064)
		(layer "F.Cu")
		(net "GND")
	)
	(segment
		(start 237.900718 -64.50584)
		(end 237.329218 -64.50584)
		(width 0.254)
		(layer "F.Cu")
		(net "GND")
	)
	(segment
		(start 87.494872 -81.841086)
		(end 86.923372 -81.841086)
		(width 0.254)
		(layer "F.Cu")
		(net "GND")
	)
	(segment
		(start 237.900718 -54.59984)
		(end 237.329218 -54.59984)
		(width 0.254)
		(layer "F.Cu")
		(net "GND")
	)
	(segment
		(start 298.399962 -147.27174)
		(end 298.399962 -145.998946)
		(width 0.4064)
		(layer "F.Cu")
		(net "GND")
	)
	(segment
		(start 317.09995 3.778758)
		(end 317.09995 2.514854)
		(width 0.4064)
		(layer "F.Cu")
		(net "GND")
	)
	(segment
		(start 33.949386 3.778758)
		(end 33.949386 3.065018)
		(width 0.3556)
		(layer "F.Cu")
		(net "GND")
	)
	(segment
		(start 249.061224 -95.709486)
		(end 248.489724 -95.709486)
		(width 0.254)
		(layer "F.Cu")
		(net "GND")
	)
	(segment
		(start 399.634964 -109.855)
		(end 399.634964 -110.854998)
		(width 0.254)
		(layer "F.Cu")
		(net "GND")
	)
	(segment
		(start 102.089204 -89.27084)
		(end 101.517704 -89.27084)
		(width 0.254)
		(layer "F.Cu")
		(net "GND")
	)
	(segment
		(start 284.071314 -93.052138)
		(end 284.642814 -93.052138)
		(width 0.254)
		(layer "F.Cu")
		(net "GND")
	)
	(segment
		(start 296.69994 -155.612846)
		(end 296.69994 -156.87294)
		(width 0.4064)
		(layer "F.Cu")
		(net "GND")
	)
	(segment
		(start 399.693892 -126.18466)
		(end 399.674334 -126.165102)
		(width 0.254)
		(layer "F.Cu")
		(net "GND")
	)
	(segment
		(start 75.475846 -100.662486)
		(end 74.904346 -100.662486)
		(width 0.254)
		(layer "F.Cu")
		(net "GND")
	)
	(segment
		(start 30.656784 -93.625162)
		(end 31.463234 -93.625162)
		(width 0.508)
		(layer "F.Cu")
		(net "GND")
	)
	(segment
		(start 245.627144 -61.038486)
		(end 245.055644 -61.038486)
		(width 0.254)
		(layer "F.Cu")
		(net "GND")
	)
	(segment
		(start 272.910808 -100.481638)
		(end 272.624042 -100.977192)
		(width 0.254)
		(layer "F.Cu")
		(net "GND")
	)
	(segment
		(start 217.4494 2.8448)
		(end 217.4494 2.667)
		(width 0.3048)
		(layer "F.Cu")
		(net "GND")
	)
	(segment
		(start 437.690006 -41.219374)
		(end 437.690006 -40.5257)
		(width 0.3556)
		(layer "F.Cu")
		(net "GND")
	)
	(segment
		(start 125.080268 -86.612984)
		(end 125.651768 -86.612984)
		(width 0.254)
		(layer "F.Cu")
		(net "GND")
	)
	(segment
		(start 136.240774 -96.023938)
		(end 136.812274 -96.023938)
		(width 0.254)
		(layer "F.Cu")
		(net "GND")
	)
	(segment
		(start 383.4765 -115.5954)
		(end 383.50571 -115.5954)
		(width 0.12446)
		(layer "F.Cu")
		(net "GND")
	)
	(segment
		(start 469.632792 -42.785792)
		(end 468.925402 -42.785792)
		(width 0.254)
		(layer "F.Cu")
		(net "GND")
	)
	(segment
		(start 166.3192 -123.22302)
		(end 165.66642 -123.22302)
		(width 0.254)
		(layer "F.Cu")
		(net "GND")
	)
	(segment
		(start 135.949436 -153.024078)
		(end 135.735568 -153.237946)
		(width 0.3556)
		(layer "F.Cu")
		(net "GND")
	)
	(segment
		(start 72.142096 0.444754)
		(end 72.142096 0.457454)
		(width 0.3556)
		(layer "F.Cu")
		(net "GND")
	)
	(segment
		(start 232.099866 -156.87294)
		(end 232.100374 -156.87294)
		(width 0.4064)
		(layer "F.Cu")
		(net "GND")
	)
	(segment
		(start 78.051406 -55.59044)
		(end 77.479906 -55.59044)
		(width 0.254)
		(layer "F.Cu")
		(net "GND")
	)
	(segment
		(start 488.1372 -148.8694)
		(end 488.1626 -148.8948)
		(width 0.254)
		(layer "F.Cu")
		(net "GND")
	)
	(segment
		(start 65.399412 -2.314956)
		(end 65.399412 -0.821182)
		(width 0.4064)
		(layer "F.Cu")
		(net "GND")
	)
	(segment
		(start 248.202704 -86.29904)
		(end 247.631204 -86.29904)
		(width 0.254)
		(layer "F.Cu")
		(net "GND")
	)
	(segment
		(start 216.799922 -156.87294)
		(end 216.799922 -155.612846)
		(width 0.4064)
		(layer "F.Cu")
		(net "GND")
	)
	(segment
		(start 386.13715 -111.85525)
		(end 386.430012 -111.562388)
		(width 0.12446)
		(layer "F.Cu")
		(net "GND")
	)
	(segment
		(start 142.749524 -10.422382)
		(end 142.749524 -9.143746)
		(width 0.4064)
		(layer "F.Cu")
		(net "GND")
	)
	(segment
		(start 261.27202 -12.961112)
		(end 261.27202 -11.65098)
		(width 0.4064)
		(layer "F.Cu")
		(net "GND")
	)
	(segment
		(start 458.933296 -50.562002)
		(end 458.940916 -50.569622)
		(width 0.508)
		(layer "F.Cu")
		(net "GND")
	)
	(segment
		(start 380.41072 -157.247336)
		(end 381.33655 -156.321506)
		(width 0.254)
		(layer "F.Cu")
		(net "GND")
	)
	(segment
		(start 292.65626 -80.174338)
		(end 293.22776 -80.174338)
		(width 0.254)
		(layer "F.Cu")
		(net "GND")
	)
	(segment
		(start 401.521168 -94.352872)
		(end 401.99564 -93.8784)
		(width 0.254)
		(layer "F.Cu")
		(net "GND")
	)
	(segment
		(start 396.15745 -99.55276)
		(end 396.65275 -99.322636)
		(width 0.254)
		(layer "F.Cu")
		(net "GND")
	)
	(segment
		(start 271.193768 -51.941984)
		(end 270.571468 -51.941984)
		(width 0.254)
		(layer "F.Cu")
		(net "GND")
	)
	(segment
		(start 279.778714 -94.538038)
		(end 280.350214 -94.538038)
		(width 0.254)
		(layer "F.Cu")
		(net "GND")
	)
	(segment
		(start 237.199932 -156.87294)
		(end 237.20044 -156.87294)
		(width 0.3556)
		(layer "F.Cu")
		(net "GND")
	)
	(segment
		(start 376.335036 -103.855012)
		(end 376.402092 -104.215692)
		(width 0.254)
		(layer "F.Cu")
		(net "GND")
	)
	(segment
		(start 234.649772 -17.110202)
		(end 234.551728 -17.208246)
		(width 0.4064)
		(layer "F.Cu")
		(net "GND")
	)
	(segment
		(start 232.099866 -155.562046)
		(end 232.099866 -156.87294)
		(width 0.4064)
		(layer "F.Cu")
		(net "GND")
	)
	(segment
		(start 382.93675 -105.45445)
		(end 383.3368 -105.0544)
		(width 0.12446)
		(layer "F.Cu")
		(net "GND")
	)
	(segment
		(start 79.768192 -60.54344)
		(end 79.196692 -60.54344)
		(width 0.254)
		(layer "F.Cu")
		(net "GND")
	)
	(segment
		(start 236.349794 -15.423642)
		(end 236.349794 -13.541756)
		(width 0.4064)
		(layer "F.Cu")
		(net "GND")
	)
	(segment
		(start 87.494872 -68.963286)
		(end 86.923372 -68.963286)
		(width 0.254)
		(layer "F.Cu")
		(net "GND")
	)
	(segment
		(start 213.400386 -10.422382)
		(end 213.399878 -10.422382)
		(width 0.4064)
		(layer "F.Cu")
		(net "GND")
	)
	(segment
		(start 140.533374 -62.838584)
		(end 141.104874 -62.838584)
		(width 0.254)
		(layer "F.Cu")
		(net "GND")
	)
	(segment
		(start 393.68095 -103.84536)
		(end 394.17625 -103.615236)
		(width 0.254)
		(layer "F.Cu")
		(net "GND")
	)
	(segment
		(start 107.051856 -51.446938)
		(end 107.051856 -50.694082)
		(width 0.254)
		(layer "F.Cu")
		(net "GND")
	)
	(segment
		(start 430.875186 -7.789672)
		(end 430.875186 -9.607296)
		(width 0.254)
		(layer "F.Cu")
		(net "GND")
	)
	(segment
		(start 398.903444 -126.566676)
		(end 398.53743 -126.93269)
		(width 0.254)
		(layer "F.Cu")
		(net "GND")
	)
	(segment
		(start 415.47288 -49.421542)
		(end 415.318448 -49.575974)
		(width 0.254)
		(layer "F.Cu")
		(net "GND")
	)
	(segment
		(start 120.649492 -2.314956)
		(end 120.649492 -0.821182)
		(width 0.4064)
		(layer "F.Cu")
		(net "GND")
	)
	(segment
		(start 454.62698 -45.560996)
		(end 454.141078 -46.046898)
		(width 0.4064)
		(layer "F.Cu")
		(net "GND")
	)
	(segment
		(start 283.099764 -11.854688)
		(end 283.04236 -11.912092)
		(width 0.4064)
		(layer "F.Cu")
		(net "GND")
	)
	(segment
		(start 141.899386 3.778758)
		(end 141.899386 1.994154)
		(width 0.4064)
		(layer "F.Cu")
		(net "GND")
	)
	(segment
		(start 273.769328 -62.343538)
		(end 273.197828 -62.343538)
		(width 0.254)
		(layer "F.Cu")
		(net "GND")
	)
	(segment
		(start 141.963394 -67.296538)
		(end 141.391894 -67.296538)
		(width 0.254)
		(layer "F.Cu")
		(net "GND")
	)
	(segment
		(start 439.676286 -3.442716)
		(end 439.615072 -3.381502)
		(width 0.254)
		(layer "F.Cu")
		(net "GND")
	)
	(segment
		(start 53.442108 -155.612846)
		(end 53.442108 -155.600146)
		(width 0.3556)
		(layer "F.Cu")
		(net "GND")
	)
	(segment
		(start 222.749872 -0.821182)
		(end 222.749872 0.444754)
		(width 0.4064)
		(layer "F.Cu")
		(net "GND")
	)
	(segment
		(start 402.223986 -83.432904)
		(end 402.223986 -83.487514)
		(width 0.254)
		(layer "F.Cu")
		(net "GND")
	)
	(segment
		(start 68.799456 -10.422382)
		(end 68.799456 -11.916156)
		(width 0.4064)
		(layer "F.Cu")
		(net "GND")
	)
	(segment
		(start 77.720952 -126.3142)
		(end 77.315568 -126.3142)
		(width 0.4064)
		(layer "F.Cu")
		(net "GND")
	)
	(segment
		(start 31.884112 -3.737356)
		(end 32.160464 -3.737356)
		(width 0.4064)
		(layer "F.Cu")
		(net "GND")
	)
	(segment
		(start 67.749166 -56.58104)
		(end 67.092068 -56.58104)
		(width 0.254)
		(layer "F.Cu")
		(net "GND")
	)
	(segment
		(start 78.051406 -53.60924)
		(end 77.479906 -53.60924)
		(width 0.254)
		(layer "F.Cu")
		(net "GND")
	)
	(segment
		(start 77.192886 -80.850486)
		(end 76.621386 -80.850486)
		(width 0.254)
		(layer "F.Cu")
		(net "GND")
	)
	(segment
		(start 233.608118 -88.775286)
		(end 233.036618 -88.775286)
		(width 0.254)
		(layer "F.Cu")
		(net "GND")
	)
	(segment
		(start 315.400436 -147.27174)
		(end 315.399928 -147.27174)
		(width 0.4064)
		(layer "F.Cu")
		(net "GND")
	)
	(segment
		(start 71.117968 2.8194)
		(end 71.117968 2.009394)
		(width 0.3556)
		(layer "F.Cu")
		(net "GND")
	)
	(segment
		(start 446.200784 -118.615714)
		(end 446.20434 -118.61927)
		(width 0.4064)
		(layer "F.Cu")
		(net "GND")
	)
	(segment
		(start 39.049452 -10.422382)
		(end 39.049452 -11.916156)
		(width 0.4064)
		(layer "F.Cu")
		(net "GND")
	)
	(segment
		(start 193.4464 -61.68136)
		(end 193.41592 -61.65088)
		(width 0.254)
		(layer "F.Cu")
		(net "GND")
	)
	(segment
		(start 294.14978 -133.891274)
		(end 293.69131 -134.349744)
		(width 0.4064)
		(layer "F.Cu")
		(net "GND")
	)
	(segment
		(start 71.349362 -142.6718)
		(end 71.349362 -143.405606)
		(width 0.3556)
		(layer "F.Cu")
		(net "GND")
	)
	(segment
		(start 117.353842 -54.418738)
		(end 116.782342 -54.418738)
		(width 0.254)
		(layer "F.Cu")
		(net "GND")
	)
	(segment
		(start 41.599358 -13.427456)
		(end 41.510458 -13.338556)
		(width 0.4064)
		(layer "F.Cu")
		(net "GND")
	)
	(segment
		(start 114.699542 -137.67054)
		(end 114.699542 -137.676382)
		(width 0.4064)
		(layer "F.Cu")
		(net "GND")
	)
	(segment
		(start 447.3829 -40.2971)
		(end 446.6971 -40.2971)
		(width 0.254)
		(layer "F.Cu")
		(net "GND")
	)
	(segment
		(start 222.749872 -2.314956)
		(end 222.749872 -0.821182)
		(width 0.4064)
		(layer "F.Cu")
		(net "GND")
	)
	(segment
		(start 299.249846 -7.509002)
		(end 299.249846 -5.822442)
		(width 0.4064)
		(layer "F.Cu")
		(net "GND")
	)
	(segment
		(start 256.6416 -3.321812)
		(end 256.295144 -2.975356)
		(width 0.4064)
		(layer "F.Cu")
		(net "GND")
	)
	(segment
		(start 487.984546 -35.686746)
		(end 488.1372 -35.534092)
		(width 0.254)
		(layer "F.Cu")
		(net "GND")
	)
	(segment
		(start 285.7881 -90.080338)
		(end 286.3596 -90.080338)
		(width 0.254)
		(layer "F.Cu")
		(net "GND")
	)
	(segment
		(start 466.199982 -115.810538)
		(end 466.66404 -115.34648)
		(width 0.4064)
		(layer "F.Cu")
		(net "GND")
	)
	(segment
		(start 87.494872 -65.991486)
		(end 86.923372 -65.991486)
		(width 0.254)
		(layer "F.Cu")
		(net "GND")
	)
	(segment
		(start 316.249812 -15.423642)
		(end 316.249812 -13.363956)
		(width 0.4064)
		(layer "F.Cu")
		(net "GND")
	)
	(segment
		(start 74.749406 -11.916156)
		(end 74.749406 -10.422382)
		(width 0.4064)
		(layer "F.Cu")
		(net "GND")
	)
	(segment
		(start 426.074586 -7.789672)
		(end 426.074586 -9.260586)
		(width 0.254)
		(layer "F.Cu")
		(net "GND")
	)
	(segment
		(start 45.387514 -4.346956)
		(end 45.84954 -4.808982)
		(width 0.4064)
		(layer "F.Cu")
		(net "GND")
	)
	(segment
		(start 254.789432 -3.3528)
		(end 255.072388 -3.635756)
		(width 0.4064)
		(layer "F.Cu")
		(net "GND")
	)
	(segment
		(start 480.5045 -143.256)
		(end 480.2505 -143.51)
		(width 0.254)
		(layer "F.Cu")
		(net "GND")
	)
	(segment
		(start 160.860232 -67.007232)
		(end 161.192464 -66.675)
		(width 0.254)
		(layer "F.Cu")
		(net "GND")
	)
	(segment
		(start 377.83135 -122.7328)
		(end 377.7488 -122.7328)
		(width 0.254)
		(layer "F.Cu")
		(net "GND")
	)
	(segment
		(start 42.449496 -2.276856)
		(end 42.411396 -2.314956)
		(width 0.4064)
		(layer "F.Cu")
		(net "GND")
	)
	(segment
		(start 238.8997 -153.093674)
		(end 238.44123 -153.552144)
		(width 0.4064)
		(layer "F.Cu")
		(net "GND")
	)
	(segment
		(start 413.90062 -126.078996)
		(end 414.239202 -125.740414)
		(width 0.254)
		(layer "F.Cu")
		(net "GND")
	)
	(segment
		(start 119.7991 -16.238474)
		(end 119.7991 -15.423896)
		(width 0.4064)
		(layer "F.Cu")
		(net "GND")
	)
	(segment
		(start 198.100442 -147.27174)
		(end 198.099934 -147.27174)
		(width 0.4064)
		(layer "F.Cu")
		(net "GND")
	)
	(segment
		(start 204.049884 -146.011646)
		(end 204.049884 -147.27174)
		(width 0.4064)
		(layer "F.Cu")
		(net "GND")
	)
	(segment
		(start 56.899556 -133.0706)
		(end 56.899556 -133.255512)
		(width 0.4064)
		(layer "F.Cu")
		(net "GND")
	)
	(segment
		(start 235.46181 -155.562046)
		(end 235.46181 -155.612846)
		(width 0.4064)
		(layer "F.Cu")
		(net "GND")
	)
	(segment
		(start 428.474886 -9.247886)
		(end 428.625 -9.398)
		(width 0.254)
		(layer "F.Cu")
		(net "GND")
	)
	(segment
		(start 126.797308 -86.612984)
		(end 127.368808 -86.612984)
		(width 0.254)
		(layer "F.Cu")
		(net "GND")
	)
	(segment
		(start 243.051838 -80.35544)
		(end 242.480338 -80.35544)
		(width 0.254)
		(layer "F.Cu")
		(net "GND")
	)
	(segment
		(start 197.249796 -142.677642)
		(end 197.249796 -144.364202)
		(width 0.4064)
		(layer "F.Cu")
		(net "GND")
	)
	(segment
		(start 140.199364 -142.6718)
		(end 140.199364 -144.462246)
		(width 0.4064)
		(layer "F.Cu")
		(net "GND")
	)
	(segment
		(start 444.485014 -5.375402)
		(end 444.476886 -5.375402)
		(width 0.254)
		(layer "F.Cu")
		(net "GND")
	)
	(segment
		(start 127.44958 -2.253488)
		(end 127.44958 -0.821182)
		(width 0.4064)
		(layer "F.Cu")
		(net "GND")
	)
	(segment
		(start 313.699906 -11.916156)
		(end 313.699906 -10.422382)
		(width 0.4064)
		(layer "F.Cu")
		(net "GND")
	)
	(segment
		(start 278.849836 -137.67054)
		(end 278.849836 -136.379966)
		(width 0.4064)
		(layer "F.Cu")
		(net "GND")
	)
	(segment
		(start 78.909672 -85.803486)
		(end 78.338172 -85.803486)
		(width 0.254)
		(layer "F.Cu")
		(net "GND")
	)
	(segment
		(start 74.617326 -70.44944)
		(end 74.045826 -70.44944)
		(width 0.254)
		(layer "F.Cu")
		(net "GND")
	)
	(segment
		(start 125.938788 -56.399938)
		(end 126.510288 -56.399938)
		(width 0.254)
		(layer "F.Cu")
		(net "GND")
	)
	(segment
		(start 33.754568 -16.3322)
		(end 33.949386 -16.137382)
		(width 0.3556)
		(layer "F.Cu")
		(net "GND")
	)
	(segment
		(start 52.448968 -134.876794)
		(end 52.471574 -134.8994)
		(width 0.3556)
		(layer "F.Cu")
		(net "GND")
	)
	(segment
		(start 227.792534 -18.757646)
		(end 227.849938 -18.81505)
		(width 0.3556)
		(layer "F.Cu")
		(net "GND")
	)
	(segment
		(start 379.81255 -98.69424)
		(end 380.30785 -98.464116)
		(width 0.254)
		(layer "F.Cu")
		(net "GND")
	)
	(segment
		(start 125.938788 -59.371484)
		(end 126.510288 -59.371484)
		(width 0.254)
		(layer "F.Cu")
		(net "GND")
	)
	(segment
		(start 285.7881 -77.202538)
		(end 286.3596 -77.202538)
		(width 0.254)
		(layer "F.Cu")
		(net "GND")
	)
	(segment
		(start 403.207982 -124.538232)
		(end 403.207982 -124.56795)
		(width 0.254)
		(layer "F.Cu")
		(net "GND")
	)
	(segment
		(start 119.929402 -55.904384)
		(end 119.357902 -55.904384)
		(width 0.254)
		(layer "F.Cu")
		(net "GND")
	)
	(segment
		(start 71.349362 3.778758)
		(end 71.349362 3.050794)
		(width 0.3556)
		(layer "F.Cu")
		(net "GND")
	)
	(segment
		(start 52.649374 3.778758)
		(end 52.649374 3.045206)
		(width 0.3048)
		(layer "F.Cu")
		(net "GND")
	)
	(segment
		(start 257.64617 -86.794086)
		(end 257.07467 -86.794086)
		(width 0.254)
		(layer "F.Cu")
		(net "GND")
	)
	(segment
		(start 78.14945 -139.2428)
		(end 78.14945 -137.67054)
		(width 0.4064)
		(layer "F.Cu")
		(net "GND")
	)
	(segment
		(start 467.000844 -113.539524)
		(end 467.2076 -113.74628)
		(width 0.4064)
		(layer "F.Cu")
		(net "GND")
	)
	(segment
		(start 278.061674 -64.819784)
		(end 277.490174 -64.819784)
		(width 0.254)
		(layer "F.Cu")
		(net "GND")
	)
	(segment
		(start 114.778282 -64.819784)
		(end 114.206782 -64.819784)
		(width 0.254)
		(layer "F.Cu")
		(net "GND")
	)
	(segment
		(start 218.500452 -137.67054)
		(end 218.499944 -137.67054)
		(width 0.3556)
		(layer "F.Cu")
		(net "GND")
	)
	(segment
		(start 135.382254 -76.706984)
		(end 135.953754 -76.706984)
		(width 0.254)
		(layer "F.Cu")
		(net "GND")
	)
	(segment
		(start 17.1196 -99.48926)
		(end 17.399 -99.20986)
		(width 0.4064)
		(layer "F.Cu")
		(net "GND")
	)
	(segment
		(start 485.5845 -32.8041)
		(end 485.5845 -33.78454)
		(width 0.254)
		(layer "F.Cu")
		(net "GND")
	)
	(segment
		(start 133.665214 -61.847984)
		(end 134.236714 -61.847984)
		(width 0.254)
		(layer "F.Cu")
		(net "GND")
	)
	(segment
		(start 398.63395 -109.624876)
		(end 398.13865 -109.855)
		(width 0.254)
		(layer "F.Cu")
		(net "GND")
	)
	(segment
		(start 398.325848 -148.192236)
		(end 398.325848 -149.182074)
		(width 0.254)
		(layer "F.Cu")
		(net "GND")
	)
	(segment
		(start 43.29938 -13.541756)
		(end 43.12158 -13.363956)
		(width 0.4064)
		(layer "F.Cu")
		(net "GND")
	)
	(segment
		(start 458.9399 -53.00599)
		(end 458.9399 -51.875944)
		(width 0.508)
		(layer "F.Cu")
		(net "GND")
	)
	(segment
		(start 433.0446 -17.721072)
		(end 433.0446 -18.533872)
		(width 0.254)
		(layer "F.Cu")
		(net "GND")
	)
	(segment
		(start 416.473386 -7.789672)
		(end 416.473386 -9.668256)
		(width 0.254)
		(layer "F.Cu")
		(net "GND")
	)
	(segment
		(start 138.499342 2.963926)
		(end 138.040872 2.505456)
		(width 0.4064)
		(layer "F.Cu")
		(net "GND")
	)
	(segment
		(start 401.88642 -95.92056)
		(end 401.93468 -95.96882)
		(width 0.254)
		(layer "F.Cu")
		(net "GND")
	)
	(segment
		(start 242.193318 -98.681286)
		(end 241.621818 -98.681286)
		(width 0.254)
		(layer "F.Cu")
		(net "GND")
	)
	(segment
		(start 229.54996 -4.808982)
		(end 229.087934 -4.346956)
		(width 0.4064)
		(layer "F.Cu")
		(net "GND")
	)
	(segment
		(start 203.2 -142.677642)
		(end 203.2 -142.856712)
		(width 0.4064)
		(layer "F.Cu")
		(net "GND")
	)
	(segment
		(start 217.649806 3.045206)
		(end 217.4494 2.8448)
		(width 0.3048)
		(layer "F.Cu")
		(net "GND")
	)
	(segment
		(start 418.70122 -38.14572)
		(end 419.090094 -38.534594)
		(width 0.254)
		(layer "F.Cu")
		(net "GND")
	)
	(segment
		(start 56.899302 -3.762756)
		(end 56.899556 -3.76301)
		(width 0.4064)
		(layer "F.Cu")
		(net "GND")
	)
	(segment
		(start 459.75016 -57.596024)
		(end 459.75016 -58.954924)
		(width 0.381)
		(layer "F.Cu")
		(net "GND")
	)
	(segment
		(start 226.149916 -21.479256)
		(end 226.111816 -21.517356)
		(width 0.4064)
		(layer "F.Cu")
		(net "GND")
	)
	(segment
		(start 77.299566 -142.677642)
		(end 77.299312 -142.677896)
		(width 0.4064)
		(layer "F.Cu")
		(net "GND")
	)
	(segment
		(start 124.89942 -144.364202)
		(end 124.801376 -144.462246)
		(width 0.4064)
		(layer "F.Cu")
		(net "GND")
	)
	(segment
		(start 117.249448 3.052826)
		(end 117.015768 2.819146)
		(width 0.3556)
		(layer "F.Cu")
		(net "GND")
	)
	(segment
		(start 218.44254 -146.011646)
		(end 218.44254 -145.998946)
		(width 0.3556)
		(layer "F.Cu")
		(net "GND")
	)
	(segment
		(start 284.929834 -86.612984)
		(end 285.501334 -86.612984)
		(width 0.254)
		(layer "F.Cu")
		(net "GND")
	)
	(segment
		(start 384.0734 -105.1179)
		(end 383.73685 -105.45445)
		(width 0.12446)
		(layer "F.Cu")
		(net "GND")
	)
	(segment
		(start 292.45052 -155.658058)
		(end 292.392608 -155.600146)
		(width 0.3556)
		(layer "F.Cu")
		(net "GND")
	)
	(segment
		(start 490.9058 -34.687002)
		(end 489.86059 -34.687002)
		(width 0.254)
		(layer "F.Cu")
		(net "GND")
	)
	(segment
		(start 284.929834 -54.913784)
		(end 284.358334 -54.913784)
		(width 0.254)
		(layer "F.Cu")
		(net "GND")
	)
	(segment
		(start 72.1995 -146.06905)
		(end 72.142096 -146.011646)
		(width 0.3556)
		(layer "F.Cu")
		(net "GND")
	)
	(segment
		(start 391.403078 -85.680042)
		(end 392.165078 -85.680042)
		(width 0.254)
		(layer "F.Cu")
		(net "GND")
	)
	(segment
		(start 449.33997 -51.875944)
		(end 449.340986 -51.875944)
		(width 0.4064)
		(layer "F.Cu")
		(net "GND")
	)
	(segment
		(start 475.5769 -147.771612)
		(end 475.238826 -148.109686)
		(width 0.254)
		(layer "F.Cu")
		(net "GND")
	)
	(segment
		(start 111.344202 -63.829184)
		(end 110.772702 -63.829184)
		(width 0.254)
		(layer "F.Cu")
		(net "GND")
	)
	(segment
		(start 446.453006 -32.4485)
		(end 445.564006 -31.5595)
		(width 0.4064)
		(layer "F.Cu")
		(net "GND")
	)
	(segment
		(start 68.607686 -59.057286)
		(end 69.753226 -59.057286)
		(width 0.254)
		(layer "F.Cu")
		(net "GND")
	)
	(segment
		(start 375.944892 -77.494892)
		(end 375.545096 -77.095096)
		(width 0.254)
		(layer "F.Cu")
		(net "GND")
	)
	(segment
		(start 236.349794 -153.006806)
		(end 236.1184 -153.2382)
		(width 0.3556)
		(layer "F.Cu")
		(net "GND")
	)
	(segment
		(start 128.68148 -21.5138)
		(end 127.392176 -21.513292)
		(width 0.254)
		(layer "F.Cu")
		(net "GND")
	)
	(segment
		(start 292.65626 -97.014538)
		(end 293.22776 -97.014538)
		(width 0.254)
		(layer "F.Cu")
		(net "GND")
	)
	(segment
		(start 72.142096 -2.310892)
		(end 72.1995 -2.253488)
		(width 0.4064)
		(layer "F.Cu")
		(net "GND")
	)
	(segment
		(start 313.699906 -20.023582)
		(end 313.699906 -18.757646)
		(width 0.4064)
		(layer "F.Cu")
		(net "GND")
	)
	(segment
		(start 243.051838 -93.23324)
		(end 242.480338 -93.23324)
		(width 0.254)
		(layer "F.Cu")
		(net "GND")
	)
	(segment
		(start 66.24955 -15.423642)
		(end 66.24955 -15.602712)
		(width 0.4064)
		(layer "F.Cu")
		(net "GND")
	)
	(segment
		(start 349.292164 -156.048964)
		(end 349.645224 -156.402024)
		(width 0.254)
		(layer "F.Cu")
		(net "GND")
	)
	(segment
		(start 31.2674 -53.452014)
		(end 31.671768 -53.856382)
		(width 0.4064)
		(layer "F.Cu")
		(net "GND")
	)
	(segment
		(start 167.300148 -147.42922)
		(end 166.649146 -148.080222)
		(width 0.254)
		(layer "F.Cu")
		(net "GND")
	)
	(segment
		(start 136.240774 -86.117938)
		(end 136.812274 -86.117938)
		(width 0.254)
		(layer "F.Cu")
		(net "GND")
	)
	(segment
		(start 210.85048 -142.6718)
		(end 210.849972 -142.677642)
		(width 0.4064)
		(layer "F.Cu")
		(net "GND")
	)
	(segment
		(start 243.910104 -65.000886)
		(end 243.338604 -65.000886)
		(width 0.254)
		(layer "F.Cu")
		(net "GND")
	)
	(segment
		(start 397.7894 -115.932458)
		(end 397.64335 -115.86464)
		(width 0.254)
		(layer "F.Cu")
		(net "GND")
	)
	(segment
		(start 282.0162 -144.44472)
		(end 282.07208 -144.5006)
		(width 0.3556)
		(layer "F.Cu")
		(net "GND")
	)
	(segment
		(start 282.067254 -100.48113)
		(end 281.61742 -101.261164)
		(width 0.254)
		(layer "F.Cu")
		(net "GND")
	)
	(segment
		(start 257.64617 -56.085486)
		(end 257.07467 -56.085486)
		(width 0.254)
		(layer "F.Cu")
		(net "GND")
	)
	(segment
		(start 139.674854 -75.221338)
		(end 140.246354 -75.221338)
		(width 0.254)
		(layer "F.Cu")
		(net "GND")
	)
	(segment
		(start 72.1995 -18.81505)
		(end 72.1995 -20.023582)
		(width 0.3556)
		(layer "F.Cu")
		(net "GND")
	)
	(segment
		(start 229.549706 -133.076696)
		(end 229.549706 -133.891274)
		(width 0.4064)
		(layer "F.Cu")
		(net "GND")
	)
	(segment
		(start 458.437996 -147.719796)
		(end 458.7748 -148.0566)
		(width 0.254)
		(layer "F.Cu")
		(net "GND")
	)
	(segment
		(start 413.84474 -87.909146)
		(end 413.87522 -87.939626)
		(width 0.3048)
		(layer "F.Cu")
		(net "GND")
	)
	(segment
		(start 236.349794 -3.940556)
		(end 236.349794 -5.822442)
		(width 0.4064)
		(layer "F.Cu")
		(net "GND")
	)
	(segment
		(start 281.495754 -99.490784)
		(end 282.067254 -99.490784)
		(width 0.254)
		(layer "F.Cu")
		(net "GND")
	)
	(segment
		(start 243.149882 -148.731732)
		(end 243.149882 -147.277582)
		(width 0.508)
		(layer "F.Cu")
		(net "GND")
	)
	(segment
		(start 218.499944 -146.06905)
		(end 218.44254 -146.011646)
		(width 0.3556)
		(layer "F.Cu")
		(net "GND")
	)
	(segment
		(start 71.183246 -59.55284)
		(end 70.611746 -59.55284)
		(width 0.254)
		(layer "F.Cu")
		(net "GND")
	)
	(segment
		(start 382.78435 -103.84536)
		(end 383.11328 -103.51643)
		(width 0.254)
		(layer "F.Cu")
		(net "GND")
	)
	(segment
		(start 317.100458 -147.27174)
		(end 317.09995 -147.27174)
		(width 0.4064)
		(layer "F.Cu")
		(net "GND")
	)
	(segment
		(start 255.3716 -139.9794)
		(end 255.521206 -139.829794)
		(width 0.4064)
		(layer "F.Cu")
		(net "GND")
	)
	(segment
		(start 113.919762 -91.070938)
		(end 114.491262 -91.070938)
		(width 0.1016)
		(layer "F.Cu")
		(net "GND")
	)
	(segment
		(start 136.799574 -21.455888)
		(end 136.74217 -21.513292)
		(width 0.4064)
		(layer "F.Cu")
		(net "GND")
	)
	(segment
		(start 214.250524 -13.364718)
		(end 214.249762 -13.363956)
		(width 0.4064)
		(layer "F.Cu")
		(net "GND")
	)
	(segment
		(start 278.849836 -148.531834)
		(end 278.849836 -147.277582)
		(width 0.508)
		(layer "F.Cu")
		(net "GND")
	)
	(segment
		(start 198.755 -134.882382)
		(end 198.772018 -134.8994)
		(width 0.3556)
		(layer "F.Cu")
		(net "GND")
	)
	(segment
		(start 278.849836 -136.379966)
		(end 278.90216 -136.327642)
		(width 0.4064)
		(layer "F.Cu")
		(net "GND")
	)
	(segment
		(start 376.362468 -122.7074)
		(end 376.335036 -122.854974)
		(width 0.254)
		(layer "F.Cu")
		(net "GND")
	)
	(segment
		(start 107.051856 -92.061538)
		(end 107.623356 -92.061538)
		(width 0.254)
		(layer "F.Cu")
		(net "GND")
	)
	(segment
		(start 224.450402 -137.67054)
		(end 224.449894 -137.67054)
		(width 0.4064)
		(layer "F.Cu")
		(net "GND")
	)
	(segment
		(start 346.6338 -22.5933)
		(end 346.6338 -21.9837)
		(width 0.4064)
		(layer "F.Cu")
		(net "GND")
	)
	(segment
		(start 374.3579 -102.855014)
		(end 373.888 -103.324914)
		(width 0.254)
		(layer "F.Cu")
		(net "GND")
	)
	(segment
		(start 442.9506 -9.8806)
		(end 442.9506 -8.4582)
		(width 0.254)
		(layer "F.Cu")
		(net "GND")
	)
	(segment
		(start 31.39948 -148.771356)
		(end 31.39948 -147.27174)
		(width 0.4064)
		(layer "F.Cu")
		(net "GND")
	)
	(segment
		(start 440.41314 -9.711182)
		(end 440.41314 -9.126982)
		(width 0.254)
		(layer "F.Cu")
		(net "GND")
	)
	(segment
		(start 141.899386 -15.423642)
		(end 141.899386 -13.363956)
		(width 0.4064)
		(layer "F.Cu")
		(net "GND")
	)
	(segment
		(start 79.768192 -97.19564)
		(end 79.196692 -97.19564)
		(width 0.254)
		(layer "F.Cu")
		(net "GND")
	)
	(segment
		(start 102.089204 -63.51524)
		(end 101.517704 -63.51524)
		(width 0.254)
		(layer "F.Cu")
		(net "GND")
	)
	(segment
		(start 448.532504 -50.5206)
		(end 448.53225 -50.490374)
		(width 0.508)
		(layer "F.Cu")
		(net "GND")
	)
	(segment
		(start 397.64335 -119.29872)
		(end 397.7894 -119.366538)
		(width 0.254)
		(layer "F.Cu")
		(net "GND")
	)
	(segment
		(start 388.23265 -120.15724)
		(end 388.72795 -120.387364)
		(width 0.254)
		(layer "F.Cu")
		(net "GND")
	)
	(segment
		(start 197.095364 -79.028544)
		(end 197.095364 -78.629764)
		(width 0.254)
		(layer "F.Cu")
		(net "GND")
	)
	(segment
		(start 212.550502 -15.423642)
		(end 212.549994 -15.423642)
		(width 0.4064)
		(layer "F.Cu")
		(net "GND")
	)
	(segment
		(start 227.849938 -155.67025)
		(end 227.849938 -156.87294)
		(width 0.3556)
		(layer "F.Cu")
		(net "GND")
	)
	(segment
		(start 196.399912 -11.916156)
		(end 196.399912 -10.422382)
		(width 0.4064)
		(layer "F.Cu")
		(net "GND")
	)
	(segment
		(start 497.949982 -54.355238)
		(end 498.32006 -53.604922)
		(width 0.254)
		(layer "F.Cu")
		(net "GND")
	)
	(segment
		(start 122.504708 -60.362338)
		(end 121.933208 -60.362338)
		(width 0.254)
		(layer "F.Cu")
		(net "GND")
	)
	(segment
		(start 173.173898 -85.330792)
		(end 173.173898 -85.467698)
		(width 0.254)
		(layer "F.Cu")
		(net "GND")
	)
	(segment
		(start 351.937574 4.434332)
		(end 351.944432 4.44119)
		(width 0.254)
		(layer "F.Cu")
		(net "GND")
	)
	(segment
		(start 72.900286 -67.47764)
		(end 72.328786 -67.47764)
		(width 0.254)
		(layer "F.Cu")
		(net "GND")
	)
	(segment
		(start 114.778282 -92.556584)
		(end 115.349782 -92.556584)
		(width 0.254)
		(layer "F.Cu")
		(net "GND")
	)
	(segment
		(start 366.2172 -100.785676)
		(end 366.548924 -101.1174)
		(width 0.254)
		(layer "F.Cu")
		(net "GND")
	)
	(segment
		(start 239.749838 -0.821182)
		(end 239.749838 0.444754)
		(width 0.4064)
		(layer "F.Cu")
		(net "GND")
	)
	(segment
		(start 124.221748 -84.136738)
		(end 124.793248 -84.136738)
		(width 0.254)
		(layer "F.Cu")
		(net "GND")
	)
	(segment
		(start 393.485116 -124.919994)
		(end 393.984988 -124.504958)
		(width 0.254)
		(layer "F.Cu")
		(net "GND")
	)
	(segment
		(start 406.561036 -150.468584)
		(end 406.172416 -150.468584)
		(width 0.4064)
		(layer "F.Cu")
		(net "GND")
	)
	(segment
		(start 198.962518 -53.7464)
		(end 198.445374 -54.263544)
		(width 0.254)
		(layer "F.Cu")
		(net "GND")
	)
	(segment
		(start 415.890456 -30.53461)
		(end 416.290252 -30.134814)
		(width 0.254)
		(layer "F.Cu")
		(net "GND")
	)
	(segment
		(start 394.67155 -117.58168)
		(end 395.16685 -117.811804)
		(width 0.254)
		(layer "F.Cu")
		(net "GND")
	)
	(segment
		(start 113.849404 1.946148)
		(end 113.726976 1.82372)
		(width 0.4064)
		(layer "F.Cu")
		(net "GND")
	)
	(segment
		(start 191.897 -2.8575)
		(end 191.897 -2.2098)
		(width 0.4064)
		(layer "F.Cu")
		(net "GND")
	)
	(segment
		(start 147.381468 -21.5138)
		(end 148.699474 -21.517356)
		(width 0.254)
		(layer "F.Cu")
		(net "GND")
	)
	(segment
		(start 392.02741 -116.016786)
		(end 392.19505 -116.094764)
		(width 0.254)
		(layer "F.Cu")
		(net "GND")
	)
	(segment
		(start 225.299778 -152.278842)
		(end 225.299778 -153.965402)
		(width 0.4064)
		(layer "F.Cu")
		(net "GND")
	)
	(segment
		(start 470.7001 -43.0784)
		(end 469.9254 -43.0784)
		(width 0.254)
		(layer "F.Cu")
		(net "GND")
	)
	(segment
		(start 116.495322 -61.847984)
		(end 115.923822 -61.847984)
		(width 0.254)
		(layer "F.Cu")
		(net "GND")
	)
	(segment
		(start 210.85048 2.964688)
		(end 210.391248 2.505456)
		(width 0.4064)
		(layer "F.Cu")
		(net "GND")
	)
	(segment
		(start 472.480132 -114.381788)
		(end 472.42222 -114.4397)
		(width 0.4064)
		(layer "F.Cu")
		(net "GND")
	)
	(segment
		(start 397.485108 -124.919994)
		(end 397.485108 -124.689108)
		(width 0.254)
		(layer "F.Cu")
		(net "GND")
	)
	(segment
		(start 278.849836 3.778758)
		(end 278.849836 1.946148)
		(width 0.4064)
		(layer "F.Cu")
		(net "GND")
	)
	(segment
		(start 118.041928 -21.513292)
		(end 118.099332 -21.455888)
		(width 0.4064)
		(layer "F.Cu")
		(net "GND")
	)
	(segment
		(start 376.555 -110.3884)
		(end 376.335036 -110.854998)
		(width 0.254)
		(layer "F.Cu")
		(net "GND")
	)
	(segment
		(start 313.699906 -21.517356)
		(end 313.699906 -20.023582)
		(width 0.4064)
		(layer "F.Cu")
		(net "GND")
	)
	(segment
		(start 117.249448 -6.548374)
		(end 117.015768 -6.782054)
		(width 0.3556)
		(layer "F.Cu")
		(net "GND")
	)
	(segment
		(start 83.202272 -67.47764)
		(end 82.630772 -67.47764)
		(width 0.254)
		(layer "F.Cu")
		(net "GND")
	)
	(segment
		(start 282.24988 -5.822442)
		(end 282.24988 -6.548374)
		(width 0.3556)
		(layer "F.Cu")
		(net "GND")
	)
	(segment
		(start 382.9304 -102.060502)
		(end 383.27965 -101.898196)
		(width 0.254)
		(layer "F.Cu")
		(net "GND")
	)
	(segment
		(start 376.335036 -105.855008)
		(end 376.428 -106.35488)
		(width 0.254)
		(layer "F.Cu")
		(net "GND")
	)
	(segment
		(start 375.089928 -101.35489)
		(end 375.92 -101.35489)
		(width 0.254)
		(layer "F.Cu")
		(net "GND")
	)
	(segment
		(start 124.221748 -60.362338)
		(end 123.650248 -60.362338)
		(width 0.254)
		(layer "F.Cu")
		(net "GND")
	)
	(segment
		(start 243.562886 -12.885166)
		(end 243.219732 -12.885166)
		(width 0.4064)
		(layer "F.Cu")
		(net "GND")
	)
	(segment
		(start 67.749166 -63.51524)
		(end 67.101466 -63.51524)
		(width 0.254)
		(layer "F.Cu")
		(net "GND")
	)
	(segment
		(start 215.0999 -20.023582)
		(end 215.0999 -18.744946)
		(width 0.4064)
		(layer "F.Cu")
		(net "GND")
	)
	(segment
		(start 138.816334 -60.857384)
		(end 139.387834 -60.857384)
		(width 0.254)
		(layer "F.Cu")
		(net "GND")
	)
	(segment
		(start 201.500486 2.964688)
		(end 201.041254 2.505456)
		(width 0.4064)
		(layer "F.Cu")
		(net "GND")
	)
	(segment
		(start 382.288542 -104.70388)
		(end 382.581404 -104.411018)
		(width 0.12446)
		(layer "F.Cu")
		(net "GND")
	)
	(segment
		(start 195.086986 -93.798898)
		(end 196.272912 -93.798898)
		(width 0.508)
		(layer "F.Cu")
		(net "GND")
	)
	(segment
		(start 67.092068 -56.58104)
		(end 67.079368 -56.56834)
		(width 0.254)
		(layer "F.Cu")
		(net "GND")
	)
	(segment
		(start 391.120122 -74.487278)
		(end 390.62152 -74.98588)
		(width 0.254)
		(layer "F.Cu")
		(net "GND")
	)
	(segment
		(start 44.092114 -9.194546)
		(end 44.092114 -9.143746)
		(width 0.4064)
		(layer "F.Cu")
		(net "GND")
	)
	(segment
		(start 277.9268 -149.8092)
		(end 278.2062 -150.0886)
		(width 0.4064)
		(layer "F.Cu")
		(net "GND")
	)
	(segment
		(start 129.372868 -78.193138)
		(end 129.944368 -78.193138)
		(width 0.254)
		(layer "F.Cu")
		(net "GND")
	)
	(segment
		(start 165.0492 -72.644)
		(end 165.6334 -73.2282)
		(width 0.254)
		(layer "F.Cu")
		(net "GND")
	)
	(segment
		(start 127.392176 -9.156446)
		(end 127.392176 -9.143746)
		(width 0.3556)
		(layer "F.Cu")
		(net "GND")
	)
	(segment
		(start 19.7231 -45.2501)
		(end 20.18792 -44.78528)
		(width 0.254)
		(layer "F.Cu")
		(net "GND")
	)
	(segment
		(start 442.076586 -4.386072)
		(end 442.076586 -5.247386)
		(width 0.254)
		(layer "F.Cu")
		(net "GND")
	)
	(segment
		(start 392.02741 -102.908862)
		(end 392.19505 -102.98684)
		(width 0.254)
		(layer "F.Cu")
		(net "GND")
	)
	(segment
		(start 247.344184 -63.019686)
		(end 246.772684 -63.019686)
		(width 0.254)
		(layer "F.Cu")
		(net "GND")
	)
	(segment
		(start 243.910104 -80.850486)
		(end 243.338604 -80.850486)
		(width 0.254)
		(layer "F.Cu")
		(net "GND")
	)
	(segment
		(start 74.617326 -74.411586)
		(end 74.045826 -74.411586)
		(width 0.254)
		(layer "F.Cu")
		(net "GND")
	)
	(segment
		(start 195.550282 -133.0706)
		(end 195.549774 -133.076442)
		(width 0.4064)
		(layer "F.Cu")
		(net "GND")
	)
	(segment
		(start 294.14978 -15.423642)
		(end 294.14978 -14.409928)
		(width 0.4064)
		(layer "F.Cu")
		(net "GND")
	)
	(segment
		(start 444.250064 -35.032442)
		(end 444.548006 -34.7345)
		(width 0.3048)
		(layer "F.Cu")
		(net "GND")
	)
	(segment
		(start 150.399496 -156.87294)
		(end 150.399496 -155.612846)
		(width 0.4064)
		(layer "F.Cu")
		(net "GND")
	)
	(segment
		(start 220.199712 -133.891274)
		(end 219.741242 -134.349744)
		(width 0.4064)
		(layer "F.Cu")
		(net "GND")
	)
	(segment
		(start 214.250524 -5.822442)
		(end 214.250524 -3.763518)
		(width 0.4064)
		(layer "F.Cu")
		(net "GND")
	)
	(segment
		(start 385.7498 -103.251)
		(end 385.75107 -103.378)
		(width 0.254)
		(layer "F.Cu")
		(net "GND")
	)
	(segment
		(start 234.649772 -13.660628)
		(end 234.649772 -15.423642)
		(width 0.4064)
		(layer "F.Cu")
		(net "GND")
	)
	(segment
		(start 70.499478 -21.479256)
		(end 70.461378 -21.517356)
		(width 0.4064)
		(layer "F.Cu")
		(net "GND")
	)
	(segment
		(start 243.051838 -100.167186)
		(end 242.480338 -100.167186)
		(width 0.254)
		(layer "F.Cu")
		(net "GND")
	)
	(segment
		(start 271.841468 -149.8092)
		(end 270.956532 -149.8092)
		(width 0.4572)
		(layer "F.Cu")
		(net "GND")
	)
	(segment
		(start 118.212362 -102.462584)
		(end 117.925342 -101.967538)
		(width 0.254)
		(layer "F.Cu")
		(net "GND")
	)
	(segment
		(start 391.0076 -81.573624)
		(end 390.67486 -81.906364)
		(width 0.254)
		(layer "F.Cu")
		(net "GND")
	)
	(segment
		(start 212.549994 -152.457912)
		(end 212.54974 -152.458166)
		(width 0.4064)
		(layer "F.Cu")
		(net "GND")
	)
	(segment
		(start 170.28922 -7.430262)
		(end 170.631358 -7.7724)
		(width 0.4064)
		(layer "F.Cu")
		(net "GND")
	)
	(segment
		(start 241.450368 -147.27174)
		(end 241.44986 -147.27174)
		(width 0.4064)
		(layer "F.Cu")
		(net "GND")
	)
	(segment
		(start 70.324726 -87.784686)
		(end 69.753226 -87.784686)
		(width 0.254)
		(layer "F.Cu")
		(net "GND")
	)
	(segment
		(start 55.19928 -6.637274)
		(end 54.74081 -7.095744)
		(width 0.4064)
		(layer "F.Cu")
		(net "GND")
	)
	(segment
		(start 310.0832 -7.606538)
		(end 310.122062 -7.6454)
		(width 0.3556)
		(layer "F.Cu")
		(net "GND")
	)
	(segment
		(start 397.750538 -75.30592)
		(end 398.004538 -75.55992)
		(width 0.254)
		(layer "F.Cu")
		(net "GND")
	)
	(segment
		(start 204.050392 -156.87294)
		(end 204.049884 -156.87294)
		(width 0.4064)
		(layer "F.Cu")
		(net "GND")
	)
	(segment
		(start 301.241206 -79.183738)
		(end 301.812706 -79.183738)
		(width 0.127)
		(layer "F.Cu")
		(net "GND")
	)
	(segment
		(start 297.807126 -85.127338)
		(end 298.378626 -85.127338)
		(width 0.3048)
		(layer "F.Cu")
		(net "GND")
	)
	(segment
		(start 146.149568 -0.821182)
		(end 146.149568 0.38735)
		(width 0.3556)
		(layer "F.Cu")
		(net "GND")
	)
	(segment
		(start 232.950512 -5.822442)
		(end 232.950512 -7.606284)
		(width 0.4064)
		(layer "F.Cu")
		(net "GND")
	)
	(segment
		(start 461.332326 -50.5206)
		(end 461.332326 -50.48885)
		(width 0.508)
		(layer "F.Cu")
		(net "GND")
	)
	(segment
		(start 74.617326 -86.29904)
		(end 74.045826 -86.29904)
		(width 0.254)
		(layer "F.Cu")
		(net "GND")
	)
	(segment
		(start 457.252324 -143.219932)
		(end 458.756004 -143.219932)
		(width 0.254)
		(layer "F.Cu")
		(net "GND")
	)
	(segment
		(start 71.117968 -6.7818)
		(end 71.117968 -7.591806)
		(width 0.3556)
		(layer "F.Cu")
		(net "GND")
	)
	(segment
		(start 37.34943 -18.757646)
		(end 37.34943 -20.023582)
		(width 0.4064)
		(layer "F.Cu")
		(net "GND")
	)
	(segment
		(start 225.299778 -134.763002)
		(end 225.201734 -134.861046)
		(width 0.4064)
		(layer "F.Cu")
		(net "GND")
	)
	(segment
		(start 67.099434 -137.67054)
		(end 67.099434 -136.410446)
		(width 0.4064)
		(layer "F.Cu")
		(net "GND")
	)
	(segment
		(start 311.092596 -146.011646)
		(end 311.092596 -145.998946)
		(width 0.3556)
		(layer "F.Cu")
		(net "GND")
	)
	(segment
		(start 207.411828 -11.916156)
		(end 207.449928 -11.878056)
		(width 0.4064)
		(layer "F.Cu")
		(net "GND")
	)
	(segment
		(start 44.149518 -156.87294)
		(end 44.149518 -155.70835)
		(width 0.4064)
		(layer "F.Cu")
		(net "GND")
	)
	(segment
		(start 247.344184 -71.935086)
		(end 246.772684 -71.935086)
		(width 0.254)
		(layer "F.Cu")
		(net "GND")
	)
	(segment
		(start 290.93922 -53.427884)
		(end 291.466016 -53.427884)
		(width 0.254)
		(layer "F.Cu")
		(net "GND")
	)
	(segment
		(start 240.599976 -152.278842)
		(end 240.599976 -152.457912)
		(width 0.4064)
		(layer "F.Cu")
		(net "GND")
	)
	(segment
		(start 169.389298 -63.731902)
		(end 169.5704 -63.5508)
		(width 0.2032)
		(layer "F.Cu")
		(net "GND")
	)
	(segment
		(start 215.950292 -5.822442)
		(end 215.949784 -5.822442)
		(width 0.4064)
		(layer "F.Cu")
		(net "GND")
	)
	(segment
		(start 131.089908 -82.155284)
		(end 131.661408 -82.155284)
		(width 0.254)
		(layer "F.Cu")
		(net "GND")
	)
	(segment
		(start 148.699474 -0.821182)
		(end 148.699474 0.444754)
		(width 0.4064)
		(layer "F.Cu")
		(net "GND")
	)
	(segment
		(start 193.117216 -59.900058)
		(end 193.117216 -60.209938)
		(width 0.254)
		(layer "F.Cu")
		(net "GND")
	)
	(segment
		(start 47.549562 -13.36421)
		(end 47.549308 -13.363956)
		(width 0.4064)
		(layer "F.Cu")
		(net "GND")
	)
	(segment
		(start 410.290264 -32.134556)
		(end 410.690314 -31.734506)
		(width 0.254)
		(layer "F.Cu")
		(net "GND")
	)
	(segment
		(start 112.202722 -102.958138)
		(end 112.774222 -102.958138)
		(width 0.254)
		(layer "F.Cu")
		(net "GND")
	)
	(segment
		(start 393.18565 -99.55276)
		(end 393.68095 -99.322636)
		(width 0.254)
		(layer "F.Cu")
		(net "GND")
	)
	(segment
		(start 487.7308 -139.3444)
		(end 488.5944 -140.208)
		(width 0.254)
		(layer "F.Cu")
		(net "GND")
	)
	(segment
		(start 121.646188 -73.735184)
		(end 122.217688 -73.735184)
		(width 0.254)
		(layer "F.Cu")
		(net "GND")
	)
	(segment
		(start 132.549392 -7.607046)
		(end 132.549392 -5.822442)
		(width 0.4064)
		(layer "F.Cu")
		(net "GND")
	)
	(segment
		(start 226.822 -3.762756)
		(end 226.9998 -3.940556)
		(width 0.4064)
		(layer "F.Cu")
		(net "GND")
	)
	(segment
		(start 61.796168 -6.756654)
		(end 61.796168 -7.62)
		(width 0.3556)
		(layer "F.Cu")
		(net "GND")
	)
	(segment
		(start 30.549342 -133.0706)
		(end 30.549342 -134.400798)
		(width 0.4064)
		(layer "F.Cu")
		(net "GND")
	)
	(segment
		(start 346.92717 -11.930888)
		(end 346.569538 -12.28852)
		(width 0.2032)
		(layer "F.Cu")
		(net "GND")
	)
	(segment
		(start 203.199746 3.599434)
		(end 203.199746 1.994154)
		(width 0.4064)
		(layer "F.Cu")
		(net "GND")
	)
	(segment
		(start 117.249448 -133.802374)
		(end 117.015768 -134.036054)
		(width 0.3556)
		(layer "F.Cu")
		(net "GND")
	)
	(segment
		(start 218.44254 -9.143746)
		(end 218.44254 -9.156446)
		(width 0.3556)
		(layer "F.Cu")
		(net "GND")
	)
	(segment
		(start 379.81255 -111.802164)
		(end 379.31725 -111.57204)
		(width 0.254)
		(layer "F.Cu")
		(net "GND")
	)
	(segment
		(start 380.80315 -117.58168)
		(end 381.29845 -117.811804)
		(width 0.254)
		(layer "F.Cu")
		(net "GND")
	)
	(segment
		(start 309.884318 -55.962042)
		(end 309.82666 -55.904384)
		(width 0.254)
		(layer "F.Cu")
		(net "GND")
	)
	(segment
		(start 287.79216 -59.866784)
		(end 288.36366 -59.866784)
		(width 0.254)
		(layer "F.Cu")
		(net "GND")
	)
	(segment
		(start 398.63395 -102.756716)
		(end 398.13865 -102.98684)
		(width 0.254)
		(layer "F.Cu")
		(net "GND")
	)
	(segment
		(start 465.442046 2.654046)
		(end 465.6074 2.8194)
		(width 0.381)
		(layer "F.Cu")
		(net "GND")
	)
	(segment
		(start 236.349794 3.778758)
		(end 236.349794 3.050794)
		(width 0.3556)
		(layer "F.Cu")
		(net "GND")
	)
	(segment
		(start 242.193318 -80.850486)
		(end 241.621818 -80.850486)
		(width 0.254)
		(layer "F.Cu")
		(net "GND")
	)
	(segment
		(start 146.149568 -146.06905)
		(end 146.092164 -146.011646)
		(width 0.3556)
		(layer "F.Cu")
		(net "GND")
	)
	(segment
		(start 385.752848 -118.6688)
		(end 385.75615 -118.670324)
		(width 0.254)
		(layer "F.Cu")
		(net "GND")
	)
	(segment
		(start 304.35042 -10.422382)
		(end 304.349912 -10.422382)
		(width 0.4064)
		(layer "F.Cu")
		(net "GND")
	)
	(segment
		(start 119.070882 -55.409338)
		(end 118.499382 -55.409338)
		(width 0.254)
		(layer "F.Cu")
		(net "GND")
	)
	(segment
		(start 340.6394 -11.7094)
		(end 340.7156 -11.7094)
		(width 0.254)
		(layer "F.Cu")
		(net "GND")
	)
	(segment
		(start 131.089908 -64.324738)
		(end 131.661408 -64.324738)
		(width 0.254)
		(layer "F.Cu")
		(net "GND")
	)
	(segment
		(start 123.363228 -65.810384)
		(end 122.791728 -65.810384)
		(width 0.254)
		(layer "F.Cu")
		(net "GND")
	)
	(segment
		(start 309.449978 -20.023582)
		(end 309.449978 -21.479256)
		(width 0.4064)
		(layer "F.Cu")
		(net "GND")
	)
	(segment
		(start 125.749558 -18.757646)
		(end 125.749558 -20.023582)
		(width 0.4064)
		(layer "F.Cu")
		(net "GND")
	)
	(segment
		(start 447.74993 -58.954924)
		(end 447.74993 -57.596024)
		(width 0.381)
		(layer "F.Cu")
		(net "GND")
	)
	(segment
		(start 235.612178 -93.23324)
		(end 234.466638 -93.23324)
		(width 0.254)
		(layer "F.Cu")
		(net "GND")
	)
	(segment
		(start 71.183246 -52.618386)
		(end 70.611746 -52.618386)
		(width 0.254)
		(layer "F.Cu")
		(net "GND")
	)
	(segment
		(start 217.4494 -6.9342)
		(end 217.4494 -6.7564)
		(width 0.3048)
		(layer "F.Cu")
		(net "GND")
	)
	(segment
		(start 399.674334 -93.544898)
		(end 399.674334 -94.179898)
		(width 0.254)
		(layer "F.Cu")
		(net "GND")
	)
	(segment
		(start 387.444488 -104.361488)
		(end 387.73735 -104.65435)
		(width 0.12446)
		(layer "F.Cu")
		(net "GND")
	)
	(segment
		(start 47.549562 -142.6718)
		(end 47.549562 -142.856712)
		(width 0.4064)
		(layer "F.Cu")
		(net "GND")
	)
	(segment
		(start 140.533374 -69.772784)
		(end 141.104874 -69.772784)
		(width 0.254)
		(layer "F.Cu")
		(net "GND")
	)
	(segment
		(start 394.67155 -115.86464)
		(end 395.16685 -116.094764)
		(width 0.254)
		(layer "F.Cu")
		(net "GND")
	)
	(segment
		(start 382.797304 -26.270966)
		(end 383.951734 -26.270966)
		(width 0.254)
		(layer "F.Cu")
		(net "GND")
	)
	(segment
		(start 53.499512 -18.81505)
		(end 53.499512 -20.023582)
		(width 0.3556)
		(layer "F.Cu")
		(net "GND")
	)
	(segment
		(start 394.002768 -117.731032)
		(end 394.17625 -117.811804)
		(width 0.254)
		(layer "F.Cu")
		(net "GND")
	)
	(segment
		(start 50.099468 -11.916156)
		(end 50.099468 -10.422382)
		(width 0.4064)
		(layer "F.Cu")
		(net "GND")
	)
	(segment
		(start 73.758806 -86.794086)
		(end 73.187306 -86.794086)
		(width 0.254)
		(layer "F.Cu")
		(net "GND")
	)
	(segment
		(start 486.41 -32.3088)
		(end 485.99344 -32.72536)
		(width 0.254)
		(layer "F.Cu")
		(net "GND")
	)
	(segment
		(start 97.796858 -88.775286)
		(end 97.225358 -88.775286)
		(width 0.254)
		(layer "F.Cu")
		(net "GND")
	)
	(segment
		(start 76.334366 -74.411586)
		(end 75.762866 -74.411586)
		(width 0.254)
		(layer "F.Cu")
		(net "GND")
	)
	(segment
		(start 400.5072 1.7272)
		(end 401.154646 1.7272)
		(width 0.254)
		(layer "F.Cu")
		(net "GND")
	)
	(segment
		(start 241.334798 -99.17684)
		(end 240.763298 -99.17684)
		(width 0.254)
		(layer "F.Cu")
		(net "GND")
	)
	(segment
		(start 292.65626 -86.117938)
		(end 293.22776 -86.117938)
		(width 0.3048)
		(layer "F.Cu")
		(net "GND")
	)
	(segment
		(start 207.450436 -156.87294)
		(end 207.449928 -156.87294)
		(width 0.4064)
		(layer "F.Cu")
		(net "GND")
	)
	(segment
		(start 236.349794 -142.677642)
		(end 236.349794 -143.405606)
		(width 0.3556)
		(layer "F.Cu")
		(net "GND")
	)
	(segment
		(start 467.233 -54.0258)
		(end 467.233 -53.721)
		(width 0.4064)
		(layer "F.Cu")
		(net "GND")
	)
	(segment
		(start 314.550298 -142.6718)
		(end 314.54979 -142.677642)
		(width 0.4064)
		(layer "F.Cu")
		(net "GND")
	)
	(segment
		(start 152.099518 -149.601682)
		(end 152.0952 -149.606)
		(width 0.4064)
		(layer "F.Cu")
		(net "GND")
	)
	(segment
		(start 382.98501 -124.504958)
		(end 382.98501 -125.33503)
		(width 0.254)
		(layer "F.Cu")
		(net "GND")
	)
	(segment
		(start 193.860928 -67.97294)
		(end 193.860928 -68.358258)
		(width 0.381)
		(layer "F.Cu")
		(net "GND")
	)
	(segment
		(start 126.797308 -53.923184)
		(end 127.368808 -53.923184)
		(width 0.254)
		(layer "F.Cu")
		(net "GND")
	)
	(segment
		(start 127.655828 -62.343538)
		(end 128.227328 -62.343538)
		(width 0.254)
		(layer "F.Cu")
		(net "GND")
	)
	(segment
		(start 36.499546 -152.273)
		(end 36.499546 -152.278842)
		(width 0.4064)
		(layer "F.Cu")
		(net "GND")
	)
	(segment
		(start 399.544286 -99.367848)
		(end 399.634964 -99.85502)
		(width 0.254)
		(layer "F.Cu")
		(net "GND")
	)
	(segment
		(start 112.202722 -93.052138)
		(end 112.774222 -93.052138)
		(width 0.254)
		(layer "F.Cu")
		(net "GND")
	)
	(segment
		(start 239.617758 -96.20504)
		(end 239.046258 -96.20504)
		(width 0.254)
		(layer "F.Cu")
		(net "GND")
	)
	(segment
		(start 451.732142 -50.489866)
		(end 451.730364 -50.488088)
		(width 0.508)
		(layer "F.Cu")
		(net "GND")
	)
	(segment
		(start 107.910376 -101.471984)
		(end 107.62361 -100.977192)
		(width 0.254)
		(layer "F.Cu")
		(net "GND")
	)
	(segment
		(start 76.334366 -51.62804)
		(end 75.762866 -51.62804)
		(width 0.254)
		(layer "F.Cu")
		(net "GND")
	)
	(segment
		(start 459.741016 -45.925486)
		(end 459.741016 -47.481998)
		(width 0.4064)
		(layer "F.Cu")
		(net "GND")
	)
	(segment
		(start 195.549774 -15.423642)
		(end 195.549774 -13.929106)
		(width 0.4064)
		(layer "F.Cu")
		(net "GND")
	)
	(segment
		(start 300.382686 -60.857384)
		(end 300.954186 -60.857384)
		(width 0.254)
		(layer "F.Cu")
		(net "GND")
	)
	(segment
		(start 396.65275 -115.86464)
		(end 397.14805 -116.094764)
		(width 0.254)
		(layer "F.Cu")
		(net "GND")
	)
	(segment
		(start 293.51478 -83.641184)
		(end 294.08628 -83.641184)
		(width 0.254)
		(layer "F.Cu")
		(net "GND")
	)
	(segment
		(start 239.617758 -52.618386)
		(end 239.046258 -52.618386)
		(width 0.254)
		(layer "F.Cu")
		(net "GND")
	)
	(segment
		(start 295.849802 -152.278842)
		(end 295.849802 -154.063446)
		(width 0.4064)
		(layer "F.Cu")
		(net "GND")
	)
	(segment
		(start 127.44958 -21.455888)
		(end 127.44958 -20.023582)
		(width 0.4064)
		(layer "F.Cu")
		(net "GND")
	)
	(segment
		(start 239.617758 -88.28024)
		(end 239.046258 -88.28024)
		(width 0.254)
		(layer "F.Cu")
		(net "GND")
	)
	(segment
		(start 127.655828 -86.117938)
		(end 128.227328 -86.117938)
		(width 0.254)
		(layer "F.Cu")
		(net "GND")
	)
	(segment
		(start 370.727986 -106.935778)
		(end 370.727986 -107.431586)
		(width 0.254)
		(layer "F.Cu")
		(net "GND")
	)
	(segment
		(start 442.89091 -28.632404)
		(end 442.921898 -28.632404)
		(width 0.3048)
		(layer "F.Cu")
		(net "GND")
	)
	(segment
		(start 279.491694 -100.976938)
		(end 279.65654 -101.261164)
		(width 0.4064)
		(layer "F.Cu")
		(net "GND")
	)
	(segment
		(start 297.807126 -97.014538)
		(end 298.378626 -97.014538)
		(width 0.254)
		(layer "F.Cu")
		(net "GND")
	)
	(segment
		(start 237.900718 -50.63744)
		(end 237.329218 -50.63744)
		(width 0.254)
		(layer "F.Cu")
		(net "GND")
	)
	(segment
		(start 255.130046 -12.613386)
		(end 255.87198 -12.613386)
		(width 0.4572)
		(layer "F.Cu")
		(net "GND")
	)
	(segment
		(start 74.617326 -76.39304)
		(end 74.045826 -76.39304)
		(width 0.254)
		(layer "F.Cu")
		(net "GND")
	)
	(segment
		(start 221.899734 -15.602966)
		(end 221.899988 -15.602712)
		(width 0.4064)
		(layer "F.Cu")
		(net "GND")
	)
	(segment
		(start 64.549528 -152.273)
		(end 64.549528 -152.278842)
		(width 0.4064)
		(layer "F.Cu")
		(net "GND")
	)
	(segment
		(start 441.722256 -27.432)
		(end 442.122052 -27.831796)
		(width 0.3048)
		(layer "F.Cu")
		(net "GND")
	)
	(segment
		(start 77.299566 -133.0706)
		(end 77.299566 -133.076442)
		(width 0.4064)
		(layer "F.Cu")
		(net "GND")
	)
	(segment
		(start 389.128 -87.062564)
		(end 389.128 -87.3125)
		(width 0.254)
		(layer "F.Cu")
		(net "GND")
	)
	(segment
		(start 66.24955 -142.856712)
		(end 66.249296 -142.856966)
		(width 0.4064)
		(layer "F.Cu")
		(net "GND")
	)
	(segment
		(start 351.72015 -138.38174)
		(end 351.72015 -138.32205)
		(width 0.508)
		(layer "F.Cu")
		(net "GND")
	)
	(segment
		(start 473.3925 -40.631364)
		(end 473.3925 -41.5925)
		(width 0.254)
		(layer "F.Cu")
		(net "GND")
	)
	(segment
		(start 125.749558 -2.276856)
		(end 125.749558 -0.821182)
		(width 0.4064)
		(layer "F.Cu")
		(net "GND")
	)
	(segment
		(start 195.549774 3.778758)
		(end 195.549774 2.514854)
		(width 0.4064)
		(layer "F.Cu")
		(net "GND")
	)
	(segment
		(start 274.070064 -53.8988)
		(end 274.056094 -53.923184)
		(width 0.254)
		(layer "F.Cu")
		(net "GND")
	)
	(segment
		(start 299.524166 -85.127338)
		(end 300.095666 -85.127338)
		(width 0.254)
		(layer "F.Cu")
		(net "GND")
	)
	(segment
		(start 124.89942 -153.965402)
		(end 124.801376 -154.063446)
		(width 0.4064)
		(layer "F.Cu")
		(net "GND")
	)
	(segment
		(start 125.080268 -78.688438)
		(end 125.651768 -78.688438)
		(width 0.254)
		(layer "F.Cu")
		(net "GND")
	)
	(segment
		(start 113.061242 -93.547184)
		(end 113.632742 -93.547184)
		(width 0.254)
		(layer "F.Cu")
		(net "GND")
	)
	(segment
		(start 91.787218 -86.29904)
		(end 91.215718 -86.29904)
		(width 0.254)
		(layer "F.Cu")
		(net "GND")
	)
	(segment
		(start 62.792102 -136.410446)
		(end 62.792102 -136.397746)
		(width 0.3556)
		(layer "F.Cu")
		(net "GND")
	)
	(segment
		(start 324.52564 -27.88412)
		(end 325.0057 -28.36418)
		(width 0.4572)
		(layer "F.Cu")
		(net "GND")
	)
	(segment
		(start 140.199364 1.994154)
		(end 140.199364 3.778758)
		(width 0.4064)
		(layer "F.Cu")
		(net "GND")
	)
	(segment
		(start 127.44958 -0.821182)
		(end 127.44958 0.38735)
		(width 0.3556)
		(layer "F.Cu")
		(net "GND")
	)
	(segment
		(start 212.549994 3.778758)
		(end 212.549994 3.599688)
		(width 0.4064)
		(layer "F.Cu")
		(net "GND")
	)
	(segment
		(start 108.768896 -102.958138)
		(end 108.768896 -103.5812)
		(width 0.254)
		(layer "F.Cu")
		(net "GND")
	)
	(segment
		(start 134.523734 -76.211938)
		(end 135.095234 -76.211938)
		(width 0.254)
		(layer "F.Cu")
		(net "GND")
	)
	(segment
		(start 62.792102 -11.912092)
		(end 62.849506 -11.854688)
		(width 0.4064)
		(layer "F.Cu")
		(net "GND")
	)
	(segment
		(start 221.899734 -142.856966)
		(end 221.899734 -144.462246)
		(width 0.4064)
		(layer "F.Cu")
		(net "GND")
	)
	(segment
		(start 391.69975 -102.756716)
		(end 392.02741 -102.908862)
		(width 0.254)
		(layer "F.Cu")
		(net "GND")
	)
	(segment
		(start 398.004538 -75.55992)
		(end 399.65884 -75.55992)
		(width 0.254)
		(layer "F.Cu")
		(net "GND")
	)
	(segment
		(start 217.650314 -142.6718)
		(end 217.649806 -142.677642)
		(width 0.3048)
		(layer "F.Cu")
		(net "GND")
	)
	(segment
		(start 298.665646 -74.725784)
		(end 299.237146 -74.725784)
		(width 0.254)
		(layer "F.Cu")
		(net "GND")
	)
	(segment
		(start 401.368768 -125.283468)
		(end 401.295108 -125.357128)
		(width 0.254)
		(layer "F.Cu")
		(net "GND")
	)
	(segment
		(start 445.350138 -58.954924)
		(end 445.350138 -57.596024)
		(width 0.381)
		(layer "F.Cu")
		(net "GND")
	)
	(segment
		(start 43.076368 -7.600188)
		(end 43.076368 -6.781546)
		(width 0.3556)
		(layer "F.Cu")
		(net "GND")
	)
	(segment
		(start 135.735568 -7.609332)
		(end 135.771636 -7.6454)
		(width 0.3556)
		(layer "F.Cu")
		(net "GND")
	)
	(segment
		(start 81.485232 -97.19564)
		(end 80.913732 -97.19564)
		(width 0.254)
		(layer "F.Cu")
		(net "GND")
	)
	(segment
		(start 68.607686 -62.029086)
		(end 68.036186 -62.029086)
		(width 0.254)
		(layer "F.Cu")
		(net "GND")
	)
	(segment
		(start 295.000426 -147.27174)
		(end 294.999918 -147.27174)
		(width 0.4064)
		(layer "F.Cu")
		(net "GND")
	)
	(segment
		(start 378.344684 -79.894684)
		(end 377.944888 -79.494888)
		(width 0.254)
		(layer "F.Cu")
		(net "GND")
	)
	(segment
		(start 234.65028 -133.0706)
		(end 234.649772 -133.076442)
		(width 0.4064)
		(layer "F.Cu")
		(net "GND")
	)
	(segment
		(start 70.499478 -156.87294)
		(end 70.499478 -155.650946)
		(width 0.4064)
		(layer "F.Cu")
		(net "GND")
	)
	(segment
		(start 197.095364 -78.629764)
		(end 196.6976 -78.232)
		(width 0.254)
		(layer "F.Cu")
		(net "GND")
	)
	(segment
		(start 196.200522 -93.871288)
		(end 196.200522 -94.481904)
		(width 0.508)
		(layer "F.Cu")
		(net "GND")
	)
	(segment
		(start 39.899336 -13.363956)
		(end 39.899336 -15.423642)
		(width 0.4064)
		(layer "F.Cu")
		(net "GND")
	)
	(segment
		(start 137.957814 -85.127338)
		(end 138.529314 -85.127338)
		(width 0.254)
		(layer "F.Cu")
		(net "GND")
	)
	(segment
		(start 291.3888 -6.7564)
		(end 291.3888 -7.612126)
		(width 0.3556)
		(layer "F.Cu")
		(net "GND")
	)
	(segment
		(start 376.335036 -118.854982)
		(end 376.428 -119.355108)
		(width 0.254)
		(layer "F.Cu")
		(net "GND")
	)
	(segment
		(start 310.0832 -134.0104)
		(end 310.0832 -134.860538)
		(width 0.3556)
		(layer "F.Cu")
		(net "GND")
	)
	(segment
		(start 282.0162 2.01168)
		(end 282.07208 1.9558)
		(width 0.3556)
		(layer "F.Cu")
		(net "GND")
	)
	(segment
		(start 79.768192 -55.59044)
		(end 79.196692 -55.59044)
		(width 0.254)
		(layer "F.Cu")
		(net "GND")
	)
	(segment
		(start 290.0807 -61.847984)
		(end 290.6522 -61.847984)
		(width 0.254)
		(layer "F.Cu")
		(net "GND")
	)
	(segment
		(start 444.06947 -145.21053)
		(end 443.484 -145.796)
		(width 0.254)
		(layer "F.Cu")
		(net "GND")
	)
	(segment
		(start 381.790448 -118.6688)
		(end 381.79375 -118.670324)
		(width 0.254)
		(layer "F.Cu")
		(net "GND")
	)
	(segment
		(start 433.07 -14.224)
		(end 433.07 -13.947394)
		(width 0.254)
		(layer "F.Cu")
		(net "GND")
	)
	(segment
		(start 451.732396 -50.5206)
		(end 451.732142 -50.489866)
		(width 0.508)
		(layer "F.Cu")
		(net "GND")
	)
	(segment
		(start 136.799574 -20.023582)
		(end 136.799574 -21.455888)
		(width 0.4064)
		(layer "F.Cu")
		(net "GND")
	)
	(segment
		(start 289.050476 -155.600654)
		(end 289.049968 -155.600146)
		(width 0.3556)
		(layer "F.Cu")
		(net "GND")
	)
	(segment
		(start 288.19983 -152.278842)
		(end 288.19983 -154.063446)
		(width 0.4064)
		(layer "F.Cu")
		(net "GND")
	)
	(segment
		(start 249.919744 -98.18624)
		(end 250.206764 -97.690686)
		(width 0.254)
		(layer "F.Cu")
		(net "GND")
	)
	(segment
		(start 70.499478 -146.049746)
		(end 70.461378 -146.011646)
		(width 0.4064)
		(layer "F.Cu")
		(net "GND")
	)
	(segment
		(start 72.900286 -92.24264)
		(end 72.328786 -92.24264)
		(width 0.254)
		(layer "F.Cu")
		(net "GND")
	)
	(segment
		(start 272.624042 -100.977192)
		(end 272.623534 -100.976684)
		(width 0.254)
		(layer "F.Cu")
		(net "GND")
	)
	(segment
		(start 172.3136 -125.21438)
		(end 172.57522 -125.21438)
		(width 0.381)
		(layer "F.Cu")
		(net "GND")
	)
	(segment
		(start 385.719828 -115.438428)
		(end 385.33705 -115.05565)
		(width 0.1143)
		(layer "F.Cu")
		(net "GND")
	)
	(segment
		(start 436.521098 -27.032458)
		(end 436.522114 -27.032458)
		(width 0.3048)
		(layer "F.Cu")
		(net "GND")
	)
	(segment
		(start 60.299346 -152.273)
		(end 60.299346 -153.965402)
		(width 0.4064)
		(layer "F.Cu")
		(net "GND")
	)
	(segment
		(start 28.7274 -60.203588)
		(end 28.677616 -60.253372)
		(width 0.254)
		(layer "F.Cu")
		(net "GND")
	)
	(segment
		(start 307.749956 -2.314956)
		(end 307.749956 -0.821182)
		(width 0.4064)
		(layer "F.Cu")
		(net "GND")
	)
	(segment
		(start 430.875186 -9.607296)
		(end 430.98593 -9.71804)
		(width 0.254)
		(layer "F.Cu")
		(net "GND")
	)
	(segment
		(start 291.3888 2.8448)
		(end 291.3888 1.989074)
		(width 0.3556)
		(layer "F.Cu")
		(net "GND")
	)
	(segment
		(start 73.758806 -60.047886)
		(end 73.187306 -60.047886)
		(width 0.254)
		(layer "F.Cu")
		(net "GND")
	)
	(segment
		(start 245.627144 -56.085486)
		(end 245.055644 -56.085486)
		(width 0.254)
		(layer "F.Cu")
		(net "GND")
	)
	(segment
		(start 423.09034 -34.534602)
		(end 423.490136 -34.934398)
		(width 0.254)
		(layer "F.Cu")
		(net "GND")
	)
	(segment
		(start 414.290256 -35.334702)
		(end 413.890206 -34.934652)
		(width 0.254)
		(layer "F.Cu")
		(net "GND")
	)
	(segment
		(start 252.495304 -87.784686)
		(end 251.923804 -87.784686)
		(width 0.254)
		(layer "F.Cu")
		(net "GND")
	)
	(segment
		(start 284.071314 -65.315338)
		(end 283.499814 -65.315338)
		(width 0.254)
		(layer "F.Cu")
		(net "GND")
	)
	(segment
		(start 2.657348 -125.5141)
		(end 2.657348 -124.629672)
		(width 0.2032)
		(layer "F.Cu")
		(net "GND")
	)
	(segment
		(start 218.500452 -10.422382)
		(end 218.499944 -10.422382)
		(width 0.3556)
		(layer "F.Cu")
		(net "GND")
	)
	(segment
		(start 283.100272 -155.658058)
		(end 283.04236 -155.600146)
		(width 0.3556)
		(layer "F.Cu")
		(net "GND")
	)
	(segment
		(start 307.103272 -67.156838)
		(end 306.963826 -67.296538)
		(width 0.254)
		(layer "F.Cu")
		(net "GND")
	)
	(segment
		(start 113.1824 -69.1642)
		(end 113.1824 -69.4182)
		(width 0.254)
		(layer "F.Cu")
		(net "GND")
	)
	(segment
		(start 168.189402 -63.890398)
		(end 168.3512 -63.7286)
		(width 0.2032)
		(layer "F.Cu")
		(net "GND")
	)
	(segment
		(start 382.78435 -102.12832)
		(end 382.9304 -102.060502)
		(width 0.254)
		(layer "F.Cu")
		(net "GND")
	)
	(segment
		(start 368.685064 -7.789926)
		(end 368.685064 -8.84682)
		(width 0.4064)
		(layer "F.Cu")
		(net "GND")
	)
	(segment
		(start 113.8682 -68.4784)
		(end 113.1824 -69.1642)
		(width 0.254)
		(layer "F.Cu")
		(net "GND")
	)
	(segment
		(start 179.492148 -72.96785)
		(end 178.86045 -72.96785)
		(width 0.508)
		(layer "F.Cu")
		(net "GND")
	)
	(segment
		(start 391.73785 -107.85475)
		(end 392.1379 -108.2548)
		(width 0.12446)
		(layer "F.Cu")
		(net "GND")
	)
	(segment
		(start 235.500418 -10.422382)
		(end 235.49991 -10.422382)
		(width 0.4064)
		(layer "F.Cu")
		(net "GND")
	)
	(segment
		(start 404.158196 -57.805828)
		(end 404.158196 -57.154318)
		(width 0.254)
		(layer "F.Cu")
		(net "GND")
	)
	(segment
		(start 52.649374 -5.822442)
		(end 52.649374 -6.555994)
		(width 0.3048)
		(layer "F.Cu")
		(net "GND")
	)
	(segment
		(start 296.948606 -90.575384)
		(end 297.520106 -90.575384)
		(width 0.3048)
		(layer "F.Cu")
		(net "GND")
	)
	(segment
		(start 299.524166 -76.211938)
		(end 300.095666 -76.211938)
		(width 0.254)
		(layer "F.Cu")
		(net "GND")
	)
	(segment
		(start 305.200304 -5.822442)
		(end 305.199796 -5.822442)
		(width 0.4064)
		(layer "F.Cu")
		(net "GND")
	)
	(segment
		(start 198.949818 -133.076442)
		(end 198.949818 -133.790182)
		(width 0.3556)
		(layer "F.Cu")
		(net "GND")
	)
	(segment
		(start 144.449546 -10.422382)
		(end 144.449546 -9.156446)
		(width 0.4064)
		(layer "F.Cu")
		(net "GND")
	)
	(segment
		(start 39.899336 -7.607046)
		(end 39.899336 -5.822442)
		(width 0.4064)
		(layer "F.Cu")
		(net "GND")
	)
	(segment
		(start 316.547754 -33.036764)
		(end 315.683392 -32.172402)
		(width 0.4064)
		(layer "F.Cu")
		(net "GND")
	)
	(segment
		(start 96.746568 -24.638)
		(end 97.660968 -24.638)
		(width 0.4064)
		(layer "F.Cu")
		(net "GND")
	)
	(segment
		(start 467.2076 -113.74628)
		(end 467.2076 -114.41176)
		(width 0.4064)
		(layer "F.Cu")
		(net "GND")
	)
	(segment
		(start 129.999486 -20.023582)
		(end 129.999486 -21.517356)
		(width 0.4064)
		(layer "F.Cu")
		(net "GND")
	)
	(segment
		(start 62.849506 -10.422382)
		(end 62.849506 -9.21385)
		(width 0.3556)
		(layer "F.Cu")
		(net "GND")
	)
	(segment
		(start 89.789 -149.8092)
		(end 90.153236 -149.444964)
		(width 0.4064)
		(layer "F.Cu")
		(net "GND")
	)
	(segment
		(start 387.484874 -125.750066)
		(end 387.985 -126.165102)
		(width 0.254)
		(layer "F.Cu")
		(net "GND")
	)
	(segment
		(start 218.44254 -9.156446)
		(end 218.499944 -9.21385)
		(width 0.3556)
		(layer "F.Cu")
		(net "GND")
	)
	(segment
		(start 205.749906 -21.517356)
		(end 205.749906 -20.023582)
		(width 0.4064)
		(layer "F.Cu")
		(net "GND")
	)
	(segment
		(start 400.880072 -115.355116)
		(end 400.05 -115.355116)
		(width 0.254)
		(layer "F.Cu")
		(net "GND")
	)
	(segment
		(start 72.900286 -99.17684)
		(end 72.328786 -99.17684)
		(width 0.254)
		(layer "F.Cu")
		(net "GND")
	)
	(segment
		(start 78.909672 -90.756486)
		(end 78.338172 -90.756486)
		(width 0.254)
		(layer "F.Cu")
		(net "GND")
	)
	(segment
		(start 294.150288 -15.423642)
		(end 294.14978 -15.423642)
		(width 0.4064)
		(layer "F.Cu")
		(net "GND")
	)
	(segment
		(start 110.485682 -97.014538)
		(end 111.057182 -97.014538)
		(width 0.254)
		(layer "F.Cu")
		(net "GND")
	)
	(segment
		(start 145.082768 -134.860538)
		(end 145.12163 -134.8994)
		(width 0.3556)
		(layer "F.Cu")
		(net "GND")
	)
	(segment
		(start 128.514348 -98.500184)
		(end 129.085848 -98.500184)
		(width 0.254)
		(layer "F.Cu")
		(net "GND")
	)
	(segment
		(start 235.46181 -11.916156)
		(end 235.46181 -12.84859)
		(width 0.4064)
		(layer "F.Cu")
		(net "GND")
	)
	(segment
		(start 280.549858 -7.509002)
		(end 280.451814 -7.607046)
		(width 0.4064)
		(layer "F.Cu")
		(net "GND")
	)
	(segment
		(start 283.100272 -20.023582)
		(end 283.099764 -20.023582)
		(width 0.3556)
		(layer "F.Cu")
		(net "GND")
	)
	(segment
		(start 480.15144 -28.61056)
		(end 479.3742 -29.3878)
		(width 0.254)
		(layer "F.Cu")
		(net "GND")
	)
	(segment
		(start 411.89021 -30.534356)
		(end 412.290006 -30.13456)
		(width 0.254)
		(layer "F.Cu")
		(net "GND")
	)
	(segment
		(start 201.499978 -133.076442)
		(end 201.499724 -133.076696)
		(width 0.4064)
		(layer "F.Cu")
		(net "GND")
	)
	(segment
		(start 77.192886 -101.653086)
		(end 76.862432 -102.214934)
		(width 0.254)
		(layer "F.Cu")
		(net "GND")
	)
	(segment
		(start 401.295108 -122.918728)
		(end 402.141182 -122.918728)
		(width 0.254)
		(layer "F.Cu")
		(net "GND")
	)
	(segment
		(start 206.59979 -5.822442)
		(end 206.59979 -7.509002)
		(width 0.4064)
		(layer "F.Cu")
		(net "GND")
	)
	(segment
		(start 118.099332 -21.455888)
		(end 118.099332 -20.023582)
		(width 0.4064)
		(layer "F.Cu")
		(net "GND")
	)
	(segment
		(start 458.258164 -50.792888)
		(end 458.258164 -50.411888)
		(width 0.508)
		(layer "F.Cu")
		(net "GND")
	)
	(segment
		(start 374.674892 -111.854996)
		(end 374.244108 -111.854996)
		(width 0.254)
		(layer "F.Cu")
		(net "GND")
	)
	(segment
		(start 310.299862 3.778758)
		(end 310.299862 3.061462)
		(width 0.3556)
		(layer "F.Cu")
		(net "GND")
	)
	(segment
		(start 282.250388 3.778758)
		(end 282.24988 3.778758)
		(width 0.3556)
		(layer "F.Cu")
		(net "GND")
	)
	(segment
		(start 316.25032 -152.273)
		(end 316.249812 -152.278842)
		(width 0.4064)
		(layer "F.Cu")
		(net "GND")
	)
	(segment
		(start 291.79774 -91.565984)
		(end 292.36924 -91.565984)
		(width 0.254)
		(layer "F.Cu")
		(net "GND")
	)
	(segment
		(start 235.46181 -12.84859)
		(end 234.649772 -13.660628)
		(width 0.4064)
		(layer "F.Cu")
		(net "GND")
	)
	(segment
		(start 46.699424 -139.170156)
		(end 46.699424 -137.67054)
		(width 0.4064)
		(layer "F.Cu")
		(net "GND")
	)
	(segment
		(start 299.249846 -152.278842)
		(end 299.249846 -153.965402)
		(width 0.4064)
		(layer "F.Cu")
		(net "GND")
	)
	(segment
		(start 236.183678 -93.23324)
		(end 235.612178 -93.23324)
		(width 0.254)
		(layer "F.Cu")
		(net "GND")
	)
	(segment
		(start 90.626692 -149.444964)
		(end 90.626692 -150.098506)
		(width 0.4064)
		(layer "F.Cu")
		(net "GND")
	)
	(segment
		(start 394.984986 -124.13488)
		(end 394.67155 -123.821444)
		(width 0.254)
		(layer "F.Cu")
		(net "GND")
	)
	(segment
		(start 250.778264 -94.718886)
		(end 250.206764 -94.718886)
		(width 0.254)
		(layer "F.Cu")
		(net "GND")
	)
	(segment
		(start 152.099518 -147.27174)
		(end 152.099518 -146.011646)
		(width 0.4064)
		(layer "F.Cu")
		(net "GND")
	)
	(segment
		(start 182.6006 -145.288)
		(end 181.9402 -144.6276)
		(width 0.254)
		(layer "F.Cu")
		(net "GND")
	)
	(segment
		(start 43.076368 -153.237946)
		(end 43.076368 -154.056588)
		(width 0.3556)
		(layer "F.Cu")
		(net "GND")
	)
	(segment
		(start 382.725676 -112.866424)
		(end 382.498092 -112.866424)
		(width 0.1143)
		(layer "F.Cu")
		(net "GND")
	)
	(segment
		(start 366.2172 -96.27616)
		(end 366.2172 -98.552)
		(width 0.254)
		(layer "F.Cu")
		(net "GND")
	)
	(segment
		(start 33.061402 -21.517356)
		(end 33.099502 -21.479256)
		(width 0.4064)
		(layer "F.Cu")
		(net "GND")
	)
	(segment
		(start 40.749474 -147.27174)
		(end 40.749474 -145.998946)
		(width 0.4064)
		(layer "F.Cu")
		(net "GND")
	)
	(segment
		(start 303.529746 -88.099138)
		(end 302.958246 -88.099138)
		(width 0.3048)
		(layer "F.Cu")
		(net "GND")
	)
	(segment
		(start 227.849938 -21.455888)
		(end 227.792534 -21.513292)
		(width 0.4064)
		(layer "F.Cu")
		(net "GND")
	)
	(segment
		(start 239.046258 -101.15804)
		(end 239.617758 -101.15804)
		(width 0.254)
		(layer "F.Cu")
		(net "GND")
	)
	(segment
		(start 212.549994 -142.677642)
		(end 212.549994 -142.856712)
		(width 0.4064)
		(layer "F.Cu")
		(net "GND")
	)
	(segment
		(start 78.051406 -57.57164)
		(end 77.479906 -57.57164)
		(width 0.254)
		(layer "F.Cu")
		(net "GND")
	)
	(segment
		(start 233.608118 -93.72854)
		(end 232.960418 -93.72854)
		(width 0.254)
		(layer "F.Cu")
		(net "GND")
	)
	(segment
		(start 80.626712 -71.935086)
		(end 80.055212 -71.935086)
		(width 0.254)
		(layer "F.Cu")
		(net "GND")
	)
	(segment
		(start 230.399844 -137.67054)
		(end 230.399844 -136.410446)
		(width 0.4064)
		(layer "F.Cu")
		(net "GND")
	)
	(segment
		(start 226.7966 -134.874)
		(end 226.822 -134.8994)
		(width 0.3556)
		(layer "F.Cu")
		(net "GND")
	)
	(segment
		(start 82.343752 -96.700086)
		(end 81.772252 -96.700086)
		(width 0.254)
		(layer "F.Cu")
		(net "GND")
	)
	(segment
		(start 44.092114 0.406654)
		(end 44.149518 0.34925)
		(width 0.4064)
		(layer "F.Cu")
		(net "GND")
	)
	(segment
		(start 418.385244 -120.975882)
		(end 418.385244 -120.415304)
		(width 0.4064)
		(layer "F.Cu")
		(net "GND")
	)
	(segment
		(start 139.674854 -58.381138)
		(end 140.246354 -58.381138)
		(width 0.254)
		(layer "F.Cu")
		(net "GND")
	)
	(segment
		(start 240.600484 -142.6718)
		(end 240.599976 -142.677642)
		(width 0.4064)
		(layer "F.Cu")
		(net "GND")
	)
	(segment
		(start 387.314186 -124.206)
		(end 387.73735 -123.821444)
		(width 0.254)
		(layer "F.Cu")
		(net "GND")
	)
	(segment
		(start 126.388368 -143.6116)
		(end 126.388368 -144.467326)
		(width 0.3556)
		(layer "F.Cu")
		(net "GND")
	)
	(segment
		(start 247.344184 -95.709486)
		(end 246.772684 -95.709486)
		(width 0.254)
		(layer "F.Cu")
		(net "GND")
	)
	(segment
		(start 56.049418 -147.27174)
		(end 56.049418 -146.011646)
		(width 0.4064)
		(layer "F.Cu")
		(net "GND")
	)
	(segment
		(start 142.749524 -156.87294)
		(end 142.749524 -155.600146)
		(width 0.4064)
		(layer "F.Cu")
		(net "GND")
	)
	(segment
		(start 299.250354 -142.6718)
		(end 299.249846 -142.677642)
		(width 0.4064)
		(layer "F.Cu")
		(net "GND")
	)
	(segment
		(start 198.950326 3.778758)
		(end 198.949818 3.778758)
		(width 0.3556)
		(layer "F.Cu")
		(net "GND")
	)
	(segment
		(start 109.055916 -55.904384)
		(end 109.627416 -55.904384)
		(width 0.254)
		(layer "F.Cu")
		(net "GND")
	)
	(segment
		(start 287.21812 -76.706984)
		(end 286.64662 -76.706984)
		(width 0.254)
		(layer "F.Cu")
		(net "GND")
	)
	(segment
		(start 418.073586 -3.515614)
		(end 418.1856 -3.4036)
		(width 0.254)
		(layer "F.Cu")
		(net "GND")
	)
	(segment
		(start 312.850276 -5.822442)
		(end 312.849768 -5.822442)
		(width 0.4064)
		(layer "F.Cu")
		(net "GND")
	)
	(segment
		(start 459.80096 -116.993162)
		(end 459.80096 -118.615714)
		(width 0.4064)
		(layer "F.Cu")
		(net "GND")
	)
	(segment
		(start 196.399912 -9.139682)
		(end 196.399912 -10.422382)
		(width 0.4064)
		(layer "F.Cu")
		(net "GND")
	)
	(segment
		(start 15.494 -97.8916)
		(end 15.2146 -98.171)
		(width 0.4064)
		(layer "F.Cu")
		(net "GND")
	)
	(segment
		(start 482.8286 -138.5316)
		(end 483.067614 -138.770614)
		(width 0.254)
		(layer "F.Cu")
		(net "GND")
	)
	(segment
		(start 306.392326 -95.033084)
		(end 307.281326 -95.033084)
		(width 0.254)
		(layer "F.Cu")
		(net "GND")
	)
	(segment
		(start 305.200304 -142.6718)
		(end 305.199796 -142.677642)
		(width 0.4064)
		(layer "F.Cu")
		(net "GND")
	)
	(segment
		(start 241.334798 -96.20504)
		(end 240.763298 -96.20504)
		(width 0.254)
		(layer "F.Cu")
		(net "GND")
	)
	(segment
		(start 85.777832 -65.991486)
		(end 85.206332 -65.991486)
		(width 0.254)
		(layer "F.Cu")
		(net "GND")
	)
	(segment
		(start 38.199314 -152.458166)
		(end 38.199314 -154.063446)
		(width 0.4064)
		(layer "F.Cu")
		(net "GND")
	)
	(segment
		(start 225.299778 -3.826256)
		(end 225.299778 -5.822442)
		(width 0.4064)
		(layer "F.Cu")
		(net "GND")
	)
	(segment
		(start 27.98572 -71.35368)
		(end 28.147518 -71.515478)
		(width 0.254)
		(layer "F.Cu")
		(net "GND")
	)
	(segment
		(start 241.334798 -94.223586)
		(end 240.763298 -94.223586)
		(width 0.254)
		(layer "F.Cu")
		(net "GND")
	)
	(segment
		(start 491.109 -136.293352)
		(end 490.081062 -135.265414)
		(width 0.254)
		(layer "F.Cu")
		(net "GND")
	)
	(segment
		(start 252.495304 -65.991486)
		(end 251.923804 -65.991486)
		(width 0.254)
		(layer "F.Cu")
		(net "GND")
	)
	(segment
		(start 215.100408 -0.821182)
		(end 215.0999 -0.821182)
		(width 0.4064)
		(layer "F.Cu")
		(net "GND")
	)
	(segment
		(start 236.183678 -72.43064)
		(end 235.612178 -72.43064)
		(width 0.254)
		(layer "F.Cu")
		(net "GND")
	)
	(segment
		(start 71.117968 2.009394)
		(end 71.171562 1.9558)
		(width 0.3556)
		(layer "F.Cu")
		(net "GND")
	)
	(segment
		(start 376.985022 -125.435106)
		(end 376.20067 -125.435106)
		(width 0.254)
		(layer "F.Cu")
		(net "GND")
	)
	(segment
		(start 208.0768 -17.201388)
		(end 208.0768 -16.382746)
		(width 0.3556)
		(layer "F.Cu")
		(net "GND")
	)
	(segment
		(start 75.599544 -152.457912)
		(end 75.59929 -152.458166)
		(width 0.4064)
		(layer "F.Cu")
		(net "GND")
	)
	(segment
		(start 135.099552 -156.87294)
		(end 135.099552 -155.612846)
		(width 0.4064)
		(layer "F.Cu")
		(net "GND")
	)
	(segment
		(start 298.399962 -155.600146)
		(end 298.399962 -156.87294)
		(width 0.4064)
		(layer "F.Cu")
		(net "GND")
	)
	(segment
		(start 374.6246 -158.2166)
		(end 373.978932 -158.2166)
		(width 0.254)
		(layer "F.Cu")
		(net "GND")
	)
	(segment
		(start 454.949814 -57.596278)
		(end 454.950068 -57.596024)
		(width 0.381)
		(layer "F.Cu")
		(net "GND")
	)
	(segment
		(start 220.200474 -142.6718)
		(end 220.199966 -142.677642)
		(width 0.4064)
		(layer "F.Cu")
		(net "GND")
	)
	(segment
		(start 26.9748 -76.8858)
		(end 26.8224 -76.7334)
		(width 0.254)
		(layer "F.Cu")
		(net "GND")
	)
	(segment
		(start 238.900462 -15.423642)
		(end 238.899954 -15.423642)
		(width 0.4064)
		(layer "F.Cu")
		(net "GND")
	)
	(segment
		(start 208.122012 -7.6454)
		(end 208.0768 -7.600188)
		(width 0.3556)
		(layer "F.Cu")
		(net "GND")
	)
	(segment
		(start 384.0226 -23.0124)
		(end 383.764028 -23.270972)
		(width 0.254)
		(layer "F.Cu")
		(net "GND")
	)
	(segment
		(start 476.4786 -40.3479)
		(end 476.1611 -40.3479)
		(width 0.254)
		(layer "F.Cu")
		(net "GND")
	)
	(segment
		(start 236.183678 -51.62804)
		(end 235.612178 -51.62804)
		(width 0.254)
		(layer "F.Cu")
		(net "GND")
	)
	(segment
		(start 13.54836 5.155184)
		(end 14.358112 5.155184)
		(width 0.381)
		(layer "F.Cu")
		(net "GND")
	)
	(segment
		(start 235.612178 -98.18624)
		(end 234.466638 -98.18624)
		(width 0.254)
		(layer "F.Cu")
		(net "GND")
	)
	(segment
		(start 206.59979 -144.364202)
		(end 206.501746 -144.462246)
		(width 0.4064)
		(layer "F.Cu")
		(net "GND")
	)
	(segment
		(start 242.193318 -101.653086)
		(end 241.862864 -102.214934)
		(width 0.254)
		(layer "F.Cu")
		(net "GND")
	)
	(segment
		(start 198.755 -143.5862)
		(end 198.755 -144.483582)
		(width 0.3556)
		(layer "F.Cu")
		(net "GND")
	)
	(segment
		(start 289.22218 -84.136738)
		(end 289.79368 -84.136738)
		(width 0.254)
		(layer "F.Cu")
		(net "GND")
	)
	(segment
		(start 447.000884 -118.615714)
		(end 447.00444 -118.61927)
		(width 0.4064)
		(layer "F.Cu")
		(net "GND")
	)
	(segment
		(start 415.757106 -49.106582)
		(end 415.47288 -49.390808)
		(width 0.254)
		(layer "F.Cu")
		(net "GND")
	)
	(segment
		(start 461.18018 -53.14442)
		(end 461.349852 -52.974748)
		(width 0.4064)
		(layer "F.Cu")
		(net "GND")
	)
	(segment
		(start 314.550298 -15.423642)
		(end 314.54979 -15.423642)
		(width 0.4064)
		(layer "F.Cu")
		(net "GND")
	)
	(segment
		(start 226.149916 -2.276856)
		(end 226.149916 -0.821182)
		(width 0.4064)
		(layer "F.Cu")
		(net "GND")
	)
	(segment
		(start 166.8526 -122.68962)
		(end 166.3192 -123.22302)
		(width 0.254)
		(layer "F.Cu")
		(net "GND")
	)
	(segment
		(start 121.499376 -17.208246)
		(end 121.499376 -15.423642)
		(width 0.4064)
		(layer "F.Cu")
		(net "GND")
	)
	(segment
		(start 124.049536 -20.023582)
		(end 124.049536 -21.517356)
		(width 0.4064)
		(layer "F.Cu")
		(net "GND")
	)
	(segment
		(start 241.450368 -137.67054)
		(end 241.44986 -137.67054)
		(width 0.4064)
		(layer "F.Cu")
		(net "GND")
	)
	(segment
		(start 232.950512 -5.822442)
		(end 232.950512 -3.763518)
		(width 0.4064)
		(layer "F.Cu")
		(net "GND")
	)
	(segment
		(start 116.495322 -51.941984)
		(end 116.495322 -50.952146)
		(width 0.2286)
		(layer "F.Cu")
		(net "GND")
	)
	(segment
		(start 374.142 -109.913674)
		(end 374.02262 -109.913674)
		(width 0.254)
		(layer "F.Cu")
		(net "GND")
	)
	(segment
		(start 96.079818 -56.085486)
		(end 95.508318 -56.085486)
		(width 0.254)
		(layer "F.Cu")
		(net "GND")
	)
	(segment
		(start 198.755 -154.084782)
		(end 198.772018 -154.1018)
		(width 0.3556)
		(layer "F.Cu")
		(net "GND")
	)
	(segment
		(start 67.099434 -18.757646)
		(end 67.099434 -20.023582)
		(width 0.4064)
		(layer "F.Cu")
		(net "GND")
	)
	(segment
		(start 298.665646 -69.772784)
		(end 299.237146 -69.772784)
		(width 0.254)
		(layer "F.Cu")
		(net "GND")
	)
	(segment
		(start 210.849718 -152.279096)
		(end 210.849718 -153.093674)
		(width 0.4064)
		(layer "F.Cu")
		(net "GND")
	)
	(segment
		(start 232.94975 -152.279096)
		(end 232.94975 -154.063446)
		(width 0.4064)
		(layer "F.Cu")
		(net "GND")
	)
	(segment
		(start 211.700364 -147.27174)
		(end 211.699856 -147.27174)
		(width 0.4064)
		(layer "F.Cu")
		(net "GND")
	)
	(segment
		(start 242.300506 -17.207484)
		(end 242.299744 -17.208246)
		(width 0.4064)
		(layer "F.Cu")
		(net "GND")
	)
	(segment
		(start 138.499342 -153.093674)
		(end 138.040872 -153.552144)
		(width 0.4064)
		(layer "F.Cu")
		(net "GND")
	)
	(segment
		(start 250.778264 -78.869286)
		(end 250.206764 -78.869286)
		(width 0.254)
		(layer "F.Cu")
		(net "GND")
	)
	(segment
		(start 311.092596 -18.744946)
		(end 311.092596 -18.757646)
		(width 0.3556)
		(layer "F.Cu")
		(net "GND")
	)
	(segment
		(start 289.22218 -97.014538)
		(end 289.79368 -97.014538)
		(width 0.1651)
		(layer "F.Cu")
		(net "GND")
	)
	(segment
		(start 80.626712 -78.869286)
		(end 80.055212 -78.869286)
		(width 0.254)
		(layer "F.Cu")
		(net "GND")
	)
	(segment
		(start 282.24988 -133.076442)
		(end 282.24988 -133.802374)
		(width 0.3556)
		(layer "F.Cu")
		(net "GND")
	)
	(segment
		(start 398.361662 -96.524064)
		(end 398.13865 -96.747076)
		(width 0.2032)
		(layer "F.Cu")
		(net "GND")
	)
	(segment
		(start 197.249796 -134.763002)
		(end 197.151752 -134.861046)
		(width 0.4064)
		(layer "F.Cu")
		(net "GND")
	)
	(segment
		(start 383.951734 -26.270966)
		(end 383.9591 -26.2636)
		(width 0.254)
		(layer "F.Cu")
		(net "GND")
	)
	(segment
		(start 290.74999 -21.479256)
		(end 290.71189 -21.517356)
		(width 0.4064)
		(layer "F.Cu")
		(net "GND")
	)
	(segment
		(start 237.142528 -18.757646)
		(end 237.199932 -18.81505)
		(width 0.3556)
		(layer "F.Cu")
		(net "GND")
	)
	(segment
		(start 131.089908 -98.995738)
		(end 131.661408 -98.995738)
		(width 0.254)
		(layer "F.Cu")
		(net "GND")
	)
	(segment
		(start 407.1112 -9.495028)
		(end 407.12136 -9.495028)
		(width 0.254)
		(layer "F.Cu")
		(net "GND")
	)
	(segment
		(start 382.93675 -115.05565)
		(end 382.688338 -115.304062)
		(width 0.1143)
		(layer "F.Cu")
		(net "GND")
	)
	(segment
		(start 157.8864 -121.75998)
		(end 156.70022 -121.75998)
		(width 0.4572)
		(layer "F.Cu")
		(net "GND")
	)
	(segment
		(start 126.388368 2.8448)
		(end 126.388368 1.989074)
		(width 0.3556)
		(layer "F.Cu")
		(net "GND")
	)
	(segment
		(start 287.21812 -87.603584)
		(end 286.64662 -87.603584)
		(width 0.254)
		(layer "F.Cu")
		(net "GND")
	)
	(segment
		(start 296.66184 -82.155284)
		(end 296.09034 -82.155284)
		(width 0.254)
		(layer "F.Cu")
		(net "GND")
	)
	(segment
		(start 278.849836 -138.79195)
		(end 278.849836 -137.676382)
		(width 0.508)
		(layer "F.Cu")
		(net "GND")
	)
	(segment
		(start 59.449462 -21.517356)
		(end 59.449462 -20.023582)
		(width 0.4064)
		(layer "F.Cu")
		(net "GND")
	)
	(segment
		(start 131.948174 -80.669384)
		(end 132.519674 -80.669384)
		(width 0.254)
		(layer "F.Cu")
		(net "GND")
	)
	(segment
		(start 135.735568 -154.065732)
		(end 135.771636 -154.1018)
		(width 0.3556)
		(layer "F.Cu")
		(net "GND")
	)
	(segment
		(start 140.199364 -13.363956)
		(end 140.199364 -15.423642)
		(width 0.4064)
		(layer "F.Cu")
		(net "GND")
	)
	(segment
		(start 239.749838 -147.27174)
		(end 239.749838 -146.011646)
		(width 0.4064)
		(layer "F.Cu")
		(net "GND")
	)
	(segment
		(start 264.51433 -53.113686)
		(end 263.94283 -53.113686)
		(width 0.254)
		(layer "F.Cu")
		(net "GND")
	)
	(segment
		(start 267.948156 -56.085486)
		(end 268.557756 -56.085486)
		(width 0.254)
		(layer "F.Cu")
		(net "GND")
	)
	(segment
		(start 401.3581 -84.328)
		(end 401.6121 -84.582)
		(width 0.254)
		(layer "F.Cu")
		(net "GND")
	)
	(segment
		(start 295.85031 -5.822442)
		(end 295.849802 -5.822442)
		(width 0.4064)
		(layer "F.Cu")
		(net "GND")
	)
	(segment
		(start 317.100458 -15.423642)
		(end 317.09995 -15.423642)
		(width 0.4064)
		(layer "F.Cu")
		(net "GND")
	)
	(segment
		(start 398.871186 -4.386072)
		(end 398.871186 -3.316986)
		(width 0.254)
		(layer "F.Cu")
		(net "GND")
	)
	(segment
		(start 452.742808 -60.6552)
		(end 452.742808 -60.378848)
		(width 0.381)
		(layer "F.Cu")
		(net "GND")
	)
	(segment
		(start 75.599544 -133.255512)
		(end 75.59929 -133.255766)
		(width 0.4064)
		(layer "F.Cu")
		(net "GND")
	)
	(segment
		(start 84.060792 -84.812886)
		(end 83.489292 -84.812886)
		(width 0.254)
		(layer "F.Cu")
		(net "GND")
	)
	(segment
		(start 418.6936 -54.353968)
		(end 417.722304 -53.382672)
		(width 0.254)
		(layer "F.Cu")
		(net "GND")
	)
	(segment
		(start 352.502724 1.317498)
		(end 352.502724 0.84328)
		(width 0.254)
		(layer "F.Cu")
		(net "GND")
	)
	(segment
		(start 129.149348 -5.822442)
		(end 129.149348 -4.808728)
		(width 0.4064)
		(layer "F.Cu")
		(net "GND")
	)
	(segment
		(start 314.54979 -7.607046)
		(end 314.54979 -5.822442)
		(width 0.4064)
		(layer "F.Cu")
		(net "GND")
	)
	(segment
		(start 396.768066 -41.54932)
		(end 396.98168 -41.54932)
		(width 0.254)
		(layer "F.Cu")
		(net "GND")
	)
	(segment
		(start 244.768624 -91.25204)
		(end 244.197124 -91.25204)
		(width 0.254)
		(layer "F.Cu")
		(net "GND")
	)
	(segment
		(start 393.18565 -113.28908)
		(end 393.18946 -113.299748)
		(width 0.254)
		(layer "F.Cu")
		(net "GND")
	)
	(segment
		(start 73.899522 -5.822442)
		(end 73.899268 -5.822696)
		(width 0.4064)
		(layer "F.Cu")
		(net "GND")
	)
	(segment
		(start 61.796168 -144.4752)
		(end 61.821568 -144.5006)
		(width 0.3556)
		(layer "F.Cu")
		(net "GND")
	)
	(segment
		(start 96.145096 -1.582928)
		(end 96.213168 -1.651)
		(width 0.254)
		(layer "F.Cu")
		(net "GND")
	)
	(segment
		(start 77.299566 -150.23211)
		(end 77.286612 -150.219156)
		(width 0.508)
		(layer "F.Cu")
		(net "GND")
	)
	(segment
		(start 394.285216 -124.206)
		(end 394.5382 -123.954286)
		(width 0.254)
		(layer "F.Cu")
		(net "GND")
	)
	(segment
		(start 117.015768 -16.383254)
		(end 117.249448 -16.149574)
		(width 0.3556)
		(layer "F.Cu")
		(net "GND")
	)
	(segment
		(start 473.400882 -113.635282)
		(end 473.5322 -113.7666)
		(width 0.4064)
		(layer "F.Cu")
		(net "GND")
	)
	(segment
		(start 425.274486 -4.386072)
		(end 425.274486 -2.941828)
		(width 0.254)
		(layer "F.Cu")
		(net "GND")
	)
	(segment
		(start 202.349862 -139.170156)
		(end 201.031856 -139.1666)
		(width 0.254)
		(layer "F.Cu")
		(net "GND")
	)
	(segment
		(start 310.0832 -16.3576)
		(end 310.299862 -16.140938)
		(width 0.3556)
		(layer "F.Cu")
		(net "GND")
	)
	(segment
		(start 145.29943 -143.394938)
		(end 145.082768 -143.6116)
		(width 0.3556)
		(layer "F.Cu")
		(net "GND")
	)
	(segment
		(start 151.257 -22.972776)
		(end 151.24938 -22.965156)
		(width 0.508)
		(layer "F.Cu")
		(net "GND")
	)
	(segment
		(start 60.299346 -144.364202)
		(end 60.201302 -144.462246)
		(width 0.4064)
		(layer "F.Cu")
		(net "GND")
	)
	(segment
		(start 290.93922 -87.108538)
		(end 291.51072 -87.108538)
		(width 0.254)
		(layer "F.Cu")
		(net "GND")
	)
	(segment
		(start 294.3733 -63.334138)
		(end 294.9448 -63.334138)
		(width 0.254)
		(layer "F.Cu")
		(net "GND")
	)
	(segment
		(start 475.64802 -27.117294)
		(end 475.64802 -27.7495)
		(width 0.254)
		(layer "F.Cu")
		(net "GND")
	)
	(segment
		(start 136.799574 -136.46785)
		(end 136.74217 -136.410446)
		(width 0.3556)
		(layer "F.Cu")
		(net "GND")
	)
	(segment
		(start 125.080268 -90.575384)
		(end 125.651768 -90.575384)
		(width 0.1651)
		(layer "F.Cu")
		(net "GND")
	)
	(segment
		(start 477.863916 -17.59839)
		(end 476.82658 -16.561054)
		(width 0.254)
		(layer "F.Cu")
		(net "GND")
	)
	(segment
		(start 237.900718 -80.35544)
		(end 237.329218 -80.35544)
		(width 0.254)
		(layer "F.Cu")
		(net "GND")
	)
	(segment
		(start 86.636352 -61.53404)
		(end 86.064852 -61.53404)
		(width 0.254)
		(layer "F.Cu")
		(net "GND")
	)
	(segment
		(start 243.051838 -78.37424)
		(end 242.480338 -78.37424)
		(width 0.254)
		(layer "F.Cu")
		(net "GND")
	)
	(segment
		(start 30.865826 -85.4837)
		(end 30.216348 -85.4837)
		(width 0.508)
		(layer "F.Cu")
		(net "GND")
	)
	(segment
		(start 173.8757 -127.88138)
		(end 174.0027 -128.00838)
		(width 0.381)
		(layer "F.Cu")
		(net "GND")
	)
	(segment
		(start 64.549274 -133.891274)
		(end 64.090804 -134.349744)
		(width 0.4064)
		(layer "F.Cu")
		(net "GND")
	)
	(segment
		(start 452.600822 -116.993162)
		(end 452.604378 -118.61927)
		(width 0.4064)
		(layer "F.Cu")
		(net "GND")
	)
	(segment
		(start 34.799524 -2.253488)
		(end 34.74212 -2.310892)
		(width 0.4064)
		(layer "F.Cu")
		(net "GND")
	)
	(segment
		(start 209.150458 -156.87294)
		(end 209.14995 -156.87294)
		(width 0.4064)
		(layer "F.Cu")
		(net "GND")
	)
	(segment
		(start 450.149976 -62.00267)
		(end 450.149976 -60.835286)
		(width 0.381)
		(layer "F.Cu")
		(net "GND")
	)
	(segment
		(start 135.382254 -67.791584)
		(end 135.953754 -67.791584)
		(width 0.254)
		(layer "F.Cu")
		(net "GND")
	)
	(segment
		(start 52.649374 -152.273)
		(end 52.649374 -153.012394)
		(width 0.3048)
		(layer "F.Cu")
		(net "GND")
	)
	(segment
		(start 121.499376 -152.273)
		(end 121.499376 -154.063446)
		(width 0.4064)
		(layer "F.Cu")
		(net "GND")
	)
	(segment
		(start 212.549994 -15.602712)
		(end 212.549994 -15.423642)
		(width 0.4064)
		(layer "F.Cu")
		(net "GND")
	)
	(segment
		(start 135.382254 -63.829184)
		(end 135.953754 -63.829184)
		(width 0.254)
		(layer "F.Cu")
		(net "GND")
	)
	(segment
		(start 92.645738 -86.794086)
		(end 92.074238 -86.794086)
		(width 0.254)
		(layer "F.Cu")
		(net "GND")
	)
	(segment
		(start 384.937 -113.0554)
		(end 384.53695 -113.45545)
		(width 0.1143)
		(layer "F.Cu")
		(net "GND")
	)
	(segment
		(start 115.636802 -97.014538)
		(end 116.208302 -97.014538)
		(width 0.254)
		(layer "F.Cu")
		(net "GND")
	)
	(segment
		(start 309.449978 -155.612846)
		(end 309.449978 -156.87294)
		(width 0.4064)
		(layer "F.Cu")
		(net "GND")
	)
	(segment
		(start 295.23182 -82.650584)
		(end 295.80332 -82.650584)
		(width 0.254)
		(layer "F.Cu")
		(net "GND")
	)
	(segment
		(start 253.353824 -83.32724)
		(end 252.782324 -83.32724)
		(width 0.254)
		(layer "F.Cu")
		(net "GND")
	)
	(segment
		(start 29.705046 -105.918508)
		(end 29.02458 -105.918508)
		(width 0.4064)
		(layer "F.Cu")
		(net "GND")
	)
	(segment
		(start 233.800396 -20.023582)
		(end 233.799888 -20.023582)
		(width 0.4064)
		(layer "F.Cu")
		(net "GND")
	)
	(segment
		(start 286.499808 -133.076442)
		(end 286.499808 -134.861046)
		(width 0.3556)
		(layer "F.Cu")
		(net "GND")
	)
	(segment
		(start 82.343752 -81.841086)
		(end 81.772252 -81.841086)
		(width 0.254)
		(layer "F.Cu")
		(net "GND")
	)
	(segment
		(start 249.919744 -86.29904)
		(end 249.348244 -86.29904)
		(width 0.254)
		(layer "F.Cu")
		(net "GND")
	)
	(segment
		(start 178.582828 -81.915)
		(end 178.054 -81.915)
		(width 0.254)
		(layer "F.Cu")
		(net "GND")
	)
	(segment
		(start 83.202272 -98.18624)
		(end 82.630772 -98.18624)
		(width 0.254)
		(layer "F.Cu")
		(net "GND")
	)
	(segment
		(start 285.650432 -156.87294)
		(end 285.650432 -155.613354)
		(width 0.3556)
		(layer "F.Cu")
		(net "GND")
	)
	(segment
		(start 288.36366 -92.556584)
		(end 288.93516 -92.556584)
		(width 0.3048)
		(layer "F.Cu")
		(net "GND")
	)
	(segment
		(start 136.240774 -60.362338)
		(end 136.812274 -60.362338)
		(width 0.254)
		(layer "F.Cu")
		(net "GND")
	)
	(segment
		(start 78.14945 -10.422382)
		(end 78.14945 -11.72845)
		(width 0.4064)
		(layer "F.Cu")
		(net "GND")
	)
	(segment
		(start 235.49991 -146.049746)
		(end 235.46181 -146.011646)
		(width 0.4064)
		(layer "F.Cu")
		(net "GND")
	)
	(segment
		(start 295.23182 -62.838584)
		(end 295.80332 -62.838584)
		(width 0.254)
		(layer "F.Cu")
		(net "GND")
	)
	(segment
		(start 389.844788 -104.361488)
		(end 390.13765 -104.65435)
		(width 0.12446)
		(layer "F.Cu")
		(net "GND")
	)
	(segment
		(start 135.771636 -3.762756)
		(end 135.949436 -3.940556)
		(width 0.4064)
		(layer "F.Cu")
		(net "GND")
	)
	(segment
		(start 234.649772 -7.509002)
		(end 234.649772 -5.822442)
		(width 0.4064)
		(layer "F.Cu")
		(net "GND")
	)
	(segment
		(start 305.199796 -7.607046)
		(end 305.199796 -5.822442)
		(width 0.4064)
		(layer "F.Cu")
		(net "GND")
	)
	(segment
		(start 48.399446 -9.156446)
		(end 48.399446 -10.422382)
		(width 0.4064)
		(layer "F.Cu")
		(net "GND")
	)
	(segment
		(start 113.849404 -10.422382)
		(end 113.849404 -9.131046)
		(width 0.4064)
		(layer "F.Cu")
		(net "GND")
	)
	(segment
		(start 139.34948 -0.821182)
		(end 139.34948 -2.314956)
		(width 0.4064)
		(layer "F.Cu")
		(net "GND")
	)
	(segment
		(start 230.399844 -0.821182)
		(end 230.399844 -2.314956)
		(width 0.4064)
		(layer "F.Cu")
		(net "GND")
	)
	(segment
		(start 158.83636 -124.46254)
		(end 158.83636 -123.34494)
		(width 0.4572)
		(layer "F.Cu")
		(net "GND")
	)
	(segment
		(start 304.675286 -73.240138)
		(end 305.246786 -73.240138)
		(width 0.254)
		(layer "F.Cu")
		(net "GND")
	)
	(segment
		(start 287.50514 -99.986338)
		(end 288.07664 -99.986338)
		(width 0.254)
		(layer "F.Cu")
		(net "GND")
	)
	(segment
		(start 55.199534 3.778758)
		(end 55.19928 3.778504)
		(width 0.4064)
		(layer "F.Cu")
		(net "GND")
	)
	(segment
		(start 75.475846 -69.953886)
		(end 74.904346 -69.953886)
		(width 0.254)
		(layer "F.Cu")
		(net "GND")
	)
	(segment
		(start 135.735568 -153.237946)
		(end 135.735568 -154.065732)
		(width 0.3556)
		(layer "F.Cu")
		(net "GND")
	)
	(segment
		(start 175.35652 -68.834)
		(end 175.438816 -68.916296)
		(width 0.4064)
		(layer "F.Cu")
		(net "GND")
	)
	(segment
		(start 127.655828 -84.136738)
		(end 128.227328 -84.136738)
		(width 0.254)
		(layer "F.Cu")
		(net "GND")
	)
	(segment
		(start 233.608118 -64.010286)
		(end 233.036618 -64.010286)
		(width 0.254)
		(layer "F.Cu")
		(net "GND")
	)
	(segment
		(start 442.939932 -51.875944)
		(end 442.940948 -51.875944)
		(width 0.4064)
		(layer "F.Cu")
		(net "GND")
	)
	(segment
		(start 133.665214 -80.669384)
		(end 134.236714 -80.669384)
		(width 0.254)
		(layer "F.Cu")
		(net "GND")
	)
	(segment
		(start 225.300286 -15.423642)
		(end 225.299778 -15.423642)
		(width 0.4064)
		(layer "F.Cu")
		(net "GND")
	)
	(segment
		(start 196.469 -11.985244)
		(end 196.399912 -11.916156)
		(width 0.381)
		(layer "F.Cu")
		(net "GND")
	)
	(segment
		(start 256.4638 -149.733)
		(end 256.116836 -150.105364)
		(width 0.381)
		(layer "F.Cu")
		(net "GND")
	)
	(segment
		(start 31.6865 -61.9125)
		(end 32.094932 -62.320932)
		(width 0.254)
		(layer "F.Cu")
		(net "GND")
	)
	(segment
		(start 376.744738 -78.294738)
		(end 376.344942 -77.894942)
		(width 0.254)
		(layer "F.Cu")
		(net "GND")
	)
	(segment
		(start 313.874658 -32.172402)
		(end 313.299602 -32.747458)
		(width 0.4064)
		(layer "F.Cu")
		(net "GND")
	)
	(segment
		(start 128.514348 -56.894984)
		(end 129.085848 -56.894984)
		(width 0.254)
		(layer "F.Cu")
		(net "GND")
	)
	(segment
		(start 158.85922 -125.1077)
		(end 158.85922 -124.4854)
		(width 0.4572)
		(layer "F.Cu")
		(net "GND")
	)
	(segment
		(start 233.799888 -10.422382)
		(end 233.799888 -9.143746)
		(width 0.4064)
		(layer "F.Cu")
		(net "GND")
	)
	(segment
		(start 226.149916 -137.67054)
		(end 226.149916 -136.410446)
		(width 0.4064)
		(layer "F.Cu")
		(net "GND")
	)
	(segment
		(start 497.73078 -41.619932)
		(end 498.213888 -42.10304)
		(width 0.254)
		(layer "F.Cu")
		(net "GND")
	)
	(segment
		(start 398.13865 -96.747076)
		(end 397.64335 -96.9772)
		(width 0.254)
		(layer "F.Cu")
		(net "GND")
	)
	(segment
		(start 298.399962 -0.821182)
		(end 298.399962 0.457454)
		(width 0.4064)
		(layer "F.Cu")
		(net "GND")
	)
	(segment
		(start 232.950512 1.994916)
		(end 232.94975 1.994154)
		(width 0.4064)
		(layer "F.Cu")
		(net "GND")
	)
	(segment
		(start 289.899852 -153.965402)
		(end 289.801808 -154.063446)
		(width 0.4064)
		(layer "F.Cu")
		(net "GND")
	)
	(segment
		(start 302.099726 -102.462584)
		(end 302.118268 -102.481126)
		(width 0.2032)
		(layer "F.Cu")
		(net "GND")
	)
	(segment
		(start 117.353842 -60.362338)
		(end 116.782342 -60.362338)
		(width 0.254)
		(layer "F.Cu")
		(net "GND")
	)
	(segment
		(start 44.149518 -21.455888)
		(end 44.092114 -21.513292)
		(width 0.4064)
		(layer "F.Cu")
		(net "GND")
	)
	(segment
		(start 128.514348 -68.782184)
		(end 129.085848 -68.782184)
		(width 0.254)
		(layer "F.Cu")
		(net "GND")
	)
	(segment
		(start 204.050392 -0.821182)
		(end 204.049884 -0.821182)
		(width 0.4064)
		(layer "F.Cu")
		(net "GND")
	)
	(segment
		(start 56.899302 -15.602966)
		(end 56.899302 -17.208246)
		(width 0.4064)
		(layer "F.Cu")
		(net "GND")
	)
	(segment
		(start 226.150424 -137.67054)
		(end 226.149916 -137.67054)
		(width 0.4064)
		(layer "F.Cu")
		(net "GND")
	)
	(segment
		(start 45.849286 -153.093674)
		(end 45.390816 -153.552144)
		(width 0.4064)
		(layer "F.Cu")
		(net "GND")
	)
	(segment
		(start 207.411828 -11.916156)
		(end 209.088482 -11.916156)
		(width 0.254)
		(layer "F.Cu")
		(net "GND")
	)
	(segment
		(start 85.761068 -12.954)
		(end 84.910168 -12.954)
		(width 0.4064)
		(layer "F.Cu")
		(net "GND")
	)
	(segment
		(start 115.636802 -60.362338)
		(end 115.065302 -60.362338)
		(width 0.254)
		(layer "F.Cu")
		(net "GND")
	)
	(segment
		(start 303.500282 3.778758)
		(end 303.499774 3.778758)
		(width 0.4064)
		(layer "F.Cu")
		(net "GND")
	)
	(segment
		(start 129.149348 -15.423642)
		(end 129.149348 -16.238474)
		(width 0.4064)
		(layer "F.Cu")
		(net "GND")
	)
	(segment
		(start 376.295666 -126.165102)
		(end 376.27814 -126.182628)
		(width 0.254)
		(layer "F.Cu")
		(net "GND")
	)
	(segment
		(start 42.449496 -11.878056)
		(end 42.449496 -10.422382)
		(width 0.4064)
		(layer "F.Cu")
		(net "GND")
	)
	(segment
		(start 60.299346 -134.763002)
		(end 60.201302 -134.861046)
		(width 0.4064)
		(layer "F.Cu")
		(net "GND")
	)
	(segment
		(start 285.7881 -78.193138)
		(end 286.3596 -78.193138)
		(width 0.254)
		(layer "F.Cu")
		(net "GND")
	)
	(segment
		(start 52.448968 -153.3906)
		(end 52.448968 -154.079194)
		(width 0.3556)
		(layer "F.Cu")
		(net "GND")
	)
	(segment
		(start 411.09011 -27.334718)
		(end 411.49016 -26.934668)
		(width 0.254)
		(layer "F.Cu")
		(net "GND")
	)
	(segment
		(start 31.877 -86.487)
		(end 32.094932 -86.704932)
		(width 0.254)
		(layer "F.Cu")
		(net "GND")
	)
	(segment
		(start 236.183678 -97.19564)
		(end 235.612178 -97.19564)
		(width 0.254)
		(layer "F.Cu")
		(net "GND")
	)
	(segment
		(start 451.7136 -152.1206)
		(end 451.25894 -151.66594)
		(width 0.254)
		(layer "F.Cu")
		(net "GND")
	)
	(segment
		(start 184.890664 -126.97333)
		(end 184.036208 -126.97333)
		(width 0.254)
		(layer "F.Cu")
		(net "GND")
	)
	(segment
		(start 263.65581 -89.27084)
		(end 263.08431 -89.27084)
		(width 0.254)
		(layer "F.Cu")
		(net "GND")
	)
	(segment
		(start 252.495304 -80.850486)
		(end 251.923804 -80.850486)
		(width 0.254)
		(layer "F.Cu")
		(net "GND")
	)
	(segment
		(start 256.379218 -13.292582)
		(end 255.87198 -13.292582)
		(width 0.508)
		(layer "F.Cu")
		(net "GND")
	)
	(segment
		(start 239.617758 -57.57164)
		(end 239.046258 -57.57164)
		(width 0.254)
		(layer "F.Cu")
		(net "GND")
	)
	(segment
		(start 294.14978 -153.093674)
		(end 293.69131 -153.552144)
		(width 0.4064)
		(layer "F.Cu")
		(net "GND")
	)
	(segment
		(start 90.814906 -139.829794)
		(end 90.167206 -139.829794)
		(width 0.4064)
		(layer "F.Cu")
		(net "GND")
	)
	(segment
		(start 75.599544 3.599688)
		(end 75.59929 3.599434)
		(width 0.4064)
		(layer "F.Cu")
		(net "GND")
	)
	(segment
		(start 7.7724 3.532378)
		(end 7.7724 3.048)
		(width 0.2032)
		(layer "F.Cu")
		(net "GND")
	)
	(segment
		(start 207.449928 -10.422382)
		(end 207.449928 -9.156446)
		(width 0.4064)
		(layer "F.Cu")
		(net "GND")
	)
	(segment
		(start 249.061224 -52.12334)
		(end 249.061224 -51.119532)
		(width 0.2032)
		(layer "F.Cu")
		(net "GND")
	)
	(segment
		(start 408.559 -18.462752)
		(end 408.066748 -18.462752)
		(width 0.254)
		(layer "F.Cu")
		(net "GND")
	)
	(segment
		(start 281.495754 -53.923184)
		(end 280.924254 -53.923184)
		(width 0.254)
		(layer "F.Cu")
		(net "GND")
	)
	(segment
		(start 32.249364 -15.423642)
		(end 32.249364 -13.427456)
		(width 0.4064)
		(layer "F.Cu")
		(net "GND")
	)
	(segment
		(start 74.617326 -54.59984)
		(end 74.045826 -54.59984)
		(width 0.254)
		(layer "F.Cu")
		(net "GND")
	)
	(segment
		(start 114.778282 -99.490784)
		(end 115.349782 -99.490784)
		(width 0.254)
		(layer "F.Cu")
		(net "GND")
	)
	(segment
		(start 59.449462 -20.023582)
		(end 59.449462 -18.744946)
		(width 0.4064)
		(layer "F.Cu")
		(net "GND")
	)
	(segment
		(start 395.16685 -108.13796)
		(end 394.17625 -108.13796)
		(width 0.254)
		(layer "F.Cu")
		(net "GND")
	)
	(segment
		(start 289.049968 -18.744946)
		(end 289.049968 -20.023582)
		(width 0.4064)
		(layer "F.Cu")
		(net "GND")
	)
	(segment
		(start 45.849286 -15.423896)
		(end 45.849286 -16.238474)
		(width 0.4064)
		(layer "F.Cu")
		(net "GND")
	)
	(segment
		(start 442.940948 -50.578004)
		(end 442.940948 -51.875944)
		(width 0.4064)
		(layer "F.Cu")
		(net "GND")
	)
	(segment
		(start 95.221298 -60.54344)
		(end 94.649798 -60.54344)
		(width 0.254)
		(layer "F.Cu")
		(net "GND")
	)
	(segment
		(start 299.249846 -3.826256)
		(end 299.160946 -3.737356)
		(width 0.4064)
		(layer "F.Cu")
		(net "GND")
	)
	(segment
		(start 452.532242 -50.5206)
		(end 452.532242 -50.515266)
		(width 0.508)
		(layer "F.Cu")
		(net "GND")
	)
	(segment
		(start 487.2228 -139.3444)
		(end 487.7308 -139.3444)
		(width 0.254)
		(layer "F.Cu")
		(net "GND")
	)
	(segment
		(start 52.649374 -6.555994)
		(end 52.448968 -6.7564)
		(width 0.3048)
		(layer "F.Cu")
		(net "GND")
	)
	(segment
		(start 484.820468 -30.849062)
		(end 484.93553 -30.734)
		(width 0.254)
		(layer "F.Cu")
		(net "GND")
	)
	(segment
		(start 82.459068 -140.208)
		(end 81.565242 -140.208)
		(width 0.4064)
		(layer "F.Cu")
		(net "GND")
	)
	(segment
		(start 465.400898 -118.615714)
		(end 465.404454 -118.61927)
		(width 0.4064)
		(layer "F.Cu")
		(net "GND")
	)
	(segment
		(start 72.041766 -97.690686)
		(end 71.470266 -97.690686)
		(width 0.254)
		(layer "F.Cu")
		(net "GND")
	)
	(segment
		(start 459.75016 -62.00267)
		(end 459.75016 -63.157354)
		(width 0.381)
		(layer "F.Cu")
		(net "GND")
	)
	(segment
		(start 240.599722 -152.458166)
		(end 240.599722 -154.063446)
		(width 0.4064)
		(layer "F.Cu")
		(net "GND")
	)
	(segment
		(start 495.149632 -39.619936)
		(end 494.069624 -40.699944)
		(width 0.254)
		(layer "F.Cu")
		(net "GND")
	)
	(segment
		(start 122.349514 -155.745434)
		(end 122.1613 -155.55722)
		(width 0.4064)
		(layer "F.Cu")
		(net "GND")
	)
	(segment
		(start 106.193336 -53.923184)
		(end 105.571036 -53.923184)
		(width 0.254)
		(layer "F.Cu")
		(net "GND")
	)
	(segment
		(start 134.249414 -15.423642)
		(end 134.249414 -17.110202)
		(width 0.4064)
		(layer "F.Cu")
		(net "GND")
	)
	(segment
		(start 69.466206 -99.17684)
		(end 68.894706 -99.17684)
		(width 0.254)
		(layer "F.Cu")
		(net "GND")
	)
	(segment
		(start 78.909672 -86.794086)
		(end 78.338172 -86.794086)
		(width 0.254)
		(layer "F.Cu")
		(net "GND")
	)
	(segment
		(start 302.958246 -101.967538)
		(end 303.3395 -102.348792)
		(width 0.254)
		(layer "F.Cu")
		(net "GND")
	)
	(segment
		(start 403.733 -22.098)
		(end 403.733 -21.544788)
		(width 0.254)
		(layer "F.Cu")
		(net "GND")
	)
	(segment
		(start 390.984994 -95.205042)
		(end 391.984992 -95.205042)
		(width 0.254)
		(layer "F.Cu")
		(net "GND")
	)
	(segment
		(start 133.665214 -57.885584)
		(end 134.236714 -57.885584)
		(width 0.254)
		(layer "F.Cu")
		(net "GND")
	)
	(segment
		(start 64.549274 -6.637274)
		(end 64.090804 -7.095744)
		(width 0.4064)
		(layer "F.Cu")
		(net "GND")
	)
	(segment
		(start 278.849836 -18.786348)
		(end 278.849836 -20.023582)
		(width 0.4064)
		(layer "F.Cu")
		(net "GND")
	)
	(segment
		(start 290.93922 -57.390538)
		(end 291.51072 -57.390538)
		(width 0.254)
		(layer "F.Cu")
		(net "GND")
	)
	(segment
		(start 255.92913 -98.681286)
		(end 255.35763 -98.681286)
		(width 0.254)
		(layer "F.Cu")
		(net "GND")
	)
	(segment
		(start 69.753226 -59.057286)
		(end 70.324726 -59.057286)
		(width 0.3048)
		(layer "F.Cu")
		(net "GND")
	)
	(segment
		(start 501.2563 -121.310146)
		(end 501.200166 -121.310146)
		(width 0.508)
		(layer "F.Cu")
		(net "GND")
	)
	(segment
		(start 87.494872 -69.953886)
		(end 86.923372 -69.953886)
		(width 0.254)
		(layer "F.Cu")
		(net "GND")
	)
	(segment
		(start 284.800294 -15.423642)
		(end 284.800294 -16.237712)
		(width 0.4064)
		(layer "F.Cu")
		(net "GND")
	)
	(segment
		(start 78.909672 -89.765886)
		(end 78.338172 -89.765886)
		(width 0.254)
		(layer "F.Cu")
		(net "GND")
	)
	(segment
		(start 133.665214 -102.462584)
		(end 134.236714 -102.462584)
		(width 0.254)
		(layer "F.Cu")
		(net "GND")
	)
	(segment
		(start 287.50514 -92.061538)
		(end 288.07664 -92.061538)
		(width 0.3048)
		(layer "F.Cu")
		(net "GND")
	)
	(segment
		(start 317.09995 -21.528278)
		(end 317.09995 -22.69363)
		(width 0.4064)
		(layer "F.Cu")
		(net "GND")
	)
	(segment
		(start 203.2 -152.457912)
		(end 203.199746 -152.458166)
		(width 0.4064)
		(layer "F.Cu")
		(net "GND")
	)
	(segment
		(start 467.106 -0.508)
		(end 467.106 -0.2032)
		(width 0.254)
		(layer "F.Cu")
		(net "GND")
	)
	(segment
		(start 74.749406 -137.67054)
		(end 74.749406 -136.410446)
		(width 0.4064)
		(layer "F.Cu")
		(net "GND")
	)
	(segment
		(start 137.099294 -75.716384)
		(end 137.670794 -75.716384)
		(width 0.254)
		(layer "F.Cu")
		(net "GND")
	)
	(segment
		(start 222.749872 -147.27174)
		(end 222.749872 -146.011646)
		(width 0.4064)
		(layer "F.Cu")
		(net "GND")
	)
	(segment
		(start 281.495754 -63.829184)
		(end 280.924254 -63.829184)
		(width 0.254)
		(layer "F.Cu")
		(net "GND")
	)
	(segment
		(start 72.900286 -57.57164)
		(end 72.328786 -57.57164)
		(width 0.254)
		(layer "F.Cu")
		(net "GND")
	)
	(segment
		(start 207.424528 -146.011646)
		(end 207.411828 -146.011646)
		(width 0.4064)
		(layer "F.Cu")
		(net "GND")
	)
	(segment
		(start 307.749956 -20.023582)
		(end 307.749956 -21.517356)
		(width 0.4064)
		(layer "F.Cu")
		(net "GND")
	)
	(segment
		(start 119.070882 -91.070938)
		(end 119.642382 -91.070938)
		(width 0.254)
		(layer "F.Cu")
		(net "GND")
	)
	(segment
		(start 457.142596 -8.79729)
		(end 457.142596 -8.86206)
		(width 0.254)
		(layer "F.Cu")
		(net "GND")
	)
	(segment
		(start 136.799574 -11.854688)
		(end 136.74217 -11.912092)
		(width 0.4064)
		(layer "F.Cu")
		(net "GND")
	)
	(segment
		(start 50.949352 2.092198)
		(end 50.851308 1.994154)
		(width 0.4064)
		(layer "F.Cu")
		(net "GND")
	)
	(segment
		(start 122.217688 -89.584784)
		(end 121.646188 -89.584784)
		(width 0.254)
		(layer "F.Cu")
		(net "GND")
	)
	(segment
		(start 86.636352 -76.39304)
		(end 86.064852 -76.39304)
		(width 0.254)
		(layer "F.Cu")
		(net "GND")
	)
	(segment
		(start 115.549426 -7.509002)
		(end 115.451382 -7.607046)
		(width 0.4064)
		(layer "F.Cu")
		(net "GND")
	)
	(segment
		(start 398.861534 -94.15145)
		(end 398.861534 -93.544898)
		(width 0.254)
		(layer "F.Cu")
		(net "GND")
	)
	(segment
		(start 303.529746 -67.504564)
		(end 303.529746 -67.296538)
		(width 0.254)
		(layer "F.Cu")
		(net "GND")
	)
	(segment
		(start 290.74999 -20.023582)
		(end 290.74999 -21.479256)
		(width 0.4064)
		(layer "F.Cu")
		(net "GND")
	)
	(segment
		(start 198.772018 -17.2466)
		(end 198.755 -17.229582)
		(width 0.3556)
		(layer "F.Cu")
		(net "GND")
	)
	(segment
		(start 278.348694 -55.409338)
		(end 278.920194 -55.409338)
		(width 0.254)
		(layer "F.Cu")
		(net "GND")
	)
	(segment
		(start 240.599976 -152.457912)
		(end 240.599722 -152.458166)
		(width 0.4064)
		(layer "F.Cu")
		(net "GND")
	)
	(segment
		(start 212.550502 -142.6718)
		(end 212.549994 -142.677642)
		(width 0.4064)
		(layer "F.Cu")
		(net "GND")
	)
	(segment
		(start 401.2438 -131.5466)
		(end 399.9738 -131.5466)
		(width 0.4064)
		(layer "F.Cu")
		(net "GND")
	)
	(segment
		(start 457.801726 -45.560996)
		(end 457.34097 -46.021752)
		(width 0.4064)
		(layer "F.Cu")
		(net "GND")
	)
	(segment
		(start 445.236854 -21.80717)
		(end 445.236854 -23.292054)
		(width 0.254)
		(layer "F.Cu")
		(net "GND")
	)
	(segment
		(start 414.290256 -32.934656)
		(end 413.890206 -33.334706)
		(width 0.254)
		(layer "F.Cu")
		(net "GND")
	)
	(segment
		(start 67.749166 -60.54344)
		(end 67.101466 -60.54344)
		(width 0.254)
		(layer "F.Cu")
		(net "GND")
	)
	(segment
		(start 152.099518 -11.927078)
		(end 152.146 -11.97356)
		(width 0.4064)
		(layer "F.Cu")
		(net "GND")
	)
	(segment
		(start 285.7881 -80.174338)
		(end 286.3596 -80.174338)
		(width 0.254)
		(layer "F.Cu")
		(net "GND")
	)
	(segment
		(start 375.145046 -71.894954)
		(end 375.545096 -71.494904)
		(width 0.254)
		(layer "F.Cu")
		(net "GND")
	)
	(segment
		(start 110.485682 -58.381138)
		(end 109.914182 -58.381138)
		(width 0.254)
		(layer "F.Cu")
		(net "GND")
	)
	(segment
		(start 131.699508 -137.67054)
		(end 131.699508 -136.410446)
		(width 0.4064)
		(layer "F.Cu")
		(net "GND")
	)
	(segment
		(start 396.15745 -101.2698)
		(end 396.248382 -101.227382)
		(width 0.254)
		(layer "F.Cu")
		(net "GND")
	)
	(segment
		(start 195.550282 -142.6718)
		(end 195.549774 -142.677642)
		(width 0.4064)
		(layer "F.Cu")
		(net "GND")
	)
	(segment
		(start 239.617758 -58.561986)
		(end 239.046258 -58.561986)
		(width 0.254)
		(layer "F.Cu")
		(net "GND")
	)
	(segment
		(start 288.36366 -101.471984)
		(end 288.93516 -101.471984)
		(width 0.254)
		(layer "F.Cu")
		(net "GND")
	)
	(segment
		(start 389.22325 -116.72316)
		(end 389.71855 -116.953284)
		(width 0.254)
		(layer "F.Cu")
		(net "GND")
	)
	(segment
		(start 129.999486 0.444754)
		(end 129.999486 -0.821182)
		(width 0.4064)
		(layer "F.Cu")
		(net "GND")
	)
	(segment
		(start 444.1952 -149.71522)
		(end 443.098174 -149.71522)
		(width 0.254)
		(layer "F.Cu")
		(net "GND")
	)
	(segment
		(start 366.548924 -101.1174)
		(end 369.2906 -101.1174)
		(width 0.254)
		(layer "F.Cu")
		(net "GND")
	)
	(segment
		(start 253.353824 -60.54344)
		(end 252.782324 -60.54344)
		(width 0.254)
		(layer "F.Cu")
		(net "GND")
	)
	(segment
		(start 28.7274 -105.621328)
		(end 28.7274 -105.3338)
		(width 0.4064)
		(layer "F.Cu")
		(net "GND")
	)
	(segment
		(start 290.74999 -2.276856)
		(end 290.74999 -0.821182)
		(width 0.4064)
		(layer "F.Cu")
		(net "GND")
	)
	(segment
		(start 237.900718 -76.39304)
		(end 237.329218 -76.39304)
		(width 0.254)
		(layer "F.Cu")
		(net "GND")
	)
	(segment
		(start 111.326168 -52.0954)
		(end 111.326168 -52.914804)
		(width 0.254)
		(layer "F.Cu")
		(net "GND")
	)
	(segment
		(start 249.061224 -56.085486)
		(end 248.489724 -56.085486)
		(width 0.254)
		(layer "F.Cu")
		(net "GND")
	)
	(segment
		(start 241.334798 -89.27084)
		(end 240.763298 -89.27084)
		(width 0.254)
		(layer "F.Cu")
		(net "GND")
	)
	(segment
		(start 280.549858 -133.076442)
		(end 280.549858 -134.763002)
		(width 0.4064)
		(layer "F.Cu")
		(net "GND")
	)
	(segment
		(start 459.168754 -53.234844)
		(end 458.9399 -53.00599)
		(width 0.508)
		(layer "F.Cu")
		(net "GND")
	)
	(segment
		(start 107.62361 -100.977192)
		(end 107.623102 -100.976684)
		(width 0.254)
		(layer "F.Cu")
		(net "GND")
	)
	(segment
		(start 368.421666 -106.217466)
		(end 367.9952 -105.791)
		(width 0.254)
		(layer "F.Cu")
		(net "GND")
	)
	(segment
		(start 394.5382 -123.954286)
		(end 394.67155 -123.821444)
		(width 0.254)
		(layer "F.Cu")
		(net "GND")
	)
	(segment
		(start 311.092596 -155.600146)
		(end 311.092596 -155.612846)
		(width 0.3556)
		(layer "F.Cu")
		(net "GND")
	)
	(segment
		(start 235.325158 -61.038486)
		(end 234.753658 -61.038486)
		(width 0.254)
		(layer "F.Cu")
		(net "GND")
	)
	(segment
		(start 115.451382 -17.208246)
		(end 115.549426 -17.110202)
		(width 0.4064)
		(layer "F.Cu")
		(net "GND")
	)
	(segment
		(start 39.899336 -5.822442)
		(end 39.899336 -3.762756)
		(width 0.4064)
		(layer "F.Cu")
		(net "GND")
	)
	(segment
		(start 436.245 -149.154642)
		(end 436.372 -149.281642)
		(width 0.254)
		(layer "F.Cu")
		(net "GND")
	)
	(segment
		(start -4.064 -135.7122)
		(end -4.064 -135.1534)
		(width 0.254)
		(layer "F.Cu")
		(net "GND")
	)
	(segment
		(start 117.249448 -133.0706)
		(end 117.249448 -133.802374)
		(width 0.3556)
		(layer "F.Cu")
		(net "GND")
	)
	(segment
		(start 169.8244 -73.8124)
		(end 169.8244 -74.5744)
		(width 0.254)
		(layer "F.Cu")
		(net "GND")
	)
	(segment
		(start 239.750346 -20.023582)
		(end 239.749838 -20.023582)
		(width 0.4064)
		(layer "F.Cu")
		(net "GND")
	)
	(segment
		(start 121.892568 -52.367434)
		(end 121.900442 -52.380896)
		(width 0.254)
		(layer "F.Cu")
		(net "GND")
	)
	(segment
		(start 237.042198 -61.038486)
		(end 236.470698 -61.038486)
		(width 0.254)
		(layer "F.Cu")
		(net "GND")
	)
	(segment
		(start 221.04985 -155.612846)
		(end 221.04985 -156.87294)
		(width 0.4064)
		(layer "F.Cu")
		(net "GND")
	)
	(segment
		(start 106.193336 -59.866784)
		(end 105.571036 -59.866784)
		(width 0.254)
		(layer "F.Cu")
		(net "GND")
	)
	(segment
		(start 89.211912 -53.113686)
		(end 89.211912 -53.322474)
		(width 0.254)
		(layer "F.Cu")
		(net "GND")
	)
	(segment
		(start 72.900286 -70.44944)
		(end 72.328786 -70.44944)
		(width 0.254)
		(layer "F.Cu")
		(net "GND")
	)
	(segment
		(start 392.303 -73.787)
		(end 392.303 -74.480166)
		(width 0.254)
		(layer "F.Cu")
		(net "GND")
	)
	(segment
		(start 19.6342 -98.199956)
		(end 19.6342 -99.2124)
		(width 0.254)
		(layer "F.Cu")
		(net "GND")
	)
	(segment
		(start 143.599408 2.092198)
		(end 143.501364 1.994154)
		(width 0.4064)
		(layer "F.Cu")
		(net "GND")
	)
	(segment
		(start 137.099294 -102.905306)
		(end 137.099294 -102.462584)
		(width 0.4064)
		(layer "F.Cu")
		(net "GND")
	)
	(segment
		(start 375.92 -101.35489)
		(end 375.92 -101.529134)
		(width 0.254)
		(layer "F.Cu")
		(net "GND")
	)
	(segment
		(start 236.183678 -63.51524)
		(end 235.612178 -63.51524)
		(width 0.254)
		(layer "F.Cu")
		(net "GND")
	)
	(segment
		(start 391.69975 -100.41128)
		(end 392.19505 -100.181156)
		(width 0.254)
		(layer "F.Cu")
		(net "GND")
	)
	(segment
		(start 198.949818 -152.992582)
		(end 198.755 -153.1874)
		(width 0.3556)
		(layer "F.Cu")
		(net "GND")
	)
	(segment
		(start 350.981518 -11.4046)
		(end 350.981518 -11.806936)
		(width 0.254)
		(layer "F.Cu")
		(net "GND")
	)
	(segment
		(start 118.099332 -2.253488)
		(end 118.099332 -0.821182)
		(width 0.4064)
		(layer "F.Cu")
		(net "GND")
	)
	(segment
		(start 445.53378 -23.58898)
		(end 445.91732 -23.58898)
		(width 0.254)
		(layer "F.Cu")
		(net "GND")
	)
	(segment
		(start 234.466638 -68.46824)
		(end 233.895138 -68.46824)
		(width 0.254)
		(layer "F.Cu")
		(net "GND")
	)
	(segment
		(start 237.199932 -155.67025)
		(end 237.199932 -156.87294)
		(width 0.3556)
		(layer "F.Cu")
		(net "GND")
	)
	(segment
		(start 237.900718 -82.33664)
		(end 237.329218 -82.33664)
		(width 0.254)
		(layer "F.Cu")
		(net "GND")
	)
	(segment
		(start 238.900462 2.964688)
		(end 238.44123 2.505456)
		(width 0.4064)
		(layer "F.Cu")
		(net "GND")
	)
	(segment
		(start 26.896568 -11.50366)
		(end 26.896568 -12.507976)
		(width 0.4064)
		(layer "F.Cu")
		(net "GND")
	)
	(segment
		(start 225.210878 -3.737356)
		(end 225.299778 -3.826256)
		(width 0.4064)
		(layer "F.Cu")
		(net "GND")
	)
	(segment
		(start 304.349912 -20.023582)
		(end 304.349912 -21.517356)
		(width 0.4064)
		(layer "F.Cu")
		(net "GND")
	)
	(segment
		(start 290.750498 -20.023582)
		(end 290.74999 -20.023582)
		(width 0.4064)
		(layer "F.Cu")
		(net "GND")
	)
	(segment
		(start 445.34963 -53.300884)
		(end 445.339978 -51.875944)
		(width 0.4064)
		(layer "F.Cu")
		(net "GND")
	)
	(segment
		(start 78.14945 -148.460714)
		(end 78.14945 -147.277582)
		(width 0.508)
		(layer "F.Cu")
		(net "GND")
	)
	(segment
		(start 209.092546 -2.310892)
		(end 209.14995 -2.253488)
		(width 0.4064)
		(layer "F.Cu")
		(net "GND")
	)
	(segment
		(start 96.938338 -60.54344)
		(end 96.366838 -60.54344)
		(width 0.254)
		(layer "F.Cu")
		(net "GND")
	)
	(segment
		(start 236.183678 -54.59984)
		(end 235.612178 -54.59984)
		(width 0.254)
		(layer "F.Cu")
		(net "GND")
	)
	(segment
		(start 125.080268 -85.622384)
		(end 125.651768 -85.622384)
		(width 0.254)
		(layer "F.Cu")
		(net "GND")
	)
	(segment
		(start 354.23729 -100.29063)
		(end 354.26904 -100.25888)
		(width 0.254)
		(layer "F.Cu")
		(net "GND")
	)
	(segment
		(start 184.9374 -115.55095)
		(end 184.9374 -115.57)
		(width 0.254)
		(layer "F.Cu")
		(net "GND")
	)
	(segment
		(start 223.600518 -152.273)
		(end 223.60001 -152.278842)
		(width 0.4064)
		(layer "F.Cu")
		(net "GND")
	)
	(segment
		(start 416.690048 -36.934648)
		(end 416.289998 -36.534598)
		(width 0.254)
		(layer "F.Cu")
		(net "GND")
	)
	(segment
		(start 448.549776 -53.236876)
		(end 448.54876 -52.451)
		(width 0.4064)
		(layer "F.Cu")
		(net "GND")
	)
	(segment
		(start 398.903444 -126.207012)
		(end 398.903444 -126.566676)
		(width 0.254)
		(layer "F.Cu")
		(net "GND")
	)
	(segment
		(start 215.100408 -20.023582)
		(end 215.0999 -20.023582)
		(width 0.4064)
		(layer "F.Cu")
		(net "GND")
	)
	(segment
		(start 394.903706 -102.02037)
		(end 395.16685 -101.898196)
		(width 0.254)
		(layer "F.Cu")
		(net "GND")
	)
	(segment
		(start 455.800968 -118.615968)
		(end 455.80427 -118.61927)
		(width 0.4064)
		(layer "F.Cu")
		(net "GND")
	)
	(segment
		(start 52.448968 -143.6116)
		(end 52.448968 -143.7894)
		(width 0.3048)
		(layer "F.Cu")
		(net "GND")
	)
	(segment
		(start 134.523734 -88.099138)
		(end 135.095234 -88.099138)
		(width 0.254)
		(layer "F.Cu")
		(net "GND")
	)
	(segment
		(start 350.482154 -149.112224)
		(end 350.94799 -148.646388)
		(width 0.381)
		(layer "F.Cu")
		(net "GND")
	)
	(segment
		(start 121.646188 -54.913784)
		(end 121.074688 -54.913784)
		(width 0.254)
		(layer "F.Cu")
		(net "GND")
	)
	(segment
		(start 81.485232 -99.17684)
		(end 80.913732 -99.17684)
		(width 0.254)
		(layer "F.Cu")
		(net "GND")
	)
	(segment
		(start 321.693032 -140.208)
		(end 321.691 -140.210032)
		(width 0.4064)
		(layer "F.Cu")
		(net "GND")
	)
	(segment
		(start 475.58706 -27.056334)
		(end 475.64802 -27.117294)
		(width 0.254)
		(layer "F.Cu")
		(net "GND")
	)
	(segment
		(start 292.392608 0.444754)
		(end 292.392608 0.457454)
		(width 0.3556)
		(layer "F.Cu")
		(net "GND")
	)
	(segment
		(start 303.499774 -152.278842)
		(end 303.499774 -153.093674)
		(width 0.4064)
		(layer "F.Cu")
		(net "GND")
	)
	(segment
		(start 209.14995 -18.85315)
		(end 209.14995 -20.023582)
		(width 0.4064)
		(layer "F.Cu")
		(net "GND")
	)
	(segment
		(start 201.500486 -142.6718)
		(end 201.499978 -142.677642)
		(width 0.4064)
		(layer "F.Cu")
		(net "GND")
	)
	(segment
		(start 236.171994 -3.762756)
		(end 236.349794 -3.940556)
		(width 0.4064)
		(layer "F.Cu")
		(net "GND")
	)
	(segment
		(start 379.81255 -107.907836)
		(end 379.81255 -107.27944)
		(width 0.254)
		(layer "F.Cu")
		(net "GND")
	)
	(segment
		(start 393.186158 -115.00612)
		(end 393.690348 -115.240308)
		(width 0.254)
		(layer "F.Cu")
		(net "GND")
	)
	(segment
		(start 209.14995 -147.27174)
		(end 209.14995 -146.10715)
		(width 0.4064)
		(layer "F.Cu")
		(net "GND")
	)
	(segment
		(start 128.514348 -73.735184)
		(end 129.085848 -73.735184)
		(width 0.254)
		(layer "F.Cu")
		(net "GND")
	)
	(segment
		(start 117.015768 -154.04592)
		(end 117.071648 -154.1018)
		(width 0.3556)
		(layer "F.Cu")
		(net "GND")
	)
	(segment
		(start 292.450012 -2.253488)
		(end 292.450012 -0.821182)
		(width 0.4064)
		(layer "F.Cu")
		(net "GND")
	)
	(segment
		(start 248.202704 -68.46824)
		(end 247.631204 -68.46824)
		(width 0.254)
		(layer "F.Cu")
		(net "GND")
	)
	(segment
		(start 484.7336 -141.4272)
		(end 484.7336 -141.6304)
		(width 0.254)
		(layer "F.Cu")
		(net "GND")
	)
	(segment
		(start 300.949868 -16.168878)
		(end 300.949868 -15.423642)
		(width 0.3556)
		(layer "F.Cu")
		(net "GND")
	)
	(segment
		(start 475.64802 -33.9725)
		(end 475.64802 -33.11398)
		(width 0.254)
		(layer "F.Cu")
		(net "GND")
	)
	(segment
		(start 366.2172 -98.552)
		(end 366.2172 -100.785676)
		(width 0.254)
		(layer "F.Cu")
		(net "GND")
	)
	(segment
		(start 164.154612 -73.914)
		(end 163.862512 -74.2061)
		(width 0.4064)
		(layer "F.Cu")
		(net "GND")
	)
	(segment
		(start 279.778714 -88.594184)
		(end 280.350214 -88.594184)
		(width 0.254)
		(layer "F.Cu")
		(net "GND")
	)
	(segment
		(start 255.521206 -139.829794)
		(end 255.815338 -139.829794)
		(width 0.4064)
		(layer "F.Cu")
		(net "GND")
	)
	(segment
		(start 126.388368 -144.467326)
		(end 126.421642 -144.5006)
		(width 0.3556)
		(layer "F.Cu")
		(net "GND")
	)
	(segment
		(start 125.080268 -99.490784)
		(end 125.651768 -99.490784)
		(width 0.254)
		(layer "F.Cu")
		(net "GND")
	)
	(segment
		(start 317.09995 -3.255518)
		(end 317.146432 -3.302)
		(width 0.4064)
		(layer "F.Cu")
		(net "GND")
	)
	(segment
		(start 68.607686 -54.104286)
		(end 68.6816 -53.977032)
		(width 0.254)
		(layer "F.Cu")
		(net "GND")
	)
	(segment
		(start 383.942336 -30.77083)
		(end 383.955036 -30.78353)
		(width 0.254)
		(layer "F.Cu")
		(net "GND")
	)
	(segment
		(start 118.041928 -2.310892)
		(end 118.099332 -2.253488)
		(width 0.4064)
		(layer "F.Cu")
		(net "GND")
	)
	(segment
		(start 221.050358 -137.67054)
		(end 221.04985 -137.67054)
		(width 0.4064)
		(layer "F.Cu")
		(net "GND")
	)
	(segment
		(start 466.8774 -0.9906)
		(end 466.8774 -0.7366)
		(width 0.254)
		(layer "F.Cu")
		(net "GND")
	)
	(segment
		(start 183.4642 -56.1086)
		(end 183.4642 -55.3974)
		(width 0.254)
		(layer "F.Cu")
		(net "GND")
	)
	(segment
		(start 130.84937 1.994154)
		(end 130.84937 3.778758)
		(width 0.4064)
		(layer "F.Cu")
		(net "GND")
	)
	(segment
		(start 84.060792 -56.085486)
		(end 83.489292 -56.085486)
		(width 0.254)
		(layer "F.Cu")
		(net "GND")
	)
	(segment
		(start 115.549426 -144.364202)
		(end 115.451382 -144.462246)
		(width 0.4064)
		(layer "F.Cu")
		(net "GND")
	)
	(segment
		(start 120.787668 -92.061538)
		(end 121.359168 -92.061538)
		(width 0.254)
		(layer "F.Cu")
		(net "GND")
	)
	(segment
		(start 312.849768 -153.093674)
		(end 312.391298 -153.552144)
		(width 0.4064)
		(layer "F.Cu")
		(net "GND")
	)
	(segment
		(start 347.3196 -149.112224)
		(end 347.3196 -148.766784)
		(width 0.4064)
		(layer "F.Cu")
		(net "GND")
	)
	(segment
		(start 302.099726 -62.838584)
		(end 301.812706 -63.125604)
		(width 0.254)
		(layer "F.Cu")
		(net "GND")
	)
	(segment
		(start 130.231388 -74.725784)
		(end 130.802888 -74.725784)
		(width 0.4064)
		(layer "F.Cu")
		(net "GND")
	)
	(segment
		(start 484.93553 -30.734)
		(end 486.0798 -30.734)
		(width 0.254)
		(layer "F.Cu")
		(net "GND")
	)
	(segment
		(start 146.149568 -18.81505)
		(end 146.149568 -20.023582)
		(width 0.3556)
		(layer "F.Cu")
		(net "GND")
	)
	(segment
		(start 237.199932 -0.821182)
		(end 237.199932 0.38735)
		(width 0.3556)
		(layer "F.Cu")
		(net "GND")
	)
	(segment
		(start 94.362778 -95.709486)
		(end 93.791278 -95.709486)
		(width 0.254)
		(layer "F.Cu")
		(net "GND")
	)
	(segment
		(start 134.523734 -98.995738)
		(end 135.095234 -98.995738)
		(width 0.254)
		(layer "F.Cu")
		(net "GND")
	)
	(segment
		(start 300.736 -17.210532)
		(end 300.736 -16.382746)
		(width 0.3556)
		(layer "F.Cu")
		(net "GND")
	)
	(segment
		(start 232.099866 -20.023582)
		(end 232.099866 -18.757646)
		(width 0.4064)
		(layer "F.Cu")
		(net "GND")
	)
	(segment
		(start 413.4612 -118.7704)
		(end 413.413956 -118.7704)
		(width 0.254)
		(layer "F.Cu")
		(net "GND")
	)
	(segment
		(start 115.636802 -98.995738)
		(end 116.208302 -98.995738)
		(width 0.254)
		(layer "F.Cu")
		(net "GND")
	)
	(segment
		(start 115.549426 -14.2113)
		(end 115.460526 -14.1224)
		(width 0.4064)
		(layer "F.Cu")
		(net "GND")
	)
	(segment
		(start 463.800952 -112.205516)
		(end 463.800952 -113.798604)
		(width 0.4064)
		(layer "F.Cu")
		(net "GND")
	)
	(segment
		(start 276.344634 -63.829184)
		(end 275.773134 -63.829184)
		(width 0.254)
		(layer "F.Cu")
		(net "GND")
	)
	(segment
		(start 243.910104 -83.822286)
		(end 243.338604 -83.822286)
		(width 0.254)
		(layer "F.Cu")
		(net "GND")
	)
	(segment
		(start 395.182852 -156.2481)
		(end 395.182852 -156.987748)
		(width 0.2032)
		(layer "F.Cu")
		(net "GND")
	)
	(segment
		(start 289.22218 -59.371484)
		(end 288.65068 -59.371484)
		(width 0.254)
		(layer "F.Cu")
		(net "GND")
	)
	(segment
		(start 256.364994 -139.829794)
		(end 255.815338 -139.829794)
		(width 0.4064)
		(layer "F.Cu")
		(net "GND")
	)
	(segment
		(start 193.8655 -59.817)
		(end 193.200274 -59.817)
		(width 0.254)
		(layer "F.Cu")
		(net "GND")
	)
	(segment
		(start 206.59979 3.778758)
		(end 206.59979 2.092198)
		(width 0.4064)
		(layer "F.Cu")
		(net "GND")
	)
	(segment
		(start 234.753658 -60.047886)
		(end 235.325158 -60.047886)
		(width 0.254)
		(layer "F.Cu")
		(net "GND")
	)
	(segment
		(start 439.626756 -145.177256)
		(end 439.626756 -144.478756)
		(width 0.254)
		(layer "F.Cu")
		(net "GND")
	)
	(segment
		(start 245.627144 -83.822286)
		(end 245.055644 -83.822286)
		(width 0.254)
		(layer "F.Cu")
		(net "GND")
	)
	(segment
		(start 205.749906 -2.314956)
		(end 205.749906 -0.821182)
		(width 0.4064)
		(layer "F.Cu")
		(net "GND")
	)
	(segment
		(start 391.3378 -104.2543)
		(end 390.93775 -104.65435)
		(width 0.12446)
		(layer "F.Cu")
		(net "GND")
	)
	(segment
		(start 30.865826 -85.4837)
		(end 30.865826 -85.81644)
		(width 0.254)
		(layer "F.Cu")
		(net "GND")
	)
	(segment
		(start 42.449496 0.444754)
		(end 42.449496 -0.821182)
		(width 0.4064)
		(layer "F.Cu")
		(net "GND")
	)
	(segment
		(start 236.183678 -58.561986)
		(end 235.612178 -58.561986)
		(width 0.254)
		(layer "F.Cu")
		(net "GND")
	)
	(segment
		(start 83.202272 -74.411586)
		(end 82.630772 -74.411586)
		(width 0.254)
		(layer "F.Cu")
		(net "GND")
	)
	(segment
		(start 348.19717 -0.653542)
		(end 348.19717 -1.06807)
		(width 0.254)
		(layer "F.Cu")
		(net "GND")
	)
	(segment
		(start 444.540894 -46.021752)
		(end 444.540894 -47.481998)
		(width 0.4064)
		(layer "F.Cu")
		(net "GND")
	)
	(segment
		(start 193.8528 -84.825078)
		(end 193.8528 -84.3026)
		(width 0.254)
		(layer "F.Cu")
		(net "GND")
	)
	(segment
		(start 203.2 -142.856712)
		(end 203.199746 -142.856966)
		(width 0.4064)
		(layer "F.Cu")
		(net "GND")
	)
	(segment
		(start 417.722304 -53.382672)
		(end 416.600386 -53.382672)
		(width 0.254)
		(layer "F.Cu")
		(net "GND")
	)
	(segment
		(start 413.87014 -18.415)
		(end 413.385 -18.415)
		(width 0.254)
		(layer "F.Cu")
		(net "GND")
	)
	(segment
		(start 403.50186 -98.12274)
		(end 403.47646 -98.14814)
		(width 0.254)
		(layer "F.Cu")
		(net "GND")
	)
	(segment
		(start 225.299778 3.778758)
		(end 225.299778 2.092198)
		(width 0.4064)
		(layer "F.Cu")
		(net "GND")
	)
	(segment
		(start 119.929402 -88.594184)
		(end 120.500902 -88.594184)
		(width 0.254)
		(layer "F.Cu")
		(net "GND")
	)
	(segment
		(start 31.463234 -94.114366)
		(end 31.0642 -94.5134)
		(width 0.508)
		(layer "F.Cu")
		(net "GND")
	)
	(segment
		(start 238.8997 -143.492474)
		(end 238.44123 -143.950944)
		(width 0.4064)
		(layer "F.Cu")
		(net "GND")
	)
	(segment
		(start 367.2205 -136.8298)
		(end 367.6269 -136.4234)
		(width 0.4064)
		(layer "F.Cu")
		(net "GND")
	)
	(segment
		(start 195.549774 -16.764)
		(end 195.549774 -15.423642)
		(width 0.4064)
		(layer "F.Cu")
		(net "GND")
	)
	(segment
		(start 311.150508 -0.821182)
		(end 311.15 -0.821182)
		(width 0.4064)
		(layer "F.Cu")
		(net "GND")
	)
	(segment
		(start 25.34158 -82.613246)
		(end 24.991314 -82.613246)
		(width 0.254)
		(layer "F.Cu")
		(net "GND")
	)
	(segment
		(start 164.99078 -0.239522)
		(end 164.418518 0.33274)
		(width 0.254)
		(layer "F.Cu")
		(net "GND")
	)
	(segment
		(start 456.600814 -118.615714)
		(end 456.60437 -118.61927)
		(width 0.4064)
		(layer "F.Cu")
		(net "GND")
	)
	(segment
		(start 236.349794 -152.278842)
		(end 236.349794 -153.006806)
		(width 0.3556)
		(layer "F.Cu")
		(net "GND")
	)
	(segment
		(start 299.250354 3.778758)
		(end 299.249846 3.778758)
		(width 0.4064)
		(layer "F.Cu")
		(net "GND")
	)
	(segment
		(start 115.549426 -152.273)
		(end 115.549426 -153.965402)
		(width 0.4064)
		(layer "F.Cu")
		(net "GND")
	)
	(segment
		(start 42.449496 -146.037046)
		(end 42.424096 -146.011646)
		(width 0.4064)
		(layer "F.Cu")
		(net "GND")
	)
	(segment
		(start 139.34948 -137.67054)
		(end 139.34948 -136.410446)
		(width 0.4064)
		(layer "F.Cu")
		(net "GND")
	)
	(segment
		(start 240.476278 -88.775286)
		(end 239.904778 -88.775286)
		(width 0.254)
		(layer "F.Cu")
		(net "GND")
	)
	(segment
		(start 136.74217 -2.310892)
		(end 138.02741 -2.3622)
		(width 0.254)
		(layer "F.Cu")
		(net "GND")
	)
	(segment
		(start 44.092114 -155.650946)
		(end 44.092114 -155.600146)
		(width 0.4064)
		(layer "F.Cu")
		(net "GND")
	)
	(segment
		(start 451.741032 -51.875944)
		(end 451.742048 -51.875944)
		(width 0.508)
		(layer "F.Cu")
		(net "GND")
	)
	(segment
		(start 296.69994 -156.87294)
		(end 296.700448 -156.87294)
		(width 0.4064)
		(layer "F.Cu")
		(net "GND")
	)
	(segment
		(start 76.449428 -147.27174)
		(end 76.449428 -147.277582)
		(width 0.4064)
		(layer "F.Cu")
		(net "GND")
	)
	(segment
		(start 284.929834 -101.471984)
		(end 284.642814 -101.967538)
		(width 0.4064)
		(layer "F.Cu")
		(net "GND")
	)
	(segment
		(start 396.15745 -105.332276)
		(end 396.15745 -104.70388)
		(width 0.254)
		(layer "F.Cu")
		(net "GND")
	)
	(segment
		(start 34.799524 -137.67054)
		(end 34.799524 -136.680702)
		(width 0.4064)
		(layer "F.Cu")
		(net "GND")
	)
	(segment
		(start 280.549858 -153.965402)
		(end 280.451814 -154.063446)
		(width 0.4064)
		(layer "F.Cu")
		(net "GND")
	)
	(segment
		(start 279.700482 -0.821182)
		(end 279.699974 -0.821182)
		(width 0.4064)
		(layer "F.Cu")
		(net "GND")
	)
	(segment
		(start 289.049968 -147.27174)
		(end 289.049968 -145.998946)
		(width 0.4064)
		(layer "F.Cu")
		(net "GND")
	)
	(segment
		(start 305.199796 -17.208246)
		(end 305.199796 -15.423642)
		(width 0.4064)
		(layer "F.Cu")
		(net "GND")
	)
	(segment
		(start 374.616726 -95.978472)
		(end 374.20677 -95.568516)
		(width 0.254)
		(layer "F.Cu")
		(net "GND")
	)
	(segment
		(start 113.919762 -99.986338)
		(end 114.491262 -99.986338)
		(width 0.254)
		(layer "F.Cu")
		(net "GND")
	)
	(segment
		(start 223.60001 -142.677642)
		(end 223.599756 -142.677896)
		(width 0.4064)
		(layer "F.Cu")
		(net "GND")
	)
	(segment
		(start 194.054984 -77.111352)
		(end 194.457828 -77.111352)
		(width 0.508)
		(layer "F.Cu")
		(net "GND")
	)
	(segment
		(start 243.051838 -55.59044)
		(end 242.480338 -55.59044)
		(width 0.254)
		(layer "F.Cu")
		(net "GND")
	)
	(segment
		(start 243.149882 -11.73099)
		(end 243.149882 -10.422382)
		(width 0.4064)
		(layer "F.Cu")
		(net "GND")
	)
	(segment
		(start 94.362778 -56.085486)
		(end 93.791278 -56.085486)
		(width 0.254)
		(layer "F.Cu")
		(net "GND")
	)
	(segment
		(start 71.183246 -53.60924)
		(end 70.611746 -53.60924)
		(width 0.254)
		(layer "F.Cu")
		(net "GND")
	)
	(segment
		(start 442.1886 -50.4952)
		(end 442.130688 -50.554128)
		(width 0.4064)
		(layer "F.Cu")
		(net "GND")
	)
	(segment
		(start 135.949436 -16.168878)
		(end 135.949436 -15.423642)
		(width 0.3556)
		(layer "F.Cu")
		(net "GND")
	)
	(segment
		(start 141.104874 -69.772784)
		(end 141.391894 -70.059804)
		(width 0.254)
		(layer "F.Cu")
		(net "GND")
	)
	(segment
		(start 29.965904 -93.715332)
		(end 30.566614 -93.715332)
		(width 0.508)
		(layer "F.Cu")
		(net "GND")
	)
	(segment
		(start 299.249846 -13.805154)
		(end 299.249846 -15.423642)
		(width 0.4064)
		(layer "F.Cu")
		(net "GND")
	)
	(segment
		(start 52.649374 3.045206)
		(end 52.448968 2.8448)
		(width 0.3048)
		(layer "F.Cu")
		(net "GND")
	)
	(segment
		(start 69.466206 -83.32724)
		(end 68.894706 -83.32724)
		(width 0.254)
		(layer "F.Cu")
		(net "GND")
	)
	(segment
		(start 383.73685 -115.05565)
		(end 384.1242 -115.443)
		(width 0.1143)
		(layer "F.Cu")
		(net "GND")
	)
	(segment
		(start 221.900496 -133.0706)
		(end 221.899988 -133.076442)
		(width 0.4064)
		(layer "F.Cu")
		(net "GND")
	)
	(segment
		(start 196.566028 -53.856382)
		(end 196.273928 -53.564282)
		(width 0.4064)
		(layer "F.Cu")
		(net "GND")
	)
	(segment
		(start 436.4228 -21.9964)
		(end 436.0926 -22.3266)
		(width 0.254)
		(layer "F.Cu")
		(net "GND")
	)
	(segment
		(start 415.2138 -67.8434)
		(end 414.807654 -68.249546)
		(width 0.508)
		(layer "F.Cu")
		(net "GND")
	)
	(segment
		(start 13.2334 -90.0684)
		(end 13.208 -90.043)
		(width 0.254)
		(layer "F.Cu")
		(net "GND")
	)
	(segment
		(start 140.199364 -133.0706)
		(end 140.199364 -134.861046)
		(width 0.4064)
		(layer "F.Cu")
		(net "GND")
	)
	(segment
		(start 73.899522 -14.410182)
		(end 73.899522 -15.423642)
		(width 0.4064)
		(layer "F.Cu")
		(net "GND")
	)
	(segment
		(start 77.192886 -69.953886)
		(end 76.621386 -69.953886)
		(width 0.254)
		(layer "F.Cu")
		(net "GND")
	)
	(segment
		(start 180.086 -57.834276)
		(end 180.086 -58.166)
		(width 0.4064)
		(layer "F.Cu")
		(net "GND")
	)
	(segment
		(start 67.949318 -5.822188)
		(end 67.949572 -5.822442)
		(width 0.4064)
		(layer "F.Cu")
		(net "GND")
	)
	(segment
		(start 127.655828 -88.099138)
		(end 128.227328 -88.099138)
		(width 0.254)
		(layer "F.Cu")
		(net "GND")
	)
	(segment
		(start 388.23265 -116.72316)
		(end 388.72795 -116.953284)
		(width 0.254)
		(layer "F.Cu")
		(net "GND")
	)
	(segment
		(start 389.71855 -119.29872)
		(end 390.21385 -119.528844)
		(width 0.254)
		(layer "F.Cu")
		(net "GND")
	)
	(segment
		(start 290.0807 -59.866784)
		(end 290.6522 -59.866784)
		(width 0.254)
		(layer "F.Cu")
		(net "GND")
	)
	(segment
		(start 290.0807 -86.612984)
		(end 290.6522 -86.612984)
		(width 0.254)
		(layer "F.Cu")
		(net "GND")
	)
	(segment
		(start 135.735568 -134.863332)
		(end 135.771636 -134.8994)
		(width 0.3556)
		(layer "F.Cu")
		(net "GND")
	)
	(segment
		(start 243.149882 -156.87294)
		(end 243.15039 -156.87294)
		(width 0.4064)
		(layer "F.Cu")
		(net "GND")
	)
	(segment
		(start 454.939908 -51.875944)
		(end 454.940924 -51.875944)
		(width 0.4064)
		(layer "F.Cu")
		(net "GND")
	)
	(segment
		(start 237.199932 -136.46785)
		(end 237.142528 -136.410446)
		(width 0.3556)
		(layer "F.Cu")
		(net "GND")
	)
	(segment
		(start 457.277978 -8.661908)
		(end 457.142596 -8.79729)
		(width 0.254)
		(layer "F.Cu")
		(net "GND")
	)
	(segment
		(start 293.22776 -93.052138)
		(end 292.65626 -93.052138)
		(width 0.3048)
		(layer "F.Cu")
		(net "GND")
	)
	(segment
		(start 322.219574 -23.368254)
		(end 322.219574 -23.547324)
		(width 0.4064)
		(layer "F.Cu")
		(net "GND")
	)
	(segment
		(start 79.768192 -66.48704)
		(end 79.196692 -66.48704)
		(width 0.254)
		(layer "F.Cu")
		(net "GND")
	)
	(segment
		(start 126.797308 -84.631784)
		(end 127.368808 -84.631784)
		(width 0.254)
		(layer "F.Cu")
		(net "GND")
	)
	(segment
		(start 80.626712 -61.038486)
		(end 80.055212 -61.038486)
		(width 0.254)
		(layer "F.Cu")
		(net "GND")
	)
	(segment
		(start 282.925774 -100.976684)
		(end 283.212794 -101.471984)
		(width 0.254)
		(layer "F.Cu")
		(net "GND")
	)
	(segment
		(start 93.504258 -87.28964)
		(end 92.932758 -87.28964)
		(width 0.254)
		(layer "F.Cu")
		(net "GND")
	)
	(segment
		(start 212.54974 -3.762756)
		(end 212.549994 -3.76301)
		(width 0.4064)
		(layer "F.Cu")
		(net "GND")
	)
	(segment
		(start 284.929834 -52.932838)
		(end 284.37205 -53.8988)
		(width 0.254)
		(layer "F.Cu")
		(net "GND")
	)
	(segment
		(start 127.392176 -18.757646)
		(end 127.44958 -18.81505)
		(width 0.3556)
		(layer "F.Cu")
		(net "GND")
	)
	(segment
		(start 221.899988 -15.602712)
		(end 221.899988 -15.423642)
		(width 0.4064)
		(layer "F.Cu")
		(net "GND")
	)
	(segment
		(start 49.24933 -152.279096)
		(end 49.24933 -154.063446)
		(width 0.4064)
		(layer "F.Cu")
		(net "GND")
	)
	(segment
		(start 57.74944 -0.821182)
		(end 57.74944 0.444754)
		(width 0.4064)
		(layer "F.Cu")
		(net "GND")
	)
	(segment
		(start 299.524166 -88.099138)
		(end 300.095666 -88.099138)
		(width 0.3048)
		(layer "F.Cu")
		(net "GND")
	)
	(segment
		(start 68.6816 -53.977032)
		(end 68.894706 -53.60924)
		(width 0.254)
		(layer "F.Cu")
		(net "GND")
	)
	(segment
		(start 66.249296 -3.762756)
		(end 66.249296 -5.822188)
		(width 0.4064)
		(layer "F.Cu")
		(net "GND")
	)
	(segment
		(start 204.050392 -137.67054)
		(end 204.049884 -137.67054)
		(width 0.4064)
		(layer "F.Cu")
		(net "GND")
	)
	(segment
		(start 73.899522 -152.273)
		(end 73.899522 -152.278842)
		(width 0.4064)
		(layer "F.Cu")
		(net "GND")
	)
	(segment
		(start 68.607686 -89.765886)
		(end 68.036186 -89.765886)
		(width 0.254)
		(layer "F.Cu")
		(net "GND")
	)
	(segment
		(start 69.64934 -144.364202)
		(end 69.551296 -144.462246)
		(width 0.4064)
		(layer "F.Cu")
		(net "GND")
	)
	(segment
		(start 280.644092 -50.324258)
		(end 280.637234 -50.3174)
		(width 0.2286)
		(layer "F.Cu")
		(net "GND")
	)
	(segment
		(start 33.099502 0.444754)
		(end 33.099502 -0.821182)
		(width 0.4064)
		(layer "F.Cu")
		(net "GND")
	)
	(segment
		(start 14.605 -97.917)
		(end 14.605 -98.5774)
		(width 0.4064)
		(layer "F.Cu")
		(net "GND")
	)
	(segment
		(start 239.749838 -156.87294)
		(end 239.750346 -156.87294)
		(width 0.4064)
		(layer "F.Cu")
		(net "GND")
	)
	(segment
		(start 441.321952 -28.632404)
		(end 441.721748 -29.0322)
		(width 0.3048)
		(layer "F.Cu")
		(net "GND")
	)
	(segment
		(start 377.081542 -126.55169)
		(end 377.2662 -126.736348)
		(width 0.254)
		(layer "F.Cu")
		(net "GND")
	)
	(segment
		(start 408.472386 -3.387852)
		(end 408.463242 -3.378708)
		(width 0.254)
		(layer "F.Cu")
		(net "GND")
	)
	(segment
		(start 221.899734 -152.458166)
		(end 221.899734 -154.063446)
		(width 0.4064)
		(layer "F.Cu")
		(net "GND")
	)
	(segment
		(start 283.04236 -136.410446)
		(end 283.04236 -136.397746)
		(width 0.3556)
		(layer "F.Cu")
		(net "GND")
	)
	(segment
		(start 206.59979 -17.110202)
		(end 206.59979 -15.423642)
		(width 0.4064)
		(layer "F.Cu")
		(net "GND")
	)
	(segment
		(start 217.4494 -154.079194)
		(end 217.472006 -154.1018)
		(width 0.3556)
		(layer "F.Cu")
		(net "GND")
	)
	(segment
		(start 2.495042 -13.98651)
		(end 2.495042 -13.599414)
		(width 0.4064)
		(layer "F.Cu")
		(net "GND")
	)
	(segment
		(start 303.500282 -152.273)
		(end 303.499774 -152.278842)
		(width 0.4064)
		(layer "F.Cu")
		(net "GND")
	)
	(segment
		(start 252.495304 -68.963286)
		(end 251.923804 -68.963286)
		(width 0.254)
		(layer "F.Cu")
		(net "GND")
	)
	(segment
		(start 146.092164 -18.757646)
		(end 146.149568 -18.81505)
		(width 0.3556)
		(layer "F.Cu")
		(net "GND")
	)
	(segment
		(start 291.600382 -5.822442)
		(end 291.599874 -5.822442)
		(width 0.4064)
		(layer "F.Cu")
		(net "GND")
	)
	(segment
		(start 241.334798 -57.57164)
		(end 240.763298 -57.57164)
		(width 0.254)
		(layer "F.Cu")
		(net "GND")
	)
	(segment
		(start 128.514348 -82.650584)
		(end 129.085848 -82.650584)
		(width 0.254)
		(layer "F.Cu")
		(net "GND")
	)
	(segment
		(start 281.320494 -67.966844)
		(end 281.320494 -68.335652)
		(width 0.254)
		(layer "F.Cu")
		(net "GND")
	)
	(segment
		(start 34.799524 -19.027902)
		(end 34.799524 -20.023582)
		(width 0.4064)
		(layer "F.Cu")
		(net "GND")
	)
	(segment
		(start 227.849938 0.38735)
		(end 227.792534 0.444754)
		(width 0.3556)
		(layer "F.Cu")
		(net "GND")
	)
	(segment
		(start 242.299744 -152.279096)
		(end 242.299744 -154.063446)
		(width 0.4064)
		(layer "F.Cu")
		(net "GND")
	)
	(segment
		(start 462.980532 -137.219944)
		(end 464.485736 -137.219944)
		(width 0.254)
		(layer "F.Cu")
		(net "GND")
	)
	(segment
		(start 203.199746 -6.001766)
		(end 203.199746 -7.607046)
		(width 0.4064)
		(layer "F.Cu")
		(net "GND")
	)
	(segment
		(start 288.200338 -133.0706)
		(end 288.19983 -133.076442)
		(width 0.4064)
		(layer "F.Cu")
		(net "GND")
	)
	(segment
		(start 306.900326 -142.6718)
		(end 306.899818 -142.677642)
		(width 0.4064)
		(layer "F.Cu")
		(net "GND")
	)
	(segment
		(start 150.399496 -20.023582)
		(end 150.399496 -21.517356)
		(width 0.4064)
		(layer "F.Cu")
		(net "GND")
	)
	(segment
		(start 413.272986 -3.083814)
		(end 413.385 -2.9718)
		(width 0.254)
		(layer "F.Cu")
		(net "GND")
	)
	(segment
		(start 412.864554 -21.409152)
		(end 412.965646 -21.510244)
		(width 0.254)
		(layer "F.Cu")
		(net "GND")
	)
	(segment
		(start 373.375428 -153.827988)
		(end 373.972328 -153.827988)
		(width 0.254)
		(layer "F.Cu")
		(net "GND")
	)
	(segment
		(start 236.1184 -6.7818)
		(end 236.1184 -7.591806)
		(width 0.3556)
		(layer "F.Cu")
		(net "GND")
	)
	(segment
		(start 287.1216 -100.64877)
		(end 286.768286 -101.261164)
		(width 0.254)
		(layer "F.Cu")
		(net "GND")
	)
	(segment
		(start 209.14995 -20.023582)
		(end 209.14995 -21.455888)
		(width 0.4064)
		(layer "F.Cu")
		(net "GND")
	)
	(segment
		(start 437.721756 -29.832808)
		(end 437.32196 -30.232604)
		(width 0.3048)
		(layer "F.Cu")
		(net "GND")
	)
	(segment
		(start 498.5512 -36.4998)
		(end 499.112032 -36.4998)
		(width 0.254)
		(layer "F.Cu")
		(net "GND")
	)
	(segment
		(start 230.399844 -156.87294)
		(end 230.400352 -156.87294)
		(width 0.4064)
		(layer "F.Cu")
		(net "GND")
	)
	(segment
		(start 195.135246 -4.317746)
		(end 194.564 -3.7465)
		(width 0.4064)
		(layer "F.Cu")
		(net "GND")
	)
	(segment
		(start 284.071314 -60.362338)
		(end 283.499814 -60.362338)
		(width 0.254)
		(layer "F.Cu")
		(net "GND")
	)
	(segment
		(start 281.400504 -137.67054)
		(end 281.399996 -137.67054)
		(width 0.4064)
		(layer "F.Cu")
		(net "GND")
	)
	(segment
		(start 239.617758 -99.17684)
		(end 239.046258 -99.17684)
		(width 0.254)
		(layer "F.Cu")
		(net "GND")
	)
	(segment
		(start 378.4854 -124.3838)
		(end 378.606558 -124.504958)
		(width 0.254)
		(layer "F.Cu")
		(net "GND")
	)
	(segment
		(start 282.0162 -134.036054)
		(end 282.0162 -134.84352)
		(width 0.3556)
		(layer "F.Cu")
		(net "GND")
	)
	(segment
		(start 174.59198 -105.3338)
		(end 173.5836 -105.3338)
		(width 0.254)
		(layer "F.Cu")
		(net "GND")
	)
	(segment
		(start 246.485664 -79.36484)
		(end 245.914164 -79.36484)
		(width 0.254)
		(layer "F.Cu")
		(net "GND")
	)
	(segment
		(start 402.022818 -99.951286)
		(end 402.790914 -99.951286)
		(width 0.1778)
		(layer "F.Cu")
		(net "GND")
	)
	(segment
		(start 126.599442 -152.273)
		(end 126.599442 -153.001726)
		(width 0.3556)
		(layer "F.Cu")
		(net "GND")
	)
	(segment
		(start 406.782016 -150.247604)
		(end 406.561036 -150.468584)
		(width 0.4064)
		(layer "F.Cu")
		(net "GND")
	)
	(segment
		(start 393.68095 -95.888556)
		(end 393.984988 -95.205042)
		(width 0.254)
		(layer "F.Cu")
		(net "GND")
	)
	(segment
		(start 71.117968 -134.0358)
		(end 71.117968 -134.845806)
		(width 0.3556)
		(layer "F.Cu")
		(net "GND")
	)
	(segment
		(start 371.073172 -93.476572)
		(end 371.7036 -94.107)
		(width 0.254)
		(layer "F.Cu")
		(net "GND")
	)
	(segment
		(start 211.699856 -137.67054)
		(end 211.699856 -139.170156)
		(width 0.4064)
		(layer "F.Cu")
		(net "GND")
	)
	(segment
		(start 70.324726 -67.972686)
		(end 69.753226 -67.972686)
		(width 0.254)
		(layer "F.Cu")
		(net "GND")
	)
	(segment
		(start 388.72795 -102.49154)
		(end 388.72795 -102.12832)
		(width 0.254)
		(layer "F.Cu")
		(net "GND")
	)
	(segment
		(start 165.608 -72.263)
		(end 165.481 -72.136)
		(width 0.254)
		(layer "F.Cu")
		(net "GND")
	)
	(segment
		(start 236.183678 -80.35544)
		(end 235.612178 -80.35544)
		(width 0.254)
		(layer "F.Cu")
		(net "GND")
	)
	(segment
		(start 128.514348 -85.622384)
		(end 129.085848 -85.622384)
		(width 0.254)
		(layer "F.Cu")
		(net "GND")
	)
	(segment
		(start 496.704874 -39.619936)
		(end 495.149632 -39.619936)
		(width 0.254)
		(layer "F.Cu")
		(net "GND")
	)
	(segment
		(start 249.061224 -78.869286)
		(end 248.489724 -78.869286)
		(width 0.254)
		(layer "F.Cu")
		(net "GND")
	)
	(segment
		(start 151.24938 -152.273)
		(end 151.24938 -154.063446)
		(width 0.4064)
		(layer "F.Cu")
		(net "GND")
	)
	(segment
		(start 61.149484 -2.276856)
		(end 61.111384 -2.314956)
		(width 0.4064)
		(layer "F.Cu")
		(net "GND")
	)
	(segment
		(start 207.449928 -155.638246)
		(end 207.424528 -155.612846)
		(width 0.4064)
		(layer "F.Cu")
		(net "GND")
	)
	(segment
		(start 72.900286 -97.19564)
		(end 72.328786 -97.19564)
		(width 0.254)
		(layer "F.Cu")
		(net "GND")
	)
	(segment
		(start 380.982982 -35.270948)
		(end 380.59233 -35.6616)
		(width 0.2032)
		(layer "F.Cu")
		(net "GND")
	)
	(segment
		(start 301.800514 -156.87294)
		(end 301.800006 -156.87294)
		(width 0.3556)
		(layer "F.Cu")
		(net "GND")
	)
	(segment
		(start 394.17625 -108.766356)
		(end 394.17625 -108.13796)
		(width 0.254)
		(layer "F.Cu")
		(net "GND")
	)
	(segment
		(start 87.494872 -87.784686)
		(end 86.923372 -87.784686)
		(width 0.254)
		(layer "F.Cu")
		(net "GND")
	)
	(segment
		(start 260.50875 -56.085486)
		(end 261.08025 -56.085486)
		(width 0.254)
		(layer "F.Cu")
		(net "GND")
	)
	(segment
		(start 382.1684 -124.34824)
		(end 382.33477 -124.206)
		(width 0.254)
		(layer "F.Cu")
		(net "GND")
	)
	(segment
		(start 133.39953 -20.023582)
		(end 133.39953 -21.517356)
		(width 0.4064)
		(layer "F.Cu")
		(net "GND")
	)
	(segment
		(start 423.890186 -26.416)
		(end 423.890186 -26.534618)
		(width 0.254)
		(layer "F.Cu")
		(net "GND")
	)
	(segment
		(start 138.816334 -86.612984)
		(end 139.387834 -86.612984)
		(width 0.254)
		(layer "F.Cu")
		(net "GND")
	)
	(segment
		(start 202.349862 -9.156446)
		(end 202.349862 -10.422382)
		(width 0.4064)
		(layer "F.Cu")
		(net "GND")
	)
	(segment
		(start 398.53743 -126.93269)
		(end 398.225518 -126.93269)
		(width 0.254)
		(layer "F.Cu")
		(net "GND")
	)
	(segment
		(start 234.65028 -152.273)
		(end 234.649772 -152.278842)
		(width 0.4064)
		(layer "F.Cu")
		(net "GND")
	)
	(segment
		(start 284.799786 -5.822442)
		(end 284.799532 -5.822696)
		(width 0.4064)
		(layer "F.Cu")
		(net "GND")
	)
	(segment
		(start 389.68172 -126.486666)
		(end 389.68172 -126.63932)
		(width 0.254)
		(layer "F.Cu")
		(net "GND")
	)
	(segment
		(start 137.670794 -81.659984)
		(end 137.099294 -81.659984)
		(width 0.254)
		(layer "F.Cu")
		(net "GND")
	)
	(segment
		(start 289.22218 -91.070938)
		(end 289.79368 -91.070938)
		(width 0.254)
		(layer "F.Cu")
		(net "GND")
	)
	(segment
		(start 237.142528 -136.410446)
		(end 237.142528 -136.397746)
		(width 0.3556)
		(layer "F.Cu")
		(net "GND")
	)
	(segment
		(start 67.099434 -10.422382)
		(end 67.099434 -9.156446)
		(width 0.4064)
		(layer "F.Cu")
		(net "GND")
	)
	(segment
		(start 237.199932 -11.854688)
		(end 237.142528 -11.912092)
		(width 0.4064)
		(layer "F.Cu")
		(net "GND")
	)
	(segment
		(start 74.617326 -95.21444)
		(end 74.045826 -95.21444)
		(width 0.254)
		(layer "F.Cu")
		(net "GND")
	)
	(segment
		(start 134.523734 -56.399938)
		(end 135.095234 -56.399938)
		(width 0.254)
		(layer "F.Cu")
		(net "GND")
	)
	(segment
		(start 243.051838 -70.44944)
		(end 242.480338 -70.44944)
		(width 0.254)
		(layer "F.Cu")
		(net "GND")
	)
	(segment
		(start 397.56334 -129.32664)
		(end 397.56334 -130.37566)
		(width 0.4064)
		(layer "F.Cu")
		(net "GND")
	)
	(segment
		(start 392.69035 -119.29872)
		(end 393.18565 -119.528844)
		(width 0.254)
		(layer "F.Cu")
		(net "GND")
	)
	(segment
		(start 158.17596 -122.68454)
		(end 158.17596 -122.04954)
		(width 0.4572)
		(layer "F.Cu")
		(net "GND")
	)
	(segment
		(start 381.29845 -97.83572)
		(end 381.79375 -97.605596)
		(width 0.254)
		(layer "F.Cu")
		(net "GND")
	)
	(segment
		(start 390.62152 -76.113894)
		(end 390.945624 -76.437998)
		(width 0.254)
		(layer "F.Cu")
		(net "GND")
	)
	(segment
		(start -0.254 -143.7132)
		(end 0 -143.9672)
		(width 0.4064)
		(layer "F.Cu")
		(net "GND")
	)
	(segment
		(start 77.747368 -25.6032)
		(end 77.264768 -26.0858)
		(width 0.4064)
		(layer "F.Cu")
		(net "GND")
	)
	(segment
		(start 34.799524 -10.422382)
		(end 34.799524 -9.426702)
		(width 0.4064)
		(layer "F.Cu")
		(net "GND")
	)
	(segment
		(start 207.450436 -0.821182)
		(end 207.449928 -0.821182)
		(width 0.4064)
		(layer "F.Cu")
		(net "GND")
	)
	(segment
		(start 399.634964 -104.85501)
		(end 399.634964 -103.855012)
		(width 0.254)
		(layer "F.Cu")
		(net "GND")
	)
	(segment
		(start 236.350302 -133.0706)
		(end 236.349794 -133.076442)
		(width 0.3556)
		(layer "F.Cu")
		(net "GND")
	)
	(segment
		(start 246.485664 -60.54344)
		(end 245.914164 -60.54344)
		(width 0.254)
		(layer "F.Cu")
		(net "GND")
	)
	(segment
		(start 232.749598 -63.51524)
		(end 232.101898 -63.51524)
		(width 0.254)
		(layer "F.Cu")
		(net "GND")
	)
	(segment
		(start 448.60083 -113.75517)
		(end 448.5894 -113.7666)
		(width 0.4064)
		(layer "F.Cu")
		(net "GND")
	)
	(segment
		(start 113.967768 -140.4874)
		(end 113.688368 -140.208)
		(width 0.4064)
		(layer "F.Cu")
		(net "GND")
	)
	(segment
		(start 299.524166 -56.399938)
		(end 300.095666 -56.399938)
		(width 0.254)
		(layer "F.Cu")
		(net "GND")
	)
	(segment
		(start 217.4494 -134.1882)
		(end 217.4494 -134.876794)
		(width 0.3556)
		(layer "F.Cu")
		(net "GND")
	)
	(segment
		(start 76.449428 -9.156446)
		(end 76.449428 -10.422382)
		(width 0.4064)
		(layer "F.Cu")
		(net "GND")
	)
	(segment
		(start 74.749406 -147.27174)
		(end 74.749406 -146.011646)
		(width 0.4064)
		(layer "F.Cu")
		(net "GND")
	)
	(segment
		(start 367.545112 -79.494888)
		(end 367.945162 -79.094838)
		(width 0.254)
		(layer "F.Cu")
		(net "GND")
	)
	(segment
		(start 480.539806 -17.59839)
		(end 481.41382 -16.724376)
		(width 0.254)
		(layer "F.Cu")
		(net "GND")
	)
	(segment
		(start 294.14978 -6.637274)
		(end 294.14978 -5.822442)
		(width 0.4064)
		(layer "F.Cu")
		(net "GND")
	)
	(segment
		(start 310.299862 -152.278842)
		(end 310.299862 -152.996138)
		(width 0.3556)
		(layer "F.Cu")
		(net "GND")
	)
	(segment
		(start 198.949818 -143.391382)
		(end 198.755 -143.5862)
		(width 0.3556)
		(layer "F.Cu")
		(net "GND")
	)
	(segment
		(start 255.87198 -12.613386)
		(end 255.87198 -13.292582)
		(width 0.4064)
		(layer "F.Cu")
		(net "GND")
	)
	(segment
		(start 237.199932 -146.06905)
		(end 237.142528 -146.011646)
		(width 0.3556)
		(layer "F.Cu")
		(net "GND")
	)
	(segment
		(start 205.749906 -20.023582)
		(end 205.749906 -18.744946)
		(width 0.4064)
		(layer "F.Cu")
		(net "GND")
	)
	(segment
		(start 274.627848 -89.584784)
		(end 275.199348 -89.584784)
		(width 0.254)
		(layer "F.Cu")
		(net "GND")
	)
	(segment
		(start 79.768192 -91.25204)
		(end 79.196692 -91.25204)
		(width 0.254)
		(layer "F.Cu")
		(net "GND")
	)
	(segment
		(start 73.899268 -152.279096)
		(end 73.899268 -153.093674)
		(width 0.4064)
		(layer "F.Cu")
		(net "GND")
	)
	(segment
		(start 277.774654 -100.976684)
		(end 278.061674 -101.472746)
		(width 0.1524)
		(layer "F.Cu")
		(net "GND")
	)
	(segment
		(start 119.799354 -142.677642)
		(end 119.7991 -142.677896)
		(width 0.4064)
		(layer "F.Cu")
		(net "GND")
	)
	(segment
		(start 231.249728 -152.458166)
		(end 231.249728 -154.063446)
		(width 0.4064)
		(layer "F.Cu")
		(net "GND")
	)
	(segment
		(start 90.928698 -63.019686)
		(end 90.357198 -63.019686)
		(width 0.254)
		(layer "F.Cu")
		(net "GND")
	)
	(segment
		(start 125.080268 -91.565984)
		(end 125.651768 -91.565984)
		(width 0.254)
		(layer "F.Cu")
		(net "GND")
	)
	(segment
		(start 72.1995 -136.46785)
		(end 72.142096 -136.410446)
		(width 0.3556)
		(layer "F.Cu")
		(net "GND")
	)
	(segment
		(start 321.6148 -31.115)
		(end 321.65798 -31.15818)
		(width 0.4572)
		(layer "F.Cu")
		(net "GND")
	)
	(segment
		(start 73.899522 -152.278842)
		(end 73.899268 -152.279096)
		(width 0.4064)
		(layer "F.Cu")
		(net "GND")
	)
	(segment
		(start 138.499342 -14.409928)
		(end 138.03757 -13.948156)
		(width 0.4064)
		(layer "F.Cu")
		(net "GND")
	)
	(segment
		(start 76.334366 -80.35544)
		(end 75.762866 -80.35544)
		(width 0.254)
		(layer "F.Cu")
		(net "GND")
	)
	(segment
		(start 119.7991 -133.891274)
		(end 119.34063 -134.349744)
		(width 0.4064)
		(layer "F.Cu")
		(net "GND")
	)
	(segment
		(start 47.549308 -15.602966)
		(end 47.549562 -15.602712)
		(width 0.4064)
		(layer "F.Cu")
		(net "GND")
	)
	(segment
		(start 297.807126 -71.258938)
		(end 298.378626 -71.258938)
		(width 0.254)
		(layer "F.Cu")
		(net "GND")
	)
	(segment
		(start 139.674854 -61.352938)
		(end 140.246354 -61.352938)
		(width 0.254)
		(layer "F.Cu")
		(net "GND")
	)
	(segment
		(start 114.699542 -145.998946)
		(end 114.699542 -147.27174)
		(width 0.4064)
		(layer "F.Cu")
		(net "GND")
	)
	(segment
		(start 282.104592 -70.422008)
		(end 281.570176 -70.956424)
		(width 0.254)
		(layer "F.Cu")
		(net "GND")
	)
	(segment
		(start 394.903706 -100.30333)
		(end 395.16685 -100.181156)
		(width 0.254)
		(layer "F.Cu")
		(net "GND")
	)
	(segment
		(start 385.33705 -106.25455)
		(end 385.7371 -106.6546)
		(width 0.254)
		(layer "F.Cu")
		(net "GND")
	)
	(segment
		(start 152.099518 -142.6718)
		(end 152.099518 -143.941546)
		(width 0.4064)
		(layer "F.Cu")
		(net "GND")
	)
	(segment
		(start 374.674892 -122.918728)
		(end 375.44121 -122.918728)
		(width 0.254)
		(layer "F.Cu")
		(net "GND")
	)
	(segment
		(start 243.051838 -74.411586)
		(end 242.480338 -74.411586)
		(width 0.254)
		(layer "F.Cu")
		(net "GND")
	)
	(segment
		(start 215.0999 -147.27174)
		(end 215.0999 -148.771356)
		(width 0.4064)
		(layer "F.Cu")
		(net "GND")
	)
	(segment
		(start 354.26904 -100.25888)
		(end 355.16312 -99.3648)
		(width 0.254)
		(layer "F.Cu")
		(net "GND")
	)
	(segment
		(start 61.149484 -0.821182)
		(end 61.149484 -2.276856)
		(width 0.4064)
		(layer "F.Cu")
		(net "GND")
	)
	(segment
		(start 139.674854 -66.305938)
		(end 140.246354 -66.305938)
		(width 0.254)
		(layer "F.Cu")
		(net "GND")
	)
	(segment
		(start 75.599544 -6.001512)
		(end 75.59929 -6.001766)
		(width 0.4064)
		(layer "F.Cu")
		(net "GND")
	)
	(segment
		(start 384.27025 -99.55276)
		(end 384.76555 -99.322636)
		(width 0.254)
		(layer "F.Cu")
		(net "GND")
	)
	(segment
		(start 137.957814 -90.080338)
		(end 138.529314 -90.080338)
		(width 0.254)
		(layer "F.Cu")
		(net "GND")
	)
	(segment
		(start 123.363228 -56.894984)
		(end 122.791728 -56.894984)
		(width 0.254)
		(layer "F.Cu")
		(net "GND")
	)
	(segment
		(start 464.600798 -112.205516)
		(end 464.600798 -114.189002)
		(width 0.4064)
		(layer "F.Cu")
		(net "GND")
	)
	(segment
		(start 199.799956 -0.821182)
		(end 199.799956 0.174498)
		(width 0.4064)
		(layer "F.Cu")
		(net "GND")
	)
	(segment
		(start 385.985004 -93.544898)
		(end 385.985004 -92.917518)
		(width 0.254)
		(layer "F.Cu")
		(net "GND")
	)
	(segment
		(start 382.1684 -119.47271)
		(end 382.28905 -119.528844)
		(width 0.254)
		(layer "F.Cu")
		(net "GND")
	)
	(segment
		(start 45.84954 -133.076442)
		(end 45.849286 -133.076696)
		(width 0.4064)
		(layer "F.Cu")
		(net "GND")
	)
	(segment
		(start 300.736 1.991868)
		(end 300.772068 1.9558)
		(width 0.3556)
		(layer "F.Cu")
		(net "GND")
	)
	(segment
		(start 14.830806 2.692654)
		(end 14.830806 3.507232)
		(width 0.254)
		(layer "F.Cu")
		(net "GND")
	)
	(segment
		(start 78.909672 -64.010286)
		(end 78.338172 -64.010286)
		(width 0.254)
		(layer "F.Cu")
		(net "GND")
	)
	(segment
		(start 274.627848 -91.565984)
		(end 275.199348 -91.565984)
		(width 0.1016)
		(layer "F.Cu")
		(net "GND")
	)
	(segment
		(start 376.581162 -112.374172)
		(end 376.335036 -111.854996)
		(width 0.254)
		(layer "F.Cu")
		(net "GND")
	)
	(segment
		(start 127.44958 0.38735)
		(end 127.392176 0.444754)
		(width 0.3556)
		(layer "F.Cu")
		(net "GND")
	)
	(segment
		(start 61.796168 1.9812)
		(end 61.821568 1.9558)
		(width 0.3556)
		(layer "F.Cu")
		(net "GND")
	)
	(segment
		(start 420.69004 -32.134556)
		(end 420.690294 -32.134556)
		(width 0.3048)
		(layer "F.Cu")
		(net "GND")
	)
	(segment
		(start 391.3378 -112.2553)
		(end 391.73785 -111.85525)
		(width 0.254)
		(layer "F.Cu")
		(net "GND")
	)
	(segment
		(start 238.899954 -133.076442)
		(end 238.8997 -133.076696)
		(width 0.4064)
		(layer "F.Cu")
		(net "GND")
	)
	(segment
		(start 248.202704 -79.36484)
		(end 247.631204 -79.36484)
		(width 0.254)
		(layer "F.Cu")
		(net "GND")
	)
	(segment
		(start 253.353824 -86.29904)
		(end 252.782324 -86.29904)
		(width 0.254)
		(layer "F.Cu")
		(net "GND")
	)
	(segment
		(start 209.14995 0.34925)
		(end 209.092546 0.406654)
		(width 0.4064)
		(layer "F.Cu")
		(net "GND")
	)
	(segment
		(start 231.249728 -133.255766)
		(end 231.249728 -134.861046)
		(width 0.4064)
		(layer "F.Cu")
		(net "GND")
	)
	(segment
		(start 303.500282 -133.0706)
		(end 303.499774 -133.076442)
		(width 0.4064)
		(layer "F.Cu")
		(net "GND")
	)
	(segment
		(start 243.910104 -85.803486)
		(end 243.338604 -85.803486)
		(width 0.254)
		(layer "F.Cu")
		(net "GND")
	)
	(segment
		(start 135.099552 -18.757646)
		(end 135.099552 -20.023582)
		(width 0.4064)
		(layer "F.Cu")
		(net "GND")
	)
	(segment
		(start 126.388368 -7.612126)
		(end 126.421642 -7.6454)
		(width 0.3556)
		(layer "F.Cu")
		(net "GND")
	)
	(segment
		(start 31.472378 -22.160992)
		(end 31.472378 -21.590254)
		(width 0.381)
		(layer "F.Cu")
		(net "GND")
	)
	(segment
		(start 87.494872 -56.085486)
		(end 86.923372 -56.085486)
		(width 0.254)
		(layer "F.Cu")
		(net "GND")
	)
	(segment
		(start 281.141424 -71.261732)
		(end 281.141424 -71.460614)
		(width 0.254)
		(layer "F.Cu")
		(net "GND")
	)
	(segment
		(start 291.51072 -89.089738)
		(end 290.93922 -89.089738)
		(width 0.254)
		(layer "F.Cu")
		(net "GND")
	)
	(segment
		(start 393.902438 -105.780332)
		(end 393.684506 -105.5624)
		(width 0.1397)
		(layer "F.Cu")
		(net "GND")
	)
	(segment
		(start 245.627144 -90.756486)
		(end 245.055644 -90.756486)
		(width 0.254)
		(layer "F.Cu")
		(net "GND")
	)
	(segment
		(start 494.31067 -58.507376)
		(end 494.31067 -58.866024)
		(width 0.254)
		(layer "F.Cu")
		(net "GND")
	)
	(segment
		(start 90.802968 -3.635756)
		(end 90.802968 -2.975356)
		(width 0.4064)
		(layer "F.Cu")
		(net "GND")
	)
	(segment
		(start 75.475846 -88.775286)
		(end 74.904346 -88.775286)
		(width 0.254)
		(layer "F.Cu")
		(net "GND")
	)
	(segment
		(start 241.334798 -51.62804)
		(end 240.763298 -51.62804)
		(width 0.254)
		(layer "F.Cu")
		(net "GND")
	)
	(segment
		(start 113.849404 -146.008852)
		(end 113.849404 -147.27174)
		(width 0.4064)
		(layer "F.Cu")
		(net "GND")
	)
	(segment
		(start 465.346796 -53.221636)
		(end 465.346796 -53.053996)
		(width 0.4064)
		(layer "F.Cu")
		(net "GND")
	)
	(segment
		(start 208.299812 -133.812534)
		(end 208.0768 -134.035546)
		(width 0.3556)
		(layer "F.Cu")
		(net "GND")
	)
	(segment
		(start 138.816334 -82.650584)
		(end 139.387834 -82.650584)
		(width 0.254)
		(layer "F.Cu")
		(net "GND")
	)
	(segment
		(start 209.14995 -155.70835)
		(end 209.092546 -155.650946)
		(width 0.4064)
		(layer "F.Cu")
		(net "GND")
	)
	(segment
		(start 309.449978 -21.479256)
		(end 309.411878 -21.517356)
		(width 0.4064)
		(layer "F.Cu")
		(net "GND")
	)
	(segment
		(start 284.071314 -91.070938)
		(end 284.642814 -91.070938)
		(width 0.254)
		(layer "F.Cu")
		(net "GND")
	)
	(segment
		(start 72.1995 -0.821182)
		(end 72.1995 0.38735)
		(width 0.3556)
		(layer "F.Cu")
		(net "GND")
	)
	(segment
		(start 26.9748 -77.1906)
		(end 26.9748 -76.8858)
		(width 0.254)
		(layer "F.Cu")
		(net "GND")
	)
	(segment
		(start 113.849404 -20.023582)
		(end 113.849404 -21.567648)
		(width 0.4064)
		(layer "F.Cu")
		(net "GND")
	)
	(segment
		(start 293.51478 -89.584784)
		(end 294.08628 -89.584784)
		(width 0.3048)
		(layer "F.Cu")
		(net "GND")
	)
	(segment
		(start 152.099518 -5.822442)
		(end 152.099518 -7.086346)
		(width 0.4064)
		(layer "F.Cu")
		(net "GND")
	)
	(segment
		(start 209.092546 -9.194546)
		(end 209.092546 -9.143746)
		(width 0.4064)
		(layer "F.Cu")
		(net "GND")
	)
	(segment
		(start 215.949784 -15.423642)
		(end 215.949784 -13.427456)
		(width 0.4064)
		(layer "F.Cu")
		(net "GND")
	)
	(segment
		(start 287.79216 -56.894984)
		(end 288.36366 -56.894984)
		(width 0.254)
		(layer "F.Cu")
		(net "GND")
	)
	(segment
		(start 204.900276 -133.0706)
		(end 204.899768 -133.076442)
		(width 0.4064)
		(layer "F.Cu")
		(net "GND")
	)
	(segment
		(start 47.549562 -15.423642)
		(end 47.549562 -13.36421)
		(width 0.4064)
		(layer "F.Cu")
		(net "GND")
	)
	(segment
		(start 486.537 -141.9606)
		(end 486.814622 -141.682978)
		(width 0.254)
		(layer "F.Cu")
		(net "GND")
	)
	(segment
		(start 398.13865 -116.72316)
		(end 398.63395 -116.953284)
		(width 0.254)
		(layer "F.Cu")
		(net "GND")
	)
	(segment
		(start 133.39953 -0.821182)
		(end 133.39953 -2.314956)
		(width 0.4064)
		(layer "F.Cu")
		(net "GND")
	)
	(segment
		(start 139.674854 -65.315338)
		(end 140.246354 -65.315338)
		(width 0.254)
		(layer "F.Cu")
		(net "GND")
	)
	(segment
		(start 370.28501 -3.446018)
		(end 370.28501 -4.389882)
		(width 0.4572)
		(layer "F.Cu")
		(net "GND")
	)
	(segment
		(start 204.900276 -5.822442)
		(end 204.899768 -5.822442)
		(width 0.4064)
		(layer "F.Cu")
		(net "GND")
	)
	(segment
		(start 117.249448 -15.423642)
		(end 117.249448 -13.541756)
		(width 0.4064)
		(layer "F.Cu")
		(net "GND")
	)
	(segment
		(start 387.73735 -97.605596)
		(end 387.24205 -97.83572)
		(width 0.254)
		(layer "F.Cu")
		(net "GND")
	)
	(segment
		(start 208.299812 -13.541756)
		(end 208.122012 -13.363956)
		(width 0.4064)
		(layer "F.Cu")
		(net "GND")
	)
	(segment
		(start 141.899386 -133.0706)
		(end 141.899386 -134.861046)
		(width 0.4064)
		(layer "F.Cu")
		(net "GND")
	)
	(segment
		(start 204.049884 -18.757646)
		(end 204.049884 -20.023582)
		(width 0.4064)
		(layer "F.Cu")
		(net "GND")
	)
	(segment
		(start 375.084848 -3.445764)
		(end 375.085102 -3.446018)
		(width 0.4572)
		(layer "F.Cu")
		(net "GND")
	)
	(segment
		(start 389.306054 -124.206)
		(end 389.71855 -123.821444)
		(width 0.254)
		(layer "F.Cu")
		(net "GND")
	)
	(segment
		(start 129.999486 -156.87294)
		(end 129.999486 -155.612846)
		(width 0.4064)
		(layer "F.Cu")
		(net "GND")
	)
	(segment
		(start 89.211912 -98.681286)
		(end 89.498678 -98.18624)
		(width 0.254)
		(layer "F.Cu")
		(net "GND")
	)
	(segment
		(start 125.080268 -59.866784)
		(end 125.651768 -59.866784)
		(width 0.254)
		(layer "F.Cu")
		(net "GND")
	)
	(segment
		(start 131.699508 -147.27174)
		(end 131.699508 -146.011646)
		(width 0.4064)
		(layer "F.Cu")
		(net "GND")
	)
	(segment
		(start 115.64366 -50.324258)
		(end 115.64366 -51.44008)
		(width 0.2286)
		(layer "F.Cu")
		(net "GND")
	)
	(segment
		(start 452.477378 -7.789672)
		(end 452.477378 -7.060184)
		(width 0.254)
		(layer "F.Cu")
		(net "GND")
	)
	(segment
		(start 215.949784 -13.427456)
		(end 215.860884 -13.338556)
		(width 0.4064)
		(layer "F.Cu")
		(net "GND")
	)
	(segment
		(start 36.499546 -4.808982)
		(end 36.03752 -4.346956)
		(width 0.4064)
		(layer "F.Cu")
		(net "GND")
	)
	(segment
		(start 304.388266 -65.028318)
		(end 304.675286 -65.315338)
		(width 0.254)
		(layer "F.Cu")
		(net "GND")
	)
	(segment
		(start 117.071648 -17.2466)
		(end 117.015768 -17.19072)
		(width 0.3556)
		(layer "F.Cu")
		(net "GND")
	)
	(segment
		(start 52.448968 2.8448)
		(end 52.448968 2.667)
		(width 0.3048)
		(layer "F.Cu")
		(net "GND")
	)
	(segment
		(start 238.899954 -5.822442)
		(end 238.8997 -5.822696)
		(width 0.4064)
		(layer "F.Cu")
		(net "GND")
	)
	(segment
		(start 84.060792 -64.010286)
		(end 83.489292 -64.010286)
		(width 0.254)
		(layer "F.Cu")
		(net "GND")
	)
	(segment
		(start 122.504708 -59.371484)
		(end 121.933208 -59.371484)
		(width 0.254)
		(layer "F.Cu")
		(net "GND")
	)
	(segment
		(start 31.702756 -78.243176)
		(end 31.318454 -78.243176)
		(width 0.254)
		(layer "F.Cu")
		(net "GND")
	)
	(segment
		(start 247.344184 -52.12334)
		(end 247.347232 -52.120292)
		(width 0.2032)
		(layer "F.Cu")
		(net "GND")
	)
	(segment
		(start 67.949572 -152.273)
		(end 67.949572 -152.278842)
		(width 0.4064)
		(layer "F.Cu")
		(net "GND")
	)
	(segment
		(start 131.699508 -0.821182)
		(end 131.699508 0.444754)
		(width 0.4064)
		(layer "F.Cu")
		(net "GND")
	)
	(segment
		(start 282.354274 -60.362338)
		(end 281.782774 -60.362338)
		(width 0.254)
		(layer "F.Cu")
		(net "GND")
	)
	(segment
		(start 117.015768 -134.036054)
		(end 117.015768 -134.84352)
		(width 0.3556)
		(layer "F.Cu")
		(net "GND")
	)
	(segment
		(start 291.79774 -75.716384)
		(end 292.36924 -75.716384)
		(width 0.254)
		(layer "F.Cu")
		(net "GND")
	)
	(segment
		(start 457.400914 -113.776506)
		(end 457.399898 -113.777522)
		(width 0.4064)
		(layer "F.Cu")
		(net "GND")
	)
	(segment
		(start 457.350114 -62.00267)
		(end 457.350114 -63.170054)
		(width 0.381)
		(layer "F.Cu")
		(net "GND")
	)
	(segment
		(start 116.495322 -89.584784)
		(end 117.066822 -89.584784)
		(width 0.254)
		(layer "F.Cu")
		(net "GND")
	)
	(segment
		(start 209.092546 -18.795746)
		(end 209.14995 -18.85315)
		(width 0.4064)
		(layer "F.Cu")
		(net "GND")
	)
	(segment
		(start 40.749474 -148.771356)
		(end 40.749474 -147.27174)
		(width 0.4064)
		(layer "F.Cu")
		(net "GND")
	)
	(segment
		(start 457.47178 -29.21)
		(end 457.8096 -29.21)
		(width 0.254)
		(layer "F.Cu")
		(net "GND")
	)
	(segment
		(start 215.0999 -9.143746)
		(end 215.0999 -10.422382)
		(width 0.4064)
		(layer "F.Cu")
		(net "GND")
	)
	(segment
		(start 230.399844 -147.27174)
		(end 230.400352 -147.27174)
		(width 0.4064)
		(layer "F.Cu")
		(net "GND")
	)
	(segment
		(start 38.199314 -7.607046)
		(end 38.199314 -6.001766)
		(width 0.4064)
		(layer "F.Cu")
		(net "GND")
	)
	(segment
		(start 423.090086 -34.534602)
		(end 423.09034 -34.534602)
		(width 0.254)
		(layer "F.Cu")
		(net "GND")
	)
	(segment
		(start 0 -134.3152)
		(end 0 -134.665212)
		(width 0.4064)
		(layer "F.Cu")
		(net "GND")
	)
	(segment
		(start 380.30785 -105.332276)
		(end 380.80315 -105.5624)
		(width 0.254)
		(layer "F.Cu")
		(net "GND")
	)
	(segment
		(start 179.61102 -78.7781)
		(end 179.61102 -77.63002)
		(width 0.254)
		(layer "F.Cu")
		(net "GND")
	)
	(segment
		(start 134.249414 -152.273)
		(end 134.249414 -153.965402)
		(width 0.4064)
		(layer "F.Cu")
		(net "GND")
	)
	(segment
		(start 237.142528 -155.600146)
		(end 237.142528 -155.612846)
		(width 0.3556)
		(layer "F.Cu")
		(net "GND")
	)
	(segment
		(start 317.949834 -133.076442)
		(end 317.949834 -134.340346)
		(width 0.4064)
		(layer "F.Cu")
		(net "GND")
	)
	(segment
		(start 287.50514 -61.352938)
		(end 286.93364 -61.352938)
		(width 0.254)
		(layer "F.Cu")
		(net "GND")
	)
	(segment
		(start 50.949352 -142.6718)
		(end 50.949352 -144.364202)
		(width 0.4064)
		(layer "F.Cu")
		(net "GND")
	)
	(segment
		(start 392.303 -71.9455)
		(end 392.303 -72.705468)
		(width 0.508)
		(layer "F.Cu")
		(net "GND")
	)
	(segment
		(start 86.636352 -84.31784)
		(end 86.064852 -84.31784)
		(width 0.254)
		(layer "F.Cu")
		(net "GND")
	)
	(segment
		(start 289.801808 -7.607046)
		(end 289.899852 -7.509002)
		(width 0.4064)
		(layer "F.Cu")
		(net "GND")
	)
	(segment
		(start 300.949868 -133.821678)
		(end 300.736 -134.035546)
		(width 0.3556)
		(layer "F.Cu")
		(net "GND")
	)
	(segment
		(start 79.768192 -53.60924)
		(end 79.196692 -53.60924)
		(width 0.254)
		(layer "F.Cu")
		(net "GND")
	)
	(segment
		(start 432.438302 -20.29079)
		(end 431.785014 -20.944078)
		(width 0.254)
		(layer "F.Cu")
		(net "GND")
	)
	(segment
		(start 411.89021 -30.53461)
		(end 411.89021 -30.534356)
		(width 0.254)
		(layer "F.Cu")
		(net "GND")
	)
	(segment
		(start 32.249364 -13.427456)
		(end 32.160464 -13.338556)
		(width 0.4064)
		(layer "F.Cu")
		(net "GND")
	)
	(segment
		(start 242.193318 -83.822286)
		(end 241.621818 -83.822286)
		(width 0.254)
		(layer "F.Cu")
		(net "GND")
	)
	(segment
		(start 322.077588 -13.492988)
		(end 321.693032 -13.108432)
		(width 0.4064)
		(layer "F.Cu")
		(net "GND")
	)
	(segment
		(start 236.183678 -81.34604)
		(end 235.612178 -81.34604)
		(width 0.254)
		(layer "F.Cu")
		(net "GND")
	)
	(segment
		(start 398.861534 -92.07119)
		(end 398.950688 -91.982036)
		(width 0.254)
		(layer "F.Cu")
		(net "GND")
	)
	(segment
		(start 38.199568 3.778758)
		(end 38.199568 3.599688)
		(width 0.4064)
		(layer "F.Cu")
		(net "GND")
	)
	(segment
		(start 296.948606 -82.650584)
		(end 297.520106 -82.650584)
		(width 0.254)
		(layer "F.Cu")
		(net "GND")
	)
	(segment
		(start 55.199534 -152.273)
		(end 55.199534 -152.278842)
		(width 0.4064)
		(layer "F.Cu")
		(net "GND")
	)
	(segment
		(start 32.249364 2.092198)
		(end 32.15132 1.994154)
		(width 0.4064)
		(layer "F.Cu")
		(net "GND")
	)
	(segment
		(start 56.899556 -6.001512)
		(end 56.899302 -6.001766)
		(width 0.4064)
		(layer "F.Cu")
		(net "GND")
	)
	(segment
		(start 294.373554 -52.437284)
		(end 294.9448 -52.437284)
		(width 0.254)
		(layer "F.Cu")
		(net "GND")
	)
	(segment
		(start 138.816334 -51.941984)
		(end 139.311888 -52.437538)
		(width 0.254)
		(layer "F.Cu")
		(net "GND")
	)
	(segment
		(start 315.399928 -9.156446)
		(end 315.399928 -10.422382)
		(width 0.4064)
		(layer "F.Cu")
		(net "GND")
	)
	(segment
		(start 124.89942 -17.110202)
		(end 124.801376 -17.208246)
		(width 0.4064)
		(layer "F.Cu")
		(net "GND")
	)
	(segment
		(start 282.0162 -16.383254)
		(end 282.24988 -16.149574)
		(width 0.3556)
		(layer "F.Cu")
		(net "GND")
	)
	(segment
		(start 387.73735 -119.29872)
		(end 388.23265 -119.528844)
		(width 0.254)
		(layer "F.Cu")
		(net "GND")
	)
	(segment
		(start 461.340962 -51.308508)
		(end 461.333342 -51.300888)
		(width 0.508)
		(layer "F.Cu")
		(net "GND")
	)
	(segment
		(start 475.238826 -148.109686)
		(end 475.238826 -148.14423)
		(width 0.254)
		(layer "F.Cu")
		(net "GND")
	)
	(segment
		(start 121.646188 -63.829184)
		(end 121.074688 -63.829184)
		(width 0.254)
		(layer "F.Cu")
		(net "GND")
	)
	(segment
		(start 34.799524 -9.426702)
		(end 34.74212 -9.369298)
		(width 0.4064)
		(layer "F.Cu")
		(net "GND")
	)
	(segment
		(start 449.950586 -13.38453)
		(end 449.520056 -12.954)
		(width 0.254)
		(layer "F.Cu")
		(net "GND")
	)
	(segment
		(start 300.100492 -147.27174)
		(end 300.099984 -147.27174)
		(width 0.4064)
		(layer "F.Cu")
		(net "GND")
	)
	(segment
		(start 414.34639 -121.740422)
		(end 413.255968 -120.65)
		(width 0.254)
		(layer "F.Cu")
		(net "GND")
	)
	(segment
		(start 259.36321 -53.113686)
		(end 260.50875 -53.113686)
		(width 0.254)
		(layer "F.Cu")
		(net "GND")
	)
	(segment
		(start 280.549858 -14.2113)
		(end 280.460958 -14.1224)
		(width 0.4064)
		(layer "F.Cu")
		(net "GND")
	)
	(segment
		(start 87.494872 -67.972686)
		(end 86.923372 -67.972686)
		(width 0.254)
		(layer "F.Cu")
		(net "GND")
	)
	(segment
		(start 227.850446 -147.27174)
		(end 227.849938 -147.27174)
		(width 0.3556)
		(layer "F.Cu")
		(net "GND")
	)
	(segment
		(start 464.269582 -37.3761)
		(end 464.282282 -37.3888)
		(width 0.4064)
		(layer "F.Cu")
		(net "GND")
	)
	(segment
		(start 458.177392 -38.591998)
		(end 457.546964 -38.591998)
		(width 0.254)
		(layer "F.Cu")
		(net "GND")
	)
	(segment
		(start 412.991554 -87.909146)
		(end 413.84474 -87.909146)
		(width 0.3048)
		(layer "F.Cu")
		(net "GND")
	)
	(segment
		(start 387.73735 -121.01576)
		(end 388.23265 -121.245884)
		(width 0.254)
		(layer "F.Cu")
		(net "GND")
	)
	(segment
		(start 217.649806 -3.940556)
		(end 217.472006 -3.762756)
		(width 0.4064)
		(layer "F.Cu")
		(net "GND")
	)
	(segment
		(start 132.549392 -133.0706)
		(end 132.549392 -134.861046)
		(width 0.4064)
		(layer "F.Cu")
		(net "GND")
	)
	(segment
		(start 119.070882 -60.362338)
		(end 118.499382 -60.362338)
		(width 0.254)
		(layer "F.Cu")
		(net "GND")
	)
	(segment
		(start 36.499292 -142.677896)
		(end 36.499292 -143.492474)
		(width 0.4064)
		(layer "F.Cu")
		(net "GND")
	)
	(segment
		(start 50.949352 -134.763002)
		(end 50.851308 -134.861046)
		(width 0.4064)
		(layer "F.Cu")
		(net "GND")
	)
	(segment
		(start 199.800464 -20.023582)
		(end 199.799956 -20.023582)
		(width 0.4064)
		(layer "F.Cu")
		(net "GND")
	)
	(segment
		(start 66.24955 -152.273)
		(end 66.24955 -152.457912)
		(width 0.4064)
		(layer "F.Cu")
		(net "GND")
	)
	(segment
		(start 458.932534 -50.4444)
		(end 458.933296 -50.562002)
		(width 0.508)
		(layer "F.Cu")
		(net "GND")
	)
	(segment
		(start 399.219928 -123.3551)
		(end 399.209768 -123.414536)
		(width 0.254)
		(layer "F.Cu")
		(net "GND")
	)
	(segment
		(start 42.424096 -155.612846)
		(end 42.411396 -155.612846)
		(width 0.4064)
		(layer "F.Cu")
		(net "GND")
	)
	(segment
		(start 82.343752 -60.047886)
		(end 81.772252 -60.047886)
		(width 0.254)
		(layer "F.Cu")
		(net "GND")
	)
	(segment
		(start 210.849718 -5.822696)
		(end 210.849718 -6.637274)
		(width 0.4064)
		(layer "F.Cu")
		(net "GND")
	)
	(segment
		(start 301.241206 -53.427884)
		(end 301.812706 -53.427884)
		(width 0.254)
		(layer "F.Cu")
		(net "GND")
	)
	(segment
		(start 297.549824 -5.822442)
		(end 297.549824 -3.762756)
		(width 0.4064)
		(layer "F.Cu")
		(net "GND")
	)
	(segment
		(start 500.579898 -49.91989)
		(end 500.579898 -50.306986)
		(width 0.254)
		(layer "F.Cu")
		(net "GND")
	)
	(segment
		(start 216.799922 -147.27174)
		(end 216.799922 -146.011646)
		(width 0.4064)
		(layer "F.Cu")
		(net "GND")
	)
	(segment
		(start 46.699424 -147.27174)
		(end 46.699424 -148.771356)
		(width 0.4064)
		(layer "F.Cu")
		(net "GND")
	)
	(segment
		(start 243.051838 -76.39304)
		(end 242.480338 -76.39304)
		(width 0.254)
		(layer "F.Cu")
		(net "GND")
	)
	(segment
		(start 278.061674 -101.472746)
		(end 278.061674 -101.471984)
		(width 0.1524)
		(layer "F.Cu")
		(net "GND")
	)
	(segment
		(start 377.33605 -109.855)
		(end 376.555 -110.3884)
		(width 0.254)
		(layer "F.Cu")
		(net "GND")
	)
	(segment
		(start 237.900718 -101.15804)
		(end 237.329218 -101.15804)
		(width 0.254)
		(layer "F.Cu")
		(net "GND")
	)
	(segment
		(start 292.392608 -136.410446)
		(end 292.392608 -136.397746)
		(width 0.3556)
		(layer "F.Cu")
		(net "GND")
	)
	(segment
		(start 8.026146 3.786124)
		(end 7.7724 3.532378)
		(width 0.2032)
		(layer "F.Cu")
		(net "GND")
	)
	(segment
		(start 73.758806 -87.784686)
		(end 73.187306 -87.784686)
		(width 0.254)
		(layer "F.Cu")
		(net "GND")
	)
	(segment
		(start 20.5232 -98.7806)
		(end 20.0914 -99.2124)
		(width 0.254)
		(layer "F.Cu")
		(net "GND")
	)
	(segment
		(start 295.23182 -102.462584)
		(end 295.80332 -102.462584)
		(width 0.3048)
		(layer "F.Cu")
		(net "GND")
	)
	(segment
		(start -4.064 -135.1534)
		(end -4.3942 -134.8232)
		(width 0.254)
		(layer "F.Cu")
		(net "GND")
	)
	(segment
		(start 351.265236 4.434332)
		(end 351.937574 4.434332)
		(width 0.254)
		(layer "F.Cu")
		(net "GND")
	)
	(segment
		(start 312.849768 -133.076442)
		(end 312.849768 -133.891274)
		(width 0.4064)
		(layer "F.Cu")
		(net "GND")
	)
	(segment
		(start 474.56725 -43.6626)
		(end 474.51645 -43.7134)
		(width 0.254)
		(layer "F.Cu")
		(net "GND")
	)
	(segment
		(start 442.922406 -31.03245)
		(end 442.921898 -31.03245)
		(width 0.3048)
		(layer "F.Cu")
		(net "GND")
	)
	(segment
		(start 290.750498 -0.821182)
		(end 290.74999 -0.821182)
		(width 0.4064)
		(layer "F.Cu")
		(net "GND")
	)
	(segment
		(start 55.19928 -5.822696)
		(end 55.19928 -6.637274)
		(width 0.4064)
		(layer "F.Cu")
		(net "GND")
	)
	(segment
		(start 240.600484 -152.273)
		(end 240.599976 -152.278842)
		(width 0.4064)
		(layer "F.Cu")
		(net "GND")
	)
	(segment
		(start 355.656388 -141.243558)
		(end 356.051358 -141.638528)
		(width 0.254)
		(layer "F.Cu")
		(net "GND")
	)
	(segment
		(start 76.449428 0.444754)
		(end 76.449428 -0.821182)
		(width 0.4064)
		(layer "F.Cu")
		(net "GND")
	)
	(segment
		(start 263.65581 -60.54344)
		(end 263.08431 -60.54344)
		(width 0.254)
		(layer "F.Cu")
		(net "GND")
	)
	(segment
		(start 78.14945 -9.133078)
		(end 78.14945 -10.422382)
		(width 0.4064)
		(layer "F.Cu")
		(net "GND")
	)
	(segment
		(start 109.627416 -91.565984)
		(end 110.198916 -91.565984)
		(width 0.1016)
		(layer "F.Cu")
		(net "GND")
	)
	(segment
		(start 295.23182 -81.659984)
		(end 295.80332 -81.659984)
		(width 0.254)
		(layer "F.Cu")
		(net "GND")
	)
	(segment
		(start 296.69994 -10.422382)
		(end 296.69994 -9.156446)
		(width 0.4064)
		(layer "F.Cu")
		(net "GND")
	)
	(segment
		(start 213.399878 -0.821182)
		(end 213.399878 -2.314956)
		(width 0.4064)
		(layer "F.Cu")
		(net "GND")
	)
	(segment
		(start 317.09995 -18.757646)
		(end 317.09995 -20.023582)
		(width 0.4064)
		(layer "F.Cu")
		(net "GND")
	)
	(segment
		(start 428.63008 -36.07435)
		(end 429.312578 -36.07435)
		(width 0.254)
		(layer "F.Cu")
		(net "GND")
	)
	(segment
		(start 80.626712 -92.737686)
		(end 80.055212 -92.737686)
		(width 0.254)
		(layer "F.Cu")
		(net "GND")
	)
	(segment
		(start 76.334366 -92.24264)
		(end 75.762866 -92.24264)
		(width 0.254)
		(layer "F.Cu")
		(net "GND")
	)
	(segment
		(start 248.202704 -93.23324)
		(end 247.631204 -93.23324)
		(width 0.254)
		(layer "F.Cu")
		(net "GND")
	)
	(segment
		(start 169.926 -73.7108)
		(end 169.8244 -73.8124)
		(width 0.254)
		(layer "F.Cu")
		(net "GND")
	)
	(segment
		(start 297.807126 -72.249538)
		(end 298.378626 -72.249538)
		(width 0.254)
		(layer "F.Cu")
		(net "GND")
	)
	(segment
		(start 33.949386 -5.822442)
		(end 33.949386 -3.940556)
		(width 0.4064)
		(layer "F.Cu")
		(net "GND")
	)
	(segment
		(start 135.949436 -133.0706)
		(end 135.949436 -133.821678)
		(width 0.3556)
		(layer "F.Cu")
		(net "GND")
	)
	(segment
		(start 246.485664 -55.59044)
		(end 245.914164 -55.59044)
		(width 0.254)
		(layer "F.Cu")
		(net "GND")
	)
	(segment
		(start 69.466206 -97.19564)
		(end 68.894706 -97.19564)
		(width 0.254)
		(layer "F.Cu")
		(net "GND")
	)
	(segment
		(start 113.849404 -136.379966)
		(end 113.901728 -136.327642)
		(width 0.4064)
		(layer "F.Cu")
		(net "GND")
	)
	(segment
		(start 415.2392 -16.383)
		(end 415.9758 -17.1196)
		(width 0.254)
		(layer "F.Cu")
		(net "GND")
	)
	(segment
		(start 370.284756 -3.420364)
		(end 370.284756 -3.445764)
		(width 0.4572)
		(layer "F.Cu")
		(net "GND")
	)
	(segment
		(start 45.84954 -152.278842)
		(end 45.849286 -152.279096)
		(width 0.4064)
		(layer "F.Cu")
		(net "GND")
	)
	(segment
		(start 242.193318 -49.991518)
		(end 241.699796 -49.497996)
		(width 0.254)
		(layer "F.Cu")
		(net "GND")
	)
	(segment
		(start 242.300506 -7.606284)
		(end 242.299744 -7.607046)
		(width 0.4064)
		(layer "F.Cu")
		(net "GND")
	)
	(segment
		(start 475.2213 -138.557)
		(end 475.2213 -137.8331)
		(width 0.254)
		(layer "F.Cu")
		(net "GND")
	)
	(segment
		(start 465.5185 -146.2405)
		(end 465.4804 -146.2024)
		(width 0.4064)
		(layer "F.Cu")
		(net "GND")
	)
	(segment
		(start 348.0054 -20.193)
		(end 348.0054 -20.955)
		(width 0.254)
		(layer "F.Cu")
		(net "GND")
	)
	(segment
		(start 287.21812 -69.772784)
		(end 286.64662 -69.772784)
		(width 0.254)
		(layer "F.Cu")
		(net "GND")
	)
	(segment
		(start 281.446732 -70.956424)
		(end 281.141424 -71.261732)
		(width 0.254)
		(layer "F.Cu")
		(net "GND")
	)
	(segment
		(start 386.74675 -116.953284)
		(end 386.25145 -116.72316)
		(width 0.254)
		(layer "F.Cu")
		(net "GND")
	)
	(segment
		(start 72.041766 -82.83194)
		(end 71.470266 -82.83194)
		(width 0.254)
		(layer "F.Cu")
		(net "GND")
	)
	(segment
		(start 401.295108 -116.854986)
		(end 400.465036 -116.854986)
		(width 0.254)
		(layer "F.Cu")
		(net "GND")
	)
	(segment
		(start 475.7801 -142.8623)
		(end 476.20555 -143.28775)
		(width 0.254)
		(layer "F.Cu")
		(net "GND")
	)
	(segment
		(start 48.399446 -139.170156)
		(end 48.399446 -137.67054)
		(width 0.4064)
		(layer "F.Cu")
		(net "GND")
	)
	(segment
		(start 111.344202 -52.932838)
		(end 111.631222 -53.427884)
		(width 0.254)
		(layer "F.Cu")
		(net "GND")
	)
	(segment
		(start 376.27814 -126.182628)
		(end 376.27814 -126.49454)
		(width 0.254)
		(layer "F.Cu")
		(net "GND")
	)
	(segment
		(start 307.250846 -89.584784)
		(end 307.898546 -89.584784)
		(width 0.254)
		(layer "F.Cu")
		(net "GND")
	)
	(segment
		(start 244.3607 -3.3528)
		(end 243.2304 -3.3528)
		(width 0.4064)
		(layer "F.Cu")
		(net "GND")
	)
	(segment
		(start 146.149568 -2.253488)
		(end 146.149568 -0.821182)
		(width 0.4064)
		(layer "F.Cu")
		(net "GND")
	)
	(segment
		(start 203.199746 -17.208246)
		(end 203.199746 -15.602966)
		(width 0.4064)
		(layer "F.Cu")
		(net "GND")
	)
	(segment
		(start 280.549858 -134.763002)
		(end 280.451814 -134.861046)
		(width 0.4064)
		(layer "F.Cu")
		(net "GND")
	)
	(segment
		(start 303.529746 -80.174338)
		(end 302.958246 -80.174338)
		(width 0.254)
		(layer "F.Cu")
		(net "GND")
	)
	(segment
		(start 237.042198 -59.057286)
		(end 236.470698 -59.057286)
		(width 0.254)
		(layer "F.Cu")
		(net "GND")
	)
	(segment
		(start 14.830806 3.507232)
		(end 15.264384 3.507232)
		(width 0.254)
		(layer "F.Cu")
		(net "GND")
	)
	(segment
		(start 250.778264 -99.67214)
		(end 251.636784 -99.17684)
		(width 0.254)
		(layer "F.Cu")
		(net "GND")
	)
	(segment
		(start 397.270986 -7.789672)
		(end 397.270986 -9.44372)
		(width 0.254)
		(layer "F.Cu")
		(net "GND")
	)
	(segment
		(start 196.399912 -10.422382)
		(end 196.40042 -10.422382)
		(width 0.4064)
		(layer "F.Cu")
		(net "GND")
	)
	(segment
		(start 113.205768 -150.0886)
		(end 112.926368 -149.8092)
		(width 0.4064)
		(layer "F.Cu")
		(net "GND")
	)
	(segment
		(start 125.938788 -57.390538)
		(end 126.510288 -57.390538)
		(width 0.254)
		(layer "F.Cu")
		(net "GND")
	)
	(segment
		(start 481.287836 -35.378644)
		(end 481.271834 -35.362642)
		(width 0.254)
		(layer "F.Cu")
		(net "GND")
	)
	(segment
		(start 71.117968 -143.637)
		(end 71.117968 -144.447006)
		(width 0.3556)
		(layer "F.Cu")
		(net "GND")
	)
	(segment
		(start 497.949982 -59.804554)
		(end 497.949982 -60.184792)
		(width 0.254)
		(layer "F.Cu")
		(net "GND")
	)
	(segment
		(start 119.799354 -5.822442)
		(end 119.7991 -5.822696)
		(width 0.4064)
		(layer "F.Cu")
		(net "GND")
	)
	(segment
		(start 497.652294 -127.210566)
		(end 497.1034 -127.75946)
		(width 0.508)
		(layer "F.Cu")
		(net "GND")
	)
	(segment
		(start 233.608118 -98.681286)
		(end 233.036618 -98.681286)
		(width 0.254)
		(layer "F.Cu")
		(net "GND")
	)
	(segment
		(start 32.094932 -54.227984)
		(end 32.094932 -54.644544)
		(width 0.254)
		(layer "F.Cu")
		(net "GND")
	)
	(segment
		(start 259.36321 -56.085486)
		(end 258.79171 -56.085486)
		(width 0.254)
		(layer "F.Cu")
		(net "GND")
	)
	(segment
		(start 217.4494 -143.7894)
		(end 217.4494 -144.477994)
		(width 0.3556)
		(layer "F.Cu")
		(net "GND")
	)
	(segment
		(start 43.29938 -16.159734)
		(end 43.29938 -15.423642)
		(width 0.3556)
		(layer "F.Cu")
		(net "GND")
	)
	(segment
		(start 388.72795 -98.69424)
		(end 389.22325 -98.464116)
		(width 0.254)
		(layer "F.Cu")
		(net "GND")
	)
	(segment
		(start 278.849836 -141.265148)
		(end 278.849836 -142.6718)
		(width 0.508)
		(layer "F.Cu")
		(net "GND")
	)
	(segment
		(start 235.46181 -2.314956)
		(end 235.49991 -2.276856)
		(width 0.4064)
		(layer "F.Cu")
		(net "GND")
	)
	(segment
		(start 368.255296 -25.489662)
		(end 367.329466 -25.489662)
		(width 0.254)
		(layer "F.Cu")
		(net "GND")
	)
	(segment
		(start 229.550468 3.778758)
		(end 229.550468 2.964688)
		(width 0.4064)
		(layer "F.Cu")
		(net "GND")
	)
	(segment
		(start 211.700364 -10.422382)
		(end 211.699856 -10.422382)
		(width 0.4064)
		(layer "F.Cu")
		(net "GND")
	)
	(segment
		(start 282.24988 -15.423642)
		(end 282.24988 -13.541756)
		(width 0.4064)
		(layer "F.Cu")
		(net "GND")
	)
	(segment
		(start 215.949784 -134.763002)
		(end 215.85174 -134.861046)
		(width 0.4064)
		(layer "F.Cu")
		(net "GND")
	)
	(segment
		(start 272.339308 -63.829184)
		(end 272.910808 -63.829184)
		(width 0.254)
		(layer "F.Cu")
		(net "GND")
	)
	(segment
		(start 445.350138 -60.835286)
		(end 445.148716 -60.633864)
		(width 0.381)
		(layer "F.Cu")
		(net "GND")
	)
	(segment
		(start 56.899556 3.778758)
		(end 56.899556 3.599688)
		(width 0.4064)
		(layer "F.Cu")
		(net "GND")
	)
	(segment
		(start 308.59984 -15.423642)
		(end 308.59984 -17.110202)
		(width 0.4064)
		(layer "F.Cu")
		(net "GND")
	)
	(segment
		(start 244.768624 -68.46824)
		(end 244.197124 -68.46824)
		(width 0.254)
		(layer "F.Cu")
		(net "GND")
	)
	(segment
		(start 222.75038 -20.023582)
		(end 222.749872 -20.023582)
		(width 0.4064)
		(layer "F.Cu")
		(net "GND")
	)
	(segment
		(start 237.900718 -99.17684)
		(end 237.329218 -99.17684)
		(width 0.254)
		(layer "F.Cu")
		(net "GND")
	)
	(segment
		(start 225.300286 -142.6718)
		(end 225.299778 -142.677642)
		(width 0.4064)
		(layer "F.Cu")
		(net "GND")
	)
	(segment
		(start 92.645738 -65.000886)
		(end 92.074238 -65.000886)
		(width 0.254)
		(layer "F.Cu")
		(net "GND")
	)
	(segment
		(start 413.490156 -29.734764)
		(end 413.49041 -29.734764)
		(width 0.254)
		(layer "F.Cu")
		(net "GND")
	)
	(segment
		(start 103.806244 -95.21444)
		(end 104.415844 -95.21444)
		(width 0.254)
		(layer "F.Cu")
		(net "GND")
	)
	(segment
		(start 297.550332 -142.6718)
		(end 297.549824 -142.677642)
		(width 0.4064)
		(layer "F.Cu")
		(net "GND")
	)
	(segment
		(start 383.11328 -103.51643)
		(end 383.11328 -103.15321)
		(width 0.254)
		(layer "F.Cu")
		(net "GND")
	)
	(segment
		(start 278.920194 -99.986338)
		(end 279.491694 -99.986338)
		(width 0.254)
		(layer "F.Cu")
		(net "GND")
	)
	(segment
		(start 144.449546 -2.276856)
		(end 144.411446 -2.314956)
		(width 0.4064)
		(layer "F.Cu")
		(net "GND")
	)
	(segment
		(start 76.699364 -49.497996)
		(end 76.618592 -49.489614)
		(width 0.254)
		(layer "F.Cu")
		(net "GND")
	)
	(segment
		(start 152.099518 -140.000482)
		(end 152.0952 -140.0048)
		(width 0.4064)
		(layer "F.Cu")
		(net "GND")
	)
	(segment
		(start 125.749558 -20.023582)
		(end 125.749558 -21.479256)
		(width 0.4064)
		(layer "F.Cu")
		(net "GND")
	)
	(segment
		(start 137.957814 -78.193138)
		(end 138.529314 -78.193138)
		(width 0.254)
		(layer "F.Cu")
		(net "GND")
	)
	(segment
		(start 311.092596 -11.912092)
		(end 311.15 -11.854688)
		(width 0.4064)
		(layer "F.Cu")
		(net "GND")
	)
	(segment
		(start 278.850344 -10.422382)
		(end 278.849836 -10.422382)
		(width 0.4064)
		(layer "F.Cu")
		(net "GND")
	)
	(segment
		(start 283.099764 0.38735)
		(end 283.04236 0.444754)
		(width 0.3556)
		(layer "F.Cu")
		(net "GND")
	)
	(segment
		(start 434.086 -32.3088)
		(end 433.7685 -32.6263)
		(width 0.254)
		(layer "F.Cu")
		(net "GND")
	)
	(segment
		(start 385.26085 -118.4402)
		(end 385.752848 -118.6688)
		(width 0.254)
		(layer "F.Cu")
		(net "GND")
	)
	(segment
		(start 199.736456 -4.2926)
		(end 200.983596 -4.2926)
		(width 0.254)
		(layer "F.Cu")
		(net "GND")
	)
	(segment
		(start 2.3114 -5.675376)
		(end 2.3114 -5.9944)
		(width 0.4064)
		(layer "F.Cu")
		(net "GND")
	)
	(segment
		(start 289.899852 -13.731748)
		(end 289.899852 -15.423642)
		(width 0.4064)
		(layer "F.Cu")
		(net "GND")
	)
	(segment
		(start 450.141086 -45.92574)
		(end 450.141086 -47.481998)
		(width 0.4064)
		(layer "F.Cu")
		(net "GND")
	)
	(segment
		(start 175.27016 -104.20096)
		(end 174.631858 -103.562658)
		(width 0.254)
		(layer "F.Cu")
		(net "GND")
	)
	(segment
		(start 419.905942 -80.913986)
		(end 419.859714 -80.960214)
		(width 0.254)
		(layer "F.Cu")
		(net "GND")
	)
	(segment
		(start 175.0822 -146.47164)
		(end 175.0822 -146.6342)
		(width 0.254)
		(layer "F.Cu")
		(net "GND")
	)
	(segment
		(start 280.550366 -133.0706)
		(end 280.549858 -133.076442)
		(width 0.4064)
		(layer "F.Cu")
		(net "GND")
	)
	(segment
		(start 432.4096 -3.366008)
		(end 432.4096 -3.6068)
		(width 0.254)
		(layer "F.Cu")
		(net "GND")
	)
	(segment
		(start 267.948156 -88.775286)
		(end 267.948156 -88.138)
		(width 0.254)
		(layer "F.Cu")
		(net "GND")
	)
	(segment
		(start 45.849286 -6.637274)
		(end 45.390816 -7.095744)
		(width 0.4064)
		(layer "F.Cu")
		(net "GND")
	)
	(segment
		(start 56.899556 3.599688)
		(end 56.899302 3.599434)
		(width 0.4064)
		(layer "F.Cu")
		(net "GND")
	)
	(segment
		(start 73.437496 -4.346956)
		(end 73.899522 -4.808982)
		(width 0.4064)
		(layer "F.Cu")
		(net "GND")
	)
	(segment
		(start 310.299862 -3.940556)
		(end 310.299862 -5.822442)
		(width 0.4064)
		(layer "F.Cu")
		(net "GND")
	)
	(segment
		(start 216.799922 -0.821182)
		(end 216.799922 -2.276856)
		(width 0.4064)
		(layer "F.Cu")
		(net "GND")
	)
	(segment
		(start 30.3276 -68.9864)
		(end 30.607 -68.9864)
		(width 0.381)
		(layer "F.Cu")
		(net "GND")
	)
	(segment
		(start 312.102754 -32.492696)
		(end 312.357516 -32.747458)
		(width 0.4064)
		(layer "F.Cu")
		(net "GND")
	)
	(segment
		(start 237.142528 -18.744946)
		(end 237.142528 -18.757646)
		(width 0.3556)
		(layer "F.Cu")
		(net "GND")
	)
	(segment
		(start 289.22218 -54.418738)
		(end 288.65068 -54.418738)
		(width 0.254)
		(layer "F.Cu")
		(net "GND")
	)
	(segment
		(start 120.649492 -156.87294)
		(end 120.649492 -155.612846)
		(width 0.4064)
		(layer "F.Cu")
		(net "GND")
	)
	(segment
		(start 211.699856 -9.156446)
		(end 211.699856 -10.422382)
		(width 0.4064)
		(layer "F.Cu")
		(net "GND")
	)
	(segment
		(start 284.929834 -99.490784)
		(end 285.501334 -99.490784)
		(width 0.254)
		(layer "F.Cu")
		(net "GND")
	)
	(segment
		(start 123.363228 -92.556584)
		(end 123.934728 -92.556584)
		(width 0.3048)
		(layer "F.Cu")
		(net "GND")
	)
	(segment
		(start 214.250524 -15.423642)
		(end 214.250524 -13.364718)
		(width 0.4064)
		(layer "F.Cu")
		(net "GND")
	)
	(segment
		(start 237.20044 -147.27174)
		(end 237.199932 -147.27174)
		(width 0.3556)
		(layer "F.Cu")
		(net "GND")
	)
	(segment
		(start 386.74675 -123.821444)
		(end 386.25145 -123.59132)
		(width 0.254)
		(layer "F.Cu")
		(net "GND")
	)
	(segment
		(start 378.386594 -113.28908)
		(end 378.32665 -113.28908)
		(width 0.2286)
		(layer "F.Cu")
		(net "GND")
	)
	(segment
		(start 199.799956 -147.27174)
		(end 199.799956 -146.281902)
		(width 0.4064)
		(layer "F.Cu")
		(net "GND")
	)
	(segment
		(start 70.324726 -81.841086)
		(end 69.753226 -81.841086)
		(width 0.254)
		(layer "F.Cu")
		(net "GND")
	)
	(segment
		(start 246.565674 -140.208)
		(end 247.4849 -140.208)
		(width 0.4572)
		(layer "F.Cu")
		(net "GND")
	)
	(segment
		(start 417.2458 -52.5272)
		(end 417.2458 -51.6636)
		(width 0.254)
		(layer "F.Cu")
		(net "GND")
	)
	(segment
		(start 379.107192 -55.16245)
		(end 379.107192 -54.643528)
		(width 0.254)
		(layer "F.Cu")
		(net "GND")
	)
	(segment
		(start 252.495304 -79.859886)
		(end 251.923804 -79.859886)
		(width 0.254)
		(layer "F.Cu")
		(net "GND")
	)
	(segment
		(start 302.099726 -69.772784)
		(end 302.671226 -69.772784)
		(width 0.254)
		(layer "F.Cu")
		(net "GND")
	)
	(segment
		(start 457.252578 -140.219938)
		(end 459.1304 -140.219938)
		(width 0.254)
		(layer "F.Cu")
		(net "GND")
	)
	(segment
		(start 452.550022 -58.954924)
		(end 452.550022 -57.596024)
		(width 0.381)
		(layer "F.Cu")
		(net "GND")
	)
	(segment
		(start 284.071314 -69.277738)
		(end 284.071314 -69.849238)
		(width 0.254)
		(layer "F.Cu")
		(net "GND")
	)
	(segment
		(start 284.929834 -72.744584)
		(end 284.358334 -72.744584)
		(width 0.254)
		(layer "F.Cu")
		(net "GND")
	)
	(segment
		(start 205.749906 -137.67054)
		(end 205.749906 -136.397746)
		(width 0.4064)
		(layer "F.Cu")
		(net "GND")
	)
	(segment
		(start 279.699974 -139.170156)
		(end 279.699974 -137.676382)
		(width 0.508)
		(layer "F.Cu")
		(net "GND")
	)
	(segment
		(start 234.466638 -69.45884)
		(end 233.895138 -69.45884)
		(width 0.254)
		(layer "F.Cu")
		(net "GND")
	)
	(segment
		(start 84.060792 -52.12334)
		(end 84.060792 -51.119532)
		(width 0.2032)
		(layer "F.Cu")
		(net "GND")
	)
	(segment
		(start 193.977006 -68.881244)
		(end 193.704464 -68.608702)
		(width 0.381)
		(layer "F.Cu")
		(net "GND")
	)
	(segment
		(start 217.649806 -13.541756)
		(end 217.472006 -13.363956)
		(width 0.4064)
		(layer "F.Cu")
		(net "GND")
	)
	(segment
		(start 76.334366 -99.17684)
		(end 75.762866 -99.17684)
		(width 0.254)
		(layer "F.Cu")
		(net "GND")
	)
	(segment
		(start 65.399412 -10.422382)
		(end 65.399412 -9.156446)
		(width 0.4064)
		(layer "F.Cu")
		(net "GND")
	)
	(segment
		(start 246.485664 -70.44944)
		(end 245.914164 -70.44944)
		(width 0.254)
		(layer "F.Cu")
		(net "GND")
	)
	(segment
		(start 238.759238 -55.094886)
		(end 238.187738 -55.094886)
		(width 0.254)
		(layer "F.Cu")
		(net "GND")
	)
	(segment
		(start 60.299346 -133.0706)
		(end 60.299346 -134.763002)
		(width 0.4064)
		(layer "F.Cu")
		(net "GND")
	)
	(segment
		(start 134.249414 -17.110202)
		(end 134.15137 -17.208246)
		(width 0.4064)
		(layer "F.Cu")
		(net "GND")
	)
	(segment
		(start 117.249448 -16.149574)
		(end 117.249448 -15.423642)
		(width 0.3556)
		(layer "F.Cu")
		(net "GND")
	)
	(segment
		(start 297.549824 3.778758)
		(end 297.549824 1.994154)
		(width 0.4064)
		(layer "F.Cu")
		(net "GND")
	)
	(segment
		(start 432.062636 -18.533872)
		(end 431.98034 -18.616168)
		(width 0.254)
		(layer "F.Cu")
		(net "GND")
	)
	(segment
		(start 208.0768 -144.455388)
		(end 208.122012 -144.5006)
		(width 0.3556)
		(layer "F.Cu")
		(net "GND")
	)
	(segment
		(start 98.655378 -89.27084)
		(end 98.083878 -89.27084)
		(width 0.254)
		(layer "F.Cu")
		(net "GND")
	)
	(segment
		(start 282.250388 -5.822442)
		(end 282.24988 -5.822442)
		(width 0.4064)
		(layer "F.Cu")
		(net "GND")
	)
	(segment
		(start 119.070882 -69.277738)
		(end 119.070882 -69.849238)
		(width 0.254)
		(layer "F.Cu")
		(net "GND")
	)
	(segment
		(start 280.549858 -5.822442)
		(end 280.549858 -3.826256)
		(width 0.4064)
		(layer "F.Cu")
		(net "GND")
	)
	(segment
		(start 407.3271 -105.529126)
		(end 407.461974 -105.664)
		(width 0.254)
		(layer "F.Cu")
		(net "GND")
	)
	(segment
		(start 272.052288 -63.334138)
		(end 271.480788 -63.334138)
		(width 0.254)
		(layer "F.Cu")
		(net "GND")
	)
	(segment
		(start 369.2906 -101.1174)
		(end 369.891818 -101.1174)
		(width 0.254)
		(layer "F.Cu")
		(net "GND")
	)
	(segment
		(start 246.485664 -94.223586)
		(end 245.914164 -94.223586)
		(width 0.254)
		(layer "F.Cu")
		(net "GND")
	)
	(segment
		(start 195.550282 -152.273)
		(end 195.549774 -152.278842)
		(width 0.4064)
		(layer "F.Cu")
		(net "GND")
	)
	(segment
		(start 302.099726 -75.716384)
		(end 302.671226 -75.716384)
		(width 0.254)
		(layer "F.Cu")
		(net "GND")
	)
	(segment
		(start 294.14978 3.778758)
		(end 294.14978 2.963926)
		(width 0.4064)
		(layer "F.Cu")
		(net "GND")
	)
	(segment
		(start 449.333112 -50.6222)
		(end 449.33235 -50.5206)
		(width 0.508)
		(layer "F.Cu")
		(net "GND")
	)
	(segment
		(start 117.249448 -153.004774)
		(end 117.015768 -153.238454)
		(width 0.3556)
		(layer "F.Cu")
		(net "GND")
	)
	(segment
		(start 292.45052 -10.422382)
		(end 292.450012 -10.422382)
		(width 0.3556)
		(layer "F.Cu")
		(net "GND")
	)
	(segment
		(start 147.849336 -6.637274)
		(end 147.849336 -5.822442)
		(width 0.4064)
		(layer "F.Cu")
		(net "GND")
	)
	(segment
		(start 418.073586 -4.386072)
		(end 418.073586 -3.515614)
		(width 0.254)
		(layer "F.Cu")
		(net "GND")
	)
	(segment
		(start 475.5769 -147.12188)
		(end 476.2246 -146.47418)
		(width 0.254)
		(layer "F.Cu")
		(net "GND")
	)
	(segment
		(start 184.036208 -126.97333)
		(end 183.831992 -126.769114)
		(width 0.254)
		(layer "F.Cu")
		(net "GND")
	)
	(segment
		(start 255.815338 -140.490194)
		(end 255.071626 -140.490194)
		(width 0.4064)
		(layer "F.Cu")
		(net "GND")
	)
	(segment
		(start 83.202272 -94.223586)
		(end 82.630772 -94.223586)
		(width 0.254)
		(layer "F.Cu")
		(net "GND")
	)
	(segment
		(start 459.344776 -9.183624)
		(end 459.678278 -8.850122)
		(width 0.254)
		(layer "F.Cu")
		(net "GND")
	)
	(segment
		(start 237.042198 -54.104286)
		(end 236.470698 -54.104286)
		(width 0.254)
		(layer "F.Cu")
		(net "GND")
	)
	(segment
		(start 65.399412 -137.67054)
		(end 65.399412 -136.410446)
		(width 0.4064)
		(layer "F.Cu")
		(net "GND")
	)
	(segment
		(start 133.39953 -147.27174)
		(end 133.39953 -145.998946)
		(width 0.4064)
		(layer "F.Cu")
		(net "GND")
	)
	(segment
		(start 463.611722 -37.3888)
		(end 463.782918 -37.3888)
		(width 0.4064)
		(layer "F.Cu")
		(net "GND")
	)
	(segment
		(start 137.957814 -74.230738)
		(end 138.529314 -74.23023)
		(width 0.254)
		(layer "F.Cu")
		(net "GND")
	)
	(segment
		(start 62.792102 0.457454)
		(end 62.792102 0.444754)
		(width 0.3556)
		(layer "F.Cu")
		(net "GND")
	)
	(segment
		(start 406.41778 -102.108)
		(end 405.9555 -102.108)
		(width 0.254)
		(layer "F.Cu")
		(net "GND")
	)
	(segment
		(start 350.0628 -156.757624)
		(end 349.7072 -156.402024)
		(width 0.4064)
		(layer "F.Cu")
		(net "GND")
	)
	(segment
		(start 462.149952 -63.170054)
		(end 462.351374 -63.371476)
		(width 0.381)
		(layer "F.Cu")
		(net "GND")
	)
	(segment
		(start 241.44986 0.444754)
		(end 241.44986 -0.821182)
		(width 0.4064)
		(layer "F.Cu")
		(net "GND")
	)
	(segment
		(start 318.522096 -32.515302)
		(end 318.6176 -32.419798)
		(width 0.254)
		(layer "F.Cu")
		(net "GND")
	)
	(segment
		(start 295.23182 -74.725784)
		(end 295.80332 -74.725784)
		(width 0.254)
		(layer "F.Cu")
		(net "GND")
	)
	(segment
		(start 401.295108 -99.85502)
		(end 400.465036 -99.85502)
		(width 0.254)
		(layer "F.Cu")
		(net "GND")
	)
	(segment
		(start 204.900276 3.778758)
		(end 204.899768 3.778758)
		(width 0.4064)
		(layer "F.Cu")
		(net "GND")
	)
	(segment
		(start 300.949868 3.033522)
		(end 300.736 2.819654)
		(width 0.3556)
		(layer "F.Cu")
		(net "GND")
	)
	(segment
		(start 39.049452 -20.023582)
		(end 39.049452 -21.517356)
		(width 0.4064)
		(layer "F.Cu")
		(net "GND")
	)
	(segment
		(start 227.849938 -137.67054)
		(end 227.849938 -136.46785)
		(width 0.3556)
		(layer "F.Cu")
		(net "GND")
	)
	(segment
		(start 303.499774 -15.423642)
		(end 303.499774 -14.409928)
		(width 0.4064)
		(layer "F.Cu")
		(net "GND")
	)
	(segment
		(start 298.665646 -57.885584)
		(end 299.237146 -57.885584)
		(width 0.254)
		(layer "F.Cu")
		(net "GND")
	)
	(segment
		(start 44.149518 -137.67054)
		(end 44.149518 -136.50595)
		(width 0.4064)
		(layer "F.Cu")
		(net "GND")
	)
	(segment
		(start 387.73735 -116.953284)
		(end 387.24205 -116.72316)
		(width 0.254)
		(layer "F.Cu")
		(net "GND")
	)
	(segment
		(start 385.985004 -95.205042)
		(end 386.985002 -95.205042)
		(width 0.254)
		(layer "F.Cu")
		(net "GND")
	)
	(segment
		(start 127.655828 -61.352938)
		(end 128.227328 -61.352938)
		(width 0.254)
		(layer "F.Cu")
		(net "GND")
	)
	(segment
		(start 382.78435 -123.821444)
		(end 382.3462 -123.61799)
		(width 0.254)
		(layer "F.Cu")
		(net "GND")
	)
	(segment
		(start 71.183246 -51.62804)
		(end 70.611746 -51.62804)
		(width 0.254)
		(layer "F.Cu")
		(net "GND")
	)
	(segment
		(start 233.608118 -61.038486)
		(end 233.036618 -61.038486)
		(width 0.254)
		(layer "F.Cu")
		(net "GND")
	)
	(segment
		(start 21.6662 -85.2424)
		(end 21.442426 -85.018626)
		(width 0.254)
		(layer "F.Cu")
		(net "GND")
	)
	(segment
		(start 33.099502 -0.821182)
		(end 33.099502 -2.276856)
		(width 0.4064)
		(layer "F.Cu")
		(net "GND")
	)
	(segment
		(start 491.9345 -44.0944)
		(end 492.586264 -44.0944)
		(width 0.4064)
		(layer "F.Cu")
		(net "GND")
	)
	(segment
		(start 260.22173 -60.54344)
		(end 259.65023 -60.54344)
		(width 0.254)
		(layer "F.Cu")
		(net "GND")
	)
	(segment
		(start 121.358152 -78.193138)
		(end 121.359168 -78.194154)
		(width 0.254)
		(layer "F.Cu")
		(net "GND")
	)
	(segment
		(start 250.778264 -71.935086)
		(end 250.206764 -71.935086)
		(width 0.254)
		(layer "F.Cu")
		(net "GND")
	)
	(segment
		(start 279.699974 -10.422382)
		(end 279.699974 -9.143746)
		(width 0.4064)
		(layer "F.Cu")
		(net "GND")
	)
	(segment
		(start 125.080268 -74.725784)
		(end 125.651768 -74.725784)
		(width 0.254)
		(layer "F.Cu")
		(net "GND")
	)
	(segment
		(start 454.940924 -50.498248)
		(end 454.930764 -50.488088)
		(width 0.508)
		(layer "F.Cu")
		(net "GND")
	)
	(segment
		(start 232.749598 -87.28964)
		(end 232.101898 -87.28964)
		(width 0.254)
		(layer "F.Cu")
		(net "GND")
	)
	(segment
		(start 374.674892 -106.855006)
		(end 374.0912 -106.855006)
		(width 0.254)
		(layer "F.Cu")
		(net "GND")
	)
	(segment
		(start 138.499342 -152.273)
		(end 138.499342 -153.093674)
		(width 0.4064)
		(layer "F.Cu")
		(net "GND")
	)
	(segment
		(start 312.849768 -133.891274)
		(end 312.391298 -134.349744)
		(width 0.4064)
		(layer "F.Cu")
		(net "GND")
	)
	(segment
		(start 121.499376 -15.423642)
		(end 121.499376 -13.363956)
		(width 0.4064)
		(layer "F.Cu")
		(net "GND")
	)
	(segment
		(start 87.494872 -71.935086)
		(end 86.923372 -71.935086)
		(width 0.254)
		(layer "F.Cu")
		(net "GND")
	)
	(segment
		(start 229.549706 -16.238474)
		(end 229.549706 -15.423896)
		(width 0.4064)
		(layer "F.Cu")
		(net "GND")
	)
	(segment
		(start 218.499944 -2.253488)
		(end 218.499944 -0.821182)
		(width 0.4064)
		(layer "F.Cu")
		(net "GND")
	)
	(segment
		(start 27.137614 -32.627316)
		(end 26.489406 -32.627316)
		(width 0.254)
		(layer "F.Cu")
		(net "GND")
	)
	(segment
		(start 127.392176 -11.912092)
		(end 127.44958 -11.854688)
		(width 0.4064)
		(layer "F.Cu")
		(net "GND")
	)
	(segment
		(start 141.391894 -71.258938)
		(end 142.039594 -71.258938)
		(width 0.254)
		(layer "F.Cu")
		(net "GND")
	)
	(segment
		(start 368.69624 -106.217466)
		(end 368.421666 -106.217466)
		(width 0.254)
		(layer "F.Cu")
		(net "GND")
	)
	(segment
		(start 140.199364 -7.607046)
		(end 140.199364 -5.822442)
		(width 0.4064)
		(layer "F.Cu")
		(net "GND")
	)
	(segment
		(start 123.363228 -80.669384)
		(end 123.934728 -80.669384)
		(width 0.254)
		(layer "F.Cu")
		(net "GND")
	)
	(segment
		(start 191.262 -130.048)
		(end 191.262 -130.92938)
		(width 0.254)
		(layer "F.Cu")
		(net "GND")
	)
	(segment
		(start 120.649492 -137.67054)
		(end 120.649492 -136.410446)
		(width 0.4064)
		(layer "F.Cu")
		(net "GND")
	)
	(segment
		(start 305.533806 -98.708718)
		(end 305.246786 -98.995738)
		(width 0.254)
		(layer "F.Cu")
		(net "GND")
	)
	(segment
		(start 78.909672 -84.812886)
		(end 78.338172 -84.812886)
		(width 0.254)
		(layer "F.Cu")
		(net "GND")
	)
	(segment
		(start 195.549774 -4.277106)
		(end 195.509134 -4.317746)
		(width 0.4064)
		(layer "F.Cu")
		(net "GND")
	)
	(segment
		(start 138.816334 -70.763384)
		(end 139.387834 -70.763384)
		(width 0.254)
		(layer "F.Cu")
		(net "GND")
	)
	(segment
		(start 234.649772 -153.965402)
		(end 234.551728 -154.063446)
		(width 0.4064)
		(layer "F.Cu")
		(net "GND")
	)
	(segment
		(start 218.44254 -155.612846)
		(end 218.44254 -155.600146)
		(width 0.3556)
		(layer "F.Cu")
		(net "GND")
	)
	(segment
		(start 181.847998 -5.321808)
		(end 181.847998 -5.459984)
		(width 0.4064)
		(layer "F.Cu")
		(net "GND")
	)
	(segment
		(start 90.928698 -56.085486)
		(end 90.357198 -56.085486)
		(width 0.254)
		(layer "F.Cu")
		(net "GND")
	)
	(segment
		(start 286.499808 -17.208246)
		(end 286.499808 -15.423642)
		(width 0.4064)
		(layer "F.Cu")
		(net "GND")
	)
	(segment
		(start 184.9374 -115.57)
		(end 185.15076 -116.282724)
		(width 0.254)
		(layer "F.Cu")
		(net "GND")
	)
	(segment
		(start 384.0734 -105.11536)
		(end 384.0734 -105.1179)
		(width 0.12446)
		(layer "F.Cu")
		(net "GND")
	)
	(segment
		(start 7.7724 3.048)
		(end 7.0104 2.286)
		(width 0.2032)
		(layer "F.Cu")
		(net "GND")
	)
	(segment
		(start 72.900286 -78.37424)
		(end 72.328786 -78.37424)
		(width 0.254)
		(layer "F.Cu")
		(net "GND")
	)
	(segment
		(start 105.9561 -12.954)
		(end 107.027472 -12.954)
		(width 0.4064)
		(layer "F.Cu")
		(net "GND")
	)
	(segment
		(start 130.231388 -84.631784)
		(end 130.802888 -84.631784)
		(width 0.254)
		(layer "F.Cu")
		(net "GND")
	)
	(segment
		(start 143.599408 -153.965402)
		(end 143.501364 -154.063446)
		(width 0.4064)
		(layer "F.Cu")
		(net "GND")
	)
	(segment
		(start 220.199712 -133.076696)
		(end 220.199712 -133.891274)
		(width 0.4064)
		(layer "F.Cu")
		(net "GND")
	)
	(segment
		(start 286.07512 -63.829184)
		(end 286.64662 -63.829184)
		(width 0.254)
		(layer "F.Cu")
		(net "GND")
	)
	(segment
		(start 349.123 -19.05)
		(end 349.377 -19.304)
		(width 0.254)
		(layer "F.Cu")
		(net "GND")
	)
	(segment
		(start 386.644388 -110.762288)
		(end 386.93725 -111.05515)
		(width 0.12446)
		(layer "F.Cu")
		(net "GND")
	)
	(segment
		(start 119.929402 -99.490784)
		(end 120.500902 -99.490784)
		(width 0.254)
		(layer "F.Cu")
		(net "GND")
	)
	(segment
		(start 52.448968 -6.9342)
		(end 52.448968 -7.622794)
		(width 0.3556)
		(layer "F.Cu")
		(net "GND")
	)
	(segment
		(start 300.382686 -65.810384)
		(end 300.954186 -65.810384)
		(width 0.254)
		(layer "F.Cu")
		(net "GND")
	)
	(segment
		(start 239.617758 -91.25204)
		(end 239.046258 -91.25204)
		(width 0.254)
		(layer "F.Cu")
		(net "GND")
	)
	(segment
		(start 132.806694 -99.986338)
		(end 133.378194 -99.986338)
		(width 0.254)
		(layer "F.Cu")
		(net "GND")
	)
	(segment
		(start 284.071314 -96.023938)
		(end 284.642814 -96.023938)
		(width 0.254)
		(layer "F.Cu")
		(net "GND")
	)
	(segment
		(start 397.98498 -95.205042)
		(end 398.027144 -95.183706)
		(width 0.254)
		(layer "F.Cu")
		(net "GND")
	)
	(segment
		(start 213.400386 -0.821182)
		(end 213.399878 -0.821182)
		(width 0.4064)
		(layer "F.Cu")
		(net "GND")
	)
	(segment
		(start 50.949352 -13.427456)
		(end 50.860452 -13.338556)
		(width 0.4064)
		(layer "F.Cu")
		(net "GND")
	)
	(segment
		(start 182.890922 -149.784308)
		(end 182.890922 -151.219916)
		(width 0.254)
		(layer "F.Cu")
		(net "GND")
	)
	(segment
		(start 79.768192 -74.411586)
		(end 79.196692 -74.411586)
		(width 0.254)
		(layer "F.Cu")
		(net "GND")
	)
	(segment
		(start 420.751 -80.913986)
		(end 419.905942 -80.913986)
		(width 0.254)
		(layer "F.Cu")
		(net "GND")
	)
	(segment
		(start 196.4436 -129.612644)
		(end 196.399912 -129.568956)
		(width 0.4064)
		(layer "F.Cu")
		(net "GND")
	)
	(segment
		(start 2.8448 -6.3754)
		(end 2.6924 -6.3754)
		(width 0.254)
		(layer "F.Cu")
		(net "GND")
	)
	(segment
		(start 229.550468 -152.273)
		(end 229.54996 -152.278842)
		(width 0.4064)
		(layer "F.Cu")
		(net "GND")
	)
	(segment
		(start 198.061834 -139.170156)
		(end 198.099934 -139.132056)
		(width 0.4064)
		(layer "F.Cu")
		(net "GND")
	)
	(segment
		(start 233.799888 -11.916156)
		(end 233.799888 -10.422382)
		(width 0.4064)
		(layer "F.Cu")
		(net "GND")
	)
	(segment
		(start 241.334798 -74.411586)
		(end 240.763298 -74.411586)
		(width 0.254)
		(layer "F.Cu")
		(net "GND")
	)
	(segment
		(start 174.8155 -68.834)
		(end 175.35652 -68.834)
		(width 0.4064)
		(layer "F.Cu")
		(net "GND")
	)
	(segment
		(start 280.549858 2.092198)
		(end 280.451814 1.994154)
		(width 0.4064)
		(layer "F.Cu")
		(net "GND")
	)
	(segment
		(start 221.899988 -3.76301)
		(end 221.899988 -5.822442)
		(width 0.4064)
		(layer "F.Cu")
		(net "GND")
	)
	(segment
		(start 235.325158 -69.953886)
		(end 234.753658 -69.953886)
		(width 0.254)
		(layer "F.Cu")
		(net "GND")
	)
	(segment
		(start 436.499 -18.161)
		(end 436.499 -18.4785)
		(width 0.254)
		(layer "F.Cu")
		(net "GND")
	)
	(segment
		(start 317.949834 -152.278842)
		(end 317.949834 -153.542746)
		(width 0.4064)
		(layer "F.Cu")
		(net "GND")
	)
	(segment
		(start 116.399564 -11.878056)
		(end 116.399564 -10.422382)
		(width 0.4064)
		(layer "F.Cu")
		(net "GND")
	)
	(segment
		(start 83.202272 -61.53404)
		(end 82.630772 -61.53404)
		(width 0.254)
		(layer "F.Cu")
		(net "GND")
	)
	(segment
		(start 79.768192 -82.33664)
		(end 79.196692 -82.33664)
		(width 0.254)
		(layer "F.Cu")
		(net "GND")
	)
	(segment
		(start 72.1995 -147.27174)
		(end 72.1995 -146.06905)
		(width 0.3556)
		(layer "F.Cu")
		(net "GND")
	)
	(segment
		(start 61.999368 -153.009854)
		(end 61.796168 -153.213054)
		(width 0.3556)
		(layer "F.Cu")
		(net "GND")
	)
	(segment
		(start 289.22218 -56.399938)
		(end 288.65068 -56.399938)
		(width 0.254)
		(layer "F.Cu")
		(net "GND")
	)
	(segment
		(start 392.98499 -126.165102)
		(end 393.2682 -126.448312)
		(width 0.254)
		(layer "F.Cu")
		(net "GND")
	)
	(segment
		(start 91.641168 -3.321812)
		(end 91.294712 -2.975356)
		(width 0.4064)
		(layer "F.Cu")
		(net "GND")
	)
	(segment
		(start 237.042198 -80.850486)
		(end 236.470698 -80.850486)
		(width 0.254)
		(layer "F.Cu")
		(net "GND")
	)
	(segment
		(start 493.903 -47.21987)
		(end 493.663986 -47.458884)
		(width 0.254)
		(layer "F.Cu")
		(net "GND")
	)
	(segment
		(start 418.211 -54.864)
		(end 418.213032 -54.864)
		(width 0.254)
		(layer "F.Cu")
		(net "GND")
	)
	(segment
		(start 371.243606 -158.493206)
		(end 371.094 -158.3436)
		(width 0.254)
		(layer "F.Cu")
		(net "GND")
	)
	(segment
		(start 239.046258 -50.63744)
		(end 239.617758 -50.63744)
		(width 0.254)
		(layer "F.Cu")
		(net "GND")
	)
	(segment
		(start 295.85031 -152.273)
		(end 295.849802 -152.278842)
		(width 0.4064)
		(layer "F.Cu")
		(net "GND")
	)
	(segment
		(start 217.650314 -15.423642)
		(end 217.649806 -15.423642)
		(width 0.3048)
		(layer "F.Cu")
		(net "GND")
	)
	(segment
		(start 249.919744 -59.55284)
		(end 249.348244 -59.55284)
		(width 0.254)
		(layer "F.Cu")
		(net "GND")
	)
	(segment
		(start 317.09995 -152.278842)
		(end 317.09995 -153.542746)
		(width 0.4064)
		(layer "F.Cu")
		(net "GND")
	)
	(segment
		(start 52.649374 -153.012394)
		(end 52.448968 -153.2128)
		(width 0.3048)
		(layer "F.Cu")
		(net "GND")
	)
	(segment
		(start 50.099468 -20.023582)
		(end 50.099468 -21.517356)
		(width 0.4064)
		(layer "F.Cu")
		(net "GND")
	)
	(segment
		(start 429.962056 -3.776218)
		(end 430.075086 -3.889248)
		(width 0.254)
		(layer "F.Cu")
		(net "GND")
	)
	(segment
		(start 379.81255 -102.12832)
		(end 380.30785 -101.898196)
		(width 0.254)
		(layer "F.Cu")
		(net "GND")
	)
	(segment
		(start 370.727986 -107.431586)
		(end 372.0084 -108.712)
		(width 0.254)
		(layer "F.Cu")
		(net "GND")
	)
	(segment
		(start 39.049452 -9.156446)
		(end 39.049452 -10.422382)
		(width 0.4064)
		(layer "F.Cu")
		(net "GND")
	)
	(segment
		(start 267.948156 -98.681286)
		(end 267.376656 -98.681286)
		(width 0.254)
		(layer "F.Cu")
		(net "GND")
	)
	(segment
		(start 127.655828 -93.052138)
		(end 128.227328 -93.052138)
		(width 0.254)
		(layer "F.Cu")
		(net "GND")
	)
	(segment
		(start 278.850344 -152.273)
		(end 278.849836 -152.273)
		(width 0.508)
		(layer "F.Cu")
		(net "GND")
	)
	(segment
		(start 71.117968 -16.383)
		(end 71.117968 -17.193006)
		(width 0.3556)
		(layer "F.Cu")
		(net "GND")
	)
	(segment
		(start 229.549706 -152.279096)
		(end 229.549706 -153.093674)
		(width 0.4064)
		(layer "F.Cu")
		(net "GND")
	)
	(segment
		(start 380.80315 -122.104404)
		(end 380.30785 -121.87428)
		(width 0.254)
		(layer "F.Cu")
		(net "GND")
	)
	(segment
		(start 49.249584 3.778758)
		(end 49.24933 3.778504)
		(width 0.4064)
		(layer "F.Cu")
		(net "GND")
	)
	(segment
		(start 75.475846 -94.718886)
		(end 74.904346 -94.718886)
		(width 0.254)
		(layer "F.Cu")
		(net "GND")
	)
	(segment
		(start 376.335036 -112.854994)
		(end 376.581162 -112.374172)
		(width 0.254)
		(layer "F.Cu")
		(net "GND")
	)
	(segment
		(start 193.860928 -75.954382)
		(end 193.761868 -76.053442)
		(width 0.254)
		(layer "F.Cu")
		(net "GND")
	)
	(segment
		(start 273.769328 -63.334138)
		(end 273.197828 -63.334138)
		(width 0.254)
		(layer "F.Cu")
		(net "GND")
	)
	(segment
		(start 74.749406 0.444754)
		(end 74.749406 -0.821182)
		(width 0.4064)
		(layer "F.Cu")
		(net "GND")
	)
	(segment
		(start 204.900276 -152.273)
		(end 204.899768 -152.278842)
		(width 0.4064)
		(layer "F.Cu")
		(net "GND")
	)
	(segment
		(start 109.627416 -54.913784)
		(end 109.055916 -54.913784)
		(width 0.254)
		(layer "F.Cu")
		(net "GND")
	)
	(segment
		(start 98.655378 -63.51524)
		(end 98.083878 -63.51524)
		(width 0.254)
		(layer "F.Cu")
		(net "GND")
	)
	(segment
		(start 133.665214 -62.838584)
		(end 134.236714 -62.838584)
		(width 0.254)
		(layer "F.Cu")
		(net "GND")
	)
	(segment
		(start 448.5894 -21.209)
		(end 448.5386 -21.2598)
		(width 0.254)
		(layer "F.Cu")
		(net "GND")
	)
	(segment
		(start 281.400504 -156.87294)
		(end 281.400504 -155.613354)
		(width 0.3556)
		(layer "F.Cu")
		(net "GND")
	)
	(segment
		(start 294.14978 -5.822442)
		(end 294.14978 -4.808728)
		(width 0.4064)
		(layer "F.Cu")
		(net "GND")
	)
	(segment
		(start 374.674892 -123.731528)
		(end 374.674892 -124.544328)
		(width 0.254)
		(layer "F.Cu")
		(net "GND")
	)
	(segment
		(start 249.919744 -63.51524)
		(end 249.348244 -63.51524)
		(width 0.254)
		(layer "F.Cu")
		(net "GND")
	)
	(segment
		(start 7.2136 0.847598)
		(end 7.5819 0.847598)
		(width 0.2032)
		(layer "F.Cu")
		(net "GND")
	)
	(segment
		(start 198.950326 -133.0706)
		(end 198.949818 -133.076442)
		(width 0.3556)
		(layer "F.Cu")
		(net "GND")
	)
	(segment
		(start 259.36321 -87.784686)
		(end 258.79171 -87.784686)
		(width 0.254)
		(layer "F.Cu")
		(net "GND")
	)
	(segment
		(start 36.499546 -142.677642)
		(end 36.499292 -142.677896)
		(width 0.4064)
		(layer "F.Cu")
		(net "GND")
	)
	(segment
		(start 82.343752 -99.67214)
		(end 82.343752 -100.662486)
		(width 0.254)
		(layer "F.Cu")
		(net "GND")
	)
	(segment
		(start 203.2 3.778758)
		(end 203.2 3.599688)
		(width 0.4064)
		(layer "F.Cu")
		(net "GND")
	)
	(segment
		(start 111.344202 -94.538038)
		(end 111.915702 -94.538038)
		(width 0.254)
		(layer "F.Cu")
		(net "GND")
	)
	(segment
		(start 34.799524 0.174498)
		(end 34.799524 -0.821182)
		(width 0.4064)
		(layer "F.Cu")
		(net "GND")
	)
	(segment
		(start 166.41953 -80.21193)
		(end 166.5986 -80.391)
		(width 0.254)
		(layer "F.Cu")
		(net "GND")
	)
	(segment
		(start 239.749838 -11.916156)
		(end 239.749838 -10.422382)
		(width 0.4064)
		(layer "F.Cu")
		(net "GND")
	)
	(segment
		(start 83.202272 -92.24264)
		(end 82.630772 -92.24264)
		(width 0.254)
		(layer "F.Cu")
		(net "GND")
	)
	(segment
		(start 175.80356 -80.772)
		(end 176.6316 -80.772)
		(width 0.254)
		(layer "F.Cu")
		(net "GND")
	)
	(segment
		(start 135.949436 -3.940556)
		(end 135.949436 -5.822442)
		(width 0.4064)
		(layer "F.Cu")
		(net "GND")
	)
	(segment
		(start 343.3064 -9.4742)
		(end 342.058498 -9.4742)
		(width 0.508)
		(layer "F.Cu")
		(net "GND")
	)
	(segment
		(start 55.19928 -133.076696)
		(end 55.19928 -133.891274)
		(width 0.4064)
		(layer "F.Cu")
		(net "GND")
	)
	(segment
		(start 141.95171 -97.014538)
		(end 141.963648 -97.0026)
		(width 0.254)
		(layer "F.Cu")
		(net "GND")
	)
	(segment
		(start 231.249982 -152.457912)
		(end 231.249728 -152.458166)
		(width 0.4064)
		(layer "F.Cu")
		(net "GND")
	)
	(segment
		(start 120.787668 -97.014538)
		(end 121.359168 -97.014538)
		(width 0.254)
		(layer "F.Cu")
		(net "GND")
	)
	(segment
		(start 262.6868 -128.766824)
		(end 262.382 -128.462024)
		(width 0.508)
		(layer "F.Cu")
		(net "GND")
	)
	(segment
		(start 221.04985 -2.314956)
		(end 221.04985 -0.821182)
		(width 0.4064)
		(layer "F.Cu")
		(net "GND")
	)
	(segment
		(start 384.27025 -116.35994)
		(end 384.27025 -116.72316)
		(width 0.12446)
		(layer "F.Cu")
		(net "GND")
	)
	(segment
		(start 469.9254 -43.0784)
		(end 469.632792 -42.785792)
		(width 0.254)
		(layer "F.Cu")
		(net "GND")
	)
	(segment
		(start 280.549858 -15.423642)
		(end 280.549858 -14.2113)
		(width 0.4064)
		(layer "F.Cu")
		(net "GND")
	)
	(segment
		(start 127.655828 -91.070938)
		(end 128.227328 -91.070938)
		(width 0.254)
		(layer "F.Cu")
		(net "GND")
	)
	(segment
		(start 204.049884 -136.410446)
		(end 204.049884 -137.67054)
		(width 0.4064)
		(layer "F.Cu")
		(net "GND")
	)
	(segment
		(start 82.459068 -12.954)
		(end 81.582768 -12.954)
		(width 0.4064)
		(layer "F.Cu")
		(net "GND")
	)
	(segment
		(start 57.74944 -147.27174)
		(end 57.74944 -146.011646)
		(width 0.4064)
		(layer "F.Cu")
		(net "GND")
	)
	(segment
		(start 78.128368 -18.7452)
		(end 78.14945 -18.766282)
		(width 0.4064)
		(layer "F.Cu")
		(net "GND")
	)
	(segment
		(start 211.700364 -137.67054)
		(end 211.699856 -137.67054)
		(width 0.4064)
		(layer "F.Cu")
		(net "GND")
	)
	(segment
		(start 281.361896 -2.314956)
		(end 281.399996 -2.276856)
		(width 0.4064)
		(layer "F.Cu")
		(net "GND")
	)
	(segment
		(start 72.1995 -155.67025)
		(end 72.142096 -155.612846)
		(width 0.3556)
		(layer "F.Cu")
		(net "GND")
	)
	(segment
		(start 31.145734 -61.095382)
		(end 30.524958 -61.716158)
		(width 0.508)
		(layer "F.Cu")
		(net "GND")
	)
	(segment
		(start 68.607686 -64.010286)
		(end 68.036186 -64.010286)
		(width 0.254)
		(layer "F.Cu")
		(net "GND")
	)
	(segment
		(start 481.494592 -35.5854)
		(end 481.287836 -35.378644)
		(width 0.254)
		(layer "F.Cu")
		(net "GND")
	)
	(segment
		(start 258.50469 -60.54344)
		(end 257.93319 -60.54344)
		(width 0.254)
		(layer "F.Cu")
		(net "GND")
	)
	(segment
		(start 297.807126 -99.986338)
		(end 298.378626 -99.986338)
		(width 0.254)
		(layer "F.Cu")
		(net "GND")
	)
	(segment
		(start 119.929402 -89.584784)
		(end 120.500902 -89.584784)
		(width 0.254)
		(layer "F.Cu")
		(net "GND")
	)
	(segment
		(start 131.948174 -101.471984)
		(end 132.519674 -101.471984)
		(width 0.254)
		(layer "F.Cu")
		(net "GND")
	)
	(segment
		(start 382.93675 -115.05565)
		(end 383.3368 -115.4557)
		(width 0.12446)
		(layer "F.Cu")
		(net "GND")
	)
	(segment
		(start 7.333234 5.196332)
		(end 6.562852 5.196332)
		(width 0.254)
		(layer "F.Cu")
		(net "GND")
	)
	(segment
		(start 197.249796 -153.965402)
		(end 197.151752 -154.063446)
		(width 0.4064)
		(layer "F.Cu")
		(net "GND")
	)
	(segment
		(start 286.900874 -52.380896)
		(end 286.93364 -52.437538)
		(width 0.254)
		(layer "F.Cu")
		(net "GND")
	)
	(segment
		(start 423.090086 -31.33471)
		(end 423.490136 -30.93466)
		(width 0.254)
		(layer "F.Cu")
		(net "GND")
	)
	(segment
		(start 53.499512 -9.21385)
		(end 53.442108 -9.156446)
		(width 0.3556)
		(layer "F.Cu")
		(net "GND")
	)
	(segment
		(start 239.617758 -64.50584)
		(end 239.046258 -64.50584)
		(width 0.254)
		(layer "F.Cu")
		(net "GND")
	)
	(segment
		(start 442.140086 -51.875944)
		(end 442.141102 -51.875944)
		(width 0.4064)
		(layer "F.Cu")
		(net "GND")
	)
	(segment
		(start 400.97202 -74.53122)
		(end 400.939 -74.53122)
		(width 0.254)
		(layer "F.Cu")
		(net "GND")
	)
	(segment
		(start 1.917446 -144.933162)
		(end 1.917446 -144.488154)
		(width 0.254)
		(layer "F.Cu")
		(net "GND")
	)
	(segment
		(start 207.449928 -137.67054)
		(end 207.449928 -139.132056)
		(width 0.4064)
		(layer "F.Cu")
		(net "GND")
	)
	(segment
		(start 150.399496 -0.821182)
		(end 150.399496 0.444754)
		(width 0.4064)
		(layer "F.Cu")
		(net "GND")
	)
	(segment
		(start 33.099502 -137.67054)
		(end 33.099502 -136.410446)
		(width 0.4064)
		(layer "F.Cu")
		(net "GND")
	)
	(segment
		(start 317.09995 0.444754)
		(end 317.09995 -0.821182)
		(width 0.4064)
		(layer "F.Cu")
		(net "GND")
	)
	(segment
		(start 243.910104 -94.718886)
		(end 243.338604 -94.718886)
		(width 0.254)
		(layer "F.Cu")
		(net "GND")
	)
	(segment
		(start 294.999918 -2.314956)
		(end 294.999918 -0.821182)
		(width 0.4064)
		(layer "F.Cu")
		(net "GND")
	)
	(segment
		(start 72.041766 -87.784686)
		(end 71.470266 -87.784686)
		(width 0.254)
		(layer "F.Cu")
		(net "GND")
	)
	(segment
		(start 383.77495 -122.104404)
		(end 383.27965 -121.87428)
		(width 0.254)
		(layer "F.Cu")
		(net "GND")
	)
	(segment
		(start 132.806694 -72.249538)
		(end 133.378194 -72.249538)
		(width 0.254)
		(layer "F.Cu")
		(net "GND")
	)
	(segment
		(start 289.22218 -74.230738)
		(end 289.79368 -74.230738)
		(width 0.254)
		(layer "F.Cu")
		(net "GND")
	)
	(segment
		(start 1.999234 -135.338566)
		(end 1.999234 -135.333486)
		(width 0.254)
		(layer "F.Cu")
		(net "GND")
	)
	(segment
		(start 125.938788 -87.108538)
		(end 126.510288 -87.108538)
		(width 0.254)
		(layer "F.Cu")
		(net "GND")
	)
	(segment
		(start 197.249796 -144.364202)
		(end 197.151752 -144.462246)
		(width 0.4064)
		(layer "F.Cu")
		(net "GND")
	)
	(segment
		(start 119.070882 -96.023938)
		(end 119.642382 -96.023938)
		(width 0.254)
		(layer "F.Cu")
		(net "GND")
	)
	(segment
		(start 306.050442 -0.821182)
		(end 306.049934 -0.821182)
		(width 0.4064)
		(layer "F.Cu")
		(net "GND")
	)
	(segment
		(start 231.25049 -15.423642)
		(end 231.25049 -17.207484)
		(width 0.4064)
		(layer "F.Cu")
		(net "GND")
	)
	(segment
		(start 78.051406 -72.43064)
		(end 77.479906 -72.43064)
		(width 0.254)
		(layer "F.Cu")
		(net "GND")
	)
	(segment
		(start 304.675286 -96.023938)
		(end 305.246786 -96.023938)
		(width 0.254)
		(layer "F.Cu")
		(net "GND")
	)
	(segment
		(start 243.051838 -69.45884)
		(end 242.480338 -69.45884)
		(width 0.254)
		(layer "F.Cu")
		(net "GND")
	)
	(segment
		(start 370.344954 -71.894954)
		(end 370.745004 -72.295004)
		(width 0.254)
		(layer "F.Cu")
		(net "GND")
	)
	(segment
		(start 303.529746 -68.078604)
		(end 303.529746 -68.287138)
		(width 0.254)
		(layer "F.Cu")
		(net "GND")
	)
	(segment
		(start 287.21812 -70.763384)
		(end 286.64662 -70.763384)
		(width 0.254)
		(layer "F.Cu")
		(net "GND")
	)
	(segment
		(start 195.549774 -153.598626)
		(end 195.5038 -153.6446)
		(width 0.4064)
		(layer "F.Cu")
		(net "GND")
	)
	(segment
		(start 208.0768 2.819654)
		(end 208.0768 2.001012)
		(width 0.3556)
		(layer "F.Cu")
		(net "GND")
	)
	(segment
		(start 204.049884 -156.87294)
		(end 204.049884 -155.612846)
		(width 0.4064)
		(layer "F.Cu")
		(net "GND")
	)
	(segment
		(start 245.627144 -71.935086)
		(end 245.055644 -71.935086)
		(width 0.254)
		(layer "F.Cu")
		(net "GND")
	)
	(segment
		(start 215.0999 -0.821182)
		(end 215.0999 -2.314956)
		(width 0.4064)
		(layer "F.Cu")
		(net "GND")
	)
	(segment
		(start 457.252324 -147.719796)
		(end 458.437996 -147.719796)
		(width 0.254)
		(layer "F.Cu")
		(net "GND")
	)
	(segment
		(start 86.636352 -86.29904)
		(end 86.064852 -86.29904)
		(width 0.254)
		(layer "F.Cu")
		(net "GND")
	)
	(segment
		(start 218.44254 -2.310892)
		(end 218.499944 -2.253488)
		(width 0.4064)
		(layer "F.Cu")
		(net "GND")
	)
	(segment
		(start 465.732368 -148.9075)
		(end 465.36737 -148.542502)
		(width 0.254)
		(layer "F.Cu")
		(net "GND")
	)
	(segment
		(start 56.049418 -20.023582)
		(end 56.049418 -21.517356)
		(width 0.4064)
		(layer "F.Cu")
		(net "GND")
	)
	(segment
		(start 31.14802 -94.59722)
		(end 31.0642 -94.5134)
		(width 0.254)
		(layer "F.Cu")
		(net "GND")
	)
	(segment
		(start 437.0324 -17.8308)
		(end 436.8292 -17.8308)
		(width 0.254)
		(layer "F.Cu")
		(net "GND")
	)
	(segment
		(start 27.88158 -79.55026)
		(end 27.92984 -79.55026)
		(width 0.254)
		(layer "F.Cu")
		(net "GND")
	)
	(segment
		(start 394.17625 -121.87428)
		(end 394.67155 -122.104404)
		(width 0.254)
		(layer "F.Cu")
		(net "GND")
	)
	(segment
		(start 235.500418 -20.023582)
		(end 235.49991 -20.023582)
		(width 0.4064)
		(layer "F.Cu")
		(net "GND")
	)
	(segment
		(start 350.62668 -139.37742)
		(end 350.62668 -139.01801)
		(width 0.508)
		(layer "F.Cu")
		(net "GND")
	)
	(segment
		(start 240.599976 -142.856712)
		(end 240.599722 -142.856966)
		(width 0.4064)
		(layer "F.Cu")
		(net "GND")
	)
	(segment
		(start 120.787668 -83.146138)
		(end 121.359168 -83.146138)
		(width 0.254)
		(layer "F.Cu")
		(net "GND")
	)
	(segment
		(start 382.797304 -32.270954)
		(end 381.851154 -32.270954)
		(width 0.254)
		(layer "F.Cu")
		(net "GND")
	)
	(segment
		(start 394.67155 -122.7328)
		(end 395.16685 -122.962924)
		(width 0.254)
		(layer "F.Cu")
		(net "GND")
	)
	(segment
		(start 392.69035 -117.58168)
		(end 393.18565 -117.811804)
		(width 0.254)
		(layer "F.Cu")
		(net "GND")
	)
	(segment
		(start 30.549342 -134.400798)
		(end 30.53334 -134.4168)
		(width 0.4064)
		(layer "F.Cu")
		(net "GND")
	)
	(segment
		(start 126.388368 -17.213326)
		(end 126.388368 -16.3576)
		(width 0.3556)
		(layer "F.Cu")
		(net "GND")
	)
	(segment
		(start 198.100442 -0.821182)
		(end 198.099934 -0.821182)
		(width 0.4064)
		(layer "F.Cu")
		(net "GND")
	)
	(segment
		(start 44.149518 -136.50595)
		(end 44.092114 -136.448546)
		(width 0.4064)
		(layer "F.Cu")
		(net "GND")
	)
	(segment
		(start 215.100408 -10.422382)
		(end 215.0999 -10.422382)
		(width 0.4064)
		(layer "F.Cu")
		(net "GND")
	)
	(segment
		(start 449.561458 -5.464048)
		(end 450.077078 -5.979668)
		(width 0.254)
		(layer "F.Cu")
		(net "GND")
	)
	(segment
		(start 201.500486 -6.636512)
		(end 201.041254 -7.095744)
		(width 0.4064)
		(layer "F.Cu")
		(net "GND")
	)
	(segment
		(start 281.495754 -58.876438)
		(end 280.924254 -58.876438)
		(width 0.254)
		(layer "F.Cu")
		(net "GND")
	)
	(segment
		(start 439.742072 -51.875944)
		(end 439.732928 -50.6222)
		(width 0.508)
		(layer "F.Cu")
		(net "GND")
	)
	(segment
		(start 109.627416 -89.584784)
		(end 110.198916 -89.584784)
		(width 0.254)
		(layer "F.Cu")
		(net "GND")
	)
	(segment
		(start 240.599976 -15.602712)
		(end 240.599976 -15.423642)
		(width 0.4064)
		(layer "F.Cu")
		(net "GND")
	)
	(segment
		(start 464.542124 -50.625248)
		(end 464.542124 -51.875944)
		(width 0.508)
		(layer "F.Cu")
		(net "GND")
	)
	(segment
		(start 395.66215 -113.519204)
		(end 395.224 -113.31575)
		(width 0.254)
		(layer "F.Cu")
		(net "GND")
	)
	(segment
		(start 413.890206 -33.334706)
		(end 413.490156 -33.734756)
		(width 0.254)
		(layer "F.Cu")
		(net "GND")
	)
	(segment
		(start 223.599756 -152.279096)
		(end 223.599756 -154.063446)
		(width 0.4064)
		(layer "F.Cu")
		(net "GND")
	)
	(segment
		(start 146.149568 -20.023582)
		(end 146.149568 -21.455888)
		(width 0.4064)
		(layer "F.Cu")
		(net "GND")
	)
	(segment
		(start 78.909672 -92.737686)
		(end 78.338172 -92.737686)
		(width 0.254)
		(layer "F.Cu")
		(net "GND")
	)
	(segment
		(start 197.249796 -15.423642)
		(end 197.249796 -13.427456)
		(width 0.4064)
		(layer "F.Cu")
		(net "GND")
	)
	(segment
		(start 443.427358 -45.611796)
		(end 443.741048 -45.925486)
		(width 0.4064)
		(layer "F.Cu")
		(net "GND")
	)
	(segment
		(start 467.643972 -136.114028)
		(end 467.643972 -137.033)
		(width 0.254)
		(layer "F.Cu")
		(net "GND")
	)
	(segment
		(start 136.74217 -9.143746)
		(end 136.74217 -9.156446)
		(width 0.3556)
		(layer "F.Cu")
		(net "GND")
	)
	(segment
		(start 381.79375 -95.888556)
		(end 381.985012 -95.205042)
		(width 0.254)
		(layer "F.Cu")
		(net "GND")
	)
	(segment
		(start 96.079818 -95.709486)
		(end 95.508318 -95.709486)
		(width 0.254)
		(layer "F.Cu")
		(net "GND")
	)
	(segment
		(start 298.399962 -137.67054)
		(end 298.399962 -136.397746)
		(width 0.4064)
		(layer "F.Cu")
		(net "GND")
	)
	(segment
		(start 146.149568 -10.422382)
		(end 146.149568 -11.854688)
		(width 0.4064)
		(layer "F.Cu")
		(net "GND")
	)
	(segment
		(start 198.099934 -147.27174)
		(end 198.099934 -146.011646)
		(width 0.4064)
		(layer "F.Cu")
		(net "GND")
	)
	(segment
		(start 384.53695 -105.45445)
		(end 384.937 -105.8545)
		(width 0.254)
		(layer "F.Cu")
		(net "GND")
	)
	(segment
		(start 324.52564 -27.8003)
		(end 324.52564 -27.88412)
		(width 0.4572)
		(layer "F.Cu")
		(net "GND")
	)
	(segment
		(start 129.149348 -4.808728)
		(end 128.687576 -4.346956)
		(width 0.4064)
		(layer "F.Cu")
		(net "GND")
	)
	(segment
		(start 20.18792 -44.78528)
		(end 20.18792 -42.808652)
		(width 0.254)
		(layer "F.Cu")
		(net "GND")
	)
	(segment
		(start 402.790914 -99.951286)
		(end 402.9456 -99.7966)
		(width 0.1524)
		(layer "F.Cu")
		(net "GND")
	)
	(segment
		(start 243.051838 -94.223586)
		(end 242.480338 -94.223586)
		(width 0.254)
		(layer "F.Cu")
		(net "GND")
	)
	(segment
		(start 462.351374 -63.371476)
		(end 462.351374 -63.626492)
		(width 0.381)
		(layer "F.Cu")
		(net "GND")
	)
	(segment
		(start 118.041928 -18.757646)
		(end 118.099332 -18.81505)
		(width 0.3556)
		(layer "F.Cu")
		(net "GND")
	)
	(segment
		(start 67.949572 -133.0706)
		(end 67.949572 -133.076442)
		(width 0.4064)
		(layer "F.Cu")
		(net "GND")
	)
	(segment
		(start 226.149916 -18.757646)
		(end 226.149916 -20.023582)
		(width 0.4064)
		(layer "F.Cu")
		(net "GND")
	)
	(segment
		(start 448.60083 -112.205516)
		(end 448.60083 -113.75517)
		(width 0.4064)
		(layer "F.Cu")
		(net "GND")
	)
	(segment
		(start 304.349912 -10.422382)
		(end 304.349912 -9.156446)
		(width 0.4064)
		(layer "F.Cu")
		(net "GND")
	)
	(segment
		(start 452.532242 -50.515266)
		(end 452.530464 -50.513488)
		(width 0.508)
		(layer "F.Cu")
		(net "GND")
	)
	(segment
		(start 395.984984 -93.544898)
		(end 395.984984 -92.917518)
		(width 0.254)
		(layer "F.Cu")
		(net "GND")
	)
	(segment
		(start 226.149916 -0.821182)
		(end 226.149916 0.444754)
		(width 0.4064)
		(layer "F.Cu")
		(net "GND")
	)
	(segment
		(start 493.663986 -47.458884)
		(end 493.168686 -47.458884)
		(width 0.254)
		(layer "F.Cu")
		(net "GND")
	)
	(segment
		(start 175.2854 -146.26844)
		(end 175.0822 -146.47164)
		(width 0.254)
		(layer "F.Cu")
		(net "GND")
	)
	(segment
		(start 113.849404 -20.023582)
		(end 113.849404 -18.786348)
		(width 0.4064)
		(layer "F.Cu")
		(net "GND")
	)
	(segment
		(start 49.249584 -152.273)
		(end 49.249584 -152.278842)
		(width 0.4064)
		(layer "F.Cu")
		(net "GND")
	)
	(segment
		(start 160.76422 -126.00305)
		(end 160.76422 -125.1077)
		(width 0.4572)
		(layer "F.Cu")
		(net "GND")
	)
	(segment
		(start 70.499478 -11.878056)
		(end 70.499478 -10.422382)
		(width 0.4064)
		(layer "F.Cu")
		(net "GND")
	)
	(segment
		(start 231.249982 -142.677642)
		(end 231.249982 -142.856712)
		(width 0.4064)
		(layer "F.Cu")
		(net "GND")
	)
	(segment
		(start 220.200474 2.964688)
		(end 219.741242 2.505456)
		(width 0.4064)
		(layer "F.Cu")
		(net "GND")
	)
	(segment
		(start 398.13865 -120.15724)
		(end 398.63395 -120.387364)
		(width 0.254)
		(layer "F.Cu")
		(net "GND")
	)
	(segment
		(start 375.504964 -102.855014)
		(end 376.335036 -102.855014)
		(width 0.254)
		(layer "F.Cu")
		(net "GND")
	)
	(segment
		(start 461.340962 -51.875944)
		(end 461.340962 -51.308508)
		(width 0.508)
		(layer "F.Cu")
		(net "GND")
	)
	(segment
		(start 341.376 -20.447)
		(end 341.376 -21.082)
		(width 0.254)
		(layer "F.Cu")
		(net "GND")
	)
	(segment
		(start 237.142528 -9.143746)
		(end 237.142528 -9.156446)
		(width 0.3556)
		(layer "F.Cu")
		(net "GND")
	)
	(segment
		(start 73.899268 -142.677896)
		(end 73.899268 -143.492474)
		(width 0.4064)
		(layer "F.Cu")
		(net "GND")
	)
	(segment
		(start 171.9326 -124.3076)
		(end 171.9326 -124.83338)
		(width 0.381)
		(layer "F.Cu")
		(net "GND")
	)
	(segment
		(start 235.49991 -2.276856)
		(end 235.49991 -0.821182)
		(width 0.4064)
		(layer "F.Cu")
		(net "GND")
	)
	(segment
		(start 303.499774 -133.891274)
		(end 303.041304 -134.349744)
		(width 0.4064)
		(layer "F.Cu")
		(net "GND")
	)
	(segment
		(start 376.335036 -108.855002)
		(end 376.889772 -109.371638)
		(width 0.254)
		(layer "F.Cu")
		(net "GND")
	)
	(segment
		(start 88.353392 -68.46824)
		(end 87.781892 -68.46824)
		(width 0.254)
		(layer "F.Cu")
		(net "GND")
	)
	(segment
		(start 173.173898 -85.467698)
		(end 173.609 -85.9028)
		(width 0.254)
		(layer "F.Cu")
		(net "GND")
	)
	(segment
		(start 125.080268 -64.819784)
		(end 125.651768 -64.819784)
		(width 0.254)
		(layer "F.Cu")
		(net "GND")
	)
	(segment
		(start 489.46181 -155.293314)
		(end 488.696 -155.293314)
		(width 0.254)
		(layer "F.Cu")
		(net "GND")
	)
	(segment
		(start 70.611746 -98.18624)
		(end 71.183246 -98.18624)
		(width 0.254)
		(layer "F.Cu")
		(net "GND")
	)
	(segment
		(start 77.299312 -5.822696)
		(end 77.299312 -7.607046)
		(width 0.4064)
		(layer "F.Cu")
		(net "GND")
	)
	(segment
		(start 180.6702 -58.1406)
		(end 180.9242 -57.8866)
		(width 0.381)
		(layer "F.Cu")
		(net "GND")
	)
	(segment
		(start 459.169008 -136.779254)
		(end 458.728318 -137.219944)
		(width 0.254)
		(layer "F.Cu")
		(net "GND")
	)
	(segment
		(start 146.149568 -147.27174)
		(end 146.149568 -146.06905)
		(width 0.3556)
		(layer "F.Cu")
		(net "GND")
	)
	(segment
		(start 402.259292 -99.363276)
		(end 402.260308 -99.364292)
		(width 0.254)
		(layer "F.Cu")
		(net "GND")
	)
	(segment
		(start 206.59979 -152.278842)
		(end 206.59979 -153.965402)
		(width 0.4064)
		(layer "F.Cu")
		(net "GND")
	)
	(segment
		(start 144.449546 0.444754)
		(end 144.449546 -0.821182)
		(width 0.4064)
		(layer "F.Cu")
		(net "GND")
	)
	(segment
		(start 59.449462 -2.314956)
		(end 59.449462 -0.821182)
		(width 0.4064)
		(layer "F.Cu")
		(net "GND")
	)
	(segment
		(start 448.534028 -50.73904)
		(end 448.533266 -50.6222)
		(width 0.508)
		(layer "F.Cu")
		(net "GND")
	)
	(segment
		(start 146.092164 -136.410446)
		(end 146.092164 -136.397746)
		(width 0.3556)
		(layer "F.Cu")
		(net "GND")
	)
	(segment
		(start 486.41 -31.0642)
		(end 486.41 -32.3088)
		(width 0.254)
		(layer "F.Cu")
		(net "GND")
	)
	(segment
		(start 233.608118 -83.822286)
		(end 233.036618 -83.822286)
		(width 0.254)
		(layer "F.Cu")
		(net "GND")
	)
	(segment
		(start 378.546106 -120.259094)
		(end 378.82195 -120.387364)
		(width 0.254)
		(layer "F.Cu")
		(net "GND")
	)
	(segment
		(start 213.400386 -156.87294)
		(end 213.399878 -156.87294)
		(width 0.4064)
		(layer "F.Cu")
		(net "GND")
	)
	(segment
		(start 242.300506 -5.822442)
		(end 242.300506 -7.606284)
		(width 0.4064)
		(layer "F.Cu")
		(net "GND")
	)
	(segment
		(start 74.617326 -63.51524)
		(end 74.045826 -63.51524)
		(width 0.254)
		(layer "F.Cu")
		(net "GND")
	)
	(segment
		(start 83.202272 -59.55284)
		(end 82.630772 -59.55284)
		(width 0.254)
		(layer "F.Cu")
		(net "GND")
	)
	(segment
		(start 481.287836 -35.378644)
		(end 481.08108 -35.5854)
		(width 0.254)
		(layer "F.Cu")
		(net "GND")
	)
	(segment
		(start 387.985 -95.205042)
		(end 388.984998 -95.205042)
		(width 0.254)
		(layer "F.Cu")
		(net "GND")
	)
	(segment
		(start 418.909754 -51.43881)
		(end 418.180012 -51.43881)
		(width 0.254)
		(layer "F.Cu")
		(net "GND")
	)
	(segment
		(start 386.985002 -124.504958)
		(end 387.308852 -124.210826)
		(width 0.254)
		(layer "F.Cu")
		(net "GND")
	)
	(segment
		(start 401.295108 -124.544328)
		(end 401.295108 -124.660914)
		(width 0.254)
		(layer "F.Cu")
		(net "GND")
	)
	(segment
		(start 57.74944 -21.517356)
		(end 57.74944 -20.023582)
		(width 0.4064)
		(layer "F.Cu")
		(net "GND")
	)
	(segment
		(start 247.344184 -69.953886)
		(end 246.772684 -69.953886)
		(width 0.254)
		(layer "F.Cu")
		(net "GND")
	)
	(segment
		(start 284.799532 -133.891274)
		(end 284.341062 -134.349744)
		(width 0.4064)
		(layer "F.Cu")
		(net "GND")
	)
	(segment
		(start 36.499292 -133.891274)
		(end 36.040822 -134.349744)
		(width 0.4064)
		(layer "F.Cu")
		(net "GND")
	)
	(segment
		(start 301.241206 -85.127338)
		(end 301.812706 -85.127338)
		(width 0.3048)
		(layer "F.Cu")
		(net "GND")
	)
	(segment
		(start 311.15 -146.06905)
		(end 311.092596 -146.011646)
		(width 0.3556)
		(layer "F.Cu")
		(net "GND")
	)
	(segment
		(start 52.448968 -134.1882)
		(end 52.448968 -134.876794)
		(width 0.3556)
		(layer "F.Cu")
		(net "GND")
	)
	(segment
		(start 119.7991 3.778504)
		(end 119.7991 2.963926)
		(width 0.4064)
		(layer "F.Cu")
		(net "GND")
	)
	(segment
		(start 222.749872 -20.023582)
		(end 222.749872 -18.757646)
		(width 0.4064)
		(layer "F.Cu")
		(net "GND")
	)
	(segment
		(start 245.627144 -79.859886)
		(end 245.055644 -79.859886)
		(width 0.254)
		(layer "F.Cu")
		(net "GND")
	)
	(segment
		(start 107.051856 -60.362338)
		(end 106.480356 -60.362338)
		(width 0.254)
		(layer "F.Cu")
		(net "GND")
	)
	(segment
		(start 118.099332 0.38735)
		(end 118.041928 0.444754)
		(width 0.3556)
		(layer "F.Cu")
		(net "GND")
	)
	(segment
		(start 236.183678 -74.411586)
		(end 235.612178 -74.411586)
		(width 0.254)
		(layer "F.Cu")
		(net "GND")
	)
	(segment
		(start 134.523734 -85.127338)
		(end 135.095234 -85.127338)
		(width 0.254)
		(layer "F.Cu")
		(net "GND")
	)
	(segment
		(start 137.957814 -76.211938)
		(end 138.529314 -76.211938)
		(width 0.254)
		(layer "F.Cu")
		(net "GND")
	)
	(segment
		(start 376.428 -98.354896)
		(end 375.92 -98.354896)
		(width 0.254)
		(layer "F.Cu")
		(net "GND")
	)
	(segment
		(start 138.816334 -93.547184)
		(end 139.387834 -93.547184)
		(width 0.254)
		(layer "F.Cu")
		(net "GND")
	)
	(segment
		(start 169.789348 -64.3509)
		(end 169.789348 -63.769748)
		(width 0.2032)
		(layer "F.Cu")
		(net "GND")
	)
	(segment
		(start 287.50514 -98.005138)
		(end 288.07664 -98.005138)
		(width 0.254)
		(layer "F.Cu")
		(net "GND")
	)
	(segment
		(start 464.416394 -144.719802)
		(end 464.4898 -144.646396)
		(width 0.254)
		(layer "F.Cu")
		(net "GND")
	)
	(segment
		(start 124.221748 -76.211938)
		(end 124.793248 -76.211938)
		(width 0.254)
		(layer "F.Cu")
		(net "GND")
	)
	(segment
		(start 298.399962 -11.916156)
		(end 298.399962 -10.422382)
		(width 0.4064)
		(layer "F.Cu")
		(net "GND")
	)
	(segment
		(start 88.353392 -60.54344)
		(end 87.781892 -60.54344)
		(width 0.254)
		(layer "F.Cu")
		(net "GND")
	)
	(segment
		(start 271.193768 -62.838584)
		(end 270.571468 -62.838584)
		(width 0.254)
		(layer "F.Cu")
		(net "GND")
	)
	(segment
		(start 305.761644 -52.705)
		(end 305.816254 -52.705)
		(width 0.254)
		(layer "F.Cu")
		(net "GND")
	)
	(segment
		(start 239.749838 -137.67054)
		(end 239.749838 -136.410446)
		(width 0.4064)
		(layer "F.Cu")
		(net "GND")
	)
	(segment
		(start 352.668586 -8.9408)
		(end 351.5868 -8.9408)
		(width 0.254)
		(layer "F.Cu")
		(net "GND")
	)
	(segment
		(start 42.449496 -156.87294)
		(end 42.449496 -155.638246)
		(width 0.4064)
		(layer "F.Cu")
		(net "GND")
	)
	(segment
		(start 357.274368 -133.33857)
		(end 357.823262 -133.887464)
		(width 0.381)
		(layer "F.Cu")
		(net "GND")
	)
	(segment
		(start 374.674892 -125.357128)
		(end 374.3452 -125.68682)
		(width 0.254)
		(layer "F.Cu")
		(net "GND")
	)
	(segment
		(start 246.485664 -81.34604)
		(end 245.914164 -81.34604)
		(width 0.254)
		(layer "F.Cu")
		(net "GND")
	)
	(segment
		(start 191.262 -130.92938)
		(end 191.133984 -131.057396)
		(width 0.254)
		(layer "F.Cu")
		(net "GND")
	)
	(segment
		(start 236.350302 -152.273)
		(end 236.349794 -152.278842)
		(width 0.3556)
		(layer "F.Cu")
		(net "GND")
	)
	(segment
		(start 299.524166 -95.033084)
		(end 300.095666 -95.033084)
		(width 0.3048)
		(layer "F.Cu")
		(net "GND")
	)
	(segment
		(start 301.800006 0.38735)
		(end 301.800006 -0.821182)
		(width 0.3556)
		(layer "F.Cu")
		(net "GND")
	)
	(segment
		(start 56.899302 -133.255766)
		(end 56.899302 -134.861046)
		(width 0.4064)
		(layer "F.Cu")
		(net "GND")
	)
	(segment
		(start 293.51478 -74.725784)
		(end 294.08628 -74.725784)
		(width 0.254)
		(layer "F.Cu")
		(net "GND")
	)
	(segment
		(start 62.849506 -156.87294)
		(end 62.849506 -155.67025)
		(width 0.3556)
		(layer "F.Cu")
		(net "GND")
	)
	(segment
		(start 352.9965 -150.368)
		(end 353.695 -150.368)
		(width 0.381)
		(layer "F.Cu")
		(net "GND")
	)
	(segment
		(start 77.192886 -88.775286)
		(end 76.621386 -88.775286)
		(width 0.254)
		(layer "F.Cu")
		(net "GND")
	)
	(segment
		(start 481.151946 -141.67866)
		(end 481.151946 -142.620746)
		(width 0.254)
		(layer "F.Cu")
		(net "GND")
	)
	(segment
		(start 96.086168 -150.256748)
		(end 95.555816 -150.7871)
		(width 0.4064)
		(layer "F.Cu")
		(net "GND")
	)
	(segment
		(start 142.749524 -147.27174)
		(end 142.749524 -145.998946)
		(width 0.4064)
		(layer "F.Cu")
		(net "GND")
	)
	(segment
		(start 312.849768 -15.423642)
		(end 312.849768 -14.409928)
		(width 0.4064)
		(layer "F.Cu")
		(net "GND")
	)
	(segment
		(start 423.090086 -32.934656)
		(end 423.490136 -32.534606)
		(width 0.254)
		(layer "F.Cu")
		(net "GND")
	)
	(segment
		(start 66.249296 -15.602966)
		(end 66.249296 -17.208246)
		(width 0.4064)
		(layer "F.Cu")
		(net "GND")
	)
	(segment
		(start 298.665646 -55.904384)
		(end 299.237146 -55.904384)
		(width 0.254)
		(layer "F.Cu")
		(net "GND")
	)
	(segment
		(start 463.000852 -116.993162)
		(end 463.000852 -118.615714)
		(width 0.4064)
		(layer "F.Cu")
		(net "GND")
	)
	(segment
		(start 407.403554 -149.21992)
		(end 407.403554 -149.72411)
		(width 0.3556)
		(layer "F.Cu")
		(net "GND")
	)
	(segment
		(start 278.061674 -88.594184)
		(end 278.061674 -88.022684)
		(width 0.381)
		(layer "F.Cu")
		(net "GND")
	)
	(segment
		(start 236.1184 -134.845806)
		(end 236.171994 -134.8994)
		(width 0.3556)
		(layer "F.Cu")
		(net "GND")
	)
	(segment
		(start 298.40047 -0.821182)
		(end 298.399962 -0.821182)
		(width 0.4064)
		(layer "F.Cu")
		(net "GND")
	)
	(segment
		(start 49.249584 -142.6718)
		(end 49.249584 -142.677642)
		(width 0.4064)
		(layer "F.Cu")
		(net "GND")
	)
	(segment
		(start 106.193336 -52.932838)
		(end 105.571036 -52.932838)
		(width 0.254)
		(layer "F.Cu")
		(net "GND")
	)
	(segment
		(start 229.54996 -152.278842)
		(end 229.549706 -152.279096)
		(width 0.4064)
		(layer "F.Cu")
		(net "GND")
	)
	(segment
		(start 383.764028 -23.270972)
		(end 382.797304 -23.270972)
		(width 0.254)
		(layer "F.Cu")
		(net "GND")
	)
	(segment
		(start 413.890206 -34.934652)
		(end 414.290256 -34.534602)
		(width 0.254)
		(layer "F.Cu")
		(net "GND")
	)
	(segment
		(start 141.899386 -17.208246)
		(end 141.899386 -15.423642)
		(width 0.4064)
		(layer "F.Cu")
		(net "GND")
	)
	(segment
		(start 229.549706 -6.637274)
		(end 229.549706 -5.822696)
		(width 0.4064)
		(layer "F.Cu")
		(net "GND")
	)
	(segment
		(start 294.3733 -52.437538)
		(end 294.373554 -52.437284)
		(width 0.254)
		(layer "F.Cu")
		(net "GND")
	)
	(segment
		(start 438.833006 -41.219374)
		(end 438.833006 -40.5257)
		(width 0.3556)
		(layer "F.Cu")
		(net "GND")
	)
	(segment
		(start 176.054004 -147.694142)
		(end 175.793146 -147.955)
		(width 0.254)
		(layer "F.Cu")
		(net "GND")
	)
	(segment
		(start 36.499292 -5.822696)
		(end 36.499546 -5.822442)
		(width 0.4064)
		(layer "F.Cu")
		(net "GND")
	)
	(segment
		(start 237.199932 -147.27174)
		(end 237.199932 -146.06905)
		(width 0.3556)
		(layer "F.Cu")
		(net "GND")
	)
	(segment
		(start 459.344776 -9.436608)
		(end 459.344776 -9.183624)
		(width 0.254)
		(layer "F.Cu")
		(net "GND")
	)
	(segment
		(start 195.550282 -15.423642)
		(end 195.549774 -15.423642)
		(width 0.4064)
		(layer "F.Cu")
		(net "GND")
	)
	(segment
		(start 284.071314 -58.381138)
		(end 283.499814 -58.381138)
		(width 0.254)
		(layer "F.Cu")
		(net "GND")
	)
	(segment
		(start 113.849404 3.778758)
		(end 113.849404 1.946148)
		(width 0.4064)
		(layer "F.Cu")
		(net "GND")
	)
	(segment
		(start 58.599578 -15.423642)
		(end 58.599324 -15.423896)
		(width 0.4064)
		(layer "F.Cu")
		(net "GND")
	)
	(segment
		(start 118.212362 -88.594184)
		(end 118.783862 -88.594184)
		(width 0.254)
		(layer "F.Cu")
		(net "GND")
	)
	(segment
		(start 70.324726 -64.010286)
		(end 69.753226 -64.010286)
		(width 0.254)
		(layer "F.Cu")
		(net "GND")
	)
	(segment
		(start 376.71121 -115.412266)
		(end 376.335036 -114.85499)
		(width 0.254)
		(layer "F.Cu")
		(net "GND")
	)
	(segment
		(start 268.679168 -3.3528)
		(end 267.794232 -3.3528)
		(width 0.381)
		(layer "F.Cu")
		(net "GND")
	)
	(segment
		(start 340.614 -11.684)
		(end 340.6394 -11.7094)
		(width 0.254)
		(layer "F.Cu")
		(net "GND")
	)
	(segment
		(start 27.432 -63.32982)
		(end 27.432 -63.559436)
		(width 0.508)
		(layer "F.Cu")
		(net "GND")
	)
	(segment
		(start 71.183246 -83.32724)
		(end 70.611746 -83.32724)
		(width 0.254)
		(layer "F.Cu")
		(net "GND")
	)
	(segment
		(start 151.257 -25.908)
		(end 151.257 -26.56586)
		(width 0.508)
		(layer "F.Cu")
		(net "GND")
	)
	(segment
		(start 282.354274 -96.023938)
		(end 282.925774 -96.023938)
		(width 0.254)
		(layer "F.Cu")
		(net "GND")
	)
	(segment
		(start 471.800936 -118.566184)
		(end 471.79992 -118.5672)
		(width 0.4064)
		(layer "F.Cu")
		(net "GND")
	)
	(segment
		(start 378.82195 -117.58168)
		(end 379.31725 -117.811804)
		(width 0.254)
		(layer "F.Cu")
		(net "GND")
	)
	(segment
		(start 108.768896 -90.080338)
		(end 109.340396 -90.080338)
		(width 0.254)
		(layer "F.Cu")
		(net "GND")
	)
	(segment
		(start 289.049968 -20.023582)
		(end 289.049968 -21.517356)
		(width 0.4064)
		(layer "F.Cu")
		(net "GND")
	)
	(segment
		(start 76.334366 -64.50584)
		(end 75.762866 -64.50584)
		(width 0.254)
		(layer "F.Cu")
		(net "GND")
	)
	(segment
		(start 29.807916 -22.994366)
		(end 30.30855 -23.495)
		(width 0.254)
		(layer "F.Cu")
		(net "GND")
	)
	(segment
		(start 292.65626 -87.108538)
		(end 293.22776 -87.108538)
		(width 0.254)
		(layer "F.Cu")
		(net "GND")
	)
	(segment
		(start 227.849938 -146.06905)
		(end 227.792534 -146.011646)
		(width 0.3556)
		(layer "F.Cu")
		(net "GND")
	)
	(segment
		(start 170.631358 -7.7724)
		(end 170.9166 -7.7724)
		(width 0.4064)
		(layer "F.Cu")
		(net "GND")
	)
	(segment
		(start 122.121168 -100.64877)
		(end 121.646188 -101.471984)
		(width 0.254)
		(layer "F.Cu")
		(net "GND")
	)
	(segment
		(start 248.202704 -94.223586)
		(end 247.631204 -94.223586)
		(width 0.254)
		(layer "F.Cu")
		(net "GND")
	)
	(segment
		(start 280.637234 -92.061538)
		(end 281.208734 -92.061538)
		(width 0.254)
		(layer "F.Cu")
		(net "GND")
	)
	(segment
		(start 483.8954 -136.652)
		(end 483.8954 -135.636)
		(width 0.254)
		(layer "F.Cu")
		(net "GND")
	)
	(segment
		(start 115.460526 -14.1224)
		(end 115.460526 -13.338556)
		(width 0.4064)
		(layer "F.Cu")
		(net "GND")
	)
	(segment
		(start 314.54979 -5.822442)
		(end 314.54979 -3.762756)
		(width 0.4064)
		(layer "F.Cu")
		(net "GND")
	)
	(segment
		(start 113.348262 -55.409338)
		(end 113.919762 -55.409338)
		(width 0.254)
		(layer "F.Cu")
		(net "GND")
	)
	(segment
		(start 58.599578 -3.76301)
		(end 58.599578 -5.822442)
		(width 0.4064)
		(layer "F.Cu")
		(net "GND")
	)
	(segment
		(start 394.903706 -98.58629)
		(end 395.16685 -98.464116)
		(width 0.254)
		(layer "F.Cu")
		(net "GND")
	)
	(segment
		(start 197.249796 -133.076442)
		(end 197.249796 -134.763002)
		(width 0.4064)
		(layer "F.Cu")
		(net "GND")
	)
	(segment
		(start 307.750464 -20.023582)
		(end 307.749956 -20.023582)
		(width 0.4064)
		(layer "F.Cu")
		(net "GND")
	)
	(segment
		(start 109.2581 -140.208)
		(end 110.111032 -140.208)
		(width 0.4064)
		(layer "F.Cu")
		(net "GND")
	)
	(segment
		(start 499.124478 -44.817538)
		(end 498.593618 -44.817538)
		(width 0.254)
		(layer "F.Cu")
		(net "GND")
	)
	(segment
		(start 494.31067 -58.866024)
		(end 495.2746 -59.829954)
		(width 0.254)
		(layer "F.Cu")
		(net "GND")
	)
	(segment
		(start 279.699974 -20.023582)
		(end 279.699974 -21.517356)
		(width 0.4064)
		(layer "F.Cu")
		(net "GND")
	)
	(segment
		(start 401.3581 -83.688682)
		(end 401.3581 -84.328)
		(width 0.254)
		(layer "F.Cu")
		(net "GND")
	)
	(segment
		(start 113.849404 -142.677642)
		(end 113.849404 -144.5768)
		(width 0.4064)
		(layer "F.Cu")
		(net "GND")
	)
	(segment
		(start 463.782918 -37.3888)
		(end 463.795618 -37.3761)
		(width 0.4064)
		(layer "F.Cu")
		(net "GND")
	)
	(segment
		(start 287.21812 -73.735184)
		(end 286.64662 -73.735184)
		(width 0.254)
		(layer "F.Cu")
		(net "GND")
	)
	(segment
		(start 381.79375 -119.29872)
		(end 382.1684 -119.47271)
		(width 0.254)
		(layer "F.Cu")
		(net "GND")
	)
	(segment
		(start 198.772018 -7.6454)
		(end 198.755 -7.628382)
		(width 0.3556)
		(layer "F.Cu")
		(net "GND")
	)
	(segment
		(start 83.202272 -82.33664)
		(end 82.630772 -82.33664)
		(width 0.254)
		(layer "F.Cu")
		(net "GND")
	)
	(segment
		(start 399.634964 -105.855008)
		(end 399.12925 -105.332276)
		(width 0.254)
		(layer "F.Cu")
		(net "GND")
	)
	(segment
		(start 481.271834 -35.362642)
		(end 481.271834 -35.222434)
		(width 0.254)
		(layer "F.Cu")
		(net "GND")
	)
	(segment
		(start 242.193318 -90.756486)
		(end 241.621818 -90.756486)
		(width 0.254)
		(layer "F.Cu")
		(net "GND")
	)
	(segment
		(start 47.549562 -142.856712)
		(end 47.549308 -142.856966)
		(width 0.4064)
		(layer "F.Cu")
		(net "GND")
	)
	(segment
		(start 72.1995 -10.422382)
		(end 72.1995 -11.854688)
		(width 0.4064)
		(layer "F.Cu")
		(net "GND")
	)
	(segment
		(start 221.04985 -156.87294)
		(end 221.050358 -156.87294)
		(width 0.4064)
		(layer "F.Cu")
		(net "GND")
	)
	(segment
		(start 399.674334 -94.179898)
		(end 399.76933 -94.274894)
		(width 0.254)
		(layer "F.Cu")
		(net "GND")
	)
	(segment
		(start 196.527928 -86.355682)
		(end 196.684138 -86.355682)
		(width 0.4064)
		(layer "F.Cu")
		(net "GND")
	)
	(segment
		(start 122.349514 -18.757646)
		(end 122.349514 -20.023582)
		(width 0.4064)
		(layer "F.Cu")
		(net "GND")
	)
	(segment
		(start 36.499292 2.963926)
		(end 36.040822 2.505456)
		(width 0.4064)
		(layer "F.Cu")
		(net "GND")
	)
	(segment
		(start 378.484892 -124.919994)
		(end 378.484892 -124.384308)
		(width 0.254)
		(layer "F.Cu")
		(net "GND")
	)
	(segment
		(start 117.015768 -134.84352)
		(end 117.071648 -134.8994)
		(width 0.3556)
		(layer "F.Cu")
		(net "GND")
	)
	(segment
		(start 92.645738 -95.709486)
		(end 92.074238 -95.709486)
		(width 0.254)
		(layer "F.Cu")
		(net "GND")
	)
	(segment
		(start 129.999486 -11.916156)
		(end 128.674368 -11.938)
		(width 0.254)
		(layer "F.Cu")
		(net "GND")
	)
	(segment
		(start 205.749906 -139.170156)
		(end 205.749906 -137.67054)
		(width 0.4064)
		(layer "F.Cu")
		(net "GND")
	)
	(segment
		(start 78.14945 -145.988278)
		(end 78.14945 -147.27174)
		(width 0.4064)
		(layer "F.Cu")
		(net "GND")
	)
	(segment
		(start 292.36924 -53.923184)
		(end 292.65626 -53.636164)
		(width 0.254)
		(layer "F.Cu")
		(net "GND")
	)
	(segment
		(start 9.81583 -43.87596)
		(end 11.249914 -45.310044)
		(width 0.508)
		(layer "F.Cu")
		(net "GND")
	)
	(segment
		(start 257.64617 -53.113686)
		(end 257.07467 -53.113686)
		(width 0.254)
		(layer "F.Cu")
		(net "GND")
	)
	(segment
		(start 383.77622 -29.27096)
		(end 383.95529 -29.09189)
		(width 0.254)
		(layer "F.Cu")
		(net "GND")
	)
	(segment
		(start 64.087502 -4.346956)
		(end 64.549528 -4.808982)
		(width 0.4064)
		(layer "F.Cu")
		(net "GND")
	)
	(segment
		(start 390.21385 -99.55276)
		(end 390.70915 -99.322636)
		(width 0.254)
		(layer "F.Cu")
		(net "GND")
	)
	(segment
		(start 126.797308 -93.547184)
		(end 127.368808 -93.547184)
		(width 0.254)
		(layer "F.Cu")
		(net "GND")
	)
	(segment
		(start 241.334798 -80.35544)
		(end 240.763298 -80.35544)
		(width 0.254)
		(layer "F.Cu")
		(net "GND")
	)
	(segment
		(start 385.75615 -98.69424)
		(end 386.25145 -98.464116)
		(width 0.254)
		(layer "F.Cu")
		(net "GND")
	)
	(segment
		(start 73.437496 -13.948156)
		(end 73.899522 -14.410182)
		(width 0.4064)
		(layer "F.Cu")
		(net "GND")
	)
	(segment
		(start 20.0914 -99.2124)
		(end 19.6342 -99.2124)
		(width 0.254)
		(layer "F.Cu")
		(net "GND")
	)
	(segment
		(start 229.550468 -15.423642)
		(end 229.54996 -15.423642)
		(width 0.4064)
		(layer "F.Cu")
		(net "GND")
	)
	(segment
		(start 96.079818 -98.681286)
		(end 95.508318 -98.681286)
		(width 0.254)
		(layer "F.Cu")
		(net "GND")
	)
	(segment
		(start 206.501746 -17.208246)
		(end 206.59979 -17.110202)
		(width 0.4064)
		(layer "F.Cu")
		(net "GND")
	)
	(segment
		(start 356.09784 -133.33857)
		(end 356.98684 -133.33857)
		(width 0.4064)
		(layer "F.Cu")
		(net "GND")
	)
	(segment
		(start 499.143528 -121.404888)
		(end 499.143528 -121.310146)
		(width 0.508)
		(layer "F.Cu")
		(net "GND")
	)
	(segment
		(start 395.224 -121.90095)
		(end 395.66215 -122.104404)
		(width 0.254)
		(layer "F.Cu")
		(net "GND")
	)
	(segment
		(start 317.950342 3.778758)
		(end 317.949834 3.778758)
		(width 0.4064)
		(layer "F.Cu")
		(net "GND")
	)
	(segment
		(start 112.202722 -61.352938)
		(end 111.631222 -61.352938)
		(width 0.254)
		(layer "F.Cu")
		(net "GND")
	)
	(segment
		(start 454.949814 -53.236114)
		(end 454.942702 -52.2478)
		(width 0.4064)
		(layer "F.Cu")
		(net "GND")
	)
	(segment
		(start 289.899852 -7.509002)
		(end 289.899852 -5.822442)
		(width 0.4064)
		(layer "F.Cu")
		(net "GND")
	)
	(segment
		(start 379.81255 -112.43056)
		(end 380.30785 -112.660684)
		(width 0.254)
		(layer "F.Cu")
		(net "GND")
	)
	(segment
		(start 317.09995 -129.579878)
		(end 317.246 -129.725928)
		(width 0.4064)
		(layer "F.Cu")
		(net "GND")
	)
	(segment
		(start 442.293756 -148.453602)
		(end 442.564774 -148.72462)
		(width 0.254)
		(layer "F.Cu")
		(net "GND")
	)
	(segment
		(start 246.485664 -76.39304)
		(end 245.914164 -76.39304)
		(width 0.254)
		(layer "F.Cu")
		(net "GND")
	)
	(segment
		(start 300.382686 -62.838584)
		(end 300.954186 -62.838584)
		(width 0.254)
		(layer "F.Cu")
		(net "GND")
	)
	(segment
		(start 285.649924 -21.517356)
		(end 285.649924 -20.023582)
		(width 0.4064)
		(layer "F.Cu")
		(net "GND")
	)
	(segment
		(start 379.48489 -94.790006)
		(end 379.985016 -95.205042)
		(width 0.254)
		(layer "F.Cu")
		(net "GND")
	)
	(segment
		(start 278.849836 -142.677642)
		(end 278.849836 -144.5768)
		(width 0.4064)
		(layer "F.Cu")
		(net "GND")
	)
	(segment
		(start 287.21812 -96.518984)
		(end 286.64662 -96.518984)
		(width 0.254)
		(layer "F.Cu")
		(net "GND")
	)
	(segment
		(start 116.399564 -20.023582)
		(end 116.399564 -21.479256)
		(width 0.4064)
		(layer "F.Cu")
		(net "GND")
	)
	(segment
		(start 240.599722 -142.856966)
		(end 240.599722 -144.462246)
		(width 0.4064)
		(layer "F.Cu")
		(net "GND")
	)
	(segment
		(start 239.617758 -85.30844)
		(end 239.046258 -85.30844)
		(width 0.254)
		(layer "F.Cu")
		(net "GND")
	)
	(segment
		(start 382.9304 -96.909382)
		(end 383.27965 -96.747076)
		(width 0.254)
		(layer "F.Cu")
		(net "GND")
	)
	(segment
		(start 114.778282 -62.838584)
		(end 114.206782 -62.838584)
		(width 0.254)
		(layer "F.Cu")
		(net "GND")
	)
	(segment
		(start 243.910104 -60.047886)
		(end 243.338604 -60.047886)
		(width 0.254)
		(layer "F.Cu")
		(net "GND")
	)
	(segment
		(start 312.387996 -4.346956)
		(end 312.849768 -4.808728)
		(width 0.4064)
		(layer "F.Cu")
		(net "GND")
	)
	(segment
		(start 137.957814 -57.390538)
		(end 138.529314 -57.390538)
		(width 0.254)
		(layer "F.Cu")
		(net "GND")
	)
	(segment
		(start 73.899522 -142.6718)
		(end 73.899522 -142.677642)
		(width 0.4064)
		(layer "F.Cu")
		(net "GND")
	)
	(segment
		(start 300.382686 -78.688438)
		(end 300.954186 -78.688438)
		(width 0.254)
		(layer "F.Cu")
		(net "GND")
	)
	(segment
		(start 70.611746 -93.23324)
		(end 71.183246 -93.23324)
		(width 0.254)
		(layer "F.Cu")
		(net "GND")
	)
	(segment
		(start 127.392176 -21.513292)
		(end 127.44958 -21.455888)
		(width 0.4064)
		(layer "F.Cu")
		(net "GND")
	)
	(segment
		(start 392.216386 -6.874256)
		(end 392.470386 -7.128256)
		(width 0.254)
		(layer "F.Cu")
		(net "GND")
	)
	(segment
		(start 221.899734 -133.255766)
		(end 221.899734 -134.861046)
		(width 0.4064)
		(layer "F.Cu")
		(net "GND")
	)
	(segment
		(start 110.772702 -54.913784)
		(end 111.344202 -54.913784)
		(width 0.254)
		(layer "F.Cu")
		(net "GND")
	)
	(segment
		(start 135.099552 0.444754)
		(end 135.099552 -0.821182)
		(width 0.4064)
		(layer "F.Cu")
		(net "GND")
	)
	(segment
		(start 384.1369 -113.8555)
		(end 384.53695 -114.25555)
		(width 0.12446)
		(layer "F.Cu")
		(net "GND")
	)
	(segment
		(start 51.79949 -137.67054)
		(end 51.79949 -136.410446)
		(width 0.4064)
		(layer "F.Cu")
		(net "GND")
	)
	(segment
		(start 101.230684 -63.019686)
		(end 100.659184 -63.019686)
		(width 0.254)
		(layer "F.Cu")
		(net "GND")
	)
	(segment
		(start 107.051856 -90.080338)
		(end 107.623356 -90.080338)
		(width 0.254)
		(layer "F.Cu")
		(net "GND")
	)
	(segment
		(start 110.485682 -63.334138)
		(end 109.914182 -63.334138)
		(width 0.254)
		(layer "F.Cu")
		(net "GND")
	)
	(segment
		(start 286.93364 -52.437538)
		(end 286.64662 -52.932838)
		(width 0.254)
		(layer "F.Cu")
		(net "GND")
	)
	(segment
		(start 284.800294 -5.822442)
		(end 284.799786 -5.822442)
		(width 0.4064)
		(layer "F.Cu")
		(net "GND")
	)
	(segment
		(start 184.2516 -76.45654)
		(end 184.7342 -76.93914)
		(width 0.508)
		(layer "F.Cu")
		(net "GND")
	)
	(segment
		(start 289.90036 -142.6718)
		(end 289.899852 -142.677642)
		(width 0.4064)
		(layer "F.Cu")
		(net "GND")
	)
	(segment
		(start 406.66924 -101.85654)
		(end 406.41778 -102.108)
		(width 0.254)
		(layer "F.Cu")
		(net "GND")
	)
	(segment
		(start 313.699906 -137.67054)
		(end 313.699906 -136.410446)
		(width 0.4064)
		(layer "F.Cu")
		(net "GND")
	)
	(segment
		(start 31.39948 -10.422382)
		(end 31.39948 -11.916156)
		(width 0.4064)
		(layer "F.Cu")
		(net "GND")
	)
	(segment
		(start 0.07112 -133.1849)
		(end 0.18034 -133.07568)
		(width 0.254)
		(layer "F.Cu")
		(net "GND")
	)
	(segment
		(start 297.807126 -60.362338)
		(end 298.378626 -60.362338)
		(width 0.254)
		(layer "F.Cu")
		(net "GND")
	)
	(segment
		(start 72.041766 -65.991486)
		(end 71.470266 -65.991486)
		(width 0.254)
		(layer "F.Cu")
		(net "GND")
	)
	(segment
		(start 420.690294 -32.134556)
		(end 421.09009 -31.73476)
		(width 0.3048)
		(layer "F.Cu")
		(net "GND")
	)
	(segment
		(start 237.20044 -20.023582)
		(end 237.199932 -20.023582)
		(width 0.3556)
		(layer "F.Cu")
		(net "GND")
	)
	(segment
		(start 135.099552 -21.479256)
		(end 135.061452 -21.517356)
		(width 0.4064)
		(layer "F.Cu")
		(net "GND")
	)
	(segment
		(start 291.79774 -65.810384)
		(end 292.36924 -65.810384)
		(width 0.254)
		(layer "F.Cu")
		(net "GND")
	)
	(segment
		(start 74.617326 -87.28964)
		(end 74.045826 -87.28964)
		(width 0.254)
		(layer "F.Cu")
		(net "GND")
	)
	(segment
		(start 285.2166 -62.343538)
		(end 285.7881 -62.343538)
		(width 0.254)
		(layer "F.Cu")
		(net "GND")
	)
	(segment
		(start 500.579898 -50.306986)
		(end 499.825518 -51.061366)
		(width 0.254)
		(layer "F.Cu")
		(net "GND")
	)
	(segment
		(start 300.772068 -3.762756)
		(end 300.949868 -3.940556)
		(width 0.4064)
		(layer "F.Cu")
		(net "GND")
	)
	(segment
		(start 71.117968 -17.193006)
		(end 71.171562 -17.2466)
		(width 0.3556)
		(layer "F.Cu")
		(net "GND")
	)
	(segment
		(start 278.849836 -152.278842)
		(end 278.849836 -154.111452)
		(width 0.4064)
		(layer "F.Cu")
		(net "GND")
	)
	(segment
		(start -1.93421 -46.744128)
		(end -0.500126 -45.310044)
		(width 0.508)
		(layer "F.Cu")
		(net "GND")
	)
	(segment
		(start 281.399996 -21.479256)
		(end 281.399996 -20.023582)
		(width 0.4064)
		(layer "F.Cu")
		(net "GND")
	)
	(segment
		(start 239.617758 -95.21444)
		(end 239.046258 -95.21444)
		(width 0.254)
		(layer "F.Cu")
		(net "GND")
	)
	(segment
		(start 117.249448 -3.940556)
		(end 117.249448 -5.822442)
		(width 0.4064)
		(layer "F.Cu")
		(net "GND")
	)
	(segment
		(start 352.711258 -8.898128)
		(end 352.668586 -8.9408)
		(width 0.254)
		(layer "F.Cu")
		(net "GND")
	)
	(segment
		(start 233.799888 -21.517356)
		(end 233.799888 -20.023582)
		(width 0.4064)
		(layer "F.Cu")
		(net "GND")
	)
	(segment
		(start 69.466206 -98.18624)
		(end 70.611746 -98.18624)
		(width 0.254)
		(layer "F.Cu")
		(net "GND")
	)
	(segment
		(start 134.523734 -70.268084)
		(end 135.095234 -70.268084)
		(width 0.254)
		(layer "F.Cu")
		(net "GND")
	)
	(segment
		(start 81.485232 -98.18624)
		(end 80.913732 -98.18624)
		(width 0.254)
		(layer "F.Cu")
		(net "GND")
	)
	(segment
		(start 378.985018 -95.205042)
		(end 377.98502 -95.205042)
		(width 0.254)
		(layer "F.Cu")
		(net "GND")
	)
	(segment
		(start 456.1713 -26.616914)
		(end 456.198986 -26.589228)
		(width 0.254)
		(layer "F.Cu")
		(net "GND")
	)
	(segment
		(start 287.350454 -156.87294)
		(end 287.350454 -155.613354)
		(width 0.3556)
		(layer "F.Cu")
		(net "GND")
	)
	(segment
		(start 132.549392 -142.6718)
		(end 132.549392 -144.462246)
		(width 0.4064)
		(layer "F.Cu")
		(net "GND")
	)
	(segment
		(start 69.64934 2.092198)
		(end 69.551296 1.994154)
		(width 0.4064)
		(layer "F.Cu")
		(net "GND")
	)
	(segment
		(start 206.59979 -134.763002)
		(end 206.501746 -134.861046)
		(width 0.4064)
		(layer "F.Cu")
		(net "GND")
	)
	(segment
		(start 317.100458 -5.822442)
		(end 317.09995 -5.822442)
		(width 0.4064)
		(layer "F.Cu")
		(net "GND")
	)
	(segment
		(start 401.361148 -96.816672)
		(end 401.859496 -96.815656)
		(width 0.254)
		(layer "F.Cu")
		(net "GND")
	)
	(segment
		(start 350.1136 -149.112224)
		(end 350.1136 -148.825712)
		(width 0.4064)
		(layer "F.Cu")
		(net "GND")
	)
	(segment
		(start 39.049452 -139.170156)
		(end 39.049452 -137.67054)
		(width 0.4064)
		(layer "F.Cu")
		(net "GND")
	)
	(segment
		(start 296.948606 -76.706984)
		(end 297.520106 -76.706984)
		(width 0.254)
		(layer "F.Cu")
		(net "GND")
	)
	(segment
		(start 33.099502 -2.276856)
		(end 33.061402 -2.314956)
		(width 0.4064)
		(layer "F.Cu")
		(net "GND")
	)
	(segment
		(start 237.900718 -94.223586)
		(end 237.329218 -94.223586)
		(width 0.254)
		(layer "F.Cu")
		(net "GND")
	)
	(segment
		(start 129.372868 -96.023938)
		(end 129.944368 -96.023938)
		(width 0.254)
		(layer "F.Cu")
		(net "GND")
	)
	(segment
		(start 388.53745 -111.85525)
		(end 388.9375 -112.2553)
		(width 0.12446)
		(layer "F.Cu")
		(net "GND")
	)
	(segment
		(start 467.26348 -114.41176)
		(end 467.800944 -113.874296)
		(width 0.254)
		(layer "F.Cu")
		(net "GND")
	)
	(segment
		(start 225.300286 3.778758)
		(end 225.299778 3.778758)
		(width 0.4064)
		(layer "F.Cu")
		(net "GND")
	)
	(segment
		(start 477.14916 -33.9725)
		(end 477.14916 -34.52876)
		(width 0.254)
		(layer "F.Cu")
		(net "GND")
	)
	(segment
		(start 243.910104 -61.038486)
		(end 243.338604 -61.038486)
		(width 0.254)
		(layer "F.Cu")
		(net "GND")
	)
	(segment
		(start 181.847998 -5.459984)
		(end 182.30088 -5.912866)
		(width 0.4064)
		(layer "F.Cu")
		(net "GND")
	)
	(segment
		(start 58.599324 -5.822696)
		(end 58.599324 -7.607046)
		(width 0.4064)
		(layer "F.Cu")
		(net "GND")
	)
	(segment
		(start 374.3452 -125.68682)
		(end 374.3452 -125.9332)
		(width 0.254)
		(layer "F.Cu")
		(net "GND")
	)
	(segment
		(start 249.9106 -140.208)
		(end 250.7615 -140.208)
		(width 0.4572)
		(layer "F.Cu")
		(net "GND")
	)
	(segment
		(start 107.051856 -101.967538)
		(end 107.623102 -101.967538)
		(width 0.254)
		(layer "F.Cu")
		(net "GND")
	)
	(segment
		(start 290.750498 -147.27174)
		(end 290.74999 -147.27174)
		(width 0.4064)
		(layer "F.Cu")
		(net "GND")
	)
	(segment
		(start 52.649374 -133.809994)
		(end 52.448968 -134.0104)
		(width 0.3048)
		(layer "F.Cu")
		(net "GND")
	)
	(segment
		(start 384.76555 -119.29872)
		(end 385.26085 -119.528844)
		(width 0.254)
		(layer "F.Cu")
		(net "GND")
	)
	(segment
		(start 56.899556 -15.602712)
		(end 56.899302 -15.602966)
		(width 0.4064)
		(layer "F.Cu")
		(net "GND")
	)
	(segment
		(start 311.150508 -147.27174)
		(end 311.15 -147.27174)
		(width 0.3556)
		(layer "F.Cu")
		(net "GND")
	)
	(segment
		(start 206.600298 -133.0706)
		(end 206.59979 -133.076442)
		(width 0.4064)
		(layer "F.Cu")
		(net "GND")
	)
	(segment
		(start 146.092164 -9.156446)
		(end 146.149568 -9.21385)
		(width 0.3556)
		(layer "F.Cu")
		(net "GND")
	)
	(segment
		(start 149.549358 -5.822442)
		(end 149.549358 -3.762756)
		(width 0.4064)
		(layer "F.Cu")
		(net "GND")
	)
	(segment
		(start 198.755 -6.731)
		(end 198.949818 -6.536182)
		(width 0.3556)
		(layer "F.Cu")
		(net "GND")
	)
	(segment
		(start 123.363228 -59.866784)
		(end 122.791728 -59.866784)
		(width 0.254)
		(layer "F.Cu")
		(net "GND")
	)
	(segment
		(start 223.599756 -133.076696)
		(end 223.599756 -134.861046)
		(width 0.4064)
		(layer "F.Cu")
		(net "GND")
	)
	(segment
		(start 70.324726 -62.029086)
		(end 69.753226 -62.029086)
		(width 0.254)
		(layer "F.Cu")
		(net "GND")
	)
	(segment
		(start 265.372596 -91.25204)
		(end 264.801096 -91.25204)
		(width 0.254)
		(layer "F.Cu")
		(net "GND")
	)
	(segment
		(start 113.061242 -94.538038)
		(end 113.632742 -94.538038)
		(width 0.254)
		(layer "F.Cu")
		(net "GND")
	)
	(segment
		(start 237.900718 -78.37424)
		(end 237.329218 -78.37424)
		(width 0.254)
		(layer "F.Cu")
		(net "GND")
	)
	(segment
		(start 377.33605 -120.15724)
		(end 377.83135 -120.387364)
		(width 0.254)
		(layer "F.Cu")
		(net "GND")
	)
	(segment
		(start 210.849972 -15.423642)
		(end 210.849972 -14.410182)
		(width 0.4064)
		(layer "F.Cu")
		(net "GND")
	)
	(segment
		(start 242.300506 -152.273)
		(end 242.299998 -152.273)
		(width 0.508)
		(layer "F.Cu")
		(net "GND")
	)
	(segment
		(start 274.627848 -95.528384)
		(end 275.199348 -95.528384)
		(width 0.1651)
		(layer "F.Cu")
		(net "GND")
	)
	(segment
		(start 13.716 -97.917)
		(end 14.605 -97.917)
		(width 0.4064)
		(layer "F.Cu")
		(net "GND")
	)
	(segment
		(start 223.600518 3.778758)
		(end 223.600518 1.994916)
		(width 0.4064)
		(layer "F.Cu")
		(net "GND")
	)
	(segment
		(start 115.636802 -62.343538)
		(end 115.065302 -62.343538)
		(width 0.254)
		(layer "F.Cu")
		(net "GND")
	)
	(segment
		(start 42.411396 -11.916156)
		(end 42.449496 -11.878056)
		(width 0.4064)
		(layer "F.Cu")
		(net "GND")
	)
	(segment
		(start 282.354274 -98.005138)
		(end 282.925774 -98.005138)
		(width 0.254)
		(layer "F.Cu")
		(net "GND")
	)
	(segment
		(start 193.5099 -69.99224)
		(end 193.5099 -68.803266)
		(width 0.254)
		(layer "F.Cu")
		(net "GND")
	)
	(segment
		(start 34.74212 -136.623298)
		(end 34.74212 -136.397746)
		(width 0.4064)
		(layer "F.Cu")
		(net "GND")
	)
	(segment
		(start 88.353392 -84.31784)
		(end 87.781892 -84.31784)
		(width 0.254)
		(layer "F.Cu")
		(net "GND")
	)
	(segment
		(start 302.958246 -91.278964)
		(end 302.671226 -91.565984)
		(width 0.254)
		(layer "F.Cu")
		(net "GND")
	)
	(segment
		(start 284.799786 -142.677642)
		(end 284.799532 -142.677896)
		(width 0.4064)
		(layer "F.Cu")
		(net "GND")
	)
	(segment
		(start 307.750464 -147.27174)
		(end 307.749956 -147.27174)
		(width 0.4064)
		(layer "F.Cu")
		(net "GND")
	)
	(segment
		(start 78.14945 -156.87294)
		(end 78.14945 -155.3464)
		(width 0.4064)
		(layer "F.Cu")
		(net "GND")
	)
	(segment
		(start 377.98502 -124.504958)
		(end 377.91771 -124.206)
		(width 0.254)
		(layer "F.Cu")
		(net "GND")
	)
	(segment
		(start 36.499292 -143.492474)
		(end 36.040822 -143.950944)
		(width 0.4064)
		(layer "F.Cu")
		(net "GND")
	)
	(segment
		(start 218.499944 -9.21385)
		(end 218.499944 -10.422382)
		(width 0.3556)
		(layer "F.Cu")
		(net "GND")
	)
	(segment
		(start 303.529746 -98.005138)
		(end 302.958246 -98.005138)
		(width 0.254)
		(layer "F.Cu")
		(net "GND")
	)
	(segment
		(start 382.33477 -124.206)
		(end 382.397 -124.15266)
		(width 0.254)
		(layer "F.Cu")
		(net "GND")
	)
	(segment
		(start 403.106382 -124.639832)
		(end 403.207982 -124.538232)
		(width 0.254)
		(layer "F.Cu")
		(net "GND")
	)
	(segment
		(start 398.13865 -109.855)
		(end 397.64335 -109.624876)
		(width 0.254)
		(layer "F.Cu")
		(net "GND")
	)
	(segment
		(start 132.806694 -71.258938)
		(end 133.378194 -71.258938)
		(width 0.254)
		(layer "F.Cu")
		(net "GND")
	)
	(segment
		(start 279.699974 -145.998946)
		(end 279.699974 -147.27174)
		(width 0.4064)
		(layer "F.Cu")
		(net "GND")
	)
	(segment
		(start 95.221298 -88.28024)
		(end 94.649798 -88.28024)
		(width 0.254)
		(layer "F.Cu")
		(net "GND")
	)
	(segment
		(start 447.74993 -60.847986)
		(end 447.942716 -60.6552)
		(width 0.381)
		(layer "F.Cu")
		(net "GND")
	)
	(segment
		(start 399.528538 -118.996714)
		(end 399.634964 -118.854982)
		(width 0.254)
		(layer "F.Cu")
		(net "GND")
	)
	(segment
		(start 291.79774 -71.753984)
		(end 292.36924 -71.753984)
		(width 0.254)
		(layer "F.Cu")
		(net "GND")
	)
	(segment
		(start 247.344184 -85.803486)
		(end 246.772684 -85.803486)
		(width 0.254)
		(layer "F.Cu")
		(net "GND")
	)
	(segment
		(start 299.249846 -17.110202)
		(end 299.151802 -17.208246)
		(width 0.4064)
		(layer "F.Cu")
		(net "GND")
	)
	(segment
		(start 249.061224 -92.737686)
		(end 248.489724 -92.737686)
		(width 0.254)
		(layer "F.Cu")
		(net "GND")
	)
	(segment
		(start 130.84937 -142.6718)
		(end 130.84937 -144.462246)
		(width 0.4064)
		(layer "F.Cu")
		(net "GND")
	)
	(segment
		(start 208.0768 -143.636746)
		(end 208.0768 -144.455388)
		(width 0.3556)
		(layer "F.Cu")
		(net "GND")
	)
	(segment
		(start 235.325158 -65.991486)
		(end 234.753658 -65.991486)
		(width 0.254)
		(layer "F.Cu")
		(net "GND")
	)
	(segment
		(start 400.465036 -116.854986)
		(end 399.634964 -116.854986)
		(width 0.254)
		(layer "F.Cu")
		(net "GND")
	)
	(segment
		(start 443.098174 -149.71522)
		(end 442.564774 -150.24862)
		(width 0.254)
		(layer "F.Cu")
		(net "GND")
	)
	(segment
		(start 367.6269 -136.4234)
		(end 368.0206 -136.4234)
		(width 0.4064)
		(layer "F.Cu")
		(net "GND")
	)
	(segment
		(start 399.634964 -112.854994)
		(end 399.634964 -113.854992)
		(width 0.254)
		(layer "F.Cu")
		(net "GND")
	)
	(segment
		(start 290.0807 -78.688438)
		(end 290.6522 -78.688438)
		(width 0.254)
		(layer "F.Cu")
		(net "GND")
	)
	(segment
		(start 398.73428 -131.5466)
		(end 399.9738 -131.5466)
		(width 0.4064)
		(layer "F.Cu")
		(net "GND")
	)
	(segment
		(start 394.17625 -108.766356)
		(end 394.17625 -109.13872)
		(width 0.254)
		(layer "F.Cu")
		(net "GND")
	)
	(segment
		(start 125.938788 -83.146138)
		(end 126.510288 -83.146138)
		(width 0.254)
		(layer "F.Cu")
		(net "GND")
	)
	(segment
		(start 420.3192 -3.5814)
		(end 420.473886 -3.736086)
		(width 0.254)
		(layer "F.Cu")
		(net "GND")
	)
	(segment
		(start 208.30032 -142.6718)
		(end 208.299812 -142.677642)
		(width 0.3556)
		(layer "F.Cu")
		(net "GND")
	)
	(segment
		(start 291.599874 -153.001726)
		(end 291.3888 -153.2128)
		(width 0.3556)
		(layer "F.Cu")
		(net "GND")
	)
	(segment
		(start 132.549392 -15.423642)
		(end 132.549392 -17.208246)
		(width 0.4064)
		(layer "F.Cu")
		(net "GND")
	)
	(segment
		(start 85.777832 -53.113686)
		(end 86.064852 -53.608732)
		(width 0.254)
		(layer "F.Cu")
		(net "GND")
	)
	(segment
		(start 238.8997 -5.822696)
		(end 238.8997 -6.637274)
		(width 0.4064)
		(layer "F.Cu")
		(net "GND")
	)
	(segment
		(start 36.499292 -16.238474)
		(end 36.040822 -16.696944)
		(width 0.4064)
		(layer "F.Cu")
		(net "GND")
	)
	(segment
		(start 278.896572 -134.913624)
		(end 278.849836 -134.866888)
		(width 0.4064)
		(layer "F.Cu")
		(net "GND")
	)
	(segment
		(start 347.5228 -156.7688)
		(end 347.6498 -156.6418)
		(width 0.4064)
		(layer "F.Cu")
		(net "GND")
	)
	(segment
		(start 130.231388 -90.575384)
		(end 130.802888 -90.575384)
		(width 0.254)
		(layer "F.Cu")
		(net "GND")
	)
	(segment
		(start 70.461378 -12.84859)
		(end 70.461378 -11.916156)
		(width 0.4064)
		(layer "F.Cu")
		(net "GND")
	)
	(segment
		(start 37.34943 -9.156446)
		(end 37.34943 -10.422382)
		(width 0.4064)
		(layer "F.Cu")
		(net "GND")
	)
	(segment
		(start 239.617758 -89.27084)
		(end 239.046258 -89.27084)
		(width 0.254)
		(layer "F.Cu")
		(net "GND")
	)
	(segment
		(start 280.549858 -152.278842)
		(end 280.549858 -153.965402)
		(width 0.4064)
		(layer "F.Cu")
		(net "GND")
	)
	(segment
		(start 442.293756 -147.621244)
		(end 442.293756 -148.453602)
		(width 0.254)
		(layer "F.Cu")
		(net "GND")
	)
	(segment
		(start 135.099552 -20.023582)
		(end 135.099552 -21.479256)
		(width 0.4064)
		(layer "F.Cu")
		(net "GND")
	)
	(segment
		(start 86.636352 -80.35544)
		(end 86.064852 -80.35544)
		(width 0.254)
		(layer "F.Cu")
		(net "GND")
	)
	(segment
		(start 114.699542 -10.422382)
		(end 114.699542 -9.143746)
		(width 0.4064)
		(layer "F.Cu")
		(net "GND")
	)
	(segment
		(start 393.68095 -108.99648)
		(end 393.94892 -109.13872)
		(width 0.254)
		(layer "F.Cu")
		(net "GND")
	)
	(segment
		(start 57.74944 -10.422382)
		(end 57.74944 -11.916156)
		(width 0.4064)
		(layer "F.Cu")
		(net "GND")
	)
	(segment
		(start 42.449496 -137.67054)
		(end 42.449496 -136.435846)
		(width 0.4064)
		(layer "F.Cu")
		(net "GND")
	)
	(segment
		(start 209.14995 -9.25195)
		(end 209.092546 -9.194546)
		(width 0.4064)
		(layer "F.Cu")
		(net "GND")
	)
	(segment
		(start 53.499512 -136.46785)
		(end 53.442108 -136.410446)
		(width 0.3556)
		(layer "F.Cu")
		(net "GND")
	)
	(segment
		(start 285.2166 -58.381138)
		(end 285.7881 -58.381138)
		(width 0.254)
		(layer "F.Cu")
		(net "GND")
	)
	(segment
		(start 247.344184 -88.775286)
		(end 246.772684 -88.775286)
		(width 0.254)
		(layer "F.Cu")
		(net "GND")
	)
	(segment
		(start 241.334798 -87.28964)
		(end 240.763298 -87.28964)
		(width 0.254)
		(layer "F.Cu")
		(net "GND")
	)
	(segment
		(start 209.14995 -10.422382)
		(end 209.14995 -9.25195)
		(width 0.4064)
		(layer "F.Cu")
		(net "GND")
	)
	(segment
		(start 282.354274 -54.418738)
		(end 281.782774 -54.418738)
		(width 0.254)
		(layer "F.Cu")
		(net "GND")
	)
	(segment
		(start 37.34943 -0.821182)
		(end 37.34943 0.444754)
		(width 0.4064)
		(layer "F.Cu")
		(net "GND")
	)
	(segment
		(start 285.7881 -73.240138)
		(end 286.3596 -73.240138)
		(width 0.254)
		(layer "F.Cu")
		(net "GND")
	)
	(segment
		(start 379.31725 -108.13796)
		(end 379.448314 -108.077)
		(width 0.254)
		(layer "F.Cu")
		(net "GND")
	)
	(segment
		(start 71.183246 -72.43064)
		(end 70.611746 -72.43064)
		(width 0.254)
		(layer "F.Cu")
		(net "GND")
	)
	(segment
		(start 131.948174 -88.594184)
		(end 132.519674 -88.594184)
		(width 0.254)
		(layer "F.Cu")
		(net "GND")
	)
	(segment
		(start 103.806244 -89.27084)
		(end 104.415844 -89.27084)
		(width 0.254)
		(layer "F.Cu")
		(net "GND")
	)
	(segment
		(start 237.142528 0.444754)
		(end 237.142528 0.457454)
		(width 0.3556)
		(layer "F.Cu")
		(net "GND")
	)
	(segment
		(start 252.495304 -98.681286)
		(end 252.782324 -99.17684)
		(width 0.254)
		(layer "F.Cu")
		(net "GND")
	)
	(segment
		(start 137.957814 -77.202538)
		(end 138.529314 -77.202538)
		(width 0.254)
		(layer "F.Cu")
		(net "GND")
	)
	(segment
		(start 143.599408 -5.822442)
		(end 143.599408 -7.509002)
		(width 0.4064)
		(layer "F.Cu")
		(net "GND")
	)
	(segment
		(start 309.449978 -18.757646)
		(end 309.449978 -20.023582)
		(width 0.4064)
		(layer "F.Cu")
		(net "GND")
	)
	(segment
		(start 144.449546 -11.878056)
		(end 144.449546 -10.422382)
		(width 0.4064)
		(layer "F.Cu")
		(net "GND")
	)
	(segment
		(start 301.241206 -72.249538)
		(end 301.812706 -72.249538)
		(width 0.254)
		(layer "F.Cu")
		(net "GND")
	)
	(segment
		(start 278.061674 -54.913784)
		(end 277.490174 -54.913784)
		(width 0.254)
		(layer "F.Cu")
		(net "GND")
	)
	(segment
		(start 278.061674 -94.538038)
		(end 278.633174 -94.538038)
		(width 0.254)
		(layer "F.Cu")
		(net "GND")
	)
	(segment
		(start 208.299812 -16.159734)
		(end 208.299812 -15.423642)
		(width 0.3556)
		(layer "F.Cu")
		(net "GND")
	)
	(segment
		(start 249.919744 -71.44004)
		(end 249.348244 -71.44004)
		(width 0.254)
		(layer "F.Cu")
		(net "GND")
	)
	(segment
		(start 130.84937 -17.208246)
		(end 130.84937 -15.423642)
		(width 0.4064)
		(layer "F.Cu")
		(net "GND")
	)
	(segment
		(start 273.769328 -58.381138)
		(end 273.197828 -58.381138)
		(width 0.254)
		(layer "F.Cu")
		(net "GND")
	)
	(segment
		(start 184.531 -5.1435)
		(end 183.388 -5.1435)
		(width 0.4064)
		(layer "F.Cu")
		(net "GND")
	)
	(segment
		(start 77.299312 3.778504)
		(end 77.299312 1.994154)
		(width 0.4064)
		(layer "F.Cu")
		(net "GND")
	)
	(segment
		(start 282.0162 -134.84352)
		(end 282.07208 -134.8994)
		(width 0.3556)
		(layer "F.Cu")
		(net "GND")
	)
	(segment
		(start 478.199958 -113.77422)
		(end 478.200974 -113.773204)
		(width 0.4064)
		(layer "F.Cu")
		(net "GND")
	)
	(segment
		(start 232.749598 -57.57164)
		(end 232.101898 -57.57164)
		(width 0.254)
		(layer "F.Cu")
		(net "GND")
	)
	(segment
		(start 210.85048 -5.822442)
		(end 210.849972 -5.822442)
		(width 0.4064)
		(layer "F.Cu")
		(net "GND")
	)
	(segment
		(start 490.474 -38.227)
		(end 491.871 -38.227)
		(width 0.254)
		(layer "F.Cu")
		(net "GND")
	)
	(segment
		(start 387.3373 -106.6546)
		(end 386.93725 -107.05465)
		(width 0.254)
		(layer "F.Cu")
		(net "GND")
	)
	(segment
		(start 115.549426 -5.822442)
		(end 115.549426 -7.509002)
		(width 0.4064)
		(layer "F.Cu")
		(net "GND")
	)
	(segment
		(start 237.042198 -69.953886)
		(end 236.470698 -69.953886)
		(width 0.254)
		(layer "F.Cu")
		(net "GND")
	)
	(segment
		(start 248.202704 -74.411586)
		(end 247.631204 -74.411586)
		(width 0.254)
		(layer "F.Cu")
		(net "GND")
	)
	(segment
		(start 432.623468 -50.482246)
		(end 432.623468 -49.928526)
		(width 0.254)
		(layer "F.Cu")
		(net "GND")
	)
	(segment
		(start 122.504708 -92.061538)
		(end 123.076208 -92.061538)
		(width 0.3048)
		(layer "F.Cu")
		(net "GND")
	)
	(segment
		(start 139.34948 -9.156446)
		(end 139.34948 -10.422382)
		(width 0.4064)
		(layer "F.Cu")
		(net "GND")
	)
	(segment
		(start 80.626712 -70.94474)
		(end 80.055212 -70.94474)
		(width 0.254)
		(layer "F.Cu")
		(net "GND")
	)
	(segment
		(start 290.0807 -94.538038)
		(end 290.6522 -94.538038)
		(width 0.3048)
		(layer "F.Cu")
		(net "GND")
	)
	(segment
		(start 397.300958 -124.504958)
		(end 396.984982 -124.504958)
		(width 0.254)
		(layer "F.Cu")
		(net "GND")
	)
	(segment
		(start 234.551728 -7.607046)
		(end 234.649772 -7.509002)
		(width 0.4064)
		(layer "F.Cu")
		(net "GND")
	)
	(segment
		(start 84.060792 -95.709486)
		(end 83.489292 -95.709486)
		(width 0.254)
		(layer "F.Cu")
		(net "GND")
	)
	(segment
		(start 432.475386 -3.672586)
		(end 432.475386 -4.386072)
		(width 0.254)
		(layer "F.Cu")
		(net "GND")
	)
	(segment
		(start 383.73685 -112.65535)
		(end 383.3368 -113.0554)
		(width 0.12446)
		(layer "F.Cu")
		(net "GND")
	)
	(segment
		(start 121.499376 -142.6718)
		(end 121.499376 -144.462246)
		(width 0.4064)
		(layer "F.Cu")
		(net "GND")
	)
	(segment
		(start 32.249364 -17.110202)
		(end 32.249364 -15.423642)
		(width 0.4064)
		(layer "F.Cu")
		(net "GND")
	)
	(segment
		(start 33.949386 -15.423642)
		(end 33.949386 -13.541756)
		(width 0.4064)
		(layer "F.Cu")
		(net "GND")
	)
	(segment
		(start 135.382254 -73.735184)
		(end 135.953754 -73.735184)
		(width 0.254)
		(layer "F.Cu")
		(net "GND")
	)
	(segment
		(start 321.591432 -3.302)
		(end 321.611244 -3.321812)
		(width 0.4064)
		(layer "F.Cu")
		(net "GND")
	)
	(segment
		(start 396.65275 -109.624876)
		(end 396.65275 -108.99648)
		(width 0.254)
		(layer "F.Cu")
		(net "GND")
	)
	(segment
		(start 249.919744 -88.28024)
		(end 249.348244 -88.28024)
		(width 0.254)
		(layer "F.Cu")
		(net "GND")
	)
	(segment
		(start 464.549744 -63.4746)
		(end 464.549744 -62.002924)
		(width 0.254)
		(layer "F.Cu")
		(net "GND")
	)
	(segment
		(start 196.743828 -53.856382)
		(end 196.566028 -53.856382)
		(width 0.4064)
		(layer "F.Cu")
		(net "GND")
	)
	(segment
		(start 306.899818 -142.677642)
		(end 306.899818 -144.462246)
		(width 0.4064)
		(layer "F.Cu")
		(net "GND")
	)
	(segment
		(start 290.6522 -70.763384)
		(end 290.0807 -70.763384)
		(width 0.254)
		(layer "F.Cu")
		(net "GND")
	)
	(segment
		(start 392.69035 -122.104404)
		(end 392.19505 -121.87428)
		(width 0.254)
		(layer "F.Cu")
		(net "GND")
	)
	(segment
		(start 2.3876 -134.9502)
		(end 2.5908 -134.747)
		(width 0.4064)
		(layer "F.Cu")
		(net "GND")
	)
	(segment
		(start 198.949818 -16.137382)
		(end 198.949818 -15.423642)
		(width 0.3556)
		(layer "F.Cu")
		(net "GND")
	)
	(segment
		(start 141.391894 -56.399938)
		(end 141.963394 -56.399938)
		(width 0.254)
		(layer "F.Cu")
		(net "GND")
	)
	(segment
		(start 376.20067 -125.447298)
		(end 375.482866 -126.165102)
		(width 0.254)
		(layer "F.Cu")
		(net "GND")
	)
	(segment
		(start 249.919744 -84.31784)
		(end 249.348244 -84.31784)
		(width 0.254)
		(layer "F.Cu")
		(net "GND")
	)
	(segment
		(start 282.354274 -93.052138)
		(end 282.925774 -93.052138)
		(width 0.254)
		(layer "F.Cu")
		(net "GND")
	)
	(segment
		(start 307.027326 -97.014538)
		(end 307.040026 -97.001838)
		(width 0.254)
		(layer "F.Cu")
		(net "GND")
	)
	(segment
		(start 70.324726 -65.991486)
		(end 69.753226 -65.991486)
		(width 0.254)
		(layer "F.Cu")
		(net "GND")
	)
	(segment
		(start 71.183246 -92.24264)
		(end 70.611746 -92.24264)
		(width 0.254)
		(layer "F.Cu")
		(net "GND")
	)
	(segment
		(start 310.0832 -134.860538)
		(end 310.122062 -134.8994)
		(width 0.3556)
		(layer "F.Cu")
		(net "GND")
	)
	(segment
		(start 416.165792 -128.740408)
		(end 416.406076 -128.980692)
		(width 0.381)
		(layer "F.Cu")
		(net "GND")
	)
	(segment
		(start 316.25032 -15.423642)
		(end 316.249812 -15.423642)
		(width 0.4064)
		(layer "F.Cu")
		(net "GND")
	)
	(segment
		(start 443.129162 -59.052206)
		(end 442.950092 -58.873136)
		(width 0.381)
		(layer "F.Cu")
		(net "GND")
	)
	(segment
		(start 296.66184 -83.146138)
		(end 296.09034 -83.146138)
		(width 0.254)
		(layer "F.Cu")
		(net "GND")
	)
	(segment
		(start 146.149568 -137.67054)
		(end 146.149568 -136.46785)
		(width 0.3556)
		(layer "F.Cu")
		(net "GND")
	)
	(segment
		(start 114.699542 -20.023582)
		(end 114.699542 -21.517356)
		(width 0.4064)
		(layer "F.Cu")
		(net "GND")
	)
	(segment
		(start 290.74999 -11.878056)
		(end 290.74999 -10.422382)
		(width 0.4064)
		(layer "F.Cu")
		(net "GND")
	)
	(segment
		(start 218.499944 0.38735)
		(end 218.44254 0.444754)
		(width 0.3556)
		(layer "F.Cu")
		(net "GND")
	)
	(segment
		(start 296.09034 -98.995738)
		(end 296.66184 -98.995738)
		(width 0.254)
		(layer "F.Cu")
		(net "GND")
	)
	(segment
		(start 131.948174 -94.538038)
		(end 132.519674 -94.538038)
		(width 0.254)
		(layer "F.Cu")
		(net "GND")
	)
	(segment
		(start 278.9174 -12.954)
		(end 277.397464 -12.954)
		(width 0.381)
		(layer "F.Cu")
		(net "GND")
	)
	(segment
		(start 266.231116 -53.113686)
		(end 265.659616 -53.113686)
		(width 0.254)
		(layer "F.Cu")
		(net "GND")
	)
	(segment
		(start 374.674892 -102.855014)
		(end 374.3579 -102.855014)
		(width 0.254)
		(layer "F.Cu")
		(net "GND")
	)
	(segment
		(start 408.472386 -4.386072)
		(end 408.472386 -3.387852)
		(width 0.254)
		(layer "F.Cu")
		(net "GND")
	)
	(segment
		(start 191.349122 -140.177012)
		(end 191.349122 -140.927582)
		(width 0.254)
		(layer "F.Cu")
		(net "GND")
	)
	(segment
		(start 300.949868 -5.822442)
		(end 300.949868 -6.567678)
		(width 0.3556)
		(layer "F.Cu")
		(net "GND")
	)
	(segment
		(start 81.485232 -57.57164)
		(end 80.913732 -57.57164)
		(width 0.254)
		(layer "F.Cu")
		(net "GND")
	)
	(segment
		(start 467.995 -135.763)
		(end 467.643972 -136.114028)
		(width 0.254)
		(layer "F.Cu")
		(net "GND")
	)
	(segment
		(start 78.14945 -147.277582)
		(end 78.14945 -147.27174)
		(width 0.4064)
		(layer "F.Cu")
		(net "GND")
	)
	(segment
		(start 389.984996 -95.205042)
		(end 390.984994 -95.205042)
		(width 0.254)
		(layer "F.Cu")
		(net "GND")
	)
	(segment
		(start 292.65626 -62.343538)
		(end 293.22776 -62.343538)
		(width 0.254)
		(layer "F.Cu")
		(net "GND")
	)
	(segment
		(start 278.920194 -60.362338)
		(end 278.348694 -60.362338)
		(width 0.254)
		(layer "F.Cu")
		(net "GND")
	)
	(segment
		(start 301.800006 -156.87294)
		(end 301.800006 -155.67025)
		(width 0.3556)
		(layer "F.Cu")
		(net "GND")
	)
	(segment
		(start 152.099518 3.778758)
		(end 152.099518 2.514854)
		(width 0.4064)
		(layer "F.Cu")
		(net "GND")
	)
	(segment
		(start 375.92 -114.355118)
		(end 376.335036 -114.85499)
		(width 0.254)
		(layer "F.Cu")
		(net "GND")
	)
	(segment
		(start 302.958246 -93.052138)
		(end 303.529746 -93.052138)
		(width 0.254)
		(layer "F.Cu")
		(net "GND")
	)
	(segment
		(start 71.349362 -13.541756)
		(end 71.349362 -15.423642)
		(width 0.4064)
		(layer "F.Cu")
		(net "GND")
	)
	(segment
		(start 201.499978 -142.677642)
		(end 201.499724 -142.677896)
		(width 0.4064)
		(layer "F.Cu")
		(net "GND")
	)
	(segment
		(start 123.363228 -63.829184)
		(end 122.791728 -63.829184)
		(width 0.254)
		(layer "F.Cu")
		(net "GND")
	)
	(segment
		(start 402.223986 -83.487514)
		(end 402.0566 -83.6549)
		(width 0.254)
		(layer "F.Cu")
		(net "GND")
	)
	(segment
		(start 199.742552 -9.143746)
		(end 199.742552 -9.369298)
		(width 0.4064)
		(layer "F.Cu")
		(net "GND")
	)
	(segment
		(start 49.249584 -133.076442)
		(end 49.24933 -133.076696)
		(width 0.4064)
		(layer "F.Cu")
		(net "GND")
	)
	(segment
		(start 183.4007 -56.1721)
		(end 183.4642 -56.1086)
		(width 0.254)
		(layer "F.Cu")
		(net "GND")
	)
	(segment
		(start 308.501796 -7.607046)
		(end 308.59984 -7.509002)
		(width 0.4064)
		(layer "F.Cu")
		(net "GND")
	)
	(segment
		(start 379.81255 -115.86464)
		(end 380.30785 -116.094764)
		(width 0.254)
		(layer "F.Cu")
		(net "GND")
	)
	(segment
		(start 247.344184 -54.104286)
		(end 247.631204 -53.60924)
		(width 0.254)
		(layer "F.Cu")
		(net "GND")
	)
	(segment
		(start 381.429514 -108.077)
		(end 381.79375 -107.907836)
		(width 0.254)
		(layer "F.Cu")
		(net "GND")
	)
	(segment
		(start 78.562454 -12.885166)
		(end 78.2193 -12.885166)
		(width 0.4064)
		(layer "F.Cu")
		(net "GND")
	)
	(segment
		(start 283.099764 -136.46785)
		(end 283.04236 -136.410446)
		(width 0.3556)
		(layer "F.Cu")
		(net "GND")
	)
	(segment
		(start 62.849506 -0.821182)
		(end 62.849506 -2.253488)
		(width 0.4064)
		(layer "F.Cu")
		(net "GND")
	)
	(segment
		(start -2.753868 -141.619732)
		(end -2.753868 -140.939012)
		(width 0.254)
		(layer "F.Cu")
		(net "GND")
	)
	(segment
		(start 304.675286 -54.418738)
		(end 304.675286 -54.210204)
		(width 0.254)
		(layer "F.Cu")
		(net "GND")
	)
	(segment
		(start 126.599442 -133.799326)
		(end 126.388368 -134.0104)
		(width 0.3556)
		(layer "F.Cu")
		(net "GND")
	)
	(segment
		(start 57.74944 -137.67054)
		(end 57.74944 -136.410446)
		(width 0.4064)
		(layer "F.Cu")
		(net "GND")
	)
	(segment
		(start 224.449894 -9.143746)
		(end 224.449894 -10.422382)
		(width 0.4064)
		(layer "F.Cu")
		(net "GND")
	)
	(segment
		(start 280.637234 -88.099138)
		(end 281.208734 -88.099138)
		(width 0.254)
		(layer "F.Cu")
		(net "GND")
	)
	(segment
		(start 140.246354 -96.023938)
		(end 139.674854 -96.023938)
		(width 0.254)
		(layer "F.Cu")
		(net "GND")
	)
	(segment
		(start 300.100492 -10.422382)
		(end 300.099984 -10.422382)
		(width 0.4064)
		(layer "F.Cu")
		(net "GND")
	)
	(segment
		(start 71.183246 -99.17684)
		(end 70.611746 -99.17684)
		(width 0.254)
		(layer "F.Cu")
		(net "GND")
	)
	(segment
		(start 66.24955 -133.0706)
		(end 66.24955 -133.255512)
		(width 0.4064)
		(layer "F.Cu")
		(net "GND")
	)
	(segment
		(start 392.523218 -85.680042)
		(end 392.165078 -85.680042)
		(width 0.254)
		(layer "F.Cu")
		(net "GND")
	)
	(segment
		(start 358.698292 -141.529054)
		(end 358.652826 -141.57452)
		(width 0.2032)
		(layer "F.Cu")
		(net "GND")
	)
	(segment
		(start 137.957814 -100.976684)
		(end 137.957814 -101.967538)
		(width 0.4064)
		(layer "F.Cu")
		(net "GND")
	)
	(segment
		(start 96.086168 -149.778212)
		(end 96.086168 -150.256748)
		(width 0.4064)
		(layer "F.Cu")
		(net "GND")
	)
	(segment
		(start 347.942154 -148.119338)
		(end 347.942154 -147.689062)
		(width 0.254)
		(layer "F.Cu")
		(net "GND")
	)
	(segment
		(start 31.671768 -53.856382)
		(end 31.72333 -53.856382)
		(width 0.4064)
		(layer "F.Cu")
		(net "GND")
	)
	(segment
		(start 289.22218 -94.042738)
		(end 289.79368 -94.042738)
		(width 0.254)
		(layer "F.Cu")
		(net "GND")
	)
	(segment
		(start 465.836 -135.255)
		(end 465.836 -135.8646)
		(width 0.254)
		(layer "F.Cu")
		(net "GND")
	)
	(segment
		(start 296.700448 -20.023582)
		(end 296.69994 -20.023582)
		(width 0.4064)
		(layer "F.Cu")
		(net "GND")
	)
	(segment
		(start 114.0206 -68.4784)
		(end 113.8682 -68.4784)
		(width 0.254)
		(layer "F.Cu")
		(net "GND")
	)
	(segment
		(start 462.368646 -53.234844)
		(end 462.149952 -53.01615)
		(width 0.4064)
		(layer "F.Cu")
		(net "GND")
	)
	(segment
		(start 313.699906 -147.27174)
		(end 313.699906 -146.011646)
		(width 0.4064)
		(layer "F.Cu")
		(net "GND")
	)
	(segment
		(start 241.450368 -10.422382)
		(end 241.44986 -10.422382)
		(width 0.4064)
		(layer "F.Cu")
		(net "GND")
	)
	(segment
		(start 118.099332 -137.67054)
		(end 118.099332 -136.46785)
		(width 0.3556)
		(layer "F.Cu")
		(net "GND")
	)
	(segment
		(start 131.089908 -83.146138)
		(end 131.661408 -83.146138)
		(width 0.254)
		(layer "F.Cu")
		(net "GND")
	)
	(segment
		(start 210.849972 -133.076442)
		(end 210.849718 -133.076696)
		(width 0.4064)
		(layer "F.Cu")
		(net "GND")
	)
	(segment
		(start 436.2069 -18.4785)
		(end 436.499 -18.4785)
		(width 0.254)
		(layer "F.Cu")
		(net "GND")
	)
	(segment
		(start 84.919312 -59.55284)
		(end 84.347812 -59.55284)
		(width 0.254)
		(layer "F.Cu")
		(net "GND")
	)
	(segment
		(start 250.778264 -83.822286)
		(end 250.206764 -83.822286)
		(width 0.254)
		(layer "F.Cu")
		(net "GND")
	)
	(segment
		(start 195.549774 -7.086346)
		(end 195.549774 -5.822442)
		(width 0.4064)
		(layer "F.Cu")
		(net "GND")
	)
	(segment
		(start 257.64617 -65.000886)
		(end 257.07467 -65.000886)
		(width 0.254)
		(layer "F.Cu")
		(net "GND")
	)
	(segment
		(start 246.485664 -62.52464)
		(end 245.914164 -62.52464)
		(width 0.254)
		(layer "F.Cu")
		(net "GND")
	)
	(segment
		(start 73.899268 -133.076696)
		(end 73.899268 -133.891274)
		(width 0.4064)
		(layer "F.Cu")
		(net "GND")
	)
	(segment
		(start 47.549308 -6.001766)
		(end 47.549308 -7.607046)
		(width 0.4064)
		(layer "F.Cu")
		(net "GND")
	)
	(segment
		(start 209.150458 -147.27174)
		(end 209.14995 -147.27174)
		(width 0.4064)
		(layer "F.Cu")
		(net "GND")
	)
	(segment
		(start 239.750346 -137.67054)
		(end 239.749838 -137.67054)
		(width 0.4064)
		(layer "F.Cu")
		(net "GND")
	)
	(segment
		(start 238.900462 -133.0706)
		(end 238.899954 -133.076442)
		(width 0.4064)
		(layer "F.Cu")
		(net "GND")
	)
	(segment
		(start 296.948606 -67.791584)
		(end 297.520106 -67.791584)
		(width 0.254)
		(layer "F.Cu")
		(net "GND")
	)
	(segment
		(start 68.799456 -2.314956)
		(end 68.799456 -0.821182)
		(width 0.4064)
		(layer "F.Cu")
		(net "GND")
	)
	(segment
		(start 289.22218 -86.117938)
		(end 289.79368 -86.117938)
		(width 0.254)
		(layer "F.Cu")
		(net "GND")
	)
	(segment
		(start 119.799354 -14.410182)
		(end 119.799354 -15.423642)
		(width 0.4064)
		(layer "F.Cu")
		(net "GND")
	)
	(segment
		(start 70.499478 -155.650946)
		(end 70.461378 -155.612846)
		(width 0.4064)
		(layer "F.Cu")
		(net "GND")
	)
	(segment
		(start 290.0807 -87.603584)
		(end 290.6522 -87.603584)
		(width 0.254)
		(layer "F.Cu")
		(net "GND")
	)
	(segment
		(start 76.449428 -20.023582)
		(end 76.449428 -21.517356)
		(width 0.4064)
		(layer "F.Cu")
		(net "GND")
	)
	(segment
		(start 442.921898 -32.632142)
		(end 442.921898 -32.632396)
		(width 0.3048)
		(layer "F.Cu")
		(net "GND")
	)
	(segment
		(start 294.14978 -142.677642)
		(end 294.14978 -143.492474)
		(width 0.4064)
		(layer "F.Cu")
		(net "GND")
	)
	(segment
		(start 134.523734 -95.033084)
		(end 135.095234 -95.033084)
		(width 0.254)
		(layer "F.Cu")
		(net "GND")
	)
	(segment
		(start 392.221974 -150.347426)
		(end 392.43 -150.1394)
		(width 0.4064)
		(layer "F.Cu")
		(net "GND")
	)
	(segment
		(start 59.449462 -156.87294)
		(end 59.449462 -155.600146)
		(width 0.4064)
		(layer "F.Cu")
		(net "GND")
	)
	(segment
		(start 115.549426 -153.965402)
		(end 115.451382 -154.063446)
		(width 0.4064)
		(layer "F.Cu")
		(net "GND")
	)
	(segment
		(start 248.202704 -56.58104)
		(end 247.631204 -56.58104)
		(width 0.254)
		(layer "F.Cu")
		(net "GND")
	)
	(segment
		(start 305.533806 -91.565984)
		(end 306.105306 -91.565984)
		(width 0.3048)
		(layer "F.Cu")
		(net "GND")
	)
	(segment
		(start 488.1372 -34.8742)
		(end 488.1372 -34.3408)
		(width 0.254)
		(layer "F.Cu")
		(net "GND")
	)
	(segment
		(start 80.626712 -50.141886)
		(end 80.626712 -49.150778)
		(width 0.2032)
		(layer "F.Cu")
		(net "GND")
	)
	(segment
		(start 416.600386 -53.382672)
		(end 416.402012 -53.184298)
		(width 0.254)
		(layer "F.Cu")
		(net "GND")
	)
	(segment
		(start 370.344954 -76.695046)
		(end 370.745004 -76.294996)
		(width 0.254)
		(layer "F.Cu")
		(net "GND")
	)
	(segment
		(start 300.736 -144.464532)
		(end 300.772068 -144.5006)
		(width 0.3556)
		(layer "F.Cu")
		(net "GND")
	)
	(segment
		(start 72.900286 -89.27084)
		(end 72.328786 -89.27084)
		(width 0.254)
		(layer "F.Cu")
		(net "GND")
	)
	(segment
		(start 414.239202 -125.740414)
		(end 415.191194 -125.740414)
		(width 0.254)
		(layer "F.Cu")
		(net "GND")
	)
	(segment
		(start 114.699542 -11.9126)
		(end 114.699542 -10.422382)
		(width 0.4064)
		(layer "F.Cu")
		(net "GND")
	)
	(segment
		(start 124.89942 -134.763002)
		(end 124.801376 -134.861046)
		(width 0.4064)
		(layer "F.Cu")
		(net "GND")
	)
	(segment
		(start 125.749558 -147.27174)
		(end 125.749558 -146.011646)
		(width 0.4064)
		(layer "F.Cu")
		(net "GND")
	)
	(segment
		(start 374.674892 -95.978472)
		(end 374.616726 -95.978472)
		(width 0.254)
		(layer "F.Cu")
		(net "GND")
	)
	(segment
		(start 201.499978 -152.278842)
		(end 201.499724 -152.279096)
		(width 0.4064)
		(layer "F.Cu")
		(net "GND")
	)
	(segment
		(start 210.85048 -152.273)
		(end 210.849972 -152.278842)
		(width 0.4064)
		(layer "F.Cu")
		(net "GND")
	)
	(segment
		(start 291.599874 3.055874)
		(end 291.3888 2.8448)
		(width 0.3556)
		(layer "F.Cu")
		(net "GND")
	)
	(segment
		(start 292.392608 -9.156446)
		(end 292.392608 -9.143746)
		(width 0.3556)
		(layer "F.Cu")
		(net "GND")
	)
	(segment
		(start 204.049884 0.444754)
		(end 204.049884 -0.821182)
		(width 0.4064)
		(layer "F.Cu")
		(net "GND")
	)
	(segment
		(start 392.98499 -125.33503)
		(end 393.081764 -125.431804)
		(width 0.254)
		(layer "F.Cu")
		(net "GND")
	)
	(segment
		(start 301.812706 -93.260164)
		(end 302.099726 -93.547184)
		(width 0.254)
		(layer "F.Cu")
		(net "GND")
	)
	(segment
		(start 38.199568 -15.423642)
		(end 38.199568 -15.602712)
		(width 0.4064)
		(layer "F.Cu")
		(net "GND")
	)
	(segment
		(start 439.741056 -51.875944)
		(end 439.742072 -51.875944)
		(width 0.508)
		(layer "F.Cu")
		(net "GND")
	)
	(segment
		(start 45.84954 -15.423642)
		(end 45.849286 -15.423896)
		(width 0.4064)
		(layer "F.Cu")
		(net "GND")
	)
	(segment
		(start 152.949402 -150.774146)
		(end 152.949402 -152.273)
		(width 0.4064)
		(layer "F.Cu")
		(net "GND")
	)
	(segment
		(start 210.849972 -152.278842)
		(end 210.849718 -152.279096)
		(width 0.4064)
		(layer "F.Cu")
		(net "GND")
	)
	(segment
		(start 246.485664 -91.25204)
		(end 245.914164 -91.25204)
		(width 0.254)
		(layer "F.Cu")
		(net "GND")
	)
	(segment
		(start 382.382268 -112.7506)
		(end 382.11379 -112.7506)
		(width 0.254)
		(layer "F.Cu")
		(net "GND")
	)
	(segment
		(start 401.295108 -95.165672)
		(end 401.320762 -95.140018)
		(width 0.254)
		(layer "F.Cu")
		(net "GND")
	)
	(segment
		(start 237.042198 -51.132486)
		(end 236.470698 -51.132486)
		(width 0.254)
		(layer "F.Cu")
		(net "GND")
	)
	(segment
		(start 224.449894 -2.314956)
		(end 224.449894 -0.821182)
		(width 0.4064)
		(layer "F.Cu")
		(net "GND")
	)
	(segment
		(start 41.599358 -15.423642)
		(end 41.599358 -13.427456)
		(width 0.4064)
		(layer "F.Cu")
		(net "GND")
	)
	(segment
		(start 379.31725 -102.98684)
		(end 378.82195 -102.756716)
		(width 0.254)
		(layer "F.Cu")
		(net "GND")
	)
	(segment
		(start 78.909672 -59.057286)
		(end 78.338172 -59.057286)
		(width 0.254)
		(layer "F.Cu")
		(net "GND")
	)
	(segment
		(start 209.140806 -13.948156)
		(end 209.08645 -13.8938)
		(width 0.254)
		(layer "F.Cu")
		(net "GND")
	)
	(segment
		(start 78.051406 -88.28024)
		(end 77.479906 -88.28024)
		(width 0.254)
		(layer "F.Cu")
		(net "GND")
	)
	(segment
		(start 78.051406 -51.62804)
		(end 78.338172 -51.132486)
		(width 0.254)
		(layer "F.Cu")
		(net "GND")
	)
	(segment
		(start 90.070178 -85.30844)
		(end 89.498678 -85.30844)
		(width 0.254)
		(layer "F.Cu")
		(net "GND")
	)
	(segment
		(start 420.69004 -38.534594)
		(end 421.09009 -38.134544)
		(width 0.254)
		(layer "F.Cu")
		(net "GND")
	)
	(segment
		(start 203.199746 -152.458166)
		(end 203.199746 -154.063446)
		(width 0.4064)
		(layer "F.Cu")
		(net "GND")
	)
	(segment
		(start 382.797304 -30.77083)
		(end 383.942336 -30.77083)
		(width 0.254)
		(layer "F.Cu")
		(net "GND")
	)
	(segment
		(start 48.399446 -147.27174)
		(end 48.399446 -148.771356)
		(width 0.4064)
		(layer "F.Cu")
		(net "GND")
	)
	(segment
		(start 191.349122 -140.927582)
		(end 191.74714 -141.3256)
		(width 0.254)
		(layer "F.Cu")
		(net "GND")
	)
	(segment
		(start 71.349362 -5.822442)
		(end 71.349362 -6.550406)
		(width 0.3556)
		(layer "F.Cu")
		(net "GND")
	)
	(segment
		(start 135.382254 -62.838584)
		(end 135.953754 -62.838584)
		(width 0.254)
		(layer "F.Cu")
		(net "GND")
	)
	(segment
		(start 282.24988 -13.541756)
		(end 282.07208 -13.363956)
		(width 0.4064)
		(layer "F.Cu")
		(net "GND")
	)
	(segment
		(start 136.240774 -65.315338)
		(end 136.812274 -65.315338)
		(width 0.254)
		(layer "F.Cu")
		(net "GND")
	)
	(segment
		(start 235.325158 -95.709486)
		(end 234.753658 -95.709486)
		(width 0.254)
		(layer "F.Cu")
		(net "GND")
	)
	(segment
		(start 70.324726 -83.822286)
		(end 69.753226 -83.822286)
		(width 0.254)
		(layer "F.Cu")
		(net "GND")
	)
	(segment
		(start 287.50514 -59.371484)
		(end 286.93364 -59.371484)
		(width 0.254)
		(layer "F.Cu")
		(net "GND")
	)
	(segment
		(start 436.547006 -41.219374)
		(end 436.547006 -40.5257)
		(width 0.3556)
		(layer "F.Cu")
		(net "GND")
	)
	(segment
		(start 235.325158 -81.841086)
		(end 234.753658 -81.841086)
		(width 0.254)
		(layer "F.Cu")
		(net "GND")
	)
	(segment
		(start 203.2 -6.001512)
		(end 203.199746 -6.001766)
		(width 0.4064)
		(layer "F.Cu")
		(net "GND")
	)
	(segment
		(start 303.816766 -100.481638)
		(end 304.103532 -100.976684)
		(width 0.254)
		(layer "F.Cu")
		(net "GND")
	)
	(segment
		(start 84.919312 -71.44004)
		(end 84.347812 -71.44004)
		(width 0.254)
		(layer "F.Cu")
		(net "GND")
	)
	(segment
		(start 378.82195 -102.756716)
		(end 378.32665 -102.98684)
		(width 0.254)
		(layer "F.Cu")
		(net "GND")
	)
	(segment
		(start 262.382 -128.462024)
		(end 261.747 -128.462024)
		(width 0.508)
		(layer "F.Cu")
		(net "GND")
	)
	(segment
		(start 396.15745 -108.13796)
		(end 396.288514 -108.077)
		(width 0.254)
		(layer "F.Cu")
		(net "GND")
	)
	(segment
		(start 278.061674 -61.847984)
		(end 277.490174 -61.847984)
		(width 0.254)
		(layer "F.Cu")
		(net "GND")
	)
	(segment
		(start 397.64335 -109.624876)
		(end 397.14805 -109.855)
		(width 0.254)
		(layer "F.Cu")
		(net "GND")
	)
	(segment
		(start 227.792534 -18.744946)
		(end 227.792534 -18.757646)
		(width 0.3556)
		(layer "F.Cu")
		(net "GND")
	)
	(segment
		(start 241.699796 -49.497996)
		(end 241.619024 -49.489614)
		(width 0.254)
		(layer "F.Cu")
		(net "GND")
	)
	(segment
		(start 401.620482 -100.855018)
		(end 401.295108 -100.855018)
		(width 0.254)
		(layer "F.Cu")
		(net "GND")
	)
	(segment
		(start 386.337302 -81.923636)
		(end 386.464302 -81.923636)
		(width 0.254)
		(layer "F.Cu")
		(net "GND")
	)
	(segment
		(start 152.099518 -133.0706)
		(end 152.099518 -134.340346)
		(width 0.4064)
		(layer "F.Cu")
		(net "GND")
	)
	(segment
		(start 7.0104 1.050798)
		(end 7.2136 0.847598)
		(width 0.2032)
		(layer "F.Cu")
		(net "GND")
	)
	(segment
		(start 109.627416 -99.490784)
		(end 110.198916 -99.490784)
		(width 0.254)
		(layer "F.Cu")
		(net "GND")
	)
	(segment
		(start 236.183678 -88.28024)
		(end 235.612178 -88.28024)
		(width 0.254)
		(layer "F.Cu")
		(net "GND")
	)
	(segment
		(start 126.388368 -153.2128)
		(end 126.388368 -154.068526)
		(width 0.3556)
		(layer "F.Cu")
		(net "GND")
	)
	(segment
		(start 226.111816 -11.916156)
		(end 226.149916 -11.878056)
		(width 0.4064)
		(layer "F.Cu")
		(net "GND")
	)
	(segment
		(start 135.949436 -15.423642)
		(end 135.949436 -13.541756)
		(width 0.4064)
		(layer "F.Cu")
		(net "GND")
	)
	(segment
		(start 50.099468 -147.27174)
		(end 50.099468 -148.771356)
		(width 0.4064)
		(layer "F.Cu")
		(net "GND")
	)
	(segment
		(start 235.325158 -87.784686)
		(end 234.753658 -87.784686)
		(width 0.254)
		(layer "F.Cu")
		(net "GND")
	)
	(segment
		(start 310.299862 -16.140938)
		(end 310.299862 -15.423642)
		(width 0.3556)
		(layer "F.Cu")
		(net "GND")
	)
	(segment
		(start 411.89021 -28.134564)
		(end 411.89021 -27.334718)
		(width 0.254)
		(layer "F.Cu")
		(net "GND")
	)
	(segment
		(start 174.625 -63.831978)
		(end 175.119538 -63.831978)
		(width 0.381)
		(layer "F.Cu")
		(net "GND")
	)
	(segment
		(start 173.874176 -6.313424)
		(end 173.9773 -6.2103)
		(width 0.4064)
		(layer "F.Cu")
		(net "GND")
	)
	(segment
		(start 221.04985 -147.27174)
		(end 221.04985 -146.011646)
		(width 0.4064)
		(layer "F.Cu")
		(net "GND")
	)
	(segment
		(start 30.607 -68.9864)
		(end 30.843982 -69.223382)
		(width 0.381)
		(layer "F.Cu")
		(net "GND")
	)
	(segment
		(start 311.15 -18.81505)
		(end 311.15 -20.023582)
		(width 0.3556)
		(layer "F.Cu")
		(net "GND")
	)
	(segment
		(start 488.5944 -140.208)
		(end 488.5944 -140.7668)
		(width 0.254)
		(layer "F.Cu")
		(net "GND")
	)
	(segment
		(start 274.627848 -93.547184)
		(end 275.199348 -93.547184)
		(width 0.1651)
		(layer "F.Cu")
		(net "GND")
	)
	(segment
		(start 242.299998 -152.273)
		(end 242.299998 -152.278842)
		(width 0.508)
		(layer "F.Cu")
		(net "GND")
	)
	(segment
		(start 133.665214 -69.772784)
		(end 134.236714 -69.772784)
		(width 0.254)
		(layer "F.Cu")
		(net "GND")
	)
	(segment
		(start 467.739984 -51.875944)
		(end 467.741 -51.875944)
		(width 0.4064)
		(layer "F.Cu")
		(net "GND")
	)
	(segment
		(start 304.675286 -89.089738)
		(end 305.246786 -89.089738)
		(width 0.3048)
		(layer "F.Cu")
		(net "GND")
	)
	(segment
		(start 475.618302 -39.805102)
		(end 474.218762 -39.805102)
		(width 0.254)
		(layer "F.Cu")
		(net "GND")
	)
	(segment
		(start 312.850276 -133.0706)
		(end 312.849768 -133.076442)
		(width 0.4064)
		(layer "F.Cu")
		(net "GND")
	)
	(segment
		(start 232.749598 -60.54344)
		(end 232.101898 -60.54344)
		(width 0.254)
		(layer "F.Cu")
		(net "GND")
	)
	(segment
		(start 286.499808 3.778758)
		(end 286.499808 1.994154)
		(width 0.4064)
		(layer "F.Cu")
		(net "GND")
	)
	(segment
		(start 120.787668 -87.108538)
		(end 121.359168 -87.108538)
		(width 0.254)
		(layer "F.Cu")
		(net "GND")
	)
	(segment
		(start 129.372868 -83.146138)
		(end 129.944368 -83.146138)
		(width 0.254)
		(layer "F.Cu")
		(net "GND")
	)
	(segment
		(start 215.0999 -137.67054)
		(end 215.0999 -136.397746)
		(width 0.4064)
		(layer "F.Cu")
		(net "GND")
	)
	(segment
		(start 262.79729 -56.085486)
		(end 262.22579 -56.085486)
		(width 0.254)
		(layer "F.Cu")
		(net "GND")
	)
	(segment
		(start 124.221748 -62.343538)
		(end 123.650248 -62.343538)
		(width 0.254)
		(layer "F.Cu")
		(net "GND")
	)
	(segment
		(start 438.5818 -45.5676)
		(end 438.14111 -46.00829)
		(width 0.4064)
		(layer "F.Cu")
		(net "GND")
	)
	(segment
		(start 433.578 -12.2936)
		(end 434.2384 -11.6332)
		(width 0.254)
		(layer "F.Cu")
		(net "GND")
	)
	(segment
		(start 33.754568 -144.483582)
		(end 33.771586 -144.5006)
		(width 0.3556)
		(layer "F.Cu")
		(net "GND")
	)
	(segment
		(start 81.485232 -70.44944)
		(end 80.913732 -70.44944)
		(width 0.254)
		(layer "F.Cu")
		(net "GND")
	)
	(segment
		(start 238.759238 -80.850486)
		(end 238.187738 -80.850486)
		(width 0.254)
		(layer "F.Cu")
		(net "GND")
	)
	(segment
		(start 392.02741 -98.542094)
		(end 392.19505 -98.464116)
		(width 0.254)
		(layer "F.Cu")
		(net "GND")
	)
	(segment
		(start 449.25488 -31.3055)
		(end 446.605406 -31.3055)
		(width 0.3556)
		(layer "F.Cu")
		(net "GND")
	)
	(segment
		(start 359.085134 -7.789926)
		(end 359.085134 -9.334246)
		(width 0.4064)
		(layer "F.Cu")
		(net "GND")
	)
	(segment
		(start 418.6936 -54.3814)
		(end 419.1635 -54.8513)
		(width 0.254)
		(layer "F.Cu")
		(net "GND")
	)
	(segment
		(start 285.425388 -69.277738)
		(end 285.7881 -69.277738)
		(width 0.254)
		(layer "F.Cu")
		(net "GND")
	)
	(segment
		(start 240.763298 -53.60924)
		(end 241.334798 -53.60924)
		(width 0.254)
		(layer "F.Cu")
		(net "GND")
	)
	(segment
		(start 141.391894 -81.164938)
		(end 142.039594 -81.164938)
		(width 0.254)
		(layer "F.Cu")
		(net "GND")
	)
	(segment
		(start 72.142096 -18.757646)
		(end 72.1995 -18.81505)
		(width 0.3556)
		(layer "F.Cu")
		(net "GND")
	)
	(segment
		(start 78.909672 -94.718886)
		(end 78.338172 -94.718886)
		(width 0.254)
		(layer "F.Cu")
		(net "GND")
	)
	(segment
		(start 449.25488 -37.1475)
		(end 445.233806 -37.1475)
		(width 0.4064)
		(layer "F.Cu")
		(net "GND")
	)
	(segment
		(start 196.272912 -93.798898)
		(end 196.200522 -93.871288)
		(width 0.508)
		(layer "F.Cu")
		(net "GND")
	)
	(segment
		(start 91.294712 -2.975356)
		(end 90.802968 -2.975356)
		(width 0.4064)
		(layer "F.Cu")
		(net "GND")
	)
	(segment
		(start 8.102346 3.786124)
		(end 8.026146 3.786124)
		(width 0.2032)
		(layer "F.Cu")
		(net "GND")
	)
	(segment
		(start 52.471574 -17.2466)
		(end 52.448968 -17.223994)
		(width 0.3556)
		(layer "F.Cu")
		(net "GND")
	)
	(segment
		(start 135.735568 -143.636746)
		(end 135.735568 -144.464532)
		(width 0.3556)
		(layer "F.Cu")
		(net "GND")
	)
	(segment
		(start 60.299346 3.778758)
		(end 60.299346 2.092198)
		(width 0.4064)
		(layer "F.Cu")
		(net "GND")
	)
	(segment
		(start 119.337328 -4.346956)
		(end 118.031768 -4.2926)
		(width 0.254)
		(layer "F.Cu")
		(net "GND")
	)
	(segment
		(start 223.600518 1.994916)
		(end 223.599756 1.994154)
		(width 0.4064)
		(layer "F.Cu")
		(net "GND")
	)
	(segment
		(start 287.50514 -88.099138)
		(end 288.07664 -88.099138)
		(width 0.254)
		(layer "F.Cu")
		(net "GND")
	)
	(segment
		(start 45.84954 -4.808982)
		(end 45.84954 -5.822442)
		(width 0.4064)
		(layer "F.Cu")
		(net "GND")
	)
	(segment
		(start 199.800464 -156.87294)
		(end 199.799956 -156.87294)
		(width 0.4064)
		(layer "F.Cu")
		(net "GND")
	)
	(segment
		(start 352.3107 -155.9687)
		(end 351.9932 -155.6512)
		(width 0.254)
		(layer "F.Cu")
		(net "GND")
	)
	(segment
		(start 218.499944 -147.27174)
		(end 218.499944 -146.06905)
		(width 0.3556)
		(layer "F.Cu")
		(net "GND")
	)
	(segment
		(start 420.69004 -35.334448)
		(end 420.288212 -34.93262)
		(width 0.254)
		(layer "F.Cu")
		(net "GND")
	)
	(segment
		(start 78.154022 -125.88113)
		(end 77.720952 -126.3142)
		(width 0.4064)
		(layer "F.Cu")
		(net "GND")
	)
	(segment
		(start 18.441162 -120.414288)
		(end 18.453862 -120.414288)
		(width 0.508)
		(layer "F.Cu")
		(net "GND")
	)
	(segment
		(start 198.445374 -54.263544)
		(end 198.445374 -54.644544)
		(width 0.254)
		(layer "F.Cu")
		(net "GND")
	)
	(segment
		(start 284.800294 -14.41069)
		(end 284.800294 -15.423642)
		(width 0.4064)
		(layer "F.Cu")
		(net "GND")
	)
	(segment
		(start 300.949868 -6.567678)
		(end 300.736 -6.781546)
		(width 0.3556)
		(layer "F.Cu")
		(net "GND")
	)
	(segment
		(start 78.909672 -54.104286)
		(end 78.338172 -54.104286)
		(width 0.254)
		(layer "F.Cu")
		(net "GND")
	)
	(segment
		(start 126.599442 3.055874)
		(end 126.388368 2.8448)
		(width 0.3556)
		(layer "F.Cu")
		(net "GND")
	)
	(segment
		(start 83.202272 -90.26144)
		(end 82.630772 -90.26144)
		(width 0.254)
		(layer "F.Cu")
		(net "GND")
	)
	(segment
		(start 198.755 -7.628382)
		(end 198.755 -6.731)
		(width 0.3556)
		(layer "F.Cu")
		(net "GND")
	)
	(segment
		(start 444.600838 -112.205516)
		(end 444.600838 -113.800382)
		(width 0.4064)
		(layer "F.Cu")
		(net "GND")
	)
	(segment
		(start 273.769328 -55.409338)
		(end 273.197828 -55.409338)
		(width 0.254)
		(layer "F.Cu")
		(net "GND")
	)
	(segment
		(start 400.03476 -75.184)
		(end 400.685 -75.184)
		(width 0.254)
		(layer "F.Cu")
		(net "GND")
	)
	(segment
		(start 203.199746 -3.762756)
		(end 203.2 -3.76301)
		(width 0.4064)
		(layer "F.Cu")
		(net "GND")
	)
	(segment
		(start 235.325158 -65.000886)
		(end 234.753658 -65.000886)
		(width 0.254)
		(layer "F.Cu")
		(net "GND")
	)
	(segment
		(start 75.59929 3.599434)
		(end 75.59929 1.994154)
		(width 0.4064)
		(layer "F.Cu")
		(net "GND")
	)
	(segment
		(start 227.000308 3.778758)
		(end 226.9998 3.778758)
		(width 0.3556)
		(layer "F.Cu")
		(net "GND")
	)
	(segment
		(start 61.999368 -3.940556)
		(end 61.999368 -5.822442)
		(width 0.4064)
		(layer "F.Cu")
		(net "GND")
	)
	(segment
		(start 273.769328 -96.023938)
		(end 274.340828 -96.023938)
		(width 0.254)
		(layer "F.Cu")
		(net "GND")
	)
	(segment
		(start 74.617326 -60.54344)
		(end 74.045826 -60.54344)
		(width 0.254)
		(layer "F.Cu")
		(net "GND")
	)
	(segment
		(start 393.68095 -107.27944)
		(end 394.081 -107.093766)
		(width 0.254)
		(layer "F.Cu")
		(net "GND")
	)
	(segment
		(start 288.36366 -91.565984)
		(end 288.93516 -91.565984)
		(width 0.3048)
		(layer "F.Cu")
		(net "GND")
	)
	(segment
		(start 226.149916 -156.87294)
		(end 226.150424 -156.87294)
		(width 0.4064)
		(layer "F.Cu")
		(net "GND")
	)
	(segment
		(start 137.957814 -71.258938)
		(end 138.529314 -71.258938)
		(width 0.254)
		(layer "F.Cu")
		(net "GND")
	)
	(segment
		(start 208.299812 -152.278842)
		(end 208.299812 -153.014934)
		(width 0.3556)
		(layer "F.Cu")
		(net "GND")
	)
	(segment
		(start 287.50514 -82.155284)
		(end 288.07664 -82.155284)
		(width 0.1016)
		(layer "F.Cu")
		(net "GND")
	)
	(segment
		(start 395.224 -120.18391)
		(end 395.66215 -120.387364)
		(width 0.254)
		(layer "F.Cu")
		(net "GND")
	)
	(segment
		(start 218.499944 -156.87294)
		(end 218.499944 -155.67025)
		(width 0.3556)
		(layer "F.Cu")
		(net "GND")
	)
	(segment
		(start 237.900718 -72.43064)
		(end 237.329218 -72.43064)
		(width 0.254)
		(layer "F.Cu")
		(net "GND")
	)
	(segment
		(start 64.549528 -14.410182)
		(end 64.549528 -15.423642)
		(width 0.4064)
		(layer "F.Cu")
		(net "GND")
	)
	(segment
		(start 199.742552 -146.224498)
		(end 199.742552 -145.998946)
		(width 0.4064)
		(layer "F.Cu")
		(net "GND")
	)
	(segment
		(start 243.051838 -83.32724)
		(end 242.480338 -83.32724)
		(width 0.254)
		(layer "F.Cu")
		(net "GND")
	)
	(segment
		(start 67.949318 -15.423896)
		(end 67.949572 -15.423642)
		(width 0.4064)
		(layer "F.Cu")
		(net "GND")
	)
	(segment
		(start 294.999918 -11.916156)
		(end 294.999918 -10.422382)
		(width 0.4064)
		(layer "F.Cu")
		(net "GND")
	)
	(segment
		(start 76.334366 -98.18624)
		(end 75.762866 -98.18624)
		(width 0.254)
		(layer "F.Cu")
		(net "GND")
	)
	(segment
		(start 206.59979 -3.826256)
		(end 206.59979 -5.822442)
		(width 0.4064)
		(layer "F.Cu")
		(net "GND")
	)
	(segment
		(start 292.450012 0.38735)
		(end 292.392608 0.444754)
		(width 0.3556)
		(layer "F.Cu")
		(net "GND")
	)
	(segment
		(start 393.18565 -96.11868)
		(end 393.68095 -95.888556)
		(width 0.254)
		(layer "F.Cu")
		(net "GND")
	)
	(segment
		(start 173.791626 -80.21193)
		(end 174.24527 -80.21193)
		(width 0.254)
		(layer "F.Cu")
		(net "GND")
	)
	(segment
		(start 71.349362 -143.405606)
		(end 71.117968 -143.637)
		(width 0.3556)
		(layer "F.Cu")
		(net "GND")
	)
	(segment
		(start 60.299346 -17.110202)
		(end 60.299346 -15.423642)
		(width 0.4064)
		(layer "F.Cu")
		(net "GND")
	)
	(segment
		(start 197.250304 -15.423642)
		(end 197.249796 -15.423642)
		(width 0.4064)
		(layer "F.Cu")
		(net "GND")
	)
	(segment
		(start 230.399844 0.444754)
		(end 230.399844 -0.821182)
		(width 0.4064)
		(layer "F.Cu")
		(net "GND")
	)
	(segment
		(start 89.211912 -63.019686)
		(end 88.640412 -63.019686)
		(width 0.254)
		(layer "F.Cu")
		(net "GND")
	)
	(segment
		(start 280.637234 -58.381138)
		(end 280.065734 -58.381138)
		(width 0.254)
		(layer "F.Cu")
		(net "GND")
	)
	(segment
		(start 238.8997 -133.891274)
		(end 238.44123 -134.349744)
		(width 0.4064)
		(layer "F.Cu")
		(net "GND")
	)
	(segment
		(start 31.72333 -53.856382)
		(end 32.094932 -54.227984)
		(width 0.254)
		(layer "F.Cu")
		(net "GND")
	)
	(segment
		(start 242.721384 -126.3142)
		(end 242.316 -126.3142)
		(width 0.4064)
		(layer "F.Cu")
		(net "GND")
	)
	(segment
		(start 71.183246 -63.51524)
		(end 70.611746 -63.51524)
		(width 0.254)
		(layer "F.Cu")
		(net "GND")
	)
	(segment
		(start 107.910376 -90.575384)
		(end 108.481876 -90.575384)
		(width 0.254)
		(layer "F.Cu")
		(net "GND")
	)
	(segment
		(start 301.800006 -0.821182)
		(end 301.800006 -2.253488)
		(width 0.4064)
		(layer "F.Cu")
		(net "GND")
	)
	(segment
		(start 246.485664 -98.18624)
		(end 245.914164 -98.18624)
		(width 0.254)
		(layer "F.Cu")
		(net "GND")
	)
	(segment
		(start 300.099984 -147.27174)
		(end 300.099984 -146.011646)
		(width 0.4064)
		(layer "F.Cu")
		(net "GND")
	)
	(segment
		(start 184.935114 -114.28095)
		(end 184.9374 -114.3)
		(width 0.254)
		(layer "F.Cu")
		(net "GND")
	)
	(segment
		(start 196.884544 -3.737356)
		(end 197.160896 -3.737356)
		(width 0.4064)
		(layer "F.Cu")
		(net "GND")
	)
	(segment
		(start 444.548006 -34.7345)
		(end 445.056006 -34.7345)
		(width 0.3048)
		(layer "F.Cu")
		(net "GND")
	)
	(segment
		(start 238.8997 -142.677896)
		(end 238.8997 -143.492474)
		(width 0.4064)
		(layer "F.Cu")
		(net "GND")
	)
	(segment
		(start 249.919744 -61.53404)
		(end 249.348244 -61.53404)
		(width 0.254)
		(layer "F.Cu")
		(net "GND")
	)
	(segment
		(start 73.899522 -142.677642)
		(end 73.899268 -142.677896)
		(width 0.4064)
		(layer "F.Cu")
		(net "GND")
	)
	(segment
		(start 304.35042 -0.821182)
		(end 304.349912 -0.821182)
		(width 0.4064)
		(layer "F.Cu")
		(net "GND")
	)
	(segment
		(start 140.533374 -91.565984)
		(end 140.8176 -91.281758)
		(width 0.254)
		(layer "F.Cu")
		(net "GND")
	)
	(segment
		(start 453.400922 -116.993162)
		(end 453.404478 -118.61927)
		(width 0.4064)
		(layer "F.Cu")
		(net "GND")
	)
	(segment
		(start 121.646188 -56.894984)
		(end 121.074688 -56.894984)
		(width 0.254)
		(layer "F.Cu")
		(net "GND")
	)
	(segment
		(start 480.335844 -152.93467)
		(end 481.051616 -152.218898)
		(width 0.254)
		(layer "F.Cu")
		(net "GND")
	)
	(segment
		(start 132.806694 -97.014538)
		(end 133.378194 -97.014538)
		(width 0.254)
		(layer "F.Cu")
		(net "GND")
	)
	(segment
		(start 234.466638 -99.17684)
		(end 233.895138 -99.17684)
		(width 0.254)
		(layer "F.Cu")
		(net "GND")
	)
	(segment
		(start 348.771718 -9.59739)
		(end 348.5896 -9.59739)
		(width 0.4064)
		(layer "F.Cu")
		(net "GND")
	)
	(segment
		(start 464.542124 -51.875944)
		(end 464.541108 -51.875944)
		(width 0.508)
		(layer "F.Cu")
		(net "GND")
	)
	(segment
		(start 94.362778 -64.010286)
		(end 93.791278 -64.010286)
		(width 0.254)
		(layer "F.Cu")
		(net "GND")
	)
	(segment
		(start 31.39948 0.457454)
		(end 31.39948 -0.821182)
		(width 0.4064)
		(layer "F.Cu")
		(net "GND")
	)
	(segment
		(start 257.64617 -98.681286)
		(end 257.07467 -98.681286)
		(width 0.254)
		(layer "F.Cu")
		(net "GND")
	)
	(segment
		(start 292.65626 -82.155284)
		(end 293.22776 -82.155284)
		(width 0.254)
		(layer "F.Cu")
		(net "GND")
	)
	(segment
		(start 317.09995 -137.67054)
		(end 317.09995 -136.410446)
		(width 0.4064)
		(layer "F.Cu")
		(net "GND")
	)
	(segment
		(start 193.750946 -60.843668)
		(end 194.142614 -60.843668)
		(width 0.254)
		(layer "F.Cu")
		(net "GND")
	)
	(segment
		(start 376.682 -88.2015)
		(end 376.682 -89.315036)
		(width 0.254)
		(layer "F.Cu")
		(net "GND")
	)
	(segment
		(start 31.39948 -137.67054)
		(end 31.39948 -136.397746)
		(width 0.4064)
		(layer "F.Cu")
		(net "GND")
	)
	(segment
		(start 284.929834 -62.838584)
		(end 284.358334 -62.838584)
		(width 0.254)
		(layer "F.Cu")
		(net "GND")
	)
	(segment
		(start 132.549392 -5.822442)
		(end 132.549392 -3.762756)
		(width 0.4064)
		(layer "F.Cu")
		(net "GND")
	)
	(segment
		(start 387.24205 -99.55276)
		(end 387.73735 -99.322636)
		(width 0.254)
		(layer "F.Cu")
		(net "GND")
	)
	(segment
		(start 292.450012 -11.854688)
		(end 292.450012 -10.422382)
		(width 0.4064)
		(layer "F.Cu")
		(net "GND")
	)
	(segment
		(start 306.392326 -70.268084)
		(end 306.392326 -70.059804)
		(width 0.254)
		(layer "F.Cu")
		(net "GND")
	)
	(segment
		(start 56.049418 -9.156446)
		(end 56.049418 -10.422382)
		(width 0.4064)
		(layer "F.Cu")
		(net "GND")
	)
	(segment
		(start 233.799888 -155.549346)
		(end 233.799888 -156.87294)
		(width 0.4064)
		(layer "F.Cu")
		(net "GND")
	)
	(segment
		(start 79.768192 -95.21444)
		(end 79.196692 -95.21444)
		(width 0.254)
		(layer "F.Cu")
		(net "GND")
	)
	(segment
		(start 285.2166 -55.409338)
		(end 285.7881 -55.409338)
		(width 0.254)
		(layer "F.Cu")
		(net "GND")
	)
	(segment
		(start 240.599976 -13.36421)
		(end 240.599722 -13.363956)
		(width 0.4064)
		(layer "F.Cu")
		(net "GND")
	)
	(segment
		(start 235.325158 -66.982086)
		(end 234.753658 -66.982086)
		(width 0.254)
		(layer "F.Cu")
		(net "GND")
	)
	(segment
		(start 291.600382 -15.423642)
		(end 291.599874 -15.423642)
		(width 0.3556)
		(layer "F.Cu")
		(net "GND")
	)
	(segment
		(start 78.051406 -69.45884)
		(end 77.479906 -69.45884)
		(width 0.254)
		(layer "F.Cu")
		(net "GND")
	)
	(segment
		(start 125.711458 -2.314956)
		(end 125.749558 -2.276856)
		(width 0.4064)
		(layer "F.Cu")
		(net "GND")
	)
	(segment
		(start 285.2166 -54.418738)
		(end 285.7881 -54.418738)
		(width 0.254)
		(layer "F.Cu")
		(net "GND")
	)
	(segment
		(start 339.5726 -22.833584)
		(end 339.599016 -22.86)
		(width 0.4064)
		(layer "F.Cu")
		(net "GND")
	)
	(segment
		(start 294.999918 -10.422382)
		(end 294.999918 -9.156446)
		(width 0.4064)
		(layer "F.Cu")
		(net "GND")
	)
	(segment
		(start 33.099502 -18.757646)
		(end 33.099502 -20.023582)
		(width 0.4064)
		(layer "F.Cu")
		(net "GND")
	)
	(segment
		(start 31.39948 -2.314956)
		(end 31.39948 -0.821182)
		(width 0.4064)
		(layer "F.Cu")
		(net "GND")
	)
	(segment
		(start 141.049502 -147.27174)
		(end 141.049502 -146.011646)
		(width 0.4064)
		(layer "F.Cu")
		(net "GND")
	)
	(segment
		(start 349.0976 -9.923272)
		(end 348.771718 -9.59739)
		(width 0.4064)
		(layer "F.Cu")
		(net "GND")
	)
	(segment
		(start 113.919762 -102.958138)
		(end 113.561114 -103.576628)
		(width 0.4064)
		(layer "F.Cu")
		(net "GND")
	)
	(segment
		(start 52.448968 -16.5354)
		(end 52.448968 -16.3576)
		(width 0.3048)
		(layer "F.Cu")
		(net "GND")
	)
	(segment
		(start 390.70915 -115.86464)
		(end 391.20445 -116.094764)
		(width 0.254)
		(layer "F.Cu")
		(net "GND")
	)
	(segment
		(start 212.54974 -6.001766)
		(end 212.54974 -7.607046)
		(width 0.4064)
		(layer "F.Cu")
		(net "GND")
	)
	(segment
		(start 352.228658 -1.261364)
		(end 352.938842 -1.261364)
		(width 0.254)
		(layer "F.Cu")
		(net "GND")
	)
	(segment
		(start 386.743448 -118.6688)
		(end 386.74675 -118.670324)
		(width 0.254)
		(layer "F.Cu")
		(net "GND")
	)
	(segment
		(start 125.749558 -137.67054)
		(end 125.749558 -136.410446)
		(width 0.4064)
		(layer "F.Cu")
		(net "GND")
	)
	(segment
		(start 72.041766 -54.104286)
		(end 71.470266 -54.104286)
		(width 0.254)
		(layer "F.Cu")
		(net "GND")
	)
	(segment
		(start 464.20151 -45.510196)
		(end 463.741008 -45.970698)
		(width 0.4064)
		(layer "F.Cu")
		(net "GND")
	)
	(segment
		(start 68.799456 -20.023582)
		(end 68.799456 -21.517356)
		(width 0.4064)
		(layer "F.Cu")
		(net "GND")
	)
	(segment
		(start 235.325158 -90.756486)
		(end 234.753658 -90.756486)
		(width 0.254)
		(layer "F.Cu")
		(net "GND")
	)
	(segment
		(start 169.11193 -147.42922)
		(end 167.300148 -147.42922)
		(width 0.254)
		(layer "F.Cu")
		(net "GND")
	)
	(segment
		(start 121.499376 1.994154)
		(end 121.499376 3.778758)
		(width 0.4064)
		(layer "F.Cu")
		(net "GND")
	)
	(segment
		(start 68.799456 -137.67054)
		(end 68.799456 -136.397746)
		(width 0.4064)
		(layer "F.Cu")
		(net "GND")
	)
	(segment
		(start 305.533806 -75.716384)
		(end 306.181506 -75.716384)
		(width 0.254)
		(layer "F.Cu")
		(net "GND")
	)
	(segment
		(start 239.750346 -10.422382)
		(end 239.749838 -10.422382)
		(width 0.4064)
		(layer "F.Cu")
		(net "GND")
	)
	(segment
		(start 297.549824 -15.423642)
		(end 297.549824 -13.363956)
		(width 0.4064)
		(layer "F.Cu")
		(net "GND")
	)
	(segment
		(start 474.523816 -134.366)
		(end 476.116904 -134.366)
		(width 0.381)
		(layer "F.Cu")
		(net "GND")
	)
	(segment
		(start 0.567436 -144.933162)
		(end 0.567436 -144.534636)
		(width 0.254)
		(layer "F.Cu")
		(net "GND")
	)
	(segment
		(start 305.246786 -63.125604)
		(end 305.246786 -63.334138)
		(width 0.254)
		(layer "F.Cu")
		(net "GND")
	)
	(segment
		(start 129.149348 -14.409928)
		(end 128.687576 -13.948156)
		(width 0.4064)
		(layer "F.Cu")
		(net "GND")
	)
	(segment
		(start 416.289998 -34.934652)
		(end 416.690048 -34.534602)
		(width 0.254)
		(layer "F.Cu")
		(net "GND")
	)
	(segment
		(start 157.099 -141.073632)
		(end 157.198568 -141.1732)
		(width 0.4064)
		(layer "F.Cu")
		(net "GND")
	)
	(segment
		(start 304.35042 -137.67054)
		(end 304.349912 -137.67054)
		(width 0.4064)
		(layer "F.Cu")
		(net "GND")
	)
	(segment
		(start 239.617758 -65.49644)
		(end 239.046258 -65.49644)
		(width 0.254)
		(layer "F.Cu")
		(net "GND")
	)
	(segment
		(start 459.75016 -63.157354)
		(end 459.557374 -63.35014)
		(width 0.381)
		(layer "F.Cu")
		(net "GND")
	)
	(segment
		(start 118.212362 -101.471984)
		(end 117.925342 -100.976684)
		(width 0.254)
		(layer "F.Cu")
		(net "GND")
	)
	(segment
		(start 244.768624 -95.21444)
		(end 244.197124 -95.21444)
		(width 0.254)
		(layer "F.Cu")
		(net "GND")
	)
	(segment
		(start 241.334798 -52.618386)
		(end 240.763298 -52.618386)
		(width 0.254)
		(layer "F.Cu")
		(net "GND")
	)
	(segment
		(start 239.750346 -0.821182)
		(end 239.749838 -0.821182)
		(width 0.4064)
		(layer "F.Cu")
		(net "GND")
	)
	(segment
		(start 203.2 -3.76301)
		(end 203.2 -5.822442)
		(width 0.4064)
		(layer "F.Cu")
		(net "GND")
	)
	(segment
		(start 278.849836 -10.422382)
		(end 278.849836 -9.275826)
		(width 0.4064)
		(layer "F.Cu")
		(net "GND")
	)
	(segment
		(start 109.82325 -67.59575)
		(end 109.728 -67.691)
		(width 0.254)
		(layer "F.Cu")
		(net "GND")
	)
	(segment
		(start 242.193318 -85.803486)
		(end 241.621818 -85.803486)
		(width 0.254)
		(layer "F.Cu")
		(net "GND")
	)
	(segment
		(start 283.212794 -52.932838)
		(end 283.219398 -52.93106)
		(width 0.254)
		(layer "F.Cu")
		(net "GND")
	)
	(segment
		(start 301.742602 0.457454)
		(end 301.742602 0.444754)
		(width 0.3556)
		(layer "F.Cu")
		(net "GND")
	)
	(segment
		(start 127.655828 -82.155284)
		(end 128.227328 -82.155284)
		(width 0.254)
		(layer "F.Cu")
		(net "GND")
	)
	(segment
		(start 223.599756 -17.208246)
		(end 223.599756 -15.423896)
		(width 0.4064)
		(layer "F.Cu")
		(net "GND")
	)
	(segment
		(start 445.792606 -38.2905)
		(end 449.25488 -38.2905)
		(width 0.3556)
		(layer "F.Cu")
		(net "GND")
	)
	(segment
		(start 236.1184 -154.048206)
		(end 236.171994 -154.1018)
		(width 0.3556)
		(layer "F.Cu")
		(net "GND")
	)
	(segment
		(start 296.948606 -91.565984)
		(end 297.520106 -91.565984)
		(width 0.3048)
		(layer "F.Cu")
		(net "GND")
	)
	(segment
		(start 360.8324 -132.9436)
		(end 360.9848 -133.096)
		(width 0.254)
		(layer "F.Cu")
		(net "GND")
	)
	(segment
		(start 126.797308 -96.518984)
		(end 127.368808 -96.518984)
		(width 0.254)
		(layer "F.Cu")
		(net "GND")
	)
	(segment
		(start 279.778714 -96.518984)
		(end 280.350214 -96.518984)
		(width 0.254)
		(layer "F.Cu")
		(net "GND")
	)
	(segment
		(start 73.758806 -55.094886)
		(end 73.187306 -55.094886)
		(width 0.254)
		(layer "F.Cu")
		(net "GND")
	)
	(segment
		(start 281.400504 -10.422382)
		(end 281.399996 -10.422382)
		(width 0.4064)
		(layer "F.Cu")
		(net "GND")
	)
	(segment
		(start 68.607686 -66.982086)
		(end 68.036186 -66.982086)
		(width 0.254)
		(layer "F.Cu")
		(net "GND")
	)
	(segment
		(start 383.73685 -115.05565)
		(end 383.3368 -115.4557)
		(width 0.12446)
		(layer "F.Cu")
		(net "GND")
	)
	(segment
		(start 45.84954 3.778758)
		(end 45.849286 3.778504)
		(width 0.4064)
		(layer "F.Cu")
		(net "GND")
	)
	(segment
		(start 458.345032 -3.011932)
		(end 458.878178 -3.545078)
		(width 0.254)
		(layer "F.Cu")
		(net "GND")
	)
	(segment
		(start 284.642814 -99.986338)
		(end 284.071314 -99.986338)
		(width 0.254)
		(layer "F.Cu")
		(net "GND")
	)
	(segment
		(start 303.529746 -76.211938)
		(end 302.958246 -76.211938)
		(width 0.254)
		(layer "F.Cu")
		(net "GND")
	)
	(segment
		(start 349.140526 -2.219198)
		(end 348.774512 -2.219198)
		(width 0.508)
		(layer "F.Cu")
		(net "GND")
	)
	(segment
		(start 43.29938 -6.558534)
		(end 43.29938 -5.822442)
		(width 0.3556)
		(layer "F.Cu")
		(net "GND")
	)
	(segment
		(start 133.665214 -52.932838)
		(end 134.236714 -52.932838)
		(width 0.254)
		(layer "F.Cu")
		(net "GND")
	)
	(segment
		(start 210.849718 -16.238474)
		(end 210.849718 -15.423896)
		(width 0.4064)
		(layer "F.Cu")
		(net "GND")
	)
	(segment
		(start 121.646188 -76.706984)
		(end 122.217688 -76.706984)
		(width 0.254)
		(layer "F.Cu")
		(net "GND")
	)
	(segment
		(start 142.250414 -55.904384)
		(end 142.898114 -55.904384)
		(width 0.254)
		(layer "F.Cu")
		(net "GND")
	)
	(segment
		(start 49.249584 -142.677642)
		(end 49.24933 -142.677896)
		(width 0.4064)
		(layer "F.Cu")
		(net "GND")
	)
	(segment
		(start 445.056006 -34.7345)
		(end 449.25488 -34.7345)
		(width 0.3556)
		(layer "F.Cu")
		(net "GND")
	)
	(segment
		(start 376.335036 -120.854978)
		(end 376.638312 -120.854978)
		(width 0.254)
		(layer "F.Cu")
		(net "GND")
	)
	(segment
		(start 224.449894 -0.821182)
		(end 224.449894 0.457454)
		(width 0.4064)
		(layer "F.Cu")
		(net "GND")
	)
	(segment
		(start 196.337428 -93.734382)
		(end 196.272912 -93.798898)
		(width 0.508)
		(layer "F.Cu")
		(net "GND")
	)
	(segment
		(start 178.943 -74.6252)
		(end 178.943 -75.050396)
		(width 0.4064)
		(layer "F.Cu")
		(net "GND")
	)
	(segment
		(start 435.5719 -18.866612)
		(end 435.818788 -18.866612)
		(width 0.254)
		(layer "F.Cu")
		(net "GND")
	)
	(segment
		(start 293.51478 -70.763384)
		(end 294.08628 -70.763384)
		(width 0.254)
		(layer "F.Cu")
		(net "GND")
	)
	(segment
		(start 67.099434 -156.87294)
		(end 67.099434 -155.562046)
		(width 0.4064)
		(layer "F.Cu")
		(net "GND")
	)
	(segment
		(start 224.449894 -18.744946)
		(end 224.449894 -20.023582)
		(width 0.4064)
		(layer "F.Cu")
		(net "GND")
	)
	(segment
		(start 400.482308 -125.352302)
		(end 400.5961 -125.466094)
		(width 0.254)
		(layer "F.Cu")
		(net "GND")
	)
	(segment
		(start 182.890922 -151.219916)
		(end 182.890922 -152.370282)
		(width 0.254)
		(layer "F.Cu")
		(net "GND")
	)
	(segment
		(start 41.599358 -134.763002)
		(end 41.501314 -134.861046)
		(width 0.4064)
		(layer "F.Cu")
		(net "GND")
	)
	(segment
		(start 464.478878 -4.386072)
		(end 464.478878 -3.81)
		(width 0.4064)
		(layer "F.Cu")
		(net "GND")
	)
	(segment
		(start 233.799888 -156.87294)
		(end 233.800396 -156.87294)
		(width 0.4064)
		(layer "F.Cu")
		(net "GND")
	)
	(segment
		(start 284.929834 -92.556584)
		(end 285.501334 -92.556584)
		(width 0.254)
		(layer "F.Cu")
		(net "GND")
	)
	(segment
		(start 237.900718 -59.55284)
		(end 237.329218 -59.55284)
		(width 0.254)
		(layer "F.Cu")
		(net "GND")
	)
	(segment
		(start 135.735568 1.991868)
		(end 135.771636 1.9558)
		(width 0.3556)
		(layer "F.Cu")
		(net "GND")
	)
	(segment
		(start 130.231388 -81.659984)
		(end 130.802888 -81.659984)
		(width 0.254)
		(layer "F.Cu")
		(net "GND")
	)
	(segment
		(start 442.9125 -151.66594)
		(end 444.1952 -151.66594)
		(width 0.254)
		(layer "F.Cu")
		(net "GND")
	)
	(segment
		(start 138.499342 -143.492474)
		(end 138.040872 -143.950944)
		(width 0.4064)
		(layer "F.Cu")
		(net "GND")
	)
	(segment
		(start 385.985004 -94.37497)
		(end 385.985004 -95.205042)
		(width 0.254)
		(layer "F.Cu")
		(net "GND")
	)
	(segment
		(start 125.938788 -88.099138)
		(end 126.510288 -88.099138)
		(width 0.254)
		(layer "F.Cu")
		(net "GND")
	)
	(segment
		(start 56.049418 0.444754)
		(end 56.049418 -0.821182)
		(width 0.4064)
		(layer "F.Cu")
		(net "GND")
	)
	(segment
		(start 350.62668 -139.9286)
		(end 351.17786 -140.47978)
		(width 0.508)
		(layer "F.Cu")
		(net "GND")
	)
	(segment
		(start 72.900286 -69.45884)
		(end 72.328786 -69.45884)
		(width 0.254)
		(layer "F.Cu")
		(net "GND")
	)
	(segment
		(start 210.849718 -133.076696)
		(end 210.849718 -133.891274)
		(width 0.4064)
		(layer "F.Cu")
		(net "GND")
	)
	(segment
		(start 481.08108 -35.5854)
		(end 480.66198 -35.5854)
		(width 0.254)
		(layer "F.Cu")
		(net "GND")
	)
	(segment
		(start 308.600348 -133.0706)
		(end 308.59984 -133.076442)
		(width 0.4064)
		(layer "F.Cu")
		(net "GND")
	)
	(segment
		(start 459.00086 -118.615714)
		(end 459.004416 -118.61927)
		(width 0.4064)
		(layer "F.Cu")
		(net "GND")
	)
	(segment
		(start 307.250846 -90.575638)
		(end 307.898546 -90.575638)
		(width 0.254)
		(layer "F.Cu")
		(net "GND")
	)
	(segment
		(start 244.768624 -100.167186)
		(end 245.055644 -99.67214)
		(width 0.254)
		(layer "F.Cu")
		(net "GND")
	)
	(segment
		(start 72.1995 -11.854688)
		(end 72.142096 -11.912092)
		(width 0.4064)
		(layer "F.Cu")
		(net "GND")
	)
	(segment
		(start 283.04236 0.444754)
		(end 283.04236 0.457454)
		(width 0.3556)
		(layer "F.Cu")
		(net "GND")
	)
	(segment
		(start 300.950376 3.778758)
		(end 300.949868 3.778758)
		(width 0.3556)
		(layer "F.Cu")
		(net "GND")
	)
	(segment
		(start 423.090086 -37.734748)
		(end 423.09034 -37.734748)
		(width 0.254)
		(layer "F.Cu")
		(net "GND")
	)
	(segment
		(start 93.504258 -64.50584)
		(end 92.932758 -64.50584)
		(width 0.254)
		(layer "F.Cu")
		(net "GND")
	)
	(segment
		(start 384.53695 -112.65535)
		(end 384.1369 -113.0554)
		(width 0.12446)
		(layer "F.Cu")
		(net "GND")
	)
	(segment
		(start 233.895138 -53.60924)
		(end 233.682032 -53.977032)
		(width 0.254)
		(layer "F.Cu")
		(net "GND")
	)
	(segment
		(start 90.928698 -85.803486)
		(end 90.357198 -85.803486)
		(width 0.254)
		(layer "F.Cu")
		(net "GND")
	)
	(segment
		(start 261.27202 -13.90142)
		(end 261.7216 -14.351)
		(width 0.4064)
		(layer "F.Cu")
		(net "GND")
	)
	(segment
		(start 117.249448 3.778758)
		(end 117.249448 3.052826)
		(width 0.3556)
		(layer "F.Cu")
		(net "GND")
	)
	(segment
		(start 26.602182 -149.7838)
		(end 26.602182 -150.914354)
		(width 0.4064)
		(layer "F.Cu")
		(net "GND")
	)
	(segment
		(start 300.736 -7.609332)
		(end 300.772068 -7.6454)
		(width 0.3556)
		(layer "F.Cu")
		(net "GND")
	)
	(segment
		(start 310.299862 -143.394938)
		(end 310.0832 -143.6116)
		(width 0.3556)
		(layer "F.Cu")
		(net "GND")
	)
	(segment
		(start 287.79216 -63.829184)
		(end 288.36366 -63.829184)
		(width 0.254)
		(layer "F.Cu")
		(net "GND")
	)
	(segment
		(start 386.326888 -74.487278)
		(end 384.739388 -74.487278)
		(width 0.254)
		(layer "F.Cu")
		(net "GND")
	)
	(segment
		(start 119.799354 -4.808982)
		(end 119.337328 -4.346956)
		(width 0.4064)
		(layer "F.Cu")
		(net "GND")
	)
	(segment
		(start 198.099934 -0.821182)
		(end 198.099934 0.444754)
		(width 0.4064)
		(layer "F.Cu")
		(net "GND")
	)
	(segment
		(start 465.342224 -52.2478)
		(end 465.339938 -51.875944)
		(width 0.4064)
		(layer "F.Cu")
		(net "GND")
	)
	(segment
		(start 275.486114 -92.061538)
		(end 276.057614 -92.061538)
		(width 0.254)
		(layer "F.Cu")
		(net "GND")
	)
	(segment
		(start 400.685 -74.78522)
		(end 400.685 -75.184)
		(width 0.254)
		(layer "F.Cu")
		(net "GND")
	)
	(segment
		(start 281.495754 -50.952146)
		(end 281.494992 -50.951384)
		(width 0.2286)
		(layer "F.Cu")
		(net "GND")
	)
	(segment
		(start 115.636802 -92.061538)
		(end 116.208302 -92.061538)
		(width 0.254)
		(layer "F.Cu")
		(net "GND")
	)
	(segment
		(start 89.211912 -84.812886)
		(end 88.640412 -84.812886)
		(width 0.254)
		(layer "F.Cu")
		(net "GND")
	)
	(segment
		(start 245.627144 -53.113686)
		(end 245.055644 -53.113686)
		(width 0.254)
		(layer "F.Cu")
		(net "GND")
	)
	(segment
		(start 135.382254 -59.866784)
		(end 135.953754 -59.866784)
		(width 0.254)
		(layer "F.Cu")
		(net "GND")
	)
	(segment
		(start 77.299312 -152.279096)
		(end 77.299312 -154.063446)
		(width 0.4064)
		(layer "F.Cu")
		(net "GND")
	)
	(segment
		(start 119.799354 -133.0706)
		(end 119.799354 -133.89102)
		(width 0.3556)
		(layer "F.Cu")
		(net "GND")
	)
	(segment
		(start 78.14945 -2.3622)
		(end 78.14945 -0.821182)
		(width 0.4064)
		(layer "F.Cu")
		(net "GND")
	)
	(segment
		(start 289.22218 -60.362338)
		(end 288.65068 -60.362338)
		(width 0.254)
		(layer "F.Cu")
		(net "GND")
	)
	(segment
		(start 118.099332 -11.854688)
		(end 118.099332 -10.422382)
		(width 0.4064)
		(layer "F.Cu")
		(net "GND")
	)
	(segment
		(start 390.54532 -7.50697)
		(end 391.178034 -6.874256)
		(width 0.254)
		(layer "F.Cu")
		(net "GND")
	)
	(segment
		(start 34.74212 -11.912092)
		(end 34.799524 -11.854688)
		(width 0.4064)
		(layer "F.Cu")
		(net "GND")
	)
	(segment
		(start 279.519634 -53.381656)
		(end 279.221184 -53.8988)
		(width 0.254)
		(layer "F.Cu")
		(net "GND")
	)
	(segment
		(start 236.183678 -76.39304)
		(end 235.612178 -76.39304)
		(width 0.254)
		(layer "F.Cu")
		(net "GND")
	)
	(segment
		(start 376.20067 -125.435106)
		(end 376.20067 -125.447298)
		(width 0.254)
		(layer "F.Cu")
		(net "GND")
	)
	(segment
		(start 303.816766 -79.678784)
		(end 304.388266 -79.678784)
		(width 0.1016)
		(layer "F.Cu")
		(net "GND")
	)
	(segment
		(start 115.636802 -55.409338)
		(end 115.065302 -55.409338)
		(width 0.254)
		(layer "F.Cu")
		(net "GND")
	)
	(segment
		(start 69.64934 -15.423642)
		(end 69.64934 -13.660628)
		(width 0.4064)
		(layer "F.Cu")
		(net "GND")
	)
	(segment
		(start 450.077078 -5.979668)
		(end 450.077078 -7.789672)
		(width 0.254)
		(layer "F.Cu")
		(net "GND")
	)
	(segment
		(start 136.799574 -18.81505)
		(end 136.799574 -20.023582)
		(width 0.3556)
		(layer "F.Cu")
		(net "GND")
	)
	(segment
		(start 83.202272 -71.44004)
		(end 82.630772 -71.44004)
		(width 0.254)
		(layer "F.Cu")
		(net "GND")
	)
	(segment
		(start 383.798318 -33.770824)
		(end 383.962656 -33.935162)
		(width 0.2032)
		(layer "F.Cu")
		(net "GND")
	)
	(segment
		(start 300.382686 -74.725784)
		(end 300.954186 -74.725784)
		(width 0.254)
		(layer "F.Cu")
		(net "GND")
	)
	(segment
		(start 454.201022 -113.867184)
		(end 454.200006 -113.8682)
		(width 0.4064)
		(layer "F.Cu")
		(net "GND")
	)
	(segment
		(start 94.362778 -53.113686)
		(end 95.508318 -53.113686)
		(width 0.254)
		(layer "F.Cu")
		(net "GND")
	)
	(segment
		(start 387.985 -125.33503)
		(end 387.985 -124.504958)
		(width 0.254)
		(layer "F.Cu")
		(net "GND")
	)
	(segment
		(start 392.69035 -115.86464)
		(end 393.18565 -116.094764)
		(width 0.254)
		(layer "F.Cu")
		(net "GND")
	)
	(segment
		(start 229.549706 -143.492474)
		(end 229.091236 -143.950944)
		(width 0.4064)
		(layer "F.Cu")
		(net "GND")
	)
	(segment
		(start 402.071586 -9.44372)
		(end 402.062442 -9.452864)
		(width 0.254)
		(layer "F.Cu")
		(net "GND")
	)
	(segment
		(start 207.411828 -2.314956)
		(end 207.449928 -2.276856)
		(width 0.4064)
		(layer "F.Cu")
		(net "GND")
	)
	(segment
		(start 221.899988 -5.822442)
		(end 221.899988 -6.001512)
		(width 0.4064)
		(layer "F.Cu")
		(net "GND")
	)
	(segment
		(start 406.872186 -9.209786)
		(end 407.1112 -9.4488)
		(width 0.254)
		(layer "F.Cu")
		(net "GND")
	)
	(segment
		(start 81.485232 -55.59044)
		(end 80.913732 -55.59044)
		(width 0.254)
		(layer "F.Cu")
		(net "GND")
	)
	(segment
		(start 166.172134 -76.593192)
		(end 166.172134 -75.915266)
		(width 0.254)
		(layer "F.Cu")
		(net "GND")
	)
	(segment
		(start 175.277526 -67.945)
		(end 175.498506 -67.72402)
		(width 0.4064)
		(layer "F.Cu")
		(net "GND")
	)
	(segment
		(start 93.504258 -91.25204)
		(end 92.932758 -91.25204)
		(width 0.254)
		(layer "F.Cu")
		(net "GND")
	)
	(segment
		(start 215.860884 -3.737356)
		(end 215.949784 -3.826256)
		(width 0.4064)
		(layer "F.Cu")
		(net "GND")
	)
	(segment
		(start 422.31564 -105.7148)
		(end 421.59936 -106.43108)
		(width 0.254)
		(layer "F.Cu")
		(net "GND")
	)
	(segment
		(start 306.392326 -99.986338)
		(end 307.040026 -99.986338)
		(width 0.254)
		(layer "F.Cu")
		(net "GND")
	)
	(segment
		(start 306.050442 -10.422382)
		(end 306.049934 -10.422382)
		(width 0.4064)
		(layer "F.Cu")
		(net "GND")
	)
	(segment
		(start 390.67486 -81.906364)
		(end 390.328912 -81.906364)
		(width 0.254)
		(layer "F.Cu")
		(net "GND")
	)
	(segment
		(start 171.8564 -71.628)
		(end 172.1993 -71.628)
		(width 0.254)
		(layer "F.Cu")
		(net "GND")
	)
	(segment
		(start 301.800006 -10.422382)
		(end 301.800006 -9.21385)
		(width 0.3556)
		(layer "F.Cu")
		(net "GND")
	)
	(segment
		(start 127.44958 -11.854688)
		(end 127.44958 -10.422382)
		(width 0.4064)
		(layer "F.Cu")
		(net "GND")
	)
	(segment
		(start 241.334798 -50.63744)
		(end 240.763298 -50.63744)
		(width 0.254)
		(layer "F.Cu")
		(net "GND")
	)
	(segment
		(start 291.3888 -154.068526)
		(end 291.422074 -154.1018)
		(width 0.3556)
		(layer "F.Cu")
		(net "GND")
	)
	(segment
		(start 307.250846 -90.575384)
		(end 307.250846 -90.575638)
		(width 0.12446)
		(layer "F.Cu")
		(net "GND")
	)
	(segment
		(start 302.099726 -74.725784)
		(end 302.671226 -74.725784)
		(width 0.254)
		(layer "F.Cu")
		(net "GND")
	)
	(segment
		(start 351.364042 -138.737848)
		(end 351.72015 -138.38174)
		(width 0.508)
		(layer "F.Cu")
		(net "GND")
	)
	(segment
		(start 399.634964 -108.855002)
		(end 399.634964 -109.855)
		(width 0.254)
		(layer "F.Cu")
		(net "GND")
	)
	(segment
		(start 237.199932 -9.21385)
		(end 237.199932 -10.422382)
		(width 0.3556)
		(layer "F.Cu")
		(net "GND")
	)
	(segment
		(start 276.344634 -52.932838)
		(end 276.631654 -53.427884)
		(width 0.254)
		(layer "F.Cu")
		(net "GND")
	)
	(segment
		(start 85.777832 -63.019686)
		(end 85.206332 -63.019686)
		(width 0.254)
		(layer "F.Cu")
		(net "GND")
	)
	(segment
		(start 136.73201 -4.2926)
		(end 138.03757 -4.346956)
		(width 0.254)
		(layer "F.Cu")
		(net "GND")
	)
	(segment
		(start 152.099518 -156.87294)
		(end 152.099518 -155.612846)
		(width 0.4064)
		(layer "F.Cu")
		(net "GND")
	)
	(segment
		(start 37.34943 -146.011646)
		(end 37.34943 -147.27174)
		(width 0.4064)
		(layer "F.Cu")
		(net "GND")
	)
	(segment
		(start 374.20677 -95.568516)
		(end 374.609614 -95.165672)
		(width 0.254)
		(layer "F.Cu")
		(net "GND")
	)
	(segment
		(start 74.749406 -10.422382)
		(end 74.749406 -9.156446)
		(width 0.4064)
		(layer "F.Cu")
		(net "GND")
	)
	(segment
		(start 132.806694 -76.211938)
		(end 133.378194 -76.211938)
		(width 0.254)
		(layer "F.Cu")
		(net "GND")
	)
	(segment
		(start 124.221748 -53.427884)
		(end 123.650248 -53.427884)
		(width 0.254)
		(layer "F.Cu")
		(net "GND")
	)
	(segment
		(start 67.949572 -142.6718)
		(end 67.949572 -142.677642)
		(width 0.4064)
		(layer "F.Cu")
		(net "GND")
	)
	(segment
		(start 415.090102 -32.934656)
		(end 415.490152 -33.334706)
		(width 0.254)
		(layer "F.Cu")
		(net "GND")
	)
	(segment
		(start 306.702968 -86.501224)
		(end 306.963826 -86.240366)
		(width 0.254)
		(layer "F.Cu")
		(net "GND")
	)
	(segment
		(start 30.549342 -152.273)
		(end 30.549342 -153.598626)
		(width 0.4064)
		(layer "F.Cu")
		(net "GND")
	)
	(segment
		(start 126.467616 -53.427884)
		(end 126.5809 -53.3146)
		(width 0.254)
		(layer "F.Cu")
		(net "GND")
	)
	(segment
		(start 260.50875 -98.681286)
		(end 261.08025 -98.681286)
		(width 0.254)
		(layer "F.Cu")
		(net "GND")
	)
	(segment
		(start 381.819404 -157.539944)
		(end 381.764032 -157.484572)
		(width 0.254)
		(layer "F.Cu")
		(net "GND")
	)
	(segment
		(start 498.032532 -37.61994)
		(end 498.5512 -37.101272)
		(width 0.254)
		(layer "F.Cu")
		(net "GND")
	)
	(segment
		(start 114.039142 -13.940282)
		(end 113.849404 -14.13002)
		(width 0.4064)
		(layer "F.Cu")
		(net "GND")
	)
	(segment
		(start 396.984982 -95.205042)
		(end 397.98498 -95.205042)
		(width 0.254)
		(layer "F.Cu")
		(net "GND")
	)
	(segment
		(start 171.6024 -36.83)
		(end 171.6024 -36.8046)
		(width 0.127)
		(layer "F.Cu")
		(net "GND")
	)
	(segment
		(start 139.674854 -59.371484)
		(end 140.246354 -59.371484)
		(width 0.254)
		(layer "F.Cu")
		(net "GND")
	)
	(segment
		(start 482.6508 -31.3944)
		(end 483.108254 -31.3944)
		(width 0.254)
		(layer "F.Cu")
		(net "GND")
	)
	(segment
		(start 76.334366 -94.223586)
		(end 75.762866 -94.223586)
		(width 0.254)
		(layer "F.Cu")
		(net "GND")
	)
	(segment
		(start 136.799574 -0.821182)
		(end 136.799574 0.38735)
		(width 0.3556)
		(layer "F.Cu")
		(net "GND")
	)
	(segment
		(start 467.000844 -112.205516)
		(end 467.000844 -113.539524)
		(width 0.4064)
		(layer "F.Cu")
		(net "GND")
	)
	(segment
		(start 483.9843 -31.684468)
		(end 484.819706 -30.849062)
		(width 0.254)
		(layer "F.Cu")
		(net "GND")
	)
	(segment
		(start 30.549342 -5.822442)
		(end 30.549342 -4.277106)
		(width 0.4064)
		(layer "F.Cu")
		(net "GND")
	)
	(segment
		(start 272.910808 -56.894984)
		(end 272.339308 -56.894984)
		(width 0.254)
		(layer "F.Cu")
		(net "GND")
	)
	(segment
		(start 441.341002 -46.021752)
		(end 441.341002 -47.481998)
		(width 0.4064)
		(layer "F.Cu")
		(net "GND")
	)
	(segment
		(start 169.3926 -83.7438)
		(end 169.157396 -83.979004)
		(width 0.254)
		(layer "F.Cu")
		(net "GND")
	)
	(segment
		(start 456.477878 -4.386072)
		(end 456.477878 -3.36423)
		(width 0.254)
		(layer "F.Cu")
		(net "GND")
	)
	(segment
		(start 124.049536 -18.744946)
		(end 124.049536 -20.023582)
		(width 0.4064)
		(layer "F.Cu")
		(net "GND")
	)
	(segment
		(start 125.080268 -87.603584)
		(end 125.651768 -87.603584)
		(width 0.254)
		(layer "F.Cu")
		(net "GND")
	)
	(segment
		(start 451.742048 -51.875944)
		(end 451.733158 -50.6222)
		(width 0.508)
		(layer "F.Cu")
		(net "GND")
	)
	(segment
		(start 235.49991 -20.023582)
		(end 235.49991 -21.479256)
		(width 0.4064)
		(layer "F.Cu")
		(net "GND")
	)
	(segment
		(start 141.049502 0.444754)
		(end 141.049502 -0.821182)
		(width 0.4064)
		(layer "F.Cu")
		(net "GND")
	)
	(segment
		(start 222.75038 -137.67054)
		(end 222.749872 -137.67054)
		(width 0.4064)
		(layer "F.Cu")
		(net "GND")
	)
	(segment
		(start 303.499774 -14.409928)
		(end 303.038002 -13.948156)
		(width 0.4064)
		(layer "F.Cu")
		(net "GND")
	)
	(segment
		(start 131.699508 -10.422382)
		(end 131.699508 -9.156446)
		(width 0.4064)
		(layer "F.Cu")
		(net "GND")
	)
	(segment
		(start 236.349794 -143.405606)
		(end 236.1184 -143.637)
		(width 0.3556)
		(layer "F.Cu")
		(net "GND")
	)
	(segment
		(start 360.7308 -132.207)
		(end 360.8324 -132.3086)
		(width 0.254)
		(layer "F.Cu")
		(net "GND")
	)
	(segment
		(start 78.909672 -93.72854)
		(end 78.338172 -93.72854)
		(width 0.254)
		(layer "F.Cu")
		(net "GND")
	)
	(segment
		(start 305.200304 -133.0706)
		(end 305.199796 -133.076442)
		(width 0.4064)
		(layer "F.Cu")
		(net "GND")
	)
	(segment
		(start 136.240774 -81.164938)
		(end 136.812274 -81.164938)
		(width 0.254)
		(layer "F.Cu")
		(net "GND")
	)
	(segment
		(start 166.5986 -149.225)
		(end 166.4716 -149.098)
		(width 0.254)
		(layer "F.Cu")
		(net "GND")
	)
	(segment
		(start 198.89343 -69.864224)
		(end 198.445374 -70.31228)
		(width 0.254)
		(layer "F.Cu")
		(net "GND")
	)
	(segment
		(start 123.199398 -3.762756)
		(end 123.199398 -5.822442)
		(width 0.4064)
		(layer "F.Cu")
		(net "GND")
	)
	(segment
		(start 384.1496 -115.48999)
		(end 383.77495 -115.86464)
		(width 0.12446)
		(layer "F.Cu")
		(net "GND")
	)
	(segment
		(start 292.65626 -78.193138)
		(end 293.22776 -78.193138)
		(width 0.254)
		(layer "F.Cu")
		(net "GND")
	)
	(segment
		(start 477.2533 -34.6329)
		(end 477.2533 -34.8996)
		(width 0.254)
		(layer "F.Cu")
		(net "GND")
	)
	(segment
		(start 44.092114 -146.049746)
		(end 44.092114 -145.998946)
		(width 0.4064)
		(layer "F.Cu")
		(net "GND")
	)
	(segment
		(start 391.3378 -114.6556)
		(end 390.93775 -114.25555)
		(width 0.254)
		(layer "F.Cu")
		(net "GND")
	)
	(segment
		(start 204.899768 -15.423642)
		(end 204.899768 -13.363956)
		(width 0.4064)
		(layer "F.Cu")
		(net "GND")
	)
	(segment
		(start 234.753658 -55.094886)
		(end 233.608118 -55.094886)
		(width 0.254)
		(layer "F.Cu")
		(net "GND")
	)
	(segment
		(start 212.549994 3.599688)
		(end 212.54974 3.599434)
		(width 0.4064)
		(layer "F.Cu")
		(net "GND")
	)
	(segment
		(start 230.399844 -20.023582)
		(end 230.399844 -21.517356)
		(width 0.4064)
		(layer "F.Cu")
		(net "GND")
	)
	(segment
		(start 376.335036 -106.855006)
		(end 376.420634 -107.315)
		(width 0.254)
		(layer "F.Cu")
		(net "GND")
	)
	(segment
		(start 309.82666 -55.904384)
		(end 307.250846 -55.904384)
		(width 0.254)
		(layer "F.Cu")
		(net "GND")
	)
	(segment
		(start 73.758806 -65.000886)
		(end 73.187306 -65.000886)
		(width 0.254)
		(layer "F.Cu")
		(net "GND")
	)
	(segment
		(start 218.44254 -18.757646)
		(end 218.499944 -18.81505)
		(width 0.3556)
		(layer "F.Cu")
		(net "GND")
	)
	(segment
		(start 417.83 -55.3339)
		(end 417.83 -55.245)
		(width 0.254)
		(layer "F.Cu")
		(net "GND")
	)
	(segment
		(start 284.071314 -102.958138)
		(end 283.784294 -103.453184)
		(width 0.4064)
		(layer "F.Cu")
		(net "GND")
	)
	(segment
		(start 377.921266 -92.959174)
		(end 378.052076 -92.828364)
		(width 0.254)
		(layer "F.Cu")
		(net "GND")
	)
	(segment
		(start 33.949386 -143.391382)
		(end 33.754568 -143.5862)
		(width 0.3556)
		(layer "F.Cu")
		(net "GND")
	)
	(segment
		(start 108.19765 -52.438554)
		(end 107.910376 -52.932838)
		(width 0.254)
		(layer "F.Cu")
		(net "GND")
	)
	(segment
		(start 401.858988 -115.854988)
		(end 401.8788 -115.8748)
		(width 0.254)
		(layer "F.Cu")
		(net "GND")
	)
	(segment
		(start 70.324726 -93.72854)
		(end 69.753226 -93.72854)
		(width 0.254)
		(layer "F.Cu")
		(net "GND")
	)
	(segment
		(start 141.1478 -52.5272)
		(end 141.478 -52.5272)
		(width 0.254)
		(layer "F.Cu")
		(net "GND")
	)
	(segment
		(start 210.85048 3.778758)
		(end 210.85048 2.964688)
		(width 0.4064)
		(layer "F.Cu")
		(net "GND")
	)
	(segment
		(start 43.29938 -152.273)
		(end 43.29938 -153.014934)
		(width 0.3556)
		(layer "F.Cu")
		(net "GND")
	)
	(segment
		(start 303.529746 -90.080338)
		(end 302.958246 -90.080338)
		(width 0.3048)
		(layer "F.Cu")
		(net "GND")
	)
	(segment
		(start 290.0807 -92.556584)
		(end 290.6522 -92.556584)
		(width 0.254)
		(layer "F.Cu")
		(net "GND")
	)
	(segment
		(start 210.387946 -13.948156)
		(end 209.140806 -13.948156)
		(width 0.254)
		(layer "F.Cu")
		(net "GND")
	)
	(segment
		(start 398.225518 -126.341886)
		(end 398.048734 -126.165102)
		(width 0.254)
		(layer "F.Cu")
		(net "GND")
	)
	(segment
		(start 47.549308 -17.208246)
		(end 47.549308 -15.602966)
		(width 0.4064)
		(layer "F.Cu")
		(net "GND")
	)
	(segment
		(start 87.781892 -99.17684)
		(end 87.494872 -98.681286)
		(width 0.254)
		(layer "F.Cu")
		(net "GND")
	)
	(segment
		(start 38.199568 -133.255512)
		(end 38.199314 -133.255766)
		(width 0.4064)
		(layer "F.Cu")
		(net "GND")
	)
	(segment
		(start 116.495322 -50.952146)
		(end 116.49456 -50.951384)
		(width 0.2286)
		(layer "F.Cu")
		(net "GND")
	)
	(segment
		(start 407.192226 -105.664)
		(end 407.3271 -105.529126)
		(width 0.254)
		(layer "F.Cu")
		(net "GND")
	)
	(segment
		(start 33.949386 -6.536182)
		(end 33.949386 -5.822442)
		(width 0.3556)
		(layer "F.Cu")
		(net "GND")
	)
	(segment
		(start 111.344202 -56.894984)
		(end 110.772702 -56.894984)
		(width 0.254)
		(layer "F.Cu")
		(net "GND")
	)
	(segment
		(start 243.910104 -69.953886)
		(end 243.338604 -69.953886)
		(width 0.254)
		(layer "F.Cu")
		(net "GND")
	)
	(segment
		(start 254.212344 -63.019686)
		(end 253.640844 -63.019686)
		(width 0.254)
		(layer "F.Cu")
		(net "GND")
	)
	(segment
		(start 61.999368 -13.541756)
		(end 61.821568 -13.363956)
		(width 0.4064)
		(layer "F.Cu")
		(net "GND")
	)
	(segment
		(start 253.353824 -67.47764)
		(end 252.782324 -67.47764)
		(width 0.254)
		(layer "F.Cu")
		(net "GND")
	)
	(segment
		(start 239.617758 -87.28964)
		(end 239.046258 -87.28964)
		(width 0.254)
		(layer "F.Cu")
		(net "GND")
	)
	(segment
		(start 235.325158 -83.822286)
		(end 234.753658 -83.822286)
		(width 0.254)
		(layer "F.Cu")
		(net "GND")
	)
	(segment
		(start 313.699906 -10.422382)
		(end 313.699906 -9.156446)
		(width 0.4064)
		(layer "F.Cu")
		(net "GND")
	)
	(segment
		(start 241.334798 -101.15804)
		(end 240.763298 -101.15804)
		(width 0.254)
		(layer "F.Cu")
		(net "GND")
	)
	(segment
		(start 365.506 -106.5149)
		(end 365.506 -107.442)
		(width 0.254)
		(layer "F.Cu")
		(net "GND")
	)
	(segment
		(start 124.89942 -5.822442)
		(end 124.89942 -7.509002)
		(width 0.4064)
		(layer "F.Cu")
		(net "GND")
	)
	(segment
		(start 130.231388 -73.735184)
		(end 130.802888 -73.735184)
		(width 0.254)
		(layer "F.Cu")
		(net "GND")
	)
	(segment
		(start 251.636784 -88.28024)
		(end 251.065284 -88.28024)
		(width 0.254)
		(layer "F.Cu")
		(net "GND")
	)
	(segment
		(start 436.522114 -28.632404)
		(end 436.522114 -28.631642)
		(width 0.3048)
		(layer "F.Cu")
		(net "GND")
	)
	(segment
		(start 234.649772 -4.7371)
		(end 234.560872 -4.6482)
		(width 0.4064)
		(layer "F.Cu")
		(net "GND")
	)
	(segment
		(start 119.929402 -56.894984)
		(end 119.357902 -56.894984)
		(width 0.254)
		(layer "F.Cu")
		(net "GND")
	)
	(segment
		(start 1.917446 -135.420354)
		(end 1.999234 -135.338566)
		(width 0.254)
		(layer "F.Cu")
		(net "GND")
	)
	(segment
		(start 243.910104 -65.991486)
		(end 243.338604 -65.991486)
		(width 0.254)
		(layer "F.Cu")
		(net "GND")
	)
	(segment
		(start 123.363228 -101.471984)
		(end 123.934728 -101.471984)
		(width 0.254)
		(layer "F.Cu")
		(net "GND")
	)
	(segment
		(start 380.985014 -124.504958)
		(end 381.985012 -124.504958)
		(width 0.254)
		(layer "F.Cu")
		(net "GND")
	)
	(segment
		(start 387.734048 -118.6688)
		(end 387.73735 -118.670324)
		(width 0.254)
		(layer "F.Cu")
		(net "GND")
	)
	(segment
		(start 145.082768 -6.7564)
		(end 145.082768 -7.606538)
		(width 0.3556)
		(layer "F.Cu")
		(net "GND")
	)
	(segment
		(start 261.27202 -12.961112)
		(end 261.27202 -13.90142)
		(width 0.4064)
		(layer "F.Cu")
		(net "GND")
	)
	(segment
		(start 109.627416 -96.518984)
		(end 110.198916 -96.518984)
		(width 0.254)
		(layer "F.Cu")
		(net "GND")
	)
	(segment
		(start 112.397032 -3.3528)
		(end 113.069878 -3.3528)
		(width 0.381)
		(layer "F.Cu")
		(net "GND")
	)
	(segment
		(start 317.100458 -137.67054)
		(end 317.09995 -137.67054)
		(width 0.4064)
		(layer "F.Cu")
		(net "GND")
	)
	(segment
		(start 83.202272 -68.46824)
		(end 82.630772 -68.46824)
		(width 0.254)
		(layer "F.Cu")
		(net "GND")
	)
	(segment
		(start 31.417768 -149.6568)
		(end 31.417768 -148.789644)
		(width 0.4064)
		(layer "F.Cu")
		(net "GND")
	)
	(segment
		(start 141.049502 -0.821182)
		(end 141.049502 -2.314956)
		(width 0.4064)
		(layer "F.Cu")
		(net "GND")
	)
	(segment
		(start 215.949784 -144.364202)
		(end 215.85174 -144.462246)
		(width 0.4064)
		(layer "F.Cu")
		(net "GND")
	)
	(segment
		(start 84.919312 -52.618386)
		(end 84.919312 -51.62804)
		(width 0.2286)
		(layer "F.Cu")
		(net "GND")
	)
	(segment
		(start 286.07512 -53.923184)
		(end 286.64662 -53.923184)
		(width 0.254)
		(layer "F.Cu")
		(net "GND")
	)
	(segment
		(start 207.449928 -146.037046)
		(end 207.424528 -146.011646)
		(width 0.4064)
		(layer "F.Cu")
		(net "GND")
	)
	(segment
		(start 244.768624 -55.59044)
		(end 244.197124 -55.59044)
		(width 0.254)
		(layer "F.Cu")
		(net "GND")
	)
	(segment
		(start 377.33605 -122.32005)
		(end 377.33605 -121.87428)
		(width 0.254)
		(layer "F.Cu")
		(net "GND")
	)
	(segment
		(start 296.66184 -92.061538)
		(end 296.09034 -92.061538)
		(width 0.3048)
		(layer "F.Cu")
		(net "GND")
	)
	(segment
		(start 252.495304 -95.709486)
		(end 251.923804 -95.709486)
		(width 0.254)
		(layer "F.Cu")
		(net "GND")
	)
	(segment
		(start 157.28188 -22.7457)
		(end 157.503368 -22.524212)
		(width 0.4064)
		(layer "F.Cu")
		(net "GND")
	)
	(segment
		(start 401.368768 -124.735844)
		(end 401.368768 -125.283468)
		(width 0.254)
		(layer "F.Cu")
		(net "GND")
	)
	(segment
		(start 303.499774 -4.808728)
		(end 303.499774 -5.822442)
		(width 0.4064)
		(layer "F.Cu")
		(net "GND")
	)
	(segment
		(start 395.16685 -117.811804)
		(end 395.66215 -117.58168)
		(width 0.254)
		(layer "F.Cu")
		(net "GND")
	)
	(segment
		(start 382.93675 -112.65535)
		(end 382.725676 -112.866424)
		(width 0.1143)
		(layer "F.Cu")
		(net "GND")
	)
	(segment
		(start 137.957814 -69.277738)
		(end 138.529314 -69.277738)
		(width 0.254)
		(layer "F.Cu")
		(net "GND")
	)
	(segment
		(start 455.779632 -33.687258)
		(end 457.2 -33.687258)
		(width 0.254)
		(layer "F.Cu")
		(net "GND")
	)
	(segment
		(start 386.644388 -110.547912)
		(end 386.93725 -110.25505)
		(width 0.12446)
		(layer "F.Cu")
		(net "GND")
	)
	(segment
		(start 261.1628 -139.954)
		(end 261.1628 -139.2174)
		(width 0.4064)
		(layer "F.Cu")
		(net "GND")
	)
	(segment
		(start 378.484892 -125.750066)
		(end 378.484892 -124.919994)
		(width 0.254)
		(layer "F.Cu")
		(net "GND")
	)
	(segment
		(start 127.44958 -156.87294)
		(end 127.44958 -155.67025)
		(width 0.3556)
		(layer "F.Cu")
		(net "GND")
	)
	(segment
		(start 291.466016 -53.427884)
		(end 291.5793 -53.3146)
		(width 0.254)
		(layer "F.Cu")
		(net "GND")
	)
	(segment
		(start 398.13865 -116.094764)
		(end 398.63395 -115.86464)
		(width 0.254)
		(layer "F.Cu")
		(net "GND")
	)
	(segment
		(start 287.79216 -65.810384)
		(end 288.36366 -65.810384)
		(width 0.254)
		(layer "F.Cu")
		(net "GND")
	)
	(segment
		(start 182.44058 -51.5874)
		(end 182.973726 -52.120546)
		(width 0.254)
		(layer "F.Cu")
		(net "GND")
	)
	(segment
		(start 249.061224 -71.935086)
		(end 248.489724 -71.935086)
		(width 0.254)
		(layer "F.Cu")
		(net "GND")
	)
	(segment
		(start 31.443168 -129.525268)
		(end 31.39948 -129.568956)
		(width 0.4064)
		(layer "F.Cu")
		(net "GND")
	)
	(segment
		(start 133.665214 -85.622384)
		(end 134.236714 -85.622384)
		(width 0.254)
		(layer "F.Cu")
		(net "GND")
	)
	(segment
		(start 220.199966 -133.076442)
		(end 220.199712 -133.076696)
		(width 0.4064)
		(layer "F.Cu")
		(net "GND")
	)
	(segment
		(start 295.23182 -83.641184)
		(end 295.80332 -83.641184)
		(width 0.254)
		(layer "F.Cu")
		(net "GND")
	)
	(segment
		(start 457.980288 -53.270912)
		(end 457.980288 -53.14442)
		(width 0.4064)
		(layer "F.Cu")
		(net "GND")
	)
	(segment
		(start 294.3733 -84.136738)
		(end 294.9448 -84.136738)
		(width 0.254)
		(layer "F.Cu")
		(net "GND")
	)
	(segment
		(start 70.324726 -82.83194)
		(end 69.753226 -82.83194)
		(width 0.254)
		(layer "F.Cu")
		(net "GND")
	)
	(segment
		(start 62.849506 -146.06905)
		(end 62.792102 -146.011646)
		(width 0.3556)
		(layer "F.Cu")
		(net "GND")
	)
	(segment
		(start 291.3888 -17.213326)
		(end 291.3888 -16.3576)
		(width 0.3556)
		(layer "F.Cu")
		(net "GND")
	)
	(segment
		(start 55.19928 -152.279096)
		(end 55.19928 -153.093674)
		(width 0.4064)
		(layer "F.Cu")
		(net "GND")
	)
	(segment
		(start 449.276978 -5.464048)
		(end 449.561458 -5.464048)
		(width 0.254)
		(layer "F.Cu")
		(net "GND")
	)
	(segment
		(start 379.81255 -114.1476)
		(end 380.30785 -114.377724)
		(width 0.254)
		(layer "F.Cu")
		(net "GND")
	)
	(segment
		(start 193.6242 -53.3654)
		(end 193.6242 -54.1274)
		(width 0.4064)
		(layer "F.Cu")
		(net "GND")
	)
	(segment
		(start 74.617326 -62.52464)
		(end 74.045826 -62.52464)
		(width 0.254)
		(layer "F.Cu")
		(net "GND")
	)
	(segment
		(start 292.450012 -146.06905)
		(end 292.392608 -146.011646)
		(width 0.3556)
		(layer "F.Cu")
		(net "GND")
	)
	(segment
		(start 71.183246 -81.34604)
		(end 70.611746 -81.34604)
		(width 0.254)
		(layer "F.Cu")
		(net "GND")
	)
	(segment
		(start 301.241206 -73.240138)
		(end 301.812706 -73.240138)
		(width 0.254)
		(layer "F.Cu")
		(net "GND")
	)
	(segment
		(start 237.20044 -10.422382)
		(end 237.199932 -10.422382)
		(width 0.3556)
		(layer "F.Cu")
		(net "GND")
	)
	(segment
		(start 296.66184 -87.108538)
		(end 296.09034 -87.108538)
		(width 0.254)
		(layer "F.Cu")
		(net "GND")
	)
	(segment
		(start 74.617326 -50.63744)
		(end 74.045826 -50.63744)
		(width 0.254)
		(layer "F.Cu")
		(net "GND")
	)
	(segment
		(start 453.573896 -2.74574)
		(end 454.077578 -3.249422)
		(width 0.4064)
		(layer "F.Cu")
		(net "GND")
	)
	(segment
		(start 410.290264 -29.734764)
		(end 409.890214 -29.334714)
		(width 0.254)
		(layer "F.Cu")
		(net "GND")
	)
	(segment
		(start 249.919744 -74.411586)
		(end 249.348244 -74.411586)
		(width 0.254)
		(layer "F.Cu")
		(net "GND")
	)
	(segment
		(start 147.849336 3.778758)
		(end 147.849336 2.963926)
		(width 0.4064)
		(layer "F.Cu")
		(net "GND")
	)
	(segment
		(start 247.344184 -100.662486)
		(end 247.344184 -101.508814)
		(width 0.2032)
		(layer "F.Cu")
		(net "GND")
	)
	(segment
		(start 71.171562 -13.363956)
		(end 71.349362 -13.541756)
		(width 0.4064)
		(layer "F.Cu")
		(net "GND")
	)
	(segment
		(start 146.092164 0.444754)
		(end 146.092164 0.457454)
		(width 0.3556)
		(layer "F.Cu")
		(net "GND")
	)
	(segment
		(start 290.0807 -68.782184)
		(end 290.6522 -68.782184)
		(width 0.254)
		(layer "F.Cu")
		(net "GND")
	)
	(segment
		(start 214.250524 -3.763518)
		(end 214.249762 -3.762756)
		(width 0.4064)
		(layer "F.Cu")
		(net "GND")
	)
	(segment
		(start 285.650432 -0.821182)
		(end 285.649924 -0.821182)
		(width 0.4064)
		(layer "F.Cu")
		(net "GND")
	)
	(segment
		(start 285.7881 -92.061538)
		(end 286.3596 -92.061538)
		(width 0.254)
		(layer "F.Cu")
		(net "GND")
	)
	(segment
		(start 465.36737 -148.083778)
		(end 465.003388 -147.719796)
		(width 0.254)
		(layer "F.Cu")
		(net "GND")
	)
	(segment
		(start 235.325158 -91.747086)
		(end 234.753658 -91.747086)
		(width 0.254)
		(layer "F.Cu")
		(net "GND")
	)
	(segment
		(start 64.549274 -15.423896)
		(end 64.549274 -16.238474)
		(width 0.4064)
		(layer "F.Cu")
		(net "GND")
	)
	(segment
		(start 180.1114 -58.1406)
		(end 180.6702 -58.1406)
		(width 0.381)
		(layer "F.Cu")
		(net "GND")
	)
	(segment
		(start 397.0782 -126.071884)
		(end 396.984982 -126.165102)
		(width 0.254)
		(layer "F.Cu")
		(net "GND")
	)
	(segment
		(start 311.15 -21.455888)
		(end 311.092596 -21.513292)
		(width 0.4064)
		(layer "F.Cu")
		(net "GND")
	)
	(segment
		(start 114.699542 -0.821182)
		(end 114.699542 0.457454)
		(width 0.4064)
		(layer "F.Cu")
		(net "GND")
	)
	(segment
		(start 145.12163 -3.762756)
		(end 145.29943 -3.940556)
		(width 0.4064)
		(layer "F.Cu")
		(net "GND")
	)
	(segment
		(start 436.921656 -32.2072)
		(end 436.522114 -32.606742)
		(width 0.3048)
		(layer "F.Cu")
		(net "GND")
	)
	(segment
		(start 227.000308 -133.0706)
		(end 226.9998 -133.076442)
		(width 0.3556)
		(layer "F.Cu")
		(net "GND")
	)
	(segment
		(start 406.600152 -148.86432)
		(end 407.047954 -148.86432)
		(width 0.3556)
		(layer "F.Cu")
		(net "GND")
	)
	(segment
		(start 220.199712 -143.492474)
		(end 219.741242 -143.950944)
		(width 0.4064)
		(layer "F.Cu")
		(net "GND")
	)
	(segment
		(start 227.000308 -15.423642)
		(end 226.9998 -15.423642)
		(width 0.3556)
		(layer "F.Cu")
		(net "GND")
	)
	(segment
		(start 75.599544 -133.0706)
		(end 75.599544 -133.255512)
		(width 0.4064)
		(layer "F.Cu")
		(net "GND")
	)
	(segment
		(start 389.71855 -122.7328)
		(end 390.21385 -122.962924)
		(width 0.254)
		(layer "F.Cu")
		(net "GND")
	)
	(segment
		(start 420.473886 -3.736086)
		(end 420.473886 -4.386072)
		(width 0.254)
		(layer "F.Cu")
		(net "GND")
	)
	(segment
		(start 389.984996 -126.165102)
		(end 389.984996 -126.18339)
		(width 0.254)
		(layer "F.Cu")
		(net "GND")
	)
	(segment
		(start 247.4595 -12.954)
		(end 246.61876 -12.954)
		(width 0.4064)
		(layer "F.Cu")
		(net "GND")
	)
	(segment
		(start 72.1995 -156.87294)
		(end 72.1995 -155.67025)
		(width 0.3556)
		(layer "F.Cu")
		(net "GND")
	)
	(segment
		(start 416.289998 -33.334706)
		(end 416.690048 -33.734756)
		(width 0.254)
		(layer "F.Cu")
		(net "GND")
	)
	(segment
		(start 448.533266 -50.6222)
		(end 448.532504 -50.5206)
		(width 0.508)
		(layer "F.Cu")
		(net "GND")
	)
	(segment
		(start 347.5228 -157.2768)
		(end 347.5228 -156.7688)
		(width 0.4064)
		(layer "F.Cu")
		(net "GND")
	)
	(segment
		(start 292.65626 -61.352938)
		(end 293.22776 -61.352938)
		(width 0.254)
		(layer "F.Cu")
		(net "GND")
	)
	(segment
		(start 290.74999 -147.27174)
		(end 290.74999 -146.011646)
		(width 0.4064)
		(layer "F.Cu")
		(net "GND")
	)
	(segment
		(start 304.349912 -137.67054)
		(end 304.349912 -136.410446)
		(width 0.4064)
		(layer "F.Cu")
		(net "GND")
	)
	(segment
		(start 317.100458 -152.273)
		(end 317.09995 -152.278842)
		(width 0.4064)
		(layer "F.Cu")
		(net "GND")
	)
	(segment
		(start 429.566578 -35.82035)
		(end 429.566578 -35.532314)
		(width 0.254)
		(layer "F.Cu")
		(net "GND")
	)
	(segment
		(start 294.14978 -143.492474)
		(end 293.69131 -143.950944)
		(width 0.4064)
		(layer "F.Cu")
		(net "GND")
	)
	(segment
		(start 387.73735 -95.888556)
		(end 387.985 -95.205042)
		(width 0.254)
		(layer "F.Cu")
		(net "GND")
	)
	(segment
		(start 398.63395 -115.86464)
		(end 399.12925 -116.094764)
		(width 0.254)
		(layer "F.Cu")
		(net "GND")
	)
	(segment
		(start 255.153668 -149.444964)
		(end 255.627124 -149.444964)
		(width 0.4572)
		(layer "F.Cu")
		(net "GND")
	)
	(segment
		(start 174.63008 -64.64046)
		(end 174.625 -64.63538)
		(width 0.4064)
		(layer "F.Cu")
		(net "GND")
	)
	(segment
		(start 393.690348 -115.240308)
		(end 393.6873 -115.240308)
		(width 0.254)
		(layer "F.Cu")
		(net "GND")
	)
	(segment
		(start 473.400882 -112.205516)
		(end 473.400882 -113.635282)
		(width 0.4064)
		(layer "F.Cu")
		(net "GND")
	)
	(segment
		(start 205.749906 -9.143746)
		(end 205.749906 -10.422382)
		(width 0.4064)
		(layer "F.Cu")
		(net "GND")
	)
	(segment
		(start 398.861534 -126.165102)
		(end 398.903444 -126.207012)
		(width 0.254)
		(layer "F.Cu")
		(net "GND")
	)
	(segment
		(start 312.849768 -143.492474)
		(end 312.391298 -143.950944)
		(width 0.4064)
		(layer "F.Cu")
		(net "GND")
	)
	(segment
		(start 304.349912 -156.87294)
		(end 304.349912 -155.612846)
		(width 0.4064)
		(layer "F.Cu")
		(net "GND")
	)
	(segment
		(start 370.284756 -3.445764)
		(end 370.28501 -3.446018)
		(width 0.4572)
		(layer "F.Cu")
		(net "GND")
	)
	(segment
		(start 346.3036 -9.850628)
		(end 346.580206 -9.574022)
		(width 0.4064)
		(layer "F.Cu")
		(net "GND")
	)
	(segment
		(start 125.938788 -98.005138)
		(end 126.510288 -98.005138)
		(width 0.254)
		(layer "F.Cu")
		(net "GND")
	)
	(segment
		(start 304.162968 -51.144424)
		(end 303.816766 -51.490626)
		(width 0.254)
		(layer "F.Cu")
		(net "GND")
	)
	(segment
		(start 215.949784 -153.965402)
		(end 215.85174 -154.063446)
		(width 0.4064)
		(layer "F.Cu")
		(net "GND")
	)
	(segment
		(start 396.248382 -101.227382)
		(end 396.65275 -101.039676)
		(width 0.254)
		(layer "F.Cu")
		(net "GND")
	)
	(segment
		(start 394.17625 -120.15724)
		(end 394.67155 -120.387364)
		(width 0.254)
		(layer "F.Cu")
		(net "GND")
	)
	(segment
		(start -4.064 -144.8562)
		(end -4.064 -143.672306)
		(width 0.254)
		(layer "F.Cu")
		(net "GND")
	)
	(segment
		(start 484.819706 -30.849062)
		(end 484.820468 -30.849062)
		(width 0.254)
		(layer "F.Cu")
		(net "GND")
	)
	(segment
		(start 468.60079 -116.993162)
		(end 468.60079 -118.47195)
		(width 0.4064)
		(layer "F.Cu")
		(net "GND")
	)
	(segment
		(start 73.758806 -96.700086)
		(end 73.187306 -96.700086)
		(width 0.254)
		(layer "F.Cu")
		(net "GND")
	)
	(segment
		(start 237.142528 -146.011646)
		(end 237.142528 -145.998946)
		(width 0.3556)
		(layer "F.Cu")
		(net "GND")
	)
	(segment
		(start 125.749558 -11.878056)
		(end 125.749558 -10.422382)
		(width 0.4064)
		(layer "F.Cu")
		(net "GND")
	)
	(segment
		(start 169.9768 -73.66)
		(end 169.926 -73.7108)
		(width 0.254)
		(layer "F.Cu")
		(net "GND")
	)
	(segment
		(start 175.27016 -104.65562)
		(end 174.59198 -105.3338)
		(width 0.254)
		(layer "F.Cu")
		(net "GND")
	)
	(segment
		(start 268.806676 -95.21444)
		(end 269.416276 -95.21444)
		(width 0.254)
		(layer "F.Cu")
		(net "GND")
	)
	(segment
		(start 306.392326 -56.399938)
		(end 308.393338 -56.399938)
		(width 0.254)
		(layer "F.Cu")
		(net "GND")
	)
	(segment
		(start 233.799888 -147.27174)
		(end 233.799888 -145.998946)
		(width 0.4064)
		(layer "F.Cu")
		(net "GND")
	)
	(segment
		(start 312.849768 -5.822442)
		(end 312.849768 -6.637274)
		(width 0.4064)
		(layer "F.Cu")
		(net "GND")
	)
	(segment
		(start 137.670794 -95.528384)
		(end 137.099294 -95.528384)
		(width 0.254)
		(layer "F.Cu")
		(net "GND")
	)
	(segment
		(start 247.344184 -60.047886)
		(end 246.772684 -60.047886)
		(width 0.254)
		(layer "F.Cu")
		(net "GND")
	)
	(segment
		(start 78.898496 -149.8092)
		(end 78.593696 -150.114)
		(width 0.508)
		(layer "F.Cu")
		(net "GND")
	)
	(segment
		(start 231.25049 -17.207484)
		(end 231.249728 -17.208246)
		(width 0.4064)
		(layer "F.Cu")
		(net "GND")
	)
	(segment
		(start 291.599874 -152.278842)
		(end 291.599874 -153.001726)
		(width 0.3556)
		(layer "F.Cu")
		(net "GND")
	)
	(segment
		(start 184.6072 -153.416)
		(end 184.6072 -154.0256)
		(width 0.254)
		(layer "F.Cu")
		(net "GND")
	)
	(segment
		(start 75.599544 -13.36421)
		(end 75.599544 -15.423642)
		(width 0.4064)
		(layer "F.Cu")
		(net "GND")
	)
	(segment
		(start 349.123 -18.669)
		(end 349.123 -19.05)
		(width 0.254)
		(layer "F.Cu")
		(net "GND")
	)
	(segment
		(start 125.080268 -62.838584)
		(end 125.651768 -62.838584)
		(width 0.254)
		(layer "F.Cu")
		(net "GND")
	)
	(segment
		(start 279.699974 -156.87294)
		(end 279.700482 -156.87294)
		(width 0.4064)
		(layer "F.Cu")
		(net "GND")
	)
	(segment
		(start 248.202704 -90.26144)
		(end 247.631204 -90.26144)
		(width 0.254)
		(layer "F.Cu")
		(net "GND")
	)
	(segment
		(start 119.070882 -93.052138)
		(end 119.642382 -93.052138)
		(width 0.254)
		(layer "F.Cu")
		(net "GND")
	)
	(segment
		(start 236.349794 -16.151606)
		(end 236.349794 -15.423642)
		(width 0.3556)
		(layer "F.Cu")
		(net "GND")
	)
	(segment
		(start 31.260796 -69.831204)
		(end 31.260796 -70.090792)
		(width 0.381)
		(layer "F.Cu")
		(net "GND")
	)
	(segment
		(start 244.768624 -78.37424)
		(end 244.197124 -78.37424)
		(width 0.254)
		(layer "F.Cu")
		(net "GND")
	)
	(segment
		(start 412.877 -22.0345)
		(end 413.5755 -22.0345)
		(width 0.254)
		(layer "F.Cu")
		(net "GND")
	)
	(segment
		(start 288.19983 -3.762756)
		(end 288.19983 -5.822442)
		(width 0.4064)
		(layer "F.Cu")
		(net "GND")
	)
	(segment
		(start 195.094606 -13.929106)
		(end 194.564 -13.3985)
		(width 0.4064)
		(layer "F.Cu")
		(net "GND")
	)
	(segment
		(start 31.400496 -77.351382)
		(end 31.400496 -78.161134)
		(width 0.508)
		(layer "F.Cu")
		(net "GND")
	)
	(segment
		(start 234.466638 -97.19564)
		(end 233.895138 -97.19564)
		(width 0.254)
		(layer "F.Cu")
		(net "GND")
	)
	(segment
		(start 232.950512 -142.6718)
		(end 232.950004 -142.677642)
		(width 0.4064)
		(layer "F.Cu")
		(net "GND")
	)
	(segment
		(start 116.495322 -53.923184)
		(end 115.923822 -53.923184)
		(width 0.254)
		(layer "F.Cu")
		(net "GND")
	)
	(segment
		(start 169.9768 -74.7268)
		(end 169.9768 -74.93)
		(width 0.254)
		(layer "F.Cu")
		(net "GND")
	)
	(segment
		(start 70.499478 -147.27174)
		(end 70.499478 -146.049746)
		(width 0.4064)
		(layer "F.Cu")
		(net "GND")
	)
	(segment
		(start 24.7015 -82.90306)
		(end 24.7015 -83.155028)
		(width 0.254)
		(layer "F.Cu")
		(net "GND")
	)
	(segment
		(start 139.674854 -54.418738)
		(end 140.246354 -54.418738)
		(width 0.254)
		(layer "F.Cu")
		(net "GND")
	)
	(segment
		(start 445.350138 -62.00267)
		(end 445.350138 -60.835286)
		(width 0.381)
		(layer "F.Cu")
		(net "GND")
	)
	(segment
		(start 232.099866 -9.156446)
		(end 232.099866 -10.422382)
		(width 0.4064)
		(layer "F.Cu")
		(net "GND")
	)
	(segment
		(start 136.240774 -79.183738)
		(end 136.812274 -79.183738)
		(width 0.254)
		(layer "F.Cu")
		(net "GND")
	)
	(segment
		(start 2.5908 -134.747)
		(end 2.5908 -134.3152)
		(width 0.4064)
		(layer "F.Cu")
		(net "GND")
	)
	(segment
		(start 203.200508 3.778758)
		(end 203.2 3.778758)
		(width 0.4064)
		(layer "F.Cu")
		(net "GND")
	)
	(segment
		(start 107.910376 -58.876438)
		(end 107.338876 -58.876438)
		(width 0.254)
		(layer "F.Cu")
		(net "GND")
	)
	(segment
		(start 236.349794 -133.804406)
		(end 236.1184 -134.0358)
		(width 0.3556)
		(layer "F.Cu")
		(net "GND")
	)
	(segment
		(start 289.22218 -58.381138)
		(end 288.65068 -58.381138)
		(width 0.254)
		(layer "F.Cu")
		(net "GND")
	)
	(segment
		(start 141.049502 -20.023582)
		(end 141.049502 -21.517356)
		(width 0.4064)
		(layer "F.Cu")
		(net "GND")
	)
	(segment
		(start 480.897692 -142.875)
		(end 480.5045 -142.875)
		(width 0.254)
		(layer "F.Cu")
		(net "GND")
	)
	(segment
		(start 217.4494 1.978406)
		(end 217.472006 1.9558)
		(width 0.3556)
		(layer "F.Cu")
		(net "GND")
	)
	(segment
		(start 295.000426 -10.422382)
		(end 294.999918 -10.422382)
		(width 0.4064)
		(layer "F.Cu")
		(net "GND")
	)
	(segment
		(start 455.749914 -53.261514)
		(end 455.742548 -52.2478)
		(width 0.4064)
		(layer "F.Cu")
		(net "GND")
	)
	(segment
		(start 125.080268 -94.538038)
		(end 125.651768 -94.538038)
		(width 0.3048)
		(layer "F.Cu")
		(net "GND")
	)
	(segment
		(start 196.399912 -147.27174)
		(end 196.399912 -148.771356)
		(width 0.4064)
		(layer "F.Cu")
		(net "GND")
	)
	(segment
		(start 43.29938 -133.0706)
		(end 43.29938 -133.812534)
		(width 0.3556)
		(layer "F.Cu")
		(net "GND")
	)
	(segment
		(start 266.231116 -89.765886)
		(end 265.659616 -89.765886)
		(width 0.254)
		(layer "F.Cu")
		(net "GND")
	)
	(segment
		(start 307.898546 -63.829184)
		(end 307.898546 -64.172084)
		(width 0.254)
		(layer "F.Cu")
		(net "GND")
	)
	(segment
		(start 260.22173 -63.51524)
		(end 259.65023 -63.51524)
		(width 0.254)
		(layer "F.Cu")
		(net "GND")
	)
	(segment
		(start 178.0286 -67.183)
		(end 178.2826 -67.437)
		(width 0.254)
		(layer "F.Cu")
		(net "GND")
	)
	(segment
		(start 301.241206 -60.362338)
		(end 301.812706 -60.362338)
		(width 0.254)
		(layer "F.Cu")
		(net "GND")
	)
	(segment
		(start 376.335036 -101.855016)
		(end 376.9233 -102.0191)
		(width 0.254)
		(layer "F.Cu")
		(net "GND")
	)
	(segment
		(start 64.549528 -152.278842)
		(end 64.549274 -152.279096)
		(width 0.4064)
		(layer "F.Cu")
		(net "GND")
	)
	(segment
		(start 223.60001 -15.423642)
		(end 223.60001 -13.36421)
		(width 0.4064)
		(layer "F.Cu")
		(net "GND")
	)
	(segment
		(start 386.644388 -109.962188)
		(end 386.93725 -110.25505)
		(width 0.12446)
		(layer "F.Cu")
		(net "GND")
	)
	(segment
		(start 254.789432 -12.954)
		(end 255.130046 -12.613386)
		(width 0.4572)
		(layer "F.Cu")
		(net "GND")
	)
	(segment
		(start 303.038002 -4.346956)
		(end 303.499774 -4.808728)
		(width 0.4064)
		(layer "F.Cu")
		(net "GND")
	)
	(segment
		(start 465.400898 -116.993162)
		(end 465.400898 -118.615714)
		(width 0.4064)
		(layer "F.Cu")
		(net "GND")
	)
	(segment
		(start 79.360268 -12.954)
		(end 78.631288 -12.954)
		(width 0.4064)
		(layer "F.Cu")
		(net "GND")
	)
	(segment
		(start 34.799524 -146.281902)
		(end 34.74212 -146.224498)
		(width 0.4064)
		(layer "F.Cu")
		(net "GND")
	)
	(segment
		(start 196.469 -2.384044)
		(end 196.469 -3.321812)
		(width 0.381)
		(layer "F.Cu")
		(net "GND")
	)
	(segment
		(start 399.542 -99.354894)
		(end 399.544286 -99.367848)
		(width 0.254)
		(layer "F.Cu")
		(net "GND")
	)
	(segment
		(start 310.30037 -152.273)
		(end 310.299862 -152.278842)
		(width 0.3556)
		(layer "F.Cu")
		(net "GND")
	)
	(segment
		(start 83.202272 -64.50584)
		(end 82.630772 -64.50584)
		(width 0.254)
		(layer "F.Cu")
		(net "GND")
	)
	(segment
		(start 129.149348 -15.423642)
		(end 129.149348 -14.409928)
		(width 0.4064)
		(layer "F.Cu")
		(net "GND")
	)
	(segment
		(start 133.39953 0.457454)
		(end 133.39953 -0.821182)
		(width 0.4064)
		(layer "F.Cu")
		(net "GND")
	)
	(segment
		(start 463.741008 -45.970698)
		(end 463.741008 -47.481998)
		(width 0.4064)
		(layer "F.Cu")
		(net "GND")
	)
	(segment
		(start 73.899522 3.778758)
		(end 73.899268 3.778504)
		(width 0.4064)
		(layer "F.Cu")
		(net "GND")
	)
	(segment
		(start 74.749406 -156.87294)
		(end 74.749406 -155.511246)
		(width 0.4064)
		(layer "F.Cu")
		(net "GND")
	)
	(segment
		(start 47.549308 -3.762756)
		(end 47.549562 -3.76301)
		(width 0.4064)
		(layer "F.Cu")
		(net "GND")
	)
	(segment
		(start 384.884676 -23.191724)
		(end 384.705352 -23.0124)
		(width 0.254)
		(layer "F.Cu")
		(net "GND")
	)
	(segment
		(start 119.929402 -68.782184)
		(end 119.357902 -68.782184)
		(width 0.254)
		(layer "F.Cu")
		(net "GND")
	)
	(segment
		(start 304.675286 -54.210204)
		(end 304.388266 -53.923184)
		(width 0.254)
		(layer "F.Cu")
		(net "GND")
	)
	(segment
		(start 420.69004 -35.334702)
		(end 420.69004 -35.334448)
		(width 0.254)
		(layer "F.Cu")
		(net "GND")
	)
	(segment
		(start 239.617758 -84.31784)
		(end 239.046258 -84.31784)
		(width 0.254)
		(layer "F.Cu")
		(net "GND")
	)
	(segment
		(start 64.549274 2.963926)
		(end 64.090804 2.505456)
		(width 0.4064)
		(layer "F.Cu")
		(net "GND")
	)
	(segment
		(start 24.991314 -82.613246)
		(end 24.7015 -82.90306)
		(width 0.254)
		(layer "F.Cu")
		(net "GND")
	)
	(segment
		(start 73.899268 -153.093674)
		(end 73.440798 -153.552144)
		(width 0.4064)
		(layer "F.Cu")
		(net "GND")
	)
	(segment
		(start 342.058498 -9.4742)
		(end 341.191088 -10.34161)
		(width 0.508)
		(layer "F.Cu")
		(net "GND")
	)
	(segment
		(start 301.742602 -18.744946)
		(end 301.742602 -18.757646)
		(width 0.3556)
		(layer "F.Cu")
		(net "GND")
	)
	(segment
		(start 235.49991 -21.479256)
		(end 235.46181 -21.517356)
		(width 0.4064)
		(layer "F.Cu")
		(net "GND")
	)
	(segment
		(start 193.6369 -87.30742)
		(end 193.6369 -86.33714)
		(width 0.254)
		(layer "F.Cu")
		(net "GND")
	)
	(segment
		(start 56.899302 -152.458166)
		(end 56.899302 -154.063446)
		(width 0.4064)
		(layer "F.Cu")
		(net "GND")
	)
	(segment
		(start 33.754568 2.8702)
		(end 33.754568 1.972818)
		(width 0.3556)
		(layer "F.Cu")
		(net "GND")
	)
	(segment
		(start 208.299812 -3.940556)
		(end 208.122012 -3.762756)
		(width 0.4064)
		(layer "F.Cu")
		(net "GND")
	)
	(segment
		(start 243.910104 -64.010286)
		(end 243.338604 -64.010286)
		(width 0.254)
		(layer "F.Cu")
		(net "GND")
	)
	(segment
		(start 208.299812 -133.076442)
		(end 208.299812 -133.812534)
		(width 0.3556)
		(layer "F.Cu")
		(net "GND")
	)
	(segment
		(start 224.450402 -0.821182)
		(end 224.449894 -0.821182)
		(width 0.4064)
		(layer "F.Cu")
		(net "GND")
	)
	(segment
		(start 285.2166 -65.315338)
		(end 285.7881 -65.315338)
		(width 0.254)
		(layer "F.Cu")
		(net "GND")
	)
	(segment
		(start 243.910104 -90.756486)
		(end 243.338604 -90.756486)
		(width 0.254)
		(layer "F.Cu")
		(net "GND")
	)
	(segment
		(start 243.910104 -84.812886)
		(end 243.338604 -84.812886)
		(width 0.254)
		(layer "F.Cu")
		(net "GND")
	)
	(segment
		(start 74.617326 -84.31784)
		(end 74.045826 -84.31784)
		(width 0.254)
		(layer "F.Cu")
		(net "GND")
	)
	(segment
		(start 416.511994 -48.717962)
		(end 415.749994 -48.717962)
		(width 0.254)
		(layer "F.Cu")
		(net "GND")
	)
	(segment
		(start 248.202704 -98.18624)
		(end 247.631204 -98.18624)
		(width 0.254)
		(layer "F.Cu")
		(net "GND")
	)
	(segment
		(start 76.334366 -52.618386)
		(end 75.762866 -52.618386)
		(width 0.254)
		(layer "F.Cu")
		(net "GND")
	)
	(segment
		(start 393.2682 -126.448312)
		(end 393.2682 -126.746)
		(width 0.254)
		(layer "F.Cu")
		(net "GND")
	)
	(segment
		(start 253.353824 -84.31784)
		(end 252.782324 -84.31784)
		(width 0.254)
		(layer "F.Cu")
		(net "GND")
	)
	(segment
		(start 203.2 -152.278842)
		(end 203.2 -152.457912)
		(width 0.4064)
		(layer "F.Cu")
		(net "GND")
	)
	(segment
		(start 146.092164 -155.612846)
		(end 146.092164 -155.600146)
		(width 0.3556)
		(layer "F.Cu")
		(net "GND")
	)
	(segment
		(start 442.950092 -58.873136)
		(end 442.950092 -57.596024)
		(width 0.381)
		(layer "F.Cu")
		(net "GND")
	)
	(segment
		(start 464.549998 -53.235098)
		(end 464.542886 -52.2478)
		(width 0.4064)
		(layer "F.Cu")
		(net "GND")
	)
	(segment
		(start 433.7685 -32.6263)
		(end 433.3494 -32.6263)
		(width 0.254)
		(layer "F.Cu")
		(net "GND")
	)
	(segment
		(start 297.550332 -152.273)
		(end 297.549824 -152.278842)
		(width 0.4064)
		(layer "F.Cu")
		(net "GND")
	)
	(segment
		(start 30.30855 -23.495)
		(end 30.549342 -23.495)
		(width 0.254)
		(layer "F.Cu")
		(net "GND")
	)
	(segment
		(start 249.061224 -65.991486)
		(end 248.489724 -65.991486)
		(width 0.254)
		(layer "F.Cu")
		(net "GND")
	)
	(segment
		(start 17.907 -119.863362)
		(end 17.907 -119.040402)
		(width 0.508)
		(layer "F.Cu")
		(net "GND")
	)
	(segment
		(start 126.599442 -13.541756)
		(end 126.421642 -13.363956)
		(width 0.4064)
		(layer "F.Cu")
		(net "GND")
	)
	(segment
		(start 116.140992 -71.1454)
		(end 116.140992 -71.460614)
		(width 0.254)
		(layer "F.Cu")
		(net "GND")
	)
	(segment
		(start 231.249982 -133.076442)
		(end 231.249982 -133.255512)
		(width 0.4064)
		(layer "F.Cu")
		(net "GND")
	)
	(segment
		(start 378.484892 -124.384308)
		(end 378.4854 -124.3838)
		(width 0.254)
		(layer "F.Cu")
		(net "GND")
	)
	(segment
		(start 158.83636 -123.34494)
		(end 158.17596 -122.68454)
		(width 0.4572)
		(layer "F.Cu")
		(net "GND")
	)
	(segment
		(start 27.101292 -55.771288)
		(end 27.101292 -54.76494)
		(width 0.508)
		(layer "F.Cu")
		(net "GND")
	)
	(segment
		(start 114.778282 -56.894984)
		(end 114.206782 -56.894984)
		(width 0.254)
		(layer "F.Cu")
		(net "GND")
	)
	(segment
		(start 464.885278 -3.4036)
		(end 464.906614 -3.4036)
		(width 0.4064)
		(layer "F.Cu")
		(net "GND")
	)
	(segment
		(start 378.32665 -99.55276)
		(end 378.82195 -99.322636)
		(width 0.254)
		(layer "F.Cu")
		(net "GND")
	)
	(segment
		(start 116.495322 -86.612984)
		(end 116.495322 -86.041484)
		(width 0.381)
		(layer "F.Cu")
		(net "GND")
	)
	(segment
		(start 346.995242 -11.14933)
		(end 346.3036 -10.457688)
		(width 0.254)
		(layer "F.Cu")
		(net "GND")
	)
	(segment
		(start 142.749524 -2.314956)
		(end 142.749524 -0.821182)
		(width 0.4064)
		(layer "F.Cu")
		(net "GND")
	)
	(segment
		(start 398.485106 -125.542294)
		(end 398.4244 -125.603)
		(width 0.254)
		(layer "F.Cu")
		(net "GND")
	)
	(segment
		(start 211.699856 -20.023582)
		(end 211.699856 -21.517356)
		(width 0.4064)
		(layer "F.Cu")
		(net "GND")
	)
	(segment
		(start 411.975046 -21.307552)
		(end 412.076646 -21.409152)
		(width 0.254)
		(layer "F.Cu")
		(net "GND")
	)
	(segment
		(start 372.34495 -74.69505)
		(end 371.945154 -75.094846)
		(width 0.254)
		(layer "F.Cu")
		(net "GND")
	)
	(segment
		(start 393.302998 -74.487278)
		(end 392.295888 -74.487278)
		(width 0.254)
		(layer "F.Cu")
		(net "GND")
	)
	(segment
		(start 199.800464 -10.422382)
		(end 199.799956 -10.422382)
		(width 0.4064)
		(layer "F.Cu")
		(net "GND")
	)
	(segment
		(start 124.89942 -142.6718)
		(end 124.89942 -144.364202)
		(width 0.4064)
		(layer "F.Cu")
		(net "GND")
	)
	(segment
		(start 66.24955 3.599688)
		(end 66.249296 3.599434)
		(width 0.4064)
		(layer "F.Cu")
		(net "GND")
	)
	(segment
		(start 73.758806 -82.83194)
		(end 73.187306 -82.83194)
		(width 0.254)
		(layer "F.Cu")
		(net "GND")
	)
	(segment
		(start 429.407828 -46.613572)
		(end 429.847248 -46.613572)
		(width 0.254)
		(layer "F.Cu")
		(net "GND")
	)
	(segment
		(start 450.149976 -58.954924)
		(end 450.149976 -57.596024)
		(width 0.381)
		(layer "F.Cu")
		(net "GND")
	)
	(segment
		(start 437.322214 -27.832558)
		(end 437.32196 -27.832558)
		(width 0.3048)
		(layer "F.Cu")
		(net "GND")
	)
	(segment
		(start 210.391248 -16.696944)
		(end 210.849718 -16.238474)
		(width 0.4064)
		(layer "F.Cu")
		(net "GND")
	)
	(segment
		(start 69.753226 -57.076086)
		(end 70.324726 -57.076086)
		(width 0.3048)
		(layer "F.Cu")
		(net "GND")
	)
	(segment
		(start 64.549528 -15.423642)
		(end 64.549274 -15.423896)
		(width 0.4064)
		(layer "F.Cu")
		(net "GND")
	)
	(segment
		(start 296.69994 -18.757646)
		(end 296.69994 -20.023582)
		(width 0.4064)
		(layer "F.Cu")
		(net "GND")
	)
	(segment
		(start 122.349514 -9.156446)
		(end 122.349514 -10.422382)
		(width 0.4064)
		(layer "F.Cu")
		(net "GND")
	)
	(segment
		(start 113.061242 -101.471984)
		(end 113.061242 -101.472746)
		(width 0.1524)
		(layer "F.Cu")
		(net "GND")
	)
	(segment
		(start 240.476278 -80.850486)
		(end 239.904778 -80.850486)
		(width 0.254)
		(layer "F.Cu")
		(net "GND")
	)
	(segment
		(start 221.899734 -17.208246)
		(end 221.899734 -15.602966)
		(width 0.4064)
		(layer "F.Cu")
		(net "GND")
	)
	(segment
		(start 6.1976 -131.953)
		(end 6.1976 -132.67944)
		(width 0.4064)
		(layer "F.Cu")
		(net "GND")
	)
	(segment
		(start 132.806694 -80.174338)
		(end 133.378194 -80.174338)
		(width 0.254)
		(layer "F.Cu")
		(net "GND")
	)
	(segment
		(start 124.049536 -137.67054)
		(end 124.049536 -136.397746)
		(width 0.4064)
		(layer "F.Cu")
		(net "GND")
	)
	(segment
		(start 292.65626 -84.136738)
		(end 293.22776 -84.136738)
		(width 0.254)
		(layer "F.Cu")
		(net "GND")
	)
	(segment
		(start 198.100442 -20.023582)
		(end 198.099934 -20.023582)
		(width 0.4064)
		(layer "F.Cu")
		(net "GND")
	)
	(segment
		(start 380.68504 -8.478012)
		(end 380.68504 -7.850124)
		(width 0.4064)
		(layer "F.Cu")
		(net "GND")
	)
	(segment
		(start 303.499774 -133.076442)
		(end 303.499774 -133.891274)
		(width 0.4064)
		(layer "F.Cu")
		(net "GND")
	)
	(segment
		(start 117.353842 -93.052138)
		(end 117.925342 -93.052138)
		(width 0.254)
		(layer "F.Cu")
		(net "GND")
	)
	(segment
		(start 496.678204 -25.055576)
		(end 495.951256 -25.055576)
		(width 0.254)
		(layer "F.Cu")
		(net "GND")
	)
	(segment
		(start 124.89942 -15.423642)
		(end 124.89942 -13.731748)
		(width 0.4064)
		(layer "F.Cu")
		(net "GND")
	)
	(segment
		(start 412.290006 -30.13456)
		(end 412.690056 -30.53461)
		(width 0.254)
		(layer "F.Cu")
		(net "GND")
	)
	(segment
		(start 33.099502 -148.733256)
		(end 33.099502 -147.27174)
		(width 0.4064)
		(layer "F.Cu")
		(net "GND")
	)
	(segment
		(start 435.404006 -41.219374)
		(end 435.404006 -40.5257)
		(width 0.3556)
		(layer "F.Cu")
		(net "GND")
	)
	(segment
		(start 127.655828 -81.164938)
		(end 128.227328 -81.164938)
		(width 0.254)
		(layer "F.Cu")
		(net "GND")
	)
	(segment
		(start 415.490152 -33.334706)
		(end 415.890202 -32.934656)
		(width 0.254)
		(layer "F.Cu")
		(net "GND")
	)
	(segment
		(start 389.99668 -109.93882)
		(end 390.07288 -109.86262)
		(width 0.12446)
		(layer "F.Cu")
		(net "GND")
	)
	(segment
		(start 461.01 -45.5422)
		(end 460.541116 -46.011084)
		(width 0.4064)
		(layer "F.Cu")
		(net "GND")
	)
	(segment
		(start 287.21812 -78.688438)
		(end 286.64662 -78.688438)
		(width 0.254)
		(layer "F.Cu")
		(net "GND")
	)
	(segment
		(start 143.599408 -7.509002)
		(end 143.501364 -7.607046)
		(width 0.4064)
		(layer "F.Cu")
		(net "GND")
	)
	(segment
		(start 292.392608 -2.310892)
		(end 292.450012 -2.253488)
		(width 0.4064)
		(layer "F.Cu")
		(net "GND")
	)
	(segment
		(start 85.777832 -67.972686)
		(end 85.206332 -67.972686)
		(width 0.254)
		(layer "F.Cu")
		(net "GND")
	)
	(segment
		(start 208.30032 -152.273)
		(end 208.299812 -152.278842)
		(width 0.3556)
		(layer "F.Cu")
		(net "GND")
	)
	(segment
		(start 296.09034 -94.042738)
		(end 296.66184 -94.042738)
		(width 0.3048)
		(layer "F.Cu")
		(net "GND")
	)
	(segment
		(start 229.54996 -15.423642)
		(end 229.54996 -14.410182)
		(width 0.4064)
		(layer "F.Cu")
		(net "GND")
	)
	(segment
		(start 288.19983 -133.076442)
		(end 288.19983 -134.861046)
		(width 0.4064)
		(layer "F.Cu")
		(net "GND")
	)
	(segment
		(start 301.800514 -10.422382)
		(end 301.800006 -10.422382)
		(width 0.3556)
		(layer "F.Cu")
		(net "GND")
	)
	(segment
		(start 395.984984 -95.205042)
		(end 394.984986 -95.205042)
		(width 0.254)
		(layer "F.Cu")
		(net "GND")
	)
	(segment
		(start 141.391894 -87.108538)
		(end 141.963394 -87.108538)
		(width 0.254)
		(layer "F.Cu")
		(net "GND")
	)
	(segment
		(start 346.569538 -12.28852)
		(end 345.408758 -12.28852)
		(width 0.2032)
		(layer "F.Cu")
		(net "GND")
	)
	(segment
		(start 495.554254 -54.329838)
		(end 495.3 -54.075584)
		(width 0.254)
		(layer "F.Cu")
		(net "GND")
	)
	(segment
		(start 414.290256 -36.934648)
		(end 413.890206 -36.534598)
		(width 0.254)
		(layer "F.Cu")
		(net "GND")
	)
	(segment
		(start 45.84954 -5.822442)
		(end 45.849286 -5.822696)
		(width 0.4064)
		(layer "F.Cu")
		(net "GND")
	)
	(segment
		(start 128.514348 -80.669384)
		(end 129.085848 -80.669384)
		(width 0.254)
		(layer "F.Cu")
		(net "GND")
	)
	(segment
		(start 401.955 -25.474168)
		(end 401.955 -24.892)
		(width 0.254)
		(layer "F.Cu")
		(net "GND")
	)
	(segment
		(start 115.549426 -5.822442)
		(end 115.549426 -3.826256)
		(width 0.4064)
		(layer "F.Cu")
		(net "GND")
	)
	(segment
		(start 79.768192 -96.20504)
		(end 79.196692 -96.20504)
		(width 0.254)
		(layer "F.Cu")
		(net "GND")
	)
	(segment
		(start 48.399446 -146.011646)
		(end 48.399446 -147.27174)
		(width 0.4064)
		(layer "F.Cu")
		(net "GND")
	)
	(segment
		(start 110.485682 -54.418738)
		(end 109.914182 -54.418738)
		(width 0.254)
		(layer "F.Cu")
		(net "GND")
	)
	(segment
		(start 232.099866 -147.27174)
		(end 232.099866 -146.011646)
		(width 0.4064)
		(layer "F.Cu")
		(net "GND")
	)
	(segment
		(start 182.1942 -75.1586)
		(end 182.1942 -75.565)
		(width 0.4064)
		(layer "F.Cu")
		(net "GND")
	)
	(segment
		(start 113.849404 -18.786348)
		(end 113.944146 -18.691606)
		(width 0.4064)
		(layer "F.Cu")
		(net "GND")
	)
	(segment
		(start 442.876686 -8.384286)
		(end 442.876686 -7.789672)
		(width 0.254)
		(layer "F.Cu")
		(net "GND")
	)
	(segment
		(start 382.288542 -104.70388)
		(end 382.581404 -104.996742)
		(width 0.12446)
		(layer "F.Cu")
		(net "GND")
	)
	(segment
		(start 61.796168 -134.010654)
		(end 61.796168 -134.874)
		(width 0.3556)
		(layer "F.Cu")
		(net "GND")
	)
	(segment
		(start 442.140086 -53.2384)
		(end 442.140086 -51.875944)
		(width 0.4064)
		(layer "F.Cu")
		(net "GND")
	)
	(segment
		(start 71.183246 -70.44944)
		(end 70.611746 -70.44944)
		(width 0.254)
		(layer "F.Cu")
		(net "GND")
	)
	(segment
		(start 280.644092 -51.44008)
		(end 280.644092 -50.324258)
		(width 0.2286)
		(layer "F.Cu")
		(net "GND")
	)
	(segment
		(start 5.1054 -5.675376)
		(end 5.1054 -6.157976)
		(width 0.4064)
		(layer "F.Cu")
		(net "GND")
	)
	(segment
		(start 453.340978 -45.925486)
		(end 453.340978 -47.481998)
		(width 0.4064)
		(layer "F.Cu")
		(net "GND")
	)
	(segment
		(start 324.41642 -29.86278)
		(end 324.82282 -30.26918)
		(width 0.4572)
		(layer "F.Cu")
		(net "GND")
	)
	(segment
		(start 353.494086 -140.47978)
		(end 354.00869 -139.965176)
		(width 0.508)
		(layer "F.Cu")
		(net "GND")
	)
	(segment
		(start 288.200338 3.778758)
		(end 288.19983 3.778758)
		(width 0.4064)
		(layer "F.Cu")
		(net "GND")
	)
	(segment
		(start 302.958246 -75.221338)
		(end 303.529746 -75.221338)
		(width 0.254)
		(layer "F.Cu")
		(net "GND")
	)
	(segment
		(start 387.24205 -123.59132)
		(end 387.73735 -123.821444)
		(width 0.254)
		(layer "F.Cu")
		(net "GND")
	)
	(segment
		(start 71.117968 -134.845806)
		(end 71.171562 -134.8994)
		(width 0.3556)
		(layer "F.Cu")
		(net "GND")
	)
	(segment
		(start 378.32665 -109.855)
		(end 378.82195 -110.085124)
		(width 0.254)
		(layer "F.Cu")
		(net "GND")
	)
	(segment
		(start 169.789348 -63.769748)
		(end 169.5704 -63.5508)
		(width 0.2032)
		(layer "F.Cu")
		(net "GND")
	)
	(segment
		(start 399.65884 -75.55992)
		(end 400.03476 -75.184)
		(width 0.254)
		(layer "F.Cu")
		(net "GND")
	)
	(segment
		(start 195.6308 -52.9844)
		(end 195.24218 -52.59578)
		(width 0.4064)
		(layer "F.Cu")
		(net "GND")
	)
	(segment
		(start 139.674854 -82.155284)
		(end 140.246354 -82.155284)
		(width 0.254)
		(layer "F.Cu")
		(net "GND")
	)
	(segment
		(start 248.202704 -64.50584)
		(end 247.631204 -64.50584)
		(width 0.254)
		(layer "F.Cu")
		(net "GND")
	)
	(segment
		(start 58.599578 -142.677642)
		(end 58.599324 -142.677896)
		(width 0.4064)
		(layer "F.Cu")
		(net "GND")
	)
	(segment
		(start 237.900718 -84.31784)
		(end 237.329218 -84.31784)
		(width 0.254)
		(layer "F.Cu")
		(net "GND")
	)
	(segment
		(start 236.349794 -6.550406)
		(end 236.1184 -6.7818)
		(width 0.3556)
		(layer "F.Cu")
		(net "GND")
	)
	(segment
		(start 226.149916 -11.878056)
		(end 226.149916 -10.422382)
		(width 0.4064)
		(layer "F.Cu")
		(net "GND")
	)
	(segment
		(start 299.524166 -73.240138)
		(end 300.095666 -73.240138)
		(width 0.254)
		(layer "F.Cu")
		(net "GND")
	)
	(segment
		(start 465.36737 -148.542502)
		(end 465.36737 -148.083778)
		(width 0.254)
		(layer "F.Cu")
		(net "GND")
	)
	(segment
		(start 47.549562 -152.457912)
		(end 47.549308 -152.458166)
		(width 0.4064)
		(layer "F.Cu")
		(net "GND")
	)
	(segment
		(start 296.66184 -86.117938)
		(end 296.09034 -86.117938)
		(width 0.3048)
		(layer "F.Cu")
		(net "GND")
	)
	(segment
		(start 110.485682 -95.033084)
		(end 111.057182 -95.033084)
		(width 0.1651)
		(layer "F.Cu")
		(net "GND")
	)
	(segment
		(start 311.092596 0.457454)
		(end 311.092596 0.444754)
		(width 0.3556)
		(layer "F.Cu")
		(net "GND")
	)
	(segment
		(start 138.816334 -51.429666)
		(end 139.0904 -51.1556)
		(width 0.254)
		(layer "F.Cu")
		(net "GND")
	)
	(segment
		(start 243.910104 -86.794086)
		(end 243.338604 -86.794086)
		(width 0.254)
		(layer "F.Cu")
		(net "GND")
	)
	(segment
		(start 391.670286 -4.386072)
		(end 391.670286 -3.506724)
		(width 0.4064)
		(layer "F.Cu")
		(net "GND")
	)
	(segment
		(start 126.797308 -73.735184)
		(end 127.368808 -73.735184)
		(width 0.254)
		(layer "F.Cu")
		(net "GND")
	)
	(segment
		(start 452.477378 -7.060184)
		(end 452.722234 -6.815328)
		(width 0.254)
		(layer "F.Cu")
		(net "GND")
	)
	(segment
		(start 367.9952 -105.791)
		(end 367.9063 -105.7021)
		(width 0.254)
		(layer "F.Cu")
		(net "GND")
	)
	(segment
		(start 70.324726 -84.812886)
		(end 69.753226 -84.812886)
		(width 0.254)
		(layer "F.Cu")
		(net "GND")
	)
	(segment
		(start 234.649772 -144.364202)
		(end 234.551728 -144.462246)
		(width 0.4064)
		(layer "F.Cu")
		(net "GND")
	)
	(segment
		(start 194.344036 -68.881244)
		(end 193.977006 -68.881244)
		(width 0.381)
		(layer "F.Cu")
		(net "GND")
	)
	(segment
		(start 204.899768 -133.076442)
		(end 204.899768 -134.861046)
		(width 0.4064)
		(layer "F.Cu")
		(net "GND")
	)
	(segment
		(start 416.402012 -52.738782)
		(end 417.034218 -52.738782)
		(width 0.254)
		(layer "F.Cu")
		(net "GND")
	)
	(segment
		(start 275.486114 -97.014538)
		(end 276.057614 -97.014538)
		(width 0.254)
		(layer "F.Cu")
		(net "GND")
	)
	(segment
		(start 310.299862 -13.541756)
		(end 310.122062 -13.363956)
		(width 0.4064)
		(layer "F.Cu")
		(net "GND")
	)
	(segment
		(start 33.754568 -6.731)
		(end 33.949386 -6.536182)
		(width 0.3556)
		(layer "F.Cu")
		(net "GND")
	)
	(segment
		(start 275.773134 -54.913784)
		(end 276.344634 -54.913784)
		(width 0.254)
		(layer "F.Cu")
		(net "GND")
	)
	(segment
		(start 47.549562 -133.0706)
		(end 47.549562 -133.255512)
		(width 0.4064)
		(layer "F.Cu")
		(net "GND")
	)
	(segment
		(start 32.094932 -95.284544)
		(end 32.094932 -94.843092)
		(width 0.254)
		(layer "F.Cu")
		(net "GND")
	)
	(segment
		(start 44.149518 -9.25195)
		(end 44.092114 -9.194546)
		(width 0.4064)
		(layer "F.Cu")
		(net "GND")
	)
	(segment
		(start 284.799786 -4.808982)
		(end 284.799786 -5.822442)
		(width 0.4064)
		(layer "F.Cu")
		(net "GND")
	)
	(segment
		(start 36.040822 -7.095744)
		(end 36.499292 -6.637274)
		(width 0.4064)
		(layer "F.Cu")
		(net "GND")
	)
	(segment
		(start 70.324726 -69.953886)
		(end 69.753226 -69.953886)
		(width 0.254)
		(layer "F.Cu")
		(net "GND")
	)
	(segment
		(start 300.949868 -142.677642)
		(end 300.949868 -143.422878)
		(width 0.3556)
		(layer "F.Cu")
		(net "GND")
	)
	(segment
		(start 67.949572 -13.36421)
		(end 67.949318 -13.363956)
		(width 0.4064)
		(layer "F.Cu")
		(net "GND")
	)
	(segment
		(start 378.353574 -106.408474)
		(end 378.32665 -106.42092)
		(width 0.254)
		(layer "F.Cu")
		(net "GND")
	)
	(segment
		(start 413.413956 -118.7704)
		(end 412.448756 -119.7356)
		(width 0.254)
		(layer "F.Cu")
		(net "GND")
	)
	(segment
		(start 389.22325 -102.98684)
		(end 388.72795 -102.49154)
		(width 0.254)
		(layer "F.Cu")
		(net "GND")
	)
	(segment
		(start 108.768896 -63.334138)
		(end 108.197396 -63.334138)
		(width 0.254)
		(layer "F.Cu")
		(net "GND")
	)
	(segment
		(start 377.33605 -115.00612)
		(end 377.83135 -115.236244)
		(width 0.254)
		(layer "F.Cu")
		(net "GND")
	)
	(segment
		(start 225.299778 -153.965402)
		(end 225.201734 -154.063446)
		(width 0.4064)
		(layer "F.Cu")
		(net "GND")
	)
	(segment
		(start 287.349946 -147.27174)
		(end 287.349946 -146.011646)
		(width 0.4064)
		(layer "F.Cu")
		(net "GND")
	)
	(segment
		(start 22.459188 -67.848988)
		(end 23.0505 -67.848988)
		(width 0.254)
		(layer "F.Cu")
		(net "GND")
	)
	(segment
		(start 401.35302 -95.92056)
		(end 401.88642 -95.92056)
		(width 0.254)
		(layer "F.Cu")
		(net "GND")
	)
	(segment
		(start 26.924 -2.877312)
		(end 26.924 -2.237232)
		(width 0.4064)
		(layer "F.Cu")
		(net "GND")
	)
	(segment
		(start 300.736 -143.636746)
		(end 300.736 -144.464532)
		(width 0.3556)
		(layer "F.Cu")
		(net "GND")
	)
	(segment
		(start 449.340986 -51.875944)
		(end 449.334128 -51.869086)
		(width 0.508)
		(layer "F.Cu")
		(net "GND")
	)
	(segment
		(start 113.849404 -11.857736)
		(end 113.849404 -10.422382)
		(width 0.4064)
		(layer "F.Cu")
		(net "GND")
	)
	(segment
		(start 175.58258 -104.65562)
		(end 176.582578 -103.655622)
		(width 0.254)
		(layer "F.Cu")
		(net "GND")
	)
	(segment
		(start 315.399928 -21.517356)
		(end 315.399928 -20.023582)
		(width 0.4064)
		(layer "F.Cu")
		(net "GND")
	)
	(segment
		(start 117.353842 -51.446938)
		(end 117.353842 -50.375058)
		(width 0.2286)
		(layer "F.Cu")
		(net "GND")
	)
	(segment
		(start 406.690068 -43.73499)
		(end 406.690068 -43.734736)
		(width 0.10795)
		(layer "F.Cu")
		(net "GND")
	)
	(segment
		(start 199.742552 -136.623298)
		(end 199.742552 -136.397746)
		(width 0.4064)
		(layer "F.Cu")
		(net "GND")
	)
	(segment
		(start 195.549774 -23.495)
		(end 194.662806 -23.495)
		(width 0.254)
		(layer "F.Cu")
		(net "GND")
	)
	(segment
		(start 275.111464 -140.208)
		(end 274.258532 -140.208)
		(width 0.4572)
		(layer "F.Cu")
		(net "GND")
	)
	(segment
		(start 376.335036 -109.855)
		(end 376.555 -110.3884)
		(width 0.254)
		(layer "F.Cu")
		(net "GND")
	)
	(segment
		(start 126.388368 -154.068526)
		(end 126.421642 -154.1018)
		(width 0.3556)
		(layer "F.Cu")
		(net "GND")
	)
	(segment
		(start 251.636784 -74.411586)
		(end 251.065284 -74.411586)
		(width 0.254)
		(layer "F.Cu")
		(net "GND")
	)
	(segment
		(start 298.665646 -61.847984)
		(end 299.237146 -61.847984)
		(width 0.254)
		(layer "F.Cu")
		(net "GND")
	)
	(segment
		(start 285.7881 -51.446938)
		(end 285.7881 -50.8127)
		(width 0.254)
		(layer "F.Cu")
		(net "GND")
	)
	(segment
		(start 45.84954 -142.677642)
		(end 45.849286 -142.677896)
		(width 0.4064)
		(layer "F.Cu")
		(net "GND")
	)
	(segment
		(start 306.702968 -86.780624)
		(end 306.702968 -86.501224)
		(width 0.254)
		(layer "F.Cu")
		(net "GND")
	)
	(segment
		(start 294.150288 -152.273)
		(end 294.14978 -152.278842)
		(width 0.4064)
		(layer "F.Cu")
		(net "GND")
	)
	(segment
		(start 127.44958 -18.81505)
		(end 127.44958 -20.023582)
		(width 0.3556)
		(layer "F.Cu")
		(net "GND")
	)
	(segment
		(start 79.768192 -100.167186)
		(end 80.055212 -99.67214)
		(width 0.254)
		(layer "F.Cu")
		(net "GND")
	)
	(segment
		(start 458.143356 -52.2478)
		(end 458.140054 -51.875944)
		(width 0.4064)
		(layer "F.Cu")
		(net "GND")
	)
	(segment
		(start 120.216168 -60.362338)
		(end 120.787668 -60.362338)
		(width 0.254)
		(layer "F.Cu")
		(net "GND")
	)
	(segment
		(start 465.442046 2.2733)
		(end 465.442046 2.654046)
		(width 0.381)
		(layer "F.Cu")
		(net "GND")
	)
	(segment
		(start 36.499292 -152.279096)
		(end 36.499292 -153.093674)
		(width 0.4064)
		(layer "F.Cu")
		(net "GND")
	)
	(segment
		(start 311.092596 -9.156446)
		(end 311.092596 -9.143746)
		(width 0.3556)
		(layer "F.Cu")
		(net "GND")
	)
	(segment
		(start 310.299862 3.061462)
		(end 310.0832 2.8448)
		(width 0.3556)
		(layer "F.Cu")
		(net "GND")
	)
	(segment
		(start 28.7274 -83.963002)
		(end 28.7274 -84.608924)
		(width 0.254)
		(layer "F.Cu")
		(net "GND")
	)
	(segment
		(start 117.249448 -152.273)
		(end 117.249448 -153.004774)
		(width 0.3556)
		(layer "F.Cu")
		(net "GND")
	)
	(segment
		(start 449.25488 -32.4485)
		(end 446.453006 -32.4485)
		(width 0.4064)
		(layer "F.Cu")
		(net "GND")
	)
	(segment
		(start 300.095666 -68.078604)
		(end 300.382686 -67.791584)
		(width 0.254)
		(layer "F.Cu")
		(net "GND")
	)
	(segment
		(start 292.450012 -137.67054)
		(end 292.450012 -136.46785)
		(width 0.3556)
		(layer "F.Cu")
		(net "GND")
	)
	(segment
		(start 380.59233 -35.6616)
		(end 379.4125 -35.6616)
		(width 0.2032)
		(layer "F.Cu")
		(net "GND")
	)
	(segment
		(start 244.768624 -96.20504)
		(end 244.197124 -96.20504)
		(width 0.254)
		(layer "F.Cu")
		(net "GND")
	)
	(segment
		(start 198.949818 -15.423642)
		(end 198.950326 -15.423642)
		(width 0.3556)
		(layer "F.Cu")
		(net "GND")
	)
	(segment
		(start 78.051406 -76.39304)
		(end 77.479906 -76.39304)
		(width 0.254)
		(layer "F.Cu")
		(net "GND")
	)
	(segment
		(start 107.62361 -100.977192)
		(end 107.910376 -100.481638)
		(width 0.254)
		(layer "F.Cu")
		(net "GND")
	)
	(segment
		(start 134.523734 -81.164938)
		(end 135.095234 -81.164938)
		(width 0.254)
		(layer "F.Cu")
		(net "GND")
	)
	(segment
		(start 91.460574 -140.490194)
		(end 90.814906 -140.490194)
		(width 0.4064)
		(layer "F.Cu")
		(net "GND")
	)
	(segment
		(start 26.602182 -141.198854)
		(end 26.774648 -141.37132)
		(width 0.4064)
		(layer "F.Cu")
		(net "GND")
	)
	(segment
		(start 309.450486 -0.821182)
		(end 309.449978 -0.821182)
		(width 0.4064)
		(layer "F.Cu")
		(net "GND")
	)
	(segment
		(start 102.947724 -88.775286)
		(end 102.947724 -88.165686)
		(width 0.254)
		(layer "F.Cu")
		(net "GND")
	)
	(segment
		(start 124.221748 -61.352938)
		(end 123.650248 -61.352938)
		(width 0.254)
		(layer "F.Cu")
		(net "GND")
	)
	(segment
		(start 74.617326 -64.50584)
		(end 74.045826 -64.50584)
		(width 0.254)
		(layer "F.Cu")
		(net "GND")
	)
	(segment
		(start 402.260308 -99.364292)
		(end 403.47646 -98.14814)
		(width 0.254)
		(layer "F.Cu")
		(net "GND")
	)
	(segment
		(start 298.399962 -20.023582)
		(end 298.399962 -21.517356)
		(width 0.4064)
		(layer "F.Cu")
		(net "GND")
	)
	(segment
		(start 76.334366 -100.167186)
		(end 75.762866 -100.167186)
		(width 0.254)
		(layer "F.Cu")
		(net "GND")
	)
	(segment
		(start 1.356106 -13.599414)
		(end 2.495042 -13.599414)
		(width 0.4064)
		(layer "F.Cu")
		(net "GND")
	)
	(segment
		(start 408.066748 -18.462752)
		(end 407.67 -18.8595)
		(width 0.254)
		(layer "F.Cu")
		(net "GND")
	)
	(segment
		(start 274.627848 -63.829184)
		(end 274.056348 -63.829184)
		(width 0.254)
		(layer "F.Cu")
		(net "GND")
	)
	(segment
		(start 375.084848 -3.420364)
		(end 375.084848 -3.445764)
		(width 0.4572)
		(layer "F.Cu")
		(net "GND")
	)
	(segment
		(start 301.812706 -96.023938)
		(end 301.241206 -96.023938)
		(width 0.3048)
		(layer "F.Cu")
		(net "GND")
	)
	(segment
		(start 126.797308 -87.603584)
		(end 127.368808 -87.603584)
		(width 0.254)
		(layer "F.Cu")
		(net "GND")
	)
	(segment
		(start 293.51478 -85.622384)
		(end 294.08628 -85.622384)
		(width 0.254)
		(layer "F.Cu")
		(net "GND")
	)
	(segment
		(start 111.344202 -92.556584)
		(end 111.915702 -92.556584)
		(width 0.254)
		(layer "F.Cu")
		(net "GND")
	)
	(segment
		(start 373.888 -103.3526)
		(end 373.8626 -103.3526)
		(width 0.254)
		(layer "F.Cu")
		(net "GND")
	)
	(segment
		(start 133.665214 -55.904384)
		(end 134.236714 -55.904384)
		(width 0.254)
		(layer "F.Cu")
		(net "GND")
	)
	(segment
		(start 116.399564 -0.821182)
		(end 116.399564 0.444754)
		(width 0.4064)
		(layer "F.Cu")
		(net "GND")
	)
	(segment
		(start 389.485124 -94.790006)
		(end 389.485124 -93.959934)
		(width 0.254)
		(layer "F.Cu")
		(net "GND")
	)
	(segment
		(start 96.086168 -3.321812)
		(end 96.086168 -2.51968)
		(width 0.4064)
		(layer "F.Cu")
		(net "GND")
	)
	(segment
		(start 303.529746 -84.136738)
		(end 302.958246 -84.136738)
		(width 0.3048)
		(layer "F.Cu")
		(net "GND")
	)
	(segment
		(start 246.485664 -61.53404)
		(end 245.914164 -61.53404)
		(width 0.254)
		(layer "F.Cu")
		(net "GND")
	)
	(segment
		(start 149.549358 -15.423642)
		(end 149.549358 -17.208246)
		(width 0.4064)
		(layer "F.Cu")
		(net "GND")
	)
	(segment
		(start 375.487692 -94.357698)
		(end 374.523 -93.393006)
		(width 0.254)
		(layer "F.Cu")
		(net "GND")
	)
	(segment
		(start 303.816766 -82.650584)
		(end 304.388266 -82.650584)
		(width 0.1016)
		(layer "F.Cu")
		(net "GND")
	)
	(segment
		(start 131.948174 -59.866784)
		(end 132.519674 -59.866784)
		(width 0.254)
		(layer "F.Cu")
		(net "GND")
	)
	(segment
		(start 454.940924 -51.875944)
		(end 454.940924 -50.498248)
		(width 0.508)
		(layer "F.Cu")
		(net "GND")
	)
	(segment
		(start 378.659898 -113.015776)
		(end 378.386594 -113.28908)
		(width 0.2286)
		(layer "F.Cu")
		(net "GND")
	)
	(segment
		(start 384.27025 -116.72316)
		(end 384.76555 -116.953284)
		(width 0.254)
		(layer "F.Cu")
		(net "GND")
	)
	(segment
		(start 115.549426 -142.6718)
		(end 115.549426 -144.364202)
		(width 0.4064)
		(layer "F.Cu")
		(net "GND")
	)
	(segment
		(start 451.740016 -51.875944)
		(end 451.741032 -51.875944)
		(width 0.4064)
		(layer "F.Cu")
		(net "GND")
	)
	(segment
		(start 198.755 2.8702)
		(end 198.755 1.972818)
		(width 0.3556)
		(layer "F.Cu")
		(net "GND")
	)
	(segment
		(start 50.949352 -153.965402)
		(end 50.851308 -154.063446)
		(width 0.4064)
		(layer "F.Cu")
		(net "GND")
	)
	(segment
		(start 75.475846 -89.765886)
		(end 74.904346 -89.765886)
		(width 0.254)
		(layer "F.Cu")
		(net "GND")
	)
	(segment
		(start 289.899852 -134.763002)
		(end 289.801808 -134.861046)
		(width 0.4064)
		(layer "F.Cu")
		(net "GND")
	)
	(segment
		(start 375.885202 -7.850124)
		(end 375.885202 -8.84682)
		(width 0.4064)
		(layer "F.Cu")
		(net "GND")
	)
	(segment
		(start 380.80315 -110.71352)
		(end 381.29845 -110.943644)
		(width 0.254)
		(layer "F.Cu")
		(net "GND")
	)
	(segment
		(start 490.08792 -120.75922)
		(end 490.08792 -120.11152)
		(width 0.254)
		(layer "F.Cu")
		(net "GND")
	)
	(segment
		(start 78.909672 -65.000886)
		(end 78.338172 -65.000886)
		(width 0.254)
		(layer "F.Cu")
		(net "GND")
	)
	(segment
		(start 211.699856 -18.757646)
		(end 211.699856 -20.023582)
		(width 0.4064)
		(layer "F.Cu")
		(net "GND")
	)
	(segment
		(start 131.089908 -86.117938)
		(end 131.661408 -86.117938)
		(width 0.254)
		(layer "F.Cu")
		(net "GND")
	)
	(segment
		(start 109.2581 -12.954)
		(end 110.111032 -12.954)
		(width 0.4064)
		(layer "F.Cu")
		(net "GND")
	)
	(segment
		(start 122.217688 -100.481384)
		(end 122.121168 -100.64877)
		(width 0.254)
		(layer "F.Cu")
		(net "GND")
	)
	(segment
		(start 445.694562 -21.349462)
		(end 445.236854 -21.80717)
		(width 0.254)
		(layer "F.Cu")
		(net "GND")
	)
	(segment
		(start 198.099934 -2.276856)
		(end 198.099934 -0.821182)
		(width 0.4064)
		(layer "F.Cu")
		(net "GND")
	)
	(segment
		(start 81.485232 -52.618386)
		(end 81.479136 -52.61229)
		(width 0.2032)
		(layer "F.Cu")
		(net "GND")
	)
	(segment
		(start 289.90036 -133.0706)
		(end 289.899852 -133.076442)
		(width 0.4064)
		(layer "F.Cu")
		(net "GND")
	)
	(segment
		(start 39.049452 -147.27174)
		(end 39.049452 -148.771356)
		(width 0.4064)
		(layer "F.Cu")
		(net "GND")
	)
	(segment
		(start 282.24988 3.778758)
		(end 282.24988 3.052826)
		(width 0.3556)
		(layer "F.Cu")
		(net "GND")
	)
	(segment
		(start 277.203154 -96.023938)
		(end 277.774654 -96.023938)
		(width 0.254)
		(layer "F.Cu")
		(net "GND")
	)
	(segment
		(start 298.665646 -52.932838)
		(end 299.237146 -52.932838)
		(width 0.254)
		(layer "F.Cu")
		(net "GND")
	)
	(segment
		(start 238.900462 3.778758)
		(end 238.900462 2.964688)
		(width 0.4064)
		(layer "F.Cu")
		(net "GND")
	)
	(segment
		(start 377.83135 -102.756716)
		(end 378.32665 -102.98684)
		(width 0.254)
		(layer "F.Cu")
		(net "GND")
	)
	(segment
		(start 253.353824 -91.25204)
		(end 252.782324 -91.25204)
		(width 0.254)
		(layer "F.Cu")
		(net "GND")
	)
	(segment
		(start 273.198082 -52.438554)
		(end 273.197828 -52.437284)
		(width 0.254)
		(layer "F.Cu")
		(net "GND")
	)
	(segment
		(start 229.550468 -142.6718)
		(end 229.54996 -142.677642)
		(width 0.4064)
		(layer "F.Cu")
		(net "GND")
	)
	(segment
		(start 388.1755 -79.2226)
		(end 388.1755 -79.8322)
		(width 0.254)
		(layer "F.Cu")
		(net "GND")
	)
	(segment
		(start 476.116904 -134.366)
		(end 476.496634 -134.74573)
		(width 0.381)
		(layer "F.Cu")
		(net "GND")
	)
	(segment
		(start 113.061242 -56.894984)
		(end 112.489742 -56.894984)
		(width 0.254)
		(layer "F.Cu")
		(net "GND")
	)
	(segment
		(start 224.449894 -10.422382)
		(end 224.449894 -11.916156)
		(width 0.4064)
		(layer "F.Cu")
		(net "GND")
	)
	(segment
		(start 295.000426 -137.67054)
		(end 294.999918 -137.67054)
		(width 0.4064)
		(layer "F.Cu")
		(net "GND")
	)
	(segment
		(start 350.1136 -149.112224)
		(end 350.482154 -149.112224)
		(width 0.381)
		(layer "F.Cu")
		(net "GND")
	)
	(segment
		(start 81.485232 -102.093014)
		(end 80.626712 -101.653086)
		(width 0.254)
		(layer "F.Cu")
		(net "GND")
	)
	(segment
		(start 283.212794 -95.528384)
		(end 283.784294 -95.528384)
		(width 0.254)
		(layer "F.Cu")
		(net "GND")
	)
	(segment
		(start 76.449428 -146.011646)
		(end 76.449428 -147.27174)
		(width 0.4064)
		(layer "F.Cu")
		(net "GND")
	)
	(segment
		(start 466.204554 -118.559834)
		(end 466.199982 -116.992908)
		(width 0.4064)
		(layer "F.Cu")
		(net "GND")
	)
	(segment
		(start 33.754568 -133.985)
		(end 33.754568 -134.882382)
		(width 0.3556)
		(layer "F.Cu")
		(net "GND")
	)
	(segment
		(start 74.904346 -51.132486)
		(end 75.475846 -51.132486)
		(width 0.254)
		(layer "F.Cu")
		(net "GND")
	)
	(segment
		(start 124.049536 -147.27174)
		(end 124.049536 -145.998946)
		(width 0.4064)
		(layer "F.Cu")
		(net "GND")
	)
	(segment
		(start 349.943928 -148.655024)
		(end 349.942912 -148.655024)
		(width 0.4064)
		(layer "F.Cu")
		(net "GND")
	)
	(segment
		(start 309.450486 -10.422382)
		(end 309.449978 -10.422382)
		(width 0.4064)
		(layer "F.Cu")
		(net "GND")
	)
	(segment
		(start 439.74004 -53.2384)
		(end 439.74004 -51.875944)
		(width 0.4064)
		(layer "F.Cu")
		(net "GND")
	)
	(segment
		(start 436.921656 -25.0317)
		(end 437.32196 -25.432004)
		(width 0.3048)
		(layer "F.Cu")
		(net "GND")
	)
	(segment
		(start 244.768624 -98.18624)
		(end 244.197124 -98.18624)
		(width 0.254)
		(layer "F.Cu")
		(net "GND")
	)
	(segment
		(start 211.699856 -0.821182)
		(end 211.699856 0.444754)
		(width 0.4064)
		(layer "F.Cu")
		(net "GND")
	)
	(segment
		(start 247.344184 -101.508814)
		(end 247.412764 -101.577394)
		(width 0.2032)
		(layer "F.Cu")
		(net "GND")
	)
	(segment
		(start 117.640862 -65.810384)
		(end 118.212362 -65.810384)
		(width 0.254)
		(layer "F.Cu")
		(net "GND")
	)
	(segment
		(start 284.800294 -16.237712)
		(end 284.341062 -16.696944)
		(width 0.4064)
		(layer "F.Cu")
		(net "GND")
	)
	(segment
		(start 401.295108 -123.731528)
		(end 402.203412 -124.639832)
		(width 0.254)
		(layer "F.Cu")
		(net "GND")
	)
	(segment
		(start 488.1626 -148.8948)
		(end 488.976162 -148.8948)
		(width 0.254)
		(layer "F.Cu")
		(net "GND")
	)
	(segment
		(start 278.850344 -20.023582)
		(end 278.849836 -20.023582)
		(width 0.4064)
		(layer "F.Cu")
		(net "GND")
	)
	(segment
		(start 141.391894 -95.033084)
		(end 142.039848 -95.033084)
		(width 0.254)
		(layer "F.Cu")
		(net "GND")
	)
	(segment
		(start 140.199364 -5.822442)
		(end 140.199364 -3.762756)
		(width 0.4064)
		(layer "F.Cu")
		(net "GND")
	)
	(segment
		(start 292.45052 -147.27174)
		(end 292.450012 -147.27174)
		(width 0.3556)
		(layer "F.Cu")
		(net "GND")
	)
	(segment
		(start 382.78435 -98.69424)
		(end 382.9304 -98.626422)
		(width 0.254)
		(layer "F.Cu")
		(net "GND")
	)
	(segment
		(start 83.202272 -86.29904)
		(end 82.630772 -86.29904)
		(width 0.254)
		(layer "F.Cu")
		(net "GND")
	)
	(segment
		(start 378.985018 -95.205042)
		(end 379.48489 -94.790006)
		(width 0.254)
		(layer "F.Cu")
		(net "GND")
	)
	(segment
		(start 480.15144 -34.671)
		(end 480.15144 -33.9725)
		(width 0.254)
		(layer "F.Cu")
		(net "GND")
	)
	(segment
		(start 306.392326 -81.164938)
		(end 307.041042 -81.164938)
		(width 0.254)
		(layer "F.Cu")
		(net "GND")
	)
	(segment
		(start 449.345812 -52.2478)
		(end 449.33997 -51.875944)
		(width 0.4064)
		(layer "F.Cu")
		(net "GND")
	)
	(segment
		(start 374.674892 -109.855)
		(end 374.200674 -109.855)
		(width 0.254)
		(layer "F.Cu")
		(net "GND")
	)
	(segment
		(start 231.25049 3.778758)
		(end 231.249982 3.778758)
		(width 0.4064)
		(layer "F.Cu")
		(net "GND")
	)
	(segment
		(start 295.85031 -15.423642)
		(end 295.849802 -15.423642)
		(width 0.4064)
		(layer "F.Cu")
		(net "GND")
	)
	(segment
		(start 212.550502 -152.273)
		(end 212.549994 -152.278842)
		(width 0.4064)
		(layer "F.Cu")
		(net "GND")
	)
	(segment
		(start 290.93922 -92.061538)
		(end 291.51072 -92.061538)
		(width 0.254)
		(layer "F.Cu")
		(net "GND")
	)
	(segment
		(start 128.514348 -91.565984)
		(end 129.085848 -91.565984)
		(width 0.254)
		(layer "F.Cu")
		(net "GND")
	)
	(segment
		(start 312.650124 -27.185112)
		(end 313.647836 -26.1874)
		(width 0.254)
		(layer "F.Cu")
		(net "GND")
	)
	(segment
		(start 72.900286 -94.223586)
		(end 72.328786 -94.223586)
		(width 0.254)
		(layer "F.Cu")
		(net "GND")
	)
	(segment
		(start 78.909672 -80.850486)
		(end 78.338172 -80.850486)
		(width 0.254)
		(layer "F.Cu")
		(net "GND")
	)
	(segment
		(start 111.344202 -52.077366)
		(end 111.326168 -52.0954)
		(width 0.254)
		(layer "F.Cu")
		(net "GND")
	)
	(segment
		(start 441.400946 -112.205516)
		(end 441.400946 -113.816384)
		(width 0.4064)
		(layer "F.Cu")
		(net "GND")
	)
	(segment
		(start 78.909672 -97.690686)
		(end 78.338172 -97.690686)
		(width 0.254)
		(layer "F.Cu")
		(net "GND")
	)
	(segment
		(start 226.7966 -6.756654)
		(end 226.7966 -7.62)
		(width 0.3556)
		(layer "F.Cu")
		(net "GND")
	)
	(segment
		(start 140.199364 -152.273)
		(end 140.199364 -154.063446)
		(width 0.4064)
		(layer "F.Cu")
		(net "GND")
	)
	(segment
		(start 112.774222 -99.986338)
		(end 112.202722 -99.986338)
		(width 0.254)
		(layer "F.Cu")
		(net "GND")
	)
	(segment
		(start 313.699906 -2.314956)
		(end 313.699906 -0.821182)
		(width 0.4064)
		(layer "F.Cu")
		(net "GND")
	)
	(segment
		(start 185.1406 -76.53274)
		(end 184.7342 -76.93914)
		(width 0.508)
		(layer "F.Cu")
		(net "GND")
	)
	(segment
		(start 300.382686 -81.659984)
		(end 300.954186 -81.659984)
		(width 0.254)
		(layer "F.Cu")
		(net "GND")
	)
	(segment
		(start 227.849938 -147.27174)
		(end 227.849938 -146.06905)
		(width 0.3556)
		(layer "F.Cu")
		(net "GND")
	)
	(segment
		(start 152.099518 -18.757646)
		(end 152.099518 -20.023582)
		(width 0.4064)
		(layer "F.Cu")
		(net "GND")
	)
	(segment
		(start 129.372868 -82.155284)
		(end 129.944368 -82.155284)
		(width 0.254)
		(layer "F.Cu")
		(net "GND")
	)
	(segment
		(start 379.81255 -110.71352)
		(end 380.30785 -110.943644)
		(width 0.254)
		(layer "F.Cu")
		(net "GND")
	)
	(segment
		(start 303.529746 -57.390538)
		(end 302.958246 -57.390538)
		(width 0.254)
		(layer "F.Cu")
		(net "GND")
	)
	(segment
		(start 254.212344 -88.775286)
		(end 253.640844 -88.775286)
		(width 0.254)
		(layer "F.Cu")
		(net "GND")
	)
	(segment
		(start 316.25032 -133.0706)
		(end 316.249812 -133.076442)
		(width 0.4064)
		(layer "F.Cu")
		(net "GND")
	)
	(segment
		(start 278.920194 -102.958138)
		(end 278.561546 -103.576628)
		(width 0.4064)
		(layer "F.Cu")
		(net "GND")
	)
	(segment
		(start 236.1184 -153.2382)
		(end 236.1184 -154.048206)
		(width 0.3556)
		(layer "F.Cu")
		(net "GND")
	)
	(segment
		(start 252.495304 -71.935086)
		(end 251.923804 -71.935086)
		(width 0.254)
		(layer "F.Cu")
		(net "GND")
	)
	(segment
		(start 301.800006 -21.455888)
		(end 301.742602 -21.513292)
		(width 0.4064)
		(layer "F.Cu")
		(net "GND")
	)
	(segment
		(start 81.485232 -79.36484)
		(end 80.913732 -79.36484)
		(width 0.254)
		(layer "F.Cu")
		(net "GND")
	)
	(segment
		(start 176.582578 -103.655622)
		(end 176.582578 -102.279704)
		(width 0.254)
		(layer "F.Cu")
		(net "GND")
	)
	(segment
		(start 289.050476 -147.27174)
		(end 289.049968 -147.27174)
		(width 0.4064)
		(layer "F.Cu")
		(net "GND")
	)
	(segment
		(start 251.065284 -53.608732)
		(end 250.778264 -54.104286)
		(width 0.254)
		(layer "F.Cu")
		(net "GND")
	)
	(segment
		(start 127.392176 -18.744946)
		(end 127.392176 -18.757646)
		(width 0.3556)
		(layer "F.Cu")
		(net "GND")
	)
	(segment
		(start 252.495304 -66.982086)
		(end 251.923804 -66.982086)
		(width 0.254)
		(layer "F.Cu")
		(net "GND")
	)
	(segment
		(start 240.476278 -54.104286)
		(end 239.904778 -54.104286)
		(width 0.254)
		(layer "F.Cu")
		(net "GND")
	)
	(segment
		(start 66.249296 -152.458166)
		(end 66.249296 -154.063446)
		(width 0.4064)
		(layer "F.Cu")
		(net "GND")
	)
	(segment
		(start 65.399412 -0.821182)
		(end 65.399412 0.444754)
		(width 0.4064)
		(layer "F.Cu")
		(net "GND")
	)
	(segment
		(start 68.607686 -91.747086)
		(end 67.959986 -91.747086)
		(width 0.254)
		(layer "F.Cu")
		(net "GND")
	)
	(segment
		(start 50.860452 -3.737356)
		(end 50.949352 -3.826256)
		(width 0.4064)
		(layer "F.Cu")
		(net "GND")
	)
	(segment
		(start 299.250354 -133.0706)
		(end 299.249846 -133.076442)
		(width 0.4064)
		(layer "F.Cu")
		(net "GND")
	)
	(segment
		(start 243.15039 -139.242292)
		(end 243.15039 -137.67054)
		(width 0.508)
		(layer "F.Cu")
		(net "GND")
	)
	(segment
		(start 141.899386 -7.607046)
		(end 141.899386 -5.822442)
		(width 0.4064)
		(layer "F.Cu")
		(net "GND")
	)
	(segment
		(start 386.007864 -81.594198)
		(end 386.337302 -81.923636)
		(width 0.254)
		(layer "F.Cu")
		(net "GND")
	)
	(segment
		(start 292.392608 -11.912092)
		(end 292.450012 -11.854688)
		(width 0.4064)
		(layer "F.Cu")
		(net "GND")
	)
	(segment
		(start 454.950068 -62.00267)
		(end 454.950068 -63.157354)
		(width 0.381)
		(layer "F.Cu")
		(net "GND")
	)
	(segment
		(start 221.050358 -0.821182)
		(end 221.04985 -0.821182)
		(width 0.4064)
		(layer "F.Cu")
		(net "GND")
	)
	(segment
		(start 20.18792 -42.808652)
		(end 20.2946 -42.701972)
		(width 0.254)
		(layer "F.Cu")
		(net "GND")
	)
	(segment
		(start 71.349362 3.050794)
		(end 71.117968 2.8194)
		(width 0.3556)
		(layer "F.Cu")
		(net "GND")
	)
	(segment
		(start 34.799524 -0.821182)
		(end 34.799524 -2.253488)
		(width 0.4064)
		(layer "F.Cu")
		(net "GND")
	)
	(segment
		(start 297.807126 -87.108538)
		(end 298.378626 -87.108538)
		(width 0.254)
		(layer "F.Cu")
		(net "GND")
	)
	(segment
		(start 47.549308 -152.458166)
		(end 47.549308 -154.063446)
		(width 0.4064)
		(layer "F.Cu")
		(net "GND")
	)
	(segment
		(start 233.608118 -84.812886)
		(end 233.036618 -84.812886)
		(width 0.254)
		(layer "F.Cu")
		(net "GND")
	)
	(segment
		(start 32.094932 -70.448932)
		(end 31.736792 -70.090792)
		(width 0.254)
		(layer "F.Cu")
		(net "GND")
	)
	(segment
		(start 280.637234 -50.3174)
		(end 280.637234 -50.3047)
		(width 0.2286)
		(layer "F.Cu")
		(net "GND")
	)
	(segment
		(start 456.600814 -116.993162)
		(end 456.600814 -118.615714)
		(width 0.4064)
		(layer "F.Cu")
		(net "GND")
	)
	(segment
		(start 300.382686 -90.575384)
		(end 300.954186 -90.575384)
		(width 0.254)
		(layer "F.Cu")
		(net "GND")
	)
	(segment
		(start 274.919186 -67.904614)
		(end 274.7518 -68.072)
		(width 0.254)
		(layer "F.Cu")
		(net "GND")
	)
	(segment
		(start 355.832156 -140.76299)
		(end 356.252526 -140.34262)
		(width 0.1778)
		(layer "F.Cu")
		(net "GND")
	)
	(segment
		(start 461.18018 -53.270912)
		(end 461.18018 -53.14442)
		(width 0.4064)
		(layer "F.Cu")
		(net "GND")
	)
	(segment
		(start 274.627848 -56.894984)
		(end 274.056348 -56.894984)
		(width 0.254)
		(layer "F.Cu")
		(net "GND")
	)
	(segment
		(start 391.795 -150.347426)
		(end 392.221974 -150.347426)
		(width 0.4064)
		(layer "F.Cu")
		(net "GND")
	)
	(segment
		(start 127.655828 -64.324738)
		(end 128.227328 -64.324738)
		(width 0.254)
		(layer "F.Cu")
		(net "GND")
	)
	(segment
		(start 297.549824 -142.677642)
		(end 297.549824 -144.462246)
		(width 0.4064)
		(layer "F.Cu")
		(net "GND")
	)
	(segment
		(start 267.948156 -63.019686)
		(end 268.557756 -63.019686)
		(width 0.254)
		(layer "F.Cu")
		(net "GND")
	)
	(segment
		(start 129.372868 -94.042738)
		(end 129.944368 -94.042738)
		(width 0.254)
		(layer "F.Cu")
		(net "GND")
	)
	(segment
		(start 143.599408 3.778758)
		(end 143.599408 2.092198)
		(width 0.4064)
		(layer "F.Cu")
		(net "GND")
	)
	(segment
		(start 288.36366 -78.688438)
		(end 288.93516 -78.688438)
		(width 0.254)
		(layer "F.Cu")
		(net "GND")
	)
	(segment
		(start 123.363228 -102.462584)
		(end 123.934728 -102.462584)
		(width 0.3048)
		(layer "F.Cu")
		(net "GND")
	)
	(segment
		(start 217.472006 -7.6454)
		(end 217.4494 -7.622794)
		(width 0.3556)
		(layer "F.Cu")
		(net "GND")
	)
	(segment
		(start 276.344634 -99.490784)
		(end 276.916134 -99.490784)
		(width 0.254)
		(layer "F.Cu")
		(net "GND")
	)
	(segment
		(start 399.634964 -103.855012)
		(end 399.634964 -102.855014)
		(width 0.254)
		(layer "F.Cu")
		(net "GND")
	)
	(segment
		(start 139.34948 -21.517356)
		(end 139.34948 -20.023582)
		(width 0.4064)
		(layer "F.Cu")
		(net "GND")
	)
	(segment
		(start 382.3462 -123.61799)
		(end 382.28905 -123.59132)
		(width 0.254)
		(layer "F.Cu")
		(net "GND")
	)
	(segment
		(start 245.627144 -70.94474)
		(end 245.055644 -70.94474)
		(width 0.254)
		(layer "F.Cu")
		(net "GND")
	)
	(segment
		(start 394.17625 -106.42092)
		(end 394.17625 -106.92257)
		(width 0.254)
		(layer "F.Cu")
		(net "GND")
	)
	(segment
		(start 61.149484 0.444754)
		(end 61.149484 -0.821182)
		(width 0.4064)
		(layer "F.Cu")
		(net "GND")
	)
	(segment
		(start 435.2417 -14.050518)
		(end 435.2417 -14.224)
		(width 0.254)
		(layer "F.Cu")
		(net "GND")
	)
	(segment
		(start 236.183678 -83.32724)
		(end 235.612178 -83.32724)
		(width 0.254)
		(layer "F.Cu")
		(net "GND")
	)
	(segment
		(start 381.29845 -115.00612)
		(end 381.782574 -115.231164)
		(width 0.254)
		(layer "F.Cu")
		(net "GND")
	)
	(segment
		(start 126.797308 -91.565984)
		(end 127.368808 -91.565984)
		(width 0.254)
		(layer "F.Cu")
		(net "GND")
	)
	(segment
		(start 122.504708 -66.305938)
		(end 121.933208 -66.305938)
		(width 0.254)
		(layer "F.Cu")
		(net "GND")
	)
	(segment
		(start 222.75038 -10.422382)
		(end 222.749872 -10.422382)
		(width 0.4064)
		(layer "F.Cu")
		(net "GND")
	)
	(segment
		(start 238.759238 -92.737686)
		(end 238.187738 -92.737686)
		(width 0.254)
		(layer "F.Cu")
		(net "GND")
	)
	(segment
		(start 69.64934 -4.7371)
		(end 69.56044 -4.6482)
		(width 0.4064)
		(layer "F.Cu")
		(net "GND")
	)
	(segment
		(start 108.768896 -62.343538)
		(end 108.197396 -62.343538)
		(width 0.254)
		(layer "F.Cu")
		(net "GND")
	)
	(segment
		(start 388.6708 -65.3288)
		(end 388.6708 -65.1764)
		(width 0.254)
		(layer "F.Cu")
		(net "GND")
	)
	(segment
		(start 295.000426 -155.613354)
		(end 294.999918 -155.612846)
		(width 0.3556)
		(layer "F.Cu")
		(net "GND")
	)
	(segment
		(start 250.778264 -65.991486)
		(end 250.206764 -65.991486)
		(width 0.254)
		(layer "F.Cu")
		(net "GND")
	)
	(segment
		(start 199.799956 -156.87294)
		(end 199.799956 -155.883102)
		(width 0.4064)
		(layer "F.Cu")
		(net "GND")
	)
	(segment
		(start 475.58706 -26.599642)
		(end 475.58706 -27.056334)
		(width 0.254)
		(layer "F.Cu")
		(net "GND")
	)
	(segment
		(start 379.301248 -113.217198)
		(end 378.985272 -113.015776)
		(width 0.2286)
		(layer "F.Cu")
		(net "GND")
	)
	(segment
		(start 56.899556 -152.273)
		(end 56.899556 -152.457912)
		(width 0.4064)
		(layer "F.Cu")
		(net "GND")
	)
	(segment
		(start 310.0832 -153.2128)
		(end 310.0832 -154.062938)
		(width 0.3556)
		(layer "F.Cu")
		(net "GND")
	)
	(segment
		(start 303.816766 -51.941984)
		(end 304.31232 -52.437538)
		(width 0.254)
		(layer "F.Cu")
		(net "GND")
	)
	(segment
		(start 72.142096 -9.143746)
		(end 72.142096 -9.156446)
		(width 0.3556)
		(layer "F.Cu")
		(net "GND")
	)
	(segment
		(start 284.929834 -89.584784)
		(end 285.501334 -89.584784)
		(width 0.254)
		(layer "F.Cu")
		(net "GND")
	)
	(segment
		(start 83.202272 -96.20504)
		(end 82.630772 -96.20504)
		(width 0.254)
		(layer "F.Cu")
		(net "GND")
	)
	(segment
		(start 124.049536 -0.821182)
		(end 124.049536 0.457454)
		(width 0.4064)
		(layer "F.Cu")
		(net "GND")
	)
	(segment
		(start 81.485232 -60.54344)
		(end 80.913732 -60.54344)
		(width 0.254)
		(layer "F.Cu")
		(net "GND")
	)
	(segment
		(start 301.241206 -93.052138)
		(end 301.812706 -93.052138)
		(width 0.3048)
		(layer "F.Cu")
		(net "GND")
	)
	(segment
		(start 117.353842 -98.005138)
		(end 117.925342 -98.005138)
		(width 0.254)
		(layer "F.Cu")
		(net "GND")
	)
	(segment
		(start 387.24205 -101.898196)
		(end 387.24205 -101.2698)
		(width 0.254)
		(layer "F.Cu")
		(net "GND")
	)
	(segment
		(start 75.59929 -152.458166)
		(end 75.59929 -154.063446)
		(width 0.4064)
		(layer "F.Cu")
		(net "GND")
	)
	(segment
		(start 197.151752 -17.208246)
		(end 197.249796 -17.110202)
		(width 0.4064)
		(layer "F.Cu")
		(net "GND")
	)
	(segment
		(start 32.160464 -3.737356)
		(end 32.249364 -3.826256)
		(width 0.4064)
		(layer "F.Cu")
		(net "GND")
	)
	(segment
		(start 412.965646 -21.945854)
		(end 412.877 -22.0345)
		(width 0.254)
		(layer "F.Cu")
		(net "GND")
	)
	(segment
		(start 91.514168 -149.8092)
		(end 91.224862 -150.098506)
		(width 0.4064)
		(layer "F.Cu")
		(net "GND")
	)
	(segment
		(start 82.412332 -101.577394)
		(end 82.343752 -101.508814)
		(width 0.2032)
		(layer "F.Cu")
		(net "GND")
	)
	(segment
		(start 117.640862 -58.876438)
		(end 118.212362 -58.876438)
		(width 0.254)
		(layer "F.Cu")
		(net "GND")
	)
	(segment
		(start 232.099866 -137.67054)
		(end 232.099866 -136.410446)
		(width 0.4064)
		(layer "F.Cu")
		(net "GND")
	)
	(segment
		(start 146.092164 -9.143746)
		(end 146.092164 -9.156446)
		(width 0.3556)
		(layer "F.Cu")
		(net "GND")
	)
	(segment
		(start 163.88842 -124.5235)
		(end 164.4523 -124.5235)
		(width 0.254)
		(layer "F.Cu")
		(net "GND")
	)
	(segment
		(start 148.699474 -11.916156)
		(end 148.699474 -10.422382)
		(width 0.4064)
		(layer "F.Cu")
		(net "GND")
	)
	(segment
		(start 387.731 -126.419102)
		(end 387.731 -126.662434)
		(width 0.254)
		(layer "F.Cu")
		(net "GND")
	)
	(segment
		(start 300.736 -153.237946)
		(end 300.736 -154.065732)
		(width 0.3556)
		(layer "F.Cu")
		(net "GND")
	)
	(segment
		(start 401.991576 -125.749558)
		(end 401.576032 -126.165102)
		(width 0.254)
		(layer "F.Cu")
		(net "GND")
	)
	(segment
		(start 195.509134 -4.317746)
		(end 195.135246 -4.317746)
		(width 0.4064)
		(layer "F.Cu")
		(net "GND")
	)
	(segment
		(start 377.83135 -119.29872)
		(end 378.32665 -119.528844)
		(width 0.254)
		(layer "F.Cu")
		(net "GND")
	)
	(segment
		(start 51.79949 -9.156446)
		(end 51.79949 -10.422382)
		(width 0.4064)
		(layer "F.Cu")
		(net "GND")
	)
	(segment
		(start 243.63172 -12.954)
		(end 243.562886 -12.885166)
		(width 0.4064)
		(layer "F.Cu")
		(net "GND")
	)
	(segment
		(start 283.212794 -88.594184)
		(end 283.784294 -88.594184)
		(width 0.254)
		(layer "F.Cu")
		(net "GND")
	)
	(segment
		(start 118.212362 -93.547184)
		(end 118.783862 -93.547184)
		(width 0.254)
		(layer "F.Cu")
		(net "GND")
	)
	(segment
		(start 212.549994 -6.001512)
		(end 212.54974 -6.001766)
		(width 0.4064)
		(layer "F.Cu")
		(net "GND")
	)
	(segment
		(start 116.399564 -147.27174)
		(end 116.399564 -146.011646)
		(width 0.4064)
		(layer "F.Cu")
		(net "GND")
	)
	(segment
		(start 399.76933 -125.435106)
		(end 398.984978 -125.435106)
		(width 0.254)
		(layer "F.Cu")
		(net "GND")
	)
	(segment
		(start 480.15144 -27.7495)
		(end 480.15144 -28.61056)
		(width 0.254)
		(layer "F.Cu")
		(net "GND")
	)
	(segment
		(start 448.437 -19.3675)
		(end 448.900296 -19.3675)
		(width 0.254)
		(layer "F.Cu")
		(net "GND")
	)
	(segment
		(start 279.700482 -137.67054)
		(end 279.699974 -137.67054)
		(width 0.4064)
		(layer "F.Cu")
		(net "GND")
	)
	(segment
		(start 108.768896 -55.409338)
		(end 108.197396 -55.409338)
		(width 0.254)
		(layer "F.Cu")
		(net "GND")
	)
	(segment
		(start 482.7778 -35.5854)
		(end 482.00056 -35.5854)
		(width 0.254)
		(layer "F.Cu")
		(net "GND")
	)
	(segment
		(start 138.499342 -6.637274)
		(end 138.040872 -7.095744)
		(width 0.4064)
		(layer "F.Cu")
		(net "GND")
	)
	(segment
		(start 387.24205 -118.4402)
		(end 387.734048 -118.6688)
		(width 0.254)
		(layer "F.Cu")
		(net "GND")
	)
	(segment
		(start 310.30037 -15.423642)
		(end 310.299862 -15.423642)
		(width 0.4064)
		(layer "F.Cu")
		(net "GND")
	)
	(segment
		(start 306.049934 -156.87294)
		(end 306.049934 -155.612846)
		(width 0.4064)
		(layer "F.Cu")
		(net "GND")
	)
	(segment
		(start 295.23182 -56.894984)
		(end 295.80332 -56.894984)
		(width 0.254)
		(layer "F.Cu")
		(net "GND")
	)
	(segment
		(start 147.390866 -7.095744)
		(end 147.849336 -6.637274)
		(width 0.4064)
		(layer "F.Cu")
		(net "GND")
	)
	(segment
		(start 303.499774 -6.637274)
		(end 303.041304 -7.095744)
		(width 0.4064)
		(layer "F.Cu")
		(net "GND")
	)
	(segment
		(start 272.052288 -90.080338)
		(end 272.623788 -90.080338)
		(width 0.254)
		(layer "F.Cu")
		(net "GND")
	)
	(segment
		(start 27.549348 -80.3148)
		(end 27.549348 -79.882492)
		(width 0.254)
		(layer "F.Cu")
		(net "GND")
	)
	(segment
		(start 112.202722 -60.362338)
		(end 111.631222 -60.362338)
		(width 0.254)
		(layer "F.Cu")
		(net "GND")
	)
	(segment
		(start 452.550022 -53.262022)
		(end 452.542656 -52.2478)
		(width 0.4064)
		(layer "F.Cu")
		(net "GND")
	)
	(segment
		(start 303.529746 -68.287138)
		(end 302.958246 -68.287138)
		(width 0.254)
		(layer "F.Cu")
		(net "GND")
	)
	(segment
		(start 459.3844 -29.845)
		(end 459.3336 -29.7942)
		(width 0.381)
		(layer "F.Cu")
		(net "GND")
	)
	(segment
		(start 462.980532 -140.219938)
		(end 464.476338 -140.219938)
		(width 0.254)
		(layer "F.Cu")
		(net "GND")
	)
	(segment
		(start 452.542148 -51.875944)
		(end 452.533004 -50.6222)
		(width 0.508)
		(layer "F.Cu")
		(net "GND")
	)
	(segment
		(start 397.212058 -157.232858)
		(end 397.212058 -157.829504)
		(width 0.2032)
		(layer "F.Cu")
		(net "GND")
	)
	(segment
		(start 391.73785 -104.65435)
		(end 391.3378 -104.2543)
		(width 0.254)
		(layer "F.Cu")
		(net "GND")
	)
	(segment
		(start 313.700414 -137.67054)
		(end 313.699906 -137.67054)
		(width 0.4064)
		(layer "F.Cu")
		(net "GND")
	)
	(segment
		(start 113.919762 -60.362338)
		(end 113.348262 -60.362338)
		(width 0.254)
		(layer "F.Cu")
		(net "GND")
	)
	(segment
		(start 114.699542 -156.87294)
		(end 114.699542 -155.600146)
		(width 0.4064)
		(layer "F.Cu")
		(net "GND")
	)
	(segment
		(start 291.3888 -134.0104)
		(end 291.3888 -134.866126)
		(width 0.3556)
		(layer "F.Cu")
		(net "GND")
	)
	(segment
		(start 289.049968 0.457454)
		(end 289.049968 -0.821182)
		(width 0.4064)
		(layer "F.Cu")
		(net "GND")
	)
	(segment
		(start 299.524166 -83.146138)
		(end 300.095666 -83.146138)
		(width 0.254)
		(layer "F.Cu")
		(net "GND")
	)
	(segment
		(start 8.632952 3.127248)
		(end 8.632952 2.69875)
		(width 0.2032)
		(layer "F.Cu")
		(net "GND")
	)
	(segment
		(start 113.849404 -138.898376)
		(end 113.849404 -137.676382)
		(width 0.508)
		(layer "F.Cu")
		(net "GND")
	)
	(segment
		(start 107.910376 -54.913784)
		(end 107.338876 -54.913784)
		(width 0.254)
		(layer "F.Cu")
		(net "GND")
	)
	(segment
		(start 50.099468 -136.397746)
		(end 50.099468 -137.67054)
		(width 0.4064)
		(layer "F.Cu")
		(net "GND")
	)
	(segment
		(start 136.240774 -72.249538)
		(end 136.812274 -72.249538)
		(width 0.254)
		(layer "F.Cu")
		(net "GND")
	)
	(segment
		(start 201.499724 -15.423896)
		(end 201.499978 -15.423642)
		(width 0.4064)
		(layer "F.Cu")
		(net "GND")
	)
	(segment
		(start 380.985014 -95.205042)
		(end 381.985012 -95.205042)
		(width 0.254)
		(layer "F.Cu")
		(net "GND")
	)
	(segment
		(start 117.925342 -99.986338)
		(end 117.353842 -99.986338)
		(width 0.254)
		(layer "F.Cu")
		(net "GND")
	)
	(segment
		(start 33.061402 -139.170156)
		(end 33.099502 -139.132056)
		(width 0.4064)
		(layer "F.Cu")
		(net "GND")
	)
	(segment
		(start 42.449496 -20.023582)
		(end 42.449496 -21.479256)
		(width 0.4064)
		(layer "F.Cu")
		(net "GND")
	)
	(segment
		(start 125.080268 -63.829184)
		(end 125.651768 -63.829184)
		(width 0.254)
		(layer "F.Cu")
		(net "GND")
	)
	(segment
		(start 399.634964 -114.85499)
		(end 400.05 -115.355116)
		(width 0.254)
		(layer "F.Cu")
		(net "GND")
	)
	(segment
		(start 204.050392 -147.27174)
		(end 204.049884 -147.27174)
		(width 0.4064)
		(layer "F.Cu")
		(net "GND")
	)
	(segment
		(start 85.777832 -57.076086)
		(end 85.206332 -57.076086)
		(width 0.254)
		(layer "F.Cu")
		(net "GND")
	)
	(segment
		(start 241.334798 -84.31784)
		(end 240.763298 -84.31784)
		(width 0.254)
		(layer "F.Cu")
		(net "GND")
	)
	(segment
		(start 34.74212 -146.224498)
		(end 34.74212 -145.998946)
		(width 0.4064)
		(layer "F.Cu")
		(net "GND")
	)
	(segment
		(start 156.4386 -130.3528)
		(end 156.944568 -130.3528)
		(width 0.4064)
		(layer "F.Cu")
		(net "GND")
	)
	(segment
		(start 109.627416 -62.838584)
		(end 109.055916 -62.838584)
		(width 0.254)
		(layer "F.Cu")
		(net "GND")
	)
	(segment
		(start 382.11379 -112.7506)
		(end 381.79375 -112.43056)
		(width 0.254)
		(layer "F.Cu")
		(net "GND")
	)
	(segment
		(start 195.549774 -142.677642)
		(end 195.549774 -143.946626)
		(width 0.4064)
		(layer "F.Cu")
		(net "GND")
	)
	(segment
		(start 312.849768 -152.278842)
		(end 312.849768 -153.093674)
		(width 0.4064)
		(layer "F.Cu")
		(net "GND")
	)
	(segment
		(start 289.899852 -5.822442)
		(end 289.899852 -3.826256)
		(width 0.4064)
		(layer "F.Cu")
		(net "GND")
	)
	(segment
		(start 127.44958 -136.46785)
		(end 127.392176 -136.410446)
		(width 0.3556)
		(layer "F.Cu")
		(net "GND")
	)
	(segment
		(start 377.33605 -102.98684)
		(end 377.83135 -102.756716)
		(width 0.254)
		(layer "F.Cu")
		(net "GND")
	)
	(segment
		(start 237.900718 -69.45884)
		(end 237.329218 -69.45884)
		(width 0.254)
		(layer "F.Cu")
		(net "GND")
	)
	(segment
		(start 211.699856 -147.27174)
		(end 211.699856 -148.771356)
		(width 0.4064)
		(layer "F.Cu")
		(net "GND")
	)
	(segment
		(start 300.736 -134.863332)
		(end 300.772068 -134.8994)
		(width 0.3556)
		(layer "F.Cu")
		(net "GND")
	)
	(segment
		(start 37.34943 -139.170156)
		(end 37.34943 -137.67054)
		(width 0.4064)
		(layer "F.Cu")
		(net "GND")
	)
	(segment
		(start 75.599544 -152.273)
		(end 75.599544 -152.457912)
		(width 0.4064)
		(layer "F.Cu")
		(net "GND")
	)
	(segment
		(start 308.600348 -15.423642)
		(end 308.59984 -15.423642)
		(width 0.4064)
		(layer "F.Cu")
		(net "GND")
	)
	(segment
		(start 286.64662 -51.941984)
		(end 286.893 -52.367434)
		(width 0.254)
		(layer "F.Cu")
		(net "GND")
	)
	(segment
		(start 399.634964 -106.855006)
		(end 399.634964 -107.855004)
		(width 0.254)
		(layer "F.Cu")
		(net "GND")
	)
	(segment
		(start 254.789432 -149.8092)
		(end 255.153668 -149.444964)
		(width 0.4572)
		(layer "F.Cu")
		(net "GND")
	)
	(segment
		(start 280.637234 -98.005138)
		(end 281.208734 -98.005138)
		(width 0.254)
		(layer "F.Cu")
		(net "GND")
	)
	(segment
		(start 86.636352 -71.44004)
		(end 86.064852 -71.44004)
		(width 0.254)
		(layer "F.Cu")
		(net "GND")
	)
	(segment
		(start 296.090594 -100.976938)
		(end 296.66184 -100.976938)
		(width 0.3048)
		(layer "F.Cu")
		(net "GND")
	)
	(segment
		(start 128.514348 -53.923184)
		(end 129.085848 -53.923184)
		(width 0.254)
		(layer "F.Cu")
		(net "GND")
	)
	(segment
		(start 138.499342 3.778758)
		(end 138.499342 2.963926)
		(width 0.4064)
		(layer "F.Cu")
		(net "GND")
	)
	(segment
		(start 386.13715 -107.05465)
		(end 386.5372 -107.4547)
		(width 0.254)
		(layer "F.Cu")
		(net "GND")
	)
	(segment
		(start 390.21385 -96.11868)
		(end 390.70915 -95.888556)
		(width 0.254)
		(layer "F.Cu")
		(net "GND")
	)
	(segment
		(start 303.038002 -4.346956)
		(end 301.732442 -4.2926)
		(width 0.254)
		(layer "F.Cu")
		(net "GND")
	)
	(segment
		(start 256.116836 -150.105364)
		(end 255.627124 -150.105364)
		(width 0.381)
		(layer "F.Cu")
		(net "GND")
	)
	(segment
		(start 220.199966 -142.677642)
		(end 220.199712 -142.677896)
		(width 0.4064)
		(layer "F.Cu")
		(net "GND")
	)
	(segment
		(start 469.40089 -116.993162)
		(end 469.40089 -115.625372)
		(width 0.4064)
		(layer "F.Cu")
		(net "GND")
	)
	(segment
		(start 294.3733 -83.146138)
		(end 294.9448 -83.146138)
		(width 0.254)
		(layer "F.Cu")
		(net "GND")
	)
	(segment
		(start 194.662806 -23.495)
		(end 194.564 -23.396194)
		(width 0.254)
		(layer "F.Cu")
		(net "GND")
	)
	(segment
		(start 92.645738 -53.113686)
		(end 92.074238 -53.113686)
		(width 0.254)
		(layer "F.Cu")
		(net "GND")
	)
	(segment
		(start 370.0145 -96.354646)
		(end 369.608354 -95.9485)
		(width 0.254)
		(layer "F.Cu")
		(net "GND")
	)
	(segment
		(start 310.0832 1.994662)
		(end 310.122062 1.9558)
		(width 0.3556)
		(layer "F.Cu")
		(net "GND")
	)
	(segment
		(start 221.04985 -137.67054)
		(end 221.04985 -136.410446)
		(width 0.4064)
		(layer "F.Cu")
		(net "GND")
	)
	(segment
		(start 55.199534 -142.677642)
		(end 55.19928 -142.677896)
		(width 0.4064)
		(layer "F.Cu")
		(net "GND")
	)
	(segment
		(start 74.617326 -92.24264)
		(end 74.045826 -92.24264)
		(width 0.254)
		(layer "F.Cu")
		(net "GND")
	)
	(segment
		(start 295.23182 -96.518984)
		(end 295.80332 -96.518984)
		(width 0.254)
		(layer "F.Cu")
		(net "GND")
	)
	(segment
		(start 216.799922 -21.479256)
		(end 216.761822 -21.517356)
		(width 0.4064)
		(layer "F.Cu")
		(net "GND")
	)
	(segment
		(start 279.699974 -2.314956)
		(end 279.699974 -0.821182)
		(width 0.4064)
		(layer "F.Cu")
		(net "GND")
	)
	(segment
		(start 116.399564 -137.67054)
		(end 116.399564 -136.410446)
		(width 0.4064)
		(layer "F.Cu")
		(net "GND")
	)
	(segment
		(start 111.344202 -51.941984)
		(end 111.344202 -52.077366)
		(width 0.254)
		(layer "F.Cu")
		(net "GND")
	)
	(segment
		(start 250.778264 -91.747086)
		(end 250.206764 -91.747086)
		(width 0.254)
		(layer "F.Cu")
		(net "GND")
	)
	(segment
		(start 283.100272 -137.67054)
		(end 283.099764 -137.67054)
		(width 0.3556)
		(layer "F.Cu")
		(net "GND")
	)
	(segment
		(start 68.894706 -53.60924)
		(end 69.466206 -53.60924)
		(width 0.254)
		(layer "F.Cu")
		(net "GND")
	)
	(segment
		(start 238.8997 -6.637274)
		(end 238.44123 -7.095744)
		(width 0.4064)
		(layer "F.Cu")
		(net "GND")
	)
	(segment
		(start 376.335036 -115.854988)
		(end 376.335036 -115.78844)
		(width 0.254)
		(layer "F.Cu")
		(net "GND")
	)
	(segment
		(start 111.344202 -61.847984)
		(end 110.772702 -61.847984)
		(width 0.254)
		(layer "F.Cu")
		(net "GND")
	)
	(segment
		(start 442.130688 -50.554128)
		(end 442.142118 -51.875944)
		(width 0.4064)
		(layer "F.Cu")
		(net "GND")
	)
	(segment
		(start 295.23182 -70.763384)
		(end 295.80332 -70.763384)
		(width 0.254)
		(layer "F.Cu")
		(net "GND")
	)
	(segment
		(start 374.609614 -95.165672)
		(end 374.674892 -95.165672)
		(width 0.254)
		(layer "F.Cu")
		(net "GND")
	)
	(segment
		(start 68.607686 -55.094886)
		(end 69.753226 -55.094886)
		(width 0.254)
		(layer "F.Cu")
		(net "GND")
	)
	(segment
		(start 476.20555 -143.28775)
		(end 476.6691 -142.8242)
		(width 0.254)
		(layer "F.Cu")
		(net "GND")
	)
	(segment
		(start 243.910104 -58.06694)
		(end 243.338604 -58.06694)
		(width 0.254)
		(layer "F.Cu")
		(net "GND")
	)
	(segment
		(start 116.495322 -54.913784)
		(end 115.923822 -54.913784)
		(width 0.254)
		(layer "F.Cu")
		(net "GND")
	)
	(segment
		(start 137.099294 -60.857384)
		(end 137.670794 -60.857384)
		(width 0.254)
		(layer "F.Cu")
		(net "GND")
	)
	(segment
		(start 40.749474 -2.314956)
		(end 40.749474 -0.821182)
		(width 0.4064)
		(layer "F.Cu")
		(net "GND")
	)
	(segment
		(start 445.148716 -60.633864)
		(end 445.148716 -60.378848)
		(width 0.381)
		(layer "F.Cu")
		(net "GND")
	)
	(segment
		(start 435.727094 -149.154642)
		(end 436.245 -149.154642)
		(width 0.254)
		(layer "F.Cu")
		(net "GND")
	)
	(segment
		(start 487.554016 -146.508978)
		(end 486.560622 -146.508978)
		(width 0.254)
		(layer "F.Cu")
		(net "GND")
	)
	(segment
		(start 384.1496 -115.443)
		(end 384.53695 -115.05565)
		(width 0.12446)
		(layer "F.Cu")
		(net "GND")
	)
	(segment
		(start 367.945162 -69.495162)
		(end 368.344958 -69.894958)
		(width 0.254)
		(layer "F.Cu")
		(net "GND")
	)
	(segment
		(start 390.578594 -155.802838)
		(end 390.578594 -155.394406)
		(width 0.254)
		(layer "F.Cu")
		(net "GND")
	)
	(segment
		(start 280.637234 -87.108538)
		(end 280.637234 -86.537038)
		(width 0.381)
		(layer "F.Cu")
		(net "GND")
	)
	(segment
		(start 289.050476 -10.422382)
		(end 289.049968 -10.422382)
		(width 0.4064)
		(layer "F.Cu")
		(net "GND")
	)
	(segment
		(start 76.334366 -76.39304)
		(end 75.762866 -76.39304)
		(width 0.254)
		(layer "F.Cu")
		(net "GND")
	)
	(segment
		(start 107.910376 -93.547184)
		(end 108.481876 -93.547184)
		(width 0.254)
		(layer "F.Cu")
		(net "GND")
	)
	(segment
		(start 282.24988 -6.548374)
		(end 282.0162 -6.782054)
		(width 0.3556)
		(layer "F.Cu")
		(net "GND")
	)
	(segment
		(start 213.399878 0.444754)
		(end 213.399878 -0.821182)
		(width 0.4064)
		(layer "F.Cu")
		(net "GND")
	)
	(segment
		(start 215.949784 -152.278842)
		(end 215.949784 -153.965402)
		(width 0.4064)
		(layer "F.Cu")
		(net "GND")
	)
	(segment
		(start 30.549342 -142.6718)
		(end 30.549342 -143.946626)
		(width 0.4064)
		(layer "F.Cu")
		(net "GND")
	)
	(segment
		(start 145.29943 -13.541756)
		(end 145.29943 -15.423642)
		(width 0.4064)
		(layer "F.Cu")
		(net "GND")
	)
	(segment
		(start 238.759238 -59.057286)
		(end 238.187738 -59.057286)
		(width 0.254)
		(layer "F.Cu")
		(net "GND")
	)
	(segment
		(start 296.69994 -20.023582)
		(end 296.69994 -21.517356)
		(width 0.4064)
		(layer "F.Cu")
		(net "GND")
	)
	(segment
		(start 206.600298 -15.423642)
		(end 206.59979 -15.423642)
		(width 0.4064)
		(layer "F.Cu")
		(net "GND")
	)
	(segment
		(start 131.699508 -156.87294)
		(end 131.699508 -155.612846)
		(width 0.4064)
		(layer "F.Cu")
		(net "GND")
	)
	(segment
		(start 239.617758 -63.51524)
		(end 239.046258 -63.51524)
		(width 0.254)
		(layer "F.Cu")
		(net "GND")
	)
	(segment
		(start 74.617326 -97.19564)
		(end 74.045826 -97.19564)
		(width 0.254)
		(layer "F.Cu")
		(net "GND")
	)
	(segment
		(start 221.04985 -9.156446)
		(end 221.04985 -10.422382)
		(width 0.4064)
		(layer "F.Cu")
		(net "GND")
	)
	(segment
		(start 285.7881 -91.070938)
		(end 286.3596 -91.070938)
		(width 0.254)
		(layer "F.Cu")
		(net "GND")
	)
	(segment
		(start 117.015768 -144.44472)
		(end 117.071648 -144.5006)
		(width 0.3556)
		(layer "F.Cu")
		(net "GND")
	)
	(segment
		(start 76.449428 -18.757646)
		(end 76.449428 -20.023582)
		(width 0.4064)
		(layer "F.Cu")
		(net "GND")
	)
	(segment
		(start 122.504708 -96.023938)
		(end 123.076208 -96.023938)
		(width 0.254)
		(layer "F.Cu")
		(net "GND")
	)
	(segment
		(start 292.450012 -147.27174)
		(end 292.450012 -146.06905)
		(width 0.3556)
		(layer "F.Cu")
		(net "GND")
	)
	(segment
		(start 377.98502 -126.101348)
		(end 377.921266 -126.165102)
		(width 0.254)
		(layer "F.Cu")
		(net "GND")
	)
	(segment
		(start 447.74104 -46.046898)
		(end 447.74104 -47.481998)
		(width 0.4064)
		(layer "F.Cu")
		(net "GND")
	)
	(segment
		(start 274.627848 -99.490784)
		(end 275.199348 -99.490784)
		(width 0.254)
		(layer "F.Cu")
		(net "GND")
	)
	(segment
		(start 394.17625 -103.615236)
		(end 394.67155 -103.84536)
		(width 0.254)
		(layer "F.Cu")
		(net "GND")
	)
	(segment
		(start 301.241206 -74.230738)
		(end 301.812706 -74.230738)
		(width 0.254)
		(layer "F.Cu")
		(net "GND")
	)
	(segment
		(start 236.1184 -16.383)
		(end 236.349794 -16.151606)
		(width 0.3556)
		(layer "F.Cu")
		(net "GND")
	)
	(segment
		(start 317.100458 -133.0706)
		(end 317.09995 -133.076442)
		(width 0.4064)
		(layer "F.Cu")
		(net "GND")
	)
	(segment
		(start 91.52763 -12.613386)
		(end 90.871548 -12.613386)
		(width 0.381)
		(layer "F.Cu")
		(net "GND")
	)
	(segment
		(start 33.099502 -10.422382)
		(end 33.099502 -9.139682)
		(width 0.4064)
		(layer "F.Cu")
		(net "GND")
	)
	(segment
		(start 217.649806 -15.423642)
		(end 217.649806 -13.541756)
		(width 0.4064)
		(layer "F.Cu")
		(net "GND")
	)
	(segment
		(start 199.799956 -137.67054)
		(end 199.799956 -136.680702)
		(width 0.4064)
		(layer "F.Cu")
		(net "GND")
	)
	(segment
		(start 394.67155 -102.12832)
		(end 394.903706 -102.02037)
		(width 0.254)
		(layer "F.Cu")
		(net "GND")
	)
	(segment
		(start 398.027144 -95.183706)
		(end 398.505426 -95.183706)
		(width 0.254)
		(layer "F.Cu")
		(net "GND")
	)
	(segment
		(start 238.759238 -60.047886)
		(end 238.187738 -60.047886)
		(width 0.254)
		(layer "F.Cu")
		(net "GND")
	)
	(segment
		(start 212.550502 3.778758)
		(end 212.549994 3.778758)
		(width 0.4064)
		(layer "F.Cu")
		(net "GND")
	)
	(segment
		(start 42.449496 -148.733256)
		(end 42.449496 -147.27174)
		(width 0.4064)
		(layer "F.Cu")
		(net "GND")
	)
	(segment
		(start 229.091236 -7.095744)
		(end 229.549706 -6.637274)
		(width 0.4064)
		(layer "F.Cu")
		(net "GND")
	)
	(segment
		(start 440.476386 -9.063736)
		(end 440.476386 -7.789672)
		(width 0.254)
		(layer "F.Cu")
		(net "GND")
	)
	(segment
		(start 412.076646 -21.409152)
		(end 412.864554 -21.409152)
		(width 0.254)
		(layer "F.Cu")
		(net "GND")
	)
	(segment
		(start 41.599358 -17.110202)
		(end 41.599358 -15.423642)
		(width 0.4064)
		(layer "F.Cu")
		(net "GND")
	)
	(segment
		(start 202.349862 -10.422382)
		(end 202.349862 -11.916156)
		(width 0.4064)
		(layer "F.Cu")
		(net "GND")
	)
	(segment
		(start 142.898114 -89.584784)
		(end 142.250414 -89.584784)
		(width 0.254)
		(layer "F.Cu")
		(net "GND")
	)
	(segment
		(start 322.066412 -130.474212)
		(end 322.326 -130.7338)
		(width 0.4064)
		(layer "F.Cu")
		(net "GND")
	)
	(segment
		(start 423.672 -105.7148)
		(end 422.31564 -105.7148)
		(width 0.254)
		(layer "F.Cu")
		(net "GND")
	)
	(segment
		(start 300.382686 -73.735184)
		(end 300.954186 -73.735184)
		(width 0.254)
		(layer "F.Cu")
		(net "GND")
	)
	(segment
		(start 234.649772 3.778758)
		(end 234.649772 2.092198)
		(width 0.4064)
		(layer "F.Cu")
		(net "GND")
	)
	(segment
		(start 72.1995 -9.21385)
		(end 72.1995 -10.422382)
		(width 0.3556)
		(layer "F.Cu")
		(net "GND")
	)
	(segment
		(start 350.0628 -148.774912)
		(end 350.0628 -148.773896)
		(width 0.4064)
		(layer "F.Cu")
		(net "GND")
	)
	(segment
		(start 102.947724 -63.019686)
		(end 103.557324 -63.019686)
		(width 0.254)
		(layer "F.Cu")
		(net "GND")
	)
	(segment
		(start 315.399928 -20.023582)
		(end 315.399928 -18.757646)
		(width 0.4064)
		(layer "F.Cu")
		(net "GND")
	)
	(segment
		(start 374.523 -93.393006)
		(end 374.523 -92.837)
		(width 0.254)
		(layer "F.Cu")
		(net "GND")
	)
	(segment
		(start 212.550502 -133.0706)
		(end 212.549994 -133.076442)
		(width 0.4064)
		(layer "F.Cu")
		(net "GND")
	)
	(segment
		(start 61.821568 -3.762756)
		(end 61.999368 -3.940556)
		(width 0.4064)
		(layer "F.Cu")
		(net "GND")
	)
	(segment
		(start 215.949784 -3.826256)
		(end 215.949784 -5.822442)
		(width 0.4064)
		(layer "F.Cu")
		(net "GND")
	)
	(segment
		(start 124.221748 -56.399938)
		(end 123.650248 -56.399938)
		(width 0.254)
		(layer "F.Cu")
		(net "GND")
	)
	(segment
		(start 223.60001 -13.36421)
		(end 223.599756 -13.363956)
		(width 0.4064)
		(layer "F.Cu")
		(net "GND")
	)
	(segment
		(start 304.675286 -55.409338)
		(end 305.246786 -55.409338)
		(width 0.254)
		(layer "F.Cu")
		(net "GND")
	)
	(segment
		(start 279.778714 -56.894984)
		(end 279.207214 -56.894984)
		(width 0.254)
		(layer "F.Cu")
		(net "GND")
	)
	(segment
		(start 413.255968 -120.65)
		(end 411.607 -120.65)
		(width 0.254)
		(layer "F.Cu")
		(net "GND")
	)
	(segment
		(start 2.657348 -124.629672)
		(end 2.652522 -124.624846)
		(width 0.2032)
		(layer "F.Cu")
		(net "GND")
	)
	(segment
		(start 493.903 -46.7106)
		(end 493.903 -47.21987)
		(width 0.254)
		(layer "F.Cu")
		(net "GND")
	)
	(segment
		(start 280.637234 -90.080338)
		(end 281.208734 -90.080338)
		(width 0.254)
		(layer "F.Cu")
		(net "GND")
	)
	(segment
		(start 232.749598 -90.26144)
		(end 232.101898 -90.26144)
		(width 0.254)
		(layer "F.Cu")
		(net "GND")
	)
	(segment
		(start 246.485664 -99.17684)
		(end 245.914164 -99.17684)
		(width 0.254)
		(layer "F.Cu")
		(net "GND")
	)
	(segment
		(start 447.000884 -116.993162)
		(end 447.000884 -118.615714)
		(width 0.4064)
		(layer "F.Cu")
		(net "GND")
	)
	(segment
		(start 196.273928 -85.733382)
		(end 196.273928 -86.101682)
		(width 0.4064)
		(layer "F.Cu")
		(net "GND")
	)
	(segment
		(start 52.649374 -142.6718)
		(end 52.649374 -143.411194)
		(width 0.3048)
		(layer "F.Cu")
		(net "GND")
	)
	(segment
		(start 418.2618 -121.9962)
		(end 418.2618 -121.099326)
		(width 0.4064)
		(layer "F.Cu")
		(net "GND")
	)
	(segment
		(start 108.768896 -99.986338)
		(end 109.340396 -99.986338)
		(width 0.254)
		(layer "F.Cu")
		(net "GND")
	)
	(segment
		(start 236.349794 -13.541756)
		(end 236.171994 -13.363956)
		(width 0.4064)
		(layer "F.Cu")
		(net "GND")
	)
	(segment
		(start 248.202704 -88.28024)
		(end 247.631204 -88.28024)
		(width 0.254)
		(layer "F.Cu")
		(net "GND")
	)
	(segment
		(start 297.549824 -17.208246)
		(end 297.549824 -15.423642)
		(width 0.4064)
		(layer "F.Cu")
		(net "GND")
	)
	(segment
		(start -3.1623 -150.10511)
		(end -2.48539 -150.10511)
		(width 0.508)
		(layer "F.Cu")
		(net "GND")
	)
	(segment
		(start 445.3636 -53.3146)
		(end 445.34963 -53.300884)
		(width 0.4064)
		(layer "F.Cu")
		(net "GND")
	)
	(segment
		(start 210.849718 -6.637274)
		(end 210.391248 -7.095744)
		(width 0.4064)
		(layer "F.Cu")
		(net "GND")
	)
	(segment
		(start 198.755 -16.3322)
		(end 198.949818 -16.137382)
		(width 0.3556)
		(layer "F.Cu")
		(net "GND")
	)
	(segment
		(start 52.448968 1.978406)
		(end 52.471574 1.9558)
		(width 0.3556)
		(layer "F.Cu")
		(net "GND")
	)
	(segment
		(start 193.860928 -92.210382)
		(end 193.129916 -92.210382)
		(width 0.254)
		(layer "F.Cu")
		(net "GND")
	)
	(segment
		(start 139.34948 -156.87294)
		(end 139.34948 -155.612846)
		(width 0.4064)
		(layer "F.Cu")
		(net "GND")
	)
	(segment
		(start 49.249584 -13.36421)
		(end 49.24933 -13.363956)
		(width 0.4064)
		(layer "F.Cu")
		(net "GND")
	)
	(segment
		(start 308.59984 -153.965402)
		(end 308.501796 -154.063446)
		(width 0.4064)
		(layer "F.Cu")
		(net "GND")
	)
	(segment
		(start 255.92913 -53.113686)
		(end 255.35763 -53.113686)
		(width 0.254)
		(layer "F.Cu")
		(net "GND")
	)
	(segment
		(start 281.399996 -2.276856)
		(end 281.399996 -0.821182)
		(width 0.4064)
		(layer "F.Cu")
		(net "GND")
	)
	(segment
		(start 197.250304 -142.6718)
		(end 197.249796 -142.677642)
		(width 0.4064)
		(layer "F.Cu")
		(net "GND")
	)
	(segment
		(start 427.26864 -17.4244)
		(end 424.360848 -17.4244)
		(width 0.254)
		(layer "F.Cu")
		(net "GND")
	)
	(segment
		(start 290.93922 -56.399938)
		(end 291.51072 -56.399938)
		(width 0.254)
		(layer "F.Cu")
		(net "GND")
	)
	(segment
		(start 256.78765 -60.54344)
		(end 256.21615 -60.54344)
		(width 0.254)
		(layer "F.Cu")
		(net "GND")
	)
	(segment
		(start 322.077588 -13.828522)
		(end 322.077588 -13.492988)
		(width 0.4064)
		(layer "F.Cu")
		(net "GND")
	)
	(segment
		(start 212.54974 -133.255766)
		(end 212.54974 -134.861046)
		(width 0.4064)
		(layer "F.Cu")
		(net "GND")
	)
	(segment
		(start 215.100408 -147.27174)
		(end 215.0999 -147.27174)
		(width 0.4064)
		(layer "F.Cu")
		(net "GND")
	)
	(segment
		(start 308.600348 -152.273)
		(end 308.59984 -152.278842)
		(width 0.4064)
		(layer "F.Cu")
		(net "GND")
	)
	(segment
		(start 112.202722 -54.418738)
		(end 111.631222 -54.418738)
		(width 0.254)
		(layer "F.Cu")
		(net "GND")
	)
	(segment
		(start 291.3888 -16.3576)
		(end 291.599874 -16.146526)
		(width 0.3556)
		(layer "F.Cu")
		(net "GND")
	)
	(segment
		(start 402.134832 -104.85501)
		(end 401.295108 -104.85501)
		(width 0.254)
		(layer "F.Cu")
		(net "GND")
	)
	(segment
		(start 215.0999 -21.517356)
		(end 215.0999 -20.023582)
		(width 0.4064)
		(layer "F.Cu")
		(net "GND")
	)
	(segment
		(start 500.291862 -35.31997)
		(end 500.579898 -35.31997)
		(width 0.254)
		(layer "F.Cu")
		(net "GND")
	)
	(segment
		(start 282.0162 2.819146)
		(end 282.0162 2.01168)
		(width 0.3556)
		(layer "F.Cu")
		(net "GND")
	)
	(segment
		(start 58.599324 3.778504)
		(end 58.599324 1.994154)
		(width 0.4064)
		(layer "F.Cu")
		(net "GND")
	)
	(segment
		(start 126.797308 -89.584784)
		(end 127.368808 -89.584784)
		(width 0.254)
		(layer "F.Cu")
		(net "GND")
	)
	(segment
		(start 124.221748 -98.995738)
		(end 124.793248 -98.995738)
		(width 0.254)
		(layer "F.Cu")
		(net "GND")
	)
	(segment
		(start 353.8728 -99.695)
		(end 353.8728 -99.50323)
		(width 0.254)
		(layer "F.Cu")
		(net "GND")
	)
	(segment
		(start 415.757106 -48.746918)
		(end 415.757106 -49.106582)
		(width 0.254)
		(layer "F.Cu")
		(net "GND")
	)
	(segment
		(start 303.529746 -71.258938)
		(end 302.958246 -71.258938)
		(width 0.254)
		(layer "F.Cu")
		(net "GND")
	)
	(segment
		(start 457.2 -33.687258)
		(end 457.2 -33.034986)
		(width 0.254)
		(layer "F.Cu")
		(net "GND")
	)
	(segment
		(start 427.674786 -3.71221)
		(end 427.965108 -3.421888)
		(width 0.254)
		(layer "F.Cu")
		(net "GND")
	)
	(segment
		(start 310.30037 -133.0706)
		(end 310.299862 -133.076442)
		(width 0.3556)
		(layer "F.Cu")
		(net "GND")
	)
	(segment
		(start 129.149348 -143.492474)
		(end 128.690878 -143.950944)
		(width 0.4064)
		(layer "F.Cu")
		(net "GND")
	)
	(segment
		(start 235.46181 -18.757646)
		(end 235.49991 -18.795746)
		(width 0.4064)
		(layer "F.Cu")
		(net "GND")
	)
	(segment
		(start 243.910104 -89.765886)
		(end 243.338604 -89.765886)
		(width 0.254)
		(layer "F.Cu")
		(net "GND")
	)
	(segment
		(start 377.093988 -95.498666)
		(end 377.093734 -95.498666)
		(width 0.254)
		(layer "F.Cu")
		(net "GND")
	)
	(segment
		(start 238.759238 -96.700086)
		(end 238.187738 -96.700086)
		(width 0.254)
		(layer "F.Cu")
		(net "GND")
	)
	(segment
		(start 300.736 2.819654)
		(end 300.736 1.991868)
		(width 0.3556)
		(layer "F.Cu")
		(net "GND")
	)
	(segment
		(start 142.898114 -87.603584)
		(end 142.250414 -87.603584)
		(width 0.254)
		(layer "F.Cu")
		(net "GND")
	)
	(segment
		(start 129.372868 -61.352938)
		(end 129.944368 -61.352938)
		(width 0.254)
		(layer "F.Cu")
		(net "GND")
	)
	(segment
		(start 235.49991 -156.87294)
		(end 235.500418 -156.87294)
		(width 0.4064)
		(layer "F.Cu")
		(net "GND")
	)
	(segment
		(start 392.69035 -102.756716)
		(end 392.43 -102.87762)
		(width 0.254)
		(layer "F.Cu")
		(net "GND")
	)
	(segment
		(start 107.051856 -98.005138)
		(end 107.623356 -98.005138)
		(width 0.254)
		(layer "F.Cu")
		(net "GND")
	)
	(segment
		(start 142.749524 -20.023582)
		(end 142.749524 -21.517356)
		(width 0.4064)
		(layer "F.Cu")
		(net "GND")
	)
	(segment
		(start 70.499478 -0.821182)
		(end 70.499478 0.444754)
		(width 0.4064)
		(layer "F.Cu")
		(net "GND")
	)
	(segment
		(start 235.325158 -82.83194)
		(end 234.753658 -82.83194)
		(width 0.254)
		(layer "F.Cu")
		(net "GND")
	)
	(segment
		(start 78.909672 -66.982086)
		(end 78.338172 -66.982086)
		(width 0.254)
		(layer "F.Cu")
		(net "GND")
	)
	(segment
		(start 250.778264 -60.047886)
		(end 250.206764 -60.047886)
		(width 0.254)
		(layer "F.Cu")
		(net "GND")
	)
	(segment
		(start 368.69624 -106.217466)
		(end 370.009674 -106.217466)
		(width 0.254)
		(layer "F.Cu")
		(net "GND")
	)
	(segment
		(start 82.343752 -71.935086)
		(end 81.772252 -71.935086)
		(width 0.254)
		(layer "F.Cu")
		(net "GND")
	)
	(segment
		(start 208.122012 -17.2466)
		(end 208.0768 -17.201388)
		(width 0.3556)
		(layer "F.Cu")
		(net "GND")
	)
	(segment
		(start 467.800944 -113.874296)
		(end 467.800944 -112.205516)
		(width 0.254)
		(layer "F.Cu")
		(net "GND")
	)
	(segment
		(start 465.4804 -146.2024)
		(end 464.5152 -146.2024)
		(width 0.4064)
		(layer "F.Cu")
		(net "GND")
	)
	(segment
		(start 280.549858 -144.364202)
		(end 280.451814 -144.462246)
		(width 0.4064)
		(layer "F.Cu")
		(net "GND")
	)
	(segment
		(start 173.609 -85.9028)
		(end 173.7614 -85.9028)
		(width 0.254)
		(layer "F.Cu")
		(net "GND")
	)
	(segment
		(start 306.963826 -59.579764)
		(end 306.963826 -59.371484)
		(width 0.254)
		(layer "F.Cu")
		(net "GND")
	)
	(segment
		(start 134.523734 -73.240138)
		(end 135.095234 -73.240138)
		(width 0.254)
		(layer "F.Cu")
		(net "GND")
	)
	(segment
		(start 462.149952 -58.954924)
		(end 462.149952 -57.596024)
		(width 0.4064)
		(layer "F.Cu")
		(net "GND")
	)
	(segment
		(start 300.949868 3.778758)
		(end 300.949868 3.033522)
		(width 0.3556)
		(layer "F.Cu")
		(net "GND")
	)
	(segment
		(start 374.200674 -109.855)
		(end 374.142 -109.913674)
		(width 0.254)
		(layer "F.Cu")
		(net "GND")
	)
	(segment
		(start 119.7991 -152.279096)
		(end 119.7991 -153.093674)
		(width 0.4064)
		(layer "F.Cu")
		(net "GND")
	)
	(segment
		(start 113.865914 -145.992342)
		(end 113.849404 -146.008852)
		(width 0.4064)
		(layer "F.Cu")
		(net "GND")
	)
	(segment
		(start 208.0768 -154.056588)
		(end 208.122012 -154.1018)
		(width 0.3556)
		(layer "F.Cu")
		(net "GND")
	)
	(segment
		(start 131.089908 -87.108538)
		(end 131.661408 -87.108538)
		(width 0.254)
		(layer "F.Cu")
		(net "GND")
	)
	(segment
		(start 307.898546 -64.172084)
		(end 307.250846 -64.819784)
		(width 0.254)
		(layer "F.Cu")
		(net "GND")
	)
	(segment
		(start 452.542656 -52.2478)
		(end 452.540116 -51.875944)
		(width 0.4064)
		(layer "F.Cu")
		(net "GND")
	)
	(segment
		(start 45.849286 -152.279096)
		(end 45.849286 -153.093674)
		(width 0.4064)
		(layer "F.Cu")
		(net "GND")
	)
	(segment
		(start 68.799456 -18.744946)
		(end 68.799456 -20.023582)
		(width 0.4064)
		(layer "F.Cu")
		(net "GND")
	)
	(segment
		(start 87.494872 -84.812886)
		(end 86.923372 -84.812886)
		(width 0.254)
		(layer "F.Cu")
		(net "GND")
	)
	(segment
		(start 101.230684 -95.709486)
		(end 100.659184 -95.709486)
		(width 0.254)
		(layer "F.Cu")
		(net "GND")
	)
	(segment
		(start 198.099934 -156.87294)
		(end 198.099934 -155.612846)
		(width 0.4064)
		(layer "F.Cu")
		(net "GND")
	)
	(segment
		(start 443.800992 -116.993162)
		(end 443.800992 -118.615714)
		(width 0.4064)
		(layer "F.Cu")
		(net "GND")
	)
	(segment
		(start 284.799532 -5.822696)
		(end 284.799532 -6.637274)
		(width 0.4064)
		(layer "F.Cu")
		(net "GND")
	)
	(segment
		(start 86.923372 -98.681286)
		(end 86.636352 -99.17684)
		(width 0.254)
		(layer "F.Cu")
		(net "GND")
	)
	(segment
		(start 424.144186 -26.162)
		(end 423.890186 -26.416)
		(width 0.254)
		(layer "F.Cu")
		(net "GND")
	)
	(segment
		(start 493.429798 -25.622758)
		(end 493.64646 -25.83942)
		(width 0.254)
		(layer "F.Cu")
		(net "GND")
	)
	(segment
		(start 351.9932 -155.6512)
		(end 351.9932 -155.575)
		(width 0.254)
		(layer "F.Cu")
		(net "GND")
	)
	(segment
		(start 209.14995 -21.455888)
		(end 209.092546 -21.513292)
		(width 0.4064)
		(layer "F.Cu")
		(net "GND")
	)
	(segment
		(start 213.400386 -147.27174)
		(end 213.399878 -147.27174)
		(width 0.4064)
		(layer "F.Cu")
		(net "GND")
	)
	(segment
		(start 122.349514 -0.821182)
		(end 122.349514 0.444754)
		(width 0.4064)
		(layer "F.Cu")
		(net "GND")
	)
	(segment
		(start 138.816334 -61.847984)
		(end 139.387834 -61.847984)
		(width 0.254)
		(layer "F.Cu")
		(net "GND")
	)
	(segment
		(start 49.24933 3.778504)
		(end 49.24933 1.994154)
		(width 0.4064)
		(layer "F.Cu")
		(net "GND")
	)
	(segment
		(start 164.99078 -0.77978)
		(end 164.99078 -0.239522)
		(width 0.254)
		(layer "F.Cu")
		(net "GND")
	)
	(segment
		(start 69.64934 -15.423642)
		(end 69.64934 -17.110202)
		(width 0.4064)
		(layer "F.Cu")
		(net "GND")
	)
	(segment
		(start 141.391894 -97.014538)
		(end 141.95171 -97.014538)
		(width 0.254)
		(layer "F.Cu")
		(net "GND")
	)
	(segment
		(start 241.334798 -100.167186)
		(end 240.763298 -100.167186)
		(width 0.254)
		(layer "F.Cu")
		(net "GND")
	)
	(segment
		(start 59.449462 -0.821182)
		(end 59.449462 0.457454)
		(width 0.4064)
		(layer "F.Cu")
		(net "GND")
	)
	(segment
		(start 240.600484 3.778758)
		(end 240.599976 3.778758)
		(width 0.4064)
		(layer "F.Cu")
		(net "GND")
	)
	(segment
		(start 313.699906 -0.821182)
		(end 313.699906 0.444754)
		(width 0.4064)
		(layer "F.Cu")
		(net "GND")
	)
	(segment
		(start 352.502724 0.84328)
		(end 352.424238 0.764794)
		(width 0.254)
		(layer "F.Cu")
		(net "GND")
	)
	(segment
		(start 464.5533 -53.2384)
		(end 464.549998 -53.235098)
		(width 0.4064)
		(layer "F.Cu")
		(net "GND")
	)
	(segment
		(start 138.499342 -15.423642)
		(end 138.499342 -16.238474)
		(width 0.4064)
		(layer "F.Cu")
		(net "GND")
	)
	(segment
		(start 136.74217 -155.612846)
		(end 136.74217 -155.600146)
		(width 0.3556)
		(layer "F.Cu")
		(net "GND")
	)
	(segment
		(start 415.163 -106.299)
		(end 415.22523 -106.23677)
		(width 0.254)
		(layer "F.Cu")
		(net "GND")
	)
	(segment
		(start 241.334798 -55.59044)
		(end 240.763298 -55.59044)
		(width 0.254)
		(layer "F.Cu")
		(net "GND")
	)
	(segment
		(start 415.490152 -36.534598)
		(end 415.890202 -36.134548)
		(width 0.254)
		(layer "F.Cu")
		(net "GND")
	)
	(segment
		(start 0.567436 -135.339836)
		(end 0.567436 -135.789162)
		(width 0.254)
		(layer "F.Cu")
		(net "GND")
	)
	(segment
		(start 347.942154 -155.993846)
		(end 347.942154 -155.613862)
		(width 0.254)
		(layer "F.Cu")
		(net "GND")
	)
	(segment
		(start 398.126458 -40.404542)
		(end 399.043144 -40.404542)
		(width 0.254)
		(layer "F.Cu")
		(net "GND")
	)
	(segment
		(start 441.119006 -41.219374)
		(end 441.119006 -40.5257)
		(width 0.3556)
		(layer "F.Cu")
		(net "GND")
	)
	(segment
		(start 282.354274 -51.446938)
		(end 282.354274 -50.375058)
		(width 0.2286)
		(layer "F.Cu")
		(net "GND")
	)
	(segment
		(start 287.350454 -137.67054)
		(end 287.349946 -137.67054)
		(width 0.4064)
		(layer "F.Cu")
		(net "GND")
	)
	(segment
		(start 134.523734 -78.193138)
		(end 135.095234 -78.193138)
		(width 0.254)
		(layer "F.Cu")
		(net "GND")
	)
	(segment
		(start 315.400436 -137.67054)
		(end 315.399928 -137.67054)
		(width 0.4064)
		(layer "F.Cu")
		(net "GND")
	)
	(segment
		(start 42.424096 -18.757646)
		(end 42.449496 -18.783046)
		(width 0.4064)
		(layer "F.Cu")
		(net "GND")
	)
	(segment
		(start 299.249846 -153.965402)
		(end 299.151802 -154.063446)
		(width 0.4064)
		(layer "F.Cu")
		(net "GND")
	)
	(segment
		(start 75.475846 -80.850486)
		(end 74.904346 -80.850486)
		(width 0.254)
		(layer "F.Cu")
		(net "GND")
	)
	(segment
		(start 227.849938 -10.422382)
		(end 227.849938 -9.21385)
		(width 0.3556)
		(layer "F.Cu")
		(net "GND")
	)
	(segment
		(start 220.199712 -5.822696)
		(end 220.199712 -6.637274)
		(width 0.4064)
		(layer "F.Cu")
		(net "GND")
	)
	(segment
		(start 239.617758 -86.29904)
		(end 239.046258 -86.29904)
		(width 0.254)
		(layer "F.Cu")
		(net "GND")
	)
	(segment
		(start 243.149882 -0.821182)
		(end 243.149882 0.468122)
		(width 0.4064)
		(layer "F.Cu")
		(net "GND")
	)
	(segment
		(start 379.81255 -108.99648)
		(end 380.151386 -108.839)
		(width 0.254)
		(layer "F.Cu")
		(net "GND")
	)
	(segment
		(start 78.051406 -67.47764)
		(end 77.479906 -67.47764)
		(width 0.254)
		(layer "F.Cu")
		(net "GND")
	)
	(segment
		(start 261.1628 -139.2174)
		(end 260.731 -138.7856)
		(width 0.4064)
		(layer "F.Cu")
		(net "GND")
	)
	(segment
		(start 353.6188 -99.949)
		(end 353.8728 -99.695)
		(width 0.254)
		(layer "F.Cu")
		(net "GND")
	)
	(segment
		(start 353.6188 -100.29063)
		(end 353.6188 -99.949)
		(width 0.254)
		(layer "F.Cu")
		(net "GND")
	)
	(segment
		(start 202.35037 -20.023582)
		(end 202.349862 -20.023582)
		(width 0.4064)
		(layer "F.Cu")
		(net "GND")
	)
	(segment
		(start 147.849336 2.963926)
		(end 147.390866 2.505456)
		(width 0.4064)
		(layer "F.Cu")
		(net "GND")
	)
	(segment
		(start 128.514348 -89.584784)
		(end 129.085848 -89.584784)
		(width 0.254)
		(layer "F.Cu")
		(net "GND")
	)
	(segment
		(start 391.73785 -110.25505)
		(end 392.1379 -110.6551)
		(width 0.12446)
		(layer "F.Cu")
		(net "GND")
	)
	(segment
		(start 272.027904 -3.3528)
		(end 270.956532 -3.3528)
		(width 0.381)
		(layer "F.Cu")
		(net "GND")
	)
	(segment
		(start 135.099552 -0.821182)
		(end 135.099552 -2.276856)
		(width 0.4064)
		(layer "F.Cu")
		(net "GND")
	)
	(segment
		(start 125.938788 -89.089738)
		(end 126.510288 -89.089738)
		(width 0.254)
		(layer "F.Cu")
		(net "GND")
	)
	(segment
		(start 398.69872 -124.70638)
		(end 398.485106 -124.919994)
		(width 0.254)
		(layer "F.Cu")
		(net "GND")
	)
	(segment
		(start 48.399446 -21.517356)
		(end 48.399446 -20.023582)
		(width 0.4064)
		(layer "F.Cu")
		(net "GND")
	)
	(segment
		(start 16.1544 -41.5036)
		(end 9.093454 -41.5036)
		(width 0.254)
		(layer "F.Cu")
		(net "GND")
	)
	(segment
		(start 231.25049 -5.822442)
		(end 231.25049 -3.763518)
		(width 0.4064)
		(layer "F.Cu")
		(net "GND")
	)
	(segment
		(start 226.150424 -0.821182)
		(end 226.149916 -0.821182)
		(width 0.4064)
		(layer "F.Cu")
		(net "GND")
	)
	(segment
		(start 125.938788 -93.052138)
		(end 126.510288 -93.052138)
		(width 0.3048)
		(layer "F.Cu")
		(net "GND")
	)
	(segment
		(start 75.475846 -84.812886)
		(end 74.904346 -84.812886)
		(width 0.254)
		(layer "F.Cu")
		(net "GND")
	)
	(segment
		(start 152.1206 -130.3528)
		(end 152.1206 -129.60096)
		(width 0.4064)
		(layer "F.Cu")
		(net "GND")
	)
	(segment
		(start 148.699474 -2.314956)
		(end 148.699474 -0.821182)
		(width 0.4064)
		(layer "F.Cu")
		(net "GND")
	)
	(segment
		(start 281.399996 -0.821182)
		(end 281.399996 0.444754)
		(width 0.4064)
		(layer "F.Cu")
		(net "GND")
	)
	(segment
		(start 4.9276 -6.335776)
		(end 4.818888 -6.335776)
		(width 0.254)
		(layer "F.Cu")
		(net "GND")
	)
	(segment
		(start 434.813202 -3.372104)
		(end 434.875686 -3.434588)
		(width 0.254)
		(layer "F.Cu")
		(net "GND")
	)
	(segment
		(start 480.2505 -143.51)
		(end 479.933 -143.51)
		(width 0.254)
		(layer "F.Cu")
		(net "GND")
	)
	(segment
		(start 133.665214 -54.913784)
		(end 134.236714 -54.913784)
		(width 0.254)
		(layer "F.Cu")
		(net "GND")
	)
	(segment
		(start -0.254 -143.256)
		(end -0.254 -143.7132)
		(width 0.4064)
		(layer "F.Cu")
		(net "GND")
	)
	(segment
		(start 279.778714 -65.810384)
		(end 279.207214 -65.810384)
		(width 0.254)
		(layer "F.Cu")
		(net "GND")
	)
	(segment
		(start 294.150288 -142.6718)
		(end 294.14978 -142.677642)
		(width 0.4064)
		(layer "F.Cu")
		(net "GND")
	)
	(segment
		(start 198.100442 -10.422382)
		(end 198.099934 -10.422382)
		(width 0.4064)
		(layer "F.Cu")
		(net "GND")
	)
	(segment
		(start 77.961744 -148.64842)
		(end 78.14945 -148.460714)
		(width 0.508)
		(layer "F.Cu")
		(net "GND")
	)
	(segment
		(start 122.217688 -99.490784)
		(end 121.646188 -99.490784)
		(width 0.254)
		(layer "F.Cu")
		(net "GND")
	)
	(segment
		(start 377.081542 -126.192026)
		(end 377.081542 -126.55169)
		(width 0.254)
		(layer "F.Cu")
		(net "GND")
	)
	(segment
		(start 196.399912 -137.67054)
		(end 196.399912 -136.397746)
		(width 0.4064)
		(layer "F.Cu")
		(net "GND")
	)
	(segment
		(start 182.372 -57.6834)
		(end 182.4482 -57.7596)
		(width 0.381)
		(layer "F.Cu")
		(net "GND")
	)
	(segment
		(start 465.6074 2.8194)
		(end 466.311996 2.8194)
		(width 0.381)
		(layer "F.Cu")
		(net "GND")
	)
	(segment
		(start 116.495322 -52.932838)
		(end 116.495322 -51.941984)
		(width 0.2286)
		(layer "F.Cu")
		(net "GND")
	)
	(segment
		(start 74.617326 -96.20504)
		(end 74.045826 -96.20504)
		(width 0.254)
		(layer "F.Cu")
		(net "GND")
	)
	(segment
		(start 198.099934 -148.733256)
		(end 198.099934 -147.27174)
		(width 0.4064)
		(layer "F.Cu")
		(net "GND")
	)
	(segment
		(start 307.041042 -81.164938)
		(end 307.041804 -81.164176)
		(width 0.254)
		(layer "F.Cu")
		(net "GND")
	)
	(segment
		(start 34.74212 -9.369298)
		(end 34.74212 -9.143746)
		(width 0.4064)
		(layer "F.Cu")
		(net "GND")
	)
	(segment
		(start 140.533374 -75.716384)
		(end 141.181074 -75.716384)
		(width 0.254)
		(layer "F.Cu")
		(net "GND")
	)
	(segment
		(start 52.649374 -133.0706)
		(end 52.649374 -133.809994)
		(width 0.3048)
		(layer "F.Cu")
		(net "GND")
	)
	(segment
		(start 129.149348 -133.891274)
		(end 128.690878 -134.349744)
		(width 0.4064)
		(layer "F.Cu")
		(net "GND")
	)
	(segment
		(start 232.950512 -152.273)
		(end 232.950004 -152.278842)
		(width 0.4064)
		(layer "F.Cu")
		(net "GND")
	)
	(segment
		(start 316.249812 -5.822442)
		(end 316.249812 -7.607046)
		(width 0.4064)
		(layer "F.Cu")
		(net "GND")
	)
	(segment
		(start 14.972792 5.158232)
		(end 15.057374 5.242814)
		(width 0.381)
		(layer "F.Cu")
		(net "GND")
	)
	(segment
		(start 229.54996 -5.822442)
		(end 229.54996 -4.808982)
		(width 0.4064)
		(layer "F.Cu")
		(net "GND")
	)
	(segment
		(start 2.3114 -5.9944)
		(end 2.6924 -6.3754)
		(width 0.4064)
		(layer "F.Cu")
		(net "GND")
	)
	(segment
		(start 157.099 -140.0048)
		(end 157.099 -141.073632)
		(width 0.4064)
		(layer "F.Cu")
		(net "GND")
	)
	(segment
		(start 384.705352 -23.0124)
		(end 384.0226 -23.0124)
		(width 0.254)
		(layer "F.Cu")
		(net "GND")
	)
	(segment
		(start 476.1611 -40.3479)
		(end 475.618302 -39.805102)
		(width 0.254)
		(layer "F.Cu")
		(net "GND")
	)
	(segment
		(start 122.349514 -147.27174)
		(end 122.349514 -146.011646)
		(width 0.4064)
		(layer "F.Cu")
		(net "GND")
	)
	(segment
		(start 442.976 -50.542952)
		(end 442.940948 -50.578004)
		(width 0.4064)
		(layer "F.Cu")
		(net "GND")
	)
	(segment
		(start 291.79774 -93.547184)
		(end 292.36924 -93.547184)
		(width 0.3048)
		(layer "F.Cu")
		(net "GND")
	)
	(segment
		(start 308.393338 -56.399938)
		(end 308.7878 -56.7944)
		(width 0.254)
		(layer "F.Cu")
		(net "GND")
	)
	(segment
		(start 322.0212 -150.289768)
		(end 321.591432 -149.86)
		(width 0.508)
		(layer "F.Cu")
		(net "GND")
	)
	(segment
		(start 306.899818 -15.423642)
		(end 306.899818 -13.363956)
		(width 0.4064)
		(layer "F.Cu")
		(net "GND")
	)
	(segment
		(start 49.249584 -3.76301)
		(end 49.24933 -3.762756)
		(width 0.4064)
		(layer "F.Cu")
		(net "GND")
	)
	(segment
		(start 238.759238 -87.784686)
		(end 238.187738 -87.784686)
		(width 0.254)
		(layer "F.Cu")
		(net "GND")
	)
	(segment
		(start 102.7938 -3.3528)
		(end 103.678736 -3.3528)
		(width 0.508)
		(layer "F.Cu")
		(net "GND")
	)
	(segment
		(start 393.68095 -123.821444)
		(end 393.18565 -123.59132)
		(width 0.254)
		(layer "F.Cu")
		(net "GND")
	)
	(segment
		(start 232.749598 -67.47764)
		(end 232.101898 -67.47764)
		(width 0.254)
		(layer "F.Cu")
		(net "GND")
	)
	(segment
		(start 252.495304 -67.972686)
		(end 251.923804 -67.972686)
		(width 0.254)
		(layer "F.Cu")
		(net "GND")
	)
	(segment
		(start 123.199398 -15.423642)
		(end 123.199398 -13.363956)
		(width 0.4064)
		(layer "F.Cu")
		(net "GND")
	)
	(segment
		(start 135.382254 -83.641184)
		(end 135.953754 -83.641184)
		(width 0.254)
		(layer "F.Cu")
		(net "GND")
	)
	(segment
		(start 434.799232 -13.60805)
		(end 435.2417 -14.050518)
		(width 0.254)
		(layer "F.Cu")
		(net "GND")
	)
	(segment
		(start 393.684506 -105.5624)
		(end 393.68095 -105.5624)
		(width 0.1397)
		(layer "F.Cu")
		(net "GND")
	)
	(segment
		(start 245.627144 -54.104286)
		(end 245.055644 -54.104286)
		(width 0.254)
		(layer "F.Cu")
		(net "GND")
	)
	(segment
		(start 144.449546 -18.757646)
		(end 144.449546 -20.023582)
		(width 0.4064)
		(layer "F.Cu")
		(net "GND")
	)
	(segment
		(start 281.495754 -67.791584)
		(end 281.320494 -67.966844)
		(width 0.254)
		(layer "F.Cu")
		(net "GND")
	)
	(segment
		(start 233.608118 -91.747086)
		(end 232.960418 -91.747086)
		(width 0.254)
		(layer "F.Cu")
		(net "GND")
	)
	(segment
		(start 294.3733 -85.127338)
		(end 294.9448 -85.127338)
		(width 0.254)
		(layer "F.Cu")
		(net "GND")
	)
	(segment
		(start 114.220752 -53.8988)
		(end 114.206782 -53.923184)
		(width 0.254)
		(layer "F.Cu")
		(net "GND")
	)
	(segment
		(start 119.327168 -2.3622)
		(end 120.649492 -2.314956)
		(width 0.254)
		(layer "F.Cu")
		(net "GND")
	)
	(segment
		(start 113.348516 -52.4383)
		(end 113.062512 -52.932584)
		(width 0.254)
		(layer "F.Cu")
		(net "GND")
	)
	(segment
		(start 372.745254 -94.107)
		(end 374.20677 -95.568516)
		(width 0.254)
		(layer "F.Cu")
		(net "GND")
	)
	(segment
		(start 286.768286 -101.261164)
		(end 286.64662 -101.471984)
		(width 0.254)
		(layer "F.Cu")
		(net "GND")
	)
	(segment
		(start 376.460004 -110.9726)
		(end 376.335036 -110.854998)
		(width 0.254)
		(layer "F.Cu")
		(net "GND")
	)
	(segment
		(start 232.749598 -64.50584)
		(end 232.101898 -64.50584)
		(width 0.254)
		(layer "F.Cu")
		(net "GND")
	)
	(segment
		(start 152.949402 -152.273)
		(end 152.949402 -153.542746)
		(width 0.4064)
		(layer "F.Cu")
		(net "GND")
	)
	(segment
		(start 251.636784 -89.27084)
		(end 251.065284 -89.27084)
		(width 0.254)
		(layer "F.Cu")
		(net "GND")
	)
	(segment
		(start 349.5548 -101.3714)
		(end 349.5548 -100.914708)
		(width 0.381)
		(layer "F.Cu")
		(net "GND")
	)
	(segment
		(start 401.295108 -115.854988)
		(end 401.858988 -115.854988)
		(width 0.254)
		(layer "F.Cu")
		(net "GND")
	)
	(segment
		(start 96.079818 -87.784686)
		(end 95.508318 -87.784686)
		(width 0.254)
		(layer "F.Cu")
		(net "GND")
	)
	(segment
		(start 121.646188 -65.810384)
		(end 121.074688 -65.810384)
		(width 0.254)
		(layer "F.Cu")
		(net "GND")
	)
	(segment
		(start 50.949352 -15.423642)
		(end 50.949352 -13.427456)
		(width 0.4064)
		(layer "F.Cu")
		(net "GND")
	)
	(segment
		(start 243.149882 -145.988278)
		(end 243.149882 -147.27174)
		(width 0.4064)
		(layer "F.Cu")
		(net "GND")
	)
	(segment
		(start 298.40047 -147.27174)
		(end 298.399962 -147.27174)
		(width 0.4064)
		(layer "F.Cu")
		(net "GND")
	)
	(segment
		(start 413.490156 -36.134548)
		(end 413.890206 -36.534598)
		(width 0.254)
		(layer "F.Cu")
		(net "GND")
	)
	(segment
		(start 196.399912 -139.170156)
		(end 196.399912 -137.67054)
		(width 0.4064)
		(layer "F.Cu")
		(net "GND")
	)
	(segment
		(start 209.14995 -156.87294)
		(end 209.14995 -155.70835)
		(width 0.4064)
		(layer "F.Cu")
		(net "GND")
	)
	(segment
		(start 418.2618 -121.099326)
		(end 418.385244 -120.975882)
		(width 0.4064)
		(layer "F.Cu")
		(net "GND")
	)
	(segment
		(start 136.799574 -9.21385)
		(end 136.799574 -10.422382)
		(width 0.3556)
		(layer "F.Cu")
		(net "GND")
	)
	(segment
		(start 125.938788 -77.202538)
		(end 126.510288 -77.202538)
		(width 0.254)
		(layer "F.Cu")
		(net "GND")
	)
	(segment
		(start 121.646188 -61.847984)
		(end 121.074688 -61.847984)
		(width 0.254)
		(layer "F.Cu")
		(net "GND")
	)
	(segment
		(start 401.271486 -3.376422)
		(end 401.262342 -3.367278)
		(width 0.254)
		(layer "F.Cu")
		(net "GND")
	)
	(segment
		(start 71.349362 -15.423642)
		(end 71.349362 -16.151606)
		(width 0.3556)
		(layer "F.Cu")
		(net "GND")
	)
	(segment
		(start 317.09995 -9.156446)
		(end 317.09995 -10.422382)
		(width 0.4064)
		(layer "F.Cu")
		(net "GND")
	)
	(segment
		(start 448.540886 -51.875944)
		(end 448.534028 -51.869086)
		(width 0.508)
		(layer "F.Cu")
		(net "GND")
	)
	(segment
		(start 283.099764 -18.81505)
		(end 283.099764 -20.023582)
		(width 0.3556)
		(layer "F.Cu")
		(net "GND")
	)
	(segment
		(start 137.099294 -74.725784)
		(end 137.670794 -74.725784)
		(width 0.254)
		(layer "F.Cu")
		(net "GND")
	)
	(segment
		(start 112.202722 -51.446938)
		(end 112.202722 -50.759614)
		(width 0.254)
		(layer "F.Cu")
		(net "GND")
	)
	(segment
		(start 84.060792 -71.935086)
		(end 83.489292 -71.935086)
		(width 0.254)
		(layer "F.Cu")
		(net "GND")
	)
	(segment
		(start 232.100374 -137.67054)
		(end 232.099866 -137.67054)
		(width 0.4064)
		(layer "F.Cu")
		(net "GND")
	)
	(segment
		(start 67.949318 -152.279096)
		(end 67.949318 -154.063446)
		(width 0.4064)
		(layer "F.Cu")
		(net "GND")
	)
	(segment
		(start 240.599976 3.599688)
		(end 240.599722 3.599434)
		(width 0.4064)
		(layer "F.Cu")
		(net "GND")
	)
	(segment
		(start 377.361958 -106.408728)
		(end 377.83135 -106.190796)
		(width 0.254)
		(layer "F.Cu")
		(net "GND")
	)
	(segment
		(start 299.151802 -7.607046)
		(end 299.249846 -7.509002)
		(width 0.4064)
		(layer "F.Cu")
		(net "GND")
	)
	(segment
		(start 435.5338 -14.859)
		(end 435.5338 -14.5161)
		(width 0.254)
		(layer "F.Cu")
		(net "GND")
	)
	(segment
		(start 72.041766 -90.756486)
		(end 71.470266 -90.756486)
		(width 0.254)
		(layer "F.Cu")
		(net "GND")
	)
	(segment
		(start 198.950326 -142.6718)
		(end 198.949818 -142.677642)
		(width 0.3556)
		(layer "F.Cu")
		(net "GND")
	)
	(segment
		(start 476.6691 -142.8242)
		(end 476.6691 -142.5067)
		(width 0.254)
		(layer "F.Cu")
		(net "GND")
	)
	(segment
		(start 347.605096 -13.966952)
		(end 347.1291 -13.966952)
		(width 0.2032)
		(layer "F.Cu")
		(net "GND")
	)
	(segment
		(start 454.877678 -8.824722)
		(end 454.8378 -8.8646)
		(width 0.254)
		(layer "F.Cu")
		(net "GND")
	)
	(segment
		(start 81.485232 -74.411586)
		(end 80.913732 -74.411586)
		(width 0.254)
		(layer "F.Cu")
		(net "GND")
	)
	(segment
		(start 123.363228 -91.565984)
		(end 123.934728 -91.565984)
		(width 0.3048)
		(layer "F.Cu")
		(net "GND")
	)
	(segment
		(start 70.324726 -89.765886)
		(end 69.753226 -89.765886)
		(width 0.254)
		(layer "F.Cu")
		(net "GND")
	)
	(segment
		(start 258.50469 -91.25204)
		(end 257.93319 -91.25204)
		(width 0.254)
		(layer "F.Cu")
		(net "GND")
	)
	(segment
		(start 386.644388 -108.947712)
		(end 386.93725 -108.65485)
		(width 0.12446)
		(layer "F.Cu")
		(net "GND")
	)
	(segment
		(start 218.44254 0.444754)
		(end 218.44254 0.457454)
		(width 0.3556)
		(layer "F.Cu")
		(net "GND")
	)
	(segment
		(start 76.334366 -101.15804)
		(end 75.762866 -101.15804)
		(width 0.254)
		(layer "F.Cu")
		(net "GND")
	)
	(segment
		(start 56.049418 -137.67054)
		(end 56.049418 -136.410446)
		(width 0.4064)
		(layer "F.Cu")
		(net "GND")
	)
	(segment
		(start 384.27025 -101.2698)
		(end 384.76555 -101.039676)
		(width 0.254)
		(layer "F.Cu")
		(net "GND")
	)
	(segment
		(start 306.392326 -94.042738)
		(end 307.141626 -94.042738)
		(width 0.254)
		(layer "F.Cu")
		(net "GND")
	)
	(segment
		(start 233.800396 -147.27174)
		(end 233.799888 -147.27174)
		(width 0.4064)
		(layer "F.Cu")
		(net "GND")
	)
	(segment
		(start 401.295108 -95.978472)
		(end 401.35302 -95.92056)
		(width 0.254)
		(layer "F.Cu")
		(net "GND")
	)
	(segment
		(start 381.309626 -105.815384)
		(end 380.80315 -105.5624)
		(width 0.254)
		(layer "F.Cu")
		(net "GND")
	)
	(segment
		(start 443.000892 -116.993162)
		(end 443.000892 -118.615714)
		(width 0.4064)
		(layer "F.Cu")
		(net "GND")
	)
	(segment
		(start 147.849336 -143.492474)
		(end 147.390866 -143.950944)
		(width 0.4064)
		(layer "F.Cu")
		(net "GND")
	)
	(segment
		(start 284.929834 -68.782184)
		(end 285.425388 -69.277738)
		(width 0.254)
		(layer "F.Cu")
		(net "GND")
	)
	(segment
		(start 88.353392 -86.29904)
		(end 87.781892 -86.29904)
		(width 0.254)
		(layer "F.Cu")
		(net "GND")
	)
	(segment
		(start 237.042198 -90.756486)
		(end 236.470698 -90.756486)
		(width 0.254)
		(layer "F.Cu")
		(net "GND")
	)
	(segment
		(start 214.250016 -142.677642)
		(end 214.249762 -142.677896)
		(width 0.4064)
		(layer "F.Cu")
		(net "GND")
	)
	(segment
		(start 455.40549 -34.0614)
		(end 455.779632 -33.687258)
		(width 0.254)
		(layer "F.Cu")
		(net "GND")
	)
	(segment
		(start 234.466638 -67.47764)
		(end 233.895138 -67.47764)
		(width 0.254)
		(layer "F.Cu")
		(net "GND")
	)
	(segment
		(start 221.900496 -152.273)
		(end 221.899988 -152.278842)
		(width 0.4064)
		(layer "F.Cu")
		(net "GND")
	)
	(segment
		(start 174.63008 -65.42278)
		(end 174.63008 -64.64046)
		(width 0.4064)
		(layer "F.Cu")
		(net "GND")
	)
	(segment
		(start 129.999486 -137.67054)
		(end 129.999486 -136.410446)
		(width 0.4064)
		(layer "F.Cu")
		(net "GND")
	)
	(segment
		(start 283.04236 -2.310892)
		(end 283.099764 -2.253488)
		(width 0.4064)
		(layer "F.Cu")
		(net "GND")
	)
	(segment
		(start 246.5832 -3.3528)
		(end 247.4595 -3.3528)
		(width 0.4064)
		(layer "F.Cu")
		(net "GND")
	)
	(segment
		(start 5.1054 -6.157976)
		(end 4.9276 -6.335776)
		(width 0.4064)
		(layer "F.Cu")
		(net "GND")
	)
	(segment
		(start 491.871 -38.227)
		(end 491.998 -38.1)
		(width 0.254)
		(layer "F.Cu")
		(net "GND")
	)
	(segment
		(start 478.30486 -17.59839)
		(end 479.19386 -17.59839)
		(width 0.254)
		(layer "F.Cu")
		(net "GND")
	)
	(segment
		(start 443.322456 -30.6324)
		(end 442.922406 -31.03245)
		(width 0.3048)
		(layer "F.Cu")
		(net "GND")
	)
	(segment
		(start 56.899556 -15.423642)
		(end 56.899556 -15.602712)
		(width 0.4064)
		(layer "F.Cu")
		(net "GND")
	)
	(segment
		(start 168.672764 -76.064364)
		(end 168.4528 -75.8444)
		(width 0.254)
		(layer "F.Cu")
		(net "GND")
	)
	(segment
		(start 107.623102 -100.976684)
		(end 107.051856 -100.976684)
		(width 0.254)
		(layer "F.Cu")
		(net "GND")
	)
	(segment
		(start 465.680552 -45.593)
		(end 465.680552 -46.009052)
		(width 0.4064)
		(layer "F.Cu")
		(net "GND")
	)
	(segment
		(start 96.938338 -63.51524)
		(end 96.366838 -63.51524)
		(width 0.254)
		(layer "F.Cu")
		(net "GND")
	)
	(segment
		(start 139.674854 -89.089738)
		(end 140.246354 -89.089738)
		(width 0.254)
		(layer "F.Cu")
		(net "GND")
	)
	(segment
		(start 116.495322 -99.490784)
		(end 117.066822 -99.490784)
		(width 0.254)
		(layer "F.Cu")
		(net "GND")
	)
	(segment
		(start 442.142118 -51.875944)
		(end 442.141102 -51.875944)
		(width 0.4064)
		(layer "F.Cu")
		(net "GND")
	)
	(segment
		(start 130.84937 -133.0706)
		(end 130.84937 -134.861046)
		(width 0.4064)
		(layer "F.Cu")
		(net "GND")
	)
	(segment
		(start 209.092546 -18.744946)
		(end 209.092546 -18.795746)
		(width 0.4064)
		(layer "F.Cu")
		(net "GND")
	)
	(segment
		(start 239.617758 -74.411586)
		(end 239.046258 -74.411586)
		(width 0.254)
		(layer "F.Cu")
		(net "GND")
	)
	(segment
		(start 311.15 -137.67054)
		(end 311.15 -136.46785)
		(width 0.3556)
		(layer "F.Cu")
		(net "GND")
	)
	(segment
		(start 287.21812 -91.565984)
		(end 286.64662 -91.565984)
		(width 0.1651)
		(layer "F.Cu")
		(net "GND")
	)
	(segment
		(start 303.529746 -81.164938)
		(end 302.958246 -81.164938)
		(width 0.254)
		(layer "F.Cu")
		(net "GND")
	)
	(segment
		(start 129.372868 -85.127338)
		(end 129.944368 -85.127338)
		(width 0.254)
		(layer "F.Cu")
		(net "GND")
	)
	(segment
		(start 203.2 -13.36421)
		(end 203.199746 -13.363956)
		(width 0.4064)
		(layer "F.Cu")
		(net "GND")
	)
	(segment
		(start 86.636352 -90.26144)
		(end 86.064852 -90.26144)
		(width 0.254)
		(layer "F.Cu")
		(net "GND")
	)
	(segment
		(start 288.200338 -142.6718)
		(end 288.19983 -142.677642)
		(width 0.4064)
		(layer "F.Cu")
		(net "GND")
	)
	(segment
		(start 195.904612 -77.620368)
		(end 195.904612 -78.211172)
		(width 0.508)
		(layer "F.Cu")
		(net "GND")
	)
	(segment
		(start 207.449928 -147.27174)
		(end 207.449928 -146.037046)
		(width 0.4064)
		(layer "F.Cu")
		(net "GND")
	)
	(segment
		(start 283.0322 -13.8938)
		(end 284.33776 -13.948156)
		(width 0.254)
		(layer "F.Cu")
		(net "GND")
	)
	(segment
		(start 315.400436 -10.422382)
		(end 315.399928 -10.422382)
		(width 0.4064)
		(layer "F.Cu")
		(net "GND")
	)
	(segment
		(start 314.54979 -15.423642)
		(end 314.54979 -13.363956)
		(width 0.4064)
		(layer "F.Cu")
		(net "GND")
	)
	(segment
		(start 397.14805 -121.87428)
		(end 397.470376 -122.02414)
		(width 0.254)
		(layer "F.Cu")
		(net "GND")
	)
	(segment
		(start 73.899268 -5.822696)
		(end 73.899268 -6.637274)
		(width 0.4064)
		(layer "F.Cu")
		(net "GND")
	)
	(segment
		(start 242.193318 -61.038486)
		(end 241.621818 -61.038486)
		(width 0.254)
		(layer "F.Cu")
		(net "GND")
	)
	(segment
		(start 84.919312 -92.24264)
		(end 84.347812 -92.24264)
		(width 0.254)
		(layer "F.Cu")
		(net "GND")
	)
	(segment
		(start 123.363228 -61.847984)
		(end 122.791728 -61.847984)
		(width 0.254)
		(layer "F.Cu")
		(net "GND")
	)
	(segment
		(start 302.958246 -53.427884)
		(end 303.529746 -53.427884)
		(width 0.254)
		(layer "F.Cu")
		(net "GND")
	)
	(segment
		(start 221.899988 -15.423642)
		(end 221.899988 -13.36421)
		(width 0.4064)
		(layer "F.Cu")
		(net "GND")
	)
	(segment
		(start 414.807654 -68.249546)
		(end 412.448248 -68.249546)
		(width 0.508)
		(layer "F.Cu")
		(net "GND")
	)
	(segment
		(start 232.950512 -7.606284)
		(end 232.94975 -7.607046)
		(width 0.4064)
		(layer "F.Cu")
		(net "GND")
	)
	(segment
		(start 75.59929 -3.762756)
		(end 75.59929 -5.822188)
		(width 0.4064)
		(layer "F.Cu")
		(net "GND")
	)
	(segment
		(start 416.406076 -128.980692)
		(end 416.406076 -129.290572)
		(width 0.381)
		(layer "F.Cu")
		(net "GND")
	)
	(segment
		(start 423.09034 -37.734748)
		(end 423.490136 -38.134544)
		(width 0.254)
		(layer "F.Cu")
		(net "GND")
	)
	(segment
		(start 61.999368 -133.0706)
		(end 61.999368 -133.807454)
		(width 0.3556)
		(layer "F.Cu")
		(net "GND")
	)
	(segment
		(start 231.25049 -13.364718)
		(end 231.249728 -13.363956)
		(width 0.4064)
		(layer "F.Cu")
		(net "GND")
	)
	(segment
		(start 201.031856 -2.3114)
		(end 202.346306 -2.3114)
		(width 0.254)
		(layer "F.Cu")
		(net "GND")
	)
	(segment
		(start 278.849836 -14.13002)
		(end 279.039574 -13.940282)
		(width 0.4064)
		(layer "F.Cu")
		(net "GND")
	)
	(segment
		(start 137.670794 -93.547184)
		(end 137.099294 -93.547184)
		(width 0.254)
		(layer "F.Cu")
		(net "GND")
	)
	(segment
		(start 161.192464 -66.675)
		(end 161.7472 -66.675)
		(width 0.254)
		(layer "F.Cu")
		(net "GND")
	)
	(segment
		(start 125.651768 -68.782184)
		(end 125.080268 -68.782184)
		(width 0.254)
		(layer "F.Cu")
		(net "GND")
	)
	(segment
		(start 296.700448 -0.821182)
		(end 296.69994 -0.821182)
		(width 0.4064)
		(layer "F.Cu")
		(net "GND")
	)
	(segment
		(start 387.308852 -124.210826)
		(end 387.314186 -124.206)
		(width 0.254)
		(layer "F.Cu")
		(net "GND")
	)
	(segment
		(start 310.0832 -17.207738)
		(end 310.0832 -16.3576)
		(width 0.3556)
		(layer "F.Cu")
		(net "GND")
	)
	(segment
		(start 221.899988 -152.278842)
		(end 221.899988 -152.457912)
		(width 0.4064)
		(layer "F.Cu")
		(net "GND")
	)
	(segment
		(start 303.816766 -72.744584)
		(end 304.388266 -72.744584)
		(width 0.254)
		(layer "F.Cu")
		(net "GND")
	)
	(segment
		(start 217.649806 -6.555994)
		(end 217.649806 -5.822442)
		(width 0.3048)
		(layer "F.Cu")
		(net "GND")
	)
	(segment
		(start 130.231388 -85.622384)
		(end 130.802888 -85.622384)
		(width 0.254)
		(layer "F.Cu")
		(net "GND")
	)
	(segment
		(start 137.957814 -81.164938)
		(end 138.529314 -81.164938)
		(width 0.254)
		(layer "F.Cu")
		(net "GND")
	)
	(segment
		(start 72.1995 0.38735)
		(end 72.142096 0.444754)
		(width 0.3556)
		(layer "F.Cu")
		(net "GND")
	)
	(segment
		(start 376.428 -104.354884)
		(end 375.92 -104.354884)
		(width 0.254)
		(layer "F.Cu")
		(net "GND")
	)
	(segment
		(start 314.54979 -133.076442)
		(end 314.54979 -134.861046)
		(width 0.4064)
		(layer "F.Cu")
		(net "GND")
	)
	(segment
		(start 109.069632 -53.8988)
		(end 109.055662 -53.923184)
		(width 0.254)
		(layer "F.Cu")
		(net "GND")
	)
	(segment
		(start 451.401688 -45.560996)
		(end 450.940932 -46.021752)
		(width 0.4064)
		(layer "F.Cu")
		(net "GND")
	)
	(segment
		(start 100.372164 -91.25204)
		(end 99.800664 -91.25204)
		(width 0.254)
		(layer "F.Cu")
		(net "GND")
	)
	(segment
		(start 64.549274 -142.677896)
		(end 64.549274 -143.492474)
		(width 0.4064)
		(layer "F.Cu")
		(net "GND")
	)
	(segment
		(start 198.755 1.972818)
		(end 198.772018 1.9558)
		(width 0.3556)
		(layer "F.Cu")
		(net "GND")
	)
	(segment
		(start 214.249762 -152.279096)
		(end 214.249762 -154.063446)
		(width 0.4064)
		(layer "F.Cu")
		(net "GND")
	)
	(segment
		(start 26.416 -61.722)
		(end 26.416 -61.58992)
		(width 0.508)
		(layer "F.Cu")
		(net "GND")
	)
	(segment
		(start 385.33705 -112.65535)
		(end 384.937 -113.0554)
		(width 0.12446)
		(layer "F.Cu")
		(net "GND")
	)
	(segment
		(start 317.09995 -0.821182)
		(end 317.09995 -2.325878)
		(width 0.4064)
		(layer "F.Cu")
		(net "GND")
	)
	(segment
		(start 145.29943 -133.793738)
		(end 145.082768 -134.0104)
		(width 0.3556)
		(layer "F.Cu")
		(net "GND")
	)
	(segment
		(start 226.9998 -133.807454)
		(end 226.7966 -134.010654)
		(width 0.3556)
		(layer "F.Cu")
		(net "GND")
	)
	(segment
		(start 48.399446 -137.67054)
		(end 48.399446 -136.410446)
		(width 0.4064)
		(layer "F.Cu")
		(net "GND")
	)
	(segment
		(start 476.179134 -43.7134)
		(end 476.4786 -43.413934)
		(width 0.254)
		(layer "F.Cu")
		(net "GND")
	)
	(segment
		(start 199.736456 -141.1478)
		(end 200.983596 -141.1478)
		(width 0.254)
		(layer "F.Cu")
		(net "GND")
	)
	(segment
		(start 235.49991 -155.650946)
		(end 235.49991 -156.87294)
		(width 0.4064)
		(layer "F.Cu")
		(net "GND")
	)
	(segment
		(start 67.749166 -86.29904)
		(end 67.101466 -86.29904)
		(width 0.254)
		(layer "F.Cu")
		(net "GND")
	)
	(segment
		(start 184.4675 -5.9817)
		(end 184.531 -5.9182)
		(width 0.4064)
		(layer "F.Cu")
		(net "GND")
	)
	(segment
		(start 199.799956 -11.854688)
		(end 199.742552 -11.912092)
		(width 0.4064)
		(layer "F.Cu")
		(net "GND")
	)
	(segment
		(start 388.594346 -7.50697)
		(end 390.54532 -7.50697)
		(width 0.254)
		(layer "F.Cu")
		(net "GND")
	)
	(segment
		(start 299.524166 -66.305938)
		(end 300.095666 -66.305938)
		(width 0.254)
		(layer "F.Cu")
		(net "GND")
	)
	(segment
		(start 376.428 -122.355102)
		(end 376.42292 -122.38228)
		(width 0.254)
		(layer "F.Cu")
		(net "GND")
	)
	(segment
		(start 171.8818 -4.174998)
		(end 170.446192 -4.174998)
		(width 0.3048)
		(layer "F.Cu")
		(net "GND")
	)
	(segment
		(start 126.599442 -6.545326)
		(end 126.388368 -6.7564)
		(width 0.3556)
		(layer "F.Cu")
		(net "GND")
	)
	(segment
		(start 61.796168 -154.0764)
		(end 61.821568 -154.1018)
		(width 0.3556)
		(layer "F.Cu")
		(net "GND")
	)
	(segment
		(start 214.250524 -7.606284)
		(end 214.249762 -7.607046)
		(width 0.4064)
		(layer "F.Cu")
		(net "GND")
	)
	(segment
		(start 235.46181 -155.612846)
		(end 235.49991 -155.650946)
		(width 0.4064)
		(layer "F.Cu")
		(net "GND")
	)
	(segment
		(start 194.39382 -52.59578)
		(end 193.6242 -53.3654)
		(width 0.4064)
		(layer "F.Cu")
		(net "GND")
	)
	(segment
		(start 383.73685 -115.05565)
		(end 384.1369 -114.6556)
		(width 0.12446)
		(layer "F.Cu")
		(net "GND")
	)
	(segment
		(start 197.095364 -54.248558)
		(end 196.743828 -53.897022)
		(width 0.254)
		(layer "F.Cu")
		(net "GND")
	)
	(segment
		(start 501.2563 -128.44018)
		(end 500.507 -127.69088)
		(width 0.508)
		(layer "F.Cu")
		(net "GND")
	)
	(segment
		(start 461.400906 -112.205516)
		(end 461.400906 -113.867184)
		(width 0.4064)
		(layer "F.Cu")
		(net "GND")
	)
	(segment
		(start 384.53695 -112.65535)
		(end 384.937 -113.0554)
		(width 0.12446)
		(layer "F.Cu")
		(net "GND")
	)
	(segment
		(start 66.24955 -133.255512)
		(end 66.249296 -133.255766)
		(width 0.4064)
		(layer "F.Cu")
		(net "GND")
	)
	(segment
		(start 142.749524 -11.916156)
		(end 142.749524 -10.422382)
		(width 0.4064)
		(layer "F.Cu")
		(net "GND")
	)
	(segment
		(start 300.949868 -143.422878)
		(end 300.736 -143.636746)
		(width 0.3556)
		(layer "F.Cu")
		(net "GND")
	)
	(segment
		(start 464.521296 -141.646402)
		(end 464.44789 -141.719808)
		(width 0.254)
		(layer "F.Cu")
		(net "GND")
	)
	(segment
		(start 31.366968 -140.0556)
		(end 31.366968 -139.202668)
		(width 0.4064)
		(layer "F.Cu")
		(net "GND")
	)
	(segment
		(start 391.20445 -120.15724)
		(end 391.69975 -120.387364)
		(width 0.254)
		(layer "F.Cu")
		(net "GND")
	)
	(segment
		(start 72.900286 -84.31784)
		(end 72.328786 -84.31784)
		(width 0.254)
		(layer "F.Cu")
		(net "GND")
	)
	(segment
		(start 203.200508 -142.6718)
		(end 203.2 -142.677642)
		(width 0.4064)
		(layer "F.Cu")
		(net "GND")
	)
	(segment
		(start 438.088532 -7.802118)
		(end 438.076086 -7.789672)
		(width 0.254)
		(layer "F.Cu")
		(net "GND")
	)
	(segment
		(start 274.056348 -55.904384)
		(end 274.627848 -55.904384)
		(width 0.254)
		(layer "F.Cu")
		(net "GND")
	)
	(segment
		(start 251.636784 -90.26144)
		(end 251.065284 -90.26144)
		(width 0.254)
		(layer "F.Cu")
		(net "GND")
	)
	(segment
		(start 148.699474 -21.517356)
		(end 148.699474 -20.023582)
		(width 0.4064)
		(layer "F.Cu")
		(net "GND")
	)
	(segment
		(start 391.69975 -96.9772)
		(end 392.02741 -96.825054)
		(width 0.254)
		(layer "F.Cu")
		(net "GND")
	)
	(segment
		(start 119.929402 -77.697584)
		(end 119.357902 -77.697584)
		(width 0.254)
		(layer "F.Cu")
		(net "GND")
	)
	(segment
		(start 233.608118 -62.029086)
		(end 233.036618 -62.029086)
		(width 0.254)
		(layer "F.Cu")
		(net "GND")
	)
	(segment
		(start 349.612712 -148.419312)
		(end 349.7072 -148.419312)
		(width 0.254)
		(layer "F.Cu")
		(net "GND")
	)
	(segment
		(start 80.626712 -90.756486)
		(end 80.055212 -90.756486)
		(width 0.254)
		(layer "F.Cu")
		(net "GND")
	)
	(segment
		(start 303.62017 -102.989126)
		(end 303.62017 -103.040942)
		(width 0.254)
		(layer "F.Cu")
		(net "GND")
	)
	(segment
		(start 50.949352 -17.110202)
		(end 50.949352 -15.423642)
		(width 0.4064)
		(layer "F.Cu")
		(net "GND")
	)
	(segment
		(start 401.295108 -104.85501)
		(end 400.465036 -104.85501)
		(width 0.254)
		(layer "F.Cu")
		(net "GND")
	)
	(segment
		(start 307.749956 -10.422382)
		(end 307.749956 -9.143746)
		(width 0.4064)
		(layer "F.Cu")
		(net "GND")
	)
	(segment
		(start 74.617326 -61.53404)
		(end 74.045826 -61.53404)
		(width 0.254)
		(layer "F.Cu")
		(net "GND")
	)
	(segment
		(start 150.399496 -11.916156)
		(end 150.399496 -10.422382)
		(width 0.4064)
		(layer "F.Cu")
		(net "GND")
	)
	(segment
		(start 40.749474 -137.67054)
		(end 40.749474 -139.170156)
		(width 0.4064)
		(layer "F.Cu")
		(net "GND")
	)
	(segment
		(start 241.44986 -155.511246)
		(end 241.44986 -156.87294)
		(width 0.4064)
		(layer "F.Cu")
		(net "GND")
	)
	(segment
		(start 66.249296 -6.001766)
		(end 66.249296 -7.607046)
		(width 0.4064)
		(layer "F.Cu")
		(net "GND")
	)
	(segment
		(start 381.819404 -158.248858)
		(end 380.875794 -158.248858)
		(width 0.254)
		(layer "F.Cu")
		(net "GND")
	)
	(segment
		(start 248.202704 -57.57164)
		(end 247.631204 -57.57164)
		(width 0.254)
		(layer "F.Cu")
		(net "GND")
	)
	(segment
		(start 122.349514 -137.67054)
		(end 122.349514 -136.410446)
		(width 0.4064)
		(layer "F.Cu")
		(net "GND")
	)
	(segment
		(start 78.051406 -78.37424)
		(end 77.479906 -78.37424)
		(width 0.254)
		(layer "F.Cu")
		(net "GND")
	)
	(segment
		(start 381.313944 -105.815384)
		(end 381.309626 -105.815384)
		(width 0.254)
		(layer "F.Cu")
		(net "GND")
	)
	(segment
		(start 237.900718 -87.28964)
		(end 237.329218 -87.28964)
		(width 0.254)
		(layer "F.Cu")
		(net "GND")
	)
	(segment
		(start 310.299862 -15.423642)
		(end 310.299862 -13.541756)
		(width 0.4064)
		(layer "F.Cu")
		(net "GND")
	)
	(segment
		(start 278.849836 -5.822442)
		(end 278.849836 -4.487164)
		(width 0.4064)
		(layer "F.Cu")
		(net "GND")
	)
	(segment
		(start 90.070178 -66.48704)
		(end 89.498678 -66.48704)
		(width 0.254)
		(layer "F.Cu")
		(net "GND")
	)
	(segment
		(start 122.349514 -20.023582)
		(end 122.349514 -21.517356)
		(width 0.4064)
		(layer "F.Cu")
		(net "GND")
	)
	(segment
		(start 272.910808 -90.575384)
		(end 273.482308 -90.575384)
		(width 0.254)
		(layer "F.Cu")
		(net "GND")
	)
	(segment
		(start 291.599874 3.778758)
		(end 291.599874 3.055874)
		(width 0.3556)
		(layer "F.Cu")
		(net "GND")
	)
	(segment
		(start 212.549994 -5.822442)
		(end 212.549994 -6.001512)
		(width 0.4064)
		(layer "F.Cu")
		(net "GND")
	)
	(segment
		(start 395.5415 -80.11414)
		(end 395.5415 -79.375)
		(width 0.254)
		(layer "F.Cu")
		(net "GND")
	)
	(segment
		(start 446.94094 -45.925486)
		(end 446.94094 -47.481998)
		(width 0.4064)
		(layer "F.Cu")
		(net "GND")
	)
	(segment
		(start 33.099502 -21.479256)
		(end 33.099502 -20.023582)
		(width 0.4064)
		(layer "F.Cu")
		(net "GND")
	)
	(segment
		(start 289.899852 -17.110202)
		(end 289.899852 -15.423642)
		(width 0.4064)
		(layer "F.Cu")
		(net "GND")
	)
	(segment
		(start 61.999368 -5.822442)
		(end 61.999368 -6.553454)
		(width 0.3556)
		(layer "F.Cu")
		(net "GND")
	)
	(segment
		(start 217.649806 -133.809994)
		(end 217.4494 -134.0104)
		(width 0.3048)
		(layer "F.Cu")
		(net "GND")
	)
	(segment
		(start 254.212344 -66.982086)
		(end 253.640844 -66.982086)
		(width 0.254)
		(layer "F.Cu")
		(net "GND")
	)
	(segment
		(start 147.849336 -5.822442)
		(end 147.849336 -4.808728)
		(width 0.4064)
		(layer "F.Cu")
		(net "GND")
	)
	(segment
		(start 352.786696 -94.685104)
		(end 352.0694 -94.685104)
		(width 0.254)
		(layer "F.Cu")
		(net "GND")
	)
	(segment
		(start 317.146432 -11.97356)
		(end 317.146432 -12.954)
		(width 0.4064)
		(layer "F.Cu")
		(net "GND")
	)
	(segment
		(start 259.65023 -91.25204)
		(end 260.22173 -91.25204)
		(width 0.254)
		(layer "F.Cu")
		(net "GND")
	)
	(segment
		(start 126.797308 -75.716384)
		(end 127.368808 -75.716384)
		(width 0.254)
		(layer "F.Cu")
		(net "GND")
	)
	(segment
		(start 399.634964 -107.855004)
		(end 399.634964 -108.855002)
		(width 0.254)
		(layer "F.Cu")
		(net "GND")
	)
	(segment
		(start 146.149568 -9.21385)
		(end 146.149568 -10.422382)
		(width 0.3556)
		(layer "F.Cu")
		(net "GND")
	)
	(segment
		(start 124.221748 -59.371484)
		(end 123.650248 -59.371484)
		(width 0.254)
		(layer "F.Cu")
		(net "GND")
	)
	(segment
		(start 136.240774 -99.986338)
		(end 136.812274 -99.986338)
		(width 0.254)
		(layer "F.Cu")
		(net "GND")
	)
	(segment
		(start 454.141078 -46.046898)
		(end 454.141078 -47.481998)
		(width 0.4064)
		(layer "F.Cu")
		(net "GND")
	)
	(segment
		(start 306.050442 -20.023582)
		(end 306.049934 -20.023582)
		(width 0.4064)
		(layer "F.Cu")
		(net "GND")
	)
	(segment
		(start 383.50571 -115.5954)
		(end 383.77495 -115.86464)
		(width 0.12446)
		(layer "F.Cu")
		(net "GND")
	)
	(segment
		(start 403.671786 -4.386072)
		(end 403.671786 -2.601214)
		(width 0.254)
		(layer "F.Cu")
		(net "GND")
	)
	(segment
		(start 132.549392 3.778758)
		(end 132.549392 1.994154)
		(width 0.4064)
		(layer "F.Cu")
		(net "GND")
	)
	(segment
		(start 382.797304 -33.770824)
		(end 383.798318 -33.770824)
		(width 0.2032)
		(layer "F.Cu")
		(net "GND")
	)
	(segment
		(start 85.777832 -78.869286)
		(end 85.206332 -78.869286)
		(width 0.254)
		(layer "F.Cu")
		(net "GND")
	)
	(segment
		(start 415.890202 -27.334718)
		(end 416.290252 -27.734768)
		(width 0.254)
		(layer "F.Cu")
		(net "GND")
	)
	(segment
		(start 138.499342 -133.891274)
		(end 138.040872 -134.349744)
		(width 0.4064)
		(layer "F.Cu")
		(net "GND")
	)
	(segment
		(start 41.599358 3.778758)
		(end 41.599358 2.092198)
		(width 0.4064)
		(layer "F.Cu")
		(net "GND")
	)
	(segment
		(start 372.685056 -4.389882)
		(end 372.685056 -3.437382)
		(width 0.4572)
		(layer "F.Cu")
		(net "GND")
	)
	(segment
		(start 415.490152 -33.334706)
		(end 415.890202 -33.734756)
		(width 0.254)
		(layer "F.Cu")
		(net "GND")
	)
	(segment
		(start 379.448314 -108.077)
		(end 379.81255 -107.907836)
		(width 0.254)
		(layer "F.Cu")
		(net "GND")
	)
	(segment
		(start 51.79949 -147.27174)
		(end 51.79949 -146.011646)
		(width 0.4064)
		(layer "F.Cu")
		(net "GND")
	)
	(segment
		(start 401.55368 -28.49499)
		(end 401.01901 -28.49499)
		(width 0.254)
		(layer "F.Cu")
		(net "GND")
	)
	(segment
		(start 355.656388 -140.76299)
		(end 355.832156 -140.76299)
		(width 0.1778)
		(layer "F.Cu")
		(net "GND")
	)
	(segment
		(start 280.550366 3.778758)
		(end 280.549858 3.778758)
		(width 0.4064)
		(layer "F.Cu")
		(net "GND")
	)
	(segment
		(start 131.948174 -69.772784)
		(end 132.519674 -69.772784)
		(width 0.254)
		(layer "F.Cu")
		(net "GND")
	)
	(segment
		(start 244.768624 -60.54344)
		(end 244.197124 -60.54344)
		(width 0.254)
		(layer "F.Cu")
		(net "GND")
	)
	(segment
		(start 34.118296 -61.298582)
		(end 34.118296 -61.677804)
		(width 0.254)
		(layer "F.Cu")
		(net "GND")
	)
	(segment
		(start 243.149882 -10.422382)
		(end 243.149882 -9.133078)
		(width 0.4064)
		(layer "F.Cu")
		(net "GND")
	)
	(segment
		(start 141.049502 -137.67054)
		(end 141.049502 -136.410446)
		(width 0.4064)
		(layer "F.Cu")
		(net "GND")
	)
	(segment
		(start 195.330826 -69.573648)
		(end 195.330826 -70.2056)
		(width 0.508)
		(layer "F.Cu")
		(net "GND")
	)
	(segment
		(start 205.749906 -145.998946)
		(end 205.749906 -147.27174)
		(width 0.4064)
		(layer "F.Cu")
		(net "GND")
	)
	(segment
		(start 293.51478 -55.904384)
		(end 294.08628 -55.904384)
		(width 0.254)
		(layer "F.Cu")
		(net "GND")
	)
	(segment
		(start 317.100458 -20.023582)
		(end 317.09995 -20.023582)
		(width 0.4064)
		(layer "F.Cu")
		(net "GND")
	)
	(segment
		(start 196.4182 -148.789644)
		(end 196.4182 -149.6568)
		(width 0.4064)
		(layer "F.Cu")
		(net "GND")
	)
	(segment
		(start 298.665646 -54.913784)
		(end 299.237146 -54.913784)
		(width 0.254)
		(layer "F.Cu")
		(net "GND")
	)
	(segment
		(start 479.620072 -152.218898)
		(end 480.335844 -152.93467)
		(width 0.254)
		(layer "F.Cu")
		(net "GND")
	)
	(segment
		(start 245.627144 -98.681286)
		(end 245.055644 -98.681286)
		(width 0.254)
		(layer "F.Cu")
		(net "GND")
	)
	(segment
		(start 393.627102 -74.163174)
		(end 393.302998 -74.487278)
		(width 0.254)
		(layer "F.Cu")
		(net "GND")
	)
	(segment
		(start 118.099332 -147.27174)
		(end 118.099332 -146.06905)
		(width 0.3556)
		(layer "F.Cu")
		(net "GND")
	)
	(segment
		(start 72.041766 -61.038486)
		(end 71.470266 -61.038486)
		(width 0.254)
		(layer "F.Cu")
		(net "GND")
	)
	(segment
		(start 217.4494 2.667)
		(end 217.4494 1.978406)
		(width 0.3556)
		(layer "F.Cu")
		(net "GND")
	)
	(segment
		(start 386.74675 -102.12832)
		(end 387.24205 -101.898196)
		(width 0.254)
		(layer "F.Cu")
		(net "GND")
	)
	(segment
		(start 300.950376 -15.423642)
		(end 300.949868 -15.423642)
		(width 0.3556)
		(layer "F.Cu")
		(net "GND")
	)
	(segment
		(start 72.1995 -21.455888)
		(end 72.142096 -21.513292)
		(width 0.4064)
		(layer "F.Cu")
		(net "GND")
	)
	(segment
		(start 495.2746 -59.829954)
		(end 496.24996 -59.829954)
		(width 0.254)
		(layer "F.Cu")
		(net "GND")
	)
	(segment
		(start 81.485232 -100.167186)
		(end 80.913732 -100.167186)
		(width 0.254)
		(layer "F.Cu")
		(net "GND")
	)
	(segment
		(start 126.797308 -71.753984)
		(end 127.368808 -71.753984)
		(width 0.254)
		(layer "F.Cu")
		(net "GND")
	)
	(segment
		(start 110.485682 -98.005138)
		(end 111.057182 -98.005138)
		(width 0.254)
		(layer "F.Cu")
		(net "GND")
	)
	(segment
		(start 386.25145 -118.4402)
		(end 386.743448 -118.6688)
		(width 0.254)
		(layer "F.Cu")
		(net "GND")
	)
	(segment
		(start 247.344184 -66.982086)
		(end 246.772684 -66.982086)
		(width 0.254)
		(layer "F.Cu")
		(net "GND")
	)
	(segment
		(start 389.984996 -126.18339)
		(end 389.68172 -126.486666)
		(width 0.254)
		(layer "F.Cu")
		(net "GND")
	)
	(segment
		(start 276.344634 -92.556584)
		(end 276.916134 -92.556584)
		(width 0.254)
		(layer "F.Cu")
		(net "GND")
	)
	(segment
		(start 225.299778 -144.364202)
		(end 225.201734 -144.462246)
		(width 0.4064)
		(layer "F.Cu")
		(net "GND")
	)
	(segment
		(start 308.59984 -13.427456)
		(end 308.59984 -15.423642)
		(width 0.4064)
		(layer "F.Cu")
		(net "GND")
	)
	(segment
		(start 402.244814 -82.195924)
		(end 402.244814 -83.412076)
		(width 0.254)
		(layer "F.Cu")
		(net "GND")
	)
	(segment
		(start 308.59984 -7.509002)
		(end 308.59984 -5.822442)
		(width 0.4064)
		(layer "F.Cu")
		(net "GND")
	)
	(segment
		(start 58.599578 3.778758)
		(end 58.599324 3.778504)
		(width 0.4064)
		(layer "F.Cu")
		(net "GND")
	)
	(segment
		(start 146.149568 -11.854688)
		(end 146.092164 -11.912092)
		(width 0.4064)
		(layer "F.Cu")
		(net "GND")
	)
	(segment
		(start 236.183678 -92.24264)
		(end 235.612178 -92.24264)
		(width 0.254)
		(layer "F.Cu")
		(net "GND")
	)
	(segment
		(start 287.50514 -54.418738)
		(end 286.93364 -54.418738)
		(width 0.254)
		(layer "F.Cu")
		(net "GND")
	)
	(segment
		(start 280.637234 -60.362338)
		(end 280.065734 -60.362338)
		(width 0.254)
		(layer "F.Cu")
		(net "GND")
	)
	(segment
		(start 58.599324 -133.076696)
		(end 58.599324 -134.861046)
		(width 0.4064)
		(layer "F.Cu")
		(net "GND")
	)
	(segment
		(start 347.6498 -156.2862)
		(end 347.942154 -155.993846)
		(width 0.254)
		(layer "F.Cu")
		(net "GND")
	)
	(segment
		(start 464.44789 -141.719808)
		(end 462.980532 -141.719808)
		(width 0.254)
		(layer "F.Cu")
		(net "GND")
	)
	(segment
		(start 64.549274 -5.822696)
		(end 64.549274 -6.637274)
		(width 0.4064)
		(layer "F.Cu")
		(net "GND")
	)
	(segment
		(start 397.4084 -126.58852)
		(end 397.4084 -127.105156)
		(width 0.254)
		(layer "F.Cu")
		(net "GND")
	)
	(segment
		(start 139.674854 -57.390538)
		(end 140.246354 -57.390538)
		(width 0.254)
		(layer "F.Cu")
		(net "GND")
	)
	(segment
		(start 462.201006 -118.615968)
		(end 462.204308 -118.61927)
		(width 0.4064)
		(layer "F.Cu")
		(net "GND")
	)
	(segment
		(start 84.060792 -83.822286)
		(end 83.489292 -83.822286)
		(width 0.254)
		(layer "F.Cu")
		(net "GND")
	)
	(segment
		(start 234.65028 -142.6718)
		(end 234.649772 -142.677642)
		(width 0.4064)
		(layer "F.Cu")
		(net "GND")
	)
	(segment
		(start 304.349912 -147.27174)
		(end 304.349912 -146.011646)
		(width 0.4064)
		(layer "F.Cu")
		(net "GND")
	)
	(segment
		(start 458.940916 -50.569622)
		(end 458.940916 -51.875944)
		(width 0.508)
		(layer "F.Cu")
		(net "GND")
	)
	(segment
		(start 243.910104 -82.83194)
		(end 243.338604 -82.83194)
		(width 0.254)
		(layer "F.Cu")
		(net "GND")
	)
	(segment
		(start 238.900462 -152.273)
		(end 238.899954 -152.278842)
		(width 0.4064)
		(layer "F.Cu")
		(net "GND")
	)
	(segment
		(start 45.849286 3.778504)
		(end 45.849286 2.963926)
		(width 0.4064)
		(layer "F.Cu")
		(net "GND")
	)
	(segment
		(start 232.950512 -15.423642)
		(end 232.950512 -13.364718)
		(width 0.4064)
		(layer "F.Cu")
		(net "GND")
	)
	(segment
		(start 285.649924 -11.916156)
		(end 285.649924 -10.422382)
		(width 0.4064)
		(layer "F.Cu")
		(net "GND")
	)
	(segment
		(start 311.150508 -10.422382)
		(end 311.15 -10.422382)
		(width 0.3556)
		(layer "F.Cu")
		(net "GND")
	)
	(segment
		(start 253.353824 -69.45884)
		(end 252.782324 -69.45884)
		(width 0.254)
		(layer "F.Cu")
		(net "GND")
	)
	(segment
		(start 229.081838 -2.3114)
		(end 230.396288 -2.3114)
		(width 0.4064)
		(layer "F.Cu")
		(net "GND")
	)
	(segment
		(start 280.549858 -17.110202)
		(end 280.549858 -15.423642)
		(width 0.4064)
		(layer "F.Cu")
		(net "GND")
	)
	(segment
		(start 76.449428 -10.422382)
		(end 76.449428 -11.916156)
		(width 0.4064)
		(layer "F.Cu")
		(net "GND")
	)
	(segment
		(start 126.797308 -56.894984)
		(end 127.368808 -56.894984)
		(width 0.254)
		(layer "F.Cu")
		(net "GND")
	)
	(segment
		(start 108.768896 -58.381138)
		(end 108.197396 -58.381138)
		(width 0.254)
		(layer "F.Cu")
		(net "GND")
	)
	(segment
		(start 87.494872 -78.869286)
		(end 86.923372 -78.869286)
		(width 0.254)
		(layer "F.Cu")
		(net "GND")
	)
	(segment
		(start 385.4704 -81.51876)
		(end 385.545838 -81.594198)
		(width 0.254)
		(layer "F.Cu")
		(net "GND")
	)
	(segment
		(start 411.49016 -26.934668)
		(end 411.89021 -27.334718)
		(width 0.254)
		(layer "F.Cu")
		(net "GND")
	)
	(segment
		(start 124.221748 -54.418738)
		(end 123.650248 -54.418738)
		(width 0.254)
		(layer "F.Cu")
		(net "GND")
	)
	(segment
		(start 485.99344 -32.72536)
		(end 485.50576 -32.72536)
		(width 0.254)
		(layer "F.Cu")
		(net "GND")
	)
	(segment
		(start 430.075086 -3.889248)
		(end 430.075086 -4.386072)
		(width 0.254)
		(layer "F.Cu")
		(net "GND")
	)
	(segment
		(start 349.741236 -2.257552)
		(end 349.421704 -1.93802)
		(width 0.381)
		(layer "F.Cu")
		(net "GND")
	)
	(segment
		(start 309.449978 -136.410446)
		(end 309.449978 -137.67054)
		(width 0.4064)
		(layer "F.Cu")
		(net "GND")
	)
	(segment
		(start 209.092546 -155.650946)
		(end 209.092546 -155.600146)
		(width 0.4064)
		(layer "F.Cu")
		(net "GND")
	)
	(segment
		(start 240.600484 -5.822442)
		(end 240.600484 -7.606284)
		(width 0.4064)
		(layer "F.Cu")
		(net "GND")
	)
	(segment
		(start 306.392326 -87.091266)
		(end 306.702968 -86.780624)
		(width 0.254)
		(layer "F.Cu")
		(net "GND")
	)
	(segment
		(start 127.655828 -80.174338)
		(end 128.227328 -80.174338)
		(width 0.254)
		(layer "F.Cu")
		(net "GND")
	)
	(segment
		(start 132.806694 -55.409338)
		(end 133.378194 -55.409338)
		(width 0.127)
		(layer "F.Cu")
		(net "GND")
	)
	(segment
		(start 443.000892 -118.615714)
		(end 443.004448 -118.61927)
		(width 0.4064)
		(layer "F.Cu")
		(net "GND")
	)
	(segment
		(start 56.049418 -0.821182)
		(end 56.049418 -2.314956)
		(width 0.4064)
		(layer "F.Cu")
		(net "GND")
	)
	(segment
		(start 113.916968 -12.954)
		(end 112.397032 -12.954)
		(width 0.381)
		(layer "F.Cu")
		(net "GND")
	)
	(segment
		(start 424.434 -26.162)
		(end 424.144186 -26.162)
		(width 0.254)
		(layer "F.Cu")
		(net "GND")
	)
	(segment
		(start 275.486114 -58.381138)
		(end 274.914614 -58.381138)
		(width 0.254)
		(layer "F.Cu")
		(net "GND")
	)
	(segment
		(start 152.1333 -21.56206)
		(end 152.1333 -22.7457)
		(width 0.4064)
		(layer "F.Cu")
		(net "GND")
	)
	(segment
		(start 397.7894 -119.366538)
		(end 398.13865 -119.528844)
		(width 0.254)
		(layer "F.Cu")
		(net "GND")
	)
	(segment
		(start 198.755 -133.985)
		(end 198.755 -134.882382)
		(width 0.3556)
		(layer "F.Cu")
		(net "GND")
	)
	(segment
		(start 31.472378 -21.590254)
		(end 31.39948 -21.517356)
		(width 0.381)
		(layer "F.Cu")
		(net "GND")
	)
	(segment
		(start 208.30032 3.778758)
		(end 208.299812 3.778758)
		(width 0.3556)
		(layer "F.Cu")
		(net "GND")
	)
	(segment
		(start 87.494872 -70.94474)
		(end 86.923372 -70.94474)
		(width 0.254)
		(layer "F.Cu")
		(net "GND")
	)
	(segment
		(start 207.411828 -21.517356)
		(end 207.449928 -21.479256)
		(width 0.4064)
		(layer "F.Cu")
		(net "GND")
	)
	(segment
		(start 449.34886 -52.451)
		(end 449.345812 -52.2478)
		(width 0.4064)
		(layer "F.Cu")
		(net "GND")
	)
	(segment
		(start 294.14978 -152.278842)
		(end 294.14978 -153.093674)
		(width 0.4064)
		(layer "F.Cu")
		(net "GND")
	)
	(segment
		(start 308.59984 2.092198)
		(end 308.501796 1.994154)
		(width 0.4064)
		(layer "F.Cu")
		(net "GND")
	)
	(segment
		(start 380.80315 -115.86464)
		(end 381.29845 -116.094764)
		(width 0.254)
		(layer "F.Cu")
		(net "GND")
	)
	(segment
		(start 207.449928 -156.87294)
		(end 207.449928 -155.638246)
		(width 0.4064)
		(layer "F.Cu")
		(net "GND")
	)
	(segment
		(start 232.950512 -133.0706)
		(end 232.950004 -133.076442)
		(width 0.4064)
		(layer "F.Cu")
		(net "GND")
	)
	(segment
		(start 160.556702 -126.210568)
		(end 160.76422 -126.00305)
		(width 0.4572)
		(layer "F.Cu")
		(net "GND")
	)
	(segment
		(start 70.324726 -96.700086)
		(end 69.753226 -96.700086)
		(width 0.254)
		(layer "F.Cu")
		(net "GND")
	)
	(segment
		(start 373.702326 -158.493206)
		(end 371.243606 -158.493206)
		(width 0.254)
		(layer "F.Cu")
		(net "GND")
	)
	(segment
		(start 119.799354 -142.6718)
		(end 119.799354 -142.677642)
		(width 0.4064)
		(layer "F.Cu")
		(net "GND")
	)
	(segment
		(start 71.183246 -88.28024)
		(end 70.611746 -88.28024)
		(width 0.254)
		(layer "F.Cu")
		(net "GND")
	)
	(segment
		(start 119.7991 -6.637274)
		(end 119.34063 -7.095744)
		(width 0.4064)
		(layer "F.Cu")
		(net "GND")
	)
	(segment
		(start 284.929834 -81.659984)
		(end 284.358334 -81.659984)
		(width 0.254)
		(layer "F.Cu")
		(net "GND")
	)
	(segment
		(start 252.495304 -83.822286)
		(end 251.923804 -83.822286)
		(width 0.254)
		(layer "F.Cu")
		(net "GND")
	)
	(segment
		(start 246.485664 -100.167186)
		(end 245.914164 -100.167186)
		(width 0.254)
		(layer "F.Cu")
		(net "GND")
	)
	(segment
		(start 400.5961 -125.466094)
		(end 400.5961 -126.056136)
		(width 0.254)
		(layer "F.Cu")
		(net "GND")
	)
	(segment
		(start 481.41382 -16.724376)
		(end 481.41382 -16.35506)
		(width 0.254)
		(layer "F.Cu")
		(net "GND")
	)
	(segment
		(start 199.800464 -137.67054)
		(end 199.799956 -137.67054)
		(width 0.4064)
		(layer "F.Cu")
		(net "GND")
	)
	(segment
		(start 169.8244 -74.5744)
		(end 169.9768 -74.7268)
		(width 0.254)
		(layer "F.Cu")
		(net "GND")
	)
	(segment
		(start 373.544846 -73.495154)
		(end 373.14505 -73.89495)
		(width 0.254)
		(layer "F.Cu")
		(net "GND")
	)
	(segment
		(start 473.03309 -38.94709)
		(end 473.075 -38.989)
		(width 0.254)
		(layer "F.Cu")
		(net "GND")
	)
	(segment
		(start 307.250846 -61.847984)
		(end 307.898546 -61.847984)
		(width 0.254)
		(layer "F.Cu")
		(net "GND")
	)
	(segment
		(start 223.599756 -3.762756)
		(end 223.60001 -3.76301)
		(width 0.4064)
		(layer "F.Cu")
		(net "GND")
	)
	(segment
		(start 215.950292 3.778758)
		(end 215.949784 3.778758)
		(width 0.4064)
		(layer "F.Cu")
		(net "GND")
	)
	(segment
		(start 397.470376 -122.02414)
		(end 397.558768 -122.065034)
		(width 0.254)
		(layer "F.Cu")
		(net "GND")
	)
	(segment
		(start 415.490152 -33.334706)
		(end 415.090102 -33.734756)
		(width 0.254)
		(layer "F.Cu")
		(net "GND")
	)
	(segment
		(start 118.099332 -9.21385)
		(end 118.041928 -9.156446)
		(width 0.3556)
		(layer "F.Cu")
		(net "GND")
	)
	(segment
		(start 136.8425 -103.1621)
		(end 137.099294 -102.905306)
		(width 0.4064)
		(layer "F.Cu")
		(net "GND")
	)
	(segment
		(start 134.523734 -68.287138)
		(end 135.095234 -68.287138)
		(width 0.254)
		(layer "F.Cu")
		(net "GND")
	)
	(segment
		(start 28.194 -76.808584)
		(end 28.601416 -77.216)
		(width 0.254)
		(layer "F.Cu")
		(net "GND")
	)
	(segment
		(start 240.600484 -5.822442)
		(end 240.600484 -3.763518)
		(width 0.4064)
		(layer "F.Cu")
		(net "GND")
	)
	(segment
		(start 285.2166 -60.362338)
		(end 285.7881 -60.362338)
		(width 0.254)
		(layer "F.Cu")
		(net "GND")
	)
	(segment
		(start 287.349946 -10.422382)
		(end 287.349946 -11.916156)
		(width 0.4064)
		(layer "F.Cu")
		(net "GND")
	)
	(segment
		(start 295.85031 -133.0706)
		(end 295.849802 -133.076442)
		(width 0.4064)
		(layer "F.Cu")
		(net "GND")
	)
	(segment
		(start 138.816334 -59.866784)
		(end 139.387834 -59.866784)
		(width 0.254)
		(layer "F.Cu")
		(net "GND")
	)
	(segment
		(start 375.089928 -114.355118)
		(end 375.92 -114.355118)
		(width 0.254)
		(layer "F.Cu")
		(net "GND")
	)
	(segment
		(start 164.9984 -86.2076)
		(end 164.846 -86.2076)
		(width 0.254)
		(layer "F.Cu")
		(net "GND")
	)
	(segment
		(start 205.750414 -0.821182)
		(end 205.749906 -0.821182)
		(width 0.4064)
		(layer "F.Cu")
		(net "GND")
	)
	(segment
		(start 135.099552 -137.67054)
		(end 135.099552 -136.410446)
		(width 0.4064)
		(layer "F.Cu")
		(net "GND")
	)
	(segment
		(start 415.72815 -48.717962)
		(end 415.757106 -48.746918)
		(width 0.254)
		(layer "F.Cu")
		(net "GND")
	)
	(segment
		(start 303.529746 -73.240138)
		(end 302.958246 -73.240138)
		(width 0.254)
		(layer "F.Cu")
		(net "GND")
	)
	(segment
		(start 78.051406 -80.35544)
		(end 77.479906 -80.35544)
		(width 0.254)
		(layer "F.Cu")
		(net "GND")
	)
	(segment
		(start 242.2652 -26.67)
		(end 242.2652 -26.0858)
		(width 0.4064)
		(layer "F.Cu")
		(net "GND")
	)
	(segment
		(start 184.7596 -145.5674)
		(end 184.7596 -145.1102)
		(width 0.254)
		(layer "F.Cu")
		(net "GND")
	)
	(segment
		(start 442.522356 -32.2326)
		(end 442.921898 -32.632142)
		(width 0.3048)
		(layer "F.Cu")
		(net "GND")
	)
	(segment
		(start 58.599578 -5.822442)
		(end 58.599324 -5.822696)
		(width 0.4064)
		(layer "F.Cu")
		(net "GND")
	)
	(segment
		(start 124.221748 -91.070938)
		(end 124.793248 -91.070938)
		(width 0.254)
		(layer "F.Cu")
		(net "GND")
	)
	(segment
		(start 291.599874 -133.076442)
		(end 291.599874 -133.799326)
		(width 0.3556)
		(layer "F.Cu")
		(net "GND")
	)
	(segment
		(start 300.950376 -5.822442)
		(end 300.949868 -5.822442)
		(width 0.4064)
		(layer "F.Cu")
		(net "GND")
	)
	(segment
		(start 115.64366 -51.44008)
		(end 115.636802 -51.446938)
		(width 0.2286)
		(layer "F.Cu")
		(net "GND")
	)
	(segment
		(start 360.9848 -133.096)
		(end 361.188 -133.096)
		(width 0.254)
		(layer "F.Cu")
		(net "GND")
	)
	(segment
		(start 419.73119 -52.795932)
		(end 419.73119 -52.260246)
		(width 0.254)
		(layer "F.Cu")
		(net "GND")
	)
	(segment
		(start 116.399564 -18.757646)
		(end 116.399564 -20.023582)
		(width 0.4064)
		(layer "F.Cu")
		(net "GND")
	)
	(segment
		(start 120.216168 -58.381138)
		(end 120.787668 -58.381138)
		(width 0.254)
		(layer "F.Cu")
		(net "GND")
	)
	(segment
		(start 391.984992 -95.205042)
		(end 392.98499 -95.205042)
		(width 0.254)
		(layer "F.Cu")
		(net "GND")
	)
	(segment
		(start 127.655828 -96.023938)
		(end 128.227328 -96.023938)
		(width 0.254)
		(layer "F.Cu")
		(net "GND")
	)
	(segment
		(start 126.797308 -67.791584)
		(end 127.368808 -67.791584)
		(width 0.254)
		(layer "F.Cu")
		(net "GND")
	)
	(segment
		(start 207.411828 -148.771356)
		(end 207.449928 -148.733256)
		(width 0.4064)
		(layer "F.Cu")
		(net "GND")
	)
	(segment
		(start 466.199982 -116.992908)
		(end 466.199982 -115.810538)
		(width 0.4064)
		(layer "F.Cu")
		(net "GND")
	)
	(segment
		(start 198.099934 -11.878056)
		(end 198.099934 -10.422382)
		(width 0.4064)
		(layer "F.Cu")
		(net "GND")
	)
	(segment
		(start 383.878582 -126.058676)
		(end 383.878582 -125.441456)
		(width 0.254)
		(layer "F.Cu")
		(net "GND")
	)
	(segment
		(start 297.549824 -133.076442)
		(end 297.549824 -134.861046)
		(width 0.4064)
		(layer "F.Cu")
		(net "GND")
	)
	(segment
		(start 199.799956 -2.253488)
		(end 199.799956 -0.821182)
		(width 0.4064)
		(layer "F.Cu")
		(net "GND")
	)
	(segment
		(start 85.777832 -71.935086)
		(end 85.206332 -71.935086)
		(width 0.254)
		(layer "F.Cu")
		(net "GND")
	)
	(segment
		(start 37.34943 -147.27174)
		(end 37.34943 -148.771356)
		(width 0.4064)
		(layer "F.Cu")
		(net "GND")
	)
	(segment
		(start 117.353842 -68.287138)
		(end 117.353842 -68.858638)
		(width 0.254)
		(layer "F.Cu")
		(net "GND")
	)
	(segment
		(start 107.910376 -95.528384)
		(end 108.481876 -95.528384)
		(width 0.254)
		(layer "F.Cu")
		(net "GND")
	)
	(segment
		(start 67.949318 3.778504)
		(end 67.949318 1.994154)
		(width 0.4064)
		(layer "F.Cu")
		(net "GND")
	)
	(segment
		(start 5.49402 -133.38302)
		(end 5.20446 -133.38302)
		(width 0.4064)
		(layer "F.Cu")
		(net "GND")
	)
	(segment
		(start 145.082768 -153.2128)
		(end 145.082768 -154.062938)
		(width 0.3556)
		(layer "F.Cu")
		(net "GND")
	)
	(segment
		(start 32.249364 -7.509002)
		(end 32.15132 -7.607046)
		(width 0.4064)
		(layer "F.Cu")
		(net "GND")
	)
	(segment
		(start -1.93421 -43.87596)
		(end -0.500126 -45.310044)
		(width 0.508)
		(layer "F.Cu")
		(net "GND")
	)
	(segment
		(start 365.485172 -3.437382)
		(end 365.485172 -4.389882)
		(width 0.4572)
		(layer "F.Cu")
		(net "GND")
	)
	(segment
		(start 203.2 3.599688)
		(end 203.199746 3.599434)
		(width 0.4064)
		(layer "F.Cu")
		(net "GND")
	)
	(segment
		(start 244.768624 -54.59984)
		(end 244.197124 -54.59984)
		(width 0.254)
		(layer "F.Cu")
		(net "GND")
	)
	(segment
		(start 474.56725 -43.6626)
		(end 474.61805 -43.7134)
		(width 0.254)
		(layer "F.Cu")
		(net "GND")
	)
	(segment
		(start 55.199534 -133.0706)
		(end 55.199534 -133.076442)
		(width 0.4064)
		(layer "F.Cu")
		(net "GND")
	)
	(segment
		(start 243.910104 -93.72854)
		(end 243.338604 -93.72854)
		(width 0.254)
		(layer "F.Cu")
		(net "GND")
	)
	(segment
		(start 235.325158 -96.700086)
		(end 234.753658 -96.700086)
		(width 0.254)
		(layer "F.Cu")
		(net "GND")
	)
	(segment
		(start 238.759238 -86.794086)
		(end 238.187738 -86.794086)
		(width 0.254)
		(layer "F.Cu")
		(net "GND")
	)
	(segment
		(start 226.9998 -15.423642)
		(end 226.9998 -13.541756)
		(width 0.4064)
		(layer "F.Cu")
		(net "GND")
	)
	(segment
		(start 295.849802 -17.208246)
		(end 295.849802 -15.423642)
		(width 0.4064)
		(layer "F.Cu")
		(net "GND")
	)
	(segment
		(start 389.881618 -156.591)
		(end 390.60628 -156.591)
		(width 0.254)
		(layer "F.Cu")
		(net "GND")
	)
	(segment
		(start 413.5755 -22.0345)
		(end 413.639 -21.971)
		(width 0.254)
		(layer "F.Cu")
		(net "GND")
	)
	(segment
		(start 290.0807 -64.819784)
		(end 290.6522 -64.819784)
		(width 0.254)
		(layer "F.Cu")
		(net "GND")
	)
	(segment
		(start 283.212794 -54.913784)
		(end 282.641294 -54.913784)
		(width 0.254)
		(layer "F.Cu")
		(net "GND")
	)
	(segment
		(start 296.948606 -69.772784)
		(end 297.520106 -69.772784)
		(width 0.254)
		(layer "F.Cu")
		(net "GND")
	)
	(segment
		(start 280.637234 -54.418738)
		(end 280.065734 -54.418738)
		(width 0.254)
		(layer "F.Cu")
		(net "GND")
	)
	(segment
		(start 152.099518 -152.273)
		(end 152.099518 -153.542746)
		(width 0.4064)
		(layer "F.Cu")
		(net "GND")
	)
	(segment
		(start 390.13765 -111.85525)
		(end 390.5377 -112.2553)
		(width 0.12446)
		(layer "F.Cu")
		(net "GND")
	)
	(segment
		(start 292.65626 -53.636164)
		(end 292.65626 -53.427884)
		(width 0.254)
		(layer "F.Cu")
		(net "GND")
	)
	(segment
		(start 250.778264 -67.972686)
		(end 250.206764 -67.972686)
		(width 0.254)
		(layer "F.Cu")
		(net "GND")
	)
	(segment
		(start 282.24988 -133.802374)
		(end 282.0162 -134.036054)
		(width 0.3556)
		(layer "F.Cu")
		(net "GND")
	)
	(segment
		(start 402.449538 1.702308)
		(end 402.982938 1.702308)
		(width 0.10795)
		(layer "F.Cu")
		(net "GND")
	)
	(segment
		(start 207.450436 -20.023582)
		(end 207.449928 -20.023582)
		(width 0.4064)
		(layer "F.Cu")
		(net "GND")
	)
	(segment
		(start 303.816766 -53.714904)
		(end 303.816766 -53.923184)
		(width 0.254)
		(layer "F.Cu")
		(net "GND")
	)
	(segment
		(start 385.6609 -55.3466)
		(end 385.572 -55.4355)
		(width 0.254)
		(layer "F.Cu")
		(net "GND")
	)
	(segment
		(start 3.132836 -7.098538)
		(end 3.132836 -6.663436)
		(width 0.254)
		(layer "F.Cu")
		(net "GND")
	)
	(segment
		(start 316.249812 -133.076442)
		(end 316.249812 -134.861046)
		(width 0.4064)
		(layer "F.Cu")
		(net "GND")
	)
	(segment
		(start 212.549994 -133.255512)
		(end 212.54974 -133.255766)
		(width 0.4064)
		(layer "F.Cu")
		(net "GND")
	)
	(segment
		(start 466.66404 -115.34648)
		(end 467.047072 -115.34648)
		(width 0.4064)
		(layer "F.Cu")
		(net "GND")
	)
	(segment
		(start 347.7641 -148.297392)
		(end 347.942154 -148.119338)
		(width 0.254)
		(layer "F.Cu")
		(net "GND")
	)
	(segment
		(start 126.421642 -17.2466)
		(end 126.388368 -17.213326)
		(width 0.3556)
		(layer "F.Cu")
		(net "GND")
	)
	(segment
		(start 197.249796 2.092198)
		(end 197.151752 1.994154)
		(width 0.4064)
		(layer "F.Cu")
		(net "GND")
	)
	(segment
		(start 249.919744 -52.618386)
		(end 249.919744 -51.62804)
		(width 0.2286)
		(layer "F.Cu")
		(net "GND")
	)
	(segment
		(start 474.61805 -43.7134)
		(end 476.179134 -43.7134)
		(width 0.254)
		(layer "F.Cu")
		(net "GND")
	)
	(segment
		(start 77.192886 -49.991518)
		(end 76.699364 -49.497996)
		(width 0.254)
		(layer "F.Cu")
		(net "GND")
	)
	(segment
		(start 302.118268 -103.363268)
		(end 302.7807 -104.0257)
		(width 0.2032)
		(layer "F.Cu")
		(net "GND")
	)
	(segment
		(start 71.349362 -153.006806)
		(end 71.117968 -153.2382)
		(width 0.3556)
		(layer "F.Cu")
		(net "GND")
	)
	(segment
		(start 404.106634 -98.12274)
		(end 403.50186 -98.12274)
		(width 0.254)
		(layer "F.Cu")
		(net "GND")
	)
	(segment
		(start 261.93877 -63.51524)
		(end 261.36727 -63.51524)
		(width 0.254)
		(layer "F.Cu")
		(net "GND")
	)
	(segment
		(start 281.570176 -70.956424)
		(end 281.446732 -70.956424)
		(width 0.254)
		(layer "F.Cu")
		(net "GND")
	)
	(segment
		(start 406.7175 -105.664)
		(end 407.192226 -105.664)
		(width 0.254)
		(layer "F.Cu")
		(net "GND")
	)
	(segment
		(start 312.391298 -16.696944)
		(end 312.849768 -16.238474)
		(width 0.4064)
		(layer "F.Cu")
		(net "GND")
	)
	(segment
		(start 51.79949 -156.87294)
		(end 51.79949 -155.612846)
		(width 0.4064)
		(layer "F.Cu")
		(net "GND")
	)
	(segment
		(start 136.240774 -85.127338)
		(end 136.812274 -85.127338)
		(width 0.254)
		(layer "F.Cu")
		(net "GND")
	)
	(segment
		(start 200.983596 -4.2926)
		(end 201.037952 -4.346956)
		(width 0.254)
		(layer "F.Cu")
		(net "GND")
	)
	(segment
		(start 26.602182 -130.5814)
		(end 26.602182 -131.40055)
		(width 0.4064)
		(layer "F.Cu")
		(net "GND")
	)
	(segment
		(start 180.086 -58.166)
		(end 180.1114 -58.1406)
		(width 0.381)
		(layer "F.Cu")
		(net "GND")
	)
	(segment
		(start 82.343752 -95.709486)
		(end 81.772252 -95.709486)
		(width 0.254)
		(layer "F.Cu")
		(net "GND")
	)
	(segment
		(start 34.74212 -155.825698)
		(end 34.74212 -155.600146)
		(width 0.4064)
		(layer "F.Cu")
		(net "GND")
	)
	(segment
		(start 305.199796 -142.677642)
		(end 305.199796 -144.462246)
		(width 0.4064)
		(layer "F.Cu")
		(net "GND")
	)
	(segment
		(start 210.85048 -15.423642)
		(end 210.849972 -15.423642)
		(width 0.4064)
		(layer "F.Cu")
		(net "GND")
	)
	(segment
		(start 234.466638 -90.26144)
		(end 233.895138 -90.26144)
		(width 0.254)
		(layer "F.Cu")
		(net "GND")
	)
	(segment
		(start 197.249796 -17.110202)
		(end 197.249796 -15.423642)
		(width 0.4064)
		(layer "F.Cu")
		(net "GND")
	)
	(segment
		(start 281.399996 -20.023582)
		(end 281.399996 -18.757646)
		(width 0.4064)
		(layer "F.Cu")
		(net "GND")
	)
	(segment
		(start 459.427326 -45.611796)
		(end 459.741016 -45.925486)
		(width 0.4064)
		(layer "F.Cu")
		(net "GND")
	)
	(segment
		(start 310.0832 -143.6116)
		(end 310.0832 -144.461738)
		(width 0.3556)
		(layer "F.Cu")
		(net "GND")
	)
	(segment
		(start 44.149518 -0.821182)
		(end 44.149518 -2.253488)
		(width 0.4064)
		(layer "F.Cu")
		(net "GND")
	)
	(segment
		(start 226.7966 1.9812)
		(end 226.822 1.9558)
		(width 0.3556)
		(layer "F.Cu")
		(net "GND")
	)
	(segment
		(start 67.949318 -142.677896)
		(end 67.949318 -144.462246)
		(width 0.4064)
		(layer "F.Cu")
		(net "GND")
	)
	(segment
		(start 51.76139 -2.314956)
		(end 51.79949 -2.276856)
		(width 0.4064)
		(layer "F.Cu")
		(net "GND")
	)
	(segment
		(start 390.70915 -95.888556)
		(end 390.984994 -95.205042)
		(width 0.254)
		(layer "F.Cu")
		(net "GND")
	)
	(segment
		(start 306.899818 3.778758)
		(end 306.899818 1.994154)
		(width 0.4064)
		(layer "F.Cu")
		(net "GND")
	)
	(segment
		(start 382.78435 -100.41128)
		(end 382.9304 -100.343462)
		(width 0.254)
		(layer "F.Cu")
		(net "GND")
	)
	(segment
		(start 68.607686 -96.700086)
		(end 67.942968 -96.700086)
		(width 0.254)
		(layer "F.Cu")
		(net "GND")
	)
	(segment
		(start 240.476278 -100.662486)
		(end 239.904778 -100.662486)
		(width 0.254)
		(layer "F.Cu")
		(net "GND")
	)
	(segment
		(start 243.051838 -98.18624)
		(end 243.338604 -98.681286)
		(width 0.254)
		(layer "F.Cu")
		(net "GND")
	)
	(segment
		(start 415.890202 -31.33471)
		(end 415.890202 -30.53461)
		(width 0.254)
		(layer "F.Cu")
		(net "GND")
	)
	(segment
		(start 71.183246 -78.37424)
		(end 70.611746 -78.37424)
		(width 0.254)
		(layer "F.Cu")
		(net "GND")
	)
	(segment
		(start 34.799524 -147.27174)
		(end 34.799524 -146.281902)
		(width 0.4064)
		(layer "F.Cu")
		(net "GND")
	)
	(segment
		(start 413.890206 -33.334706)
		(end 414.290256 -33.734756)
		(width 0.254)
		(layer "F.Cu")
		(net "GND")
	)
	(segment
		(start 251.636784 -91.25204)
		(end 251.065284 -91.25204)
		(width 0.254)
		(layer "F.Cu")
		(net "GND")
	)
	(segment
		(start 283.099764 -137.67054)
		(end 283.099764 -136.46785)
		(width 0.3556)
		(layer "F.Cu")
		(net "GND")
	)
	(segment
		(start 300.061884 -11.916156)
		(end 300.099984 -11.878056)
		(width 0.4064)
		(layer "F.Cu")
		(net "GND")
	)
	(segment
		(start 45.849286 -16.238474)
		(end 45.390816 -16.696944)
		(width 0.4064)
		(layer "F.Cu")
		(net "GND")
	)
	(segment
		(start 132.806694 -60.362338)
		(end 133.378194 -60.362338)
		(width 0.254)
		(layer "F.Cu")
		(net "GND")
	)
	(segment
		(start 30.216348 -85.4837)
		(end 29.71673 -85.983318)
		(width 0.508)
		(layer "F.Cu")
		(net "GND")
	)
	(segment
		(start 390.70915 -117.58168)
		(end 391.20445 -117.811804)
		(width 0.254)
		(layer "F.Cu")
		(net "GND")
	)
	(segment
		(start 404.109174 -98.12528)
		(end 404.106634 -98.12274)
		(width 0.254)
		(layer "F.Cu")
		(net "GND")
	)
	(segment
		(start 33.061402 -148.771356)
		(end 33.099502 -148.733256)
		(width 0.4064)
		(layer "F.Cu")
		(net "GND")
	)
	(segment
		(start 349.942912 -148.655024)
		(end 349.7072 -148.419312)
		(width 0.4064)
		(layer "F.Cu")
		(net "GND")
	)
	(segment
		(start 217.649806 3.778758)
		(end 217.649806 3.045206)
		(width 0.3048)
		(layer "F.Cu")
		(net "GND")
	)
	(segment
		(start 150.399496 -137.67054)
		(end 150.399496 -136.410446)
		(width 0.4064)
		(layer "F.Cu")
		(net "GND")
	)
	(segment
		(start 122.504708 -74.230738)
		(end 123.076208 -74.23023)
		(width 0.254)
		(layer "F.Cu")
		(net "GND")
	)
	(segment
		(start 283.212794 -86.612984)
		(end 283.784294 -86.612984)
		(width 0.4064)
		(layer "F.Cu")
		(net "GND")
	)
	(segment
		(start 301.742602 0.444754)
		(end 301.800006 0.38735)
		(width 0.3556)
		(layer "F.Cu")
		(net "GND")
	)
	(segment
		(start 210.85048 -133.0706)
		(end 210.849972 -133.076442)
		(width 0.4064)
		(layer "F.Cu")
		(net "GND")
	)
	(segment
		(start 143.599408 -17.110202)
		(end 143.501364 -17.208246)
		(width 0.4064)
		(layer "F.Cu")
		(net "GND")
	)
	(segment
		(start 68.607686 -83.822286)
		(end 68.036186 -83.822286)
		(width 0.254)
		(layer "F.Cu")
		(net "GND")
	)
	(segment
		(start 127.655828 -53.636164)
		(end 127.655828 -53.427884)
		(width 0.254)
		(layer "F.Cu")
		(net "GND")
	)
	(segment
		(start 299.524166 -74.230738)
		(end 300.095666 -74.230738)
		(width 0.254)
		(layer "F.Cu")
		(net "GND")
	)
	(segment
		(start 452.5518 -53.2638)
		(end 452.550022 -53.262022)
		(width 0.4064)
		(layer "F.Cu")
		(net "GND")
	)
	(segment
		(start 196.40042 -147.27174)
		(end 196.399912 -147.27174)
		(width 0.4064)
		(layer "F.Cu")
		(net "GND")
	)
	(segment
		(start 107.910376 -56.894984)
		(end 107.338876 -56.894984)
		(width 0.254)
		(layer "F.Cu")
		(net "GND")
	)
	(segment
		(start 251.636784 -59.55284)
		(end 251.065284 -59.55284)
		(width 0.254)
		(layer "F.Cu")
		(net "GND")
	)
	(segment
		(start 401.6121 -84.582)
		(end 401.813014 -84.582)
		(width 0.254)
		(layer "F.Cu")
		(net "GND")
	)
	(segment
		(start 303.529746 -53.427884)
		(end 303.816766 -53.714904)
		(width 0.254)
		(layer "F.Cu")
		(net "GND")
	)
	(segment
		(start 74.617326 -65.49644)
		(end 74.045826 -65.49644)
		(width 0.254)
		(layer "F.Cu")
		(net "GND")
	)
	(segment
		(start 483.8954 -135.636)
		(end 483.87 -135.6106)
		(width 0.254)
		(layer "F.Cu")
		(net "GND")
	)
	(segment
		(start 376.428 -105.354882)
		(end 375.92 -105.354882)
		(width 0.254)
		(layer "F.Cu")
		(net "GND")
	)
	(segment
		(start 71.183246 -87.28964)
		(end 70.611746 -87.28964)
		(width 0.254)
		(layer "F.Cu")
		(net "GND")
	)
	(segment
		(start 140.533374 -98.500184)
		(end 141.10462 -98.500184)
		(width 0.254)
		(layer "F.Cu")
		(net "GND")
	)
	(segment
		(start 78.051406 -68.46824)
		(end 77.479906 -68.46824)
		(width 0.254)
		(layer "F.Cu")
		(net "GND")
	)
	(segment
		(start 239.617758 -61.53404)
		(end 239.046258 -61.53404)
		(width 0.254)
		(layer "F.Cu")
		(net "GND")
	)
	(segment
		(start 402.071586 -7.789672)
		(end 402.071586 -9.44372)
		(width 0.254)
		(layer "F.Cu")
		(net "GND")
	)
	(segment
		(start 429.312578 -36.07435)
		(end 429.566578 -35.82035)
		(width 0.254)
		(layer "F.Cu")
		(net "GND")
	)
	(segment
		(start 282.354274 -68.287138)
		(end 282.354274 -68.9102)
		(width 0.254)
		(layer "F.Cu")
		(net "GND")
	)
	(segment
		(start 238.759238 -65.000886)
		(end 238.187738 -65.000886)
		(width 0.254)
		(layer "F.Cu")
		(net "GND")
	)
	(segment
		(start 312.849768 -142.677642)
		(end 312.849768 -143.492474)
		(width 0.4064)
		(layer "F.Cu")
		(net "GND")
	)
	(segment
		(start 290.750498 -155.613354)
		(end 290.74999 -155.612846)
		(width 0.3556)
		(layer "F.Cu")
		(net "GND")
	)
	(segment
		(start 243.051838 -57.57164)
		(end 242.480338 -57.57164)
		(width 0.254)
		(layer "F.Cu")
		(net "GND")
	)
	(segment
		(start 467.2076 -114.41176)
		(end 467.26348 -114.41176)
		(width 0.254)
		(layer "F.Cu")
		(net "GND")
	)
	(segment
		(start 301.800514 -137.67054)
		(end 301.800006 -137.67054)
		(width 0.3556)
		(layer "F.Cu")
		(net "GND")
	)
	(segment
		(start 77.192886 -67.972686)
		(end 76.621386 -67.972686)
		(width 0.254)
		(layer "F.Cu")
		(net "GND")
	)
	(segment
		(start 375.089928 -105.354882)
		(end 375.92 -105.354882)
		(width 0.254)
		(layer "F.Cu")
		(net "GND")
	)
	(segment
		(start 201.499724 -152.279096)
		(end 201.499724 -153.093674)
		(width 0.4064)
		(layer "F.Cu")
		(net "GND")
	)
	(segment
		(start 278.849836 1.946148)
		(end 278.727408 1.82372)
		(width 0.4064)
		(layer "F.Cu")
		(net "GND")
	)
	(segment
		(start 202.35037 -137.67054)
		(end 202.349862 -137.67054)
		(width 0.4064)
		(layer "F.Cu")
		(net "GND")
	)
	(segment
		(start 125.749558 -21.479256)
		(end 125.711458 -21.517356)
		(width 0.4064)
		(layer "F.Cu")
		(net "GND")
	)
	(segment
		(start 191.897 -22.507194)
		(end 191.897 -21.427694)
		(width 0.4064)
		(layer "F.Cu")
		(net "GND")
	)
	(segment
		(start 308.59984 -152.278842)
		(end 308.59984 -153.965402)
		(width 0.4064)
		(layer "F.Cu")
		(net "GND")
	)
	(segment
		(start 225.201734 -17.208246)
		(end 225.299778 -17.110202)
		(width 0.4064)
		(layer "F.Cu")
		(net "GND")
	)
	(segment
		(start 118.099332 -18.81505)
		(end 118.099332 -20.023582)
		(width 0.3556)
		(layer "F.Cu")
		(net "GND")
	)
	(segment
		(start 256.78765 -65.49644)
		(end 256.21615 -65.49644)
		(width 0.254)
		(layer "F.Cu")
		(net "GND")
	)
	(segment
		(start 118.099332 -10.422382)
		(end 118.099332 -9.21385)
		(width 0.3556)
		(layer "F.Cu")
		(net "GND")
	)
	(segment
		(start 120.787668 -69.277738)
		(end 121.359168 -69.277738)
		(width 0.254)
		(layer "F.Cu")
		(net "GND")
	)
	(segment
		(start 304.349912 -0.821182)
		(end 304.349912 -2.314956)
		(width 0.4064)
		(layer "F.Cu")
		(net "GND")
	)
	(segment
		(start 229.54996 -142.677642)
		(end 229.549706 -142.677896)
		(width 0.4064)
		(layer "F.Cu")
		(net "GND")
	)
	(segment
		(start 439.732166 -50.51679)
		(end 439.728864 -50.513488)
		(width 0.508)
		(layer "F.Cu")
		(net "GND")
	)
	(segment
		(start 120.602248 -11.9634)
		(end 120.649492 -11.916156)
		(width 0.4064)
		(layer "F.Cu")
		(net "GND")
	)
	(segment
		(start 83.202272 -85.30844)
		(end 82.630772 -85.30844)
		(width 0.254)
		(layer "F.Cu")
		(net "GND")
	)
	(segment
		(start 462.149952 -62.00267)
		(end 462.149952 -63.170054)
		(width 0.381)
		(layer "F.Cu")
		(net "GND")
	)
	(segment
		(start 398.63395 -119.29872)
		(end 399.12925 -119.528844)
		(width 0.254)
		(layer "F.Cu")
		(net "GND")
	)
	(segment
		(start 378.763784 -55.505858)
		(end 379.107192 -55.16245)
		(width 0.254)
		(layer "F.Cu")
		(net "GND")
	)
	(segment
		(start 303.529746 -75.221338)
		(end 304.675286 -75.221338)
		(width 0.254)
		(layer "F.Cu")
		(net "GND")
	)
	(segment
		(start 226.9998 -152.278842)
		(end 226.9998 -153.009854)
		(width 0.3556)
		(layer "F.Cu")
		(net "GND")
	)
	(segment
		(start 298.665646 -72.744584)
		(end 299.237146 -72.744584)
		(width 0.254)
		(layer "F.Cu")
		(net "GND")
	)
	(segment
		(start 278.061674 -95.528384)
		(end 278.633174 -95.528384)
		(width 0.254)
		(layer "F.Cu")
		(net "GND")
	)
	(segment
		(start 352.421952 0.76708)
		(end 352.424238 0.764794)
		(width 0.254)
		(layer "F.Cu")
		(net "GND")
	)
	(segment
		(start 243.910104 -54.104286)
		(end 243.338604 -54.104286)
		(width 0.254)
		(layer "F.Cu")
		(net "GND")
	)
	(segment
		(start 321.691 -140.210032)
		(end 321.691 -140.6652)
		(width 0.4064)
		(layer "F.Cu")
		(net "GND")
	)
	(segment
		(start 239.617758 -56.58104)
		(end 239.046258 -56.58104)
		(width 0.254)
		(layer "F.Cu")
		(net "GND")
	)
	(segment
		(start 292.450012 -0.821182)
		(end 292.450012 0.38735)
		(width 0.3556)
		(layer "F.Cu")
		(net "GND")
	)
	(segment
		(start 371.7036 -94.107)
		(end 372.745254 -94.107)
		(width 0.254)
		(layer "F.Cu")
		(net "GND")
	)
	(segment
		(start 306.049934 -11.916156)
		(end 306.049934 -10.422382)
		(width 0.4064)
		(layer "F.Cu")
		(net "GND")
	)
	(segment
		(start 134.249414 -7.509002)
		(end 134.15137 -7.607046)
		(width 0.4064)
		(layer "F.Cu")
		(net "GND")
	)
	(segment
		(start 442.200792 -112.205516)
		(end 442.200792 -113.909094)
		(width 0.4064)
		(layer "F.Cu")
		(net "GND")
	)
	(segment
		(start 233.608118 -60.047886)
		(end 234.753658 -60.047886)
		(width 0.254)
		(layer "F.Cu")
		(net "GND")
	)
	(segment
		(start 115.636802 -87.108538)
		(end 115.636802 -86.537038)
		(width 0.381)
		(layer "F.Cu")
		(net "GND")
	)
	(segment
		(start 168.3512 -63.7286)
		(end 168.3512 -63.1444)
		(width 0.2032)
		(layer "F.Cu")
		(net "GND")
	)
	(segment
		(start 291.3888 -143.6116)
		(end 291.3888 -144.467326)
		(width 0.3556)
		(layer "F.Cu")
		(net "GND")
	)
	(segment
		(start 300.954186 -63.829184)
		(end 300.382686 -63.829184)
		(width 0.254)
		(layer "F.Cu")
		(net "GND")
	)
	(segment
		(start 311.15 -147.27174)
		(end 311.15 -146.06905)
		(width 0.3556)
		(layer "F.Cu")
		(net "GND")
	)
	(segment
		(start 117.015768 -143.637254)
		(end 117.015768 -144.44472)
		(width 0.3556)
		(layer "F.Cu")
		(net "GND")
	)
	(segment
		(start 59.449462 -147.27174)
		(end 59.449462 -145.998946)
		(width 0.4064)
		(layer "F.Cu")
		(net "GND")
	)
	(segment
		(start 467.999572 -139.954)
		(end 467.643972 -139.5984)
		(width 0.254)
		(layer "F.Cu")
		(net "GND")
	)
	(segment
		(start 86.636352 -98.18624)
		(end 86.923372 -98.681286)
		(width 0.254)
		(layer "F.Cu")
		(net "GND")
	)
	(segment
		(start 317.950342 -15.423642)
		(end 317.949834 -15.423642)
		(width 0.4064)
		(layer "F.Cu")
		(net "GND")
	)
	(segment
		(start 383.985008 -126.69012)
		(end 383.985008 -126.165102)
		(width 0.254)
		(layer "F.Cu")
		(net "GND")
	)
	(segment
		(start 458.140054 -51.875944)
		(end 458.14107 -51.875944)
		(width 0.4064)
		(layer "F.Cu")
		(net "GND")
	)
	(segment
		(start 242.300506 -15.423642)
		(end 242.300506 -17.207484)
		(width 0.4064)
		(layer "F.Cu")
		(net "GND")
	)
	(segment
		(start 223.60001 -5.822442)
		(end 223.599756 -5.822696)
		(width 0.4064)
		(layer "F.Cu")
		(net "GND")
	)
	(segment
		(start 51.79949 -10.422382)
		(end 51.79949 -11.878056)
		(width 0.4064)
		(layer "F.Cu")
		(net "GND")
	)
	(segment
		(start 202.349862 0.444754)
		(end 202.349862 -0.821182)
		(width 0.4064)
		(layer "F.Cu")
		(net "GND")
	)
	(segment
		(start 445.400938 -112.205516)
		(end 445.400938 -113.816384)
		(width 0.4064)
		(layer "F.Cu")
		(net "GND")
	)
	(segment
		(start 84.060792 -65.991486)
		(end 83.489292 -65.991486)
		(width 0.254)
		(layer "F.Cu")
		(net "GND")
	)
	(segment
		(start 360.68508 -3.446018)
		(end 360.68508 -4.389882)
		(width 0.4572)
		(layer "F.Cu")
		(net "GND")
	)
	(segment
		(start 50.949352 -144.364202)
		(end 50.851308 -144.462246)
		(width 0.4064)
		(layer "F.Cu")
		(net "GND")
	)
	(segment
		(start 276.344634 -89.584784)
		(end 276.916134 -89.584784)
		(width 0.254)
		(layer "F.Cu")
		(net "GND")
	)
	(segment
		(start 242.193318 -88.775286)
		(end 241.621818 -88.775286)
		(width 0.254)
		(layer "F.Cu")
		(net "GND")
	)
	(segment
		(start 304.349912 -2.314956)
		(end 303.60874 -2.341626)
		(width 0.254)
		(layer "F.Cu")
		(net "GND")
	)
	(segment
		(start 252.495304 -98.681286)
		(end 251.923804 -98.681286)
		(width 0.254)
		(layer "F.Cu")
		(net "GND")
	)
	(segment
		(start 317.09995 -133.076442)
		(end 317.09995 -134.340346)
		(width 0.4064)
		(layer "F.Cu")
		(net "GND")
	)
	(segment
		(start 150.399496 -147.27174)
		(end 150.399496 -146.011646)
		(width 0.4064)
		(layer "F.Cu")
		(net "GND")
	)
	(segment
		(start 152.099518 -21.528278)
		(end 152.1333 -21.56206)
		(width 0.4064)
		(layer "F.Cu")
		(net "GND")
	)
	(segment
		(start 283.212794 -56.894984)
		(end 282.641294 -56.894984)
		(width 0.254)
		(layer "F.Cu")
		(net "GND")
	)
	(segment
		(start 237.142528 -155.612846)
		(end 237.199932 -155.67025)
		(width 0.3556)
		(layer "F.Cu")
		(net "GND")
	)
	(segment
		(start 152.949402 3.778758)
		(end 152.949402 2.514854)
		(width 0.4064)
		(layer "F.Cu")
		(net "GND")
	)
	(segment
		(start 91.224862 -150.098506)
		(end 90.626692 -150.098506)
		(width 0.4064)
		(layer "F.Cu")
		(net "GND")
	)
	(segment
		(start 281.495754 -92.556584)
		(end 282.067254 -92.556584)
		(width 0.254)
		(layer "F.Cu")
		(net "GND")
	)
	(segment
		(start 227.850446 -137.67054)
		(end 227.849938 -137.67054)
		(width 0.3556)
		(layer "F.Cu")
		(net "GND")
	)
	(segment
		(start 429.731678 -3.359404)
		(end 429.962056 -3.589782)
		(width 0.254)
		(layer "F.Cu")
		(net "GND")
	)
	(segment
		(start 135.099552 -147.27174)
		(end 135.099552 -146.011646)
		(width 0.4064)
		(layer "F.Cu")
		(net "GND")
	)
	(segment
		(start 455.740008 -51.875944)
		(end 455.741024 -51.875944)
		(width 0.4064)
		(layer "F.Cu")
		(net "GND")
	)
	(segment
		(start 134.249414 -153.965402)
		(end 134.15137 -154.063446)
		(width 0.4064)
		(layer "F.Cu")
		(net "GND")
	)
	(segment
		(start 218.499944 -0.821182)
		(end 218.499944 0.38735)
		(width 0.3556)
		(layer "F.Cu")
		(net "GND")
	)
	(segment
		(start 480.335844 -152.93467)
		(end 481.051616 -153.650442)
		(width 0.254)
		(layer "F.Cu")
		(net "GND")
	)
	(segment
		(start 2.3114 -144.0942)
		(end 2.3114 -143.9926)
		(width 0.254)
		(layer "F.Cu")
		(net "GND")
	)
	(segment
		(start 56.899556 -133.255512)
		(end 56.899302 -133.255766)
		(width 0.4064)
		(layer "F.Cu")
		(net "GND")
	)
	(segment
		(start 391.5156 -3.352038)
		(end 391.5156 -3.175)
		(width 0.4064)
		(layer "F.Cu")
		(net "GND")
	)
	(segment
		(start 287.350454 -10.422382)
		(end 287.349946 -10.422382)
		(width 0.4064)
		(layer "F.Cu")
		(net "GND")
	)
	(segment
		(start 287.50514 -102.958138)
		(end 288.07664 -102.958138)
		(width 0.3048)
		(layer "F.Cu")
		(net "GND")
	)
	(segment
		(start 70.324726 -91.747086)
		(end 69.753226 -91.747086)
		(width 0.254)
		(layer "F.Cu")
		(net "GND")
	)
	(segment
		(start 113.849404 -133.0706)
		(end 113.849404 -134.866888)
		(width 0.4064)
		(layer "F.Cu")
		(net "GND")
	)
	(segment
		(start 278.920194 -58.381138)
		(end 278.348694 -58.381138)
		(width 0.254)
		(layer "F.Cu")
		(net "GND")
	)
	(segment
		(start 285.649924 -20.023582)
		(end 285.649924 -18.757646)
		(width 0.4064)
		(layer "F.Cu")
		(net "GND")
	)
	(segment
		(start 278.07031 -3.3528)
		(end 278.19731 -3.4798)
		(width 0.381)
		(layer "F.Cu")
		(net "GND")
	)
	(segment
		(start 255.072388 -3.635756)
		(end 255.8034 -3.635756)
		(width 0.4064)
		(layer "F.Cu")
		(net "GND")
	)
	(segment
		(start 391.0076 -81.3308)
		(end 391.0076 -81.573624)
		(width 0.254)
		(layer "F.Cu")
		(net "GND")
	)
	(segment
		(start 78.051406 -96.20504)
		(end 77.479906 -96.20504)
		(width 0.254)
		(layer "F.Cu")
		(net "GND")
	)
	(segment
		(start 72.041766 -68.963286)
		(end 71.470266 -68.963286)
		(width 0.254)
		(layer "F.Cu")
		(net "GND")
	)
	(segment
		(start 433.1335 -12.2936)
		(end 433.578 -12.2936)
		(width 0.254)
		(layer "F.Cu")
		(net "GND")
	)
	(segment
		(start 455.741024 -51.875944)
		(end 455.741024 -50.523648)
		(width 0.508)
		(layer "F.Cu")
		(net "GND")
	)
	(segment
		(start 306.899818 -133.076442)
		(end 306.899818 -134.861046)
		(width 0.4064)
		(layer "F.Cu")
		(net "GND")
	)
	(segment
		(start 221.900496 -142.6718)
		(end 221.899988 -142.677642)
		(width 0.4064)
		(layer "F.Cu")
		(net "GND")
	)
	(segment
		(start 236.183678 -87.28964)
		(end 235.612178 -87.28964)
		(width 0.254)
		(layer "F.Cu")
		(net "GND")
	)
	(segment
		(start 392.121644 -72.886824)
		(end 392.121644 -73.605644)
		(width 0.508)
		(layer "F.Cu")
		(net "GND")
	)
	(segment
		(start 378.284994 -7.789926)
		(end 378.284994 -7.850124)
		(width 0.254)
		(layer "F.Cu")
		(net "GND")
	)
	(segment
		(start 229.550468 -5.822442)
		(end 229.54996 -5.822442)
		(width 0.4064)
		(layer "F.Cu")
		(net "GND")
	)
	(segment
		(start 212.549994 -13.36421)
		(end 212.54974 -13.363956)
		(width 0.4064)
		(layer "F.Cu")
		(net "GND")
	)
	(segment
		(start 235.325158 -58.06694)
		(end 234.753658 -58.06694)
		(width 0.254)
		(layer "F.Cu")
		(net "GND")
	)
	(segment
		(start 47.549562 -15.602712)
		(end 47.549562 -15.423642)
		(width 0.4064)
		(layer "F.Cu")
		(net "GND")
	)
	(segment
		(start 210.849718 -143.492474)
		(end 210.391248 -143.950944)
		(width 0.4064)
		(layer "F.Cu")
		(net "GND")
	)
	(segment
		(start 30.549342 -13.929106)
		(end 30.020006 -13.929106)
		(width 0.4064)
		(layer "F.Cu")
		(net "GND")
	)
	(segment
		(start 99.513898 -53.113686)
		(end 98.942398 -53.113686)
		(width 0.254)
		(layer "F.Cu")
		(net "GND")
	)
	(segment
		(start 113.849404 -154.111452)
		(end 113.849404 -152.278842)
		(width 0.4064)
		(layer "F.Cu")
		(net "GND")
	)
	(segment
		(start 251.636784 -84.31784)
		(end 251.065284 -84.31784)
		(width 0.254)
		(layer "F.Cu")
		(net "GND")
	)
	(segment
		(start 127.392176 -155.612846)
		(end 127.392176 -155.600146)
		(width 0.3556)
		(layer "F.Cu")
		(net "GND")
	)
	(segment
		(start 193.4464 -62.36208)
		(end 193.4464 -61.68136)
		(width 0.254)
		(layer "F.Cu")
		(net "GND")
	)
	(segment
		(start 384.985006 -124.504958)
		(end 385.75615 -123.821444)
		(width 0.254)
		(layer "F.Cu")
		(net "GND")
	)
	(segment
		(start 227.849938 -18.81505)
		(end 227.849938 -20.023582)
		(width 0.3556)
		(layer "F.Cu")
		(net "GND")
	)
	(segment
		(start 390.945624 -76.437998)
		(end 392.295888 -76.437998)
		(width 0.254)
		(layer "F.Cu")
		(net "GND")
	)
	(segment
		(start 242.299998 -152.278842)
		(end 242.299744 -152.279096)
		(width 0.4064)
		(layer "F.Cu")
		(net "GND")
	)
	(segment
		(start 298.40047 -10.422382)
		(end 298.399962 -10.422382)
		(width 0.4064)
		(layer "F.Cu")
		(net "GND")
	)
	(segment
		(start 300.099984 -0.821182)
		(end 300.099984 -2.276856)
		(width 0.4064)
		(layer "F.Cu")
		(net "GND")
	)
	(segment
		(start 129.372868 -53.427884)
		(end 129.944368 -53.427884)
		(width 0.254)
		(layer "F.Cu")
		(net "GND")
	)
	(segment
		(start 229.549706 -5.822696)
		(end 229.54996 -5.822442)
		(width 0.4064)
		(layer "F.Cu")
		(net "GND")
	)
	(segment
		(start 77.299566 -140.63091)
		(end 77.286612 -140.617956)
		(width 0.4064)
		(layer "F.Cu")
		(net "GND")
	)
	(segment
		(start 135.949436 -152.273)
		(end 135.949436 -153.024078)
		(width 0.3556)
		(layer "F.Cu")
		(net "GND")
	)
	(segment
		(start 279.699974 -11.9126)
		(end 279.699974 -10.422382)
		(width 0.4064)
		(layer "F.Cu")
		(net "GND")
	)
	(segment
		(start 55.199534 -142.6718)
		(end 55.199534 -142.677642)
		(width 0.4064)
		(layer "F.Cu")
		(net "GND")
	)
	(segment
		(start 72.041766 -64.010286)
		(end 71.470266 -64.010286)
		(width 0.254)
		(layer "F.Cu")
		(net "GND")
	)
	(segment
		(start 88.353392 -69.45884)
		(end 87.781892 -69.45884)
		(width 0.254)
		(layer "F.Cu")
		(net "GND")
	)
	(segment
		(start 272.052288 -59.371484)
		(end 271.480788 -59.371484)
		(width 0.254)
		(layer "F.Cu")
		(net "GND")
	)
	(segment
		(start 305.199796 3.778758)
		(end 305.199796 1.994154)
		(width 0.4064)
		(layer "F.Cu")
		(net "GND")
	)
	(segment
		(start 40.749474 -136.397746)
		(end 40.749474 -137.67054)
		(width 0.4064)
		(layer "F.Cu")
		(net "GND")
	)
	(segment
		(start 381.29845 -102.98684)
		(end 381.79375 -102.756716)
		(width 0.254)
		(layer "F.Cu")
		(net "GND")
	)
	(segment
		(start 250.206764 -55.094886)
		(end 250.778264 -55.094886)
		(width 0.254)
		(layer "F.Cu")
		(net "GND")
	)
	(segment
		(start 135.735568 -144.464532)
		(end 135.771636 -144.5006)
		(width 0.3556)
		(layer "F.Cu")
		(net "GND")
	)
	(segment
		(start 235.325158 -93.72854)
		(end 234.753658 -93.72854)
		(width 0.254)
		(layer "F.Cu")
		(net "GND")
	)
	(segment
		(start 36.499546 -142.6718)
		(end 36.499546 -142.677642)
		(width 0.4064)
		(layer "F.Cu")
		(net "GND")
	)
	(segment
		(start 453.027288 -45.611796)
		(end 453.340978 -45.925486)
		(width 0.4064)
		(layer "F.Cu")
		(net "GND")
	)
	(segment
		(start 390.70915 -102.756716)
		(end 391.20445 -102.98684)
		(width 0.254)
		(layer "F.Cu")
		(net "GND")
	)
	(segment
		(start 94.649798 -91.25204)
		(end 95.221298 -91.25204)
		(width 0.254)
		(layer "F.Cu")
		(net "GND")
	)
	(segment
		(start 156.591 -3.302)
		(end 156.610812 -3.321812)
		(width 0.4064)
		(layer "F.Cu")
		(net "GND")
	)
	(segment
		(start 296.66184 -52.437538)
		(end 296.09034 -52.437538)
		(width 0.254)
		(layer "F.Cu")
		(net "GND")
	)
	(segment
		(start 347.829632 -13.742416)
		(end 347.605096 -13.966952)
		(width 0.2032)
		(layer "F.Cu")
		(net "GND")
	)
	(segment
		(start 196.40042 -20.023582)
		(end 196.399912 -20.023582)
		(width 0.4064)
		(layer "F.Cu")
		(net "GND")
	)
	(segment
		(start 198.928228 -93.861382)
		(end 198.928228 -94.390972)
		(width 0.254)
		(layer "F.Cu")
		(net "GND")
	)
	(segment
		(start 301.241206 -102.958138)
		(end 301.241206 -103.5812)
		(width 0.254)
		(layer "F.Cu")
		(net "GND")
	)
	(segment
		(start 210.387946 -4.346956)
		(end 210.849972 -4.808982)
		(width 0.4064)
		(layer "F.Cu")
		(net "GND")
	)
	(segment
		(start 384.53695 -113.45545)
		(end 384.1369 -113.8555)
		(width 0.12446)
		(layer "F.Cu")
		(net "GND")
	)
	(segment
		(start 124.221748 -57.390538)
		(end 123.650248 -57.390538)
		(width 0.254)
		(layer "F.Cu")
		(net "GND")
	)
	(segment
		(start 0 -134.3152)
		(end -0.9652 -134.3152)
		(width 0.381)
		(layer "F.Cu")
		(net "GND")
	)
	(segment
		(start 196.3674 -139.202668)
		(end 196.3674 -140.0556)
		(width 0.4064)
		(layer "F.Cu")
		(net "GND")
	)
	(segment
		(start 312.849768 -6.637274)
		(end 312.391298 -7.095744)
		(width 0.4064)
		(layer "F.Cu")
		(net "GND")
	)
	(segment
		(start 314.550298 -5.822442)
		(end 314.54979 -5.822442)
		(width 0.4064)
		(layer "F.Cu")
		(net "GND")
	)
	(segment
		(start 418.5031 -54.5719)
		(end 418.6936 -54.3814)
		(width 0.254)
		(layer "F.Cu")
		(net "GND")
	)
	(segment
		(start 375.44121 -122.918728)
		(end 375.504964 -122.854974)
		(width 0.254)
		(layer "F.Cu")
		(net "GND")
	)
	(segment
		(start 409.862528 -55.617872)
		(end 410.3624 -55.118)
		(width 0.254)
		(layer "F.Cu")
		(net "GND")
	)
	(segment
		(start -0.342138 -6.047486)
		(end 0.011684 -6.047486)
		(width 0.254)
		(layer "F.Cu")
		(net "GND")
	)
	(segment
		(start 374.015 -86.632796)
		(end 374.015 -87.3125)
		(width 0.254)
		(layer "F.Cu")
		(net "GND")
	)
	(segment
		(start 102.7938 -140.208)
		(end 103.678736 -140.208)
		(width 0.4064)
		(layer "F.Cu")
		(net "GND")
	)
	(segment
		(start 283.100272 -10.422382)
		(end 283.099764 -10.422382)
		(width 0.3556)
		(layer "F.Cu")
		(net "GND")
	)
	(segment
		(start 295.23182 -94.538038)
		(end 295.80332 -94.538038)
		(width 0.3048)
		(layer "F.Cu")
		(net "GND")
	)
	(segment
		(start 121.646188 -70.763384)
		(end 122.217688 -70.763384)
		(width 0.254)
		(layer "F.Cu")
		(net "GND")
	)
	(segment
		(start 382.98501 -95.205042)
		(end 381.985012 -95.205042)
		(width 0.254)
		(layer "F.Cu")
		(net "GND")
	)
	(segment
		(start 339.599016 -22.86)
		(end 340.233 -22.86)
		(width 0.4064)
		(layer "F.Cu")
		(net "GND")
	)
	(segment
		(start 197.082664 -94.873064)
		(end 196.691504 -94.481904)
		(width 0.254)
		(layer "F.Cu")
		(net "GND")
	)
	(segment
		(start 295.23182 -68.782184)
		(end 295.80332 -68.782184)
		(width 0.254)
		(layer "F.Cu")
		(net "GND")
	)
	(segment
		(start 55.19928 3.778504)
		(end 55.19928 2.963926)
		(width 0.4064)
		(layer "F.Cu")
		(net "GND")
	)
	(segment
		(start 138.499342 -133.0706)
		(end 138.499342 -133.891274)
		(width 0.4064)
		(layer "F.Cu")
		(net "GND")
	)
	(segment
		(start 398.13865 -116.094764)
		(end 397.7894 -115.932458)
		(width 0.254)
		(layer "F.Cu")
		(net "GND")
	)
	(segment
		(start 1.27 -118.959376)
		(end 0.946658 -118.636034)
		(width 0.254)
		(layer "F.Cu")
		(net "GND")
	)
	(segment
		(start 32.094932 -94.843092)
		(end 31.84906 -94.59722)
		(width 0.254)
		(layer "F.Cu")
		(net "GND")
	)
	(segment
		(start 197.249796 -13.427456)
		(end 197.160896 -13.338556)
		(width 0.4064)
		(layer "F.Cu")
		(net "GND")
	)
	(segment
		(start 62.792102 -18.744946)
		(end 62.792102 -18.757646)
		(width 0.3556)
		(layer "F.Cu")
		(net "GND")
	)
	(segment
		(start 227.792534 -155.612846)
		(end 227.849938 -155.67025)
		(width 0.3556)
		(layer "F.Cu")
		(net "GND")
	)
	(segment
		(start 50.949352 -7.509002)
		(end 50.851308 -7.607046)
		(width 0.4064)
		(layer "F.Cu")
		(net "GND")
	)
	(segment
		(start 283.212794 -65.810384)
		(end 282.641294 -65.810384)
		(width 0.254)
		(layer "F.Cu")
		(net "GND")
	)
	(segment
		(start 303.816766 -59.866784)
		(end 304.388266 -59.866784)
		(width 0.254)
		(layer "F.Cu")
		(net "GND")
	)
	(segment
		(start 237.042198 -82.83194)
		(end 236.470698 -82.83194)
		(width 0.254)
		(layer "F.Cu")
		(net "GND")
	)
	(segment
		(start 30.818582 -62.009782)
		(end 30.524958 -61.716158)
		(width 0.508)
		(layer "F.Cu")
		(net "GND")
	)
	(segment
		(start 350.0755 -157.2895)
		(end 351.505266 -157.2895)
		(width 0.508)
		(layer "F.Cu")
		(net "GND")
	)
	(segment
		(start 53.442108 -18.744946)
		(end 53.442108 -18.757646)
		(width 0.3556)
		(layer "F.Cu")
		(net "GND")
	)
	(segment
		(start 434.5051 -42.2148)
		(end 434.213 -42.2148)
		(width 0.254)
		(layer "F.Cu")
		(net "GND")
	)
	(segment
		(start 122.349514 -156.87294)
		(end 122.349514 -155.745434)
		(width 0.4064)
		(layer "F.Cu")
		(net "GND")
	)
	(segment
		(start 133.39953 -9.143746)
		(end 133.39953 -10.422382)
		(width 0.4064)
		(layer "F.Cu")
		(net "GND")
	)
	(segment
		(start 212.54974 -152.458166)
		(end 212.54974 -154.063446)
		(width 0.4064)
		(layer "F.Cu")
		(net "GND")
	)
	(segment
		(start 281.495754 -94.538038)
		(end 282.067254 -94.538038)
		(width 0.1651)
		(layer "F.Cu")
		(net "GND")
	)
	(segment
		(start 84.919312 -88.28024)
		(end 84.347812 -88.28024)
		(width 0.254)
		(layer "F.Cu")
		(net "GND")
	)
	(segment
		(start 346.3036 -10.2108)
		(end 346.3036 -9.850628)
		(width 0.4064)
		(layer "F.Cu")
		(net "GND")
	)
	(segment
		(start 62.792102 -155.612846)
		(end 62.792102 -155.600146)
		(width 0.3556)
		(layer "F.Cu")
		(net "GND")
	)
	(segment
		(start 72.900286 -74.411586)
		(end 72.328786 -74.411586)
		(width 0.254)
		(layer "F.Cu")
		(net "GND")
	)
	(segment
		(start 251.636784 -76.39304)
		(end 251.065284 -76.39304)
		(width 0.254)
		(layer "F.Cu")
		(net "GND")
	)
	(segment
		(start 350.7486 -15.19428)
		(end 350.41332 -14.859)
		(width 0.2032)
		(layer "F.Cu")
		(net "GND")
	)
	(segment
		(start 243.910104 -87.784686)
		(end 243.338604 -87.784686)
		(width 0.254)
		(layer "F.Cu")
		(net "GND")
	)
	(segment
		(start 199.742552 -9.369298)
		(end 199.799956 -9.426702)
		(width 0.4064)
		(layer "F.Cu")
		(net "GND")
	)
	(segment
		(start 247.344184 -96.700086)
		(end 246.772684 -96.700086)
		(width 0.254)
		(layer "F.Cu")
		(net "GND")
	)
	(segment
		(start 234.466638 -53.60924)
		(end 233.895138 -53.60924)
		(width 0.254)
		(layer "F.Cu")
		(net "GND")
	)
	(segment
		(start 458.756004 -143.219932)
		(end 459.221332 -143.68526)
		(width 0.254)
		(layer "F.Cu")
		(net "GND")
	)
	(segment
		(start 289.90036 3.778758)
		(end 289.899852 3.778758)
		(width 0.4064)
		(layer "F.Cu")
		(net "GND")
	)
	(segment
		(start 53.499512 -11.854688)
		(end 53.499512 -10.422382)
		(width 0.4064)
		(layer "F.Cu")
		(net "GND")
	)
	(segment
		(start 272.624042 -100.977192)
		(end 272.910808 -101.471984)
		(width 0.254)
		(layer "F.Cu")
		(net "GND")
	)
	(segment
		(start 310.299862 -5.822442)
		(end 310.299862 -6.539738)
		(width 0.3556)
		(layer "F.Cu")
		(net "GND")
	)
	(segment
		(start 46.699424 -20.023582)
		(end 46.699424 -18.757646)
		(width 0.4064)
		(layer "F.Cu")
		(net "GND")
	)
	(segment
		(start 72.1995 -2.253488)
		(end 72.1995 -0.821182)
		(width 0.4064)
		(layer "F.Cu")
		(net "GND")
	)
	(segment
		(start 398.861534 -93.544898)
		(end 398.861534 -92.07119)
		(width 0.254)
		(layer "F.Cu")
		(net "GND")
	)
	(segment
		(start 197.082664 -95.284544)
		(end 197.082664 -94.873064)
		(width 0.254)
		(layer "F.Cu")
		(net "GND")
	)
	(segment
		(start 75.599544 -142.6718)
		(end 75.599544 -142.856712)
		(width 0.4064)
		(layer "F.Cu")
		(net "GND")
	)
	(segment
		(start 378.82195 -106.190796)
		(end 378.353574 -106.408474)
		(width 0.254)
		(layer "F.Cu")
		(net "GND")
	)
	(segment
		(start 471.800936 -116.993162)
		(end 471.800936 -118.566184)
		(width 0.4064)
		(layer "F.Cu")
		(net "GND")
	)
	(segment
		(start 78.909672 -60.047886)
		(end 78.338172 -60.047886)
		(width 0.254)
		(layer "F.Cu")
		(net "GND")
	)
	(segment
		(start 58.599578 -13.36421)
		(end 58.599578 -15.423642)
		(width 0.4064)
		(layer "F.Cu")
		(net "GND")
	)
	(segment
		(start 78.909672 -65.991486)
		(end 78.338172 -65.991486)
		(width 0.254)
		(layer "F.Cu")
		(net "GND")
	)
	(segment
		(start 89.789 -3.3528)
		(end 90.071956 -3.635756)
		(width 0.4064)
		(layer "F.Cu")
		(net "GND")
	)
	(segment
		(start 146.149568 -156.87294)
		(end 146.149568 -155.67025)
		(width 0.3556)
		(layer "F.Cu")
		(net "GND")
	)
	(segment
		(start 352.3107 -156.2989)
		(end 352.3107 -155.9687)
		(width 0.254)
		(layer "F.Cu")
		(net "GND")
	)
	(segment
		(start 287.50514 -94.042738)
		(end 288.07664 -94.042738)
		(width 0.3048)
		(layer "F.Cu")
		(net "GND")
	)
	(segment
		(start 278.849836 -146.008852)
		(end 278.866346 -145.992342)
		(width 0.4064)
		(layer "F.Cu")
		(net "GND")
	)
	(segment
		(start 282.0162 -154.04592)
		(end 282.07208 -154.1018)
		(width 0.3556)
		(layer "F.Cu")
		(net "GND")
	)
	(segment
		(start 283.100272 -147.27174)
		(end 283.099764 -147.27174)
		(width 0.3556)
		(layer "F.Cu")
		(net "GND")
	)
	(segment
		(start 41.599358 -5.822442)
		(end 41.599358 -3.826256)
		(width 0.4064)
		(layer "F.Cu")
		(net "GND")
	)
	(segment
		(start 152.099518 0.444754)
		(end 152.099518 -0.821182)
		(width 0.4064)
		(layer "F.Cu")
		(net "GND")
	)
	(segment
		(start 72.900286 -72.43064)
		(end 72.328786 -72.43064)
		(width 0.254)
		(layer "F.Cu")
		(net "GND")
	)
	(segment
		(start 446.62725 -45.611796)
		(end 446.94094 -45.925486)
		(width 0.4064)
		(layer "F.Cu")
		(net "GND")
	)
	(segment
		(start 262.9662 -25.2476)
		(end 263.1186 -25.0952)
		(width 0.4064)
		(layer "F.Cu")
		(net "GND")
	)
	(segment
		(start 111.344202 -89.584784)
		(end 111.915702 -89.584784)
		(width 0.254)
		(layer "F.Cu")
		(net "GND")
	)
	(segment
		(start 74.749406 -18.757646)
		(end 74.749406 -20.023582)
		(width 0.4064)
		(layer "F.Cu")
		(net "GND")
	)
	(segment
		(start 442.9506 -8.4582)
		(end 442.876686 -8.384286)
		(width 0.254)
		(layer "F.Cu")
		(net "GND")
	)
	(segment
		(start 390.13765 -114.25555)
		(end 390.5377 -114.6556)
		(width 0.12446)
		(layer "F.Cu")
		(net "GND")
	)
	(segment
		(start 95.451168 -1.88468)
		(end 95.451168 -1.651)
		(width 0.4064)
		(layer "F.Cu")
		(net "GND")
	)
	(segment
		(start 279.699974 -155.600146)
		(end 279.699974 -156.87294)
		(width 0.4064)
		(layer "F.Cu")
		(net "GND")
	)
	(segment
		(start 84.060792 -54.104286)
		(end 83.773772 -54.599332)
		(width 0.254)
		(layer "F.Cu")
		(net "GND")
	)
	(segment
		(start 139.34948 -11.916156)
		(end 139.34948 -10.422382)
		(width 0.4064)
		(layer "F.Cu")
		(net "GND")
	)
	(segment
		(start 371.945154 -73.495154)
		(end 372.34495 -73.89495)
		(width 0.254)
		(layer "F.Cu")
		(net "GND")
	)
	(segment
		(start 74.617326 -99.17684)
		(end 74.045826 -99.17684)
		(width 0.254)
		(layer "F.Cu")
		(net "GND")
	)
	(segment
		(start 292.450012 -136.46785)
		(end 292.392608 -136.410446)
		(width 0.3556)
		(layer "F.Cu")
		(net "GND")
	)
	(segment
		(start 356.98684 -133.33857)
		(end 357.274368 -133.33857)
		(width 0.381)
		(layer "F.Cu")
		(net "GND")
	)
	(segment
		(start 136.799574 -156.87294)
		(end 136.799574 -155.67025)
		(width 0.3556)
		(layer "F.Cu")
		(net "GND")
	)
	(segment
		(start 73.758806 -59.057286)
		(end 73.187306 -59.057286)
		(width 0.254)
		(layer "F.Cu")
		(net "GND")
	)
	(segment
		(start 392.165078 -85.100922)
		(end 392.165078 -85.680042)
		(width 0.254)
		(layer "F.Cu")
		(net "GND")
	)
	(segment
		(start 152.099518 -10.422382)
		(end 152.099518 -11.927078)
		(width 0.4064)
		(layer "F.Cu")
		(net "GND")
	)
	(segment
		(start 124.81052 -3.737356)
		(end 124.89942 -3.826256)
		(width 0.4064)
		(layer "F.Cu")
		(net "GND")
	)
	(segment
		(start 76.449428 -156.87294)
		(end 76.449428 -155.511246)
		(width 0.4064)
		(layer "F.Cu")
		(net "GND")
	)
	(segment
		(start 113.348262 -52.437284)
		(end 113.348516 -52.4383)
		(width 0.254)
		(layer "F.Cu")
		(net "GND")
	)
	(segment
		(start 272.052288 -95.033084)
		(end 272.623788 -95.033084)
		(width 0.254)
		(layer "F.Cu")
		(net "GND")
	)
	(segment
		(start 479.933 -143.51)
		(end 479.806 -143.637)
		(width 0.254)
		(layer "F.Cu")
		(net "GND")
	)
	(segment
		(start 201.500486 -4.80949)
		(end 201.500486 -5.822442)
		(width 0.4064)
		(layer "F.Cu")
		(net "GND")
	)
	(segment
		(start 71.183246 -97.19564)
		(end 70.611746 -97.19564)
		(width 0.254)
		(layer "F.Cu")
		(net "GND")
	)
	(segment
		(start 58.599578 -133.076442)
		(end 58.599324 -133.076696)
		(width 0.4064)
		(layer "F.Cu")
		(net "GND")
	)
	(segment
		(start 143.599408 -142.6718)
		(end 143.599408 -144.364202)
		(width 0.4064)
		(layer "F.Cu")
		(net "GND")
	)
	(segment
		(start 309.449978 -137.67054)
		(end 309.450486 -137.67054)
		(width 0.4064)
		(layer "F.Cu")
		(net "GND")
	)
	(segment
		(start 70.499478 -137.67054)
		(end 70.499478 -136.448546)
		(width 0.4064)
		(layer "F.Cu")
		(net "GND")
	)
	(segment
		(start 232.749598 -86.29904)
		(end 232.101898 -86.29904)
		(width 0.254)
		(layer "F.Cu")
		(net "GND")
	)
	(segment
		(start 303.529746 -93.260164)
		(end 303.816766 -93.547184)
		(width 0.254)
		(layer "F.Cu")
		(net "GND")
	)
	(segment
		(start 300.099984 -156.87294)
		(end 300.100492 -156.87294)
		(width 0.4064)
		(layer "F.Cu")
		(net "GND")
	)
	(segment
		(start 33.949386 -152.992582)
		(end 33.754568 -153.1874)
		(width 0.3556)
		(layer "F.Cu")
		(net "GND")
	)
	(segment
		(start 303.041304 -16.696944)
		(end 303.499774 -16.238474)
		(width 0.4064)
		(layer "F.Cu")
		(net "GND")
	)
	(segment
		(start 299.524166 -78.193138)
		(end 300.095666 -78.193138)
		(width 0.254)
		(layer "F.Cu")
		(net "GND")
	)
	(segment
		(start 207.424528 -136.410446)
		(end 207.449928 -136.435846)
		(width 0.4064)
		(layer "F.Cu")
		(net "GND")
	)
	(segment
		(start 50.099468 -0.821182)
		(end 50.099468 0.457454)
		(width 0.4064)
		(layer "F.Cu")
		(net "GND")
	)
	(segment
		(start 134.249414 -5.822442)
		(end 134.249414 -7.509002)
		(width 0.4064)
		(layer "F.Cu")
		(net "GND")
	)
	(segment
		(start 31.463234 -93.625162)
		(end 31.463234 -94.114366)
		(width 0.508)
		(layer "F.Cu")
		(net "GND")
	)
	(segment
		(start 119.929402 -63.829184)
		(end 119.357902 -63.829184)
		(width 0.254)
		(layer "F.Cu")
		(net "GND")
	)
	(segment
		(start 141.899386 -142.6718)
		(end 141.899386 -144.462246)
		(width 0.4064)
		(layer "F.Cu")
		(net "GND")
	)
	(segment
		(start 290.0807 -88.594184)
		(end 290.6522 -88.594184)
		(width 0.254)
		(layer "F.Cu")
		(net "GND")
	)
	(segment
		(start 369.545108 -77.494892)
		(end 369.145058 -77.894942)
		(width 0.254)
		(layer "F.Cu")
		(net "GND")
	)
	(segment
		(start 376.376438 -108.077)
		(end 376.385836 -108.1278)
		(width 0.254)
		(layer "F.Cu")
		(net "GND")
	)
	(segment
		(start 278.849836 -9.275826)
		(end 278.849836 -9.131046)
		(width 0.254)
		(layer "F.Cu")
		(net "GND")
	)
	(segment
		(start 296.66184 -55.409338)
		(end 296.09034 -55.409338)
		(width 0.254)
		(layer "F.Cu")
		(net "GND")
	)
	(segment
		(start 113.849404 -142.6718)
		(end 113.849404 -142.677642)
		(width 0.508)
		(layer "F.Cu")
		(net "GND")
	)
	(segment
		(start 390.13765 -107.05465)
		(end 390.5377 -106.6546)
		(width 0.12446)
		(layer "F.Cu")
		(net "GND")
	)
	(segment
		(start 82.343752 -63.019686)
		(end 81.772252 -63.019686)
		(width 0.254)
		(layer "F.Cu")
		(net "GND")
	)
	(segment
		(start 172.2247 -71.6026)
		(end 172.72 -71.6026)
		(width 0.254)
		(layer "F.Cu")
		(net "GND")
	)
	(segment
		(start 435.5338 -14.5161)
		(end 435.2417 -14.224)
		(width 0.254)
		(layer "F.Cu")
		(net "GND")
	)
	(segment
		(start 389.485124 -94.790006)
		(end 389.984996 -95.205042)
		(width 0.254)
		(layer "F.Cu")
		(net "GND")
	)
	(segment
		(start 232.099866 -0.821182)
		(end 232.099866 -2.314956)
		(width 0.4064)
		(layer "F.Cu")
		(net "GND")
	)
	(segment
		(start 38.199314 -6.001766)
		(end 38.199568 -6.001512)
		(width 0.4064)
		(layer "F.Cu")
		(net "GND")
	)
	(segment
		(start 306.899818 -152.278842)
		(end 306.899818 -154.063446)
		(width 0.4064)
		(layer "F.Cu")
		(net "GND")
	)
	(segment
		(start 49.24933 -17.208246)
		(end 49.24933 -15.423896)
		(width 0.4064)
		(layer "F.Cu")
		(net "GND")
	)
	(segment
		(start 432.623468 -49.928526)
		(end 434.243988 -48.308006)
		(width 0.254)
		(layer "F.Cu")
		(net "GND")
	)
	(segment
		(start 125.711458 -11.916156)
		(end 125.749558 -11.878056)
		(width 0.4064)
		(layer "F.Cu")
		(net "GND")
	)
	(segment
		(start 136.799574 0.38735)
		(end 136.74217 0.444754)
		(width 0.3556)
		(layer "F.Cu")
		(net "GND")
	)
	(segment
		(start 472.600782 -116.993162)
		(end 472.600782 -118.397782)
		(width 0.4064)
		(layer "F.Cu")
		(net "GND")
	)
	(segment
		(start 118.218966 -52.93106)
		(end 118.212362 -52.932838)
		(width 0.254)
		(layer "F.Cu")
		(net "GND")
	)
	(segment
		(start 246.485664 -71.44004)
		(end 245.914164 -71.44004)
		(width 0.254)
		(layer "F.Cu")
		(net "GND")
	)
	(segment
		(start 387.73735 -114.25555)
		(end 388.11454 -114.63274)
		(width 0.254)
		(layer "F.Cu")
		(net "GND")
	)
	(segment
		(start 272.910808 -91.565984)
		(end 273.482308 -91.565984)
		(width 0.254)
		(layer "F.Cu")
		(net "GND")
	)
	(segment
		(start 476.52178 -139.96162)
		(end 476.52178 -140.335)
		(width 0.254)
		(layer "F.Cu")
		(net "GND")
	)
	(segment
		(start 304.349912 -11.916156)
		(end 303.025048 -11.938)
		(width 0.254)
		(layer "F.Cu")
		(net "GND")
	)
	(segment
		(start 239.904778 -51.132486)
		(end 240.476278 -51.132486)
		(width 0.254)
		(layer "F.Cu")
		(net "GND")
	)
	(segment
		(start 376.375422 -122.0724)
		(end 376.428 -122.355102)
		(width 0.254)
		(layer "F.Cu")
		(net "GND")
	)
	(segment
		(start 292.65626 -81.164938)
		(end 293.22776 -81.164938)
		(width 0.254)
		(layer "F.Cu")
		(net "GND")
	)
	(segment
		(start 57.74944 -20.023582)
		(end 57.74944 -18.757646)
		(width 0.4064)
		(layer "F.Cu")
		(net "GND")
	)
	(segment
		(start 136.812274 -52.437538)
		(end 136.240774 -52.437538)
		(width 0.254)
		(layer "F.Cu")
		(net "GND")
	)
	(segment
		(start 66.24955 -142.6718)
		(end 66.24955 -142.856712)
		(width 0.4064)
		(layer "F.Cu")
		(net "GND")
	)
	(segment
		(start 227.849938 -2.253488)
		(end 227.849938 -0.821182)
		(width 0.4064)
		(layer "F.Cu")
		(net "GND")
	)
	(segment
		(start 72.041766 -92.737686)
		(end 71.470266 -92.737686)
		(width 0.254)
		(layer "F.Cu")
		(net "GND")
	)
	(segment
		(start 40.749474 -155.600146)
		(end 40.749474 -156.87294)
		(width 0.4064)
		(layer "F.Cu")
		(net "GND")
	)
	(segment
		(start 69.466206 -90.26144)
		(end 68.894706 -90.26144)
		(width 0.254)
		(layer "F.Cu")
		(net "GND")
	)
	(segment
		(start 284.929834 -57.885584)
		(end 284.358334 -57.885584)
		(width 0.254)
		(layer "F.Cu")
		(net "GND")
	)
	(segment
		(start 221.050358 -20.023582)
		(end 221.04985 -20.023582)
		(width 0.4064)
		(layer "F.Cu")
		(net "GND")
	)
	(segment
		(start 282.250388 -142.6718)
		(end 282.24988 -142.677642)
		(width 0.3556)
		(layer "F.Cu")
		(net "GND")
	)
	(segment
		(start 43.29938 3.778758)
		(end 43.29938 3.042666)
		(width 0.3556)
		(layer "F.Cu")
		(net "GND")
	)
	(segment
		(start 277.774654 -99.986338)
		(end 278.061674 -100.481638)
		(width 0.254)
		(layer "F.Cu")
		(net "GND")
	)
	(segment
		(start 202.35037 -10.422382)
		(end 202.349862 -10.422382)
		(width 0.4064)
		(layer "F.Cu")
		(net "GND")
	)
	(segment
		(start 259.36321 -64.010286)
		(end 258.79171 -64.010286)
		(width 0.254)
		(layer "F.Cu")
		(net "GND")
	)
	(segment
		(start 9.81583 -46.744128)
		(end 11.249914 -45.310044)
		(width 0.508)
		(layer "F.Cu")
		(net "GND")
	)
	(segment
		(start 382.9304 -119.366538)
		(end 383.27965 -119.528844)
		(width 0.254)
		(layer "F.Cu")
		(net "GND")
	)
	(segment
		(start 364.611666 -107.469178)
		(end 364.611666 -109.187742)
		(width 0.254)
		(layer "F.Cu")
		(net "GND")
	)
	(segment
		(start 165.054026 -80.21193)
		(end 166.41953 -80.21193)
		(width 0.254)
		(layer "F.Cu")
		(net "GND")
	)
	(segment
		(start 274.627848 -52.932838)
		(end 274.627594 -52.932838)
		(width 0.254)
		(layer "F.Cu")
		(net "GND")
	)
	(segment
		(start 82.343752 -91.747086)
		(end 81.772252 -91.747086)
		(width 0.254)
		(layer "F.Cu")
		(net "GND")
	)
	(segment
		(start 469.40089 -115.625372)
		(end 469.18499 -115.409472)
		(width 0.4064)
		(layer "F.Cu")
		(net "GND")
	)
	(segment
		(start 310.0832 -154.062938)
		(end 310.122062 -154.1018)
		(width 0.3556)
		(layer "F.Cu")
		(net "GND")
	)
	(segment
		(start 78.051406 -63.51524)
		(end 77.479906 -63.51524)
		(width 0.254)
		(layer "F.Cu")
		(net "GND")
	)
	(segment
		(start 382.97739 -35.72002)
		(end 382.797304 -35.539934)
		(width 0.2032)
		(layer "F.Cu")
		(net "GND")
	)
	(segment
		(start 384.75412 -115.27282)
		(end 384.53695 -115.05565)
		(width 0.12446)
		(layer "F.Cu")
		(net "GND")
	)
	(segment
		(start 279.700482 -147.27174)
		(end 279.699974 -147.27174)
		(width 0.4064)
		(layer "F.Cu")
		(net "GND")
	)
	(segment
		(start 28.194 -76.454)
		(end 28.194 -76.808584)
		(width 0.254)
		(layer "F.Cu")
		(net "GND")
	)
	(segment
		(start 91.787218 -65.49644)
		(end 91.215718 -65.49644)
		(width 0.254)
		(layer "F.Cu")
		(net "GND")
	)
	(segment
		(start 296.948606 -88.594184)
		(end 297.520106 -88.594184)
		(width 0.3048)
		(layer "F.Cu")
		(net "GND")
	)
	(segment
		(start 127.655828 -58.381138)
		(end 128.227328 -58.381138)
		(width 0.254)
		(layer "F.Cu")
		(net "GND")
	)
	(segment
		(start 364.611666 -109.187742)
		(end 365.024924 -109.601)
		(width 0.254)
		(layer "F.Cu")
		(net "GND")
	)
	(segment
		(start 241.334798 -78.37424)
		(end 240.763298 -78.37424)
		(width 0.254)
		(layer "F.Cu")
		(net "GND")
	)
	(segment
		(start 77.192886 -83.822286)
		(end 76.621386 -83.822286)
		(width 0.254)
		(layer "F.Cu")
		(net "GND")
	)
	(segment
		(start 290.750498 -156.87294)
		(end 290.750498 -155.613354)
		(width 0.3556)
		(layer "F.Cu")
		(net "GND")
	)
	(segment
		(start 387.73735 -120.387364)
		(end 387.24205 -120.15724)
		(width 0.254)
		(layer "F.Cu")
		(net "GND")
	)
	(segment
		(start 77.299312 -5.822188)
		(end 77.299566 -5.822442)
		(width 0.4064)
		(layer "F.Cu")
		(net "GND")
	)
	(segment
		(start 274.937728 -67.21348)
		(end 274.919186 -67.21348)
		(width 0.254)
		(layer "F.Cu")
		(net "GND")
	)
	(segment
		(start 383.11328 -103.15321)
		(end 383.27965 -102.98684)
		(width 0.254)
		(layer "F.Cu")
		(net "GND")
	)
	(segment
		(start 195.58 -69.324474)
		(end 195.330826 -69.573648)
		(width 0.508)
		(layer "F.Cu")
		(net "GND")
	)
	(segment
		(start 250.778264 -57.076086)
		(end 250.206764 -57.076086)
		(width 0.254)
		(layer "F.Cu")
		(net "GND")
	)
	(segment
		(start 283.100272 -0.821182)
		(end 283.099764 -0.821182)
		(width 0.4064)
		(layer "F.Cu")
		(net "GND")
	)
	(segment
		(start 36.03752 -13.948156)
		(end 36.499546 -14.410182)
		(width 0.4064)
		(layer "F.Cu")
		(net "GND")
	)
	(segment
		(start 112.926368 -149.8092)
		(end 112.397032 -149.8092)
		(width 0.4064)
		(layer "F.Cu")
		(net "GND")
	)
	(segment
		(start 486.814622 -141.682978)
		(end 487.554016 -141.682978)
		(width 0.254)
		(layer "F.Cu")
		(net "GND")
	)
	(segment
		(start 44.092114 0.457454)
		(end 44.092114 0.406654)
		(width 0.4064)
		(layer "F.Cu")
		(net "GND")
	)
	(segment
		(start 142.250414 -84.631784)
		(end 142.898114 -84.631784)
		(width 0.254)
		(layer "F.Cu")
		(net "GND")
	)
	(segment
		(start 355.24948 -134.853934)
		(end 354.36048 -134.853934)
		(width 0.508)
		(layer "F.Cu")
		(net "GND")
	)
	(segment
		(start 204.899768 -17.208246)
		(end 204.899768 -15.423642)
		(width 0.4064)
		(layer "F.Cu")
		(net "GND")
	)
	(segment
		(start 383.27965 -120.15724)
		(end 383.77495 -120.387364)
		(width 0.254)
		(layer "F.Cu")
		(net "GND")
	)
	(segment
		(start 280.549858 -142.677642)
		(end 280.549858 -144.364202)
		(width 0.4064)
		(layer "F.Cu")
		(net "GND")
	)
	(segment
		(start 387.73735 -123.821444)
		(end 387.876796 -124.206)
		(width 0.254)
		(layer "F.Cu")
		(net "GND")
	)
	(segment
		(start 248.202704 -82.33664)
		(end 247.631204 -82.33664)
		(width 0.254)
		(layer "F.Cu")
		(net "GND")
	)
	(segment
		(start 226.9998 -3.940556)
		(end 226.9998 -5.822442)
		(width 0.4064)
		(layer "F.Cu")
		(net "GND")
	)
	(segment
		(start 416.289998 -36.534598)
		(end 416.690048 -36.134548)
		(width 0.254)
		(layer "F.Cu")
		(net "GND")
	)
	(segment
		(start 293.51478 -82.650584)
		(end 294.08628 -82.650584)
		(width 0.254)
		(layer "F.Cu")
		(net "GND")
	)
	(segment
		(start 74.617326 -72.43064)
		(end 74.045826 -72.43064)
		(width 0.254)
		(layer "F.Cu")
		(net "GND")
	)
	(segment
		(start 215.949784 -7.509002)
		(end 215.85174 -7.607046)
		(width 0.4064)
		(layer "F.Cu")
		(net "GND")
	)
	(segment
		(start 59.449462 -11.916156)
		(end 59.449462 -10.422382)
		(width 0.4064)
		(layer "F.Cu")
		(net "GND")
	)
	(segment
		(start 177.43424 -95.10522)
		(end 176.836832 -95.10522)
		(width 0.254)
		(layer "F.Cu")
		(net "GND")
	)
	(segment
		(start 27.432 -63.559436)
		(end 27.962352 -64.089788)
		(width 0.508)
		(layer "F.Cu")
		(net "GND")
	)
	(segment
		(start 101.230684 -53.113686)
		(end 100.659184 -53.113686)
		(width 0.254)
		(layer "F.Cu")
		(net "GND")
	)
	(segment
		(start 227.849938 -9.21385)
		(end 227.792534 -9.156446)
		(width 0.3556)
		(layer "F.Cu")
		(net "GND")
	)
	(segment
		(start 55.19928 -143.492474)
		(end 54.74081 -143.950944)
		(width 0.4064)
		(layer "F.Cu")
		(net "GND")
	)
	(segment
		(start 381.29845 -105.813098)
		(end 381.313944 -105.813098)
		(width 0.254)
		(layer "F.Cu")
		(net "GND")
	)
	(segment
		(start 275.486114 -60.362338)
		(end 274.914614 -60.362338)
		(width 0.254)
		(layer "F.Cu")
		(net "GND")
	)
	(segment
		(start 321.558412 -130.474212)
		(end 322.066412 -130.474212)
		(width 0.4064)
		(layer "F.Cu")
		(net "GND")
	)
	(segment
		(start 196.154294 -85.613748)
		(end 196.273928 -85.733382)
		(width 0.4064)
		(layer "F.Cu")
		(net "GND")
	)
	(segment
		(start 242.300506 1.994916)
		(end 242.299744 1.994154)
		(width 0.4064)
		(layer "F.Cu")
		(net "GND")
	)
	(segment
		(start 55.19928 -142.677896)
		(end 55.19928 -143.492474)
		(width 0.4064)
		(layer "F.Cu")
		(net "GND")
	)
	(segment
		(start 391.212832 -102.98303)
		(end 391.69975 -102.756716)
		(width 0.254)
		(layer "F.Cu")
		(net "GND")
	)
	(segment
		(start 303.529746 -85.127338)
		(end 302.958246 -85.127338)
		(width 0.3048)
		(layer "F.Cu")
		(net "GND")
	)
	(segment
		(start 385.844288 -112.948212)
		(end 386.13715 -112.65535)
		(width 0.12446)
		(layer "F.Cu")
		(net "GND")
	)
	(segment
		(start 75.475846 -57.076086)
		(end 74.904346 -57.076086)
		(width 0.254)
		(layer "F.Cu")
		(net "GND")
	)
	(segment
		(start 226.7966 -16.357854)
		(end 226.9998 -16.154654)
		(width 0.3556)
		(layer "F.Cu")
		(net "GND")
	)
	(segment
		(start 283.099764 -20.023582)
		(end 283.099764 -21.455888)
		(width 0.4064)
		(layer "F.Cu")
		(net "GND")
	)
	(segment
		(start 108.197396 -52.437284)
		(end 108.19765 -52.438554)
		(width 0.254)
		(layer "F.Cu")
		(net "GND")
	)
	(segment
		(start 170.815 -71.5264)
		(end 171.704 -71.5264)
		(width 0.254)
		(layer "F.Cu")
		(net "GND")
	)
	(segment
		(start 81.582768 -149.8092)
		(end 82.459068 -149.8092)
		(width 0.4064)
		(layer "F.Cu")
		(net "GND")
	)
	(segment
		(start 213.399878 -10.422382)
		(end 213.399878 -9.156446)
		(width 0.4064)
		(layer "F.Cu")
		(net "GND")
	)
	(segment
		(start 229.54996 -133.076442)
		(end 229.549706 -133.076696)
		(width 0.4064)
		(layer "F.Cu")
		(net "GND")
	)
	(segment
		(start 106.193336 -62.838584)
		(end 105.571036 -62.838584)
		(width 0.254)
		(layer "F.Cu")
		(net "GND")
	)
	(segment
		(start 86.636352 -60.54344)
		(end 86.064852 -60.54344)
		(width 0.254)
		(layer "F.Cu")
		(net "GND")
	)
	(segment
		(start 317.09995 -148.782278)
		(end 317.09995 -149.813518)
		(width 0.4064)
		(layer "F.Cu")
		(net "GND")
	)
	(segment
		(start 107.910376 -91.565984)
		(end 108.481876 -91.565984)
		(width 0.254)
		(layer "F.Cu")
		(net "GND")
	)
	(segment
		(start 232.950512 -13.364718)
		(end 232.94975 -13.363956)
		(width 0.4064)
		(layer "F.Cu")
		(net "GND")
	)
	(segment
		(start 57.74944 -2.314956)
		(end 57.74944 -0.821182)
		(width 0.4064)
		(layer "F.Cu")
		(net "GND")
	)
	(segment
		(start 367.1062 -109.5502)
		(end 367.1062 -108.614972)
		(width 0.254)
		(layer "F.Cu")
		(net "GND")
	)
	(segment
		(start 32.249364 -134.763002)
		(end 32.15132 -134.861046)
		(width 0.4064)
		(layer "F.Cu")
		(net "GND")
	)
	(segment
		(start 291.79774 -92.556584)
		(end 292.36924 -92.556584)
		(width 0.254)
		(layer "F.Cu")
		(net "GND")
	)
	(segment
		(start 249.919744 -79.36484)
		(end 249.348244 -79.36484)
		(width 0.254)
		(layer "F.Cu")
		(net "GND")
	)
	(segment
		(start 350.0628 -157.2768)
		(end 350.0755 -157.2895)
		(width 0.508)
		(layer "F.Cu")
		(net "GND")
	)
	(segment
		(start 138.499342 -142.6718)
		(end 138.499342 -143.492474)
		(width 0.4064)
		(layer "F.Cu")
		(net "GND")
	)
	(segment
		(start 243.8908 -149.8092)
		(end 243.586 -150.114)
		(width 0.4572)
		(layer "F.Cu")
		(net "GND")
	)
	(segment
		(start 399.12925 -119.528844)
		(end 399.528538 -118.996714)
		(width 0.254)
		(layer "F.Cu")
		(net "GND")
	)
	(segment
		(start 295.85031 3.778758)
		(end 295.849802 3.778758)
		(width 0.4064)
		(layer "F.Cu")
		(net "GND")
	)
	(segment
		(start 297.550332 -5.822442)
		(end 297.549824 -5.822442)
		(width 0.4064)
		(layer "F.Cu")
		(net "GND")
	)
	(segment
		(start 242.193318 -63.019686)
		(end 241.621818 -63.019686)
		(width 0.254)
		(layer "F.Cu")
		(net "GND")
	)
	(segment
		(start 78.14945 -18.766282)
		(end 78.14945 -20.023582)
		(width 0.4064)
		(layer "F.Cu")
		(net "GND")
	)
	(segment
		(start 278.849836 -15.423642)
		(end 278.849836 -14.13002)
		(width 0.4064)
		(layer "F.Cu")
		(net "GND")
	)
	(segment
		(start 391.670286 -3.506724)
		(end 391.5156 -3.352038)
		(width 0.4064)
		(layer "F.Cu")
		(net "GND")
	)
	(segment
		(start 137.957814 -88.099138)
		(end 138.529314 -88.099138)
		(width 0.254)
		(layer "F.Cu")
		(net "GND")
	)
	(segment
		(start 236.350302 3.778758)
		(end 236.349794 3.778758)
		(width 0.3556)
		(layer "F.Cu")
		(net "GND")
	)
	(segment
		(start 223.60001 -133.076442)
		(end 223.599756 -133.076696)
		(width 0.4064)
		(layer "F.Cu")
		(net "GND")
	)
	(segment
		(start 215.949784 -5.822442)
		(end 215.949784 -7.509002)
		(width 0.4064)
		(layer "F.Cu")
		(net "GND")
	)
	(segment
		(start 151.24938 -3.762756)
		(end 151.24938 -5.822442)
		(width 0.4064)
		(layer "F.Cu")
		(net "GND")
	)
	(segment
		(start 41.599358 -7.509002)
		(end 41.599358 -5.822442)
		(width 0.4064)
		(layer "F.Cu")
		(net "GND")
	)
	(segment
		(start 239.617758 -50.63744)
		(end 239.904778 -51.132486)
		(width 0.254)
		(layer "F.Cu")
		(net "GND")
	)
	(segment
		(start 385.449064 -100.656898)
		(end 385.75615 -100.41128)
		(width 0.254)
		(layer "F.Cu")
		(net "GND")
	)
	(segment
		(start 118.499382 -52.437284)
		(end 118.50116 -52.443634)
		(width 0.254)
		(layer "F.Cu")
		(net "GND")
	)
	(segment
		(start 77.192886 -85.803486)
		(end 76.621386 -85.803486)
		(width 0.254)
		(layer "F.Cu")
		(net "GND")
	)
	(segment
		(start 382.797304 -35.539934)
		(end 382.797304 -35.270948)
		(width 0.2032)
		(layer "F.Cu")
		(net "GND")
	)
	(segment
		(start 90.070178 -60.54344)
		(end 89.498678 -60.54344)
		(width 0.254)
		(layer "F.Cu")
		(net "GND")
	)
	(segment
		(start 85.761068 -140.208)
		(end 84.910168 -140.208)
		(width 0.4064)
		(layer "F.Cu")
		(net "GND")
	)
	(segment
		(start 119.34063 -16.696944)
		(end 119.7991 -16.238474)
		(width 0.4064)
		(layer "F.Cu")
		(net "GND")
	)
	(segment
		(start 33.949386 -133.790182)
		(end 33.754568 -133.985)
		(width 0.3556)
		(layer "F.Cu")
		(net "GND")
	)
	(segment
		(start 201.037952 -4.346956)
		(end 201.500486 -4.80949)
		(width 0.4064)
		(layer "F.Cu")
		(net "GND")
	)
	(segment
		(start 243.910104 -66.982086)
		(end 243.338604 -66.982086)
		(width 0.254)
		(layer "F.Cu")
		(net "GND")
	)
	(segment
		(start 4.31546 -133.38302)
		(end 5.20446 -133.38302)
		(width 0.4064)
		(layer "F.Cu")
		(net "GND")
	)
	(segment
		(start 390.13765 -110.25505)
		(end 389.99668 -110.11408)
		(width 0.12446)
		(layer "F.Cu")
		(net "GND")
	)
	(segment
		(start 239.750346 -147.27174)
		(end 239.749838 -147.27174)
		(width 0.4064)
		(layer "F.Cu")
		(net "GND")
	)
	(segment
		(start 400.487134 -93.544898)
		(end 400.487134 -92.260674)
		(width 0.254)
		(layer "F.Cu")
		(net "GND")
	)
	(segment
		(start 201.499724 -133.891274)
		(end 201.041254 -134.349744)
		(width 0.4064)
		(layer "F.Cu")
		(net "GND")
	)
	(segment
		(start 117.249448 -142.6718)
		(end 117.249448 -143.403574)
		(width 0.3556)
		(layer "F.Cu")
		(net "GND")
	)
	(segment
		(start 30.549342 -7.086346)
		(end 30.549342 -5.822442)
		(width 0.4064)
		(layer "F.Cu")
		(net "GND")
	)
	(segment
		(start 458.0636 -28.956)
		(end 458.9018 -29.7942)
		(width 0.381)
		(layer "F.Cu")
		(net "GND")
	)
	(segment
		(start 94.8817 -150.7871)
		(end 95.555816 -150.7871)
		(width 0.4572)
		(layer "F.Cu")
		(net "GND")
	)
	(segment
		(start 281.400504 -155.613354)
		(end 281.399996 -155.612846)
		(width 0.3556)
		(layer "F.Cu")
		(net "GND")
	)
	(segment
		(start 21.863812 -67.8053)
		(end 21.2725 -67.8053)
		(width 0.254)
		(layer "F.Cu")
		(net "GND")
	)
	(segment
		(start 232.099866 -21.517356)
		(end 232.099866 -20.023582)
		(width 0.4064)
		(layer "F.Cu")
		(net "GND")
	)
	(segment
		(start 275.486114 -90.080338)
		(end 276.057614 -90.080338)
		(width 0.254)
		(layer "F.Cu")
		(net "GND")
	)
	(segment
		(start 208.0768 -153.237946)
		(end 208.0768 -154.056588)
		(width 0.3556)
		(layer "F.Cu")
		(net "GND")
	)
	(segment
		(start 7.819644 5.196332)
		(end 7.333234 5.196332)
		(width 0.254)
		(layer "F.Cu")
		(net "GND")
	)
	(segment
		(start 130.231388 -82.650584)
		(end 130.802888 -82.650584)
		(width 0.254)
		(layer "F.Cu")
		(net "GND")
	)
	(segment
		(start 449.3514 -53.2638)
		(end 449.349876 -53.262276)
		(width 0.4064)
		(layer "F.Cu")
		(net "GND")
	)
	(segment
		(start 291.600382 3.778758)
		(end 291.599874 3.778758)
		(width 0.3556)
		(layer "F.Cu")
		(net "GND")
	)
	(segment
		(start 278.899112 -69.969888)
		(end 279.4508 -69.4182)
		(width 0.254)
		(layer "F.Cu")
		(net "GND")
	)
	(segment
		(start 281.495754 -65.810384)
		(end 280.924254 -65.810384)
		(width 0.254)
		(layer "F.Cu")
		(net "GND")
	)
	(segment
		(start 119.070882 -62.343538)
		(end 118.499382 -62.343538)
		(width 0.254)
		(layer "F.Cu")
		(net "GND")
	)
	(segment
		(start 383.985008 -126.165102)
		(end 383.878582 -126.058676)
		(width 0.254)
		(layer "F.Cu")
		(net "GND")
	)
	(segment
		(start 278.062944 -52.932584)
		(end 278.348948 -52.4383)
		(width 0.254)
		(layer "F.Cu")
		(net "GND")
	)
	(segment
		(start 52.649374 -3.940556)
		(end 52.649374 -5.822442)
		(width 0.4064)
		(layer "F.Cu")
		(net "GND")
	)
	(segment
		(start 213.399878 -156.87294)
		(end 213.399878 -155.612846)
		(width 0.4064)
		(layer "F.Cu")
		(net "GND")
	)
	(segment
		(start 309.450486 -147.27174)
		(end 309.449978 -147.27174)
		(width 0.4064)
		(layer "F.Cu")
		(net "GND")
	)
	(segment
		(start 199.799956 -10.422382)
		(end 199.799956 -11.854688)
		(width 0.4064)
		(layer "F.Cu")
		(net "GND")
	)
	(segment
		(start 195.722494 -61.205364)
		(end 195.21424 -61.713618)
		(width 0.508)
		(layer "F.Cu")
		(net "GND")
	)
	(segment
		(start 402.223986 -81.548986)
		(end 402.223986 -82.175096)
		(width 0.254)
		(layer "F.Cu")
		(net "GND")
	)
	(segment
		(start 242.193318 -93.72854)
		(end 241.621818 -93.72854)
		(width 0.254)
		(layer "F.Cu")
		(net "GND")
	)
	(segment
		(start 463.003392 -37.067998)
		(end 463.29092 -37.067998)
		(width 0.4064)
		(layer "F.Cu")
		(net "GND")
	)
	(segment
		(start 41.599358 -153.965402)
		(end 41.501314 -154.063446)
		(width 0.4064)
		(layer "F.Cu")
		(net "GND")
	)
	(segment
		(start 281.495754 -51.941984)
		(end 281.495754 -50.952146)
		(width 0.2286)
		(layer "F.Cu")
		(net "GND")
	)
	(segment
		(start 137.957814 -59.371484)
		(end 138.529314 -59.371484)
		(width 0.254)
		(layer "F.Cu")
		(net "GND")
	)
	(segment
		(start 313.700414 -0.821182)
		(end 313.699906 -0.821182)
		(width 0.4064)
		(layer "F.Cu")
		(net "GND")
	)
	(segment
		(start 457.350114 -58.954924)
		(end 457.350114 -57.596024)
		(width 0.381)
		(layer "F.Cu")
		(net "GND")
	)
	(segment
		(start 351.17786 -140.47978)
		(end 353.494086 -140.47978)
		(width 0.508)
		(layer "F.Cu")
		(net "GND")
	)
	(segment
		(start 166.172134 -75.915266)
		(end 166.243 -75.8444)
		(width 0.254)
		(layer "F.Cu")
		(net "GND")
	)
	(segment
		(start 90.153236 -149.444964)
		(end 90.626692 -149.444964)
		(width 0.4064)
		(layer "F.Cu")
		(net "GND")
	)
	(segment
		(start 76.449428 -137.67054)
		(end 76.449428 -136.410446)
		(width 0.4064)
		(layer "F.Cu")
		(net "GND")
	)
	(segment
		(start 214.250524 -152.273)
		(end 214.250016 -152.278842)
		(width 0.4064)
		(layer "F.Cu")
		(net "GND")
	)
	(segment
		(start 290.93922 -88.099138)
		(end 291.51072 -88.099138)
		(width 0.254)
		(layer "F.Cu")
		(net "GND")
	)
	(segment
		(start 219.741242 -16.696944)
		(end 220.199712 -16.238474)
		(width 0.4064)
		(layer "F.Cu")
		(net "GND")
	)
	(segment
		(start 252.495304 -53.113686)
		(end 253.640844 -53.113686)
		(width 0.254)
		(layer "F.Cu")
		(net "GND")
	)
	(segment
		(start 213.399878 -148.771356)
		(end 213.399878 -147.27174)
		(width 0.4064)
		(layer "F.Cu")
		(net "GND")
	)
	(segment
		(start 88.353392 -87.28964)
		(end 87.781892 -87.28964)
		(width 0.254)
		(layer "F.Cu")
		(net "GND")
	)
	(segment
		(start 143.599408 -134.763002)
		(end 143.501364 -134.861046)
		(width 0.4064)
		(layer "F.Cu")
		(net "GND")
	)
	(segment
		(start 72.1995 -137.67054)
		(end 72.1995 -136.46785)
		(width 0.3556)
		(layer "F.Cu")
		(net "GND")
	)
	(segment
		(start 288.07664 -68.287138)
		(end 287.50514 -68.287138)
		(width 0.254)
		(layer "F.Cu")
		(net "GND")
	)
	(segment
		(start 52.448968 -7.622794)
		(end 52.471574 -7.6454)
		(width 0.3556)
		(layer "F.Cu")
		(net "GND")
	)
	(segment
		(start 149.549358 -152.273)
		(end 149.549358 -154.063446)
		(width 0.4064)
		(layer "F.Cu")
		(net "GND")
	)
	(segment
		(start 402.134832 -25.654)
		(end 401.955 -25.474168)
		(width 0.254)
		(layer "F.Cu")
		(net "GND")
	)
	(segment
		(start 74.617326 -78.37424)
		(end 74.045826 -78.37424)
		(width 0.254)
		(layer "F.Cu")
		(net "GND")
	)
	(segment
		(start 214.250524 -5.822442)
		(end 214.250524 -7.606284)
		(width 0.4064)
		(layer "F.Cu")
		(net "GND")
	)
	(segment
		(start 281.495754 -56.894984)
		(end 280.924254 -56.894984)
		(width 0.254)
		(layer "F.Cu")
		(net "GND")
	)
	(segment
		(start 136.240774 -56.399938)
		(end 136.812274 -56.399938)
		(width 0.1016)
		(layer "F.Cu")
		(net "GND")
	)
	(segment
		(start 58.599578 -133.0706)
		(end 58.599578 -133.076442)
		(width 0.4064)
		(layer "F.Cu")
		(net "GND")
	)
	(segment
		(start 391.73785 -109.45495)
		(end 392.1379 -109.0549)
		(width 0.12446)
		(layer "F.Cu")
		(net "GND")
	)
	(segment
		(start 86.923372 -98.681286)
		(end 87.494872 -98.681286)
		(width 0.254)
		(layer "F.Cu")
		(net "GND")
	)
	(segment
		(start 74.617326 -52.618386)
		(end 74.045826 -52.618386)
		(width 0.254)
		(layer "F.Cu")
		(net "GND")
	)
	(segment
		(start 116.495322 -66.800984)
		(end 115.923822 -66.800984)
		(width 0.254)
		(layer "F.Cu")
		(net "GND")
	)
	(segment
		(start 195.549774 -5.822442)
		(end 195.549774 -4.277106)
		(width 0.4064)
		(layer "F.Cu")
		(net "GND")
	)
	(segment
		(start 84.060792 -59.057286)
		(end 83.489292 -59.057286)
		(width 0.254)
		(layer "F.Cu")
		(net "GND")
	)
	(segment
		(start 117.640862 -54.913784)
		(end 118.212362 -54.913784)
		(width 0.254)
		(layer "F.Cu")
		(net "GND")
	)
	(segment
		(start 313.647836 -26.1874)
		(end 314.2996 -26.1874)
		(width 0.254)
		(layer "F.Cu")
		(net "GND")
	)
	(segment
		(start 317.09995 -140.161518)
		(end 317.146432 -140.208)
		(width 0.4064)
		(layer "F.Cu")
		(net "GND")
	)
	(segment
		(start 134.249414 -133.0706)
		(end 134.249414 -134.763002)
		(width 0.4064)
		(layer "F.Cu")
		(net "GND")
	)
	(segment
		(start 237.199932 -20.023582)
		(end 237.199932 -21.455888)
		(width 0.4064)
		(layer "F.Cu")
		(net "GND")
	)
	(segment
		(start 278.061674 -93.547184)
		(end 278.633174 -93.547184)
		(width 0.254)
		(layer "F.Cu")
		(net "GND")
	)
	(segment
		(start 284.800294 -142.6718)
		(end 284.799786 -142.677642)
		(width 0.4064)
		(layer "F.Cu")
		(net "GND")
	)
	(segment
		(start 376.682 -89.315036)
		(end 376.725688 -89.358724)
		(width 0.254)
		(layer "F.Cu")
		(net "GND")
	)
	(segment
		(start 300.095666 -68.287138)
		(end 300.095666 -68.078604)
		(width 0.254)
		(layer "F.Cu")
		(net "GND")
	)
	(segment
		(start 197.250304 -133.0706)
		(end 197.249796 -133.076442)
		(width 0.4064)
		(layer "F.Cu")
		(net "GND")
	)
	(segment
		(start 368.967004 -26.20137)
		(end 368.255296 -25.489662)
		(width 0.254)
		(layer "F.Cu")
		(net "GND")
	)
	(segment
		(start 30.549342 -143.946626)
		(end 30.503368 -143.9926)
		(width 0.4064)
		(layer "F.Cu")
		(net "GND")
	)
	(segment
		(start 397.2052 -145.8722)
		(end 397.2052 -147.071588)
		(width 0.254)
		(layer "F.Cu")
		(net "GND")
	)
	(segment
		(start 31.39948 -11.916156)
		(end 31.468568 -11.985244)
		(width 0.381)
		(layer "F.Cu")
		(net "GND")
	)
	(segment
		(start 375.504964 -122.854974)
		(end 376.335036 -122.854974)
		(width 0.254)
		(layer "F.Cu")
		(net "GND")
	)
	(segment
		(start 151.24938 -13.363956)
		(end 151.24938 -15.423642)
		(width 0.4064)
		(layer "F.Cu")
		(net "GND")
	)
	(segment
		(start 208.299812 -142.677642)
		(end 208.299812 -143.413734)
		(width 0.3556)
		(layer "F.Cu")
		(net "GND")
	)
	(segment
		(start 132.806694 -85.127338)
		(end 133.378194 -85.127338)
		(width 0.254)
		(layer "F.Cu")
		(net "GND")
	)
	(segment
		(start 214.249762 -133.076696)
		(end 214.249762 -134.861046)
		(width 0.4064)
		(layer "F.Cu")
		(net "GND")
	)
	(segment
		(start 282.354274 -66.305938)
		(end 281.782774 -66.305938)
		(width 0.254)
		(layer "F.Cu")
		(net "GND")
	)
	(segment
		(start 317.09995 -20.023582)
		(end 317.09995 -21.528278)
		(width 0.4064)
		(layer "F.Cu")
		(net "GND")
	)
	(segment
		(start 396.15745 -112.660684)
		(end 395.66215 -112.43056)
		(width 0.254)
		(layer "F.Cu")
		(net "GND")
	)
	(segment
		(start 488.1372 -35.534092)
		(end 488.1372 -34.8742)
		(width 0.254)
		(layer "F.Cu")
		(net "GND")
	)
	(segment
		(start 293.51478 -68.782184)
		(end 294.08628 -68.782184)
		(width 0.254)
		(layer "F.Cu")
		(net "GND")
	)
	(segment
		(start 418.873686 -9.693656)
		(end 418.864542 -9.7028)
		(width 0.254)
		(layer "F.Cu")
		(net "GND")
	)
	(segment
		(start 311.092596 -155.612846)
		(end 311.15 -155.67025)
		(width 0.3556)
		(layer "F.Cu")
		(net "GND")
	)
	(segment
		(start 97.796858 -63.019686)
		(end 97.225358 -63.019686)
		(width 0.254)
		(layer "F.Cu")
		(net "GND")
	)
	(segment
		(start 83.202272 -57.57164)
		(end 82.630772 -57.57164)
		(width 0.254)
		(layer "F.Cu")
		(net "GND")
	)
	(segment
		(start 316.25032 -142.6718)
		(end 316.249812 -142.677642)
		(width 0.4064)
		(layer "F.Cu")
		(net "GND")
	)
	(segment
		(start 462.201006 -116.993162)
		(end 462.201006 -118.615968)
		(width 0.4064)
		(layer "F.Cu")
		(net "GND")
	)
	(segment
		(start 350.05518 -2.257552)
		(end 349.741236 -2.257552)
		(width 0.381)
		(layer "F.Cu")
		(net "GND")
	)
	(segment
		(start 300.736 -154.065732)
		(end 300.772068 -154.1018)
		(width 0.3556)
		(layer "F.Cu")
		(net "GND")
	)
	(segment
		(start 147.849336 -15.423642)
		(end 147.849336 -14.409928)
		(width 0.4064)
		(layer "F.Cu")
		(net "GND")
	)
	(segment
		(start 295.85031 -142.6718)
		(end 295.849802 -142.677642)
		(width 0.4064)
		(layer "F.Cu")
		(net "GND")
	)
	(segment
		(start 396.15745 -116.72316)
		(end 396.65275 -116.953284)
		(width 0.254)
		(layer "F.Cu")
		(net "GND")
	)
	(segment
		(start 406.88006 -150.247604)
		(end 406.782016 -150.247604)
		(width 0.3556)
		(layer "F.Cu")
		(net "GND")
	)
	(segment
		(start 6.1976 -132.67944)
		(end 5.49402 -133.38302)
		(width 0.4064)
		(layer "F.Cu")
		(net "GND")
	)
	(segment
		(start 312.357516 -32.747458)
		(end 313.299602 -32.747458)
		(width 0.4064)
		(layer "F.Cu")
		(net "GND")
	)
	(segment
		(start 301.742602 -136.410446)
		(end 301.742602 -136.397746)
		(width 0.3556)
		(layer "F.Cu")
		(net "GND")
	)
	(segment
		(start 456.477878 -3.36423)
		(end 456.863704 -2.978404)
		(width 0.254)
		(layer "F.Cu")
		(net "GND")
	)
	(segment
		(start 4.879848 -126.565152)
		(end 4.5085 -126.565152)
		(width 0.2032)
		(layer "F.Cu")
		(net "GND")
	)
	(segment
		(start 33.754568 -17.229582)
		(end 33.754568 -16.3322)
		(width 0.3556)
		(layer "F.Cu")
		(net "GND")
	)
	(segment
		(start 301.241206 -81.164938)
		(end 301.812706 -81.164938)
		(width 0.254)
		(layer "F.Cu")
		(net "GND")
	)
	(segment
		(start 125.080268 -92.556584)
		(end 125.651768 -92.556584)
		(width 0.254)
		(layer "F.Cu")
		(net "GND")
	)
	(segment
		(start 306.050442 -147.27174)
		(end 306.049934 -147.27174)
		(width 0.4064)
		(layer "F.Cu")
		(net "GND")
	)
	(segment
		(start 244.768624 -76.39304)
		(end 244.197124 -76.39304)
		(width 0.254)
		(layer "F.Cu")
		(net "GND")
	)
	(segment
		(start 482.00056 -35.5854)
		(end 481.494592 -35.5854)
		(width 0.254)
		(layer "F.Cu")
		(net "GND")
	)
	(segment
		(start 70.324726 -65.000886)
		(end 69.753226 -65.000886)
		(width 0.254)
		(layer "F.Cu")
		(net "GND")
	)
	(segment
		(start 305.199796 -15.423642)
		(end 305.199796 -13.363956)
		(width 0.4064)
		(layer "F.Cu")
		(net "GND")
	)
	(segment
		(start 119.929402 -52.932838)
		(end 119.371618 -53.8988)
		(width 0.254)
		(layer "F.Cu")
		(net "GND")
	)
	(segment
		(start 288.36366 -69.772784)
		(end 288.93516 -69.772784)
		(width 0.254)
		(layer "F.Cu")
		(net "GND")
	)
	(segment
		(start 201.500486 3.778758)
		(end 201.500486 2.964688)
		(width 0.4064)
		(layer "F.Cu")
		(net "GND")
	)
	(segment
		(start 314.54979 -142.677642)
		(end 314.54979 -144.462246)
		(width 0.4064)
		(layer "F.Cu")
		(net "GND")
	)
	(segment
		(start 135.735568 -17.210532)
		(end 135.735568 -16.382746)
		(width 0.3556)
		(layer "F.Cu")
		(net "GND")
	)
	(segment
		(start 442.076586 -5.247386)
		(end 442.214 -5.3848)
		(width 0.254)
		(layer "F.Cu")
		(net "GND")
	)
	(segment
		(start 315.683392 -32.172402)
		(end 313.874658 -32.172402)
		(width 0.4064)
		(layer "F.Cu")
		(net "GND")
	)
	(segment
		(start 286.07512 -54.913784)
		(end 286.64662 -54.913784)
		(width 0.254)
		(layer "F.Cu")
		(net "GND")
	)
	(segment
		(start 289.049968 -137.67054)
		(end 289.049968 -136.397746)
		(width 0.4064)
		(layer "F.Cu")
		(net "GND")
	)
	(segment
		(start 76.334366 -84.31784)
		(end 75.762866 -84.31784)
		(width 0.254)
		(layer "F.Cu")
		(net "GND")
	)
	(segment
		(start 389.33755 -107.05465)
		(end 389.7376 -106.6546)
		(width 0.254)
		(layer "F.Cu")
		(net "GND")
	)
	(segment
		(start 79.768192 -98.18624)
		(end 79.196692 -98.18624)
		(width 0.254)
		(layer "F.Cu")
		(net "GND")
	)
	(segment
		(start 139.311888 -52.437538)
		(end 139.674854 -52.437538)
		(width 0.254)
		(layer "F.Cu")
		(net "GND")
	)
	(segment
		(start 393.103354 -85.406484)
		(end 392.796776 -85.406484)
		(width 0.254)
		(layer "F.Cu")
		(net "GND")
	)
	(segment
		(start 376.402092 -104.215692)
		(end 376.428 -104.354884)
		(width 0.254)
		(layer "F.Cu")
		(net "GND")
	)
	(segment
		(start 264.51433 -89.765886)
		(end 263.94283 -89.765886)
		(width 0.254)
		(layer "F.Cu")
		(net "GND")
	)
	(segment
		(start 285.650432 -155.613354)
		(end 285.649924 -155.612846)
		(width 0.3556)
		(layer "F.Cu")
		(net "GND")
	)
	(segment
		(start 285.7881 -83.146138)
		(end 286.3596 -83.146138)
		(width 0.254)
		(layer "F.Cu")
		(net "GND")
	)
	(segment
		(start 266.231116 -63.019686)
		(end 265.659616 -63.019686)
		(width 0.254)
		(layer "F.Cu")
		(net "GND")
	)
	(segment
		(start 74.617326 -66.48704)
		(end 74.045826 -66.48704)
		(width 0.254)
		(layer "F.Cu")
		(net "GND")
	)
	(segment
		(start 416.406076 -129.290572)
		(end 415.956242 -129.740406)
		(width 0.381)
		(layer "F.Cu")
		(net "GND")
	)
	(segment
		(start 379.31725 -106.42092)
		(end 379.289564 -106.407966)
		(width 0.254)
		(layer "F.Cu")
		(net "GND")
	)
	(segment
		(start 294.999918 -137.67054)
		(end 294.999918 -136.410446)
		(width 0.4064)
		(layer "F.Cu")
		(net "GND")
	)
	(segment
		(start 283.099764 -146.06905)
		(end 283.04236 -146.011646)
		(width 0.3556)
		(layer "F.Cu")
		(net "GND")
	)
	(segment
		(start 224.449894 -156.87294)
		(end 224.450402 -156.87294)
		(width 0.4064)
		(layer "F.Cu")
		(net "GND")
	)
	(segment
		(start 206.51089 -3.737356)
		(end 206.59979 -3.826256)
		(width 0.4064)
		(layer "F.Cu")
		(net "GND")
	)
	(segment
		(start 443.2935 -145.9865)
		(end 443.2935 -146.5834)
		(width 0.254)
		(layer "F.Cu")
		(net "GND")
	)
	(segment
		(start 226.7966 -154.0764)
		(end 226.822 -154.1018)
		(width 0.3556)
		(layer "F.Cu")
		(net "GND")
	)
	(segment
		(start 77.192886 -53.113686)
		(end 76.621386 -53.113686)
		(width 0.254)
		(layer "F.Cu")
		(net "GND")
	)
	(segment
		(start 401.154646 1.7272)
		(end 401.179538 1.702308)
		(width 0.254)
		(layer "F.Cu")
		(net "GND")
	)
	(segment
		(start 239.617758 -97.19564)
		(end 239.046258 -97.19564)
		(width 0.254)
		(layer "F.Cu")
		(net "GND")
	)
	(segment
		(start 252.495304 -69.953886)
		(end 251.923804 -69.953886)
		(width 0.254)
		(layer "F.Cu")
		(net "GND")
	)
	(segment
		(start 384.1369 -114.6556)
		(end 384.53695 -115.05565)
		(width 0.12446)
		(layer "F.Cu")
		(net "GND")
	)
	(segment
		(start 305.200304 3.778758)
		(end 305.199796 3.778758)
		(width 0.4064)
		(layer "F.Cu")
		(net "GND")
	)
	(segment
		(start 75.475846 -66.982086)
		(end 74.904346 -66.982086)
		(width 0.254)
		(layer "F.Cu")
		(net "GND")
	)
	(segment
		(start 403.733 -21.544788)
		(end 403.8346 -21.443188)
		(width 0.254)
		(layer "F.Cu")
		(net "GND")
	)
	(segment
		(start 217.4494 -7.622794)
		(end 217.4494 -6.9342)
		(width 0.3556)
		(layer "F.Cu")
		(net "GND")
	)
	(segment
		(start 226.149916 -147.27174)
		(end 226.150424 -147.27174)
		(width 0.4064)
		(layer "F.Cu")
		(net "GND")
	)
	(segment
		(start 3.215386 -14.645386)
		(end 2.836418 -14.266418)
		(width 0.254)
		(layer "F.Cu")
		(net "GND")
	)
	(segment
		(start 291.599874 -5.822442)
		(end 291.599874 -6.545326)
		(width 0.3556)
		(layer "F.Cu")
		(net "GND")
	)
	(segment
		(start 38.199568 -15.602712)
		(end 38.199314 -15.602966)
		(width 0.4064)
		(layer "F.Cu")
		(net "GND")
	)
	(segment
		(start 226.9998 3.778758)
		(end 226.9998 3.047746)
		(width 0.3556)
		(layer "F.Cu")
		(net "GND")
	)
	(segment
		(start 195.165218 -85.613748)
		(end 196.154294 -85.613748)
		(width 0.4064)
		(layer "F.Cu")
		(net "GND")
	)
	(segment
		(start 117.353842 -96.023938)
		(end 117.925342 -96.023938)
		(width 0.254)
		(layer "F.Cu")
		(net "GND")
	)
	(segment
		(start 266.231116 -98.681286)
		(end 265.659616 -98.681286)
		(width 0.254)
		(layer "F.Cu")
		(net "GND")
	)
	(segment
		(start 291.599874 -6.545326)
		(end 291.3888 -6.7564)
		(width 0.3556)
		(layer "F.Cu")
		(net "GND")
	)
	(segment
		(start 140.533374 -54.913784)
		(end 141.104874 -54.913784)
		(width 0.254)
		(layer "F.Cu")
		(net "GND")
	)
	(segment
		(start 462.142078 -51.875944)
		(end 462.142078 -50.513488)
		(width 0.508)
		(layer "F.Cu")
		(net "GND")
	)
	(segment
		(start 378.32665 -122.962924)
		(end 377.83135 -122.7328)
		(width 0.254)
		(layer "F.Cu")
		(net "GND")
	)
	(segment
		(start 239.617758 -80.35544)
		(end 239.046258 -80.35544)
		(width 0.254)
		(layer "F.Cu")
		(net "GND")
	)
	(segment
		(start 307.250846 -87.603584)
		(end 307.898546 -87.603584)
		(width 0.254)
		(layer "F.Cu")
		(net "GND")
	)
	(segment
		(start 383.77495 -102.756716)
		(end 383.27965 -102.98684)
		(width 0.254)
		(layer "F.Cu")
		(net "GND")
	)
	(segment
		(start 206.59979 -133.076442)
		(end 206.59979 -134.763002)
		(width 0.4064)
		(layer "F.Cu")
		(net "GND")
	)
	(segment
		(start 383.942336 -27.770836)
		(end 383.9591 -27.7876)
		(width 0.254)
		(layer "F.Cu")
		(net "GND")
	)
	(segment
		(start 315.400436 -20.023582)
		(end 315.399928 -20.023582)
		(width 0.4064)
		(layer "F.Cu")
		(net "GND")
	)
	(segment
		(start 95.221298 -63.51524)
		(end 94.649798 -63.51524)
		(width 0.254)
		(layer "F.Cu")
		(net "GND")
	)
	(segment
		(start 240.476278 -97.690686)
		(end 239.904778 -97.690686)
		(width 0.254)
		(layer "F.Cu")
		(net "GND")
	)
	(segment
		(start 225.299778 -5.822442)
		(end 225.299778 -7.509002)
		(width 0.4064)
		(layer "F.Cu")
		(net "GND")
	)
	(segment
		(start 39.049452 -18.757646)
		(end 39.049452 -20.023582)
		(width 0.4064)
		(layer "F.Cu")
		(net "GND")
	)
	(segment
		(start 198.445374 -70.31228)
		(end 198.445374 -70.900544)
		(width 0.254)
		(layer "F.Cu")
		(net "GND")
	)
	(segment
		(start 311.15 0.38735)
		(end 311.15 -0.821182)
		(width 0.3556)
		(layer "F.Cu")
		(net "GND")
	)
	(segment
		(start 84.060792 -87.784686)
		(end 83.489292 -87.784686)
		(width 0.254)
		(layer "F.Cu")
		(net "GND")
	)
	(segment
		(start 178.943 -6.6802)
		(end 178.943 -7.2898)
		(width 0.4064)
		(layer "F.Cu")
		(net "GND")
	)
	(segment
		(start 225.299778 -15.423642)
		(end 225.299778 -13.427456)
		(width 0.4064)
		(layer "F.Cu")
		(net "GND")
	)
	(segment
		(start 31.39948 -139.170156)
		(end 31.39948 -137.67054)
		(width 0.4064)
		(layer "F.Cu")
		(net "GND")
	)
	(segment
		(start 296.66184 -80.174338)
		(end 296.09034 -80.174338)
		(width 0.254)
		(layer "F.Cu")
		(net "GND")
	)
	(segment
		(start 210.849972 -14.410182)
		(end 210.387946 -13.948156)
		(width 0.4064)
		(layer "F.Cu")
		(net "GND")
	)
	(segment
		(start 123.199398 -142.6718)
		(end 123.199398 -144.462246)
		(width 0.4064)
		(layer "F.Cu")
		(net "GND")
	)
	(segment
		(start 451.25894 -151.66594)
		(end 450.1642 -151.66594)
		(width 0.254)
		(layer "F.Cu")
		(net "GND")
	)
	(segment
		(start 239.617758 -67.47764)
		(end 239.046258 -67.47764)
		(width 0.254)
		(layer "F.Cu")
		(net "GND")
	)
	(segment
		(start 124.221748 -55.409338)
		(end 123.650248 -55.409338)
		(width 0.254)
		(layer "F.Cu")
		(net "GND")
	)
	(segment
		(start 394.070586 -3.287268)
		(end 394.070586 -4.386072)
		(width 0.254)
		(layer "F.Cu")
		(net "GND")
	)
	(segment
		(start 265.372596 -63.51524)
		(end 264.801096 -63.51524)
		(width 0.254)
		(layer "F.Cu")
		(net "GND")
	)
	(segment
		(start 298.399962 -18.744946)
		(end 298.399962 -20.023582)
		(width 0.4064)
		(layer "F.Cu")
		(net "GND")
	)
	(segment
		(start 461.333342 -51.300888)
		(end 461.33258 -50.6222)
		(width 0.508)
		(layer "F.Cu")
		(net "GND")
	)
	(segment
		(start 300.949868 -15.423642)
		(end 300.949868 -13.541756)
		(width 0.4064)
		(layer "F.Cu")
		(net "GND")
	)
	(segment
		(start 118.041928 0.444754)
		(end 118.041928 0.457454)
		(width 0.3556)
		(layer "F.Cu")
		(net "GND")
	)
	(segment
		(start 113.919762 -58.381138)
		(end 113.348262 -58.381138)
		(width 0.254)
		(layer "F.Cu")
		(net "GND")
	)
	(segment
		(start 238.8997 -16.238474)
		(end 238.8997 -15.423896)
		(width 0.4064)
		(layer "F.Cu")
		(net "GND")
	)
	(segment
		(start 205.749906 -10.422382)
		(end 205.749906 -11.916156)
		(width 0.4064)
		(layer "F.Cu")
		(net "GND")
	)
	(segment
		(start 118.212362 -86.612984)
		(end 118.783862 -86.612984)
		(width 0.254)
		(layer "F.Cu")
		(net "GND")
	)
	(segment
		(start 299.249846 -5.822442)
		(end 299.249846 -3.826256)
		(width 0.4064)
		(layer "F.Cu")
		(net "GND")
	)
	(segment
		(start 271.193768 -56.894984)
		(end 270.571468 -56.894984)
		(width 0.254)
		(layer "F.Cu")
		(net "GND")
	)
	(segment
		(start 306.392326 -69.277738)
		(end 306.963826 -69.277738)
		(width 0.254)
		(layer "F.Cu")
		(net "GND")
	)
	(segment
		(start 113.849404 -134.866888)
		(end 113.89614 -134.913624)
		(width 0.4064)
		(layer "F.Cu")
		(net "GND")
	)
	(segment
		(start 212.549994 -3.76301)
		(end 212.549994 -5.822442)
		(width 0.4064)
		(layer "F.Cu")
		(net "GND")
	)
	(segment
		(start 30.549342 -4.277106)
		(end 30.101794 -4.277106)
		(width 0.4064)
		(layer "F.Cu")
		(net "GND")
	)
	(segment
		(start 258.50469 -87.28964)
		(end 257.93319 -87.28964)
		(width 0.254)
		(layer "F.Cu")
		(net "GND")
	)
	(segment
		(start 396.98168 -41.54932)
		(end 398.126458 -40.404542)
		(width 0.254)
		(layer "F.Cu")
		(net "GND")
	)
	(segment
		(start 74.617326 -55.59044)
		(end 74.045826 -55.59044)
		(width 0.254)
		(layer "F.Cu")
		(net "GND")
	)
	(segment
		(start 27.905964 -88.540844)
		(end 27.905964 -87.707216)
		(width 0.254)
		(layer "F.Cu")
		(net "GND")
	)
	(segment
		(start 301.800006 -147.27174)
		(end 301.800006 -146.06905)
		(width 0.3556)
		(layer "F.Cu")
		(net "GND")
	)
	(segment
		(start 282.0162 -153.238454)
		(end 282.0162 -154.04592)
		(width 0.3556)
		(layer "F.Cu")
		(net "GND")
	)
	(segment
		(start 75.599544 3.778758)
		(end 75.599544 3.599688)
		(width 0.4064)
		(layer "F.Cu")
		(net "GND")
	)
	(segment
		(start 34.74212 0.231902)
		(end 34.799524 0.174498)
		(width 0.4064)
		(layer "F.Cu")
		(net "GND")
	)
	(segment
		(start 317.09995 -142.677642)
		(end 317.09995 -143.941546)
		(width 0.4064)
		(layer "F.Cu")
		(net "GND")
	)
	(segment
		(start 378.32665 -97.83572)
		(end 378.82195 -97.605596)
		(width 0.254)
		(layer "F.Cu")
		(net "GND")
	)
	(segment
		(start 135.949436 -143.422878)
		(end 135.735568 -143.636746)
		(width 0.3556)
		(layer "F.Cu")
		(net "GND")
	)
	(segment
		(start 232.100374 -147.27174)
		(end 232.099866 -147.27174)
		(width 0.4064)
		(layer "F.Cu")
		(net "GND")
	)
	(segment
		(start 254.212344 -95.709486)
		(end 253.640844 -95.709486)
		(width 0.254)
		(layer "F.Cu")
		(net "GND")
	)
	(segment
		(start 75.599544 -15.423642)
		(end 75.599544 -15.602712)
		(width 0.4064)
		(layer "F.Cu")
		(net "GND")
	)
	(segment
		(start 250.7615 -12.954)
		(end 249.9106 -12.954)
		(width 0.4064)
		(layer "F.Cu")
		(net "GND")
	)
	(segment
		(start 61.149484 -10.422382)
		(end 61.149484 -9.156446)
		(width 0.4064)
		(layer "F.Cu")
		(net "GND")
	)
	(segment
		(start 434.875686 -3.434588)
		(end 434.875686 -4.386072)
		(width 0.254)
		(layer "F.Cu")
		(net "GND")
	)
	(segment
		(start 173.9773 -6.2103)
		(end 174.4218 -6.2103)
		(width 0.4064)
		(layer "F.Cu")
		(net "GND")
	)
	(segment
		(start 272.910808 -94.538038)
		(end 273.482308 -94.538038)
		(width 0.254)
		(layer "F.Cu")
		(net "GND")
	)
	(segment
		(start 216.80043 -20.023582)
		(end 216.799922 -20.023582)
		(width 0.4064)
		(layer "F.Cu")
		(net "GND")
	)
	(segment
		(start 227.792534 -11.912092)
		(end 227.849938 -11.854688)
		(width 0.4064)
		(layer "F.Cu")
		(net "GND")
	)
	(segment
		(start 67.949318 -3.762756)
		(end 67.949318 -5.822188)
		(width 0.4064)
		(layer "F.Cu")
		(net "GND")
	)
	(segment
		(start 285.650432 -147.27174)
		(end 285.649924 -147.27174)
		(width 0.4064)
		(layer "F.Cu")
		(net "GND")
	)
	(segment
		(start 60.299346 -3.826256)
		(end 60.299346 -5.822442)
		(width 0.4064)
		(layer "F.Cu")
		(net "GND")
	)
	(segment
		(start 99.513898 -98.681286)
		(end 98.942398 -98.681286)
		(width 0.254)
		(layer "F.Cu")
		(net "GND")
	)
	(segment
		(start 464.485736 -137.219944)
		(end 464.4898 -137.224008)
		(width 0.254)
		(layer "F.Cu")
		(net "GND")
	)
	(segment
		(start 292.65626 -96.023938)
		(end 293.22776 -96.023938)
		(width 0.254)
		(layer "F.Cu")
		(net "GND")
	)
	(segment
		(start 470.75471 -38.94709)
		(end 473.03309 -38.94709)
		(width 0.254)
		(layer "F.Cu")
		(net "GND")
	)
	(segment
		(start 70.461378 -18.757646)
		(end 70.499478 -18.795746)
		(width 0.4064)
		(layer "F.Cu")
		(net "GND")
	)
	(segment
		(start 33.099502 -155.612846)
		(end 33.099502 -156.87294)
		(width 0.4064)
		(layer "F.Cu")
		(net "GND")
	)
	(segment
		(start 450.149976 -60.835286)
		(end 449.948554 -60.633864)
		(width 0.381)
		(layer "F.Cu")
		(net "GND")
	)
	(segment
		(start 13.589 -78.0542)
		(end 13.6398 -78.105)
		(width 0.254)
		(layer "F.Cu")
		(net "GND")
	)
	(segment
		(start 413.49041 -29.734764)
		(end 413.890206 -30.13456)
		(width 0.254)
		(layer "F.Cu")
		(net "GND")
	)
	(segment
		(start 297.807126 -64.324738)
		(end 298.378626 -64.324738)
		(width 0.254)
		(layer "F.Cu")
		(net "GND")
	)
	(segment
		(start 56.899556 -5.822442)
		(end 56.899556 -6.001512)
		(width 0.4064)
		(layer "F.Cu")
		(net "GND")
	)
	(segment
		(start 241.334798 -98.18624)
		(end 240.763298 -98.18624)
		(width 0.254)
		(layer "F.Cu")
		(net "GND")
	)
	(segment
		(start 76.334366 -62.52464)
		(end 75.762866 -62.52464)
		(width 0.254)
		(layer "F.Cu")
		(net "GND")
	)
	(segment
		(start 276.344634 -51.941984)
		(end 276.344634 -52.077366)
		(width 0.254)
		(layer "F.Cu")
		(net "GND")
	)
	(segment
		(start 299.524166 -102.175564)
		(end 299.524166 -101.967538)
		(width 0.254)
		(layer "F.Cu")
		(net "GND")
	)
	(segment
		(start 48.399446 -0.821182)
		(end 48.399446 0.444754)
		(width 0.4064)
		(layer "F.Cu")
		(net "GND")
	)
	(segment
		(start 461.349852 -52.974748)
		(end 461.343248 -52.2478)
		(width 0.4064)
		(layer "F.Cu")
		(net "GND")
	)
	(segment
		(start 267.948156 -53.113686)
		(end 268.557756 -53.113686)
		(width 0.254)
		(layer "F.Cu")
		(net "GND")
	)
	(segment
		(start 237.199932 -18.81505)
		(end 237.199932 -20.023582)
		(width 0.3556)
		(layer "F.Cu")
		(net "GND")
	)
	(segment
		(start 384.985006 -95.205042)
		(end 383.985008 -95.205042)
		(width 0.254)
		(layer "F.Cu")
		(net "GND")
	)
	(segment
		(start 233.800396 -0.821182)
		(end 233.799888 -0.821182)
		(width 0.4064)
		(layer "F.Cu")
		(net "GND")
	)
	(segment
		(start 26.602182 -150.914354)
		(end 26.759408 -151.07158)
		(width 0.4064)
		(layer "F.Cu")
		(net "GND")
	)
	(segment
		(start 83.202272 -88.28024)
		(end 82.630772 -88.28024)
		(width 0.254)
		(layer "F.Cu")
		(net "GND")
	)
	(segment
		(start 198.949818 -133.790182)
		(end 198.755 -133.985)
		(width 0.3556)
		(layer "F.Cu")
		(net "GND")
	)
	(segment
		(start 396.288514 -108.077)
		(end 396.65275 -107.907836)
		(width 0.254)
		(layer "F.Cu")
		(net "GND")
	)
	(segment
		(start 499.112032 -36.4998)
		(end 500.291862 -35.31997)
		(width 0.254)
		(layer "F.Cu")
		(net "GND")
	)
	(segment
		(start 55.19928 -133.891274)
		(end 54.74081 -134.349744)
		(width 0.4064)
		(layer "F.Cu")
		(net "GND")
	)
	(segment
		(start 396.984982 -124.504958)
		(end 395.984984 -124.504958)
		(width 0.254)
		(layer "F.Cu")
		(net "GND")
	)
	(segment
		(start 234.649772 2.092198)
		(end 234.551728 1.994154)
		(width 0.4064)
		(layer "F.Cu")
		(net "GND")
	)
	(segment
		(start 84.919312 -96.20504)
		(end 84.347812 -96.20504)
		(width 0.254)
		(layer "F.Cu")
		(net "GND")
	)
	(segment
		(start 74.617326 -59.55284)
		(end 74.045826 -59.55284)
		(width 0.254)
		(layer "F.Cu")
		(net "GND")
	)
	(segment
		(start 51.79949 -21.479256)
		(end 51.76139 -21.517356)
		(width 0.4064)
		(layer "F.Cu")
		(net "GND")
	)
	(segment
		(start 240.599722 -134.861046)
		(end 240.599976 -134.860792)
		(width 0.4064)
		(layer "F.Cu")
		(net "GND")
	)
	(segment
		(start 50.949352 -3.826256)
		(end 50.949352 -5.822442)
		(width 0.4064)
		(layer "F.Cu")
		(net "GND")
	)
	(segment
		(start 271.193768 -53.923184)
		(end 270.571468 -53.923184)
		(width 0.254)
		(layer "F.Cu")
		(net "GND")
	)
	(segment
		(start 224.449894 -155.600146)
		(end 224.449894 -156.87294)
		(width 0.4064)
		(layer "F.Cu")
		(net "GND")
	)
	(segment
		(start 485.50576 -32.72536)
		(end 485.5845 -32.8041)
		(width 0.254)
		(layer "F.Cu")
		(net "GND")
	)
	(segment
		(start 77.299566 -133.076442)
		(end 77.299312 -133.076696)
		(width 0.4064)
		(layer "F.Cu")
		(net "GND")
	)
	(segment
		(start 134.523734 -101.967538)
		(end 135.095234 -101.967538)
		(width 0.254)
		(layer "F.Cu")
		(net "GND")
	)
	(segment
		(start 149.549358 -7.607046)
		(end 149.549358 -5.822442)
		(width 0.4064)
		(layer "F.Cu")
		(net "GND")
	)
	(segment
		(start 5.334 -125.9332)
		(end 5.334 -126.111)
		(width 0.2032)
		(layer "F.Cu")
		(net "GND")
	)
	(segment
		(start 32.249364 -3.826256)
		(end 32.249364 -5.822442)
		(width 0.4064)
		(layer "F.Cu")
		(net "GND")
	)
	(segment
		(start 122.504708 -102.958138)
		(end 123.076208 -102.958138)
		(width 0.3048)
		(layer "F.Cu")
		(net "GND")
	)
	(segment
		(start 289.050476 -137.67054)
		(end 289.049968 -137.67054)
		(width 0.4064)
		(layer "F.Cu")
		(net "GND")
	)
	(segment
		(start 226.111816 -2.314956)
		(end 226.149916 -2.276856)
		(width 0.4064)
		(layer "F.Cu")
		(net "GND")
	)
	(segment
		(start 312.849768 -16.238474)
		(end 312.849768 -15.423642)
		(width 0.4064)
		(layer "F.Cu")
		(net "GND")
	)
	(segment
		(start 30.549342 -153.598626)
		(end 30.503368 -153.6446)
		(width 0.4064)
		(layer "F.Cu")
		(net "GND")
	)
	(segment
		(start 221.899734 -6.001766)
		(end 221.899734 -7.607046)
		(width 0.4064)
		(layer "F.Cu")
		(net "GND")
	)
	(segment
		(start 451.800976 -113.816384)
		(end 451.79996 -113.8174)
		(width 0.4064)
		(layer "F.Cu")
		(net "GND")
	)
	(segment
		(start 355.16312 -99.3648)
		(end 355.16312 -98.730054)
		(width 0.254)
		(layer "F.Cu")
		(net "GND")
	)
	(segment
		(start 292.65626 -91.070938)
		(end 293.22776 -91.070938)
		(width 0.3048)
		(layer "F.Cu")
		(net "GND")
	)
	(segment
		(start 397.270986 -9.44372)
		(end 397.261842 -9.452864)
		(width 0.254)
		(layer "F.Cu")
		(net "GND")
	)
	(segment
		(start 126.599442 -5.822442)
		(end 126.599442 -6.545326)
		(width 0.3556)
		(layer "F.Cu")
		(net "GND")
	)
	(segment
		(start 292.392608 -146.011646)
		(end 292.392608 -145.998946)
		(width 0.3556)
		(layer "F.Cu")
		(net "GND")
	)
	(segment
		(start 86.636352 -64.50584)
		(end 86.064852 -64.50584)
		(width 0.254)
		(layer "F.Cu")
		(net "GND")
	)
	(segment
		(start 398.679162 -123.59132)
		(end 398.13865 -123.59132)
		(width 0.254)
		(layer "F.Cu")
		(net "GND")
	)
	(segment
		(start 113.061242 -95.528384)
		(end 113.632742 -95.528384)
		(width 0.254)
		(layer "F.Cu")
		(net "GND")
	)
	(segment
		(start 148.699474 -156.87294)
		(end 148.699474 -155.612846)
		(width 0.4064)
		(layer "F.Cu")
		(net "GND")
	)
	(segment
		(start 252.495304 -65.000886)
		(end 251.923804 -65.000886)
		(width 0.254)
		(layer "F.Cu")
		(net "GND")
	)
	(segment
		(start 398.984978 -94.274894)
		(end 398.861534 -94.15145)
		(width 0.254)
		(layer "F.Cu")
		(net "GND")
	)
	(segment
		(start 82.343752 -88.775286)
		(end 81.772252 -88.775286)
		(width 0.254)
		(layer "F.Cu")
		(net "GND")
	)
	(segment
		(start 231.249728 -142.856966)
		(end 231.249728 -144.462246)
		(width 0.4064)
		(layer "F.Cu")
		(net "GND")
	)
	(segment
		(start 135.949436 -6.567678)
		(end 135.735568 -6.781546)
		(width 0.3556)
		(layer "F.Cu")
		(net "GND")
	)
	(segment
		(start 8.4836 3.2766)
		(end 8.632952 3.127248)
		(width 0.2032)
		(layer "F.Cu")
		(net "GND")
	)
	(segment
		(start 120.787668 -98.005138)
		(end 121.359168 -98.005138)
		(width 0.254)
		(layer "F.Cu")
		(net "GND")
	)
	(segment
		(start 388.72795 -96.9772)
		(end 389.22325 -96.747076)
		(width 0.254)
		(layer "F.Cu")
		(net "GND")
	)
	(segment
		(start 80.626712 -98.681286)
		(end 80.055212 -98.681286)
		(width 0.254)
		(layer "F.Cu")
		(net "GND")
	)
	(segment
		(start 388.2009 -112.202214)
		(end 388.53745 -111.865664)
		(width 0.1143)
		(layer "F.Cu")
		(net "GND")
	)
	(segment
		(start 235.500418 -137.67054)
		(end 235.49991 -137.67054)
		(width 0.4064)
		(layer "F.Cu")
		(net "GND")
	)
	(segment
		(start 140.533374 -78.688438)
		(end 141.181074 -78.688438)
		(width 0.254)
		(layer "F.Cu")
		(net "GND")
	)
	(segment
		(start 294.3733 -86.117938)
		(end 294.9448 -86.117938)
		(width 0.254)
		(layer "F.Cu")
		(net "GND")
	)
	(segment
		(start 394.9192 -73.8124)
		(end 394.568426 -74.163174)
		(width 0.254)
		(layer "F.Cu")
		(net "GND")
	)
	(segment
		(start 254.212344 -84.812886)
		(end 253.640844 -84.812886)
		(width 0.254)
		(layer "F.Cu")
		(net "GND")
	)
	(segment
		(start 215.950292 -133.0706)
		(end 215.949784 -133.076442)
		(width 0.4064)
		(layer "F.Cu")
		(net "GND")
	)
	(segment
		(start 27.84856 -95.52178)
		(end 27.84856 -96.07042)
		(width 0.254)
		(layer "F.Cu")
		(net "GND")
	)
	(segment
		(start 484.27386 -28.08224)
		(end 484.2764 -28.0797)
		(width 0.254)
		(layer "F.Cu")
		(net "GND")
	)
	(segment
		(start 291.3888 -144.467326)
		(end 291.422074 -144.5006)
		(width 0.3556)
		(layer "F.Cu")
		(net "GND")
	)
	(segment
		(start 79.768192 -76.39304)
		(end 79.196692 -76.39304)
		(width 0.254)
		(layer "F.Cu")
		(net "GND")
	)
	(segment
		(start 232.950512 -15.423642)
		(end 232.950512 -17.207484)
		(width 0.4064)
		(layer "F.Cu")
		(net "GND")
	)
	(segment
		(start 299.249846 -15.423642)
		(end 299.249846 -17.110202)
		(width 0.4064)
		(layer "F.Cu")
		(net "GND")
	)
	(segment
		(start 203.199746 -133.255766)
		(end 203.199746 -134.861046)
		(width 0.4064)
		(layer "F.Cu")
		(net "GND")
	)
	(segment
		(start 168.672764 -76.593192)
		(end 168.672764 -76.064364)
		(width 0.254)
		(layer "F.Cu")
		(net "GND")
	)
	(segment
		(start 82.3468 -52.120292)
		(end 82.3468 -51.132232)
		(width 0.2032)
		(layer "F.Cu")
		(net "GND")
	)
	(segment
		(start 350.012 -18.669)
		(end 349.377 -19.304)
		(width 0.254)
		(layer "F.Cu")
		(net "GND")
	)
	(segment
		(start 87.494872 -82.83194)
		(end 86.923372 -82.83194)
		(width 0.254)
		(layer "F.Cu")
		(net "GND")
	)
	(segment
		(start 382.28905 -116.72316)
		(end 382.3462 -116.74983)
		(width 0.254)
		(layer "F.Cu")
		(net "GND")
	)
	(segment
		(start 308.59984 3.778758)
		(end 308.59984 2.092198)
		(width 0.4064)
		(layer "F.Cu")
		(net "GND")
	)
	(segment
		(start 141.049502 -11.916156)
		(end 141.049502 -10.422382)
		(width 0.4064)
		(layer "F.Cu")
		(net "GND")
	)
	(segment
		(start 384.1496 -115.443)
		(end 384.1496 -115.48999)
		(width 0.12446)
		(layer "F.Cu")
		(net "GND")
	)
	(segment
		(start 174.6377 -69.723)
		(end 174.8155 -69.5452)
		(width 0.381)
		(layer "F.Cu")
		(net "GND")
	)
	(segment
		(start 134.523734 -52.437538)
		(end 135.095234 -52.437538)
		(width 0.254)
		(layer "F.Cu")
		(net "GND")
	)
	(segment
		(start 381.851154 -32.270954)
		(end 381.20828 -31.62808)
		(width 0.254)
		(layer "F.Cu")
		(net "GND")
	)
	(segment
		(start 140.533374 -77.697584)
		(end 141.181074 -77.697584)
		(width 0.254)
		(layer "F.Cu")
		(net "GND")
	)
	(segment
		(start 89.211912 -95.709486)
		(end 88.640412 -95.709486)
		(width 0.254)
		(layer "F.Cu")
		(net "GND")
	)
	(segment
		(start 43.29938 -15.423642)
		(end 43.29938 -13.541756)
		(width 0.4064)
		(layer "F.Cu")
		(net "GND")
	)
	(segment
		(start 191.349122 -148.842222)
		(end 191.135 -148.6281)
		(width 0.254)
		(layer "F.Cu")
		(net "GND")
	)
	(segment
		(start 469.18499 -115.409472)
		(end 470.20099 -114.393472)
		(width 0.381)
		(layer "F.Cu")
		(net "GND")
	)
	(segment
		(start 440.540902 -45.925486)
		(end 440.540902 -47.481998)
		(width 0.4064)
		(layer "F.Cu")
		(net "GND")
	)
	(segment
		(start 145.082768 2.8448)
		(end 145.082768 1.994662)
		(width 0.3556)
		(layer "F.Cu")
		(net "GND")
	)
	(segment
		(start 386.13715 -104.22636)
		(end 385.75615 -103.84536)
		(width 0.254)
		(layer "F.Cu")
		(net "GND")
	)
	(segment
		(start 389.33755 -111.85525)
		(end 389.7376 -112.2553)
		(width 0.12446)
		(layer "F.Cu")
		(net "GND")
	)
	(segment
		(start 39.049452 -0.821182)
		(end 39.049452 0.444754)
		(width 0.4064)
		(layer "F.Cu")
		(net "GND")
	)
	(segment
		(start 62.792102 0.444754)
		(end 62.849506 0.38735)
		(width 0.3556)
		(layer "F.Cu")
		(net "GND")
	)
	(segment
		(start 113.061242 -64.819784)
		(end 112.489742 -64.819784)
		(width 0.254)
		(layer "F.Cu")
		(net "GND")
	)
	(segment
		(start 220.200474 -133.0706)
		(end 220.199966 -133.076442)
		(width 0.4064)
		(layer "F.Cu")
		(net "GND")
	)
	(segment
		(start 115.549426 -134.763002)
		(end 115.451382 -134.861046)
		(width 0.4064)
		(layer "F.Cu")
		(net "GND")
	)
	(segment
		(start 281.495754 -89.584784)
		(end 282.067254 -89.584784)
		(width 0.254)
		(layer "F.Cu")
		(net "GND")
	)
	(segment
		(start 199.799956 -20.023582)
		(end 199.799956 -21.455888)
		(width 0.4064)
		(layer "F.Cu")
		(net "GND")
	)
	(segment
		(start 62.792102 -146.011646)
		(end 62.792102 -145.998946)
		(width 0.3556)
		(layer "F.Cu")
		(net "GND")
	)
	(segment
		(start 65.399412 -11.916156)
		(end 65.399412 -10.422382)
		(width 0.4064)
		(layer "F.Cu")
		(net "GND")
	)
	(segment
		(start 304.349912 -11.916156)
		(end 304.349912 -10.422382)
		(width 0.4064)
		(layer "F.Cu")
		(net "GND")
	)
	(segment
		(start 88.353392 -83.32724)
		(end 87.781892 -83.32724)
		(width 0.254)
		(layer "F.Cu")
		(net "GND")
	)
	(segment
		(start 467.233 -53.721)
		(end 467.74735 -53.20665)
		(width 0.4064)
		(layer "F.Cu")
		(net "GND")
	)
	(segment
		(start 229.550468 2.964688)
		(end 229.091236 2.505456)
		(width 0.4064)
		(layer "F.Cu")
		(net "GND")
	)
	(segment
		(start 227.849938 -156.87294)
		(end 227.850446 -156.87294)
		(width 0.3556)
		(layer "F.Cu")
		(net "GND")
	)
	(segment
		(start 280.451814 -17.208246)
		(end 280.549858 -17.110202)
		(width 0.4064)
		(layer "F.Cu")
		(net "GND")
	)
	(segment
		(start 268.679168 -12.954)
		(end 267.794232 -12.954)
		(width 0.381)
		(layer "F.Cu")
		(net "GND")
	)
	(segment
		(start 44.149518 -18.85315)
		(end 44.149518 -20.023582)
		(width 0.4064)
		(layer "F.Cu")
		(net "GND")
	)
	(segment
		(start 135.382254 -65.810384)
		(end 135.953754 -65.810384)
		(width 0.254)
		(layer "F.Cu")
		(net "GND")
	)
	(segment
		(start 296.948606 -55.904384)
		(end 297.520106 -55.904384)
		(width 0.254)
		(layer "F.Cu")
		(net "GND")
	)
	(segment
		(start 386.644388 -111.348012)
		(end 386.93725 -111.05515)
		(width 0.12446)
		(layer "F.Cu")
		(net "GND")
	)
	(segment
		(start 388.53745 -111.865664)
		(end 388.53745 -111.85525)
		(width 0.1143)
		(layer "F.Cu")
		(net "GND")
	)
	(segment
		(start 279.5524 -53.325014)
		(end 279.519634 -53.381656)
		(width 0.254)
		(layer "F.Cu")
		(net "GND")
	)
	(segment
		(start 291.599874 -13.541756)
		(end 291.422074 -13.363956)
		(width 0.4064)
		(layer "F.Cu")
		(net "GND")
	)
	(segment
		(start 300.950376 -152.273)
		(end 300.949868 -152.278842)
		(width 0.3556)
		(layer "F.Cu")
		(net "GND")
	)
	(segment
		(start 87.494872 -80.850486)
		(end 86.923372 -80.850486)
		(width 0.254)
		(layer "F.Cu")
		(net "GND")
	)
	(segment
		(start 308.59984 -5.822442)
		(end 308.59984 -3.828796)
		(width 0.4064)
		(layer "F.Cu")
		(net "GND")
	)
	(segment
		(start 113.919762 -62.343538)
		(end 113.348262 -62.343538)
		(width 0.254)
		(layer "F.Cu")
		(net "GND")
	)
	(segment
		(start 194.804538 -52.59578)
		(end 194.39382 -52.59578)
		(width 0.4064)
		(layer "F.Cu")
		(net "GND")
	)
	(segment
		(start 218.44254 -18.744946)
		(end 218.44254 -18.757646)
		(width 0.3556)
		(layer "F.Cu")
		(net "GND")
	)
	(segment
		(start 399.255996 -117.854984)
		(end 399.634964 -117.854984)
		(width 0.254)
		(layer "F.Cu")
		(net "GND")
	)
	(segment
		(start 291.600382 -133.0706)
		(end 291.599874 -133.076442)
		(width 0.3556)
		(layer "F.Cu")
		(net "GND")
	)
	(segment
		(start 303.816766 -67.791584)
		(end 303.529746 -67.504564)
		(width 0.254)
		(layer "F.Cu")
		(net "GND")
	)
	(segment
		(start 239.617758 -70.44944)
		(end 239.046258 -70.44944)
		(width 0.254)
		(layer "F.Cu")
		(net "GND")
	)
	(segment
		(start 389.71855 -102.756716)
		(end 389.7376 -102.765606)
		(width 0.254)
		(layer "F.Cu")
		(net "GND")
	)
	(segment
		(start 236.183678 -100.167186)
		(end 235.612178 -100.167186)
		(width 0.254)
		(layer "F.Cu")
		(net "GND")
	)
	(segment
		(start 288.36366 -80.669384)
		(end 288.93516 -80.669384)
		(width 0.254)
		(layer "F.Cu")
		(net "GND")
	)
	(segment
		(start 476.4786 -40.3479)
		(end 477.2406 -40.3479)
		(width 0.254)
		(layer "F.Cu")
		(net "GND")
	)
	(segment
		(start 289.22218 -57.390538)
		(end 288.65068 -57.390538)
		(width 0.254)
		(layer "F.Cu")
		(net "GND")
	)
	(segment
		(start 376.27814 -126.49454)
		(end 376.5042 -126.7206)
		(width 0.254)
		(layer "F.Cu")
		(net "GND")
	)
	(segment
		(start 78.909672 -62.029086)
		(end 78.338172 -62.029086)
		(width 0.254)
		(layer "F.Cu")
		(net "GND")
	)
	(segment
		(start 117.353842 -66.305938)
		(end 116.782342 -66.305938)
		(width 0.254)
		(layer "F.Cu")
		(net "GND")
	)
	(segment
		(start 47.549308 3.599434)
		(end 47.549308 1.994154)
		(width 0.4064)
		(layer "F.Cu")
		(net "GND")
	)
	(segment
		(start 203.2 -5.822442)
		(end 203.2 -6.001512)
		(width 0.4064)
		(layer "F.Cu")
		(net "GND")
	)
	(segment
		(start 45.849286 -142.677896)
		(end 45.849286 -143.492474)
		(width 0.4064)
		(layer "F.Cu")
		(net "GND")
	)
	(segment
		(start 82.343752 -85.803486)
		(end 81.772252 -85.803486)
		(width 0.254)
		(layer "F.Cu")
		(net "GND")
	)
	(segment
		(start 239.617758 -66.48704)
		(end 239.046258 -66.48704)
		(width 0.254)
		(layer "F.Cu")
		(net "GND")
	)
	(segment
		(start 303.499774 -143.492474)
		(end 303.041304 -143.950944)
		(width 0.4064)
		(layer "F.Cu")
		(net "GND")
	)
	(segment
		(start 224.449894 -20.023582)
		(end 224.449894 -21.517356)
		(width 0.4064)
		(layer "F.Cu")
		(net "GND")
	)
	(segment
		(start 422.874186 -3.384042)
		(end 422.865042 -3.374898)
		(width 0.254)
		(layer "F.Cu")
		(net "GND")
	)
	(segment
		(start 431.8762 -24.054562)
		(end 431.8 -24.130762)
		(width 0.254)
		(layer "F.Cu")
		(net "GND")
	)
	(segment
		(start 392.19505 -118.4402)
		(end 392.687048 -118.6688)
		(width 0.254)
		(layer "F.Cu")
		(net "GND")
	)
	(segment
		(start 233.799888 -2.314956)
		(end 233.799888 -0.821182)
		(width 0.4064)
		(layer "F.Cu")
		(net "GND")
	)
	(segment
		(start 442.849 -9.9822)
		(end 442.9506 -9.8806)
		(width 0.254)
		(layer "F.Cu")
		(net "GND")
	)
	(segment
		(start 114.778282 -57.885584)
		(end 114.206782 -57.885584)
		(width 0.254)
		(layer "F.Cu")
		(net "GND")
	)
	(segment
		(start 114.778282 -88.594184)
		(end 115.349782 -88.594184)
		(width 0.254)
		(layer "F.Cu")
		(net "GND")
	)
	(segment
		(start 206.59979 -15.423642)
		(end 206.59979 -13.427456)
		(width 0.4064)
		(layer "F.Cu")
		(net "GND")
	)
	(segment
		(start 282.24988 -152.278842)
		(end 282.24988 -153.004774)
		(width 0.3556)
		(layer "F.Cu")
		(net "GND")
	)
	(segment
		(start 119.642382 -99.986338)
		(end 119.070882 -99.986338)
		(width 0.254)
		(layer "F.Cu")
		(net "GND")
	)
	(segment
		(start 314.550298 -133.0706)
		(end 314.54979 -133.076442)
		(width 0.4064)
		(layer "F.Cu")
		(net "GND")
	)
	(segment
		(start 286.893 -52.367434)
		(end 286.900874 -52.380896)
		(width 0.254)
		(layer "F.Cu")
		(net "GND")
	)
	(segment
		(start 290.74999 -0.821182)
		(end 290.74999 0.444754)
		(width 0.4064)
		(layer "F.Cu")
		(net "GND")
	)
	(segment
		(start 392.98499 -95.205042)
		(end 393.984988 -95.205042)
		(width 0.254)
		(layer "F.Cu")
		(net "GND")
	)
	(segment
		(start 32.249364 -152.273)
		(end 32.249364 -153.965402)
		(width 0.4064)
		(layer "F.Cu")
		(net "GND")
	)
	(segment
		(start 221.050358 -147.27174)
		(end 221.04985 -147.27174)
		(width 0.4064)
		(layer "F.Cu")
		(net "GND")
	)
	(segment
		(start 395.984984 -94.37497)
		(end 395.984984 -95.205042)
		(width 0.254)
		(layer "F.Cu")
		(net "GND")
	)
	(segment
		(start 52.448968 -17.223994)
		(end 52.448968 -16.5354)
		(width 0.3556)
		(layer "F.Cu")
		(net "GND")
	)
	(segment
		(start 361.48518 -7.789926)
		(end 361.48518 -9.30529)
		(width 0.4064)
		(layer "F.Cu")
		(net "GND")
	)
	(segment
		(start 250.778264 -88.775286)
		(end 250.206764 -88.775286)
		(width 0.254)
		(layer "F.Cu")
		(net "GND")
	)
	(segment
		(start 396.15745 -110.943644)
		(end 395.66215 -110.71352)
		(width 0.254)
		(layer "F.Cu")
		(net "GND")
	)
	(segment
		(start 314.54979 3.778758)
		(end 314.54979 1.994154)
		(width 0.4064)
		(layer "F.Cu")
		(net "GND")
	)
	(segment
		(start 36.499546 -14.410182)
		(end 36.499546 -15.423642)
		(width 0.4064)
		(layer "F.Cu")
		(net "GND")
	)
	(segment
		(start 231.25049 -5.822442)
		(end 231.25049 -7.606284)
		(width 0.4064)
		(layer "F.Cu")
		(net "GND")
	)
	(segment
		(start 382.797304 -24.770842)
		(end 383.666746 -24.770842)
		(width 0.254)
		(layer "F.Cu")
		(net "GND")
	)
	(segment
		(start 388.1755 -79.8322)
		(end 388.1755 -80.6196)
		(width 0.254)
		(layer "F.Cu")
		(net "GND")
	)
	(segment
		(start 245.627144 -50.141886)
		(end 245.627144 -49.150778)
		(width 0.2032)
		(layer "F.Cu")
		(net "GND")
	)
	(segment
		(start 31.19628 -62.009782)
		(end 30.818582 -62.009782)
		(width 0.508)
		(layer "F.Cu")
		(net "GND")
	)
	(segment
		(start 255.92913 -63.019686)
		(end 255.35763 -63.019686)
		(width 0.254)
		(layer "F.Cu")
		(net "GND")
	)
	(segment
		(start 393.94892 -109.13872)
		(end 394.17625 -109.13872)
		(width 0.254)
		(layer "F.Cu")
		(net "GND")
	)
	(segment
		(start 1.917446 -144.488154)
		(end 2.3114 -144.0942)
		(width 0.254)
		(layer "F.Cu")
		(net "GND")
	)
	(segment
		(start 52.448968 2.667)
		(end 52.448968 1.978406)
		(width 0.3556)
		(layer "F.Cu")
		(net "GND")
	)
	(segment
		(start 388.628382 -86.562946)
		(end 389.128 -87.062564)
		(width 0.254)
		(layer "F.Cu")
		(net "GND")
	)
	(segment
		(start 218.500452 -0.821182)
		(end 218.499944 -0.821182)
		(width 0.4064)
		(layer "F.Cu")
		(net "GND")
	)
	(segment
		(start 52.448968 -134.0104)
		(end 52.448968 -134.1882)
		(width 0.3048)
		(layer "F.Cu")
		(net "GND")
	)
	(segment
		(start 440.41314 -9.126982)
		(end 440.476386 -9.063736)
		(width 0.254)
		(layer "F.Cu")
		(net "GND")
	)
	(segment
		(start 256.78765 -86.29904)
		(end 256.21615 -86.29904)
		(width 0.254)
		(layer "F.Cu")
		(net "GND")
	)
	(segment
		(start 292.65626 -58.381138)
		(end 293.22776 -58.381138)
		(width 0.254)
		(layer "F.Cu")
		(net "GND")
	)
	(segment
		(start 291.599874 -133.799326)
		(end 291.3888 -134.0104)
		(width 0.3556)
		(layer "F.Cu")
		(net "GND")
	)
	(segment
		(start 178.943 -130.8735)
		(end 178.943 -130.2639)
		(width 0.4064)
		(layer "F.Cu")
		(net "GND")
	)
	(segment
		(start 221.900496 -5.822442)
		(end 221.899988 -5.822442)
		(width 0.4064)
		(layer "F.Cu")
		(net "GND")
	)
	(segment
		(start 279.778714 -52.932838)
		(end 279.5524 -53.325014)
		(width 0.254)
		(layer "F.Cu")
		(net "GND")
	)
	(segment
		(start 216.80043 -10.422382)
		(end 216.799922 -10.422382)
		(width 0.4064)
		(layer "F.Cu")
		(net "GND")
	)
	(segment
		(start 137.957814 -68.287138)
		(end 138.529314 -68.287138)
		(width 0.1016)
		(layer "F.Cu")
		(net "GND")
	)
	(segment
		(start 238.437928 -4.346956)
		(end 238.899954 -4.808982)
		(width 0.4064)
		(layer "F.Cu")
		(net "GND")
	)
	(segment
		(start 108.768896 -98.005138)
		(end 109.340396 -98.005138)
		(width 0.254)
		(layer "F.Cu")
		(net "GND")
	)
	(segment
		(start 283.099764 -2.253488)
		(end 283.099764 -0.821182)
		(width 0.4064)
		(layer "F.Cu")
		(net "GND")
	)
	(segment
		(start 381.29845 -116.72316)
		(end 381.79375 -116.953284)
		(width 0.254)
		(layer "F.Cu")
		(net "GND")
	)
	(segment
		(start 40.749474 -21.517356)
		(end 40.749474 -20.023582)
		(width 0.4064)
		(layer "F.Cu")
		(net "GND")
	)
	(segment
		(start 202.35037 -0.821182)
		(end 202.349862 -0.821182)
		(width 0.4064)
		(layer "F.Cu")
		(net "GND")
	)
	(segment
		(start 27.1526 -31.467552)
		(end 27.1526 -32.432498)
		(width 0.254)
		(layer "F.Cu")
		(net "GND")
	)
	(segment
		(start 227.000308 -142.6718)
		(end 226.9998 -142.677642)
		(width 0.3556)
		(layer "F.Cu")
		(net "GND")
	)
	(segment
		(start 113.061242 -58.876438)
		(end 112.489742 -58.876438)
		(width 0.254)
		(layer "F.Cu")
		(net "GND")
	)
	(segment
		(start 303.499774 -142.677642)
		(end 303.499774 -143.492474)
		(width 0.4064)
		(layer "F.Cu")
		(net "GND")
	)
	(segment
		(start 398.4244 -125.603)
		(end 398.817084 -125.603)
		(width 0.254)
		(layer "F.Cu")
		(net "GND")
	)
	(segment
		(start 378.284994 -7.850124)
		(end 378.284994 -8.84682)
		(width 0.4064)
		(layer "F.Cu")
		(net "GND")
	)
	(segment
		(start 126.797308 -65.810384)
		(end 127.368808 -65.810384)
		(width 0.254)
		(layer "F.Cu")
		(net "GND")
	)
	(segment
		(start 257.64617 -95.709486)
		(end 257.07467 -95.709486)
		(width 0.254)
		(layer "F.Cu")
		(net "GND")
	)
	(segment
		(start 284.929834 -77.697584)
		(end 284.358334 -77.697584)
		(width 0.4064)
		(layer "F.Cu")
		(net "GND")
	)
	(segment
		(start 307.750464 -137.67054)
		(end 307.749956 -137.67054)
		(width 0.4064)
		(layer "F.Cu")
		(net "GND")
	)
	(segment
		(start 458.14107 -51.875944)
		(end 458.14107 -50.909982)
		(width 0.508)
		(layer "F.Cu")
		(net "GND")
	)
	(segment
		(start 142.10284 -67.156838)
		(end 141.963394 -67.296538)
		(width 0.254)
		(layer "F.Cu")
		(net "GND")
	)
	(segment
		(start 387.44652 -54.84368)
		(end 386.9436 -55.3466)
		(width 0.254)
		(layer "F.Cu")
		(net "GND")
	)
	(segment
		(start 130.84937 -5.822442)
		(end 130.84937 -7.607046)
		(width 0.4064)
		(layer "F.Cu")
		(net "GND")
	)
	(segment
		(start 204.899768 -142.677642)
		(end 204.899768 -144.462246)
		(width 0.4064)
		(layer "F.Cu")
		(net "GND")
	)
	(segment
		(start 123.363228 -71.753984)
		(end 123.934728 -71.753984)
		(width 0.254)
		(layer "F.Cu")
		(net "GND")
	)
	(segment
		(start 89.211912 -56.085486)
		(end 88.640412 -56.085486)
		(width 0.254)
		(layer "F.Cu")
		(net "GND")
	)
	(segment
		(start 289.899852 2.092198)
		(end 289.801808 1.994154)
		(width 0.4064)
		(layer "F.Cu")
		(net "GND")
	)
	(segment
		(start 278.944578 -18.691606)
		(end 278.849836 -18.786348)
		(width 0.4064)
		(layer "F.Cu")
		(net "GND")
	)
	(segment
		(start 97.796858 -98.681286)
		(end 97.225358 -98.681286)
		(width 0.254)
		(layer "F.Cu")
		(net "GND")
	)
	(segment
		(start 70.324726 -94.718886)
		(end 69.753226 -94.718886)
		(width 0.254)
		(layer "F.Cu")
		(net "GND")
	)
	(segment
		(start 464.282282 -37.3888)
		(end 465.4042 -37.3888)
		(width 0.4064)
		(layer "F.Cu")
		(net "GND")
	)
	(segment
		(start 385.75107 -103.378)
		(end 385.75615 -103.84536)
		(width 0.254)
		(layer "F.Cu")
		(net "GND")
	)
	(segment
		(start 113.196878 -3.4798)
		(end 113.866168 -3.4798)
		(width 0.381)
		(layer "F.Cu")
		(net "GND")
	)
	(segment
		(start 205.749906 -147.27174)
		(end 205.749906 -148.771356)
		(width 0.4064)
		(layer "F.Cu")
		(net "GND")
	)
	(segment
		(start 291.51072 -91.070938)
		(end 290.93922 -91.070938)
		(width 0.254)
		(layer "F.Cu")
		(net "GND")
	)
	(segment
		(start 110.485682 -51.446938)
		(end 110.485682 -50.528474)
		(width 0.254)
		(layer "F.Cu")
		(net "GND")
	)
	(segment
		(start 207.449928 -20.023582)
		(end 207.449928 -18.783046)
		(width 0.4064)
		(layer "F.Cu")
		(net "GND")
	)
	(segment
		(start 65.399412 -20.023582)
		(end 65.399412 -18.757646)
		(width 0.4064)
		(layer "F.Cu")
		(net "GND")
	)
	(segment
		(start 382.78435 -119.29872)
		(end 382.9304 -119.366538)
		(width 0.254)
		(layer "F.Cu")
		(net "GND")
	)
	(segment
		(start 392.796776 -85.406484)
		(end 392.523218 -85.680042)
		(width 0.254)
		(layer "F.Cu")
		(net "GND")
	)
	(segment
		(start 198.099934 -139.132056)
		(end 198.099934 -137.67054)
		(width 0.4064)
		(layer "F.Cu")
		(net "GND")
	)
	(segment
		(start 399.12925 -116.094764)
		(end 399.634964 -115.854988)
		(width 0.254)
		(layer "F.Cu")
		(net "GND")
	)
	(segment
		(start 129.149348 -142.6718)
		(end 129.149348 -143.492474)
		(width 0.4064)
		(layer "F.Cu")
		(net "GND")
	)
	(segment
		(start 307.250846 -63.829184)
		(end 307.898546 -63.829184)
		(width 0.254)
		(layer "F.Cu")
		(net "GND")
	)
	(segment
		(start 226.7966 -144.4752)
		(end 226.822 -144.5006)
		(width 0.3556)
		(layer "F.Cu")
		(net "GND")
	)
	(segment
		(start 381.29845 -109.855)
		(end 381.79375 -110.085124)
		(width 0.254)
		(layer "F.Cu")
		(net "GND")
	)
	(segment
		(start 179.4002 -80.8736)
		(end 179.4002 -81.097628)
		(width 0.254)
		(layer "F.Cu")
		(net "GND")
	)
	(segment
		(start 239.617758 -60.54344)
		(end 239.046258 -60.54344)
		(width 0.254)
		(layer "F.Cu")
		(net "GND")
	)
	(segment
		(start 377.921266 -93.544898)
		(end 377.921266 -92.959174)
		(width 0.254)
		(layer "F.Cu")
		(net "GND")
	)
	(segment
		(start 141.391894 -94.042738)
		(end 142.039848 -94.042738)
		(width 0.254)
		(layer "F.Cu")
		(net "GND")
	)
	(segment
		(start 391.984992 -124.504958)
		(end 392.98499 -124.504958)
		(width 0.254)
		(layer "F.Cu")
		(net "GND")
	)
	(segment
		(start 218.499944 -137.67054)
		(end 218.499944 -136.46785)
		(width 0.3556)
		(layer "F.Cu")
		(net "GND")
	)
	(segment
		(start 82.343752 -66.982086)
		(end 81.772252 -66.982086)
		(width 0.254)
		(layer "F.Cu")
		(net "GND")
	)
	(segment
		(start 95.51924 -1.582928)
		(end 96.145096 -1.582928)
		(width 0.254)
		(layer "F.Cu")
		(net "GND")
	)
	(segment
		(start 84.919312 -63.51524)
		(end 84.347812 -63.51524)
		(width 0.254)
		(layer "F.Cu")
		(net "GND")
	)
	(segment
		(start 145.29943 -16.140938)
		(end 145.082768 -16.3576)
		(width 0.3556)
		(layer "F.Cu")
		(net "GND")
	)
	(segment
		(start 465.4042 -37.3888)
		(end 465.7344 -37.0586)
		(width 0.4064)
		(layer "F.Cu")
		(net "GND")
	)
	(segment
		(start 381.29845 -123.59132)
		(end 382.28905 -123.59132)
		(width 0.254)
		(layer "F.Cu")
		(net "GND")
	)
	(segment
		(start 49.24933 -142.677896)
		(end 49.24933 -144.462246)
		(width 0.4064)
		(layer "F.Cu")
		(net "GND")
	)
	(segment
		(start 134.523734 -83.146138)
		(end 135.095234 -83.146138)
		(width 0.1016)
		(layer "F.Cu")
		(net "GND")
	)
	(segment
		(start 129.149348 -6.637274)
		(end 128.690878 -7.095744)
		(width 0.4064)
		(layer "F.Cu")
		(net "GND")
	)
	(segment
		(start 232.94975 -142.677896)
		(end 232.94975 -144.462246)
		(width 0.4064)
		(layer "F.Cu")
		(net "GND")
	)
	(segment
		(start 384.76555 -122.7328)
		(end 385.26085 -122.962924)
		(width 0.254)
		(layer "F.Cu")
		(net "GND")
	)
	(segment
		(start 399.634964 -98.855022)
		(end 399.542 -99.354894)
		(width 0.254)
		(layer "F.Cu")
		(net "GND")
	)
	(segment
		(start 293.51478 -53.923184)
		(end 294.08628 -53.923184)
		(width 0.254)
		(layer "F.Cu")
		(net "GND")
	)
	(segment
		(start 174.3456 -80.1116)
		(end 175.14316 -80.1116)
		(width 0.254)
		(layer "F.Cu")
		(net "GND")
	)
	(segment
		(start 52.448968 -143.7894)
		(end 52.448968 -144.477994)
		(width 0.3556)
		(layer "F.Cu")
		(net "GND")
	)
	(segment
		(start 70.461378 -155.612846)
		(end 70.461378 -155.562046)
		(width 0.4064)
		(layer "F.Cu")
		(net "GND")
	)
	(segment
		(start 296.66184 -64.324738)
		(end 296.09034 -64.324738)
		(width 0.254)
		(layer "F.Cu")
		(net "GND")
	)
	(segment
		(start 138.03757 -4.346956)
		(end 138.499342 -4.808728)
		(width 0.4064)
		(layer "F.Cu")
		(net "GND")
	)
	(segment
		(start 75.59929 -15.602966)
		(end 75.59929 -17.208246)
		(width 0.4064)
		(layer "F.Cu")
		(net "GND")
	)
	(segment
		(start 174.9044 -93.0656)
		(end 175.2346 -93.3958)
		(width 0.254)
		(layer "F.Cu")
		(net "GND")
	)
	(segment
		(start 446.200784 -116.993162)
		(end 446.200784 -118.615714)
		(width 0.4064)
		(layer "F.Cu")
		(net "GND")
	)
	(segment
		(start 289.90036 -5.822442)
		(end 289.899852 -5.822442)
		(width 0.4064)
		(layer "F.Cu")
		(net "GND")
	)
	(segment
		(start 315.399928 -147.27174)
		(end 315.399928 -146.011646)
		(width 0.4064)
		(layer "F.Cu")
		(net "GND")
	)
	(segment
		(start 306.963826 -86.240366)
		(end 306.963826 -86.117938)
		(width 0.254)
		(layer "F.Cu")
		(net "GND")
	)
	(segment
		(start 131.948174 -67.791584)
		(end 132.519674 -67.791584)
		(width 0.254)
		(layer "F.Cu")
		(net "GND")
	)
	(segment
		(start 81.485232 -90.26144)
		(end 80.913732 -90.26144)
		(width 0.254)
		(layer "F.Cu")
		(net "GND")
	)
	(segment
		(start 210.849972 -5.822442)
		(end 210.849718 -5.822696)
		(width 0.4064)
		(layer "F.Cu")
		(net "GND")
	)
	(segment
		(start 461.332326 -50.48885)
		(end 461.331564 -50.488088)
		(width 0.508)
		(layer "F.Cu")
		(net "GND")
	)
	(segment
		(start 277.203154 -51.446938)
		(end 277.203154 -50.759614)
		(width 0.254)
		(layer "F.Cu")
		(net "GND")
	)
	(segment
		(start 138.499342 -15.423642)
		(end 138.499342 -14.409928)
		(width 0.4064)
		(layer "F.Cu")
		(net "GND")
	)
	(segment
		(start 400.465036 -104.85501)
		(end 399.634964 -104.85501)
		(width 0.254)
		(layer "F.Cu")
		(net "GND")
	)
	(segment
		(start 196.6976 -78.232)
		(end 195.92544 -78.232)
		(width 0.254)
		(layer "F.Cu")
		(net "GND")
	)
	(segment
		(start 420.3192 -3.433572)
		(end 420.3192 -3.5814)
		(width 0.254)
		(layer "F.Cu")
		(net "GND")
	)
	(segment
		(start 457.34097 -46.021752)
		(end 457.34097 -47.481998)
		(width 0.4064)
		(layer "F.Cu")
		(net "GND")
	)
	(segment
		(start 198.949818 -6.536182)
		(end 198.949818 -5.822442)
		(width 0.3556)
		(layer "F.Cu")
		(net "GND")
	)
	(segment
		(start 306.900326 -152.273)
		(end 306.899818 -152.278842)
		(width 0.4064)
		(layer "F.Cu")
		(net "GND")
	)
	(segment
		(start 282.07208 -17.2466)
		(end 282.0162 -17.19072)
		(width 0.3556)
		(layer "F.Cu")
		(net "GND")
	)
	(segment
		(start 69.466206 -93.23324)
		(end 70.611746 -93.23324)
		(width 0.254)
		(layer "F.Cu")
		(net "GND")
	)
	(segment
		(start 287.350454 -155.613354)
		(end 287.349946 -155.612846)
		(width 0.3556)
		(layer "F.Cu")
		(net "GND")
	)
	(segment
		(start 311.15 -156.87294)
		(end 311.150508 -156.87294)
		(width 0.3556)
		(layer "F.Cu")
		(net "GND")
	)
	(segment
		(start 70.499478 -9.156446)
		(end 70.499478 -10.422382)
		(width 0.4064)
		(layer "F.Cu")
		(net "GND")
	)
	(segment
		(start 145.29943 -15.423642)
		(end 145.29943 -16.140938)
		(width 0.3556)
		(layer "F.Cu")
		(net "GND")
	)
	(segment
		(start 348.276164 -8.787638)
		(end 348.276164 -9.283954)
		(width 0.254)
		(layer "F.Cu")
		(net "GND")
	)
	(segment
		(start 217.650314 -133.0706)
		(end 217.649806 -133.076442)
		(width 0.3048)
		(layer "F.Cu")
		(net "GND")
	)
	(segment
		(start 252.495304 -56.085486)
		(end 251.923804 -56.085486)
		(width 0.254)
		(layer "F.Cu")
		(net "GND")
	)
	(segment
		(start 399.634964 -110.854998)
		(end 400.05 -111.355124)
		(width 0.254)
		(layer "F.Cu")
		(net "GND")
	)
	(segment
		(start 227.850446 -10.422382)
		(end 227.849938 -10.422382)
		(width 0.3556)
		(layer "F.Cu")
		(net "GND")
	)
	(segment
		(start 71.183246 -68.46824)
		(end 70.611746 -68.46824)
		(width 0.254)
		(layer "F.Cu")
		(net "GND")
	)
	(segment
		(start 110.485682 -98.995738)
		(end 111.057182 -98.995738)
		(width 0.254)
		(layer "F.Cu")
		(net "GND")
	)
	(segment
		(start 243.149882 -147.277582)
		(end 243.149882 -147.27174)
		(width 0.4064)
		(layer "F.Cu")
		(net "GND")
	)
	(segment
		(start 438.14111 -46.00829)
		(end 438.14111 -47.481998)
		(width 0.4064)
		(layer "F.Cu")
		(net "GND")
	)
	(segment
		(start 242.300506 -133.0706)
		(end 242.300506 -134.860284)
		(width 0.4064)
		(layer "F.Cu")
		(net "GND")
	)
	(segment
		(start 231.249982 3.778758)
		(end 231.249982 3.599688)
		(width 0.4064)
		(layer "F.Cu")
		(net "GND")
	)
	(segment
		(start 142.250414 -63.829184)
		(end 142.898114 -63.829184)
		(width 0.254)
		(layer "F.Cu")
		(net "GND")
	)
	(segment
		(start 46.699424 0.444754)
		(end 46.699424 -0.821182)
		(width 0.4064)
		(layer "F.Cu")
		(net "GND")
	)
	(segment
		(start 236.183678 -64.50584)
		(end 235.612178 -64.50584)
		(width 0.254)
		(layer "F.Cu")
		(net "GND")
	)
	(segment
		(start 303.43602 -2.347722)
		(end 303.027842 -2.3622)
		(width 0.254)
		(layer "F.Cu")
		(net "GND")
	)
	(segment
		(start 310.30037 -142.6718)
		(end 310.299862 -142.677642)
		(width 0.3556)
		(layer "F.Cu")
		(net "GND")
	)
	(segment
		(start 260.50875 -87.784686)
		(end 261.08025 -87.784686)
		(width 0.254)
		(layer "F.Cu")
		(net "GND")
	)
	(segment
		(start 301.800006 -2.253488)
		(end 301.742602 -2.310892)
		(width 0.4064)
		(layer "F.Cu")
		(net "GND")
	)
	(segment
		(start 73.899522 -133.076442)
		(end 73.899268 -133.076696)
		(width 0.4064)
		(layer "F.Cu")
		(net "GND")
	)
	(segment
		(start 299.250354 -5.822442)
		(end 299.249846 -5.822442)
		(width 0.4064)
		(layer "F.Cu")
		(net "GND")
	)
	(segment
		(start 196.399912 -2.314956)
		(end 196.469 -2.384044)
		(width 0.381)
		(layer "F.Cu")
		(net "GND")
	)
	(segment
		(start 484.7336 -141.6304)
		(end 485.0638 -141.9606)
		(width 0.254)
		(layer "F.Cu")
		(net "GND")
	)
	(segment
		(start 98.655378 -91.25204)
		(end 98.083878 -91.25204)
		(width 0.254)
		(layer "F.Cu")
		(net "GND")
	)
	(segment
		(start 165.354 -73.914)
		(end 164.465 -73.914)
		(width 0.4064)
		(layer "F.Cu")
		(net "GND")
	)
	(segment
		(start 287.349946 -0.821182)
		(end 287.349946 -2.314956)
		(width 0.4064)
		(layer "F.Cu")
		(net "GND")
	)
	(segment
		(start 72.142096 -155.612846)
		(end 72.142096 -155.600146)
		(width 0.3556)
		(layer "F.Cu")
		(net "GND")
	)
	(segment
		(start 347.62567 -148.460714)
		(end 347.7641 -148.322284)
		(width 0.254)
		(layer "F.Cu")
		(net "GND")
	)
	(segment
		(start 278.920194 -96.023938)
		(end 279.491694 -96.023938)
		(width 0.254)
		(layer "F.Cu")
		(net "GND")
	)
	(segment
		(start 275.486114 -51.446938)
		(end 275.486114 -50.528474)
		(width 0.254)
		(layer "F.Cu")
		(net "GND")
	)
	(segment
		(start 279.699974 -137.67054)
		(end 279.699974 -136.397746)
		(width 0.4064)
		(layer "F.Cu")
		(net "GND")
	)
	(segment
		(start 38.199314 -15.602966)
		(end 38.199314 -17.208246)
		(width 0.4064)
		(layer "F.Cu")
		(net "GND")
	)
	(segment
		(start 125.749558 -9.156446)
		(end 125.749558 -10.422382)
		(width 0.4064)
		(layer "F.Cu")
		(net "GND")
	)
	(segment
		(start 215.950292 -15.423642)
		(end 215.949784 -15.423642)
		(width 0.4064)
		(layer "F.Cu")
		(net "GND")
	)
	(segment
		(start 174.396146 -145.667222)
		(end 175.055022 -145.667222)
		(width 0.254)
		(layer "F.Cu")
		(net "GND")
	)
	(segment
		(start 368.745262 -70.295262)
		(end 369.145058 -70.695058)
		(width 0.254)
		(layer "F.Cu")
		(net "GND")
	)
	(segment
		(start 464.4898 -50.4952)
		(end 464.4898 -50.572924)
		(width 0.508)
		(layer "F.Cu")
		(net "GND")
	)
	(segment
		(start 317.09995 -15.423642)
		(end 317.09995 -16.687546)
		(width 0.4064)
		(layer "F.Cu")
		(net "GND")
	)
	(segment
		(start 309.411878 -11.916156)
		(end 309.449978 -11.878056)
		(width 0.4064)
		(layer "F.Cu")
		(net "GND")
	)
	(segment
		(start 45.849286 -133.076696)
		(end 45.849286 -133.891274)
		(width 0.4064)
		(layer "F.Cu")
		(net "GND")
	)
	(segment
		(start 203.2 -133.076442)
		(end 203.2 -133.255512)
		(width 0.4064)
		(layer "F.Cu")
		(net "GND")
	)
	(segment
		(start 396.15745 -97.83572)
		(end 396.65275 -97.605596)
		(width 0.254)
		(layer "F.Cu")
		(net "GND")
	)
	(segment
		(start 4.482846 -6.671818)
		(end 4.482846 -7.098538)
		(width 0.254)
		(layer "F.Cu")
		(net "GND")
	)
	(segment
		(start 182.372 -57.0484)
		(end 182.372 -57.6834)
		(width 0.381)
		(layer "F.Cu")
		(net "GND")
	)
	(segment
		(start 176.836832 -95.10522)
		(end 176.582578 -95.359474)
		(width 0.254)
		(layer "F.Cu")
		(net "GND")
	)
	(segment
		(start 37.34943 -155.612846)
		(end 37.34943 -156.87294)
		(width 0.4064)
		(layer "F.Cu")
		(net "GND")
	)
	(segment
		(start 78.051406 -62.52464)
		(end 77.479906 -62.52464)
		(width 0.254)
		(layer "F.Cu")
		(net "GND")
	)
	(segment
		(start 482.8286 -137.7188)
		(end 482.8286 -138.5316)
		(width 0.254)
		(layer "F.Cu")
		(net "GND")
	)
	(segment
		(start 196.684138 -86.355682)
		(end 197.095364 -86.766908)
		(width 0.254)
		(layer "F.Cu")
		(net "GND")
	)
	(segment
		(start 125.080268 -88.594184)
		(end 125.651768 -88.594184)
		(width 0.254)
		(layer "F.Cu")
		(net "GND")
	)
	(segment
		(start 296.66184 -81.164938)
		(end 296.09034 -81.164938)
		(width 0.254)
		(layer "F.Cu")
		(net "GND")
	)
	(segment
		(start 311.15 -11.854688)
		(end 311.15 -10.422382)
		(width 0.4064)
		(layer "F.Cu")
		(net "GND")
	)
	(segment
		(start 217.4494 -134.876794)
		(end 217.472006 -134.8994)
		(width 0.3556)
		(layer "F.Cu")
		(net "GND")
	)
	(segment
		(start 279.221184 -53.8988)
		(end 279.207214 -53.923184)
		(width 0.254)
		(layer "F.Cu")
		(net "GND")
	)
	(segment
		(start 77.192886 -61.038486)
		(end 76.621386 -61.038486)
		(width 0.254)
		(layer "F.Cu")
		(net "GND")
	)
	(segment
		(start 145.082768 -17.207738)
		(end 145.12163 -17.2466)
		(width 0.3556)
		(layer "F.Cu")
		(net "GND")
	)
	(segment
		(start 227.792534 -136.410446)
		(end 227.792534 -136.397746)
		(width 0.3556)
		(layer "F.Cu")
		(net "GND")
	)
	(segment
		(start 315.399928 -10.422382)
		(end 315.399928 -11.916156)
		(width 0.4064)
		(layer "F.Cu")
		(net "GND")
	)
	(segment
		(start 30.865826 -85.81644)
		(end 31.536386 -86.487)
		(width 0.254)
		(layer "F.Cu")
		(net "GND")
	)
	(segment
		(start 120.216168 -55.409338)
		(end 120.787668 -55.409338)
		(width 0.254)
		(layer "F.Cu")
		(net "GND")
	)
	(segment
		(start 317.949834 -15.423642)
		(end 317.949834 -16.687546)
		(width 0.4064)
		(layer "F.Cu")
		(net "GND")
	)
	(segment
		(start 238.899954 -15.423642)
		(end 238.899954 -14.410182)
		(width 0.4064)
		(layer "F.Cu")
		(net "GND")
	)
	(segment
		(start 240.476278 -69.953886)
		(end 239.904778 -69.953886)
		(width 0.254)
		(layer "F.Cu")
		(net "GND")
	)
	(segment
		(start 111.344202 -53.923184)
		(end 110.772702 -53.923184)
		(width 0.254)
		(layer "F.Cu")
		(net "GND")
	)
	(segment
		(start 394.17625 -105.332276)
		(end 394.67155 -105.5624)
		(width 0.254)
		(layer "F.Cu")
		(net "GND")
	)
	(segment
		(start 197.095364 -62.772544)
		(end 197.095364 -62.348364)
		(width 0.254)
		(layer "F.Cu")
		(net "GND")
	)
	(segment
		(start 241.334798 -72.43064)
		(end 240.763298 -72.43064)
		(width 0.254)
		(layer "F.Cu")
		(net "GND")
	)
	(segment
		(start 283.212794 -58.876438)
		(end 282.641294 -58.876438)
		(width 0.254)
		(layer "F.Cu")
		(net "GND")
	)
	(segment
		(start 41.599358 -152.273)
		(end 41.599358 -153.965402)
		(width 0.4064)
		(layer "F.Cu")
		(net "GND")
	)
	(segment
		(start 37.34943 -20.023582)
		(end 37.34943 -21.517356)
		(width 0.4064)
		(layer "F.Cu")
		(net "GND")
	)
	(segment
		(start 122.504708 -68.287138)
		(end 123.076208 -68.287138)
		(width 0.254)
		(layer "F.Cu")
		(net "GND")
	)
	(segment
		(start 31.417768 -148.789644)
		(end 31.39948 -148.771356)
		(width 0.4064)
		(layer "F.Cu")
		(net "GND")
	)
	(segment
		(start 442.522356 -25.0317)
		(end 442.122052 -25.432004)
		(width 0.3048)
		(layer "F.Cu")
		(net "GND")
	)
	(segment
		(start 249.061224 -64.010286)
		(end 248.489724 -64.010286)
		(width 0.254)
		(layer "F.Cu")
		(net "GND")
	)
	(segment
		(start 73.899522 -4.808982)
		(end 73.899522 -5.822442)
		(width 0.4064)
		(layer "F.Cu")
		(net "GND")
	)
	(segment
		(start 394.67155 -98.69424)
		(end 394.903706 -98.58629)
		(width 0.254)
		(layer "F.Cu")
		(net "GND")
	)
	(segment
		(start 201.500486 -15.423642)
		(end 201.499978 -15.423642)
		(width 0.4064)
		(layer "F.Cu")
		(net "GND")
	)
	(segment
		(start 283.04236 -18.744946)
		(end 283.04236 -18.757646)
		(width 0.3556)
		(layer "F.Cu")
		(net "GND")
	)
	(segment
		(start 291.79774 -100.481638)
		(end 292.36924 -100.481638)
		(width 0.254)
		(layer "F.Cu")
		(net "GND")
	)
	(segment
		(start 377.108466 -93.544898)
		(end 377.108466 -93.091)
		(width 0.254)
		(layer "F.Cu")
		(net "GND")
	)
	(segment
		(start 309.449978 -11.878056)
		(end 309.449978 -10.422382)
		(width 0.4064)
		(layer "F.Cu")
		(net "GND")
	)
	(segment
		(start 68.607686 -98.681286)
		(end 68.036186 -98.681286)
		(width 0.254)
		(layer "F.Cu")
		(net "GND")
	)
	(segment
		(start 79.768192 -70.44944)
		(end 79.196692 -70.44944)
		(width 0.254)
		(layer "F.Cu")
		(net "GND")
	)
	(segment
		(start 130.84937 -3.762756)
		(end 130.84937 -5.822442)
		(width 0.4064)
		(layer "F.Cu")
		(net "GND")
	)
	(segment
		(start 501.200166 -121.310146)
		(end 500.44858 -120.55856)
		(width 0.508)
		(layer "F.Cu")
		(net "GND")
	)
	(segment
		(start 313.700414 -10.422382)
		(end 313.699906 -10.422382)
		(width 0.4064)
		(layer "F.Cu")
		(net "GND")
	)
	(segment
		(start 304.675286 -72.249538)
		(end 305.246786 -72.249538)
		(width 0.254)
		(layer "F.Cu")
		(net "GND")
	)
	(segment
		(start 206.59979 -153.965402)
		(end 206.501746 -154.063446)
		(width 0.4064)
		(layer "F.Cu")
		(net "GND")
	)
	(segment
		(start 369.8494 -127.762)
		(end 369.5954 -127.762)
		(width 0.254)
		(layer "F.Cu")
		(net "GND")
	)
	(segment
		(start 129.372868 -63.334138)
		(end 129.944368 -63.334138)
		(width 0.254)
		(layer "F.Cu")
		(net "GND")
	)
	(segment
		(start 464.540092 -51.875944)
		(end 464.541108 -51.875944)
		(width 0.4064)
		(layer "F.Cu")
		(net "GND")
	)
	(segment
		(start 117.353842 -61.352938)
		(end 116.782342 -61.352938)
		(width 0.254)
		(layer "F.Cu")
		(net "GND")
	)
	(segment
		(start 27.1526 -32.432498)
		(end 27.242516 -32.522414)
		(width 0.254)
		(layer "F.Cu")
		(net "GND")
	)
	(segment
		(start 113.061242 -61.847984)
		(end 112.489742 -61.847984)
		(width 0.254)
		(layer "F.Cu")
		(net "GND")
	)
	(segment
		(start 464.549744 -62.002924)
		(end 464.549998 -62.00267)
		(width 0.254)
		(layer "F.Cu")
		(net "GND")
	)
	(segment
		(start 276.344634 -53.923184)
		(end 275.773134 -53.923184)
		(width 0.254)
		(layer "F.Cu")
		(net "GND")
	)
	(segment
		(start 376.428 -119.355108)
		(end 376.335036 -119.85498)
		(width 0.254)
		(layer "F.Cu")
		(net "GND")
	)
	(segment
		(start 289.050476 -156.87294)
		(end 289.050476 -155.600654)
		(width 0.3556)
		(layer "F.Cu")
		(net "GND")
	)
	(segment
		(start 107.910376 -61.847984)
		(end 107.338876 -61.847984)
		(width 0.254)
		(layer "F.Cu")
		(net "GND")
	)
	(segment
		(start 195.549774 -13.929106)
		(end 195.094606 -13.929106)
		(width 0.4064)
		(layer "F.Cu")
		(net "GND")
	)
	(segment
		(start 204.049884 -9.156446)
		(end 204.049884 -10.422382)
		(width 0.4064)
		(layer "F.Cu")
		(net "GND")
	)
	(segment
		(start 225.299778 2.092198)
		(end 225.201734 1.994154)
		(width 0.4064)
		(layer "F.Cu")
		(net "GND")
	)
	(segment
		(start 294.3733 -72.249538)
		(end 294.9448 -72.249538)
		(width 0.254)
		(layer "F.Cu")
		(net "GND")
	)
	(segment
		(start 26.924 -2.237232)
		(end 26.896568 -2.2098)
		(width 0.4064)
		(layer "F.Cu")
		(net "GND")
	)
	(segment
		(start 379.81255 -115.236244)
		(end 379.31725 -115.00612)
		(width 0.254)
		(layer "F.Cu")
		(net "GND")
	)
	(segment
		(start 192.764918 -80.363568)
		(end 192.099438 -80.363568)
		(width 0.254)
		(layer "F.Cu")
		(net "GND")
	)
	(segment
		(start 136.799574 -0.821182)
		(end 136.799574 -2.253488)
		(width 0.4064)
		(layer "F.Cu")
		(net "GND")
	)
	(segment
		(start 61.796168 -17.2212)
		(end 61.796168 -16.357854)
		(width 0.3556)
		(layer "F.Cu")
		(net "GND")
	)
	(segment
		(start 203.2 -133.255512)
		(end 203.199746 -133.255766)
		(width 0.4064)
		(layer "F.Cu")
		(net "GND")
	)
	(segment
		(start 282.925774 -99.986338)
		(end 282.354274 -99.986338)
		(width 0.254)
		(layer "F.Cu")
		(net "GND")
	)
	(segment
		(start 207.449928 -148.733256)
		(end 207.449928 -147.27174)
		(width 0.4064)
		(layer "F.Cu")
		(net "GND")
	)
	(segment
		(start 173.8757 -126.99238)
		(end 173.8757 -127.88138)
		(width 0.381)
		(layer "F.Cu")
		(net "GND")
	)
	(segment
		(start 221.04985 -20.023582)
		(end 221.04985 -18.757646)
		(width 0.4064)
		(layer "F.Cu")
		(net "GND")
	)
	(segment
		(start 129.999486 -10.422382)
		(end 129.999486 -11.916156)
		(width 0.4064)
		(layer "F.Cu")
		(net "GND")
	)
	(segment
		(start 317.09995 -147.27174)
		(end 317.09995 -146.011646)
		(width 0.4064)
		(layer "F.Cu")
		(net "GND")
	)
	(segment
		(start 346.9894 -20.193)
		(end 346.9894 -20.955)
		(width 0.254)
		(layer "F.Cu")
		(net "GND")
	)
	(segment
		(start 239.617758 -83.32724)
		(end 239.046258 -83.32724)
		(width 0.254)
		(layer "F.Cu")
		(net "GND")
	)
	(segment
		(start 216.799922 -137.67054)
		(end 216.799922 -136.410446)
		(width 0.4064)
		(layer "F.Cu")
		(net "GND")
	)
	(segment
		(start 152.1206 -129.60096)
		(end 152.099518 -129.579878)
		(width 0.4064)
		(layer "F.Cu")
		(net "GND")
	)
	(segment
		(start 199.742552 0.231902)
		(end 199.742552 0.457454)
		(width 0.4064)
		(layer "F.Cu")
		(net "GND")
	)
	(segment
		(start 31.84906 -94.59722)
		(end 31.14802 -94.59722)
		(width 0.254)
		(layer "F.Cu")
		(net "GND")
	)
	(segment
		(start 401.295108 -99.85502)
		(end 401.786852 -99.363276)
		(width 0.254)
		(layer "F.Cu")
		(net "GND")
	)
	(segment
		(start 402.223986 -82.175096)
		(end 402.244814 -82.195924)
		(width 0.254)
		(layer "F.Cu")
		(net "GND")
	)
	(segment
		(start 415.890202 -29.734764)
		(end 415.890202 -28.934664)
		(width 0.254)
		(layer "F.Cu")
		(net "GND")
	)
	(segment
		(start 203.200508 -5.822442)
		(end 203.2 -5.822442)
		(width 0.4064)
		(layer "F.Cu")
		(net "GND")
	)
	(segment
		(start 381.29845 -111.57204)
		(end 381.79375 -111.802164)
		(width 0.254)
		(layer "F.Cu")
		(net "GND")
	)
	(segment
		(start 413.490156 -34.534602)
		(end 413.890206 -34.934652)
		(width 0.254)
		(layer "F.Cu")
		(net "GND")
	)
	(segment
		(start 398.63395 -117.58168)
		(end 398.834864 -117.679724)
		(width 0.254)
		(layer "F.Cu")
		(net "GND")
	)
	(segment
		(start 392.1379 -109.0549)
		(end 391.73785 -108.65485)
		(width 0.1143)
		(layer "F.Cu")
		(net "GND")
	)
	(segment
		(start 31.443168 -128.8542)
		(end 31.443168 -129.525268)
		(width 0.4064)
		(layer "F.Cu")
		(net "GND")
	)
	(segment
		(start 400.487134 -92.260674)
		(end 400.40052 -92.17406)
		(width 0.254)
		(layer "F.Cu")
		(net "GND")
	)
	(segment
		(start 208.0768 -7.600188)
		(end 208.0768 -6.781546)
		(width 0.3556)
		(layer "F.Cu")
		(net "GND")
	)
	(segment
		(start 234.753658 -59.057286)
		(end 233.608118 -59.057286)
		(width 0.254)
		(layer "F.Cu")
		(net "GND")
	)
	(segment
		(start 80.626712 -54.104286)
		(end 80.055212 -54.104286)
		(width 0.254)
		(layer "F.Cu")
		(net "GND")
	)
	(segment
		(start 204.050392 -10.422382)
		(end 204.049884 -10.422382)
		(width 0.4064)
		(layer "F.Cu")
		(net "GND")
	)
	(segment
		(start 135.382254 -97.509584)
		(end 135.953754 -97.509584)
		(width 0.254)
		(layer "F.Cu")
		(net "GND")
	)
	(segment
		(start 306.049934 -10.422382)
		(end 306.049934 -9.156446)
		(width 0.4064)
		(layer "F.Cu")
		(net "GND")
	)
	(segment
		(start 411.48 -89.59342)
		(end 411.451806 -89.621614)
		(width 0.254)
		(layer "F.Cu")
		(net "GND")
	)
	(segment
		(start 90.928698 -53.113686)
		(end 90.357198 -53.113686)
		(width 0.254)
		(layer "F.Cu")
		(net "GND")
	)
	(segment
		(start 303.499774 2.963926)
		(end 303.041304 2.505456)
		(width 0.4064)
		(layer "F.Cu")
		(net "GND")
	)
	(segment
		(start 351.72015 -138.32205)
		(end 351.798382 -138.243818)
		(width 0.508)
		(layer "F.Cu")
		(net "GND")
	)
	(segment
		(start 249.061224 -87.784686)
		(end 248.489724 -87.784686)
		(width 0.254)
		(layer "F.Cu")
		(net "GND")
	)
	(segment
		(start 146.092164 -146.011646)
		(end 146.092164 -145.998946)
		(width 0.3556)
		(layer "F.Cu")
		(net "GND")
	)
	(segment
		(start 184.2516 -76.3143)
		(end 184.2516 -76.45654)
		(width 0.508)
		(layer "F.Cu")
		(net "GND")
	)
	(segment
		(start 211.700364 -156.87294)
		(end 211.699856 -156.87294)
		(width 0.4064)
		(layer "F.Cu")
		(net "GND")
	)
	(segment
		(start 475.5769 -147.4089)
		(end 475.5769 -147.771612)
		(width 0.254)
		(layer "F.Cu")
		(net "GND")
	)
	(segment
		(start 306.963826 -67.296538)
		(end 306.392326 -67.296538)
		(width 0.254)
		(layer "F.Cu")
		(net "GND")
	)
	(segment
		(start 392.687048 -118.6688)
		(end 392.69035 -118.670324)
		(width 0.254)
		(layer "F.Cu")
		(net "GND")
	)
	(segment
		(start 378.299726 -106.408474)
		(end 378.32665 -106.42092)
		(width 0.254)
		(layer "F.Cu")
		(net "GND")
	)
	(segment
		(start 54.737508 -13.948156)
		(end 55.199534 -14.410182)
		(width 0.4064)
		(layer "F.Cu")
		(net "GND")
	)
	(segment
		(start 237.042198 -68.963286)
		(end 236.470698 -68.963286)
		(width 0.254)
		(layer "F.Cu")
		(net "GND")
	)
	(segment
		(start 379.81255 -110.085124)
		(end 379.31725 -109.855)
		(width 0.254)
		(layer "F.Cu")
		(net "GND")
	)
	(segment
		(start 492.47298 -121.80062)
		(end 492.506 -121.7676)
		(width 0.254)
		(layer "F.Cu")
		(net "GND")
	)
	(segment
		(start 64.087502 -13.948156)
		(end 64.549528 -14.410182)
		(width 0.4064)
		(layer "F.Cu")
		(net "GND")
	)
	(segment
		(start 397.7894 -114.215418)
		(end 398.13865 -114.377724)
		(width 0.254)
		(layer "F.Cu")
		(net "GND")
	)
	(segment
		(start 61.999368 -133.807454)
		(end 61.796168 -134.010654)
		(width 0.3556)
		(layer "F.Cu")
		(net "GND")
	)
	(segment
		(start 113.061242 -101.472746)
		(end 112.774222 -100.976684)
		(width 0.1524)
		(layer "F.Cu")
		(net "GND")
	)
	(segment
		(start 253.353824 -81.34604)
		(end 252.782324 -81.34604)
		(width 0.254)
		(layer "F.Cu")
		(net "GND")
	)
	(segment
		(start 208.299812 -5.822442)
		(end 208.299812 -3.940556)
		(width 0.4064)
		(layer "F.Cu")
		(net "GND")
	)
	(segment
		(start 350.41332 -14.859)
		(end 350.012 -14.859)
		(width 0.2032)
		(layer "F.Cu")
		(net "GND")
	)
	(segment
		(start 118.099332 -0.821182)
		(end 118.099332 0.38735)
		(width 0.3556)
		(layer "F.Cu")
		(net "GND")
	)
	(segment
		(start 46.699424 -155.612846)
		(end 46.699424 -156.87294)
		(width 0.4064)
		(layer "F.Cu")
		(net "GND")
	)
	(segment
		(start 303.3395 -102.348792)
		(end 303.3395 -102.708456)
		(width 0.254)
		(layer "F.Cu")
		(net "GND")
	)
	(segment
		(start 208.299812 3.042666)
		(end 208.0768 2.819654)
		(width 0.3556)
		(layer "F.Cu")
		(net "GND")
	)
	(segment
		(start 290.93922 -99.986338)
		(end 291.51072 -99.986338)
		(width 0.254)
		(layer "F.Cu")
		(net "GND")
	)
	(segment
		(start 442.200792 -113.909094)
		(end 442.204602 -113.912904)
		(width 0.4064)
		(layer "F.Cu")
		(net "GND")
	)
	(segment
		(start 412.965646 -21.510244)
		(end 412.965646 -21.945854)
		(width 0.254)
		(layer "F.Cu")
		(net "GND")
	)
	(segment
		(start 369.2652 -93.476572)
		(end 371.073172 -93.476572)
		(width 0.254)
		(layer "F.Cu")
		(net "GND")
	)
	(segment
		(start 33.949386 3.065018)
		(end 33.754568 2.8702)
		(width 0.3556)
		(layer "F.Cu")
		(net "GND")
	)
	(segment
		(start 176.582578 -95.359474)
		(end 176.582578 -96.310704)
		(width 0.254)
		(layer "F.Cu")
		(net "GND")
	)
	(segment
		(start 216.799922 -11.878056)
		(end 216.761822 -11.916156)
		(width 0.4064)
		(layer "F.Cu")
		(net "GND")
	)
	(segment
		(start 317.246 -129.725928)
		(end 317.246 -130.3528)
		(width 0.4064)
		(layer "F.Cu")
		(net "GND")
	)
	(segment
		(start 125.749558 -156.87294)
		(end 125.749558 -155.612846)
		(width 0.4064)
		(layer "F.Cu")
		(net "GND")
	)
	(segment
		(start 295.23182 -60.857384)
		(end 295.80332 -60.857384)
		(width 0.254)
		(layer "F.Cu")
		(net "GND")
	)
	(segment
		(start 470.0778 -39.624)
		(end 470.75471 -38.94709)
		(width 0.254)
		(layer "F.Cu")
		(net "GND")
	)
	(segment
		(start 446.141094 -52.841906)
		(end 446.141094 -51.875944)
		(width 0.4064)
		(layer "F.Cu")
		(net "GND")
	)
	(segment
		(start 145.29943 -152.996138)
		(end 145.082768 -153.2128)
		(width 0.3556)
		(layer "F.Cu")
		(net "GND")
	)
	(segment
		(start 56.899302 -6.001766)
		(end 56.899302 -7.607046)
		(width 0.4064)
		(layer "F.Cu")
		(net "GND")
	)
	(segment
		(start 237.900718 -89.27084)
		(end 237.329218 -89.27084)
		(width 0.254)
		(layer "F.Cu")
		(net "GND")
	)
	(segment
		(start 260.50875 -95.709486)
		(end 261.08025 -95.709486)
		(width 0.254)
		(layer "F.Cu")
		(net "GND")
	)
	(segment
		(start 247.344184 -99.67214)
		(end 247.344184 -100.662486)
		(width 0.254)
		(layer "F.Cu")
		(net "GND")
	)
	(segment
		(start 208.0768 -6.781546)
		(end 208.299812 -6.558534)
		(width 0.3556)
		(layer "F.Cu")
		(net "GND")
	)
	(segment
		(start 139.674854 -72.249538)
		(end 140.246354 -72.249538)
		(width 0.254)
		(layer "F.Cu")
		(net "GND")
	)
	(segment
		(start 201.500486 -133.0706)
		(end 201.499978 -133.076442)
		(width 0.4064)
		(layer "F.Cu")
		(net "GND")
	)
	(segment
		(start 212.549994 -142.856712)
		(end 212.54974 -142.856966)
		(width 0.4064)
		(layer "F.Cu")
		(net "GND")
	)
	(segment
		(start 128.514348 -74.725784)
		(end 129.085848 -74.725784)
		(width 0.254)
		(layer "F.Cu")
		(net "GND")
	)
	(segment
		(start 196.40042 -137.67054)
		(end 196.399912 -137.67054)
		(width 0.4064)
		(layer "F.Cu")
		(net "GND")
	)
	(segment
		(start 376.335036 -121.854976)
		(end 376.375422 -122.0724)
		(width 0.254)
		(layer "F.Cu")
		(net "GND")
	)
	(segment
		(start 281.361896 -11.916156)
		(end 281.399996 -11.878056)
		(width 0.4064)
		(layer "F.Cu")
		(net "GND")
	)
	(segment
		(start 240.599722 3.599434)
		(end 240.599722 1.994154)
		(width 0.4064)
		(layer "F.Cu")
		(net "GND")
	)
	(segment
		(start 468.658194 -43.053)
		(end 467.995 -43.053)
		(width 0.254)
		(layer "F.Cu")
		(net "GND")
	)
	(segment
		(start 56.899556 -152.457912)
		(end 56.899302 -152.458166)
		(width 0.4064)
		(layer "F.Cu")
		(net "GND")
	)
	(segment
		(start 74.617326 -88.28024)
		(end 74.045826 -88.28024)
		(width 0.254)
		(layer "F.Cu")
		(net "GND")
	)
	(segment
		(start 136.240774 -74.230738)
		(end 136.812274 -74.23023)
		(width 0.254)
		(layer "F.Cu")
		(net "GND")
	)
	(segment
		(start 295.23182 -76.706984)
		(end 295.80332 -76.706984)
		(width 0.254)
		(layer "F.Cu")
		(net "GND")
	)
	(segment
		(start 401.98548 -100.49002)
		(end 401.828 -100.6475)
		(width 0.1524)
		(layer "F.Cu")
		(net "GND")
	)
	(segment
		(start 32.15132 -17.208246)
		(end 32.249364 -17.110202)
		(width 0.4064)
		(layer "F.Cu")
		(net "GND")
	)
	(segment
		(start 28.067 -102.235)
		(end 28.040838 -102.261162)
		(width 0.4064)
		(layer "F.Cu")
		(net "GND")
	)
	(segment
		(start 388.53745 -107.05465)
		(end 388.9375 -106.6546)
		(width 0.254)
		(layer "F.Cu")
		(net "GND")
	)
	(segment
		(start 196.399912 -20.023582)
		(end 196.399912 -21.517356)
		(width 0.4064)
		(layer "F.Cu")
		(net "GND")
	)
	(segment
		(start 213.399878 -147.27174)
		(end 213.399878 -146.011646)
		(width 0.4064)
		(layer "F.Cu")
		(net "GND")
	)
	(segment
		(start 221.899734 -3.762756)
		(end 221.899988 -3.76301)
		(width 0.4064)
		(layer "F.Cu")
		(net "GND")
	)
	(segment
		(start 394.17625 -118.4402)
		(end 394.668248 -118.6688)
		(width 0.254)
		(layer "F.Cu")
		(net "GND")
	)
	(segment
		(start 225.299778 -7.509002)
		(end 225.201734 -7.607046)
		(width 0.4064)
		(layer "F.Cu")
		(net "GND")
	)
	(segment
		(start 29.810202 -106.023664)
		(end 29.705046 -105.918508)
		(width 0.4064)
		(layer "F.Cu")
		(net "GND")
	)
	(segment
		(start 107.051856 -63.334138)
		(end 106.480356 -63.334138)
		(width 0.254)
		(layer "F.Cu")
		(net "GND")
	)
	(segment
		(start 422.874186 -4.386072)
		(end 422.874186 -3.384042)
		(width 0.254)
		(layer "F.Cu")
		(net "GND")
	)
	(segment
		(start 86.636352 -59.55284)
		(end 86.064852 -59.55284)
		(width 0.254)
		(layer "F.Cu")
		(net "GND")
	)
	(segment
		(start 65.399412 -156.87294)
		(end 65.399412 -155.612846)
		(width 0.4064)
		(layer "F.Cu")
		(net "GND")
	)
	(segment
		(start 304.31232 -52.437538)
		(end 304.675286 -52.437538)
		(width 0.254)
		(layer "F.Cu")
		(net "GND")
	)
	(segment
		(start 44.149518 0.34925)
		(end 44.149518 -0.821182)
		(width 0.4064)
		(layer "F.Cu")
		(net "GND")
	)
	(segment
		(start 91.787218 -60.54344)
		(end 91.215718 -60.54344)
		(width 0.254)
		(layer "F.Cu")
		(net "GND")
	)
	(segment
		(start 129.999486 -147.27174)
		(end 129.999486 -146.011646)
		(width 0.4064)
		(layer "F.Cu")
		(net "GND")
	)
	(segment
		(start 450.20103 -118.615714)
		(end 450.204586 -118.61927)
		(width 0.4064)
		(layer "F.Cu")
		(net "GND")
	)
	(segment
		(start 120.649492 -147.27174)
		(end 120.649492 -146.011646)
		(width 0.4064)
		(layer "F.Cu")
		(net "GND")
	)
	(segment
		(start 78.051406 -70.44944)
		(end 77.479906 -70.44944)
		(width 0.254)
		(layer "F.Cu")
		(net "GND")
	)
	(segment
		(start 389.984996 -125.33503)
		(end 389.89 -125.430026)
		(width 0.254)
		(layer "F.Cu")
		(net "GND")
	)
	(segment
		(start 459.678278 -8.850122)
		(end 459.678278 -7.789672)
		(width 0.254)
		(layer "F.Cu")
		(net "GND")
	)
	(segment
		(start 288.36366 -94.538038)
		(end 288.93516 -94.538038)
		(width 0.3048)
		(layer "F.Cu")
		(net "GND")
	)
	(segment
		(start 423.089832 -36.134548)
		(end 422.690036 -35.734752)
		(width 0.254)
		(layer "F.Cu")
		(net "GND")
	)
	(segment
		(start 53.442108 -9.156446)
		(end 53.442108 -9.143746)
		(width 0.3556)
		(layer "F.Cu")
		(net "GND")
	)
	(segment
		(start 204.049884 -20.023582)
		(end 204.049884 -21.517356)
		(width 0.4064)
		(layer "F.Cu")
		(net "GND")
	)
	(segment
		(start 120.787668 -77.202538)
		(end 121.359168 -77.202538)
		(width 0.254)
		(layer "F.Cu")
		(net "GND")
	)
	(segment
		(start 306.024026 -52.497228)
		(end 306.262786 -52.497228)
		(width 0.254)
		(layer "F.Cu")
		(net "GND")
	)
	(segment
		(start 274.627848 -54.913784)
		(end 274.056348 -54.913784)
		(width 0.254)
		(layer "F.Cu")
		(net "GND")
	)
	(segment
		(start 208.0768 2.001012)
		(end 208.122012 1.9558)
		(width 0.3556)
		(layer "F.Cu")
		(net "GND")
	)
	(segment
		(start 124.221748 -58.381138)
		(end 123.650248 -58.381138)
		(width 0.254)
		(layer "F.Cu")
		(net "GND")
	)
	(segment
		(start 255.07061 -85.30844)
		(end 254.49911 -85.30844)
		(width 0.254)
		(layer "F.Cu")
		(net "GND")
	)
	(segment
		(start 79.768192 -72.43064)
		(end 79.196692 -72.43064)
		(width 0.254)
		(layer "F.Cu")
		(net "GND")
	)
	(segment
		(start 240.476278 -58.06694)
		(end 239.904778 -58.06694)
		(width 0.254)
		(layer "F.Cu")
		(net "GND")
	)
	(segment
		(start 425.274486 -2.941828)
		(end 424.796458 -2.4638)
		(width 0.254)
		(layer "F.Cu")
		(net "GND")
	)
	(segment
		(start 276.344634 -94.538038)
		(end 276.916134 -94.538038)
		(width 0.254)
		(layer "F.Cu")
		(net "GND")
	)
	(segment
		(start 208.30032 -133.0706)
		(end 208.299812 -133.076442)
		(width 0.3556)
		(layer "F.Cu")
		(net "GND")
	)
	(segment
		(start 31.468568 -2.384044)
		(end 31.39948 -2.314956)
		(width 0.381)
		(layer "F.Cu")
		(net "GND")
	)
	(segment
		(start 480.1616 -140.8684)
		(end 480.8728 -140.8684)
		(width 0.254)
		(layer "F.Cu")
		(net "GND")
	)
	(segment
		(start 445.276986 -7.789672)
		(end 445.276986 -8.9662)
		(width 0.254)
		(layer "F.Cu")
		(net "GND")
	)
	(segment
		(start 125.938788 -53.427884)
		(end 126.467616 -53.427884)
		(width 0.254)
		(layer "F.Cu")
		(net "GND")
	)
	(segment
		(start 457.400914 -112.205516)
		(end 457.400914 -113.776506)
		(width 0.4064)
		(layer "F.Cu")
		(net "GND")
	)
	(segment
		(start 278.95169 -17.29486)
		(end 278.849836 -17.193006)
		(width 0.4064)
		(layer "F.Cu")
		(net "GND")
	)
	(segment
		(start 303.499774 3.778758)
		(end 303.499774 2.963926)
		(width 0.4064)
		(layer "F.Cu")
		(net "GND")
	)
	(segment
		(start 73.758806 -91.747086)
		(end 73.187306 -91.747086)
		(width 0.254)
		(layer "F.Cu")
		(net "GND")
	)
	(segment
		(start 226.7966 -143.611854)
		(end 226.7966 -144.4752)
		(width 0.3556)
		(layer "F.Cu")
		(net "GND")
	)
	(segment
		(start 383.790698 -80.941926)
		(end 384.893566 -80.941926)
		(width 0.254)
		(layer "F.Cu")
		(net "GND")
	)
	(segment
		(start 171.983146 -147.42922)
		(end 170.547538 -147.42922)
		(width 0.254)
		(layer "F.Cu")
		(net "GND")
	)
	(segment
		(start 248.202704 -67.47764)
		(end 247.631204 -67.47764)
		(width 0.1524)
		(layer "F.Cu")
		(net "GND")
	)
	(segment
		(start 386.985002 -95.205042)
		(end 387.985 -95.205042)
		(width 0.254)
		(layer "F.Cu")
		(net "GND")
	)
	(segment
		(start 290.74999 -10.422382)
		(end 290.74999 -9.156446)
		(width 0.4064)
		(layer "F.Cu")
		(net "GND")
	)
	(segment
		(start 130.231388 -62.838584)
		(end 130.802888 -62.838584)
		(width 0.254)
		(layer "F.Cu")
		(net "GND")
	)
	(segment
		(start 496.704874 -41.619932)
		(end 497.73078 -41.619932)
		(width 0.254)
		(layer "F.Cu")
		(net "GND")
	)
	(segment
		(start 278.849836 -10.422382)
		(end 278.849836 -11.857736)
		(width 0.4064)
		(layer "F.Cu")
		(net "GND")
	)
	(segment
		(start 291.79774 -87.603584)
		(end 292.36924 -87.603584)
		(width 0.254)
		(layer "F.Cu")
		(net "GND")
	)
	(segment
		(start 250.778264 -53.113686)
		(end 251.065284 -53.608732)
		(width 0.254)
		(layer "F.Cu")
		(net "GND")
	)
	(segment
		(start 81.485232 -62.52464)
		(end 80.913732 -62.52464)
		(width 0.254)
		(layer "F.Cu")
		(net "GND")
	)
	(segment
		(start 278.850344 -142.6718)
		(end 278.849836 -142.6718)
		(width 0.508)
		(layer "F.Cu")
		(net "GND")
	)
	(segment
		(start 135.949436 -133.821678)
		(end 135.735568 -134.035546)
		(width 0.3556)
		(layer "F.Cu")
		(net "GND")
	)
	(segment
		(start 350.906842 -138.737848)
		(end 351.364042 -138.737848)
		(width 0.508)
		(layer "F.Cu")
		(net "GND")
	)
	(segment
		(start 305.199796 -5.822442)
		(end 305.199796 -3.762756)
		(width 0.4064)
		(layer "F.Cu")
		(net "GND")
	)
	(segment
		(start 303.816766 -60.857384)
		(end 304.388266 -60.857384)
		(width 0.254)
		(layer "F.Cu")
		(net "GND")
	)
	(segment
		(start 220.199966 -4.808982)
		(end 220.199966 -5.822442)
		(width 0.4064)
		(layer "F.Cu")
		(net "GND")
	)
	(segment
		(start 87.494872 -53.113686)
		(end 88.640412 -53.113686)
		(width 0.254)
		(layer "F.Cu")
		(net "GND")
	)
	(segment
		(start 281.400504 -0.821182)
		(end 281.399996 -0.821182)
		(width 0.4064)
		(layer "F.Cu")
		(net "GND")
	)
	(segment
		(start 67.949572 3.778758)
		(end 67.949318 3.778504)
		(width 0.4064)
		(layer "F.Cu")
		(net "GND")
	)
	(segment
		(start 303.500282 -142.6718)
		(end 303.499774 -142.677642)
		(width 0.4064)
		(layer "F.Cu")
		(net "GND")
	)
	(segment
		(start 313.700414 -156.87294)
		(end 313.699906 -156.87294)
		(width 0.4064)
		(layer "F.Cu")
		(net "GND")
	)
	(segment
		(start 251.636784 -86.29904)
		(end 251.065284 -86.29904)
		(width 0.254)
		(layer "F.Cu")
		(net "GND")
	)
	(segment
		(start 392.1379 -110.6551)
		(end 391.73785 -111.05515)
		(width 0.254)
		(layer "F.Cu")
		(net "GND")
	)
	(segment
		(start 38.199314 -13.363956)
		(end 38.199568 -13.36421)
		(width 0.4064)
		(layer "F.Cu")
		(net "GND")
	)
	(segment
		(start 385.75615 -123.821444)
		(end 385.26085 -123.59132)
		(width 0.254)
		(layer "F.Cu")
		(net "GND")
	)
	(segment
		(start 317.100458 3.778758)
		(end 317.09995 3.778758)
		(width 0.4064)
		(layer "F.Cu")
		(net "GND")
	)
	(segment
		(start 145.29943 -142.6718)
		(end 145.29943 -143.394938)
		(width 0.3556)
		(layer "F.Cu")
		(net "GND")
	)
	(segment
		(start 377.98502 -95.205042)
		(end 377.093988 -95.498666)
		(width 0.254)
		(layer "F.Cu")
		(net "GND")
	)
	(segment
		(start 248.202704 -95.21444)
		(end 247.631204 -95.21444)
		(width 0.254)
		(layer "F.Cu")
		(net "GND")
	)
	(segment
		(start 211.700364 -20.023582)
		(end 211.699856 -20.023582)
		(width 0.4064)
		(layer "F.Cu")
		(net "GND")
	)
	(segment
		(start 95.508318 -53.113686)
		(end 96.079818 -53.113686)
		(width 0.254)
		(layer "F.Cu")
		(net "GND")
	)
	(segment
		(start 390.906 -150.347426)
		(end 391.795 -150.347426)
		(width 0.4064)
		(layer "F.Cu")
		(net "GND")
	)
	(segment
		(start 84.060792 -67.972686)
		(end 83.489292 -67.972686)
		(width 0.254)
		(layer "F.Cu")
		(net "GND")
	)
	(segment
		(start 231.25049 -7.606284)
		(end 231.249728 -7.607046)
		(width 0.4064)
		(layer "F.Cu")
		(net "GND")
	)
	(segment
		(start 431.785014 -20.944078)
		(end 431.785014 -21.505672)
		(width 0.254)
		(layer "F.Cu")
		(net "GND")
	)
	(segment
		(start 55.199534 -15.423642)
		(end 55.19928 -15.423896)
		(width 0.4064)
		(layer "F.Cu")
		(net "GND")
	)
	(segment
		(start 347.829632 -12.821666)
		(end 347.829632 -13.742416)
		(width 0.2032)
		(layer "F.Cu")
		(net "GND")
	)
	(segment
		(start 413.511492 -43.356022)
		(end 413.511492 -43.904916)
		(width 0.254)
		(layer "F.Cu")
		(net "GND")
	)
	(segment
		(start 306.899818 -17.208246)
		(end 306.899818 -15.423642)
		(width 0.4064)
		(layer "F.Cu")
		(net "GND")
	)
	(segment
		(start 71.349362 -6.550406)
		(end 71.117968 -6.7818)
		(width 0.3556)
		(layer "F.Cu")
		(net "GND")
	)
	(segment
		(start 395.182852 -156.987748)
		(end 394.9192 -157.2514)
		(width 0.2032)
		(layer "F.Cu")
		(net "GND")
	)
	(segment
		(start 201.499724 -133.076696)
		(end 201.499724 -133.891274)
		(width 0.4064)
		(layer "F.Cu")
		(net "GND")
	)
	(segment
		(start 294.999918 -0.821182)
		(end 294.999918 0.444754)
		(width 0.4064)
		(layer "F.Cu")
		(net "GND")
	)
	(segment
		(start 451.749922 -53.236622)
		(end 451.74281 -52.2478)
		(width 0.4064)
		(layer "F.Cu")
		(net "GND")
	)
	(segment
		(start 255.92913 -88.775286)
		(end 255.35763 -88.775286)
		(width 0.254)
		(layer "F.Cu")
		(net "GND")
	)
	(segment
		(start 272.910808 -58.876438)
		(end 272.339308 -58.876438)
		(width 0.254)
		(layer "F.Cu")
		(net "GND")
	)
	(segment
		(start 439.676286 -4.386072)
		(end 439.676286 -3.442716)
		(width 0.254)
		(layer "F.Cu")
		(net "GND")
	)
	(segment
		(start 259.36321 -95.709486)
		(end 258.79171 -95.709486)
		(width 0.254)
		(layer "F.Cu")
		(net "GND")
	)
	(segment
		(start 136.240774 -54.418738)
		(end 136.812274 -54.418738)
		(width 0.254)
		(layer "F.Cu")
		(net "GND")
	)
	(segment
		(start 281.400504 -20.023582)
		(end 281.399996 -20.023582)
		(width 0.4064)
		(layer "F.Cu")
		(net "GND")
	)
	(segment
		(start 131.089908 -100.976684)
		(end 131.661408 -100.976684)
		(width 0.254)
		(layer "F.Cu")
		(net "GND")
	)
	(segment
		(start 289.22218 -95.033084)
		(end 289.79368 -95.033084)
		(width 0.3048)
		(layer "F.Cu")
		(net "GND")
	)
	(segment
		(start 182.6514 -145.288)
		(end 182.6006 -145.288)
		(width 0.254)
		(layer "F.Cu")
		(net "GND")
	)
	(segment
		(start 277.203154 -61.352938)
		(end 276.631654 -61.352938)
		(width 0.254)
		(layer "F.Cu")
		(net "GND")
	)
	(segment
		(start 202.349862 -20.023582)
		(end 202.349862 -18.757646)
		(width 0.4064)
		(layer "F.Cu")
		(net "GND")
	)
	(segment
		(start 152.949402 -15.423642)
		(end 152.949402 -16.687546)
		(width 0.4064)
		(layer "F.Cu")
		(net "GND")
	)
	(segment
		(start 30.101794 -4.277106)
		(end 29.591 -3.766312)
		(width 0.4064)
		(layer "F.Cu")
		(net "GND")
	)
	(segment
		(start 73.758806 -80.850486)
		(end 73.187306 -80.850486)
		(width 0.254)
		(layer "F.Cu")
		(net "GND")
	)
	(segment
		(start 496.704874 -37.61994)
		(end 498.032532 -37.61994)
		(width 0.254)
		(layer "F.Cu")
		(net "GND")
	)
	(segment
		(start 458.14107 -50.909982)
		(end 458.258164 -50.792888)
		(width 0.508)
		(layer "F.Cu")
		(net "GND")
	)
	(segment
		(start 293.51478 -60.857384)
		(end 294.08628 -60.857384)
		(width 0.254)
		(layer "F.Cu")
		(net "GND")
	)
	(segment
		(start 62.849506 -2.253488)
		(end 62.792102 -2.310892)
		(width 0.4064)
		(layer "F.Cu")
		(net "GND")
	)
	(segment
		(start 102.7938 -149.8092)
		(end 103.678736 -149.8092)
		(width 0.4064)
		(layer "F.Cu")
		(net "GND")
	)
	(segment
		(start 31.6865 -61.599064)
		(end 31.6865 -61.9125)
		(width 0.254)
		(layer "F.Cu")
		(net "GND")
	)
	(segment
		(start 281.495754 -54.913784)
		(end 280.924254 -54.913784)
		(width 0.254)
		(layer "F.Cu")
		(net "GND")
	)
	(segment
		(start 477.2406 -40.3479)
		(end 477.3041 -40.4114)
		(width 0.254)
		(layer "F.Cu")
		(net "GND")
	)
	(segment
		(start 238.759238 -82.83194)
		(end 238.187738 -82.83194)
		(width 0.254)
		(layer "F.Cu")
		(net "GND")
	)
	(segment
		(start 198.949818 -142.677642)
		(end 198.949818 -143.391382)
		(width 0.3556)
		(layer "F.Cu")
		(net "GND")
	)
	(segment
		(start 244.768624 -66.48704)
		(end 244.197124 -66.48704)
		(width 0.254)
		(layer "F.Cu")
		(net "GND")
	)
	(segment
		(start 240.599976 -134.860792)
		(end 240.599976 -133.076442)
		(width 0.4064)
		(layer "F.Cu")
		(net "GND")
	)
	(segment
		(start 73.899522 -133.0706)
		(end 73.899522 -133.076442)
		(width 0.4064)
		(layer "F.Cu")
		(net "GND")
	)
	(segment
		(start 464.439 -0.254)
		(end 464.439 -0.85725)
		(width 0.254)
		(layer "F.Cu")
		(net "GND")
	)
	(segment
		(start 398.225518 -126.93269)
		(end 398.225518 -126.341886)
		(width 0.254)
		(layer "F.Cu")
		(net "GND")
	)
	(segment
		(start 294.3733 -94.042738)
		(end 294.9448 -94.042738)
		(width 0.3048)
		(layer "F.Cu")
		(net "GND")
	)
	(segment
		(start 118.041928 -11.912092)
		(end 118.099332 -11.854688)
		(width 0.4064)
		(layer "F.Cu")
		(net "GND")
	)
	(segment
		(start 209.14995 -137.67054)
		(end 209.14995 -136.50595)
		(width 0.4064)
		(layer "F.Cu")
		(net "GND")
	)
	(segment
		(start 393.670282 -113.523014)
		(end 393.68095 -113.519204)
		(width 0.254)
		(layer "F.Cu")
		(net "GND")
	)
	(segment
		(start 204.049884 -137.67054)
		(end 204.049884 -139.170156)
		(width 0.4064)
		(layer "F.Cu")
		(net "GND")
	)
	(segment
		(start 87.494872 -65.000886)
		(end 86.923372 -65.000886)
		(width 0.254)
		(layer "F.Cu")
		(net "GND")
	)
	(segment
		(start 278.0538 -140.208)
		(end 277.397464 -140.208)
		(width 0.4572)
		(layer "F.Cu")
		(net "GND")
	)
	(segment
		(start 413.272986 -4.386072)
		(end 413.272986 -3.083814)
		(width 0.254)
		(layer "F.Cu")
		(net "GND")
	)
	(segment
		(start 233.799888 -20.023582)
		(end 233.799888 -18.744946)
		(width 0.4064)
		(layer "F.Cu")
		(net "GND")
	)
	(segment
		(start 77.299312 -133.076696)
		(end 77.299312 -134.861046)
		(width 0.4064)
		(layer "F.Cu")
		(net "GND")
	)
	(segment
		(start 294.14978 -133.076442)
		(end 294.14978 -133.891274)
		(width 0.4064)
		(layer "F.Cu")
		(net "GND")
	)
	(segment
		(start 236.183678 -68.46824)
		(end 235.612178 -68.46824)
		(width 0.254)
		(layer "F.Cu")
		(net "GND")
	)
	(segment
		(start 376.295666 -93.544898)
		(end 375.827798 -92.886022)
		(width 0.254)
		(layer "F.Cu")
		(net "GND")
	)
	(segment
		(start 393.18565 -120.15724)
		(end 393.68095 -120.387364)
		(width 0.254)
		(layer "F.Cu")
		(net "GND")
	)
	(segment
		(start 387.985 -126.165102)
		(end 387.731 -126.419102)
		(width 0.254)
		(layer "F.Cu")
		(net "GND")
	)
	(segment
		(start 381.99568 -104.996742)
		(end 382.288542 -104.70388)
		(width 0.12446)
		(layer "F.Cu")
		(net "GND")
	)
	(segment
		(start 133.665214 -75.716384)
		(end 134.236714 -75.716384)
		(width 0.254)
		(layer "F.Cu")
		(net "GND")
	)
	(segment
		(start 212.550502 -5.822442)
		(end 212.549994 -5.822442)
		(width 0.4064)
		(layer "F.Cu")
		(net "GND")
	)
	(segment
		(start 407.793698 -54.229)
		(end 409.18257 -55.617872)
		(width 0.254)
		(layer "F.Cu")
		(net "GND")
	)
	(segment
		(start 119.799354 -152.278842)
		(end 119.7991 -152.279096)
		(width 0.4064)
		(layer "F.Cu")
		(net "GND")
	)
	(segment
		(start 198.949818 3.065018)
		(end 198.755 2.8702)
		(width 0.3556)
		(layer "F.Cu")
		(net "GND")
	)
	(segment
		(start 209.14995 -146.10715)
		(end 209.092546 -146.049746)
		(width 0.4064)
		(layer "F.Cu")
		(net "GND")
	)
	(segment
		(start 182.890922 -148.3487)
		(end 182.890922 -149.784308)
		(width 0.3048)
		(layer "F.Cu")
		(net "GND")
	)
	(segment
		(start 373.485156 -7.789926)
		(end 373.485156 -7.850124)
		(width 0.254)
		(layer "F.Cu")
		(net "GND")
	)
	(segment
		(start 61.149484 -156.87294)
		(end 61.149484 -155.612846)
		(width 0.4064)
		(layer "F.Cu")
		(net "GND")
	)
	(segment
		(start 277.203154 -54.418738)
		(end 276.631654 -54.418738)
		(width 0.254)
		(layer "F.Cu")
		(net "GND")
	)
	(segment
		(start 389.7376 -102.765606)
		(end 390.21385 -102.98684)
		(width 0.254)
		(layer "F.Cu")
		(net "GND")
	)
	(segment
		(start 15.264384 3.507232)
		(end 15.532608 3.239008)
		(width 0.254)
		(layer "F.Cu")
		(net "GND")
	)
	(segment
		(start 282.24988 -142.677642)
		(end 282.24988 -143.403574)
		(width 0.3556)
		(layer "F.Cu")
		(net "GND")
	)
	(segment
		(start 400.467576 -126.18466)
		(end 399.693892 -126.18466)
		(width 0.254)
		(layer "F.Cu")
		(net "GND")
	)
	(segment
		(start 124.049536 -2.314956)
		(end 124.049536 -0.821182)
		(width 0.4064)
		(layer "F.Cu")
		(net "GND")
	)
	(segment
		(start 69.64934 -134.763002)
		(end 69.551296 -134.861046)
		(width 0.4064)
		(layer "F.Cu")
		(net "GND")
	)
	(segment
		(start 69.753226 -60.047886)
		(end 70.324726 -60.047886)
		(width 0.254)
		(layer "F.Cu")
		(net "GND")
	)
	(segment
		(start 144.449546 -156.87294)
		(end 144.449546 -155.612846)
		(width 0.4064)
		(layer "F.Cu")
		(net "GND")
	)
	(segment
		(start 199.799956 -146.281902)
		(end 199.742552 -146.224498)
		(width 0.4064)
		(layer "F.Cu")
		(net "GND")
	)
	(segment
		(start 141.391894 -58.381138)
		(end 141.963394 -58.381138)
		(width 0.254)
		(layer "F.Cu")
		(net "GND")
	)
	(segment
		(start 193.129916 -92.210382)
		(end 193.07556 -92.156026)
		(width 0.254)
		(layer "F.Cu")
		(net "GND")
	)
	(segment
		(start 311.15 -0.821182)
		(end 311.15 -2.253488)
		(width 0.4064)
		(layer "F.Cu")
		(net "GND")
	)
	(segment
		(start 397.0782 -125.428248)
		(end 397.0782 -126.071884)
		(width 0.254)
		(layer "F.Cu")
		(net "GND")
	)
	(segment
		(start 256.295144 -2.975356)
		(end 255.8034 -2.975356)
		(width 0.4064)
		(layer "F.Cu")
		(net "GND")
	)
	(segment
		(start 77.299566 -152.278842)
		(end 77.299312 -152.279096)
		(width 0.4064)
		(layer "F.Cu")
		(net "GND")
	)
	(segment
		(start 278.849836 -150.710138)
		(end 278.849836 -152.273)
		(width 0.508)
		(layer "F.Cu")
		(net "GND")
	)
	(segment
		(start 393.485116 -125.750066)
		(end 393.485116 -124.919994)
		(width 0.254)
		(layer "F.Cu")
		(net "GND")
	)
	(segment
		(start 454.077578 -3.249422)
		(end 454.077578 -4.386072)
		(width 0.4064)
		(layer "F.Cu")
		(net "GND")
	)
	(segment
		(start 451.7517 -53.2384)
		(end 451.749922 -53.236622)
		(width 0.4064)
		(layer "F.Cu")
		(net "GND")
	)
	(segment
		(start 135.061452 -12.993116)
		(end 134.249414 -13.805154)
		(width 0.4064)
		(layer "F.Cu")
		(net "GND")
	)
	(segment
		(start 298.378626 -52.437538)
		(end 297.807126 -52.437538)
		(width 0.254)
		(layer "F.Cu")
		(net "GND")
	)
	(segment
		(start 44.149518 -146.10715)
		(end 44.092114 -146.049746)
		(width 0.4064)
		(layer "F.Cu")
		(net "GND")
	)
	(segment
		(start 138.03757 -13.948156)
		(end 136.729216 -13.8938)
		(width 0.254)
		(layer "F.Cu")
		(net "GND")
	)
	(segment
		(start 75.599544 -142.856712)
		(end 75.59929 -142.856966)
		(width 0.4064)
		(layer "F.Cu")
		(net "GND")
	)
	(segment
		(start 113.967768 -150.0886)
		(end 113.205768 -150.0886)
		(width 0.4064)
		(layer "F.Cu")
		(net "GND")
	)
	(segment
		(start 291.79774 -86.612984)
		(end 292.36924 -86.612984)
		(width 0.3048)
		(layer "F.Cu")
		(net "GND")
	)
	(segment
		(start 238.759238 -101.653086)
		(end 238.187738 -101.653086)
		(width 0.254)
		(layer "F.Cu")
		(net "GND")
	)
	(segment
		(start 311.15 -136.46785)
		(end 311.092596 -136.410446)
		(width 0.3556)
		(layer "F.Cu")
		(net "GND")
	)
	(segment
		(start 72.142096 -18.744946)
		(end 72.142096 -18.757646)
		(width 0.3556)
		(layer "F.Cu")
		(net "GND")
	)
	(segment
		(start 453.514968 -2.74574)
		(end 453.573896 -2.74574)
		(width 0.4064)
		(layer "F.Cu")
		(net "GND")
	)
	(segment
		(start 279.699974 -0.821182)
		(end 279.699974 0.457454)
		(width 0.4064)
		(layer "F.Cu")
		(net "GND")
	)
	(segment
		(start 82.343752 -78.869286)
		(end 81.772252 -78.869286)
		(width 0.254)
		(layer "F.Cu")
		(net "GND")
	)
	(segment
		(start 302.099726 -95.528384)
		(end 301.812706 -95.815404)
		(width 0.254)
		(layer "F.Cu")
		(net "GND")
	)
	(segment
		(start 211.700364 -0.821182)
		(end 211.699856 -0.821182)
		(width 0.4064)
		(layer "F.Cu")
		(net "GND")
	)
	(segment
		(start 58.599324 -142.677896)
		(end 58.599324 -144.462246)
		(width 0.4064)
		(layer "F.Cu")
		(net "GND")
	)
	(segment
		(start 196.399912 -148.771356)
		(end 196.4182 -148.789644)
		(width 0.4064)
		(layer "F.Cu")
		(net "GND")
	)
	(segment
		(start 436.921656 -33.8328)
		(end 436.522114 -34.232342)
		(width 0.3048)
		(layer "F.Cu")
		(net "GND")
	)
	(segment
		(start 235.49991 -137.67054)
		(end 235.49991 -136.448546)
		(width 0.4064)
		(layer "F.Cu")
		(net "GND")
	)
	(segment
		(start 277.203154 -59.371484)
		(end 276.631654 -59.371484)
		(width 0.254)
		(layer "F.Cu")
		(net "GND")
	)
	(segment
		(start 109.627416 -93.547184)
		(end 110.198916 -93.547184)
		(width 0.1651)
		(layer "F.Cu")
		(net "GND")
	)
	(segment
		(start 324.82282 -30.26918)
		(end 325.0057 -30.26918)
		(width 0.4572)
		(layer "F.Cu")
		(net "GND")
	)
	(segment
		(start 207.450436 -137.67054)
		(end 207.449928 -137.67054)
		(width 0.4064)
		(layer "F.Cu")
		(net "GND")
	)
	(segment
		(start 53.499512 -137.67054)
		(end 53.499512 -136.46785)
		(width 0.3556)
		(layer "F.Cu")
		(net "GND")
	)
	(segment
		(start 296.948606 -58.876438)
		(end 297.520106 -58.876438)
		(width 0.254)
		(layer "F.Cu")
		(net "GND")
	)
	(segment
		(start 102.947724 -98.681286)
		(end 102.376224 -98.681286)
		(width 0.254)
		(layer "F.Cu")
		(net "GND")
	)
	(segment
		(start 122.504708 -54.418738)
		(end 121.933208 -54.418738)
		(width 0.254)
		(layer "F.Cu")
		(net "GND")
	)
	(segment
		(start 393.18946 -113.299748)
		(end 393.670282 -113.523014)
		(width 0.254)
		(layer "F.Cu")
		(net "GND")
	)
	(segment
		(start 295.23182 -90.575384)
		(end 295.80332 -90.575384)
		(width 0.3048)
		(layer "F.Cu")
		(net "GND")
	)
	(segment
		(start 376.428 -100.354892)
		(end 376.335036 -99.85502)
		(width 0.254)
		(layer "F.Cu")
		(net "GND")
	)
	(segment
		(start 220.199712 -142.677896)
		(end 220.199712 -143.492474)
		(width 0.4064)
		(layer "F.Cu")
		(net "GND")
	)
	(segment
		(start 197.095364 -62.348364)
		(end 196.177154 -61.430154)
		(width 0.254)
		(layer "F.Cu")
		(net "GND")
	)
	(segment
		(start 376.335036 -117.854984)
		(end 376.428 -117.355112)
		(width 0.254)
		(layer "F.Cu")
		(net "GND")
	)
	(segment
		(start 283.212794 -94.538038)
		(end 283.784294 -94.538038)
		(width 0.254)
		(layer "F.Cu")
		(net "GND")
	)
	(segment
		(start 198.928228 -94.390972)
		(end 198.432674 -94.886526)
		(width 0.254)
		(layer "F.Cu")
		(net "GND")
	)
	(segment
		(start 262.3566 -25.2476)
		(end 262.9662 -25.2476)
		(width 0.4064)
		(layer "F.Cu")
		(net "GND")
	)
	(segment
		(start 52.649374 -15.423642)
		(end 52.649374 -13.541756)
		(width 0.4064)
		(layer "F.Cu")
		(net "GND")
	)
	(segment
		(start 70.324726 -92.737686)
		(end 69.753226 -92.737686)
		(width 0.254)
		(layer "F.Cu")
		(net "GND")
	)
	(segment
		(start 394.870686 -9.44372)
		(end 394.861542 -9.452864)
		(width 0.254)
		(layer "F.Cu")
		(net "GND")
	)
	(segment
		(start 283.219398 -52.93106)
		(end 283.3624 -52.684172)
		(width 0.254)
		(layer "F.Cu")
		(net "GND")
	)
	(segment
		(start 388.53745 -114.25555)
		(end 388.9375 -114.6556)
		(width 0.254)
		(layer "F.Cu")
		(net "GND")
	)
	(segment
		(start 105.9561 -149.8092)
		(end 106.841036 -149.8092)
		(width 0.4064)
		(layer "F.Cu")
		(net "GND")
	)
	(segment
		(start 222.749872 -156.87294)
		(end 222.75038 -156.87294)
		(width 0.4064)
		(layer "F.Cu")
		(net "GND")
	)
	(segment
		(start 236.350302 -5.822442)
		(end 236.349794 -5.822442)
		(width 0.4064)
		(layer "F.Cu")
		(net "GND")
	)
	(segment
		(start 367.4618 -98.5266)
		(end 366.2426 -98.5266)
		(width 0.254)
		(layer "F.Cu")
		(net "GND")
	)
	(segment
		(start 167.3098 -7.874)
		(end 167.3098 -7.3914)
		(width 0.254)
		(layer "F.Cu")
		(net "GND")
	)
	(segment
		(start 250.778264 -64.010286)
		(end 250.206764 -64.010286)
		(width 0.254)
		(layer "F.Cu")
		(net "GND")
	)
	(segment
		(start 119.929402 -94.538038)
		(end 120.500902 -94.538038)
		(width 0.254)
		(layer "F.Cu")
		(net "GND")
	)
	(segment
		(start 279.778714 -99.490784)
		(end 280.350214 -99.490784)
		(width 0.254)
		(layer "F.Cu")
		(net "GND")
	)
	(segment
		(start 277.203154 -89.089738)
		(end 277.203154 -88.518238)
		(width 0.381)
		(layer "F.Cu")
		(net "GND")
	)
	(segment
		(start 380.875794 -158.248858)
		(end 380.41072 -157.783784)
		(width 0.254)
		(layer "F.Cu")
		(net "GND")
	)
	(segment
		(start 216.799922 -9.156446)
		(end 216.799922 -10.422382)
		(width 0.4064)
		(layer "F.Cu")
		(net "GND")
	)
	(segment
		(start 298.665646 -85.622384)
		(end 299.237146 -85.622384)
		(width 0.3048)
		(layer "F.Cu")
		(net "GND")
	)
	(segment
		(start 197.250304 -5.822442)
		(end 197.249796 -5.822442)
		(width 0.4064)
		(layer "F.Cu")
		(net "GND")
	)
	(segment
		(start 379.876558 -124.3965)
		(end 379.093476 -124.3965)
		(width 0.254)
		(layer "F.Cu")
		(net "GND")
	)
	(segment
		(start 298.665646 -75.716384)
		(end 299.237146 -75.716384)
		(width 0.254)
		(layer "F.Cu")
		(net "GND")
	)
	(segment
		(start 255.92913 -95.709486)
		(end 255.35763 -95.709486)
		(width 0.254)
		(layer "F.Cu")
		(net "GND")
	)
	(segment
		(start 207.411828 -136.410446)
		(end 207.424528 -136.410446)
		(width 0.4064)
		(layer "F.Cu")
		(net "GND")
	)
	(segment
		(start 81.485232 -71.44004)
		(end 80.913732 -71.44004)
		(width 0.254)
		(layer "F.Cu")
		(net "GND")
	)
	(segment
		(start 287.50514 -76.211938)
		(end 288.07664 -76.211938)
		(width 0.254)
		(layer "F.Cu")
		(net "GND")
	)
	(segment
		(start 317.09995 -5.822442)
		(end 317.09995 -7.086346)
		(width 0.4064)
		(layer "F.Cu")
		(net "GND")
	)
	(segment
		(start 401.828 -100.6475)
		(end 401.620482 -100.855018)
		(width 0.254)
		(layer "F.Cu")
		(net "GND")
	)
	(segment
		(start 235.49991 -10.422382)
		(end 235.49991 -9.156446)
		(width 0.4064)
		(layer "F.Cu")
		(net "GND")
	)
	(segment
		(start 62.849506 -147.27174)
		(end 62.849506 -146.06905)
		(width 0.3556)
		(layer "F.Cu")
		(net "GND")
	)
	(segment
		(start 226.822 -17.2466)
		(end 226.7966 -17.2212)
		(width 0.3556)
		(layer "F.Cu")
		(net "GND")
	)
	(segment
		(start 291.79774 -84.631784)
		(end 292.36924 -84.631784)
		(width 0.254)
		(layer "F.Cu")
		(net "GND")
	)
	(segment
		(start 68.607686 -60.047886)
		(end 69.753226 -60.047886)
		(width 0.254)
		(layer "F.Cu")
		(net "GND")
	)
	(segment
		(start 118.212362 -95.528384)
		(end 118.783862 -95.528384)
		(width 0.254)
		(layer "F.Cu")
		(net "GND")
	)
	(segment
		(start 293.51478 -84.631784)
		(end 294.08628 -84.631784)
		(width 0.254)
		(layer "F.Cu")
		(net "GND")
	)
	(segment
		(start 275.111464 -3.3528)
		(end 274.258532 -3.3528)
		(width 0.381)
		(layer "F.Cu")
		(net "GND")
	)
	(segment
		(start 379.289564 -106.407966)
		(end 378.82195 -106.190796)
		(width 0.254)
		(layer "F.Cu")
		(net "GND")
	)
	(segment
		(start 273.769328 -99.986338)
		(end 274.340828 -99.986338)
		(width 0.254)
		(layer "F.Cu")
		(net "GND")
	)
	(segment
		(start 79.360268 -3.3528)
		(end 78.229968 -3.3528)
		(width 0.4064)
		(layer "F.Cu")
		(net "GND")
	)
	(segment
		(start 303.499774 -16.238474)
		(end 303.499774 -15.423642)
		(width 0.4064)
		(layer "F.Cu")
		(net "GND")
	)
	(segment
		(start 280.637234 -91.070938)
		(end 281.208734 -91.070938)
		(width 0.254)
		(layer "F.Cu")
		(net "GND")
	)
	(segment
		(start 211.699856 -10.422382)
		(end 211.699856 -11.916156)
		(width 0.4064)
		(layer "F.Cu")
		(net "GND")
	)
	(segment
		(start 475.238826 -148.14423)
		(end 475.206568 -148.14423)
		(width 0.254)
		(layer "F.Cu")
		(net "GND")
	)
	(segment
		(start 30.549342 -16.764)
		(end 30.549342 -15.423642)
		(width 0.4064)
		(layer "F.Cu")
		(net "GND")
	)
	(segment
		(start 220.199712 -153.093674)
		(end 219.741242 -153.552144)
		(width 0.4064)
		(layer "F.Cu")
		(net "GND")
	)
	(segment
		(start 382.9304 -98.626422)
		(end 383.27965 -98.464116)
		(width 0.254)
		(layer "F.Cu")
		(net "GND")
	)
	(segment
		(start 236.183678 -59.55284)
		(end 235.612178 -59.55284)
		(width 0.254)
		(layer "F.Cu")
		(net "GND")
	)
	(segment
		(start 465.397596 -53.272436)
		(end 465.346796 -53.221636)
		(width 0.4064)
		(layer "F.Cu")
		(net "GND")
	)
	(segment
		(start 129.999486 -9.156446)
		(end 129.999486 -10.422382)
		(width 0.4064)
		(layer "F.Cu")
		(net "GND")
	)
	(segment
		(start 339.471 -21.971)
		(end 339.471 -22.833584)
		(width 0.4064)
		(layer "F.Cu")
		(net "GND")
	)
	(segment
		(start 393.081764 -125.431804)
		(end 393.081764 -126.068328)
		(width 0.254)
		(layer "F.Cu")
		(net "GND")
	)
	(segment
		(start 60.210446 -3.737356)
		(end 60.299346 -3.826256)
		(width 0.4064)
		(layer "F.Cu")
		(net "GND")
	)
	(segment
		(start 77.192886 -63.019686)
		(end 76.621386 -63.019686)
		(width 0.254)
		(layer "F.Cu")
		(net "GND")
	)
	(segment
		(start 26.602182 -140.1826)
		(end 26.602182 -141.198854)
		(width 0.4064)
		(layer "F.Cu")
		(net "GND")
	)
	(segment
		(start 398.63395 -102.12832)
		(end 398.63395 -102.756716)
		(width 0.254)
		(layer "F.Cu")
		(net "GND")
	)
	(segment
		(start 235.325158 -89.765886)
		(end 234.753658 -89.765886)
		(width 0.254)
		(layer "F.Cu")
		(net "GND")
	)
	(segment
		(start 216.799922 -2.276856)
		(end 216.761822 -2.314956)
		(width 0.4064)
		(layer "F.Cu")
		(net "GND")
	)
	(segment
		(start 220.199966 -15.423642)
		(end 220.199966 -14.410182)
		(width 0.4064)
		(layer "F.Cu")
		(net "GND")
	)
	(segment
		(start 289.22218 -55.409338)
		(end 288.65068 -55.409338)
		(width 0.254)
		(layer "F.Cu")
		(net "GND")
	)
	(segment
		(start 72.900286 -54.59984)
		(end 72.328786 -54.59984)
		(width 0.254)
		(layer "F.Cu")
		(net "GND")
	)
	(segment
		(start 397.14805 -109.855)
		(end 396.65275 -109.624876)
		(width 0.254)
		(layer "F.Cu")
		(net "GND")
	)
	(segment
		(start 131.948174 -65.810384)
		(end 132.519674 -65.810384)
		(width 0.254)
		(layer "F.Cu")
		(net "GND")
	)
	(segment
		(start 126.599442 -153.001726)
		(end 126.388368 -153.2128)
		(width 0.3556)
		(layer "F.Cu")
		(net "GND")
	)
	(segment
		(start 59.449462 -10.422382)
		(end 59.449462 -9.143746)
		(width 0.4064)
		(layer "F.Cu")
		(net "GND")
	)
	(segment
		(start 244.768624 -56.58104)
		(end 244.197124 -56.58104)
		(width 0.254)
		(layer "F.Cu")
		(net "GND")
	)
	(segment
		(start 414.290256 -38.534594)
		(end 413.890206 -38.134544)
		(width 0.254)
		(layer "F.Cu")
		(net "GND")
	)
	(segment
		(start 74.617326 -80.35544)
		(end 74.045826 -80.35544)
		(width 0.254)
		(layer "F.Cu")
		(net "GND")
	)
	(segment
		(start 317.09995 -139.181078)
		(end 317.09995 -140.161518)
		(width 0.4064)
		(layer "F.Cu")
		(net "GND")
	)
	(segment
		(start 55.19928 -15.423896)
		(end 55.19928 -16.238474)
		(width 0.4064)
		(layer "F.Cu")
		(net "GND")
	)
	(segment
		(start 449.827142 -45.611796)
		(end 450.141086 -45.92574)
		(width 0.4064)
		(layer "F.Cu")
		(net "GND")
	)
	(segment
		(start 66.249296 -5.822188)
		(end 66.24955 -5.822442)
		(width 0.4064)
		(layer "F.Cu")
		(net "GND")
	)
	(segment
		(start 135.949436 3.033522)
		(end 135.735568 2.819654)
		(width 0.3556)
		(layer "F.Cu")
		(net "GND")
	)
	(segment
		(start 415.890202 -38.534594)
		(end 416.290252 -38.934644)
		(width 0.254)
		(layer "F.Cu")
		(net "GND")
	)
	(segment
		(start 61.796168 -7.62)
		(end 61.821568 -7.6454)
		(width 0.3556)
		(layer "F.Cu")
		(net "GND")
	)
	(segment
		(start 211.699856 -146.011646)
		(end 211.699856 -147.27174)
		(width 0.4064)
		(layer "F.Cu")
		(net "GND")
	)
	(segment
		(start 291.599874 -142.677642)
		(end 291.599874 -143.400526)
		(width 0.3556)
		(layer "F.Cu")
		(net "GND")
	)
	(segment
		(start 248.202704 -69.45884)
		(end 247.631204 -69.45884)
		(width 0.254)
		(layer "F.Cu")
		(net "GND")
	)
	(segment
		(start 451.74281 -52.2478)
		(end 451.740016 -51.875944)
		(width 0.4064)
		(layer "F.Cu")
		(net "GND")
	)
	(segment
		(start 475.2213 -137.8331)
		(end 475.0435 -137.6553)
		(width 0.254)
		(layer "F.Cu")
		(net "GND")
	)
	(segment
		(start 62.849506 -9.21385)
		(end 62.792102 -9.156446)
		(width 0.3556)
		(layer "F.Cu")
		(net "GND")
	)
	(segment
		(start 199.799956 -9.426702)
		(end 199.799956 -10.422382)
		(width 0.4064)
		(layer "F.Cu")
		(net "GND")
	)
	(segment
		(start 307.250846 -59.866784)
		(end 306.963826 -59.579764)
		(width 0.254)
		(layer "F.Cu")
		(net "GND")
	)
	(segment
		(start 391.69975 -98.69424)
		(end 392.02741 -98.542094)
		(width 0.254)
		(layer "F.Cu")
		(net "GND")
	)
	(segment
		(start 64.549274 -143.492474)
		(end 64.090804 -143.950944)
		(width 0.4064)
		(layer "F.Cu")
		(net "GND")
	)
	(segment
		(start 297.550332 -133.0706)
		(end 297.549824 -133.076442)
		(width 0.4064)
		(layer "F.Cu")
		(net "GND")
	)
	(segment
		(start 296.09034 -100.976684)
		(end 296.090594 -100.976938)
		(width 0.3048)
		(layer "F.Cu")
		(net "GND")
	)
	(segment
		(start 232.749598 -56.58104)
		(end 232.0925 -56.58104)
		(width 0.254)
		(layer "F.Cu")
		(net "GND")
	)
	(segment
		(start 284.799532 -6.637274)
		(end 284.341062 -7.095744)
		(width 0.4064)
		(layer "F.Cu")
		(net "GND")
	)
	(segment
		(start 290.93922 -98.005138)
		(end 291.51072 -98.005138)
		(width 0.254)
		(layer "F.Cu")
		(net "GND")
	)
	(segment
		(start 457.5048 -134.5692)
		(end 457.252578 -134.821422)
		(width 0.254)
		(layer "F.Cu")
		(net "GND")
	)
	(segment
		(start 375.92 -101.529134)
		(end 376.245882 -101.855016)
		(width 0.254)
		(layer "F.Cu")
		(net "GND")
	)
	(segment
		(start 296.948606 -65.810384)
		(end 297.520106 -65.810384)
		(width 0.254)
		(layer "F.Cu")
		(net "GND")
	)
	(segment
		(start 251.636784 -79.36484)
		(end 251.065284 -79.36484)
		(width 0.254)
		(layer "F.Cu")
		(net "GND")
	)
	(segment
		(start 81.485232 -89.27084)
		(end 80.913732 -89.27084)
		(width 0.254)
		(layer "F.Cu")
		(net "GND")
	)
	(segment
		(start 195.549774 -134.400798)
		(end 195.533772 -134.4168)
		(width 0.4064)
		(layer "F.Cu")
		(net "GND")
	)
	(segment
		(start 49.24933 -133.076696)
		(end 49.24933 -134.861046)
		(width 0.4064)
		(layer "F.Cu")
		(net "GND")
	)
	(segment
		(start 27.84856 -96.07042)
		(end 27.97048 -96.19234)
		(width 0.254)
		(layer "F.Cu")
		(net "GND")
	)
	(segment
		(start 142.250414 -69.772784)
		(end 142.55623 -70.0786)
		(width 0.254)
		(layer "F.Cu")
		(net "GND")
	)
	(segment
		(start 74.617326 -68.46824)
		(end 74.045826 -68.46824)
		(width 0.254)
		(layer "F.Cu")
		(net "GND")
	)
	(segment
		(start 33.949386 -16.137382)
		(end 33.949386 -15.423642)
		(width 0.3556)
		(layer "F.Cu")
		(net "GND")
	)
	(segment
		(start 119.929402 -92.556584)
		(end 120.500902 -92.556584)
		(width 0.254)
		(layer "F.Cu")
		(net "GND")
	)
	(segment
		(start 291.3888 -134.866126)
		(end 291.422074 -134.8994)
		(width 0.3556)
		(layer "F.Cu")
		(net "GND")
	)
	(segment
		(start 84.919312 -90.26144)
		(end 84.347812 -90.26144)
		(width 0.254)
		(layer "F.Cu")
		(net "GND")
	)
	(segment
		(start 38.199568 -5.822442)
		(end 38.199568 -3.76301)
		(width 0.4064)
		(layer "F.Cu")
		(net "GND")
	)
	(segment
		(start 461.400906 -113.867184)
		(end 461.39989 -113.8682)
		(width 0.4064)
		(layer "F.Cu")
		(net "GND")
	)
	(segment
		(start 299.524166 -52.437538)
		(end 300.095666 -52.437538)
		(width 0.254)
		(layer "F.Cu")
		(net "GND")
	)
	(segment
		(start 39.049452 -155.612846)
		(end 39.049452 -156.87294)
		(width 0.4064)
		(layer "F.Cu")
		(net "GND")
	)
	(segment
		(start 207.449928 -139.132056)
		(end 207.411828 -139.170156)
		(width 0.4064)
		(layer "F.Cu")
		(net "GND")
	)
	(segment
		(start 75.475846 -93.72854)
		(end 74.904346 -93.72854)
		(width 0.254)
		(layer "F.Cu")
		(net "GND")
	)
	(segment
		(start 74.617326 -93.23324)
		(end 74.045826 -93.23324)
		(width 0.254)
		(layer "F.Cu")
		(net "GND")
	)
	(segment
		(start 235.49991 -0.821182)
		(end 235.49991 0.444754)
		(width 0.4064)
		(layer "F.Cu")
		(net "GND")
	)
	(segment
		(start 27.451558 -22.063456)
		(end 27.451558 -21.488146)
		(width 0.508)
		(layer "F.Cu")
		(net "GND")
	)
	(segment
		(start 396.65275 -103.84536)
		(end 397.14805 -103.615236)
		(width 0.254)
		(layer "F.Cu")
		(net "GND")
	)
	(segment
		(start 78.909672 -82.83194)
		(end 78.338172 -82.83194)
		(width 0.254)
		(layer "F.Cu")
		(net "GND")
	)
	(segment
		(start 278.849836 -4.487164)
		(end 279.019 -4.318)
		(width 0.4064)
		(layer "F.Cu")
		(net "GND")
	)
	(segment
		(start 135.735568 -16.382746)
		(end 135.949436 -16.168878)
		(width 0.3556)
		(layer "F.Cu")
		(net "GND")
	)
	(segment
		(start 78.14945 -0.821182)
		(end 78.14945 0.468122)
		(width 0.4064)
		(layer "F.Cu")
		(net "GND")
	)
	(segment
		(start 376.40006 -108.204)
		(end 376.428 -108.35513)
		(width 0.254)
		(layer "F.Cu")
		(net "GND")
	)
	(segment
		(start 398.485106 -124.919994)
		(end 398.485106 -125.542294)
		(width 0.254)
		(layer "F.Cu")
		(net "GND")
	)
	(segment
		(start 77.286612 -22.965156)
		(end 77.286612 -25.142444)
		(width 0.4064)
		(layer "F.Cu")
		(net "GND")
	)
	(segment
		(start 289.899852 -152.278842)
		(end 289.899852 -153.965402)
		(width 0.4064)
		(layer "F.Cu")
		(net "GND")
	)
	(via
		(at 33.761934 14.926056)
		(size 0.5588)
		(drill 0.3048)
		(layers "F.Cu" "B.Cu")
		(net "GND")
	)
	(via
		(at 471.200734 -165.596824)
		(size 0.5588)
		(drill 0.3048)
		(layers "F.Cu" "B.Cu")
		(net "GND")
	)
	(via
		(at 101.573076 -82.339942)
		(size 0.5588)
		(drill 0.3048)
		(layers "F.Cu" "B.Cu")
		(net "GND")
	)
	(via
		(at 448.340734 -167.832024)
		(size 0.5588)
		(drill 0.3048)
		(layers "F.Cu" "B.Cu")
		(net "GND")
	)
	(via
		(at 208.122012 -17.2466)
		(size 0.508)
		(drill 0.254)
		(layers "F.Cu" "B.Cu")
		(net "GND")
	)
	(via
		(at 387.477 -146.731736)
		(size 0.508)
		(drill 0.254)
		(layers "F.Cu" "B.Cu")
		(net "GND")
	)
	(via
		(at 242.480338 -84.31784)
		(size 0.508)
		(drill 0.254)
		(layers "F.Cu" "B.Cu")
		(net "GND")
	)
	(via
		(at 79.196692 -55.59044)
		(size 0.508)
		(drill 0.254)
		(layers "F.Cu" "B.Cu")
		(net "GND")
	)
	(via
		(at 337.8454 -39.37)
		(size 0.508)
		(drill 0.254)
		(layers "F.Cu" "B.Cu")
		(net "GND")
	)
	(via
		(at 103.557324 -56.085486)
		(size 0.508)
		(drill 0.254)
		(layers "F.Cu" "B.Cu")
		(net "GND")
	)
	(via
		(at 303.031906 -21.5138)
		(size 0.508)
		(drill 0.254)
		(layers "F.Cu" "B.Cu")
		(net "GND")
	)
	(via
		(at 333.9846 -59.679586)
		(size 0.508)
		(drill 0.254)
		(layers "F.Cu" "B.Cu")
		(net "GND")
	)
	(via
		(at 296.69994 -146.011646)
		(size 0.508)
		(drill 0.254)
		(layers "F.Cu" "B.Cu")
		(net "GND")
	)
	(via
		(at 85.206332 -97.690686)
		(size 0.508)
		(drill 0.254)
		(layers "F.Cu" "B.Cu")
		(net "GND")
	)
	(via
		(at 13.335 -11.0998)
		(size 0.508)
		(drill 0.254)
		(layers "F.Cu" "B.Cu")
		(net "GND")
	)
	(via
		(at 344.48242 -32.131)
		(size 0.508)
		(drill 0.254)
		(layers "F.Cu" "B.Cu")
		(net "GND")
	)
	(via
		(at 206.51089 -140.592556)
		(size 0.508)
		(drill 0.254)
		(layers "F.Cu" "B.Cu")
		(net "GND")
	)
	(via
		(at 484.611934 11.624056)
		(size 0.5588)
		(drill 0.3048)
		(layers "F.Cu" "B.Cu")
		(net "GND")
	)
	(via
		(at 144.411446 -2.314956)
		(size 0.508)
		(drill 0.254)
		(layers "F.Cu" "B.Cu")
		(net "GND")
	)
	(via
		(at 277.601934 14.926056)
		(size 0.5588)
		(drill 0.3048)
		(layers "F.Cu" "B.Cu")
		(net "GND")
	)
	(via
		(at 430.18075 -33.83788)
		(size 0.4572)
		(drill 0.2032)
		(layers "F.Cu" "B.Cu")
		(net "GND")
	)
	(via
		(at 90.626692 -150.098506)
		(size 0.508)
		(drill 0.254)
		(layers "F.Cu" "B.Cu")
		(net "GND")
	)
	(via
		(at 470.027 -14.351)
		(size 0.508)
		(drill 0.254)
		(layers "F.Cu" "B.Cu")
		(net "GND")
	)
	(via
		(at 450.321934 14.926056)
		(size 0.5588)
		(drill 0.3048)
		(layers "F.Cu" "B.Cu")
		(net "GND")
	)
	(via
		(at 76.621386 -88.775286)
		(size 0.508)
		(drill 0.254)
		(layers "F.Cu" "B.Cu")
		(net "GND")
	)
	(via
		(at 280.460958 -130.991356)
		(size 0.508)
		(drill 0.254)
		(layers "F.Cu" "B.Cu")
		(net "GND")
	)
	(via
		(at 239.046258 -67.47764)
		(size 0.508)
		(drill 0.254)
		(layers "F.Cu" "B.Cu")
		(net "GND")
	)
	(via
		(at 306.899818 -154.063446)
		(size 0.508)
		(drill 0.254)
		(layers "F.Cu" "B.Cu")
		(net "GND")
	)
	(via
		(at 370.344954 -71.894954)
		(size 0.4572)
		(drill 0.2032)
		(layers "F.Cu" "B.Cu")
		(net "GND")
	)
	(via
		(at 426.191934 14.926056)
		(size 0.5588)
		(drill 0.3048)
		(layers "F.Cu" "B.Cu")
		(net "GND")
	)
	(via
		(at 397.64335 -122.104404)
		(size 0.508)
		(drill 0.254)
		(layers "F.Cu" "B.Cu")
		(net "GND")
	)
	(via
		(at 0.995934 14.926056)
		(size 0.5588)
		(drill 0.3048)
		(layers "F.Cu" "B.Cu")
		(net "GND")
	)
	(via
		(at 184.778396 -92.675202)
		(size 0.508)
		(drill 0.254)
		(layers "F.Cu" "B.Cu")
		(net "GND")
	)
	(via
		(at 284.358334 -56.894984)
		(size 0.508)
		(drill 0.254)
		(layers "F.Cu" "B.Cu")
		(net "GND")
	)
	(via
		(at 77.479906 -83.32724)
		(size 0.508)
		(drill 0.254)
		(layers "F.Cu" "B.Cu")
		(net "GND")
	)
	(via
		(at 237.329218 -67.47764)
		(size 0.508)
		(drill 0.254)
		(layers "F.Cu" "B.Cu")
		(net "GND")
	)
	(via
		(at 105.161334 -167.832024)
		(size 0.5588)
		(drill 0.3048)
		(layers "F.Cu" "B.Cu")
		(net "GND")
	)
	(via
		(at 229.087934 -150.803356)
		(size 0.508)
		(drill 0.254)
		(layers "F.Cu" "B.Cu")
		(net "GND")
	)
	(via
		(at 198.099934 0.444754)
		(size 0.508)
		(drill 0.254)
		(layers "F.Cu" "B.Cu")
		(net "GND")
	)
	(via
		(at 483.341934 13.910056)
		(size 0.5588)
		(drill 0.3048)
		(layers "F.Cu" "B.Cu")
		(net "GND")
	)
	(via
		(at 128.687576 -141.202156)
		(size 0.508)
		(drill 0.254)
		(layers "F.Cu" "B.Cu")
		(net "GND")
	)
	(via
		(at 418.70122 -38.141402)
		(size 0.4572)
		(drill 0.2032)
		(layers "F.Cu" "B.Cu")
		(net "GND")
	)
	(via
		(at 391.491724 -162.243262)
		(size 0.5588)
		(drill 0.3048)
		(layers "F.Cu" "B.Cu")
		(net "GND")
	)
	(via
		(at 299.173646 -124.699776)
		(size 0.508)
		(drill 0.254)
		(layers "F.Cu" "B.Cu")
		(net "GND")
	)
	(via
		(at 174.379382 -49.942496)
		(size 0.508)
		(drill 0.254)
		(layers "F.Cu" "B.Cu")
		(net "GND")
	)
	(via
		(at 406.72258 -151.6888)
		(size 0.508)
		(drill 0.254)
		(layers "F.Cu" "B.Cu")
		(net "GND")
	)
	(via
		(at 130.802888 -83.641184)
		(size 0.508)
		(drill 0.254)
		(layers "F.Cu" "B.Cu")
		(net "GND")
	)
	(via
		(at 172.466 -88.392)
		(size 0.508)
		(drill 0.254)
		(layers "F.Cu" "B.Cu")
		(net "GND")
	)
	(via
		(at 376.502422 -145.36801)
		(size 0.508)
		(drill 0.254)
		(layers "F.Cu" "B.Cu")
		(net "GND")
	)
	(via
		(at 234.753658 -66.982086)
		(size 0.508)
		(drill 0.254)
		(layers "F.Cu" "B.Cu")
		(net "GND")
	)
	(via
		(at 182.71744 -61.342016)
		(size 0.508)
		(drill 0.254)
		(layers "F.Cu" "B.Cu")
		(net "GND")
	)
	(via
		(at 84.347812 -96.20504)
		(size 0.508)
		(drill 0.254)
		(layers "F.Cu" "B.Cu")
		(net "GND")
	)
	(via
		(at 307.281326 -95.033084)
		(size 0.508)
		(drill 0.254)
		(layers "F.Cu" "B.Cu")
		(net "GND")
	)
	(via
		(at 127.368808 -71.753984)
		(size 0.508)
		(drill 0.254)
		(layers "F.Cu" "B.Cu")
		(net "GND")
	)
	(via
		(at 294.08628 -56.894984)
		(size 0.508)
		(drill 0.254)
		(layers "F.Cu" "B.Cu")
		(net "GND")
	)
	(via
		(at 462.310734 -164.479224)
		(size 0.5588)
		(drill 0.3048)
		(layers "F.Cu" "B.Cu")
		(net "GND")
	)
	(via
		(at 344.4748 -7.1628)
		(size 0.508)
		(drill 0.254)
		(layers "F.Cu" "B.Cu")
		(net "GND")
	)
	(via
		(at 219.731844 -148.7678)
		(size 0.508)
		(drill 0.254)
		(layers "F.Cu" "B.Cu")
		(net "GND")
	)
	(via
		(at 380.30785 -116.094764)
		(size 0.508)
		(drill 0.254)
		(layers "F.Cu" "B.Cu")
		(net "GND")
	)
	(via
		(at 127.368808 -65.810384)
		(size 0.508)
		(drill 0.254)
		(layers "F.Cu" "B.Cu")
		(net "GND")
	)
	(via
		(at 2.50952 -23.53818)
		(size 0.508)
		(drill 0.254)
		(layers "F.Cu" "B.Cu")
		(net "GND")
	)
	(via
		(at 249.661934 9.084056)
		(size 0.5588)
		(drill 0.3048)
		(layers "F.Cu" "B.Cu")
		(net "GND")
	)
	(via
		(at 473.740734 -165.596824)
		(size 0.5588)
		(drill 0.3048)
		(layers "F.Cu" "B.Cu")
		(net "GND")
	)
	(via
		(at 251.065284 -62.52464)
		(size 0.508)
		(drill 0.254)
		(layers "F.Cu" "B.Cu")
		(net "GND")
	)
	(via
		(at 331.45476 -8.2169)
		(size 0.508)
		(drill 0.254)
		(layers "F.Cu" "B.Cu")
		(net "GND")
	)
	(via
		(at 179.466494 -55.858918)
		(size 0.508)
		(drill 0.254)
		(layers "F.Cu" "B.Cu")
		(net "GND")
	)
	(via
		(at 61.821568 -17.2466)
		(size 0.508)
		(drill 0.254)
		(layers "F.Cu" "B.Cu")
		(net "GND")
	)
	(via
		(at 119.327168 -11.9634)
		(size 0.508)
		(drill 0.254)
		(layers "F.Cu" "B.Cu")
		(net "GND")
	)
	(via
		(at 411.607 -120.65)
		(size 0.508)
		(drill 0.254)
		(layers "F.Cu" "B.Cu")
		(net "GND")
	)
	(via
		(at 291.422074 -150.219156)
		(size 0.508)
		(drill 0.254)
		(layers "F.Cu" "B.Cu")
		(net "GND")
	)
	(via
		(at 191.897 -2.2098)
		(size 0.508)
		(drill 0.254)
		(layers "F.Cu" "B.Cu")
		(net "GND")
	)
	(via
		(at 170.497246 -30.160976)
		(size 0.508)
		(drill 0.254)
		(layers "F.Cu" "B.Cu")
		(net "GND")
	)
	(via
		(at 212.54974 -154.063446)
		(size 0.508)
		(drill 0.254)
		(layers "F.Cu" "B.Cu")
		(net "GND")
	)
	(via
		(at 123.076208 -76.211938)
		(size 0.508)
		(drill 0.254)
		(layers "F.Cu" "B.Cu")
		(net "GND")
	)
	(via
		(at 109.055662 -53.923184)
		(size 0.508)
		(drill 0.254)
		(layers "F.Cu" "B.Cu")
		(net "GND")
	)
	(via
		(at 50.099468 -129.568956)
		(size 0.508)
		(drill 0.254)
		(layers "F.Cu" "B.Cu")
		(net "GND")
	)
	(via
		(at 134.236714 -74.725784)
		(size 0.508)
		(drill 0.254)
		(layers "F.Cu" "B.Cu")
		(net "GND")
	)
	(via
		(at 279.699974 -21.517356)
		(size 0.508)
		(drill 0.254)
		(layers "F.Cu" "B.Cu")
		(net "GND")
	)
	(via
		(at 466.120734 -164.479224)
		(size 0.5588)
		(drill 0.3048)
		(layers "F.Cu" "B.Cu")
		(net "GND")
	)
	(via
		(at 479.531934 10.354056)
		(size 0.5588)
		(drill 0.3048)
		(layers "F.Cu" "B.Cu")
		(net "GND")
	)
	(via
		(at 272.24228 -82.340196)
		(size 0.5588)
		(drill 0.3048)
		(layers "F.Cu" "B.Cu")
		(net "GND")
	)
	(via
		(at 49.24933 -13.363956)
		(size 0.508)
		(drill 0.254)
		(layers "F.Cu" "B.Cu")
		(net "GND")
	)
	(via
		(at 468.660734 -167.832024)
		(size 0.5588)
		(drill 0.3048)
		(layers "F.Cu" "B.Cu")
		(net "GND")
	)
	(via
		(at 170.921934 14.926056)
		(size 0.5588)
		(drill 0.3048)
		(layers "F.Cu" "B.Cu")
		(net "GND")
	)
	(via
		(at 26.1874 -104.5972)
		(size 0.508)
		(drill 0.254)
		(layers "F.Cu" "B.Cu")
		(net "GND")
	)
	(via
		(at 311.913524 -162.243262)
		(size 0.5588)
		(drill 0.3048)
		(layers "F.Cu" "B.Cu")
		(net "GND")
	)
	(via
		(at 125.651768 -87.603584)
		(size 0.508)
		(drill 0.254)
		(layers "F.Cu" "B.Cu")
		(net "GND")
	)
	(via
		(at 419.130734 -166.714424)
		(size 0.5588)
		(drill 0.3048)
		(layers "F.Cu" "B.Cu")
		(net "GND")
	)
	(via
		(at 35.0266 -69.2912)
		(size 0.5588)
		(drill 0.3048)
		(layers "F.Cu" "B.Cu")
		(net "GND")
	)
	(via
		(at 77.479906 -88.28024)
		(size 0.508)
		(drill 0.254)
		(layers "F.Cu" "B.Cu")
		(net "GND")
	)
	(via
		(at 166.5986 -78.1558)
		(size 0.508)
		(drill 0.254)
		(layers "F.Cu" "B.Cu")
		(net "GND")
	)
	(via
		(at 378.32665 -122.962924)
		(size 0.508)
		(drill 0.254)
		(layers "F.Cu" "B.Cu")
		(net "GND")
	)
	(via
		(at 121.359168 -98.995738)
		(size 0.508)
		(drill 0.254)
		(layers "F.Cu" "B.Cu")
		(net "GND")
	)
	(via
		(at 480.801934 9.084056)
		(size 0.5588)
		(drill 0.3048)
		(layers "F.Cu" "B.Cu")
		(net "GND")
	)
	(via
		(at 214.0204 -76.1746)
		(size 0.508)
		(drill 0.254)
		(layers "F.Cu" "B.Cu")
		(net "GND")
	)
	(via
		(at 129.944368 -72.249538)
		(size 0.508)
		(drill 0.254)
		(layers "F.Cu" "B.Cu")
		(net "GND")
	)
	(via
		(at 448.8942 -120.0658)
		(size 0.508)
		(drill 0.254)
		(layers "F.Cu" "B.Cu")
		(net "GND")
	)
	(via
		(at 143.0528 -90.575384)
		(size 0.508)
		(drill 0.254)
		(layers "F.Cu" "B.Cu")
		(net "GND")
	)
	(via
		(at 140.441934 14.926056)
		(size 0.5588)
		(drill 0.3048)
		(layers "F.Cu" "B.Cu")
		(net "GND")
	)
	(via
		(at 240.599722 -7.607046)
		(size 0.508)
		(drill 0.254)
		(layers "F.Cu" "B.Cu")
		(net "GND")
	)
	(via
		(at 126.421642 -17.2466)
		(size 0.508)
		(drill 0.254)
		(layers "F.Cu" "B.Cu")
		(net "GND")
	)
	(via
		(at 348.0054 -38.1)
		(size 0.508)
		(drill 0.254)
		(layers "F.Cu" "B.Cu")
		(net "GND")
	)
	(via
		(at 224.449894 -21.517356)
		(size 0.508)
		(drill 0.254)
		(layers "F.Cu" "B.Cu")
		(net "GND")
	)
	(via
		(at 61.111384 -2.314956)
		(size 0.508)
		(drill 0.254)
		(layers "F.Cu" "B.Cu")
		(net "GND")
	)
	(via
		(at 50.851308 -7.607046)
		(size 0.508)
		(drill 0.254)
		(layers "F.Cu" "B.Cu")
		(net "GND")
	)
	(via
		(at 111.057182 -92.061538)
		(size 0.508)
		(drill 0.254)
		(layers "F.Cu" "B.Cu")
		(net "GND")
	)
	(via
		(at 362.332524 -162.268662)
		(size 0.5588)
		(drill 0.3048)
		(layers "F.Cu" "B.Cu")
		(net "GND")
	)
	(via
		(at 202.349862 -148.771356)
		(size 0.508)
		(drill 0.254)
		(layers "F.Cu" "B.Cu")
		(net "GND")
	)
	(via
		(at 413.890206 -34.934652)
		(size 0.4572)
		(drill 0.2032)
		(layers "F.Cu" "B.Cu")
		(net "GND")
	)
	(via
		(at 306.049934 -2.314956)
		(size 0.508)
		(drill 0.254)
		(layers "F.Cu" "B.Cu")
		(net "GND")
	)
	(via
		(at 197.160896 -3.737356)
		(size 0.508)
		(drill 0.254)
		(layers "F.Cu" "B.Cu")
		(net "GND")
	)
	(via
		(at 102.926134 -167.832024)
		(size 0.5588)
		(drill 0.3048)
		(layers "F.Cu" "B.Cu")
		(net "GND")
	)
	(via
		(at 135.099552 -155.612846)
		(size 0.508)
		(drill 0.254)
		(layers "F.Cu" "B.Cu")
		(net "GND")
	)
	(via
		(at 348.9579 -29.8323)
		(size 0.508)
		(drill 0.254)
		(layers "F.Cu" "B.Cu")
		(net "GND")
	)
	(via
		(at 205.1558 -76.5048)
		(size 0.5588)
		(drill 0.3048)
		(layers "F.Cu" "B.Cu")
		(net "GND")
	)
	(via
		(at 314.148724 -162.243262)
		(size 0.5588)
		(drill 0.3048)
		(layers "F.Cu" "B.Cu")
		(net "GND")
	)
	(via
		(at 64.241934 9.084056)
		(size 0.5588)
		(drill 0.3048)
		(layers "F.Cu" "B.Cu")
		(net "GND")
	)
	(via
		(at 19.558 -127.541782)
		(size 0.508)
		(drill 0.254)
		(layers "F.Cu" "B.Cu")
		(net "GND")
	)
	(via
		(at 289.049968 -148.771356)
		(size 0.508)
		(drill 0.254)
		(layers "F.Cu" "B.Cu")
		(net "GND")
	)
	(via
		(at 28.829 -93.726)
		(size 0.508)
		(drill 0.254)
		(layers "F.Cu" "B.Cu")
		(net "GND")
	)
	(via
		(at 200.8886 -58.3438)
		(size 0.508)
		(drill 0.254)
		(layers "F.Cu" "B.Cu")
		(net "GND")
	)
	(via
		(at 378.818648 -151.392128)
		(size 0.508)
		(drill 0.254)
		(layers "F.Cu" "B.Cu")
		(net "GND")
	)
	(via
		(at 74.904346 -97.690686)
		(size 0.508)
		(drill 0.254)
		(layers "F.Cu" "B.Cu")
		(net "GND")
	)
	(via
		(at 219.181934 14.926056)
		(size 0.5588)
		(drill 0.3048)
		(layers "F.Cu" "B.Cu")
		(net "GND")
	)
	(via
		(at 172.185584 -30.249622)
		(size 0.508)
		(drill 0.254)
		(layers "F.Cu" "B.Cu")
		(net "GND")
	)
	(via
		(at 260.4643 -150.7871)
		(size 0.508)
		(drill 0.254)
		(layers "F.Cu" "B.Cu")
		(net "GND")
	)
	(via
		(at 82.021934 14.926056)
		(size 0.5588)
		(drill 0.3048)
		(layers "F.Cu" "B.Cu")
		(net "GND")
	)
	(via
		(at 115.065302 -55.409338)
		(size 0.508)
		(drill 0.254)
		(layers "F.Cu" "B.Cu")
		(net "GND")
	)
	(via
		(at 40.749474 -155.600146)
		(size 0.508)
		(drill 0.254)
		(layers "F.Cu" "B.Cu")
		(net "GND")
	)
	(via
		(at 259.8293 -150.7871)
		(size 0.508)
		(drill 0.254)
		(layers "F.Cu" "B.Cu")
		(net "GND")
	)
	(via
		(at 86.064852 -76.39304)
		(size 0.508)
		(drill 0.254)
		(layers "F.Cu" "B.Cu")
		(net "GND")
	)
	(via
		(at 226.822 -3.762756)
		(size 0.508)
		(drill 0.254)
		(layers "F.Cu" "B.Cu")
		(net "GND")
	)
	(via
		(at 229.341934 9.084056)
		(size 0.5588)
		(drill 0.3048)
		(layers "F.Cu" "B.Cu")
		(net "GND")
	)
	(via
		(at 118.035832 -141.1478)
		(size 0.508)
		(drill 0.254)
		(layers "F.Cu" "B.Cu")
		(net "GND")
	)
	(via
		(at 125.711458 -148.771356)
		(size 0.508)
		(drill 0.254)
		(layers "F.Cu" "B.Cu")
		(net "GND")
	)
	(via
		(at 289.79368 -92.061538)
		(size 0.508)
		(drill 0.254)
		(layers "F.Cu" "B.Cu")
		(net "GND")
	)
	(via
		(at 148.878544 -113.36909)
		(size 0.508)
		(drill 0.254)
		(layers "F.Cu" "B.Cu")
		(net "GND")
	)
	(via
		(at 251.923804 -84.812886)
		(size 0.508)
		(drill 0.254)
		(layers "F.Cu" "B.Cu")
		(net "GND")
	)
	(via
		(at 122.217688 -73.735184)
		(size 0.508)
		(drill 0.254)
		(layers "F.Cu" "B.Cu")
		(net "GND")
	)
	(via
		(at 3.231134 9.084056)
		(size 0.5588)
		(drill 0.3048)
		(layers "F.Cu" "B.Cu")
		(net "GND")
	)
	(via
		(at 120.216168 -58.381138)
		(size 0.508)
		(drill 0.254)
		(layers "F.Cu" "B.Cu")
		(net "GND")
	)
	(via
		(at 441.990734 -164.479224)
		(size 0.5588)
		(drill 0.3048)
		(layers "F.Cu" "B.Cu")
		(net "GND")
	)
	(via
		(at 140.917168 -125.955298)
		(size 0.508)
		(drill 0.254)
		(layers "F.Cu" "B.Cu")
		(net "GND")
	)
	(via
		(at 276.057614 -91.070938)
		(size 0.508)
		(drill 0.254)
		(layers "F.Cu" "B.Cu")
		(net "GND")
	)
	(via
		(at 116.399564 0.444754)
		(size 0.508)
		(drill 0.254)
		(layers "F.Cu" "B.Cu")
		(net "GND")
	)
	(via
		(at 48.399446 -148.771356)
		(size 0.508)
		(drill 0.254)
		(layers "F.Cu" "B.Cu")
		(net "GND")
	)
	(via
		(at 251.923804 -68.963286)
		(size 0.508)
		(drill 0.254)
		(layers "F.Cu" "B.Cu")
		(net "GND")
	)
	(via
		(at 73.437496 -141.202156)
		(size 0.508)
		(drill 0.254)
		(layers "F.Cu" "B.Cu")
		(net "GND")
	)
	(via
		(at 344.421206 0.996696)
		(size 0.508)
		(drill 0.254)
		(layers "F.Cu" "B.Cu")
		(net "GND")
	)
	(via
		(at 200.868534 -95.838264)
		(size 0.508)
		(drill 0.254)
		(layers "F.Cu" "B.Cu")
		(net "GND")
	)
	(via
		(at 286.499808 -3.762756)
		(size 0.508)
		(drill 0.254)
		(layers "F.Cu" "B.Cu")
		(net "GND")
	)
	(via
		(at 351.8154 -39.37)
		(size 0.508)
		(drill 0.254)
		(layers "F.Cu" "B.Cu")
		(net "GND")
	)
	(via
		(at 87.275924 -162.243262)
		(size 0.5588)
		(drill 0.3048)
		(layers "F.Cu" "B.Cu")
		(net "GND")
	)
	(via
		(at 417.860734 -164.479224)
		(size 0.5588)
		(drill 0.3048)
		(layers "F.Cu" "B.Cu")
		(net "GND")
	)
	(via
		(at 177.89144 -18.32864)
		(size 0.508)
		(drill 0.254)
		(layers "F.Cu" "B.Cu")
		(net "GND")
	)
	(via
		(at 462.627218 -45.611796)
		(size 0.508)
		(drill 0.254)
		(layers "F.Cu" "B.Cu")
		(net "GND")
	)
	(via
		(at 476.991934 13.910056)
		(size 0.5588)
		(drill 0.3048)
		(layers "F.Cu" "B.Cu")
		(net "GND")
	)
	(via
		(at 222.749872 -9.156446)
		(size 0.508)
		(drill 0.254)
		(layers "F.Cu" "B.Cu")
		(net "GND")
	)
	(via
		(at 412.780734 -163.361624)
		(size 0.5588)
		(drill 0.3048)
		(layers "F.Cu" "B.Cu")
		(net "GND")
	)
	(via
		(at 407.289 -125.8062)
		(size 0.508)
		(drill 0.254)
		(layers "F.Cu" "B.Cu")
		(net "GND")
	)
	(via
		(at 69.56044 -3.737356)
		(size 0.508)
		(drill 0.254)
		(layers "F.Cu" "B.Cu")
		(net "GND")
	)
	(via
		(at 413.275272 -130.207004)
		(size 0.508)
		(drill 0.254)
		(layers "F.Cu" "B.Cu")
		(net "GND")
	)
	(via
		(at 445.233806 -37.1475)
		(size 0.4572)
		(drill 0.2032)
		(layers "F.Cu" "B.Cu")
		(net "GND")
	)
	(via
		(at 129.085848 -58.876438)
		(size 0.508)
		(drill 0.254)
		(layers "F.Cu" "B.Cu")
		(net "GND")
	)
	(via
		(at 237.329218 -78.37424)
		(size 0.508)
		(drill 0.254)
		(layers "F.Cu" "B.Cu")
		(net "GND")
	)
	(via
		(at 201.037952 -141.202156)
		(size 0.508)
		(drill 0.254)
		(layers "F.Cu" "B.Cu")
		(net "GND")
	)
	(via
		(at 282.641294 -54.913784)
		(size 0.508)
		(drill 0.254)
		(layers "F.Cu" "B.Cu")
		(net "GND")
	)
	(via
		(at 297.363134 -27.829256)
		(size 0.508)
		(drill 0.254)
		(layers "F.Cu" "B.Cu")
		(net "GND")
	)
	(via
		(at 69.753226 -67.972686)
		(size 0.508)
		(drill 0.254)
		(layers "F.Cu" "B.Cu")
		(net "GND")
	)
	(via
		(at 164.9984 -125.0696)
		(size 0.508)
		(drill 0.254)
		(layers "F.Cu" "B.Cu")
		(net "GND")
	)
	(via
		(at 124.81052 -150.193756)
		(size 0.508)
		(drill 0.254)
		(layers "F.Cu" "B.Cu")
		(net "GND")
	)
	(via
		(at 196.399912 -2.314956)
		(size 0.508)
		(drill 0.254)
		(layers "F.Cu" "B.Cu")
		(net "GND")
	)
	(via
		(at 300.061884 -129.568956)
		(size 0.508)
		(drill 0.254)
		(layers "F.Cu" "B.Cu")
		(net "GND")
	)
	(via
		(at 110.772702 -56.894984)
		(size 0.508)
		(drill 0.254)
		(layers "F.Cu" "B.Cu")
		(net "GND")
	)
	(via
		(at 463.576924 -162.243262)
		(size 0.5588)
		(drill 0.3048)
		(layers "F.Cu" "B.Cu")
		(net "GND")
	)
	(via
		(at 300.095666 -95.033084)
		(size 0.508)
		(drill 0.254)
		(layers "F.Cu" "B.Cu")
		(net "GND")
	)
	(via
		(at 492.790734 -164.479224)
		(size 0.5588)
		(drill 0.3048)
		(layers "F.Cu" "B.Cu")
		(net "GND")
	)
	(via
		(at 95.714566 -138.760962)
		(size 0.508)
		(drill 0.254)
		(layers "F.Cu" "B.Cu")
		(net "GND")
	)
	(via
		(at 138.03757 -150.803356)
		(size 0.508)
		(drill 0.254)
		(layers "F.Cu" "B.Cu")
		(net "GND")
	)
	(via
		(at 139.387834 -61.847984)
		(size 0.508)
		(drill 0.254)
		(layers "F.Cu" "B.Cu")
		(net "GND")
	)
	(via
		(at 235.612178 -76.39304)
		(size 0.508)
		(drill 0.254)
		(layers "F.Cu" "B.Cu")
		(net "GND")
	)
	(via
		(at 225.862134 -167.832024)
		(size 0.5588)
		(drill 0.3048)
		(layers "F.Cu" "B.Cu")
		(net "GND")
	)
	(via
		(at 261.091934 9.084056)
		(size 0.5588)
		(drill 0.3048)
		(layers "F.Cu" "B.Cu")
		(net "GND")
	)
	(via
		(at 62.792102 -129.564892)
		(size 0.508)
		(drill 0.254)
		(layers "F.Cu" "B.Cu")
		(net "GND")
	)
	(via
		(at 301.812706 -54.418738)
		(size 0.508)
		(drill 0.254)
		(layers "F.Cu" "B.Cu")
		(net "GND")
	)
	(via
		(at 284.642814 -89.089738)
		(size 0.508)
		(drill 0.254)
		(layers "F.Cu" "B.Cu")
		(net "GND")
	)
	(via
		(at 191.216534 -167.832024)
		(size 0.5588)
		(drill 0.3048)
		(layers "F.Cu" "B.Cu")
		(net "GND")
	)
	(via
		(at 344.490294 -3.941318)
		(size 0.508)
		(drill 0.254)
		(layers "F.Cu" "B.Cu")
		(net "GND")
	)
	(via
		(at 38.199314 -131.016756)
		(size 0.508)
		(drill 0.254)
		(layers "F.Cu" "B.Cu")
		(net "GND")
	)
	(via
		(at 95.508318 -56.085486)
		(size 0.508)
		(drill 0.254)
		(layers "F.Cu" "B.Cu")
		(net "GND")
	)
	(via
		(at 141.899386 -150.219156)
		(size 0.508)
		(drill 0.254)
		(layers "F.Cu" "B.Cu")
		(net "GND")
	)
	(via
		(at 459.770734 -166.714424)
		(size 0.5588)
		(drill 0.3048)
		(layers "F.Cu" "B.Cu")
		(net "GND")
	)
	(via
		(at 297.520106 -94.538038)
		(size 0.508)
		(drill 0.254)
		(layers "F.Cu" "B.Cu")
		(net "GND")
	)
	(via
		(at 23.576534 -167.832024)
		(size 0.5588)
		(drill 0.3048)
		(layers "F.Cu" "B.Cu")
		(net "GND")
	)
	(via
		(at 71.470266 -59.057286)
		(size 0.508)
		(drill 0.254)
		(layers "F.Cu" "B.Cu")
		(net "GND")
	)
	(via
		(at 78.14945 0.468122)
		(size 0.508)
		(drill 0.254)
		(layers "F.Cu" "B.Cu")
		(net "GND")
	)
	(via
		(at 229.087934 -13.948156)
		(size 0.508)
		(drill 0.254)
		(layers "F.Cu" "B.Cu")
		(net "GND")
	)
	(via
		(at 314.54979 -22.965156)
		(size 0.508)
		(drill 0.254)
		(layers "F.Cu" "B.Cu")
		(net "GND")
	)
	(via
		(at 35.466274 -96.4946)
		(size 0.508)
		(drill 0.254)
		(layers "F.Cu" "B.Cu")
		(net "GND")
	)
	(via
		(at 288.65068 -56.399938)
		(size 0.508)
		(drill 0.254)
		(layers "F.Cu" "B.Cu")
		(net "GND")
	)
	(via
		(at 425.480734 -164.479224)
		(size 0.5588)
		(drill 0.3048)
		(layers "F.Cu" "B.Cu")
		(net "GND")
	)
	(via
		(at 299.237146 -74.725784)
		(size 0.508)
		(drill 0.254)
		(layers "F.Cu" "B.Cu")
		(net "GND")
	)
	(via
		(at 233.799888 -139.170156)
		(size 0.508)
		(drill 0.254)
		(layers "F.Cu" "B.Cu")
		(net "GND")
	)
	(via
		(at 407.700734 -164.479224)
		(size 0.5588)
		(drill 0.3048)
		(layers "F.Cu" "B.Cu")
		(net "GND")
	)
	(via
		(at 471.911934 13.910056)
		(size 0.5588)
		(drill 0.3048)
		(layers "F.Cu" "B.Cu")
		(net "GND")
	)
	(via
		(at 33.771586 -150.219156)
		(size 0.508)
		(drill 0.254)
		(layers "F.Cu" "B.Cu")
		(net "GND")
	)
	(via
		(at 109.055916 -54.913784)
		(size 0.508)
		(drill 0.254)
		(layers "F.Cu" "B.Cu")
		(net "GND")
	)
	(via
		(at 200.87209 -89.928192)
		(size 0.508)
		(drill 0.254)
		(layers "F.Cu" "B.Cu")
		(net "GND")
	)
	(via
		(at 430.560734 -163.361624)
		(size 0.5588)
		(drill 0.3048)
		(layers "F.Cu" "B.Cu")
		(net "GND")
	)
	(via
		(at 127.368808 -84.631784)
		(size 0.508)
		(drill 0.254)
		(layers "F.Cu" "B.Cu")
		(net "GND")
	)
	(via
		(at 383.039874 -152.380188)
		(size 0.508)
		(drill 0.254)
		(layers "F.Cu" "B.Cu")
		(net "GND")
	)
	(via
		(at 415.490152 -34.934652)
		(size 0.4572)
		(drill 0.2032)
		(layers "F.Cu" "B.Cu")
		(net "GND")
	)
	(via
		(at 207.119728 -60.198)
		(size 0.5588)
		(drill 0.3048)
		(layers "F.Cu" "B.Cu")
		(net "GND")
	)
	(via
		(at 128.687576 -131.600956)
		(size 0.508)
		(drill 0.254)
		(layers "F.Cu" "B.Cu")
		(net "GND")
	)
	(via
		(at 276.631654 -59.371484)
		(size 0.508)
		(drill 0.254)
		(layers "F.Cu" "B.Cu")
		(net "GND")
	)
	(via
		(at 388.1755 -79.2226)
		(size 0.508)
		(drill 0.254)
		(layers "F.Cu" "B.Cu")
		(net "GND")
	)
	(via
		(at 196.908928 -64.930782)
		(size 0.508)
		(drill 0.254)
		(layers "F.Cu" "B.Cu")
		(net "GND")
	)
	(via
		(at 120.649492 -18.757646)
		(size 0.508)
		(drill 0.254)
		(layers "F.Cu" "B.Cu")
		(net "GND")
	)
	(via
		(at 158.85922 -124.4854)
		(size 0.508)
		(drill 0.254)
		(layers "F.Cu" "B.Cu")
		(net "GND")
	)
	(via
		(at 222.749872 0.444754)
		(size 0.508)
		(drill 0.254)
		(layers "F.Cu" "B.Cu")
		(net "GND")
	)
	(via
		(at 70.515734 -167.832024)
		(size 0.5588)
		(drill 0.3048)
		(layers "F.Cu" "B.Cu")
		(net "GND")
	)
	(via
		(at 237.136432 -131.5466)
		(size 0.508)
		(drill 0.254)
		(layers "F.Cu" "B.Cu")
		(net "GND")
	)
	(via
		(at 401.350734 -167.832024)
		(size 0.5588)
		(drill 0.3048)
		(layers "F.Cu" "B.Cu")
		(net "GND")
	)
	(via
		(at 387.034024 -27.625548)
		(size 0.508)
		(drill 0.254)
		(layers "F.Cu" "B.Cu")
		(net "GND")
	)
	(via
		(at 181.73827 -39.389304)
		(size 0.508)
		(drill 0.254)
		(layers "F.Cu" "B.Cu")
		(net "GND")
	)
	(via
		(at 192.330324 -162.243262)
		(size 0.5588)
		(drill 0.3048)
		(layers "F.Cu" "B.Cu")
		(net "GND")
	)
	(via
		(at 410.21762 -148.40204)
		(size 0.508)
		(drill 0.254)
		(layers "F.Cu" "B.Cu")
		(net "GND")
	)
	(via
		(at 127.368808 -62.838584)
		(size 0.508)
		(drill 0.254)
		(layers "F.Cu" "B.Cu")
		(net "GND")
	)
	(via
		(at 276.057614 -98.005138)
		(size 0.508)
		(drill 0.254)
		(layers "F.Cu" "B.Cu")
		(net "GND")
	)
	(via
		(at 486.440734 -164.479224)
		(size 0.5588)
		(drill 0.3048)
		(layers "F.Cu" "B.Cu")
		(net "GND")
	)
	(via
		(at 140.246354 -57.390538)
		(size 0.508)
		(drill 0.254)
		(layers "F.Cu" "B.Cu")
		(net "GND")
	)
	(via
		(at 47.549308 -150.219156)
		(size 0.508)
		(drill 0.254)
		(layers "F.Cu" "B.Cu")
		(net "GND")
	)
	(via
		(at 398.806924 -162.243262)
		(size 0.5588)
		(drill 0.3048)
		(layers "F.Cu" "B.Cu")
		(net "GND")
	)
	(via
		(at 148.059648 -119.112792)
		(size 0.508)
		(drill 0.254)
		(layers "F.Cu" "B.Cu")
		(net "GND")
	)
	(via
		(at 123.076208 -68.287138)
		(size 0.508)
		(drill 0.254)
		(layers "F.Cu" "B.Cu")
		(net "GND")
	)
	(via
		(at 77.479906 -68.46824)
		(size 0.508)
		(drill 0.254)
		(layers "F.Cu" "B.Cu")
		(net "GND")
	)
	(via
		(at 36.177982 -76.468478)
		(size 0.5588)
		(drill 0.3048)
		(layers "F.Cu" "B.Cu")
		(net "GND")
	)
	(via
		(at 327.279 -33.528)
		(size 0.508)
		(drill 0.254)
		(layers "F.Cu" "B.Cu")
		(net "GND")
	)
	(via
		(at 36.044124 0.5207)
		(size 0.508)
		(drill 0.254)
		(layers "F.Cu" "B.Cu")
		(net "GND")
	)
	(via
		(at 167.1066 -32.1691)
		(size 0.508)
		(drill 0.254)
		(layers "F.Cu" "B.Cu")
		(net "GND")
	)
	(via
		(at 295.849802 1.994154)
		(size 0.508)
		(drill 0.254)
		(layers "F.Cu" "B.Cu")
		(net "GND")
	)
	(via
		(at 128.690878 -143.950944)
		(size 0.508)
		(drill 0.254)
		(layers "F.Cu" "B.Cu")
		(net "GND")
	)
	(via
		(at 34.74212 0.457454)
		(size 0.508)
		(drill 0.254)
		(layers "F.Cu" "B.Cu")
		(net "GND")
	)
	(via
		(at 428.016924 -162.243262)
		(size 0.5588)
		(drill 0.3048)
		(layers "F.Cu" "B.Cu")
		(net "GND")
	)
	(via
		(at 87.781892 -60.54344)
		(size 0.508)
		(drill 0.254)
		(layers "F.Cu" "B.Cu")
		(net "GND")
	)
	(via
		(at 85.206332 -67.972686)
		(size 0.508)
		(drill 0.254)
		(layers "F.Cu" "B.Cu")
		(net "GND")
	)
	(via
		(at 344.7796 -149.4536)
		(size 0.508)
		(drill 0.254)
		(layers "F.Cu" "B.Cu")
		(net "GND")
	)
	(via
		(at 289.049968 -136.397746)
		(size 0.508)
		(drill 0.254)
		(layers "F.Cu" "B.Cu")
		(net "GND")
	)
	(via
		(at 316.971934 14.926056)
		(size 0.5588)
		(drill 0.3048)
		(layers "F.Cu" "B.Cu")
		(net "GND")
	)
	(via
		(at 445.241934 12.894056)
		(size 0.5588)
		(drill 0.3048)
		(layers "F.Cu" "B.Cu")
		(net "GND")
	)
	(via
		(at 9.047734 -167.832024)
		(size 0.5588)
		(drill 0.3048)
		(layers "F.Cu" "B.Cu")
		(net "GND")
	)
	(via
		(at 304.349912 -11.916156)
		(size 0.508)
		(drill 0.254)
		(layers "F.Cu" "B.Cu")
		(net "GND")
	)
	(via
		(at 122.791728 -59.866784)
		(size 0.508)
		(drill 0.254)
		(layers "F.Cu" "B.Cu")
		(net "GND")
	)
	(via
		(at 304.094134 -167.832024)
		(size 0.5588)
		(drill 0.3048)
		(layers "F.Cu" "B.Cu")
		(net "GND")
	)
	(via
		(at 470.16162 -152.81021)
		(size 0.5588)
		(drill 0.3048)
		(layers "F.Cu" "B.Cu")
		(net "GND")
	)
	(via
		(at 253.640844 -63.019686)
		(size 0.508)
		(drill 0.254)
		(layers "F.Cu" "B.Cu")
		(net "GND")
	)
	(via
		(at 242.041934 9.084056)
		(size 0.5588)
		(drill 0.3048)
		(layers "F.Cu" "B.Cu")
		(net "GND")
	)
	(via
		(at 203.199746 -17.208246)
		(size 0.508)
		(drill 0.254)
		(layers "F.Cu" "B.Cu")
		(net "GND")
	)
	(via
		(at 286.499808 -17.208246)
		(size 0.508)
		(drill 0.254)
		(layers "F.Cu" "B.Cu")
		(net "GND")
	)
	(via
		(at 119.357902 -77.697584)
		(size 0.508)
		(drill 0.254)
		(layers "F.Cu" "B.Cu")
		(net "GND")
	)
	(via
		(at 292.4048 2.4638)
		(size 0.508)
		(drill 0.254)
		(layers "F.Cu" "B.Cu")
		(net "GND")
	)
	(via
		(at 64.094106 -136.3345)
		(size 0.508)
		(drill 0.254)
		(layers "F.Cu" "B.Cu")
		(net "GND")
	)
	(via
		(at 395.16685 -101.898196)
		(size 0.508)
		(drill 0.254)
		(layers "F.Cu" "B.Cu")
		(net "GND")
	)
	(via
		(at 441.431934 10.354056)
		(size 0.5588)
		(drill 0.3048)
		(layers "F.Cu" "B.Cu")
		(net "GND")
	)
	(via
		(at 258.561078 -79.354934)
		(size 0.508)
		(drill 0.254)
		(layers "F.Cu" "B.Cu")
		(net "GND")
	)
	(via
		(at 201.044556 0.5207)
		(size 0.508)
		(drill 0.254)
		(layers "F.Cu" "B.Cu")
		(net "GND")
	)
	(via
		(at 123.650248 -65.315338)
		(size 0.508)
		(drill 0.254)
		(layers "F.Cu" "B.Cu")
		(net "GND")
	)
	(via
		(at 60.210446 -3.737356)
		(size 0.508)
		(drill 0.254)
		(layers "F.Cu" "B.Cu")
		(net "GND")
	)
	(via
		(at 33.771586 -7.6454)
		(size 0.508)
		(drill 0.254)
		(layers "F.Cu" "B.Cu")
		(net "GND")
	)
	(via
		(at 113.89614 -134.913624)
		(size 0.508)
		(drill 0.254)
		(layers "F.Cu" "B.Cu")
		(net "GND")
	)
	(via
		(at 432.541934 14.926056)
		(size 0.5588)
		(drill 0.3048)
		(layers "F.Cu" "B.Cu")
		(net "GND")
	)
	(via
		(at 261.621524 -162.243262)
		(size 0.5588)
		(drill 0.3048)
		(layers "F.Cu" "B.Cu")
		(net "GND")
	)
	(via
		(at 107.027472 -8.1534)
		(size 0.508)
		(drill 0.254)
		(layers "F.Cu" "B.Cu")
		(net "GND")
	)
	(via
		(at 409.681934 9.084056)
		(size 0.5588)
		(drill 0.3048)
		(layers "F.Cu" "B.Cu")
		(net "GND")
	)
	(via
		(at 297.549824 -17.208246)
		(size 0.508)
		(drill 0.254)
		(layers "F.Cu" "B.Cu")
		(net "GND")
	)
	(via
		(at 499.501668 -45.619924)
		(size 0.508)
		(drill 0.254)
		(layers "F.Cu" "B.Cu")
		(net "GND")
	)
	(via
		(at 237.329218 -92.24264)
		(size 0.508)
		(drill 0.254)
		(layers "F.Cu" "B.Cu")
		(net "GND")
	)
	(via
		(at 149.549358 -17.208246)
		(size 0.508)
		(drill 0.254)
		(layers "F.Cu" "B.Cu")
		(net "GND")
	)
	(via
		(at 67.099434 -146.011646)
		(size 0.508)
		(drill 0.254)
		(layers "F.Cu" "B.Cu")
		(net "GND")
	)
	(via
		(at 76.862432 -102.214934)
		(size 0.508)
		(drill 0.254)
		(layers "F.Cu" "B.Cu")
		(net "GND")
	)
	(via
		(at 266.171934 14.926056)
		(size 0.5588)
		(drill 0.3048)
		(layers "F.Cu" "B.Cu")
		(net "GND")
	)
	(via
		(at 284.642814 -99.986338)
		(size 0.508)
		(drill 0.254)
		(layers "F.Cu" "B.Cu")
		(net "GND")
	)
	(via
		(at 335.947512 -25.434036)
		(size 0.508)
		(drill 0.254)
		(layers "F.Cu" "B.Cu")
		(net "GND")
	)
	(via
		(at 78.229968 -135.4074)
		(size 0.508)
		(drill 0.254)
		(layers "F.Cu" "B.Cu")
		(net "GND")
	)
	(via
		(at 68.799456 -2.314956)
		(size 0.508)
		(drill 0.254)
		(layers "F.Cu" "B.Cu")
		(net "GND")
	)
	(via
		(at 70.611746 -97.19564)
		(size 0.508)
		(drill 0.254)
		(layers "F.Cu" "B.Cu")
		(net "GND")
	)
	(via
		(at 68.894706 -68.46824)
		(size 0.508)
		(drill 0.254)
		(layers "F.Cu" "B.Cu")
		(net "GND")
	)
	(via
		(at 193.451734 -167.832024)
		(size 0.5588)
		(drill 0.3048)
		(layers "F.Cu" "B.Cu")
		(net "GND")
	)
	(via
		(at 239.046258 -59.55284)
		(size 0.508)
		(drill 0.254)
		(layers "F.Cu" "B.Cu")
		(net "GND")
	)
	(via
		(at 197.591934 14.926056)
		(size 0.5588)
		(drill 0.3048)
		(layers "F.Cu" "B.Cu")
		(net "GND")
	)
	(via
		(at 344.8812 -6.6294)
		(size 0.508)
		(drill 0.254)
		(layers "F.Cu" "B.Cu")
		(net "GND")
	)
	(via
		(at 170.82262 -62.5602)
		(size 0.508)
		(drill 0.254)
		(layers "F.Cu" "B.Cu")
		(net "GND")
	)
	(via
		(at 277.774654 -91.070938)
		(size 0.508)
		(drill 0.254)
		(layers "F.Cu" "B.Cu")
		(net "GND")
	)
	(via
		(at 126.421642 -7.6454)
		(size 0.508)
		(drill 0.254)
		(layers "F.Cu" "B.Cu")
		(net "GND")
	)
	(via
		(at 241.619024 -49.489614)
		(size 0.508)
		(drill 0.254)
		(layers "F.Cu" "B.Cu")
		(net "GND")
	)
	(via
		(at 392.69035 -122.104404)
		(size 0.508)
		(drill 0.254)
		(layers "F.Cu" "B.Cu")
		(net "GND")
	)
	(via
		(at 302.671226 -60.857384)
		(size 0.508)
		(drill 0.254)
		(layers "F.Cu" "B.Cu")
		(net "GND")
	)
	(via
		(at 461.39989 -113.8682)
		(size 0.508)
		(drill 0.254)
		(layers "F.Cu" "B.Cu")
		(net "GND")
	)
	(via
		(at 83.489292 -56.085486)
		(size 0.508)
		(drill 0.254)
		(layers "F.Cu" "B.Cu")
		(net "GND")
	)
	(via
		(at 357.382826 -141.57452)
		(size 0.508)
		(drill 0.254)
		(layers "F.Cu" "B.Cu")
		(net "GND")
	)
	(via
		(at 280.620724 -162.243262)
		(size 0.5588)
		(drill 0.3048)
		(layers "F.Cu" "B.Cu")
		(net "GND")
	)
	(via
		(at 147.387564 -4.346956)
		(size 0.508)
		(drill 0.254)
		(layers "F.Cu" "B.Cu")
		(net "GND")
	)
	(via
		(at 202.349862 -146.011646)
		(size 0.508)
		(drill 0.254)
		(layers "F.Cu" "B.Cu")
		(net "GND")
	)
	(via
		(at 254.741934 9.084056)
		(size 0.5588)
		(drill 0.3048)
		(layers "F.Cu" "B.Cu")
		(net "GND")
	)
	(via
		(at 42.088054 -86.55431)
		(size 0.5588)
		(drill 0.3048)
		(layers "F.Cu" "B.Cu")
		(net "GND")
	)
	(via
		(at 64.094106 0.5207)
		(size 0.508)
		(drill 0.254)
		(layers "F.Cu" "B.Cu")
		(net "GND")
	)
	(via
		(at 345.965272 -99.91979)
		(size 0.508)
		(drill 0.254)
		(layers "F.Cu" "B.Cu")
		(net "GND")
	)
	(via
		(at 77.299312 -7.607046)
		(size 0.508)
		(drill 0.254)
		(layers "F.Cu" "B.Cu")
		(net "GND")
	)
	(via
		(at 213.399878 0.444754)
		(size 0.508)
		(drill 0.254)
		(layers "F.Cu" "B.Cu")
		(net "GND")
	)
	(via
		(at 236.171994 -131.016756)
		(size 0.508)
		(drill 0.254)
		(layers "F.Cu" "B.Cu")
		(net "GND")
	)
	(via
		(at 279.699974 -129.568956)
		(size 0.508)
		(drill 0.254)
		(layers "F.Cu" "B.Cu")
		(net "GND")
	)
	(via
		(at 145.12163 -140.617956)
		(size 0.508)
		(drill 0.254)
		(layers "F.Cu" "B.Cu")
		(net "GND")
	)
	(via
		(at 375.747534 -167.857424)
		(size 0.5588)
		(drill 0.3048)
		(layers "F.Cu" "B.Cu")
		(net "GND")
	)
	(via
		(at 462.05775 -124.92482)
		(size 0.508)
		(drill 0.254)
		(layers "F.Cu" "B.Cu")
		(net "GND")
	)
	(via
		(at 208.122012 1.9558)
		(size 0.508)
		(drill 0.254)
		(layers "F.Cu" "B.Cu")
		(net "GND")
	)
	(via
		(at 240.763298 -52.618386)
		(size 0.508)
		(drill 0.254)
		(layers "F.Cu" "B.Cu")
		(net "GND")
	)
	(via
		(at 490.250734 -166.714424)
		(size 0.5588)
		(drill 0.3048)
		(layers "F.Cu" "B.Cu")
		(net "GND")
	)
	(via
		(at 98.942398 -56.085486)
		(size 0.508)
		(drill 0.254)
		(layers "F.Cu" "B.Cu")
		(net "GND")
	)
	(via
		(at 38.354 -52.197)
		(size 0.5588)
		(drill 0.3048)
		(layers "F.Cu" "B.Cu")
		(net "GND")
	)
	(via
		(at 162.158934 -167.832024)
		(size 0.5588)
		(drill 0.3048)
		(layers "F.Cu" "B.Cu")
		(net "GND")
	)
	(via
		(at 443.322456 -29.0322)
		(size 0.4572)
		(drill 0.2032)
		(layers "F.Cu" "B.Cu")
		(net "GND")
	)
	(via
		(at 362.931456 -152.674066)
		(size 0.5588)
		(drill 0.3048)
		(layers "F.Cu" "B.Cu")
		(net "GND")
	)
	(via
		(at 79.196692 -98.18624)
		(size 0.508)
		(drill 0.254)
		(layers "F.Cu" "B.Cu")
		(net "GND")
	)
	(via
		(at 378.344684 -79.894684)
		(size 0.4572)
		(drill 0.2032)
		(layers "F.Cu" "B.Cu")
		(net "GND")
	)
	(via
		(at 2.9464 -8.621776)
		(size 0.508)
		(drill 0.254)
		(layers "F.Cu" "B.Cu")
		(net "GND")
	)
	(via
		(at 130.84937 -13.363956)
		(size 0.508)
		(drill 0.254)
		(layers "F.Cu" "B.Cu")
		(net "GND")
	)
	(via
		(at 107.421934 9.084056)
		(size 0.5588)
		(drill 0.3048)
		(layers "F.Cu" "B.Cu")
		(net "GND")
	)
	(via
		(at 38.445186 -47.6758)
		(size 0.508)
		(drill 0.254)
		(layers "F.Cu" "B.Cu")
		(net "GND")
	)
	(via
		(at 397.540734 -163.361624)
		(size 0.5588)
		(drill 0.3048)
		(layers "F.Cu" "B.Cu")
		(net "GND")
	)
	(via
		(at 395.5415 -80.11414)
		(size 0.508)
		(drill 0.254)
		(layers "F.Cu" "B.Cu")
		(net "GND")
	)
	(via
		(at 447.781934 11.624056)
		(size 0.5588)
		(drill 0.3048)
		(layers "F.Cu" "B.Cu")
		(net "GND")
	)
	(via
		(at 56.899302 -17.208246)
		(size 0.508)
		(drill 0.254)
		(layers "F.Cu" "B.Cu")
		(net "GND")
	)
	(via
		(at 141.899386 -131.016756)
		(size 0.508)
		(drill 0.254)
		(layers "F.Cu" "B.Cu")
		(net "GND")
	)
	(via
		(at 417.301934 14.926056)
		(size 0.5588)
		(drill 0.3048)
		(layers "F.Cu" "B.Cu")
		(net "GND")
	)
	(via
		(at 160.761934 14.926056)
		(size 0.5588)
		(drill 0.3048)
		(layers "F.Cu" "B.Cu")
		(net "GND")
	)
	(via
		(at 144.411446 -148.771356)
		(size 0.508)
		(drill 0.254)
		(layers "F.Cu" "B.Cu")
		(net "GND")
	)
	(via
		(at 135.953754 -90.575384)
		(size 0.508)
		(drill 0.254)
		(layers "F.Cu" "B.Cu")
		(net "GND")
	)
	(via
		(at 269.981934 9.084056)
		(size 0.5588)
		(drill 0.3048)
		(layers "F.Cu" "B.Cu")
		(net "GND")
	)
	(via
		(at 221.899734 -134.861046)
		(size 0.508)
		(drill 0.254)
		(layers "F.Cu" "B.Cu")
		(net "GND")
	)
	(via
		(at 44.098718 -144.0053)
		(size 0.508)
		(drill 0.254)
		(layers "F.Cu" "B.Cu")
		(net "GND")
	)
	(via
		(at 169.909744 -94.023434)
		(size 0.508)
		(drill 0.254)
		(layers "F.Cu" "B.Cu")
		(net "GND")
	)
	(via
		(at 21.341334 -167.832024)
		(size 0.5588)
		(drill 0.3048)
		(layers "F.Cu" "B.Cu")
		(net "GND")
	)
	(via
		(at 433.100734 -165.596824)
		(size 0.5588)
		(drill 0.3048)
		(layers "F.Cu" "B.Cu")
		(net "GND")
	)
	(via
		(at 235.916724 -162.243262)
		(size 0.5588)
		(drill 0.3048)
		(layers "F.Cu" "B.Cu")
		(net "GND")
	)
	(via
		(at 80.055212 -99.67214)
		(size 0.508)
		(drill 0.254)
		(layers "F.Cu" "B.Cu")
		(net "GND")
	)
	(via
		(at 339.979 -81.1784)
		(size 0.508)
		(drill 0.254)
		(layers "F.Cu" "B.Cu")
		(net "GND")
	)
	(via
		(at 303.529746 -57.390538)
		(size 0.508)
		(drill 0.254)
		(layers "F.Cu" "B.Cu")
		(net "GND")
	)
	(via
		(at 37.34943 -2.314956)
		(size 0.508)
		(drill 0.254)
		(layers "F.Cu" "B.Cu")
		(net "GND")
	)
	(via
		(at 461.751934 10.354056)
		(size 0.5588)
		(drill 0.3048)
		(layers "F.Cu" "B.Cu")
		(net "GND")
	)
	(via
		(at 171.221146 -145.667222)
		(size 0.508)
		(drill 0.254)
		(layers "F.Cu" "B.Cu")
		(net "GND")
	)
	(via
		(at 179.3494 -149.8219)
		(size 0.508)
		(drill 0.254)
		(layers "F.Cu" "B.Cu")
		(net "GND")
	)
	(via
		(at 41.501314 -134.861046)
		(size 0.508)
		(drill 0.254)
		(layers "F.Cu" "B.Cu")
		(net "GND")
	)
	(via
		(at 10.04062 -1.32207)
		(size 0.508)
		(drill 0.254)
		(layers "F.Cu" "B.Cu")
		(net "GND")
	)
	(via
		(at 274.056348 -54.913784)
		(size 0.508)
		(drill 0.254)
		(layers "F.Cu" "B.Cu")
		(net "GND")
	)
	(via
		(at 260.461252 -79.344774)
		(size 0.508)
		(drill 0.254)
		(layers "F.Cu" "B.Cu")
		(net "GND")
	)
	(via
		(at 79.196692 -78.37424)
		(size 0.508)
		(drill 0.254)
		(layers "F.Cu" "B.Cu")
		(net "GND")
	)
	(via
		(at 458.541374 -15.799054)
		(size 0.5588)
		(drill 0.3048)
		(layers "F.Cu" "B.Cu")
		(net "GND")
	)
	(via
		(at 252.782324 -83.32724)
		(size 0.508)
		(drill 0.254)
		(layers "F.Cu" "B.Cu")
		(net "GND")
	)
	(via
		(at 150.399496 -139.170156)
		(size 0.508)
		(drill 0.254)
		(layers "F.Cu" "B.Cu")
		(net "GND")
	)
	(via
		(at 39.899336 -13.363956)
		(size 0.508)
		(drill 0.254)
		(layers "F.Cu" "B.Cu")
		(net "GND")
	)
	(via
		(at 44.092114 -21.513292)
		(size 0.508)
		(drill 0.254)
		(layers "F.Cu" "B.Cu")
		(net "GND")
	)
	(via
		(at 75.762866 -100.167186)
		(size 0.508)
		(drill 0.254)
		(layers "F.Cu" "B.Cu")
		(net "GND")
	)
	(via
		(at 0.22225 -53.679344)
		(size 0.5588)
		(drill 0.3048)
		(layers "F.Cu" "B.Cu")
		(net "GND")
	)
	(via
		(at 471.911934 12.894056)
		(size 0.5588)
		(drill 0.3048)
		(layers "F.Cu" "B.Cu")
		(net "GND")
	)
	(via
		(at 146.092164 -148.767292)
		(size 0.508)
		(drill 0.254)
		(layers "F.Cu" "B.Cu")
		(net "GND")
	)
	(via
		(at 405.871934 9.084056)
		(size 0.5588)
		(drill 0.3048)
		(layers "F.Cu" "B.Cu")
		(net "GND")
	)
	(via
		(at 396.65275 -95.888556)
		(size 0.508)
		(drill 0.254)
		(layers "F.Cu" "B.Cu")
		(net "GND")
	)
	(via
		(at 188.410596 -95.621602)
		(size 0.5588)
		(drill 0.3048)
		(layers "F.Cu" "B.Cu")
		(net "GND")
	)
	(via
		(at 201.2696 -70.2056)
		(size 0.5588)
		(drill 0.3048)
		(layers "F.Cu" "B.Cu")
		(net "GND")
	)
	(via
		(at 35.5092 -66.9798)
		(size 0.508)
		(drill 0.254)
		(layers "F.Cu" "B.Cu")
		(net "GND")
	)
	(via
		(at 221.899734 -22.965156)
		(size 0.508)
		(drill 0.254)
		(layers "F.Cu" "B.Cu")
		(net "GND")
	)
	(via
		(at 197.160896 -150.193756)
		(size 0.508)
		(drill 0.254)
		(layers "F.Cu" "B.Cu")
		(net "GND")
	)
	(via
		(at 121.359168 -83.146138)
		(size 0.508)
		(drill 0.254)
		(layers "F.Cu" "B.Cu")
		(net "GND")
	)
	(via
		(at 158.221934 9.084056)
		(size 0.5588)
		(drill 0.3048)
		(layers "F.Cu" "B.Cu")
		(net "GND")
	)
	(via
		(at 200.515728 -60.184538)
		(size 0.5588)
		(drill 0.3048)
		(layers "F.Cu" "B.Cu")
		(net "GND")
	)
	(via
		(at 231.249728 -3.762756)
		(size 0.508)
		(drill 0.254)
		(layers "F.Cu" "B.Cu")
		(net "GND")
	)
	(via
		(at 111.631222 -64.324738)
		(size 0.508)
		(drill 0.254)
		(layers "F.Cu" "B.Cu")
		(net "GND")
	)
	(via
		(at 168.0718 -36.1442)
		(size 0.508)
		(drill 0.254)
		(layers "F.Cu" "B.Cu")
		(net "GND")
	)
	(via
		(at 471.621612 -22.198838)
		(size 0.508)
		(drill 0.254)
		(layers "F.Cu" "B.Cu")
		(net "GND")
	)
	(via
		(at 173.9646 -88.392)
		(size 0.508)
		(drill 0.254)
		(layers "F.Cu" "B.Cu")
		(net "GND")
	)
	(via
		(at 411.489144 -49.831244)
		(size 0.508)
		(drill 0.254)
		(layers "F.Cu" "B.Cu")
		(net "GND")
	)
	(via
		(at 294.999918 -136.410446)
		(size 0.508)
		(drill 0.254)
		(layers "F.Cu" "B.Cu")
		(net "GND")
	)
	(via
		(at 382.78435 -123.821444)
		(size 0.508)
		(drill 0.254)
		(layers "F.Cu" "B.Cu")
		(net "GND")
	)
	(via
		(at 178.870356 -73.85685)
		(size 0.508)
		(drill 0.254)
		(layers "F.Cu" "B.Cu")
		(net "GND")
	)
	(via
		(at 0.680212 -56.138572)
		(size 0.5588)
		(drill 0.3048)
		(layers "F.Cu" "B.Cu")
		(net "GND")
	)
	(via
		(at 403.733 0.1524)
		(size 0.508)
		(drill 0.254)
		(layers "F.Cu" "B.Cu")
		(net "GND")
	)
	(via
		(at 76.449428 -9.156446)
		(size 0.508)
		(drill 0.254)
		(layers "F.Cu" "B.Cu")
		(net "GND")
	)
	(via
		(at 52.630324 -162.243262)
		(size 0.5588)
		(drill 0.3048)
		(layers "F.Cu" "B.Cu")
		(net "GND")
	)
	(via
		(at 78.211934 9.084056)
		(size 0.5588)
		(drill 0.3048)
		(layers "F.Cu" "B.Cu")
		(net "GND")
	)
	(via
		(at 350.7486 -15.19428)
		(size 0.508)
		(drill 0.254)
		(layers "F.Cu" "B.Cu")
		(net "GND")
	)
	(via
		(at 301.855124 -162.243262)
		(size 0.5588)
		(drill 0.3048)
		(layers "F.Cu" "B.Cu")
		(net "GND")
	)
	(via
		(at 496.041934 9.084056)
		(size 0.5588)
		(drill 0.3048)
		(layers "F.Cu" "B.Cu")
		(net "GND")
	)
	(via
		(at 449.051934 9.084056)
		(size 0.5588)
		(drill 0.3048)
		(layers "F.Cu" "B.Cu")
		(net "GND")
	)
	(via
		(at 87.781892 -83.32724)
		(size 0.508)
		(drill 0.254)
		(layers "F.Cu" "B.Cu")
		(net "GND")
	)
	(via
		(at 84.347812 -92.24264)
		(size 0.508)
		(drill 0.254)
		(layers "F.Cu" "B.Cu")
		(net "GND")
	)
	(via
		(at 473.181934 9.084056)
		(size 0.5588)
		(drill 0.3048)
		(layers "F.Cu" "B.Cu")
		(net "GND")
	)
	(via
		(at 407.036016 4.405884)
		(size 0.508)
		(drill 0.254)
		(layers "F.Cu" "B.Cu")
		(net "GND")
	)
	(via
		(at 71.470266 -95.709486)
		(size 0.508)
		(drill 0.254)
		(layers "F.Cu" "B.Cu")
		(net "GND")
	)
	(via
		(at 104.039924 -162.243262)
		(size 0.5588)
		(drill 0.3048)
		(layers "F.Cu" "B.Cu")
		(net "GND")
	)
	(via
		(at 139.803124 -162.243262)
		(size 0.5588)
		(drill 0.3048)
		(layers "F.Cu" "B.Cu")
		(net "GND")
	)
	(via
		(at 450.880734 -167.832024)
		(size 0.5588)
		(drill 0.3048)
		(layers "F.Cu" "B.Cu")
		(net "GND")
	)
	(via
		(at 127.741934 14.926056)
		(size 0.5588)
		(drill 0.3048)
		(layers "F.Cu" "B.Cu")
		(net "GND")
	)
	(via
		(at 422.936924 -162.243262)
		(size 0.5588)
		(drill 0.3048)
		(layers "F.Cu" "B.Cu")
		(net "GND")
	)
	(via
		(at 116.782342 -61.352938)
		(size 0.508)
		(drill 0.254)
		(layers "F.Cu" "B.Cu")
		(net "GND")
	)
	(via
		(at 345.502738 -144.11706)
		(size 0.508)
		(drill 0.254)
		(layers "F.Cu" "B.Cu")
		(net "GND")
	)
	(via
		(at 30.503368 -143.9926)
		(size 0.508)
		(drill 0.254)
		(layers "F.Cu" "B.Cu")
		(net "GND")
	)
	(via
		(at 69.753226 -59.057286)
		(size 0.508)
		(drill 0.254)
		(layers "F.Cu" "B.Cu")
		(net "GND")
	)
	(via
		(at 345.4654 -36.83)
		(size 0.508)
		(drill 0.254)
		(layers "F.Cu" "B.Cu")
		(net "GND")
	)
	(via
		(at 279.207214 -55.904384)
		(size 0.508)
		(drill 0.254)
		(layers "F.Cu" "B.Cu")
		(net "GND")
	)
	(via
		(at 235.691934 9.084056)
		(size 0.5588)
		(drill 0.3048)
		(layers "F.Cu" "B.Cu")
		(net "GND")
	)
	(via
		(at 71.171562 -144.5006)
		(size 0.508)
		(drill 0.254)
		(layers "F.Cu" "B.Cu")
		(net "GND")
	)
	(via
		(at 215.860884 -130.991356)
		(size 0.508)
		(drill 0.254)
		(layers "F.Cu" "B.Cu")
		(net "GND")
	)
	(via
		(at 393.2682 -128.6764)
		(size 0.508)
		(drill 0.254)
		(layers "F.Cu" "B.Cu")
		(net "GND")
	)
	(via
		(at 304.349912 0.444754)
		(size 0.508)
		(drill 0.254)
		(layers "F.Cu" "B.Cu")
		(net "GND")
	)
	(via
		(at 28.046934 -167.832024)
		(size 0.5588)
		(drill 0.3048)
		(layers "F.Cu" "B.Cu")
		(net "GND")
	)
	(via
		(at 118.851934 9.084056)
		(size 0.5588)
		(drill 0.3048)
		(layers "F.Cu" "B.Cu")
		(net "GND")
	)
	(via
		(at 300.461934 14.926056)
		(size 0.5588)
		(drill 0.3048)
		(layers "F.Cu" "B.Cu")
		(net "GND")
	)
	(via
		(at 312.387996 -131.600956)
		(size 0.508)
		(drill 0.254)
		(layers "F.Cu" "B.Cu")
		(net "GND")
	)
	(via
		(at 32.160464 -22.939756)
		(size 0.508)
		(drill 0.254)
		(layers "F.Cu" "B.Cu")
		(net "GND")
	)
	(via
		(at 126.421642 -27.829256)
		(size 0.508)
		(drill 0.254)
		(layers "F.Cu" "B.Cu")
		(net "GND")
	)
	(via
		(at 209.08645 -4.2926)
		(size 0.508)
		(drill 0.254)
		(layers "F.Cu" "B.Cu")
		(net "GND")
	)
	(via
		(at 197.151752 1.994154)
		(size 0.508)
		(drill 0.254)
		(layers "F.Cu" "B.Cu")
		(net "GND")
	)
	(via
		(at 230.611934 14.926056)
		(size 0.5588)
		(drill 0.3048)
		(layers "F.Cu" "B.Cu")
		(net "GND")
	)
	(via
		(at 242.299744 1.994154)
		(size 0.508)
		(drill 0.254)
		(layers "F.Cu" "B.Cu")
		(net "GND")
	)
	(via
		(at 458.216 -113.7666)
		(size 0.508)
		(drill 0.254)
		(layers "F.Cu" "B.Cu")
		(net "GND")
	)
	(via
		(at 177.93335 -157.523688)
		(size 0.5588)
		(drill 0.3048)
		(layers "F.Cu" "B.Cu")
		(net "GND")
	)
	(via
		(at 82.630772 -53.60924)
		(size 0.508)
		(drill 0.254)
		(layers "F.Cu" "B.Cu")
		(net "GND")
	)
	(via
		(at 487.151934 13.910056)
		(size 0.5588)
		(drill 0.3048)
		(layers "F.Cu" "B.Cu")
		(net "GND")
	)
	(via
		(at 324.207124 -162.243262)
		(size 0.5588)
		(drill 0.3048)
		(layers "F.Cu" "B.Cu")
		(net "GND")
	)
	(via
		(at 119.357902 -68.782184)
		(size 0.508)
		(drill 0.254)
		(layers "F.Cu" "B.Cu")
		(net "GND")
	)
	(via
		(at 242.480338 -100.167186)
		(size 0.508)
		(drill 0.254)
		(layers "F.Cu" "B.Cu")
		(net "GND")
	)
	(via
		(at 248.489724 -83.822286)
		(size 0.508)
		(drill 0.254)
		(layers "F.Cu" "B.Cu")
		(net "GND")
	)
	(via
		(at 490.2454 -110.7948)
		(size 0.508)
		(drill 0.254)
		(layers "F.Cu" "B.Cu")
		(net "GND")
	)
	(via
		(at 171.54652 -62.57036)
		(size 0.508)
		(drill 0.254)
		(layers "F.Cu" "B.Cu")
		(net "GND")
	)
	(via
		(at 201.031856 -139.1666)
		(size 0.508)
		(drill 0.254)
		(layers "F.Cu" "B.Cu")
		(net "GND")
	)
	(via
		(at 482.630734 -163.361624)
		(size 0.5588)
		(drill 0.3048)
		(layers "F.Cu" "B.Cu")
		(net "GND")
	)
	(via
		(at 72.328786 -70.44944)
		(size 0.508)
		(drill 0.254)
		(layers "F.Cu" "B.Cu")
		(net "GND")
	)
	(via
		(at 70.611746 -53.60924)
		(size 0.508)
		(drill 0.254)
		(layers "F.Cu" "B.Cu")
		(net "GND")
	)
	(via
		(at 274.340828 -96.023938)
		(size 0.508)
		(drill 0.254)
		(layers "F.Cu" "B.Cu")
		(net "GND")
	)
	(via
		(at 151.24938 -134.861046)
		(size 0.508)
		(drill 0.254)
		(layers "F.Cu" "B.Cu")
		(net "GND")
	)
	(via
		(at 154.411934 9.084056)
		(size 0.5588)
		(drill 0.3048)
		(layers "F.Cu" "B.Cu")
		(net "GND")
	)
	(via
		(at 322.065904 -18.713704)
		(size 0.508)
		(drill 0.254)
		(layers "F.Cu" "B.Cu")
		(net "GND")
	)
	(via
		(at 233.036618 -89.765886)
		(size 0.508)
		(drill 0.254)
		(layers "F.Cu" "B.Cu")
		(net "GND")
	)
	(via
		(at 117.640862 -58.876438)
		(size 0.508)
		(drill 0.254)
		(layers "F.Cu" "B.Cu")
		(net "GND")
	)
	(via
		(at 299.237146 -57.885584)
		(size 0.508)
		(drill 0.254)
		(layers "F.Cu" "B.Cu")
		(net "GND")
	)
	(via
		(at 255.35763 -85.803486)
		(size 0.508)
		(drill 0.254)
		(layers "F.Cu" "B.Cu")
		(net "GND")
	)
	(via
		(at 108.126276 -70.84314)
		(size 0.5588)
		(drill 0.3048)
		(layers "F.Cu" "B.Cu")
		(net "GND")
	)
	(via
		(at 80.913732 -96.20504)
		(size 0.508)
		(drill 0.254)
		(layers "F.Cu" "B.Cu")
		(net "GND")
	)
	(via
		(at 66.249296 -124.725176)
		(size 0.508)
		(drill 0.254)
		(layers "F.Cu" "B.Cu")
		(net "GND")
	)
	(via
		(at 203.199746 -3.762756)
		(size 0.508)
		(drill 0.254)
		(layers "F.Cu" "B.Cu")
		(net "GND")
	)
	(via
		(at 75.59929 -144.462246)
		(size 0.508)
		(drill 0.254)
		(layers "F.Cu" "B.Cu")
		(net "GND")
	)
	(via
		(at 414.050734 -164.479224)
		(size 0.5588)
		(drill 0.3048)
		(layers "F.Cu" "B.Cu")
		(net "GND")
	)
	(via
		(at 378.32665 -119.528844)
		(size 0.508)
		(drill 0.254)
		(layers "F.Cu" "B.Cu")
		(net "GND")
	)
	(via
		(at 34.74212 -21.513292)
		(size 0.508)
		(drill 0.254)
		(layers "F.Cu" "B.Cu")
		(net "GND")
	)
	(via
		(at 421.273986 -9.62406)
		(size 0.508)
		(drill 0.254)
		(layers "F.Cu" "B.Cu")
		(net "GND")
	)
	(via
		(at 226.111816 -21.517356)
		(size 0.508)
		(drill 0.254)
		(layers "F.Cu" "B.Cu")
		(net "GND")
	)
	(via
		(at 316.547754 -33.036764)
		(size 0.508)
		(drill 0.254)
		(layers "F.Cu" "B.Cu")
		(net "GND")
	)
	(via
		(at 468.2998 -64.3636)
		(size 0.508)
		(drill 0.254)
		(layers "F.Cu" "B.Cu")
		(net "GND")
	)
	(via
		(at 239.046258 -97.19564)
		(size 0.508)
		(drill 0.254)
		(layers "F.Cu" "B.Cu")
		(net "GND")
	)
	(via
		(at 205.749906 -155.600146)
		(size 0.508)
		(drill 0.254)
		(layers "F.Cu" "B.Cu")
		(net "GND")
	)
	(via
		(at 233.036618 -84.812886)
		(size 0.508)
		(drill 0.254)
		(layers "F.Cu" "B.Cu")
		(net "GND")
	)
	(via
		(at 388.066788 -146.33702)
		(size 0.508)
		(drill 0.254)
		(layers "F.Cu" "B.Cu")
		(net "GND")
	)
	(via
		(at 112.980724 -162.243262)
		(size 0.5588)
		(drill 0.3048)
		(layers "F.Cu" "B.Cu")
		(net "GND")
	)
	(via
		(at 234.753658 -56.085486)
		(size 0.508)
		(drill 0.254)
		(layers "F.Cu" "B.Cu")
		(net "GND")
	)
	(via
		(at 397.540734 -167.832024)
		(size 0.5588)
		(drill 0.3048)
		(layers "F.Cu" "B.Cu")
		(net "GND")
	)
	(via
		(at 300.954186 -78.688438)
		(size 0.508)
		(drill 0.254)
		(layers "F.Cu" "B.Cu")
		(net "GND")
	)
	(via
		(at 445.800734 -165.596824)
		(size 0.5588)
		(drill 0.3048)
		(layers "F.Cu" "B.Cu")
		(net "GND")
	)
	(via
		(at 4.353306 -136.444482)
		(size 0.508)
		(drill 0.254)
		(layers "F.Cu" "B.Cu")
		(net "GND")
	)
	(via
		(at 39.899336 -7.607046)
		(size 0.508)
		(drill 0.254)
		(layers "F.Cu" "B.Cu")
		(net "GND")
	)
	(via
		(at 198.772018 -22.965156)
		(size 0.508)
		(drill 0.254)
		(layers "F.Cu" "B.Cu")
		(net "GND")
	)
	(via
		(at 78.274164 -22.198076)
		(size 0.508)
		(drill 0.254)
		(layers "F.Cu" "B.Cu")
		(net "GND")
	)
	(via
		(at 31.908496 -73.058782)
		(size 0.508)
		(drill 0.254)
		(layers "F.Cu" "B.Cu")
		(net "GND")
	)
	(via
		(at 300.095666 -81.164938)
		(size 0.508)
		(drill 0.254)
		(layers "F.Cu" "B.Cu")
		(net "GND")
	)
	(via
		(at 273.791934 14.926056)
		(size 0.5588)
		(drill 0.3048)
		(layers "F.Cu" "B.Cu")
		(net "GND")
	)
	(via
		(at 129.085848 -74.725784)
		(size 0.508)
		(drill 0.254)
		(layers "F.Cu" "B.Cu")
		(net "GND")
	)
	(via
		(at 247.631204 -88.28024)
		(size 0.508)
		(drill 0.254)
		(layers "F.Cu" "B.Cu")
		(net "GND")
	)
	(via
		(at 44.098718 -134.4041)
		(size 0.508)
		(drill 0.254)
		(layers "F.Cu" "B.Cu")
		(net "GND")
	)
	(via
		(at 448.8815 -26.543)
		(size 0.508)
		(drill 0.254)
		(layers "F.Cu" "B.Cu")
		(net "GND")
	)
	(via
		(at 123.650248 -55.409338)
		(size 0.508)
		(drill 0.254)
		(layers "F.Cu" "B.Cu")
		(net "GND")
	)
	(via
		(at 395.16685 -96.747076)
		(size 0.508)
		(drill 0.254)
		(layers "F.Cu" "B.Cu")
		(net "GND")
	)
	(via
		(at 11.054334 9.084056)
		(size 0.5588)
		(drill 0.3048)
		(layers "F.Cu" "B.Cu")
		(net "GND")
	)
	(via
		(at 82.630772 -61.53404)
		(size 0.508)
		(drill 0.254)
		(layers "F.Cu" "B.Cu")
		(net "GND")
	)
	(via
		(at 234.753658 -85.803486)
		(size 0.508)
		(drill 0.254)
		(layers "F.Cu" "B.Cu")
		(net "GND")
	)
	(via
		(at 77.479906 -84.31784)
		(size 0.508)
		(drill 0.254)
		(layers "F.Cu" "B.Cu")
		(net "GND")
	)
	(via
		(at 389.01751 -44.86783)
		(size 0.508)
		(drill 0.254)
		(layers "F.Cu" "B.Cu")
		(net "GND")
	)
	(via
		(at 224.449894 -18.744946)
		(size 0.508)
		(drill 0.254)
		(layers "F.Cu" "B.Cu")
		(net "GND")
	)
	(via
		(at 402.449538 1.702308)
		(size 0.508)
		(drill 0.254)
		(layers "F.Cu" "B.Cu")
		(net "GND")
	)
	(via
		(at 317.09995 -7.086346)
		(size 0.508)
		(drill 0.254)
		(layers "F.Cu" "B.Cu")
		(net "GND")
	)
	(via
		(at 226.111816 -2.314956)
		(size 0.508)
		(drill 0.254)
		(layers "F.Cu" "B.Cu")
		(net "GND")
	)
	(via
		(at 341.6554 -38.1)
		(size 0.508)
		(drill 0.254)
		(layers "F.Cu" "B.Cu")
		(net "GND")
	)
	(via
		(at 54.737508 -23.549356)
		(size 0.508)
		(drill 0.254)
		(layers "F.Cu" "B.Cu")
		(net "GND")
	)
	(via
		(at 148.355304 -112.732312)
		(size 0.508)
		(drill 0.254)
		(layers "F.Cu" "B.Cu")
		(net "GND")
	)
	(via
		(at 176.367694 -56.722518)
		(size 0.508)
		(drill 0.254)
		(layers "F.Cu" "B.Cu")
		(net "GND")
	)
	(via
		(at 137.670794 -75.716384)
		(size 0.508)
		(drill 0.254)
		(layers "F.Cu" "B.Cu")
		(net "GND")
	)
	(via
		(at 19.44116 -100.92817)
		(size 0.5588)
		(drill 0.3048)
		(layers "F.Cu" "B.Cu")
		(net "GND")
	)
	(via
		(at 301.749206 -26.73731)
		(size 0.508)
		(drill 0.254)
		(layers "F.Cu" "B.Cu")
		(net "GND")
	)
	(via
		(at 84.347812 -61.53404)
		(size 0.508)
		(drill 0.254)
		(layers "F.Cu" "B.Cu")
		(net "GND")
	)
	(via
		(at 211.699856 0.444754)
		(size 0.508)
		(drill 0.254)
		(layers "F.Cu" "B.Cu")
		(net "GND")
	)
	(via
		(at 438.891934 11.624056)
		(size 0.5588)
		(drill 0.3048)
		(layers "F.Cu" "B.Cu")
		(net "GND")
	)
	(via
		(at 86.923372 -83.822286)
		(size 0.508)
		(drill 0.254)
		(layers "F.Cu" "B.Cu")
		(net "GND")
	)
	(via
		(at 178.934364 1.999996)
		(size 0.5588)
		(drill 0.3048)
		(layers "F.Cu" "B.Cu")
		(net "GND")
	)
	(via
		(at 284.331664 -21.5138)
		(size 0.508)
		(drill 0.254)
		(layers "F.Cu" "B.Cu")
		(net "GND")
	)
	(via
		(at 237.142528 -136.397746)
		(size 0.508)
		(drill 0.254)
		(layers "F.Cu" "B.Cu")
		(net "GND")
	)
	(via
		(at 309.929276 -61.819536)
		(size 0.508)
		(drill 0.254)
		(layers "F.Cu" "B.Cu")
		(net "GND")
	)
	(via
		(at 262.739124 -162.243262)
		(size 0.5588)
		(drill 0.3048)
		(layers "F.Cu" "B.Cu")
		(net "GND")
	)
	(via
		(at 464.850734 -165.596824)
		(size 0.5588)
		(drill 0.3048)
		(layers "F.Cu" "B.Cu")
		(net "GND")
	)
	(via
		(at 393.68095 -95.888556)
		(size 0.508)
		(drill 0.254)
		(layers "F.Cu" "B.Cu")
		(net "GND")
	)
	(via
		(at 278.896572 -134.913624)
		(size 0.508)
		(drill 0.254)
		(layers "F.Cu" "B.Cu")
		(net "GND")
	)
	(via
		(at 500.406924 -162.243262)
		(size 0.5588)
		(drill 0.3048)
		(layers "F.Cu" "B.Cu")
		(net "GND")
	)
	(via
		(at 240.650522 -126.401576)
		(size 0.508)
		(drill 0.254)
		(layers "F.Cu" "B.Cu")
		(net "GND")
	)
	(via
		(at 412.290006 -30.13456)
		(size 0.4572)
		(drill 0.2032)
		(layers "F.Cu" "B.Cu")
		(net "GND")
	)
	(via
		(at 441.801758 -45.560996)
		(size 0.508)
		(drill 0.254)
		(layers "F.Cu" "B.Cu")
		(net "GND")
	)
	(via
		(at 422.940734 -164.479224)
		(size 0.5588)
		(drill 0.3048)
		(layers "F.Cu" "B.Cu")
		(net "GND")
	)
	(via
		(at 442.522356 -25.8318)
		(size 0.4572)
		(drill 0.2032)
		(layers "F.Cu" "B.Cu")
		(net "GND")
	)
	(via
		(at 279.491694 -89.089738)
		(size 0.508)
		(drill 0.254)
		(layers "F.Cu" "B.Cu")
		(net "GND")
	)
	(via
		(at 147.626324 -162.243262)
		(size 0.5588)
		(drill 0.3048)
		(layers "F.Cu" "B.Cu")
		(net "GND")
	)
	(via
		(at 344.8558 -4.5212)
		(size 0.508)
		(drill 0.254)
		(layers "F.Cu" "B.Cu")
		(net "GND")
	)
	(via
		(at 35.51301 -68.319396)
		(size 0.5588)
		(drill 0.3048)
		(layers "F.Cu" "B.Cu")
		(net "GND")
	)
	(via
		(at 119.357902 -64.819784)
		(size 0.508)
		(drill 0.254)
		(layers "F.Cu" "B.Cu")
		(net "GND")
	)
	(via
		(at 131.690618 -26.495756)
		(size 0.508)
		(drill 0.254)
		(layers "F.Cu" "B.Cu")
		(net "GND")
	)
	(via
		(at 42.5958 -92.4306)
		(size 0.5588)
		(drill 0.3048)
		(layers "F.Cu" "B.Cu")
		(net "GND")
	)
	(via
		(at 243.338604 -59.057286)
		(size 0.508)
		(drill 0.254)
		(layers "F.Cu" "B.Cu")
		(net "GND")
	)
	(via
		(at 431.271934 11.624056)
		(size 0.5588)
		(drill 0.3048)
		(layers "F.Cu" "B.Cu")
		(net "GND")
	)
	(via
		(at 282.067254 -89.584784)
		(size 0.508)
		(drill 0.254)
		(layers "F.Cu" "B.Cu")
		(net "GND")
	)
	(via
		(at 45.390816 -16.696944)
		(size 0.508)
		(drill 0.254)
		(layers "F.Cu" "B.Cu")
		(net "GND")
	)
	(via
		(at 97.225358 -95.709486)
		(size 0.508)
		(drill 0.254)
		(layers "F.Cu" "B.Cu")
		(net "GND")
	)
	(via
		(at 34.748724 -7.1501)
		(size 0.508)
		(drill 0.254)
		(layers "F.Cu" "B.Cu")
		(net "GND")
	)
	(via
		(at 215.2904 -84.201)
		(size 0.508)
		(drill 0.254)
		(layers "F.Cu" "B.Cu")
		(net "GND")
	)
	(via
		(at 293.22776 -81.164938)
		(size 0.508)
		(drill 0.254)
		(layers "F.Cu" "B.Cu")
		(net "GND")
	)
	(via
		(at 94.649798 -88.28024)
		(size 0.508)
		(drill 0.254)
		(layers "F.Cu" "B.Cu")
		(net "GND")
	)
	(via
		(at 345.1098 -98.2218)
		(size 0.508)
		(drill 0.254)
		(layers "F.Cu" "B.Cu")
		(net "GND")
	)
	(via
		(at 251.923804 -78.869286)
		(size 0.508)
		(drill 0.254)
		(layers "F.Cu" "B.Cu")
		(net "GND")
	)
	(via
		(at 292.392608 -28.730956)
		(size 0.508)
		(drill 0.254)
		(layers "F.Cu" "B.Cu")
		(net "GND")
	)
	(via
		(at 247.631204 -92.24264)
		(size 0.508)
		(drill 0.254)
		(layers "F.Cu" "B.Cu")
		(net "GND")
	)
	(via
		(at 122.349514 -11.916156)
		(size 0.508)
		(drill 0.254)
		(layers "F.Cu" "B.Cu")
		(net "GND")
	)
	(via
		(at 486.4354 -121.9327)
		(size 0.508)
		(drill 0.254)
		(layers "F.Cu" "B.Cu")
		(net "GND")
	)
	(via
		(at 230.332534 -167.832024)
		(size 0.5588)
		(drill 0.3048)
		(layers "F.Cu" "B.Cu")
		(net "GND")
	)
	(via
		(at 276.916134 -96.518984)
		(size 0.508)
		(drill 0.254)
		(layers "F.Cu" "B.Cu")
		(net "GND")
	)
	(via
		(at 392.938 -66.929)
		(size 0.508)
		(drill 0.254)
		(layers "F.Cu" "B.Cu")
		(net "GND")
	)
	(via
		(at 411.593538 -94.977204)
		(size 0.508)
		(drill 0.254)
		(layers "F.Cu" "B.Cu")
		(net "GND")
	)
	(via
		(at 500.09298 -122.35434)
		(size 0.508)
		(drill 0.254)
		(layers "F.Cu" "B.Cu")
		(net "GND")
	)
	(via
		(at 272.027904 -135.4074)
		(size 0.508)
		(drill 0.254)
		(layers "F.Cu" "B.Cu")
		(net "GND")
	)
	(via
		(at 485.881934 11.624056)
		(size 0.5588)
		(drill 0.3048)
		(layers "F.Cu" "B.Cu")
		(net "GND")
	)
	(via
		(at 123.934728 -91.565984)
		(size 0.508)
		(drill 0.254)
		(layers "F.Cu" "B.Cu")
		(net "GND")
	)
	(via
		(at 106.480356 -60.362338)
		(size 0.508)
		(drill 0.254)
		(layers "F.Cu" "B.Cu")
		(net "GND")
	)
	(via
		(at 216.799922 0.444754)
		(size 0.508)
		(drill 0.254)
		(layers "F.Cu" "B.Cu")
		(net "GND")
	)
	(via
		(at 215.2904 -61.8236)
		(size 0.508)
		(drill 0.254)
		(layers "F.Cu" "B.Cu")
		(net "GND")
	)
	(via
		(at 459.804516 -118.61927)
		(size 0.508)
		(drill 0.254)
		(layers "F.Cu" "B.Cu")
		(net "GND")
	)
	(via
		(at 41.461182 -77.789278)
		(size 0.5588)
		(drill 0.3048)
		(layers "F.Cu" "B.Cu")
		(net "GND")
	)
	(via
		(at 200.881234 -75.746864)
		(size 0.508)
		(drill 0.254)
		(layers "F.Cu" "B.Cu")
		(net "GND")
	)
	(via
		(at 349.673926 -30.927802)
		(size 0.508)
		(drill 0.254)
		(layers "F.Cu" "B.Cu")
		(net "GND")
	)
	(via
		(at 311.0992 -16.7513)
		(size 0.508)
		(drill 0.254)
		(layers "F.Cu" "B.Cu")
		(net "GND")
	)
	(via
		(at 249.9106 -135.4074)
		(size 0.508)
		(drill 0.254)
		(layers "F.Cu" "B.Cu")
		(net "GND")
	)
	(via
		(at 107.027472 -17.7546)
		(size 0.508)
		(drill 0.254)
		(layers "F.Cu" "B.Cu")
		(net "GND")
	)
	(via
		(at 437.621934 12.894056)
		(size 0.5588)
		(drill 0.3048)
		(layers "F.Cu" "B.Cu")
		(net "GND")
	)
	(via
		(at 340.3854 -112.395)
		(size 0.508)
		(drill 0.254)
		(layers "F.Cu" "B.Cu")
		(net "GND")
	)
	(via
		(at 500.410734 -166.714424)
		(size 0.5588)
		(drill 0.3048)
		(layers "F.Cu" "B.Cu")
		(net "GND")
	)
	(via
		(at 305.246786 -58.381138)
		(size 0.508)
		(drill 0.254)
		(layers "F.Cu" "B.Cu")
		(net "GND")
	)
	(via
		(at 295.80332 -102.462584)
		(size 0.508)
		(drill 0.254)
		(layers "F.Cu" "B.Cu")
		(net "GND")
	)
	(via
		(at 276.916134 -92.556584)
		(size 0.508)
		(drill 0.254)
		(layers "F.Cu" "B.Cu")
		(net "GND")
	)
	(via
		(at 215.860884 -3.737356)
		(size 0.508)
		(drill 0.254)
		(layers "F.Cu" "B.Cu")
		(net "GND")
	)
	(via
		(at 198.772018 -3.762756)
		(size 0.508)
		(drill 0.254)
		(layers "F.Cu" "B.Cu")
		(net "GND")
	)
	(via
		(at 171.81322 -21.0947)
		(size 0.508)
		(drill 0.254)
		(layers "F.Cu" "B.Cu")
		(net "GND")
	)
	(via
		(at 489.691934 13.910056)
		(size 0.5588)
		(drill 0.3048)
		(layers "F.Cu" "B.Cu")
		(net "GND")
	)
	(via
		(at 360.101134 -167.857424)
		(size 0.5588)
		(drill 0.3048)
		(layers "F.Cu" "B.Cu")
		(net "GND")
	)
	(via
		(at 4.816856 13.609066)
		(size 0.5588)
		(drill 0.3048)
		(layers "F.Cu" "B.Cu")
		(net "GND")
	)
	(via
		(at 119.357648 -53.923184)
		(size 0.508)
		(drill 0.254)
		(layers "F.Cu" "B.Cu")
		(net "GND")
	)
	(via
		(at 454.131934 10.354056)
		(size 0.5588)
		(drill 0.3048)
		(layers "F.Cu" "B.Cu")
		(net "GND")
	)
	(via
		(at 80.055212 -92.737686)
		(size 0.508)
		(drill 0.254)
		(layers "F.Cu" "B.Cu")
		(net "GND")
	)
	(via
		(at 42.449496 -9.156446)
		(size 0.508)
		(drill 0.254)
		(layers "F.Cu" "B.Cu")
		(net "GND")
	)
	(via
		(at 119.357902 -56.894984)
		(size 0.508)
		(drill 0.254)
		(layers "F.Cu" "B.Cu")
		(net "GND")
	)
	(via
		(at 232.099866 -21.517356)
		(size 0.508)
		(drill 0.254)
		(layers "F.Cu" "B.Cu")
		(net "GND")
	)
	(via
		(at 470.641934 12.894056)
		(size 0.5588)
		(drill 0.3048)
		(layers "F.Cu" "B.Cu")
		(net "GND")
	)
	(via
		(at 73.4314 -21.5138)
		(size 0.508)
		(drill 0.254)
		(layers "F.Cu" "B.Cu")
		(net "GND")
	)
	(via
		(at 71.171562 -17.2466)
		(size 0.508)
		(drill 0.254)
		(layers "F.Cu" "B.Cu")
		(net "GND")
	)
	(via
		(at 299.237146 -55.904384)
		(size 0.508)
		(drill 0.254)
		(layers "F.Cu" "B.Cu")
		(net "GND")
	)
	(via
		(at 280.924254 -61.847984)
		(size 0.508)
		(drill 0.254)
		(layers "F.Cu" "B.Cu")
		(net "GND")
	)
	(via
		(at 211.699856 -155.612846)
		(size 0.508)
		(drill 0.254)
		(layers "F.Cu" "B.Cu")
		(net "GND")
	)
	(via
		(at 359.085134 -9.334246)
		(size 0.508)
		(drill 0.254)
		(layers "F.Cu" "B.Cu")
		(net "GND")
	)
	(via
		(at 72.328786 -74.411586)
		(size 0.508)
		(drill 0.254)
		(layers "F.Cu" "B.Cu")
		(net "GND")
	)
	(via
		(at 146.098768 -7.1374)
		(size 0.508)
		(drill 0.254)
		(layers "F.Cu" "B.Cu")
		(net "GND")
	)
	(via
		(at 288.93516 -71.753984)
		(size 0.508)
		(drill 0.254)
		(layers "F.Cu" "B.Cu")
		(net "GND")
	)
	(via
		(at 81.687924 -162.243262)
		(size 0.5588)
		(drill 0.3048)
		(layers "F.Cu" "B.Cu")
		(net "GND")
	)
	(via
		(at 14.715744 -131.067048)
		(size 0.508)
		(drill 0.254)
		(layers "F.Cu" "B.Cu")
		(net "GND")
	)
	(via
		(at 296.66184 -81.164938)
		(size 0.508)
		(drill 0.254)
		(layers "F.Cu" "B.Cu")
		(net "GND")
	)
	(via
		(at 446.511934 13.910056)
		(size 0.5588)
		(drill 0.3048)
		(layers "F.Cu" "B.Cu")
		(net "GND")
	)
	(via
		(at 222.749872 -11.916156)
		(size 0.508)
		(drill 0.254)
		(layers "F.Cu" "B.Cu")
		(net "GND")
	)
	(via
		(at -2.959608 -113.16462)
		(size 0.5588)
		(drill 0.3048)
		(layers "F.Cu" "B.Cu")
		(net "GND")
	)
	(via
		(at 85.206332 -78.869286)
		(size 0.508)
		(drill 0.254)
		(layers "F.Cu" "B.Cu")
		(net "GND")
	)
	(via
		(at 297.921934 14.926056)
		(size 0.5588)
		(drill 0.3048)
		(layers "F.Cu" "B.Cu")
		(net "GND")
	)
	(via
		(at 61.574934 -167.832024)
		(size 0.5588)
		(drill 0.3048)
		(layers "F.Cu" "B.Cu")
		(net "GND")
	)
	(via
		(at 242.480338 -96.20504)
		(size 0.508)
		(drill 0.254)
		(layers "F.Cu" "B.Cu")
		(net "GND")
	)
	(via
		(at 33.175702 -109.130338)
		(size 0.5588)
		(drill 0.3048)
		(layers "F.Cu" "B.Cu")
		(net "GND")
	)
	(via
		(at 347.66631 -136.508998)
		(size 0.508)
		(drill 0.254)
		(layers "F.Cu" "B.Cu")
		(net "GND")
	)
	(via
		(at 471.196924 -162.243262)
		(size 0.5588)
		(drill 0.3048)
		(layers "F.Cu" "B.Cu")
		(net "GND")
	)
	(via
		(at 90.357198 -88.775286)
		(size 0.508)
		(drill 0.254)
		(layers "F.Cu" "B.Cu")
		(net "GND")
	)
	(via
		(at 39.899336 -134.861046)
		(size 0.508)
		(drill 0.254)
		(layers "F.Cu" "B.Cu")
		(net "GND")
	)
	(via
		(at 467.390734 -166.714424)
		(size 0.5588)
		(drill 0.3048)
		(layers "F.Cu" "B.Cu")
		(net "GND")
	)
	(via
		(at 263.83488 -82.340196)
		(size 0.5588)
		(drill 0.3048)
		(layers "F.Cu" "B.Cu")
		(net "GND")
	)
	(via
		(at 115.451382 -144.462246)
		(size 0.508)
		(drill 0.254)
		(layers "F.Cu" "B.Cu")
		(net "GND")
	)
	(via
		(at 449.610734 -166.714424)
		(size 0.5588)
		(drill 0.3048)
		(layers "F.Cu" "B.Cu")
		(net "GND")
	)
	(via
		(at 116.333524 -162.243262)
		(size 0.5588)
		(drill 0.3048)
		(layers "F.Cu" "B.Cu")
		(net "GND")
	)
	(via
		(at 500.552466 -19.804126)
		(size 0.508)
		(drill 0.254)
		(layers "F.Cu" "B.Cu")
		(net "GND")
	)
	(via
		(at 437.621934 13.910056)
		(size 0.5588)
		(drill 0.3048)
		(layers "F.Cu" "B.Cu")
		(net "GND")
	)
	(via
		(at 299.237146 -69.772784)
		(size 0.508)
		(drill 0.254)
		(layers "F.Cu" "B.Cu")
		(net "GND")
	)
	(via
		(at 390.5377 -106.6546)
		(size 0.508)
		(drill 0.254)
		(layers "F.Cu" "B.Cu")
		(net "GND")
	)
	(via
		(at 132.549392 -140.617956)
		(size 0.508)
		(drill 0.254)
		(layers "F.Cu" "B.Cu")
		(net "GND")
	)
	(via
		(at 458.97165 -124.87402)
		(size 0.508)
		(drill 0.254)
		(layers "F.Cu" "B.Cu")
		(net "GND")
	)
	(via
		(at 211.329524 -162.243262)
		(size 0.5588)
		(drill 0.3048)
		(layers "F.Cu" "B.Cu")
		(net "GND")
	)
	(via
		(at 243.2304 -145.0086)
		(size 0.508)
		(drill 0.254)
		(layers "F.Cu" "B.Cu")
		(net "GND")
	)
	(via
		(at 118.048532 -153.6065)
		(size 0.508)
		(drill 0.254)
		(layers "F.Cu" "B.Cu")
		(net "GND")
	)
	(via
		(at 19.556984 -128.165098)
		(size 0.508)
		(drill 0.254)
		(layers "F.Cu" "B.Cu")
		(net "GND")
	)
	(via
		(at 312.391298 -16.696944)
		(size 0.508)
		(drill 0.254)
		(layers "F.Cu" "B.Cu")
		(net "GND")
	)
	(via
		(at 455.960734 -164.479224)
		(size 0.5588)
		(drill 0.3048)
		(layers "F.Cu" "B.Cu")
		(net "GND")
	)
	(via
		(at 130.84937 -17.208246)
		(size 0.508)
		(drill 0.254)
		(layers "F.Cu" "B.Cu")
		(net "GND")
	)
	(via
		(at 134.236714 -69.772784)
		(size 0.508)
		(drill 0.254)
		(layers "F.Cu" "B.Cu")
		(net "GND")
	)
	(via
		(at 303.044606 -18.6817)
		(size 0.508)
		(drill 0.254)
		(layers "F.Cu" "B.Cu")
		(net "GND")
	)
	(via
		(at 117.925342 -99.986338)
		(size 0.508)
		(drill 0.254)
		(layers "F.Cu" "B.Cu")
		(net "GND")
	)
	(via
		(at 360.097324 -162.268662)
		(size 0.5588)
		(drill 0.3048)
		(layers "F.Cu" "B.Cu")
		(net "GND")
	)
	(via
		(at 350.901 -100.6348)
		(size 0.508)
		(drill 0.254)
		(layers "F.Cu" "B.Cu")
		(net "GND")
	)
	(via
		(at 317.09995 -143.941546)
		(size 0.508)
		(drill 0.254)
		(layers "F.Cu" "B.Cu")
		(net "GND")
	)
	(via
		(at 296.69994 -148.771356)
		(size 0.508)
		(drill 0.254)
		(layers "F.Cu" "B.Cu")
		(net "GND")
	)
	(via
		(at 295.849802 -3.762756)
		(size 0.508)
		(drill 0.254)
		(layers "F.Cu" "B.Cu")
		(net "GND")
	)
	(via
		(at 280.065734 -60.362338)
		(size 0.508)
		(drill 0.254)
		(layers "F.Cu" "B.Cu")
		(net "GND")
	)
	(via
		(at 297.520106 -91.565984)
		(size 0.508)
		(drill 0.254)
		(layers "F.Cu" "B.Cu")
		(net "GND")
	)
	(via
		(at 486.436924 -162.243262)
		(size 0.5588)
		(drill 0.3048)
		(layers "F.Cu" "B.Cu")
		(net "GND")
	)
	(via
		(at 279.699974 -2.314956)
		(size 0.508)
		(drill 0.254)
		(layers "F.Cu" "B.Cu")
		(net "GND")
	)
	(via
		(at 376.865134 -167.857424)
		(size 0.5588)
		(drill 0.3048)
		(layers "F.Cu" "B.Cu")
		(net "GND")
	)
	(via
		(at 258.551934 9.084056)
		(size 0.5588)
		(drill 0.3048)
		(layers "F.Cu" "B.Cu")
		(net "GND")
	)
	(via
		(at 400.791934 14.926056)
		(size 0.5588)
		(drill 0.3048)
		(layers "F.Cu" "B.Cu")
		(net "GND")
	)
	(via
		(at 383.011934 14.926056)
		(size 0.5588)
		(drill 0.3048)
		(layers "F.Cu" "B.Cu")
		(net "GND")
	)
	(via
		(at 317.09995 2.514854)
		(size 0.508)
		(drill 0.254)
		(layers "F.Cu" "B.Cu")
		(net "GND")
	)
	(via
		(at 242.480338 -53.60924)
		(size 0.508)
		(drill 0.254)
		(layers "F.Cu" "B.Cu")
		(net "GND")
	)
	(via
		(at 232.966768 -124.769626)
		(size 0.508)
		(drill 0.254)
		(layers "F.Cu" "B.Cu")
		(net "GND")
	)
	(via
		(at 294.111934 9.084056)
		(size 0.5588)
		(drill 0.3048)
		(layers "F.Cu" "B.Cu")
		(net "GND")
	)
	(via
		(at 388.091934 14.926056)
		(size 0.5588)
		(drill 0.3048)
		(layers "F.Cu" "B.Cu")
		(net "GND")
	)
	(via
		(at 191.133984 -131.057396)
		(size 0.508)
		(drill 0.254)
		(layers "F.Cu" "B.Cu")
		(net "GND")
	)
	(via
		(at 124.049536 -18.744946)
		(size 0.508)
		(drill 0.254)
		(layers "F.Cu" "B.Cu")
		(net "GND")
	)
	(via
		(at 452.150734 -163.361624)
		(size 0.5588)
		(drill 0.3048)
		(layers "F.Cu" "B.Cu")
		(net "GND")
	)
	(via
		(at 5.434838 -112.865916)
		(size 0.508)
		(drill 0.254)
		(layers "F.Cu" "B.Cu")
		(net "GND")
	)
	(via
		(at 280.350214 -94.538038)
		(size 0.508)
		(drill 0.254)
		(layers "F.Cu" "B.Cu")
		(net "GND")
	)
	(via
		(at 350.6978 -31.8643)
		(size 0.508)
		(drill 0.254)
		(layers "F.Cu" "B.Cu")
		(net "GND")
	)
	(via
		(at 210.211924 -162.243262)
		(size 0.5588)
		(drill 0.3048)
		(layers "F.Cu" "B.Cu")
		(net "GND")
	)
	(via
		(at 12.3952 -30.2006)
		(size 0.508)
		(drill 0.254)
		(layers "F.Cu" "B.Cu")
		(net "GND")
	)
	(via
		(at 329.671934 14.926056)
		(size 0.5588)
		(drill 0.3048)
		(layers "F.Cu" "B.Cu")
		(net "GND")
	)
	(via
		(at 450.321934 10.354056)
		(size 0.5588)
		(drill 0.3048)
		(layers "F.Cu" "B.Cu")
		(net "GND")
	)
	(via
		(at 29.164534 -167.832024)
		(size 0.5588)
		(drill 0.3048)
		(layers "F.Cu" "B.Cu")
		(net "GND")
	)
	(via
		(at 345.0844 -97.2312)
		(size 0.508)
		(drill 0.254)
		(layers "F.Cu" "B.Cu")
		(net "GND")
	)
	(via
		(at 367.920524 -162.268662)
		(size 0.5588)
		(drill 0.3048)
		(layers "F.Cu" "B.Cu")
		(net "GND")
	)
	(via
		(at 77.479906 -89.27084)
		(size 0.508)
		(drill 0.254)
		(layers "F.Cu" "B.Cu")
		(net "GND")
	)
	(via
		(at 316.249812 -134.861046)
		(size 0.508)
		(drill 0.254)
		(layers "F.Cu" "B.Cu")
		(net "GND")
	)
	(via
		(at 314.54979 -144.462246)
		(size 0.508)
		(drill 0.254)
		(layers "F.Cu" "B.Cu")
		(net "GND")
	)
	(via
		(at 329.7174 -150.495)
		(size 0.508)
		(drill 0.254)
		(layers "F.Cu" "B.Cu")
		(net "GND")
	)
	(via
		(at 397.261842 -9.452864)
		(size 0.508)
		(drill 0.254)
		(layers "F.Cu" "B.Cu")
		(net "GND")
	)
	(via
		(at 301.736506 -150.749)
		(size 0.508)
		(drill 0.254)
		(layers "F.Cu" "B.Cu")
		(net "GND")
	)
	(via
		(at 166.7002 -79.3242)
		(size 0.508)
		(drill 0.254)
		(layers "F.Cu" "B.Cu")
		(net "GND")
	)
	(via
		(at 305.199796 -13.363956)
		(size 0.508)
		(drill 0.254)
		(layers "F.Cu" "B.Cu")
		(net "GND")
	)
	(via
		(at 420.3192 -3.433572)
		(size 0.508)
		(drill 0.254)
		(layers "F.Cu" "B.Cu")
		(net "GND")
	)
	(via
		(at 238.431832 -129.5654)
		(size 0.508)
		(drill 0.254)
		(layers "F.Cu" "B.Cu")
		(net "GND")
	)
	(via
		(at 154.181048 -118.363238)
		(size 0.508)
		(drill 0.254)
		(layers "F.Cu" "B.Cu")
		(net "GND")
	)
	(via
		(at 146.791934 14.926056)
		(size 0.5588)
		(drill 0.3048)
		(layers "F.Cu" "B.Cu")
		(net "GND")
	)
	(via
		(at 299.151802 -134.861046)
		(size 0.508)
		(drill 0.254)
		(layers "F.Cu" "B.Cu")
		(net "GND")
	)
	(via
		(at 349.5294 -29.4894)
		(size 0.508)
		(drill 0.254)
		(layers "F.Cu" "B.Cu")
		(net "GND")
	)
	(via
		(at 160.02 -32.149288)
		(size 0.508)
		(drill 0.254)
		(layers "F.Cu" "B.Cu")
		(net "GND")
	)
	(via
		(at 457.230734 -165.596824)
		(size 0.5588)
		(drill 0.3048)
		(layers "F.Cu" "B.Cu")
		(net "GND")
	)
	(via
		(at 171.085764 -29.647896)
		(size 0.508)
		(drill 0.254)
		(layers "F.Cu" "B.Cu")
		(net "GND")
	)
	(via
		(at 339.1154 -114.935)
		(size 0.508)
		(drill 0.254)
		(layers "F.Cu" "B.Cu")
		(net "GND")
	)
	(via
		(at 11.65352 -141.68628)
		(size 0.508)
		(drill 0.254)
		(layers "F.Cu" "B.Cu")
		(net "GND")
	)
	(via
		(at 21.061934 14.926056)
		(size 0.5588)
		(drill 0.3048)
		(layers "F.Cu" "B.Cu")
		(net "GND")
	)
	(via
		(at 16.453612 -55.387748)
		(size 0.5588)
		(drill 0.3048)
		(layers "F.Cu" "B.Cu")
		(net "GND")
	)
	(via
		(at 69.593968 -124.750576)
		(size 0.508)
		(drill 0.254)
		(layers "F.Cu" "B.Cu")
		(net "GND")
	)
	(via
		(at 436.906924 -162.243262)
		(size 0.5588)
		(drill 0.3048)
		(layers "F.Cu" "B.Cu")
		(net "GND")
	)
	(via
		(at 121.499376 -13.363956)
		(size 0.508)
		(drill 0.254)
		(layers "F.Cu" "B.Cu")
		(net "GND")
	)
	(via
		(at 206.321914 -69.661278)
		(size 0.5588)
		(drill 0.3048)
		(layers "F.Cu" "B.Cu")
		(net "GND")
	)
	(via
		(at 73.4441 0.5207)
		(size 0.508)
		(drill 0.254)
		(layers "F.Cu" "B.Cu")
		(net "GND")
	)
	(via
		(at 295.849802 -7.607046)
		(size 0.508)
		(drill 0.254)
		(layers "F.Cu" "B.Cu")
		(net "GND")
	)
	(via
		(at 128.690878 -16.696944)
		(size 0.508)
		(drill 0.254)
		(layers "F.Cu" "B.Cu")
		(net "GND")
	)
	(via
		(at 245.914164 -90.26144)
		(size 0.508)
		(drill 0.254)
		(layers "F.Cu" "B.Cu")
		(net "GND")
	)
	(via
		(at 450.128132 -155.18384)
		(size 0.508)
		(drill 0.254)
		(layers "F.Cu" "B.Cu")
		(net "GND")
	)
	(via
		(at 452.150734 -164.479224)
		(size 0.5588)
		(drill 0.3048)
		(layers "F.Cu" "B.Cu")
		(net "GND")
	)
	(via
		(at 261.36727 -63.51524)
		(size 0.508)
		(drill 0.254)
		(layers "F.Cu" "B.Cu")
		(net "GND")
	)
	(via
		(at 86.064852 -84.31784)
		(size 0.508)
		(drill 0.254)
		(layers "F.Cu" "B.Cu")
		(net "GND")
	)
	(via
		(at 240.763298 -53.60924)
		(size 0.508)
		(drill 0.254)
		(layers "F.Cu" "B.Cu")
		(net "GND")
	)
	(via
		(at 284.33776 -150.803356)
		(size 0.508)
		(drill 0.254)
		(layers "F.Cu" "B.Cu")
		(net "GND")
	)
	(via
		(at 76.449428 -136.410446)
		(size 0.508)
		(drill 0.254)
		(layers "F.Cu" "B.Cu")
		(net "GND")
	)
	(via
		(at 74.045826 -59.55284)
		(size 0.508)
		(drill 0.254)
		(layers "F.Cu" "B.Cu")
		(net "GND")
	)
	(via
		(at 58.599324 -154.063446)
		(size 0.508)
		(drill 0.254)
		(layers "F.Cu" "B.Cu")
		(net "GND")
	)
	(via
		(at 147.368768 -2.3622)
		(size 0.508)
		(drill 0.254)
		(layers "F.Cu" "B.Cu")
		(net "GND")
	)
	(via
		(at 119.337328 -150.803356)
		(size 0.508)
		(drill 0.254)
		(layers "F.Cu" "B.Cu")
		(net "GND")
	)
	(via
		(at 202.349862 -136.410446)
		(size 0.508)
		(drill 0.254)
		(layers "F.Cu" "B.Cu")
		(net "GND")
	)
	(via
		(at 59.449462 -2.314956)
		(size 0.508)
		(drill 0.254)
		(layers "F.Cu" "B.Cu")
		(net "GND")
	)
	(via
		(at 35.6108 -51.9176)
		(size 0.5588)
		(drill 0.3048)
		(layers "F.Cu" "B.Cu")
		(net "GND")
	)
	(via
		(at 227.799138 -26.73731)
		(size 0.508)
		(drill 0.254)
		(layers "F.Cu" "B.Cu")
		(net "GND")
	)
	(via
		(at 124.049536 -125.955298)
		(size 0.508)
		(drill 0.254)
		(layers "F.Cu" "B.Cu")
		(net "GND")
	)
	(via
		(at 50.860452 -140.592556)
		(size 0.508)
		(drill 0.254)
		(layers "F.Cu" "B.Cu")
		(net "GND")
	)
	(via
		(at 347.451934 14.926056)
		(size 0.5588)
		(drill 0.3048)
		(layers "F.Cu" "B.Cu")
		(net "GND")
	)
	(via
		(at 399.12925 -119.528844)
		(size 0.508)
		(drill 0.254)
		(layers "F.Cu" "B.Cu")
		(net "GND")
	)
	(via
		(at 67.101466 -86.29904)
		(size 0.508)
		(drill 0.254)
		(layers "F.Cu" "B.Cu")
		(net "GND")
	)
	(via
		(at 445.276986 -8.9662)
		(size 0.508)
		(drill 0.254)
		(layers "F.Cu" "B.Cu")
		(net "GND")
	)
	(via
		(at 211.333334 -167.832024)
		(size 0.5588)
		(drill 0.3048)
		(layers "F.Cu" "B.Cu")
		(net "GND")
	)
	(via
		(at 280.141934 9.084056)
		(size 0.5588)
		(drill 0.3048)
		(layers "F.Cu" "B.Cu")
		(net "GND")
	)
	(via
		(at 138.529314 -93.052138)
		(size 0.508)
		(drill 0.254)
		(layers "F.Cu" "B.Cu")
		(net "GND")
	)
	(via
		(at 407.716736 -15.505176)
		(size 0.508)
		(drill 0.254)
		(layers "F.Cu" "B.Cu")
		(net "GND")
	)
	(via
		(at 195.549774 -7.086346)
		(size 0.508)
		(drill 0.254)
		(layers "F.Cu" "B.Cu")
		(net "GND")
	)
	(via
		(at 499.917466 -20.439126)
		(size 0.508)
		(drill 0.254)
		(layers "F.Cu" "B.Cu")
		(net "GND")
	)
	(via
		(at 280.451814 -17.208246)
		(size 0.508)
		(drill 0.254)
		(layers "F.Cu" "B.Cu")
		(net "GND")
	)
	(via
		(at 344.56624 -101.32314)
		(size 0.508)
		(drill 0.254)
		(layers "F.Cu" "B.Cu")
		(net "GND")
	)
	(via
		(at 121.359168 -77.202538)
		(size 0.508)
		(drill 0.254)
		(layers "F.Cu" "B.Cu")
		(net "GND")
	)
	(via
		(at 349.4786 -154.090624)
		(size 0.508)
		(drill 0.254)
		(layers "F.Cu" "B.Cu")
		(net "GND")
	)
	(via
		(at 169.147744 -92.499434)
		(size 0.508)
		(drill 0.254)
		(layers "F.Cu" "B.Cu")
		(net "GND")
	)
	(via
		(at 278.232108 -82.271616)
		(size 0.5588)
		(drill 0.3048)
		(layers "F.Cu" "B.Cu")
		(net "GND")
	)
	(via
		(at 39.47795 -60.183522)
		(size 0.5588)
		(drill 0.3048)
		(layers "F.Cu" "B.Cu")
		(net "GND")
	)
	(via
		(at 415.320734 -164.479224)
		(size 0.5588)
		(drill 0.3048)
		(layers "F.Cu" "B.Cu")
		(net "GND")
	)
	(via
		(at 273.197828 -63.334138)
		(size 0.508)
		(drill 0.254)
		(layers "F.Cu" "B.Cu")
		(net "GND")
	)
	(via
		(at 236.171994 1.9558)
		(size 0.508)
		(drill 0.254)
		(layers "F.Cu" "B.Cu")
		(net "GND")
	)
	(via
		(at 345.497404 -150.123398)
		(size 0.508)
		(drill 0.254)
		(layers "F.Cu" "B.Cu")
		(net "GND")
	)
	(via
		(at 278.727408 -154.23388)
		(size 0.508)
		(drill 0.254)
		(layers "F.Cu" "B.Cu")
		(net "GND")
	)
	(via
		(at 365.6076 -122.8344)
		(size 0.508)
		(drill 0.254)
		(layers "F.Cu" "B.Cu")
		(net "GND")
	)
	(via
		(at 33.771586 -13.363956)
		(size 0.508)
		(drill 0.254)
		(layers "F.Cu" "B.Cu")
		(net "GND")
	)
	(via
		(at 303.038002 -150.803356)
		(size 0.508)
		(drill 0.254)
		(layers "F.Cu" "B.Cu")
		(net "GND")
	)
	(via
		(at 7.7216 -21.2852)
		(size 0.508)
		(drill 0.254)
		(layers "F.Cu" "B.Cu")
		(net "GND")
	)
	(via
		(at 123.199398 -13.363956)
		(size 0.508)
		(drill 0.254)
		(layers "F.Cu" "B.Cu")
		(net "GND")
	)
	(via
		(at 239.904778 -58.06694)
		(size 0.508)
		(drill 0.254)
		(layers "F.Cu" "B.Cu")
		(net "GND")
	)
	(via
		(at 64.927734 -167.832024)
		(size 0.5588)
		(drill 0.3048)
		(layers "F.Cu" "B.Cu")
		(net "GND")
	)
	(via
		(at 127.368808 -90.575384)
		(size 0.508)
		(drill 0.254)
		(layers "F.Cu" "B.Cu")
		(net "GND")
	)
	(via
		(at 35.499802 -58.8518)
		(size 0.508)
		(drill 0.254)
		(layers "F.Cu" "B.Cu")
		(net "GND")
	)
	(via
		(at 101.808534 -167.832024)
		(size 0.5588)
		(drill 0.3048)
		(layers "F.Cu" "B.Cu")
		(net "GND")
	)
	(via
		(at 250.206764 -83.822286)
		(size 0.508)
		(drill 0.254)
		(layers "F.Cu" "B.Cu")
		(net "GND")
	)
	(via
		(at 438.5564 -131.826)
		(size 0.508)
		(drill 0.254)
		(layers "F.Cu" "B.Cu")
		(net "GND")
	)
	(via
		(at 367.0554 -109.601)
		(size 0.508)
		(drill 0.254)
		(layers "F.Cu" "B.Cu")
		(net "GND")
	)
	(via
		(at 41.105582 -92.572078)
		(size 0.5588)
		(drill 0.3048)
		(layers "F.Cu" "B.Cu")
		(net "GND")
	)
	(via
		(at 124.801376 1.994154)
		(size 0.508)
		(drill 0.254)
		(layers "F.Cu" "B.Cu")
		(net "GND")
	)
	(via
		(at 474.451934 11.624056)
		(size 0.5588)
		(drill 0.3048)
		(layers "F.Cu" "B.Cu")
		(net "GND")
	)
	(via
		(at 123.650248 -61.352938)
		(size 0.508)
		(drill 0.254)
		(layers "F.Cu" "B.Cu")
		(net "GND")
	)
	(via
		(at 88.640412 -63.019686)
		(size 0.508)
		(drill 0.254)
		(layers "F.Cu" "B.Cu")
		(net "GND")
	)
	(via
		(at 438.088532 -9.8044)
		(size 0.508)
		(drill 0.254)
		(layers "F.Cu" "B.Cu")
		(net "GND")
	)
	(via
		(at 140.199364 -140.617956)
		(size 0.508)
		(drill 0.254)
		(layers "F.Cu" "B.Cu")
		(net "GND")
	)
	(via
		(at 394.996924 -162.243262)
		(size 0.5588)
		(drill 0.3048)
		(layers "F.Cu" "B.Cu")
		(net "GND")
	)
	(via
		(at 71.171562 -131.016756)
		(size 0.508)
		(drill 0.254)
		(layers "F.Cu" "B.Cu")
		(net "GND")
	)
	(via
		(at 2.6924 -6.3754)
		(size 0.508)
		(drill 0.254)
		(layers "F.Cu" "B.Cu")
		(net "GND")
	)
	(via
		(at 376.428 -108.35513)
		(size 0.508)
		(drill 0.254)
		(layers "F.Cu" "B.Cu")
		(net "GND")
	)
	(via
		(at 363.453934 -167.857424)
		(size 0.5588)
		(drill 0.3048)
		(layers "F.Cu" "B.Cu")
		(net "GND")
	)
	(via
		(at 113.951258 -17.29486)
		(size 0.508)
		(drill 0.254)
		(layers "F.Cu" "B.Cu")
		(net "GND")
	)
	(via
		(at 385.7371 -106.6546)
		(size 0.508)
		(drill 0.254)
		(layers "F.Cu" "B.Cu")
		(net "GND")
	)
	(via
		(at 415.320734 -163.361624)
		(size 0.5588)
		(drill 0.3048)
		(layers "F.Cu" "B.Cu")
		(net "GND")
	)
	(via
		(at 152.949402 -4.317746)
		(size 0.508)
		(drill 0.254)
		(layers "F.Cu" "B.Cu")
		(net "GND")
	)
	(via
		(at 96.086676 -75.159616)
		(size 0.5588)
		(drill 0.3048)
		(layers "F.Cu" "B.Cu")
		(net "GND")
	)
	(via
		(at 281.361896 -21.517356)
		(size 0.508)
		(drill 0.254)
		(layers "F.Cu" "B.Cu")
		(net "GND")
	)
	(via
		(at 78.338172 -85.803486)
		(size 0.508)
		(drill 0.254)
		(layers "F.Cu" "B.Cu")
		(net "GND")
	)
	(via
		(at 248.489724 -92.737686)
		(size 0.508)
		(drill 0.254)
		(layers "F.Cu" "B.Cu")
		(net "GND")
	)
	(via
		(at 346.564204 -149.005798)
		(size 0.508)
		(drill 0.254)
		(layers "F.Cu" "B.Cu")
		(net "GND")
	)
	(via
		(at 244.197124 -96.20504)
		(size 0.508)
		(drill 0.254)
		(layers "F.Cu" "B.Cu")
		(net "GND")
	)
	(via
		(at 81.772252 -56.085486)
		(size 0.508)
		(drill 0.254)
		(layers "F.Cu" "B.Cu")
		(net "GND")
	)
	(via
		(at 66.041524 -162.243262)
		(size 0.5588)
		(drill 0.3048)
		(layers "F.Cu" "B.Cu")
		(net "GND")
	)
	(via
		(at 280.460958 -150.193756)
		(size 0.508)
		(drill 0.254)
		(layers "F.Cu" "B.Cu")
		(net "GND")
	)
	(via
		(at 471.6018 -27.982418)
		(size 0.508)
		(drill 0.254)
		(layers "F.Cu" "B.Cu")
		(net "GND")
	)
	(via
		(at 210.39455 -155.5369)
		(size 0.508)
		(drill 0.254)
		(layers "F.Cu" "B.Cu")
		(net "GND")
	)
	(via
		(at 388.23265 -121.245884)
		(size 0.508)
		(drill 0.254)
		(layers "F.Cu" "B.Cu")
		(net "GND")
	)
	(via
		(at 434.370734 -164.479224)
		(size 0.5588)
		(drill 0.3048)
		(layers "F.Cu" "B.Cu")
		(net "GND")
	)
	(via
		(at 128.227328 -84.136738)
		(size 0.508)
		(drill 0.254)
		(layers "F.Cu" "B.Cu")
		(net "GND")
	)
	(via
		(at 48.163734 -167.832024)
		(size 0.5588)
		(drill 0.3048)
		(layers "F.Cu" "B.Cu")
		(net "GND")
	)
	(via
		(at 306.899818 -150.219156)
		(size 0.508)
		(drill 0.254)
		(layers "F.Cu" "B.Cu")
		(net "GND")
	)
	(via
		(at 31.406592 -107.960414)
		(size 0.5588)
		(drill 0.3048)
		(layers "F.Cu" "B.Cu")
		(net "GND")
	)
	(via
		(at 419.126924 -162.243262)
		(size 0.5588)
		(drill 0.3048)
		(layers "F.Cu" "B.Cu")
		(net "GND")
	)
	(via
		(at 288.65068 -62.343538)
		(size 0.508)
		(drill 0.254)
		(layers "F.Cu" "B.Cu")
		(net "GND")
	)
	(via
		(at 182.351934 14.926056)
		(size 0.5588)
		(drill 0.3048)
		(layers "F.Cu" "B.Cu")
		(net "GND")
	)
	(via
		(at 450.469 -119.9134)
		(size 0.508)
		(drill 0.254)
		(layers "F.Cu" "B.Cu")
		(net "GND")
	)
	(via
		(at 459.427326 -45.611796)
		(size 0.508)
		(drill 0.254)
		(layers "F.Cu" "B.Cu")
		(net "GND")
	)
	(via
		(at 34.74212 -136.397746)
		(size 0.508)
		(drill 0.254)
		(layers "F.Cu" "B.Cu")
		(net "GND")
	)
	(via
		(at 347.080586 -139.849606)
		(size 0.508)
		(drill 0.254)
		(layers "F.Cu" "B.Cu")
		(net "GND")
	)
	(via
		(at 210.39455 -9.0805)
		(size 0.508)
		(drill 0.254)
		(layers "F.Cu" "B.Cu")
		(net "GND")
	)
	(via
		(at 62.798706 -153.6065)
		(size 0.508)
		(drill 0.254)
		(layers "F.Cu" "B.Cu")
		(net "GND")
	)
	(via
		(at 145.12163 -131.016756)
		(size 0.508)
		(drill 0.254)
		(layers "F.Cu" "B.Cu")
		(net "GND")
	)
	(via
		(at 71.171562 1.9558)
		(size 0.508)
		(drill 0.254)
		(layers "F.Cu" "B.Cu")
		(net "GND")
	)
	(via
		(at 223.599756 1.994154)
		(size 0.508)
		(drill 0.254)
		(layers "F.Cu" "B.Cu")
		(net "GND")
	)
	(via
		(at 11.2522 -31.9024)
		(size 0.508)
		(drill 0.254)
		(layers "F.Cu" "B.Cu")
		(net "GND")
	)
	(via
		(at 367.945162 -79.094838)
		(size 0.4572)
		(drill 0.2032)
		(layers "F.Cu" "B.Cu")
		(net "GND")
	)
	(via
		(at 282.07208 -154.1018)
		(size 0.508)
		(drill 0.254)
		(layers "F.Cu" "B.Cu")
		(net "GND")
	)
	(via
		(at 446.511934 10.354056)
		(size 0.5588)
		(drill 0.3048)
		(layers "F.Cu" "B.Cu")
		(net "GND")
	)
	(via
		(at 44.098718 -16.7513)
		(size 0.508)
		(drill 0.254)
		(layers "F.Cu" "B.Cu")
		(net "GND")
	)
	(via
		(at 110.198916 -95.528384)
		(size 0.508)
		(drill 0.254)
		(layers "F.Cu" "B.Cu")
		(net "GND")
	)
	(via
		(at 231.249728 -17.208246)
		(size 0.508)
		(drill 0.254)
		(layers "F.Cu" "B.Cu")
		(net "GND")
	)
	(via
		(at 255.8034 -2.975356)
		(size 0.508)
		(drill 0.254)
		(layers "F.Cu" "B.Cu")
		(net "GND")
	)
	(via
		(at 74.904346 -51.132486)
		(size 0.508)
		(drill 0.254)
		(layers "F.Cu" "B.Cu")
		(net "GND")
	)
	(via
		(at 345.9734 -144.5514)
		(size 0.508)
		(drill 0.254)
		(layers "F.Cu" "B.Cu")
		(net "GND")
	)
	(via
		(at 199.992234 -54.664864)
		(size 0.508)
		(drill 0.254)
		(layers "F.Cu" "B.Cu")
		(net "GND")
	)
	(via
		(at 275.773134 -56.894984)
		(size 0.508)
		(drill 0.254)
		(layers "F.Cu" "B.Cu")
		(net "GND")
	)
	(via
		(at 130.802888 -76.706984)
		(size 0.508)
		(drill 0.254)
		(layers "F.Cu" "B.Cu")
		(net "GND")
	)
	(via
		(at 249.331734 -167.832024)
		(size 0.5588)
		(drill 0.3048)
		(layers "F.Cu" "B.Cu")
		(net "GND")
	)
	(via
		(at 252.782324 -87.28964)
		(size 0.508)
		(drill 0.254)
		(layers "F.Cu" "B.Cu")
		(net "GND")
	)
	(via
		(at 214.249762 -7.607046)
		(size 0.508)
		(drill 0.254)
		(layers "F.Cu" "B.Cu")
		(net "GND")
	)
	(via
		(at 65.399412 0.444754)
		(size 0.508)
		(drill 0.254)
		(layers "F.Cu" "B.Cu")
		(net "GND")
	)
	(via
		(at 23.84298 -50.579274)
		(size 0.5588)
		(drill 0.3048)
		(layers "F.Cu" "B.Cu")
		(net "GND")
	)
	(via
		(at 81.618836 -135.4074)
		(size 0.508)
		(drill 0.254)
		(layers "F.Cu" "B.Cu")
		(net "GND")
	)
	(via
		(at 80.055212 -95.709486)
		(size 0.508)
		(drill 0.254)
		(layers "F.Cu" "B.Cu")
		(net "GND")
	)
	(via
		(at 86.064852 -91.25204)
		(size 0.508)
		(drill 0.254)
		(layers "F.Cu" "B.Cu")
		(net "GND")
	)
	(via
		(at 235.46181 -139.170156)
		(size 0.508)
		(drill 0.254)
		(layers "F.Cu" "B.Cu")
		(net "GND")
	)
	(via
		(at 393.171934 9.084056)
		(size 0.5588)
		(drill 0.3048)
		(layers "F.Cu" "B.Cu")
		(net "GND")
	)
	(via
		(at 129.944368 -85.127338)
		(size 0.508)
		(drill 0.254)
		(layers "F.Cu" "B.Cu")
		(net "GND")
	)
	(via
		(at 82.021934 9.084056)
		(size 0.5588)
		(drill 0.3048)
		(layers "F.Cu" "B.Cu")
		(net "GND")
	)
	(via
		(at 295.80332 -74.725784)
		(size 0.508)
		(drill 0.254)
		(layers "F.Cu" "B.Cu")
		(net "GND")
	)
	(via
		(at 496.041934 14.926056)
		(size 0.5588)
		(drill 0.3048)
		(layers "F.Cu" "B.Cu")
		(net "GND")
	)
	(via
		(at 157.503368 -22.524212)
		(size 0.508)
		(drill 0.254)
		(layers "F.Cu" "B.Cu")
		(net "GND")
	)
	(via
		(at 260.503924 -162.243262)
		(size 0.5588)
		(drill 0.3048)
		(layers "F.Cu" "B.Cu")
		(net "GND")
	)
	(via
		(at 250.206764 -71.935086)
		(size 0.508)
		(drill 0.254)
		(layers "F.Cu" "B.Cu")
		(net "GND")
	)
	(via
		(at 447.8274 -5.461)
		(size 0.508)
		(drill 0.254)
		(layers "F.Cu" "B.Cu")
		(net "GND")
	)
	(via
		(at 129.999486 -155.612846)
		(size 0.508)
		(drill 0.254)
		(layers "F.Cu" "B.Cu")
		(net "GND")
	)
	(via
		(at 357.77932 -78.900528)
		(size 0.508)
		(drill 0.254)
		(layers "F.Cu" "B.Cu")
		(net "GND")
	)
	(via
		(at 292.386512 -150.749)
		(size 0.508)
		(drill 0.254)
		(layers "F.Cu" "B.Cu")
		(net "GND")
	)
	(via
		(at 213.399878 -148.771356)
		(size 0.508)
		(drill 0.254)
		(layers "F.Cu" "B.Cu")
		(net "GND")
	)
	(via
		(at 199.9488 -69.0626)
		(size 0.5588)
		(drill 0.3048)
		(layers "F.Cu" "B.Cu")
		(net "GND")
	)
	(via
		(at 219.73794 -13.948156)
		(size 0.508)
		(drill 0.254)
		(layers "F.Cu" "B.Cu")
		(net "GND")
	)
	(via
		(at 61.821568 -27.821636)
		(size 0.508)
		(drill 0.254)
		(layers "F.Cu" "B.Cu")
		(net "GND")
	)
	(via
		(at 359.41 -101.346)
		(size 0.508)
		(drill 0.254)
		(layers "F.Cu" "B.Cu")
		(net "GND")
	)
	(via
		(at 299.151802 1.994154)
		(size 0.508)
		(drill 0.254)
		(layers "F.Cu" "B.Cu")
		(net "GND")
	)
	(via
		(at 208.122012 -134.8994)
		(size 0.508)
		(drill 0.254)
		(layers "F.Cu" "B.Cu")
		(net "GND")
	)
	(via
		(at 114.491262 -99.986338)
		(size 0.508)
		(drill 0.254)
		(layers "F.Cu" "B.Cu")
		(net "GND")
	)
	(via
		(at 132.519674 -90.575384)
		(size 0.508)
		(drill 0.254)
		(layers "F.Cu" "B.Cu")
		(net "GND")
	)
	(via
		(at 42.9641 -89.3064)
		(size 0.5588)
		(drill 0.3048)
		(layers "F.Cu" "B.Cu")
		(net "GND")
	)
	(via
		(at 85.831934 14.926056)
		(size 0.5588)
		(drill 0.3048)
		(layers "F.Cu" "B.Cu")
		(net "GND")
	)
	(via
		(at 493.501934 12.894056)
		(size 0.5588)
		(drill 0.3048)
		(layers "F.Cu" "B.Cu")
		(net "GND")
	)
	(via
		(at 132.519674 -80.669384)
		(size 0.508)
		(drill 0.254)
		(layers "F.Cu" "B.Cu")
		(net "GND")
	)
	(via
		(at 447.929 -152.1714)
		(size 0.508)
		(drill 0.254)
		(layers "F.Cu" "B.Cu")
		(net "GND")
	)
	(via
		(at 237.329218 -94.223586)
		(size 0.508)
		(drill 0.254)
		(layers "F.Cu" "B.Cu")
		(net "GND")
	)
	(via
		(at 78.274164 -130.249676)
		(size 0.508)
		(drill 0.254)
		(layers "F.Cu" "B.Cu")
		(net "GND")
	)
	(via
		(at 126.421642 -125.347476)
		(size 0.508)
		(drill 0.254)
		(layers "F.Cu" "B.Cu")
		(net "GND")
	)
	(via
		(at 447.74993 -58.954924)
		(size 0.508)
		(drill 0.254)
		(layers "F.Cu" "B.Cu")
		(net "GND")
	)
	(via
		(at 471.084402 -40.194992)
		(size 0.508)
		(drill 0.254)
		(layers "F.Cu" "B.Cu")
		(net "GND")
	)
	(via
		(at 294.08628 -98.500184)
		(size 0.508)
		(drill 0.254)
		(layers "F.Cu" "B.Cu")
		(net "GND")
	)
	(via
		(at 469.930734 -166.714424)
		(size 0.5588)
		(drill 0.3048)
		(layers "F.Cu" "B.Cu")
		(net "GND")
	)
	(via
		(at 247.412764 -101.577394)
		(size 0.508)
		(drill 0.254)
		(layers "F.Cu" "B.Cu")
		(net "GND")
	)
	(via
		(at 39.222934 -167.832024)
		(size 0.5588)
		(drill 0.3048)
		(layers "F.Cu" "B.Cu")
		(net "GND")
	)
	(via
		(at 345.379294 -8.843518)
		(size 0.508)
		(drill 0.254)
		(layers "F.Cu" "B.Cu")
		(net "GND")
	)
	(via
		(at 211.699856 -139.170156)
		(size 0.508)
		(drill 0.254)
		(layers "F.Cu" "B.Cu")
		(net "GND")
	)
	(via
		(at 406.3746 -123.7234)
		(size 0.508)
		(drill 0.254)
		(layers "F.Cu" "B.Cu")
		(net "GND")
	)
	(via
		(at 484.599996 -113.8936)
		(size 0.508)
		(drill 0.254)
		(layers "F.Cu" "B.Cu")
		(net "GND")
	)
	(via
		(at 468.101934 12.894056)
		(size 0.5588)
		(drill 0.3048)
		(layers "F.Cu" "B.Cu")
		(net "GND")
	)
	(via
		(at 126.510288 -89.089738)
		(size 0.508)
		(drill 0.254)
		(layers "F.Cu" "B.Cu")
		(net "GND")
	)
	(via
		(at 257.07467 -98.681286)
		(size 0.508)
		(drill 0.254)
		(layers "F.Cu" "B.Cu")
		(net "GND")
	)
	(via
		(at 55.983124 -162.243262)
		(size 0.5588)
		(drill 0.3048)
		(layers "F.Cu" "B.Cu")
		(net "GND")
	)
	(via
		(at 78.211934 14.926056)
		(size 0.5588)
		(drill 0.3048)
		(layers "F.Cu" "B.Cu")
		(net "GND")
	)
	(via
		(at 247.096534 -167.832024)
		(size 0.5588)
		(drill 0.3048)
		(layers "F.Cu" "B.Cu")
		(net "GND")
	)
	(via
		(at 291.422074 -13.363956)
		(size 0.508)
		(drill 0.254)
		(layers "F.Cu" "B.Cu")
		(net "GND")
	)
	(via
		(at 147.390866 -16.696944)
		(size 0.508)
		(drill 0.254)
		(layers "F.Cu" "B.Cu")
		(net "GND")
	)
	(via
		(at 259.258308 -70.841616)
		(size 0.5588)
		(drill 0.3048)
		(layers "F.Cu" "B.Cu")
		(net "GND")
	)
	(via
		(at 80.913732 -55.59044)
		(size 0.508)
		(drill 0.254)
		(layers "F.Cu" "B.Cu")
		(net "GND")
	)
	(via
		(at 353.65436 -78.89875)
		(size 0.508)
		(drill 0.254)
		(layers "F.Cu" "B.Cu")
		(net "GND")
	)
	(via
		(at 186.048396 -85.182202)
		(size 0.508)
		(drill 0.254)
		(layers "F.Cu" "B.Cu")
		(net "GND")
	)
	(via
		(at 119.357902 -62.838584)
		(size 0.508)
		(drill 0.254)
		(layers "F.Cu" "B.Cu")
		(net "GND")
	)
	(via
		(at 8.482584 -141.647672)
		(size 0.508)
		(drill 0.254)
		(layers "F.Cu" "B.Cu")
		(net "GND")
	)
	(via
		(at 471.911934 11.624056)
		(size 0.5588)
		(drill 0.3048)
		(layers "F.Cu" "B.Cu")
		(net "GND")
	)
	(via
		(at 67.099434 -136.410446)
		(size 0.508)
		(drill 0.254)
		(layers "F.Cu" "B.Cu")
		(net "GND")
	)
	(via
		(at 222.505524 -162.243262)
		(size 0.5588)
		(drill 0.3048)
		(layers "F.Cu" "B.Cu")
		(net "GND")
	)
	(via
		(at 291.51072 -90.080338)
		(size 0.508)
		(drill 0.254)
		(layers "F.Cu" "B.Cu")
		(net "GND")
	)
	(via
		(at 182.30088 -5.912866)
		(size 0.508)
		(drill 0.254)
		(layers "F.Cu" "B.Cu")
		(net "GND")
	)
	(via
		(at 280.350214 -89.584784)
		(size 0.508)
		(drill 0.254)
		(layers "F.Cu" "B.Cu")
		(net "GND")
	)
	(via
		(at 168.381934 14.926056)
		(size 0.5588)
		(drill 0.3048)
		(layers "F.Cu" "B.Cu")
		(net "GND")
	)
	(via
		(at 30.549342 -131.5466)
		(size 0.508)
		(drill 0.254)
		(layers "F.Cu" "B.Cu")
		(net "GND")
	)
	(via
		(at 489.1024 -61.6458)
		(size 0.508)
		(drill 0.254)
		(layers "F.Cu" "B.Cu")
		(net "GND")
	)
	(via
		(at 239.046258 -89.27084)
		(size 0.508)
		(drill 0.254)
		(layers "F.Cu" "B.Cu")
		(net "GND")
	)
	(via
		(at 207.515714 -86.349078)
		(size 0.5588)
		(drill 0.3048)
		(layers "F.Cu" "B.Cu")
		(net "GND")
	)
	(via
		(at 300.772068 -144.5006)
		(size 0.508)
		(drill 0.254)
		(layers "F.Cu" "B.Cu")
		(net "GND")
	)
	(via
		(at 277.601934 9.084056)
		(size 0.5588)
		(drill 0.3048)
		(layers "F.Cu" "B.Cu")
		(net "GND")
	)
	(via
		(at 27.52979 -21.409914)
		(size 0.508)
		(drill 0.254)
		(layers "F.Cu" "B.Cu")
		(net "GND")
	)
	(via
		(at 476.4278 -32.3342)
		(size 0.508)
		(drill 0.254)
		(layers "F.Cu" "B.Cu")
		(net "GND")
	)
	(via
		(at 450.321934 13.910056)
		(size 0.5588)
		(drill 0.3048)
		(layers "F.Cu" "B.Cu")
		(net "GND")
	)
	(via
		(at 237.149132 -16.7513)
		(size 0.508)
		(drill 0.254)
		(layers "F.Cu" "B.Cu")
		(net "GND")
	)
	(via
		(at 192.052956 -80.317086)
		(size 0.508)
		(drill 0.254)
		(layers "F.Cu" "B.Cu")
		(net "GND")
	)
	(via
		(at 464.850734 -166.714424)
		(size 0.5588)
		(drill 0.3048)
		(layers "F.Cu" "B.Cu")
		(net "GND")
	)
	(via
		(at 51.79949 -155.612846)
		(size 0.508)
		(drill 0.254)
		(layers "F.Cu" "B.Cu")
		(net "GND")
	)
	(via
		(at 81.772252 -66.982086)
		(size 0.508)
		(drill 0.254)
		(layers "F.Cu" "B.Cu")
		(net "GND")
	)
	(via
		(at 243.193824 -149.436836)
		(size 0.508)
		(drill 0.254)
		(layers "F.Cu" "B.Cu")
		(net "GND")
	)
	(via
		(at 258.184142 -148.771356)
		(size 0.508)
		(drill 0.254)
		(layers "F.Cu" "B.Cu")
		(net "GND")
	)
	(via
		(at 317.949834 -131.571746)
		(size 0.508)
		(drill 0.254)
		(layers "F.Cu" "B.Cu")
		(net "GND")
	)
	(via
		(at 350.641666 -137.189718)
		(size 0.508)
		(drill 0.254)
		(layers "F.Cu" "B.Cu")
		(net "GND")
	)
	(via
		(at 41.510458 -130.991356)
		(size 0.508)
		(drill 0.254)
		(layers "F.Cu" "B.Cu")
		(net "GND")
	)
	(via
		(at 398.63395 -120.387364)
		(size 0.508)
		(drill 0.254)
		(layers "F.Cu" "B.Cu")
		(net "GND")
	)
	(via
		(at 110.111032 -3.3528)
		(size 0.508)
		(drill 0.254)
		(layers "F.Cu" "B.Cu")
		(net "GND")
	)
	(via
		(at 302.671226 -75.716384)
		(size 0.508)
		(drill 0.254)
		(layers "F.Cu" "B.Cu")
		(net "GND")
	)
	(via
		(at 395.780006 -27.195018)
		(size 0.508)
		(drill 0.254)
		(layers "F.Cu" "B.Cu")
		(net "GND")
	)
	(via
		(at 360.505502 5.428996)
		(size 0.5588)
		(drill 0.3048)
		(layers "F.Cu" "B.Cu")
		(net "GND")
	)
	(via
		(at 149.549358 -140.617956)
		(size 0.508)
		(drill 0.254)
		(layers "F.Cu" "B.Cu")
		(net "GND")
	)
	(via
		(at 306.899818 -134.861046)
		(size 0.508)
		(drill 0.254)
		(layers "F.Cu" "B.Cu")
		(net "GND")
	)
	(via
		(at 42.088054 -84.57311)
		(size 0.5588)
		(drill 0.3048)
		(layers "F.Cu" "B.Cu")
		(net "GND")
	)
	(via
		(at 120.121934 9.084056)
		(size 0.5588)
		(drill 0.3048)
		(layers "F.Cu" "B.Cu")
		(net "GND")
	)
	(via
		(at 356.744524 -162.268662)
		(size 0.5588)
		(drill 0.3048)
		(layers "F.Cu" "B.Cu")
		(net "GND")
	)
	(via
		(at 57.74944 -129.568956)
		(size 0.508)
		(drill 0.254)
		(layers "F.Cu" "B.Cu")
		(net "GND")
	)
	(via
		(at 496.6716 -134.747)
		(size 0.508)
		(drill 0.254)
		(layers "F.Cu" "B.Cu")
		(net "GND")
	)
	(via
		(at 464.291934 11.624056)
		(size 0.5588)
		(drill 0.3048)
		(layers "F.Cu" "B.Cu")
		(net "GND")
	)
	(via
		(at 288.19983 -22.965156)
		(size 0.508)
		(drill 0.254)
		(layers "F.Cu" "B.Cu")
		(net "GND")
	)
	(via
		(at 371.581934 9.084056)
		(size 0.5588)
		(drill 0.3048)
		(layers "F.Cu" "B.Cu")
		(net "GND")
	)
	(via
		(at 48.399446 -139.170156)
		(size 0.508)
		(drill 0.254)
		(layers "F.Cu" "B.Cu")
		(net "GND")
	)
	(via
		(at 204.049884 -146.011646)
		(size 0.508)
		(drill 0.254)
		(layers "F.Cu" "B.Cu")
		(net "GND")
	)
	(via
		(at 241.504724 -162.243262)
		(size 0.5588)
		(drill 0.3048)
		(layers "F.Cu" "B.Cu")
		(net "GND")
	)
	(via
		(at 351.029524 -162.243262)
		(size 0.5588)
		(drill 0.3048)
		(layers "F.Cu" "B.Cu")
		(net "GND")
	)
	(via
		(at -5.2832 -8.7376)
		(size 0.508)
		(drill 0.254)
		(layers "F.Cu" "B.Cu")
		(net "GND")
	)
	(via
		(at 239.749838 -146.011646)
		(size 0.508)
		(drill 0.254)
		(layers "F.Cu" "B.Cu")
		(net "GND")
	)
	(via
		(at -4.418838 -143.317468)
		(size 0.508)
		(drill 0.254)
		(layers "F.Cu" "B.Cu")
		(net "GND")
	)
	(via
		(at 163.7792 -74.2061)
		(size 0.508)
		(drill 0.254)
		(layers "F.Cu" "B.Cu")
		(net "GND")
	)
	(via
		(at 266.539218 -75.148186)
		(size 0.5588)
		(drill 0.3048)
		(layers "F.Cu" "B.Cu")
		(net "GND")
	)
	(via
		(at 181.9402 -144.6276)
		(size 0.508)
		(drill 0.254)
		(layers "F.Cu" "B.Cu")
		(net "GND")
	)
	(via
		(at 389.361934 9.084056)
		(size 0.5588)
		(drill 0.3048)
		(layers "F.Cu" "B.Cu")
		(net "GND")
	)
	(via
		(at 1.224534 -166.714424)
		(size 0.5588)
		(drill 0.3048)
		(layers "F.Cu" "B.Cu")
		(net "GND")
	)
	(via
		(at 317.09995 0.444754)
		(size 0.508)
		(drill 0.254)
		(layers "F.Cu" "B.Cu")
		(net "GND")
	)
	(via
		(at 458.345032 -3.011932)
		(size 0.508)
		(drill 0.254)
		(layers "F.Cu" "B.Cu")
		(net "GND")
	)
	(via
		(at 380.028196 -130.612134)
		(size 0.508)
		(drill 0.254)
		(layers "F.Cu" "B.Cu")
		(net "GND")
	)
	(via
		(at 151.24938 -140.617956)
		(size 0.508)
		(drill 0.254)
		(layers "F.Cu" "B.Cu")
		(net "GND")
	)
	(via
		(at 132.519674 -52.932838)
		(size 0.508)
		(drill 0.254)
		(layers "F.Cu" "B.Cu")
		(net "GND")
	)
	(via
		(at 129.085848 -70.763384)
		(size 0.508)
		(drill 0.254)
		(layers "F.Cu" "B.Cu")
		(net "GND")
	)
	(via
		(at 234.753658 -95.709486)
		(size 0.508)
		(drill 0.254)
		(layers "F.Cu" "B.Cu")
		(net "GND")
	)
	(via
		(at 422.940734 -166.714424)
		(size 0.5588)
		(drill 0.3048)
		(layers "F.Cu" "B.Cu")
		(net "GND")
	)
	(via
		(at 351.895664 -104.267508)
		(size 0.508)
		(drill 0.254)
		(layers "F.Cu" "B.Cu")
		(net "GND")
	)
	(via
		(at 142.749524 -9.143746)
		(size 0.508)
		(drill 0.254)
		(layers "F.Cu" "B.Cu")
		(net "GND")
	)
	(via
		(at 233.036618 -61.038486)
		(size 0.508)
		(drill 0.254)
		(layers "F.Cu" "B.Cu")
		(net "GND")
	)
	(via
		(at 381.29845 -110.943644)
		(size 0.508)
		(drill 0.254)
		(layers "F.Cu" "B.Cu")
		(net "GND")
	)
	(via
		(at 477.901 -30.861)
		(size 0.508)
		(drill 0.254)
		(layers "F.Cu" "B.Cu")
		(net "GND")
	)
	(via
		(at 381.37846 -128.266952)
		(size 0.508)
		(drill 0.254)
		(layers "F.Cu" "B.Cu")
		(net "GND")
	)
	(via
		(at 292.392608 -2.310892)
		(size 0.508)
		(drill 0.254)
		(layers "F.Cu" "B.Cu")
		(net "GND")
	)
	(via
		(at 215.371934 9.084056)
		(size 0.5588)
		(drill 0.3048)
		(layers "F.Cu" "B.Cu")
		(net "GND")
	)
	(via
		(at 417.301934 9.084056)
		(size 0.5588)
		(drill 0.3048)
		(layers "F.Cu" "B.Cu")
		(net "GND")
	)
	(via
		(at 128.687576 -124.680218)
		(size 0.508)
		(drill 0.254)
		(layers "F.Cu" "B.Cu")
		(net "GND")
	)
	(via
		(at 437.621934 11.624056)
		(size 0.5588)
		(drill 0.3048)
		(layers "F.Cu" "B.Cu")
		(net "GND")
	)
	(via
		(at 135.099552 -18.757646)
		(size 0.508)
		(drill 0.254)
		(layers "F.Cu" "B.Cu")
		(net "GND")
	)
	(via
		(at 67.162934 -167.832024)
		(size 0.5588)
		(drill 0.3048)
		(layers "F.Cu" "B.Cu")
		(net "GND")
	)
	(via
		(at 332.211934 14.926056)
		(size 0.5588)
		(drill 0.3048)
		(layers "F.Cu" "B.Cu")
		(net "GND")
	)
	(via
		(at 392.405616 -84.838032)
		(size 0.508)
		(drill 0.254)
		(layers "F.Cu" "B.Cu")
		(net "GND")
	)
	(via
		(at 465.582 -38.969696)
		(size 0.5588)
		(drill 0.3048)
		(layers "F.Cu" "B.Cu")
		(net "GND")
	)
	(via
		(at 353.66452 -77.37856)
		(size 0.508)
		(drill 0.254)
		(layers "F.Cu" "B.Cu")
		(net "GND")
	)
	(via
		(at 183.393334 -167.832024)
		(size 0.5588)
		(drill 0.3048)
		(layers "F.Cu" "B.Cu")
		(net "GND")
	)
	(via
		(at 480.263962 -16.050006)
		(size 0.508)
		(drill 0.254)
		(layers "F.Cu" "B.Cu")
		(net "GND")
	)
	(via
		(at 73.187306 -68.963286)
		(size 0.508)
		(drill 0.254)
		(layers "F.Cu" "B.Cu")
		(net "GND")
	)
	(via
		(at 387.73735 -116.953284)
		(size 0.508)
		(drill 0.254)
		(layers "F.Cu" "B.Cu")
		(net "GND")
	)
	(via
		(at 77.479906 -69.45884)
		(size 0.508)
		(drill 0.254)
		(layers "F.Cu" "B.Cu")
		(net "GND")
	)
	(via
		(at 306.049934 -139.170156)
		(size 0.508)
		(drill 0.254)
		(layers "F.Cu" "B.Cu")
		(net "GND")
	)
	(via
		(at 124.160534 -167.832024)
		(size 0.5588)
		(drill 0.3048)
		(layers "F.Cu" "B.Cu")
		(net "GND")
	)
	(via
		(at 62.971934 9.084056)
		(size 0.5588)
		(drill 0.3048)
		(layers "F.Cu" "B.Cu")
		(net "GND")
	)
	(via
		(at 468.101934 9.084056)
		(size 0.5588)
		(drill 0.3048)
		(layers "F.Cu" "B.Cu")
		(net "GND")
	)
	(via
		(at 182.4228 -74.93)
		(size 0.508)
		(drill 0.254)
		(layers "F.Cu" "B.Cu")
		(net "GND")
	)
	(via
		(at 119.327168 -2.3622)
		(size 0.508)
		(drill 0.254)
		(layers "F.Cu" "B.Cu")
		(net "GND")
	)
	(via
		(at 216.641934 14.926056)
		(size 0.5588)
		(drill 0.3048)
		(layers "F.Cu" "B.Cu")
		(net "GND")
	)
	(via
		(at 229.087934 -4.346956)
		(size 0.508)
		(drill 0.254)
		(layers "F.Cu" "B.Cu")
		(net "GND")
	)
	(via
		(at 441.119006 -40.5257)
		(size 0.508)
		(drill 0.254)
		(layers "F.Cu" "B.Cu")
		(net "GND")
	)
	(via
		(at 107.027472 -145.0086)
		(size 0.508)
		(drill 0.254)
		(layers "F.Cu" "B.Cu")
		(net "GND")
	)
	(via
		(at 435.081934 11.624056)
		(size 0.5588)
		(drill 0.3048)
		(layers "F.Cu" "B.Cu")
		(net "GND")
	)
	(via
		(at 135.771636 -134.8994)
		(size 0.508)
		(drill 0.254)
		(layers "F.Cu" "B.Cu")
		(net "GND")
	)
	(via
		(at 475.206568 -148.14423)
		(size 0.508)
		(drill 0.254)
		(layers "F.Cu" "B.Cu")
		(net "GND")
	)
	(via
		(at 239.046258 -57.57164)
		(size 0.508)
		(drill 0.254)
		(layers "F.Cu" "B.Cu")
		(net "GND")
	)
	(via
		(at 172.212 -62.5856)
		(size 0.508)
		(drill 0.254)
		(layers "F.Cu" "B.Cu")
		(net "GND")
	)
	(via
		(at 235.612178 -72.43064)
		(size 0.508)
		(drill 0.254)
		(layers "F.Cu" "B.Cu")
		(net "GND")
	)
	(via
		(at 245.914164 -96.20504)
		(size 0.508)
		(drill 0.254)
		(layers "F.Cu" "B.Cu")
		(net "GND")
	)
	(via
		(at 170.5356 -5.8674)
		(size 0.508)
		(drill 0.254)
		(layers "F.Cu" "B.Cu")
		(net "GND")
	)
	(via
		(at 253.802134 -167.832024)
		(size 0.5588)
		(drill 0.3048)
		(layers "F.Cu" "B.Cu")
		(net "GND")
	)
	(via
		(at 471.932 -145.796)
		(size 0.508)
		(drill 0.254)
		(layers "F.Cu" "B.Cu")
		(net "GND")
	)
	(via
		(at 184.507124 -162.243262)
		(size 0.5588)
		(drill 0.3048)
		(layers "F.Cu" "B.Cu")
		(net "GND")
	)
	(via
		(at 69.753226 -86.794086)
		(size 0.508)
		(drill 0.254)
		(layers "F.Cu" "B.Cu")
		(net "GND")
	)
	(via
		(at 167.3606 -88.392)
		(size 0.508)
		(drill 0.254)
		(layers "F.Cu" "B.Cu")
		(net "GND")
	)
	(via
		(at 209.08645 -131.5466)
		(size 0.508)
		(drill 0.254)
		(layers "F.Cu" "B.Cu")
		(net "GND")
	)
	(via
		(at 472.470734 -167.832024)
		(size 0.5588)
		(drill 0.3048)
		(layers "F.Cu" "B.Cu")
		(net "GND")
	)
	(via
		(at 131.661408 -98.995738)
		(size 0.508)
		(drill 0.254)
		(layers "F.Cu" "B.Cu")
		(net "GND")
	)
	(via
		(at 407.700734 -166.714424)
		(size 0.5588)
		(drill 0.3048)
		(layers "F.Cu" "B.Cu")
		(net "GND")
	)
	(via
		(at 275.111464 -8.1534)
		(size 0.508)
		(drill 0.254)
		(layers "F.Cu" "B.Cu")
		(net "GND")
	)
	(via
		(at 349.991934 14.926056)
		(size 0.5588)
		(drill 0.3048)
		(layers "F.Cu" "B.Cu")
		(net "GND")
	)
	(via
		(at 232.94975 -154.063446)
		(size 0.508)
		(drill 0.254)
		(layers "F.Cu" "B.Cu")
		(net "GND")
	)
	(via
		(at -0.070866 12.741656)
		(size 0.5588)
		(drill 0.3048)
		(layers "F.Cu" "B.Cu")
		(net "GND")
	)
	(via
		(at 313.699906 -139.170156)
		(size 0.508)
		(drill 0.254)
		(layers "F.Cu" "B.Cu")
		(net "GND")
	)
	(via
		(at 136.812274 -72.249538)
		(size 0.508)
		(drill 0.254)
		(layers "F.Cu" "B.Cu")
		(net "GND")
	)
	(via
		(at 283.04236 -136.397746)
		(size 0.508)
		(drill 0.254)
		(layers "F.Cu" "B.Cu")
		(net "GND")
	)
	(via
		(at 231.249728 -124.725176)
		(size 0.508)
		(drill 0.254)
		(layers "F.Cu" "B.Cu")
		(net "GND")
	)
	(via
		(at 345.4654 -149.4536)
		(size 0.508)
		(drill 0.254)
		(layers "F.Cu" "B.Cu")
		(net "GND")
	)
	(via
		(at 458.7748 -148.0566)
		(size 0.508)
		(drill 0.254)
		(layers "F.Cu" "B.Cu")
		(net "GND")
	)
	(via
		(at 210.215734 -167.832024)
		(size 0.5588)
		(drill 0.3048)
		(layers "F.Cu" "B.Cu")
		(net "GND")
	)
	(via
		(at 149.549358 -7.607046)
		(size 0.508)
		(drill 0.254)
		(layers "F.Cu" "B.Cu")
		(net "GND")
	)
	(via
		(at 200.880218 -65.461896)
		(size 0.508)
		(drill 0.254)
		(layers "F.Cu" "B.Cu")
		(net "GND")
	)
	(via
		(at 297.520106 -59.866784)
		(size 0.508)
		(drill 0.254)
		(layers "F.Cu" "B.Cu")
		(net "GND")
	)
	(via
		(at 1.313942 -56.906668)
		(size 0.5588)
		(drill 0.3048)
		(layers "F.Cu" "B.Cu")
		(net "GND")
	)
	(via
		(at 44.086018 -23.495)
		(size 0.508)
		(drill 0.254)
		(layers "F.Cu" "B.Cu")
		(net "GND")
	)
	(via
		(at 377.978924 -162.268662)
		(size 0.5588)
		(drill 0.3048)
		(layers "F.Cu" "B.Cu")
		(net "GND")
	)
	(via
		(at 135.095234 -79.183738)
		(size 0.508)
		(drill 0.254)
		(layers "F.Cu" "B.Cu")
		(net "GND")
	)
	(via
		(at 65.399412 -21.517356)
		(size 0.508)
		(drill 0.254)
		(layers "F.Cu" "B.Cu")
		(net "GND")
	)
	(via
		(at 74.045826 -93.23324)
		(size 0.508)
		(drill 0.254)
		(layers "F.Cu" "B.Cu")
		(net "GND")
	)
	(via
		(at 150.399496 -11.916156)
		(size 0.508)
		(drill 0.254)
		(layers "F.Cu" "B.Cu")
		(net "GND")
	)
	(via
		(at 181.638956 -6.70433)
		(size 0.508)
		(drill 0.254)
		(layers "F.Cu" "B.Cu")
		(net "GND")
	)
	(via
		(at 345.4908 -152.908)
		(size 0.508)
		(drill 0.254)
		(layers "F.Cu" "B.Cu")
		(net "GND")
	)
	(via
		(at 35.785806 -53.840888)
		(size 0.5588)
		(drill 0.3048)
		(layers "F.Cu" "B.Cu")
		(net "GND")
	)
	(via
		(at 126.421642 -154.1018)
		(size 0.508)
		(drill 0.254)
		(layers "F.Cu" "B.Cu")
		(net "GND")
	)
	(via
		(at 71.171562 -124.623576)
		(size 0.508)
		(drill 0.254)
		(layers "F.Cu" "B.Cu")
		(net "GND")
	)
	(via
		(at 252.684534 -167.832024)
		(size 0.5588)
		(drill 0.3048)
		(layers "F.Cu" "B.Cu")
		(net "GND")
	)
	(via
		(at 67.099434 -148.771356)
		(size 0.508)
		(drill 0.254)
		(layers "F.Cu" "B.Cu")
		(net "GND")
	)
	(via
		(at 210.38185 -2.3114)
		(size 0.508)
		(drill 0.254)
		(layers "F.Cu" "B.Cu")
		(net "GND")
	)
	(via
		(at 117.640862 -65.810384)
		(size 0.508)
		(drill 0.254)
		(layers "F.Cu" "B.Cu")
		(net "GND")
	)
	(via
		(at 40.06723 -84.5312)
		(size 0.5588)
		(drill 0.3048)
		(layers "F.Cu" "B.Cu")
		(net "GND")
	)
	(via
		(at 307.898546 -63.829184)
		(size 0.508)
		(drill 0.254)
		(layers "F.Cu" "B.Cu")
		(net "GND")
	)
	(via
		(at 462.2292 -9.017)
		(size 0.508)
		(drill 0.254)
		(layers "F.Cu" "B.Cu")
		(net "GND")
	)
	(via
		(at 299.237146 -52.932838)
		(size 0.508)
		(drill 0.254)
		(layers "F.Cu" "B.Cu")
		(net "GND")
	)
	(via
		(at 40.13835 -60.183522)
		(size 0.5588)
		(drill 0.3048)
		(layers "F.Cu" "B.Cu")
		(net "GND")
	)
	(via
		(at 175.4124 -109.855)
		(size 0.508)
		(drill 0.254)
		(layers "F.Cu" "B.Cu")
		(net "GND")
	)
	(via
		(at 315.394848 -47.67834)
		(size 0.508)
		(drill 0.254)
		(layers "F.Cu" "B.Cu")
		(net "GND")
	)
	(via
		(at 283.048964 -153.6065)
		(size 0.508)
		(drill 0.254)
		(layers "F.Cu" "B.Cu")
		(net "GND")
	)
	(via
		(at 357.823262 -133.989572)
		(size 0.508)
		(drill 0.254)
		(layers "F.Cu" "B.Cu")
		(net "GND")
	)
	(via
		(at 487.710734 -163.361624)
		(size 0.5588)
		(drill 0.3048)
		(layers "F.Cu" "B.Cu")
		(net "GND")
	)
	(via
		(at 454.131934 11.624056)
		(size 0.5588)
		(drill 0.3048)
		(layers "F.Cu" "B.Cu")
		(net "GND")
	)
	(via
		(at 436.921656 -28.2321)
		(size 0.4572)
		(drill 0.2032)
		(layers "F.Cu" "B.Cu")
		(net "GND")
	)
	(via
		(at 483.341934 9.084056)
		(size 0.5588)
		(drill 0.3048)
		(layers "F.Cu" "B.Cu")
		(net "GND")
	)
	(via
		(at 35.867594 -82.68081)
		(size 0.508)
		(drill 0.254)
		(layers "F.Cu" "B.Cu")
		(net "GND")
	)
	(via
		(at 196.893434 -71.784464)
		(size 0.508)
		(drill 0.254)
		(layers "F.Cu" "B.Cu")
		(net "GND")
	)
	(via
		(at 400.080734 -163.361624)
		(size 0.5588)
		(drill 0.3048)
		(layers "F.Cu" "B.Cu")
		(net "GND")
	)
	(via
		(at 6.1976 -131.953)
		(size 0.508)
		(drill 0.254)
		(layers "F.Cu" "B.Cu")
		(net "GND")
	)
	(via
		(at 452.861934 13.910056)
		(size 0.5588)
		(drill 0.3048)
		(layers "F.Cu" "B.Cu")
		(net "GND")
	)
	(via
		(at 200.8886 -81.788)
		(size 0.508)
		(drill 0.254)
		(layers "F.Cu" "B.Cu")
		(net "GND")
	)
	(via
		(at 268.711934 14.926056)
		(size 0.5588)
		(drill 0.3048)
		(layers "F.Cu" "B.Cu")
		(net "GND")
	)
	(via
		(at 264.801096 -63.51524)
		(size 0.508)
		(drill 0.254)
		(layers "F.Cu" "B.Cu")
		(net "GND")
	)
	(via
		(at 51.516534 -167.832024)
		(size 0.5588)
		(drill 0.3048)
		(layers "F.Cu" "B.Cu")
		(net "GND")
	)
	(via
		(at 38.199314 -13.363956)
		(size 0.508)
		(drill 0.254)
		(layers "F.Cu" "B.Cu")
		(net "GND")
	)
	(via
		(at 68.036186 -61.038486)
		(size 0.508)
		(drill 0.254)
		(layers "F.Cu" "B.Cu")
		(net "GND")
	)
	(via
		(at 394.20546 -106.974132)
		(size 0.508)
		(drill 0.254)
		(layers "F.Cu" "B.Cu")
		(net "GND")
	)
	(via
		(at 134.15137 -154.063446)
		(size 0.508)
		(drill 0.254)
		(layers "F.Cu" "B.Cu")
		(net "GND")
	)
	(via
		(at 459.221332 -143.68526)
		(size 0.508)
		(drill 0.254)
		(layers "F.Cu" "B.Cu")
		(net "GND")
	)
	(via
		(at 60.830968 -126.619)
		(size 0.508)
		(drill 0.254)
		(layers "F.Cu" "B.Cu")
		(net "GND")
	)
	(via
		(at 176.001934 14.926056)
		(size 0.5588)
		(drill 0.3048)
		(layers "F.Cu" "B.Cu")
		(net "GND")
	)
	(via
		(at 67.949318 -131.016756)
		(size 0.508)
		(drill 0.254)
		(layers "F.Cu" "B.Cu")
		(net "GND")
	)
	(via
		(at 239.904778 -62.029086)
		(size 0.508)
		(drill 0.254)
		(layers "F.Cu" "B.Cu")
		(net "GND")
	)
	(via
		(at 34.748724 -16.7513)
		(size 0.508)
		(drill 0.254)
		(layers "F.Cu" "B.Cu")
		(net "GND")
	)
	(via
		(at 284.3276 -11.9634)
		(size 0.508)
		(drill 0.254)
		(layers "F.Cu" "B.Cu")
		(net "GND")
	)
	(via
		(at 300.772068 -7.6454)
		(size 0.508)
		(drill 0.254)
		(layers "F.Cu" "B.Cu")
		(net "GND")
	)
	(via
		(at 339.1154 -40.64)
		(size 0.508)
		(drill 0.254)
		(layers "F.Cu" "B.Cu")
		(net "GND")
	)
	(via
		(at 136.74217 -145.998946)
		(size 0.508)
		(drill 0.254)
		(layers "F.Cu" "B.Cu")
		(net "GND")
	)
	(via
		(at 129.944368 -86.117938)
		(size 0.508)
		(drill 0.254)
		(layers "F.Cu" "B.Cu")
		(net "GND")
	)
	(via
		(at 238.44123 -153.552144)
		(size 0.508)
		(drill 0.254)
		(layers "F.Cu" "B.Cu")
		(net "GND")
	)
	(via
		(at 389.71855 -116.953284)
		(size 0.508)
		(drill 0.254)
		(layers "F.Cu" "B.Cu")
		(net "GND")
	)
	(via
		(at 277.512018 -75.148186)
		(size 0.5588)
		(drill 0.3048)
		(layers "F.Cu" "B.Cu")
		(net "GND")
	)
	(via
		(at 126.510288 -99.986338)
		(size 0.508)
		(drill 0.254)
		(layers "F.Cu" "B.Cu")
		(net "GND")
	)
	(via
		(at 444.530734 -167.832024)
		(size 0.5588)
		(drill 0.3048)
		(layers "F.Cu" "B.Cu")
		(net "GND")
	)
	(via
		(at 425.31157 -43.177714)
		(size 0.508)
		(drill 0.254)
		(layers "F.Cu" "B.Cu")
		(net "GND")
	)
	(via
		(at 454.690734 -167.832024)
		(size 0.5588)
		(drill 0.3048)
		(layers "F.Cu" "B.Cu")
		(net "GND")
	)
	(via
		(at 196.893434 -79.912464)
		(size 0.508)
		(drill 0.254)
		(layers "F.Cu" "B.Cu")
		(net "GND")
	)
	(via
		(at 134.236714 -54.913784)
		(size 0.508)
		(drill 0.254)
		(layers "F.Cu" "B.Cu")
		(net "GND")
	)
	(via
		(at 285.649924 0.444754)
		(size 0.508)
		(drill 0.254)
		(layers "F.Cu" "B.Cu")
		(net "GND")
	)
	(via
		(at 483.997254 -20.26666)
		(size 0.508)
		(drill 0.254)
		(layers "F.Cu" "B.Cu")
		(net "GND")
	)
	(via
		(at 411.510734 -164.479224)
		(size 0.5588)
		(drill 0.3048)
		(layers "F.Cu" "B.Cu")
		(net "GND")
	)
	(via
		(at 77.479906 -63.51524)
		(size 0.508)
		(drill 0.254)
		(layers "F.Cu" "B.Cu")
		(net "GND")
	)
	(via
		(at 48.399446 -2.314956)
		(size 0.508)
		(drill 0.254)
		(layers "F.Cu" "B.Cu")
		(net "GND")
	)
	(via
		(at 282.07208 -22.939756)
		(size 0.508)
		(drill 0.254)
		(layers "F.Cu" "B.Cu")
		(net "GND")
	)
	(via
		(at 288.65068 -59.371484)
		(size 0.508)
		(drill 0.254)
		(layers "F.Cu" "B.Cu")
		(net "GND")
	)
	(via
		(at 140.246354 -63.334138)
		(size 0.508)
		(drill 0.254)
		(layers "F.Cu" "B.Cu")
		(net "GND")
	)
	(via
		(at 65.377568 -125.9332)
		(size 0.508)
		(drill 0.254)
		(layers "F.Cu" "B.Cu")
		(net "GND")
	)
	(via
		(at 380.30785 -96.747076)
		(size 0.508)
		(drill 0.254)
		(layers "F.Cu" "B.Cu")
		(net "GND")
	)
	(via
		(at 436.351934 14.926056)
		(size 0.5588)
		(drill 0.3048)
		(layers "F.Cu" "B.Cu")
		(net "GND")
	)
	(via
		(at 283.04236 -155.600146)
		(size 0.508)
		(drill 0.254)
		(layers "F.Cu" "B.Cu")
		(net "GND")
	)
	(via
		(at 235.612178 -99.17684)
		(size 0.508)
		(drill 0.254)
		(layers "F.Cu" "B.Cu")
		(net "GND")
	)
	(via
		(at 346.7354 -39.37)
		(size 0.508)
		(drill 0.254)
		(layers "F.Cu" "B.Cu")
		(net "GND")
	)
	(via
		(at 462.444592 -41.512998)
		(size 0.508)
		(drill 0.254)
		(layers "F.Cu" "B.Cu")
		(net "GND")
	)
	(via
		(at 226.822 -140.617956)
		(size 0.508)
		(drill 0.254)
		(layers "F.Cu" "B.Cu")
		(net "GND")
	)
	(via
		(at 497.866924 -162.243262)
		(size 0.5588)
		(drill 0.3048)
		(layers "F.Cu" "B.Cu")
		(net "GND")
	)
	(via
		(at 128.69418 -155.5369)
		(size 0.508)
		(drill 0.254)
		(layers "F.Cu" "B.Cu")
		(net "GND")
	)
	(via
		(at 452.861934 11.624056)
		(size 0.5588)
		(drill 0.3048)
		(layers "F.Cu" "B.Cu")
		(net "GND")
	)
	(via
		(at 111.915702 -89.584784)
		(size 0.508)
		(drill 0.254)
		(layers "F.Cu" "B.Cu")
		(net "GND")
	)
	(via
		(at 407.700734 -165.596824)
		(size 0.5588)
		(drill 0.3048)
		(layers "F.Cu" "B.Cu")
		(net "GND")
	)
	(via
		(at 185.413396 -87.544402)
		(size 0.508)
		(drill 0.254)
		(layers "F.Cu" "B.Cu")
		(net "GND")
	)
	(via
		(at 249.348244 -68.46824)
		(size 0.508)
		(drill 0.254)
		(layers "F.Cu" "B.Cu")
		(net "GND")
	)
	(via
		(at 69.753226 -89.765886)
		(size 0.508)
		(drill 0.254)
		(layers "F.Cu" "B.Cu")
		(net "GND")
	)
	(via
		(at 34.748724 -144.0053)
		(size 0.508)
		(drill 0.254)
		(layers "F.Cu" "B.Cu")
		(net "GND")
	)
	(via
		(at 459.270608 -150.266654)
		(size 0.508)
		(drill 0.254)
		(layers "F.Cu" "B.Cu")
		(net "GND")
	)
	(via
		(at 107.392724 -162.243262)
		(size 0.5588)
		(drill 0.3048)
		(layers "F.Cu" "B.Cu")
		(net "GND")
	)
	(via
		(at 416.590734 -166.714424)
		(size 0.5588)
		(drill 0.3048)
		(layers "F.Cu" "B.Cu")
		(net "GND")
	)
	(via
		(at 459.211934 13.910056)
		(size 0.5588)
		(drill 0.3048)
		(layers "F.Cu" "B.Cu")
		(net "GND")
	)
	(via
		(at 380.30785 -108.766356)
		(size 0.508)
		(drill 0.254)
		(layers "F.Cu" "B.Cu")
		(net "GND")
	)
	(via
		(at 211.699856 -129.568956)
		(size 0.508)
		(drill 0.254)
		(layers "F.Cu" "B.Cu")
		(net "GND")
	)
	(via
		(at 70.511924 -162.243262)
		(size 0.5588)
		(drill 0.3048)
		(layers "F.Cu" "B.Cu")
		(net "GND")
	)
	(via
		(at 72.750934 -167.832024)
		(size 0.5588)
		(drill 0.3048)
		(layers "F.Cu" "B.Cu")
		(net "GND")
	)
	(via
		(at 358.9782 -115.4176)
		(size 0.508)
		(drill 0.254)
		(layers "F.Cu" "B.Cu")
		(net "GND")
	)
	(via
		(at 6.583934 9.084056)
		(size 0.5588)
		(drill 0.3048)
		(layers "F.Cu" "B.Cu")
		(net "GND")
	)
	(via
		(at 344.862404 -150.123398)
		(size 0.508)
		(drill 0.254)
		(layers "F.Cu" "B.Cu")
		(net "GND")
	)
	(via
		(at 474.451934 14.926056)
		(size 0.5588)
		(drill 0.3048)
		(layers "F.Cu" "B.Cu")
		(net "GND")
	)
	(via
		(at 69.398134 -167.832024)
		(size 0.5588)
		(drill 0.3048)
		(layers "F.Cu" "B.Cu")
		(net "GND")
	)
	(via
		(at 446.511934 12.894056)
		(size 0.5588)
		(drill 0.3048)
		(layers "F.Cu" "B.Cu")
		(net "GND")
	)
	(via
		(at 126.510288 -56.399938)
		(size 0.508)
		(drill 0.254)
		(layers "F.Cu" "B.Cu")
		(net "GND")
	)
	(via
		(at 59.449462 -139.170156)
		(size 0.508)
		(drill 0.254)
		(layers "F.Cu" "B.Cu")
		(net "GND")
	)
	(via
		(at 204.049884 -136.410446)
		(size 0.508)
		(drill 0.254)
		(layers "F.Cu" "B.Cu")
		(net "GND")
	)
	(via
		(at 279.207214 -64.819784)
		(size 0.508)
		(drill 0.254)
		(layers "F.Cu" "B.Cu")
		(net "GND")
	)
	(via
		(at 57.891934 9.084056)
		(size 0.5588)
		(drill 0.3048)
		(layers "F.Cu" "B.Cu")
		(net "GND")
	)
	(via
		(at 41.427654 -85.23351)
		(size 0.5588)
		(drill 0.3048)
		(layers "F.Cu" "B.Cu")
		(net "GND")
	)
	(via
		(at 215.85174 -154.063446)
		(size 0.508)
		(drill 0.254)
		(layers "F.Cu" "B.Cu")
		(net "GND")
	)
	(via
		(at 376.428 -100.354892)
		(size 0.508)
		(drill 0.254)
		(layers "F.Cu" "B.Cu")
		(net "GND")
	)
	(via
		(at 338.864702 -69.37121)
		(size 0.508)
		(drill 0.254)
		(layers "F.Cu" "B.Cu")
		(net "GND")
	)
	(via
		(at 234.551728 -154.063446)
		(size 0.508)
		(drill 0.254)
		(layers "F.Cu" "B.Cu")
		(net "GND")
	)
	(via
		(at 72.328786 -78.37424)
		(size 0.508)
		(drill 0.254)
		(layers "F.Cu" "B.Cu")
		(net "GND")
	)
	(via
		(at 74.045826 -92.24264)
		(size 0.508)
		(drill 0.254)
		(layers "F.Cu" "B.Cu")
		(net "GND")
	)
	(via
		(at 242.287044 -22.965156)
		(size 0.508)
		(drill 0.254)
		(layers "F.Cu" "B.Cu")
		(net "GND")
	)
	(via
		(at 131.699508 -11.916156)
		(size 0.508)
		(drill 0.254)
		(layers "F.Cu" "B.Cu")
		(net "GND")
	)
	(via
		(at 434.2384 -11.6332)
		(size 0.508)
		(drill 0.254)
		(layers "F.Cu" "B.Cu")
		(net "GND")
	)
	(via
		(at 484.611934 9.084056)
		(size 0.5588)
		(drill 0.3048)
		(layers "F.Cu" "B.Cu")
		(net "GND")
	)
	(via
		(at 416.590734 -164.479224)
		(size 0.5588)
		(drill 0.3048)
		(layers "F.Cu" "B.Cu")
		(net "GND")
	)
	(via
		(at 175.662082 -49.942496)
		(size 0.508)
		(drill 0.254)
		(layers "F.Cu" "B.Cu")
		(net "GND")
	)
	(via
		(at 183.160924 -154.8257)
		(size 0.508)
		(drill 0.254)
		(layers "F.Cu" "B.Cu")
		(net "GND")
	)
	(via
		(at 287.349946 -11.916156)
		(size 0.508)
		(drill 0.254)
		(layers "F.Cu" "B.Cu")
		(net "GND")
	)
	(via
		(at 113.897156 -9.083294)
		(size 0.508)
		(drill 0.254)
		(layers "F.Cu" "B.Cu")
		(net "GND")
	)
	(via
		(at 56.621934 9.084056)
		(size 0.5588)
		(drill 0.3048)
		(layers "F.Cu" "B.Cu")
		(net "GND")
	)
	(via
		(at 350.634046 -104.261666)
		(size 0.508)
		(drill 0.254)
		(layers "F.Cu" "B.Cu")
		(net "GND")
	)
	(via
		(at 98.942398 -95.709486)
		(size 0.508)
		(drill 0.254)
		(layers "F.Cu" "B.Cu")
		(net "GND")
	)
	(via
		(at 286.07512 -56.894984)
		(size 0.508)
		(drill 0.254)
		(layers "F.Cu" "B.Cu")
		(net "GND")
	)
	(via
		(at 62.688724 -162.243262)
		(size 0.5588)
		(drill 0.3048)
		(layers "F.Cu" "B.Cu")
		(net "GND")
	)
	(via
		(at 241.44986 -129.568956)
		(size 0.508)
		(drill 0.254)
		(layers "F.Cu" "B.Cu")
		(net "GND")
	)
	(via
		(at 175.768 -12.319)
		(size 0.508)
		(drill 0.254)
		(layers "F.Cu" "B.Cu")
		(net "GND")
	)
	(via
		(at 142.039848 -99.986338)
		(size 0.508)
		(drill 0.254)
		(layers "F.Cu" "B.Cu")
		(net "GND")
	)
	(via
		(at 42.088054 -85.23351)
		(size 0.5588)
		(drill 0.3048)
		(layers "F.Cu" "B.Cu")
		(net "GND")
	)
	(via
		(at 377.485148 -3.429)
		(size 0.508)
		(drill 0.254)
		(layers "F.Cu" "B.Cu")
		(net "GND")
	)
	(via
		(at 125.651768 -72.744584)
		(size 0.508)
		(drill 0.254)
		(layers "F.Cu" "B.Cu")
		(net "GND")
	)
	(via
		(at 405.09952 -125.69952)
		(size 0.508)
		(drill 0.254)
		(layers "F.Cu" "B.Cu")
		(net "GND")
	)
	(via
		(at 165.507924 -162.243262)
		(size 0.5588)
		(drill 0.3048)
		(layers "F.Cu" "B.Cu")
		(net "GND")
	)
	(via
		(at 94.257876 -75.159616)
		(size 0.5588)
		(drill 0.3048)
		(layers "F.Cu" "B.Cu")
		(net "GND")
	)
	(via
		(at 306.899818 -22.965156)
		(size 0.508)
		(drill 0.254)
		(layers "F.Cu" "B.Cu")
		(net "GND")
	)
	(via
		(at 256.037334 -167.832024)
		(size 0.5588)
		(drill 0.3048)
		(layers "F.Cu" "B.Cu")
		(net "GND")
	)
	(via
		(at 300.772068 -22.965156)
		(size 0.508)
		(drill 0.254)
		(layers "F.Cu" "B.Cu")
		(net "GND")
	)
	(via
		(at 334.0354 -109.855)
		(size 0.508)
		(drill 0.254)
		(layers "F.Cu" "B.Cu")
		(net "GND")
	)
	(via
		(at 166.652194 -30.8737)
		(size 0.508)
		(drill 0.254)
		(layers "F.Cu" "B.Cu")
		(net "GND")
	)
	(via
		(at 100.811076 -75.159616)
		(size 0.5588)
		(drill 0.3048)
		(layers "F.Cu" "B.Cu")
		(net "GND")
	)
	(via
		(at 99.801934 14.926056)
		(size 0.5588)
		(drill 0.3048)
		(layers "F.Cu" "B.Cu")
		(net "GND")
	)
	(via
		(at 62.792102 -2.310892)
		(size 0.508)
		(drill 0.254)
		(layers "F.Cu" "B.Cu")
		(net "GND")
	)
	(via
		(at 145.12163 -22.965156)
		(size 0.508)
		(drill 0.254)
		(layers "F.Cu" "B.Cu")
		(net "GND")
	)
	(via
		(at 360.505502 -158.52902)
		(size 0.5588)
		(drill 0.3048)
		(layers "F.Cu" "B.Cu")
		(net "GND")
	)
	(via
		(at 42.781982 -76.468478)
		(size 0.5588)
		(drill 0.3048)
		(layers "F.Cu" "B.Cu")
		(net "GND")
	)
	(via
		(at 442.0616 -126.0602)
		(size 0.508)
		(drill 0.254)
		(layers "F.Cu" "B.Cu")
		(net "GND")
	)
	(via
		(at 118.568724 -162.243262)
		(size 0.5588)
		(drill 0.3048)
		(layers "F.Cu" "B.Cu")
		(net "GND")
	)
	(via
		(at 278.849836 -7.1374)
		(size 0.508)
		(drill 0.254)
		(layers "F.Cu" "B.Cu")
		(net "GND")
	)
	(via
		(at 120.216168 -62.343538)
		(size 0.508)
		(drill 0.254)
		(layers "F.Cu" "B.Cu")
		(net "GND")
	)
	(via
		(at 285.649924 -136.410446)
		(size 0.508)
		(drill 0.254)
		(layers "F.Cu" "B.Cu")
		(net "GND")
	)
	(via
		(at 103.678736 -12.954)
		(size 0.508)
		(drill 0.254)
		(layers "F.Cu" "B.Cu")
		(net "GND")
	)
	(via
		(at 171.161456 -157.389322)
		(size 0.5588)
		(drill 0.3048)
		(layers "F.Cu" "B.Cu")
		(net "GND")
	)
	(via
		(at 219.744544 -18.6817)
		(size 0.508)
		(drill 0.254)
		(layers "F.Cu" "B.Cu")
		(net "GND")
	)
	(via
		(at 278.8666 -3.4798)
		(size 0.508)
		(drill 0.254)
		(layers "F.Cu" "B.Cu")
		(net "GND")
	)
	(via
		(at 424.921934 9.084056)
		(size 0.5588)
		(drill 0.3048)
		(layers "F.Cu" "B.Cu")
		(net "GND")
	)
	(via
		(at 427.461934 13.910056)
		(size 0.5588)
		(drill 0.3048)
		(layers "F.Cu" "B.Cu")
		(net "GND")
	)
	(via
		(at 277.271734 -167.832024)
		(size 0.5588)
		(drill 0.3048)
		(layers "F.Cu" "B.Cu")
		(net "GND")
	)
	(via
		(at 352.626676 1.44145)
		(size 0.508)
		(drill 0.254)
		(layers "F.Cu" "B.Cu")
		(net "GND")
	)
	(via
		(at 283.784294 -88.594184)
		(size 0.508)
		(drill 0.254)
		(layers "F.Cu" "B.Cu")
		(net "GND")
	)
	(via
		(at 236.171994 -13.363956)
		(size 0.508)
		(drill 0.254)
		(layers "F.Cu" "B.Cu")
		(net "GND")
	)
	(via
		(at 303.529746 -73.240138)
		(size 0.508)
		(drill 0.254)
		(layers "F.Cu" "B.Cu")
		(net "GND")
	)
	(via
		(at 181.7751 -139.2555)
		(size 0.508)
		(drill 0.254)
		(layers "F.Cu" "B.Cu")
		(net "GND")
	)
	(via
		(at 375.1072 -126.7206)
		(size 0.508)
		(drill 0.254)
		(layers "F.Cu" "B.Cu")
		(net "GND")
	)
	(via
		(at 81.485232 -102.093014)
		(size 0.508)
		(drill 0.254)
		(layers "F.Cu" "B.Cu")
		(net "GND")
	)
	(via
		(at 351.413826 -123.81103)
		(size 0.508)
		(drill 0.254)
		(layers "F.Cu" "B.Cu")
		(net "GND")
	)
	(via
		(at 92.932758 -64.50584)
		(size 0.508)
		(drill 0.254)
		(layers "F.Cu" "B.Cu")
		(net "GND")
	)
	(via
		(at 161.037524 -162.243262)
		(size 0.5588)
		(drill 0.3048)
		(layers "F.Cu" "B.Cu")
		(net "GND")
	)
	(via
		(at 170.6372 -2.501138)
		(size 0.508)
		(drill 0.254)
		(layers "F.Cu" "B.Cu")
		(net "GND")
	)
	(via
		(at 107.338876 -63.829184)
		(size 0.508)
		(drill 0.254)
		(layers "F.Cu" "B.Cu")
		(net "GND")
	)
	(via
		(at 117.925342 -100.976684)
		(size 0.508)
		(drill 0.254)
		(layers "F.Cu" "B.Cu")
		(net "GND")
	)
	(via
		(at 92.074238 -98.681286)
		(size 0.508)
		(drill 0.254)
		(layers "F.Cu" "B.Cu")
		(net "GND")
	)
	(via
		(at 350.5454 -39.37)
		(size 0.508)
		(drill 0.254)
		(layers "F.Cu" "B.Cu")
		(net "GND")
	)
	(via
		(at 314.54979 -7.607046)
		(size 0.508)
		(drill 0.254)
		(layers "F.Cu" "B.Cu")
		(net "GND")
	)
	(via
		(at 438.97423 -148.651976)
		(size 0.508)
		(drill 0.254)
		(layers "F.Cu" "B.Cu")
		(net "GND")
	)
	(via
		(at 396.768066 -41.54932)
		(size 0.508)
		(drill 0.254)
		(layers "F.Cu" "B.Cu")
		(net "GND")
	)
	(via
		(at 411.73654 -110.71098)
		(size 0.508)
		(drill 0.254)
		(layers "F.Cu" "B.Cu")
		(net "GND")
	)
	(via
		(at 118.041928 -155.600146)
		(size 0.508)
		(drill 0.254)
		(layers "F.Cu" "B.Cu")
		(net "GND")
	)
	(via
		(at 230.611934 9.084056)
		(size 0.5588)
		(drill 0.3048)
		(layers "F.Cu" "B.Cu")
		(net "GND")
	)
	(via
		(at 316.820804 -31.191708)
		(size 0.508)
		(drill 0.254)
		(layers "F.Cu" "B.Cu")
		(net "GND")
	)
	(via
		(at 41.454324 -162.243262)
		(size 0.5588)
		(drill 0.3048)
		(layers "F.Cu" "B.Cu")
		(net "GND")
	)
	(via
		(at 126.510288 -100.976684)
		(size 0.508)
		(drill 0.254)
		(layers "F.Cu" "B.Cu")
		(net "GND")
	)
	(via
		(at 117.640862 -63.829184)
		(size 0.508)
		(drill 0.254)
		(layers "F.Cu" "B.Cu")
		(net "GND")
	)
	(via
		(at 284.642814 -98.005138)
		(size 0.508)
		(drill 0.254)
		(layers "F.Cu" "B.Cu")
		(net "GND")
	)
	(via
		(at 195.549774 -141.1478)
		(size 0.508)
		(drill 0.254)
		(layers "F.Cu" "B.Cu")
		(net "GND")
	)
	(via
		(at 371.38737 -150.561294)
		(size 0.508)
		(drill 0.254)
		(layers "F.Cu" "B.Cu")
		(net "GND")
	)
	(via
		(at 68.799456 -145.998946)
		(size 0.508)
		(drill 0.254)
		(layers "F.Cu" "B.Cu")
		(net "GND")
	)
	(via
		(at 492.790734 -166.714424)
		(size 0.5588)
		(drill 0.3048)
		(layers "F.Cu" "B.Cu")
		(net "GND")
	)
	(via
		(at 115.041934 9.084056)
		(size 0.5588)
		(drill 0.3048)
		(layers "F.Cu" "B.Cu")
		(net "GND")
	)
	(via
		(at 309.449978 -146.011646)
		(size 0.508)
		(drill 0.254)
		(layers "F.Cu" "B.Cu")
		(net "GND")
	)
	(via
		(at 209.092546 0.457454)
		(size 0.508)
		(drill 0.254)
		(layers "F.Cu" "B.Cu")
		(net "GND")
	)
	(via
		(at 123.076208 -88.099138)
		(size 0.508)
		(drill 0.254)
		(layers "F.Cu" "B.Cu")
		(net "GND")
	)
	(via
		(at 129.944368 -61.352938)
		(size 0.508)
		(drill 0.254)
		(layers "F.Cu" "B.Cu")
		(net "GND")
	)
	(via
		(at 118.499382 -60.362338)
		(size 0.508)
		(drill 0.254)
		(layers "F.Cu" "B.Cu")
		(net "GND")
	)
	(via
		(at 31.39948 -136.397746)
		(size 0.508)
		(drill 0.254)
		(layers "F.Cu" "B.Cu")
		(net "GND")
	)
	(via
		(at 199.742552 -21.513292)
		(size 0.508)
		(drill 0.254)
		(layers "F.Cu" "B.Cu")
		(net "GND")
	)
	(via
		(at 71.470266 -64.010286)
		(size 0.508)
		(drill 0.254)
		(layers "F.Cu" "B.Cu")
		(net "GND")
	)
	(via
		(at 268.679168 -17.7546)
		(size 0.508)
		(drill 0.254)
		(layers "F.Cu" "B.Cu")
		(net "GND")
	)
	(via
		(at 482.626924 -162.243262)
		(size 0.5588)
		(drill 0.3048)
		(layers "F.Cu" "B.Cu")
		(net "GND")
	)
	(via
		(at 305.541934 14.926056)
		(size 0.5588)
		(drill 0.3048)
		(layers "F.Cu" "B.Cu")
		(net "GND")
	)
	(via
		(at 3.14452 -23.53818)
		(size 0.508)
		(drill 0.254)
		(layers "F.Cu" "B.Cu")
		(net "GND")
	)
	(via
		(at 223.599756 -3.762756)
		(size 0.508)
		(drill 0.254)
		(layers "F.Cu" "B.Cu")
		(net "GND")
	)
	(via
		(at 37.8206 -45.8216)
		(size 0.508)
		(drill 0.254)
		(layers "F.Cu" "B.Cu")
		(net "GND")
	)
	(via
		(at 345.506294 -155.593542)
		(size 0.508)
		(drill 0.254)
		(layers "F.Cu" "B.Cu")
		(net "GND")
	)
	(via
		(at 334.751934 9.084056)
		(size 0.5588)
		(drill 0.3048)
		(layers "F.Cu" "B.Cu")
		(net "GND")
	)
	(via
		(at 332.7654 -108.585)
		(size 0.508)
		(drill 0.254)
		(layers "F.Cu" "B.Cu")
		(net "GND")
	)
	(via
		(at 201.8538 -76.5048)
		(size 0.5588)
		(drill 0.3048)
		(layers "F.Cu" "B.Cu")
		(net "GND")
	)
	(via
		(at 241.621818 -69.953886)
		(size 0.508)
		(drill 0.254)
		(layers "F.Cu" "B.Cu")
		(net "GND")
	)
	(via
		(at 51.76139 -139.170156)
		(size 0.508)
		(drill 0.254)
		(layers "F.Cu" "B.Cu")
		(net "GND")
	)
	(via
		(at 305.211734 -167.832024)
		(size 0.5588)
		(drill 0.3048)
		(layers "F.Cu" "B.Cu")
		(net "GND")
	)
	(via
		(at 132.549392 -154.063446)
		(size 0.508)
		(drill 0.254)
		(layers "F.Cu" "B.Cu")
		(net "GND")
	)
	(via
		(at 270.167608 -70.84314)
		(size 0.5588)
		(drill 0.3048)
		(layers "F.Cu" "B.Cu")
		(net "GND")
	)
	(via
		(at 392.938 -68.4276)
		(size 0.508)
		(drill 0.254)
		(layers "F.Cu" "B.Cu")
		(net "GND")
	)
	(via
		(at 420.400734 -165.596824)
		(size 0.5588)
		(drill 0.3048)
		(layers "F.Cu" "B.Cu")
		(net "GND")
	)
	(via
		(at 345.4654 -39.37)
		(size 0.508)
		(drill 0.254)
		(layers "F.Cu" "B.Cu")
		(net "GND")
	)
	(via
		(at 491.210092 -55.043578)
		(size 0.508)
		(drill 0.254)
		(layers "F.Cu" "B.Cu")
		(net "GND")
	)
	(via
		(at 242.480338 -55.59044)
		(size 0.508)
		(drill 0.254)
		(layers "F.Cu" "B.Cu")
		(net "GND")
	)
	(via
		(at 463.021934 10.354056)
		(size 0.5588)
		(drill 0.3048)
		(layers "F.Cu" "B.Cu")
		(net "GND")
	)
	(via
		(at 295.149524 -162.243262)
		(size 0.5588)
		(drill 0.3048)
		(layers "F.Cu" "B.Cu")
		(net "GND")
	)
	(via
		(at 219.741242 -153.552144)
		(size 0.508)
		(drill 0.254)
		(layers "F.Cu" "B.Cu")
		(net "GND")
	)
	(via
		(at 215.860884 -150.193756)
		(size 0.508)
		(drill 0.254)
		(layers "F.Cu" "B.Cu")
		(net "GND")
	)
	(via
		(at 429.566578 -35.532314)
		(size 0.4572)
		(drill 0.2032)
		(layers "F.Cu" "B.Cu")
		(net "GND")
	)
	(via
		(at 297.549824 -134.861046)
		(size 0.508)
		(drill 0.254)
		(layers "F.Cu" "B.Cu")
		(net "GND")
	)
	(via
		(at 82.630772 -67.47764)
		(size 0.508)
		(drill 0.254)
		(layers "F.Cu" "B.Cu")
		(net "GND")
	)
	(via
		(at 294.08628 -84.631784)
		(size 0.508)
		(drill 0.254)
		(layers "F.Cu" "B.Cu")
		(net "GND")
	)
	(via
		(at 310.621934 9.084056)
		(size 0.5588)
		(drill 0.3048)
		(layers "F.Cu" "B.Cu")
		(net "GND")
	)
	(via
		(at 188.701934 14.926056)
		(size 0.5588)
		(drill 0.3048)
		(layers "F.Cu" "B.Cu")
		(net "GND")
	)
	(via
		(at 418.1856 -3.4036)
		(size 0.508)
		(drill 0.254)
		(layers "F.Cu" "B.Cu")
		(net "GND")
	)
	(via
		(at 440.161934 11.624056)
		(size 0.5588)
		(drill 0.3048)
		(layers "F.Cu" "B.Cu")
		(net "GND")
	)
	(via
		(at 86.064852 -53.608732)
		(size 0.508)
		(drill 0.254)
		(layers "F.Cu" "B.Cu")
		(net "GND")
	)
	(via
		(at 283.499814 -60.362338)
		(size 0.508)
		(drill 0.254)
		(layers "F.Cu" "B.Cu")
		(net "GND")
	)
	(via
		(at 362.9914 -115.1636)
		(size 0.508)
		(drill 0.254)
		(layers "F.Cu" "B.Cu")
		(net "GND")
	)
	(via
		(at 271.480788 -63.334138)
		(size 0.508)
		(drill 0.254)
		(layers "F.Cu" "B.Cu")
		(net "GND")
	)
	(via
		(at 239.904778 -66.982086)
		(size 0.508)
		(drill 0.254)
		(layers "F.Cu" "B.Cu")
		(net "GND")
	)
	(via
		(at 429.651414 -3.359404)
		(size 0.508)
		(drill 0.254)
		(layers "F.Cu" "B.Cu")
		(net "GND")
	)
	(via
		(at 148.699474 -139.170156)
		(size 0.508)
		(drill 0.254)
		(layers "F.Cu" "B.Cu")
		(net "GND")
	)
	(via
		(at 382.78435 -116.953284)
		(size 0.508)
		(drill 0.254)
		(layers "F.Cu" "B.Cu")
		(net "GND")
	)
	(via
		(at 292.36924 -89.584784)
		(size 0.508)
		(drill 0.254)
		(layers "F.Cu" "B.Cu")
		(net "GND")
	)
	(via
		(at 90.911934 9.084056)
		(size 0.5588)
		(drill 0.3048)
		(layers "F.Cu" "B.Cu")
		(net "GND")
	)
	(via
		(at 292.36924 -100.481638)
		(size 0.508)
		(drill 0.254)
		(layers "F.Cu" "B.Cu")
		(net "GND")
	)
	(via
		(at 50.851308 -17.208246)
		(size 0.508)
		(drill 0.254)
		(layers "F.Cu" "B.Cu")
		(net "GND")
	)
	(via
		(at 209.092546 -136.397746)
		(size 0.508)
		(drill 0.254)
		(layers "F.Cu" "B.Cu")
		(net "GND")
	)
	(via
		(at 301.742602 -155.600146)
		(size 0.508)
		(drill 0.254)
		(layers "F.Cu" "B.Cu")
		(net "GND")
	)
	(via
		(at 77.299312 -13.363956)
		(size 0.508)
		(drill 0.254)
		(layers "F.Cu" "B.Cu")
		(net "GND")
	)
	(via
		(at 128.227328 -58.381138)
		(size 0.508)
		(drill 0.254)
		(layers "F.Cu" "B.Cu")
		(net "GND")
	)
	(via
		(at 40.948864 -53.221382)
		(size 0.5588)
		(drill 0.3048)
		(layers "F.Cu" "B.Cu")
		(net "GND")
	)
	(via
		(at 416.590734 -165.596824)
		(size 0.5588)
		(drill 0.3048)
		(layers "F.Cu" "B.Cu")
		(net "GND")
	)
	(via
		(at 36.040822 -7.095744)
		(size 0.508)
		(drill 0.254)
		(layers "F.Cu" "B.Cu")
		(net "GND")
	)
	(via
		(at 484.81361 -26.546048)
		(size 0.508)
		(drill 0.254)
		(layers "F.Cu" "B.Cu")
		(net "GND")
	)
	(via
		(at 4.784344 -112.21339)
		(size 0.508)
		(drill 0.254)
		(layers "F.Cu" "B.Cu")
		(net "GND")
	)
	(via
		(at 199.736456 -131.5466)
		(size 0.508)
		(drill 0.254)
		(layers "F.Cu" "B.Cu")
		(net "GND")
	)
	(via
		(at 299.160946 -3.737356)
		(size 0.508)
		(drill 0.254)
		(layers "F.Cu" "B.Cu")
		(net "GND")
	)
	(via
		(at 360.705654 -100.643944)
		(size 0.508)
		(drill 0.254)
		(layers "F.Cu" "B.Cu")
		(net "GND")
	)
	(via
		(at 188.142372 -38.343078)
		(size 0.508)
		(drill 0.254)
		(layers "F.Cu" "B.Cu")
		(net "GND")
	)
	(via
		(at 6.99135 -19.778218)
		(size 0.508)
		(drill 0.254)
		(layers "F.Cu" "B.Cu")
		(net "GND")
	)
	(via
		(at 4.0132 -146.1262)
		(size 0.508)
		(drill 0.254)
		(layers "F.Cu" "B.Cu")
		(net "GND")
	)
	(via
		(at 291.51072 -91.070938)
		(size 0.508)
		(drill 0.254)
		(layers "F.Cu" "B.Cu")
		(net "GND")
	)
	(via
		(at 489.691934 12.894056)
		(size 0.5588)
		(drill 0.3048)
		(layers "F.Cu" "B.Cu")
		(net "GND")
	)
	(via
		(at 303.041304 -134.349744)
		(size 0.508)
		(drill 0.254)
		(layers "F.Cu" "B.Cu")
		(net "GND")
	)
	(via
		(at 243.338604 -86.794086)
		(size 0.508)
		(drill 0.254)
		(layers "F.Cu" "B.Cu")
		(net "GND")
	)
	(via
		(at 93.791278 -64.010286)
		(size 0.508)
		(drill 0.254)
		(layers "F.Cu" "B.Cu")
		(net "GND")
	)
	(via
		(at 239.046258 -86.29904)
		(size 0.508)
		(drill 0.254)
		(layers "F.Cu" "B.Cu")
		(net "GND")
	)
	(via
		(at 75.762866 -59.55284)
		(size 0.508)
		(drill 0.254)
		(layers "F.Cu" "B.Cu")
		(net "GND")
	)
	(via
		(at 37.34943 -9.156446)
		(size 0.508)
		(drill 0.254)
		(layers "F.Cu" "B.Cu")
		(net "GND")
	)
	(via
		(at 103.678736 -17.7546)
		(size 0.508)
		(drill 0.254)
		(layers "F.Cu" "B.Cu")
		(net "GND")
	)
	(via
		(at 360.207052 -98.135694)
		(size 0.508)
		(drill 0.254)
		(layers "F.Cu" "B.Cu")
		(net "GND")
	)
	(via
		(at 35.499802 -74.168)
		(size 0.508)
		(drill 0.254)
		(layers "F.Cu" "B.Cu")
		(net "GND")
	)
	(via
		(at 182.51297 4.101338)
		(size 0.508)
		(drill 0.254)
		(layers "F.Cu" "B.Cu")
		(net "GND")
	)
	(via
		(at 386.8166 -151.7142)
		(size 0.508)
		(drill 0.254)
		(layers "F.Cu" "B.Cu")
		(net "GND")
	)
	(via
		(at 17.272 -28.194)
		(size 0.508)
		(drill 0.254)
		(layers "F.Cu" "B.Cu")
		(net "GND")
	)
	(via
		(at 22.101302 -110.838234)
		(size 0.5588)
		(drill 0.3048)
		(layers "F.Cu" "B.Cu")
		(net "GND")
	)
	(via
		(at 389.22325 -96.747076)
		(size 0.508)
		(drill 0.254)
		(layers "F.Cu" "B.Cu")
		(net "GND")
	)
	(via
		(at 421.395652 -24.158194)
		(size 0.508)
		(drill 0.254)
		(layers "F.Cu" "B.Cu")
		(net "GND")
	)
	(via
		(at 243.338604 -94.718886)
		(size 0.508)
		(drill 0.254)
		(layers "F.Cu" "B.Cu")
		(net "GND")
	)
	(via
		(at 251.923804 -69.953886)
		(size 0.508)
		(drill 0.254)
		(layers "F.Cu" "B.Cu")
		(net "GND")
	)
	(via
		(at 257.07467 -53.113686)
		(size 0.508)
		(drill 0.254)
		(layers "F.Cu" "B.Cu")
		(net "GND")
	)
	(via
		(at 78.14945 -9.133078)
		(size 0.508)
		(drill 0.254)
		(layers "F.Cu" "B.Cu")
		(net "GND")
	)
	(via
		(at 138.529314 -53.427884)
		(size 0.508)
		(drill 0.254)
		(layers "F.Cu" "B.Cu")
		(net "GND")
	)
	(via
		(at 318.241934 14.926056)
		(size 0.5588)
		(drill 0.3048)
		(layers "F.Cu" "B.Cu")
		(net "GND")
	)
	(via
		(at 133.378194 -76.211938)
		(size 0.508)
		(drill 0.254)
		(layers "F.Cu" "B.Cu")
		(net "GND")
	)
	(via
		(at 215.860884 -13.338556)
		(size 0.508)
		(drill 0.254)
		(layers "F.Cu" "B.Cu")
		(net "GND")
	)
	(via
		(at 121.925334 -167.832024)
		(size 0.5588)
		(drill 0.3048)
		(layers "F.Cu" "B.Cu")
		(net "GND")
	)
	(via
		(at 152.099518 -134.340346)
		(size 0.508)
		(drill 0.254)
		(layers "F.Cu" "B.Cu")
		(net "GND")
	)
	(via
		(at 72.142096 -124.623576)
		(size 0.508)
		(drill 0.254)
		(layers "F.Cu" "B.Cu")
		(net "GND")
	)
	(via
		(at 408.559 -18.462752)
		(size 0.508)
		(drill 0.254)
		(layers "F.Cu" "B.Cu")
		(net "GND")
	)
	(via
		(at 25.34158 -82.613246)
		(size 0.508)
		(drill 0.254)
		(layers "F.Cu" "B.Cu")
		(net "GND")
	)
	(via
		(at 121.074688 -58.876438)
		(size 0.508)
		(drill 0.254)
		(layers "F.Cu" "B.Cu")
		(net "GND")
	)
	(via
		(at 300.954186 -76.706984)
		(size 0.508)
		(drill 0.254)
		(layers "F.Cu" "B.Cu")
		(net "GND")
	)
	(via
		(at 71.470266 -65.991486)
		(size 0.508)
		(drill 0.254)
		(layers "F.Cu" "B.Cu")
		(net "GND")
	)
	(via
		(at 90.874088 -18.01749)
		(size 0.508)
		(drill 0.254)
		(layers "F.Cu" "B.Cu")
		(net "GND")
	)
	(via
		(at 235.612178 -52.618386)
		(size 0.508)
		(drill 0.254)
		(layers "F.Cu" "B.Cu")
		(net "GND")
	)
	(via
		(at 239.749838 -21.517356)
		(size 0.508)
		(drill 0.254)
		(layers "F.Cu" "B.Cu")
		(net "GND")
	)
	(via
		(at 294.9448 -78.193138)
		(size 0.508)
		(drill 0.254)
		(layers "F.Cu" "B.Cu")
		(net "GND")
	)
	(via
		(at 281.361896 -148.771356)
		(size 0.508)
		(drill 0.254)
		(layers "F.Cu" "B.Cu")
		(net "GND")
	)
	(via
		(at 0.22225 -52.921408)
		(size 0.5588)
		(drill 0.3048)
		(layers "F.Cu" "B.Cu")
		(net "GND")
	)
	(via
		(at 347.623384 -137.131806)
		(size 0.508)
		(drill 0.254)
		(layers "F.Cu" "B.Cu")
		(net "GND")
	)
	(via
		(at 497.65204 -128.52654)
		(size 0.508)
		(drill 0.254)
		(layers "F.Cu" "B.Cu")
		(net "GND")
	)
	(via
		(at 171.161456 -152.81021)
		(size 0.5588)
		(drill 0.3048)
		(layers "F.Cu" "B.Cu")
		(net "GND")
	)
	(via
		(at 128.227328 -61.352938)
		(size 0.508)
		(drill 0.254)
		(layers "F.Cu" "B.Cu")
		(net "GND")
	)
	(via
		(at 226.111816 -11.916156)
		(size 0.508)
		(drill 0.254)
		(layers "F.Cu" "B.Cu")
		(net "GND")
	)
	(via
		(at 274.056094 -53.923184)
		(size 0.508)
		(drill 0.254)
		(layers "F.Cu" "B.Cu")
		(net "GND")
	)
	(via
		(at 385.4704 -81.51876)
		(size 0.508)
		(drill 0.254)
		(layers "F.Cu" "B.Cu")
		(net "GND")
	)
	(via
		(at 3.013456 -15.949676)
		(size 0.508)
		(drill 0.254)
		(layers "F.Cu" "B.Cu")
		(net "GND")
	)
	(via
		(at 59.449462 -155.600146)
		(size 0.508)
		(drill 0.254)
		(layers "F.Cu" "B.Cu")
		(net "GND")
	)
	(via
		(at -3.588766 -59.746134)
		(size 0.5588)
		(drill 0.3048)
		(layers "F.Cu" "B.Cu")
		(net "GND")
	)
	(via
		(at 128.687576 -150.803356)
		(size 0.508)
		(drill 0.254)
		(layers "F.Cu" "B.Cu")
		(net "GND")
	)
	(via
		(at 97.915476 -82.339942)
		(size 0.5588)
		(drill 0.3048)
		(layers "F.Cu" "B.Cu")
		(net "GND")
	)
	(via
		(at 199.749156 -153.6065)
		(size 0.508)
		(drill 0.254)
		(layers "F.Cu" "B.Cu")
		(net "GND")
	)
	(via
		(at 234.421934 9.084056)
		(size 0.5588)
		(drill 0.3048)
		(layers "F.Cu" "B.Cu")
		(net "GND")
	)
	(via
		(at 128.687576 -23.549356)
		(size 0.508)
		(drill 0.254)
		(layers "F.Cu" "B.Cu")
		(net "GND")
	)
	(via
		(at 286.07512 -63.829184)
		(size 0.508)
		(drill 0.254)
		(layers "F.Cu" "B.Cu")
		(net "GND")
	)
	(via
		(at 25.3746 -47.1678)
		(size 0.508)
		(drill 0.254)
		(layers "F.Cu" "B.Cu")
		(net "GND")
	)
	(via
		(at 200.880218 -88.906096)
		(size 0.508)
		(drill 0.254)
		(layers "F.Cu" "B.Cu")
		(net "GND")
	)
	(via
		(at 354.412804 -26.266902)
		(size 0.508)
		(drill 0.254)
		(layers "F.Cu" "B.Cu")
		(net "GND")
	)
	(via
		(at 128.674368 -11.938)
		(size 0.508)
		(drill 0.254)
		(layers "F.Cu" "B.Cu")
		(net "GND")
	)
	(via
		(at 50.271934 9.084056)
		(size 0.5588)
		(drill 0.3048)
		(layers "F.Cu" "B.Cu")
		(net "GND")
	)
	(via
		(at 342.088724 -162.243262)
		(size 0.5588)
		(drill 0.3048)
		(layers "F.Cu" "B.Cu")
		(net "GND")
	)
	(via
		(at 285.649924 -2.314956)
		(size 0.508)
		(drill 0.254)
		(layers "F.Cu" "B.Cu")
		(net "GND")
	)
	(via
		(at 122.349514 -18.757646)
		(size 0.508)
		(drill 0.254)
		(layers "F.Cu" "B.Cu")
		(net "GND")
	)
	(via
		(at 395.829282 -30.861)
		(size 0.508)
		(drill 0.254)
		(layers "F.Cu" "B.Cu")
		(net "GND")
	)
	(via
		(at 185.413396 -88.306402)
		(size 0.508)
		(drill 0.254)
		(layers "F.Cu" "B.Cu")
		(net "GND")
	)
	(via
		(at 243.338604 -83.822286)
		(size 0.508)
		(drill 0.254)
		(layers "F.Cu" "B.Cu")
		(net "GND")
	)
	(via
		(at 234.753658 -92.737686)
		(size 0.508)
		(drill 0.254)
		(layers "F.Cu" "B.Cu")
		(net "GND")
	)
	(via
		(at 229.091236 2.505456)
		(size 0.508)
		(drill 0.254)
		(layers "F.Cu" "B.Cu")
		(net "GND")
	)
	(via
		(at 208.122012 -154.1018)
		(size 0.508)
		(drill 0.254)
		(layers "F.Cu" "B.Cu")
		(net "GND")
	)
	(via
		(at 69.56044 -22.939756)
		(size 0.508)
		(drill 0.254)
		(layers "F.Cu" "B.Cu")
		(net "GND")
	)
	(via
		(at 291.422074 -27.829256)
		(size 0.508)
		(drill 0.254)
		(layers "F.Cu" "B.Cu")
		(net "GND")
	)
	(via
		(at 251.923804 -83.822286)
		(size 0.508)
		(drill 0.254)
		(layers "F.Cu" "B.Cu")
		(net "GND")
	)
	(via
		(at 383.77495 -120.387364)
		(size 0.508)
		(drill 0.254)
		(layers "F.Cu" "B.Cu")
		(net "GND")
	)
	(via
		(at 119.642382 -89.089738)
		(size 0.508)
		(drill 0.254)
		(layers "F.Cu" "B.Cu")
		(net "GND")
	)
	(via
		(at 118.851934 14.926056)
		(size 0.5588)
		(drill 0.3048)
		(layers "F.Cu" "B.Cu")
		(net "GND")
	)
	(via
		(at 88.393524 -162.243262)
		(size 0.5588)
		(drill 0.3048)
		(layers "F.Cu" "B.Cu")
		(net "GND")
	)
	(via
		(at 298.378626 -72.249538)
		(size 0.508)
		(drill 0.254)
		(layers "F.Cu" "B.Cu")
		(net "GND")
	)
	(via
		(at 70.461378 -136.410446)
		(size 0.508)
		(drill 0.254)
		(layers "F.Cu" "B.Cu")
		(net "GND")
	)
	(via
		(at 470.641934 9.084056)
		(size 0.5588)
		(drill 0.3048)
		(layers "F.Cu" "B.Cu")
		(net "GND")
	)
	(via
		(at 221.899734 -144.462246)
		(size 0.508)
		(drill 0.254)
		(layers "F.Cu" "B.Cu")
		(net "GND")
	)
	(via
		(at 479.531934 9.084056)
		(size 0.5588)
		(drill 0.3048)
		(layers "F.Cu" "B.Cu")
		(net "GND")
	)
	(via
		(at 437.621934 14.926056)
		(size 0.5588)
		(drill 0.3048)
		(layers "F.Cu" "B.Cu")
		(net "GND")
	)
	(via
		(at 152.949402 -150.774146)
		(size 0.508)
		(drill 0.254)
		(layers "F.Cu" "B.Cu")
		(net "GND")
	)
	(via
		(at 227.799138 2.4511)
		(size 0.508)
		(drill 0.254)
		(layers "F.Cu" "B.Cu")
		(net "GND")
	)
	(via
		(at 274.056348 -56.894984)
		(size 0.508)
		(drill 0.254)
		(layers "F.Cu" "B.Cu")
		(net "GND")
	)
	(via
		(at 356.4382 -77.37856)
		(size 0.508)
		(drill 0.254)
		(layers "F.Cu" "B.Cu")
		(net "GND")
	)
	(via
		(at 115.636802 -50.3047)
		(size 0.508)
		(drill 0.254)
		(layers "F.Cu" "B.Cu")
		(net "GND")
	)
	(via
		(at 294.031924 -162.243262)
		(size 0.5588)
		(drill 0.3048)
		(layers "F.Cu" "B.Cu")
		(net "GND")
	)
	(via
		(at 454.690734 -163.361624)
		(size 0.5588)
		(drill 0.3048)
		(layers "F.Cu" "B.Cu")
		(net "GND")
	)
	(via
		(at 78.338172 -64.010286)
		(size 0.508)
		(drill 0.254)
		(layers "F.Cu" "B.Cu")
		(net "GND")
	)
	(via
		(at 135.953754 -83.641184)
		(size 0.508)
		(drill 0.254)
		(layers "F.Cu" "B.Cu")
		(net "GND")
	)
	(via
		(at 235.46181 -146.011646)
		(size 0.508)
		(drill 0.254)
		(layers "F.Cu" "B.Cu")
		(net "GND")
	)
	(via
		(at 3.459734 -167.832024)
		(size 0.5588)
		(drill 0.3048)
		(layers "F.Cu" "B.Cu")
		(net "GND")
	)
	(via
		(at 117.353842 -50.375058)
		(size 0.508)
		(drill 0.254)
		(layers "F.Cu" "B.Cu")
		(net "GND")
	)
	(via
		(at 170.7388 -83.7692)
		(size 0.508)
		(drill 0.254)
		(layers "F.Cu" "B.Cu")
		(net "GND")
	)
	(via
		(at 120.500902 -85.622384)
		(size 0.508)
		(drill 0.254)
		(layers "F.Cu" "B.Cu")
		(net "GND")
	)
	(via
		(at 167.25646 -29.319728)
		(size 0.508)
		(drill 0.254)
		(layers "F.Cu" "B.Cu")
		(net "GND")
	)
	(via
		(at 391.20445 -117.811804)
		(size 0.508)
		(drill 0.254)
		(layers "F.Cu" "B.Cu")
		(net "GND")
	)
	(via
		(at 398.225518 -126.93269)
		(size 0.508)
		(drill 0.254)
		(layers "F.Cu" "B.Cu")
		(net "GND")
	)
	(via
		(at 207.137 -76.5048)
		(size 0.5588)
		(drill 0.3048)
		(layers "F.Cu" "B.Cu")
		(net "GND")
	)
	(via
		(at 326.442324 -162.243262)
		(size 0.5588)
		(drill 0.3048)
		(layers "F.Cu" "B.Cu")
		(net "GND")
	)
	(via
		(at 208.122012 -140.605256)
		(size 0.508)
		(drill 0.254)
		(layers "F.Cu" "B.Cu")
		(net "GND")
	)
	(via
		(at 66.249296 -27.935936)
		(size 0.508)
		(drill 0.254)
		(layers "F.Cu" "B.Cu")
		(net "GND")
	)
	(via
		(at 499.140734 -164.479224)
		(size 0.5588)
		(drill 0.3048)
		(layers "F.Cu" "B.Cu")
		(net "GND")
	)
	(via
		(at 138.03757 -141.202156)
		(size 0.508)
		(drill 0.254)
		(layers "F.Cu" "B.Cu")
		(net "GND")
	)
	(via
		(at 151.871934 9.084056)
		(size 0.5588)
		(drill 0.3048)
		(layers "F.Cu" "B.Cu")
		(net "GND")
	)
	(via
		(at 120.649492 -11.916156)
		(size 0.508)
		(drill 0.254)
		(layers "F.Cu" "B.Cu")
		(net "GND")
	)
	(via
		(at 297.520106 -52.932838)
		(size 0.508)
		(drill 0.254)
		(layers "F.Cu" "B.Cu")
		(net "GND")
	)
	(via
		(at 103.557324 -53.113686)
		(size 0.508)
		(drill 0.254)
		(layers "F.Cu" "B.Cu")
		(net "GND")
	)
	(via
		(at 394.95603 -33.8836)
		(size 0.508)
		(drill 0.254)
		(layers "F.Cu" "B.Cu")
		(net "GND")
	)
	(via
		(at 383.27965 -119.528844)
		(size 0.508)
		(drill 0.254)
		(layers "F.Cu" "B.Cu")
		(net "GND")
	)
	(via
		(at 41.501314 -144.462246)
		(size 0.508)
		(drill 0.254)
		(layers "F.Cu" "B.Cu")
		(net "GND")
	)
	(via
		(at -2.916936 -59.74461)
		(size 0.5588)
		(drill 0.3048)
		(layers "F.Cu" "B.Cu")
		(net "GND")
	)
	(via
		(at 213.399878 -11.916156)
		(size 0.508)
		(drill 0.254)
		(layers "F.Cu" "B.Cu")
		(net "GND")
	)
	(via
		(at 454.62698 -45.560996)
		(size 0.508)
		(drill 0.254)
		(layers "F.Cu" "B.Cu")
		(net "GND")
	)
	(via
		(at 60.210446 -22.939756)
		(size 0.508)
		(drill 0.254)
		(layers "F.Cu" "B.Cu")
		(net "GND")
	)
	(via
		(at 35.880294 -73.679304)
		(size 0.508)
		(drill 0.254)
		(layers "F.Cu" "B.Cu")
		(net "GND")
	)
	(via
		(at 6.575044 -18.152618)
		(size 0.508)
		(drill 0.254)
		(layers "F.Cu" "B.Cu")
		(net "GND")
	)
	(via
		(at 5.832856 11.373866)
		(size 0.5588)
		(drill 0.3048)
		(layers "F.Cu" "B.Cu")
		(net "GND")
	)
	(via
		(at 245.055644 -78.869286)
		(size 0.508)
		(drill 0.254)
		(layers "F.Cu" "B.Cu")
		(net "GND")
	)
	(via
		(at 245.055644 -81.841086)
		(size 0.508)
		(drill 0.254)
		(layers "F.Cu" "B.Cu")
		(net "GND")
	)
	(via
		(at 146.086068 -23.495)
		(size 0.508)
		(drill 0.254)
		(layers "F.Cu" "B.Cu")
		(net "GND")
	)
	(via
		(at 430.001934 12.894056)
		(size 0.5588)
		(drill 0.3048)
		(layers "F.Cu" "B.Cu")
		(net "GND")
	)
	(via
		(at 140.246354 -65.315338)
		(size 0.508)
		(drill 0.254)
		(layers "F.Cu" "B.Cu")
		(net "GND")
	)
	(via
		(at 283.499814 -67.296538)
		(size 0.508)
		(drill 0.254)
		(layers "F.Cu" "B.Cu")
		(net "GND")
	)
	(via
		(at 207.414622 -90.47734)
		(size 0.5588)
		(drill 0.3048)
		(layers "F.Cu" "B.Cu")
		(net "GND")
	)
	(via
		(at 117.353842 -68.858638)
		(size 0.508)
		(drill 0.254)
		(layers "F.Cu" "B.Cu")
		(net "GND")
	)
	(via
		(at 488.980734 -166.714424)
		(size 0.5588)
		(drill 0.3048)
		(layers "F.Cu" "B.Cu")
		(net "GND")
	)
	(via
		(at 252.782324 -67.47764)
		(size 0.508)
		(drill 0.254)
		(layers "F.Cu" "B.Cu")
		(net "GND")
	)
	(via
		(at 69.753226 -63.019686)
		(size 0.508)
		(drill 0.254)
		(layers "F.Cu" "B.Cu")
		(net "GND")
	)
	(via
		(at 453.545448 -2.725166)
		(size 0.508)
		(drill 0.254)
		(layers "F.Cu" "B.Cu")
		(net "GND")
	)
	(via
		(at 117.588792 -80.073754)
		(size 0.508)
		(drill 0.254)
		(layers "F.Cu" "B.Cu")
		(net "GND")
	)
	(via
		(at 262.361934 9.084056)
		(size 0.5588)
		(drill 0.3048)
		(layers "F.Cu" "B.Cu")
		(net "GND")
	)
	(via
		(at 181.227222 -106.794046)
		(size 0.508)
		(drill 0.254)
		(layers "F.Cu" "B.Cu")
		(net "GND")
	)
	(via
		(at 35.031934 14.926056)
		(size 0.5588)
		(drill 0.3048)
		(layers "F.Cu" "B.Cu")
		(net "GND")
	)
	(via
		(at 198.861934 9.084056)
		(size 0.5588)
		(drill 0.3048)
		(layers "F.Cu" "B.Cu")
		(net "GND")
	)
	(via
		(at 350.647 -13.843)
		(size 0.508)
		(drill 0.254)
		(layers "F.Cu" "B.Cu")
		(net "GND")
	)
	(via
		(at 223.599756 -17.208246)
		(size 0.508)
		(drill 0.254)
		(layers "F.Cu" "B.Cu")
		(net "GND")
	)
	(via
		(at 212.54974 -134.861046)
		(size 0.508)
		(drill 0.254)
		(layers "F.Cu" "B.Cu")
		(net "GND")
	)
	(via
		(at 74.401934 9.084056)
		(size 0.5588)
		(drill 0.3048)
		(layers "F.Cu" "B.Cu")
		(net "GND")
	)
	(via
		(at 384.76555 -97.605596)
		(size 0.508)
		(drill 0.254)
		(layers "F.Cu" "B.Cu")
		(net "GND")
	)
	(via
		(at 203.3524 -54.1274)
		(size 0.5588)
		(drill 0.3048)
		(layers "F.Cu" "B.Cu")
		(net "GND")
	)
	(via
		(at 242.626134 -167.832024)
		(size 0.5588)
		(drill 0.3048)
		(layers "F.Cu" "B.Cu")
		(net "GND")
	)
	(via
		(at 119.642382 -99.986338)
		(size 0.508)
		(drill 0.254)
		(layers "F.Cu" "B.Cu")
		(net "GND")
	)
	(via
		(at 113.726976 -154.23388)
		(size 0.508)
		(drill 0.254)
		(layers "F.Cu" "B.Cu")
		(net "GND")
	)
	(via
		(at 260.50875 -98.681286)
		(size 0.508)
		(drill 0.254)
		(layers "F.Cu" "B.Cu")
		(net "GND")
	)
	(via
		(at 269.981934 14.926056)
		(size 0.5588)
		(drill 0.3048)
		(layers "F.Cu" "B.Cu")
		(net "GND")
	)
	(via
		(at 191.897 -11.8618)
		(size 0.508)
		(drill 0.254)
		(layers "F.Cu" "B.Cu")
		(net "GND")
	)
	(via
		(at 52.634134 -167.832024)
		(size 0.5588)
		(drill 0.3048)
		(layers "F.Cu" "B.Cu")
		(net "GND")
	)
	(via
		(at 128.690878 -26.682954)
		(size 0.508)
		(drill 0.254)
		(layers "F.Cu" "B.Cu")
		(net "GND")
	)
	(via
		(at 24.765 -47.1678)
		(size 0.508)
		(drill 0.254)
		(layers "F.Cu" "B.Cu")
		(net "GND")
	)
	(via
		(at 64.087502 -124.590556)
		(size 0.508)
		(drill 0.254)
		(layers "F.Cu" "B.Cu")
		(net "GND")
	)
	(via
		(at 5.694934 -163.361624)
		(size 0.5588)
		(drill 0.3048)
		(layers "F.Cu" "B.Cu")
		(net "GND")
	)
	(via
		(at 239.046258 -63.51524)
		(size 0.508)
		(drill 0.254)
		(layers "F.Cu" "B.Cu")
		(net "GND")
	)
	(via
		(at 378.82195 -97.605596)
		(size 0.508)
		(drill 0.254)
		(layers "F.Cu" "B.Cu")
		(net "GND")
	)
	(via
		(at 347.712538 -79.754222)
		(size 0.508)
		(drill 0.254)
		(layers "F.Cu" "B.Cu")
		(net "GND")
	)
	(via
		(at 236.470698 -87.784686)
		(size 0.508)
		(drill 0.254)
		(layers "F.Cu" "B.Cu")
		(net "GND")
	)
	(via
		(at 109.914182 -60.362338)
		(size 0.508)
		(drill 0.254)
		(layers "F.Cu" "B.Cu")
		(net "GND")
	)
	(via
		(at 174.915322 -57.39892)
		(size 0.508)
		(drill 0.254)
		(layers "F.Cu" "B.Cu")
		(net "GND")
	)
	(via
		(at 345.735402 -137.173208)
		(size 0.508)
		(drill 0.254)
		(layers "F.Cu" "B.Cu")
		(net "GND")
	)
	(via
		(at 341.1474 -143.8402)
		(size 0.508)
		(drill 0.254)
		(layers "F.Cu" "B.Cu")
		(net "GND")
	)
	(via
		(at 443.256924 -162.243262)
		(size 0.5588)
		(drill 0.3048)
		(layers "F.Cu" "B.Cu")
		(net "GND")
	)
	(via
		(at 294.9448 -83.146138)
		(size 0.508)
		(drill 0.254)
		(layers "F.Cu" "B.Cu")
		(net "GND")
	)
	(via
		(at 307.898546 -90.575638)
		(size 0.508)
		(drill 0.254)
		(layers "F.Cu" "B.Cu")
		(net "GND")
	)
	(via
		(at 124.049536 -139.170156)
		(size 0.508)
		(drill 0.254)
		(layers "F.Cu" "B.Cu")
		(net "GND")
	)
	(via
		(at 419.130734 -165.596824)
		(size 0.5588)
		(drill 0.3048)
		(layers "F.Cu" "B.Cu")
		(net "GND")
	)
	(via
		(at 83.489292 -83.822286)
		(size 0.508)
		(drill 0.254)
		(layers "F.Cu" "B.Cu")
		(net "GND")
	)
	(via
		(at 440.720734 -166.714424)
		(size 0.5588)
		(drill 0.3048)
		(layers "F.Cu" "B.Cu")
		(net "GND")
	)
	(via
		(at 7.7724 3.048)
		(size 0.508)
		(drill 0.254)
		(layers "F.Cu" "B.Cu")
		(net "GND")
	)
	(via
		(at 293.688008 -150.803356)
		(size 0.508)
		(drill 0.254)
		(layers "F.Cu" "B.Cu")
		(net "GND")
	)
	(via
		(at 286.07512 -58.876438)
		(size 0.508)
		(drill 0.254)
		(layers "F.Cu" "B.Cu")
		(net "GND")
	)
	(via
		(at 127.392176 0.457454)
		(size 0.508)
		(drill 0.254)
		(layers "F.Cu" "B.Cu")
		(net "GND")
	)
	(via
		(at 493.7506 -60.579)
		(size 0.508)
		(drill 0.254)
		(layers "F.Cu" "B.Cu")
		(net "GND")
	)
	(via
		(at 303.529746 -98.005138)
		(size 0.508)
		(drill 0.254)
		(layers "F.Cu" "B.Cu")
		(net "GND")
	)
	(via
		(at 90.861896 -145.281142)
		(size 0.508)
		(drill 0.254)
		(layers "F.Cu" "B.Cu")
		(net "GND")
	)
	(via
		(at 202.671934 14.926056)
		(size 0.5588)
		(drill 0.3048)
		(layers "F.Cu" "B.Cu")
		(net "GND")
	)
	(via
		(at 428.020734 -165.596824)
		(size 0.5588)
		(drill 0.3048)
		(layers "F.Cu" "B.Cu")
		(net "GND")
	)
	(via
		(at 38.101524 -162.243262)
		(size 0.5588)
		(drill 0.3048)
		(layers "F.Cu" "B.Cu")
		(net "GND")
	)
	(via
		(at 215.2904 -76.1746)
		(size 0.508)
		(drill 0.254)
		(layers "F.Cu" "B.Cu")
		(net "GND")
	)
	(via
		(at 201.031856 -21.5138)
		(size 0.508)
		(drill 0.254)
		(layers "F.Cu" "B.Cu")
		(net "GND")
	)
	(via
		(at 283.784294 -95.528384)
		(size 0.508)
		(drill 0.254)
		(layers "F.Cu" "B.Cu")
		(net "GND")
	)
	(via
		(at 293.22776 -61.352938)
		(size 0.508)
		(drill 0.254)
		(layers "F.Cu" "B.Cu")
		(net "GND")
	)
	(via
		(at 39.049452 -139.170156)
		(size 0.508)
		(drill 0.254)
		(layers "F.Cu" "B.Cu")
		(net "GND")
	)
	(via
		(at 185.15076 -116.282724)
		(size 0.508)
		(drill 0.254)
		(layers "F.Cu" "B.Cu")
		(net "GND")
	)
	(via
		(at 368.685064 -8.84682)
		(size 0.508)
		(drill 0.254)
		(layers "F.Cu" "B.Cu")
		(net "GND")
	)
	(via
		(at 458.216 -126.536704)
		(size 0.508)
		(drill 0.254)
		(layers "F.Cu" "B.Cu")
		(net "GND")
	)
	(via
		(at 211.699856 -146.011646)
		(size 0.508)
		(drill 0.254)
		(layers "F.Cu" "B.Cu")
		(net "GND")
	)
	(via
		(at 200.515728 -81.2546)
		(size 0.508)
		(drill 0.254)
		(layers "F.Cu" "B.Cu")
		(net "GND")
	)
	(via
		(at 398.13865 -107.049316)
		(size 0.508)
		(drill 0.254)
		(layers "F.Cu" "B.Cu")
		(net "GND")
	)
	(via
		(at 177.165 -11.43)
		(size 0.508)
		(drill 0.254)
		(layers "F.Cu" "B.Cu")
		(net "GND")
	)
	(via
		(at 232.94975 -134.861046)
		(size 0.508)
		(drill 0.254)
		(layers "F.Cu" "B.Cu")
		(net "GND")
	)
	(via
		(at 68.036186 -89.765886)
		(size 0.508)
		(drill 0.254)
		(layers "F.Cu" "B.Cu")
		(net "GND")
	)
	(via
		(at 240.599722 -17.208246)
		(size 0.508)
		(drill 0.254)
		(layers "F.Cu" "B.Cu")
		(net "GND")
	)
	(via
		(at 406.782016 -150.247604)
		(size 0.508)
		(drill 0.254)
		(layers "F.Cu" "B.Cu")
		(net "GND")
	)
	(via
		(at 233.799888 -129.568956)
		(size 0.508)
		(drill 0.254)
		(layers "F.Cu" "B.Cu")
		(net "GND")
	)
	(via
		(at 282.925774 -100.976684)
		(size 0.508)
		(drill 0.254)
		(layers "F.Cu" "B.Cu")
		(net "GND")
	)
	(via
		(at 305.246786 -63.334138)
		(size 0.508)
		(drill 0.254)
		(layers "F.Cu" "B.Cu")
		(net "GND")
	)
	(via
		(at 175.2854 -146.26844)
		(size 0.508)
		(drill 0.254)
		(layers "F.Cu" "B.Cu")
		(net "GND")
	)
	(via
		(at 329.7174 -151.9682)
		(size 0.508)
		(drill 0.254)
		(layers "F.Cu" "B.Cu")
		(net "GND")
	)
	(via
		(at 212.54974 -17.208246)
		(size 0.508)
		(drill 0.254)
		(layers "F.Cu" "B.Cu")
		(net "GND")
	)
	(via
		(at 145.12163 1.9558)
		(size 0.508)
		(drill 0.254)
		(layers "F.Cu" "B.Cu")
		(net "GND")
	)
	(via
		(at 286.07512 -65.810384)
		(size 0.508)
		(drill 0.254)
		(layers "F.Cu" "B.Cu")
		(net "GND")
	)
	(via
		(at 384.884676 -23.191724)
		(size 0.508)
		(drill 0.254)
		(layers "F.Cu" "B.Cu")
		(net "GND")
	)
	(via
		(at 34.748724 2.4511)
		(size 0.508)
		(drill 0.254)
		(layers "F.Cu" "B.Cu")
		(net "GND")
	)
	(via
		(at 138.529314 -71.258938)
		(size 0.508)
		(drill 0.254)
		(layers "F.Cu" "B.Cu")
		(net "GND")
	)
	(via
		(at 294.08628 -68.782184)
		(size 0.508)
		(drill 0.254)
		(layers "F.Cu" "B.Cu")
		(net "GND")
	)
	(via
		(at 45.387514 -150.803356)
		(size 0.508)
		(drill 0.254)
		(layers "F.Cu" "B.Cu")
		(net "GND")
	)
	(via
		(at 184.778396 -85.182202)
		(size 0.508)
		(drill 0.254)
		(layers "F.Cu" "B.Cu")
		(net "GND")
	)
	(via
		(at 344.1954 -38.1)
		(size 0.508)
		(drill 0.254)
		(layers "F.Cu" "B.Cu")
		(net "GND")
	)
	(via
		(at 200.515728 -64.008)
		(size 0.508)
		(drill 0.254)
		(layers "F.Cu" "B.Cu")
		(net "GND")
	)
	(via
		(at 135.095234 -101.967538)
		(size 0.508)
		(drill 0.254)
		(layers "F.Cu" "B.Cu")
		(net "GND")
	)
	(via
		(at 337.8454 -112.395)
		(size 0.508)
		(drill 0.254)
		(layers "F.Cu" "B.Cu")
		(net "GND")
	)
	(via
		(at 35.880802 -67.618864)
		(size 0.508)
		(drill 0.254)
		(layers "F.Cu" "B.Cu")
		(net "GND")
	)
	(via
		(at 307.749956 -136.397746)
		(size 0.508)
		(drill 0.254)
		(layers "F.Cu" "B.Cu")
		(net "GND")
	)
	(via
		(at 239.501934 14.926056)
		(size 0.5588)
		(drill 0.3048)
		(layers "F.Cu" "B.Cu")
		(net "GND")
	)
	(via
		(at 36.17595 -60.183522)
		(size 0.5588)
		(drill 0.3048)
		(layers "F.Cu" "B.Cu")
		(net "GND")
	)
	(via
		(at 294.999918 -2.314956)
		(size 0.508)
		(drill 0.254)
		(layers "F.Cu" "B.Cu")
		(net "GND")
	)
	(via
		(at 42.25036 -95.19539)
		(size 0.5588)
		(drill 0.3048)
		(layers "F.Cu" "B.Cu")
		(net "GND")
	)
	(via
		(at 42.651934 9.084056)
		(size 0.5588)
		(drill 0.3048)
		(layers "F.Cu" "B.Cu")
		(net "GND")
	)
	(via
		(at 136.748774 -16.7513)
		(size 0.508)
		(drill 0.254)
		(layers "F.Cu" "B.Cu")
		(net "GND")
	)
	(via
		(at 374.523 -92.837)
		(size 0.508)
		(drill 0.254)
		(layers "F.Cu" "B.Cu")
		(net "GND")
	)
	(via
		(at 132.549392 1.994154)
		(size 0.508)
		(drill 0.254)
		(layers "F.Cu" "B.Cu")
		(net "GND")
	)
	(via
		(at 73.440798 -16.696944)
		(size 0.508)
		(drill 0.254)
		(layers "F.Cu" "B.Cu")
		(net "GND")
	)
	(via
		(at 136.812274 -60.362338)
		(size 0.508)
		(drill 0.254)
		(layers "F.Cu" "B.Cu")
		(net "GND")
	)
	(via
		(at 312.3819 -21.5138)
		(size 0.508)
		(drill 0.254)
		(layers "F.Cu" "B.Cu")
		(net "GND")
	)
	(via
		(at 97.851976 -128.022858)
		(size 0.508)
		(drill 0.254)
		(layers "F.Cu" "B.Cu")
		(net "GND")
	)
	(via
		(at 25.882092 -155.316682)
		(size 0.508)
		(drill 0.254)
		(layers "F.Cu" "B.Cu")
		(net "GND")
	)
	(via
		(at 104.415844 -95.21444)
		(size 0.508)
		(drill 0.254)
		(layers "F.Cu" "B.Cu")
		(net "GND")
	)
	(via
		(at 167.6146 -68.3768)
		(size 0.508)
		(drill 0.254)
		(layers "F.Cu" "B.Cu")
		(net "GND")
	)
	(via
		(at 182.70601 -60.732416)
		(size 0.508)
		(drill 0.254)
		(layers "F.Cu" "B.Cu")
		(net "GND")
	)
	(via
		(at 138.529314 -98.005138)
		(size 0.508)
		(drill 0.254)
		(layers "F.Cu" "B.Cu")
		(net "GND")
	)
	(via
		(at 119.070882 -69.849238)
		(size 0.508)
		(drill 0.254)
		(layers "F.Cu" "B.Cu")
		(net "GND")
	)
	(via
		(at 378.264166 -151.783034)
		(size 0.508)
		(drill 0.254)
		(layers "F.Cu" "B.Cu")
		(net "GND")
	)
	(via
		(at 224.744534 -167.832024)
		(size 0.5588)
		(drill 0.3048)
		(layers "F.Cu" "B.Cu")
		(net "GND")
	)
	(via
		(at 225.201734 -7.607046)
		(size 0.508)
		(drill 0.254)
		(layers "F.Cu" "B.Cu")
		(net "GND")
	)
	(via
		(at 379.1966 -1.016)
		(size 0.508)
		(drill 0.254)
		(layers "F.Cu" "B.Cu")
		(net "GND")
	)
	(via
		(at 103.611934 9.084056)
		(size 0.5588)
		(drill 0.3048)
		(layers "F.Cu" "B.Cu")
		(net "GND")
	)
	(via
		(at 64.094106 -28.66771)
		(size 0.508)
		(drill 0.254)
		(layers "F.Cu" "B.Cu")
		(net "GND")
	)
	(via
		(at 286.499808 -13.363956)
		(size 0.508)
		(drill 0.254)
		(layers "F.Cu" "B.Cu")
		(net "GND")
	)
	(via
		(at 290.6522 -87.603584)
		(size 0.508)
		(drill 0.254)
		(layers "F.Cu" "B.Cu")
		(net "GND")
	)
	(via
		(at 229.094538 -136.3345)
		(size 0.508)
		(drill 0.254)
		(layers "F.Cu" "B.Cu")
		(net "GND")
	)
	(via
		(at 459.210664 -14.45133)
		(size 0.5588)
		(drill 0.3048)
		(layers "F.Cu" "B.Cu")
		(net "GND")
	)
	(via
		(at 243.338604 -87.784686)
		(size 0.508)
		(drill 0.254)
		(layers "F.Cu" "B.Cu")
		(net "GND")
	)
	(via
		(at 484.1367 -144.5514)
		(size 0.508)
		(drill 0.254)
		(layers "F.Cu" "B.Cu")
		(net "GND")
	)
	(via
		(at 198.772018 -134.8994)
		(size 0.508)
		(drill 0.254)
		(layers "F.Cu" "B.Cu")
		(net "GND")
	)
	(via
		(at 136.73201 -4.2926)
		(size 0.508)
		(drill 0.254)
		(layers "F.Cu" "B.Cu")
		(net "GND")
	)
	(via
		(at 284.344364 -136.3345)
		(size 0.508)
		(drill 0.254)
		(layers "F.Cu" "B.Cu")
		(net "GND")
	)
	(via
		(at 285.091124 -162.243262)
		(size 0.5588)
		(drill 0.3048)
		(layers "F.Cu" "B.Cu")
		(net "GND")
	)
	(via
		(at 177.931318 -152.674066)
		(size 0.5588)
		(drill 0.3048)
		(layers "F.Cu" "B.Cu")
		(net "GND")
	)
	(via
		(at 119.34063 2.505456)
		(size 0.508)
		(drill 0.254)
		(layers "F.Cu" "B.Cu")
		(net "GND")
	)
	(via
		(at 97.261934 14.926056)
		(size 0.5588)
		(drill 0.3048)
		(layers "F.Cu" "B.Cu")
		(net "GND")
	)
	(via
		(at 151.24938 -144.462246)
		(size 0.508)
		(drill 0.254)
		(layers "F.Cu" "B.Cu")
		(net "GND")
	)
	(via
		(at 440.4106 -23.4188)
		(size 0.508)
		(drill 0.254)
		(layers "F.Cu" "B.Cu")
		(net "GND")
	)
	(via
		(at 115.065302 -62.343538)
		(size 0.508)
		(drill 0.254)
		(layers "F.Cu" "B.Cu")
		(net "GND")
	)
	(via
		(at 62.971934 14.926056)
		(size 0.5588)
		(drill 0.3048)
		(layers "F.Cu" "B.Cu")
		(net "GND")
	)
	(via
		(at 9.117584 -141.647672)
		(size 0.508)
		(drill 0.254)
		(layers "F.Cu" "B.Cu")
		(net "GND")
	)
	(via
		(at 6.858 -135.2042)
		(size 0.508)
		(drill 0.254)
		(layers "F.Cu" "B.Cu")
		(net "GND")
	)
	(via
		(at 31.908496 -56.167782)
		(size 0.508)
		(drill 0.254)
		(layers "F.Cu" "B.Cu")
		(net "GND")
	)
	(via
		(at 305.246786 -98.995738)
		(size 0.508)
		(drill 0.254)
		(layers "F.Cu" "B.Cu")
		(net "GND")
	)
	(via
		(at 252.782324 -81.34604)
		(size 0.508)
		(drill 0.254)
		(layers "F.Cu" "B.Cu")
		(net "GND")
	)
	(via
		(at 271.251934 9.084056)
		(size 0.5588)
		(drill 0.3048)
		(layers "F.Cu" "B.Cu")
		(net "GND")
	)
	(via
		(at 287.79216 -56.894984)
		(size 0.508)
		(drill 0.254)
		(layers "F.Cu" "B.Cu")
		(net "GND")
	)
	(via
		(at 123.076208 -82.155284)
		(size 0.508)
		(drill 0.254)
		(layers "F.Cu" "B.Cu")
		(net "GND")
	)
	(via
		(at 250.449334 -167.832024)
		(size 0.5588)
		(drill 0.3048)
		(layers "F.Cu" "B.Cu")
		(net "GND")
	)
	(via
		(at 138.040872 -134.349744)
		(size 0.508)
		(drill 0.254)
		(layers "F.Cu" "B.Cu")
		(net "GND")
	)
	(via
		(at 317.09995 -2.325878)
		(size 0.508)
		(drill 0.254)
		(layers "F.Cu" "B.Cu")
		(net "GND")
	)
	(via
		(at 403.886924 -162.243262)
		(size 0.5588)
		(drill 0.3048)
		(layers "F.Cu" "B.Cu")
		(net "GND")
	)
	(via
		(at 408.556206 -64.03213)
		(size 0.508)
		(drill 0.254)
		(layers "F.Cu" "B.Cu")
		(net "GND")
	)
	(via
		(at 156.49321 -27.518106)
		(size 0.508)
		(drill 0.254)
		(layers "F.Cu" "B.Cu")
		(net "GND")
	)
	(via
		(at 283.04236 -9.143746)
		(size 0.508)
		(drill 0.254)
		(layers "F.Cu" "B.Cu")
		(net "GND")
	)
	(via
		(at 298.506134 -167.832024)
		(size 0.5588)
		(drill 0.3048)
		(layers "F.Cu" "B.Cu")
		(net "GND")
	)
	(via
		(at 258.79171 -98.681286)
		(size 0.508)
		(drill 0.254)
		(layers "F.Cu" "B.Cu")
		(net "GND")
	)
	(via
		(at 199.992234 -87.811864)
		(size 0.508)
		(drill 0.254)
		(layers "F.Cu" "B.Cu")
		(net "GND")
	)
	(via
		(at 173.3296 -32.27959)
		(size 0.508)
		(drill 0.254)
		(layers "F.Cu" "B.Cu")
		(net "GND")
	)
	(via
		(at 439.450734 -165.596824)
		(size 0.5588)
		(drill 0.3048)
		(layers "F.Cu" "B.Cu")
		(net "GND")
	)
	(via
		(at 278.9682 -140.4874)
		(size 0.508)
		(drill 0.254)
		(layers "F.Cu" "B.Cu")
		(net "GND")
	)
	(via
		(at 69.753226 -95.709486)
		(size 0.508)
		(drill 0.254)
		(layers "F.Cu" "B.Cu")
		(net "GND")
	)
	(via
		(at 6.5278 -11.2776)
		(size 0.508)
		(drill 0.254)
		(layers "F.Cu" "B.Cu")
		(net "GND")
	)
	(via
		(at 271.216882 -70.84314)
		(size 0.5588)
		(drill 0.3048)
		(layers "F.Cu" "B.Cu")
		(net "GND")
	)
	(via
		(at 207.518 -64.135)
		(size 0.5588)
		(drill 0.3048)
		(layers "F.Cu" "B.Cu")
		(net "GND")
	)
	(via
		(at 186.060588 -133.174232)
		(size 0.508)
		(drill 0.254)
		(layers "F.Cu" "B.Cu")
		(net "GND")
	)
	(via
		(at 243.274596 -22.198076)
		(size 0.508)
		(drill 0.254)
		(layers "F.Cu" "B.Cu")
		(net "GND")
	)
	(via
		(at 43.12158 -17.2466)
		(size 0.508)
		(drill 0.254)
		(layers "F.Cu" "B.Cu")
		(net "GND")
	)
	(via
		(at 182.7784 -70.9676)
		(size 0.508)
		(drill 0.254)
		(layers "F.Cu" "B.Cu")
		(net "GND")
	)
	(via
		(at 186.060588 -133.809232)
		(size 0.508)
		(drill 0.254)
		(layers "F.Cu" "B.Cu")
		(net "GND")
	)
	(via
		(at 111.915702 -100.48113)
		(size 0.508)
		(drill 0.254)
		(layers "F.Cu" "B.Cu")
		(net "GND")
	)
	(via
		(at 98.083878 -63.51524)
		(size 0.508)
		(drill 0.254)
		(layers "F.Cu" "B.Cu")
		(net "GND")
	)
	(via
		(at 80.913732 -100.167186)
		(size 0.508)
		(drill 0.254)
		(layers "F.Cu" "B.Cu")
		(net "GND")
	)
	(via
		(at 118.041928 -18.744946)
		(size 0.508)
		(drill 0.254)
		(layers "F.Cu" "B.Cu")
		(net "GND")
	)
	(via
		(at 141.899386 -7.607046)
		(size 0.508)
		(drill 0.254)
		(layers "F.Cu" "B.Cu")
		(net "GND")
	)
	(via
		(at 34.991802 -55.299864)
		(size 0.508)
		(drill 0.254)
		(layers "F.Cu" "B.Cu")
		(net "GND")
	)
	(via
		(at 489.204 -53.9496)
		(size 0.508)
		(drill 0.254)
		(layers "F.Cu" "B.Cu")
		(net "GND")
	)
	(via
		(at 463.580734 -165.596824)
		(size 0.5588)
		(drill 0.3048)
		(layers "F.Cu" "B.Cu")
		(net "GND")
	)
	(via
		(at -5.207 -13.0302)
		(size 0.508)
		(drill 0.254)
		(layers "F.Cu" "B.Cu")
		(net "GND")
	)
	(via
		(at 69.551296 -7.607046)
		(size 0.508)
		(drill 0.254)
		(layers "F.Cu" "B.Cu")
		(net "GND")
	)
	(via
		(at 219.741242 -16.696944)
		(size 0.508)
		(drill 0.254)
		(layers "F.Cu" "B.Cu")
		(net "GND")
	)
	(via
		(at 219.741242 -143.950944)
		(size 0.508)
		(drill 0.254)
		(layers "F.Cu" "B.Cu")
		(net "GND")
	)
	(via
		(at 140.246354 -66.305938)
		(size 0.508)
		(drill 0.254)
		(layers "F.Cu" "B.Cu")
		(net "GND")
	)
	(via
		(at 465.97316 -131.9784)
		(size 0.508)
		(drill 0.254)
		(layers "F.Cu" "B.Cu")
		(net "GND")
	)
	(via
		(at 248.489724 -78.869286)
		(size 0.508)
		(drill 0.254)
		(layers "F.Cu" "B.Cu")
		(net "GND")
	)
	(via
		(at 211.561934 14.926056)
		(size 0.5588)
		(drill 0.3048)
		(layers "F.Cu" "B.Cu")
		(net "GND")
	)
	(via
		(at 444.548006 -40.5257)
		(size 0.508)
		(drill 0.254)
		(layers "F.Cu" "B.Cu")
		(net "GND")
	)
	(via
		(at 492.231934 14.926056)
		(size 0.5588)
		(drill 0.3048)
		(layers "F.Cu" "B.Cu")
		(net "GND")
	)
	(via
		(at 29.6926 -45.847)
		(size 0.508)
		(drill 0.254)
		(layers "F.Cu" "B.Cu")
		(net "GND")
	)
	(via
		(at 310.122062 -17.2466)
		(size 0.508)
		(drill 0.254)
		(layers "F.Cu" "B.Cu")
		(net "GND")
	)
	(via
		(at 370.311934 14.926056)
		(size 0.5588)
		(drill 0.3048)
		(layers "F.Cu" "B.Cu")
		(net "GND")
	)
	(via
		(at 174.448724 -162.243262)
		(size 0.5588)
		(drill 0.3048)
		(layers "F.Cu" "B.Cu")
		(net "GND")
	)
	(via
		(at 35.8648 -58.3184)
		(size 0.508)
		(drill 0.254)
		(layers "F.Cu" "B.Cu")
		(net "GND")
	)
	(via
		(at 237.142528 -148.767292)
		(size 0.508)
		(drill 0.254)
		(layers "F.Cu" "B.Cu")
		(net "GND")
	)
	(via
		(at 243.219732 -12.885166)
		(size 0.508)
		(drill 0.254)
		(layers "F.Cu" "B.Cu")
		(net "GND")
	)
	(via
		(at 139.387834 -79.678784)
		(size 0.508)
		(drill 0.254)
		(layers "F.Cu" "B.Cu")
		(net "GND")
	)
	(via
		(at 113.348262 -58.381138)
		(size 0.508)
		(drill 0.254)
		(layers "F.Cu" "B.Cu")
		(net "GND")
	)
	(via
		(at 42.11955 -62.164722)
		(size 0.5588)
		(drill 0.3048)
		(layers "F.Cu" "B.Cu")
		(net "GND")
	)
	(via
		(at 300.095666 -52.437538)
		(size 0.508)
		(drill 0.254)
		(layers "F.Cu" "B.Cu")
		(net "GND")
	)
	(via
		(at 203.199746 -131.016756)
		(size 0.508)
		(drill 0.254)
		(layers "F.Cu" "B.Cu")
		(net "GND")
	)
	(via
		(at 128.227328 -78.193138)
		(size 0.508)
		(drill 0.254)
		(layers "F.Cu" "B.Cu")
		(net "GND")
	)
	(via
		(at 476.4278 -30.861)
		(size 0.508)
		(drill 0.254)
		(layers "F.Cu" "B.Cu")
		(net "GND")
	)
	(via
		(at 140.441934 9.084056)
		(size 0.5588)
		(drill 0.3048)
		(layers "F.Cu" "B.Cu")
		(net "GND")
	)
	(via
		(at 496.596924 -162.243262)
		(size 0.5588)
		(drill 0.3048)
		(layers "F.Cu" "B.Cu")
		(net "GND")
	)
	(via
		(at 473.740734 -164.479224)
		(size 0.5588)
		(drill 0.3048)
		(layers "F.Cu" "B.Cu")
		(net "GND")
	)
	(via
		(at 224.449894 -2.314956)
		(size 0.508)
		(drill 0.254)
		(layers "F.Cu" "B.Cu")
		(net "GND")
	)
	(via
		(at 119.337328 -13.948156)
		(size 0.508)
		(drill 0.254)
		(layers "F.Cu" "B.Cu")
		(net "GND")
	)
	(via
		(at 485.881934 9.084056)
		(size 0.5588)
		(drill 0.3048)
		(layers "F.Cu" "B.Cu")
		(net "GND")
	)
	(via
		(at 74.045826 -94.223586)
		(size 0.508)
		(drill 0.254)
		(layers "F.Cu" "B.Cu")
		(net "GND")
	)
	(via
		(at 239.749838 -9.156446)
		(size 0.508)
		(drill 0.254)
		(layers "F.Cu" "B.Cu")
		(net "GND")
	)
	(via
		(at 170.815 -56.9214)
		(size 0.508)
		(drill 0.254)
		(layers "F.Cu" "B.Cu")
		(net "GND")
	)
	(via
		(at 445.800734 -166.714424)
		(size 0.5588)
		(drill 0.3048)
		(layers "F.Cu" "B.Cu")
		(net "GND")
	)
	(via
		(at 459.770734 -165.596824)
		(size 0.5588)
		(drill 0.3048)
		(layers "F.Cu" "B.Cu")
		(net "GND")
	)
	(via
		(at 452.861934 12.894056)
		(size 0.5588)
		(drill 0.3048)
		(layers "F.Cu" "B.Cu")
		(net "GND")
	)
	(via
		(at 17.438116 -30.14472)
		(size 0.508)
		(drill 0.254)
		(layers "F.Cu" "B.Cu")
		(net "GND")
	)
	(via
		(at 398.251934 14.926056)
		(size 0.5588)
		(drill 0.3048)
		(layers "F.Cu" "B.Cu")
		(net "GND")
	)
	(via
		(at 492.231934 12.894056)
		(size 0.5588)
		(drill 0.3048)
		(layers "F.Cu" "B.Cu")
		(net "GND")
	)
	(via
		(at 72.328786 -52.618386)
		(size 0.508)
		(drill 0.254)
		(layers "F.Cu" "B.Cu")
		(net "GND")
	)
	(via
		(at 299.237146 -102.462584)
		(size 0.508)
		(drill 0.254)
		(layers "F.Cu" "B.Cu")
		(net "GND")
	)
	(via
		(at 286.3596 -80.174338)
		(size 0.508)
		(drill 0.254)
		(layers "F.Cu" "B.Cu")
		(net "GND")
	)
	(via
		(at 421.9448 -154.2542)
		(size 0.508)
		(drill 0.254)
		(layers "F.Cu" "B.Cu")
		(net "GND")
	)
	(via
		(at 62.786006 -4.2926)
		(size 0.508)
		(drill 0.254)
		(layers "F.Cu" "B.Cu")
		(net "GND")
	)
	(via
		(at 215.2904 -60.5536)
		(size 0.508)
		(drill 0.254)
		(layers "F.Cu" "B.Cu")
		(net "GND")
	)
	(via
		(at 123.042934 -167.832024)
		(size 0.5588)
		(drill 0.3048)
		(layers "F.Cu" "B.Cu")
		(net "GND")
	)
	(via
		(at 469.930734 -163.361624)
		(size 0.5588)
		(drill 0.3048)
		(layers "F.Cu" "B.Cu")
		(net "GND")
	)
	(via
		(at 72.136 -141.1478)
		(size 0.508)
		(drill 0.254)
		(layers "F.Cu" "B.Cu")
		(net "GND")
	)
	(via
		(at 345.4908 -98.806)
		(size 0.508)
		(drill 0.254)
		(layers "F.Cu" "B.Cu")
		(net "GND")
	)
	(via
		(at 235.920534 -167.832024)
		(size 0.5588)
		(drill 0.3048)
		(layers "F.Cu" "B.Cu")
		(net "GND")
	)
	(via
		(at 135.771636 -27.829256)
		(size 0.508)
		(drill 0.254)
		(layers "F.Cu" "B.Cu")
		(net "GND")
	)
	(via
		(at 198.061834 -129.568956)
		(size 0.508)
		(drill 0.254)
		(layers "F.Cu" "B.Cu")
		(net "GND")
	)
	(via
		(at 208.122012 -150.206456)
		(size 0.508)
		(drill 0.254)
		(layers "F.Cu" "B.Cu")
		(net "GND")
	)
	(via
		(at 200.8886 -99.9236)
		(size 0.508)
		(drill 0.254)
		(layers "F.Cu" "B.Cu")
		(net "GND")
	)
	(via
		(at 287.21812 -89.584784)
		(size 0.508)
		(drill 0.254)
		(layers "F.Cu" "B.Cu")
		(net "GND")
	)
	(via
		(at 41.510458 -150.193756)
		(size 0.508)
		(drill 0.254)
		(layers "F.Cu" "B.Cu")
		(net "GND")
	)
	(via
		(at 84.347812 -71.44004)
		(size 0.508)
		(drill 0.254)
		(layers "F.Cu" "B.Cu")
		(net "GND")
	)
	(via
		(at 410.951934 9.084056)
		(size 0.5588)
		(drill 0.3048)
		(layers "F.Cu" "B.Cu")
		(net "GND")
	)
	(via
		(at 250.206764 -88.775286)
		(size 0.508)
		(drill 0.254)
		(layers "F.Cu" "B.Cu")
		(net "GND")
	)
	(via
		(at 449.610734 -164.479224)
		(size 0.5588)
		(drill 0.3048)
		(layers "F.Cu" "B.Cu")
		(net "GND")
	)
	(via
		(at 242.480338 -83.32724)
		(size 0.508)
		(drill 0.254)
		(layers "F.Cu" "B.Cu")
		(net "GND")
	)
	(via
		(at 53.442108 -136.397746)
		(size 0.508)
		(drill 0.254)
		(layers "F.Cu" "B.Cu")
		(net "GND")
	)
	(via
		(at 288.93516 -92.556584)
		(size 0.508)
		(drill 0.254)
		(layers "F.Cu" "B.Cu")
		(net "GND")
	)
	(via
		(at 462.351374 -63.626492)
		(size 0.508)
		(drill 0.254)
		(layers "F.Cu" "B.Cu")
		(net "GND")
	)
	(via
		(at 344.90152 -102.55504)
		(size 0.508)
		(drill 0.254)
		(layers "F.Cu" "B.Cu")
		(net "GND")
	)
	(via
		(at 70.611746 -72.43064)
		(size 0.508)
		(drill 0.254)
		(layers "F.Cu" "B.Cu")
		(net "GND")
	)
	(via
		(at 124.793248 -74.23023)
		(size 0.508)
		(drill 0.254)
		(layers "F.Cu" "B.Cu")
		(net "GND")
	)
	(via
		(at 218.449144 2.4511)
		(size 0.508)
		(drill 0.254)
		(layers "F.Cu" "B.Cu")
		(net "GND")
	)
	(via
		(at 427.461934 10.354056)
		(size 0.5588)
		(drill 0.3048)
		(layers "F.Cu" "B.Cu")
		(net "GND")
	)
	(via
		(at 280.141934 14.926056)
		(size 0.5588)
		(drill 0.3048)
		(layers "F.Cu" "B.Cu")
		(net "GND")
	)
	(via
		(at 30.53334 -134.4168)
		(size 0.508)
		(drill 0.254)
		(layers "F.Cu" "B.Cu")
		(net "GND")
	)
	(via
		(at 278.389334 -167.832024)
		(size 0.5588)
		(drill 0.3048)
		(layers "F.Cu" "B.Cu")
		(net "GND")
	)
	(via
		(at 122.349514 -21.517356)
		(size 0.508)
		(drill 0.254)
		(layers "F.Cu" "B.Cu")
		(net "GND")
	)
	(via
		(at 129.999486 -18.757646)
		(size 0.508)
		(drill 0.254)
		(layers "F.Cu" "B.Cu")
		(net "GND")
	)
	(via
		(at 303.529746 -71.258938)
		(size 0.508)
		(drill 0.254)
		(layers "F.Cu" "B.Cu")
		(net "GND")
	)
	(via
		(at 312.3946 -136.3345)
		(size 0.508)
		(drill 0.254)
		(layers "F.Cu" "B.Cu")
		(net "GND")
	)
	(via
		(at 110.745524 -162.243262)
		(size 0.5588)
		(drill 0.3048)
		(layers "F.Cu" "B.Cu")
		(net "GND")
	)
	(via
		(at 262.22579 -53.113686)
		(size 0.508)
		(drill 0.254)
		(layers "F.Cu" "B.Cu")
		(net "GND")
	)
	(via
		(at 54.869334 -167.832024)
		(size 0.5588)
		(drill 0.3048)
		(layers "F.Cu" "B.Cu")
		(net "GND")
	)
	(via
		(at 103.678736 -135.4074)
		(size 0.508)
		(drill 0.254)
		(layers "F.Cu" "B.Cu")
		(net "GND")
	)
	(via
		(at 72.142096 0.457454)
		(size 0.508)
		(drill 0.254)
		(layers "F.Cu" "B.Cu")
		(net "GND")
	)
	(via
		(at 294.9448 -94.042738)
		(size 0.508)
		(drill 0.254)
		(layers "F.Cu" "B.Cu")
		(net "GND")
	)
	(via
		(at 488.1372 -148.8694)
		(size 0.508)
		(drill 0.254)
		(layers "F.Cu" "B.Cu")
		(net "GND")
	)
	(via
		(at 269.444724 -162.243262)
		(size 0.5588)
		(drill 0.3048)
		(layers "F.Cu" "B.Cu")
		(net "GND")
	)
	(via
		(at 109.055916 -57.885584)
		(size 0.508)
		(drill 0.254)
		(layers "F.Cu" "B.Cu")
		(net "GND")
	)
	(via
		(at 311.0865 -131.5466)
		(size 0.508)
		(drill 0.254)
		(layers "F.Cu" "B.Cu")
		(net "GND")
	)
	(via
		(at 135.953754 -62.838584)
		(size 0.508)
		(drill 0.254)
		(layers "F.Cu" "B.Cu")
		(net "GND")
	)
	(via
		(at 295.849802 -140.617956)
		(size 0.508)
		(drill 0.254)
		(layers "F.Cu" "B.Cu")
		(net "GND")
	)
	(via
		(at 138.049762 0.508)
		(size 0.508)
		(drill 0.254)
		(layers "F.Cu" "B.Cu")
		(net "GND")
	)
	(via
		(at 205.8162 -76.5048)
		(size 0.5588)
		(drill 0.3048)
		(layers "F.Cu" "B.Cu")
		(net "GND")
	)
	(via
		(at 278.9174 -12.954)
		(size 0.508)
		(drill 0.254)
		(layers "F.Cu" "B.Cu")
		(net "GND")
	)
	(via
		(at 355.626924 -162.268662)
		(size 0.5588)
		(drill 0.3048)
		(layers "F.Cu" "B.Cu")
		(net "GND")
	)
	(via
		(at 421.09009 -38.134544)
		(size 0.4572)
		(drill 0.2032)
		(layers "F.Cu" "B.Cu")
		(net "GND")
	)
	(via
		(at 119.34063 -7.095744)
		(size 0.508)
		(drill 0.254)
		(layers "F.Cu" "B.Cu")
		(net "GND")
	)
	(via
		(at 181.2671 -138.1125)
		(size 0.508)
		(drill 0.254)
		(layers "F.Cu" "B.Cu")
		(net "GND")
	)
	(via
		(at 303.529746 -93.052138)
		(size 0.508)
		(drill 0.254)
		(layers "F.Cu" "B.Cu")
		(net "GND")
	)
	(via
		(at 291.51072 -88.099138)
		(size 0.508)
		(drill 0.254)
		(layers "F.Cu" "B.Cu")
		(net "GND")
	)
	(via
		(at 398.810734 -167.832024)
		(size 0.5588)
		(drill 0.3048)
		(layers "F.Cu" "B.Cu")
		(net "GND")
	)
	(via
		(at 74.045826 -99.17684)
		(size 0.508)
		(drill 0.254)
		(layers "F.Cu" "B.Cu")
		(net "GND")
	)
	(via
		(at 288.65068 -57.390538)
		(size 0.508)
		(drill 0.254)
		(layers "F.Cu" "B.Cu")
		(net "GND")
	)
	(via
		(at 137.670794 -81.659984)
		(size 0.508)
		(drill 0.254)
		(layers "F.Cu" "B.Cu")
		(net "GND")
	)
	(via
		(at 486.41762 -37.4015)
		(size 0.508)
		(drill 0.254)
		(layers "F.Cu" "B.Cu")
		(net "GND")
	)
	(via
		(at 272.624042 -101.968046)
		(size 0.508)
		(drill 0.254)
		(layers "F.Cu" "B.Cu")
		(net "GND")
	)
	(via
		(at 239.749838 -155.511246)
		(size 0.508)
		(drill 0.254)
		(layers "F.Cu" "B.Cu")
		(net "GND")
	)
	(via
		(at 263.08431 -89.27084)
		(size 0.508)
		(drill 0.254)
		(layers "F.Cu" "B.Cu")
		(net "GND")
	)
	(via
		(at 37.6428 -86.6902)
		(size 0.5588)
		(drill 0.3048)
		(layers "F.Cu" "B.Cu")
		(net "GND")
	)
	(via
		(at 115.460526 -22.939756)
		(size 0.508)
		(drill 0.254)
		(layers "F.Cu" "B.Cu")
		(net "GND")
	)
	(via
		(at 62.798706 -144.0053)
		(size 0.508)
		(drill 0.254)
		(layers "F.Cu" "B.Cu")
		(net "GND")
	)
	(via
		(at 290.74999 0.444754)
		(size 0.508)
		(drill 0.254)
		(layers "F.Cu" "B.Cu")
		(net "GND")
	)
	(via
		(at 398.63395 -109.624876)
		(size 0.508)
		(drill 0.254)
		(layers "F.Cu" "B.Cu")
		(net "GND")
	)
	(via
		(at 42.571924 -162.243262)
		(size 0.5588)
		(drill 0.3048)
		(layers "F.Cu" "B.Cu")
		(net "GND")
	)
	(via
		(at 396.65275 -109.624876)
		(size 0.508)
		(drill 0.254)
		(layers "F.Cu" "B.Cu")
		(net "GND")
	)
	(via
		(at 242.287044 -131.016756)
		(size 0.508)
		(drill 0.254)
		(layers "F.Cu" "B.Cu")
		(net "GND")
	)
	(via
		(at 272.801334 -167.832024)
		(size 0.5588)
		(drill 0.3048)
		(layers "F.Cu" "B.Cu")
		(net "GND")
	)
	(via
		(at -3.73126 -119.66956)
		(size 0.508)
		(drill 0.254)
		(layers "F.Cu" "B.Cu")
		(net "GND")
	)
	(via
		(at -2.916936 -58.98261)
		(size 0.5588)
		(drill 0.3048)
		(layers "F.Cu" "B.Cu")
		(net "GND")
	)
	(via
		(at 343.11082 -15.42542)
		(size 0.508)
		(drill 0.254)
		(layers "F.Cu" "B.Cu")
		(net "GND")
	)
	(via
		(at 395.2748 -153.0096)
		(size 0.508)
		(drill 0.254)
		(layers "F.Cu" "B.Cu")
		(net "GND")
	)
	(via
		(at -4.555744 11.424666)
		(size 0.5588)
		(drill 0.3048)
		(layers "F.Cu" "B.Cu")
		(net "GND")
	)
	(via
		(at 345.738196 -136.517634)
		(size 0.508)
		(drill 0.254)
		(layers "F.Cu" "B.Cu")
		(net "GND")
	)
	(via
		(at 275.061934 9.084056)
		(size 0.5588)
		(drill 0.3048)
		(layers "F.Cu" "B.Cu")
		(net "GND")
	)
	(via
		(at 251.065284 -74.411586)
		(size 0.508)
		(drill 0.254)
		(layers "F.Cu" "B.Cu")
		(net "GND")
	)
	(via
		(at 197.160896 -22.939756)
		(size 0.508)
		(drill 0.254)
		(layers "F.Cu" "B.Cu")
		(net "GND")
	)
	(via
		(at 405.160734 -163.361624)
		(size 0.5588)
		(drill 0.3048)
		(layers "F.Cu" "B.Cu")
		(net "GND")
	)
	(via
		(at 485.69626 -45.43298)
		(size 0.508)
		(drill 0.254)
		(layers "F.Cu" "B.Cu")
		(net "GND")
	)
	(via
		(at 120.649492 -129.568956)
		(size 0.508)
		(drill 0.254)
		(layers "F.Cu" "B.Cu")
		(net "GND")
	)
	(via
		(at 193.41592 -61.65088)
		(size 0.508)
		(drill 0.254)
		(layers "F.Cu" "B.Cu")
		(net "GND")
	)
	(via
		(at 15.057374 5.242814)
		(size 0.508)
		(drill 0.254)
		(layers "F.Cu" "B.Cu")
		(net "GND")
	)
	(via
		(at 367.4618 -98.5266)
		(size 0.508)
		(drill 0.254)
		(layers "F.Cu" "B.Cu")
		(net "GND")
	)
	(via
		(at 57.891934 14.926056)
		(size 0.5588)
		(drill 0.3048)
		(layers "F.Cu" "B.Cu")
		(net "GND")
	)
	(via
		(at 246.772684 -78.869286)
		(size 0.508)
		(drill 0.254)
		(layers "F.Cu" "B.Cu")
		(net "GND")
	)
	(via
		(at 82.630772 -71.44004)
		(size 0.508)
		(drill 0.254)
		(layers "F.Cu" "B.Cu")
		(net "GND")
	)
	(via
		(at 146.092164 -136.397746)
		(size 0.508)
		(drill 0.254)
		(layers "F.Cu" "B.Cu")
		(net "GND")
	)
	(via
		(at 430.001934 13.910056)
		(size 0.5588)
		(drill 0.3048)
		(layers "F.Cu" "B.Cu")
		(net "GND")
	)
	(via
		(at 485.881934 13.910056)
		(size 0.5588)
		(drill 0.3048)
		(layers "F.Cu" "B.Cu")
		(net "GND")
	)
	(via
		(at 476.991934 14.926056)
		(size 0.5588)
		(drill 0.3048)
		(layers "F.Cu" "B.Cu")
		(net "GND")
	)
	(via
		(at 136.748774 -153.6065)
		(size 0.508)
		(drill 0.254)
		(layers "F.Cu" "B.Cu")
		(net "GND")
	)
	(via
		(at 336.6262 -71.7804)
		(size 0.508)
		(drill 0.254)
		(layers "F.Cu" "B.Cu")
		(net "GND")
	)
	(via
		(at 226.822 -7.6454)
		(size 0.508)
		(drill 0.254)
		(layers "F.Cu" "B.Cu")
		(net "GND")
	)
	(via
		(at 293.22776 -91.070938)
		(size 0.508)
		(drill 0.254)
		(layers "F.Cu" "B.Cu")
		(net "GND")
	)
	(via
		(at 295.80332 -85.622384)
		(size 0.508)
		(drill 0.254)
		(layers "F.Cu" "B.Cu")
		(net "GND")
	)
	(via
		(at 65.511934 9.084056)
		(size 0.5588)
		(drill 0.3048)
		(layers "F.Cu" "B.Cu")
		(net "GND")
	)
	(via
		(at 145.12163 -3.762756)
		(size 0.508)
		(drill 0.254)
		(layers "F.Cu" "B.Cu")
		(net "GND")
	)
	(via
		(at -4.572 -66.7258)
		(size 0.508)
		(drill 0.254)
		(layers "F.Cu" "B.Cu")
		(net "GND")
	)
	(via
		(at 358.1781 -14.188186)
		(size 0.508)
		(drill 0.254)
		(layers "F.Cu" "B.Cu")
		(net "GND")
	)
	(via
		(at 99.744276 -70.841616)
		(size 0.5588)
		(drill 0.3048)
		(layers "F.Cu" "B.Cu")
		(net "GND")
	)
	(via
		(at 77.479906 -57.57164)
		(size 0.508)
		(drill 0.254)
		(layers "F.Cu" "B.Cu")
		(net "GND")
	)
	(via
		(at 42.411396 -155.612846)
		(size 0.508)
		(drill 0.254)
		(layers "F.Cu" "B.Cu")
		(net "GND")
	)
	(via
		(at 240.599722 -150.219156)
		(size 0.508)
		(drill 0.254)
		(layers "F.Cu" "B.Cu")
		(net "GND")
	)
	(via
		(at 39.899336 1.994154)
		(size 0.508)
		(drill 0.254)
		(layers "F.Cu" "B.Cu")
		(net "GND")
	)
	(via
		(at 234.551728 1.994154)
		(size 0.508)
		(drill 0.254)
		(layers "F.Cu" "B.Cu")
		(net "GND")
	)
	(via
		(at 373.508524 -162.268662)
		(size 0.5588)
		(drill 0.3048)
		(layers "F.Cu" "B.Cu")
		(net "GND")
	)
	(via
		(at 134.160514 -140.592556)
		(size 0.508)
		(drill 0.254)
		(layers "F.Cu" "B.Cu")
		(net "GND")
	)
	(via
		(at 428.731934 10.354056)
		(size 0.5588)
		(drill 0.3048)
		(layers "F.Cu" "B.Cu")
		(net "GND")
	)
	(via
		(at 76.449428 -155.511246)
		(size 0.508)
		(drill 0.254)
		(layers "F.Cu" "B.Cu")
		(net "GND")
	)
	(via
		(at 30.2387 -86.77275)
		(size 0.508)
		(drill 0.254)
		(layers "F.Cu" "B.Cu")
		(net "GND")
	)
	(via
		(at 288.65068 -58.381138)
		(size 0.508)
		(drill 0.254)
		(layers "F.Cu" "B.Cu")
		(net "GND")
	)
	(via
		(at 73.437496 -124.623576)
		(size 0.508)
		(drill 0.254)
		(layers "F.Cu" "B.Cu")
		(net "GND")
	)
	(via
		(at 257.281934 14.926056)
		(size 0.5588)
		(drill 0.3048)
		(layers "F.Cu" "B.Cu")
		(net "GND")
	)
	(via
		(at 469.930734 -164.479224)
		(size 0.5588)
		(drill 0.3048)
		(layers "F.Cu" "B.Cu")
		(net "GND")
	)
	(via
		(at 289.79368 -88.099138)
		(size 0.508)
		(drill 0.254)
		(layers "F.Cu" "B.Cu")
		(net "GND")
	)
	(via
		(at 122.791728 -56.894984)
		(size 0.508)
		(drill 0.254)
		(layers "F.Cu" "B.Cu")
		(net "GND")
	)
	(via
		(at 171.2722 -58.9788)
		(size 0.508)
		(drill 0.254)
		(layers "F.Cu" "B.Cu")
		(net "GND")
	)
	(via
		(at 384.937 -113.0554)
		(size 0.508)
		(drill 0.254)
		(layers "F.Cu" "B.Cu")
		(net "GND")
	)
	(via
		(at 52.471574 -140.617956)
		(size 0.508)
		(drill 0.254)
		(layers "F.Cu" "B.Cu")
		(net "GND")
	)
	(via
		(at 301.736506 -131.5466)
		(size 0.508)
		(drill 0.254)
		(layers "F.Cu" "B.Cu")
		(net "GND")
	)
	(via
		(at 122.349514 -9.156446)
		(size 0.508)
		(drill 0.254)
		(layers "F.Cu" "B.Cu")
		(net "GND")
	)
	(via
		(at 181.3306 -88.3412)
		(size 0.508)
		(drill 0.254)
		(layers "F.Cu" "B.Cu")
		(net "GND")
	)
	(via
		(at 233.895138 -83.32724)
		(size 0.508)
		(drill 0.254)
		(layers "F.Cu" "B.Cu")
		(net "GND")
	)
	(via
		(at 251.566934 -167.832024)
		(size 0.5588)
		(drill 0.3048)
		(layers "F.Cu" "B.Cu")
		(net "GND")
	)
	(via
		(at 132.519674 -94.538038)
		(size 0.508)
		(drill 0.254)
		(layers "F.Cu" "B.Cu")
		(net "GND")
	)
	(via
		(at 375.539 -92.837)
		(size 0.508)
		(drill 0.254)
		(layers "F.Cu" "B.Cu")
		(net "GND")
	)
	(via
		(at 232.960418 -91.747086)
		(size 0.508)
		(drill 0.254)
		(layers "F.Cu" "B.Cu")
		(net "GND")
	)
	(via
		(at 214.101934 9.084056)
		(size 0.5588)
		(drill 0.3048)
		(layers "F.Cu" "B.Cu")
		(net "GND")
	)
	(via
		(at 284.358334 -55.904384)
		(size 0.508)
		(drill 0.254)
		(layers "F.Cu" "B.Cu")
		(net "GND")
	)
	(via
		(at 176.6062 -85.8774)
		(size 0.508)
		(drill 0.254)
		(layers "F.Cu" "B.Cu")
		(net "GND")
	)
	(via
		(at 374.3452 -125.9332)
		(size 0.508)
		(drill 0.254)
		(layers "F.Cu" "B.Cu")
		(net "GND")
	)
	(via
		(at 484.611934 12.894056)
		(size 0.5588)
		(drill 0.3048)
		(layers "F.Cu" "B.Cu")
		(net "GND")
	)
	(via
		(at 157.503368 -3.321812)
		(size 0.508)
		(drill 0.254)
		(layers "F.Cu" "B.Cu")
		(net "GND")
	)
	(via
		(at 308.564534 -167.832024)
		(size 0.5588)
		(drill 0.3048)
		(layers "F.Cu" "B.Cu")
		(net "GND")
	)
	(via
		(at 291.51072 -89.089738)
		(size 0.508)
		(drill 0.254)
		(layers "F.Cu" "B.Cu")
		(net "GND")
	)
	(via
		(at 315.701934 9.084056)
		(size 0.5588)
		(drill 0.3048)
		(layers "F.Cu" "B.Cu")
		(net "GND")
	)
	(via
		(at 127.392176 -9.143746)
		(size 0.508)
		(drill 0.254)
		(layers "F.Cu" "B.Cu")
		(net "GND")
	)
	(via
		(at 240.771934 14.926056)
		(size 0.5588)
		(drill 0.3048)
		(layers "F.Cu" "B.Cu")
		(net "GND")
	)
	(via
		(at 74.045826 -68.46824)
		(size 0.508)
		(drill 0.254)
		(layers "F.Cu" "B.Cu")
		(net "GND")
	)
	(via
		(at 323.321934 9.084056)
		(size 0.5588)
		(drill 0.3048)
		(layers "F.Cu" "B.Cu")
		(net "GND")
	)
	(via
		(at 319.740534 -167.832024)
		(size 0.5588)
		(drill 0.3048)
		(layers "F.Cu" "B.Cu")
		(net "GND")
	)
	(via
		(at 365.6076 -125.6538)
		(size 0.508)
		(drill 0.254)
		(layers "F.Cu" "B.Cu")
		(net "GND")
	)
	(via
		(at 304.388266 -64.819784)
		(size 0.508)
		(drill 0.254)
		(layers "F.Cu" "B.Cu")
		(net "GND")
	)
	(via
		(at 234.802934 -167.832024)
		(size 0.5588)
		(drill 0.3048)
		(layers "F.Cu" "B.Cu")
		(net "GND")
	)
	(via
		(at 488.421934 11.624056)
		(size 0.5588)
		(drill 0.3048)
		(layers "F.Cu" "B.Cu")
		(net "GND")
	)
	(via
		(at 464.291934 13.910056)
		(size 0.5588)
		(drill 0.3048)
		(layers "F.Cu" "B.Cu")
		(net "GND")
	)
	(via
		(at 306.811934 9.084056)
		(size 0.5588)
		(drill 0.3048)
		(layers "F.Cu" "B.Cu")
		(net "GND")
	)
	(via
		(at 57.74944 -148.771356)
		(size 0.508)
		(drill 0.254)
		(layers "F.Cu" "B.Cu")
		(net "GND")
	)
	(via
		(at 283.048964 -16.7513)
		(size 0.508)
		(drill 0.254)
		(layers "F.Cu" "B.Cu")
		(net "GND")
	)
	(via
		(at 298.399962 -136.397746)
		(size 0.508)
		(drill 0.254)
		(layers "F.Cu" "B.Cu")
		(net "GND")
	)
	(via
		(at 68.799456 -139.170156)
		(size 0.508)
		(drill 0.254)
		(layers "F.Cu" "B.Cu")
		(net "GND")
	)
	(via
		(at 4.353306 -135.809482)
		(size 0.508)
		(drill 0.254)
		(layers "F.Cu" "B.Cu")
		(net "GND")
	)
	(via
		(at 398.4244 -125.603)
		(size 0.508)
		(drill 0.254)
		(layers "F.Cu" "B.Cu")
		(net "GND")
	)
	(via
		(at 347.91142 -32.766)
		(size 0.508)
		(drill 0.254)
		(layers "F.Cu" "B.Cu")
		(net "GND")
	)
	(via
		(at 456.018392 -43.697398)
		(size 0.508)
		(drill 0.254)
		(layers "F.Cu" "B.Cu")
		(net "GND")
	)
	(via
		(at 311.0865 -150.749)
		(size 0.508)
		(drill 0.254)
		(layers "F.Cu" "B.Cu")
		(net "GND")
	)
	(via
		(at 416.281108 -28.52547)
		(size 0.4572)
		(drill 0.2032)
		(layers "F.Cu" "B.Cu")
		(net "GND")
	)
	(via
		(at 102.341934 14.926056)
		(size 0.5588)
		(drill 0.3048)
		(layers "F.Cu" "B.Cu")
		(net "GND")
	)
	(via
		(at 292.392608 -21.513292)
		(size 0.508)
		(drill 0.254)
		(layers "F.Cu" "B.Cu")
		(net "GND")
	)
	(via
		(at 316.249812 -154.063446)
		(size 0.508)
		(drill 0.254)
		(layers "F.Cu" "B.Cu")
		(net "GND")
	)
	(via
		(at 195.549774 -16.764)
		(size 0.508)
		(drill 0.254)
		(layers "F.Cu" "B.Cu")
		(net "GND")
	)
	(via
		(at 108.197396 -58.381138)
		(size 0.508)
		(drill 0.254)
		(layers "F.Cu" "B.Cu")
		(net "GND")
	)
	(via
		(at 98.942398 -63.019686)
		(size 0.508)
		(drill 0.254)
		(layers "F.Cu" "B.Cu")
		(net "GND")
	)
	(via
		(at 255.87198 -13.292582)
		(size 0.508)
		(drill 0.254)
		(layers "F.Cu" "B.Cu")
		(net "GND")
	)
	(via
		(at 196.399912 -148.771356)
		(size 0.508)
		(drill 0.254)
		(layers "F.Cu" "B.Cu")
		(net "GND")
	)
	(via
		(at 275.199348 -89.584784)
		(size 0.508)
		(drill 0.254)
		(layers "F.Cu" "B.Cu")
		(net "GND")
	)
	(via
		(at 37.571934 9.084056)
		(size 0.5588)
		(drill 0.3048)
		(layers "F.Cu" "B.Cu")
		(net "GND")
	)
	(via
		(at 89.641934 14.926056)
		(size 0.5588)
		(drill 0.3048)
		(layers "F.Cu" "B.Cu")
		(net "GND")
	)
	(via
		(at 133.378194 -72.249538)
		(size 0.508)
		(drill 0.254)
		(layers "F.Cu" "B.Cu")
		(net "GND")
	)
	(via
		(at 322.199 -141.1732)
		(size 0.508)
		(drill 0.254)
		(layers "F.Cu" "B.Cu")
		(net "GND")
	)
	(via
		(at 469.052402 -40.194992)
		(size 0.508)
		(drill 0.254)
		(layers "F.Cu" "B.Cu")
		(net "GND")
	)
	(via
		(at 342.092534 -167.832024)
		(size 0.5588)
		(drill 0.3048)
		(layers "F.Cu" "B.Cu")
		(net "GND")
	)
	(via
		(at 246.772684 -60.047886)
		(size 0.508)
		(drill 0.254)
		(layers "F.Cu" "B.Cu")
		(net "GND")
	)
	(via
		(at 336.021934 9.084056)
		(size 0.5588)
		(drill 0.3048)
		(layers "F.Cu" "B.Cu")
		(net "GND")
	)
	(via
		(at 50.271934 14.926056)
		(size 0.5588)
		(drill 0.3048)
		(layers "F.Cu" "B.Cu")
		(net "GND")
	)
	(via
		(at 411.099 -46.14672)
		(size 0.508)
		(drill 0.254)
		(layers "F.Cu" "B.Cu")
		(net "GND")
	)
	(via
		(at 477.1263 -139.3571)
		(size 0.508)
		(drill 0.254)
		(layers "F.Cu" "B.Cu")
		(net "GND")
	)
	(via
		(at 201.041254 -153.552144)
		(size 0.508)
		(drill 0.254)
		(layers "F.Cu" "B.Cu")
		(net "GND")
	)
	(via
		(at 106.480356 -61.352938)
		(size 0.508)
		(drill 0.254)
		(layers "F.Cu" "B.Cu")
		(net "GND")
	)
	(via
		(at 428.7393 -47.2821)
		(size 0.508)
		(drill 0.254)
		(layers "F.Cu" "B.Cu")
		(net "GND")
	)
	(via
		(at 165.841934 9.084056)
		(size 0.5588)
		(drill 0.3048)
		(layers "F.Cu" "B.Cu")
		(net "GND")
	)
	(via
		(at 176.6316 -80.772)
		(size 0.508)
		(drill 0.254)
		(layers "F.Cu" "B.Cu")
		(net "GND")
	)
	(via
		(at 341.6554 -112.395)
		(size 0.508)
		(drill 0.254)
		(layers "F.Cu" "B.Cu")
		(net "GND")
	)
	(via
		(at 68.894706 -83.32724)
		(size 0.508)
		(drill 0.254)
		(layers "F.Cu" "B.Cu")
		(net "GND")
	)
	(via
		(at 297.549824 1.994154)
		(size 0.508)
		(drill 0.254)
		(layers "F.Cu" "B.Cu")
		(net "GND")
	)
	(via
		(at 96.051624 -79.360014)
		(size 0.508)
		(drill 0.254)
		(layers "F.Cu" "B.Cu")
		(net "GND")
	)
	(via
		(at 61.821568 -134.8994)
		(size 0.508)
		(drill 0.254)
		(layers "F.Cu" "B.Cu")
		(net "GND")
	)
	(via
		(at 270.571468 -62.838584)
		(size 0.508)
		(drill 0.254)
		(layers "F.Cu" "B.Cu")
		(net "GND")
	)
	(via
		(at 113.865914 -145.992342)
		(size 0.508)
		(drill 0.254)
		(layers "F.Cu" "B.Cu")
		(net "GND")
	)
	(via
		(at 41.510458 -3.737356)
		(size 0.508)
		(drill 0.254)
		(layers "F.Cu" "B.Cu")
		(net "GND")
	)
	(via
		(at 236.470698 -97.690686)
		(size 0.508)
		(drill 0.254)
		(layers "F.Cu" "B.Cu")
		(net "GND")
	)
	(via
		(at 57.74944 -146.011646)
		(size 0.508)
		(drill 0.254)
		(layers "F.Cu" "B.Cu")
		(net "GND")
	)
	(via
		(at 117.066822 -96.518984)
		(size 0.508)
		(drill 0.254)
		(layers "F.Cu" "B.Cu")
		(net "GND")
	)
	(via
		(at 293.22776 -58.381138)
		(size 0.508)
		(drill 0.254)
		(layers "F.Cu" "B.Cu")
		(net "GND")
	)
	(via
		(at 38.971982 -92.572078)
		(size 0.5588)
		(drill 0.3048)
		(layers "F.Cu" "B.Cu")
		(net "GND")
	)
	(via
		(at 346.373196 -136.517634)
		(size 0.508)
		(drill 0.254)
		(layers "F.Cu" "B.Cu")
		(net "GND")
	)
	(via
		(at 28.043124 -162.243262)
		(size 0.5588)
		(drill 0.3048)
		(layers "F.Cu" "B.Cu")
		(net "GND")
	)
	(via
		(at 239.046258 -60.54344)
		(size 0.508)
		(drill 0.254)
		(layers "F.Cu" "B.Cu")
		(net "GND")
	)
	(via
		(at 129.085848 -91.565984)
		(size 0.508)
		(drill 0.254)
		(layers "F.Cu" "B.Cu")
		(net "GND")
	)
	(via
		(at 233.895138 -60.54344)
		(size 0.508)
		(drill 0.254)
		(layers "F.Cu" "B.Cu")
		(net "GND")
	)
	(via
		(at 434.370734 -165.596824)
		(size 0.5588)
		(drill 0.3048)
		(layers "F.Cu" "B.Cu")
		(net "GND")
	)
	(via
		(at 34.991802 -63.427864)
		(size 0.508)
		(drill 0.254)
		(layers "F.Cu" "B.Cu")
		(net "GND")
	)
	(via
		(at 235.612178 -98.18624)
		(size 0.508)
		(drill 0.254)
		(layers "F.Cu" "B.Cu")
		(net "GND")
	)
	(via
		(at 2.342134 -164.479224)
		(size 0.5588)
		(drill 0.3048)
		(layers "F.Cu" "B.Cu")
		(net "GND")
	)
	(via
		(at 106.151934 14.926056)
		(size 0.5588)
		(drill 0.3048)
		(layers "F.Cu" "B.Cu")
		(net "GND")
	)
	(via
		(at 203.941934 9.084056)
		(size 0.5588)
		(drill 0.3048)
		(layers "F.Cu" "B.Cu")
		(net "GND")
	)
	(via
		(at 28.071826 -104.217978)
		(size 0.5588)
		(drill 0.3048)
		(layers "F.Cu" "B.Cu")
		(net "GND")
	)
	(via
		(at 50.099468 -155.600146)
		(size 0.508)
		(drill 0.254)
		(layers "F.Cu" "B.Cu")
		(net "GND")
	)
	(via
		(at 451.7517 -53.2384)
		(size 0.508)
		(drill 0.254)
		(layers "F.Cu" "B.Cu")
		(net "GND")
	)
	(via
		(at 213.399878 -139.170156)
		(size 0.508)
		(drill 0.254)
		(layers "F.Cu" "B.Cu")
		(net "GND")
	)
	(via
		(at 116.208302 -98.005138)
		(size 0.508)
		(drill 0.254)
		(layers "F.Cu" "B.Cu")
		(net "GND")
	)
	(via
		(at 301.742602 -2.310892)
		(size 0.508)
		(drill 0.254)
		(layers "F.Cu" "B.Cu")
		(net "GND")
	)
	(via
		(at 213.568534 -167.832024)
		(size 0.5588)
		(drill 0.3048)
		(layers "F.Cu" "B.Cu")
		(net "GND")
	)
	(via
		(at 280.637234 -50.3047)
		(size 0.508)
		(drill 0.254)
		(layers "F.Cu" "B.Cu")
		(net "GND")
	)
	(via
		(at 219.181934 9.084056)
		(size 0.5588)
		(drill 0.3048)
		(layers "F.Cu" "B.Cu")
		(net "GND")
	)
	(via
		(at 59.339734 -167.832024)
		(size 0.5588)
		(drill 0.3048)
		(layers "F.Cu" "B.Cu")
		(net "GND")
	)
	(via
		(at 344.385138 3.11785)
		(size 0.508)
		(drill 0.254)
		(layers "F.Cu" "B.Cu")
		(net "GND")
	)
	(via
		(at 300.954186 -90.575384)
		(size 0.508)
		(drill 0.254)
		(layers "F.Cu" "B.Cu")
		(net "GND")
	)
	(via
		(at 426.191934 12.894056)
		(size 0.5588)
		(drill 0.3048)
		(layers "F.Cu" "B.Cu")
		(net "GND")
	)
	(via
		(at 102.922324 -162.243262)
		(size 0.5588)
		(drill 0.3048)
		(layers "F.Cu" "B.Cu")
		(net "GND")
	)
	(via
		(at 234.560872 -3.737356)
		(size 0.508)
		(drill 0.254)
		(layers "F.Cu" "B.Cu")
		(net "GND")
	)
	(via
		(at 72.747124 -162.243262)
		(size 0.5588)
		(drill 0.3048)
		(layers "F.Cu" "B.Cu")
		(net "GND")
	)
	(via
		(at 499.140734 -165.596824)
		(size 0.5588)
		(drill 0.3048)
		(layers "F.Cu" "B.Cu")
		(net "GND")
	)
	(via
		(at 281.738324 -162.243262)
		(size 0.5588)
		(drill 0.3048)
		(layers "F.Cu" "B.Cu")
		(net "GND")
	)
	(via
		(at 71.171562 -3.762756)
		(size 0.508)
		(drill 0.254)
		(layers "F.Cu" "B.Cu")
		(net "GND")
	)
	(via
		(at 137.901934 14.926056)
		(size 0.5588)
		(drill 0.3048)
		(layers "F.Cu" "B.Cu")
		(net "GND")
	)
	(via
		(at 465.561934 14.926056)
		(size 0.5588)
		(drill 0.3048)
		(layers "F.Cu" "B.Cu")
		(net "GND")
	)
	(via
		(at 124.801376 -7.607046)
		(size 0.508)
		(drill 0.254)
		(layers "F.Cu" "B.Cu")
		(net "GND")
	)
	(via
		(at 274.914614 -60.362338)
		(size 0.508)
		(drill 0.254)
		(layers "F.Cu" "B.Cu")
		(net "GND")
	)
	(via
		(at 56.621934 14.926056)
		(size 0.5588)
		(drill 0.3048)
		(layers "F.Cu" "B.Cu")
		(net "GND")
	)
	(via
		(at 65.399412 -139.170156)
		(size 0.508)
		(drill 0.254)
		(layers "F.Cu" "B.Cu")
		(net "GND")
	)
	(via
		(at 214.249762 -13.363956)
		(size 0.508)
		(drill 0.254)
		(layers "F.Cu" "B.Cu")
		(net "GND")
	)
	(via
		(at 131.699508 -129.568956)
		(size 0.508)
		(drill 0.254)
		(layers "F.Cu" "B.Cu")
		(net "GND")
	)
	(via
		(at 461.869282 -33.852358)
		(size 0.508)
		(drill 0.254)
		(layers "F.Cu" "B.Cu")
		(net "GND")
	)
	(via
		(at 58.599324 -150.219156)
		(size 0.508)
		(drill 0.254)
		(layers "F.Cu" "B.Cu")
		(net "GND")
	)
	(via
		(at 410.240734 -165.596824)
		(size 0.5588)
		(drill 0.3048)
		(layers "F.Cu" "B.Cu")
		(net "GND")
	)
	(via
		(at 238.437928 -4.346956)
		(size 0.508)
		(drill 0.254)
		(layers "F.Cu" "B.Cu")
		(net "GND")
	)
	(via
		(at 300.954186 -62.838584)
		(size 0.508)
		(drill 0.254)
		(layers "F.Cu" "B.Cu")
		(net "GND")
	)
	(via
		(at 68.799456 -148.771356)
		(size 0.508)
		(drill 0.254)
		(layers "F.Cu" "B.Cu")
		(net "GND")
	)
	(via
		(at 172.0596 -59.0042)
		(size 0.508)
		(drill 0.254)
		(layers "F.Cu" "B.Cu")
		(net "GND")
	)
	(via
		(at 352.77171 -132.026152)
		(size 0.508)
		(drill 0.254)
		(layers "F.Cu" "B.Cu")
		(net "GND")
	)
	(via
		(at 35.880802 -83.874864)
		(size 0.508)
		(drill 0.254)
		(layers "F.Cu" "B.Cu")
		(net "GND")
	)
	(via
		(at 126.421642 -144.5006)
		(size 0.508)
		(drill 0.254)
		(layers "F.Cu" "B.Cu")
		(net "GND")
	)
	(via
		(at 243.149882 -9.133078)
		(size 0.508)
		(drill 0.254)
		(layers "F.Cu" "B.Cu")
		(net "GND")
	)
	(via
		(at 48.7426 -91.483942)
		(size 0.508)
		(drill 0.254)
		(layers "F.Cu" "B.Cu")
		(net "GND")
	)
	(via
		(at 286.499808 -150.219156)
		(size 0.508)
		(drill 0.254)
		(layers "F.Cu" "B.Cu")
		(net "GND")
	)
	(via
		(at 122.217688 -69.772784)
		(size 0.508)
		(drill 0.254)
		(layers "F.Cu" "B.Cu")
		(net "GND")
	)
	(via
		(at 262.0264 -10.8966)
		(size 0.508)
		(drill 0.254)
		(layers "F.Cu" "B.Cu")
		(net "GND")
	)
	(via
		(at 227.786438 -23.495)
		(size 0.508)
		(drill 0.254)
		(layers "F.Cu" "B.Cu")
		(net "GND")
	)
	(via
		(at 34.991802 -54.664864)
		(size 0.508)
		(drill 0.254)
		(layers "F.Cu" "B.Cu")
		(net "GND")
	)
	(via
		(at 412.448756 -119.7356)
		(size 0.508)
		(drill 0.254)
		(layers "F.Cu" "B.Cu")
		(net "GND")
	)
	(via
		(at 298.399962 -145.998946)
		(size 0.508)
		(drill 0.254)
		(layers "F.Cu" "B.Cu")
		(net "GND")
	)
	(via
		(at 339.831934 14.926056)
		(size 0.5588)
		(drill 0.3048)
		(layers "F.Cu" "B.Cu")
		(net "GND")
	)
	(via
		(at 141.76883 -72.828658)
		(size 0.508)
		(drill 0.254)
		(layers "F.Cu" "B.Cu")
		(net "GND")
	)
	(via
		(at 365.506 -52.959)
		(size 0.508)
		(drill 0.254)
		(layers "F.Cu" "B.Cu")
		(net "GND")
	)
	(via
		(at 136.736074 -141.1478)
		(size 0.508)
		(drill 0.254)
		(layers "F.Cu" "B.Cu")
		(net "GND")
	)
	(via
		(at 343.922096 -101.34219)
		(size 0.508)
		(drill 0.254)
		(layers "F.Cu" "B.Cu")
		(net "GND")
	)
	(via
		(at 299.237146 -85.622384)
		(size 0.508)
		(drill 0.254)
		(layers "F.Cu" "B.Cu")
		(net "GND")
	)
	(via
		(at 74.045826 -66.48704)
		(size 0.508)
		(drill 0.254)
		(layers "F.Cu" "B.Cu")
		(net "GND")
	)
	(via
		(at 335.3054 -112.395)
		(size 0.508)
		(drill 0.254)
		(layers "F.Cu" "B.Cu")
		(net "GND")
	)
	(via
		(at 19.74342 -32.22244)
		(size 0.508)
		(drill 0.254)
		(layers "F.Cu" "B.Cu")
		(net "GND")
	)
	(via
		(at 230.399844 -146.011646)
		(size 0.508)
		(drill 0.254)
		(layers "F.Cu" "B.Cu")
		(net "GND")
	)
	(via
		(at 73.4441 -145.9357)
		(size 0.508)
		(drill 0.254)
		(layers "F.Cu" "B.Cu")
		(net "GND")
	)
	(via
		(at 45.394118 0.5207)
		(size 0.508)
		(drill 0.254)
		(layers "F.Cu" "B.Cu")
		(net "GND")
	)
	(via
		(at 459.770734 -163.361624)
		(size 0.5588)
		(drill 0.3048)
		(layers "F.Cu" "B.Cu")
		(net "GND")
	)
	(via
		(at 31.893002 -55.528464)
		(size 0.508)
		(drill 0.254)
		(layers "F.Cu" "B.Cu")
		(net "GND")
	)
	(via
		(at 415.3154 -46.4312)
		(size 0.508)
		(drill 0.254)
		(layers "F.Cu" "B.Cu")
		(net "GND")
	)
	(via
		(at 409.150312 -96.872298)
		(size 0.508)
		(drill 0.254)
		(layers "F.Cu" "B.Cu")
		(net "GND")
	)
	(via
		(at 498.581934 9.084056)
		(size 0.5588)
		(drill 0.3048)
		(layers "F.Cu" "B.Cu")
		(net "GND")
	)
	(via
		(at 54.731412 -21.5138)
		(size 0.508)
		(drill 0.254)
		(layers "F.Cu" "B.Cu")
		(net "GND")
	)
	(via
		(at 168.4528 -75.8444)
		(size 0.508)
		(drill 0.254)
		(layers "F.Cu" "B.Cu")
		(net "GND")
	)
	(via
		(at 16.4338 -53.3654)
		(size 0.5588)
		(drill 0.3048)
		(layers "F.Cu" "B.Cu")
		(net "GND")
	)
	(via
		(at 298.378626 -71.258938)
		(size 0.508)
		(drill 0.254)
		(layers "F.Cu" "B.Cu")
		(net "GND")
	)
	(via
		(at 178.934364 -155.10002)
		(size 0.5588)
		(drill 0.3048)
		(layers "F.Cu" "B.Cu")
		(net "GND")
	)
	(via
		(at 71.171562 -154.1018)
		(size 0.508)
		(drill 0.254)
		(layers "F.Cu" "B.Cu")
		(net "GND")
	)
	(via
		(at 467.390734 -164.479224)
		(size 0.5588)
		(drill 0.3048)
		(layers "F.Cu" "B.Cu")
		(net "GND")
	)
	(via
		(at 81.582768 -149.8092)
		(size 0.508)
		(drill 0.254)
		(layers "F.Cu" "B.Cu")
		(net "GND")
	)
	(via
		(at 274.914614 -58.381138)
		(size 0.508)
		(drill 0.254)
		(layers "F.Cu" "B.Cu")
		(net "GND")
	)
	(via
		(at 41.381934 9.084056)
		(size 0.5588)
		(drill 0.3048)
		(layers "F.Cu" "B.Cu")
		(net "GND")
	)
	(via
		(at 268.711934 9.084056)
		(size 0.5588)
		(drill 0.3048)
		(layers "F.Cu" "B.Cu")
		(net "GND")
	)
	(via
		(at 62.692534 -167.832024)
		(size 0.5588)
		(drill 0.3048)
		(layers "F.Cu" "B.Cu")
		(net "GND")
	)
	(via
		(at 18.521934 14.926056)
		(size 0.5588)
		(drill 0.3048)
		(layers "F.Cu" "B.Cu")
		(net "GND")
	)
	(via
		(at 237.329218 -64.50584)
		(size 0.508)
		(drill 0.254)
		(layers "F.Cu" "B.Cu")
		(net "GND")
	)
	(via
		(at 36.2458 -70.1548)
		(size 0.5588)
		(drill 0.3048)
		(layers "F.Cu" "B.Cu")
		(net "GND")
	)
	(via
		(at 210.391248 -7.095744)
		(size 0.508)
		(drill 0.254)
		(layers "F.Cu" "B.Cu")
		(net "GND")
	)
	(via
		(at 177.43424 -95.10522)
		(size 0.508)
		(drill 0.254)
		(layers "F.Cu" "B.Cu")
		(net "GND")
	)
	(via
		(at 147.394168 -18.6817)
		(size 0.508)
		(drill 0.254)
		(layers "F.Cu" "B.Cu")
		(net "GND")
	)
	(via
		(at 34.736024 -150.749)
		(size 0.508)
		(drill 0.254)
		(layers "F.Cu" "B.Cu")
		(net "GND")
	)
	(via
		(at 290.71189 -148.771356)
		(size 0.508)
		(drill 0.254)
		(layers "F.Cu" "B.Cu")
		(net "GND")
	)
	(via
		(at 218.038934 -167.832024)
		(size 0.5588)
		(drill 0.3048)
		(layers "F.Cu" "B.Cu")
		(net "GND")
	)
	(via
		(at 32.5628 -63.6778)
		(size 0.508)
		(drill 0.254)
		(layers "F.Cu" "B.Cu")
		(net "GND")
	)
	(via
		(at 232.099866 -18.757646)
		(size 0.508)
		(drill 0.254)
		(layers "F.Cu" "B.Cu")
		(net "GND")
	)
	(via
		(at 381.437134 -167.832024)
		(size 0.5588)
		(drill 0.3048)
		(layers "F.Cu" "B.Cu")
		(net "GND")
	)
	(via
		(at 290.74999 -155.612846)
		(size 0.508)
		(drill 0.254)
		(layers "F.Cu" "B.Cu")
		(net "GND")
	)
	(via
		(at 123.934728 -101.471984)
		(size 0.508)
		(drill 0.254)
		(layers "F.Cu" "B.Cu")
		(net "GND")
	)
	(via
		(at 30.549342 -141.1478)
		(size 0.508)
		(drill 0.254)
		(layers "F.Cu" "B.Cu")
		(net "GND")
	)
	(via
		(at 59.449462 -26.488136)
		(size 0.508)
		(drill 0.254)
		(layers "F.Cu" "B.Cu")
		(net "GND")
	)
	(via
		(at 363.450124 -162.268662)
		(size 0.5588)
		(drill 0.3048)
		(layers "F.Cu" "B.Cu")
		(net "GND")
	)
	(via
		(at 316.249812 -150.219156)
		(size 0.508)
		(drill 0.254)
		(layers "F.Cu" "B.Cu")
		(net "GND")
	)
	(via
		(at 229.091236 -134.349744)
		(size 0.508)
		(drill 0.254)
		(layers "F.Cu" "B.Cu")
		(net "GND")
	)
	(via
		(at 295.80332 -96.518984)
		(size 0.508)
		(drill 0.254)
		(layers "F.Cu" "B.Cu")
		(net "GND")
	)
	(via
		(at 135.095234 -78.193138)
		(size 0.508)
		(drill 0.254)
		(layers "F.Cu" "B.Cu")
		(net "GND")
	)
	(via
		(at 134.15137 -134.861046)
		(size 0.508)
		(drill 0.254)
		(layers "F.Cu" "B.Cu")
		(net "GND")
	)
	(via
		(at 499.825518 -51.061366)
		(size 0.508)
		(drill 0.254)
		(layers "F.Cu" "B.Cu")
		(net "GND")
	)
	(via
		(at 282.07208 -17.2466)
		(size 0.508)
		(drill 0.254)
		(layers "F.Cu" "B.Cu")
		(net "GND")
	)
	(via
		(at 240.763298 -87.28964)
		(size 0.508)
		(drill 0.254)
		(layers "F.Cu" "B.Cu")
		(net "GND")
	)
	(via
		(at 167.8686 -32.1691)
		(size 0.508)
		(drill 0.254)
		(layers "F.Cu" "B.Cu")
		(net "GND")
	)
	(via
		(at 156.570934 -167.832024)
		(size 0.5588)
		(drill 0.3048)
		(layers "F.Cu" "B.Cu")
		(net "GND")
	)
	(via
		(at 218.44254 -129.564892)
		(size 0.508)
		(drill 0.254)
		(layers "F.Cu" "B.Cu")
		(net "GND")
	)
	(via
		(at 150.399496 -146.011646)
		(size 0.508)
		(drill 0.254)
		(layers "F.Cu" "B.Cu")
		(net "GND")
	)
	(via
		(at 284.341062 -134.349744)
		(size 0.508)
		(drill 0.254)
		(layers "F.Cu" "B.Cu")
		(net "GND")
	)
	(via
		(at 308.081934 9.084056)
		(size 0.5588)
		(drill 0.3048)
		(layers "F.Cu" "B.Cu")
		(net "GND")
	)
	(via
		(at 115.349782 -99.490784)
		(size 0.508)
		(drill 0.254)
		(layers "F.Cu" "B.Cu")
		(net "GND")
	)
	(via
		(at 340.971124 -162.243262)
		(size 0.5588)
		(drill 0.3048)
		(layers "F.Cu" "B.Cu")
		(net "GND")
	)
	(via
		(at 335.386934 -167.832024)
		(size 0.5588)
		(drill 0.3048)
		(layers "F.Cu" "B.Cu")
		(net "GND")
	)
	(via
		(at 261.744206 -68.805806)
		(size 0.5588)
		(drill 0.3048)
		(layers "F.Cu" "B.Cu")
		(net "GND")
	)
	(via
		(at 141.049502 -155.612846)
		(size 0.508)
		(drill 0.254)
		(layers "F.Cu" "B.Cu")
		(net "GND")
	)
	(via
		(at 275.061934 14.926056)
		(size 0.5588)
		(drill 0.3048)
		(layers "F.Cu" "B.Cu")
		(net "GND")
	)
	(via
		(at 472.15552 -157.653228)
		(size 0.5588)
		(drill 0.3048)
		(layers "F.Cu" "B.Cu")
		(net "GND")
	)
	(via
		(at 11.2268 -28.321)
		(size 0.508)
		(drill 0.254)
		(layers "F.Cu" "B.Cu")
		(net "GND")
	)
	(via
		(at 380.66599 -57.07761)
		(size 0.508)
		(drill 0.254)
		(layers "F.Cu" "B.Cu")
		(net "GND")
	)
	(via
		(at 287.761934 9.084056)
		(size 0.5588)
		(drill 0.3048)
		(layers "F.Cu" "B.Cu")
		(net "GND")
	)
	(via
		(at 415.320734 -165.596824)
		(size 0.5588)
		(drill 0.3048)
		(layers "F.Cu" "B.Cu")
		(net "GND")
	)
	(via
		(at 135.332724 -162.243262)
		(size 0.5588)
		(drill 0.3048)
		(layers "F.Cu" "B.Cu")
		(net "GND")
	)
	(via
		(at 459.168754 -53.234844)
		(size 0.508)
		(drill 0.254)
		(layers "F.Cu" "B.Cu")
		(net "GND")
	)
	(via
		(at 345.835732 -104.273858)
		(size 0.508)
		(drill 0.254)
		(layers "F.Cu" "B.Cu")
		(net "GND")
	)
	(via
		(at 438.891934 13.910056)
		(size 0.5588)
		(drill 0.3048)
		(layers "F.Cu" "B.Cu")
		(net "GND")
	)
	(via
		(at 344.165428 -102.655116)
		(size 0.508)
		(drill 0.254)
		(layers "F.Cu" "B.Cu")
		(net "GND")
	)
	(via
		(at 70.611746 -76.39304)
		(size 0.508)
		(drill 0.254)
		(layers "F.Cu" "B.Cu")
		(net "GND")
	)
	(via
		(at 406.430734 -166.714424)
		(size 0.5588)
		(drill 0.3048)
		(layers "F.Cu" "B.Cu")
		(net "GND")
	)
	(via
		(at 165.608 -130.5306)
		(size 0.508)
		(drill 0.254)
		(layers "F.Cu" "B.Cu")
		(net "GND")
	)
	(via
		(at 452.604378 -118.61927)
		(size 0.508)
		(drill 0.254)
		(layers "F.Cu" "B.Cu")
		(net "GND")
	)
	(via
		(at 82.630772 -98.18624)
		(size 0.508)
		(drill 0.254)
		(layers "F.Cu" "B.Cu")
		(net "GND")
	)
	(via
		(at 413.35452 -9.309608)
		(size 0.508)
		(drill 0.254)
		(layers "F.Cu" "B.Cu")
		(net "GND")
	)
	(via
		(at 102.341934 9.084056)
		(size 0.5588)
		(drill 0.3048)
		(layers "F.Cu" "B.Cu")
		(net "GND")
	)
	(via
		(at 317.501524 -162.243262)
		(size 0.5588)
		(drill 0.3048)
		(layers "F.Cu" "B.Cu")
		(net "GND")
	)
	(via
		(at 61.821568 -150.219156)
		(size 0.508)
		(drill 0.254)
		(layers "F.Cu" "B.Cu")
		(net "GND")
	)
	(via
		(at 299.160946 -130.991356)
		(size 0.508)
		(drill 0.254)
		(layers "F.Cu" "B.Cu")
		(net "GND")
	)
	(via
		(at 411.510734 -167.832024)
		(size 0.5588)
		(drill 0.3048)
		(layers "F.Cu" "B.Cu")
		(net "GND")
	)
	(via
		(at 319.4812 -28.1686)
		(size 0.508)
		(drill 0.254)
		(layers "F.Cu" "B.Cu")
		(net "GND")
	)
	(via
		(at 50.099468 -21.517356)
		(size 0.508)
		(drill 0.254)
		(layers "F.Cu" "B.Cu")
		(net "GND")
	)
	(via
		(at 162.155124 -162.243262)
		(size 0.5588)
		(drill 0.3048)
		(layers "F.Cu" "B.Cu")
		(net "GND")
	)
	(via
		(at 238.187738 -64.010286)
		(size 0.508)
		(drill 0.254)
		(layers "F.Cu" "B.Cu")
		(net "GND")
	)
	(via
		(at 267.51788 -82.340196)
		(size 0.5588)
		(drill 0.3048)
		(layers "F.Cu" "B.Cu")
		(net "GND")
	)
	(via
		(at 31.221934 14.926056)
		(size 0.5588)
		(drill 0.3048)
		(layers "F.Cu" "B.Cu")
		(net "GND")
	)
	(via
		(at 485.166924 -162.243262)
		(size 0.5588)
		(drill 0.3048)
		(layers "F.Cu" "B.Cu")
		(net "GND")
	)
	(via
		(at 98.942398 -98.681286)
		(size 0.508)
		(drill 0.254)
		(layers "F.Cu" "B.Cu")
		(net "GND")
	)
	(via
		(at 135.771636 -17.2466)
		(size 0.508)
		(drill 0.254)
		(layers "F.Cu" "B.Cu")
		(net "GND")
	)
	(via
		(at 184.2262 -68.4276)
		(size 0.508)
		(drill 0.254)
		(layers "F.Cu" "B.Cu")
		(net "GND")
	)
	(via
		(at 337.8454 -36.83)
		(size 0.508)
		(drill 0.254)
		(layers "F.Cu" "B.Cu")
		(net "GND")
	)
	(via
		(at 96.366838 -88.28024)
		(size 0.508)
		(drill 0.254)
		(layers "F.Cu" "B.Cu")
		(net "GND")
	)
	(via
		(at 95.070168 -19.6088)
		(size 0.508)
		(drill 0.254)
		(layers "F.Cu" "B.Cu")
		(net "GND")
	)
	(via
		(at 201.1934 -76.5048)
		(size 0.5588)
		(drill 0.3048)
		(layers "F.Cu" "B.Cu")
		(net "GND")
	)
	(via
		(at 198.099934 -155.612846)
		(size 0.508)
		(drill 0.254)
		(layers "F.Cu" "B.Cu")
		(net "GND")
	)
	(via
		(at 129.085848 -79.678784)
		(size 0.508)
		(drill 0.254)
		(layers "F.Cu" "B.Cu")
		(net "GND")
	)
	(via
		(at 343.493852 -102.654862)
		(size 0.508)
		(drill 0.254)
		(layers "F.Cu" "B.Cu")
		(net "GND")
	)
	(via
		(at 370.586 -114.299238)
		(size 0.508)
		(drill 0.254)
		(layers "F.Cu" "B.Cu")
		(net "GND")
	)
	(via
		(at 239.046258 -56.58104)
		(size 0.508)
		(drill 0.254)
		(layers "F.Cu" "B.Cu")
		(net "GND")
	)
	(via
		(at 132.519674 -62.838584)
		(size 0.508)
		(drill 0.254)
		(layers "F.Cu" "B.Cu")
		(net "GND")
	)
	(via
		(at 272.339308 -58.876438)
		(size 0.508)
		(drill 0.254)
		(layers "F.Cu" "B.Cu")
		(net "GND")
	)
	(via
		(at 320.854324 -162.243262)
		(size 0.5588)
		(drill 0.3048)
		(layers "F.Cu" "B.Cu")
		(net "GND")
	)
	(via
		(at 465.561934 13.910056)
		(size 0.5588)
		(drill 0.3048)
		(layers "F.Cu" "B.Cu")
		(net "GND")
	)
	(via
		(at 36.18611 -84.56676)
		(size 0.5588)
		(drill 0.3048)
		(layers "F.Cu" "B.Cu")
		(net "GND")
	)
	(via
		(at 235.49991 0.444754)
		(size 0.508)
		(drill 0.254)
		(layers "F.Cu" "B.Cu")
		(net "GND")
	)
	(via
		(at 393.68095 -120.387364)
		(size 0.508)
		(drill 0.254)
		(layers "F.Cu" "B.Cu")
		(net "GND")
	)
	(via
		(at 348.794324 -162.243262)
		(size 0.5588)
		(drill 0.3048)
		(layers "F.Cu" "B.Cu")
		(net "GND")
	)
	(via
		(at 78.338172 -90.756486)
		(size 0.508)
		(drill 0.254)
		(layers "F.Cu" "B.Cu")
		(net "GND")
	)
	(via
		(at 240.599722 -144.462246)
		(size 0.508)
		(drill 0.254)
		(layers "F.Cu" "B.Cu")
		(net "GND")
	)
	(via
		(at 273.918934 -167.832024)
		(size 0.5588)
		(drill 0.3048)
		(layers "F.Cu" "B.Cu")
		(net "GND")
	)
	(via
		(at 473.181934 11.624056)
		(size 0.5588)
		(drill 0.3048)
		(layers "F.Cu" "B.Cu")
		(net "GND")
	)
	(via
		(at 148.699474 -129.568956)
		(size 0.508)
		(drill 0.254)
		(layers "F.Cu" "B.Cu")
		(net "GND")
	)
	(via
		(at 442.701934 9.084056)
		(size 0.5588)
		(drill 0.3048)
		(layers "F.Cu" "B.Cu")
		(net "GND")
	)
	(via
		(at 349.882968 -131.290568)
		(size 0.508)
		(drill 0.254)
		(layers "F.Cu" "B.Cu")
		(net "GND")
	)
	(via
		(at -1.010666 -167.832024)
		(size 0.5588)
		(drill 0.3048)
		(layers "F.Cu" "B.Cu")
		(net "GND")
	)
	(via
		(at 31.72333 -53.856382)
		(size 0.508)
		(drill 0.254)
		(layers "F.Cu" "B.Cu")
		(net "GND")
	)
	(via
		(at 239.273334 -167.832024)
		(size 0.5588)
		(drill 0.3048)
		(layers "F.Cu" "B.Cu")
		(net "GND")
	)
	(via
		(at 449.610734 -163.361624)
		(size 0.5588)
		(drill 0.3048)
		(layers "F.Cu" "B.Cu")
		(net "GND")
	)
	(via
		(at 237.136432 -141.1478)
		(size 0.508)
		(drill 0.254)
		(layers "F.Cu" "B.Cu")
		(net "GND")
	)
	(via
		(at 54.865524 -162.243262)
		(size 0.5588)
		(drill 0.3048)
		(layers "F.Cu" "B.Cu")
		(net "GND")
	)
	(via
		(at 441.990734 -165.596824)
		(size 0.5588)
		(drill 0.3048)
		(layers "F.Cu" "B.Cu")
		(net "GND")
	)
	(via
		(at 287.21812 -76.706984)
		(size 0.508)
		(drill 0.254)
		(layers "F.Cu" "B.Cu")
		(net "GND")
	)
	(via
		(at 238.187738 -82.83194)
		(size 0.508)
		(drill 0.254)
		(layers "F.Cu" "B.Cu")
		(net "GND")
	)
	(via
		(at 288.07664 -94.042738)
		(size 0.508)
		(drill 0.254)
		(layers "F.Cu" "B.Cu")
		(net "GND")
	)
	(via
		(at 128.627124 -162.243262)
		(size 0.5588)
		(drill 0.3048)
		(layers "F.Cu" "B.Cu")
		(net "GND")
	)
	(via
		(at 333.147924 -162.243262)
		(size 0.5588)
		(drill 0.3048)
		(layers "F.Cu" "B.Cu")
		(net "GND")
	)
	(via
		(at 391.3378 -114.6556)
		(size 0.508)
		(drill 0.254)
		(layers "F.Cu" "B.Cu")
		(net "GND")
	)
	(via
		(at 274.914614 -63.334138)
		(size 0.508)
		(drill 0.254)
		(layers "F.Cu" "B.Cu")
		(net "GND")
	)
	(via
		(at 322.0466 -145.8722)
		(size 0.508)
		(drill 0.254)
		(layers "F.Cu" "B.Cu")
		(net "GND")
	)
	(via
		(at 20.8026 -101.1682)
		(size 0.5588)
		(drill 0.3048)
		(layers "F.Cu" "B.Cu")
		(net "GND")
	)
	(via
		(at 86.162134 -167.832024)
		(size 0.5588)
		(drill 0.3048)
		(layers "F.Cu" "B.Cu")
		(net "GND")
	)
	(via
		(at 143.155924 -162.243262)
		(size 0.5588)
		(drill 0.3048)
		(layers "F.Cu" "B.Cu")
		(net "GND")
	)
	(via
		(at 85.206332 -71.935086)
		(size 0.508)
		(drill 0.254)
		(layers "F.Cu" "B.Cu")
		(net "GND")
	)
	(via
		(at 54.737508 -141.202156)
		(size 0.508)
		(drill 0.254)
		(layers "F.Cu" "B.Cu")
		(net "GND")
	)
	(via
		(at 377.544838 -79.094838)
		(size 0.4572)
		(drill 0.2032)
		(layers "F.Cu" "B.Cu")
		(net "GND")
	)
	(via
		(at 138.044174 -145.9357)
		(size 0.508)
		(drill 0.254)
		(layers "F.Cu" "B.Cu")
		(net "GND")
	)
	(via
		(at 292.36924 -62.838584)
		(size 0.508)
		(drill 0.254)
		(layers "F.Cu" "B.Cu")
		(net "GND")
	)
	(via
		(at 358.1781 -14.950186)
		(size 0.508)
		(drill 0.254)
		(layers "F.Cu" "B.Cu")
		(net "GND")
	)
	(via
		(at 251.065284 -91.25204)
		(size 0.508)
		(drill 0.254)
		(layers "F.Cu" "B.Cu")
		(net "GND")
	)
	(via
		(at 85.206332 -91.747086)
		(size 0.508)
		(drill 0.254)
		(layers "F.Cu" "B.Cu")
		(net "GND")
	)
	(via
		(at -4.592066 9.084056)
		(size 0.5588)
		(drill 0.3048)
		(layers "F.Cu" "B.Cu")
		(net "GND")
	)
	(via
		(at 400.080734 -166.714424)
		(size 0.5588)
		(drill 0.3048)
		(layers "F.Cu" "B.Cu")
		(net "GND")
	)
	(via
		(at 236.470698 -56.085486)
		(size 0.508)
		(drill 0.254)
		(layers "F.Cu" "B.Cu")
		(net "GND")
	)
	(via
		(at 245.055644 -55.094886)
		(size 0.508)
		(drill 0.254)
		(layers "F.Cu" "B.Cu")
		(net "GND")
	)
	(via
		(at 81.772252 -88.775286)
		(size 0.508)
		(drill 0.254)
		(layers "F.Cu" "B.Cu")
		(net "GND")
	)
	(via
		(at 499.136924 -162.243262)
		(size 0.5588)
		(drill 0.3048)
		(layers "F.Cu" "B.Cu")
		(net "GND")
	)
	(via
		(at 238.431832 -11.9126)
		(size 0.508)
		(drill 0.254)
		(layers "F.Cu" "B.Cu")
		(net "GND")
	)
	(via
		(at 458.932534 -50.4444)
		(size 0.508)
		(drill 0.254)
		(layers "F.Cu" "B.Cu")
		(net "GND")
	)
	(via
		(at 60.210446 -27.910536)
		(size 0.508)
		(drill 0.254)
		(layers "F.Cu" "B.Cu")
		(net "GND")
	)
	(via
		(at 95.508318 -87.784686)
		(size 0.508)
		(drill 0.254)
		(layers "F.Cu" "B.Cu")
		(net "GND")
	)
	(via
		(at 247.631204 -76.39304)
		(size 0.508)
		(drill 0.254)
		(layers "F.Cu" "B.Cu")
		(net "GND")
	)
	(via
		(at 169.909744 -94.785434)
		(size 0.508)
		(drill 0.254)
		(layers "F.Cu" "B.Cu")
		(net "GND")
	)
	(via
		(at 270.562324 -162.243262)
		(size 0.5588)
		(drill 0.3048)
		(layers "F.Cu" "B.Cu")
		(net "GND")
	)
	(via
		(at 69.753226 -54.104286)
		(size 0.508)
		(drill 0.254)
		(layers "F.Cu" "B.Cu")
		(net "GND")
	)
	(via
		(at 289.79368 -76.211938)
		(size 0.508)
		(drill 0.254)
		(layers "F.Cu" "B.Cu")
		(net "GND")
	)
	(via
		(at 171.2468 -149.5806)
		(size 0.508)
		(drill 0.254)
		(layers "F.Cu" "B.Cu")
		(net "GND")
	)
	(via
		(at 401.350734 -164.479224)
		(size 0.5588)
		(drill 0.3048)
		(layers "F.Cu" "B.Cu")
		(net "GND")
	)
	(via
		(at 273.30908 -82.340196)
		(size 0.5588)
		(drill 0.3048)
		(layers "F.Cu" "B.Cu")
		(net "GND")
	)
	(via
		(at 174.1424 -109.855)
		(size 0.508)
		(drill 0.254)
		(layers "F.Cu" "B.Cu")
		(net "GND")
	)
	(via
		(at 352.274124 -162.268662)
		(size 0.5588)
		(drill 0.3048)
		(layers "F.Cu" "B.Cu")
		(net "GND")
	)
	(via
		(at 58.599324 1.994154)
		(size 0.508)
		(drill 0.254)
		(layers "F.Cu" "B.Cu")
		(net "GND")
	)
	(via
		(at 475.015052 -123.375928)
		(size 0.508)
		(drill 0.254)
		(layers "F.Cu" "B.Cu")
		(net "GND")
	)
	(via
		(at 382.53924 -129.07772)
		(size 0.508)
		(drill 0.254)
		(layers "F.Cu" "B.Cu")
		(net "GND")
	)
	(via
		(at 292.386512 -141.1478)
		(size 0.508)
		(drill 0.254)
		(layers "F.Cu" "B.Cu")
		(net "GND")
	)
	(via
		(at 296.69994 -9.156446)
		(size 0.508)
		(drill 0.254)
		(layers "F.Cu" "B.Cu")
		(net "GND")
	)
	(via
		(at 283.784294 -94.538038)
		(size 0.508)
		(drill 0.254)
		(layers "F.Cu" "B.Cu")
		(net "GND")
	)
	(via
		(at 425.480734 -165.596824)
		(size 0.5588)
		(drill 0.3048)
		(layers "F.Cu" "B.Cu")
		(net "GND")
	)
	(via
		(at 322.051934 14.926056)
		(size 0.5588)
		(drill 0.3048)
		(layers "F.Cu" "B.Cu")
		(net "GND")
	)
	(via
		(at 317.09995 -155.612846)
		(size 0.508)
		(drill 0.254)
		(layers "F.Cu" "B.Cu")
		(net "GND")
	)
	(via
		(at 200.557638 -90.45067)
		(size 0.508)
		(drill 0.254)
		(layers "F.Cu" "B.Cu")
		(net "GND")
	)
	(via
		(at 36.03752 -23.549356)
		(size 0.508)
		(drill 0.254)
		(layers "F.Cu" "B.Cu")
		(net "GND")
	)
	(via
		(at 268.679168 -3.3528)
		(size 0.508)
		(drill 0.254)
		(layers "F.Cu" "B.Cu")
		(net "GND")
	)
	(via
		(at 170.7261 -73.2409)
		(size 0.508)
		(drill 0.254)
		(layers "F.Cu" "B.Cu")
		(net "GND")
	)
	(via
		(at 298.378626 -64.324738)
		(size 0.508)
		(drill 0.254)
		(layers "F.Cu" "B.Cu")
		(net "GND")
	)
	(via
		(at 117.071648 -7.6454)
		(size 0.508)
		(drill 0.254)
		(layers "F.Cu" "B.Cu")
		(net "GND")
	)
	(via
		(at 196.200522 -94.481904)
		(size 0.508)
		(drill 0.254)
		(layers "F.Cu" "B.Cu")
		(net "GND")
	)
	(via
		(at 239.046258 -101.15804)
		(size 0.508)
		(drill 0.254)
		(layers "F.Cu" "B.Cu")
		(net "GND")
	)
	(via
		(at 132.519674 -55.904384)
		(size 0.508)
		(drill 0.254)
		(layers "F.Cu" "B.Cu")
		(net "GND")
	)
	(via
		(at 200.475596 -53.711602)
		(size 0.5588)
		(drill 0.3048)
		(layers "F.Cu" "B.Cu")
		(net "GND")
	)
	(via
		(at 258.79171 -95.709486)
		(size 0.508)
		(drill 0.254)
		(layers "F.Cu" "B.Cu")
		(net "GND")
	)
	(via
		(at 92.863924 -162.243262)
		(size 0.5588)
		(drill 0.3048)
		(layers "F.Cu" "B.Cu")
		(net "GND")
	)
	(via
		(at 165.511734 -167.832024)
		(size 0.5588)
		(drill 0.3048)
		(layers "F.Cu" "B.Cu")
		(net "GND")
	)
	(via
		(at 113.726976 1.82372)
		(size 0.508)
		(drill 0.254)
		(layers "F.Cu" "B.Cu")
		(net "GND")
	)
	(via
		(at 79.196692 -76.39304)
		(size 0.508)
		(drill 0.254)
		(layers "F.Cu" "B.Cu")
		(net "GND")
	)
	(via
		(at 307.040026 -99.986338)
		(size 0.508)
		(drill 0.254)
		(layers "F.Cu" "B.Cu")
		(net "GND")
	)
	(via
		(at 197.151752 -17.208246)
		(size 0.508)
		(drill 0.254)
		(layers "F.Cu" "B.Cu")
		(net "GND")
	)
	(via
		(at 131.661408 -94.042738)
		(size 0.508)
		(drill 0.254)
		(layers "F.Cu" "B.Cu")
		(net "GND")
	)
	(via
		(at 225.858324 -162.243262)
		(size 0.5588)
		(drill 0.3048)
		(layers "F.Cu" "B.Cu")
		(net "GND")
	)
	(via
		(at 221.721934 14.926056)
		(size 0.5588)
		(drill 0.3048)
		(layers "F.Cu" "B.Cu")
		(net "GND")
	)
	(via
		(at 185.413396 -85.182202)
		(size 0.508)
		(drill 0.254)
		(layers "F.Cu" "B.Cu")
		(net "GND")
	)
	(via
		(at 127.368808 -100.481638)
		(size 0.508)
		(drill 0.254)
		(layers "F.Cu" "B.Cu")
		(net "GND")
	)
	(via
		(at 126.471934 9.084056)
		(size 0.5588)
		(drill 0.3048)
		(layers "F.Cu" "B.Cu")
		(net "GND")
	)
	(via
		(at 432.541934 13.910056)
		(size 0.5588)
		(drill 0.3048)
		(layers "F.Cu" "B.Cu")
		(net "GND")
	)
	(via
		(at 397.115792 -143.958564)
		(size 0.508)
		(drill 0.254)
		(layers "F.Cu" "B.Cu")
		(net "GND")
	)
	(via
		(at 390.21385 -119.528844)
		(size 0.508)
		(drill 0.254)
		(layers "F.Cu" "B.Cu")
		(net "GND")
	)
	(via
		(at 295.80332 -84.631784)
		(size 0.508)
		(drill 0.254)
		(layers "F.Cu" "B.Cu")
		(net "GND")
	)
	(via
		(at 221.899734 -17.208246)
		(size 0.508)
		(drill 0.254)
		(layers "F.Cu" "B.Cu")
		(net "GND")
	)
	(via
		(at 410.21 -3.048)
		(size 0.508)
		(drill 0.254)
		(layers "F.Cu" "B.Cu")
		(net "GND")
	)
	(via
		(at 141.899386 -27.943556)
		(size 0.508)
		(drill 0.254)
		(layers "F.Cu" "B.Cu")
		(net "GND")
	)
	(via
		(at 286.07512 -54.913784)
		(size 0.508)
		(drill 0.254)
		(layers "F.Cu" "B.Cu")
		(net "GND")
	)
	(via
		(at 35.880802 -99.165664)
		(size 0.508)
		(drill 0.254)
		(layers "F.Cu" "B.Cu")
		(net "GND")
	)
	(via
		(at 350.75114 -78.8162)
		(size 0.508)
		(drill 0.254)
		(layers "F.Cu" "B.Cu")
		(net "GND")
	)
	(via
		(at 384.76555 -122.104404)
		(size 0.508)
		(drill 0.254)
		(layers "F.Cu" "B.Cu")
		(net "GND")
	)
	(via
		(at 120.807734 -167.832024)
		(size 0.5588)
		(drill 0.3048)
		(layers "F.Cu" "B.Cu")
		(net "GND")
	)
	(via
		(at 484.608378 -22.154642)
		(size 0.508)
		(drill 0.254)
		(layers "F.Cu" "B.Cu")
		(net "GND")
	)
	(via
		(at 18.441162 -120.414288)
		(size 0.508)
		(drill 0.254)
		(layers "F.Cu" "B.Cu")
		(net "GND")
	)
	(via
		(at 31.39948 -9.139682)
		(size 0.508)
		(drill 0.254)
		(layers "F.Cu" "B.Cu")
		(net "GND")
	)
	(via
		(at 350.652334 -135.960104)
		(size 0.508)
		(drill 0.254)
		(layers "F.Cu" "B.Cu")
		(net "GND")
	)
	(via
		(at 300.954186 -74.725784)
		(size 0.508)
		(drill 0.254)
		(layers "F.Cu" "B.Cu")
		(net "GND")
	)
	(via
		(at 112.545876 -75.159616)
		(size 0.5588)
		(drill 0.3048)
		(layers "F.Cu" "B.Cu")
		(net "GND")
	)
	(via
		(at 112.774222 -91.070938)
		(size 0.508)
		(drill 0.254)
		(layers "F.Cu" "B.Cu")
		(net "GND")
	)
	(via
		(at 136.736074 -150.749)
		(size 0.508)
		(drill 0.254)
		(layers "F.Cu" "B.Cu")
		(net "GND")
	)
	(via
		(at 146.098768 -153.6065)
		(size 0.508)
		(drill 0.254)
		(layers "F.Cu" "B.Cu")
		(net "GND")
	)
	(via
		(at 401.350734 -166.714424)
		(size 0.5588)
		(drill 0.3048)
		(layers "F.Cu" "B.Cu")
		(net "GND")
	)
	(via
		(at 224.449894 -26.488136)
		(size 0.508)
		(drill 0.254)
		(layers "F.Cu" "B.Cu")
		(net "GND")
	)
	(via
		(at 307.749956 -148.771356)
		(size 0.508)
		(drill 0.254)
		(layers "F.Cu" "B.Cu")
		(net "GND")
	)
	(via
		(at 252.680724 -162.243262)
		(size 0.5588)
		(drill 0.3048)
		(layers "F.Cu" "B.Cu")
		(net "GND")
	)
	(via
		(at 340.5378 -143.8402)
		(size 0.508)
		(drill 0.254)
		(layers "F.Cu" "B.Cu")
		(net "GND")
	)
	(via
		(at 150.399496 -155.612846)
		(size 0.508)
		(drill 0.254)
		(layers "F.Cu" "B.Cu")
		(net "GND")
	)
	(via
		(at 472.470734 -166.714424)
		(size 0.5588)
		(drill 0.3048)
		(layers "F.Cu" "B.Cu")
		(net "GND")
	)
	(via
		(at 443.260734 -163.361624)
		(size 0.5588)
		(drill 0.3048)
		(layers "F.Cu" "B.Cu")
		(net "GND")
	)
	(via
		(at 429.913542 -21.801582)
		(size 0.508)
		(drill 0.254)
		(layers "F.Cu" "B.Cu")
		(net "GND")
	)
	(via
		(at 429.290734 -167.832024)
		(size 0.5588)
		(drill 0.3048)
		(layers "F.Cu" "B.Cu")
		(net "GND")
	)
	(via
		(at 426.750734 -166.714424)
		(size 0.5588)
		(drill 0.3048)
		(layers "F.Cu" "B.Cu")
		(net "GND")
	)
	(via
		(at 287.21812 -69.772784)
		(size 0.508)
		(drill 0.254)
		(layers "F.Cu" "B.Cu")
		(net "GND")
	)
	(via
		(at 380.30785 -112.660684)
		(size 0.508)
		(drill 0.254)
		(layers "F.Cu" "B.Cu")
		(net "GND")
	)
	(via
		(at 148.699474 -9.156446)
		(size 0.508)
		(drill 0.254)
		(layers "F.Cu" "B.Cu")
		(net "GND")
	)
	(via
		(at 72.328786 -89.27084)
		(size 0.508)
		(drill 0.254)
		(layers "F.Cu" "B.Cu")
		(net "GND")
	)
	(via
		(at 225.210878 -140.592556)
		(size 0.508)
		(drill 0.254)
		(layers "F.Cu" "B.Cu")
		(net "GND")
	)
	(via
		(at 113.348262 -62.343538)
		(size 0.508)
		(drill 0.254)
		(layers "F.Cu" "B.Cu")
		(net "GND")
	)
	(via
		(at 340.3854 -114.935)
		(size 0.508)
		(drill 0.254)
		(layers "F.Cu" "B.Cu")
		(net "GND")
	)
	(via
		(at 438.891934 14.926056)
		(size 0.5588)
		(drill 0.3048)
		(layers "F.Cu" "B.Cu")
		(net "GND")
	)
	(via
		(at 488.421934 13.910056)
		(size 0.5588)
		(drill 0.3048)
		(layers "F.Cu" "B.Cu")
		(net "GND")
	)
	(via
		(at 197.160896 -130.991356)
		(size 0.508)
		(drill 0.254)
		(layers "F.Cu" "B.Cu")
		(net "GND")
	)
	(via
		(at 109.055916 -63.829184)
		(size 0.508)
		(drill 0.254)
		(layers "F.Cu" "B.Cu")
		(net "GND")
	)
	(via
		(at 387.021324 -162.243262)
		(size 0.5588)
		(drill 0.3048)
		(layers "F.Cu" "B.Cu")
		(net "GND")
	)
	(via
		(at 159.923734 -167.832024)
		(size 0.5588)
		(drill 0.3048)
		(layers "F.Cu" "B.Cu")
		(net "GND")
	)
	(via
		(at 129.999486 -2.314956)
		(size 0.508)
		(drill 0.254)
		(layers "F.Cu" "B.Cu")
		(net "GND")
	)
	(via
		(at 36.301934 14.926056)
		(size 0.5588)
		(drill 0.3048)
		(layers "F.Cu" "B.Cu")
		(net "GND")
	)
	(via
		(at 143.501364 1.994154)
		(size 0.508)
		(drill 0.254)
		(layers "F.Cu" "B.Cu")
		(net "GND")
	)
	(via
		(at 499.851934 13.910056)
		(size 0.5588)
		(drill 0.3048)
		(layers "F.Cu" "B.Cu")
		(net "GND")
	)
	(via
		(at 236.470698 -92.737686)
		(size 0.508)
		(drill 0.254)
		(layers "F.Cu" "B.Cu")
		(net "GND")
	)
	(via
		(at 41.359582 -68.917058)
		(size 0.5588)
		(drill 0.3048)
		(layers "F.Cu" "B.Cu")
		(net "GND")
	)
	(via
		(at 160.556702 -126.210568)
		(size 0.508)
		(drill 0.254)
		(layers "F.Cu" "B.Cu")
		(net "GND")
	)
	(via
		(at 127.404368 2.4638)
		(size 0.508)
		(drill 0.254)
		(layers "F.Cu" "B.Cu")
		(net "GND")
	)
	(via
		(at 229.081838 -139.1666)
		(size 0.508)
		(drill 0.254)
		(layers "F.Cu" "B.Cu")
		(net "GND")
	)
	(via
		(at 127.368808 -69.772784)
		(size 0.508)
		(drill 0.254)
		(layers "F.Cu" "B.Cu")
		(net "GND")
	)
	(via
		(at 422.865042 -3.374898)
		(size 0.508)
		(drill 0.254)
		(layers "F.Cu" "B.Cu")
		(net "GND")
	)
	(via
		(at 116.361464 -21.517356)
		(size 0.508)
		(drill 0.254)
		(layers "F.Cu" "B.Cu")
		(net "GND")
	)
	(via
		(at 326.644 -33.528)
		(size 0.508)
		(drill 0.254)
		(layers "F.Cu" "B.Cu")
		(net "GND")
	)
	(via
		(at 123.5075 -150.11908)
		(size 0.508)
		(drill 0.254)
		(layers "F.Cu" "B.Cu")
		(net "GND")
	)
	(via
		(at 221.04985 -129.568956)
		(size 0.508)
		(drill 0.254)
		(layers "F.Cu" "B.Cu")
		(net "GND")
	)
	(via
		(at 104.018588 5.281676)
		(size 0.508)
		(drill 0.254)
		(layers "F.Cu" "B.Cu")
		(net "GND")
	)
	(via
		(at 303.027842 -2.3622)
		(size 0.508)
		(drill 0.254)
		(layers "F.Cu" "B.Cu")
		(net "GND")
	)
	(via
		(at 278.93264 -135.587486)
		(size 0.508)
		(drill 0.254)
		(layers "F.Cu" "B.Cu")
		(net "GND")
	)
	(via
		(at 442.976 -50.4952)
		(size 0.508)
		(drill 0.254)
		(layers "F.Cu" "B.Cu")
		(net "GND")
	)
	(via
		(at 303.529746 -53.427884)
		(size 0.508)
		(drill 0.254)
		(layers "F.Cu" "B.Cu")
		(net "GND")
	)
	(via
		(at 128.227328 -91.070938)
		(size 0.508)
		(drill 0.254)
		(layers "F.Cu" "B.Cu")
		(net "GND")
	)
	(via
		(at 2.342134 -167.832024)
		(size 0.5588)
		(drill 0.3048)
		(layers "F.Cu" "B.Cu")
		(net "GND")
	)
	(via
		(at 495.326924 -162.243262)
		(size 0.5588)
		(drill 0.3048)
		(layers "F.Cu" "B.Cu")
		(net "GND")
	)
	(via
		(at 70.461378 -155.562046)
		(size 0.508)
		(drill 0.254)
		(layers "F.Cu" "B.Cu")
		(net "GND")
	)
	(via
		(at 403.890734 -163.361624)
		(size 0.5588)
		(drill 0.3048)
		(layers "F.Cu" "B.Cu")
		(net "GND")
	)
	(via
		(at 493.501934 13.910056)
		(size 0.5588)
		(drill 0.3048)
		(layers "F.Cu" "B.Cu")
		(net "GND")
	)
	(via
		(at 115.627404 -74.088244)
		(size 0.5588)
		(drill 0.3048)
		(layers "F.Cu" "B.Cu")
		(net "GND")
	)
	(via
		(at 215.85174 -17.208246)
		(size 0.508)
		(drill 0.254)
		(layers "F.Cu" "B.Cu")
		(net "GND")
	)
	(via
		(at 108.126276 -82.339942)
		(size 0.5588)
		(drill 0.3048)
		(layers "F.Cu" "B.Cu")
		(net "GND")
	)
	(via
		(at 389.291068 -147.282662)
		(size 0.508)
		(drill 0.254)
		(layers "F.Cu" "B.Cu")
		(net "GND")
	)
	(via
		(at 291.422074 -125.347476)
		(size 0.508)
		(drill 0.254)
		(layers "F.Cu" "B.Cu")
		(net "GND")
	)
	(via
		(at 345.2114 -67.4624)
		(size 0.508)
		(drill 0.254)
		(layers "F.Cu" "B.Cu")
		(net "GND")
	)
	(via
		(at 240.387124 -162.243262)
		(size 0.5588)
		(drill 0.3048)
		(layers "F.Cu" "B.Cu")
		(net "GND")
	)
	(via
		(at 309.411878 -139.170156)
		(size 0.508)
		(drill 0.254)
		(layers "F.Cu" "B.Cu")
		(net "GND")
	)
	(via
		(at 389.991346 -48.49368)
		(size 0.508)
		(drill 0.254)
		(layers "F.Cu" "B.Cu")
		(net "GND")
	)
	(via
		(at 346.5322 -85.9282)
		(size 0.508)
		(drill 0.254)
		(layers "F.Cu" "B.Cu")
		(net "GND")
	)
	(via
		(at 275.032724 -162.243262)
		(size 0.5588)
		(drill 0.3048)
		(layers "F.Cu" "B.Cu")
		(net "GND")
	)
	(via
		(at 231.249728 -27.935936)
		(size 0.508)
		(drill 0.254)
		(layers "F.Cu" "B.Cu")
		(net "GND")
	)
	(via
		(at 246.5832 -12.91844)
		(size 0.508)
		(drill 0.254)
		(layers "F.Cu" "B.Cu")
		(net "GND")
	)
	(via
		(at 243.1288 -18.7452)
		(size 0.508)
		(drill 0.254)
		(layers "F.Cu" "B.Cu")
		(net "GND")
	)
	(via
		(at 216.761822 -148.771356)
		(size 0.508)
		(drill 0.254)
		(layers "F.Cu" "B.Cu")
		(net "GND")
	)
	(via
		(at 277.774654 -100.976684)
		(size 0.508)
		(drill 0.254)
		(layers "F.Cu" "B.Cu")
		(net "GND")
	)
	(via
		(at 139.34948 -11.916156)
		(size 0.508)
		(drill 0.254)
		(layers "F.Cu" "B.Cu")
		(net "GND")
	)
	(via
		(at 79.196692 -74.411586)
		(size 0.508)
		(drill 0.254)
		(layers "F.Cu" "B.Cu")
		(net "GND")
	)
	(via
		(at 121.074688 -65.810384)
		(size 0.508)
		(drill 0.254)
		(layers "F.Cu" "B.Cu")
		(net "GND")
	)
	(via
		(at 52.471574 -134.8994)
		(size 0.508)
		(drill 0.254)
		(layers "F.Cu" "B.Cu")
		(net "GND")
	)
	(via
		(at 303.050194 0.508)
		(size 0.508)
		(drill 0.254)
		(layers "F.Cu" "B.Cu")
		(net "GND")
	)
	(via
		(at 295.80332 -56.894984)
		(size 0.508)
		(drill 0.254)
		(layers "F.Cu" "B.Cu")
		(net "GND")
	)
	(via
		(at 304.162968 -51.144424)
		(size 0.508)
		(drill 0.254)
		(layers "F.Cu" "B.Cu")
		(net "GND")
	)
	(via
		(at 0.89662 -24.08936)
		(size 0.508)
		(drill 0.254)
		(layers "F.Cu" "B.Cu")
		(net "GND")
	)
	(via
		(at 267.213334 -167.832024)
		(size 0.5588)
		(drill 0.3048)
		(layers "F.Cu" "B.Cu")
		(net "GND")
	)
	(via
		(at 272.027904 -17.7546)
		(size 0.508)
		(drill 0.254)
		(layers "F.Cu" "B.Cu")
		(net "GND")
	)
	(via
		(at 265.1252 2.4638)
		(size 0.508)
		(drill 0.254)
		(layers "F.Cu" "B.Cu")
		(net "GND")
	)
	(via
		(at 239.046258 -80.35544)
		(size 0.508)
		(drill 0.254)
		(layers "F.Cu" "B.Cu")
		(net "GND")
	)
	(via
		(at 73.187306 -92.737686)
		(size 0.508)
		(drill 0.254)
		(layers "F.Cu" "B.Cu")
		(net "GND")
	)
	(via
		(at -4.555744 10.307066)
		(size 0.5588)
		(drill 0.3048)
		(layers "F.Cu" "B.Cu")
		(net "GND")
	)
	(via
		(at 389.7376 -114.6556)
		(size 0.508)
		(drill 0.254)
		(layers "F.Cu" "B.Cu")
		(net "GND")
	)
	(via
		(at 257.151124 -162.243262)
		(size 0.5588)
		(drill 0.3048)
		(layers "F.Cu" "B.Cu")
		(net "GND")
	)
	(via
		(at 68.036186 -64.010286)
		(size 0.508)
		(drill 0.254)
		(layers "F.Cu" "B.Cu")
		(net "GND")
	)
	(via
		(at 210.38185 -11.9126)
		(size 0.508)
		(drill 0.254)
		(layers "F.Cu" "B.Cu")
		(net "GND")
	)
	(via
		(at 204.899768 -144.462246)
		(size 0.508)
		(drill 0.254)
		(layers "F.Cu" "B.Cu")
		(net "GND")
	)
	(via
		(at 197.160896 -140.592556)
		(size 0.508)
		(drill 0.254)
		(layers "F.Cu" "B.Cu")
		(net "GND")
	)
	(via
		(at 430.556924 -162.243262)
		(size 0.5588)
		(drill 0.3048)
		(layers "F.Cu" "B.Cu")
		(net "GND")
	)
	(via
		(at 90.357198 -65.991486)
		(size 0.508)
		(drill 0.254)
		(layers "F.Cu" "B.Cu")
		(net "GND")
	)
	(via
		(at 334.265524 -162.243262)
		(size 0.5588)
		(drill 0.3048)
		(layers "F.Cu" "B.Cu")
		(net "GND")
	)
	(via
		(at 293.694612 -145.9357)
		(size 0.508)
		(drill 0.254)
		(layers "F.Cu" "B.Cu")
		(net "GND")
	)
	(via
		(at 126.391924 -162.243262)
		(size 0.5588)
		(drill 0.3048)
		(layers "F.Cu" "B.Cu")
		(net "GND")
	)
	(via
		(at 84.347812 -84.31784)
		(size 0.508)
		(drill 0.254)
		(layers "F.Cu" "B.Cu")
		(net "GND")
	)
	(via
		(at 171.095924 -162.243262)
		(size 0.5588)
		(drill 0.3048)
		(layers "F.Cu" "B.Cu")
		(net "GND")
	)
	(via
		(at 64.923924 -162.243262)
		(size 0.5588)
		(drill 0.3048)
		(layers "F.Cu" "B.Cu")
		(net "GND")
	)
	(via
		(at 243.338604 -65.991486)
		(size 0.508)
		(drill 0.254)
		(layers "F.Cu" "B.Cu")
		(net "GND")
	)
	(via
		(at 210.387946 -13.948156)
		(size 0.508)
		(drill 0.254)
		(layers "F.Cu" "B.Cu")
		(net "GND")
	)
	(via
		(at 477.84639 -118.630446)
		(size 0.508)
		(drill 0.254)
		(layers "F.Cu" "B.Cu")
		(net "GND")
	)
	(via
		(at 380.30785 -114.377724)
		(size 0.508)
		(drill 0.254)
		(layers "F.Cu" "B.Cu")
		(net "GND")
	)
	(via
		(at 365.7981 -44.5897)
		(size 0.508)
		(drill 0.254)
		(layers "F.Cu" "B.Cu")
		(net "GND")
	)
	(via
		(at 84.910168 -12.954)
		(size 0.508)
		(drill 0.254)
		(layers "F.Cu" "B.Cu")
		(net "GND")
	)
	(via
		(at 464.291934 10.354056)
		(size 0.5588)
		(drill 0.3048)
		(layers "F.Cu" "B.Cu")
		(net "GND")
	)
	(via
		(at 40.709596 -85.231224)
		(size 0.5588)
		(drill 0.3048)
		(layers "F.Cu" "B.Cu")
		(net "GND")
	)
	(via
		(at 466.415374 -149.636988)
		(size 0.508)
		(drill 0.254)
		(layers "F.Cu" "B.Cu")
		(net "GND")
	)
	(via
		(at 483.650544 -35.60064)
		(size 0.508)
		(drill 0.254)
		(layers "F.Cu" "B.Cu")
		(net "GND")
	)
	(via
		(at 304.388266 -82.650584)
		(size 0.508)
		(drill 0.254)
		(layers "F.Cu" "B.Cu")
		(net "GND")
	)
	(via
		(at 301.812706 -93.052138)
		(size 0.508)
		(drill 0.254)
		(layers "F.Cu" "B.Cu")
		(net "GND")
	)
	(via
		(at 291.422074 -134.8994)
		(size 0.508)
		(drill 0.254)
		(layers "F.Cu" "B.Cu")
		(net "GND")
	)
	(via
		(at 311.104788 2.4638)
		(size 0.508)
		(drill 0.254)
		(layers "F.Cu" "B.Cu")
		(net "GND")
	)
	(via
		(at 189.153292 -84.535264)
		(size 0.5588)
		(drill 0.3048)
		(layers "F.Cu" "B.Cu")
		(net "GND")
	)
	(via
		(at 92.932758 -60.54344)
		(size 0.508)
		(drill 0.254)
		(layers "F.Cu" "B.Cu")
		(net "GND")
	)
	(via
		(at 74.045826 -54.59984)
		(size 0.508)
		(drill 0.254)
		(layers "F.Cu" "B.Cu")
		(net "GND")
	)
	(via
		(at 470.4842 -64.008)
		(size 0.508)
		(drill 0.254)
		(layers "F.Cu" "B.Cu")
		(net "GND")
	)
	(via
		(at 352.052382 -126.697994)
		(size 0.508)
		(drill 0.254)
		(layers "F.Cu" "B.Cu")
		(net "GND")
	)
	(via
		(at 288.19983 1.994154)
		(size 0.508)
		(drill 0.254)
		(layers "F.Cu" "B.Cu")
		(net "GND")
	)
	(via
		(at 127.407162 -7.1374)
		(size 0.508)
		(drill 0.254)
		(layers "F.Cu" "B.Cu")
		(net "GND")
	)
	(via
		(at 116.208302 -90.080338)
		(size 0.508)
		(drill 0.254)
		(layers "F.Cu" "B.Cu")
		(net "GND")
	)
	(via
		(at 467.390734 -163.361624)
		(size 0.5588)
		(drill 0.3048)
		(layers "F.Cu" "B.Cu")
		(net "GND")
	)
	(via
		(at 71.171562 -22.965156)
		(size 0.508)
		(drill 0.254)
		(layers "F.Cu" "B.Cu")
		(net "GND")
	)
	(via
		(at 345.4654 -40.64)
		(size 0.508)
		(drill 0.254)
		(layers "F.Cu" "B.Cu")
		(net "GND")
	)
	(via
		(at 37.34943 -21.517356)
		(size 0.508)
		(drill 0.254)
		(layers "F.Cu" "B.Cu")
		(net "GND")
	)
	(via
		(at 464.4898 -137.224008)
		(size 0.508)
		(drill 0.254)
		(layers "F.Cu" "B.Cu")
		(net "GND")
	)
	(via
		(at 358.92105 -116.220494)
		(size 0.508)
		(drill 0.254)
		(layers "F.Cu" "B.Cu")
		(net "GND")
	)
	(via
		(at 336.504534 -167.832024)
		(size 0.5588)
		(drill 0.3048)
		(layers "F.Cu" "B.Cu")
		(net "GND")
	)
	(via
		(at 200.533 -98.3742)
		(size 0.508)
		(drill 0.254)
		(layers "F.Cu" "B.Cu")
		(net "GND")
	)
	(via
		(at 141.049502 -148.771356)
		(size 0.508)
		(drill 0.254)
		(layers "F.Cu" "B.Cu")
		(net "GND")
	)
	(via
		(at 465.561934 12.894056)
		(size 0.5588)
		(drill 0.3048)
		(layers "F.Cu" "B.Cu")
		(net "GND")
	)
	(via
		(at 494.771934 13.910056)
		(size 0.5588)
		(drill 0.3048)
		(layers "F.Cu" "B.Cu")
		(net "GND")
	)
	(via
		(at 197.151752 -7.607046)
		(size 0.508)
		(drill 0.254)
		(layers "F.Cu" "B.Cu")
		(net "GND")
	)
	(via
		(at 47.549308 1.994154)
		(size 0.508)
		(drill 0.254)
		(layers "F.Cu" "B.Cu")
		(net "GND")
	)
	(via
		(at 203.199746 -134.861046)
		(size 0.508)
		(drill 0.254)
		(layers "F.Cu" "B.Cu")
		(net "GND")
	)
	(via
		(at 284.358334 -57.885584)
		(size 0.508)
		(drill 0.254)
		(layers "F.Cu" "B.Cu")
		(net "GND")
	)
	(via
		(at 58.599324 -17.208246)
		(size 0.508)
		(drill 0.254)
		(layers "F.Cu" "B.Cu")
		(net "GND")
	)
	(via
		(at 396.65275 -116.953284)
		(size 0.508)
		(drill 0.254)
		(layers "F.Cu" "B.Cu")
		(net "GND")
	)
	(via
		(at 267.441934 9.084056)
		(size 0.5588)
		(drill 0.3048)
		(layers "F.Cu" "B.Cu")
		(net "GND")
	)
	(via
		(at 233.151934 9.084056)
		(size 0.5588)
		(drill 0.3048)
		(layers "F.Cu" "B.Cu")
		(net "GND")
	)
	(via
		(at 152.099518 -148.782278)
		(size 0.508)
		(drill 0.254)
		(layers "F.Cu" "B.Cu")
		(net "GND")
	)
	(via
		(at 342.9254 -39.37)
		(size 0.508)
		(drill 0.254)
		(layers "F.Cu" "B.Cu")
		(net "GND")
	)
	(via
		(at 76.451968 -28.5242)
		(size 0.508)
		(drill 0.254)
		(layers "F.Cu" "B.Cu")
		(net "GND")
	)
	(via
		(at 434.370734 -167.832024)
		(size 0.5588)
		(drill 0.3048)
		(layers "F.Cu" "B.Cu")
		(net "GND")
	)
	(via
		(at 117.071648 -130.991356)
		(size 0.508)
		(drill 0.254)
		(layers "F.Cu" "B.Cu")
		(net "GND")
	)
	(via
		(at 378.284994 -8.84682)
		(size 0.508)
		(drill 0.254)
		(layers "F.Cu" "B.Cu")
		(net "GND")
	)
	(via
		(at 281.399996 -155.612846)
		(size 0.508)
		(drill 0.254)
		(layers "F.Cu" "B.Cu")
		(net "GND")
	)
	(via
		(at 64.090804 -26.682954)
		(size 0.508)
		(drill 0.254)
		(layers "F.Cu" "B.Cu")
		(net "GND")
	)
	(via
		(at 346.395294 -147.668742)
		(size 0.508)
		(drill 0.254)
		(layers "F.Cu" "B.Cu")
		(net "GND")
	)
	(via
		(at 369.041934 -167.857424)
		(size 0.5588)
		(drill 0.3048)
		(layers "F.Cu" "B.Cu")
		(net "GND")
	)
	(via
		(at 289.049968 -11.916156)
		(size 0.508)
		(drill 0.254)
		(layers "F.Cu" "B.Cu")
		(net "GND")
	)
	(via
		(at 234.560872 -150.193756)
		(size 0.508)
		(drill 0.254)
		(layers "F.Cu" "B.Cu")
		(net "GND")
	)
	(via
		(at 349.504 -146.165824)
		(size 0.508)
		(drill 0.254)
		(layers "F.Cu" "B.Cu")
		(net "GND")
	)
	(via
		(at 358.78643 -107.181396)
		(size 0.508)
		(drill 0.254)
		(layers "F.Cu" "B.Cu")
		(net "GND")
	)
	(via
		(at 242.480338 -69.45884)
		(size 0.508)
		(drill 0.254)
		(layers "F.Cu" "B.Cu")
		(net "GND")
	)
	(via
		(at 156.567124 -162.243262)
		(size 0.5588)
		(drill 0.3048)
		(layers "F.Cu" "B.Cu")
		(net "GND")
	)
	(via
		(at 500.410734 -165.596824)
		(size 0.5588)
		(drill 0.3048)
		(layers "F.Cu" "B.Cu")
		(net "GND")
	)
	(via
		(at 280.924254 -65.810384)
		(size 0.508)
		(drill 0.254)
		(layers "F.Cu" "B.Cu")
		(net "GND")
	)
	(via
		(at 270.196818 -75.148186)
		(size 0.5588)
		(drill 0.3048)
		(layers "F.Cu" "B.Cu")
		(net "GND")
	)
	(via
		(at 255.627124 -150.105364)
		(size 0.508)
		(drill 0.254)
		(layers "F.Cu" "B.Cu")
		(net "GND")
	)
	(via
		(at 378.4854 -124.3838)
		(size 0.508)
		(drill 0.254)
		(layers "F.Cu" "B.Cu")
		(net "GND")
	)
	(via
		(at 204.899768 1.994154)
		(size 0.508)
		(drill 0.254)
		(layers "F.Cu" "B.Cu")
		(net "GND")
	)
	(via
		(at 181.0004 -145.2626)
		(size 0.508)
		(drill 0.254)
		(layers "F.Cu" "B.Cu")
		(net "GND")
	)
	(via
		(at 301.736506 -23.495)
		(size 0.508)
		(drill 0.254)
		(layers "F.Cu" "B.Cu")
		(net "GND")
	)
	(via
		(at 279.699974 -11.9126)
		(size 0.508)
		(drill 0.254)
		(layers "F.Cu" "B.Cu")
		(net "GND")
	)
	(via
		(at 40.394382 -92.572078)
		(size 0.5588)
		(drill 0.3048)
		(layers "F.Cu" "B.Cu")
		(net "GND")
	)
	(via
		(at 73.187306 -80.850486)
		(size 0.508)
		(drill 0.254)
		(layers "F.Cu" "B.Cu")
		(net "GND")
	)
	(via
		(at 294.9448 -61.352938)
		(size 0.508)
		(drill 0.254)
		(layers "F.Cu" "B.Cu")
		(net "GND")
	)
	(via
		(at 236.171994 -22.965156)
		(size 0.508)
		(drill 0.254)
		(layers "F.Cu" "B.Cu")
		(net "GND")
	)
	(via
		(at 485.452674 -34.822638)
		(size 0.508)
		(drill 0.254)
		(layers "F.Cu" "B.Cu")
		(net "GND")
	)
	(via
		(at 220.451934 9.084056)
		(size 0.5588)
		(drill 0.3048)
		(layers "F.Cu" "B.Cu")
		(net "GND")
	)
	(via
		(at 200.944988 -51.902106)
		(size 0.5588)
		(drill 0.3048)
		(layers "F.Cu" "B.Cu")
		(net "GND")
	)
	(via
		(at -4.572 -62.8396)
		(size 0.508)
		(drill 0.254)
		(layers "F.Cu" "B.Cu")
		(net "GND")
	)
	(via
		(at 14.711934 14.926056)
		(size 0.5588)
		(drill 0.3048)
		(layers "F.Cu" "B.Cu")
		(net "GND")
	)
	(via
		(at 227.786438 -141.1478)
		(size 0.508)
		(drill 0.254)
		(layers "F.Cu" "B.Cu")
		(net "GND")
	)
	(via
		(at 208.122012 -131.004056)
		(size 0.508)
		(drill 0.254)
		(layers "F.Cu" "B.Cu")
		(net "GND")
	)
	(via
		(at 93.791278 -56.085486)
		(size 0.508)
		(drill 0.254)
		(layers "F.Cu" "B.Cu")
		(net "GND")
	)
	(via
		(at 268.27988 -82.340196)
		(size 0.5588)
		(drill 0.3048)
		(layers "F.Cu" "B.Cu")
		(net "GND")
	)
	(via
		(at 69.551296 -154.063446)
		(size 0.508)
		(drill 0.254)
		(layers "F.Cu" "B.Cu")
		(net "GND")
	)
	(via
		(at 192.511934 14.926056)
		(size 0.5588)
		(drill 0.3048)
		(layers "F.Cu" "B.Cu")
		(net "GND")
	)
	(via
		(at 355.16185 -115.204494)
		(size 0.508)
		(drill 0.254)
		(layers "F.Cu" "B.Cu")
		(net "GND")
	)
	(via
		(at 365.685324 -162.268662)
		(size 0.5588)
		(drill 0.3048)
		(layers "F.Cu" "B.Cu")
		(net "GND")
	)
	(via
		(at 5.832856 13.609066)
		(size 0.5588)
		(drill 0.3048)
		(layers "F.Cu" "B.Cu")
		(net "GND")
	)
	(via
		(at 301.812706 -60.362338)
		(size 0.508)
		(drill 0.254)
		(layers "F.Cu" "B.Cu")
		(net "GND")
	)
	(via
		(at 286.499808 -134.861046)
		(size 0.508)
		(drill 0.254)
		(layers "F.Cu" "B.Cu")
		(net "GND")
	)
	(via
		(at 314.431934 9.084056)
		(size 0.5588)
		(drill 0.3048)
		(layers "F.Cu" "B.Cu")
		(net "GND")
	)
	(via
		(at 82.343498 -126.947422)
		(size 0.508)
		(drill 0.254)
		(layers "F.Cu" "B.Cu")
		(net "GND")
	)
	(via
		(at 117.071648 -17.2466)
		(size 0.508)
		(drill 0.254)
		(layers "F.Cu" "B.Cu")
		(net "GND")
	)
	(via
		(at 78.338172 -66.982086)
		(size 0.508)
		(drill 0.254)
		(layers "F.Cu" "B.Cu")
		(net "GND")
	)
	(via
		(at 286.3596 -73.240138)
		(size 0.508)
		(drill 0.254)
		(layers "F.Cu" "B.Cu")
		(net "GND")
	)
	(via
		(at 247.4214 -26.289)
		(size 0.508)
		(drill 0.254)
		(layers "F.Cu" "B.Cu")
		(net "GND")
	)
	(via
		(at 126.5809 -53.3146)
		(size 0.508)
		(drill 0.254)
		(layers "F.Cu" "B.Cu")
		(net "GND")
	)
	(via
		(at 39.049452 -21.517356)
		(size 0.508)
		(drill 0.254)
		(layers "F.Cu" "B.Cu")
		(net "GND")
	)
	(via
		(at 17.988534 -167.832024)
		(size 0.5588)
		(drill 0.3048)
		(layers "F.Cu" "B.Cu")
		(net "GND")
	)
	(via
		(at 239.904778 -94.718886)
		(size 0.508)
		(drill 0.254)
		(layers "F.Cu" "B.Cu")
		(net "GND")
	)
	(via
		(at 456.671934 10.354056)
		(size 0.5588)
		(drill 0.3048)
		(layers "F.Cu" "B.Cu")
		(net "GND")
	)
	(via
		(at 300.737524 -162.243262)
		(size 0.5588)
		(drill 0.3048)
		(layers "F.Cu" "B.Cu")
		(net "GND")
	)
	(via
		(at 168.381934 9.084056)
		(size 0.5588)
		(drill 0.3048)
		(layers "F.Cu" "B.Cu")
		(net "GND")
	)
	(via
		(at 465.836 -135.8646)
		(size 0.508)
		(drill 0.254)
		(layers "F.Cu" "B.Cu")
		(net "GND")
	)
	(via
		(at 416.289998 -36.534598)
		(size 0.4572)
		(drill 0.2032)
		(layers "F.Cu" "B.Cu")
		(net "GND")
	)
	(via
		(at 290.74999 -146.011646)
		(size 0.508)
		(drill 0.254)
		(layers "F.Cu" "B.Cu")
		(net "GND")
	)
	(via
		(at 39.899336 -144.462246)
		(size 0.508)
		(drill 0.254)
		(layers "F.Cu" "B.Cu")
		(net "GND")
	)
	(via
		(at 81.772252 -78.869286)
		(size 0.508)
		(drill 0.254)
		(layers "F.Cu" "B.Cu")
		(net "GND")
	)
	(via
		(at 382.28905 -119.528844)
		(size 0.508)
		(drill 0.254)
		(layers "F.Cu" "B.Cu")
		(net "GND")
	)
	(via
		(at 178.308 -61.9506)
		(size 0.508)
		(drill 0.254)
		(layers "F.Cu" "B.Cu")
		(net "GND")
	)
	(via
		(at 135.771636 -140.617956)
		(size 0.508)
		(drill 0.254)
		(layers "F.Cu" "B.Cu")
		(net "GND")
	)
	(via
		(at 140.246354 -73.240138)
		(size 0.508)
		(drill 0.254)
		(layers "F.Cu" "B.Cu")
		(net "GND")
	)
	(via
		(at 300.772068 -150.219156)
		(size 0.508)
		(drill 0.254)
		(layers "F.Cu" "B.Cu")
		(net "GND")
	)
	(via
		(at 488.980734 -165.596824)
		(size 0.5588)
		(drill 0.3048)
		(layers "F.Cu" "B.Cu")
		(net "GND")
	)
	(via
		(at 395.16685 -122.962924)
		(size 0.508)
		(drill 0.254)
		(layers "F.Cu" "B.Cu")
		(net "GND")
	)
	(via
		(at 6.583934 14.926056)
		(size 0.5588)
		(drill 0.3048)
		(layers "F.Cu" "B.Cu")
		(net "GND")
	)
	(via
		(at 491.520734 -165.596824)
		(size 0.5588)
		(drill 0.3048)
		(layers "F.Cu" "B.Cu")
		(net "GND")
	)
	(via
		(at 280.451814 -7.607046)
		(size 0.508)
		(drill 0.254)
		(layers "F.Cu" "B.Cu")
		(net "GND")
	)
	(via
		(at 277.203154 -88.518238)
		(size 0.508)
		(drill 0.254)
		(layers "F.Cu" "B.Cu")
		(net "GND")
	)
	(via
		(at 14.605 -98.5774)
		(size 0.508)
		(drill 0.254)
		(layers "F.Cu" "B.Cu")
		(net "GND")
	)
	(via
		(at 257.6449 -18.542)
		(size 0.508)
		(drill 0.254)
		(layers "F.Cu" "B.Cu")
		(net "GND")
	)
	(via
		(at 27.234896 -100.037392)
		(size 0.508)
		(drill 0.254)
		(layers "F.Cu" "B.Cu")
		(net "GND")
	)
	(via
		(at 359.6132 -121.285)
		(size 0.508)
		(drill 0.254)
		(layers "F.Cu" "B.Cu")
		(net "GND")
	)
	(via
		(at 445.564006 -31.5595)
		(size 0.4572)
		(drill 0.2032)
		(layers "F.Cu" "B.Cu")
		(net "GND")
	)
	(via
		(at 294.9448 -100.976684)
		(size 0.508)
		(drill 0.254)
		(layers "F.Cu" "B.Cu")
		(net "GND")
	)
	(via
		(at 26.774648 -141.37132)
		(size 0.508)
		(drill 0.254)
		(layers "F.Cu" "B.Cu")
		(net "GND")
	)
	(via
		(at 450.149976 -58.954924)
		(size 0.508)
		(drill 0.254)
		(layers "F.Cu" "B.Cu")
		(net "GND")
	)
	(via
		(at 45.381418 -21.5138)
		(size 0.508)
		(drill 0.254)
		(layers "F.Cu" "B.Cu")
		(net "GND")
	)
	(via
		(at 102.335076 -82.339942)
		(size 0.5588)
		(drill 0.3048)
		(layers "F.Cu" "B.Cu")
		(net "GND")
	)
	(via
		(at 480.090734 -166.714424)
		(size 0.5588)
		(drill 0.3048)
		(layers "F.Cu" "B.Cu")
		(net "GND")
	)
	(via
		(at 128.690878 2.505456)
		(size 0.508)
		(drill 0.254)
		(layers "F.Cu" "B.Cu")
		(net "GND")
	)
	(via
		(at 364.4392 -63.2206)
		(size 0.508)
		(drill 0.254)
		(layers "F.Cu" "B.Cu")
		(net "GND")
	)
	(via
		(at 374.0277 -100.965)
		(size 0.508)
		(drill 0.254)
		(layers "F.Cu" "B.Cu")
		(net "GND")
	)
	(via
		(at 200.6092 -70.2056)
		(size 0.5588)
		(drill 0.3048)
		(layers "F.Cu" "B.Cu")
		(net "GND")
	)
	(via
		(at 300.772068 -140.617956)
		(size 0.508)
		(drill 0.254)
		(layers "F.Cu" "B.Cu")
		(net "GND")
	)
	(via
		(at 144.251934 9.084056)
		(size 0.5588)
		(drill 0.3048)
		(layers "F.Cu" "B.Cu")
		(net "GND")
	)
	(via
		(at 280.924254 -54.913784)
		(size 0.508)
		(drill 0.254)
		(layers "F.Cu" "B.Cu")
		(net "GND")
	)
	(via
		(at 69.753226 -57.076086)
		(size 0.508)
		(drill 0.254)
		(layers "F.Cu" "B.Cu")
		(net "GND")
	)
	(via
		(at 141.104874 -62.838584)
		(size 0.508)
		(drill 0.254)
		(layers "F.Cu" "B.Cu")
		(net "GND")
	)
	(via
		(at 475.45117 -26.463752)
		(size 0.508)
		(drill 0.254)
		(layers "F.Cu" "B.Cu")
		(net "GND")
	)
	(via
		(at 183.389524 -162.243262)
		(size 0.5588)
		(drill 0.3048)
		(layers "F.Cu" "B.Cu")
		(net "GND")
	)
	(via
		(at 53.448712 2.4511)
		(size 0.508)
		(drill 0.254)
		(layers "F.Cu" "B.Cu")
		(net "GND")
	)
	(via
		(at 233.895138 -53.60924)
		(size 0.508)
		(drill 0.254)
		(layers "F.Cu" "B.Cu")
		(net "GND")
	)
	(via
		(at 119.690134 -167.832024)
		(size 0.5588)
		(drill 0.3048)
		(layers "F.Cu" "B.Cu")
		(net "GND")
	)
	(via
		(at 184.778396 -88.306402)
		(size 0.508)
		(drill 0.254)
		(layers "F.Cu" "B.Cu")
		(net "GND")
	)
	(via
		(at 389.02132 -129.74066)
		(size 0.508)
		(drill 0.254)
		(layers "F.Cu" "B.Cu")
		(net "GND")
	)
	(via
		(at 131.699508 -18.757646)
		(size 0.508)
		(drill 0.254)
		(layers "F.Cu" "B.Cu")
		(net "GND")
	)
	(via
		(at 32.15132 1.994154)
		(size 0.508)
		(drill 0.254)
		(layers "F.Cu" "B.Cu")
		(net "GND")
	)
	(via
		(at 368.623342 -37.82187)
		(size 0.508)
		(drill 0.254)
		(layers "F.Cu" "B.Cu")
		(net "GND")
	)
	(via
		(at 229.081838 -129.5654)
		(size 0.508)
		(drill 0.254)
		(layers "F.Cu" "B.Cu")
		(net "GND")
	)
	(via
		(at 395.66215 -115.236244)
		(size 0.508)
		(drill 0.254)
		(layers "F.Cu" "B.Cu")
		(net "GND")
	)
	(via
		(at 86.923372 -80.850486)
		(size 0.508)
		(drill 0.254)
		(layers "F.Cu" "B.Cu")
		(net "GND")
	)
	(via
		(at 33.771586 -140.617956)
		(size 0.508)
		(drill 0.254)
		(layers "F.Cu" "B.Cu")
		(net "GND")
	)
	(via
		(at 125.651768 -64.819784)
		(size 0.508)
		(drill 0.254)
		(layers "F.Cu" "B.Cu")
		(net "GND")
	)
	(via
		(at 74.904346 -54.104286)
		(size 0.508)
		(drill 0.254)
		(layers "F.Cu" "B.Cu")
		(net "GND")
	)
	(via
		(at 210.39455 0.5207)
		(size 0.508)
		(drill 0.254)
		(layers "F.Cu" "B.Cu")
		(net "GND")
	)
	(via
		(at 456.671934 11.624056)
		(size 0.5588)
		(drill 0.3048)
		(layers "F.Cu" "B.Cu")
		(net "GND")
	)
	(via
		(at 26.929334 -167.832024)
		(size 0.5588)
		(drill 0.3048)
		(layers "F.Cu" "B.Cu")
		(net "GND")
	)
	(via
		(at 43.12158 -134.8994)
		(size 0.508)
		(drill 0.254)
		(layers "F.Cu" "B.Cu")
		(net "GND")
	)
	(via
		(at 287.21812 -94.538038)
		(size 0.508)
		(drill 0.254)
		(layers "F.Cu" "B.Cu")
		(net "GND")
	)
	(via
		(at 451.591934 11.624056)
		(size 0.5588)
		(drill 0.3048)
		(layers "F.Cu" "B.Cu")
		(net "GND")
	)
	(via
		(at 334.858614 -16.002)
		(size 0.508)
		(drill 0.254)
		(layers "F.Cu" "B.Cu")
		(net "GND")
	)
	(via
		(at 298.399962 -2.314956)
		(size 0.508)
		(drill 0.254)
		(layers "F.Cu" "B.Cu")
		(net "GND")
	)
	(via
		(at 276.057614 -97.014538)
		(size 0.508)
		(drill 0.254)
		(layers "F.Cu" "B.Cu")
		(net "GND")
	)
	(via
		(at 253.640844 -95.709486)
		(size 0.508)
		(drill 0.254)
		(layers "F.Cu" "B.Cu")
		(net "GND")
	)
	(via
		(at 287.79216 -59.866784)
		(size 0.508)
		(drill 0.254)
		(layers "F.Cu" "B.Cu")
		(net "GND")
	)
	(via
		(at 68.894706 -99.17684)
		(size 0.508)
		(drill 0.254)
		(layers "F.Cu" "B.Cu")
		(net "GND")
	)
	(via
		(at 49.001934 14.926056)
		(size 0.5588)
		(drill 0.3048)
		(layers "F.Cu" "B.Cu")
		(net "GND")
	)
	(via
		(at 297.520106 -55.904384)
		(size 0.508)
		(drill 0.254)
		(layers "F.Cu" "B.Cu")
		(net "GND")
	)
	(via
		(at 201.228452 -100.775262)
		(size 0.5588)
		(drill 0.3048)
		(layers "F.Cu" "B.Cu")
		(net "GND")
	)
	(via
		(at 305.199796 -7.607046)
		(size 0.508)
		(drill 0.254)
		(layers "F.Cu" "B.Cu")
		(net "GND")
	)
	(via
		(at 397.64335 -109.624876)
		(size 0.508)
		(drill 0.254)
		(layers "F.Cu" "B.Cu")
		(net "GND")
	)
	(via
		(at 219.744544 0.5207)
		(size 0.508)
		(drill 0.254)
		(layers "F.Cu" "B.Cu")
		(net "GND")
	)
	(via
		(at 499.282466 -19.804126)
		(size 0.508)
		(drill 0.254)
		(layers "F.Cu" "B.Cu")
		(net "GND")
	)
	(via
		(at 282.925774 -102.958138)
		(size 0.508)
		(drill 0.254)
		(layers "F.Cu" "B.Cu")
		(net "GND")
	)
	(via
		(at 17.251934 14.926056)
		(size 0.5588)
		(drill 0.3048)
		(layers "F.Cu" "B.Cu")
		(net "GND")
	)
	(via
		(at 481.5332 -37.8968)
		(size 0.508)
		(drill 0.254)
		(layers "F.Cu" "B.Cu")
		(net "GND")
	)
	(via
		(at 384.522218 -155.686506)
		(size 0.508)
		(drill 0.254)
		(layers "F.Cu" "B.Cu")
		(net "GND")
	)
	(via
		(at 207.518 -64.7954)
		(size 0.5588)
		(drill 0.3048)
		(layers "F.Cu" "B.Cu")
		(net "GND")
	)
	(via
		(at 74.749406 -136.410446)
		(size 0.508)
		(drill 0.254)
		(layers "F.Cu" "B.Cu")
		(net "GND")
	)
	(via
		(at 73.131934 9.084056)
		(size 0.5588)
		(drill 0.3048)
		(layers "F.Cu" "B.Cu")
		(net "GND")
	)
	(via
		(at 343.4588 -26.6573)
		(size 0.508)
		(drill 0.254)
		(layers "F.Cu" "B.Cu")
		(net "GND")
	)
	(via
		(at 75.59929 -140.617956)
		(size 0.508)
		(drill 0.254)
		(layers "F.Cu" "B.Cu")
		(net "GND")
	)
	(via
		(at 283.04236 -18.744946)
		(size 0.508)
		(drill 0.254)
		(layers "F.Cu" "B.Cu")
		(net "GND")
	)
	(via
		(at 90.814906 -139.829794)
		(size 0.508)
		(drill 0.254)
		(layers "F.Cu" "B.Cu")
		(net "GND")
	)
	(via
		(at 290.71189 -11.916156)
		(size 0.508)
		(drill 0.254)
		(layers "F.Cu" "B.Cu")
		(net "GND")
	)
	(via
		(at 397.4084 -127.105156)
		(size 0.508)
		(drill 0.254)
		(layers "F.Cu" "B.Cu")
		(net "GND")
	)
	(via
		(at 482.630734 -164.479224)
		(size 0.5588)
		(drill 0.3048)
		(layers "F.Cu" "B.Cu")
		(net "GND")
	)
	(via
		(at 122.217688 -96.518984)
		(size 0.508)
		(drill 0.254)
		(layers "F.Cu" "B.Cu")
		(net "GND")
	)
	(via
		(at 358.70388 -98.64344)
		(size 0.508)
		(drill 0.254)
		(layers "F.Cu" "B.Cu")
		(net "GND")
	)
	(via
		(at 135.099552 -146.011646)
		(size 0.508)
		(drill 0.254)
		(layers "F.Cu" "B.Cu")
		(net "GND")
	)
	(via
		(at 114.206782 -54.913784)
		(size 0.508)
		(drill 0.254)
		(layers "F.Cu" "B.Cu")
		(net "GND")
	)
	(via
		(at 4.353306 -144.953482)
		(size 0.508)
		(drill 0.254)
		(layers "F.Cu" "B.Cu")
		(net "GND")
	)
	(via
		(at 42.77995 -60.183522)
		(size 0.5588)
		(drill 0.3048)
		(layers "F.Cu" "B.Cu")
		(net "GND")
	)
	(via
		(at 324.210934 -167.832024)
		(size 0.5588)
		(drill 0.3048)
		(layers "F.Cu" "B.Cu")
		(net "GND")
	)
	(via
		(at 165.890194 -30.8737)
		(size 0.508)
		(drill 0.254)
		(layers "F.Cu" "B.Cu")
		(net "GND")
	)
	(via
		(at 177.93335 -0.423672)
		(size 0.5588)
		(drill 0.3048)
		(layers "F.Cu" "B.Cu")
		(net "GND")
	)
	(via
		(at 349.7072 -148.419312)
		(size 0.508)
		(drill 0.254)
		(layers "F.Cu" "B.Cu")
		(net "GND")
	)
	(via
		(at 147.387564 -131.600956)
		(size 0.508)
		(drill 0.254)
		(layers "F.Cu" "B.Cu")
		(net "GND")
	)
	(via
		(at 456.606656 -15.578836)
		(size 0.5588)
		(drill 0.3048)
		(layers "F.Cu" "B.Cu")
		(net "GND")
	)
	(via
		(at 74.749406 -129.568956)
		(size 0.508)
		(drill 0.254)
		(layers "F.Cu" "B.Cu")
		(net "GND")
	)
	(via
		(at 236.961934 9.084056)
		(size 0.5588)
		(drill 0.3048)
		(layers "F.Cu" "B.Cu")
		(net "GND")
	)
	(via
		(at 127.39878 -153.6065)
		(size 0.508)
		(drill 0.254)
		(layers "F.Cu" "B.Cu")
		(net "GND")
	)
	(via
		(at 9.936734 9.084056)
		(size 0.5588)
		(drill 0.3048)
		(layers "F.Cu" "B.Cu")
		(net "GND")
	)
	(via
		(at 401.3581 -83.688682)
		(size 0.508)
		(drill 0.254)
		(layers "F.Cu" "B.Cu")
		(net "GND")
	)
	(via
		(at 296.69994 -18.757646)
		(size 0.508)
		(drill 0.254)
		(layers "F.Cu" "B.Cu")
		(net "GND")
	)
	(via
		(at 295.80332 -82.650584)
		(size 0.508)
		(drill 0.254)
		(layers "F.Cu" "B.Cu")
		(net "GND")
	)
	(via
		(at 423.488358 -135.946134)
		(size 0.508)
		(drill 0.254)
		(layers "F.Cu" "B.Cu")
		(net "GND")
	)
	(via
		(at 272.623788 -98.005138)
		(size 0.508)
		(drill 0.254)
		(layers "F.Cu" "B.Cu")
		(net "GND")
	)
	(via
		(at 35.880802 -62.792864)
		(size 0.508)
		(drill 0.254)
		(layers "F.Cu" "B.Cu")
		(net "GND")
	)
	(via
		(at 261.36727 -91.25204)
		(size 0.508)
		(drill 0.254)
		(layers "F.Cu" "B.Cu")
		(net "GND")
	)
	(via
		(at 100.124768 2.4638)
		(size 0.508)
		(drill 0.254)
		(layers "F.Cu" "B.Cu")
		(net "GND")
	)
	(via
		(at 207.7974 -76.5048)
		(size 0.5588)
		(drill 0.3048)
		(layers "F.Cu" "B.Cu")
		(net "GND")
	)
	(via
		(at 352.57359 -104.261666)
		(size 0.508)
		(drill 0.254)
		(layers "F.Cu" "B.Cu")
		(net "GND")
	)
	(via
		(at 27.990546 -105.118408)
		(size 0.5588)
		(drill 0.3048)
		(layers "F.Cu" "B.Cu")
		(net "GND")
	)
	(via
		(at 295.849802 -144.462246)
		(size 0.508)
		(drill 0.254)
		(layers "F.Cu" "B.Cu")
		(net "GND")
	)
	(via
		(at 207.976724 -162.243262)
		(size 0.5588)
		(drill 0.3048)
		(layers "F.Cu" "B.Cu")
		(net "GND")
	)
	(via
		(at 256.21615 -91.25204)
		(size 0.508)
		(drill 0.254)
		(layers "F.Cu" "B.Cu")
		(net "GND")
	)
	(via
		(at 495.552476 -44.13123)
		(size 0.508)
		(drill 0.254)
		(layers "F.Cu" "B.Cu")
		(net "GND")
	)
	(via
		(at 113.771934 14.926056)
		(size 0.5588)
		(drill 0.3048)
		(layers "F.Cu" "B.Cu")
		(net "GND")
	)
	(via
		(at 42.019982 -69.577458)
		(size 0.5588)
		(drill 0.3048)
		(layers "F.Cu" "B.Cu")
		(net "GND")
	)
	(via
		(at 393.18565 -117.811804)
		(size 0.508)
		(drill 0.254)
		(layers "F.Cu" "B.Cu")
		(net "GND")
	)
	(via
		(at 136.812274 -86.117938)
		(size 0.508)
		(drill 0.254)
		(layers "F.Cu" "B.Cu")
		(net "GND")
	)
	(via
		(at 130.84937 -7.607046)
		(size 0.508)
		(drill 0.254)
		(layers "F.Cu" "B.Cu")
		(net "GND")
	)
	(via
		(at 148.699474 -18.757646)
		(size 0.508)
		(drill 0.254)
		(layers "F.Cu" "B.Cu")
		(net "GND")
	)
	(via
		(at 288.65068 -54.418738)
		(size 0.508)
		(drill 0.254)
		(layers "F.Cu" "B.Cu")
		(net "GND")
	)
	(via
		(at 247.631204 -85.30844)
		(size 0.508)
		(drill 0.254)
		(layers "F.Cu" "B.Cu")
		(net "GND")
	)
	(via
		(at 81.772252 -96.700086)
		(size 0.508)
		(drill 0.254)
		(layers "F.Cu" "B.Cu")
		(net "GND")
	)
	(via
		(at 109.955076 -82.339942)
		(size 0.5588)
		(drill 0.3048)
		(layers "F.Cu" "B.Cu")
		(net "GND")
	)
	(via
		(at 387.024626 -37.969952)
		(size 0.508)
		(drill 0.254)
		(layers "F.Cu" "B.Cu")
		(net "GND")
	)
	(via
		(at 282.641294 -56.894984)
		(size 0.508)
		(drill 0.254)
		(layers "F.Cu" "B.Cu")
		(net "GND")
	)
	(via
		(at 387.73735 -120.387364)
		(size 0.508)
		(drill 0.254)
		(layers "F.Cu" "B.Cu")
		(net "GND")
	)
	(via
		(at 134.15137 -17.208246)
		(size 0.508)
		(drill 0.254)
		(layers "F.Cu" "B.Cu")
		(net "GND")
	)
	(via
		(at 241.621818 -67.972686)
		(size 0.508)
		(drill 0.254)
		(layers "F.Cu" "B.Cu")
		(net "GND")
	)
	(via
		(at 416.1155 -31.9405)
		(size 0.4572)
		(drill 0.2032)
		(layers "F.Cu" "B.Cu")
		(net "GND")
	)
	(via
		(at 101.573076 -75.159616)
		(size 0.5588)
		(drill 0.3048)
		(layers "F.Cu" "B.Cu")
		(net "GND")
	)
	(via
		(at 141.963394 -69.277738)
		(size 0.508)
		(drill 0.254)
		(layers "F.Cu" "B.Cu")
		(net "GND")
	)
	(via
		(at 108.197396 -60.362338)
		(size 0.508)
		(drill 0.254)
		(layers "F.Cu" "B.Cu")
		(net "GND")
	)
	(via
		(at 115.349782 -92.556584)
		(size 0.508)
		(drill 0.254)
		(layers "F.Cu" "B.Cu")
		(net "GND")
	)
	(via
		(at 34.729166 -70.202044)
		(size 0.5588)
		(drill 0.3048)
		(layers "F.Cu" "B.Cu")
		(net "GND")
	)
	(via
		(at 145.12163 -13.363956)
		(size 0.508)
		(drill 0.254)
		(layers "F.Cu" "B.Cu")
		(net "GND")
	)
	(via
		(at 338.561934 14.926056)
		(size 0.5588)
		(drill 0.3048)
		(layers "F.Cu" "B.Cu")
		(net "GND")
	)
	(via
		(at 7.926324 -162.243262)
		(size 0.5588)
		(drill 0.3048)
		(layers "F.Cu" "B.Cu")
		(net "GND")
	)
	(via
		(at 74.749406 -155.511246)
		(size 0.508)
		(drill 0.254)
		(layers "F.Cu" "B.Cu")
		(net "GND")
	)
	(via
		(at 470.641934 13.910056)
		(size 0.5588)
		(drill 0.3048)
		(layers "F.Cu" "B.Cu")
		(net "GND")
	)
	(via
		(at 3.77952 -23.53818)
		(size 0.508)
		(drill 0.254)
		(layers "F.Cu" "B.Cu")
		(net "GND")
	)
	(via
		(at 316.249812 -144.462246)
		(size 0.508)
		(drill 0.254)
		(layers "F.Cu" "B.Cu")
		(net "GND")
	)
	(via
		(at 34.74212 -18.744946)
		(size 0.508)
		(drill 0.254)
		(layers "F.Cu" "B.Cu")
		(net "GND")
	)
	(via
		(at 69.753226 -56.085486)
		(size 0.508)
		(drill 0.254)
		(layers "F.Cu" "B.Cu")
		(net "GND")
	)
	(via
		(at 133.39953 -2.314956)
		(size 0.508)
		(drill 0.254)
		(layers "F.Cu" "B.Cu")
		(net "GND")
	)
	(via
		(at 124.793248 -84.136738)
		(size 0.508)
		(drill 0.254)
		(layers "F.Cu" "B.Cu")
		(net "GND")
	)
	(via
		(at 53.448712 -144.0053)
		(size 0.508)
		(drill 0.254)
		(layers "F.Cu" "B.Cu")
		(net "GND")
	)
	(via
		(at 274.056348 -101.471984)
		(size 0.508)
		(drill 0.254)
		(layers "F.Cu" "B.Cu")
		(net "GND")
	)
	(via
		(at 303.041304 2.505456)
		(size 0.508)
		(drill 0.254)
		(layers "F.Cu" "B.Cu")
		(net "GND")
	)
	(via
		(at 200.515728 -65.9892)
		(size 0.508)
		(drill 0.254)
		(layers "F.Cu" "B.Cu")
		(net "GND")
	)
	(via
		(at 100.659184 -95.709486)
		(size 0.508)
		(drill 0.254)
		(layers "F.Cu" "B.Cu")
		(net "GND")
	)
	(via
		(at 49.24933 -140.617956)
		(size 0.508)
		(drill 0.254)
		(layers "F.Cu" "B.Cu")
		(net "GND")
	)
	(via
		(at 72.136 -150.749)
		(size 0.508)
		(drill 0.254)
		(layers "F.Cu" "B.Cu")
		(net "GND")
	)
	(via
		(at 227.792534 -129.564892)
		(size 0.508)
		(drill 0.254)
		(layers "F.Cu" "B.Cu")
		(net "GND")
	)
	(via
		(at 257.154934 -167.832024)
		(size 0.5588)
		(drill 0.3048)
		(layers "F.Cu" "B.Cu")
		(net "GND")
	)
	(via
		(at 309.351934 14.926056)
		(size 0.5588)
		(drill 0.3048)
		(layers "F.Cu" "B.Cu")
		(net "GND")
	)
	(via
		(at 12.171934 9.084056)
		(size 0.5588)
		(drill 0.3048)
		(layers "F.Cu" "B.Cu")
		(net "GND")
	)
	(via
		(at 242.480338 -68.46824)
		(size 0.508)
		(drill 0.254)
		(layers "F.Cu" "B.Cu")
		(net "GND")
	)
	(via
		(at 402.239734 -22.152102)
		(size 0.508)
		(drill 0.254)
		(layers "F.Cu" "B.Cu")
		(net "GND")
	)
	(via
		(at 389.2296 -147.9042)
		(size 0.508)
		(drill 0.254)
		(layers "F.Cu" "B.Cu")
		(net "GND")
	)
	(via
		(at 239.046258 -50.63744)
		(size 0.508)
		(drill 0.254)
		(layers "F.Cu" "B.Cu")
		(net "GND")
	)
	(via
		(at 122.217688 -89.584784)
		(size 0.508)
		(drill 0.254)
		(layers "F.Cu" "B.Cu")
		(net "GND")
	)
	(via
		(at 294.08628 -89.584784)
		(size 0.508)
		(drill 0.254)
		(layers "F.Cu" "B.Cu")
		(net "GND")
	)
	(via
		(at 274.056348 -62.838584)
		(size 0.508)
		(drill 0.254)
		(layers "F.Cu" "B.Cu")
		(net "GND")
	)
	(via
		(at 206.501746 -17.208246)
		(size 0.508)
		(drill 0.254)
		(layers "F.Cu" "B.Cu")
		(net "GND")
	)
	(via
		(at 396.15745 -112.660684)
		(size 0.508)
		(drill 0.254)
		(layers "F.Cu" "B.Cu")
		(net "GND")
	)
	(via
		(at 468.101934 13.910056)
		(size 0.5588)
		(drill 0.3048)
		(layers "F.Cu" "B.Cu")
		(net "GND")
	)
	(via
		(at 226.822 -13.363956)
		(size 0.508)
		(drill 0.254)
		(layers "F.Cu" "B.Cu")
		(net "GND")
	)
	(via
		(at 383.84861 -128.976374)
		(size 0.508)
		(drill 0.254)
		(layers "F.Cu" "B.Cu")
		(net "GND")
	)
	(via
		(at 135.771636 -154.1018)
		(size 0.508)
		(drill 0.254)
		(layers "F.Cu" "B.Cu")
		(net "GND")
	)
	(via
		(at 128.227328 -82.155284)
		(size 0.508)
		(drill 0.254)
		(layers "F.Cu" "B.Cu")
		(net "GND")
	)
	(via
		(at 169.651934 14.926056)
		(size 0.5588)
		(drill 0.3048)
		(layers "F.Cu" "B.Cu")
		(net "GND")
	)
	(via
		(at 80.913732 -90.26144)
		(size 0.508)
		(drill 0.254)
		(layers "F.Cu" "B.Cu")
		(net "GND")
	)
	(via
		(at 480.801934 14.926056)
		(size 0.5588)
		(drill 0.3048)
		(layers "F.Cu" "B.Cu")
		(net "GND")
	)
	(via
		(at 335.04505 -127.254)
		(size 0.508)
		(drill 0.254)
		(layers "F.Cu" "B.Cu")
		(net "GND")
	)
	(via
		(at 0.995934 9.084056)
		(size 0.5588)
		(drill 0.3048)
		(layers "F.Cu" "B.Cu")
		(net "GND")
	)
	(via
		(at 125.651768 -68.782184)
		(size 0.508)
		(drill 0.254)
		(layers "F.Cu" "B.Cu")
		(net "GND")
	)
	(via
		(at 232.567734 -167.832024)
		(size 0.5588)
		(drill 0.3048)
		(layers "F.Cu" "B.Cu")
		(net "GND")
	)
	(via
		(at 139.387834 -70.763384)
		(size 0.508)
		(drill 0.254)
		(layers "F.Cu" "B.Cu")
		(net "GND")
	)
	(via
		(at 141.049502 -11.916156)
		(size 0.508)
		(drill 0.254)
		(layers "F.Cu" "B.Cu")
		(net "GND")
	)
	(via
		(at 415.163 -106.299)
		(size 0.508)
		(drill 0.254)
		(layers "F.Cu" "B.Cu")
		(net "GND")
	)
	(via
		(at 90.814906 -140.490194)
		(size 0.508)
		(drill 0.254)
		(layers "F.Cu" "B.Cu")
		(net "GND")
	)
	(via
		(at 3.231134 14.926056)
		(size 0.5588)
		(drill 0.3048)
		(layers "F.Cu" "B.Cu")
		(net "GND")
	)
	(via
		(at 464.521296 -0.939546)
		(size 0.508)
		(drill 0.254)
		(layers "F.Cu" "B.Cu")
		(net "GND")
	)
	(via
		(at 35.68065 -100.91674)
		(size 0.5588)
		(drill 0.3048)
		(layers "F.Cu" "B.Cu")
		(net "GND")
	)
	(via
		(at 117.066822 -94.538038)
		(size 0.508)
		(drill 0.254)
		(layers "F.Cu" "B.Cu")
		(net "GND")
	)
	(via
		(at 142.038324 -162.243262)
		(size 0.5588)
		(drill 0.3048)
		(layers "F.Cu" "B.Cu")
		(net "GND")
	)
	(via
		(at 356.341934 9.084056)
		(size 0.5588)
		(drill 0.3048)
		(layers "F.Cu" "B.Cu")
		(net "GND")
	)
	(via
		(at 392.613134 -167.832024)
		(size 0.5588)
		(drill 0.3048)
		(layers "F.Cu" "B.Cu")
		(net "GND")
	)
	(via
		(at 459.344776 -9.436608)
		(size 0.508)
		(drill 0.254)
		(layers "F.Cu" "B.Cu")
		(net "GND")
	)
	(via
		(at 262.742934 -167.832024)
		(size 0.5588)
		(drill 0.3048)
		(layers "F.Cu" "B.Cu")
		(net "GND")
	)
	(via
		(at 304.388266 -79.678784)
		(size 0.508)
		(drill 0.254)
		(layers "F.Cu" "B.Cu")
		(net "GND")
	)
	(via
		(at 199.9996 -86.4616)
		(size 0.5588)
		(drill 0.3048)
		(layers "F.Cu" "B.Cu")
		(net "GND")
	)
	(via
		(at 447.070734 -165.596824)
		(size 0.5588)
		(drill 0.3048)
		(layers "F.Cu" "B.Cu")
		(net "GND")
	)
	(via
		(at 204.049884 -148.771356)
		(size 0.508)
		(drill 0.254)
		(layers "F.Cu" "B.Cu")
		(net "GND")
	)
	(via
		(at 199.62368 -52.009802)
		(size 0.5588)
		(drill 0.3048)
		(layers "F.Cu" "B.Cu")
		(net "GND")
	)
	(via
		(at 351.8154 -40.64)
		(size 0.508)
		(drill 0.254)
		(layers "F.Cu" "B.Cu")
		(net "GND")
	)
	(via
		(at 89.498678 -66.48704)
		(size 0.508)
		(drill 0.254)
		(layers "F.Cu" "B.Cu")
		(net "GND")
	)
	(via
		(at 152.099518 -136.410446)
		(size 0.508)
		(drill 0.254)
		(layers "F.Cu" "B.Cu")
		(net "GND")
	)
	(via
		(at 123.076208 -96.023938)
		(size 0.508)
		(drill 0.254)
		(layers "F.Cu" "B.Cu")
		(net "GND")
	)
	(via
		(at 443.971934 9.084056)
		(size 0.5588)
		(drill 0.3048)
		(layers "F.Cu" "B.Cu")
		(net "GND")
	)
	(via
		(at 38.199314 1.994154)
		(size 0.508)
		(drill 0.254)
		(layers "F.Cu" "B.Cu")
		(net "GND")
	)
	(via
		(at 229.094538 -28.66771)
		(size 0.508)
		(drill 0.254)
		(layers "F.Cu" "B.Cu")
		(net "GND")
	)
	(via
		(at 304.349912 -18.757646)
		(size 0.508)
		(drill 0.254)
		(layers "F.Cu" "B.Cu")
		(net "GND")
	)
	(via
		(at 335.383124 -162.243262)
		(size 0.5588)
		(drill 0.3048)
		(layers "F.Cu" "B.Cu")
		(net "GND")
	)
	(via
		(at 246.772684 -91.747086)
		(size 0.508)
		(drill 0.254)
		(layers "F.Cu" "B.Cu")
		(net "GND")
	)
	(via
		(at 245.914164 -94.223586)
		(size 0.508)
		(drill 0.254)
		(layers "F.Cu" "B.Cu")
		(net "GND")
	)
	(via
		(at 166.243 -75.8444)
		(size 0.508)
		(drill 0.254)
		(layers "F.Cu" "B.Cu")
		(net "GND")
	)
	(via
		(at 294.08628 -85.622384)
		(size 0.508)
		(drill 0.254)
		(layers "F.Cu" "B.Cu")
		(net "GND")
	)
	(via
		(at 115.451382 -154.063446)
		(size 0.508)
		(drill 0.254)
		(layers "F.Cu" "B.Cu")
		(net "GND")
	)
	(via
		(at 290.74999 -26.495756)
		(size 0.508)
		(drill 0.254)
		(layers "F.Cu" "B.Cu")
		(net "GND")
	)
	(via
		(at 294.9448 -86.117938)
		(size 0.508)
		(drill 0.254)
		(layers "F.Cu" "B.Cu")
		(net "GND")
	)
	(via
		(at 421.005 -73.1012)
		(size 0.508)
		(drill 0.254)
		(layers "F.Cu" "B.Cu")
		(net "GND")
	)
	(via
		(at 6.5024 -8.255)
		(size 0.508)
		(drill 0.254)
		(layers "F.Cu" "B.Cu")
		(net "GND")
	)
	(via
		(at 229.091236 -143.950944)
		(size 0.508)
		(drill 0.254)
		(layers "F.Cu" "B.Cu")
		(net "GND")
	)
	(via
		(at 30.549342 -16.764)
		(size 0.508)
		(drill 0.254)
		(layers "F.Cu" "B.Cu")
		(net "GND")
	)
	(via
		(at 242.299744 -7.607046)
		(size 0.508)
		(drill 0.254)
		(layers "F.Cu" "B.Cu")
		(net "GND")
	)
	(via
		(at 429.79848 -127.35814)
		(size 0.508)
		(drill 0.254)
		(layers "F.Cu" "B.Cu")
		(net "GND")
	)
	(via
		(at 123.650248 -62.343538)
		(size 0.508)
		(drill 0.254)
		(layers "F.Cu" "B.Cu")
		(net "GND")
	)
	(via
		(at 341.128604 -143.087598)
		(size 0.508)
		(drill 0.254)
		(layers "F.Cu" "B.Cu")
		(net "GND")
	)
	(via
		(at 238.187738 -96.700086)
		(size 0.508)
		(drill 0.254)
		(layers "F.Cu" "B.Cu")
		(net "GND")
	)
	(via
		(at 181.931818 -132.59308)
		(size 0.508)
		(drill 0.254)
		(layers "F.Cu" "B.Cu")
		(net "GND")
	)
	(via
		(at 280.460958 -140.592556)
		(size 0.508)
		(drill 0.254)
		(layers "F.Cu" "B.Cu")
		(net "GND")
	)
	(via
		(at 280.350214 -92.556584)
		(size 0.508)
		(drill 0.254)
		(layers "F.Cu" "B.Cu")
		(net "GND")
	)
	(via
		(at 357.611934 14.926056)
		(size 0.5588)
		(drill 0.3048)
		(layers "F.Cu" "B.Cu")
		(net "GND")
	)
	(via
		(at 301.742602 -18.744946)
		(size 0.508)
		(drill 0.254)
		(layers "F.Cu" "B.Cu")
		(net "GND")
	)
	(via
		(at 312.391298 -143.950944)
		(size 0.508)
		(drill 0.254)
		(layers "F.Cu" "B.Cu")
		(net "GND")
	)
	(via
		(at 288.65068 -60.362338)
		(size 0.508)
		(drill 0.254)
		(layers "F.Cu" "B.Cu")
		(net "GND")
	)
	(via
		(at 13.335 -15.4178)
		(size 0.508)
		(drill 0.254)
		(layers "F.Cu" "B.Cu")
		(net "GND")
	)
	(via
		(at 118.041928 -11.912092)
		(size 0.508)
		(drill 0.254)
		(layers "F.Cu" "B.Cu")
		(net "GND")
	)
	(via
		(at 7.930134 -164.479224)
		(size 0.5588)
		(drill 0.3048)
		(layers "F.Cu" "B.Cu")
		(net "GND")
	)
	(via
		(at 408.04338 -23.814786)
		(size 0.4572)
		(drill 0.2032)
		(layers "F.Cu" "B.Cu")
		(net "GND")
	)
	(via
		(at 27.323034 -103.197914)
		(size 0.5588)
		(drill 0.3048)
		(layers "F.Cu" "B.Cu")
		(net "GND")
	)
	(via
		(at 3.505454 -151.67102)
		(size 0.5588)
		(drill 0.3048)
		(layers "F.Cu" "B.Cu")
		(net "GND")
	)
	(via
		(at 395.66215 -107.907836)
		(size 0.508)
		(drill 0.254)
		(layers "F.Cu" "B.Cu")
		(net "GND")
	)
	(via
		(at 115.923822 -58.876438)
		(size 0.508)
		(drill 0.254)
		(layers "F.Cu" "B.Cu")
		(net "GND")
	)
	(via
		(at 224.261934 14.926056)
		(size 0.5588)
		(drill 0.3048)
		(layers "F.Cu" "B.Cu")
		(net "GND")
	)
	(via
		(at 248.489724 -71.935086)
		(size 0.508)
		(drill 0.254)
		(layers "F.Cu" "B.Cu")
		(net "GND")
	)
	(via
		(at 454.131934 14.926056)
		(size 0.5588)
		(drill 0.3048)
		(layers "F.Cu" "B.Cu")
		(net "GND")
	)
	(via
		(at 118.041928 -9.143746)
		(size 0.508)
		(drill 0.254)
		(layers "F.Cu" "B.Cu")
		(net "GND")
	)
	(via
		(at 197.5358 -71.7804)
		(size 0.508)
		(drill 0.254)
		(layers "F.Cu" "B.Cu")
		(net "GND")
	)
	(via
		(at 50.851308 -134.861046)
		(size 0.508)
		(drill 0.254)
		(layers "F.Cu" "B.Cu")
		(net "GND")
	)
	(via
		(at 70.461378 -146.011646)
		(size 0.508)
		(drill 0.254)
		(layers "F.Cu" "B.Cu")
		(net "GND")
	)
	(via
		(at 38.2524 -54.0766)
		(size 0.5588)
		(drill 0.3048)
		(layers "F.Cu" "B.Cu")
		(net "GND")
	)
	(via
		(at 177.801524 -162.243262)
		(size 0.5588)
		(drill 0.3048)
		(layers "F.Cu" "B.Cu")
		(net "GND")
	)
	(via
		(at 0 -143.9672)
		(size 0.508)
		(drill 0.254)
		(layers "F.Cu" "B.Cu")
		(net "GND")
	)
	(via
		(at 288.93516 -69.772784)
		(size 0.508)
		(drill 0.254)
		(layers "F.Cu" "B.Cu")
		(net "GND")
	)
	(via
		(at 234.753658 -54.104286)
		(size 0.508)
		(drill 0.254)
		(layers "F.Cu" "B.Cu")
		(net "GND")
	)
	(via
		(at 61.111384 -11.916156)
		(size 0.508)
		(drill 0.254)
		(layers "F.Cu" "B.Cu")
		(net "GND")
	)
	(via
		(at 199.749156 -7.1501)
		(size 0.508)
		(drill 0.254)
		(layers "F.Cu" "B.Cu")
		(net "GND")
	)
	(via
		(at 207.485996 -54.067202)
		(size 0.5588)
		(drill 0.3048)
		(layers "F.Cu" "B.Cu")
		(net "GND")
	)
	(via
		(at 268.679168 -8.1534)
		(size 0.508)
		(drill 0.254)
		(layers "F.Cu" "B.Cu")
		(net "GND")
	)
	(via
		(at 222.749872 -136.410446)
		(size 0.508)
		(drill 0.254)
		(layers "F.Cu" "B.Cu")
		(net "GND")
	)
	(via
		(at 300.095666 -76.211938)
		(size 0.508)
		(drill 0.254)
		(layers "F.Cu" "B.Cu")
		(net "GND")
	)
	(via
		(at 319.9892 -117.6782)
		(size 0.508)
		(drill 0.254)
		(layers "F.Cu" "B.Cu")
		(net "GND")
	)
	(via
		(at 415.318448 -49.575974)
		(size 0.508)
		(drill 0.254)
		(layers "F.Cu" "B.Cu")
		(net "GND")
	)
	(via
		(at 290.6522 -91.565984)
		(size 0.508)
		(drill 0.254)
		(layers "F.Cu" "B.Cu")
		(net "GND")
	)
	(via
		(at 73.440798 2.505456)
		(size 0.508)
		(drill 0.254)
		(layers "F.Cu" "B.Cu")
		(net "GND")
	)
	(via
		(at 58.599324 -134.861046)
		(size 0.508)
		(drill 0.254)
		(layers "F.Cu" "B.Cu")
		(net "GND")
	)
	(via
		(at 129.944368 -83.146138)
		(size 0.508)
		(drill 0.254)
		(layers "F.Cu" "B.Cu")
		(net "GND")
	)
	(via
		(at 139.34948 -146.011646)
		(size 0.508)
		(drill 0.254)
		(layers "F.Cu" "B.Cu")
		(net "GND")
	)
	(via
		(at 112.774222 -93.052138)
		(size 0.508)
		(drill 0.254)
		(layers "F.Cu" "B.Cu")
		(net "GND")
	)
	(via
		(at 114.699542 -2.314956)
		(size 0.508)
		(drill 0.254)
		(layers "F.Cu" "B.Cu")
		(net "GND")
	)
	(via
		(at 192.405 -94.996)
		(size 0.5588)
		(drill 0.3048)
		(layers "F.Cu" "B.Cu")
		(net "GND")
	)
	(via
		(at 449.1863 -19.653504)
		(size 0.508)
		(drill 0.254)
		(layers "F.Cu" "B.Cu")
		(net "GND")
	)
	(via
		(at 36.03752 -141.202156)
		(size 0.508)
		(drill 0.254)
		(layers "F.Cu" "B.Cu")
		(net "GND")
	)
	(via
		(at 211.699856 -18.757646)
		(size 0.508)
		(drill 0.254)
		(layers "F.Cu" "B.Cu")
		(net "GND")
	)
	(via
		(at 342.371934 14.926056)
		(size 0.5588)
		(drill 0.3048)
		(layers "F.Cu" "B.Cu")
		(net "GND")
	)
	(via
		(at 439.450734 -163.361624)
		(size 0.5588)
		(drill 0.3048)
		(layers "F.Cu" "B.Cu")
		(net "GND")
	)
	(via
		(at 121.933208 -66.305938)
		(size 0.508)
		(drill 0.254)
		(layers "F.Cu" "B.Cu")
		(net "GND")
	)
	(via
		(at 80.913732 -98.18624)
		(size 0.508)
		(drill 0.254)
		(layers "F.Cu" "B.Cu")
		(net "GND")
	)
	(via
		(at 113.866168 -3.4798)
		(size 0.508)
		(drill 0.254)
		(layers "F.Cu" "B.Cu")
		(net "GND")
	)
	(via
		(at 49.24933 -22.965156)
		(size 0.508)
		(drill 0.254)
		(layers "F.Cu" "B.Cu")
		(net "GND")
	)
	(via
		(at 365.592614 -124.288042)
		(size 0.508)
		(drill 0.254)
		(layers "F.Cu" "B.Cu")
		(net "GND")
	)
	(via
		(at 414.046924 -162.243262)
		(size 0.5588)
		(drill 0.3048)
		(layers "F.Cu" "B.Cu")
		(net "GND")
	)
	(via
		(at 288.19983 -17.208246)
		(size 0.508)
		(drill 0.254)
		(layers "F.Cu" "B.Cu")
		(net "GND")
	)
	(via
		(at 298.378626 -55.409338)
		(size 0.508)
		(drill 0.254)
		(layers "F.Cu" "B.Cu")
		(net "GND")
	)
	(via
		(at 144.411446 -129.568956)
		(size 0.508)
		(drill 0.254)
		(layers "F.Cu" "B.Cu")
		(net "GND")
	)
	(via
		(at 15.5702 -22.8092)
		(size 0.508)
		(drill 0.254)
		(layers "F.Cu" "B.Cu")
		(net "GND")
	)
	(via
		(at 202.392534 -167.832024)
		(size 0.5588)
		(drill 0.3048)
		(layers "F.Cu" "B.Cu")
		(net "GND")
	)
	(via
		(at 491.998 -38.1)
		(size 0.508)
		(drill 0.254)
		(layers "F.Cu" "B.Cu")
		(net "GND")
	)
	(via
		(at 478.1677 -25.26538)
		(size 0.508)
		(drill 0.254)
		(layers "F.Cu" "B.Cu")
		(net "GND")
	)
	(via
		(at 455.960734 -166.714424)
		(size 0.5588)
		(drill 0.3048)
		(layers "F.Cu" "B.Cu")
		(net "GND")
	)
	(via
		(at 77.479906 -53.60924)
		(size 0.508)
		(drill 0.254)
		(layers "F.Cu" "B.Cu")
		(net "GND")
	)
	(via
		(at 294.08628 -73.735184)
		(size 0.508)
		(drill 0.254)
		(layers "F.Cu" "B.Cu")
		(net "GND")
	)
	(via
		(at 295.153334 -167.832024)
		(size 0.5588)
		(drill 0.3048)
		(layers "F.Cu" "B.Cu")
		(net "GND")
	)
	(via
		(at 264.974324 -162.243262)
		(size 0.5588)
		(drill 0.3048)
		(layers "F.Cu" "B.Cu")
		(net "GND")
	)
	(via
		(at 300.095666 -73.240138)
		(size 0.508)
		(drill 0.254)
		(layers "F.Cu" "B.Cu")
		(net "GND")
	)
	(via
		(at 203.817728 -60.198)
		(size 0.5588)
		(drill 0.3048)
		(layers "F.Cu" "B.Cu")
		(net "GND")
	)
	(via
		(at 466.831934 10.354056)
		(size 0.5588)
		(drill 0.3048)
		(layers "F.Cu" "B.Cu")
		(net "GND")
	)
	(via
		(at 478.199958 -113.77422)
		(size 0.508)
		(drill 0.254)
		(layers "F.Cu" "B.Cu")
		(net "GND")
	)
	(via
		(at 448.529964 -50.488088)
		(size 0.508)
		(drill 0.254)
		(layers "F.Cu" "B.Cu")
		(net "GND")
	)
	(via
		(at 35.870134 -167.832024)
		(size 0.5588)
		(drill 0.3048)
		(layers "F.Cu" "B.Cu")
		(net "GND")
	)
	(via
		(at 148.061934 14.926056)
		(size 0.5588)
		(drill 0.3048)
		(layers "F.Cu" "B.Cu")
		(net "GND")
	)
	(via
		(at 433.8955 -41.8973)
		(size 0.508)
		(drill 0.254)
		(layers "F.Cu" "B.Cu")
		(net "GND")
	)
	(via
		(at 74.749406 -21.517356)
		(size 0.508)
		(drill 0.254)
		(layers "F.Cu" "B.Cu")
		(net "GND")
	)
	(via
		(at 206.855314 -85.688678)
		(size 0.5588)
		(drill 0.3048)
		(layers "F.Cu" "B.Cu")
		(net "GND")
	)
	(via
		(at 289.049968 0.457454)
		(size 0.508)
		(drill 0.254)
		(layers "F.Cu" "B.Cu")
		(net "GND")
	)
	(via
		(at 24.929846 -101.541326)
		(size 0.5588)
		(drill 0.3048)
		(layers "F.Cu" "B.Cu")
		(net "GND")
	)
	(via
		(at 367.924334 -167.857424)
		(size 0.5588)
		(drill 0.3048)
		(layers "F.Cu" "B.Cu")
		(net "GND")
	)
	(via
		(at 236.171994 -154.1018)
		(size 0.508)
		(drill 0.254)
		(layers "F.Cu" "B.Cu")
		(net "GND")
	)
	(via
		(at 387.787388 -75.0316)
		(size 0.508)
		(drill 0.254)
		(layers "F.Cu" "B.Cu")
		(net "GND")
	)
	(via
		(at 412.780734 -165.596824)
		(size 0.5588)
		(drill 0.3048)
		(layers "F.Cu" "B.Cu")
		(net "GND")
	)
	(via
		(at 120.500902 -92.556584)
		(size 0.508)
		(drill 0.254)
		(layers "F.Cu" "B.Cu")
		(net "GND")
	)
	(via
		(at 407.365708 -123.75007)
		(size 0.508)
		(drill 0.254)
		(layers "F.Cu" "B.Cu")
		(net "GND")
	)
	(via
		(at 401.752816 -148.817584)
		(size 0.508)
		(drill 0.254)
		(layers "F.Cu" "B.Cu")
		(net "GND")
	)
	(via
		(at 387.73735 -95.888556)
		(size 0.508)
		(drill 0.254)
		(layers "F.Cu" "B.Cu")
		(net "GND")
	)
	(via
		(at 205.749906 -21.517356)
		(size 0.508)
		(drill 0.254)
		(layers "F.Cu" "B.Cu")
		(net "GND")
	)
	(via
		(at 43.689524 -162.243262)
		(size 0.5588)
		(drill 0.3048)
		(layers "F.Cu" "B.Cu")
		(net "GND")
	)
	(via
		(at 308.560724 -162.243262)
		(size 0.5588)
		(drill 0.3048)
		(layers "F.Cu" "B.Cu")
		(net "GND")
	)
	(via
		(at 79.196692 -66.48704)
		(size 0.508)
		(drill 0.254)
		(layers "F.Cu" "B.Cu")
		(net "GND")
	)
	(via
		(at 460.172816 -140.802614)
		(size 0.508)
		(drill 0.254)
		(layers "F.Cu" "B.Cu")
		(net "GND")
	)
	(via
		(at 74.045826 -58.561986)
		(size 0.508)
		(drill 0.254)
		(layers "F.Cu" "B.Cu")
		(net "GND")
	)
	(via
		(at 329.419712 -12.3698)
		(size 0.508)
		(drill 0.254)
		(layers "F.Cu" "B.Cu")
		(net "GND")
	)
	(via
		(at 353.218242 -146.046444)
		(size 0.508)
		(drill 0.254)
		(layers "F.Cu" "B.Cu")
		(net "GND")
	)
	(via
		(at 91.215718 -91.25204)
		(size 0.508)
		(drill 0.254)
		(layers "F.Cu" "B.Cu")
		(net "GND")
	)
	(via
		(at 67.949318 -140.617956)
		(size 0.508)
		(drill 0.254)
		(layers "F.Cu" "B.Cu")
		(net "GND")
	)
	(via
		(at 136.748774 -26.73731)
		(size 0.508)
		(drill 0.254)
		(layers "F.Cu" "B.Cu")
		(net "GND")
	)
	(via
		(at 67.099434 -9.156446)
		(size 0.508)
		(drill 0.254)
		(layers "F.Cu" "B.Cu")
		(net "GND")
	)
	(via
		(at 50.072798 -91.5289)
		(size 0.508)
		(drill 0.254)
		(layers "F.Cu" "B.Cu")
		(net "GND")
	)
	(via
		(at 247.631204 -67.47764)
		(size 0.508)
		(drill 0.254)
		(layers "F.Cu" "B.Cu")
		(net "GND")
	)
	(via
		(at 110.717076 -75.159616)
		(size 0.5588)
		(drill 0.3048)
		(layers "F.Cu" "B.Cu")
		(net "GND")
	)
	(via
		(at 499.851934 10.354056)
		(size 0.5588)
		(drill 0.3048)
		(layers "F.Cu" "B.Cu")
		(net "GND")
	)
	(via
		(at 179.834794 -106.445812)
		(size 0.508)
		(drill 0.254)
		(layers "F.Cu" "B.Cu")
		(net "GND")
	)
	(via
		(at 201.401934 9.084056)
		(size 0.5588)
		(drill 0.3048)
		(layers "F.Cu" "B.Cu")
		(net "GND")
	)
	(via
		(at 376.2756 -137.0838)
		(size 0.508)
		(drill 0.254)
		(layers "F.Cu" "B.Cu")
		(net "GND")
	)
	(via
		(at 85.206332 -57.076086)
		(size 0.508)
		(drill 0.254)
		(layers "F.Cu" "B.Cu")
		(net "GND")
	)
	(via
		(at 0.63119 -126.53899)
		(size 0.508)
		(drill 0.254)
		(layers "F.Cu" "B.Cu")
		(net "GND")
	)
	(via
		(at 345.948 -146.4818)
		(size 0.508)
		(drill 0.254)
		(layers "F.Cu" "B.Cu")
		(net "GND")
	)
	(via
		(at 184.911238 -60.75553)
		(size 0.508)
		(drill 0.254)
		(layers "F.Cu" "B.Cu")
		(net "GND")
	)
	(via
		(at 442.522356 -28.2321)
		(size 0.4572)
		(drill 0.2032)
		(layers "F.Cu" "B.Cu")
		(net "GND")
	)
	(via
		(at 37.7952 -46.4566)
		(size 0.508)
		(drill 0.254)
		(layers "F.Cu" "B.Cu")
		(net "GND")
	)
	(via
		(at 42.9641 -81.1784)
		(size 0.5588)
		(drill 0.3048)
		(layers "F.Cu" "B.Cu")
		(net "GND")
	)
	(via
		(at 440.161934 10.354056)
		(size 0.5588)
		(drill 0.3048)
		(layers "F.Cu" "B.Cu")
		(net "GND")
	)
	(via
		(at 207.642714 -69.000878)
		(size 0.5588)
		(drill 0.3048)
		(layers "F.Cu" "B.Cu")
		(net "GND")
	)
	(via
		(at 376.11304 -155.346908)
		(size 0.508)
		(drill 0.254)
		(layers "F.Cu" "B.Cu")
		(net "GND")
	)
	(via
		(at 364.567724 -162.268662)
		(size 0.5588)
		(drill 0.3048)
		(layers "F.Cu" "B.Cu")
		(net "GND")
	)
	(via
		(at 200.868534 -95.228664)
		(size 0.508)
		(drill 0.254)
		(layers "F.Cu" "B.Cu")
		(net "GND")
	)
	(via
		(at 388.138924 -162.243262)
		(size 0.5588)
		(drill 0.3048)
		(layers "F.Cu" "B.Cu")
		(net "GND")
	)
	(via
		(at 217.911934 9.084056)
		(size 0.5588)
		(drill 0.3048)
		(layers "F.Cu" "B.Cu")
		(net "GND")
	)
	(via
		(at -3.603244 -50.797206)
		(size 0.5588)
		(drill 0.3048)
		(layers "F.Cu" "B.Cu")
		(net "GND")
	)
	(via
		(at 449.404486 -118.61927)
		(size 0.508)
		(drill 0.254)
		(layers "F.Cu" "B.Cu")
		(net "GND")
	)
	(via
		(at 279.491694 -91.070938)
		(size 0.508)
		(drill 0.254)
		(layers "F.Cu" "B.Cu")
		(net "GND")
	)
	(via
		(at 376.5042 -30.0736)
		(size 0.508)
		(drill 0.254)
		(layers "F.Cu" "B.Cu")
		(net "GND")
	)
	(via
		(at 31.908496 -81.186782)
		(size 0.508)
		(drill 0.254)
		(layers "F.Cu" "B.Cu")
		(net "GND")
	)
	(via
		(at 134.091934 14.926056)
		(size 0.5588)
		(drill 0.3048)
		(layers "F.Cu" "B.Cu")
		(net "GND")
	)
	(via
		(at 446.6971 -40.2971)
		(size 0.508)
		(drill 0.254)
		(layers "F.Cu" "B.Cu")
		(net "GND")
	)
	(via
		(at 82.630772 -87.28964)
		(size 0.508)
		(drill 0.254)
		(layers "F.Cu" "B.Cu")
		(net "GND")
	)
	(via
		(at 184.4675 -5.9817)
		(size 0.508)
		(drill 0.254)
		(layers "F.Cu" "B.Cu")
		(net "GND")
	)
	(via
		(at 77.299312 -154.063446)
		(size 0.508)
		(drill 0.254)
		(layers "F.Cu" "B.Cu")
		(net "GND")
	)
	(via
		(at 144.411446 -21.517356)
		(size 0.508)
		(drill 0.254)
		(layers "F.Cu" "B.Cu")
		(net "GND")
	)
	(via
		(at 436.0926 -22.3266)
		(size 0.508)
		(drill 0.254)
		(layers "F.Cu" "B.Cu")
		(net "GND")
	)
	(via
		(at 143.383 -68.2752)
		(size 0.508)
		(drill 0.254)
		(layers "F.Cu" "B.Cu")
		(net "GND")
	)
	(via
		(at 279.036018 -75.143614)
		(size 0.5588)
		(drill 0.3048)
		(layers "F.Cu" "B.Cu")
		(net "GND")
	)
	(via
		(at 79.196692 -80.35544)
		(size 0.508)
		(drill 0.254)
		(layers "F.Cu" "B.Cu")
		(net "GND")
	)
	(via
		(at 313.699906 -21.517356)
		(size 0.508)
		(drill 0.254)
		(layers "F.Cu" "B.Cu")
		(net "GND")
	)
	(via
		(at 115.923822 -54.913784)
		(size 0.508)
		(drill 0.254)
		(layers "F.Cu" "B.Cu")
		(net "GND")
	)
	(via
		(at 479.531934 11.624056)
		(size 0.5588)
		(drill 0.3048)
		(layers "F.Cu" "B.Cu")
		(net "GND")
	)
	(via
		(at 291.571934 14.926056)
		(size 0.5588)
		(drill 0.3048)
		(layers "F.Cu" "B.Cu")
		(net "GND")
	)
	(via
		(at 32.639 -96.1898)
		(size 0.508)
		(drill 0.254)
		(layers "F.Cu" "B.Cu")
		(net "GND")
	)
	(via
		(at 109.961934 9.084056)
		(size 0.5588)
		(drill 0.3048)
		(layers "F.Cu" "B.Cu")
		(net "GND")
	)
	(via
		(at 290.74999 -18.757646)
		(size 0.508)
		(drill 0.254)
		(layers "F.Cu" "B.Cu")
		(net "GND")
	)
	(via
		(at 73.187306 -65.000886)
		(size 0.508)
		(drill 0.254)
		(layers "F.Cu" "B.Cu")
		(net "GND")
	)
	(via
		(at 201.041254 2.505456)
		(size 0.508)
		(drill 0.254)
		(layers "F.Cu" "B.Cu")
		(net "GND")
	)
	(via
		(at 498.221 -142.6718)
		(size 0.508)
		(drill 0.254)
		(layers "F.Cu" "B.Cu")
		(net "GND")
	)
	(via
		(at 189.484 -38.227)
		(size 0.508)
		(drill 0.254)
		(layers "F.Cu" "B.Cu")
		(net "GND")
	)
	(via
		(at 341.101934 14.926056)
		(size 0.5588)
		(drill 0.3048)
		(layers "F.Cu" "B.Cu")
		(net "GND")
	)
	(via
		(at 5.6134 -14.3256)
		(size 0.508)
		(drill 0.254)
		(layers "F.Cu" "B.Cu")
		(net "GND")
	)
	(via
		(at -1.992884 -59.017154)
		(size 0.5588)
		(drill 0.3048)
		(layers "F.Cu" "B.Cu")
		(net "GND")
	)
	(via
		(at 279.699974 -18.744946)
		(size 0.508)
		(drill 0.254)
		(layers "F.Cu" "B.Cu")
		(net "GND")
	)
	(via
		(at 339.1154 -39.37)
		(size 0.508)
		(drill 0.254)
		(layers "F.Cu" "B.Cu")
		(net "GND")
	)
	(via
		(at 205.388972 -52.979066)
		(size 0.5588)
		(drill 0.3048)
		(layers "F.Cu" "B.Cu")
		(net "GND")
	)
	(via
		(at 161.531554 -32.364426)
		(size 0.508)
		(drill 0.254)
		(layers "F.Cu" "B.Cu")
		(net "GND")
	)
	(via
		(at 141.104874 -69.772784)
		(size 0.508)
		(drill 0.254)
		(layers "F.Cu" "B.Cu")
		(net "GND")
	)
	(via
		(at 157.528768 -8.122412)
		(size 0.508)
		(drill 0.254)
		(layers "F.Cu" "B.Cu")
		(net "GND")
	)
	(via
		(at 455.401934 12.894056)
		(size 0.5588)
		(drill 0.3048)
		(layers "F.Cu" "B.Cu")
		(net "GND")
	)
	(via
		(at 75.59929 -13.363956)
		(size 0.508)
		(drill 0.254)
		(layers "F.Cu" "B.Cu")
		(net "GND")
	)
	(via
		(at 5.691124 -162.243262)
		(size 0.5588)
		(drill 0.3048)
		(layers "F.Cu" "B.Cu")
		(net "GND")
	)
	(via
		(at 487.710734 -164.479224)
		(size 0.5588)
		(drill 0.3048)
		(layers "F.Cu" "B.Cu")
		(net "GND")
	)
	(via
		(at 183.0578 -39.3065)
		(size 0.508)
		(drill 0.254)
		(layers "F.Cu" "B.Cu")
		(net "GND")
	)
	(via
		(at 212.54974 -13.363956)
		(size 0.508)
		(drill 0.254)
		(layers "F.Cu" "B.Cu")
		(net "GND")
	)
	(via
		(at 300.772068 -13.363956)
		(size 0.508)
		(drill 0.254)
		(layers "F.Cu" "B.Cu")
		(net "GND")
	)
	(via
		(at 113.933478 -135.651494)
		(size 0.508)
		(drill 0.254)
		(layers "F.Cu" "B.Cu")
		(net "GND")
	)
	(via
		(at 80.574134 -167.832024)
		(size 0.5588)
		(drill 0.3048)
		(layers "F.Cu" "B.Cu")
		(net "GND")
	)
	(via
		(at 313.699906 0.444754)
		(size 0.508)
		(drill 0.254)
		(layers "F.Cu" "B.Cu")
		(net "GND")
	)
	(via
		(at 74.045826 -90.26144)
		(size 0.508)
		(drill 0.254)
		(layers "F.Cu" "B.Cu")
		(net "GND")
	)
	(via
		(at 31.908496 -88.679782)
		(size 0.508)
		(drill 0.254)
		(layers "F.Cu" "B.Cu")
		(net "GND")
	)
	(via
		(at 358.15524 4.553458)
		(size 0.5588)
		(drill 0.3048)
		(layers "F.Cu" "B.Cu")
		(net "GND")
	)
	(via
		(at 483.900734 -165.596824)
		(size 0.5588)
		(drill 0.3048)
		(layers "F.Cu" "B.Cu")
		(net "GND")
	)
	(via
		(at 353.0854 -41.91)
		(size 0.508)
		(drill 0.254)
		(layers "F.Cu" "B.Cu")
		(net "GND")
	)
	(via
		(at 82.630772 -68.46824)
		(size 0.508)
		(drill 0.254)
		(layers "F.Cu" "B.Cu")
		(net "GND")
	)
	(via
		(at 303.041304 -153.552144)
		(size 0.508)
		(drill 0.254)
		(layers "F.Cu" "B.Cu")
		(net "GND")
	)
	(via
		(at 37.498782 -76.468478)
		(size 0.5588)
		(drill 0.3048)
		(layers "F.Cu" "B.Cu")
		(net "GND")
	)
	(via
		(at 500.552466 -20.439126)
		(size 0.508)
		(drill 0.254)
		(layers "F.Cu" "B.Cu")
		(net "GND")
	)
	(via
		(at 457.801726 -45.560996)
		(size 0.508)
		(drill 0.254)
		(layers "F.Cu" "B.Cu")
		(net "GND")
	)
	(via
		(at 129.085848 -60.857384)
		(size 0.508)
		(drill 0.254)
		(layers "F.Cu" "B.Cu")
		(net "GND")
	)
	(via
		(at 305.246786 -55.409338)
		(size 0.508)
		(drill 0.254)
		(layers "F.Cu" "B.Cu")
		(net "GND")
	)
	(via
		(at 59.449462 -129.568956)
		(size 0.508)
		(drill 0.254)
		(layers "F.Cu" "B.Cu")
		(net "GND")
	)
	(via
		(at 140.199364 -150.219156)
		(size 0.508)
		(drill 0.254)
		(layers "F.Cu" "B.Cu")
		(net "GND")
	)
	(via
		(at 79.196692 -82.33664)
		(size 0.508)
		(drill 0.254)
		(layers "F.Cu" "B.Cu")
		(net "GND")
	)
	(via
		(at 29.951934 9.084056)
		(size 0.5588)
		(drill 0.3048)
		(layers "F.Cu" "B.Cu")
		(net "GND")
	)
	(via
		(at 205.749906 -145.998946)
		(size 0.508)
		(drill 0.254)
		(layers "F.Cu" "B.Cu")
		(net "GND")
	)
	(via
		(at 125.749558 -26.495756)
		(size 0.508)
		(drill 0.254)
		(layers "F.Cu" "B.Cu")
		(net "GND")
	)
	(via
		(at 78.229968 -145.0086)
		(size 0.508)
		(drill 0.254)
		(layers "F.Cu" "B.Cu")
		(net "GND")
	)
	(via
		(at 370.311934 9.084056)
		(size 0.5588)
		(drill 0.3048)
		(layers "F.Cu" "B.Cu")
		(net "GND")
	)
	(via
		(at 282.07208 -7.6454)
		(size 0.508)
		(drill 0.254)
		(layers "F.Cu" "B.Cu")
		(net "GND")
	)
	(via
		(at 78.338172 -65.991486)
		(size 0.508)
		(drill 0.254)
		(layers "F.Cu" "B.Cu")
		(net "GND")
	)
	(via
		(at 191.286892 -85.932264)
		(size 0.5588)
		(drill 0.3048)
		(layers "F.Cu" "B.Cu")
		(net "GND")
	)
	(via
		(at 37.7952 -47.6758)
		(size 0.508)
		(drill 0.254)
		(layers "F.Cu" "B.Cu")
		(net "GND")
	)
	(via
		(at 78.338172 -83.822286)
		(size 0.508)
		(drill 0.254)
		(layers "F.Cu" "B.Cu")
		(net "GND")
	)
	(via
		(at 447.942716 -60.378848)
		(size 0.508)
		(drill 0.254)
		(layers "F.Cu" "B.Cu")
		(net "GND")
	)
	(via
		(at 44.092114 0.457454)
		(size 0.508)
		(drill 0.254)
		(layers "F.Cu" "B.Cu")
		(net "GND")
	)
	(via
		(at 410.6926 -38.9128)
		(size 0.4572)
		(drill 0.2032)
		(layers "F.Cu" "B.Cu")
		(net "GND")
	)
	(via
		(at 317.949834 -150.774146)
		(size 0.508)
		(drill 0.254)
		(layers "F.Cu" "B.Cu")
		(net "GND")
	)
	(via
		(at 47.549308 -134.861046)
		(size 0.508)
		(drill 0.254)
		(layers "F.Cu" "B.Cu")
		(net "GND")
	)
	(via
		(at 161.0868 -110.9472)
		(size 0.508)
		(drill 0.254)
		(layers "F.Cu" "B.Cu")
		(net "GND")
	)
	(via
		(at 81.772252 -85.803486)
		(size 0.508)
		(drill 0.254)
		(layers "F.Cu" "B.Cu")
		(net "GND")
	)
	(via
		(at 221.04985 -148.771356)
		(size 0.508)
		(drill 0.254)
		(layers "F.Cu" "B.Cu")
		(net "GND")
	)
	(via
		(at 41.816782 -93.892878)
		(size 0.5588)
		(drill 0.3048)
		(layers "F.Cu" "B.Cu")
		(net "GND")
	)
	(via
		(at 301.742602 -9.143746)
		(size 0.508)
		(drill 0.254)
		(layers "F.Cu" "B.Cu")
		(net "GND")
	)
	(via
		(at 245.055644 -95.709486)
		(size 0.508)
		(drill 0.254)
		(layers "F.Cu" "B.Cu")
		(net "GND")
	)
	(via
		(at 436.2704 -11.7094)
		(size 0.508)
		(drill 0.254)
		(layers "F.Cu" "B.Cu")
		(net "GND")
	)
	(via
		(at 295.764712 -27.829256)
		(size 0.508)
		(drill 0.254)
		(layers "F.Cu" "B.Cu")
		(net "GND")
	)
	(via
		(at 195.533772 -134.4168)
		(size 0.508)
		(drill 0.254)
		(layers "F.Cu" "B.Cu")
		(net "GND")
	)
	(via
		(at 42.411396 -146.011646)
		(size 0.508)
		(drill 0.254)
		(layers "F.Cu" "B.Cu")
		(net "GND")
	)
	(via
		(at 6.9342 -8.7122)
		(size 0.508)
		(drill 0.254)
		(layers "F.Cu" "B.Cu")
		(net "GND")
	)
	(via
		(at 460.33055 -122.25528)
		(size 0.508)
		(drill 0.254)
		(layers "F.Cu" "B.Cu")
		(net "GND")
	)
	(via
		(at 385.551934 14.926056)
		(size 0.5588)
		(drill 0.3048)
		(layers "F.Cu" "B.Cu")
		(net "GND")
	)
	(via
		(at 80.913732 -89.27084)
		(size 0.508)
		(drill 0.254)
		(layers "F.Cu" "B.Cu")
		(net "GND")
	)
	(via
		(at 454.2028 -21.59)
		(size 0.508)
		(drill 0.254)
		(layers "F.Cu" "B.Cu")
		(net "GND")
	)
	(via
		(at 218.44254 -148.767292)
		(size 0.508)
		(drill 0.254)
		(layers "F.Cu" "B.Cu")
		(net "GND")
	)
	(via
		(at 294.999918 -11.916156)
		(size 0.508)
		(drill 0.254)
		(layers "F.Cu" "B.Cu")
		(net "GND")
	)
	(via
		(at 439.0898 -127.6604)
		(size 0.508)
		(drill 0.254)
		(layers "F.Cu" "B.Cu")
		(net "GND")
	)
	(via
		(at 468.660734 -164.479224)
		(size 0.5588)
		(drill 0.3048)
		(layers "F.Cu" "B.Cu")
		(net "GND")
	)
	(via
		(at 149.331934 14.926056)
		(size 0.5588)
		(drill 0.3048)
		(layers "F.Cu" "B.Cu")
		(net "GND")
	)
	(via
		(at 421.670734 -164.479224)
		(size 0.5588)
		(drill 0.3048)
		(layers "F.Cu" "B.Cu")
		(net "GND")
	)
	(via
		(at 490.250734 -167.832024)
		(size 0.5588)
		(drill 0.3048)
		(layers "F.Cu" "B.Cu")
		(net "GND")
	)
	(via
		(at 85.206332 -83.822286)
		(size 0.508)
		(drill 0.254)
		(layers "F.Cu" "B.Cu")
		(net "GND")
	)
	(via
		(at 214.249762 -150.219156)
		(size 0.508)
		(drill 0.254)
		(layers "F.Cu" "B.Cu")
		(net "GND")
	)
	(via
		(at 401.3962 -142.367)
		(size 0.508)
		(drill 0.254)
		(layers "F.Cu" "B.Cu")
		(net "GND")
	)
	(via
		(at 11.82624 -147.574)
		(size 0.508)
		(drill 0.254)
		(layers "F.Cu" "B.Cu")
		(net "GND")
	)
	(via
		(at 348.0054 -40.64)
		(size 0.508)
		(drill 0.254)
		(layers "F.Cu" "B.Cu")
		(net "GND")
	)
	(via
		(at 383.3368 -115.4557)
		(size 0.508)
		(drill 0.254)
		(layers "F.Cu" "B.Cu")
		(net "GND")
	)
	(via
		(at 127.39878 -26.73731)
		(size 0.508)
		(drill 0.254)
		(layers "F.Cu" "B.Cu")
		(net "GND")
	)
	(via
		(at 91.082368 -7.806944)
		(size 0.508)
		(drill 0.254)
		(layers "F.Cu" "B.Cu")
		(net "GND")
	)
	(via
		(at 393.68095 -99.322636)
		(size 0.508)
		(drill 0.254)
		(layers "F.Cu" "B.Cu")
		(net "GND")
	)
	(via
		(at 236.470698 -64.010286)
		(size 0.508)
		(drill 0.254)
		(layers "F.Cu" "B.Cu")
		(net "GND")
	)
	(via
		(at 263.94283 -63.019686)
		(size 0.508)
		(drill 0.254)
		(layers "F.Cu" "B.Cu")
		(net "GND")
	)
	(via
		(at 40.749474 -11.916156)
		(size 0.508)
		(drill 0.254)
		(layers "F.Cu" "B.Cu")
		(net "GND")
	)
	(via
		(at 376.3518 -133.1468)
		(size 0.508)
		(drill 0.254)
		(layers "F.Cu" "B.Cu")
		(net "GND")
	)
	(via
		(at 235.46181 -2.314956)
		(size 0.508)
		(drill 0.254)
		(layers "F.Cu" "B.Cu")
		(net "GND")
	)
	(via
		(at 36.838382 -92.572078)
		(size 0.5588)
		(drill 0.3048)
		(layers "F.Cu" "B.Cu")
		(net "GND")
	)
	(via
		(at 206.542386 -92.60205)
		(size 0.5588)
		(drill 0.3048)
		(layers "F.Cu" "B.Cu")
		(net "GND")
	)
	(via
		(at 107.338876 -61.847984)
		(size 0.508)
		(drill 0.254)
		(layers "F.Cu" "B.Cu")
		(net "GND")
	)
	(via
		(at 453.8726 -140.335)
		(size 0.508)
		(drill 0.254)
		(layers "F.Cu" "B.Cu")
		(net "GND")
	)
	(via
		(at 123.934728 -95.528384)
		(size 0.508)
		(drill 0.254)
		(layers "F.Cu" "B.Cu")
		(net "GND")
	)
	(via
		(at 239.749838 -148.771356)
		(size 0.508)
		(drill 0.254)
		(layers "F.Cu" "B.Cu")
		(net "GND")
	)
	(via
		(at 329.7174 -151.3332)
		(size 0.508)
		(drill 0.254)
		(layers "F.Cu" "B.Cu")
		(net "GND")
	)
	(via
		(at 440.720734 -167.832024)
		(size 0.5588)
		(drill 0.3048)
		(layers "F.Cu" "B.Cu")
		(net "GND")
	)
	(via
		(at 7.673848 -150.219918)
		(size 0.508)
		(drill 0.254)
		(layers "F.Cu" "B.Cu")
		(net "GND")
	)
	(via
		(at 146.086068 -131.5466)
		(size 0.508)
		(drill 0.254)
		(layers "F.Cu" "B.Cu")
		(net "GND")
	)
	(via
		(at 384.76555 -123.821444)
		(size 0.508)
		(drill 0.254)
		(layers "F.Cu" "B.Cu")
		(net "GND")
	)
	(via
		(at 57.74944 -136.410446)
		(size 0.508)
		(drill 0.254)
		(layers "F.Cu" "B.Cu")
		(net "GND")
	)
	(via
		(at 345.445334 -167.832024)
		(size 0.5588)
		(drill 0.3048)
		(layers "F.Cu" "B.Cu")
		(net "GND")
	)
	(via
		(at 293.22776 -88.099138)
		(size 0.508)
		(drill 0.254)
		(layers "F.Cu" "B.Cu")
		(net "GND")
	)
	(via
		(at 276.631654 -64.324738)
		(size 0.508)
		(drill 0.254)
		(layers "F.Cu" "B.Cu")
		(net "GND")
	)
	(via
		(at 285.649924 -11.916156)
		(size 0.508)
		(drill 0.254)
		(layers "F.Cu" "B.Cu")
		(net "GND")
	)
	(via
		(at 407.239978 -99.878896)
		(size 0.508)
		(drill 0.254)
		(layers "F.Cu" "B.Cu")
		(net "GND")
	)
	(via
		(at 114.206782 -65.810384)
		(size 0.508)
		(drill 0.254)
		(layers "F.Cu" "B.Cu")
		(net "GND")
	)
	(via
		(at 68.799456 -155.549346)
		(size 0.508)
		(drill 0.254)
		(layers "F.Cu" "B.Cu")
		(net "GND")
	)
	(via
		(at 157.046168 -145.8722)
		(size 0.508)
		(drill 0.254)
		(layers "F.Cu" "B.Cu")
		(net "GND")
	)
	(via
		(at 169.5704 -63.5508)
		(size 0.508)
		(drill 0.254)
		(layers "F.Cu" "B.Cu")
		(net "GND")
	)
	(via
		(at 145.521934 14.926056)
		(size 0.5588)
		(drill 0.3048)
		(layers "F.Cu" "B.Cu")
		(net "GND")
	)
	(via
		(at 139.387834 -60.857384)
		(size 0.508)
		(drill 0.254)
		(layers "F.Cu" "B.Cu")
		(net "GND")
	)
	(via
		(at 173.155356 -157.653228)
		(size 0.5588)
		(drill 0.3048)
		(layers "F.Cu" "B.Cu")
		(net "GND")
	)
	(via
		(at 127.39624 -124.680218)
		(size 0.508)
		(drill 0.254)
		(layers "F.Cu" "B.Cu")
		(net "GND")
	)
	(via
		(at 33.099502 -18.757646)
		(size 0.508)
		(drill 0.254)
		(layers "F.Cu" "B.Cu")
		(net "GND")
	)
	(via
		(at 44.092114 -129.564892)
		(size 0.508)
		(drill 0.254)
		(layers "F.Cu" "B.Cu")
		(net "GND")
	)
	(via
		(at 95.421196 -79.360014)
		(size 0.508)
		(drill 0.254)
		(layers "F.Cu" "B.Cu")
		(net "GND")
	)
	(via
		(at 215.0999 0.457454)
		(size 0.508)
		(drill 0.254)
		(layers "F.Cu" "B.Cu")
		(net "GND")
	)
	(via
		(at 78.338172 -59.057286)
		(size 0.508)
		(drill 0.254)
		(layers "F.Cu" "B.Cu")
		(net "GND")
	)
	(via
		(at 62.792102 -9.143746)
		(size 0.508)
		(drill 0.254)
		(layers "F.Cu" "B.Cu")
		(net "GND")
	)
	(via
		(at 153.7462 -31.6484)
		(size 0.508)
		(drill 0.254)
		(layers "F.Cu" "B.Cu")
		(net "GND")
	)
	(via
		(at 454.999852 -113.8936)
		(size 0.508)
		(drill 0.254)
		(layers "F.Cu" "B.Cu")
		(net "GND")
	)
	(via
		(at 77.299312 -17.208246)
		(size 0.508)
		(drill 0.254)
		(layers "F.Cu" "B.Cu")
		(net "GND")
	)
	(via
		(at 239.904778 -80.850486)
		(size 0.508)
		(drill 0.254)
		(layers "F.Cu" "B.Cu")
		(net "GND")
	)
	(via
		(at 239.046258 -52.618386)
		(size 0.508)
		(drill 0.254)
		(layers "F.Cu" "B.Cu")
		(net "GND")
	)
	(via
		(at 72.142096 -18.744946)
		(size 0.508)
		(drill 0.254)
		(layers "F.Cu" "B.Cu")
		(net "GND")
	)
	(via
		(at 459.194408 -135.534654)
		(size 0.508)
		(drill 0.254)
		(layers "F.Cu" "B.Cu")
		(net "GND")
	)
	(via
		(at 407.141934 9.084056)
		(size 0.5588)
		(drill 0.3048)
		(layers "F.Cu" "B.Cu")
		(net "GND")
	)
	(via
		(at 71.470266 -54.104286)
		(size 0.508)
		(drill 0.254)
		(layers "F.Cu" "B.Cu")
		(net "GND")
	)
	(via
		(at 196.893434 -88.040464)
		(size 0.508)
		(drill 0.254)
		(layers "F.Cu" "B.Cu")
		(net "GND")
	)
	(via
		(at 460.362808 -135.534654)
		(size 0.508)
		(drill 0.254)
		(layers "F.Cu" "B.Cu")
		(net "GND")
	)
	(via
		(at 488.976924 -162.243262)
		(size 0.5588)
		(drill 0.3048)
		(layers "F.Cu" "B.Cu")
		(net "GND")
	)
	(via
		(at 72.328786 -84.31784)
		(size 0.508)
		(drill 0.254)
		(layers "F.Cu" "B.Cu")
		(net "GND")
	)
	(via
		(at 45.381418 -148.7678)
		(size 0.508)
		(drill 0.254)
		(layers "F.Cu" "B.Cu")
		(net "GND")
	)
	(via
		(at 381.19685 -24.917654)
		(size 0.508)
		(drill 0.254)
		(layers "F.Cu" "B.Cu")
		(net "GND")
	)
	(via
		(at 277.490174 -54.913784)
		(size 0.508)
		(drill 0.254)
		(layers "F.Cu" "B.Cu")
		(net "GND")
	)
	(via
		(at 457.941934 10.354056)
		(size 0.5588)
		(drill 0.3048)
		(layers "F.Cu" "B.Cu")
		(net "GND")
	)
	(via
		(at 344.8558 -27.5336)
		(size 0.508)
		(drill 0.254)
		(layers "F.Cu" "B.Cu")
		(net "GND")
	)
	(via
		(at 141.049502 -9.156446)
		(size 0.508)
		(drill 0.254)
		(layers "F.Cu" "B.Cu")
		(net "GND")
	)
	(via
		(at 278.8666 -8.1026)
		(size 0.508)
		(drill 0.254)
		(layers "F.Cu" "B.Cu")
		(net "GND")
	)
	(via
		(at 289.031934 14.926056)
		(size 0.5588)
		(drill 0.3048)
		(layers "F.Cu" "B.Cu")
		(net "GND")
	)
	(via
		(at 123.199398 -140.617956)
		(size 0.508)
		(drill 0.254)
		(layers "F.Cu" "B.Cu")
		(net "GND")
	)
	(via
		(at 277.490174 -56.894984)
		(size 0.508)
		(drill 0.254)
		(layers "F.Cu" "B.Cu")
		(net "GND")
	)
	(via
		(at 288.19983 -131.016756)
		(size 0.508)
		(drill 0.254)
		(layers "F.Cu" "B.Cu")
		(net "GND")
	)
	(via
		(at 294.08628 -83.641184)
		(size 0.508)
		(drill 0.254)
		(layers "F.Cu" "B.Cu")
		(net "GND")
	)
	(via
		(at 6.981952 -16.426434)
		(size 0.508)
		(drill 0.254)
		(layers "F.Cu" "B.Cu")
		(net "GND")
	)
	(via
		(at 407.197052 -16.73606)
		(size 0.508)
		(drill 0.254)
		(layers "F.Cu" "B.Cu")
		(net "GND")
	)
	(via
		(at 275.111464 -3.3528)
		(size 0.508)
		(drill 0.254)
		(layers "F.Cu" "B.Cu")
		(net "GND")
	)
	(via
		(at 444.530734 -165.596824)
		(size 0.5588)
		(drill 0.3048)
		(layers "F.Cu" "B.Cu")
		(net "GND")
	)
	(via
		(at 428.020734 -164.479224)
		(size 0.5588)
		(drill 0.3048)
		(layers "F.Cu" "B.Cu")
		(net "GND")
	)
	(via
		(at 201.168 -101.449886)
		(size 0.5588)
		(drill 0.3048)
		(layers "F.Cu" "B.Cu")
		(net "GND")
	)
	(via
		(at 345.4908 -95.8596)
		(size 0.508)
		(drill 0.254)
		(layers "F.Cu" "B.Cu")
		(net "GND")
	)
	(via
		(at 67.101466 -57.57164)
		(size 0.508)
		(drill 0.254)
		(layers "F.Cu" "B.Cu")
		(net "GND")
	)
	(via
		(at 32.15132 -154.063446)
		(size 0.508)
		(drill 0.254)
		(layers "F.Cu" "B.Cu")
		(net "GND")
	)
	(via
		(at 282.07208 -144.5006)
		(size 0.508)
		(drill 0.254)
		(layers "F.Cu" "B.Cu")
		(net "GND")
	)
	(via
		(at 294.111934 14.926056)
		(size 0.5588)
		(drill 0.3048)
		(layers "F.Cu" "B.Cu")
		(net "GND")
	)
	(via
		(at 242.299744 -17.208246)
		(size 0.508)
		(drill 0.254)
		(layers "F.Cu" "B.Cu")
		(net "GND")
	)
	(via
		(at 223.599756 -7.607046)
		(size 0.508)
		(drill 0.254)
		(layers "F.Cu" "B.Cu")
		(net "GND")
	)
	(via
		(at 376.581162 -112.374172)
		(size 0.508)
		(drill 0.254)
		(layers "F.Cu" "B.Cu")
		(net "GND")
	)
	(via
		(at 436.910734 -166.714424)
		(size 0.5588)
		(drill 0.3048)
		(layers "F.Cu" "B.Cu")
		(net "GND")
	)
	(via
		(at 397.764 -146.25828)
		(size 0.508)
		(drill 0.254)
		(layers "F.Cu" "B.Cu")
		(net "GND")
	)
	(via
		(at 299.151802 -17.208246)
		(size 0.508)
		(drill 0.254)
		(layers "F.Cu" "B.Cu")
		(net "GND")
	)
	(via
		(at 407.17724 -148.06168)
		(size 0.508)
		(drill 0.254)
		(layers "F.Cu" "B.Cu")
		(net "GND")
	)
	(via
		(at 234.753658 -58.06694)
		(size 0.508)
		(drill 0.254)
		(layers "F.Cu" "B.Cu")
		(net "GND")
	)
	(via
		(at 126.421642 1.9558)
		(size 0.508)
		(drill 0.254)
		(layers "F.Cu" "B.Cu")
		(net "GND")
	)
	(via
		(at 419.0746 -148.209)
		(size 0.508)
		(drill 0.254)
		(layers "F.Cu" "B.Cu")
		(net "GND")
	)
	(via
		(at 364.777274 -1.332992)
		(size 0.508)
		(drill 0.254)
		(layers "F.Cu" "B.Cu")
		(net "GND")
	)
	(via
		(at 454.8378 -8.8646)
		(size 0.508)
		(drill 0.254)
		(layers "F.Cu" "B.Cu")
		(net "GND")
	)
	(via
		(at 135.095234 -68.287138)
		(size 0.508)
		(drill 0.254)
		(layers "F.Cu" "B.Cu")
		(net "GND")
	)
	(via
		(at 279.699974 -9.143746)
		(size 0.508)
		(drill 0.254)
		(layers "F.Cu" "B.Cu")
		(net "GND")
	)
	(via
		(at 81.772252 -71.935086)
		(size 0.508)
		(drill 0.254)
		(layers "F.Cu" "B.Cu")
		(net "GND")
	)
	(via
		(at 361.214924 -162.268662)
		(size 0.5588)
		(drill 0.3048)
		(layers "F.Cu" "B.Cu")
		(net "GND")
	)
	(via
		(at 376.725688 -89.358724)
		(size 0.508)
		(drill 0.254)
		(layers "F.Cu" "B.Cu")
		(net "GND")
	)
	(via
		(at 495.549682 -37.425376)
		(size 0.508)
		(drill 0.254)
		(layers "F.Cu" "B.Cu")
		(net "GND")
	)
	(via
		(at 403.34438 -119.98198)
		(size 0.508)
		(drill 0.254)
		(layers "F.Cu" "B.Cu")
		(net "GND")
	)
	(via
		(at 29.951934 14.926056)
		(size 0.5588)
		(drill 0.3048)
		(layers "F.Cu" "B.Cu")
		(net "GND")
	)
	(via
		(at 388.1374 -104.2797)
		(size 0.508)
		(drill 0.254)
		(layers "F.Cu" "B.Cu")
		(net "GND")
	)
	(via
		(at 290.71189 -2.314956)
		(size 0.508)
		(drill 0.254)
		(layers "F.Cu" "B.Cu")
		(net "GND")
	)
	(via
		(at 115.923822 -61.847984)
		(size 0.508)
		(drill 0.254)
		(layers "F.Cu" "B.Cu")
		(net "GND")
	)
	(via
		(at 238.44123 -7.095744)
		(size 0.508)
		(drill 0.254)
		(layers "F.Cu" "B.Cu")
		(net "GND")
	)
	(via
		(at 128.227328 -62.343538)
		(size 0.508)
		(drill 0.254)
		(layers "F.Cu" "B.Cu")
		(net "GND")
	)
	(via
		(at 243.338604 -57.076086)
		(size 0.508)
		(drill 0.254)
		(layers "F.Cu" "B.Cu")
		(net "GND")
	)
	(via
		(at 379.81255 -111.802164)
		(size 0.508)
		(drill 0.254)
		(layers "F.Cu" "B.Cu")
		(net "GND")
	)
	(via
		(at 175.4124 -111.125)
		(size 0.508)
		(drill 0.254)
		(layers "F.Cu" "B.Cu")
		(net "GND")
	)
	(via
		(at 283.04236 -139.166092)
		(size 0.508)
		(drill 0.254)
		(layers "F.Cu" "B.Cu")
		(net "GND")
	)
	(via
		(at 129.944368 -96.023938)
		(size 0.508)
		(drill 0.254)
		(layers "F.Cu" "B.Cu")
		(net "GND")
	)
	(via
		(at 73.4314 -139.1666)
		(size 0.508)
		(drill 0.254)
		(layers "F.Cu" "B.Cu")
		(net "GND")
	)
	(via
		(at 492.231934 11.624056)
		(size 0.5588)
		(drill 0.3048)
		(layers "F.Cu" "B.Cu")
		(net "GND")
	)
	(via
		(at 297.549824 -150.219156)
		(size 0.508)
		(drill 0.254)
		(layers "F.Cu" "B.Cu")
		(net "GND")
	)
	(via
		(at 293.681912 -148.7678)
		(size 0.508)
		(drill 0.254)
		(layers "F.Cu" "B.Cu")
		(net "GND")
	)
	(via
		(at 242.480338 -89.27084)
		(size 0.508)
		(drill 0.254)
		(layers "F.Cu" "B.Cu")
		(net "GND")
	)
	(via
		(at 501.0658 -140.3858)
		(size 0.508)
		(drill 0.254)
		(layers "F.Cu" "B.Cu")
		(net "GND")
	)
	(via
		(at 207.4926 -91.7956)
		(size 0.5588)
		(drill 0.3048)
		(layers "F.Cu" "B.Cu")
		(net "GND")
	)
	(via
		(at 1.964944 -112.21339)
		(size 0.508)
		(drill 0.254)
		(layers "F.Cu" "B.Cu")
		(net "GND")
	)
	(via
		(at 475.010734 -165.596824)
		(size 0.5588)
		(drill 0.3048)
		(layers "F.Cu" "B.Cu")
		(net "GND")
	)
	(via
		(at 294.08628 -82.650584)
		(size 0.508)
		(drill 0.254)
		(layers "F.Cu" "B.Cu")
		(net "GND")
	)
	(via
		(at 349.2754 -40.64)
		(size 0.508)
		(drill 0.254)
		(layers "F.Cu" "B.Cu")
		(net "GND")
	)
	(via
		(at 383.8829 -155.702)
		(size 0.508)
		(drill 0.254)
		(layers "F.Cu" "B.Cu")
		(net "GND")
	)
	(via
		(at 70.611746 -63.51524)
		(size 0.508)
		(drill 0.254)
		(layers "F.Cu" "B.Cu")
		(net "GND")
	)
	(via
		(at 34.8742 -85.6488)
		(size 0.508)
		(drill 0.254)
		(layers "F.Cu" "B.Cu")
		(net "GND")
	)
	(via
		(at 167.6146 -65.2526)
		(size 0.508)
		(drill 0.254)
		(layers "F.Cu" "B.Cu")
		(net "GND")
	)
	(via
		(at 295.849802 -150.219156)
		(size 0.508)
		(drill 0.254)
		(layers "F.Cu" "B.Cu")
		(net "GND")
	)
	(via
		(at 100.659184 -63.019686)
		(size 0.508)
		(drill 0.254)
		(layers "F.Cu" "B.Cu")
		(net "GND")
	)
	(via
		(at 291.51072 -100.976684)
		(size 0.508)
		(drill 0.254)
		(layers "F.Cu" "B.Cu")
		(net "GND")
	)
	(via
		(at 299.619924 -162.243262)
		(size 0.5588)
		(drill 0.3048)
		(layers "F.Cu" "B.Cu")
		(net "GND")
	)
	(via
		(at 439.068464 -50.513488)
		(size 0.508)
		(drill 0.254)
		(layers "F.Cu" "B.Cu")
		(net "GND")
	)
	(via
		(at 188.705998 -55.517796)
		(size 0.508)
		(drill 0.254)
		(layers "F.Cu" "B.Cu")
		(net "GND")
	)
	(via
		(at 377.982734 -167.857424)
		(size 0.5588)
		(drill 0.3048)
		(layers "F.Cu" "B.Cu")
		(net "GND")
	)
	(via
		(at 2.9464 -9.256776)
		(size 0.508)
		(drill 0.254)
		(layers "F.Cu" "B.Cu")
		(net "GND")
	)
	(via
		(at 123.650248 -53.427884)
		(size 0.508)
		(drill 0.254)
		(layers "F.Cu" "B.Cu")
		(net "GND")
	)
	(via
		(at 6.79704 -12.59713)
		(size 0.508)
		(drill 0.254)
		(layers "F.Cu" "B.Cu")
		(net "GND")
	)
	(via
		(at 235.691934 14.926056)
		(size 0.5588)
		(drill 0.3048)
		(layers "F.Cu" "B.Cu")
		(net "GND")
	)
	(via
		(at 90.357198 -53.113686)
		(size 0.508)
		(drill 0.254)
		(layers "F.Cu" "B.Cu")
		(net "GND")
	)
	(via
		(at -0.121666 9.084056)
		(size 0.5588)
		(drill 0.3048)
		(layers "F.Cu" "B.Cu")
		(net "GND")
	)
	(via
		(at 124.793248 -94.042738)
		(size 0.508)
		(drill 0.254)
		(layers "F.Cu" "B.Cu")
		(net "GND")
	)
	(via
		(at 297.549824 -13.363956)
		(size 0.508)
		(drill 0.254)
		(layers "F.Cu" "B.Cu")
		(net "GND")
	)
	(via
		(at 474.451934 9.084056)
		(size 0.5588)
		(drill 0.3048)
		(layers "F.Cu" "B.Cu")
		(net "GND")
	)
	(via
		(at 195.549774 -4.277106)
		(size 0.508)
		(drill 0.254)
		(layers "F.Cu" "B.Cu")
		(net "GND")
	)
	(via
		(at 345.066366 -136.522968)
		(size 0.508)
		(drill 0.254)
		(layers "F.Cu" "B.Cu")
		(net "GND")
	)
	(via
		(at 453.420734 -167.832024)
		(size 0.5588)
		(drill 0.3048)
		(layers "F.Cu" "B.Cu")
		(net "GND")
	)
	(via
		(at 200.881234 -54.664864)
		(size 0.508)
		(drill 0.254)
		(layers "F.Cu" "B.Cu")
		(net "GND")
	)
	(via
		(at 306.049934 -21.517356)
		(size 0.508)
		(drill 0.254)
		(layers "F.Cu" "B.Cu")
		(net "GND")
	)
	(via
		(at 498.729 -132.334)
		(size 0.508)
		(drill 0.254)
		(layers "F.Cu" "B.Cu")
		(net "GND")
	)
	(via
		(at 42.449496 0.444754)
		(size 0.508)
		(drill 0.254)
		(layers "F.Cu" "B.Cu")
		(net "GND")
	)
	(via
		(at 238.187738 -60.047886)
		(size 0.508)
		(drill 0.254)
		(layers "F.Cu" "B.Cu")
		(net "GND")
	)
	(via
		(at 279.207214 -65.810384)
		(size 0.508)
		(drill 0.254)
		(layers "F.Cu" "B.Cu")
		(net "GND")
	)
	(via
		(at 348.383606 0.869696)
		(size 0.508)
		(drill 0.254)
		(layers "F.Cu" "B.Cu")
		(net "GND")
	)
	(via
		(at 240.763298 -99.17684)
		(size 0.508)
		(drill 0.254)
		(layers "F.Cu" "B.Cu")
		(net "GND")
	)
	(via
		(at 72.1487 -7.1501)
		(size 0.508)
		(drill 0.254)
		(layers "F.Cu" "B.Cu")
		(net "GND")
	)
	(via
		(at 379.885194 -3.420364)
		(size 0.508)
		(drill 0.254)
		(layers "F.Cu" "B.Cu")
		(net "GND")
	)
	(via
		(at 342.431116 4.676394)
		(size 0.508)
		(drill 0.254)
		(layers "F.Cu" "B.Cu")
		(net "GND")
	)
	(via
		(at 297.549824 -140.617956)
		(size 0.508)
		(drill 0.254)
		(layers "F.Cu" "B.Cu")
		(net "GND")
	)
	(via
		(at 370.344954 -76.695046)
		(size 0.4572)
		(drill 0.2032)
		(layers "F.Cu" "B.Cu")
		(net "GND")
	)
	(via
		(at 237.329218 -87.28964)
		(size 0.508)
		(drill 0.254)
		(layers "F.Cu" "B.Cu")
		(net "GND")
	)
	(via
		(at 139.387834 -59.866784)
		(size 0.508)
		(drill 0.254)
		(layers "F.Cu" "B.Cu")
		(net "GND")
	)
	(via
		(at 128.687576 -126.712218)
		(size 0.508)
		(drill 0.254)
		(layers "F.Cu" "B.Cu")
		(net "GND")
	)
	(via
		(at 52.471574 -150.219156)
		(size 0.508)
		(drill 0.254)
		(layers "F.Cu" "B.Cu")
		(net "GND")
	)
	(via
		(at 108.768896 -103.5812)
		(size 0.508)
		(drill 0.254)
		(layers "F.Cu" "B.Cu")
		(net "GND")
	)
	(via
		(at 168.021 -130.5306)
		(size 0.508)
		(drill 0.254)
		(layers "F.Cu" "B.Cu")
		(net "GND")
	)
	(via
		(at 343.468706 -102.004622)
		(size 0.508)
		(drill 0.254)
		(layers "F.Cu" "B.Cu")
		(net "GND")
	)
	(via
		(at 279.207214 -56.894984)
		(size 0.508)
		(drill 0.254)
		(layers "F.Cu" "B.Cu")
		(net "GND")
	)
	(via
		(at 381.29845 -117.811804)
		(size 0.508)
		(drill 0.254)
		(layers "F.Cu" "B.Cu")
		(net "GND")
	)
	(via
		(at 416.290252 -38.934644)
		(size 0.4572)
		(drill 0.2032)
		(layers "F.Cu" "B.Cu")
		(net "GND")
	)
	(via
		(at 235.612178 -68.46824)
		(size 0.508)
		(drill 0.254)
		(layers "F.Cu" "B.Cu")
		(net "GND")
	)
	(via
		(at 346.92717 -11.930888)
		(size 0.508)
		(drill 0.254)
		(layers "F.Cu" "B.Cu")
		(net "GND")
	)
	(via
		(at 373.992648 -151.392128)
		(size 0.508)
		(drill 0.254)
		(layers "F.Cu" "B.Cu")
		(net "GND")
	)
	(via
		(at 38.199314 -7.607046)
		(size 0.508)
		(drill 0.254)
		(layers "F.Cu" "B.Cu")
		(net "GND")
	)
	(via
		(at 287.349946 -18.757646)
		(size 0.508)
		(drill 0.254)
		(layers "F.Cu" "B.Cu")
		(net "GND")
	)
	(via
		(at 289.113468 -26.495756)
		(size 0.508)
		(drill 0.254)
		(layers "F.Cu" "B.Cu")
		(net "GND")
	)
	(via
		(at 224.449894 -139.170156)
		(size 0.508)
		(drill 0.254)
		(layers "F.Cu" "B.Cu")
		(net "GND")
	)
	(via
		(at 250.206764 -97.690686)
		(size 0.508)
		(drill 0.254)
		(layers "F.Cu" "B.Cu")
		(net "GND")
	)
	(via
		(at 410.690314 -31.734506)
		(size 0.4572)
		(drill 0.2032)
		(layers "F.Cu" "B.Cu")
		(net "GND")
	)
	(via
		(at 253.640844 -66.982086)
		(size 0.508)
		(drill 0.254)
		(layers "F.Cu" "B.Cu")
		(net "GND")
	)
	(via
		(at 80.626712 -49.150778)
		(size 0.508)
		(drill 0.254)
		(layers "F.Cu" "B.Cu")
		(net "GND")
	)
	(via
		(at 243.256054 -140.208)
		(size 0.508)
		(drill 0.254)
		(layers "F.Cu" "B.Cu")
		(net "GND")
	)
	(via
		(at 337.8454 -38.1)
		(size 0.508)
		(drill 0.254)
		(layers "F.Cu" "B.Cu")
		(net "GND")
	)
	(via
		(at 274.937728 -67.21348)
		(size 0.5588)
		(drill 0.3048)
		(layers "F.Cu" "B.Cu")
		(net "GND")
	)
	(via
		(at 53.442108 -9.143746)
		(size 0.508)
		(drill 0.254)
		(layers "F.Cu" "B.Cu")
		(net "GND")
	)
	(via
		(at 205.749906 -9.143746)
		(size 0.508)
		(drill 0.254)
		(layers "F.Cu" "B.Cu")
		(net "GND")
	)
	(via
		(at 272.027904 -12.954)
		(size 0.508)
		(drill 0.254)
		(layers "F.Cu" "B.Cu")
		(net "GND")
	)
	(via
		(at 117.563392 -79.436214)
		(size 0.508)
		(drill 0.254)
		(layers "F.Cu" "B.Cu")
		(net "GND")
	)
	(via
		(at 286.93364 -61.352938)
		(size 0.508)
		(drill 0.254)
		(layers "F.Cu" "B.Cu")
		(net "GND")
	)
	(via
		(at 292.392608 -136.397746)
		(size 0.508)
		(drill 0.254)
		(layers "F.Cu" "B.Cu")
		(net "GND")
	)
	(via
		(at 272.025618 -75.148186)
		(size 0.5588)
		(drill 0.3048)
		(layers "F.Cu" "B.Cu")
		(net "GND")
	)
	(via
		(at -5.207 -13.7922)
		(size 0.508)
		(drill 0.254)
		(layers "F.Cu" "B.Cu")
		(net "GND")
	)
	(via
		(at 423.674286 -9.398)
		(size 0.508)
		(drill 0.254)
		(layers "F.Cu" "B.Cu")
		(net "GND")
	)
	(via
		(at 436.921656 -24.7777)
		(size 0.4572)
		(drill 0.2032)
		(layers "F.Cu" "B.Cu")
		(net "GND")
	)
	(via
		(at 221.04985 -9.156446)
		(size 0.508)
		(drill 0.254)
		(layers "F.Cu" "B.Cu")
		(net "GND")
	)
	(via
		(at 209.092546 -148.767292)
		(size 0.508)
		(drill 0.254)
		(layers "F.Cu" "B.Cu")
		(net "GND")
	)
	(via
		(at 296.270934 -167.832024)
		(size 0.5588)
		(drill 0.3048)
		(layers "F.Cu" "B.Cu")
		(net "GND")
	)
	(via
		(at 39.062152 -47.576486)
		(size 0.508)
		(drill 0.254)
		(layers "F.Cu" "B.Cu")
		(net "GND")
	)
	(via
		(at 10.161524 -162.243262)
		(size 0.5588)
		(drill 0.3048)
		(layers "F.Cu" "B.Cu")
		(net "GND")
	)
	(via
		(at 196.399912 0.457454)
		(size 0.508)
		(drill 0.254)
		(layers "F.Cu" "B.Cu")
		(net "GND")
	)
	(via
		(at 3.459734 -165.596824)
		(size 0.5588)
		(drill 0.3048)
		(layers "F.Cu" "B.Cu")
		(net "GND")
	)
	(via
		(at 201.044556 -136.3345)
		(size 0.508)
		(drill 0.254)
		(layers "F.Cu" "B.Cu")
		(net "GND")
	)
	(via
		(at 107.338876 -58.876438)
		(size 0.508)
		(drill 0.254)
		(layers "F.Cu" "B.Cu")
		(net "GND")
	)
	(via
		(at 344.327734 -167.832024)
		(size 0.5588)
		(drill 0.3048)
		(layers "F.Cu" "B.Cu")
		(net "GND")
	)
	(via
		(at 213.399878 -18.757646)
		(size 0.508)
		(drill 0.254)
		(layers "F.Cu" "B.Cu")
		(net "GND")
	)
	(via
		(at 232.94975 -13.363956)
		(size 0.508)
		(drill 0.254)
		(layers "F.Cu" "B.Cu")
		(net "GND")
	)
	(via
		(at 86.064852 -64.50584)
		(size 0.508)
		(drill 0.254)
		(layers "F.Cu" "B.Cu")
		(net "GND")
	)
	(via
		(at 444.9572 -35.9918)
		(size 0.4572)
		(drill 0.2032)
		(layers "F.Cu" "B.Cu")
		(net "GND")
	)
	(via
		(at 6.98373 -150.217886)
		(size 0.508)
		(drill 0.254)
		(layers "F.Cu" "B.Cu")
		(net "GND")
	)
	(via
		(at 64.090804 2.505456)
		(size 0.508)
		(drill 0.254)
		(layers "F.Cu" "B.Cu")
		(net "GND")
	)
	(via
		(at 44.086018 -13.8938)
		(size 0.508)
		(drill 0.254)
		(layers "F.Cu" "B.Cu")
		(net "GND")
	)
	(via
		(at 36.987734 -167.832024)
		(size 0.5588)
		(drill 0.3048)
		(layers "F.Cu" "B.Cu")
		(net "GND")
	)
	(via
		(at 377.112022 -145.36801)
		(size 0.508)
		(drill 0.254)
		(layers "F.Cu" "B.Cu")
		(net "GND")
	)
	(via
		(at 284.3276 -9.0932)
		(size 0.508)
		(drill 0.254)
		(layers "F.Cu" "B.Cu")
		(net "GND")
	)
	(via
		(at 45.381418 -2.3114)
		(size 0.508)
		(drill 0.254)
		(layers "F.Cu" "B.Cu")
		(net "GND")
	)
	(via
		(at 24.694134 -167.832024)
		(size 0.5588)
		(drill 0.3048)
		(layers "F.Cu" "B.Cu")
		(net "GND")
	)
	(via
		(at 490.961934 12.894056)
		(size 0.5588)
		(drill 0.3048)
		(layers "F.Cu" "B.Cu")
		(net "GND")
	)
	(via
		(at 71.470266 -85.803486)
		(size 0.508)
		(drill 0.254)
		(layers "F.Cu" "B.Cu")
		(net "GND")
	)
	(via
		(at 20.701 -104.6734)
		(size 0.5588)
		(drill 0.3048)
		(layers "F.Cu" "B.Cu")
		(net "GND")
	)
	(via
		(at 11.2268 -35.4076)
		(size 0.508)
		(drill 0.254)
		(layers "F.Cu" "B.Cu")
		(net "GND")
	)
	(via
		(at 306.899818 -131.016756)
		(size 0.508)
		(drill 0.254)
		(layers "F.Cu" "B.Cu")
		(net "GND")
	)
	(via
		(at 204.899768 -140.617956)
		(size 0.508)
		(drill 0.254)
		(layers "F.Cu" "B.Cu")
		(net "GND")
	)
	(via
		(at 73.187306 -96.700086)
		(size 0.508)
		(drill 0.254)
		(layers "F.Cu" "B.Cu")
		(net "GND")
	)
	(via
		(at 343.7636 -59.679586)
		(size 0.508)
		(drill 0.254)
		(layers "F.Cu" "B.Cu")
		(net "GND")
	)
	(via
		(at 64.087502 -141.202156)
		(size 0.508)
		(drill 0.254)
		(layers "F.Cu" "B.Cu")
		(net "GND")
	)
	(via
		(at 144.277334 -167.832024)
		(size 0.5588)
		(drill 0.3048)
		(layers "F.Cu" "B.Cu")
		(net "GND")
	)
	(via
		(at 243.149882 -2.3622)
		(size 0.508)
		(drill 0.254)
		(layers "F.Cu" "B.Cu")
		(net "GND")
	)
	(via
		(at 358.155494 -157.653228)
		(size 0.5588)
		(drill 0.3048)
		(layers "F.Cu" "B.Cu")
		(net "GND")
	)
	(via
		(at 35.8902 -64.4398)
		(size 0.508)
		(drill 0.254)
		(layers "F.Cu" "B.Cu")
		(net "GND")
	)
	(via
		(at 74.986134 -167.832024)
		(size 0.5588)
		(drill 0.3048)
		(layers "F.Cu" "B.Cu")
		(net "GND")
	)
	(via
		(at 128.68148 -139.1666)
		(size 0.508)
		(drill 0.254)
		(layers "F.Cu" "B.Cu")
		(net "GND")
	)
	(via
		(at 71.470266 -80.850486)
		(size 0.508)
		(drill 0.254)
		(layers "F.Cu" "B.Cu")
		(net "GND")
	)
	(via
		(at 11.054334 14.926056)
		(size 0.5588)
		(drill 0.3048)
		(layers "F.Cu" "B.Cu")
		(net "GND")
	)
	(via
		(at 140.199364 -17.208246)
		(size 0.508)
		(drill 0.254)
		(layers "F.Cu" "B.Cu")
		(net "GND")
	)
	(via
		(at 4.0132 -148.209)
		(size 0.508)
		(drill 0.254)
		(layers "F.Cu" "B.Cu")
		(net "GND")
	)
	(via
		(at 42.680382 -68.256658)
		(size 0.5588)
		(drill 0.3048)
		(layers "F.Cu" "B.Cu")
		(net "GND")
	)
	(via
		(at 424.210734 -164.479224)
		(size 0.5588)
		(drill 0.3048)
		(layers "F.Cu" "B.Cu")
		(net "GND")
	)
	(via
		(at 76.941934 14.926056)
		(size 0.5588)
		(drill 0.3048)
		(layers "F.Cu" "B.Cu")
		(net "GND")
	)
	(via
		(at 246.619268 -17.7546)
		(size 0.508)
		(drill 0.254)
		(layers "F.Cu" "B.Cu")
		(net "GND")
	)
	(via
		(at 39.899336 -131.016756)
		(size 0.508)
		(drill 0.254)
		(layers "F.Cu" "B.Cu")
		(net "GND")
	)
	(via
		(at 445.056006 -34.7345)
		(size 0.4572)
		(drill 0.2032)
		(layers "F.Cu" "B.Cu")
		(net "GND")
	)
	(via
		(at 98.451924 -162.243262)
		(size 0.5588)
		(drill 0.3048)
		(layers "F.Cu" "B.Cu")
		(net "GND")
	)
	(via
		(at 237.149132 -26.73731)
		(size 0.508)
		(drill 0.254)
		(layers "F.Cu" "B.Cu")
		(net "GND")
	)
	(via
		(at 240.763298 -76.39304)
		(size 0.508)
		(drill 0.254)
		(layers "F.Cu" "B.Cu")
		(net "GND")
	)
	(via
		(at 444.1444 -123.19)
		(size 0.508)
		(drill 0.254)
		(layers "F.Cu" "B.Cu")
		(net "GND")
	)
	(via
		(at 247.631204 -64.50584)
		(size 0.508)
		(drill 0.254)
		(layers "F.Cu" "B.Cu")
		(net "GND")
	)
	(via
		(at 88.397334 -167.832024)
		(size 0.5588)
		(drill 0.3048)
		(layers "F.Cu" "B.Cu")
		(net "GND")
	)
	(via
		(at 373.8626 -103.3526)
		(size 0.508)
		(drill 0.254)
		(layers "F.Cu" "B.Cu")
		(net "GND")
	)
	(via
		(at 135.061452 -129.568956)
		(size 0.508)
		(drill 0.254)
		(layers "F.Cu" "B.Cu")
		(net "GND")
	)
	(via
		(at 181.7751 -140.0175)
		(size 0.508)
		(drill 0.254)
		(layers "F.Cu" "B.Cu")
		(net "GND")
	)
	(via
		(at 386.25145 -98.464116)
		(size 0.508)
		(drill 0.254)
		(layers "F.Cu" "B.Cu")
		(net "GND")
	)
	(via
		(at 370.0145 -96.9899)
		(size 0.508)
		(drill 0.254)
		(layers "F.Cu" "B.Cu")
		(net "GND")
	)
	(via
		(at 224.740724 -162.243262)
		(size 0.5588)
		(drill 0.3048)
		(layers "F.Cu" "B.Cu")
		(net "GND")
	)
	(via
		(at 137.670794 -69.772784)
		(size 0.508)
		(drill 0.254)
		(layers "F.Cu" "B.Cu")
		(net "GND")
	)
	(via
		(at 136.631934 14.926056)
		(size 0.5588)
		(drill 0.3048)
		(layers "F.Cu" "B.Cu")
		(net "GND")
	)
	(via
		(at 138.040872 -143.950944)
		(size 0.508)
		(drill 0.254)
		(layers "F.Cu" "B.Cu")
		(net "GND")
	)
	(via
		(at 251.923804 -80.850486)
		(size 0.508)
		(drill 0.254)
		(layers "F.Cu" "B.Cu")
		(net "GND")
	)
	(via
		(at 73.4441 -136.3345)
		(size 0.508)
		(drill 0.254)
		(layers "F.Cu" "B.Cu")
		(net "GND")
	)
	(via
		(at 309.449978 -18.757646)
		(size 0.508)
		(drill 0.254)
		(layers "F.Cu" "B.Cu")
		(net "GND")
	)
	(via
		(at 381.433324 -162.243262)
		(size 0.5588)
		(drill 0.3048)
		(layers "F.Cu" "B.Cu")
		(net "GND")
	)
	(via
		(at 26.023824 -100.014024)
		(size 0.5588)
		(drill 0.3048)
		(layers "F.Cu" "B.Cu")
		(net "GND")
	)
	(via
		(at 239.904778 -81.841086)
		(size 0.508)
		(drill 0.254)
		(layers "F.Cu" "B.Cu")
		(net "GND")
	)
	(via
		(at 286.499808 -140.617956)
		(size 0.508)
		(drill 0.254)
		(layers "F.Cu" "B.Cu")
		(net "GND")
	)
	(via
		(at 225.531934 9.084056)
		(size 0.5588)
		(drill 0.3048)
		(layers "F.Cu" "B.Cu")
		(net "GND")
	)
	(via
		(at 282.925774 -93.052138)
		(size 0.508)
		(drill 0.254)
		(layers "F.Cu" "B.Cu")
		(net "GND")
	)
	(via
		(at 274.340828 -98.005138)
		(size 0.508)
		(drill 0.254)
		(layers "F.Cu" "B.Cu")
		(net "GND")
	)
	(via
		(at 149.549358 -134.861046)
		(size 0.508)
		(drill 0.254)
		(layers "F.Cu" "B.Cu")
		(net "GND")
	)
	(via
		(at 138.03757 -131.600956)
		(size 0.508)
		(drill 0.254)
		(layers "F.Cu" "B.Cu")
		(net "GND")
	)
	(via
		(at 34.271966 -101.675184)
		(size 0.5588)
		(drill 0.3048)
		(layers "F.Cu" "B.Cu")
		(net "GND")
	)
	(via
		(at 340.3854 -108.585)
		(size 0.508)
		(drill 0.254)
		(layers "F.Cu" "B.Cu")
		(net "GND")
	)
	(via
		(at 196.908928 -80.551782)
		(size 0.508)
		(drill 0.254)
		(layers "F.Cu" "B.Cu")
		(net "GND")
	)
	(via
		(at 224.449894 -155.600146)
		(size 0.508)
		(drill 0.254)
		(layers "F.Cu" "B.Cu")
		(net "GND")
	)
	(via
		(at 115.460526 -13.338556)
		(size 0.508)
		(drill 0.254)
		(layers "F.Cu" "B.Cu")
		(net "GND")
	)
	(via
		(at 202.349862 0.444754)
		(size 0.508)
		(drill 0.254)
		(layers "F.Cu" "B.Cu")
		(net "GND")
	)
	(via
		(at 500.44858 -120.55856)
		(size 0.508)
		(drill 0.254)
		(layers "F.Cu" "B.Cu")
		(net "GND")
	)
	(via
		(at 238.444532 -136.3345)
		(size 0.508)
		(drill 0.254)
		(layers "F.Cu" "B.Cu")
		(net "GND")
	)
	(via
		(at 90.874088 -17.35709)
		(size 0.508)
		(drill 0.254)
		(layers "F.Cu" "B.Cu")
		(net "GND")
	)
	(via
		(at 122.661934 9.084056)
		(size 0.5588)
		(drill 0.3048)
		(layers "F.Cu" "B.Cu")
		(net "GND")
	)
	(via
		(at 294.999918 0.444754)
		(size 0.508)
		(drill 0.254)
		(layers "F.Cu" "B.Cu")
		(net "GND")
	)
	(via
		(at 66.249296 1.994154)
		(size 0.508)
		(drill 0.254)
		(layers "F.Cu" "B.Cu")
		(net "GND")
	)
	(via
		(at 99.350576 -82.339942)
		(size 0.5588)
		(drill 0.3048)
		(layers "F.Cu" "B.Cu")
		(net "GND")
	)
	(via
		(at 223.599756 -134.861046)
		(size 0.508)
		(drill 0.254)
		(layers "F.Cu" "B.Cu")
		(net "GND")
	)
	(via
		(at 73.4314 -148.7678)
		(size 0.508)
		(drill 0.254)
		(layers "F.Cu" "B.Cu")
		(net "GND")
	)
	(via
		(at 42.77995 -60.843922)
		(size 0.5588)
		(drill 0.3048)
		(layers "F.Cu" "B.Cu")
		(net "GND")
	)
	(via
		(at 410.8958 -124.3838)
		(size 0.508)
		(drill 0.254)
		(layers "F.Cu" "B.Cu")
		(net "GND")
	)
	(via
		(at 396.65275 -107.907836)
		(size 0.508)
		(drill 0.254)
		(layers "F.Cu" "B.Cu")
		(net "GND")
	)
	(via
		(at 232.94975 -27.935936)
		(size 0.508)
		(drill 0.254)
		(layers "F.Cu" "B.Cu")
		(net "GND")
	)
	(via
		(at 451.942962 -126.300484)
		(size 0.508)
		(drill 0.254)
		(layers "F.Cu" "B.Cu")
		(net "GND")
	)
	(via
		(at 243.338604 -98.681286)
		(size 0.508)
		(drill 0.254)
		(layers "F.Cu" "B.Cu")
		(net "GND")
	)
	(via
		(at 82.630772 -82.33664)
		(size 0.508)
		(drill 0.254)
		(layers "F.Cu" "B.Cu")
		(net "GND")
	)
	(via
		(at 292.841934 9.084056)
		(size 0.5588)
		(drill 0.3048)
		(layers "F.Cu" "B.Cu")
		(net "GND")
	)
	(via
		(at 117.066822 -100.48113)
		(size 0.508)
		(drill 0.254)
		(layers "F.Cu" "B.Cu")
		(net "GND")
	)
	(via
		(at 397.11376 -63.74257)
		(size 0.508)
		(drill 0.254)
		(layers "F.Cu" "B.Cu")
		(net "GND")
	)
	(via
		(at 232.099866 -26.488136)
		(size 0.508)
		(drill 0.254)
		(layers "F.Cu" "B.Cu")
		(net "GND")
	)
	(via
		(at 230.328724 -162.243262)
		(size 0.5588)
		(drill 0.3048)
		(layers "F.Cu" "B.Cu")
		(net "GND")
	)
	(via
		(at 122.349514 -146.011646)
		(size 0.508)
		(drill 0.254)
		(layers "F.Cu" "B.Cu")
		(net "GND")
	)
	(via
		(at 387.604 -86.614)
		(size 0.508)
		(drill 0.254)
		(layers "F.Cu" "B.Cu")
		(net "GND")
	)
	(via
		(at 235.46181 -136.410446)
		(size 0.508)
		(drill 0.254)
		(layers "F.Cu" "B.Cu")
		(net "GND")
	)
	(via
		(at 362.931456 4.42595)
		(size 0.5588)
		(drill 0.3048)
		(layers "F.Cu" "B.Cu")
		(net "GND")
	)
	(via
		(at 127.38608 -150.749)
		(size 0.508)
		(drill 0.254)
		(layers "F.Cu" "B.Cu")
		(net "GND")
	)
	(via
		(at 243.2304 -135.4074)
		(size 0.508)
		(drill 0.254)
		(layers "F.Cu" "B.Cu")
		(net "GND")
	)
	(via
		(at 116.361464 -11.916156)
		(size 0.508)
		(drill 0.254)
		(layers "F.Cu" "B.Cu")
		(net "GND")
	)
	(via
		(at 334.0354 -36.83)
		(size 0.508)
		(drill 0.254)
		(layers "F.Cu" "B.Cu")
		(net "GND")
	)
	(via
		(at 31.39948 0.457454)
		(size 0.508)
		(drill 0.254)
		(layers "F.Cu" "B.Cu")
		(net "GND")
	)
	(via
		(at 225.201734 1.994154)
		(size 0.508)
		(drill 0.254)
		(layers "F.Cu" "B.Cu")
		(net "GND")
	)
	(via
		(at 198.772018 -131.016756)
		(size 0.508)
		(drill 0.254)
		(layers "F.Cu" "B.Cu")
		(net "GND")
	)
	(via
		(at 34.736024 -141.1478)
		(size 0.508)
		(drill 0.254)
		(layers "F.Cu" "B.Cu")
		(net "GND")
	)
	(via
		(at 376.9233 -102.0191)
		(size 0.508)
		(drill 0.254)
		(layers "F.Cu" "B.Cu")
		(net "GND")
	)
	(via
		(at 5.93344 -157.523688)
		(size 0.5588)
		(drill 0.3048)
		(layers "F.Cu" "B.Cu")
		(net "GND")
	)
	(via
		(at 459.296008 -151.485854)
		(size 0.508)
		(drill 0.254)
		(layers "F.Cu" "B.Cu")
		(net "GND")
	)
	(via
		(at 417.096956 -93.508068)
		(size 0.508)
		(drill 0.254)
		(layers "F.Cu" "B.Cu")
		(net "GND")
	)
	(via
		(at 132.549392 -144.462246)
		(size 0.508)
		(drill 0.254)
		(layers "F.Cu" "B.Cu")
		(net "GND")
	)
	(via
		(at 449.3514 -53.2638)
		(size 0.508)
		(drill 0.254)
		(layers "F.Cu" "B.Cu")
		(net "GND")
	)
	(via
		(at 386.74675 -116.953284)
		(size 0.508)
		(drill 0.254)
		(layers "F.Cu" "B.Cu")
		(net "GND")
	)
	(via
		(at 227.792534 -155.600146)
		(size 0.508)
		(drill 0.254)
		(layers "F.Cu" "B.Cu")
		(net "GND")
	)
	(via
		(at 239.904778 -54.104286)
		(size 0.508)
		(drill 0.254)
		(layers "F.Cu" "B.Cu")
		(net "GND")
	)
	(via
		(at 454.316592 -25.77846)
		(size 0.508)
		(drill 0.254)
		(layers "F.Cu" "B.Cu")
		(net "GND")
	)
	(via
		(at 6.918706 -7.118858)
		(size 0.508)
		(drill 0.254)
		(layers "F.Cu" "B.Cu")
		(net "GND")
	)
	(via
		(at 129.085848 -89.584784)
		(size 0.508)
		(drill 0.254)
		(layers "F.Cu" "B.Cu")
		(net "GND")
	)
	(via
		(at 36.044124 -136.3345)
		(size 0.508)
		(drill 0.254)
		(layers "F.Cu" "B.Cu")
		(net "GND")
	)
	(via
		(at 111.631222 -53.427884)
		(size 0.508)
		(drill 0.254)
		(layers "F.Cu" "B.Cu")
		(net "GND")
	)
	(via
		(at 239.046258 -85.30844)
		(size 0.508)
		(drill 0.254)
		(layers "F.Cu" "B.Cu")
		(net "GND")
	)
	(via
		(at 425.480734 -163.361624)
		(size 0.5588)
		(drill 0.3048)
		(layers "F.Cu" "B.Cu")
		(net "GND")
	)
	(via
		(at 40.8432 -54.0766)
		(size 0.5588)
		(drill 0.3048)
		(layers "F.Cu" "B.Cu")
		(net "GND")
	)
	(via
		(at 20.10156 -100.92817)
		(size 0.5588)
		(drill 0.3048)
		(layers "F.Cu" "B.Cu")
		(net "GND")
	)
	(via
		(at 218.44254 -11.912092)
		(size 0.508)
		(drill 0.254)
		(layers "F.Cu" "B.Cu")
		(net "GND")
	)
	(via
		(at 243.2304 -3.3528)
		(size 0.508)
		(drill 0.254)
		(layers "F.Cu" "B.Cu")
		(net "GND")
	)
	(via
		(at 467.233 -54.0258)
		(size 0.508)
		(drill 0.254)
		(layers "F.Cu" "B.Cu")
		(net "GND")
	)
	(via
		(at 33.761934 9.084056)
		(size 0.5588)
		(drill 0.3048)
		(layers "F.Cu" "B.Cu")
		(net "GND")
	)
	(via
		(at 3.05435 -108.6866)
		(size 0.508)
		(drill 0.254)
		(layers "F.Cu" "B.Cu")
		(net "GND")
	)
	(via
		(at 304.3174 -125.9332)
		(size 0.508)
		(drill 0.254)
		(layers "F.Cu" "B.Cu")
		(net "GND")
	)
	(via
		(at 110.485682 -50.528474)
		(size 0.508)
		(drill 0.254)
		(layers "F.Cu" "B.Cu")
		(net "GND")
	)
	(via
		(at 493.903 -46.7106)
		(size 0.508)
		(drill 0.254)
		(layers "F.Cu" "B.Cu")
		(net "GND")
	)
	(via
		(at 202.349862 -139.170156)
		(size 0.508)
		(drill 0.254)
		(layers "F.Cu" "B.Cu")
		(net "GND")
	)
	(via
		(at 69.753226 -81.841086)
		(size 0.508)
		(drill 0.254)
		(layers "F.Cu" "B.Cu")
		(net "GND")
	)
	(via
		(at 123.076208 -99.986338)
		(size 0.508)
		(drill 0.254)
		(layers "F.Cu" "B.Cu")
		(net "GND")
	)
	(via
		(at 235.612178 -81.34604)
		(size 0.508)
		(drill 0.254)
		(layers "F.Cu" "B.Cu")
		(net "GND")
	)
	(via
		(at 380.30785 -110.943644)
		(size 0.508)
		(drill 0.254)
		(layers "F.Cu" "B.Cu")
		(net "GND")
	)
	(via
		(at 0.882396 -53.660802)
		(size 0.5588)
		(drill 0.3048)
		(layers "F.Cu" "B.Cu")
		(net "GND")
	)
	(via
		(at 135.771636 -13.363956)
		(size 0.508)
		(drill 0.254)
		(layers "F.Cu" "B.Cu")
		(net "GND")
	)
	(via
		(at 80.913732 -91.25204)
		(size 0.508)
		(drill 0.254)
		(layers "F.Cu" "B.Cu")
		(net "GND")
	)
	(via
		(at 126.421642 -3.762756)
		(size 0.508)
		(drill 0.254)
		(layers "F.Cu" "B.Cu")
		(net "GND")
	)
	(via
		(at 145.12163 -154.1018)
		(size 0.508)
		(drill 0.254)
		(layers "F.Cu" "B.Cu")
		(net "GND")
	)
	(via
		(at 442.522356 -32.2326)
		(size 0.4572)
		(drill 0.2032)
		(layers "F.Cu" "B.Cu")
		(net "GND")
	)
	(via
		(at 308.501796 -144.462246)
		(size 0.508)
		(drill 0.254)
		(layers "F.Cu" "B.Cu")
		(net "GND")
	)
	(via
		(at 292.392608 0.457454)
		(size 0.508)
		(drill 0.254)
		(layers "F.Cu" "B.Cu")
		(net "GND")
	)
	(via
		(at 126.510288 -83.146138)
		(size 0.508)
		(drill 0.254)
		(layers "F.Cu" "B.Cu")
		(net "GND")
	)
	(via
		(at 67.949318 -134.861046)
		(size 0.508)
		(drill 0.254)
		(layers "F.Cu" "B.Cu")
		(net "GND")
	)
	(via
		(at 112.774222 -100.976684)
		(size 0.508)
		(drill 0.254)
		(layers "F.Cu" "B.Cu")
		(net "GND")
	)
	(via
		(at 133.39953 -9.143746)
		(size 0.508)
		(drill 0.254)
		(layers "F.Cu" "B.Cu")
		(net "GND")
	)
	(via
		(at 138.529314 -77.202538)
		(size 0.508)
		(drill 0.254)
		(layers "F.Cu" "B.Cu")
		(net "GND")
	)
	(via
		(at 308.081934 14.926056)
		(size 0.5588)
		(drill 0.3048)
		(layers "F.Cu" "B.Cu")
		(net "GND")
	)
	(via
		(at 392.1379 -110.6551)
		(size 0.508)
		(drill 0.254)
		(layers "F.Cu" "B.Cu")
		(net "GND")
	)
	(via
		(at 181.441598 -1.359408)
		(size 0.508)
		(drill 0.254)
		(layers "F.Cu" "B.Cu")
		(net "GND")
	)
	(via
		(at 376.7836 -111.2774)
		(size 0.508)
		(drill 0.254)
		(layers "F.Cu" "B.Cu")
		(net "GND")
	)
	(via
		(at 333.190088 -127.254)
		(size 0.508)
		(drill 0.254)
		(layers "F.Cu" "B.Cu")
		(net "GND")
	)
	(via
		(at 242.299744 -134.861046)
		(size 0.508)
		(drill 0.254)
		(layers "F.Cu" "B.Cu")
		(net "GND")
	)
	(via
		(at 108.481876 -90.575384)
		(size 0.508)
		(drill 0.254)
		(layers "F.Cu" "B.Cu")
		(net "GND")
	)
	(via
		(at 464.5152 -138.811)
		(size 0.508)
		(drill 0.254)
		(layers "F.Cu" "B.Cu")
		(net "GND")
	)
	(via
		(at 128.68148 -21.5138)
		(size 0.508)
		(drill 0.254)
		(layers "F.Cu" "B.Cu")
		(net "GND")
	)
	(via
		(at 394.9192 -32.7914)
		(size 0.508)
		(drill 0.254)
		(layers "F.Cu" "B.Cu")
		(net "GND")
	)
	(via
		(at 142.898114 -89.584784)
		(size 0.508)
		(drill 0.254)
		(layers "F.Cu" "B.Cu")
		(net "GND")
	)
	(via
		(at 108.481876 -94.538038)
		(size 0.508)
		(drill 0.254)
		(layers "F.Cu" "B.Cu")
		(net "GND")
	)
	(via
		(at 358.6861 -18.099786)
		(size 0.508)
		(drill 0.254)
		(layers "F.Cu" "B.Cu")
		(net "GND")
	)
	(via
		(at 303.041304 -26.682954)
		(size 0.508)
		(drill 0.254)
		(layers "F.Cu" "B.Cu")
		(net "GND")
	)
	(via
		(at 272.339308 -54.913784)
		(size 0.508)
		(drill 0.254)
		(layers "F.Cu" "B.Cu")
		(net "GND")
	)
	(via
		(at 431.830734 -163.361624)
		(size 0.5588)
		(drill 0.3048)
		(layers "F.Cu" "B.Cu")
		(net "GND")
	)
	(via
		(at 207.566514 -77.814678)
		(size 0.5588)
		(drill 0.3048)
		(layers "F.Cu" "B.Cu")
		(net "GND")
	)
	(via
		(at 141.899386 1.994154)
		(size 0.508)
		(drill 0.254)
		(layers "F.Cu" "B.Cu")
		(net "GND")
	)
	(via
		(at 174.5996 -23.8506)
		(size 0.508)
		(drill 0.254)
		(layers "F.Cu" "B.Cu")
		(net "GND")
	)
	(via
		(at 173.7614 -85.9028)
		(size 0.508)
		(drill 0.254)
		(layers "F.Cu" "B.Cu")
		(net "GND")
	)
	(via
		(at 50.099468 -145.998946)
		(size 0.508)
		(drill 0.254)
		(layers "F.Cu" "B.Cu")
		(net "GND")
	)
	(via
		(at 128.630934 -167.832024)
		(size 0.5588)
		(drill 0.3048)
		(layers "F.Cu" "B.Cu")
		(net "GND")
	)
	(via
		(at 267.606018 -75.148186)
		(size 0.5588)
		(drill 0.3048)
		(layers "F.Cu" "B.Cu")
		(net "GND")
	)
	(via
		(at 271.263618 -75.148186)
		(size 0.5588)
		(drill 0.3048)
		(layers "F.Cu" "B.Cu")
		(net "GND")
	)
	(via
		(at 56.899302 -150.219156)
		(size 0.508)
		(drill 0.254)
		(layers "F.Cu" "B.Cu")
		(net "GND")
	)
	(via
		(at 207.564482 -61.529722)
		(size 0.5588)
		(drill 0.3048)
		(layers "F.Cu" "B.Cu")
		(net "GND")
	)
	(via
		(at 252.782324 -69.45884)
		(size 0.508)
		(drill 0.254)
		(layers "F.Cu" "B.Cu")
		(net "GND")
	)
	(via
		(at 286.07512 -61.847984)
		(size 0.508)
		(drill 0.254)
		(layers "F.Cu" "B.Cu")
		(net "GND")
	)
	(via
		(at 165.58768 -31.9405)
		(size 0.508)
		(drill 0.254)
		(layers "F.Cu" "B.Cu")
		(net "GND")
	)
	(via
		(at 483.310184 -20.27428)
		(size 0.508)
		(drill 0.254)
		(layers "F.Cu" "B.Cu")
		(net "GND")
	)
	(via
		(at 131.983734 -167.832024)
		(size 0.5588)
		(drill 0.3048)
		(layers "F.Cu" "B.Cu")
		(net "GND")
	)
	(via
		(at 315.399928 -136.410446)
		(size 0.508)
		(drill 0.254)
		(layers "F.Cu" "B.Cu")
		(net "GND")
	)
	(via
		(at 74.749406 -148.771356)
		(size 0.508)
		(drill 0.254)
		(layers "F.Cu" "B.Cu")
		(net "GND")
	)
	(via
		(at 166.257732 -29.235654)
		(size 0.508)
		(drill 0.254)
		(layers "F.Cu" "B.Cu")
		(net "GND")
	)
	(via
		(at 146.791934 9.084056)
		(size 0.5588)
		(drill 0.3048)
		(layers "F.Cu" "B.Cu")
		(net "GND")
	)
	(via
		(at 288.07664 -88.099138)
		(size 0.508)
		(drill 0.254)
		(layers "F.Cu" "B.Cu")
		(net "GND")
	)
	(via
		(at 10.97534 -151.17572)
		(size 0.508)
		(drill 0.254)
		(layers "F.Cu" "B.Cu")
		(net "GND")
	)
	(via
		(at 300.061884 -11.916156)
		(size 0.508)
		(drill 0.254)
		(layers "F.Cu" "B.Cu")
		(net "GND")
	)
	(via
		(at 353.3648 -98.1202)
		(size 0.508)
		(drill 0.254)
		(layers "F.Cu" "B.Cu")
		(net "GND")
	)
	(via
		(at 138.02741 -2.3622)
		(size 0.508)
		(drill 0.254)
		(layers "F.Cu" "B.Cu")
		(net "GND")
	)
	(via
		(at 226.801934 9.084056)
		(size 0.5588)
		(drill 0.3048)
		(layers "F.Cu" "B.Cu")
		(net "GND")
	)
	(via
		(at 42.748454 -86.55431)
		(size 0.5588)
		(drill 0.3048)
		(layers "F.Cu" "B.Cu")
		(net "GND")
	)
	(via
		(at 312.391298 -134.349744)
		(size 0.508)
		(drill 0.254)
		(layers "F.Cu" "B.Cu")
		(net "GND")
	)
	(via
		(at 287.349946 -146.011646)
		(size 0.508)
		(drill 0.254)
		(layers "F.Cu" "B.Cu")
		(net "GND")
	)
	(via
		(at 76.621386 -53.113686)
		(size 0.508)
		(drill 0.254)
		(layers "F.Cu" "B.Cu")
		(net "GND")
	)
	(via
		(at 42.11955 -60.843922)
		(size 0.5588)
		(drill 0.3048)
		(layers "F.Cu" "B.Cu")
		(net "GND")
	)
	(via
		(at 75.762866 -96.20504)
		(size 0.508)
		(drill 0.254)
		(layers "F.Cu" "B.Cu")
		(net "GND")
	)
	(via
		(at 209.08645 -141.1478)
		(size 0.508)
		(drill 0.254)
		(layers "F.Cu" "B.Cu")
		(net "GND")
	)
	(via
		(at 360.807 -139.6492)
		(size 0.508)
		(drill 0.254)
		(layers "F.Cu" "B.Cu")
		(net "GND")
	)
	(via
		(at 411.451806 -89.621614)
		(size 0.508)
		(drill 0.254)
		(layers "F.Cu" "B.Cu")
		(net "GND")
	)
	(via
		(at 306.899818 -3.762756)
		(size 0.508)
		(drill 0.254)
		(layers "F.Cu" "B.Cu")
		(net "GND")
	)
	(via
		(at 86.923372 -67.972686)
		(size 0.508)
		(drill 0.254)
		(layers "F.Cu" "B.Cu")
		(net "GND")
	)
	(via
		(at 141.899386 -17.208246)
		(size 0.508)
		(drill 0.254)
		(layers "F.Cu" "B.Cu")
		(net "GND")
	)
	(via
		(at 237.142528 -18.744946)
		(size 0.508)
		(drill 0.254)
		(layers "F.Cu" "B.Cu")
		(net "GND")
	)
	(via
		(at 330.916534 -167.832024)
		(size 0.5588)
		(drill 0.3048)
		(layers "F.Cu" "B.Cu")
		(net "GND")
	)
	(via
		(at 180.45176 -16.18234)
		(size 0.508)
		(drill 0.254)
		(layers "F.Cu" "B.Cu")
		(net "GND")
	)
	(via
		(at 315.399928 -9.156446)
		(size 0.508)
		(drill 0.254)
		(layers "F.Cu" "B.Cu")
		(net "GND")
	)
	(via
		(at 230.378 -125.9332)
		(size 0.508)
		(drill 0.254)
		(layers "F.Cu" "B.Cu")
		(net "GND")
	)
	(via
		(at 104.881934 14.926056)
		(size 0.5588)
		(drill 0.3048)
		(layers "F.Cu" "B.Cu")
		(net "GND")
	)
	(via
		(at 307.446934 -167.832024)
		(size 0.5588)
		(drill 0.3048)
		(layers "F.Cu" "B.Cu")
		(net "GND")
	)
	(via
		(at 209.098134 -167.832024)
		(size 0.5588)
		(drill 0.3048)
		(layers "F.Cu" "B.Cu")
		(net "GND")
	)
	(via
		(at 198.772018 -17.2466)
		(size 0.508)
		(drill 0.254)
		(layers "F.Cu" "B.Cu")
		(net "GND")
	)
	(via
		(at 75.59929 -131.016756)
		(size 0.508)
		(drill 0.254)
		(layers "F.Cu" "B.Cu")
		(net "GND")
	)
	(via
		(at 241.621818 -58.06694)
		(size 0.508)
		(drill 0.254)
		(layers "F.Cu" "B.Cu")
		(net "GND")
	)
	(via
		(at 35.887406 -88.769952)
		(size 0.508)
		(drill 0.254)
		(layers "F.Cu" "B.Cu")
		(net "GND")
	)
	(via
		(at 394.441934 9.084056)
		(size 0.5588)
		(drill 0.3048)
		(layers "F.Cu" "B.Cu")
		(net "GND")
	)
	(via
		(at 301.812706 -65.315338)
		(size 0.508)
		(drill 0.254)
		(layers "F.Cu" "B.Cu")
		(net "GND")
	)
	(via
		(at 125.651768 -99.490784)
		(size 0.508)
		(drill 0.254)
		(layers "F.Cu" "B.Cu")
		(net "GND")
	)
	(via
		(at 60.201302 -144.462246)
		(size 0.508)
		(drill 0.254)
		(layers "F.Cu" "B.Cu")
		(net "GND")
	)
	(via
		(at 191.77 -156.083)
		(size 0.508)
		(drill 0.254)
		(layers "F.Cu" "B.Cu")
		(net "GND")
	)
	(via
		(at 455.401934 14.926056)
		(size 0.5588)
		(drill 0.3048)
		(layers "F.Cu" "B.Cu")
		(net "GND")
	)
	(via
		(at 121.359168 -80.174338)
		(size 0.508)
		(drill 0.254)
		(layers "F.Cu" "B.Cu")
		(net "GND")
	)
	(via
		(at 145.391124 -162.243262)
		(size 0.5588)
		(drill 0.3048)
		(layers "F.Cu" "B.Cu")
		(net "GND")
	)
	(via
		(at 114.699542 -9.143746)
		(size 0.508)
		(drill 0.254)
		(layers "F.Cu" "B.Cu")
		(net "GND")
	)
	(via
		(at 72.328786 -72.43064)
		(size 0.508)
		(drill 0.254)
		(layers "F.Cu" "B.Cu")
		(net "GND")
	)
	(via
		(at 38.199314 -154.063446)
		(size 0.508)
		(drill 0.254)
		(layers "F.Cu" "B.Cu")
		(net "GND")
	)
	(via
		(at 293.688008 -124.680218)
		(size 0.508)
		(drill 0.254)
		(layers "F.Cu" "B.Cu")
		(net "GND")
	)
	(via
		(at 411.607 -117.786658)
		(size 0.508)
		(drill 0.254)
		(layers "F.Cu" "B.Cu")
		(net "GND")
	)
	(via
		(at 98.03003 -70.73392)
		(size 0.5588)
		(drill 0.3048)
		(layers "F.Cu" "B.Cu")
		(net "GND")
	)
	(via
		(at 50.194718 -60.474606)
		(size 0.508)
		(drill 0.254)
		(layers "F.Cu" "B.Cu")
		(net "GND")
	)
	(via
		(at 375.1072 -128.8542)
		(size 0.508)
		(drill 0.254)
		(layers "F.Cu" "B.Cu")
		(net "GND")
	)
	(via
		(at 16.149828 -29.567886)
		(size 0.508)
		(drill 0.254)
		(layers "F.Cu" "B.Cu")
		(net "GND")
	)
	(via
		(at 169.909744 -93.261434)
		(size 0.508)
		(drill 0.254)
		(layers "F.Cu" "B.Cu")
		(net "GND")
	)
	(via
		(at 27.92984 -79.55026)
		(size 0.508)
		(drill 0.254)
		(layers "F.Cu" "B.Cu")
		(net "GND")
	)
	(via
		(at 210.291934 9.084056)
		(size 0.5588)
		(drill 0.3048)
		(layers "F.Cu" "B.Cu")
		(net "GND")
	)
	(via
		(at 213.399878 -129.568956)
		(size 0.508)
		(drill 0.254)
		(layers "F.Cu" "B.Cu")
		(net "GND")
	)
	(via
		(at 456.2856 -126.492)
		(size 0.508)
		(drill 0.254)
		(layers "F.Cu" "B.Cu")
		(net "GND")
	)
	(via
		(at 285.2166 -60.362338)
		(size 0.508)
		(drill 0.254)
		(layers "F.Cu" "B.Cu")
		(net "GND")
	)
	(via
		(at 225.210878 -150.193756)
		(size 0.508)
		(drill 0.254)
		(layers "F.Cu" "B.Cu")
		(net "GND")
	)
	(via
		(at 227.786438 -131.5466)
		(size 0.508)
		(drill 0.254)
		(layers "F.Cu" "B.Cu")
		(net "GND")
	)
	(via
		(at 469.138 -21.971)
		(size 0.508)
		(drill 0.254)
		(layers "F.Cu" "B.Cu")
		(net "GND")
	)
	(via
		(at 271.480788 -61.352938)
		(size 0.508)
		(drill 0.254)
		(layers "F.Cu" "B.Cu")
		(net "GND")
	)
	(via
		(at 300.461934 9.084056)
		(size 0.5588)
		(drill 0.3048)
		(layers "F.Cu" "B.Cu")
		(net "GND")
	)
	(via
		(at 32.491934 9.084056)
		(size 0.5588)
		(drill 0.3048)
		(layers "F.Cu" "B.Cu")
		(net "GND")
	)
	(via
		(at 431.271934 13.910056)
		(size 0.5588)
		(drill 0.3048)
		(layers "F.Cu" "B.Cu")
		(net "GND")
	)
	(via
		(at 39.866316 -48.989488)
		(size 0.508)
		(drill 0.254)
		(layers "F.Cu" "B.Cu")
		(net "GND")
	)
	(via
		(at 376.428 -104.354884)
		(size 0.508)
		(drill 0.254)
		(layers "F.Cu" "B.Cu")
		(net "GND")
	)
	(via
		(at 275.199348 -91.565984)
		(size 0.508)
		(drill 0.254)
		(layers "F.Cu" "B.Cu")
		(net "GND")
	)
	(via
		(at 187.863734 -167.832024)
		(size 0.5588)
		(drill 0.3048)
		(layers "F.Cu" "B.Cu")
		(net "GND")
	)
	(via
		(at 135.361934 14.926056)
		(size 0.5588)
		(drill 0.3048)
		(layers "F.Cu" "B.Cu")
		(net "GND")
	)
	(via
		(at 115.460526 -150.193756)
		(size 0.508)
		(drill 0.254)
		(layers "F.Cu" "B.Cu")
		(net "GND")
	)
	(via
		(at 265.659616 -63.019686)
		(size 0.508)
		(drill 0.254)
		(layers "F.Cu" "B.Cu")
		(net "GND")
	)
	(via
		(at 64.087502 -150.803356)
		(size 0.508)
		(drill 0.254)
		(layers "F.Cu" "B.Cu")
		(net "GND")
	)
	(via
		(at 482.7778 -42.49166)
		(size 0.508)
		(drill 0.254)
		(layers "F.Cu" "B.Cu")
		(net "GND")
	)
	(via
		(at 140.924534 -167.832024)
		(size 0.5588)
		(drill 0.3048)
		(layers "F.Cu" "B.Cu")
		(net "GND")
	)
	(via
		(at 275.199348 -99.490784)
		(size 0.508)
		(drill 0.254)
		(layers "F.Cu" "B.Cu")
		(net "GND")
	)
	(via
		(at 439.450734 -164.479224)
		(size 0.5588)
		(drill 0.3048)
		(layers "F.Cu" "B.Cu")
		(net "GND")
	)
	(via
		(at 470.49436 -129.32156)
		(size 0.508)
		(drill 0.254)
		(layers "F.Cu" "B.Cu")
		(net "GND")
	)
	(via
		(at 231.249728 -134.861046)
		(size 0.508)
		(drill 0.254)
		(layers "F.Cu" "B.Cu")
		(net "GND")
	)
	(via
		(at 71.470266 -68.963286)
		(size 0.508)
		(drill 0.254)
		(layers "F.Cu" "B.Cu")
		(net "GND")
	)
	(via
		(at 449.66255 -124.52477)
		(size 0.508)
		(drill 0.254)
		(layers "F.Cu" "B.Cu")
		(net "GND")
	)
	(via
		(at 147.390866 -153.552144)
		(size 0.508)
		(drill 0.254)
		(layers "F.Cu" "B.Cu")
		(net "GND")
	)
	(via
		(at 1.006856 11.373866)
		(size 0.5588)
		(drill 0.3048)
		(layers "F.Cu" "B.Cu")
		(net "GND")
	)
	(via
		(at 31.318454 -78.243176)
		(size 0.508)
		(drill 0.254)
		(layers "F.Cu" "B.Cu")
		(net "GND")
	)
	(via
		(at 170.671744 -93.261434)
		(size 0.508)
		(drill 0.254)
		(layers "F.Cu" "B.Cu")
		(net "GND")
	)
	(via
		(at 9.542272 -122.640344)
		(size 0.508)
		(drill 0.254)
		(layers "F.Cu" "B.Cu")
		(net "GND")
	)
	(via
		(at 239.046258 -96.20504)
		(size 0.508)
		(drill 0.254)
		(layers "F.Cu" "B.Cu")
		(net "GND")
	)
	(via
		(at 200.157334 -167.832024)
		(size 0.5588)
		(drill 0.3048)
		(layers "F.Cu" "B.Cu")
		(net "GND")
	)
	(via
		(at 113.967768 -130.8862)
		(size 0.508)
		(drill 0.254)
		(layers "F.Cu" "B.Cu")
		(net "GND")
	)
	(via
		(at 105.571036 -62.838584)
		(size 0.508)
		(drill 0.254)
		(layers "F.Cu" "B.Cu")
		(net "GND")
	)
	(via
		(at 380.217934 -167.857424)
		(size 0.5588)
		(drill 0.3048)
		(layers "F.Cu" "B.Cu")
		(net "GND")
	)
	(via
		(at 199.742552 -148.767292)
		(size 0.508)
		(drill 0.254)
		(layers "F.Cu" "B.Cu")
		(net "GND")
	)
	(via
		(at 343.066116 4.676394)
		(size 0.508)
		(drill 0.254)
		(layers "F.Cu" "B.Cu")
		(net "GND")
	)
	(via
		(at 167.746934 -167.832024)
		(size 0.5588)
		(drill 0.3048)
		(layers "F.Cu" "B.Cu")
		(net "GND")
	)
	(via
		(at 147.381468 -139.1666)
		(size 0.508)
		(drill 0.254)
		(layers "F.Cu" "B.Cu")
		(net "GND")
	)
	(via
		(at 223.599756 -144.462246)
		(size 0.508)
		(drill 0.254)
		(layers "F.Cu" "B.Cu")
		(net "GND")
	)
	(via
		(at 118.048532 2.451608)
		(size 0.508)
		(drill 0.254)
		(layers "F.Cu" "B.Cu")
		(net "GND")
	)
	(via
		(at 284.341062 -143.950944)
		(size 0.508)
		(drill 0.254)
		(layers "F.Cu" "B.Cu")
		(net "GND")
	)
	(via
		(at 67.966336 -124.769626)
		(size 0.508)
		(drill 0.254)
		(layers "F.Cu" "B.Cu")
		(net "GND")
	)
	(via
		(at 335.203546 -119.971058)
		(size 0.508)
		(drill 0.254)
		(layers "F.Cu" "B.Cu")
		(net "GND")
	)
	(via
		(at 299.623734 -167.832024)
		(size 0.5588)
		(drill 0.3048)
		(layers "F.Cu" "B.Cu")
		(net "GND")
	)
	(via
		(at 384.76555 -95.888556)
		(size 0.508)
		(drill 0.254)
		(layers "F.Cu" "B.Cu")
		(net "GND")
	)
	(via
		(at 444.119 -20.193)
		(size 0.508)
		(drill 0.254)
		(layers "F.Cu" "B.Cu")
		(net "GND")
	)
	(via
		(at -1.239266 14.926056)
		(size 0.5588)
		(drill 0.3048)
		(layers "F.Cu" "B.Cu")
		(net "GND")
	)
	(via
		(at 281.361896 -129.568956)
		(size 0.508)
		(drill 0.254)
		(layers "F.Cu" "B.Cu")
		(net "GND")
	)
	(via
		(at 189.8904 -41.0083)
		(size 0.508)
		(drill 0.254)
		(layers "F.Cu" "B.Cu")
		(net "GND")
	)
	(via
		(at 346.898214 -125.151642)
		(size 0.508)
		(drill 0.254)
		(layers "F.Cu" "B.Cu")
		(net "GND")
	)
	(via
		(at 478.028 -20.1422)
		(size 0.508)
		(drill 0.254)
		(layers "F.Cu" "B.Cu")
		(net "GND")
	)
	(via
		(at 237.329218 -76.39304)
		(size 0.508)
		(drill 0.254)
		(layers "F.Cu" "B.Cu")
		(net "GND")
	)
	(via
		(at 447.066924 -162.243262)
		(size 0.5588)
		(drill 0.3048)
		(layers "F.Cu" "B.Cu")
		(net "GND")
	)
	(via
		(at 314.54979 -3.762756)
		(size 0.508)
		(drill 0.254)
		(layers "F.Cu" "B.Cu")
		(net "GND")
	)
	(via
		(at 446.511934 14.926056)
		(size 0.5588)
		(drill 0.3048)
		(layers "F.Cu" "B.Cu")
		(net "GND")
	)
	(via
		(at 352.604832 -86.738206)
		(size 0.508)
		(drill 0.254)
		(layers "F.Cu" "B.Cu")
		(net "GND")
	)
	(via
		(at 81.772252 -65.991486)
		(size 0.508)
		(drill 0.254)
		(layers "F.Cu" "B.Cu")
		(net "GND")
	)
	(via
		(at 93.985334 -167.832024)
		(size 0.5588)
		(drill 0.3048)
		(layers "F.Cu" "B.Cu")
		(net "GND")
	)
	(via
		(at 335.7372 -134.6835)
		(size 0.508)
		(drill 0.254)
		(layers "F.Cu" "B.Cu")
		(net "GND")
	)
	(via
		(at 239.904778 -88.775286)
		(size 0.508)
		(drill 0.254)
		(layers "F.Cu" "B.Cu")
		(net "GND")
	)
	(via
		(at 73.187306 -55.094886)
		(size 0.508)
		(drill 0.254)
		(layers "F.Cu" "B.Cu")
		(net "GND")
	)
	(via
		(at 207.449928 0.444754)
		(size 0.508)
		(drill 0.254)
		(layers "F.Cu" "B.Cu")
		(net "GND")
	)
	(via
		(at 66.249296 -17.208246)
		(size 0.508)
		(drill 0.254)
		(layers "F.Cu" "B.Cu")
		(net "GND")
	)
	(via
		(at 36.044124 -18.6817)
		(size 0.508)
		(drill 0.254)
		(layers "F.Cu" "B.Cu")
		(net "GND")
	)
	(via
		(at 209.092546 -145.998946)
		(size 0.508)
		(drill 0.254)
		(layers "F.Cu" "B.Cu")
		(net "GND")
	)
	(via
		(at 164.7952 -88.392)
		(size 0.508)
		(drill 0.254)
		(layers "F.Cu" "B.Cu")
		(net "GND")
	)
	(via
		(at 345.62542 -32.766)
		(size 0.508)
		(drill 0.254)
		(layers "F.Cu" "B.Cu")
		(net "GND")
	)
	(via
		(at 122.217688 -79.678784)
		(size 0.508)
		(drill 0.254)
		(layers "F.Cu" "B.Cu")
		(net "GND")
	)
	(via
		(at 308.7878 -56.7944)
		(size 0.508)
		(drill 0.254)
		(layers "F.Cu" "B.Cu")
		(net "GND")
	)
	(via
		(at 455.960734 -165.596824)
		(size 0.5588)
		(drill 0.3048)
		(layers "F.Cu" "B.Cu")
		(net "GND")
	)
	(via
		(at 346.1766 -15.367)
		(size 0.508)
		(drill 0.254)
		(layers "F.Cu" "B.Cu")
		(net "GND")
	)
	(via
		(at 97.334324 -162.243262)
		(size 0.5588)
		(drill 0.3048)
		(layers "F.Cu" "B.Cu")
		(net "GND")
	)
	(via
		(at 135.771636 -3.762756)
		(size 0.508)
		(drill 0.254)
		(layers "F.Cu" "B.Cu")
		(net "GND")
	)
	(via
		(at 395.000734 -165.596824)
		(size 0.5588)
		(drill 0.3048)
		(layers "F.Cu" "B.Cu")
		(net "GND")
	)
	(via
		(at 258.268724 -162.243262)
		(size 0.5588)
		(drill 0.3048)
		(layers "F.Cu" "B.Cu")
		(net "GND")
	)
	(via
		(at 70.611746 -70.44944)
		(size 0.508)
		(drill 0.254)
		(layers "F.Cu" "B.Cu")
		(net "GND")
	)
	(via
		(at 87.781892 -84.31784)
		(size 0.508)
		(drill 0.254)
		(layers "F.Cu" "B.Cu")
		(net "GND")
	)
	(via
		(at 316.249812 -7.607046)
		(size 0.508)
		(drill 0.254)
		(layers "F.Cu" "B.Cu")
		(net "GND")
	)
	(via
		(at 293.694612 -28.66771)
		(size 0.508)
		(drill 0.254)
		(layers "F.Cu" "B.Cu")
		(net "GND")
	)
	(via
		(at 243.338604 -66.982086)
		(size 0.508)
		(drill 0.254)
		(layers "F.Cu" "B.Cu")
		(net "GND")
	)
	(via
		(at 26.141934 9.084056)
		(size 0.5588)
		(drill 0.3048)
		(layers "F.Cu" "B.Cu")
		(net "GND")
	)
	(via
		(at 296.66184 -98.995738)
		(size 0.508)
		(drill 0.254)
		(layers "F.Cu" "B.Cu")
		(net "GND")
	)
	(via
		(at 245.914164 -76.39304)
		(size 0.508)
		(drill 0.254)
		(layers "F.Cu" "B.Cu")
		(net "GND")
	)
	(via
		(at 459.16723 -26.543)
		(size 0.508)
		(drill 0.254)
		(layers "F.Cu" "B.Cu")
		(net "GND")
	)
	(via
		(at 483.799896 -115.423188)
		(size 0.508)
		(drill 0.254)
		(layers "F.Cu" "B.Cu")
		(net "GND")
	)
	(via
		(at 383.3368 -105.0544)
		(size 0.508)
		(drill 0.254)
		(layers "F.Cu" "B.Cu")
		(net "GND")
	)
	(via
		(at 381.741934 14.926056)
		(size 0.5588)
		(drill 0.3048)
		(layers "F.Cu" "B.Cu")
		(net "GND")
	)
	(via
		(at 303.529746 -80.174338)
		(size 0.508)
		(drill 0.254)
		(layers "F.Cu" "B.Cu")
		(net "GND")
	)
	(via
		(at 295.849802 -13.363956)
		(size 0.508)
		(drill 0.254)
		(layers "F.Cu" "B.Cu")
		(net "GND")
	)
	(via
		(at 403.759416 -148.817584)
		(size 0.508)
		(drill 0.254)
		(layers "F.Cu" "B.Cu")
		(net "GND")
	)
	(via
		(at 464.291934 14.926056)
		(size 0.5588)
		(drill 0.3048)
		(layers "F.Cu" "B.Cu")
		(net "GND")
	)
	(via
		(at 216.799922 -18.757646)
		(size 0.508)
		(drill 0.254)
		(layers "F.Cu" "B.Cu")
		(net "GND")
	)
	(via
		(at 283.499814 -65.315338)
		(size 0.508)
		(drill 0.254)
		(layers "F.Cu" "B.Cu")
		(net "GND")
	)
	(via
		(at 410.951934 14.926056)
		(size 0.5588)
		(drill 0.3048)
		(layers "F.Cu" "B.Cu")
		(net "GND")
	)
	(via
		(at 380.901702 -21.347684)
		(size 0.508)
		(drill 0.254)
		(layers "F.Cu" "B.Cu")
		(net "GND")
	)
	(via
		(at 141.104874 -54.913784)
		(size 0.508)
		(drill 0.254)
		(layers "F.Cu" "B.Cu")
		(net "GND")
	)
	(via
		(at 90.802968 -2.975356)
		(size 0.508)
		(drill 0.254)
		(layers "F.Cu" "B.Cu")
		(net "GND")
	)
	(via
		(at 104.415844 -89.27084)
		(size 0.508)
		(drill 0.254)
		(layers "F.Cu" "B.Cu")
		(net "GND")
	)
	(via
		(at 300.099984 -18.757646)
		(size 0.508)
		(drill 0.254)
		(layers "F.Cu" "B.Cu")
		(net "GND")
	)
	(via
		(at 83.291934 9.084056)
		(size 0.5588)
		(drill 0.3048)
		(layers "F.Cu" "B.Cu")
		(net "GND")
	)
	(via
		(at 260.507734 -167.832024)
		(size 0.5588)
		(drill 0.3048)
		(layers "F.Cu" "B.Cu")
		(net "GND")
	)
	(via
		(at 108.197396 -52.437284)
		(size 0.508)
		(drill 0.254)
		(layers "F.Cu" "B.Cu")
		(net "GND")
	)
	(via
		(at 275.773134 -63.829184)
		(size 0.508)
		(drill 0.254)
		(layers "F.Cu" "B.Cu")
		(net "GND")
	)
	(via
		(at 214.6554 -84.201)
		(size 0.508)
		(drill 0.254)
		(layers "F.Cu" "B.Cu")
		(net "GND")
	)
	(via
		(at 135.771636 1.9558)
		(size 0.508)
		(drill 0.254)
		(layers "F.Cu" "B.Cu")
		(net "GND")
	)
	(via
		(at 296.69994 -2.314956)
		(size 0.508)
		(drill 0.254)
		(layers "F.Cu" "B.Cu")
		(net "GND")
	)
	(via
		(at 335.3054 -108.585)
		(size 0.508)
		(drill 0.254)
		(layers "F.Cu" "B.Cu")
		(net "GND")
	)
	(via
		(at 422.940734 -163.361624)
		(size 0.5588)
		(drill 0.3048)
		(layers "F.Cu" "B.Cu")
		(net "GND")
	)
	(via
		(at 207.515714 -85.028278)
		(size 0.5588)
		(drill 0.3048)
		(layers "F.Cu" "B.Cu")
		(net "GND")
	)
	(via
		(at 74.045826 -65.49644)
		(size 0.508)
		(drill 0.254)
		(layers "F.Cu" "B.Cu")
		(net "GND")
	)
	(via
		(at 202.00874 -92.639134)
		(size 0.5588)
		(drill 0.3048)
		(layers "F.Cu" "B.Cu")
		(net "GND")
	)
	(via
		(at 187.2996 -134.4676)
		(size 0.508)
		(drill 0.254)
		(layers "F.Cu" "B.Cu")
		(net "GND")
	)
	(via
		(at 111.915702 -93.547184)
		(size 0.508)
		(drill 0.254)
		(layers "F.Cu" "B.Cu")
		(net "GND")
	)
	(via
		(at 237.329218 -69.45884)
		(size 0.508)
		(drill 0.254)
		(layers "F.Cu" "B.Cu")
		(net "GND")
	)
	(via
		(at 163.301934 14.926056)
		(size 0.5588)
		(drill 0.3048)
		(layers "F.Cu" "B.Cu")
		(net "GND")
	)
	(via
		(at 106.480356 -59.371484)
		(size 0.508)
		(drill 0.254)
		(layers "F.Cu" "B.Cu")
		(net "GND")
	)
	(via
		(at 289.79368 -91.070938)
		(size 0.508)
		(drill 0.254)
		(layers "F.Cu" "B.Cu")
		(net "GND")
	)
	(via
		(at 489.7374 -34.563812)
		(size 0.508)
		(drill 0.254)
		(layers "F.Cu" "B.Cu")
		(net "GND")
	)
	(via
		(at 352.679 -89.119456)
		(size 0.508)
		(drill 0.254)
		(layers "F.Cu" "B.Cu")
		(net "GND")
	)
	(via
		(at 357.865934 -167.857424)
		(size 0.5588)
		(drill 0.3048)
		(layers "F.Cu" "B.Cu")
		(net "GND")
	)
	(via
		(at 107.62361 -100.977192)
		(size 0.508)
		(drill 0.254)
		(layers "F.Cu" "B.Cu")
		(net "GND")
	)
	(via
		(at 96.721168 -6.332982)
		(size 0.508)
		(drill 0.254)
		(layers "F.Cu" "B.Cu")
		(net "GND")
	)
	(via
		(at 42.680382 -68.917058)
		(size 0.5588)
		(drill 0.3048)
		(layers "F.Cu" "B.Cu")
		(net "GND")
	)
	(via
		(at 114.491262 -98.005138)
		(size 0.508)
		(drill 0.254)
		(layers "F.Cu" "B.Cu")
		(net "GND")
	)
	(via
		(at 196.800724 -162.243262)
		(size 0.5588)
		(drill 0.3048)
		(layers "F.Cu" "B.Cu")
		(net "GND")
	)
	(via
		(at 191.700404 -52.079398)
		(size 0.508)
		(drill 0.254)
		(layers "F.Cu" "B.Cu")
		(net "GND")
	)
	(via
		(at 112.545876 -70.841616)
		(size 0.5588)
		(drill 0.3048)
		(layers "F.Cu" "B.Cu")
		(net "GND")
	)
	(via
		(at 60.453524 -162.243262)
		(size 0.5588)
		(drill 0.3048)
		(layers "F.Cu" "B.Cu")
		(net "GND")
	)
	(via
		(at 101.071934 9.084056)
		(size 0.5588)
		(drill 0.3048)
		(layers "F.Cu" "B.Cu")
		(net "GND")
	)
	(via
		(at 252.782324 -68.46824)
		(size 0.508)
		(drill 0.254)
		(layers "F.Cu" "B.Cu")
		(net "GND")
	)
	(via
		(at 261.723378 2.270252)
		(size 0.508)
		(drill 0.254)
		(layers "F.Cu" "B.Cu")
		(net "GND")
	)
	(via
		(at 123.934728 -78.688438)
		(size 0.508)
		(drill 0.254)
		(layers "F.Cu" "B.Cu")
		(net "GND")
	)
	(via
		(at 86.064852 -62.52464)
		(size 0.508)
		(drill 0.254)
		(layers "F.Cu" "B.Cu")
		(net "GND")
	)
	(via
		(at 469.340438 -6.688074)
		(size 0.5588)
		(drill 0.3048)
		(layers "F.Cu" "B.Cu")
		(net "GND")
	)
	(via
		(at 383.9591 -26.2636)
		(size 0.508)
		(drill 0.254)
		(layers "F.Cu" "B.Cu")
		(net "GND")
	)
	(via
		(at 363.885226 -8.84682)
		(size 0.508)
		(drill 0.254)
		(layers "F.Cu" "B.Cu")
		(net "GND")
	)
	(via
		(at 303.529746 -59.371484)
		(size 0.508)
		(drill 0.254)
		(layers "F.Cu" "B.Cu")
		(net "GND")
	)
	(via
		(at 31.893002 -63.656464)
		(size 0.508)
		(drill 0.254)
		(layers "F.Cu" "B.Cu")
		(net "GND")
	)
	(via
		(at 351.8154 -38.1)
		(size 0.508)
		(drill 0.254)
		(layers "F.Cu" "B.Cu")
		(net "GND")
	)
	(via
		(at 453.404478 -118.61927)
		(size 0.508)
		(drill 0.254)
		(layers "F.Cu" "B.Cu")
		(net "GND")
	)
	(via
		(at 145.12163 -17.2466)
		(size 0.508)
		(drill 0.254)
		(layers "F.Cu" "B.Cu")
		(net "GND")
	)
	(via
		(at 237.142528 -11.912092)
		(size 0.508)
		(drill 0.254)
		(layers "F.Cu" "B.Cu")
		(net "GND")
	)
	(via
		(at 249.348244 -61.53404)
		(size 0.508)
		(drill 0.254)
		(layers "F.Cu" "B.Cu")
		(net "GND")
	)
	(via
		(at 76.621386 -85.803486)
		(size 0.508)
		(drill 0.254)
		(layers "F.Cu" "B.Cu")
		(net "GND")
	)
	(via
		(at 281.399996 -136.410446)
		(size 0.508)
		(drill 0.254)
		(layers "F.Cu" "B.Cu")
		(net "GND")
	)
	(via
		(at 355.08565 -116.220494)
		(size 0.508)
		(drill 0.254)
		(layers "F.Cu" "B.Cu")
		(net "GND")
	)
	(via
		(at 50.047398 -84.44992)
		(size 0.508)
		(drill 0.254)
		(layers "F.Cu" "B.Cu")
		(net "GND")
	)
	(via
		(at 139.387834 -72.744584)
		(size 0.508)
		(drill 0.254)
		(layers "F.Cu" "B.Cu")
		(net "GND")
	)
	(via
		(at 132.519674 -69.772784)
		(size 0.508)
		(drill 0.254)
		(layers "F.Cu" "B.Cu")
		(net "GND")
	)
	(via
		(at 289.049968 -129.568956)
		(size 0.508)
		(drill 0.254)
		(layers "F.Cu" "B.Cu")
		(net "GND")
	)
	(via
		(at 477.012 -136.906)
		(size 0.508)
		(drill 0.254)
		(layers "F.Cu" "B.Cu")
		(net "GND")
	)
	(via
		(at 288.93516 -91.565984)
		(size 0.508)
		(drill 0.254)
		(layers "F.Cu" "B.Cu")
		(net "GND")
	)
	(via
		(at 83.489292 -64.010286)
		(size 0.508)
		(drill 0.254)
		(layers "F.Cu" "B.Cu")
		(net "GND")
	)
	(via
		(at 369.57 -158.3436)
		(size 0.508)
		(drill 0.254)
		(layers "F.Cu" "B.Cu")
		(net "GND")
	)
	(via
		(at 245.055644 -98.681286)
		(size 0.508)
		(drill 0.254)
		(layers "F.Cu" "B.Cu")
		(net "GND")
	)
	(via
		(at 217.472006 -17.2466)
		(size 0.508)
		(drill 0.254)
		(layers "F.Cu" "B.Cu")
		(net "GND")
	)
	(via
		(at 200.8886 -98.8822)
		(size 0.508)
		(drill 0.254)
		(layers "F.Cu" "B.Cu")
		(net "GND")
	)
	(via
		(at 414.050734 -9.552686)
		(size 0.508)
		(drill 0.254)
		(layers "F.Cu" "B.Cu")
		(net "GND")
	)
	(via
		(at 71.633334 -167.832024)
		(size 0.5588)
		(drill 0.3048)
		(layers "F.Cu" "B.Cu")
		(net "GND")
	)
	(via
		(at 247.631204 -61.53404)
		(size 0.508)
		(drill 0.254)
		(layers "F.Cu" "B.Cu")
		(net "GND")
	)
	(via
		(at 281.411934 14.926056)
		(size 0.5588)
		(drill 0.3048)
		(layers "F.Cu" "B.Cu")
		(net "GND")
	)
	(via
		(at 117.925342 -101.967538)
		(size 0.508)
		(drill 0.254)
		(layers "F.Cu" "B.Cu")
		(net "GND")
	)
	(via
		(at 269.448534 -167.832024)
		(size 0.5588)
		(drill 0.3048)
		(layers "F.Cu" "B.Cu")
		(net "GND")
	)
	(via
		(at 171.19854 -19.80438)
		(size 0.508)
		(drill 0.254)
		(layers "F.Cu" "B.Cu")
		(net "GND")
	)
	(via
		(at 236.171994 -17.2466)
		(size 0.508)
		(drill 0.254)
		(layers "F.Cu" "B.Cu")
		(net "GND")
	)
	(via
		(at 259.8928 -155.1178)
		(size 0.508)
		(drill 0.254)
		(layers "F.Cu" "B.Cu")
		(net "GND")
	)
	(via
		(at 223.599756 -131.016756)
		(size 0.508)
		(drill 0.254)
		(layers "F.Cu" "B.Cu")
		(net "GND")
	)
	(via
		(at 152.099518 -2.325878)
		(size 0.508)
		(drill 0.254)
		(layers "F.Cu" "B.Cu")
		(net "GND")
	)
	(via
		(at 273.126708 -70.84314)
		(size 0.5588)
		(drill 0.3048)
		(layers "F.Cu" "B.Cu")
		(net "GND")
	)
	(via
		(at 80.913732 -94.223586)
		(size 0.508)
		(drill 0.254)
		(layers "F.Cu" "B.Cu")
		(net "GND")
	)
	(via
		(at 486.440734 -163.361624)
		(size 0.5588)
		(drill 0.3048)
		(layers "F.Cu" "B.Cu")
		(net "GND")
	)
	(via
		(at 94.257876 -70.841616)
		(size 0.5588)
		(drill 0.3048)
		(layers "F.Cu" "B.Cu")
		(net "GND")
	)
	(via
		(at 443.322456 -37.0332)
		(size 0.4572)
		(drill 0.2032)
		(layers "F.Cu" "B.Cu")
		(net "GND")
	)
	(via
		(at 159.491934 14.926056)
		(size 0.5588)
		(drill 0.3048)
		(layers "F.Cu" "B.Cu")
		(net "GND")
	)
	(via
		(at 224.449894 -11.916156)
		(size 0.508)
		(drill 0.254)
		(layers "F.Cu" "B.Cu")
		(net "GND")
	)
	(via
		(at 290.71189 -21.517356)
		(size 0.508)
		(drill 0.254)
		(layers "F.Cu" "B.Cu")
		(net "GND")
	)
	(via
		(at 20.944586 -157.208728)
		(size 0.508)
		(drill 0.254)
		(layers "F.Cu" "B.Cu")
		(net "GND")
	)
	(via
		(at 311.092596 -148.767292)
		(size 0.508)
		(drill 0.254)
		(layers "F.Cu" "B.Cu")
		(net "GND")
	)
	(via
		(at 306.049934 -129.568956)
		(size 0.508)
		(drill 0.254)
		(layers "F.Cu" "B.Cu")
		(net "GND")
	)
	(via
		(at 142.749524 -145.998946)
		(size 0.508)
		(drill 0.254)
		(layers "F.Cu" "B.Cu")
		(net "GND")
	)
	(via
		(at 50.099468 -9.143746)
		(size 0.508)
		(drill 0.254)
		(layers "F.Cu" "B.Cu")
		(net "GND")
	)
	(via
		(at 283.04236 -11.912092)
		(size 0.508)
		(drill 0.254)
		(layers "F.Cu" "B.Cu")
		(net "GND")
	)
	(via
		(at 261.625334 -167.832024)
		(size 0.5588)
		(drill 0.3048)
		(layers "F.Cu" "B.Cu")
		(net "GND")
	)
	(via
		(at 430.001934 14.926056)
		(size 0.5588)
		(drill 0.3048)
		(layers "F.Cu" "B.Cu")
		(net "GND")
	)
	(via
		(at 349.215456 -67.469766)
		(size 0.508)
		(drill 0.254)
		(layers "F.Cu" "B.Cu")
		(net "GND")
	)
	(via
		(at 113.632742 -95.528384)
		(size 0.508)
		(drill 0.254)
		(layers "F.Cu" "B.Cu")
		(net "GND")
	)
	(via
		(at 103.097076 -82.339942)
		(size 0.5588)
		(drill 0.3048)
		(layers "F.Cu" "B.Cu")
		(net "GND")
	)
	(via
		(at 234.753658 -96.700086)
		(size 0.508)
		(drill 0.254)
		(layers "F.Cu" "B.Cu")
		(net "GND")
	)
	(via
		(at 86.064852 -59.55284)
		(size 0.508)
		(drill 0.254)
		(layers "F.Cu" "B.Cu")
		(net "GND")
	)
	(via
		(at 471.911934 10.354056)
		(size 0.5588)
		(drill 0.3048)
		(layers "F.Cu" "B.Cu")
		(net "GND")
	)
	(via
		(at 167.811704 0.6604)
		(size 0.508)
		(drill 0.254)
		(layers "F.Cu" "B.Cu")
		(net "GND")
	)
	(via
		(at 422.690036 -35.734752)
		(size 0.4572)
		(drill 0.2032)
		(layers "F.Cu" "B.Cu")
		(net "GND")
	)
	(via
		(at 185.624724 -162.243262)
		(size 0.5588)
		(drill 0.3048)
		(layers "F.Cu" "B.Cu")
		(net "GND")
	)
	(via
		(at 499.357142 -42.21226)
		(size 0.508)
		(drill 0.254)
		(layers "F.Cu" "B.Cu")
		(net "GND")
	)
	(via
		(at 243.338604 -51.132486)
		(size 0.508)
		(drill 0.254)
		(layers "F.Cu" "B.Cu")
		(net "GND")
	)
	(via
		(at 272.521934 9.084056)
		(size 0.5588)
		(drill 0.3048)
		(layers "F.Cu" "B.Cu")
		(net "GND")
	)
	(via
		(at 295.80332 -73.735184)
		(size 0.508)
		(drill 0.254)
		(layers "F.Cu" "B.Cu")
		(net "GND")
	)
	(via
		(at 116.435632 -70.85076)
		(size 0.508)
		(drill 0.254)
		(layers "F.Cu" "B.Cu")
		(net "GND")
	)
	(via
		(at 475.721934 13.910056)
		(size 0.5588)
		(drill 0.3048)
		(layers "F.Cu" "B.Cu")
		(net "GND")
	)
	(via
		(at 11.538966 1.185926)
		(size 0.508)
		(drill 0.254)
		(layers "F.Cu" "B.Cu")
		(net "GND")
	)
	(via
		(at 162.31743 -76.08697)
		(size 0.508)
		(drill 0.254)
		(layers "F.Cu" "B.Cu")
		(net "GND")
	)
	(via
		(at 423.490136 -30.93466)
		(size 0.4572)
		(drill 0.2032)
		(layers "F.Cu" "B.Cu")
		(net "GND")
	)
	(via
		(at 133.24713 -125.929898)
		(size 0.508)
		(drill 0.254)
		(layers "F.Cu" "B.Cu")
		(net "GND")
	)
	(via
		(at 217.472006 -131.016756)
		(size 0.508)
		(drill 0.254)
		(layers "F.Cu" "B.Cu")
		(net "GND")
	)
	(via
		(at 119.357902 -63.829184)
		(size 0.508)
		(drill 0.254)
		(layers "F.Cu" "B.Cu")
		(net "GND")
	)
	(via
		(at 345.4654 -154.9654)
		(size 0.508)
		(drill 0.254)
		(layers "F.Cu" "B.Cu")
		(net "GND")
	)
	(via
		(at 21.6535 -32.43072)
		(size 0.508)
		(drill 0.254)
		(layers "F.Cu" "B.Cu")
		(net "GND")
	)
	(via
		(at 124.81052 -125.410976)
		(size 0.508)
		(drill 0.254)
		(layers "F.Cu" "B.Cu")
		(net "GND")
	)
	(via
		(at 255.35763 -63.019686)
		(size 0.508)
		(drill 0.254)
		(layers "F.Cu" "B.Cu")
		(net "GND")
	)
	(via
		(at 476.4278 -29.3878)
		(size 0.508)
		(drill 0.254)
		(layers "F.Cu" "B.Cu")
		(net "GND")
	)
	(via
		(at 234.551728 -144.462246)
		(size 0.508)
		(drill 0.254)
		(layers "F.Cu" "B.Cu")
		(net "GND")
	)
	(via
		(at 128.677416 -2.3622)
		(size 0.508)
		(drill 0.254)
		(layers "F.Cu" "B.Cu")
		(net "GND")
	)
	(via
		(at 149.549358 -150.219156)
		(size 0.508)
		(drill 0.254)
		(layers "F.Cu" "B.Cu")
		(net "GND")
	)
	(via
		(at 239.904778 -84.812886)
		(size 0.508)
		(drill 0.254)
		(layers "F.Cu" "B.Cu")
		(net "GND")
	)
	(via
		(at 410.2608 -124.3838)
		(size 0.508)
		(drill 0.254)
		(layers "F.Cu" "B.Cu")
		(net "GND")
	)
	(via
		(at 131.661408 -64.324738)
		(size 0.508)
		(drill 0.254)
		(layers "F.Cu" "B.Cu")
		(net "GND")
	)
	(via
		(at 486.6767 -153.5303)
		(size 0.508)
		(drill 0.254)
		(layers "F.Cu" "B.Cu")
		(net "GND")
	)
	(via
		(at 28.11018 -87.503)
		(size 0.508)
		(drill 0.254)
		(layers "F.Cu" "B.Cu")
		(net "GND")
	)
	(via
		(at 68.036186 -86.794086)
		(size 0.508)
		(drill 0.254)
		(layers "F.Cu" "B.Cu")
		(net "GND")
	)
	(via
		(at 200.515728 -64.9732)
		(size 0.508)
		(drill 0.254)
		(layers "F.Cu" "B.Cu")
		(net "GND")
	)
	(via
		(at 105.571036 -52.932838)
		(size 0.508)
		(drill 0.254)
		(layers "F.Cu" "B.Cu")
		(net "GND")
	)
	(via
		(at 138.03757 -23.549356)
		(size 0.508)
		(drill 0.254)
		(layers "F.Cu" "B.Cu")
		(net "GND")
	)
	(via
		(at 33.631124 -162.243262)
		(size 0.5588)
		(drill 0.3048)
		(layers "F.Cu" "B.Cu")
		(net "GND")
	)
	(via
		(at 138.040872 -7.095744)
		(size 0.508)
		(drill 0.254)
		(layers "F.Cu" "B.Cu")
		(net "GND")
	)
	(via
		(at 409.956 -119.253)
		(size 0.508)
		(drill 0.254)
		(layers "F.Cu" "B.Cu")
		(net "GND")
	)
	(via
		(at 68.799456 -9.143746)
		(size 0.508)
		(drill 0.254)
		(layers "F.Cu" "B.Cu")
		(net "GND")
	)
	(via
		(at 220.274134 -167.832024)
		(size 0.5588)
		(drill 0.3048)
		(layers "F.Cu" "B.Cu")
		(net "GND")
	)
	(via
		(at 394.8176 -152.2222)
		(size 0.508)
		(drill 0.254)
		(layers "F.Cu" "B.Cu")
		(net "GND")
	)
	(via
		(at 475.718632 -119.719852)
		(size 0.508)
		(drill 0.254)
		(layers "F.Cu" "B.Cu")
		(net "GND")
	)
	(via
		(at 441.990734 -163.361624)
		(size 0.5588)
		(drill 0.3048)
		(layers "F.Cu" "B.Cu")
		(net "GND")
	)
	(via
		(at 130.802888 -85.622384)
		(size 0.508)
		(drill 0.254)
		(layers "F.Cu" "B.Cu")
		(net "GND")
	)
	(via
		(at 247.121934 9.084056)
		(size 0.5588)
		(drill 0.3048)
		(layers "F.Cu" "B.Cu")
		(net "GND")
	)
	(via
		(at 250.206764 -78.869286)
		(size 0.508)
		(drill 0.254)
		(layers "F.Cu" "B.Cu")
		(net "GND")
	)
	(via
		(at 378.911104 -145.687034)
		(size 0.508)
		(drill 0.254)
		(layers "F.Cu" "B.Cu")
		(net "GND")
	)
	(via
		(at 306.105306 -69.772784)
		(size 0.508)
		(drill 0.254)
		(layers "F.Cu" "B.Cu")
		(net "GND")
	)
	(via
		(at 316.971934 9.084056)
		(size 0.5588)
		(drill 0.3048)
		(layers "F.Cu" "B.Cu")
		(net "GND")
	)
	(via
		(at 428.731934 9.084056)
		(size 0.5588)
		(drill 0.3048)
		(layers "F.Cu" "B.Cu")
		(net "GND")
	)
	(via
		(at 243.338604 -85.803486)
		(size 0.508)
		(drill 0.254)
		(layers "F.Cu" "B.Cu")
		(net "GND")
	)
	(via
		(at 277.774654 -99.986338)
		(size 0.508)
		(drill 0.254)
		(layers "F.Cu" "B.Cu")
		(net "GND")
	)
	(via
		(at 142.749524 -11.916156)
		(size 0.508)
		(drill 0.254)
		(layers "F.Cu" "B.Cu")
		(net "GND")
	)
	(via
		(at 492.790734 -167.832024)
		(size 0.5588)
		(drill 0.3048)
		(layers "F.Cu" "B.Cu")
		(net "GND")
	)
	(via
		(at 11.82624 -146.685)
		(size 0.508)
		(drill 0.254)
		(layers "F.Cu" "B.Cu")
		(net "GND")
	)
	(via
		(at 126.421642 -134.8994)
		(size 0.508)
		(drill 0.254)
		(layers "F.Cu" "B.Cu")
		(net "GND")
	)
	(via
		(at 406.430734 -165.596824)
		(size 0.5588)
		(drill 0.3048)
		(layers "F.Cu" "B.Cu")
		(net "GND")
	)
	(via
		(at 365.585756 -121.341642)
		(size 0.508)
		(drill 0.254)
		(layers "F.Cu" "B.Cu")
		(net "GND")
	)
	(via
		(at 301.812706 -99.986338)
		(size 0.508)
		(drill 0.254)
		(layers "F.Cu" "B.Cu")
		(net "GND")
	)
	(via
		(at 120.649492 -21.517356)
		(size 0.508)
		(drill 0.254)
		(layers "F.Cu" "B.Cu")
		(net "GND")
	)
	(via
		(at 96.220534 -167.832024)
		(size 0.5588)
		(drill 0.3048)
		(layers "F.Cu" "B.Cu")
		(net "GND")
	)
	(via
		(at 301.812706 -96.023938)
		(size 0.508)
		(drill 0.254)
		(layers "F.Cu" "B.Cu")
		(net "GND")
	)
	(via
		(at 436.547006 -40.5257)
		(size 0.508)
		(drill 0.254)
		(layers "F.Cu" "B.Cu")
		(net "GND")
	)
	(via
		(at 279.491694 -96.023938)
		(size 0.508)
		(drill 0.254)
		(layers "F.Cu" "B.Cu")
		(net "GND")
	)
	(via
		(at 68.894706 -90.26144)
		(size 0.508)
		(drill 0.254)
		(layers "F.Cu" "B.Cu")
		(net "GND")
	)
	(via
		(at 415.490152 -36.534598)
		(size 0.4572)
		(drill 0.2032)
		(layers "F.Cu" "B.Cu")
		(net "GND")
	)
	(via
		(at 411.510734 -165.596824)
		(size 0.5588)
		(drill 0.3048)
		(layers "F.Cu" "B.Cu")
		(net "GND")
	)
	(via
		(at 67.101466 -90.26144)
		(size 0.508)
		(drill 0.254)
		(layers "F.Cu" "B.Cu")
		(net "GND")
	)
	(via
		(at 293.22776 -78.193138)
		(size 0.508)
		(drill 0.254)
		(layers "F.Cu" "B.Cu")
		(net "GND")
	)
	(via
		(at 235.612178 -78.37424)
		(size 0.508)
		(drill 0.254)
		(layers "F.Cu" "B.Cu")
		(net "GND")
	)
	(via
		(at 96.366838 -60.54344)
		(size 0.508)
		(drill 0.254)
		(layers "F.Cu" "B.Cu")
		(net "GND")
	)
	(via
		(at 68.799456 -11.916156)
		(size 0.508)
		(drill 0.254)
		(layers "F.Cu" "B.Cu")
		(net "GND")
	)
	(via
		(at 297.520106 -67.791584)
		(size 0.508)
		(drill 0.254)
		(layers "F.Cu" "B.Cu")
		(net "GND")
	)
	(via
		(at 384.76555 -99.322636)
		(size 0.508)
		(drill 0.254)
		(layers "F.Cu" "B.Cu")
		(net "GND")
	)
	(via
		(at 132.549392 -17.208246)
		(size 0.508)
		(drill 0.254)
		(layers "F.Cu" "B.Cu")
		(net "GND")
	)
	(via
		(at 241.508534 -167.832024)
		(size 0.5588)
		(drill 0.3048)
		(layers "F.Cu" "B.Cu")
		(net "GND")
	)
	(via
		(at 322.4784 -122.1232)
		(size 0.508)
		(drill 0.254)
		(layers "F.Cu" "B.Cu")
		(net "GND")
	)
	(via
		(at 4.0132 -139.065)
		(size 0.508)
		(drill 0.254)
		(layers "F.Cu" "B.Cu")
		(net "GND")
	)
	(via
		(at 200.533 -58.8772)
		(size 0.508)
		(drill 0.254)
		(layers "F.Cu" "B.Cu")
		(net "GND")
	)
	(via
		(at 141.049502 -129.568956)
		(size 0.508)
		(drill 0.254)
		(layers "F.Cu" "B.Cu")
		(net "GND")
	)
	(via
		(at 175.505364 -158.52902)
		(size 0.5588)
		(drill 0.3048)
		(layers "F.Cu" "B.Cu")
		(net "GND")
	)
	(via
		(at 217.472006 -140.617956)
		(size 0.508)
		(drill 0.254)
		(layers "F.Cu" "B.Cu")
		(net "GND")
	)
	(via
		(at 177.271934 9.084056)
		(size 0.5588)
		(drill 0.3048)
		(layers "F.Cu" "B.Cu")
		(net "GND")
	)
	(via
		(at 226.111816 -139.170156)
		(size 0.508)
		(drill 0.254)
		(layers "F.Cu" "B.Cu")
		(net "GND")
	)
	(via
		(at 38.841934 14.926056)
		(size 0.5588)
		(drill 0.3048)
		(layers "F.Cu" "B.Cu")
		(net "GND")
	)
	(via
		(at 75.59929 -150.219156)
		(size 0.508)
		(drill 0.254)
		(layers "F.Cu" "B.Cu")
		(net "GND")
	)
	(via
		(at 466.831934 12.894056)
		(size 0.5588)
		(drill 0.3048)
		(layers "F.Cu" "B.Cu")
		(net "GND")
	)
	(via
		(at 272.339308 -56.894984)
		(size 0.508)
		(drill 0.254)
		(layers "F.Cu" "B.Cu")
		(net "GND")
	)
	(via
		(at -2.306066 13.783056)
		(size 0.5588)
		(drill 0.3048)
		(layers "F.Cu" "B.Cu")
		(net "GND")
	)
	(via
		(at 371.887496 -89.859104)
		(size 0.508)
		(drill 0.254)
		(layers "F.Cu" "B.Cu")
		(net "GND")
	)
	(via
		(at 30.282134 -167.832024)
		(size 0.5588)
		(drill 0.3048)
		(layers "F.Cu" "B.Cu")
		(net "GND")
	)
	(via
		(at 124.049536 -148.771356)
		(size 0.508)
		(drill 0.254)
		(layers "F.Cu" "B.Cu")
		(net "GND")
	)
	(via
		(at 288.65068 -53.427884)
		(size 0.508)
		(drill 0.254)
		(layers "F.Cu" "B.Cu")
		(net "GND")
	)
	(via
		(at 42.411396 -2.314956)
		(size 0.508)
		(drill 0.254)
		(layers "F.Cu" "B.Cu")
		(net "GND")
	)
	(via
		(at 69.753226 -85.803486)
		(size 0.508)
		(drill 0.254)
		(layers "F.Cu" "B.Cu")
		(net "GND")
	)
	(via
		(at 300.095666 -66.305938)
		(size 0.508)
		(drill 0.254)
		(layers "F.Cu" "B.Cu")
		(net "GND")
	)
	(via
		(at 357.4161 -14.188186)
		(size 0.508)
		(drill 0.254)
		(layers "F.Cu" "B.Cu")
		(net "GND")
	)
	(via
		(at 206.481934 9.084056)
		(size 0.5588)
		(drill 0.3048)
		(layers "F.Cu" "B.Cu")
		(net "GND")
	)
	(via
		(at 114.0206 -68.4784)
		(size 0.508)
		(drill 0.254)
		(layers "F.Cu" "B.Cu")
		(net "GND")
	)
	(via
		(at 300.099984 0.444754)
		(size 0.508)
		(drill 0.254)
		(layers "F.Cu" "B.Cu")
		(net "GND")
	)
	(via
		(at 300.095666 -85.127338)
		(size 0.508)
		(drill 0.254)
		(layers "F.Cu" "B.Cu")
		(net "GND")
	)
	(via
		(at 138.529314 -91.070938)
		(size 0.508)
		(drill 0.254)
		(layers "F.Cu" "B.Cu")
		(net "GND")
	)
	(via
		(at 1.224534 -164.479224)
		(size 0.5588)
		(drill 0.3048)
		(layers "F.Cu" "B.Cu")
		(net "GND")
	)
	(via
		(at 378.3584 -1.016)
		(size 0.508)
		(drill 0.254)
		(layers "F.Cu" "B.Cu")
		(net "GND")
	)
	(via
		(at 490.961934 9.084056)
		(size 0.5588)
		(drill 0.3048)
		(layers "F.Cu" "B.Cu")
		(net "GND")
	)
	(via
		(at 270.566134 -167.832024)
		(size 0.5588)
		(drill 0.3048)
		(layers "F.Cu" "B.Cu")
		(net "GND")
	)
	(via
		(at 215.371934 14.926056)
		(size 0.5588)
		(drill 0.3048)
		(layers "F.Cu" "B.Cu")
		(net "GND")
	)
	(via
		(at 236.470698 -85.803486)
		(size 0.508)
		(drill 0.254)
		(layers "F.Cu" "B.Cu")
		(net "GND")
	)
	(via
		(at 107.623356 -90.080338)
		(size 0.508)
		(drill 0.254)
		(layers "F.Cu" "B.Cu")
		(net "GND")
	)
	(via
		(at 181.1147 -16.1671)
		(size 0.508)
		(drill 0.254)
		(layers "F.Cu" "B.Cu")
		(net "GND")
	)
	(via
		(at 478.8916 -37.338)
		(size 0.508)
		(drill 0.254)
		(layers "F.Cu" "B.Cu")
		(net "GND")
	)
	(via
		(at 336.021934 14.926056)
		(size 0.5588)
		(drill 0.3048)
		(layers "F.Cu" "B.Cu")
		(net "GND")
	)
	(via
		(at 4.353306 -149.779482)
		(size 0.508)
		(drill 0.254)
		(layers "F.Cu" "B.Cu")
		(net "GND")
	)
	(via
		(at 127.392176 -18.744946)
		(size 0.508)
		(drill 0.254)
		(layers "F.Cu" "B.Cu")
		(net "GND")
	)
	(via
		(at 131.979924 -162.243262)
		(size 0.5588)
		(drill 0.3048)
		(layers "F.Cu" "B.Cu")
		(net "GND")
	)
	(via
		(at 436.351934 11.624056)
		(size 0.5588)
		(drill 0.3048)
		(layers "F.Cu" "B.Cu")
		(net "GND")
	)
	(via
		(at 113.849404 -144.5768)
		(size 0.508)
		(drill 0.254)
		(layers "F.Cu" "B.Cu")
		(net "GND")
	)
	(via
		(at 472.466924 -162.243262)
		(size 0.5588)
		(drill 0.3048)
		(layers "F.Cu" "B.Cu")
		(net "GND")
	)
	(via
		(at -5.2578 -7.1374)
		(size 0.508)
		(drill 0.254)
		(layers "F.Cu" "B.Cu")
		(net "GND")
	)
	(via
		(at 240.763298 -57.57164)
		(size 0.508)
		(drill 0.254)
		(layers "F.Cu" "B.Cu")
		(net "GND")
	)
	(via
		(at 317.09995 -18.757646)
		(size 0.508)
		(drill 0.254)
		(layers "F.Cu" "B.Cu")
		(net "GND")
	)
	(via
		(at 433.811934 9.084056)
		(size 0.5588)
		(drill 0.3048)
		(layers "F.Cu" "B.Cu")
		(net "GND")
	)
	(via
		(at 383.286 -126.6825)
		(size 0.508)
		(drill 0.254)
		(layers "F.Cu" "B.Cu")
		(net "GND")
	)
	(via
		(at 81.582768 -3.3528)
		(size 0.508)
		(drill 0.254)
		(layers "F.Cu" "B.Cu")
		(net "GND")
	)
	(via
		(at 154.411934 14.926056)
		(size 0.5588)
		(drill 0.3048)
		(layers "F.Cu" "B.Cu")
		(net "GND")
	)
	(via
		(at 67.949318 -27.935936)
		(size 0.508)
		(drill 0.254)
		(layers "F.Cu" "B.Cu")
		(net "GND")
	)
	(via
		(at 219.152724 -162.243262)
		(size 0.5588)
		(drill 0.3048)
		(layers "F.Cu" "B.Cu")
		(net "GND")
	)
	(via
		(at 369.545108 -77.494892)
		(size 0.4572)
		(drill 0.2032)
		(layers "F.Cu" "B.Cu")
		(net "GND")
	)
	(via
		(at 147.394168 -136.3345)
		(size 0.508)
		(drill 0.254)
		(layers "F.Cu" "B.Cu")
		(net "GND")
	)
	(via
		(at 258.496308 -70.841616)
		(size 0.5588)
		(drill 0.3048)
		(layers "F.Cu" "B.Cu")
		(net "GND")
	)
	(via
		(at 466.8774 -0.9906)
		(size 0.508)
		(drill 0.254)
		(layers "F.Cu" "B.Cu")
		(net "GND")
	)
	(via
		(at 135.095234 -95.033084)
		(size 0.508)
		(drill 0.254)
		(layers "F.Cu" "B.Cu")
		(net "GND")
	)
	(via
		(at 282.07208 -3.762756)
		(size 0.508)
		(drill 0.254)
		(layers "F.Cu" "B.Cu")
		(net "GND")
	)
	(via
		(at 301.241206 -103.5812)
		(size 0.508)
		(drill 0.254)
		(layers "F.Cu" "B.Cu")
		(net "GND")
	)
	(via
		(at 186.161934 14.926056)
		(size 0.5588)
		(drill 0.3048)
		(layers "F.Cu" "B.Cu")
		(net "GND")
	)
	(via
		(at 68.036186 -84.812886)
		(size 0.508)
		(drill 0.254)
		(layers "F.Cu" "B.Cu")
		(net "GND")
	)
	(via
		(at 206.481934 14.926056)
		(size 0.5588)
		(drill 0.3048)
		(layers "F.Cu" "B.Cu")
		(net "GND")
	)
	(via
		(at 297.549824 -3.762756)
		(size 0.508)
		(drill 0.254)
		(layers "F.Cu" "B.Cu")
		(net "GND")
	)
	(via
		(at 439.446924 -162.243262)
		(size 0.5588)
		(drill 0.3048)
		(layers "F.Cu" "B.Cu")
		(net "GND")
	)
	(via
		(at 34.991802 -79.683864)
		(size 0.508)
		(drill 0.254)
		(layers "F.Cu" "B.Cu")
		(net "GND")
	)
	(via
		(at 97.338134 -167.832024)
		(size 0.5588)
		(drill 0.3048)
		(layers "F.Cu" "B.Cu")
		(net "GND")
	)
	(via
		(at 440.040522 -150.454868)
		(size 0.508)
		(drill 0.254)
		(layers "F.Cu" "B.Cu")
		(net "GND")
	)
	(via
		(at 345.4908 -97.7138)
		(size 0.508)
		(drill 0.254)
		(layers "F.Cu" "B.Cu")
		(net "GND")
	)
	(via
		(at 115.065302 -66.305938)
		(size 0.508)
		(drill 0.254)
		(layers "F.Cu" "B.Cu")
		(net "GND")
	)
	(via
		(at 444.338456 -9.898634)
		(size 0.508)
		(drill 0.254)
		(layers "F.Cu" "B.Cu")
		(net "GND")
	)
	(via
		(at 378.82195 -102.756716)
		(size 0.508)
		(drill 0.254)
		(layers "F.Cu" "B.Cu")
		(net "GND")
	)
	(via
		(at 4.577334 -164.479224)
		(size 0.5588)
		(drill 0.3048)
		(layers "F.Cu" "B.Cu")
		(net "GND")
	)
	(via
		(at 83.489292 -59.057286)
		(size 0.508)
		(drill 0.254)
		(layers "F.Cu" "B.Cu")
		(net "GND")
	)
	(via
		(at 376.428 -97.354898)
		(size 0.508)
		(drill 0.254)
		(layers "F.Cu" "B.Cu")
		(net "GND")
	)
	(via
		(at 314.54979 1.994154)
		(size 0.508)
		(drill 0.254)
		(layers "F.Cu" "B.Cu")
		(net "GND")
	)
	(via
		(at 440.040522 -151.674068)
		(size 0.508)
		(drill 0.254)
		(layers "F.Cu" "B.Cu")
		(net "GND")
	)
	(via
		(at 14.554708 -125.842268)
		(size 0.508)
		(drill 0.254)
		(layers "F.Cu" "B.Cu")
		(net "GND")
	)
	(via
		(at 466.116924 -162.243262)
		(size 0.5588)
		(drill 0.3048)
		(layers "F.Cu" "B.Cu")
		(net "GND")
	)
	(via
		(at 77.479906 -80.35544)
		(size 0.508)
		(drill 0.254)
		(layers "F.Cu" "B.Cu")
		(net "GND")
	)
	(via
		(at 165.841934 14.926056)
		(size 0.5588)
		(drill 0.3048)
		(layers "F.Cu" "B.Cu")
		(net "GND")
	)
	(via
		(at 384.932428 -71.3232)
		(size 0.508)
		(drill 0.254)
		(layers "F.Cu" "B.Cu")
		(net "GND")
	)
	(via
		(at 288.07664 -82.155284)
		(size 0.508)
		(drill 0.254)
		(layers "F.Cu" "B.Cu")
		(net "GND")
	)
	(via
		(at 442.6966 -123.19)
		(size 0.508)
		(drill 0.254)
		(layers "F.Cu" "B.Cu")
		(net "GND")
	)
	(via
		(at 149.42439 -113.869724)
		(size 0.508)
		(drill 0.254)
		(layers "F.Cu" "B.Cu")
		(net "GND")
	)
	(via
		(at 219.731844 -21.5138)
		(size 0.508)
		(drill 0.254)
		(layers "F.Cu" "B.Cu")
		(net "GND")
	)
	(via
		(at 279.699974 -145.998946)
		(size 0.508)
		(drill 0.254)
		(layers "F.Cu" "B.Cu")
		(net "GND")
	)
	(via
		(at 113.771934 9.084056)
		(size 0.5588)
		(drill 0.3048)
		(layers "F.Cu" "B.Cu")
		(net "GND")
	)
	(via
		(at 134.236714 -57.885584)
		(size 0.508)
		(drill 0.254)
		(layers "F.Cu" "B.Cu")
		(net "GND")
	)
	(via
		(at 35.453828 -55.8292)
		(size 0.508)
		(drill 0.254)
		(layers "F.Cu" "B.Cu")
		(net "GND")
	)
	(via
		(at 277.203154 -50.759614)
		(size 0.508)
		(drill 0.254)
		(layers "F.Cu" "B.Cu")
		(net "GND")
	)
	(via
		(at 339.223604 -143.824198)
		(size 0.508)
		(drill 0.254)
		(layers "F.Cu" "B.Cu")
		(net "GND")
	)
	(via
		(at 121.933208 -59.371484)
		(size 0.508)
		(drill 0.254)
		(layers "F.Cu" "B.Cu")
		(net "GND")
	)
	(via
		(at 146.104356 2.4638)
		(size 0.508)
		(drill 0.254)
		(layers "F.Cu" "B.Cu")
		(net "GND")
	)
	(via
		(at 128.687576 -4.346956)
		(size 0.508)
		(drill 0.254)
		(layers "F.Cu" "B.Cu")
		(net "GND")
	)
	(via
		(at 481.711 -141.0462)
		(size 0.508)
		(drill 0.254)
		(layers "F.Cu" "B.Cu")
		(net "GND")
	)
	(via
		(at 339.1154 -38.1)
		(size 0.508)
		(drill 0.254)
		(layers "F.Cu" "B.Cu")
		(net "GND")
	)
	(via
		(at 349.3516 -59.7154)
		(size 0.508)
		(drill 0.254)
		(layers "F.Cu" "B.Cu")
		(net "GND")
	)
	(via
		(at 98.982276 -75.159616)
		(size 0.5588)
		(drill 0.3048)
		(layers "F.Cu" "B.Cu")
		(net "GND")
	)
	(via
		(at 51.79949 -146.011646)
		(size 0.508)
		(drill 0.254)
		(layers "F.Cu" "B.Cu")
		(net "GND")
	)
	(via
		(at 6.9342 -9.7282)
		(size 0.508)
		(drill 0.254)
		(layers "F.Cu" "B.Cu")
		(net "GND")
	)
	(via
		(at 297.921934 9.084056)
		(size 0.5588)
		(drill 0.3048)
		(layers "F.Cu" "B.Cu")
		(net "GND")
	)
	(via
		(at 234.551728 -134.861046)
		(size 0.508)
		(drill 0.254)
		(layers "F.Cu" "B.Cu")
		(net "GND")
	)
	(via
		(at 301.812706 -85.127338)
		(size 0.508)
		(drill 0.254)
		(layers "F.Cu" "B.Cu")
		(net "GND")
	)
	(via
		(at 445.241934 9.084056)
		(size 0.5588)
		(drill 0.3048)
		(layers "F.Cu" "B.Cu")
		(net "GND")
	)
	(via
		(at 457.546964 -38.591998)
		(size 0.508)
		(drill 0.254)
		(layers "F.Cu" "B.Cu")
		(net "GND")
	)
	(via
		(at 58.599324 -22.965156)
		(size 0.508)
		(drill 0.254)
		(layers "F.Cu" "B.Cu")
		(net "GND")
	)
	(via
		(at 113.348262 -60.362338)
		(size 0.508)
		(drill 0.254)
		(layers "F.Cu" "B.Cu")
		(net "GND")
	)
	(via
		(at 388.593076 -146.644868)
		(size 0.508)
		(drill 0.254)
		(layers "F.Cu" "B.Cu")
		(net "GND")
	)
	(via
		(at 417.856924 -162.243262)
		(size 0.5588)
		(drill 0.3048)
		(layers "F.Cu" "B.Cu")
		(net "GND")
	)
	(via
		(at 10.412476 1.815592)
		(size 0.508)
		(drill 0.254)
		(layers "F.Cu" "B.Cu")
		(net "GND")
	)
	(via
		(at 288.93516 -102.462584)
		(size 0.508)
		(drill 0.254)
		(layers "F.Cu" "B.Cu")
		(net "GND")
	)
	(via
		(at 132.519674 -91.565984)
		(size 0.508)
		(drill 0.254)
		(layers "F.Cu" "B.Cu")
		(net "GND")
	)
	(via
		(at 260.731 -137.414)
		(size 0.508)
		(drill 0.254)
		(layers "F.Cu" "B.Cu")
		(net "GND")
	)
	(via
		(at 317.949834 -23.520146)
		(size 0.508)
		(drill 0.254)
		(layers "F.Cu" "B.Cu")
		(net "GND")
	)
	(via
		(at 197.160896 -13.338556)
		(size 0.508)
		(drill 0.254)
		(layers "F.Cu" "B.Cu")
		(net "GND")
	)
	(via
		(at 427.47819 -0.736854)
		(size 0.508)
		(drill 0.254)
		(layers "F.Cu" "B.Cu")
		(net "GND")
	)
	(via
		(at 292.396672 -126.712218)
		(size 0.508)
		(drill 0.254)
		(layers "F.Cu" "B.Cu")
		(net "GND")
	)
	(via
		(at 235.612178 -92.24264)
		(size 0.508)
		(drill 0.254)
		(layers "F.Cu" "B.Cu")
		(net "GND")
	)
	(via
		(at 179.832 -140.5255)
		(size 0.508)
		(drill 0.254)
		(layers "F.Cu" "B.Cu")
		(net "GND")
	)
	(via
		(at 282.641294 -63.829184)
		(size 0.508)
		(drill 0.254)
		(layers "F.Cu" "B.Cu")
		(net "GND")
	)
	(via
		(at 372.041674 -109.967268)
		(size 0.508)
		(drill 0.254)
		(layers "F.Cu" "B.Cu")
		(net "GND")
	)
	(via
		(at 86.923372 -65.991486)
		(size 0.508)
		(drill 0.254)
		(layers "F.Cu" "B.Cu")
		(net "GND")
	)
	(via
		(at 219.73794 -150.803356)
		(size 0.508)
		(drill 0.254)
		(layers "F.Cu" "B.Cu")
		(net "GND")
	)
	(via
		(at 77.479906 -96.20504)
		(size 0.508)
		(drill 0.254)
		(layers "F.Cu" "B.Cu")
		(net "GND")
	)
	(via
		(at 40.749474 -136.397746)
		(size 0.508)
		(drill 0.254)
		(layers "F.Cu" "B.Cu")
		(net "GND")
	)
	(via
		(at 498.221 -148.0058)
		(size 0.508)
		(drill 0.254)
		(layers "F.Cu" "B.Cu")
		(net "GND")
	)
	(via
		(at 272.027904 -140.208)
		(size 0.508)
		(drill 0.254)
		(layers "F.Cu" "B.Cu")
		(net "GND")
	)
	(via
		(at 384.76555 -101.039676)
		(size 0.508)
		(drill 0.254)
		(layers "F.Cu" "B.Cu")
		(net "GND")
	)
	(via
		(at 245.914164 -62.52464)
		(size 0.508)
		(drill 0.254)
		(layers "F.Cu" "B.Cu")
		(net "GND")
	)
	(via
		(at 265.777218 -75.148186)
		(size 0.5588)
		(drill 0.3048)
		(layers "F.Cu" "B.Cu")
		(net "GND")
	)
	(via
		(at 112.489742 -56.894984)
		(size 0.508)
		(drill 0.254)
		(layers "F.Cu" "B.Cu")
		(net "GND")
	)
	(via
		(at 342.9254 -40.64)
		(size 0.508)
		(drill 0.254)
		(layers "F.Cu" "B.Cu")
		(net "GND")
	)
	(via
		(at 117.640862 -56.894984)
		(size 0.508)
		(drill 0.254)
		(layers "F.Cu" "B.Cu")
		(net "GND")
	)
	(via
		(at 37.34943 -155.612846)
		(size 0.508)
		(drill 0.254)
		(layers "F.Cu" "B.Cu")
		(net "GND")
	)
	(via
		(at 420.10838 -154.26436)
		(size 0.508)
		(drill 0.254)
		(layers "F.Cu" "B.Cu")
		(net "GND")
	)
	(via
		(at 116.208302 -88.099138)
		(size 0.508)
		(drill 0.254)
		(layers "F.Cu" "B.Cu")
		(net "GND")
	)
	(via
		(at 129.944368 -100.976684)
		(size 0.508)
		(drill 0.254)
		(layers "F.Cu" "B.Cu")
		(net "GND")
	)
	(via
		(at 473.508832 -22.281896)
		(size 0.508)
		(drill 0.254)
		(layers "F.Cu" "B.Cu")
		(net "GND")
	)
	(via
		(at 4.32689 -139.587732)
		(size 0.508)
		(drill 0.254)
		(layers "F.Cu" "B.Cu")
		(net "GND")
	)
	(via
		(at 117.066822 -89.584784)
		(size 0.508)
		(drill 0.254)
		(layers "F.Cu" "B.Cu")
		(net "GND")
	)
	(via
		(at 349.407734 -135.954516)
		(size 0.508)
		(drill 0.254)
		(layers "F.Cu" "B.Cu")
		(net "GND")
	)
	(via
		(at 232.101898 -64.50584)
		(size 0.508)
		(drill 0.254)
		(layers "F.Cu" "B.Cu")
		(net "GND")
	)
	(via
		(at 418.22116 -112.07496)
		(size 0.508)
		(drill 0.254)
		(layers "F.Cu" "B.Cu")
		(net "GND")
	)
	(via
		(at 347.53042 -32.131)
		(size 0.508)
		(drill 0.254)
		(layers "F.Cu" "B.Cu")
		(net "GND")
	)
	(via
		(at 355.079808 -26.923492)
		(size 0.508)
		(drill 0.254)
		(layers "F.Cu" "B.Cu")
		(net "GND")
	)
	(via
		(at 294.035734 -167.832024)
		(size 0.5588)
		(drill 0.3048)
		(layers "F.Cu" "B.Cu")
		(net "GND")
	)
	(via
		(at 4.573524 -162.243262)
		(size 0.5588)
		(drill 0.3048)
		(layers "F.Cu" "B.Cu")
		(net "GND")
	)
	(via
		(at 80.913732 -74.411586)
		(size 0.508)
		(drill 0.254)
		(layers "F.Cu" "B.Cu")
		(net "GND")
	)
	(via
		(at 50.099468 -148.771356)
		(size 0.508)
		(drill 0.254)
		(layers "F.Cu" "B.Cu")
		(net "GND")
	)
	(via
		(at 57.104534 -167.832024)
		(size 0.5588)
		(drill 0.3048)
		(layers "F.Cu" "B.Cu")
		(net "GND")
	)
	(via
		(at 75.762866 -53.60924)
		(size 0.508)
		(drill 0.254)
		(layers "F.Cu" "B.Cu")
		(net "GND")
	)
	(via
		(at 387.73735 -123.821444)
		(size 0.508)
		(drill 0.254)
		(layers "F.Cu" "B.Cu")
		(net "GND")
	)
	(via
		(at 71.861934 9.084056)
		(size 0.5588)
		(drill 0.3048)
		(layers "F.Cu" "B.Cu")
		(net "GND")
	)
	(via
		(at 389.256524 -162.243262)
		(size 0.5588)
		(drill 0.3048)
		(layers "F.Cu" "B.Cu")
		(net "GND")
	)
	(via
		(at 108.510324 -162.243262)
		(size 0.5588)
		(drill 0.3048)
		(layers "F.Cu" "B.Cu")
		(net "GND")
	)
	(via
		(at 117.581934 9.084056)
		(size 0.5588)
		(drill 0.3048)
		(layers "F.Cu" "B.Cu")
		(net "GND")
	)
	(via
		(at 271.480788 -59.371484)
		(size 0.508)
		(drill 0.254)
		(layers "F.Cu" "B.Cu")
		(net "GND")
	)
	(via
		(at 241.44986 -146.011646)
		(size 0.508)
		(drill 0.254)
		(layers "F.Cu" "B.Cu")
		(net "GND")
	)
	(via
		(at 5.694934 -164.479224)
		(size 0.5588)
		(drill 0.3048)
		(layers "F.Cu" "B.Cu")
		(net "GND")
	)
	(via
		(at 53.442108 -21.513292)
		(size 0.508)
		(drill 0.254)
		(layers "F.Cu" "B.Cu")
		(net "GND")
	)
	(via
		(at 288.19983 -134.861046)
		(size 0.508)
		(drill 0.254)
		(layers "F.Cu" "B.Cu")
		(net "GND")
	)
	(via
		(at 206.501746 -154.063446)
		(size 0.508)
		(drill 0.254)
		(layers "F.Cu" "B.Cu")
		(net "GND")
	)
	(via
		(at 11.0617 -109.5502)
		(size 0.508)
		(drill 0.254)
		(layers "F.Cu" "B.Cu")
		(net "GND")
	)
	(via
		(at 95.102934 -167.832024)
		(size 0.5588)
		(drill 0.3048)
		(layers "F.Cu" "B.Cu")
		(net "GND")
	)
	(via
		(at 223.599756 -22.965156)
		(size 0.508)
		(drill 0.254)
		(layers "F.Cu" "B.Cu")
		(net "GND")
	)
	(via
		(at 347.956378 -104.270302)
		(size 0.508)
		(drill 0.254)
		(layers "F.Cu" "B.Cu")
		(net "GND")
	)
	(via
		(at 389.415528 -40.149272)
		(size 0.508)
		(drill 0.254)
		(layers "F.Cu" "B.Cu")
		(net "GND")
	)
	(via
		(at 232.101898 -60.54344)
		(size 0.508)
		(drill 0.254)
		(layers "F.Cu" "B.Cu")
		(net "GND")
	)
	(via
		(at 35.453828 -80.2132)
		(size 0.508)
		(drill 0.254)
		(layers "F.Cu" "B.Cu")
		(net "GND")
	)
	(via
		(at 343.641934 9.084056)
		(size 0.5588)
		(drill 0.3048)
		(layers "F.Cu" "B.Cu")
		(net "GND")
	)
	(via
		(at 426.0342 -139.7508)
		(size 0.508)
		(drill 0.254)
		(layers "F.Cu" "B.Cu")
		(net "GND")
	)
	(via
		(at 9.043924 -162.243262)
		(size 0.5588)
		(drill 0.3048)
		(layers "F.Cu" "B.Cu")
		(net "GND")
	)
	(via
		(at 102.376224 -98.681286)
		(size 0.508)
		(drill 0.254)
		(layers "F.Cu" "B.Cu")
		(net "GND")
	)
	(via
		(at 110.772702 -53.923184)
		(size 0.508)
		(drill 0.254)
		(layers "F.Cu" "B.Cu")
		(net "GND")
	)
	(via
		(at 214.6554 -76.1746)
		(size 0.508)
		(drill 0.254)
		(layers "F.Cu" "B.Cu")
		(net "GND")
	)
	(via
		(at 478.816924 -162.243262)
		(size 0.5588)
		(drill 0.3048)
		(layers "F.Cu" "B.Cu")
		(net "GND")
	)
	(via
		(at 365.225838 -102.18801)
		(size 0.508)
		(drill 0.254)
		(layers "F.Cu" "B.Cu")
		(net "GND")
	)
	(via
		(at 25.811734 -167.832024)
		(size 0.5588)
		(drill 0.3048)
		(layers "F.Cu" "B.Cu")
		(net "GND")
	)
	(via
		(at 447.070734 -163.361624)
		(size 0.5588)
		(drill 0.3048)
		(layers "F.Cu" "B.Cu")
		(net "GND")
	)
	(via
		(at 5.466334 14.926056)
		(size 0.5588)
		(drill 0.3048)
		(layers "F.Cu" "B.Cu")
		(net "GND")
	)
	(via
		(at 34.991802 -71.555864)
		(size 0.508)
		(drill 0.254)
		(layers "F.Cu" "B.Cu")
		(net "GND")
	)
	(via
		(at 0.51435 -108.6866)
		(size 0.508)
		(drill 0.254)
		(layers "F.Cu" "B.Cu")
		(net "GND")
	)
	(via
		(at 444.246 -140.427202)
		(size 0.508)
		(drill 0.254)
		(layers "F.Cu" "B.Cu")
		(net "GND")
	)
	(via
		(at 450.880734 -166.714424)
		(size 0.5588)
		(drill 0.3048)
		(layers "F.Cu" "B.Cu")
		(net "GND")
	)
	(via
		(at 224.449894 -136.397746)
		(size 0.508)
		(drill 0.254)
		(layers "F.Cu" "B.Cu")
		(net "GND")
	)
	(via
		(at 440.720734 -164.479224)
		(size 0.5588)
		(drill 0.3048)
		(layers "F.Cu" "B.Cu")
		(net "GND")
	)
	(via
		(at 345.506294 -147.668742)
		(size 0.508)
		(drill 0.254)
		(layers "F.Cu" "B.Cu")
		(net "GND")
	)
	(via
		(at 434.086 -32.3088)
		(size 0.4572)
		(drill 0.2032)
		(layers "F.Cu" "B.Cu")
		(net "GND")
	)
	(via
		(at 478.820734 -166.714424)
		(size 0.5588)
		(drill 0.3048)
		(layers "F.Cu" "B.Cu")
		(net "GND")
	)
	(via
		(at 436.910734 -163.361624)
		(size 0.5588)
		(drill 0.3048)
		(layers "F.Cu" "B.Cu")
		(net "GND")
	)
	(via
		(at 236.470698 -90.756486)
		(size 0.508)
		(drill 0.254)
		(layers "F.Cu" "B.Cu")
		(net "GND")
	)
	(via
		(at 83.489292 -82.83194)
		(size 0.508)
		(drill 0.254)
		(layers "F.Cu" "B.Cu")
		(net "GND")
	)
	(via
		(at 483.341934 14.926056)
		(size 0.5588)
		(drill 0.3048)
		(layers "F.Cu" "B.Cu")
		(net "GND")
	)
	(via
		(at 239.501934 9.084056)
		(size 0.5588)
		(drill 0.3048)
		(layers "F.Cu" "B.Cu")
		(net "GND")
	)
	(via
		(at 119.337328 -131.600956)
		(size 0.508)
		(drill 0.254)
		(layers "F.Cu" "B.Cu")
		(net "GND")
	)
	(via
		(at 304.349912 -21.517356)
		(size 0.508)
		(drill 0.254)
		(layers "F.Cu" "B.Cu")
		(net "GND")
	)
	(via
		(at 305.246786 -57.390538)
		(size 0.508)
		(drill 0.254)
		(layers "F.Cu" "B.Cu")
		(net "GND")
	)
	(via
		(at 135.953754 -63.829184)
		(size 0.508)
		(drill 0.254)
		(layers "F.Cu" "B.Cu")
		(net "GND")
	)
	(via
		(at 468.101934 10.354056)
		(size 0.5588)
		(drill 0.3048)
		(layers "F.Cu" "B.Cu")
		(net "GND")
	)
	(via
		(at 399.12925 -116.094764)
		(size 0.508)
		(drill 0.254)
		(layers "F.Cu" "B.Cu")
		(net "GND")
	)
	(via
		(at 243.338604 -89.765886)
		(size 0.508)
		(drill 0.254)
		(layers "F.Cu" "B.Cu")
		(net "GND")
	)
	(via
		(at 74.904346 -63.019686)
		(size 0.508)
		(drill 0.254)
		(layers "F.Cu" "B.Cu")
		(net "GND")
	)
	(via
		(at 207.566514 -77.154278)
		(size 0.5588)
		(drill 0.3048)
		(layers "F.Cu" "B.Cu")
		(net "GND")
	)
	(via
		(at 426.721778 -139.170918)
		(size 0.508)
		(drill 0.254)
		(layers "F.Cu" "B.Cu")
		(net "GND")
	)
	(via
		(at 63.810134 -167.832024)
		(size 0.5588)
		(drill 0.3048)
		(layers "F.Cu" "B.Cu")
		(net "GND")
	)
	(via
		(at 51.79949 -18.757646)
		(size 0.508)
		(drill 0.254)
		(layers "F.Cu" "B.Cu")
		(net "GND")
	)
	(via
		(at 2.03073 -72.48779)
		(size 0.508)
		(drill 0.254)
		(layers "F.Cu" "B.Cu")
		(net "GND")
	)
	(via
		(at 195.549774 -13.929106)
		(size 0.508)
		(drill 0.254)
		(layers "F.Cu" "B.Cu")
		(net "GND")
	)
	(via
		(at 121.074688 -63.829184)
		(size 0.508)
		(drill 0.254)
		(layers "F.Cu" "B.Cu")
		(net "GND")
	)
	(via
		(at 459.211934 11.624056)
		(size 0.5588)
		(drill 0.3048)
		(layers "F.Cu" "B.Cu")
		(net "GND")
	)
	(via
		(at 481.360734 -163.361624)
		(size 0.5588)
		(drill 0.3048)
		(layers "F.Cu" "B.Cu")
		(net "GND")
	)
	(via
		(at 304.349912 -139.170156)
		(size 0.508)
		(drill 0.254)
		(layers "F.Cu" "B.Cu")
		(net "GND")
	)
	(via
		(at 304.388266 -60.857384)
		(size 0.508)
		(drill 0.254)
		(layers "F.Cu" "B.Cu")
		(net "GND")
	)
	(via
		(at 207.411828 -11.916156)
		(size 0.508)
		(drill 0.254)
		(layers "F.Cu" "B.Cu")
		(net "GND")
	)
	(via
		(at 132.519674 -82.650584)
		(size 0.508)
		(drill 0.254)
		(layers "F.Cu" "B.Cu")
		(net "GND")
	)
	(via
		(at 464.291934 12.894056)
		(size 0.5588)
		(drill 0.3048)
		(layers "F.Cu" "B.Cu")
		(net "GND")
	)
	(via
		(at 464.5406 -140.2842)
		(size 0.508)
		(drill 0.254)
		(layers "F.Cu" "B.Cu")
		(net "GND")
	)
	(via
		(at 107.059476 -82.339942)
		(size 0.5588)
		(drill 0.3048)
		(layers "F.Cu" "B.Cu")
		(net "GND")
	)
	(via
		(at 275.773134 -61.847984)
		(size 0.508)
		(drill 0.254)
		(layers "F.Cu" "B.Cu")
		(net "GND")
	)
	(via
		(at 298.399962 -155.600146)
		(size 0.508)
		(drill 0.254)
		(layers "F.Cu" "B.Cu")
		(net "GND")
	)
	(via
		(at 452.150734 -165.596824)
		(size 0.5588)
		(drill 0.3048)
		(layers "F.Cu" "B.Cu")
		(net "GND")
	)
	(via
		(at 286.499808 -7.607046)
		(size 0.508)
		(drill 0.254)
		(layers "F.Cu" "B.Cu")
		(net "GND")
	)
	(via
		(at 292.392608 -145.998946)
		(size 0.508)
		(drill 0.254)
		(layers "F.Cu" "B.Cu")
		(net "GND")
	)
	(via
		(at 443.260734 -165.596824)
		(size 0.5588)
		(drill 0.3048)
		(layers "F.Cu" "B.Cu")
		(net "GND")
	)
	(via
		(at 125.749558 -146.011646)
		(size 0.508)
		(drill 0.254)
		(layers "F.Cu" "B.Cu")
		(net "GND")
	)
	(via
		(at 127.39878 -16.7513)
		(size 0.508)
		(drill 0.254)
		(layers "F.Cu" "B.Cu")
		(net "GND")
	)
	(via
		(at 66.249296 -22.965156)
		(size 0.508)
		(drill 0.254)
		(layers "F.Cu" "B.Cu")
		(net "GND")
	)
	(via
		(at 278.921972 -139.660122)
		(size 0.508)
		(drill 0.254)
		(layers "F.Cu" "B.Cu")
		(net "GND")
	)
	(via
		(at 26.9748 -6.731)
		(size 0.508)
		(drill 0.254)
		(layers "F.Cu" "B.Cu")
		(net "GND")
	)
	(via
		(at 118.048532 -144.0053)
		(size 0.508)
		(drill 0.254)
		(layers "F.Cu" "B.Cu")
		(net "GND")
	)
	(via
		(at 396.15745 -117.811804)
		(size 0.508)
		(drill 0.254)
		(layers "F.Cu" "B.Cu")
		(net "GND")
	)
	(via
		(at 488.421934 10.354056)
		(size 0.5588)
		(drill 0.3048)
		(layers "F.Cu" "B.Cu")
		(net "GND")
	)
	(via
		(at 450.321934 12.894056)
		(size 0.5588)
		(drill 0.3048)
		(layers "F.Cu" "B.Cu")
		(net "GND")
	)
	(via
		(at 314.54979 -134.861046)
		(size 0.508)
		(drill 0.254)
		(layers "F.Cu" "B.Cu")
		(net "GND")
	)
	(via
		(at 19.34591 0.35941)
		(size 0.508)
		(drill 0.254)
		(layers "F.Cu" "B.Cu")
		(net "GND")
	)
	(via
		(at 291.51072 -93.052138)
		(size 0.508)
		(drill 0.254)
		(layers "F.Cu" "B.Cu")
		(net "GND")
	)
	(via
		(at 381.79375 -118.670324)
		(size 0.508)
		(drill 0.254)
		(layers "F.Cu" "B.Cu")
		(net "GND")
	)
	(via
		(at 289.049968 -139.170156)
		(size 0.508)
		(drill 0.254)
		(layers "F.Cu" "B.Cu")
		(net "GND")
	)
	(via
		(at 233.685334 -167.832024)
		(size 0.5588)
		(drill 0.3048)
		(layers "F.Cu" "B.Cu")
		(net "GND")
	)
	(via
		(at 240.763298 -89.27084)
		(size 0.508)
		(drill 0.254)
		(layers "F.Cu" "B.Cu")
		(net "GND")
	)
	(via
		(at 128.227328 -96.023938)
		(size 0.508)
		(drill 0.254)
		(layers "F.Cu" "B.Cu")
		(net "GND")
	)
	(via
		(at 93.981524 -162.243262)
		(size 0.5588)
		(drill 0.3048)
		(layers "F.Cu" "B.Cu")
		(net "GND")
	)
	(via
		(at 441.431934 12.894056)
		(size 0.5588)
		(drill 0.3048)
		(layers "F.Cu" "B.Cu")
		(net "GND")
	)
	(via
		(at 438.5818 -45.5676)
		(size 0.508)
		(drill 0.254)
		(layers "F.Cu" "B.Cu")
		(net "GND")
	)
	(via
		(at 112.489742 -58.876438)
		(size 0.508)
		(drill 0.254)
		(layers "F.Cu" "B.Cu")
		(net "GND")
	)
	(via
		(at 303.031906 -148.7678)
		(size 0.508)
		(drill 0.254)
		(layers "F.Cu" "B.Cu")
		(net "GND")
	)
	(via
		(at 68.051934 14.926056)
		(size 0.5588)
		(drill 0.3048)
		(layers "F.Cu" "B.Cu")
		(net "GND")
	)
	(via
		(at 480.090734 -163.361624)
		(size 0.5588)
		(drill 0.3048)
		(layers "F.Cu" "B.Cu")
		(net "GND")
	)
	(via
		(at 207.434688 -91.137486)
		(size 0.5588)
		(drill 0.3048)
		(layers "F.Cu" "B.Cu")
		(net "GND")
	)
	(via
		(at 115.065302 -60.362338)
		(size 0.508)
		(drill 0.254)
		(layers "F.Cu" "B.Cu")
		(net "GND")
	)
	(via
		(at 394.67155 -123.821444)
		(size 0.508)
		(drill 0.254)
		(layers "F.Cu" "B.Cu")
		(net "GND")
	)
	(via
		(at 200.88479 -66.474594)
		(size 0.508)
		(drill 0.254)
		(layers "F.Cu" "B.Cu")
		(net "GND")
	)
	(via
		(at 9.1186 -107.569)
		(size 0.508)
		(drill 0.254)
		(layers "F.Cu" "B.Cu")
		(net "GND")
	)
	(via
		(at -5.2324 -10.4648)
		(size 0.508)
		(drill 0.254)
		(layers "F.Cu" "B.Cu")
		(net "GND")
	)
	(via
		(at 238.437928 -126.655576)
		(size 0.508)
		(drill 0.254)
		(layers "F.Cu" "B.Cu")
		(net "GND")
	)
	(via
		(at 217.472006 1.9558)
		(size 0.508)
		(drill 0.254)
		(layers "F.Cu" "B.Cu")
		(net "GND")
	)
	(via
		(at 35.880802 -59.490864)
		(size 0.508)
		(drill 0.254)
		(layers "F.Cu" "B.Cu")
		(net "GND")
	)
	(via
		(at 442.521848 -29.832554)
		(size 0.4572)
		(drill 0.2032)
		(layers "F.Cu" "B.Cu")
		(net "GND")
	)
	(via
		(at 233.799888 -21.517356)
		(size 0.508)
		(drill 0.254)
		(layers "F.Cu" "B.Cu")
		(net "GND")
	)
	(via
		(at 89.514934 -167.832024)
		(size 0.5588)
		(drill 0.3048)
		(layers "F.Cu" "B.Cu")
		(net "GND")
	)
	(via
		(at 105.157524 -162.243262)
		(size 0.5588)
		(drill 0.3048)
		(layers "F.Cu" "B.Cu")
		(net "GND")
	)
	(via
		(at 156.506418 -30.131258)
		(size 0.508)
		(drill 0.254)
		(layers "F.Cu" "B.Cu")
		(net "GND")
	)
	(via
		(at 292.36924 -53.923184)
		(size 0.508)
		(drill 0.254)
		(layers "F.Cu" "B.Cu")
		(net "GND")
	)
	(via
		(at 127.392176 -2.310892)
		(size 0.508)
		(drill 0.254)
		(layers "F.Cu" "B.Cu")
		(net "GND")
	)
	(via
		(at 245.914164 -68.46824)
		(size 0.508)
		(drill 0.254)
		(layers "F.Cu" "B.Cu")
		(net "GND")
	)
	(via
		(at 67.101466 -67.47764)
		(size 0.508)
		(drill 0.254)
		(layers "F.Cu" "B.Cu")
		(net "GND")
	)
	(via
		(at 95.991934 9.084056)
		(size 0.5588)
		(drill 0.3048)
		(layers "F.Cu" "B.Cu")
		(net "GND")
	)
	(via
		(at 119.642382 -93.052138)
		(size 0.508)
		(drill 0.254)
		(layers "F.Cu" "B.Cu")
		(net "GND")
	)
	(via
		(at 199.749156 -134.4041)
		(size 0.508)
		(drill 0.254)
		(layers "F.Cu" "B.Cu")
		(net "GND")
	)
	(via
		(at 136.812274 -56.399938)
		(size 0.508)
		(drill 0.254)
		(layers "F.Cu" "B.Cu")
		(net "GND")
	)
	(via
		(at 125.651768 -88.594184)
		(size 0.508)
		(drill 0.254)
		(layers "F.Cu" "B.Cu")
		(net "GND")
	)
	(via
		(at 79.196692 -95.21444)
		(size 0.508)
		(drill 0.254)
		(layers "F.Cu" "B.Cu")
		(net "GND")
	)
	(via
		(at 474.451934 12.894056)
		(size 0.5588)
		(drill 0.3048)
		(layers "F.Cu" "B.Cu")
		(net "GND")
	)
	(via
		(at 294.08628 -80.669384)
		(size 0.508)
		(drill 0.254)
		(layers "F.Cu" "B.Cu")
		(net "GND")
	)
	(via
		(at 163.276534 -167.832024)
		(size 0.5588)
		(drill 0.3048)
		(layers "F.Cu" "B.Cu")
		(net "GND")
	)
	(via
		(at 243.338604 -80.850486)
		(size 0.508)
		(drill 0.254)
		(layers "F.Cu" "B.Cu")
		(net "GND")
	)
	(via
		(at 74.749406 0.444754)
		(size 0.508)
		(drill 0.254)
		(layers "F.Cu" "B.Cu")
		(net "GND")
	)
	(via
		(at 390.377934 -167.832024)
		(size 0.5588)
		(drill 0.3048)
		(layers "F.Cu" "B.Cu")
		(net "GND")
	)
	(via
		(at 303.031906 -139.1666)
		(size 0.508)
		(drill 0.254)
		(layers "F.Cu" "B.Cu")
		(net "GND")
	)
	(via
		(at 89.498678 -53.60924)
		(size 0.508)
		(drill 0.254)
		(layers "F.Cu" "B.Cu")
		(net "GND")
	)
	(via
		(at 244.197124 -82.33664)
		(size 0.508)
		(drill 0.254)
		(layers "F.Cu" "B.Cu")
		(net "GND")
	)
	(via
		(at 66.249296 -144.462246)
		(size 0.508)
		(drill 0.254)
		(layers "F.Cu" "B.Cu")
		(net "GND")
	)
	(via
		(at 12.4206 -31.369)
		(size 0.508)
		(drill 0.254)
		(layers "F.Cu" "B.Cu")
		(net "GND")
	)
	(via
		(at 241.44986 -139.170156)
		(size 0.508)
		(drill 0.254)
		(layers "F.Cu" "B.Cu")
		(net "GND")
	)
	(via
		(at 294.999918 -146.011646)
		(size 0.508)
		(drill 0.254)
		(layers "F.Cu" "B.Cu")
		(net "GND")
	)
	(via
		(at 74.749406 -9.156446)
		(size 0.508)
		(drill 0.254)
		(layers "F.Cu" "B.Cu")
		(net "GND")
	)
	(via
		(at 181.3306 -87.0712)
		(size 0.508)
		(drill 0.254)
		(layers "F.Cu" "B.Cu")
		(net "GND")
	)
	(via
		(at 307.898546 -87.603584)
		(size 0.508)
		(drill 0.254)
		(layers "F.Cu" "B.Cu")
		(net "GND")
	)
	(via
		(at 35.880802 -95.304864)
		(size 0.508)
		(drill 0.254)
		(layers "F.Cu" "B.Cu")
		(net "GND")
	)
	(via
		(at 316.249812 -13.363956)
		(size 0.508)
		(drill 0.254)
		(layers "F.Cu" "B.Cu")
		(net "GND")
	)
	(via
		(at 47.549308 -144.462246)
		(size 0.508)
		(drill 0.254)
		(layers "F.Cu" "B.Cu")
		(net "GND")
	)
	(via
		(at 348.3991 0.230378)
		(size 0.508)
		(drill 0.254)
		(layers "F.Cu" "B.Cu")
		(net "GND")
	)
	(via
		(at 421.670734 -167.832024)
		(size 0.5588)
		(drill 0.3048)
		(layers "F.Cu" "B.Cu")
		(net "GND")
	)
	(via
		(at 151.24938 1.994154)
		(size 0.508)
		(drill 0.254)
		(layers "F.Cu" "B.Cu")
		(net "GND")
	)
	(via
		(at 182.9308 -140.1445)
		(size 0.508)
		(drill 0.254)
		(layers "F.Cu" "B.Cu")
		(net "GND")
	)
	(via
		(at 268.557756 -63.019686)
		(size 0.508)
		(drill 0.254)
		(layers "F.Cu" "B.Cu")
		(net "GND")
	)
	(via
		(at 14.631924 -162.243262)
		(size 0.5588)
		(drill 0.3048)
		(layers "F.Cu" "B.Cu")
		(net "GND")
	)
	(via
		(at 199.979534 -95.228664)
		(size 0.508)
		(drill 0.254)
		(layers "F.Cu" "B.Cu")
		(net "GND")
	)
	(via
		(at 243.739924 -162.243262)
		(size 0.5588)
		(drill 0.3048)
		(layers "F.Cu" "B.Cu")
		(net "GND")
	)
	(via
		(at 348.0054 -39.37)
		(size 0.508)
		(drill 0.254)
		(layers "F.Cu" "B.Cu")
		(net "GND")
	)
	(via
		(at 42.019982 -70.237858)
		(size 0.5588)
		(drill 0.3048)
		(layers "F.Cu" "B.Cu")
		(net "GND")
	)
	(via
		(at 291.422074 -3.762756)
		(size 0.508)
		(drill 0.254)
		(layers "F.Cu" "B.Cu")
		(net "GND")
	)
	(via
		(at 39.899336 -140.617956)
		(size 0.508)
		(drill 0.254)
		(layers "F.Cu" "B.Cu")
		(net "GND")
	)
	(via
		(at 282.925774 -89.089738)
		(size 0.508)
		(drill 0.254)
		(layers "F.Cu" "B.Cu")
		(net "GND")
	)
	(via
		(at 36.275772 -101.641402)
		(size 0.5588)
		(drill 0.3048)
		(layers "F.Cu" "B.Cu")
		(net "GND")
	)
	(via
		(at 343.1032 -16.9164)
		(size 0.508)
		(drill 0.254)
		(layers "F.Cu" "B.Cu")
		(net "GND")
	)
	(via
		(at 499.917466 -19.143726)
		(size 0.508)
		(drill 0.254)
		(layers "F.Cu" "B.Cu")
		(net "GND")
	)
	(via
		(at 311.0865 -141.1478)
		(size 0.508)
		(drill 0.254)
		(layers "F.Cu" "B.Cu")
		(net "GND")
	)
	(via
		(at 412.864554 -21.409152)
		(size 0.508)
		(drill 0.254)
		(layers "F.Cu" "B.Cu")
		(net "GND")
	)
	(via
		(at 473.181934 13.910056)
		(size 0.5588)
		(drill 0.3048)
		(layers "F.Cu" "B.Cu")
		(net "GND")
	)
	(via
		(at -4.592066 14.926056)
		(size 0.5588)
		(drill 0.3048)
		(layers "F.Cu" "B.Cu")
		(net "GND")
	)
	(via
		(at 193.886582 -101.653848)
		(size 0.508)
		(drill 0.254)
		(layers "F.Cu" "B.Cu")
		(net "GND")
	)
	(via
		(at 174.850552 -58.74512)
		(size 0.508)
		(drill 0.254)
		(layers "F.Cu" "B.Cu")
		(net "GND")
	)
	(via
		(at 419.490144 -30.93466)
		(size 0.4572)
		(drill 0.2032)
		(layers "F.Cu" "B.Cu")
		(net "GND")
	)
	(via
		(at 281.361896 -139.170156)
		(size 0.508)
		(drill 0.254)
		(layers "F.Cu" "B.Cu")
		(net "GND")
	)
	(via
		(at 275.721572 -70.84314)
		(size 0.5588)
		(drill 0.3048)
		(layers "F.Cu" "B.Cu")
		(net "GND")
	)
	(via
		(at 333.151734 -167.832024)
		(size 0.5588)
		(drill 0.3048)
		(layers "F.Cu" "B.Cu")
		(net "GND")
	)
	(via
		(at 179.331112 -125.1204)
		(size 0.508)
		(drill 0.254)
		(layers "F.Cu" "B.Cu")
		(net "GND")
	)
	(via
		(at 42.9641 -82.1944)
		(size 0.5588)
		(drill 0.3048)
		(layers "F.Cu" "B.Cu")
		(net "GND")
	)
	(via
		(at 137.901934 9.084056)
		(size 0.5588)
		(drill 0.3048)
		(layers "F.Cu" "B.Cu")
		(net "GND")
	)
	(via
		(at 69.551296 -144.462246)
		(size 0.508)
		(drill 0.254)
		(layers "F.Cu" "B.Cu")
		(net "GND")
	)
	(via
		(at 393.730734 -166.714424)
		(size 0.5588)
		(drill 0.3048)
		(layers "F.Cu" "B.Cu")
		(net "GND")
	)
	(via
		(at 87.101934 14.926056)
		(size 0.5588)
		(drill 0.3048)
		(layers "F.Cu" "B.Cu")
		(net "GND")
	)
	(via
		(at 214.686134 -167.832024)
		(size 0.5588)
		(drill 0.3048)
		(layers "F.Cu" "B.Cu")
		(net "GND")
	)
	(via
		(at 123.934728 -69.772784)
		(size 0.508)
		(drill 0.254)
		(layers "F.Cu" "B.Cu")
		(net "GND")
	)
	(via
		(at 464.4898 -144.646396)
		(size 0.508)
		(drill 0.254)
		(layers "F.Cu" "B.Cu")
		(net "GND")
	)
	(via
		(at 68.051934 9.084056)
		(size 0.5588)
		(drill 0.3048)
		(layers "F.Cu" "B.Cu")
		(net "GND")
	)
	(via
		(at 79.196692 -53.60924)
		(size 0.508)
		(drill 0.254)
		(layers "F.Cu" "B.Cu")
		(net "GND")
	)
	(via
		(at 206.859124 -162.243262)
		(size 0.5588)
		(drill 0.3048)
		(layers "F.Cu" "B.Cu")
		(net "GND")
	)
	(via
		(at 350.647 -12.827)
		(size 0.508)
		(drill 0.254)
		(layers "F.Cu" "B.Cu")
		(net "GND")
	)
	(via
		(at 200.8886 -73.7362)
		(size 0.508)
		(drill 0.254)
		(layers "F.Cu" "B.Cu")
		(net "GND")
	)
	(via
		(at 72.142096 -145.998946)
		(size 0.508)
		(drill 0.254)
		(layers "F.Cu" "B.Cu")
		(net "GND")
	)
	(via
		(at 444.208916 -14.867382)
		(size 0.508)
		(drill 0.254)
		(layers "F.Cu" "B.Cu")
		(net "GND")
	)
	(via
		(at 344.1954 -108.585)
		(size 0.508)
		(drill 0.254)
		(layers "F.Cu" "B.Cu")
		(net "GND")
	)
	(via
		(at 238.444532 0.5207)
		(size 0.508)
		(drill 0.254)
		(layers "F.Cu" "B.Cu")
		(net "GND")
	)
	(via
		(at 283.036264 -150.749)
		(size 0.508)
		(drill 0.254)
		(layers "F.Cu" "B.Cu")
		(net "GND")
	)
	(via
		(at 87.101934 9.084056)
		(size 0.5588)
		(drill 0.3048)
		(layers "F.Cu" "B.Cu")
		(net "GND")
	)
	(via
		(at 405.160734 -166.714424)
		(size 0.5588)
		(drill 0.3048)
		(layers "F.Cu" "B.Cu")
		(net "GND")
	)
	(via
		(at 83.489292 -65.991486)
		(size 0.508)
		(drill 0.254)
		(layers "F.Cu" "B.Cu")
		(net "GND")
	)
	(via
		(at 238.187738 -59.057286)
		(size 0.508)
		(drill 0.254)
		(layers "F.Cu" "B.Cu")
		(net "GND")
	)
	(via
		(at 38.819582 -76.468478)
		(size 0.5588)
		(drill 0.3048)
		(layers "F.Cu" "B.Cu")
		(net "GND")
	)
	(via
		(at 114.699542 0.457454)
		(size 0.508)
		(drill 0.254)
		(layers "F.Cu" "B.Cu")
		(net "GND")
	)
	(via
		(at 476.20555 -143.28775)
		(size 0.508)
		(drill 0.254)
		(layers "F.Cu" "B.Cu")
		(net "GND")
	)
	(via
		(at 306.899818 -144.462246)
		(size 0.508)
		(drill 0.254)
		(layers "F.Cu" "B.Cu")
		(net "GND")
	)
	(via
		(at 36.044124 -145.9357)
		(size 0.508)
		(drill 0.254)
		(layers "F.Cu" "B.Cu")
		(net "GND")
	)
	(via
		(at 75.671934 9.084056)
		(size 0.5588)
		(drill 0.3048)
		(layers "F.Cu" "B.Cu")
		(net "GND")
	)
	(via
		(at 354.561902 -155.10002)
		(size 0.5588)
		(drill 0.3048)
		(layers "F.Cu" "B.Cu")
		(net "GND")
	)
	(via
		(at 386.74675 -120.387364)
		(size 0.508)
		(drill 0.254)
		(layers "F.Cu" "B.Cu")
		(net "GND")
	)
	(via
		(at -0.6858 -50.851308)
		(size 0.5588)
		(drill 0.3048)
		(layers "F.Cu" "B.Cu")
		(net "GND")
	)
	(via
		(at 199.992234 -71.555864)
		(size 0.508)
		(drill 0.254)
		(layers "F.Cu" "B.Cu")
		(net "GND")
	)
	(via
		(at 199.742552 -11.912092)
		(size 0.508)
		(drill 0.254)
		(layers "F.Cu" "B.Cu")
		(net "GND")
	)
	(via
		(at 131.661408 -100.976684)
		(size 0.508)
		(drill 0.254)
		(layers "F.Cu" "B.Cu")
		(net "GND")
	)
	(via
		(at 78.338172 -91.747086)
		(size 0.508)
		(drill 0.254)
		(layers "F.Cu" "B.Cu")
		(net "GND")
	)
	(via
		(at 383.892552 -134.88543)
		(size 0.508)
		(drill 0.254)
		(layers "F.Cu" "B.Cu")
		(net "GND")
	)
	(via
		(at 115.460526 -140.592556)
		(size 0.508)
		(drill 0.254)
		(layers "F.Cu" "B.Cu")
		(net "GND")
	)
	(via
		(at 491.4265 -61.6458)
		(size 0.508)
		(drill 0.254)
		(layers "F.Cu" "B.Cu")
		(net "GND")
	)
	(via
		(at 298.399962 -21.517356)
		(size 0.508)
		(drill 0.254)
		(layers "F.Cu" "B.Cu")
		(net "GND")
	)
	(via
		(at 235.612178 -70.44944)
		(size 0.508)
		(drill 0.254)
		(layers "F.Cu" "B.Cu")
		(net "GND")
	)
	(via
		(at 401.991576 -125.749558)
		(size 0.508)
		(drill 0.254)
		(layers "F.Cu" "B.Cu")
		(net "GND")
	)
	(via
		(at 462.310734 -166.714424)
		(size 0.5588)
		(drill 0.3048)
		(layers "F.Cu" "B.Cu")
		(net "GND")
	)
	(via
		(at 205.749906 -139.170156)
		(size 0.508)
		(drill 0.254)
		(layers "F.Cu" "B.Cu")
		(net "GND")
	)
	(via
		(at 378.331222 -145.36801)
		(size 0.508)
		(drill 0.254)
		(layers "F.Cu" "B.Cu")
		(net "GND")
	)
	(via
		(at 445.800734 -163.361624)
		(size 0.5588)
		(drill 0.3048)
		(layers "F.Cu" "B.Cu")
		(net "GND")
	)
	(via
		(at 281.411934 9.084056)
		(size 0.5588)
		(drill 0.3048)
		(layers "F.Cu" "B.Cu")
		(net "GND")
	)
	(via
		(at 226.111816 -129.568956)
		(size 0.508)
		(drill 0.254)
		(layers "F.Cu" "B.Cu")
		(net "GND")
	)
	(via
		(at 244.197124 -55.59044)
		(size 0.508)
		(drill 0.254)
		(layers "F.Cu" "B.Cu")
		(net "GND")
	)
	(via
		(at 394.67155 -118.670324)
		(size 0.508)
		(drill 0.254)
		(layers "F.Cu" "B.Cu")
		(net "GND")
	)
	(via
		(at 135.771636 -22.965156)
		(size 0.508)
		(drill 0.254)
		(layers "F.Cu" "B.Cu")
		(net "GND")
	)
	(via
		(at 410.240734 -166.714424)
		(size 0.5588)
		(drill 0.3048)
		(layers "F.Cu" "B.Cu")
		(net "GND")
	)
	(via
		(at 314.152534 -167.832024)
		(size 0.5588)
		(drill 0.3048)
		(layers "F.Cu" "B.Cu")
		(net "GND")
	)
	(via
		(at 61.111384 -129.568956)
		(size 0.508)
		(drill 0.254)
		(layers "F.Cu" "B.Cu")
		(net "GND")
	)
	(via
		(at 41.501314 1.994154)
		(size 0.508)
		(drill 0.254)
		(layers "F.Cu" "B.Cu")
		(net "GND")
	)
	(via
		(at 203.199746 -150.219156)
		(size 0.508)
		(drill 0.254)
		(layers "F.Cu" "B.Cu")
		(net "GND")
	)
	(via
		(at 388.72795 -116.953284)
		(size 0.508)
		(drill 0.254)
		(layers "F.Cu" "B.Cu")
		(net "GND")
	)
	(via
		(at 142.749524 0.457454)
		(size 0.508)
		(drill 0.254)
		(layers "F.Cu" "B.Cu")
		(net "GND")
	)
	(via
		(at 423.956734 -139.172442)
		(size 0.508)
		(drill 0.254)
		(layers "F.Cu" "B.Cu")
		(net "GND")
	)
	(via
		(at 32.160464 -140.592556)
		(size 0.508)
		(drill 0.254)
		(layers "F.Cu" "B.Cu")
		(net "GND")
	)
	(via
		(at 100.687124 -162.243262)
		(size 0.5588)
		(drill 0.3048)
		(layers "F.Cu" "B.Cu")
		(net "GND")
	)
	(via
		(at 335.213452 -121.284238)
		(size 0.508)
		(drill 0.254)
		(layers "F.Cu" "B.Cu")
		(net "GND")
	)
	(via
		(at 280.065734 -58.381138)
		(size 0.508)
		(drill 0.254)
		(layers "F.Cu" "B.Cu")
		(net "GND")
	)
	(via
		(at 485.170734 -165.596824)
		(size 0.5588)
		(drill 0.3048)
		(layers "F.Cu" "B.Cu")
		(net "GND")
	)
	(via
		(at 40.699182 -68.256658)
		(size 0.5588)
		(drill 0.3048)
		(layers "F.Cu" "B.Cu")
		(net "GND")
	)
	(via
		(at 35.5346 -98.552)
		(size 0.508)
		(drill 0.254)
		(layers "F.Cu" "B.Cu")
		(net "GND")
	)
	(via
		(at 301.812706 -56.399938)
		(size 0.508)
		(drill 0.254)
		(layers "F.Cu" "B.Cu")
		(net "GND")
	)
	(via
		(at 283.04236 -2.310892)
		(size 0.508)
		(drill 0.254)
		(layers "F.Cu" "B.Cu")
		(net "GND")
	)
	(via
		(at 223.599756 -140.617956)
		(size 0.508)
		(drill 0.254)
		(layers "F.Cu" "B.Cu")
		(net "GND")
	)
	(via
		(at 148.699474 -148.771356)
		(size 0.508)
		(drill 0.254)
		(layers "F.Cu" "B.Cu")
		(net "GND")
	)
	(via
		(at 458.8764 -119.64797)
		(size 0.508)
		(drill 0.254)
		(layers "F.Cu" "B.Cu")
		(net "GND")
	)
	(via
		(at 328.401934 14.926056)
		(size 0.5588)
		(drill 0.3048)
		(layers "F.Cu" "B.Cu")
		(net "GND")
	)
	(via
		(at 142.898114 -61.847984)
		(size 0.508)
		(drill 0.254)
		(layers "F.Cu" "B.Cu")
		(net "GND")
	)
	(via
		(at 144.449546 -9.156446)
		(size 0.508)
		(drill 0.254)
		(layers "F.Cu" "B.Cu")
		(net "GND")
	)
	(via
		(at 96.721168 -14.351)
		(size 0.508)
		(drill 0.254)
		(layers "F.Cu" "B.Cu")
		(net "GND")
	)
	(via
		(at 73.437496 -23.549356)
		(size 0.508)
		(drill 0.254)
		(layers "F.Cu" "B.Cu")
		(net "GND")
	)
	(via
		(at 212.447124 -162.243262)
		(size 0.5588)
		(drill 0.3048)
		(layers "F.Cu" "B.Cu")
		(net "GND")
	)
	(via
		(at 487.268266 -21.536152)
		(size 0.508)
		(drill 0.254)
		(layers "F.Cu" "B.Cu")
		(net "GND")
	)
	(via
		(at 72.142096 -139.166092)
		(size 0.508)
		(drill 0.254)
		(layers "F.Cu" "B.Cu")
		(net "GND")
	)
	(via
		(at 65.399412 -148.771356)
		(size 0.508)
		(drill 0.254)
		(layers "F.Cu" "B.Cu")
		(net "GND")
	)
	(via
		(at 61.821568 -144.5006)
		(size 0.508)
		(drill 0.254)
		(layers "F.Cu" "B.Cu")
		(net "GND")
	)
	(via
		(at 143.501364 -7.607046)
		(size 0.508)
		(drill 0.254)
		(layers "F.Cu" "B.Cu")
		(net "GND")
	)
	(via
		(at 373.9896 -108.728002)
		(size 0.508)
		(drill 0.254)
		(layers "F.Cu" "B.Cu")
		(net "GND")
	)
	(via
		(at 179.811934 14.926056)
		(size 0.5588)
		(drill 0.3048)
		(layers "F.Cu" "B.Cu")
		(net "GND")
	)
	(via
		(at 237.329218 -82.33664)
		(size 0.508)
		(drill 0.254)
		(layers "F.Cu" "B.Cu")
		(net "GND")
	)
	(via
		(at 119.34063 -134.349744)
		(size 0.508)
		(drill 0.254)
		(layers "F.Cu" "B.Cu")
		(net "GND")
	)
	(via
		(at 218.436444 -150.749)
		(size 0.508)
		(drill 0.254)
		(layers "F.Cu" "B.Cu")
		(net "GND")
	)
	(via
		(at 360.7816 -136.652)
		(size 0.508)
		(drill 0.254)
		(layers "F.Cu" "B.Cu")
		(net "GND")
	)
	(via
		(at 261.7216 -14.351)
		(size 0.508)
		(drill 0.254)
		(layers "F.Cu" "B.Cu")
		(net "GND")
	)
	(via
		(at 327.131934 9.084056)
		(size 0.5588)
		(drill 0.3048)
		(layers "F.Cu" "B.Cu")
		(net "GND")
	)
	(via
		(at 288.07664 -96.023938)
		(size 0.508)
		(drill 0.254)
		(layers "F.Cu" "B.Cu")
		(net "GND")
	)
	(via
		(at 84.561934 14.926056)
		(size 0.5588)
		(drill 0.3048)
		(layers "F.Cu" "B.Cu")
		(net "GND")
	)
	(via
		(at 415.417762 -87.895684)
		(size 0.508)
		(drill 0.254)
		(layers "F.Cu" "B.Cu")
		(net "GND")
	)
	(via
		(at 300.954186 -51.941984)
		(size 0.508)
		(drill 0.254)
		(layers "F.Cu" "B.Cu")
		(net "GND")
	)
	(via
		(at 303.044606 -28.66771)
		(size 0.508)
		(drill 0.254)
		(layers "F.Cu" "B.Cu")
		(net "GND")
	)
	(via
		(at 471.689176 -47.318168)
		(size 0.508)
		(drill 0.254)
		(layers "F.Cu" "B.Cu")
		(net "GND")
	)
	(via
		(at 424.921934 14.926056)
		(size 0.5588)
		(drill 0.3048)
		(layers "F.Cu" "B.Cu")
		(net "GND")
	)
	(via
		(at 494.771934 10.354056)
		(size 0.5588)
		(drill 0.3048)
		(layers "F.Cu" "B.Cu")
		(net "GND")
	)
	(via
		(at 297.520106 -65.810384)
		(size 0.508)
		(drill 0.254)
		(layers "F.Cu" "B.Cu")
		(net "GND")
	)
	(via
		(at 402.620734 -166.714424)
		(size 0.5588)
		(drill 0.3048)
		(layers "F.Cu" "B.Cu")
		(net "GND")
	)
	(via
		(at 73.187306 -64.010286)
		(size 0.508)
		(drill 0.254)
		(layers "F.Cu" "B.Cu")
		(net "GND")
	)
	(via
		(at 135.953754 -73.735184)
		(size 0.508)
		(drill 0.254)
		(layers "F.Cu" "B.Cu")
		(net "GND")
	)
	(via
		(at 130.862324 -162.243262)
		(size 0.5588)
		(drill 0.3048)
		(layers "F.Cu" "B.Cu")
		(net "GND")
	)
	(via
		(at 371.08511 -8.84682)
		(size 0.508)
		(drill 0.254)
		(layers "F.Cu" "B.Cu")
		(net "GND")
	)
	(via
		(at 141.963394 -58.381138)
		(size 0.508)
		(drill 0.254)
		(layers "F.Cu" "B.Cu")
		(net "GND")
	)
	(via
		(at 442.849 -9.9822)
		(size 0.508)
		(drill 0.254)
		(layers "F.Cu" "B.Cu")
		(net "GND")
	)
	(via
		(at 62.786006 -150.749)
		(size 0.508)
		(drill 0.254)
		(layers "F.Cu" "B.Cu")
		(net "GND")
	)
	(via
		(at 105.383076 -82.339942)
		(size 0.5588)
		(drill 0.3048)
		(layers "F.Cu" "B.Cu")
		(net "GND")
	)
	(via
		(at 116.311934 14.926056)
		(size 0.5588)
		(drill 0.3048)
		(layers "F.Cu" "B.Cu")
		(net "GND")
	)
	(via
		(at 163.493196 -31.387542)
		(size 0.508)
		(drill 0.254)
		(layers "F.Cu" "B.Cu")
		(net "GND")
	)
	(via
		(at 230.399844 -155.612846)
		(size 0.508)
		(drill 0.254)
		(layers "F.Cu" "B.Cu")
		(net "GND")
	)
	(via
		(at 206.501746 -134.861046)
		(size 0.508)
		(drill 0.254)
		(layers "F.Cu" "B.Cu")
		(net "GND")
	)
	(via
		(at 384.1369 -113.0554)
		(size 0.508)
		(drill 0.254)
		(layers "F.Cu" "B.Cu")
		(net "GND")
	)
	(via
		(at 215.0999 -136.397746)
		(size 0.508)
		(drill 0.254)
		(layers "F.Cu" "B.Cu")
		(net "GND")
	)
	(via
		(at 53.448712 -153.6065)
		(size 0.508)
		(drill 0.254)
		(layers "F.Cu" "B.Cu")
		(net "GND")
	)
	(via
		(at 345.821 -151.3078)
		(size 0.508)
		(drill 0.254)
		(layers "F.Cu" "B.Cu")
		(net "GND")
	)
	(via
		(at 33.771586 -134.8994)
		(size 0.508)
		(drill 0.254)
		(layers "F.Cu" "B.Cu")
		(net "GND")
	)
	(via
		(at 45.387514 -131.600956)
		(size 0.508)
		(drill 0.254)
		(layers "F.Cu" "B.Cu")
		(net "GND")
	)
	(via
		(at 438.135776 -63.582296)
		(size 0.508)
		(drill 0.254)
		(layers "F.Cu" "B.Cu")
		(net "GND")
	)
	(via
		(at 69.56044 -150.193756)
		(size 0.508)
		(drill 0.254)
		(layers "F.Cu" "B.Cu")
		(net "GND")
	)
	(via
		(at 286.3596 -98.005138)
		(size 0.508)
		(drill 0.254)
		(layers "F.Cu" "B.Cu")
		(net "GND")
	)
	(via
		(at 413.890206 -30.13456)
		(size 0.4572)
		(drill 0.2032)
		(layers "F.Cu" "B.Cu")
		(net "GND")
	)
	(via
		(at 472.64701 -23.160736)
		(size 0.508)
		(drill 0.254)
		(layers "F.Cu" "B.Cu")
		(net "GND")
	)
	(via
		(at 468.71382 -118.58498)
		(size 0.508)
		(drill 0.254)
		(layers "F.Cu" "B.Cu")
		(net "GND")
	)
	(via
		(at 366.501934 9.084056)
		(size 0.5588)
		(drill 0.3048)
		(layers "F.Cu" "B.Cu")
		(net "GND")
	)
	(via
		(at 189.971934 9.084056)
		(size 0.5588)
		(drill 0.3048)
		(layers "F.Cu" "B.Cu")
		(net "GND")
	)
	(via
		(at 374.002046 -111.612934)
		(size 0.508)
		(drill 0.254)
		(layers "F.Cu" "B.Cu")
		(net "GND")
	)
	(via
		(at 284.35808 -53.923184)
		(size 0.508)
		(drill 0.254)
		(layers "F.Cu" "B.Cu")
		(net "GND")
	)
	(via
		(at 381.79375 -99.322636)
		(size 0.508)
		(drill 0.254)
		(layers "F.Cu" "B.Cu")
		(net "GND")
	)
	(via
		(at 169.291 -123.0884)
		(size 0.508)
		(drill 0.254)
		(layers "F.Cu" "B.Cu")
		(net "GND")
	)
	(via
		(at 74.045826 -89.27084)
		(size 0.508)
		(drill 0.254)
		(layers "F.Cu" "B.Cu")
		(net "GND")
	)
	(via
		(at 219.741242 -134.349744)
		(size 0.508)
		(drill 0.254)
		(layers "F.Cu" "B.Cu")
		(net "GND")
	)
	(via
		(at 449.610734 -167.832024)
		(size 0.5588)
		(drill 0.3048)
		(layers "F.Cu" "B.Cu")
		(net "GND")
	)
	(via
		(at 286.07512 -53.923184)
		(size 0.508)
		(drill 0.254)
		(layers "F.Cu" "B.Cu")
		(net "GND")
	)
	(via
		(at 152.9334 -27.8384)
		(size 0.508)
		(drill 0.254)
		(layers "F.Cu" "B.Cu")
		(net "GND")
	)
	(via
		(at 111.915702 -94.538038)
		(size 0.508)
		(drill 0.254)
		(layers "F.Cu" "B.Cu")
		(net "GND")
	)
	(via
		(at 66.249296 -3.762756)
		(size 0.508)
		(drill 0.254)
		(layers "F.Cu" "B.Cu")
		(net "GND")
	)
	(via
		(at 425.166282 -31.574232)
		(size 0.4572)
		(drill 0.2032)
		(layers "F.Cu" "B.Cu")
		(net "GND")
	)
	(via
		(at 406.9461 -155.12288)
		(size 0.508)
		(drill 0.254)
		(layers "F.Cu" "B.Cu")
		(net "GND")
	)
	(via
		(at 88.640412 -88.775286)
		(size 0.508)
		(drill 0.254)
		(layers "F.Cu" "B.Cu")
		(net "GND")
	)
	(via
		(at 294.999918 -139.170156)
		(size 0.508)
		(drill 0.254)
		(layers "F.Cu" "B.Cu")
		(net "GND")
	)
	(via
		(at 36.044124 -9.0805)
		(size 0.508)
		(drill 0.254)
		(layers "F.Cu" "B.Cu")
		(net "GND")
	)
	(via
		(at 5.334 -125.9332)
		(size 0.508)
		(drill 0.254)
		(layers "F.Cu" "B.Cu")
		(net "GND")
	)
	(via
		(at 6.812534 -163.361624)
		(size 0.5588)
		(drill 0.3048)
		(layers "F.Cu" "B.Cu")
		(net "GND")
	)
	(via
		(at 152.099518 0.444754)
		(size 0.508)
		(drill 0.254)
		(layers "F.Cu" "B.Cu")
		(net "GND")
	)
	(via
		(at 469.371934 13.910056)
		(size 0.5588)
		(drill 0.3048)
		(layers "F.Cu" "B.Cu")
		(net "GND")
	)
	(via
		(at -4.555744 13.659866)
		(size 0.5588)
		(drill 0.3048)
		(layers "F.Cu" "B.Cu")
		(net "GND")
	)
	(via
		(at 113.348262 -52.437284)
		(size 0.508)
		(drill 0.254)
		(layers "F.Cu" "B.Cu")
		(net "GND")
	)
	(via
		(at 447.070734 -167.832024)
		(size 0.5588)
		(drill 0.3048)
		(layers "F.Cu" "B.Cu")
		(net "GND")
	)
	(via
		(at 73.437496 -126.655576)
		(size 0.508)
		(drill 0.254)
		(layers "F.Cu" "B.Cu")
		(net "GND")
	)
	(via
		(at 456.21575 -124.92482)
		(size 0.508)
		(drill 0.254)
		(layers "F.Cu" "B.Cu")
		(net "GND")
	)
	(via
		(at 142.739364 -82.677508)
		(size 0.508)
		(drill 0.254)
		(layers "F.Cu" "B.Cu")
		(net "GND")
	)
	(via
		(at 344.911934 14.926056)
		(size 0.5588)
		(drill 0.3048)
		(layers "F.Cu" "B.Cu")
		(net "GND")
	)
	(via
		(at 103.678736 -140.208)
		(size 0.508)
		(drill 0.254)
		(layers "F.Cu" "B.Cu")
		(net "GND")
	)
	(via
		(at 467.995 -135.763)
		(size 0.508)
		(drill 0.254)
		(layers "F.Cu" "B.Cu")
		(net "GND")
	)
	(via
		(at 80.913732 -99.17684)
		(size 0.508)
		(drill 0.254)
		(layers "F.Cu" "B.Cu")
		(net "GND")
	)
	(via
		(at 70.499478 -9.156446)
		(size 0.508)
		(drill 0.254)
		(layers "F.Cu" "B.Cu")
		(net "GND")
	)
	(via
		(at 47.046134 -167.832024)
		(size 0.5588)
		(drill 0.3048)
		(layers "F.Cu" "B.Cu")
		(net "GND")
	)
	(via
		(at -3.245866 -165.596824)
		(size 0.5588)
		(drill 0.3048)
		(layers "F.Cu" "B.Cu")
		(net "GND")
	)
	(via
		(at 45.390816 -143.950944)
		(size 0.508)
		(drill 0.254)
		(layers "F.Cu" "B.Cu")
		(net "GND")
	)
	(via
		(at 127.368808 -96.518984)
		(size 0.508)
		(drill 0.254)
		(layers "F.Cu" "B.Cu")
		(net "GND")
	)
	(via
		(at 378.052076 -92.828364)
		(size 0.508)
		(drill 0.254)
		(layers "F.Cu" "B.Cu")
		(net "GND")
	)
	(via
		(at 416.464242 -9.6774)
		(size 0.508)
		(drill 0.254)
		(layers "F.Cu" "B.Cu")
		(net "GND")
	)
	(via
		(at 35.880802 -71.555864)
		(size 0.508)
		(drill 0.254)
		(layers "F.Cu" "B.Cu")
		(net "GND")
	)
	(via
		(at 273.482308 -89.584784)
		(size 0.508)
		(drill 0.254)
		(layers "F.Cu" "B.Cu")
		(net "GND")
	)
	(via
		(at 35.492944 -99.6442)
		(size 0.508)
		(drill 0.254)
		(layers "F.Cu" "B.Cu")
		(net "GND")
	)
	(via
		(at 376.232166 -151.783034)
		(size 0.508)
		(drill 0.254)
		(layers "F.Cu" "B.Cu")
		(net "GND")
	)
	(via
		(at 263.08431 -63.51524)
		(size 0.508)
		(drill 0.254)
		(layers "F.Cu" "B.Cu")
		(net "GND")
	)
	(via
		(at 392.1379 -109.0549)
		(size 0.508)
		(drill 0.254)
		(layers "F.Cu" "B.Cu")
		(net "GND")
	)
	(via
		(at 147.394168 -155.5369)
		(size 0.508)
		(drill 0.254)
		(layers "F.Cu" "B.Cu")
		(net "GND")
	)
	(via
		(at 54.74081 -16.696944)
		(size 0.508)
		(drill 0.254)
		(layers "F.Cu" "B.Cu")
		(net "GND")
	)
	(via
		(at 119.343932 -145.9357)
		(size 0.508)
		(drill 0.254)
		(layers "F.Cu" "B.Cu")
		(net "GND")
	)
	(via
		(at 311.092596 -11.912092)
		(size 0.508)
		(drill 0.254)
		(layers "F.Cu" "B.Cu")
		(net "GND")
	)
	(via
		(at 87.781892 -87.28964)
		(size 0.508)
		(drill 0.254)
		(layers "F.Cu" "B.Cu")
		(net "GND")
	)
	(via
		(at 457.230734 -163.361624)
		(size 0.5588)
		(drill 0.3048)
		(layers "F.Cu" "B.Cu")
		(net "GND")
	)
	(via
		(at 297.520106 -90.575384)
		(size 0.508)
		(drill 0.254)
		(layers "F.Cu" "B.Cu")
		(net "GND")
	)
	(via
		(at 97.225358 -98.681286)
		(size 0.508)
		(drill 0.254)
		(layers "F.Cu" "B.Cu")
		(net "GND")
	)
	(via
		(at 379.45822 -132.7912)
		(size 0.508)
		(drill 0.254)
		(layers "F.Cu" "B.Cu")
		(net "GND")
	)
	(via
		(at 403.890734 -164.479224)
		(size 0.5588)
		(drill 0.3048)
		(layers "F.Cu" "B.Cu")
		(net "GND")
	)
	(via
		(at 369.545108 -71.095108)
		(size 0.4572)
		(drill 0.2032)
		(layers "F.Cu" "B.Cu")
		(net "GND")
	)
	(via
		(at 138.529314 -81.164938)
		(size 0.508)
		(drill 0.254)
		(layers "F.Cu" "B.Cu")
		(net "GND")
	)
	(via
		(at 16.257778 -103.702104)
		(size 0.508)
		(drill 0.254)
		(layers "F.Cu" "B.Cu")
		(net "GND")
	)
	(via
		(at 300.772068 -154.1018)
		(size 0.508)
		(drill 0.254)
		(layers "F.Cu" "B.Cu")
		(net "GND")
	)
	(via
		(at 200.62444 -92.696538)
		(size 0.5588)
		(drill 0.3048)
		(layers "F.Cu" "B.Cu")
		(net "GND")
	)
	(via
		(at 224.449894 -148.771356)
		(size 0.508)
		(drill 0.254)
		(layers "F.Cu" "B.Cu")
		(net "GND")
	)
	(via
		(at 435.081934 13.910056)
		(size 0.5588)
		(drill 0.3048)
		(layers "F.Cu" "B.Cu")
		(net "GND")
	)
	(via
		(at 120.649492 0.444754)
		(size 0.508)
		(drill 0.254)
		(layers "F.Cu" "B.Cu")
		(net "GND")
	)
	(via
		(at 217.472006 -13.363956)
		(size 0.508)
		(drill 0.254)
		(layers "F.Cu" "B.Cu")
		(net "GND")
	)
	(via
		(at 401.262342 -3.367278)
		(size 0.508)
		(drill 0.254)
		(layers "F.Cu" "B.Cu")
		(net "GND")
	)
	(via
		(at 4.577334 -165.596824)
		(size 0.5588)
		(drill 0.3048)
		(layers "F.Cu" "B.Cu")
		(net "GND")
	)
	(via
		(at 90.802968 -3.635756)
		(size 0.508)
		(drill 0.254)
		(layers "F.Cu" "B.Cu")
		(net "GND")
	)
	(via
		(at 400.97202 -74.53122)
		(size 0.508)
		(drill 0.254)
		(layers "F.Cu" "B.Cu")
		(net "GND")
	)
	(via
		(at 290.6522 -78.688438)
		(size 0.508)
		(drill 0.254)
		(layers "F.Cu" "B.Cu")
		(net "GND")
	)
	(via
		(at 242.480338 -80.35544)
		(size 0.508)
		(drill 0.254)
		(layers "F.Cu" "B.Cu")
		(net "GND")
	)
	(via
		(at 432.541934 11.624056)
		(size 0.5588)
		(drill 0.3048)
		(layers "F.Cu" "B.Cu")
		(net "GND")
	)
	(via
		(at 370.6622 -109.22)
		(size 0.508)
		(drill 0.254)
		(layers "F.Cu" "B.Cu")
		(net "GND")
	)
	(via
		(at 349.310706 -104.28986)
		(size 0.508)
		(drill 0.254)
		(layers "F.Cu" "B.Cu")
		(net "GND")
	)
	(via
		(at 106.304842 -70.84314)
		(size 0.5588)
		(drill 0.3048)
		(layers "F.Cu" "B.Cu")
		(net "GND")
	)
	(via
		(at 33.061402 -148.771356)
		(size 0.508)
		(drill 0.254)
		(layers "F.Cu" "B.Cu")
		(net "GND")
	)
	(via
		(at 121.499376 -150.219156)
		(size 0.508)
		(drill 0.254)
		(layers "F.Cu" "B.Cu")
		(net "GND")
	)
	(via
		(at 40.111934 14.926056)
		(size 0.5588)
		(drill 0.3048)
		(layers "F.Cu" "B.Cu")
		(net "GND")
	)
	(via
		(at 43.693334 -167.832024)
		(size 0.5588)
		(drill 0.3048)
		(layers "F.Cu" "B.Cu")
		(net "GND")
	)
	(via
		(at 303.529746 -69.277738)
		(size 0.508)
		(drill 0.254)
		(layers "F.Cu" "B.Cu")
		(net "GND")
	)
	(via
		(at 301.812706 -52.437538)
		(size 0.508)
		(drill 0.254)
		(layers "F.Cu" "B.Cu")
		(net "GND")
	)
	(via
		(at 114.206782 -63.829184)
		(size 0.508)
		(drill 0.254)
		(layers "F.Cu" "B.Cu")
		(net "GND")
	)
	(via
		(at 115.065302 -65.315338)
		(size 0.508)
		(drill 0.254)
		(layers "F.Cu" "B.Cu")
		(net "GND")
	)
	(via
		(at 325.328534 -167.832024)
		(size 0.5588)
		(drill 0.3048)
		(layers "F.Cu" "B.Cu")
		(net "GND")
	)
	(via
		(at 248.489724 -87.784686)
		(size 0.508)
		(drill 0.254)
		(layers "F.Cu" "B.Cu")
		(net "GND")
	)
	(via
		(at 350.017334 -135.960104)
		(size 0.508)
		(drill 0.254)
		(layers "F.Cu" "B.Cu")
		(net "GND")
	)
	(via
		(at 110.772702 -58.876438)
		(size 0.508)
		(drill 0.254)
		(layers "F.Cu" "B.Cu")
		(net "GND")
	)
	(via
		(at 138.044174 -155.5369)
		(size 0.508)
		(drill 0.254)
		(layers "F.Cu" "B.Cu")
		(net "GND")
	)
	(via
		(at 136.748774 -134.4041)
		(size 0.508)
		(drill 0.254)
		(layers "F.Cu" "B.Cu")
		(net "GND")
	)
	(via
		(at 349.494094 -146.805142)
		(size 0.508)
		(drill 0.254)
		(layers "F.Cu" "B.Cu")
		(net "GND")
	)
	(via
		(at 65.399412 -129.568956)
		(size 0.508)
		(drill 0.254)
		(layers "F.Cu" "B.Cu")
		(net "GND")
	)
	(via
		(at 349.301054 -100.660962)
		(size 0.508)
		(drill 0.254)
		(layers "F.Cu" "B.Cu")
		(net "GND")
	)
	(via
		(at 238.431832 -21.5138)
		(size 0.508)
		(drill 0.254)
		(layers "F.Cu" "B.Cu")
		(net "GND")
	)
	(via
		(at 245.055644 -99.67214)
		(size 0.508)
		(drill 0.254)
		(layers "F.Cu" "B.Cu")
		(net "GND")
	)
	(via
		(at 274.914614 -62.343538)
		(size 0.508)
		(drill 0.254)
		(layers "F.Cu" "B.Cu")
		(net "GND")
	)
	(via
		(at 7.4676 -135.2042)
		(size 0.508)
		(drill 0.254)
		(layers "F.Cu" "B.Cu")
		(net "GND")
	)
	(via
		(at 26.289 -76.7334)
		(size 0.508)
		(drill 0.254)
		(layers "F.Cu" "B.Cu")
		(net "GND")
	)
	(via
		(at 239.269524 -162.243262)
		(size 0.5588)
		(drill 0.3048)
		(layers "F.Cu" "B.Cu")
		(net "GND")
	)
	(via
		(at 78.338172 -86.794086)
		(size 0.508)
		(drill 0.254)
		(layers "F.Cu" "B.Cu")
		(net "GND")
	)
	(via
		(at 247.631204 -98.18624)
		(size 0.508)
		(drill 0.254)
		(layers "F.Cu" "B.Cu")
		(net "GND")
	)
	(via
		(at 119.34063 -16.696944)
		(size 0.508)
		(drill 0.254)
		(layers "F.Cu" "B.Cu")
		(net "GND")
	)
	(via
		(at 112.489742 -61.847984)
		(size 0.508)
		(drill 0.254)
		(layers "F.Cu" "B.Cu")
		(net "GND")
	)
	(via
		(at 374.121934 9.084056)
		(size 0.5588)
		(drill 0.3048)
		(layers "F.Cu" "B.Cu")
		(net "GND")
	)
	(via
		(at 387.562598 -145.9738)
		(size 0.508)
		(drill 0.254)
		(layers "F.Cu" "B.Cu")
		(net "GND")
	)
	(via
		(at 351.4598 -32.6263)
		(size 0.508)
		(drill 0.254)
		(layers "F.Cu" "B.Cu")
		(net "GND")
	)
	(via
		(at 67.101466 -64.50584)
		(size 0.508)
		(drill 0.254)
		(layers "F.Cu" "B.Cu")
		(net "GND")
	)
	(via
		(at 344.792808 -81.12633)
		(size 0.508)
		(drill 0.254)
		(layers "F.Cu" "B.Cu")
		(net "GND")
	)
	(via
		(at 45.387514 -13.948156)
		(size 0.508)
		(drill 0.254)
		(layers "F.Cu" "B.Cu")
		(net "GND")
	)
	(via
		(at 295.80332 -60.857384)
		(size 0.508)
		(drill 0.254)
		(layers "F.Cu" "B.Cu")
		(net "GND")
	)
	(via
		(at 182.973726 -52.120546)
		(size 0.508)
		(drill 0.254)
		(layers "F.Cu" "B.Cu")
		(net "GND")
	)
	(via
		(at 78.255368 -8.1534)
		(size 0.508)
		(drill 0.254)
		(layers "F.Cu" "B.Cu")
		(net "GND")
	)
	(via
		(at 315.195458 -39.352728)
		(size 0.508)
		(drill 0.254)
		(layers "F.Cu" "B.Cu")
		(net "GND")
	)
	(via
		(at 395.66215 -122.104404)
		(size 0.508)
		(drill 0.254)
		(layers "F.Cu" "B.Cu")
		(net "GND")
	)
	(via
		(at 214.249762 -140.617956)
		(size 0.508)
		(drill 0.254)
		(layers "F.Cu" "B.Cu")
		(net "GND")
	)
	(via
		(at 117.925342 -93.052138)
		(size 0.508)
		(drill 0.254)
		(layers "F.Cu" "B.Cu")
		(net "GND")
	)
	(via
		(at 297.549824 -22.965156)
		(size 0.508)
		(drill 0.254)
		(layers "F.Cu" "B.Cu")
		(net "GND")
	)
	(via
		(at 468.101934 14.926056)
		(size 0.5588)
		(drill 0.3048)
		(layers "F.Cu" "B.Cu")
		(net "GND")
	)
	(via
		(at 288.07664 -99.986338)
		(size 0.508)
		(drill 0.254)
		(layers "F.Cu" "B.Cu")
		(net "GND")
	)
	(via
		(at 6.5278 -9.1948)
		(size 0.508)
		(drill 0.254)
		(layers "F.Cu" "B.Cu")
		(net "GND")
	)
	(via
		(at 123.934728 -93.547184)
		(size 0.508)
		(drill 0.254)
		(layers "F.Cu" "B.Cu")
		(net "GND")
	)
	(via
		(at 347.680534 -167.832024)
		(size 0.5588)
		(drill 0.3048)
		(layers "F.Cu" "B.Cu")
		(net "GND")
	)
	(via
		(at -0.6604 -59.0042)
		(size 0.5588)
		(drill 0.3048)
		(layers "F.Cu" "B.Cu")
		(net "GND")
	)
	(via
		(at 475.010734 -163.361624)
		(size 0.5588)
		(drill 0.3048)
		(layers "F.Cu" "B.Cu")
		(net "GND")
	)
	(via
		(at 140.246354 -89.089738)
		(size 0.508)
		(drill 0.254)
		(layers "F.Cu" "B.Cu")
		(net "GND")
	)
	(via
		(at 461.01 -45.5422)
		(size 0.508)
		(drill 0.254)
		(layers "F.Cu" "B.Cu")
		(net "GND")
	)
	(via
		(at 219.73794 -131.600956)
		(size 0.508)
		(drill 0.254)
		(layers "F.Cu" "B.Cu")
		(net "GND")
	)
	(via
		(at 279.491694 -99.986338)
		(size 0.508)
		(drill 0.254)
		(layers "F.Cu" "B.Cu")
		(net "GND")
	)
	(via
		(at 109.631734 -167.832024)
		(size 0.5588)
		(drill 0.3048)
		(layers "F.Cu" "B.Cu")
		(net "GND")
	)
	(via
		(at 112.489742 -54.913784)
		(size 0.508)
		(drill 0.254)
		(layers "F.Cu" "B.Cu")
		(net "GND")
	)
	(via
		(at 457.941934 11.624056)
		(size 0.5588)
		(drill 0.3048)
		(layers "F.Cu" "B.Cu")
		(net "GND")
	)
	(via
		(at 232.101898 -86.29904)
		(size 0.508)
		(drill 0.254)
		(layers "F.Cu" "B.Cu")
		(net "GND")
	)
	(via
		(at 1.006856 12.491466)
		(size 0.5588)
		(drill 0.3048)
		(layers "F.Cu" "B.Cu")
		(net "GND")
	)
	(via
		(at 142.749524 -148.771356)
		(size 0.508)
		(drill 0.254)
		(layers "F.Cu" "B.Cu")
		(net "GND")
	)
	(via
		(at 130.281934 14.926056)
		(size 0.5588)
		(drill 0.3048)
		(layers "F.Cu" "B.Cu")
		(net "GND")
	)
	(via
		(at 132.549392 -13.363956)
		(size 0.508)
		(drill 0.254)
		(layers "F.Cu" "B.Cu")
		(net "GND")
	)
	(via
		(at 1.542796 -53.668422)
		(size 0.5588)
		(drill 0.3048)
		(layers "F.Cu" "B.Cu")
		(net "GND")
	)
	(via
		(at 154.335734 -167.832024)
		(size 0.5588)
		(drill 0.3048)
		(layers "F.Cu" "B.Cu")
		(net "GND")
	)
	(via
		(at 38.159182 -76.468478)
		(size 0.5588)
		(drill 0.3048)
		(layers "F.Cu" "B.Cu")
		(net "GND")
	)
	(via
		(at 481.356924 -162.243262)
		(size 0.5588)
		(drill 0.3048)
		(layers "F.Cu" "B.Cu")
		(net "GND")
	)
	(via
		(at 138.529314 -76.211938)
		(size 0.508)
		(drill 0.254)
		(layers "F.Cu" "B.Cu")
		(net "GND")
	)
	(via
		(at 234.753658 -63.019686)
		(size 0.508)
		(drill 0.254)
		(layers "F.Cu" "B.Cu")
		(net "GND")
	)
	(via
		(at 457.980288 -53.270912)
		(size 0.508)
		(drill 0.254)
		(layers "F.Cu" "B.Cu")
		(net "GND")
	)
	(via
		(at 237.136432 -23.495)
		(size 0.508)
		(drill 0.254)
		(layers "F.Cu" "B.Cu")
		(net "GND")
	)
	(via
		(at 124.81052 -130.991356)
		(size 0.508)
		(drill 0.254)
		(layers "F.Cu" "B.Cu")
		(net "GND")
	)
	(via
		(at 407.19248 -146.81708)
		(size 0.508)
		(drill 0.254)
		(layers "F.Cu" "B.Cu")
		(net "GND")
	)
	(via
		(at 209.092546 -21.513292)
		(size 0.508)
		(drill 0.254)
		(layers "F.Cu" "B.Cu")
		(net "GND")
	)
	(via
		(at 200.881234 -79.048864)
		(size 0.508)
		(drill 0.254)
		(layers "F.Cu" "B.Cu")
		(net "GND")
	)
	(via
		(at 205.46441 -100.911406)
		(size 0.5588)
		(drill 0.3048)
		(layers "F.Cu" "B.Cu")
		(net "GND")
	)
	(via
		(at 474.505528 5.428996)
		(size 0.5588)
		(drill 0.3048)
		(layers "F.Cu" "B.Cu")
		(net "GND")
	)
	(via
		(at 242.480338 -70.44944)
		(size 0.508)
		(drill 0.254)
		(layers "F.Cu" "B.Cu")
		(net "GND")
	)
	(via
		(at 227.792534 0.457454)
		(size 0.508)
		(drill 0.254)
		(layers "F.Cu" "B.Cu")
		(net "GND")
	)
	(via
		(at 290.301934 14.926056)
		(size 0.5588)
		(drill 0.3048)
		(layers "F.Cu" "B.Cu")
		(net "GND")
	)
	(via
		(at -1.188466 13.783056)
		(size 0.5588)
		(drill 0.3048)
		(layers "F.Cu" "B.Cu")
		(net "GND")
	)
	(via
		(at 358.062022 -142.327122)
		(size 0.508)
		(drill 0.254)
		(layers "F.Cu" "B.Cu")
		(net "GND")
	)
	(via
		(at 284.33776 -131.600956)
		(size 0.508)
		(drill 0.254)
		(layers "F.Cu" "B.Cu")
		(net "GND")
	)
	(via
		(at 473.494862 -23.175214)
		(size 0.508)
		(drill 0.254)
		(layers "F.Cu" "B.Cu")
		(net "GND")
	)
	(via
		(at 247.631204 -87.28964)
		(size 0.508)
		(drill 0.254)
		(layers "F.Cu" "B.Cu")
		(net "GND")
	)
	(via
		(at 157.020768 -150.7744)
		(size 0.508)
		(drill 0.254)
		(layers "F.Cu" "B.Cu")
		(net "GND")
	)
	(via
		(at 127.368808 -88.594184)
		(size 0.508)
		(drill 0.254)
		(layers "F.Cu" "B.Cu")
		(net "GND")
	)
	(via
		(at 80.913732 -97.19564)
		(size 0.508)
		(drill 0.254)
		(layers "F.Cu" "B.Cu")
		(net "GND")
	)
	(via
		(at 289.049968 -125.955298)
		(size 0.508)
		(drill 0.254)
		(layers "F.Cu" "B.Cu")
		(net "GND")
	)
	(via
		(at 366.3188 -158.3436)
		(size 0.508)
		(drill 0.254)
		(layers "F.Cu" "B.Cu")
		(net "GND")
	)
	(via
		(at 399.126964 -101.893116)
		(size 0.508)
		(drill 0.254)
		(layers "F.Cu" "B.Cu")
		(net "GND")
	)
	(via
		(at 344.7796 5.0292)
		(size 0.508)
		(drill 0.254)
		(layers "F.Cu" "B.Cu")
		(net "GND")
	)
	(via
		(at 383.959354 -25.06345)
		(size 0.508)
		(drill 0.254)
		(layers "F.Cu" "B.Cu")
		(net "GND")
	)
	(via
		(at 180.4924 -106.747818)
		(size 0.508)
		(drill 0.254)
		(layers "F.Cu" "B.Cu")
		(net "GND")
	)
	(via
		(at 123.199398 -144.462246)
		(size 0.508)
		(drill 0.254)
		(layers "F.Cu" "B.Cu")
		(net "GND")
	)
	(via
		(at 221.04985 -136.410446)
		(size 0.508)
		(drill 0.254)
		(layers "F.Cu" "B.Cu")
		(net "GND")
	)
	(via
		(at 181.441598 -0.724408)
		(size 0.508)
		(drill 0.254)
		(layers "F.Cu" "B.Cu")
		(net "GND")
	)
	(via
		(at 35.8648 -90.7288)
		(size 0.508)
		(drill 0.254)
		(layers "F.Cu" "B.Cu")
		(net "GND")
	)
	(via
		(at 122.791728 -63.829184)
		(size 0.508)
		(drill 0.254)
		(layers "F.Cu" "B.Cu")
		(net "GND")
	)
	(via
		(at 95.508318 -98.681286)
		(size 0.508)
		(drill 0.254)
		(layers "F.Cu" "B.Cu")
		(net "GND")
	)
	(via
		(at 133.39953 -145.998946)
		(size 0.508)
		(drill 0.254)
		(layers "F.Cu" "B.Cu")
		(net "GND")
	)
	(via
		(at 123.934728 -94.538038)
		(size 0.508)
		(drill 0.254)
		(layers "F.Cu" "B.Cu")
		(net "GND")
	)
	(via
		(at 83.926934 -167.832024)
		(size 0.5588)
		(drill 0.3048)
		(layers "F.Cu" "B.Cu")
		(net "GND")
	)
	(via
		(at 292.914324 -162.243262)
		(size 0.5588)
		(drill 0.3048)
		(layers "F.Cu" "B.Cu")
		(net "GND")
	)
	(via
		(at 31.908496 -96.807782)
		(size 0.508)
		(drill 0.254)
		(layers "F.Cu" "B.Cu")
		(net "GND")
	)
	(via
		(at 471.79992 -118.5672)
		(size 0.508)
		(drill 0.254)
		(layers "F.Cu" "B.Cu")
		(net "GND")
	)
	(via
		(at 44.092114 -136.397746)
		(size 0.508)
		(drill 0.254)
		(layers "F.Cu" "B.Cu")
		(net "GND")
	)
	(via
		(at 494.060734 -167.832024)
		(size 0.5588)
		(drill 0.3048)
		(layers "F.Cu" "B.Cu")
		(net "GND")
	)
	(via
		(at 379.100334 -167.857424)
		(size 0.5588)
		(drill 0.3048)
		(layers "F.Cu" "B.Cu")
		(net "GND")
	)
	(via
		(at 113.632742 -94.538038)
		(size 0.508)
		(drill 0.254)
		(layers "F.Cu" "B.Cu")
		(net "GND")
	)
	(via
		(at 295.80332 -81.659984)
		(size 0.508)
		(drill 0.254)
		(layers "F.Cu" "B.Cu")
		(net "GND")
	)
	(via
		(at 60.431934 14.926056)
		(size 0.5588)
		(drill 0.3048)
		(layers "F.Cu" "B.Cu")
		(net "GND")
	)
	(via
		(at 173.9646 -32.27959)
		(size 0.508)
		(drill 0.254)
		(layers "F.Cu" "B.Cu")
		(net "GND")
	)
	(via
		(at 492.586264 -44.0944)
		(size 0.508)
		(drill 0.254)
		(layers "F.Cu" "B.Cu")
		(net "GND")
	)
	(via
		(at 458.7748 -139.4968)
		(size 0.508)
		(drill 0.254)
		(layers "F.Cu" "B.Cu")
		(net "GND")
	)
	(via
		(at 15.532608 3.239008)
		(size 0.508)
		(drill 0.254)
		(layers "F.Cu" "B.Cu")
		(net "GND")
	)
	(via
		(at 274.340828 -99.986338)
		(size 0.508)
		(drill 0.254)
		(layers "F.Cu" "B.Cu")
		(net "GND")
	)
	(via
		(at 129.944368 -52.437538)
		(size 0.508)
		(drill 0.254)
		(layers "F.Cu" "B.Cu")
		(net "GND")
	)
	(via
		(at 424.206924 -162.243262)
		(size 0.5588)
		(drill 0.3048)
		(layers "F.Cu" "B.Cu")
		(net "GND")
	)
	(via
		(at 138.024616 -11.938)
		(size 0.508)
		(drill 0.254)
		(layers "F.Cu" "B.Cu")
		(net "GND")
	)
	(via
		(at 204.899768 -13.363956)
		(size 0.508)
		(drill 0.254)
		(layers "F.Cu" "B.Cu")
		(net "GND")
	)
	(via
		(at 284.344364 -155.5369)
		(size 0.508)
		(drill 0.254)
		(layers "F.Cu" "B.Cu")
		(net "GND")
	)
	(via
		(at 37.34943 -136.410446)
		(size 0.508)
		(drill 0.254)
		(layers "F.Cu" "B.Cu")
		(net "GND")
	)
	(via
		(at 52.471574 -154.1018)
		(size 0.508)
		(drill 0.254)
		(layers "F.Cu" "B.Cu")
		(net "GND")
	)
	(via
		(at 489.691934 9.084056)
		(size 0.5588)
		(drill 0.3048)
		(layers "F.Cu" "B.Cu")
		(net "GND")
	)
	(via
		(at 67.101466 -63.51524)
		(size 0.508)
		(drill 0.254)
		(layers "F.Cu" "B.Cu")
		(net "GND")
	)
	(via
		(at 38.199314 -150.219156)
		(size 0.508)
		(drill 0.254)
		(layers "F.Cu" "B.Cu")
		(net "GND")
	)
	(via
		(at 142.981934 9.084056)
		(size 0.5588)
		(drill 0.3048)
		(layers "F.Cu" "B.Cu")
		(net "GND")
	)
	(via
		(at 128.227328 -87.108538)
		(size 0.508)
		(drill 0.254)
		(layers "F.Cu" "B.Cu")
		(net "GND")
	)
	(via
		(at 193.07556 -92.156026)
		(size 0.508)
		(drill 0.254)
		(layers "F.Cu" "B.Cu")
		(net "GND")
	)
	(via
		(at 283.784294 -93.547184)
		(size 0.508)
		(drill 0.254)
		(layers "F.Cu" "B.Cu")
		(net "GND")
	)
	(via
		(at 234.753658 -67.972686)
		(size 0.508)
		(drill 0.254)
		(layers "F.Cu" "B.Cu")
		(net "GND")
	)
	(via
		(at 464.20151 -45.510196)
		(size 0.508)
		(drill 0.254)
		(layers "F.Cu" "B.Cu")
		(net "GND")
	)
	(via
		(at 392.69035 -102.756716)
		(size 0.508)
		(drill 0.254)
		(layers "F.Cu" "B.Cu")
		(net "GND")
	)
	(via
		(at 404.18258 -23.86076)
		(size 0.508)
		(drill 0.254)
		(layers "F.Cu" "B.Cu")
		(net "GND")
	)
	(via
		(at 242.480338 -76.39304)
		(size 0.508)
		(drill 0.254)
		(layers "F.Cu" "B.Cu")
		(net "GND")
	)
	(via
		(at 238.187738 -68.963286)
		(size 0.508)
		(drill 0.254)
		(layers "F.Cu" "B.Cu")
		(net "GND")
	)
	(via
		(at 118.783862 -93.547184)
		(size 0.508)
		(drill 0.254)
		(layers "F.Cu" "B.Cu")
		(net "GND")
	)
	(via
		(at 40.635682 -70.232778)
		(size 0.5588)
		(drill 0.3048)
		(layers "F.Cu" "B.Cu")
		(net "GND")
	)
	(via
		(at 273.197828 -60.362338)
		(size 0.508)
		(drill 0.254)
		(layers "F.Cu" "B.Cu")
		(net "GND")
	)
	(via
		(at 482.6254 -36.8554)
		(size 0.508)
		(drill 0.254)
		(layers "F.Cu" "B.Cu")
		(net "GND")
	)
	(via
		(at 300.099984 -9.156446)
		(size 0.508)
		(drill 0.254)
		(layers "F.Cu" "B.Cu")
		(net "GND")
	)
	(via
		(at 496.041934 12.894056)
		(size 0.5588)
		(drill 0.3048)
		(layers "F.Cu" "B.Cu")
		(net "GND")
	)
	(via
		(at 187.4012 -14.1732)
		(size 0.508)
		(drill 0.254)
		(layers "F.Cu" "B.Cu")
		(net "GND")
	)
	(via
		(at 391.77595 -130.0988)
		(size 0.508)
		(drill 0.254)
		(layers "F.Cu" "B.Cu")
		(net "GND")
	)
	(via
		(at 124.049536 -2.314956)
		(size 0.508)
		(drill 0.254)
		(layers "F.Cu" "B.Cu")
		(net "GND")
	)
	(via
		(at 44.098718 -7.1501)
		(size 0.508)
		(drill 0.254)
		(layers "F.Cu" "B.Cu")
		(net "GND")
	)
	(via
		(at 281.208734 -90.080338)
		(size 0.508)
		(drill 0.254)
		(layers "F.Cu" "B.Cu")
		(net "GND")
	)
	(via
		(at 263.08431 -60.54344)
		(size 0.508)
		(drill 0.254)
		(layers "F.Cu" "B.Cu")
		(net "GND")
	)
	(via
		(at 134.15137 -7.607046)
		(size 0.508)
		(drill 0.254)
		(layers "F.Cu" "B.Cu")
		(net "GND")
	)
	(via
		(at 491.520734 -166.714424)
		(size 0.5588)
		(drill 0.3048)
		(layers "F.Cu" "B.Cu")
		(net "GND")
	)
	(via
		(at 119.34063 -143.950944)
		(size 0.508)
		(drill 0.254)
		(layers "F.Cu" "B.Cu")
		(net "GND")
	)
	(via
		(at 234.560872 -130.991356)
		(size 0.508)
		(drill 0.254)
		(layers "F.Cu" "B.Cu")
		(net "GND")
	)
	(via
		(at 47.549308 -13.363956)
		(size 0.508)
		(drill 0.254)
		(layers "F.Cu" "B.Cu")
		(net "GND")
	)
	(via
		(at 135.095234 -83.146138)
		(size 0.508)
		(drill 0.254)
		(layers "F.Cu" "B.Cu")
		(net "GND")
	)
	(via
		(at 401.3962 -143.002)
		(size 0.508)
		(drill 0.254)
		(layers "F.Cu" "B.Cu")
		(net "GND")
	)
	(via
		(at 262.22579 -63.019686)
		(size 0.508)
		(drill 0.254)
		(layers "F.Cu" "B.Cu")
		(net "GND")
	)
	(via
		(at 204.623924 -162.243262)
		(size 0.5588)
		(drill 0.3048)
		(layers "F.Cu" "B.Cu")
		(net "GND")
	)
	(via
		(at 216.641934 9.084056)
		(size 0.5588)
		(drill 0.3048)
		(layers "F.Cu" "B.Cu")
		(net "GND")
	)
	(via
		(at 38.15715 -60.183522)
		(size 0.5588)
		(drill 0.3048)
		(layers "F.Cu" "B.Cu")
		(net "GND")
	)
	(via
		(at 169.561764 -155.10002)
		(size 0.5588)
		(drill 0.3048)
		(layers "F.Cu" "B.Cu")
		(net "GND")
	)
	(via
		(at 452.742808 -60.378848)
		(size 0.508)
		(drill 0.254)
		(layers "F.Cu" "B.Cu")
		(net "GND")
	)
	(via
		(at 460.601822 -15.111222)
		(size 0.5588)
		(drill 0.3048)
		(layers "F.Cu" "B.Cu")
		(net "GND")
	)
	(via
		(at 354.513134 -167.857424)
		(size 0.5588)
		(drill 0.3048)
		(layers "F.Cu" "B.Cu")
		(net "GND")
	)
	(via
		(at 322.5292 1.478788)
		(size 0.508)
		(drill 0.254)
		(layers "F.Cu" "B.Cu")
		(net "GND")
	)
	(via
		(at 292.392608 -129.564892)
		(size 0.508)
		(drill 0.254)
		(layers "F.Cu" "B.Cu")
		(net "GND")
	)
	(via
		(at 381.556768 -41.877234)
		(size 0.508)
		(drill 0.254)
		(layers "F.Cu" "B.Cu")
		(net "GND")
	)
	(via
		(at 455.401934 10.354056)
		(size 0.5588)
		(drill 0.3048)
		(layers "F.Cu" "B.Cu")
		(net "GND")
	)
	(via
		(at 66.249296 -140.617956)
		(size 0.508)
		(drill 0.254)
		(layers "F.Cu" "B.Cu")
		(net "GND")
	)
	(via
		(at 346.181934 9.084056)
		(size 0.5588)
		(drill 0.3048)
		(layers "F.Cu" "B.Cu")
		(net "GND")
	)
	(via
		(at 346.21216 -16.93164)
		(size 0.508)
		(drill 0.254)
		(layers "F.Cu" "B.Cu")
		(net "GND")
	)
	(via
		(at 292.36924 -69.772784)
		(size 0.508)
		(drill 0.254)
		(layers "F.Cu" "B.Cu")
		(net "GND")
	)
	(via
		(at 447.8782 -63.5254)
		(size 0.508)
		(drill 0.254)
		(layers "F.Cu" "B.Cu")
		(net "GND")
	)
	(via
		(at 329.795124 -162.243262)
		(size 0.5588)
		(drill 0.3048)
		(layers "F.Cu" "B.Cu")
		(net "GND")
	)
	(via
		(at 58.599324 -140.617956)
		(size 0.508)
		(drill 0.254)
		(layers "F.Cu" "B.Cu")
		(net "GND")
	)
	(via
		(at 53.442108 -11.912092)
		(size 0.508)
		(drill 0.254)
		(layers "F.Cu" "B.Cu")
		(net "GND")
	)
	(via
		(at 436.121556 -35.433)
		(size 0.4572)
		(drill 0.2032)
		(layers "F.Cu" "B.Cu")
		(net "GND")
	)
	(via
		(at 184.3151 -39.37)
		(size 0.508)
		(drill 0.254)
		(layers "F.Cu" "B.Cu")
		(net "GND")
	)
	(via
		(at 375.391934 9.084056)
		(size 0.5588)
		(drill 0.3048)
		(layers "F.Cu" "B.Cu")
		(net "GND")
	)
	(via
		(at 240.390934 -167.832024)
		(size 0.5588)
		(drill 0.3048)
		(layers "F.Cu" "B.Cu")
		(net "GND")
	)
	(via
		(at 454.53935 -124.92482)
		(size 0.508)
		(drill 0.254)
		(layers "F.Cu" "B.Cu")
		(net "GND")
	)
	(via
		(at 381.764032 -157.484572)
		(size 0.508)
		(drill 0.254)
		(layers "F.Cu" "B.Cu")
		(net "GND")
	)
	(via
		(at 129.085848 -84.631784)
		(size 0.508)
		(drill 0.254)
		(layers "F.Cu" "B.Cu")
		(net "GND")
	)
	(via
		(at 290.6522 -64.819784)
		(size 0.508)
		(drill 0.254)
		(layers "F.Cu" "B.Cu")
		(net "GND")
	)
	(via
		(at 140.920724 -162.243262)
		(size 0.5588)
		(drill 0.3048)
		(layers "F.Cu" "B.Cu")
		(net "GND")
	)
	(via
		(at 250.206764 -94.718886)
		(size 0.508)
		(drill 0.254)
		(layers "F.Cu" "B.Cu")
		(net "GND")
	)
	(via
		(at 171.099734 -167.832024)
		(size 0.5588)
		(drill 0.3048)
		(layers "F.Cu" "B.Cu")
		(net "GND")
	)
	(via
		(at 471.200734 -163.361624)
		(size 0.5588)
		(drill 0.3048)
		(layers "F.Cu" "B.Cu")
		(net "GND")
	)
	(via
		(at 352.277934 -167.857424)
		(size 0.5588)
		(drill 0.3048)
		(layers "F.Cu" "B.Cu")
		(net "GND")
	)
	(via
		(at 4.07162 -24.08936)
		(size 0.508)
		(drill 0.254)
		(layers "F.Cu" "B.Cu")
		(net "GND")
	)
	(via
		(at 330.941934 14.926056)
		(size 0.5588)
		(drill 0.3048)
		(layers "F.Cu" "B.Cu")
		(net "GND")
	)
	(via
		(at 230.399844 -148.771356)
		(size 0.508)
		(drill 0.254)
		(layers "F.Cu" "B.Cu")
		(net "GND")
	)
	(via
		(at 452.50354 -138.775948)
		(size 0.508)
		(drill 0.254)
		(layers "F.Cu" "B.Cu")
		(net "GND")
	)
	(via
		(at 271.841468 -149.8092)
		(size 0.508)
		(drill 0.254)
		(layers "F.Cu" "B.Cu")
		(net "GND")
	)
	(via
		(at 4.577334 -166.714424)
		(size 0.5588)
		(drill 0.3048)
		(layers "F.Cu" "B.Cu")
		(net "GND")
	)
	(via
		(at 96.74479 -69.564504)
		(size 0.5588)
		(drill 0.3048)
		(layers "F.Cu" "B.Cu")
		(net "GND")
	)
	(via
		(at 280.924254 -66.800984)
		(size 0.508)
		(drill 0.254)
		(layers "F.Cu" "B.Cu")
		(net "GND")
	)
	(via
		(at 376.428 -103.354886)
		(size 0.508)
		(drill 0.254)
		(layers "F.Cu" "B.Cu")
		(net "GND")
	)
	(via
		(at 200.884028 -56.317642)
		(size 0.508)
		(drill 0.254)
		(layers "F.Cu" "B.Cu")
		(net "GND")
	)
	(via
		(at 345.062048 -94.435168)
		(size 0.508)
		(drill 0.254)
		(layers "F.Cu" "B.Cu")
		(net "GND")
	)
	(via
		(at 240.763298 -98.18624)
		(size 0.508)
		(drill 0.254)
		(layers "F.Cu" "B.Cu")
		(net "GND")
	)
	(via
		(at 151.871934 14.926056)
		(size 0.5588)
		(drill 0.3048)
		(layers "F.Cu" "B.Cu")
		(net "GND")
	)
	(via
		(at 274.056348 -57.885584)
		(size 0.508)
		(drill 0.254)
		(layers "F.Cu" "B.Cu")
		(net "GND")
	)
	(via
		(at 5.832856 10.256266)
		(size 0.5588)
		(drill 0.3048)
		(layers "F.Cu" "B.Cu")
		(net "GND")
	)
	(via
		(at 483.888796 -50.333402)
		(size 0.508)
		(drill 0.254)
		(layers "F.Cu" "B.Cu")
		(net "GND")
	)
	(via
		(at 49.24933 -131.016756)
		(size 0.508)
		(drill 0.254)
		(layers "F.Cu" "B.Cu")
		(net "GND")
	)
	(via
		(at 450.99986 -113.8174)
		(size 0.508)
		(drill 0.254)
		(layers "F.Cu" "B.Cu")
		(net "GND")
	)
	(via
		(at 112.501934 14.926056)
		(size 0.5588)
		(drill 0.3048)
		(layers "F.Cu" "B.Cu")
		(net "GND")
	)
	(via
		(at 131.661408 -55.409338)
		(size 0.508)
		(drill 0.254)
		(layers "F.Cu" "B.Cu")
		(net "GND")
	)
	(via
		(at 284.642814 -93.052138)
		(size 0.508)
		(drill 0.254)
		(layers "F.Cu" "B.Cu")
		(net "GND")
	)
	(via
		(at 209.092546 -18.744946)
		(size 0.508)
		(drill 0.254)
		(layers "F.Cu" "B.Cu")
		(net "GND")
	)
	(via
		(at 448.340734 -165.596824)
		(size 0.5588)
		(drill 0.3048)
		(layers "F.Cu" "B.Cu")
		(net "GND")
	)
	(via
		(at 286.93364 -52.437538)
		(size 0.508)
		(drill 0.254)
		(layers "F.Cu" "B.Cu")
		(net "GND")
	)
	(via
		(at 353.395534 -167.857424)
		(size 0.5588)
		(drill 0.3048)
		(layers "F.Cu" "B.Cu")
		(net "GND")
	)
	(via
		(at 76.449428 0.444754)
		(size 0.508)
		(drill 0.254)
		(layers "F.Cu" "B.Cu")
		(net "GND")
	)
	(via
		(at 279.699974 -136.397746)
		(size 0.508)
		(drill 0.254)
		(layers "F.Cu" "B.Cu")
		(net "GND")
	)
	(via
		(at 74.904346 -57.076086)
		(size 0.508)
		(drill 0.254)
		(layers "F.Cu" "B.Cu")
		(net "GND")
	)
	(via
		(at 306.899818 -140.617956)
		(size 0.508)
		(drill 0.254)
		(layers "F.Cu" "B.Cu")
		(net "GND")
	)
	(via
		(at 486.440734 -166.714424)
		(size 0.5588)
		(drill 0.3048)
		(layers "F.Cu" "B.Cu")
		(net "GND")
	)
	(via
		(at 256.011934 14.926056)
		(size 0.5588)
		(drill 0.3048)
		(layers "F.Cu" "B.Cu")
		(net "GND")
	)
	(via
		(at 34.74212 -155.600146)
		(size 0.508)
		(drill 0.254)
		(layers "F.Cu" "B.Cu")
		(net "GND")
	)
	(via
		(at 8.819134 9.084056)
		(size 0.5588)
		(drill 0.3048)
		(layers "F.Cu" "B.Cu")
		(net "GND")
	)
	(via
		(at 322.3387 -123.6091)
		(size 0.508)
		(drill 0.254)
		(layers "F.Cu" "B.Cu")
		(net "GND")
	)
	(via
		(at 466.120734 -165.596824)
		(size 0.5588)
		(drill 0.3048)
		(layers "F.Cu" "B.Cu")
		(net "GND")
	)
	(via
		(at 141.049502 -139.170156)
		(size 0.508)
		(drill 0.254)
		(layers "F.Cu" "B.Cu")
		(net "GND")
	)
	(via
		(at 276.916134 -93.547184)
		(size 0.508)
		(drill 0.254)
		(layers "F.Cu" "B.Cu")
		(net "GND")
	)
	(via
		(at 255.815338 -139.829794)
		(size 0.508)
		(drill 0.254)
		(layers "F.Cu" "B.Cu")
		(net "GND")
	)
	(via
		(at 339.857334 -167.832024)
		(size 0.5588)
		(drill 0.3048)
		(layers "F.Cu" "B.Cu")
		(net "GND")
	)
	(via
		(at 147.368768 -9.0805)
		(size 0.508)
		(drill 0.254)
		(layers "F.Cu" "B.Cu")
		(net "GND")
	)
	(via
		(at 111.631222 -54.418738)
		(size 0.508)
		(drill 0.254)
		(layers "F.Cu" "B.Cu")
		(net "GND")
	)
	(via
		(at 377.931934 9.084056)
		(size 0.5588)
		(drill 0.3048)
		(layers "F.Cu" "B.Cu")
		(net "GND")
	)
	(via
		(at 0.381 -147.0914)
		(size 0.508)
		(drill 0.254)
		(layers "F.Cu" "B.Cu")
		(net "GND")
	)
	(via
		(at 289.79368 -89.089738)
		(size 0.508)
		(drill 0.254)
		(layers "F.Cu" "B.Cu")
		(net "GND")
	)
	(via
		(at 168.5798 -16.6624)
		(size 0.508)
		(drill 0.254)
		(layers "F.Cu" "B.Cu")
		(net "GND")
	)
	(via
		(at 390.70915 -120.387364)
		(size 0.508)
		(drill 0.254)
		(layers "F.Cu" "B.Cu")
		(net "GND")
	)
	(via
		(at 301.749206 -134.4041)
		(size 0.508)
		(drill 0.254)
		(layers "F.Cu" "B.Cu")
		(net "GND")
	)
	(via
		(at 328.681334 -167.832024)
		(size 0.5588)
		(drill 0.3048)
		(layers "F.Cu" "B.Cu")
		(net "GND")
	)
	(via
		(at 499.851934 11.624056)
		(size 0.5588)
		(drill 0.3048)
		(layers "F.Cu" "B.Cu")
		(net "GND")
	)
	(via
		(at 74.749406 -139.170156)
		(size 0.508)
		(drill 0.254)
		(layers "F.Cu" "B.Cu")
		(net "GND")
	)
	(via
		(at 195.21424 -61.98997)
		(size 0.508)
		(drill 0.254)
		(layers "F.Cu" "B.Cu")
		(net "GND")
	)
	(via
		(at 35.8648 -72.6694)
		(size 0.508)
		(drill 0.254)
		(layers "F.Cu" "B.Cu")
		(net "GND")
	)
	(via
		(at 385.985004 -92.917518)
		(size 0.508)
		(drill 0.254)
		(layers "F.Cu" "B.Cu")
		(net "GND")
	)
	(via
		(at 129.999486 -139.170156)
		(size 0.508)
		(drill 0.254)
		(layers "F.Cu" "B.Cu")
		(net "GND")
	)
	(via
		(at 485.881934 12.894056)
		(size 0.5588)
		(drill 0.3048)
		(layers "F.Cu" "B.Cu")
		(net "GND")
	)
	(via
		(at 200.5076 -75.2348)
		(size 0.508)
		(drill 0.254)
		(layers "F.Cu" "B.Cu")
		(net "GND")
	)
	(via
		(at 423.672 -105.7148)
		(size 0.508)
		(drill 0.254)
		(layers "F.Cu" "B.Cu")
		(net "GND")
	)
	(via
		(at 293.681912 -139.1666)
		(size 0.508)
		(drill 0.254)
		(layers "F.Cu" "B.Cu")
		(net "GND")
	)
	(via
		(at 25.9334 -18.7452)
		(size 0.508)
		(drill 0.254)
		(layers "F.Cu" "B.Cu")
		(net "GND")
	)
	(via
		(at 300.954186 -60.857384)
		(size 0.508)
		(drill 0.254)
		(layers "F.Cu" "B.Cu")
		(net "GND")
	)
	(via
		(at 72.1487 -144.0053)
		(size 0.508)
		(drill 0.254)
		(layers "F.Cu" "B.Cu")
		(net "GND")
	)
	(via
		(at 131.699508 -139.170156)
		(size 0.508)
		(drill 0.254)
		(layers "F.Cu" "B.Cu")
		(net "GND")
	)
	(via
		(at 165.8874 -149.098)
		(size 0.508)
		(drill 0.254)
		(layers "F.Cu" "B.Cu")
		(net "GND")
	)
	(via
		(at 301.749206 -153.6065)
		(size 0.508)
		(drill 0.254)
		(layers "F.Cu" "B.Cu")
		(net "GND")
	)
	(via
		(at 448.818 -143.129)
		(size 0.508)
		(drill 0.254)
		(layers "F.Cu" "B.Cu")
		(net "GND")
	)
	(via
		(at 476.280734 -166.714424)
		(size 0.5588)
		(drill 0.3048)
		(layers "F.Cu" "B.Cu")
		(net "GND")
	)
	(via
		(at 86.923372 -87.784686)
		(size 0.508)
		(drill 0.254)
		(layers "F.Cu" "B.Cu")
		(net "GND")
	)
	(via
		(at 240.763298 -67.47764)
		(size 0.508)
		(drill 0.254)
		(layers "F.Cu" "B.Cu")
		(net "GND")
	)
	(via
		(at 120.500902 -94.538038)
		(size 0.508)
		(drill 0.254)
		(layers "F.Cu" "B.Cu")
		(net "GND")
	)
	(via
		(at 346.216986 -79.886556)
		(size 0.508)
		(drill 0.254)
		(layers "F.Cu" "B.Cu")
		(net "GND")
	)
	(via
		(at 318.5922 -26.7208)
		(size 0.508)
		(drill 0.254)
		(layers "F.Cu" "B.Cu")
		(net "GND")
	)
	(via
		(at 201.037952 -23.549356)
		(size 0.508)
		(drill 0.254)
		(layers "F.Cu" "B.Cu")
		(net "GND")
	)
	(via
		(at 413.491934 9.084056)
		(size 0.5588)
		(drill 0.3048)
		(layers "F.Cu" "B.Cu")
		(net "GND")
	)
	(via
		(at 337.8454 -40.64)
		(size 0.508)
		(drill 0.254)
		(layers "F.Cu" "B.Cu")
		(net "GND")
	)
	(via
		(at 292.399212 -134.4041)
		(size 0.508)
		(drill 0.254)
		(layers "F.Cu" "B.Cu")
		(net "GND")
	)
	(via
		(at 73.440798 -26.682954)
		(size 0.508)
		(drill 0.254)
		(layers "F.Cu" "B.Cu")
		(net "GND")
	)
	(via
		(at 395.16685 -116.094764)
		(size 0.508)
		(drill 0.254)
		(layers "F.Cu" "B.Cu")
		(net "GND")
	)
	(via
		(at 59.256168 -125.9586)
		(size 0.508)
		(drill 0.254)
		(layers "F.Cu" "B.Cu")
		(net "GND")
	)
	(via
		(at 450.321934 9.084056)
		(size 0.5588)
		(drill 0.3048)
		(layers "F.Cu" "B.Cu")
		(net "GND")
	)
	(via
		(at 293.688008 -131.600956)
		(size 0.508)
		(drill 0.254)
		(layers "F.Cu" "B.Cu")
		(net "GND")
	)
	(via
		(at 300.954186 -65.810384)
		(size 0.508)
		(drill 0.254)
		(layers "F.Cu" "B.Cu")
		(net "GND")
	)
	(via
		(at 430.560734 -167.832024)
		(size 0.5588)
		(drill 0.3048)
		(layers "F.Cu" "B.Cu")
		(net "GND")
	)
	(via
		(at 457.2 -20.32)
		(size 0.508)
		(drill 0.254)
		(layers "F.Cu" "B.Cu")
		(net "GND")
	)
	(via
		(at 39.049452 -2.314956)
		(size 0.508)
		(drill 0.254)
		(layers "F.Cu" "B.Cu")
		(net "GND")
	)
	(via
		(at 233.799888 -136.397746)
		(size 0.508)
		(drill 0.254)
		(layers "F.Cu" "B.Cu")
		(net "GND")
	)
	(via
		(at 463.580734 -166.714424)
		(size 0.5588)
		(drill 0.3048)
		(layers "F.Cu" "B.Cu")
		(net "GND")
	)
	(via
		(at 34.752534 -167.832024)
		(size 0.5588)
		(drill 0.3048)
		(layers "F.Cu" "B.Cu")
		(net "GND")
	)
	(via
		(at 170.921934 9.084056)
		(size 0.5588)
		(drill 0.3048)
		(layers "F.Cu" "B.Cu")
		(net "GND")
	)
	(via
		(at 411.510734 -166.714424)
		(size 0.5588)
		(drill 0.3048)
		(layers "F.Cu" "B.Cu")
		(net "GND")
	)
	(via
		(at 314.54979 -154.063446)
		(size 0.508)
		(drill 0.254)
		(layers "F.Cu" "B.Cu")
		(net "GND")
	)
	(via
		(at 476.931482 4.42595)
		(size 0.5588)
		(drill 0.3048)
		(layers "F.Cu" "B.Cu")
		(net "GND")
	)
	(via
		(at 256.033524 -162.243262)
		(size 0.5588)
		(drill 0.3048)
		(layers "F.Cu" "B.Cu")
		(net "GND")
	)
	(via
		(at 445.800734 -167.832024)
		(size 0.5588)
		(drill 0.3048)
		(layers "F.Cu" "B.Cu")
		(net "GND")
	)
	(via
		(at 445.241934 11.624056)
		(size 0.5588)
		(drill 0.3048)
		(layers "F.Cu" "B.Cu")
		(net "GND")
	)
	(via
		(at 86.064852 -88.28024)
		(size 0.508)
		(drill 0.254)
		(layers "F.Cu" "B.Cu")
		(net "GND")
	)
	(via
		(at 82.630772 -92.24264)
		(size 0.508)
		(drill 0.254)
		(layers "F.Cu" "B.Cu")
		(net "GND")
	)
	(via
		(at 342.431116 4.041394)
		(size 0.508)
		(drill 0.254)
		(layers "F.Cu" "B.Cu")
		(net "GND")
	)
	(via
		(at 346.395294 -154.958542)
		(size 0.508)
		(drill 0.254)
		(layers "F.Cu" "B.Cu")
		(net "GND")
	)
	(via
		(at 146.092164 -9.143746)
		(size 0.508)
		(drill 0.254)
		(layers "F.Cu" "B.Cu")
		(net "GND")
	)
	(via
		(at 272.052288 -50.694082)
		(size 0.508)
		(drill 0.254)
		(layers "F.Cu" "B.Cu")
		(net "GND")
	)
	(via
		(at 39.219124 -162.243262)
		(size 0.5588)
		(drill 0.3048)
		(layers "F.Cu" "B.Cu")
		(net "GND")
	)
	(via
		(at 126.510288 -93.052138)
		(size 0.508)
		(drill 0.254)
		(layers "F.Cu" "B.Cu")
		(net "GND")
	)
	(via
		(at 290.6522 -62.838584)
		(size 0.508)
		(drill 0.254)
		(layers "F.Cu" "B.Cu")
		(net "GND")
	)
	(via
		(at 66.249296 -13.363956)
		(size 0.508)
		(drill 0.254)
		(layers "F.Cu" "B.Cu")
		(net "GND")
	)
	(via
		(at 436.351934 9.084056)
		(size 0.5588)
		(drill 0.3048)
		(layers "F.Cu" "B.Cu")
		(net "GND")
	)
	(via
		(at 447.781934 9.084056)
		(size 0.5588)
		(drill 0.3048)
		(layers "F.Cu" "B.Cu")
		(net "GND")
	)
	(via
		(at 84.347812 -88.28024)
		(size 0.508)
		(drill 0.254)
		(layers "F.Cu" "B.Cu")
		(net "GND")
	)
	(via
		(at 106.297476 -82.339942)
		(size 0.5588)
		(drill 0.3048)
		(layers "F.Cu" "B.Cu")
		(net "GND")
	)
	(via
		(at 45.394118 -136.3345)
		(size 0.508)
		(drill 0.254)
		(layers "F.Cu" "B.Cu")
		(net "GND")
	)
	(via
		(at 62.792102 -21.513292)
		(size 0.508)
		(drill 0.254)
		(layers "F.Cu" "B.Cu")
		(net "GND")
	)
	(via
		(at 241.44986 -2.314956)
		(size 0.508)
		(drill 0.254)
		(layers "F.Cu" "B.Cu")
		(net "GND")
	)
	(via
		(at 70.461378 -129.568956)
		(size 0.508)
		(drill 0.254)
		(layers "F.Cu" "B.Cu")
		(net "GND")
	)
	(via
		(at 304.388266 -86.612984)
		(size 0.508)
		(drill 0.254)
		(layers "F.Cu" "B.Cu")
		(net "GND")
	)
	(via
		(at 121.499376 -3.762756)
		(size 0.508)
		(drill 0.254)
		(layers "F.Cu" "B.Cu")
		(net "GND")
	)
	(via
		(at 243.205 -150.114)
		(size 0.508)
		(drill 0.254)
		(layers "F.Cu" "B.Cu")
		(net "GND")
	)
	(via
		(at 41.461182 -78.449678)
		(size 0.5588)
		(drill 0.3048)
		(layers "F.Cu" "B.Cu")
		(net "GND")
	)
	(via
		(at 338.735924 -162.243262)
		(size 0.5588)
		(drill 0.3048)
		(layers "F.Cu" "B.Cu")
		(net "GND")
	)
	(via
		(at 137.670794 -62.838584)
		(size 0.508)
		(drill 0.254)
		(layers "F.Cu" "B.Cu")
		(net "GND")
	)
	(via
		(at 408.10942 -21.39442)
		(size 0.508)
		(drill 0.254)
		(layers "F.Cu" "B.Cu")
		(net "GND")
	)
	(via
		(at 445.694562 -21.349462)
		(size 0.508)
		(drill 0.254)
		(layers "F.Cu" "B.Cu")
		(net "GND")
	)
	(via
		(at 487.151934 12.894056)
		(size 0.5588)
		(drill 0.3048)
		(layers "F.Cu" "B.Cu")
		(net "GND")
	)
	(via
		(at 74.045826 -52.618386)
		(size 0.508)
		(drill 0.254)
		(layers "F.Cu" "B.Cu")
		(net "GND")
	)
	(via
		(at 472.69273 -21.465286)
		(size 0.508)
		(drill 0.254)
		(layers "F.Cu" "B.Cu")
		(net "GND")
	)
	(via
		(at 13.5636 -70.505828)
		(size 0.508)
		(drill 0.254)
		(layers "F.Cu" "B.Cu")
		(net "GND")
	)
	(via
		(at 52.471574 -22.965156)
		(size 0.508)
		(drill 0.254)
		(layers "F.Cu" "B.Cu")
		(net "GND")
	)
	(via
		(at 227.792534 -145.998946)
		(size 0.508)
		(drill 0.254)
		(layers "F.Cu" "B.Cu")
		(net "GND")
	)
	(via
		(at 210.39455 -136.3345)
		(size 0.508)
		(drill 0.254)
		(layers "F.Cu" "B.Cu")
		(net "GND")
	)
	(via
		(at 302.671226 -69.772784)
		(size 0.508)
		(drill 0.254)
		(layers "F.Cu" "B.Cu")
		(net "GND")
	)
	(via
		(at 31.39948 -2.314956)
		(size 0.508)
		(drill 0.254)
		(layers "F.Cu" "B.Cu")
		(net "GND")
	)
	(via
		(at 84.561934 9.084056)
		(size 0.5588)
		(drill 0.3048)
		(layers "F.Cu" "B.Cu")
		(net "GND")
	)
	(via
		(at 216.921334 -167.832024)
		(size 0.5588)
		(drill 0.3048)
		(layers "F.Cu" "B.Cu")
		(net "GND")
	)
	(via
		(at 246.479568 -51.617626)
		(size 0.4572)
		(drill 0.2032)
		(layers "F.Cu" "B.Cu")
		(net "GND")
	)
	(via
		(at 352.056192 -78.81874)
		(size 0.508)
		(drill 0.254)
		(layers "F.Cu" "B.Cu")
		(net "GND")
	)
	(via
		(at 48.399446 -9.156446)
		(size 0.508)
		(drill 0.254)
		(layers "F.Cu" "B.Cu")
		(net "GND")
	)
	(via
		(at 446.291716 -16.778986)
		(size 0.508)
		(drill 0.254)
		(layers "F.Cu" "B.Cu")
		(net "GND")
	)
	(via
		(at 343.210134 -167.832024)
		(size 0.5588)
		(drill 0.3048)
		(layers "F.Cu" "B.Cu")
		(net "GND")
	)
	(via
		(at 170.2562 -95.4024)
		(size 0.508)
		(drill 0.254)
		(layers "F.Cu" "B.Cu")
		(net "GND")
	)
	(via
		(at 94.649798 -63.51524)
		(size 0.508)
		(drill 0.254)
		(layers "F.Cu" "B.Cu")
		(net "GND")
	)
	(via
		(at 300.095666 -79.183738)
		(size 0.508)
		(drill 0.254)
		(layers "F.Cu" "B.Cu")
		(net "GND")
	)
	(via
		(at 122.349514 -129.568956)
		(size 0.508)
		(drill 0.254)
		(layers "F.Cu" "B.Cu")
		(net "GND")
	)
	(via
		(at 40.749474 -2.314956)
		(size 0.508)
		(drill 0.254)
		(layers "F.Cu" "B.Cu")
		(net "GND")
	)
	(via
		(at 430.38014 -126.95682)
		(size 0.508)
		(drill 0.254)
		(layers "F.Cu" "B.Cu")
		(net "GND")
	)
	(via
		(at 345.076272 -99.28479)
		(size 0.508)
		(drill 0.254)
		(layers "F.Cu" "B.Cu")
		(net "GND")
	)
	(via
		(at 76.449428 -139.170156)
		(size 0.508)
		(drill 0.254)
		(layers "F.Cu" "B.Cu")
		(net "GND")
	)
	(via
		(at 57.74944 0.444754)
		(size 0.508)
		(drill 0.254)
		(layers "F.Cu" "B.Cu")
		(net "GND")
	)
	(via
		(at 406.426924 -162.243262)
		(size 0.5588)
		(drill 0.3048)
		(layers "F.Cu" "B.Cu")
		(net "GND")
	)
	(via
		(at 243.311934 14.926056)
		(size 0.5588)
		(drill 0.3048)
		(layers "F.Cu" "B.Cu")
		(net "GND")
	)
	(via
		(at 213.399878 -9.156446)
		(size 0.508)
		(drill 0.254)
		(layers "F.Cu" "B.Cu")
		(net "GND")
	)
	(via
		(at 111.631222 -60.362338)
		(size 0.508)
		(drill 0.254)
		(layers "F.Cu" "B.Cu")
		(net "GND")
	)
	(via
		(at 272.521934 14.926056)
		(size 0.5588)
		(drill 0.3048)
		(layers "F.Cu" "B.Cu")
		(net "GND")
	)
	(via
		(at 352.823272 -19.953224)
		(size 0.508)
		(drill 0.254)
		(layers "F.Cu" "B.Cu")
		(net "GND")
	)
	(via
		(at 0.653796 -56.886602)
		(size 0.5588)
		(drill 0.3048)
		(layers "F.Cu" "B.Cu")
		(net "GND")
	)
	(via
		(at 263.856724 -162.243262)
		(size 0.5588)
		(drill 0.3048)
		(layers "F.Cu" "B.Cu")
		(net "GND")
	)
	(via
		(at 135.061452 -11.916156)
		(size 0.508)
		(drill 0.254)
		(layers "F.Cu" "B.Cu")
		(net "GND")
	)
	(via
		(at 86.923372 -95.709486)
		(size 0.508)
		(drill 0.254)
		(layers "F.Cu" "B.Cu")
		(net "GND")
	)
	(via
		(at 234.753658 -60.047886)
		(size 0.508)
		(drill 0.254)
		(layers "F.Cu" "B.Cu")
		(net "GND")
	)
	(via
		(at 85.206332 -94.718886)
		(size 0.508)
		(drill 0.254)
		(layers "F.Cu" "B.Cu")
		(net "GND")
	)
	(via
		(at 299.237146 -72.744584)
		(size 0.508)
		(drill 0.254)
		(layers "F.Cu" "B.Cu")
		(net "GND")
	)
	(via
		(at 155.449524 -162.243262)
		(size 0.5588)
		(drill 0.3048)
		(layers "F.Cu" "B.Cu")
		(net "GND")
	)
	(via
		(at 43.12158 -150.206456)
		(size 0.508)
		(drill 0.254)
		(layers "F.Cu" "B.Cu")
		(net "GND")
	)
	(via
		(at 80.055212 -70.94474)
		(size 0.508)
		(drill 0.254)
		(layers "F.Cu" "B.Cu")
		(net "GND")
	)
	(via
		(at 119.686324 -162.243262)
		(size 0.5588)
		(drill 0.3048)
		(layers "F.Cu" "B.Cu")
		(net "GND")
	)
	(via
		(at 298.247562 -125.929898)
		(size 0.508)
		(drill 0.254)
		(layers "F.Cu" "B.Cu")
		(net "GND")
	)
	(via
		(at 78.204568 -150.114)
		(size 0.508)
		(drill 0.254)
		(layers "F.Cu" "B.Cu")
		(net "GND")
	)
	(via
		(at 211.699856 -136.410446)
		(size 0.508)
		(drill 0.254)
		(layers "F.Cu" "B.Cu")
		(net "GND")
	)
	(via
		(at 67.099434 -18.757646)
		(size 0.508)
		(drill 0.254)
		(layers "F.Cu" "B.Cu")
		(net "GND")
	)
	(via
		(at 84.910168 -145.0086)
		(size 0.508)
		(drill 0.254)
		(layers "F.Cu" "B.Cu")
		(net "GND")
	)
	(via
		(at 61.571124 -162.243262)
		(size 0.5588)
		(drill 0.3048)
		(layers "F.Cu" "B.Cu")
		(net "GND")
	)
	(via
		(at 205.749906 -18.744946)
		(size 0.508)
		(drill 0.254)
		(layers "F.Cu" "B.Cu")
		(net "GND")
	)
	(via
		(at 460.59979 -113.77803)
		(size 0.508)
		(drill 0.254)
		(layers "F.Cu" "B.Cu")
		(net "GND")
	)
	(via
		(at 374.02262 -109.913674)
		(size 0.508)
		(drill 0.254)
		(layers "F.Cu" "B.Cu")
		(net "GND")
	)
	(via
		(at 181.8132 -15.11046)
		(size 0.508)
		(drill 0.254)
		(layers "F.Cu" "B.Cu")
		(net "GND")
	)
	(via
		(at 69.753226 -84.812886)
		(size 0.508)
		(drill 0.254)
		(layers "F.Cu" "B.Cu")
		(net "GND")
	)
	(via
		(at 441.722256 -29.0322)
		(size 0.4572)
		(drill 0.2032)
		(layers "F.Cu" "B.Cu")
		(net "GND")
	)
	(via
		(at 365.689134 -167.857424)
		(size 0.5588)
		(drill 0.3048)
		(layers "F.Cu" "B.Cu")
		(net "GND")
	)
	(via
		(at 301.742602 -145.998946)
		(size 0.508)
		(drill 0.254)
		(layers "F.Cu" "B.Cu")
		(net "GND")
	)
	(via
		(at 238.44123 -16.696944)
		(size 0.508)
		(drill 0.254)
		(layers "F.Cu" "B.Cu")
		(net "GND")
	)
	(via
		(at 46.699424 -9.156446)
		(size 0.508)
		(drill 0.254)
		(layers "F.Cu" "B.Cu")
		(net "GND")
	)
	(via
		(at 436.351934 10.354056)
		(size 0.5588)
		(drill 0.3048)
		(layers "F.Cu" "B.Cu")
		(net "GND")
	)
	(via
		(at 255.87198 -12.613386)
		(size 0.508)
		(drill 0.254)
		(layers "F.Cu" "B.Cu")
		(net "GND")
	)
	(via
		(at 320.781934 9.084056)
		(size 0.5588)
		(drill 0.3048)
		(layers "F.Cu" "B.Cu")
		(net "GND")
	)
	(via
		(at 435.675786 -9.042908)
		(size 0.508)
		(drill 0.254)
		(layers "F.Cu" "B.Cu")
		(net "GND")
	)
	(via
		(at 487.710734 -165.596824)
		(size 0.5588)
		(drill 0.3048)
		(layers "F.Cu" "B.Cu")
		(net "GND")
	)
	(via
		(at 58.599324 -131.016756)
		(size 0.508)
		(drill 0.254)
		(layers "F.Cu" "B.Cu")
		(net "GND")
	)
	(via
		(at 13.335 -17.0688)
		(size 0.508)
		(drill 0.254)
		(layers "F.Cu" "B.Cu")
		(net "GND")
	)
	(via
		(at 142.898114 -84.631784)
		(size 0.508)
		(drill 0.254)
		(layers "F.Cu" "B.Cu")
		(net "GND")
	)
	(via
		(at 480.0092 -147.3708)
		(size 0.508)
		(drill 0.254)
		(layers "F.Cu" "B.Cu")
		(net "GND")
	)
	(via
		(at 275.773134 -58.876438)
		(size 0.508)
		(drill 0.254)
		(layers "F.Cu" "B.Cu")
		(net "GND")
	)
	(via
		(at 317.09995 -148.782278)
		(size 0.508)
		(drill 0.254)
		(layers "F.Cu" "B.Cu")
		(net "GND")
	)
	(via
		(at 27.920696 -100.037392)
		(size 0.508)
		(drill 0.254)
		(layers "F.Cu" "B.Cu")
		(net "GND")
	)
	(via
		(at 293.22776 -85.127338)
		(size 0.508)
		(drill 0.254)
		(layers "F.Cu" "B.Cu")
		(net "GND")
	)
	(via
		(at 484.23576 -45.39488)
		(size 0.508)
		(drill 0.254)
		(layers "F.Cu" "B.Cu")
		(net "GND")
	)
	(via
		(at 289.79368 -74.230738)
		(size 0.508)
		(drill 0.254)
		(layers "F.Cu" "B.Cu")
		(net "GND")
	)
	(via
		(at 111.631222 -61.352938)
		(size 0.508)
		(drill 0.254)
		(layers "F.Cu" "B.Cu")
		(net "GND")
	)
	(via
		(at 4.816856 12.491466)
		(size 0.5588)
		(drill 0.3048)
		(layers "F.Cu" "B.Cu")
		(net "GND")
	)
	(via
		(at 173.6852 -6.313424)
		(size 0.508)
		(drill 0.254)
		(layers "F.Cu" "B.Cu")
		(net "GND")
	)
	(via
		(at 73.4441 -18.6817)
		(size 0.508)
		(drill 0.254)
		(layers "F.Cu" "B.Cu")
		(net "GND")
	)
	(via
		(at 396.270734 -164.479224)
		(size 0.5588)
		(drill 0.3048)
		(layers "F.Cu" "B.Cu")
		(net "GND")
	)
	(via
		(at 35.867594 -57.30621)
		(size 0.508)
		(drill 0.254)
		(layers "F.Cu" "B.Cu")
		(net "GND")
	)
	(via
		(at 247.347232 -51.132232)
		(size 0.508)
		(drill 0.254)
		(layers "F.Cu" "B.Cu")
		(net "GND")
	)
	(via
		(at 238.187738 -80.850486)
		(size 0.508)
		(drill 0.254)
		(layers "F.Cu" "B.Cu")
		(net "GND")
	)
	(via
		(at 242.480338 -67.47764)
		(size 0.508)
		(drill 0.254)
		(layers "F.Cu" "B.Cu")
		(net "GND")
	)
	(via
		(at 342.773 -67.437)
		(size 0.508)
		(drill 0.254)
		(layers "F.Cu" "B.Cu")
		(net "GND")
	)
	(via
		(at 497.870734 -167.832024)
		(size 0.5588)
		(drill 0.3048)
		(layers "F.Cu" "B.Cu")
		(net "GND")
	)
	(via
		(at 311.09666 -4.2926)
		(size 0.508)
		(drill 0.254)
		(layers "F.Cu" "B.Cu")
		(net "GND")
	)
	(via
		(at 473.740734 -167.832024)
		(size 0.5588)
		(drill 0.3048)
		(layers "F.Cu" "B.Cu")
		(net "GND")
	)
	(via
		(at 440.41314 -9.711182)
		(size 0.508)
		(drill 0.254)
		(layers "F.Cu" "B.Cu")
		(net "GND")
	)
	(via
		(at 306.197 -78.688438)
		(size 0.508)
		(drill 0.254)
		(layers "F.Cu" "B.Cu")
		(net "GND")
	)
	(via
		(at 340.9696 -59.679586)
		(size 0.508)
		(drill 0.254)
		(layers "F.Cu" "B.Cu")
		(net "GND")
	)
	(via
		(at 7.087616 -14.298676)
		(size 0.508)
		(drill 0.254)
		(layers "F.Cu" "B.Cu")
		(net "GND")
	)
	(via
		(at 500.410734 -164.479224)
		(size 0.5588)
		(drill 0.3048)
		(layers "F.Cu" "B.Cu")
		(net "GND")
	)
	(via
		(at 84.347812 -86.29904)
		(size 0.508)
		(drill 0.254)
		(layers "F.Cu" "B.Cu")
		(net "GND")
	)
	(via
		(at 76.621386 -58.06694)
		(size 0.508)
		(drill 0.254)
		(layers "F.Cu" "B.Cu")
		(net "GND")
	)
	(via
		(at 183.9468 -16.44142)
		(size 0.508)
		(drill 0.254)
		(layers "F.Cu" "B.Cu")
		(net "GND")
	)
	(via
		(at 344.490294 -8.132318)
		(size 0.508)
		(drill 0.254)
		(layers "F.Cu" "B.Cu")
		(net "GND")
	)
	(via
		(at 86.064852 -60.54344)
		(size 0.508)
		(drill 0.254)
		(layers "F.Cu" "B.Cu")
		(net "GND")
	)
	(via
		(at 1.87452 -23.53818)
		(size 0.508)
		(drill 0.254)
		(layers "F.Cu" "B.Cu")
		(net "GND")
	)
	(via
		(at 306.262786 -52.497228)
		(size 0.508)
		(drill 0.254)
		(layers "F.Cu" "B.Cu")
		(net "GND")
	)
	(via
		(at 198.772018 1.9558)
		(size 0.508)
		(drill 0.254)
		(layers "F.Cu" "B.Cu")
		(net "GND")
	)
	(via
		(at 130.802888 -70.763384)
		(size 0.508)
		(drill 0.254)
		(layers "F.Cu" "B.Cu")
		(net "GND")
	)
	(via
		(at 126.471934 14.926056)
		(size 0.5588)
		(drill 0.3048)
		(layers "F.Cu" "B.Cu")
		(net "GND")
	)
	(via
		(at 278.061674 -88.022684)
		(size 0.508)
		(drill 0.254)
		(layers "F.Cu" "B.Cu")
		(net "GND")
	)
	(via
		(at 261.7216 -6.6421)
		(size 0.508)
		(drill 0.254)
		(layers "F.Cu" "B.Cu")
		(net "GND")
	)
	(via
		(at 176.50714 -18.34388)
		(size 0.508)
		(drill 0.254)
		(layers "F.Cu" "B.Cu")
		(net "GND")
	)
	(via
		(at 172.2882 -23.52802)
		(size 0.508)
		(drill 0.254)
		(layers "F.Cu" "B.Cu")
		(net "GND")
	)
	(via
		(at 494.056924 -162.243262)
		(size 0.5588)
		(drill 0.3048)
		(layers "F.Cu" "B.Cu")
		(net "GND")
	)
	(via
		(at 238.44123 -26.682954)
		(size 0.508)
		(drill 0.254)
		(layers "F.Cu" "B.Cu")
		(net "GND")
	)
	(via
		(at 354.412804 -25.631902)
		(size 0.508)
		(drill 0.254)
		(layers "F.Cu" "B.Cu")
		(net "GND")
	)
	(via
		(at 341.531702 -141.954504)
		(size 0.508)
		(drill 0.254)
		(layers "F.Cu" "B.Cu")
		(net "GND")
	)
	(via
		(at 236.470698 -100.662486)
		(size 0.508)
		(drill 0.254)
		(layers "F.Cu" "B.Cu")
		(net "GND")
	)
	(via
		(at 155.681934 9.084056)
		(size 0.5588)
		(drill 0.3048)
		(layers "F.Cu" "B.Cu")
		(net "GND")
	)
	(via
		(at 180.0606 -149.8219)
		(size 0.508)
		(drill 0.254)
		(layers "F.Cu" "B.Cu")
		(net "GND")
	)
	(via
		(at 138.529314 -57.390538)
		(size 0.508)
		(drill 0.254)
		(layers "F.Cu" "B.Cu")
		(net "GND")
	)
	(via
		(at 352.3107 -156.2989)
		(size 0.508)
		(drill 0.254)
		(layers "F.Cu" "B.Cu")
		(net "GND")
	)
	(via
		(at 6.812534 -164.479224)
		(size 0.5588)
		(drill 0.3048)
		(layers "F.Cu" "B.Cu")
		(net "GND")
	)
	(via
		(at 188.1251 -40.3352)
		(size 0.508)
		(drill 0.254)
		(layers "F.Cu" "B.Cu")
		(net "GND")
	)
	(via
		(at 244.861334 -167.832024)
		(size 0.5588)
		(drill 0.3048)
		(layers "F.Cu" "B.Cu")
		(net "GND")
	)
	(via
		(at 211.699856 -148.771356)
		(size 0.508)
		(drill 0.254)
		(layers "F.Cu" "B.Cu")
		(net "GND")
	)
	(via
		(at 245.914164 -100.167186)
		(size 0.508)
		(drill 0.254)
		(layers "F.Cu" "B.Cu")
		(net "GND")
	)
	(via
		(at 60.210446 -150.193756)
		(size 0.508)
		(drill 0.254)
		(layers "F.Cu" "B.Cu")
		(net "GND")
	)
	(via
		(at 403.861016 -153.795984)
		(size 0.508)
		(drill 0.254)
		(layers "F.Cu" "B.Cu")
		(net "GND")
	)
	(via
		(at 245.914164 -99.17684)
		(size 0.508)
		(drill 0.254)
		(layers "F.Cu" "B.Cu")
		(net "GND")
	)
	(via
		(at 277.774654 -93.052138)
		(size 0.508)
		(drill 0.254)
		(layers "F.Cu" "B.Cu")
		(net "GND")
	)
	(via
		(at 221.04985 0.444754)
		(size 0.508)
		(drill 0.254)
		(layers "F.Cu" "B.Cu")
		(net "GND")
	)
	(via
		(at 62.786006 -13.8938)
		(size 0.508)
		(drill 0.254)
		(layers "F.Cu" "B.Cu")
		(net "GND")
	)
	(via
		(at 273.482308 -94.538038)
		(size 0.508)
		(drill 0.254)
		(layers "F.Cu" "B.Cu")
		(net "GND")
	)
	(via
		(at 282.925774 -96.023938)
		(size 0.508)
		(drill 0.254)
		(layers "F.Cu" "B.Cu")
		(net "GND")
	)
	(via
		(at 402.061934 9.084056)
		(size 0.5588)
		(drill 0.3048)
		(layers "F.Cu" "B.Cu")
		(net "GND")
	)
	(via
		(at 27.023568 -136.398)
		(size 0.508)
		(drill 0.254)
		(layers "F.Cu" "B.Cu")
		(net "GND")
	)
	(via
		(at 237.329218 -62.52464)
		(size 0.508)
		(drill 0.254)
		(layers "F.Cu" "B.Cu")
		(net "GND")
	)
	(via
		(at 356.2858 -12.9794)
		(size 0.508)
		(drill 0.254)
		(layers "F.Cu" "B.Cu")
		(net "GND")
	)
	(via
		(at 363.934502 -155.10002)
		(size 0.5588)
		(drill 0.3048)
		(layers "F.Cu" "B.Cu")
		(net "GND")
	)
	(via
		(at 225.210878 -130.991356)
		(size 0.508)
		(drill 0.254)
		(layers "F.Cu" "B.Cu")
		(net "GND")
	)
	(via
		(at 41.45915 -61.504322)
		(size 0.5588)
		(drill 0.3048)
		(layers "F.Cu" "B.Cu")
		(net "GND")
	)
	(via
		(at 17.653 -81.788)
		(size 0.508)
		(drill 0.254)
		(layers "F.Cu" "B.Cu")
		(net "GND")
	)
	(via
		(at 26.896568 -11.50366)
		(size 0.508)
		(drill 0.254)
		(layers "F.Cu" "B.Cu")
		(net "GND")
	)
	(via
		(at 123.934728 -92.556584)
		(size 0.508)
		(drill 0.254)
		(layers "F.Cu" "B.Cu")
		(net "GND")
	)
	(via
		(at 204.561186 -92.60205)
		(size 0.5588)
		(drill 0.3048)
		(layers "F.Cu" "B.Cu")
		(net "GND")
	)
	(via
		(at 125.274324 -162.243262)
		(size 0.5588)
		(drill 0.3048)
		(layers "F.Cu" "B.Cu")
		(net "GND")
	)
	(via
		(at 187.10275 -61.038232)
		(size 0.508)
		(drill 0.254)
		(layers "F.Cu" "B.Cu")
		(net "GND")
	)
	(via
		(at 232.94975 -3.762756)
		(size 0.508)
		(drill 0.254)
		(layers "F.Cu" "B.Cu")
		(net "GND")
	)
	(via
		(at 487.151934 11.624056)
		(size 0.5588)
		(drill 0.3048)
		(layers "F.Cu" "B.Cu")
		(net "GND")
	)
	(via
		(at 136.8425 -103.1748)
		(size 0.508)
		(drill 0.254)
		(layers "F.Cu" "B.Cu")
		(net "GND")
	)
	(via
		(at 107.623356 -95.033084)
		(size 0.508)
		(drill 0.254)
		(layers "F.Cu" "B.Cu")
		(net "GND")
	)
	(via
		(at 251.065284 -90.26144)
		(size 0.508)
		(drill 0.254)
		(layers "F.Cu" "B.Cu")
		(net "GND")
	)
	(via
		(at 121.359168 -73.240138)
		(size 0.508)
		(drill 0.254)
		(layers "F.Cu" "B.Cu")
		(net "GND")
	)
	(via
		(at 457.350114 -58.954924)
		(size 0.508)
		(drill 0.254)
		(layers "F.Cu" "B.Cu")
		(net "GND")
	)
	(via
		(at 139.806934 -167.832024)
		(size 0.5588)
		(drill 0.3048)
		(layers "F.Cu" "B.Cu")
		(net "GND")
	)
	(via
		(at 349.2754 -38.1)
		(size 0.508)
		(drill 0.254)
		(layers "F.Cu" "B.Cu")
		(net "GND")
	)
	(via
		(at 121.359168 -92.061538)
		(size 0.508)
		(drill 0.254)
		(layers "F.Cu" "B.Cu")
		(net "GND")
	)
	(via
		(at 3.3782 -129.4384)
		(size 0.508)
		(drill 0.254)
		(layers "F.Cu" "B.Cu")
		(net "GND")
	)
	(via
		(at 127.39878 -144.0053)
		(size 0.508)
		(drill 0.254)
		(layers "F.Cu" "B.Cu")
		(net "GND")
	)
	(via
		(at 239.046258 -88.28024)
		(size 0.508)
		(drill 0.254)
		(layers "F.Cu" "B.Cu")
		(net "GND")
	)
	(via
		(at 473.740734 -163.361624)
		(size 0.5588)
		(drill 0.3048)
		(layers "F.Cu" "B.Cu")
		(net "GND")
	)
	(via
		(at 237.034324 -162.243262)
		(size 0.5588)
		(drill 0.3048)
		(layers "F.Cu" "B.Cu")
		(net "GND")
	)
	(via
		(at 163.272724 -162.243262)
		(size 0.5588)
		(drill 0.3048)
		(layers "F.Cu" "B.Cu")
		(net "GND")
	)
	(via
		(at 327.279 -35.433)
		(size 0.508)
		(drill 0.254)
		(layers "F.Cu" "B.Cu")
		(net "GND")
	)
	(via
		(at 126.510288 -81.164938)
		(size 0.508)
		(drill 0.254)
		(layers "F.Cu" "B.Cu")
		(net "GND")
	)
	(via
		(at 76.621386 -98.681286)
		(size 0.508)
		(drill 0.254)
		(layers "F.Cu" "B.Cu")
		(net "GND")
	)
	(via
		(at 118.041928 0.457454)
		(size 0.508)
		(drill 0.254)
		(layers "F.Cu" "B.Cu")
		(net "GND")
	)
	(via
		(at 360.513122 -78.905608)
		(size 0.508)
		(drill 0.254)
		(layers "F.Cu" "B.Cu")
		(net "GND")
	)
	(via
		(at 263.631934 14.926056)
		(size 0.5588)
		(drill 0.3048)
		(layers "F.Cu" "B.Cu")
		(net "GND")
	)
	(via
		(at 243.338604 -97.690686)
		(size 0.508)
		(drill 0.254)
		(layers "F.Cu" "B.Cu")
		(net "GND")
	)
	(via
		(at 353.77247 -91.558364)
		(size 0.508)
		(drill 0.254)
		(layers "F.Cu" "B.Cu")
		(net "GND")
	)
	(via
		(at 257.07467 -65.000886)
		(size 0.508)
		(drill 0.254)
		(layers "F.Cu" "B.Cu")
		(net "GND")
	)
	(via
		(at 132.549392 -3.762756)
		(size 0.508)
		(drill 0.254)
		(layers "F.Cu" "B.Cu")
		(net "GND")
	)
	(via
		(at 186.048396 -87.544402)
		(size 0.508)
		(drill 0.254)
		(layers "F.Cu" "B.Cu")
		(net "GND")
	)
	(via
		(at 19.7231 -45.2501)
		(size 0.508)
		(drill 0.254)
		(layers "F.Cu" "B.Cu")
		(net "GND")
	)
	(via
		(at 313.699906 -129.568956)
		(size 0.508)
		(drill 0.254)
		(layers "F.Cu" "B.Cu")
		(net "GND")
	)
	(via
		(at 455.960734 -167.832024)
		(size 0.5588)
		(drill 0.3048)
		(layers "F.Cu" "B.Cu")
		(net "GND")
	)
	(via
		(at 408.896566 -141.376146)
		(size 0.508)
		(drill 0.254)
		(layers "F.Cu" "B.Cu")
		(net "GND")
	)
	(via
		(at 115.923822 -56.894984)
		(size 0.508)
		(drill 0.254)
		(layers "F.Cu" "B.Cu")
		(net "GND")
	)
	(via
		(at 215.803734 -167.832024)
		(size 0.5588)
		(drill 0.3048)
		(layers "F.Cu" "B.Cu")
		(net "GND")
	)
	(via
		(at 179.919884 -105.628186)
		(size 0.508)
		(drill 0.254)
		(layers "F.Cu" "B.Cu")
		(net "GND")
	)
	(via
		(at 73.437496 -131.600956)
		(size 0.508)
		(drill 0.254)
		(layers "F.Cu" "B.Cu")
		(net "GND")
	)
	(via
		(at 184.510934 -167.832024)
		(size 0.5588)
		(drill 0.3048)
		(layers "F.Cu" "B.Cu")
		(net "GND")
	)
	(via
		(at 341.531702 -142.589504)
		(size 0.508)
		(drill 0.254)
		(layers "F.Cu" "B.Cu")
		(net "GND")
	)
	(via
		(at 200.881234 -55.299864)
		(size 0.508)
		(drill 0.254)
		(layers "F.Cu" "B.Cu")
		(net "GND")
	)
	(via
		(at 92.886022 -79.220822)
		(size 0.5588)
		(drill 0.3048)
		(layers "F.Cu" "B.Cu")
		(net "GND")
	)
	(via
		(at 305.199796 -131.016756)
		(size 0.508)
		(drill 0.254)
		(layers "F.Cu" "B.Cu")
		(net "GND")
	)
	(via
		(at 251.923804 -79.859886)
		(size 0.508)
		(drill 0.254)
		(layers "F.Cu" "B.Cu")
		(net "GND")
	)
	(via
		(at 281.782774 -54.418738)
		(size 0.508)
		(drill 0.254)
		(layers "F.Cu" "B.Cu")
		(net "GND")
	)
	(via
		(at 234.753658 -99.67214)
		(size 0.508)
		(drill 0.254)
		(layers "F.Cu" "B.Cu")
		(net "GND")
	)
	(via
		(at 395.16685 -112.660684)
		(size 0.508)
		(drill 0.254)
		(layers "F.Cu" "B.Cu")
		(net "GND")
	)
	(via
		(at 260.325108 -70.841616)
		(size 0.5588)
		(drill 0.3048)
		(layers "F.Cu" "B.Cu")
		(net "GND")
	)
	(via
		(at 114.72545 -74.101706)
		(size 0.5588)
		(drill 0.3048)
		(layers "F.Cu" "B.Cu")
		(net "GND")
	)
	(via
		(at 453.420734 -165.596824)
		(size 0.5588)
		(drill 0.3048)
		(layers "F.Cu" "B.Cu")
		(net "GND")
	)
	(via
		(at 439.5597 -5.37464)
		(size 0.508)
		(drill 0.254)
		(layers "F.Cu" "B.Cu")
		(net "GND")
	)
	(via
		(at 32.5628 -71.7804)
		(size 0.508)
		(drill 0.254)
		(layers "F.Cu" "B.Cu")
		(net "GND")
	)
	(via
		(at 436.351934 12.894056)
		(size 0.5588)
		(drill 0.3048)
		(layers "F.Cu" "B.Cu")
		(net "GND")
	)
	(via
		(at 291.422074 -131.016756)
		(size 0.508)
		(drill 0.254)
		(layers "F.Cu" "B.Cu")
		(net "GND")
	)
	(via
		(at 41.510458 -13.338556)
		(size 0.508)
		(drill 0.254)
		(layers "F.Cu" "B.Cu")
		(net "GND")
	)
	(via
		(at 86.923372 -65.000886)
		(size 0.508)
		(drill 0.254)
		(layers "F.Cu" "B.Cu")
		(net "GND")
	)
	(via
		(at 135.953754 -59.866784)
		(size 0.508)
		(drill 0.254)
		(layers "F.Cu" "B.Cu")
		(net "GND")
	)
	(via
		(at 16.219932 -24.79548)
		(size 0.508)
		(drill 0.254)
		(layers "F.Cu" "B.Cu")
		(net "GND")
	)
	(via
		(at 169.147744 -93.261434)
		(size 0.508)
		(drill 0.254)
		(layers "F.Cu" "B.Cu")
		(net "GND")
	)
	(via
		(at 70.461378 -18.757646)
		(size 0.508)
		(drill 0.254)
		(layers "F.Cu" "B.Cu")
		(net "GND")
	)
	(via
		(at 295.748202 -124.725176)
		(size 0.508)
		(drill 0.254)
		(layers "F.Cu" "B.Cu")
		(net "GND")
	)
	(via
		(at 282.07208 -13.363956)
		(size 0.508)
		(drill 0.254)
		(layers "F.Cu" "B.Cu")
		(net "GND")
	)
	(via
		(at 206.753714 -94.604078)
		(size 0.5588)
		(drill 0.3048)
		(layers "F.Cu" "B.Cu")
		(net "GND")
	)
	(via
		(at 397.2052 -143.2814)
		(size 0.508)
		(drill 0.254)
		(layers "F.Cu" "B.Cu")
		(net "GND")
	)
	(via
		(at 115.923822 -66.800984)
		(size 0.508)
		(drill 0.254)
		(layers "F.Cu" "B.Cu")
		(net "GND")
	)
	(via
		(at 42.411396 -139.170156)
		(size 0.508)
		(drill 0.254)
		(layers "F.Cu" "B.Cu")
		(net "GND")
	)
	(via
		(at 388.9375 -112.2553)
		(size 0.508)
		(drill 0.254)
		(layers "F.Cu" "B.Cu")
		(net "GND")
	)
	(via
		(at 288.07664 -92.061538)
		(size 0.508)
		(drill 0.254)
		(layers "F.Cu" "B.Cu")
		(net "GND")
	)
	(via
		(at 97.153476 -70.841616)
		(size 0.5588)
		(drill 0.3048)
		(layers "F.Cu" "B.Cu")
		(net "GND")
	)
	(via
		(at 340.3854 -36.83)
		(size 0.508)
		(drill 0.254)
		(layers "F.Cu" "B.Cu")
		(net "GND")
	)
	(via
		(at 79.196692 -70.44944)
		(size 0.508)
		(drill 0.254)
		(layers "F.Cu" "B.Cu")
		(net "GND")
	)
	(via
		(at 481.39985 -115.423188)
		(size 0.508)
		(drill 0.254)
		(layers "F.Cu" "B.Cu")
		(net "GND")
	)
	(via
		(at 488.980734 -167.832024)
		(size 0.5588)
		(drill 0.3048)
		(layers "F.Cu" "B.Cu")
		(net "GND")
	)
	(via
		(at 130.802888 -57.885584)
		(size 0.508)
		(drill 0.254)
		(layers "F.Cu" "B.Cu")
		(net "GND")
	)
	(via
		(at 157.488382 -154.655012)
		(size 0.508)
		(drill 0.254)
		(layers "F.Cu" "B.Cu")
		(net "GND")
	)
	(via
		(at 224.2566 -125.9586)
		(size 0.508)
		(drill 0.254)
		(layers "F.Cu" "B.Cu")
		(net "GND")
	)
	(via
		(at 234.753658 -87.784686)
		(size 0.508)
		(drill 0.254)
		(layers "F.Cu" "B.Cu")
		(net "GND")
	)
	(via
		(at 388.035292 -147.03298)
		(size 0.508)
		(drill 0.254)
		(layers "F.Cu" "B.Cu")
		(net "GND")
	)
	(via
		(at 451.591934 10.354056)
		(size 0.5588)
		(drill 0.3048)
		(layers "F.Cu" "B.Cu")
		(net "GND")
	)
	(via
		(at 128.69418 -28.66771)
		(size 0.508)
		(drill 0.254)
		(layers "F.Cu" "B.Cu")
		(net "GND")
	)
	(via
		(at 240.599722 -140.617956)
		(size 0.508)
		(drill 0.254)
		(layers "F.Cu" "B.Cu")
		(net "GND")
	)
	(via
		(at -3.245866 -164.479224)
		(size 0.5588)
		(drill 0.3048)
		(layers "F.Cu" "B.Cu")
		(net "GND")
	)
	(via
		(at 135.953754 -74.725784)
		(size 0.508)
		(drill 0.254)
		(layers "F.Cu" "B.Cu")
		(net "GND")
	)
	(via
		(at 181.09692 -106.1466)
		(size 0.508)
		(drill 0.254)
		(layers "F.Cu" "B.Cu")
		(net "GND")
	)
	(via
		(at 455.401934 11.624056)
		(size 0.5588)
		(drill 0.3048)
		(layers "F.Cu" "B.Cu")
		(net "GND")
	)
	(via
		(at 133.39953 0.457454)
		(size 0.508)
		(drill 0.254)
		(layers "F.Cu" "B.Cu")
		(net "GND")
	)
	(via
		(at 137.670794 -88.594184)
		(size 0.508)
		(drill 0.254)
		(layers "F.Cu" "B.Cu")
		(net "GND")
	)
	(via
		(at 460.481934 12.894056)
		(size 0.5588)
		(drill 0.3048)
		(layers "F.Cu" "B.Cu")
		(net "GND")
	)
	(via
		(at 84.910168 -17.7546)
		(size 0.508)
		(drill 0.254)
		(layers "F.Cu" "B.Cu")
		(net "GND")
	)
	(via
		(at 316.249812 1.994154)
		(size 0.508)
		(drill 0.254)
		(layers "F.Cu" "B.Cu")
		(net "GND")
	)
	(via
		(at 209.021934 9.084056)
		(size 0.5588)
		(drill 0.3048)
		(layers "F.Cu" "B.Cu")
		(net "GND")
	)
	(via
		(at 206.243682 -62.190122)
		(size 0.5588)
		(drill 0.3048)
		(layers "F.Cu" "B.Cu")
		(net "GND")
	)
	(via
		(at 83.489292 -95.709486)
		(size 0.508)
		(drill 0.254)
		(layers "F.Cu" "B.Cu")
		(net "GND")
	)
	(via
		(at 411.506924 -162.243262)
		(size 0.5588)
		(drill 0.3048)
		(layers "F.Cu" "B.Cu")
		(net "GND")
	)
	(via
		(at 121.499376 -22.965156)
		(size 0.508)
		(drill 0.254)
		(layers "F.Cu" "B.Cu")
		(net "GND")
	)
	(via
		(at 409.890214 -29.334714)
		(size 0.4572)
		(drill 0.2032)
		(layers "F.Cu" "B.Cu")
		(net "GND")
	)
	(via
		(at 167.8686 -83.7692)
		(size 0.508)
		(drill 0.254)
		(layers "F.Cu" "B.Cu")
		(net "GND")
	)
	(via
		(at 212.54974 -7.607046)
		(size 0.508)
		(drill 0.254)
		(layers "F.Cu" "B.Cu")
		(net "GND")
	)
	(via
		(at 81.772252 -83.822286)
		(size 0.508)
		(drill 0.254)
		(layers "F.Cu" "B.Cu")
		(net "GND")
	)
	(via
		(at 73.187306 -82.83194)
		(size 0.508)
		(drill 0.254)
		(layers "F.Cu" "B.Cu")
		(net "GND")
	)
	(via
		(at 445.148716 -60.378848)
		(size 0.508)
		(drill 0.254)
		(layers "F.Cu" "B.Cu")
		(net "GND")
	)
	(via
		(at 173.0502 -23.52802)
		(size 0.508)
		(drill 0.254)
		(layers "F.Cu" "B.Cu")
		(net "GND")
	)
	(via
		(at 215.284558 -96.987868)
		(size 0.508)
		(drill 0.254)
		(layers "F.Cu" "B.Cu")
		(net "GND")
	)
	(via
		(at 434.370734 -166.714424)
		(size 0.5588)
		(drill 0.3048)
		(layers "F.Cu" "B.Cu")
		(net "GND")
	)
	(via
		(at 65.399412 -9.156446)
		(size 0.508)
		(drill 0.254)
		(layers "F.Cu" "B.Cu")
		(net "GND")
	)
	(via
		(at 35.866324 -162.243262)
		(size 0.5588)
		(drill 0.3048)
		(layers "F.Cu" "B.Cu")
		(net "GND")
	)
	(via
		(at 263.94283 -95.709486)
		(size 0.508)
		(drill 0.254)
		(layers "F.Cu" "B.Cu")
		(net "GND")
	)
	(via
		(at 477.550734 -166.714424)
		(size 0.5588)
		(drill 0.3048)
		(layers "F.Cu" "B.Cu")
		(net "GND")
	)
	(via
		(at 200.515728 -73.2282)
		(size 0.508)
		(drill 0.254)
		(layers "F.Cu" "B.Cu")
		(net "GND")
	)
	(via
		(at 457.230734 -164.479224)
		(size 0.5588)
		(drill 0.3048)
		(layers "F.Cu" "B.Cu")
		(net "GND")
	)
	(via
		(at 191.897 -21.427694)
		(size 0.508)
		(drill 0.254)
		(layers "F.Cu" "B.Cu")
		(net "GND")
	)
	(via
		(at 79.456534 -167.832024)
		(size 0.5588)
		(drill 0.3048)
		(layers "F.Cu" "B.Cu")
		(net "GND")
	)
	(via
		(at 350.641666 -136.580118)
		(size 0.508)
		(drill 0.254)
		(layers "F.Cu" "B.Cu")
		(net "GND")
	)
	(via
		(at 402.620734 -164.479224)
		(size 0.5588)
		(drill 0.3048)
		(layers "F.Cu" "B.Cu")
		(net "GND")
	)
	(via
		(at 410.240734 -167.832024)
		(size 0.5588)
		(drill 0.3048)
		(layers "F.Cu" "B.Cu")
		(net "GND")
	)
	(via
		(at 343.0651 -80.0227)
		(size 0.508)
		(drill 0.254)
		(layers "F.Cu" "B.Cu")
		(net "GND")
	)
	(via
		(at 30.999176 -41.23436)
		(size 0.5588)
		(drill 0.3048)
		(layers "F.Cu" "B.Cu")
		(net "GND")
	)
	(via
		(at 457.226924 -162.243262)
		(size 0.5588)
		(drill 0.3048)
		(layers "F.Cu" "B.Cu")
		(net "GND")
	)
	(via
		(at 276.631654 -60.362338)
		(size 0.508)
		(drill 0.254)
		(layers "F.Cu" "B.Cu")
		(net "GND")
	)
	(via
		(at 43.921934 14.926056)
		(size 0.5588)
		(drill 0.3048)
		(layers "F.Cu" "B.Cu")
		(net "GND")
	)
	(via
		(at 340.3854 -40.64)
		(size 0.508)
		(drill 0.254)
		(layers "F.Cu" "B.Cu")
		(net "GND")
	)
	(via
		(at 455.730864 -50.513488)
		(size 0.508)
		(drill 0.254)
		(layers "F.Cu" "B.Cu")
		(net "GND")
	)
	(via
		(at 205.439772 -53.639466)
		(size 0.5588)
		(drill 0.3048)
		(layers "F.Cu" "B.Cu")
		(net "GND")
	)
	(via
		(at 191.135 -148.6281)
		(size 0.508)
		(drill 0.254)
		(layers "F.Cu" "B.Cu")
		(net "GND")
	)
	(via
		(at 186.048396 -93.335602)
		(size 0.508)
		(drill 0.254)
		(layers "F.Cu" "B.Cu")
		(net "GND")
	)
	(via
		(at 82.630772 -79.36484)
		(size 0.508)
		(drill 0.254)
		(layers "F.Cu" "B.Cu")
		(net "GND")
	)
	(via
		(at 428.731934 11.624056)
		(size 0.5588)
		(drill 0.3048)
		(layers "F.Cu" "B.Cu")
		(net "GND")
	)
	(via
		(at 463.53984 -120.39092)
		(size 0.508)
		(drill 0.254)
		(layers "F.Cu" "B.Cu")
		(net "GND")
	)
	(via
		(at 43.12158 -3.762756)
		(size 0.508)
		(drill 0.254)
		(layers "F.Cu" "B.Cu")
		(net "GND")
	)
	(via
		(at 419.7858 -152.6159)
		(size 0.508)
		(drill 0.254)
		(layers "F.Cu" "B.Cu")
		(net "GND")
	)
	(via
		(at 34.74212 -2.310892)
		(size 0.508)
		(drill 0.254)
		(layers "F.Cu" "B.Cu")
		(net "GND")
	)
	(via
		(at 36.031424 -21.5138)
		(size 0.508)
		(drill 0.254)
		(layers "F.Cu" "B.Cu")
		(net "GND")
	)
	(via
		(at 171.1706 -20.447)
		(size 0.508)
		(drill 0.254)
		(layers "F.Cu" "B.Cu")
		(net "GND")
	)
	(via
		(at 56.049418 -18.757646)
		(size 0.508)
		(drill 0.254)
		(layers "F.Cu" "B.Cu")
		(net "GND")
	)
	(via
		(at 54.731412 -11.9126)
		(size 0.508)
		(drill 0.254)
		(layers "F.Cu" "B.Cu")
		(net "GND")
	)
	(via
		(at 32.491934 14.926056)
		(size 0.5588)
		(drill 0.3048)
		(layers "F.Cu" "B.Cu")
		(net "GND")
	)
	(via
		(at 490.08792 -120.11152)
		(size 0.508)
		(drill 0.254)
		(layers "F.Cu" "B.Cu")
		(net "GND")
	)
	(via
		(at 373.992648 -152.281128)
		(size 0.508)
		(drill 0.254)
		(layers "F.Cu" "B.Cu")
		(net "GND")
	)
	(via
		(at 199.035924 -162.243262)
		(size 0.5588)
		(drill 0.3048)
		(layers "F.Cu" "B.Cu")
		(net "GND")
	)
	(via
		(at 175.7426 -134.9629)
		(size 0.508)
		(drill 0.254)
		(layers "F.Cu" "B.Cu")
		(net "GND")
	)
	(via
		(at 376.9868 -133.1468)
		(size 0.508)
		(drill 0.254)
		(layers "F.Cu" "B.Cu")
		(net "GND")
	)
	(via
		(at 387.985 -42.602404)
		(size 0.508)
		(drill 0.254)
		(layers "F.Cu" "B.Cu")
		(net "GND")
	)
	(via
		(at 206.51089 -13.338556)
		(size 0.508)
		(drill 0.254)
		(layers "F.Cu" "B.Cu")
		(net "GND")
	)
	(via
		(at 297.388534 -167.832024)
		(size 0.5588)
		(drill 0.3048)
		(layers "F.Cu" "B.Cu")
		(net "GND")
	)
	(via
		(at 324.41642 -29.86278)
		(size 0.508)
		(drill 0.254)
		(layers "F.Cu" "B.Cu")
		(net "GND")
	)
	(via
		(at 78.338172 -60.047886)
		(size 0.508)
		(drill 0.254)
		(layers "F.Cu" "B.Cu")
		(net "GND")
	)
	(via
		(at 34.748724 -153.6065)
		(size 0.508)
		(drill 0.254)
		(layers "F.Cu" "B.Cu")
		(net "GND")
	)
	(via
		(at 416.289998 -33.334706)
		(size 0.4572)
		(drill 0.2032)
		(layers "F.Cu" "B.Cu")
		(net "GND")
	)
	(via
		(at 36.162234 -62.073536)
		(size 0.5588)
		(drill 0.3048)
		(layers "F.Cu" "B.Cu")
		(net "GND")
	)
	(via
		(at 6.934454 -155.10002)
		(size 0.5588)
		(drill 0.3048)
		(layers "F.Cu" "B.Cu")
		(net "GND")
	)
	(via
		(at 356.161594 4.289806)
		(size 0.5588)
		(drill 0.3048)
		(layers "F.Cu" "B.Cu")
		(net "GND")
	)
	(via
		(at 181.25694 -14.15542)
		(size 0.508)
		(drill 0.254)
		(layers "F.Cu" "B.Cu")
		(net "GND")
	)
	(via
		(at 309.411878 -21.517356)
		(size 0.508)
		(drill 0.254)
		(layers "F.Cu" "B.Cu")
		(net "GND")
	)
	(via
		(at 301.746412 -126.646686)
		(size 0.508)
		(drill 0.254)
		(layers "F.Cu" "B.Cu")
		(net "GND")
	)
	(via
		(at 207.414114 -93.943678)
		(size 0.5588)
		(drill 0.3048)
		(layers "F.Cu" "B.Cu")
		(net "GND")
	)
	(via
		(at 408.879294 -94.636336)
		(size 0.508)
		(drill 0.254)
		(layers "F.Cu" "B.Cu")
		(net "GND")
	)
	(via
		(at 196.896228 -97.442782)
		(size 0.508)
		(drill 0.254)
		(layers "F.Cu" "B.Cu")
		(net "GND")
	)
	(via
		(at 244.197124 -60.54344)
		(size 0.508)
		(drill 0.254)
		(layers "F.Cu" "B.Cu")
		(net "GND")
	)
	(via
		(at 20.752308 2.89433)
		(size 0.508)
		(drill 0.254)
		(layers "F.Cu" "B.Cu")
		(net "GND")
	)
	(via
		(at 445.00165 -45.560996)
		(size 0.508)
		(drill 0.254)
		(layers "F.Cu" "B.Cu")
		(net "GND")
	)
	(via
		(at 306.181506 -77.697584)
		(size 0.508)
		(drill 0.254)
		(layers "F.Cu" "B.Cu")
		(net "GND")
	)
	(via
		(at 167.69842 -151.93518)
		(size 0.508)
		(drill 0.254)
		(layers "F.Cu" "B.Cu")
		(net "GND")
	)
	(via
		(at 410.240734 -163.361624)
		(size 0.5588)
		(drill 0.3048)
		(layers "F.Cu" "B.Cu")
		(net "GND")
	)
	(via
		(at 289.823652 -27.829256)
		(size 0.508)
		(drill 0.254)
		(layers "F.Cu" "B.Cu")
		(net "GND")
	)
	(via
		(at 182.275734 -167.832024)
		(size 0.5588)
		(drill 0.3048)
		(layers "F.Cu" "B.Cu")
		(net "GND")
	)
	(via
		(at 315.399928 -18.757646)
		(size 0.508)
		(drill 0.254)
		(layers "F.Cu" "B.Cu")
		(net "GND")
	)
	(via
		(at 133.39953 -148.771356)
		(size 0.508)
		(drill 0.254)
		(layers "F.Cu" "B.Cu")
		(net "GND")
	)
	(via
		(at 195.3514 -26.1366)
		(size 0.508)
		(drill 0.254)
		(layers "F.Cu" "B.Cu")
		(net "GND")
	)
	(via
		(at 175.26 -3.8862)
		(size 0.508)
		(drill 0.254)
		(layers "F.Cu" "B.Cu")
		(net "GND")
	)
	(via
		(at 292.392608 -11.912092)
		(size 0.508)
		(drill 0.254)
		(layers "F.Cu" "B.Cu")
		(net "GND")
	)
	(via
		(at 293.22776 -90.080338)
		(size 0.508)
		(drill 0.254)
		(layers "F.Cu" "B.Cu")
		(net "GND")
	)
	(via
		(at 355.071934 14.926056)
		(size 0.5588)
		(drill 0.3048)
		(layers "F.Cu" "B.Cu")
		(net "GND")
	)
	(via
		(at 40.749474 -21.517356)
		(size 0.508)
		(drill 0.254)
		(layers "F.Cu" "B.Cu")
		(net "GND")
	)
	(via
		(at 293.22776 -93.052138)
		(size 0.508)
		(drill 0.254)
		(layers "F.Cu" "B.Cu")
		(net "GND")
	)
	(via
		(at 243.338604 -65.000886)
		(size 0.508)
		(drill 0.254)
		(layers "F.Cu" "B.Cu")
		(net "GND")
	)
	(via
		(at 80.751934 9.084056)
		(size 0.5588)
		(drill 0.3048)
		(layers "F.Cu" "B.Cu")
		(net "GND")
	)
	(via
		(at 472.470734 -163.361624)
		(size 0.5588)
		(drill 0.3048)
		(layers "F.Cu" "B.Cu")
		(net "GND")
	)
	(via
		(at 234.560872 -22.939756)
		(size 0.508)
		(drill 0.254)
		(layers "F.Cu" "B.Cu")
		(net "GND")
	)
	(via
		(at 438.770776 -63.582296)
		(size 0.508)
		(drill 0.254)
		(layers "F.Cu" "B.Cu")
		(net "GND")
	)
	(via
		(at 444.26886 -130.50266)
		(size 0.508)
		(drill 0.254)
		(layers "F.Cu" "B.Cu")
		(net "GND")
	)
	(via
		(at 160.860232 -67.007232)
		(size 0.508)
		(drill 0.254)
		(layers "F.Cu" "B.Cu")
		(net "GND")
	)
	(via
		(at 350.5454 -114.935)
		(size 0.508)
		(drill 0.254)
		(layers "F.Cu" "B.Cu")
		(net "GND")
	)
	(via
		(at 218.44254 -155.600146)
		(size 0.508)
		(drill 0.254)
		(layers "F.Cu" "B.Cu")
		(net "GND")
	)
	(via
		(at 170.1165 -62.5729)
		(size 0.508)
		(drill 0.254)
		(layers "F.Cu" "B.Cu")
		(net "GND")
	)
	(via
		(at 249.9106 -3.3528)
		(size 0.508)
		(drill 0.254)
		(layers "F.Cu" "B.Cu")
		(net "GND")
	)
	(via
		(at 36.031424 -2.3114)
		(size 0.508)
		(drill 0.254)
		(layers "F.Cu" "B.Cu")
		(net "GND")
	)
	(via
		(at 358.983534 -167.857424)
		(size 0.5588)
		(drill 0.3048)
		(layers "F.Cu" "B.Cu")
		(net "GND")
	)
	(via
		(at 45.390816 -153.552144)
		(size 0.508)
		(drill 0.254)
		(layers "F.Cu" "B.Cu")
		(net "GND")
	)
	(via
		(at 247.631204 -57.57164)
		(size 0.508)
		(drill 0.254)
		(layers "F.Cu" "B.Cu")
		(net "GND")
	)
	(via
		(at 475.57436 -37.397944)
		(size 0.508)
		(drill 0.254)
		(layers "F.Cu" "B.Cu")
		(net "GND")
	)
	(via
		(at 72.142096 -9.143746)
		(size 0.508)
		(drill 0.254)
		(layers "F.Cu" "B.Cu")
		(net "GND")
	)
	(via
		(at 128.69418 -136.3345)
		(size 0.508)
		(drill 0.254)
		(layers "F.Cu" "B.Cu")
		(net "GND")
	)
	(via
		(at 121.499376 -17.208246)
		(size 0.508)
		(drill 0.254)
		(layers "F.Cu" "B.Cu")
		(net "GND")
	)
	(via
		(at 35.479482 -70.148196)
		(size 0.5588)
		(drill 0.3048)
		(layers "F.Cu" "B.Cu")
		(net "GND")
	)
	(via
		(at 342.44026 -77.16774)
		(size 0.508)
		(drill 0.254)
		(layers "F.Cu" "B.Cu")
		(net "GND")
	)
	(via
		(at 174.379382 -50.831496)
		(size 0.508)
		(drill 0.254)
		(layers "F.Cu" "B.Cu")
		(net "GND")
	)
	(via
		(at 387.3373 -112.2553)
		(size 0.508)
		(drill 0.254)
		(layers "F.Cu" "B.Cu")
		(net "GND")
	)
	(via
		(at 169.3926 -83.7438)
		(size 0.508)
		(drill 0.254)
		(layers "F.Cu" "B.Cu")
		(net "GND")
	)
	(via
		(at 289.049968 -9.143746)
		(size 0.508)
		(drill 0.254)
		(layers "F.Cu" "B.Cu")
		(net "GND")
	)
	(via
		(at 292.382448 -4.2926)
		(size 0.508)
		(drill 0.254)
		(layers "F.Cu" "B.Cu")
		(net "GND")
	)
	(via
		(at 56.049418 -148.771356)
		(size 0.508)
		(drill 0.254)
		(layers "F.Cu" "B.Cu")
		(net "GND")
	)
	(via
		(at 103.401876 -75.159616)
		(size 0.5588)
		(drill 0.3048)
		(layers "F.Cu" "B.Cu")
		(net "GND")
	)
	(via
		(at 125.651768 -70.763384)
		(size 0.508)
		(drill 0.254)
		(layers "F.Cu" "B.Cu")
		(net "GND")
	)
	(via
		(at 159.919924 -162.243262)
		(size 0.5588)
		(drill 0.3048)
		(layers "F.Cu" "B.Cu")
		(net "GND")
	)
	(via
		(at 118.041928 -129.564892)
		(size 0.508)
		(drill 0.254)
		(layers "F.Cu" "B.Cu")
		(net "GND")
	)
	(via
		(at 20.193 4.2164)
		(size 0.508)
		(drill 0.254)
		(layers "F.Cu" "B.Cu")
		(net "GND")
	)
	(via
		(at 162.3314 -78.613)
		(size 0.508)
		(drill 0.254)
		(layers "F.Cu" "B.Cu")
		(net "GND")
	)
	(via
		(at 488.696 -155.293314)
		(size 0.508)
		(drill 0.254)
		(layers "F.Cu" "B.Cu")
		(net "GND")
	)
	(via
		(at 278.944578 -18.691606)
		(size 0.508)
		(drill 0.254)
		(layers "F.Cu" "B.Cu")
		(net "GND")
	)
	(via
		(at 398.810734 -165.596824)
		(size 0.5588)
		(drill 0.3048)
		(layers "F.Cu" "B.Cu")
		(net "GND")
	)
	(via
		(at 142.749524 -18.744946)
		(size 0.508)
		(drill 0.254)
		(layers "F.Cu" "B.Cu")
		(net "GND")
	)
	(via
		(at 276.916134 -89.584784)
		(size 0.508)
		(drill 0.254)
		(layers "F.Cu" "B.Cu")
		(net "GND")
	)
	(via
		(at 76.477368 -124.6378)
		(size 0.508)
		(drill 0.254)
		(layers "F.Cu" "B.Cu")
		(net "GND")
	)
	(via
		(at 39.899336 -3.762756)
		(size 0.508)
		(drill 0.254)
		(layers "F.Cu" "B.Cu")
		(net "GND")
	)
	(via
		(at 174.0027 -128.00838)
		(size 0.508)
		(drill 0.254)
		(layers "F.Cu" "B.Cu")
		(net "GND")
	)
	(via
		(at 435.640734 -163.361624)
		(size 0.5588)
		(drill 0.3048)
		(layers "F.Cu" "B.Cu")
		(net "GND")
	)
	(via
		(at 31.908496 -64.295782)
		(size 0.508)
		(drill 0.254)
		(layers "F.Cu" "B.Cu")
		(net "GND")
	)
	(via
		(at 250.206764 -60.047886)
		(size 0.508)
		(drill 0.254)
		(layers "F.Cu" "B.Cu")
		(net "GND")
	)
	(via
		(at 120.649492 -9.156446)
		(size 0.508)
		(drill 0.254)
		(layers "F.Cu" "B.Cu")
		(net "GND")
	)
	(via
		(at 11.2522 -26.0858)
		(size 0.508)
		(drill 0.254)
		(layers "F.Cu" "B.Cu")
		(net "GND")
	)
	(via
		(at 61.701934 14.926056)
		(size 0.5588)
		(drill 0.3048)
		(layers "F.Cu" "B.Cu")
		(net "GND")
	)
	(via
		(at 374.627648 -151.392128)
		(size 0.508)
		(drill 0.254)
		(layers "F.Cu" "B.Cu")
		(net "GND")
	)
	(via
		(at 428.253144 -139.255754)
		(size 0.508)
		(drill 0.254)
		(layers "F.Cu" "B.Cu")
		(net "GND")
	)
	(via
		(at 141.049502 -2.314956)
		(size 0.508)
		(drill 0.254)
		(layers "F.Cu" "B.Cu")
		(net "GND")
	)
	(via
		(at 64.094106 -18.6817)
		(size 0.508)
		(drill 0.254)
		(layers "F.Cu" "B.Cu")
		(net "GND")
	)
	(via
		(at 11.7856 -136.21766)
		(size 0.508)
		(drill 0.254)
		(layers "F.Cu" "B.Cu")
		(net "GND")
	)
	(via
		(at 280.350214 -99.490784)
		(size 0.508)
		(drill 0.254)
		(layers "F.Cu" "B.Cu")
		(net "GND")
	)
	(via
		(at 114.699542 -21.517356)
		(size 0.508)
		(drill 0.254)
		(layers "F.Cu" "B.Cu")
		(net "GND")
	)
	(via
		(at 178.86045 -72.96785)
		(size 0.508)
		(drill 0.254)
		(layers "F.Cu" "B.Cu")
		(net "GND")
	)
	(via
		(at 406.1714 -101.3714)
		(size 0.508)
		(drill 0.254)
		(layers "F.Cu" "B.Cu")
		(net "GND")
	)
	(via
		(at 386.25145 -116.094764)
		(size 0.508)
		(drill 0.254)
		(layers "F.Cu" "B.Cu")
		(net "GND")
	)
	(via
		(at 472.470734 -164.479224)
		(size 0.5588)
		(drill 0.3048)
		(layers "F.Cu" "B.Cu")
		(net "GND")
	)
	(via
		(at 140.199364 -3.762756)
		(size 0.508)
		(drill 0.254)
		(layers "F.Cu" "B.Cu")
		(net "GND")
	)
	(via
		(at 57.74944 -18.757646)
		(size 0.508)
		(drill 0.254)
		(layers "F.Cu" "B.Cu")
		(net "GND")
	)
	(via
		(at 385.903724 -162.243262)
		(size 0.5588)
		(drill 0.3048)
		(layers "F.Cu" "B.Cu")
		(net "GND")
	)
	(via
		(at 129.085848 -53.923184)
		(size 0.508)
		(drill 0.254)
		(layers "F.Cu" "B.Cu")
		(net "GND")
	)
	(via
		(at 371.317012 -148.731224)
		(size 0.508)
		(drill 0.254)
		(layers "F.Cu" "B.Cu")
		(net "GND")
	)
	(via
		(at 251.065284 -59.55284)
		(size 0.508)
		(drill 0.254)
		(layers "F.Cu" "B.Cu")
		(net "GND")
	)
	(via
		(at 68.799456 0.457454)
		(size 0.508)
		(drill 0.254)
		(layers "F.Cu" "B.Cu")
		(net "GND")
	)
	(via
		(at 215.0999 -9.143746)
		(size 0.508)
		(drill 0.254)
		(layers "F.Cu" "B.Cu")
		(net "GND")
	)
	(via
		(at 40.749474 -129.568956)
		(size 0.508)
		(drill 0.254)
		(layers "F.Cu" "B.Cu")
		(net "GND")
	)
	(via
		(at 389.71855 -102.756716)
		(size 0.508)
		(drill 0.254)
		(layers "F.Cu" "B.Cu")
		(net "GND")
	)
	(via
		(at 131.699508 -2.314956)
		(size 0.508)
		(drill 0.254)
		(layers "F.Cu" "B.Cu")
		(net "GND")
	)
	(via
		(at 129.944368 -94.042738)
		(size 0.508)
		(drill 0.254)
		(layers "F.Cu" "B.Cu")
		(net "GND")
	)
	(via
		(at 48.159924 -162.243262)
		(size 0.5588)
		(drill 0.3048)
		(layers "F.Cu" "B.Cu")
		(net "GND")
	)
	(via
		(at 119.357902 -55.904384)
		(size 0.508)
		(drill 0.254)
		(layers "F.Cu" "B.Cu")
		(net "GND")
	)
	(via
		(at 9.047734 -163.361624)
		(size 0.5588)
		(drill 0.3048)
		(layers "F.Cu" "B.Cu")
		(net "GND")
	)
	(via
		(at 485.881934 14.926056)
		(size 0.5588)
		(drill 0.3048)
		(layers "F.Cu" "B.Cu")
		(net "GND")
	)
	(via
		(at 249.9106 -149.8092)
		(size 0.508)
		(drill 0.254)
		(layers "F.Cu" "B.Cu")
		(net "GND")
	)
	(via
		(at 237.329218 -97.19564)
		(size 0.508)
		(drill 0.254)
		(layers "F.Cu" "B.Cu")
		(net "GND")
	)
	(via
		(at 62.786006 -23.495)
		(size 0.508)
		(drill 0.254)
		(layers "F.Cu" "B.Cu")
		(net "GND")
	)
	(via
		(at 127.368808 -75.716384)
		(size 0.508)
		(drill 0.254)
		(layers "F.Cu" "B.Cu")
		(net "GND")
	)
	(via
		(at 130.802888 -102.462584)
		(size 0.508)
		(drill 0.254)
		(layers "F.Cu" "B.Cu")
		(net "GND")
	)
	(via
		(at 450.204586 -118.61927)
		(size 0.508)
		(drill 0.254)
		(layers "F.Cu" "B.Cu")
		(net "GND")
	)
	(via
		(at 6.812534 -165.596824)
		(size 0.5588)
		(drill 0.3048)
		(layers "F.Cu" "B.Cu")
		(net "GND")
	)
	(via
		(at 309.411878 -129.568956)
		(size 0.508)
		(drill 0.254)
		(layers "F.Cu" "B.Cu")
		(net "GND")
	)
	(via
		(at 244.197124 -72.43064)
		(size 0.508)
		(drill 0.254)
		(layers "F.Cu" "B.Cu")
		(net "GND")
	)
	(via
		(at 127.368808 -56.894984)
		(size 0.508)
		(drill 0.254)
		(layers "F.Cu" "B.Cu")
		(net "GND")
	)
	(via
		(at 415.320734 -166.714424)
		(size 0.5588)
		(drill 0.3048)
		(layers "F.Cu" "B.Cu")
		(net "GND")
	)
	(via
		(at 289.049968 -21.517356)
		(size 0.508)
		(drill 0.254)
		(layers "F.Cu" "B.Cu")
		(net "GND")
	)
	(via
		(at 206.982314 -69.661278)
		(size 0.5588)
		(drill 0.3048)
		(layers "F.Cu" "B.Cu")
		(net "GND")
	)
	(via
		(at 242.316 -126.3142)
		(size 0.508)
		(drill 0.254)
		(layers "F.Cu" "B.Cu")
		(net "GND")
	)
	(via
		(at 314.54979 -150.219156)
		(size 0.508)
		(drill 0.254)
		(layers "F.Cu" "B.Cu")
		(net "GND")
	)
	(via
		(at 363.961934 9.084056)
		(size 0.5588)
		(drill 0.3048)
		(layers "F.Cu" "B.Cu")
		(net "GND")
	)
	(via
		(at 123.650248 -57.390538)
		(size 0.508)
		(drill 0.254)
		(layers "F.Cu" "B.Cu")
		(net "GND")
	)
	(via
		(at 340.995 -79.2734)
		(size 0.508)
		(drill 0.254)
		(layers "F.Cu" "B.Cu")
		(net "GND")
	)
	(via
		(at 344.1954 -39.37)
		(size 0.508)
		(drill 0.254)
		(layers "F.Cu" "B.Cu")
		(net "GND")
	)
	(via
		(at 353.695 -87.5284)
		(size 0.508)
		(drill 0.254)
		(layers "F.Cu" "B.Cu")
		(net "GND")
	)
	(via
		(at 262.6868 -128.766824)
		(size 0.508)
		(drill 0.254)
		(layers "F.Cu" "B.Cu")
		(net "GND")
	)
	(via
		(at 266.518136 -89.27084)
		(size 0.508)
		(drill 0.254)
		(layers "F.Cu" "B.Cu")
		(net "GND")
	)
	(via
		(at 395.66215 -113.519204)
		(size 0.508)
		(drill 0.254)
		(layers "F.Cu" "B.Cu")
		(net "GND")
	)
	(via
		(at 384.739388 -74.487278)
		(size 0.508)
		(drill 0.254)
		(layers "F.Cu" "B.Cu")
		(net "GND")
	)
	(via
		(at 80.055212 -53.113686)
		(size 0.508)
		(drill 0.254)
		(layers "F.Cu" "B.Cu")
		(net "GND")
	)
	(via
		(at 351.033334 -167.832024)
		(size 0.5588)
		(drill 0.3048)
		(layers "F.Cu" "B.Cu")
		(net "GND")
	)
	(via
		(at 454.200006 -113.8682)
		(size 0.508)
		(drill 0.254)
		(layers "F.Cu" "B.Cu")
		(net "GND")
	)
	(via
		(at 31.39948 -139.170156)
		(size 0.508)
		(drill 0.254)
		(layers "F.Cu" "B.Cu")
		(net "GND")
	)
	(via
		(at 397.212058 -157.829504)
		(size 0.508)
		(drill 0.254)
		(layers "F.Cu" "B.Cu")
		(net "GND")
	)
	(via
		(at 124.793248 -89.089738)
		(size 0.508)
		(drill 0.254)
		(layers "F.Cu" "B.Cu")
		(net "GND")
	)
	(via
		(at 7.930134 -165.596824)
		(size 0.5588)
		(drill 0.3048)
		(layers "F.Cu" "B.Cu")
		(net "GND")
	)
	(via
		(at 287.349946 -148.771356)
		(size 0.508)
		(drill 0.254)
		(layers "F.Cu" "B.Cu")
		(net "GND")
	)
	(via
		(at 440.716924 -162.243262)
		(size 0.5588)
		(drill 0.3048)
		(layers "F.Cu" "B.Cu")
		(net "GND")
	)
	(via
		(at 450.880734 -163.361624)
		(size 0.5588)
		(drill 0.3048)
		(layers "F.Cu" "B.Cu")
		(net "GND")
	)
	(via
		(at 379.81255 -104.473756)
		(size 0.508)
		(drill 0.254)
		(layers "F.Cu" "B.Cu")
		(net "GND")
	)
	(via
		(at 448.5386 -21.2598)
		(size 0.508)
		(drill 0.254)
		(layers "F.Cu" "B.Cu")
		(net "GND")
	)
	(via
		(at 294.999918 -18.757646)
		(size 0.508)
		(drill 0.254)
		(layers "F.Cu" "B.Cu")
		(net "GND")
	)
	(via
		(at 350.5454 -38.1)
		(size 0.508)
		(drill 0.254)
		(layers "F.Cu" "B.Cu")
		(net "GND")
	)
	(via
		(at 44.098718 -153.6065)
		(size 0.508)
		(drill 0.254)
		(layers "F.Cu" "B.Cu")
		(net "GND")
	)
	(via
		(at 395.16685 -110.943644)
		(size 0.508)
		(drill 0.254)
		(layers "F.Cu" "B.Cu")
		(net "GND")
	)
	(via
		(at 47.731934 14.926056)
		(size 0.5588)
		(drill 0.3048)
		(layers "F.Cu" "B.Cu")
		(net "GND")
	)
	(via
		(at 31.0642 -94.5134)
		(size 0.508)
		(drill 0.254)
		(layers "F.Cu" "B.Cu")
		(net "GND")
	)
	(via
		(at 116.49456 -50.951384)
		(size 0.4572)
		(drill 0.2032)
		(layers "F.Cu" "B.Cu")
		(net "GND")
	)
	(via
		(at 121.359168 -81.164938)
		(size 0.508)
		(drill 0.254)
		(layers "F.Cu" "B.Cu")
		(net "GND")
	)
	(via
		(at 180.213 -141.1605)
		(size 0.508)
		(drill 0.254)
		(layers "F.Cu" "B.Cu")
		(net "GND")
	)
	(via
		(at 227.799138 -144.0053)
		(size 0.508)
		(drill 0.254)
		(layers "F.Cu" "B.Cu")
		(net "GND")
	)
	(via
		(at 28.702 -77.216)
		(size 0.508)
		(drill 0.254)
		(layers "F.Cu" "B.Cu")
		(net "GND")
	)
	(via
		(at 490.961934 13.910056)
		(size 0.5588)
		(drill 0.3048)
		(layers "F.Cu" "B.Cu")
		(net "GND")
	)
	(via
		(at 134.236714 -80.669384)
		(size 0.508)
		(drill 0.254)
		(layers "F.Cu" "B.Cu")
		(net "GND")
	)
	(via
		(at 291.422074 -17.2466)
		(size 0.508)
		(drill 0.254)
		(layers "F.Cu" "B.Cu")
		(net "GND")
	)
	(via
		(at 432.414934 -3.360674)
		(size 0.508)
		(drill 0.254)
		(layers "F.Cu" "B.Cu")
		(net "GND")
	)
	(via
		(at 250.206764 -65.991486)
		(size 0.508)
		(drill 0.254)
		(layers "F.Cu" "B.Cu")
		(net "GND")
	)
	(via
		(at 255.35763 -95.709486)
		(size 0.508)
		(drill 0.254)
		(layers "F.Cu" "B.Cu")
		(net "GND")
	)
	(via
		(at 31.39948 -145.998946)
		(size 0.508)
		(drill 0.254)
		(layers "F.Cu" "B.Cu")
		(net "GND")
	)
	(via
		(at -5.2578 -7.9756)
		(size 0.508)
		(drill 0.254)
		(layers "F.Cu" "B.Cu")
		(net "GND")
	)
	(via
		(at 462.149952 -58.954924)
		(size 0.508)
		(drill 0.254)
		(layers "F.Cu" "B.Cu")
		(net "GND")
	)
	(via
		(at 359.3592 -147.2692)
		(size 0.508)
		(drill 0.254)
		(layers "F.Cu" "B.Cu")
		(net "GND")
	)
	(via
		(at 282.681934 9.084056)
		(size 0.5588)
		(drill 0.3048)
		(layers "F.Cu" "B.Cu")
		(net "GND")
	)
	(via
		(at 352.1456 -59.679586)
		(size 0.508)
		(drill 0.254)
		(layers "F.Cu" "B.Cu")
		(net "GND")
	)
	(via
		(at 475.721934 9.084056)
		(size 0.5588)
		(drill 0.3048)
		(layers "F.Cu" "B.Cu")
		(net "GND")
	)
	(via
		(at 309.411878 -148.771356)
		(size 0.508)
		(drill 0.254)
		(layers "F.Cu" "B.Cu")
		(net "GND")
	)
	(via
		(at 44.098718 2.4511)
		(size 0.508)
		(drill 0.254)
		(layers "F.Cu" "B.Cu")
		(net "GND")
	)
	(via
		(at 98.942398 -89.765886)
		(size 0.508)
		(drill 0.254)
		(layers "F.Cu" "B.Cu")
		(net "GND")
	)
	(via
		(at 134.091934 9.084056)
		(size 0.5588)
		(drill 0.3048)
		(layers "F.Cu" "B.Cu")
		(net "GND")
	)
	(via
		(at 43.12158 -131.004056)
		(size 0.508)
		(drill 0.254)
		(layers "F.Cu" "B.Cu")
		(net "GND")
	)
	(via
		(at 244.197124 -54.59984)
		(size 0.508)
		(drill 0.254)
		(layers "F.Cu" "B.Cu")
		(net "GND")
	)
	(via
		(at 317.09995 -153.542746)
		(size 0.508)
		(drill 0.254)
		(layers "F.Cu" "B.Cu")
		(net "GND")
	)
	(via
		(at 142.039594 -71.258938)
		(size 0.508)
		(drill 0.254)
		(layers "F.Cu" "B.Cu")
		(net "GND")
	)
	(via
		(at 7.7216 -22.8092)
		(size 0.508)
		(drill 0.254)
		(layers "F.Cu" "B.Cu")
		(net "GND")
	)
	(via
		(at 141.711934 14.926056)
		(size 0.5588)
		(drill 0.3048)
		(layers "F.Cu" "B.Cu")
		(net "GND")
	)
	(via
		(at 116.361464 -2.314956)
		(size 0.508)
		(drill 0.254)
		(layers "F.Cu" "B.Cu")
		(net "GND")
	)
	(via
		(at 229.087934 -23.549356)
		(size 0.508)
		(drill 0.254)
		(layers "F.Cu" "B.Cu")
		(net "GND")
	)
	(via
		(at 284.344364 -18.6817)
		(size 0.508)
		(drill 0.254)
		(layers "F.Cu" "B.Cu")
		(net "GND")
	)
	(via
		(at 360.084624 -93.356938)
		(size 0.508)
		(drill 0.254)
		(layers "F.Cu" "B.Cu")
		(net "GND")
	)
	(via
		(at 278.9682 -150.0886)
		(size 0.508)
		(drill 0.254)
		(layers "F.Cu" "B.Cu")
		(net "GND")
	)
	(via
		(at 279.207214 -57.885584)
		(size 0.508)
		(drill 0.254)
		(layers "F.Cu" "B.Cu")
		(net "GND")
	)
	(via
		(at 2.276856 13.609066)
		(size 0.5588)
		(drill 0.3048)
		(layers "F.Cu" "B.Cu")
		(net "GND")
	)
	(via
		(at 238.231934 14.926056)
		(size 0.5588)
		(drill 0.3048)
		(layers "F.Cu" "B.Cu")
		(net "GND")
	)
	(via
		(at 466.831934 13.910056)
		(size 0.5588)
		(drill 0.3048)
		(layers "F.Cu" "B.Cu")
		(net "GND")
	)
	(via
		(at 381.491236 -130.313938)
		(size 0.508)
		(drill 0.254)
		(layers "F.Cu" "B.Cu")
		(net "GND")
	)
	(via
		(at 282.07208 -150.193756)
		(size 0.508)
		(drill 0.254)
		(layers "F.Cu" "B.Cu")
		(net "GND")
	)
	(via
		(at 307.898546 -89.584784)
		(size 0.508)
		(drill 0.254)
		(layers "F.Cu" "B.Cu")
		(net "GND")
	)
	(via
		(at 31.893002 -88.040464)
		(size 0.508)
		(drill 0.254)
		(layers "F.Cu" "B.Cu")
		(net "GND")
	)
	(via
		(at 8.282686 -150.250652)
		(size 0.508)
		(drill 0.254)
		(layers "F.Cu" "B.Cu")
		(net "GND")
	)
	(via
		(at 288.93516 -95.528384)
		(size 0.508)
		(drill 0.254)
		(layers "F.Cu" "B.Cu")
		(net "GND")
	)
	(via
		(at 136.74217 -28.730956)
		(size 0.508)
		(drill 0.254)
		(layers "F.Cu" "B.Cu")
		(net "GND")
	)
	(via
		(at 160.663128 -61.396118)
		(size 0.508)
		(drill 0.254)
		(layers "F.Cu" "B.Cu")
		(net "GND")
	)
	(via
		(at 295.80332 -80.669384)
		(size 0.508)
		(drill 0.254)
		(layers "F.Cu" "B.Cu")
		(net "GND")
	)
	(via
		(at 408.970734 -163.361624)
		(size 0.5588)
		(drill 0.3048)
		(layers "F.Cu" "B.Cu")
		(net "GND")
	)
	(via
		(at 84.910168 -135.4074)
		(size 0.508)
		(drill 0.254)
		(layers "F.Cu" "B.Cu")
		(net "GND")
	)
	(via
		(at 282.07208 -134.8994)
		(size 0.508)
		(drill 0.254)
		(layers "F.Cu" "B.Cu")
		(net "GND")
	)
	(via
		(at 149.549358 -131.016756)
		(size 0.508)
		(drill 0.254)
		(layers "F.Cu" "B.Cu")
		(net "GND")
	)
	(via
		(at 357.024432 -116.017294)
		(size 0.508)
		(drill 0.254)
		(layers "F.Cu" "B.Cu")
		(net "GND")
	)
	(via
		(at 11.7856 -137.10666)
		(size 0.508)
		(drill 0.254)
		(layers "F.Cu" "B.Cu")
		(net "GND")
	)
	(via
		(at 424.921934 12.894056)
		(size 0.5588)
		(drill 0.3048)
		(layers "F.Cu" "B.Cu")
		(net "GND")
	)
	(via
		(at 353.604576 -92.612718)
		(size 0.508)
		(drill 0.254)
		(layers "F.Cu" "B.Cu")
		(net "GND")
	)
	(via
		(at 34.991802 -87.811864)
		(size 0.508)
		(drill 0.254)
		(layers "F.Cu" "B.Cu")
		(net "GND")
	)
	(via
		(at 232.099866 -11.916156)
		(size 0.508)
		(drill 0.254)
		(layers "F.Cu" "B.Cu")
		(net "GND")
	)
	(via
		(at 234.753658 -90.756486)
		(size 0.508)
		(drill 0.254)
		(layers "F.Cu" "B.Cu")
		(net "GND")
	)
	(via
		(at 419.1762 -49.593754)
		(size 0.508)
		(drill 0.254)
		(layers "F.Cu" "B.Cu")
		(net "GND")
	)
	(via
		(at 11.2268 -33.1978)
		(size 0.508)
		(drill 0.254)
		(layers "F.Cu" "B.Cu")
		(net "GND")
	)
	(via
		(at 262.22579 -88.775286)
		(size 0.508)
		(drill 0.254)
		(layers "F.Cu" "B.Cu")
		(net "GND")
	)
	(via
		(at 313.034934 -167.832024)
		(size 0.5588)
		(drill 0.3048)
		(layers "F.Cu" "B.Cu")
		(net "GND")
	)
	(via
		(at 305.246786 -66.305938)
		(size 0.508)
		(drill 0.254)
		(layers "F.Cu" "B.Cu")
		(net "GND")
	)
	(via
		(at 233.799888 -148.771356)
		(size 0.508)
		(drill 0.254)
		(layers "F.Cu" "B.Cu")
		(net "GND")
	)
	(via
		(at 252.201934 9.084056)
		(size 0.5588)
		(drill 0.3048)
		(layers "F.Cu" "B.Cu")
		(net "GND")
	)
	(via
		(at 394.17625 -108.766356)
		(size 0.508)
		(drill 0.254)
		(layers "F.Cu" "B.Cu")
		(net "GND")
	)
	(via
		(at 40.749474 -139.170156)
		(size 0.508)
		(drill 0.254)
		(layers "F.Cu" "B.Cu")
		(net "GND")
	)
	(via
		(at 125.749558 0.444754)
		(size 0.508)
		(drill 0.254)
		(layers "F.Cu" "B.Cu")
		(net "GND")
	)
	(via
		(at 308.501796 -17.208246)
		(size 0.508)
		(drill 0.254)
		(layers "F.Cu" "B.Cu")
		(net "GND")
	)
	(via
		(at 345.5416 -2.6924)
		(size 0.508)
		(drill 0.254)
		(layers "F.Cu" "B.Cu")
		(net "GND")
	)
	(via
		(at 0.381 -146.4564)
		(size 0.508)
		(drill 0.254)
		(layers "F.Cu" "B.Cu")
		(net "GND")
	)
	(via
		(at 164.390324 -162.243262)
		(size 0.5588)
		(drill 0.3048)
		(layers "F.Cu" "B.Cu")
		(net "GND")
	)
	(via
		(at 200.556114 -68.351654)
		(size 0.5588)
		(drill 0.3048)
		(layers "F.Cu" "B.Cu")
		(net "GND")
	)
	(via
		(at 120.500902 -88.594184)
		(size 0.508)
		(drill 0.254)
		(layers "F.Cu" "B.Cu")
		(net "GND")
	)
	(via
		(at 343.55786 -131.86918)
		(size 0.508)
		(drill 0.254)
		(layers "F.Cu" "B.Cu")
		(net "GND")
	)
	(via
		(at 461.040734 -164.479224)
		(size 0.5588)
		(drill 0.3048)
		(layers "F.Cu" "B.Cu")
		(net "GND")
	)
	(via
		(at 301.732442 -4.2926)
		(size 0.508)
		(drill 0.254)
		(layers "F.Cu" "B.Cu")
		(net "GND")
	)
	(via
		(at 61.701934 9.084056)
		(size 0.5588)
		(drill 0.3048)
		(layers "F.Cu" "B.Cu")
		(net "GND")
	)
	(via
		(at 118.041928 -148.767292)
		(size 0.508)
		(drill 0.254)
		(layers "F.Cu" "B.Cu")
		(net "GND")
	)
	(via
		(at 288.07664 -74.230738)
		(size 0.508)
		(drill 0.254)
		(layers "F.Cu" "B.Cu")
		(net "GND")
	)
	(via
		(at 90.357198 -63.019686)
		(size 0.508)
		(drill 0.254)
		(layers "F.Cu" "B.Cu")
		(net "GND")
	)
	(via
		(at 283.04236 -145.998946)
		(size 0.508)
		(drill 0.254)
		(layers "F.Cu" "B.Cu")
		(net "GND")
	)
	(via
		(at 344.431366 -136.522968)
		(size 0.508)
		(drill 0.254)
		(layers "F.Cu" "B.Cu")
		(net "GND")
	)
	(via
		(at 381.309626 -105.815384)
		(size 0.508)
		(drill 0.254)
		(layers "F.Cu" "B.Cu")
		(net "GND")
	)
	(via
		(at 339.853524 -162.243262)
		(size 0.5588)
		(drill 0.3048)
		(layers "F.Cu" "B.Cu")
		(net "GND")
	)
	(via
		(at 282.07208 1.9558)
		(size 0.508)
		(drill 0.254)
		(layers "F.Cu" "B.Cu")
		(net "GND")
	)
	(via
		(at 235.612178 -64.50584)
		(size 0.508)
		(drill 0.254)
		(layers "F.Cu" "B.Cu")
		(net "GND")
	)
	(via
		(at 485.881934 10.354056)
		(size 0.5588)
		(drill 0.3048)
		(layers "F.Cu" "B.Cu")
		(net "GND")
	)
	(via
		(at 301.812706 -57.390538)
		(size 0.508)
		(drill 0.254)
		(layers "F.Cu" "B.Cu")
		(net "GND")
	)
	(via
		(at 317.09995 -146.011646)
		(size 0.508)
		(drill 0.254)
		(layers "F.Cu" "B.Cu")
		(net "GND")
	)
	(via
		(at 119.337328 -4.346956)
		(size 0.508)
		(drill 0.254)
		(layers "F.Cu" "B.Cu")
		(net "GND")
	)
	(via
		(at 367.2332 -145.8722)
		(size 0.508)
		(drill 0.254)
		(layers "F.Cu" "B.Cu")
		(net "GND")
	)
	(via
		(at 287.349946 -139.170156)
		(size 0.508)
		(drill 0.254)
		(layers "F.Cu" "B.Cu")
		(net "GND")
	)
	(via
		(at 227.792534 -21.513292)
		(size 0.508)
		(drill 0.254)
		(layers "F.Cu" "B.Cu")
		(net "GND")
	)
	(via
		(at 61.111384 -139.170156)
		(size 0.508)
		(drill 0.254)
		(layers "F.Cu" "B.Cu")
		(net "GND")
	)
	(via
		(at 454.131934 9.084056)
		(size 0.5588)
		(drill 0.3048)
		(layers "F.Cu" "B.Cu")
		(net "GND")
	)
	(via
		(at 311.092596 -145.998946)
		(size 0.508)
		(drill 0.254)
		(layers "F.Cu" "B.Cu")
		(net "GND")
	)
	(via
		(at 32.160464 -150.193756)
		(size 0.508)
		(drill 0.254)
		(layers "F.Cu" "B.Cu")
		(net "GND")
	)
	(via
		(at 240.763298 -78.37424)
		(size 0.508)
		(drill 0.254)
		(layers "F.Cu" "B.Cu")
		(net "GND")
	)
	(via
		(at 82.630772 -58.561986)
		(size 0.508)
		(drill 0.254)
		(layers "F.Cu" "B.Cu")
		(net "GND")
	)
	(via
		(at 131.699508 -155.612846)
		(size 0.508)
		(drill 0.254)
		(layers "F.Cu" "B.Cu")
		(net "GND")
	)
	(via
		(at 284.642814 -91.070938)
		(size 0.508)
		(drill 0.254)
		(layers "F.Cu" "B.Cu")
		(net "GND")
	)
	(via
		(at 479.531934 12.894056)
		(size 0.5588)
		(drill 0.3048)
		(layers "F.Cu" "B.Cu")
		(net "GND")
	)
	(via
		(at 218.44254 -2.310892)
		(size 0.508)
		(drill 0.254)
		(layers "F.Cu" "B.Cu")
		(net "GND")
	)
	(via
		(at 278.994108 -82.300318)
		(size 0.5588)
		(drill 0.3048)
		(layers "F.Cu" "B.Cu")
		(net "GND")
	)
	(via
		(at -2.942844 -50.797206)
		(size 0.5588)
		(drill 0.3048)
		(layers "F.Cu" "B.Cu")
		(net "GND")
	)
	(via
		(at 15.3162 -38.481)
		(size 0.508)
		(drill 0.254)
		(layers "F.Cu" "B.Cu")
		(net "GND")
	)
	(via
		(at 138.040872 -26.682954)
		(size 0.508)
		(drill 0.254)
		(layers "F.Cu" "B.Cu")
		(net "GND")
	)
	(via
		(at 99.569524 -162.243262)
		(size 0.5588)
		(drill 0.3048)
		(layers "F.Cu" "B.Cu")
		(net "GND")
	)
	(via
		(at 127.368808 -93.547184)
		(size 0.508)
		(drill 0.254)
		(layers "F.Cu" "B.Cu")
		(net "GND")
	)
	(via
		(at 273.854418 -75.148186)
		(size 0.5588)
		(drill 0.3048)
		(layers "F.Cu" "B.Cu")
		(net "GND")
	)
	(via
		(at 289.79368 -100.976684)
		(size 0.508)
		(drill 0.254)
		(layers "F.Cu" "B.Cu")
		(net "GND")
	)
	(via
		(at 293.69131 -134.349744)
		(size 0.508)
		(drill 0.254)
		(layers "F.Cu" "B.Cu")
		(net "GND")
	)
	(via
		(at 118.041928 -136.397746)
		(size 0.508)
		(drill 0.254)
		(layers "F.Cu" "B.Cu")
		(net "GND")
	)
	(via
		(at 265.23188 -82.340196)
		(size 0.5588)
		(drill 0.3048)
		(layers "F.Cu" "B.Cu")
		(net "GND")
	)
	(via
		(at 229.081838 -2.3114)
		(size 0.508)
		(drill 0.254)
		(layers "F.Cu" "B.Cu")
		(net "GND")
	)
	(via
		(at 61.149484 -9.156446)
		(size 0.508)
		(drill 0.254)
		(layers "F.Cu" "B.Cu")
		(net "GND")
	)
	(via
		(at 27.98572 -71.35368)
		(size 0.508)
		(drill 0.254)
		(layers "F.Cu" "B.Cu")
		(net "GND")
	)
	(via
		(at 255.35763 -88.775286)
		(size 0.508)
		(drill 0.254)
		(layers "F.Cu" "B.Cu")
		(net "GND")
	)
	(via
		(at 7.794244 -20.305522)
		(size 0.508)
		(drill 0.254)
		(layers "F.Cu" "B.Cu")
		(net "GND")
	)
	(via
		(at 346.4052 -122.3264)
		(size 0.508)
		(drill 0.254)
		(layers "F.Cu" "B.Cu")
		(net "GND")
	)
	(via
		(at 177.931318 4.42595)
		(size 0.5588)
		(drill 0.3048)
		(layers "F.Cu" "B.Cu")
		(net "GND")
	)
	(via
		(at 196.908928 -72.423782)
		(size 0.508)
		(drill 0.254)
		(layers "F.Cu" "B.Cu")
		(net "GND")
	)
	(via
		(at 381.29845 -116.094764)
		(size 0.508)
		(drill 0.254)
		(layers "F.Cu" "B.Cu")
		(net "GND")
	)
	(via
		(at 388.605268 -147.282662)
		(size 0.508)
		(drill 0.254)
		(layers "F.Cu" "B.Cu")
		(net "GND")
	)
	(via
		(at 458.258164 -50.411888)
		(size 0.508)
		(drill 0.254)
		(layers "F.Cu" "B.Cu")
		(net "GND")
	)
	(via
		(at 117.925342 -91.070938)
		(size 0.508)
		(drill 0.254)
		(layers "F.Cu" "B.Cu")
		(net "GND")
	)
	(via
		(at 175.566324 -162.243262)
		(size 0.5588)
		(drill 0.3048)
		(layers "F.Cu" "B.Cu")
		(net "GND")
	)
	(via
		(at 109.914182 -63.334138)
		(size 0.508)
		(drill 0.254)
		(layers "F.Cu" "B.Cu")
		(net "GND")
	)
	(via
		(at 486.560622 -146.508978)
		(size 0.508)
		(drill 0.254)
		(layers "F.Cu" "B.Cu")
		(net "GND")
	)
	(via
		(at 239.904778 -63.019686)
		(size 0.508)
		(drill 0.254)
		(layers "F.Cu" "B.Cu")
		(net "GND")
	)
	(via
		(at 251.923804 -71.935086)
		(size 0.508)
		(drill 0.254)
		(layers "F.Cu" "B.Cu")
		(net "GND")
	)
	(via
		(at 205.749906 -148.771356)
		(size 0.508)
		(drill 0.254)
		(layers "F.Cu" "B.Cu")
		(net "GND")
	)
	(via
		(at 150.399496 -129.568956)
		(size 0.508)
		(drill 0.254)
		(layers "F.Cu" "B.Cu")
		(net "GND")
	)
	(via
		(at 380.30785 -105.332276)
		(size 0.508)
		(drill 0.254)
		(layers "F.Cu" "B.Cu")
		(net "GND")
	)
	(via
		(at 31.833312 -108.526326)
		(size 0.5588)
		(drill 0.3048)
		(layers "F.Cu" "B.Cu")
		(net "GND")
	)
	(via
		(at 346.467176 -78.661514)
		(size 0.508)
		(drill 0.254)
		(layers "F.Cu" "B.Cu")
		(net "GND")
	)
	(via
		(at 76.449428 -129.568956)
		(size 0.508)
		(drill 0.254)
		(layers "F.Cu" "B.Cu")
		(net "GND")
	)
	(via
		(at 291.422074 -154.1018)
		(size 0.508)
		(drill 0.254)
		(layers "F.Cu" "B.Cu")
		(net "GND")
	)
	(via
		(at 196.448426 -68.685156)
		(size 0.5588)
		(drill 0.3048)
		(layers "F.Cu" "B.Cu")
		(net "GND")
	)
	(via
		(at 315.399928 0.444754)
		(size 0.508)
		(drill 0.254)
		(layers "F.Cu" "B.Cu")
		(net "GND")
	)
	(via
		(at 169.949622 -88.42248)
		(size 0.508)
		(drill 0.254)
		(layers "F.Cu" "B.Cu")
		(net "GND")
	)
	(via
		(at 129.944368 -81.164938)
		(size 0.508)
		(drill 0.254)
		(layers "F.Cu" "B.Cu")
		(net "GND")
	)
	(via
		(at 386.821934 14.926056)
		(size 0.5588)
		(drill 0.3048)
		(layers "F.Cu" "B.Cu")
		(net "GND")
	)
	(via
		(at 127.368808 -91.565984)
		(size 0.508)
		(drill 0.254)
		(layers "F.Cu" "B.Cu")
		(net "GND")
	)
	(via
		(at 476.889572 -134.00024)
		(size 0.508)
		(drill 0.254)
		(layers "F.Cu" "B.Cu")
		(net "GND")
	)
	(via
		(at 397.14805 -107.049316)
		(size 0.508)
		(drill 0.254)
		(layers "F.Cu" "B.Cu")
		(net "GND")
	)
	(via
		(at 231.249728 -13.363956)
		(size 0.508)
		(drill 0.254)
		(layers "F.Cu" "B.Cu")
		(net "GND")
	)
	(via
		(at 135.953754 -60.857384)
		(size 0.508)
		(drill 0.254)
		(layers "F.Cu" "B.Cu")
		(net "GND")
	)
	(via
		(at 346.7354 -112.395)
		(size 0.508)
		(drill 0.254)
		(layers "F.Cu" "B.Cu")
		(net "GND")
	)
	(via
		(at 87.781892 -68.46824)
		(size 0.508)
		(drill 0.254)
		(layers "F.Cu" "B.Cu")
		(net "GND")
	)
	(via
		(at 119.357902 -57.885584)
		(size 0.508)
		(drill 0.254)
		(layers "F.Cu" "B.Cu")
		(net "GND")
	)
	(via
		(at 240.599722 -13.363956)
		(size 0.508)
		(drill 0.254)
		(layers "F.Cu" "B.Cu")
		(net "GND")
	)
	(via
		(at 288.65068 -61.352938)
		(size 0.508)
		(drill 0.254)
		(layers "F.Cu" "B.Cu")
		(net "GND")
	)
	(via
		(at 206.904082 -61.529722)
		(size 0.5588)
		(drill 0.3048)
		(layers "F.Cu" "B.Cu")
		(net "GND")
	)
	(via
		(at 92.181934 9.084056)
		(size 0.5588)
		(drill 0.3048)
		(layers "F.Cu" "B.Cu")
		(net "GND")
	)
	(via
		(at 426.191934 13.910056)
		(size 0.5588)
		(drill 0.3048)
		(layers "F.Cu" "B.Cu")
		(net "GND")
	)
	(via
		(at 411.2514 -1.651)
		(size 0.508)
		(drill 0.254)
		(layers "F.Cu" "B.Cu")
		(net "GND")
	)
	(via
		(at 79.196692 -72.43064)
		(size 0.508)
		(drill 0.254)
		(layers "F.Cu" "B.Cu")
		(net "GND")
	)
	(via
		(at 178.0286 -67.0814)
		(size 0.508)
		(drill 0.254)
		(layers "F.Cu" "B.Cu")
		(net "GND")
	)
	(via
		(at 303.529746 -84.136738)
		(size 0.508)
		(drill 0.254)
		(layers "F.Cu" "B.Cu")
		(net "GND")
	)
	(via
		(at 304.349912 -155.612846)
		(size 0.508)
		(drill 0.254)
		(layers "F.Cu" "B.Cu")
		(net "GND")
	)
	(via
		(at 171.1706 -5.8674)
		(size 0.508)
		(drill 0.254)
		(layers "F.Cu" "B.Cu")
		(net "GND")
	)
	(via
		(at 124.801376 -144.462246)
		(size 0.508)
		(drill 0.254)
		(layers "F.Cu" "B.Cu")
		(net "GND")
	)
	(via
		(at 200.881234 -83.874864)
		(size 0.508)
		(drill 0.254)
		(layers "F.Cu" "B.Cu")
		(net "GND")
	)
	(via
		(at 286.499808 -22.965156)
		(size 0.508)
		(drill 0.254)
		(layers "F.Cu" "B.Cu")
		(net "GND")
	)
	(via
		(at 200.553828 -97.3328)
		(size 0.508)
		(drill 0.254)
		(layers "F.Cu" "B.Cu")
		(net "GND")
	)
	(via
		(at 289.79368 -97.014538)
		(size 0.508)
		(drill 0.254)
		(layers "F.Cu" "B.Cu")
		(net "GND")
	)
	(via
		(at 200.8886 -59.436)
		(size 0.508)
		(drill 0.254)
		(layers "F.Cu" "B.Cu")
		(net "GND")
	)
	(via
		(at -5.207 -15.3162)
		(size 0.508)
		(drill 0.254)
		(layers "F.Cu" "B.Cu")
		(net "GND")
	)
	(via
		(at 245.914164 -57.57164)
		(size 0.508)
		(drill 0.254)
		(layers "F.Cu" "B.Cu")
		(net "GND")
	)
	(via
		(at 12.4206 -33.6804)
		(size 0.508)
		(drill 0.254)
		(layers "F.Cu" "B.Cu")
		(net "GND")
	)
	(via
		(at 99.801934 9.084056)
		(size 0.5588)
		(drill 0.3048)
		(layers "F.Cu" "B.Cu")
		(net "GND")
	)
	(via
		(at 228.093524 -162.243262)
		(size 0.5588)
		(drill 0.3048)
		(layers "F.Cu" "B.Cu")
		(net "GND")
	)
	(via
		(at 301.731934 9.084056)
		(size 0.5588)
		(drill 0.3048)
		(layers "F.Cu" "B.Cu")
		(net "GND")
	)
	(via
		(at 392.19505 -119.528844)
		(size 0.508)
		(drill 0.254)
		(layers "F.Cu" "B.Cu")
		(net "GND")
	)
	(via
		(at 282.57246 -79.431642)
		(size 0.5588)
		(drill 0.3048)
		(layers "F.Cu" "B.Cu")
		(net "GND")
	)
	(via
		(at 233.799888 -9.143746)
		(size 0.508)
		(drill 0.254)
		(layers "F.Cu" "B.Cu")
		(net "GND")
	)
	(via
		(at 107.338876 -56.894984)
		(size 0.508)
		(drill 0.254)
		(layers "F.Cu" "B.Cu")
		(net "GND")
	)
	(via
		(at 169.291 -12.192)
		(size 0.508)
		(drill 0.254)
		(layers "F.Cu" "B.Cu")
		(net "GND")
	)
	(via
		(at 297.549824 -131.016756)
		(size 0.508)
		(drill 0.254)
		(layers "F.Cu" "B.Cu")
		(net "GND")
	)
	(via
		(at 225.171 -125.3236)
		(size 0.508)
		(drill 0.254)
		(layers "F.Cu" "B.Cu")
		(net "GND")
	)
	(via
		(at 114.018568 -4.318)
		(size 0.508)
		(drill 0.254)
		(layers "F.Cu" "B.Cu")
		(net "GND")
	)
	(via
		(at 127.368808 -53.923184)
		(size 0.508)
		(drill 0.254)
		(layers "F.Cu" "B.Cu")
		(net "GND")
	)
	(via
		(at 227.792534 -2.310892)
		(size 0.508)
		(drill 0.254)
		(layers "F.Cu" "B.Cu")
		(net "GND")
	)
	(via
		(at 32.160464 -3.737356)
		(size 0.508)
		(drill 0.254)
		(layers "F.Cu" "B.Cu")
		(net "GND")
	)
	(via
		(at 468.925402 -42.785792)
		(size 0.508)
		(drill 0.254)
		(layers "F.Cu" "B.Cu")
		(net "GND")
	)
	(via
		(at 456.671934 14.926056)
		(size 0.5588)
		(drill 0.3048)
		(layers "F.Cu" "B.Cu")
		(net "GND")
	)
	(via
		(at 152.099518 -11.927078)
		(size 0.508)
		(drill 0.254)
		(layers "F.Cu" "B.Cu")
		(net "GND")
	)
	(via
		(at 466.120734 -163.361624)
		(size 0.5588)
		(drill 0.3048)
		(layers "F.Cu" "B.Cu")
		(net "GND")
	)
	(via
		(at -1.239266 9.084056)
		(size 0.5588)
		(drill 0.3048)
		(layers "F.Cu" "B.Cu")
		(net "GND")
	)
	(via
		(at 84.060792 -51.119532)
		(size 0.4572)
		(drill 0.2032)
		(layers "F.Cu" "B.Cu")
		(net "GND")
	)
	(via
		(at 493.5728 -54.5592)
		(size 0.508)
		(drill 0.254)
		(layers "F.Cu" "B.Cu")
		(net "GND")
	)
	(via
		(at 246.772684 -95.709486)
		(size 0.508)
		(drill 0.254)
		(layers "F.Cu" "B.Cu")
		(net "GND")
	)
	(via
		(at 246.619268 -8.1534)
		(size 0.508)
		(drill 0.254)
		(layers "F.Cu" "B.Cu")
		(net "GND")
	)
	(via
		(at 196.908928 -81.186782)
		(size 0.508)
		(drill 0.254)
		(layers "F.Cu" "B.Cu")
		(net "GND")
	)
	(via
		(at 198.061834 -148.771356)
		(size 0.508)
		(drill 0.254)
		(layers "F.Cu" "B.Cu")
		(net "GND")
	)
	(via
		(at 119.642382 -96.023938)
		(size 0.508)
		(drill 0.254)
		(layers "F.Cu" "B.Cu")
		(net "GND")
	)
	(via
		(at 76.621386 -83.822286)
		(size 0.508)
		(drill 0.254)
		(layers "F.Cu" "B.Cu")
		(net "GND")
	)
	(via
		(at 73.4441 -28.66771)
		(size 0.508)
		(drill 0.254)
		(layers "F.Cu" "B.Cu")
		(net "GND")
	)
	(via
		(at 288.65068 -65.315338)
		(size 0.508)
		(drill 0.254)
		(layers "F.Cu" "B.Cu")
		(net "GND")
	)
	(via
		(at 20.701 -108.5596)
		(size 0.5588)
		(drill 0.3048)
		(layers "F.Cu" "B.Cu")
		(net "GND")
	)
	(via
		(at 229.091236 -153.552144)
		(size 0.508)
		(drill 0.254)
		(layers "F.Cu" "B.Cu")
		(net "GND")
	)
	(via
		(at 305.199796 -17.208246)
		(size 0.508)
		(drill 0.254)
		(layers "F.Cu" "B.Cu")
		(net "GND")
	)
	(via
		(at 254.49911 -66.48704)
		(size 0.508)
		(drill 0.254)
		(layers "F.Cu" "B.Cu")
		(net "GND")
	)
	(via
		(at 237.142528 -21.513292)
		(size 0.508)
		(drill 0.254)
		(layers "F.Cu" "B.Cu")
		(net "GND")
	)
	(via
		(at 305.199796 -22.965156)
		(size 0.508)
		(drill 0.254)
		(layers "F.Cu" "B.Cu")
		(net "GND")
	)
	(via
		(at 459.004416 -118.61927)
		(size 0.508)
		(drill 0.254)
		(layers "F.Cu" "B.Cu")
		(net "GND")
	)
	(via
		(at 113.061242 -88.022684)
		(size 0.508)
		(drill 0.254)
		(layers "F.Cu" "B.Cu")
		(net "GND")
	)
	(via
		(at 288.443924 -162.243262)
		(size 0.5588)
		(drill 0.3048)
		(layers "F.Cu" "B.Cu")
		(net "GND")
	)
	(via
		(at 295.849802 -17.208246)
		(size 0.508)
		(drill 0.254)
		(layers "F.Cu" "B.Cu")
		(net "GND")
	)
	(via
		(at 397.6624 -144.2974)
		(size 0.508)
		(drill 0.254)
		(layers "F.Cu" "B.Cu")
		(net "GND")
	)
	(via
		(at 33.099502 -9.139682)
		(size 0.508)
		(drill 0.254)
		(layers "F.Cu" "B.Cu")
		(net "GND")
	)
	(via
		(at 109.340396 -96.023938)
		(size 0.508)
		(drill 0.254)
		(layers "F.Cu" "B.Cu")
		(net "GND")
	)
	(via
		(at 201.037952 -4.346956)
		(size 0.508)
		(drill 0.254)
		(layers "F.Cu" "B.Cu")
		(net "GND")
	)
	(via
		(at 178.919124 -162.243262)
		(size 0.5588)
		(drill 0.3048)
		(layers "F.Cu" "B.Cu")
		(net "GND")
	)
	(via
		(at 215.0999 -145.998946)
		(size 0.508)
		(drill 0.254)
		(layers "F.Cu" "B.Cu")
		(net "GND")
	)
	(via
		(at 301.812706 -53.427884)
		(size 0.508)
		(drill 0.254)
		(layers "F.Cu" "B.Cu")
		(net "GND")
	)
	(via
		(at 135.095234 -98.995738)
		(size 0.508)
		(drill 0.254)
		(layers "F.Cu" "B.Cu")
		(net "GND")
	)
	(via
		(at 373.544846 -73.495154)
		(size 0.4572)
		(drill 0.2032)
		(layers "F.Cu" "B.Cu")
		(net "GND")
	)
	(via
		(at 138.040872 -16.696944)
		(size 0.508)
		(drill 0.254)
		(layers "F.Cu" "B.Cu")
		(net "GND")
	)
	(via
		(at 227.792534 -136.397746)
		(size 0.508)
		(drill 0.254)
		(layers "F.Cu" "B.Cu")
		(net "GND")
	)
	(via
		(at 269.416276 -95.21444)
		(size 0.508)
		(drill 0.254)
		(layers "F.Cu" "B.Cu")
		(net "GND")
	)
	(via
		(at 312.387996 -150.803356)
		(size 0.508)
		(drill 0.254)
		(layers "F.Cu" "B.Cu")
		(net "GND")
	)
	(via
		(at 198.061834 -139.170156)
		(size 0.508)
		(drill 0.254)
		(layers "F.Cu" "B.Cu")
		(net "GND")
	)
	(via
		(at 381.79375 -110.085124)
		(size 0.508)
		(drill 0.254)
		(layers "F.Cu" "B.Cu")
		(net "GND")
	)
	(via
		(at 71.171562 -140.617956)
		(size 0.508)
		(drill 0.254)
		(layers "F.Cu" "B.Cu")
		(net "GND")
	)
	(via
		(at 372.194836 -157.115256)
		(size 0.508)
		(drill 0.254)
		(layers "F.Cu" "B.Cu")
		(net "GND")
	)
	(via
		(at 91.215718 -86.29904)
		(size 0.508)
		(drill 0.254)
		(layers "F.Cu" "B.Cu")
		(net "GND")
	)
	(via
		(at 25.171908 3.05054)
		(size 0.508)
		(drill 0.254)
		(layers "F.Cu" "B.Cu")
		(net "GND")
	)
	(via
		(at 104.984296 -158.383986)
		(size 0.508)
		(drill 0.254)
		(layers "F.Cu" "B.Cu")
		(net "GND")
	)
	(via
		(at 358.3432 -80.2894)
		(size 0.508)
		(drill 0.254)
		(layers "F.Cu" "B.Cu")
		(net "GND")
	)
	(via
		(at 31.395924 -162.243262)
		(size 0.5588)
		(drill 0.3048)
		(layers "F.Cu" "B.Cu")
		(net "GND")
	)
	(via
		(at 173.461934 9.084056)
		(size 0.5588)
		(drill 0.3048)
		(layers "F.Cu" "B.Cu")
		(net "GND")
	)
	(via
		(at 86.923372 -56.085486)
		(size 0.508)
		(drill 0.254)
		(layers "F.Cu" "B.Cu")
		(net "GND")
	)
	(via
		(at 73.187306 -87.784686)
		(size 0.508)
		(drill 0.254)
		(layers "F.Cu" "B.Cu")
		(net "GND")
	)
	(via
		(at 487.151934 10.354056)
		(size 0.5588)
		(drill 0.3048)
		(layers "F.Cu" "B.Cu")
		(net "GND")
	)
	(via
		(at 121.359168 -97.014538)
		(size 0.508)
		(drill 0.254)
		(layers "F.Cu" "B.Cu")
		(net "GND")
	)
	(via
		(at 438.891934 12.894056)
		(size 0.5588)
		(drill 0.3048)
		(layers "F.Cu" "B.Cu")
		(net "GND")
	)
	(via
		(at 73.440798 -134.349744)
		(size 0.508)
		(drill 0.254)
		(layers "F.Cu" "B.Cu")
		(net "GND")
	)
	(via
		(at 356.615492 -109.16285)
		(size 0.508)
		(drill 0.254)
		(layers "F.Cu" "B.Cu")
		(net "GND")
	)
	(via
		(at 233.799888 -11.916156)
		(size 0.508)
		(drill 0.254)
		(layers "F.Cu" "B.Cu")
		(net "GND")
	)
	(via
		(at 344.8304 -1.30556)
		(size 0.508)
		(drill 0.254)
		(layers "F.Cu" "B.Cu")
		(net "GND")
	)
	(via
		(at 218.436444 -131.5466)
		(size 0.508)
		(drill 0.254)
		(layers "F.Cu" "B.Cu")
		(net "GND")
	)
	(via
		(at 52.811934 14.926056)
		(size 0.5588)
		(drill 0.3048)
		(layers "F.Cu" "B.Cu")
		(net "GND")
	)
	(via
		(at 76.621386 -80.850486)
		(size 0.508)
		(drill 0.254)
		(layers "F.Cu" "B.Cu")
		(net "GND")
	)
	(via
		(at 37.571934 14.926056)
		(size 0.5588)
		(drill 0.3048)
		(layers "F.Cu" "B.Cu")
		(net "GND")
	)
	(via
		(at 273.482308 -95.528384)
		(size 0.508)
		(drill 0.254)
		(layers "F.Cu" "B.Cu")
		(net "GND")
	)
	(via
		(at 54.737508 -131.600956)
		(size 0.508)
		(drill 0.254)
		(layers "F.Cu" "B.Cu")
		(net "GND")
	)
	(via
		(at 389.22325 -98.464116)
		(size 0.508)
		(drill 0.254)
		(layers "F.Cu" "B.Cu")
		(net "GND")
	)
	(via
		(at 130.866134 -167.832024)
		(size 0.5588)
		(drill 0.3048)
		(layers "F.Cu" "B.Cu")
		(net "GND")
	)
	(via
		(at 212.54974 1.994154)
		(size 0.508)
		(drill 0.254)
		(layers "F.Cu" "B.Cu")
		(net "GND")
	)
	(via
		(at 33.634934 -167.832024)
		(size 0.5588)
		(drill 0.3048)
		(layers "F.Cu" "B.Cu")
		(net "GND")
	)
	(via
		(at 41.45915 -62.164722)
		(size 0.5588)
		(drill 0.3048)
		(layers "F.Cu" "B.Cu")
		(net "GND")
	)
	(via
		(at 353.695 -150.368)
		(size 0.508)
		(drill 0.254)
		(layers "F.Cu" "B.Cu")
		(net "GND")
	)
	(via
		(at 410.690822 -35.758628)
		(size 0.4572)
		(drill 0.2032)
		(layers "F.Cu" "B.Cu")
		(net "GND")
	)
	(via
		(at 123.039124 -162.243262)
		(size 0.5588)
		(drill 0.3048)
		(layers "F.Cu" "B.Cu")
		(net "GND")
	)
	(via
		(at 36.044124 -155.5369)
		(size 0.508)
		(drill 0.254)
		(layers "F.Cu" "B.Cu")
		(net "GND")
	)
	(via
		(at 114.206782 -57.885584)
		(size 0.508)
		(drill 0.254)
		(layers "F.Cu" "B.Cu")
		(net "GND")
	)
	(via
		(at 240.763298 -50.63744)
		(size 0.508)
		(drill 0.254)
		(layers "F.Cu" "B.Cu")
		(net "GND")
	)
	(via
		(at 219.73794 -141.202156)
		(size 0.508)
		(drill 0.254)
		(layers "F.Cu" "B.Cu")
		(net "GND")
	)
	(via
		(at 263.0805 -127.763524)
		(size 0.508)
		(drill 0.254)
		(layers "F.Cu" "B.Cu")
		(net "GND")
	)
	(via
		(at 45.387514 -141.202156)
		(size 0.508)
		(drill 0.254)
		(layers "F.Cu" "B.Cu")
		(net "GND")
	)
	(via
		(at 127.382016 -4.2926)
		(size 0.508)
		(drill 0.254)
		(layers "F.Cu" "B.Cu")
		(net "GND")
	)
	(via
		(at 480.090734 -167.832024)
		(size 0.5588)
		(drill 0.3048)
		(layers "F.Cu" "B.Cu")
		(net "GND")
	)
	(via
		(at 41.5036 -54.0766)
		(size 0.5588)
		(drill 0.3048)
		(layers "F.Cu" "B.Cu")
		(net "GND")
	)
	(via
		(at 274.921218 -75.148186)
		(size 0.5588)
		(drill 0.3048)
		(layers "F.Cu" "B.Cu")
		(net "GND")
	)
	(via
		(at 349.421704 -1.93802)
		(size 0.508)
		(drill 0.254)
		(layers "F.Cu" "B.Cu")
		(net "GND")
	)
	(via
		(at 207.980534 -167.832024)
		(size 0.5588)
		(drill 0.3048)
		(layers "F.Cu" "B.Cu")
		(net "GND")
	)
	(via
		(at 202.349862 -11.916156)
		(size 0.508)
		(drill 0.254)
		(layers "F.Cu" "B.Cu")
		(net "GND")
	)
	(via
		(at 135.095234 -85.127338)
		(size 0.508)
		(drill 0.254)
		(layers "F.Cu" "B.Cu")
		(net "GND")
	)
	(via
		(at 205.749906 -11.916156)
		(size 0.508)
		(drill 0.254)
		(layers "F.Cu" "B.Cu")
		(net "GND")
	)
	(via
		(at 11.2522 -36.7792)
		(size 0.508)
		(drill 0.254)
		(layers "F.Cu" "B.Cu")
		(net "GND")
	)
	(via
		(at 243.338604 -93.72854)
		(size 0.508)
		(drill 0.254)
		(layers "F.Cu" "B.Cu")
		(net "GND")
	)
	(via
		(at 382.458722 -131.093718)
		(size 0.508)
		(drill 0.254)
		(layers "F.Cu" "B.Cu")
		(net "GND")
	)
	(via
		(at 215.2904 -68.1228)
		(size 0.508)
		(drill 0.254)
		(layers "F.Cu" "B.Cu")
		(net "GND")
	)
	(via
		(at 317.949834 -16.687546)
		(size 0.508)
		(drill 0.254)
		(layers "F.Cu" "B.Cu")
		(net "GND")
	)
	(via
		(at 77.479906 -70.44944)
		(size 0.508)
		(drill 0.254)
		(layers "F.Cu" "B.Cu")
		(net "GND")
	)
	(via
		(at 88.640412 -53.113686)
		(size 0.508)
		(drill 0.254)
		(layers "F.Cu" "B.Cu")
		(net "GND")
	)
	(via
		(at 307.040026 -71.258938)
		(size 0.508)
		(drill 0.254)
		(layers "F.Cu" "B.Cu")
		(net "GND")
	)
	(via
		(at 299.160946 -27.918156)
		(size 0.508)
		(drill 0.254)
		(layers "F.Cu" "B.Cu")
		(net "GND")
	)
	(via
		(at 238.187738 -101.653086)
		(size 0.508)
		(drill 0.254)
		(layers "F.Cu" "B.Cu")
		(net "GND")
	)
	(via
		(at 136.754362 2.4638)
		(size 0.508)
		(drill 0.254)
		(layers "F.Cu" "B.Cu")
		(net "GND")
	)
	(via
		(at 76.621386 -65.991486)
		(size 0.508)
		(drill 0.254)
		(layers "F.Cu" "B.Cu")
		(net "GND")
	)
	(via
		(at 309.449978 -9.156446)
		(size 0.508)
		(drill 0.254)
		(layers "F.Cu" "B.Cu")
		(net "GND")
	)
	(via
		(at 49.403 -91.4908)
		(size 0.508)
		(drill 0.254)
		(layers "F.Cu" "B.Cu")
		(net "GND")
	)
	(via
		(at 229.094538 -155.5369)
		(size 0.508)
		(drill 0.254)
		(layers "F.Cu" "B.Cu")
		(net "GND")
	)
	(via
		(at 33.771586 -144.5006)
		(size 0.508)
		(drill 0.254)
		(layers "F.Cu" "B.Cu")
		(net "GND")
	)
	(via
		(at 292.36924 -56.894984)
		(size 0.508)
		(drill 0.254)
		(layers "F.Cu" "B.Cu")
		(net "GND")
	)
	(via
		(at 279.798018 -75.148186)
		(size 0.5588)
		(drill 0.3048)
		(layers "F.Cu" "B.Cu")
		(net "GND")
	)
	(via
		(at 468.561928 1.999996)
		(size 0.5588)
		(drill 0.3048)
		(layers "F.Cu" "B.Cu")
		(net "GND")
	)
	(via
		(at 369.041934 14.926056)
		(size 0.5588)
		(drill 0.3048)
		(layers "F.Cu" "B.Cu")
		(net "GND")
	)
	(via
		(at 349.26016 -77.25029)
		(size 0.508)
		(drill 0.254)
		(layers "F.Cu" "B.Cu")
		(net "GND")
	)
	(via
		(at 4.70662 -24.08936)
		(size 0.508)
		(drill 0.254)
		(layers "F.Cu" "B.Cu")
		(net "GND")
	)
	(via
		(at 417.860734 -165.596824)
		(size 0.5588)
		(drill 0.3048)
		(layers "F.Cu" "B.Cu")
		(net "GND")
	)
	(via
		(at 87.279734 -167.832024)
		(size 0.5588)
		(drill 0.3048)
		(layers "F.Cu" "B.Cu")
		(net "GND")
	)
	(via
		(at 125.749558 -155.612846)
		(size 0.508)
		(drill 0.254)
		(layers "F.Cu" "B.Cu")
		(net "GND")
	)
	(via
		(at 304.090324 -162.243262)
		(size 0.5588)
		(drill 0.3048)
		(layers "F.Cu" "B.Cu")
		(net "GND")
	)
	(via
		(at 478.820734 -163.361624)
		(size 0.5588)
		(drill 0.3048)
		(layers "F.Cu" "B.Cu")
		(net "GND")
	)
	(via
		(at 383.228088 -134.725664)
		(size 0.508)
		(drill 0.254)
		(layers "F.Cu" "B.Cu")
		(net "GND")
	)
	(via
		(at 475.721934 14.926056)
		(size 0.5588)
		(drill 0.3048)
		(layers "F.Cu" "B.Cu")
		(net "GND")
	)
	(via
		(at -5.213604 -11.242802)
		(size 0.508)
		(drill 0.254)
		(layers "F.Cu" "B.Cu")
		(net "GND")
	)
	(via
		(at 398.13865 -114.377724)
		(size 0.508)
		(drill 0.254)
		(layers "F.Cu" "B.Cu")
		(net "GND")
	)
	(via
		(at 232.101898 -87.28964)
		(size 0.508)
		(drill 0.254)
		(layers "F.Cu" "B.Cu")
		(net "GND")
	)
	(via
		(at 114.621818 -82.416904)
		(size 0.5588)
		(drill 0.3048)
		(layers "F.Cu" "B.Cu")
		(net "GND")
	)
	(via
		(at 93.451934 14.926056)
		(size 0.5588)
		(drill 0.3048)
		(layers "F.Cu" "B.Cu")
		(net "GND")
	)
	(via
		(at 244.581934 9.084056)
		(size 0.5588)
		(drill 0.3048)
		(layers "F.Cu" "B.Cu")
		(net "GND")
	)
	(via
		(at 258.79171 -56.085486)
		(size 0.508)
		(drill 0.254)
		(layers "F.Cu" "B.Cu")
		(net "GND")
	)
	(via
		(at 231.249728 -154.063446)
		(size 0.508)
		(drill 0.254)
		(layers "F.Cu" "B.Cu")
		(net "GND")
	)
	(via
		(at 461.751934 14.926056)
		(size 0.5588)
		(drill 0.3048)
		(layers "F.Cu" "B.Cu")
		(net "GND")
	)
	(via
		(at 122.661934 14.926056)
		(size 0.5588)
		(drill 0.3048)
		(layers "F.Cu" "B.Cu")
		(net "GND")
	)
	(via
		(at 483.900734 -166.714424)
		(size 0.5588)
		(drill 0.3048)
		(layers "F.Cu" "B.Cu")
		(net "GND")
	)
	(via
		(at 477.393 -20.1422)
		(size 0.508)
		(drill 0.254)
		(layers "F.Cu" "B.Cu")
		(net "GND")
	)
	(via
		(at 59.161934 14.926056)
		(size 0.5588)
		(drill 0.3048)
		(layers "F.Cu" "B.Cu")
		(net "GND")
	)
	(via
		(at 90.871548 -13.292582)
		(size 0.508)
		(drill 0.254)
		(layers "F.Cu" "B.Cu")
		(net "GND")
	)
	(via
		(at 185.899298 -10.392664)
		(size 0.508)
		(drill 0.254)
		(layers "F.Cu" "B.Cu")
		(net "GND")
	)
	(via
		(at 344.490294 -8.767318)
		(size 0.508)
		(drill 0.254)
		(layers "F.Cu" "B.Cu")
		(net "GND")
	)
	(via
		(at 455.960734 -163.361624)
		(size 0.5588)
		(drill 0.3048)
		(layers "F.Cu" "B.Cu")
		(net "GND")
	)
	(via
		(at 50.860452 -3.737356)
		(size 0.508)
		(drill 0.254)
		(layers "F.Cu" "B.Cu")
		(net "GND")
	)
	(via
		(at 290.6522 -85.622384)
		(size 0.508)
		(drill 0.254)
		(layers "F.Cu" "B.Cu")
		(net "GND")
	)
	(via
		(at 34.74212 -9.143746)
		(size 0.508)
		(drill 0.254)
		(layers "F.Cu" "B.Cu")
		(net "GND")
	)
	(via
		(at 20.2438 -104.0638)
		(size 0.5588)
		(drill 0.3048)
		(layers "F.Cu" "B.Cu")
		(net "GND")
	)
	(via
		(at 487.706924 -162.243262)
		(size 0.5588)
		(drill 0.3048)
		(layers "F.Cu" "B.Cu")
		(net "GND")
	)
	(via
		(at 386.25145 -96.747076)
		(size 0.508)
		(drill 0.254)
		(layers "F.Cu" "B.Cu")
		(net "GND")
	)
	(via
		(at 108.197396 -62.343538)
		(size 0.508)
		(drill 0.254)
		(layers "F.Cu" "B.Cu")
		(net "GND")
	)
	(via
		(at 348.383606 1.504696)
		(size 0.508)
		(drill 0.254)
		(layers "F.Cu" "B.Cu")
		(net "GND")
	)
	(via
		(at 362.966 -111.012986)
		(size 0.508)
		(drill 0.254)
		(layers "F.Cu" "B.Cu")
		(net "GND")
	)
	(via
		(at 356.24008 -104.964484)
		(size 0.508)
		(drill 0.254)
		(layers "F.Cu" "B.Cu")
		(net "GND")
	)
	(via
		(at 299.160946 -150.193756)
		(size 0.508)
		(drill 0.254)
		(layers "F.Cu" "B.Cu")
		(net "GND")
	)
	(via
		(at 494.060734 -164.479224)
		(size 0.5588)
		(drill 0.3048)
		(layers "F.Cu" "B.Cu")
		(net "GND")
	)
	(via
		(at 347.9546 -59.679586)
		(size 0.508)
		(drill 0.254)
		(layers "F.Cu" "B.Cu")
		(net "GND")
	)
	(via
		(at 365.5949 -103.3526)
		(size 0.508)
		(drill 0.254)
		(layers "F.Cu" "B.Cu")
		(net "GND")
	)
	(via
		(at 239.046258 -72.43064)
		(size 0.508)
		(drill 0.254)
		(layers "F.Cu" "B.Cu")
		(net "GND")
	)
	(via
		(at 138.040872 -153.552144)
		(size 0.508)
		(drill 0.254)
		(layers "F.Cu" "B.Cu")
		(net "GND")
	)
	(via
		(at 351.261934 14.926056)
		(size 0.5588)
		(drill 0.3048)
		(layers "F.Cu" "B.Cu")
		(net "GND")
	)
	(via
		(at 396.270734 -167.832024)
		(size 0.5588)
		(drill 0.3048)
		(layers "F.Cu" "B.Cu")
		(net "GND")
	)
	(via
		(at 185.6994 -92.0242)
		(size 0.508)
		(drill 0.254)
		(layers "F.Cu" "B.Cu")
		(net "GND")
	)
	(via
		(at 473.736924 -162.243262)
		(size 0.5588)
		(drill 0.3048)
		(layers "F.Cu" "B.Cu")
		(net "GND")
	)
	(via
		(at 214.249762 -22.965156)
		(size 0.508)
		(drill 0.254)
		(layers "F.Cu" "B.Cu")
		(net "GND")
	)
	(via
		(at 264.978134 -167.832024)
		(size 0.5588)
		(drill 0.3048)
		(layers "F.Cu" "B.Cu")
		(net "GND")
	)
	(via
		(at 240.763298 -70.44944)
		(size 0.508)
		(drill 0.254)
		(layers "F.Cu" "B.Cu")
		(net "GND")
	)
	(via
		(at 294.9448 -82.155284)
		(size 0.508)
		(drill 0.254)
		(layers "F.Cu" "B.Cu")
		(net "GND")
	)
	(via
		(at 177.271934 14.926056)
		(size 0.5588)
		(drill 0.3048)
		(layers "F.Cu" "B.Cu")
		(net "GND")
	)
	(via
		(at 50.099468 -11.916156)
		(size 0.508)
		(drill 0.254)
		(layers "F.Cu" "B.Cu")
		(net "GND")
	)
	(via
		(at 424.210734 -167.832024)
		(size 0.5588)
		(drill 0.3048)
		(layers "F.Cu" "B.Cu")
		(net "GND")
	)
	(via
		(at 477.1517 -25.26538)
		(size 0.508)
		(drill 0.254)
		(layers "F.Cu" "B.Cu")
		(net "GND")
	)
	(via
		(at 442.701934 14.926056)
		(size 0.5588)
		(drill 0.3048)
		(layers "F.Cu" "B.Cu")
		(net "GND")
	)
	(via
		(at 464.4898 -50.4952)
		(size 0.508)
		(drill 0.254)
		(layers "F.Cu" "B.Cu")
		(net "GND")
	)
	(via
		(at 123.076208 -94.042738)
		(size 0.508)
		(drill 0.254)
		(layers "F.Cu" "B.Cu")
		(net "GND")
	)
	(via
		(at 346.7354 -113.665)
		(size 0.508)
		(drill 0.254)
		(layers "F.Cu" "B.Cu")
		(net "GND")
	)
	(via
		(at 56.049418 -139.170156)
		(size 0.508)
		(drill 0.254)
		(layers "F.Cu" "B.Cu")
		(net "GND")
	)
	(via
		(at 384.937 -105.8545)
		(size 0.508)
		(drill 0.254)
		(layers "F.Cu" "B.Cu")
		(net "GND")
	)
	(via
		(at 336.5754 -109.855)
		(size 0.508)
		(drill 0.254)
		(layers "F.Cu" "B.Cu")
		(net "GND")
	)
	(via
		(at 473.432632 -35.811968)
		(size 0.508)
		(drill 0.254)
		(layers "F.Cu" "B.Cu")
		(net "GND")
	)
	(via
		(at 500.410734 -163.361624)
		(size 0.5588)
		(drill 0.3048)
		(layers "F.Cu" "B.Cu")
		(net "GND")
	)
	(via
		(at 131.661408 -52.43703)
		(size 0.508)
		(drill 0.254)
		(layers "F.Cu" "B.Cu")
		(net "GND")
	)
	(via
		(at 4.3434 -146.6596)
		(size 0.508)
		(drill 0.254)
		(layers "F.Cu" "B.Cu")
		(net "GND")
	)
	(via
		(at 455.401934 9.084056)
		(size 0.5588)
		(drill 0.3048)
		(layers "F.Cu" "B.Cu")
		(net "GND")
	)
	(via
		(at 239.749838 -2.314956)
		(size 0.508)
		(drill 0.254)
		(layers "F.Cu" "B.Cu")
		(net "GND")
	)
	(via
		(at 236.171994 -150.219156)
		(size 0.508)
		(drill 0.254)
		(layers "F.Cu" "B.Cu")
		(net "GND")
	)
	(via
		(at 151.24938 -150.219156)
		(size 0.508)
		(drill 0.254)
		(layers "F.Cu" "B.Cu")
		(net "GND")
	)
	(via
		(at 33.061402 -139.170156)
		(size 0.508)
		(drill 0.254)
		(layers "F.Cu" "B.Cu")
		(net "GND")
	)
	(via
		(at 274.07108 -82.340196)
		(size 0.5588)
		(drill 0.3048)
		(layers "F.Cu" "B.Cu")
		(net "GND")
	)
	(via
		(at 91.215718 -65.49644)
		(size 0.508)
		(drill 0.254)
		(layers "F.Cu" "B.Cu")
		(net "GND")
	)
	(via
		(at 36.03752 -4.346956)
		(size 0.508)
		(drill 0.254)
		(layers "F.Cu" "B.Cu")
		(net "GND")
	)
	(via
		(at 378.82195 -99.322636)
		(size 0.508)
		(drill 0.254)
		(layers "F.Cu" "B.Cu")
		(net "GND")
	)
	(via
		(at 204.0128 -54.1274)
		(size 0.5588)
		(drill 0.3048)
		(layers "F.Cu" "B.Cu")
		(net "GND")
	)
	(via
		(at 256.0828 -7.806944)
		(size 0.508)
		(drill 0.254)
		(layers "F.Cu" "B.Cu")
		(net "GND")
	)
	(via
		(at 278.348694 -60.362338)
		(size 0.508)
		(drill 0.254)
		(layers "F.Cu" "B.Cu")
		(net "GND")
	)
	(via
		(at 463.021934 9.084056)
		(size 0.5588)
		(drill 0.3048)
		(layers "F.Cu" "B.Cu")
		(net "GND")
	)
	(via
		(at 214.0204 -84.201)
		(size 0.508)
		(drill 0.254)
		(layers "F.Cu" "B.Cu")
		(net "GND")
	)
	(via
		(at 298.399962 -18.744946)
		(size 0.508)
		(drill 0.254)
		(layers "F.Cu" "B.Cu")
		(net "GND")
	)
	(via
		(at 372.618 -115.3414)
		(size 0.508)
		(drill 0.254)
		(layers "F.Cu" "B.Cu")
		(net "GND")
	)
	(via
		(at 124.793248 -93.052138)
		(size 0.508)
		(drill 0.254)
		(layers "F.Cu" "B.Cu")
		(net "GND")
	)
	(via
		(at 193.704464 -68.608702)
		(size 0.508)
		(drill 0.254)
		(layers "F.Cu" "B.Cu")
		(net "GND")
	)
	(via
		(at 56.899302 1.994154)
		(size 0.508)
		(drill 0.254)
		(layers "F.Cu" "B.Cu")
		(net "GND")
	)
	(via
		(at 76.941934 9.084056)
		(size 0.5588)
		(drill 0.3048)
		(layers "F.Cu" "B.Cu")
		(net "GND")
	)
	(via
		(at 225.210878 -3.737356)
		(size 0.508)
		(drill 0.254)
		(layers "F.Cu" "B.Cu")
		(net "GND")
	)
	(via
		(at 462.204308 -118.61927)
		(size 0.508)
		(drill 0.254)
		(layers "F.Cu" "B.Cu")
		(net "GND")
	)
	(via
		(at 449.950586 -13.38453)
		(size 0.508)
		(drill 0.254)
		(layers "F.Cu" "B.Cu")
		(net "GND")
	)
	(via
		(at 395.000734 -164.479224)
		(size 0.5588)
		(drill 0.3048)
		(layers "F.Cu" "B.Cu")
		(net "GND")
	)
	(via
		(at 305.199796 -144.462246)
		(size 0.508)
		(drill 0.254)
		(layers "F.Cu" "B.Cu")
		(net "GND")
	)
	(via
		(at 401.955 -93.8784)
		(size 0.508)
		(drill 0.254)
		(layers "F.Cu" "B.Cu")
		(net "GND")
	)
	(via
		(at -3.603244 -50.035206)
		(size 0.5588)
		(drill 0.3048)
		(layers "F.Cu" "B.Cu")
		(net "GND")
	)
	(via
		(at 413.890206 -38.134544)
		(size 0.4572)
		(drill 0.2032)
		(layers "F.Cu" "B.Cu")
		(net "GND")
	)
	(via
		(at 241.44986 -148.771356)
		(size 0.508)
		(drill 0.254)
		(layers "F.Cu" "B.Cu")
		(net "GND")
	)
	(via
		(at 33.061402 -21.517356)
		(size 0.508)
		(drill 0.254)
		(layers "F.Cu" "B.Cu")
		(net "GND")
	)
	(via
		(at 335.1022 -134.0739)
		(size 0.508)
		(drill 0.254)
		(layers "F.Cu" "B.Cu")
		(net "GND")
	)
	(via
		(at 190.933832 -18.7452)
		(size 0.508)
		(drill 0.254)
		(layers "F.Cu" "B.Cu")
		(net "GND")
	)
	(via
		(at 85.206332 -65.991486)
		(size 0.508)
		(drill 0.254)
		(layers "F.Cu" "B.Cu")
		(net "GND")
	)
	(via
		(at 229.094538 -18.6817)
		(size 0.508)
		(drill 0.254)
		(layers "F.Cu" "B.Cu")
		(net "GND")
	)
	(via
		(at 60.210446 -130.991356)
		(size 0.508)
		(drill 0.254)
		(layers "F.Cu" "B.Cu")
		(net "GND")
	)
	(via
		(at 238.437928 -150.803356)
		(size 0.508)
		(drill 0.254)
		(layers "F.Cu" "B.Cu")
		(net "GND")
	)
	(via
		(at 294.9448 -55.409338)
		(size 0.508)
		(drill 0.254)
		(layers "F.Cu" "B.Cu")
		(net "GND")
	)
	(via
		(at 476.991934 11.624056)
		(size 0.5588)
		(drill 0.3048)
		(layers "F.Cu" "B.Cu")
		(net "GND")
	)
	(via
		(at 72.1487 2.4511)
		(size 0.508)
		(drill 0.254)
		(layers "F.Cu" "B.Cu")
		(net "GND")
	)
	(via
		(at 444.530734 -163.361624)
		(size 0.5588)
		(drill 0.3048)
		(layers "F.Cu" "B.Cu")
		(net "GND")
	)
	(via
		(at 107.027472 -3.3528)
		(size 0.508)
		(drill 0.254)
		(layers "F.Cu" "B.Cu")
		(net "GND")
	)
	(via
		(at 117.071648 -134.8994)
		(size 0.508)
		(drill 0.254)
		(layers "F.Cu" "B.Cu")
		(net "GND")
	)
	(via
		(at 288.93516 -80.669384)
		(size 0.508)
		(drill 0.254)
		(layers "F.Cu" "B.Cu")
		(net "GND")
	)
	(via
		(at 56.899302 -3.762756)
		(size 0.508)
		(drill 0.254)
		(layers "F.Cu" "B.Cu")
		(net "GND")
	)
	(via
		(at 202.671934 9.084056)
		(size 0.5588)
		(drill 0.3048)
		(layers "F.Cu" "B.Cu")
		(net "GND")
	)
	(via
		(at 142.749524 -2.314956)
		(size 0.508)
		(drill 0.254)
		(layers "F.Cu" "B.Cu")
		(net "GND")
	)
	(via
		(at 395.000734 -166.714424)
		(size 0.5588)
		(drill 0.3048)
		(layers "F.Cu" "B.Cu")
		(net "GND")
	)
	(via
		(at 284.331664 -139.1666)
		(size 0.508)
		(drill 0.254)
		(layers "F.Cu" "B.Cu")
		(net "GND")
	)
	(via
		(at 26.913332 -131.7117)
		(size 0.508)
		(drill 0.254)
		(layers "F.Cu" "B.Cu")
		(net "GND")
	)
	(via
		(at 90.861896 -144.646396)
		(size 0.508)
		(drill 0.254)
		(layers "F.Cu" "B.Cu")
		(net "GND")
	)
	(via
		(at 341.6554 -39.37)
		(size 0.508)
		(drill 0.254)
		(layers "F.Cu" "B.Cu")
		(net "GND")
	)
	(via
		(at 404.601934 9.084056)
		(size 0.5588)
		(drill 0.3048)
		(layers "F.Cu" "B.Cu")
		(net "GND")
	)
	(via
		(at 362.966 -112.4204)
		(size 0.508)
		(drill 0.254)
		(layers "F.Cu" "B.Cu")
		(net "GND")
	)
	(via
		(at 6.3754 -14.3002)
		(size 0.508)
		(drill 0.254)
		(layers "F.Cu" "B.Cu")
		(net "GND")
	)
	(via
		(at 459.838298 -145.14449)
		(size 0.508)
		(drill 0.254)
		(layers "F.Cu" "B.Cu")
		(net "GND")
	)
	(via
		(at 454.131934 12.894056)
		(size 0.5588)
		(drill 0.3048)
		(layers "F.Cu" "B.Cu")
		(net "GND")
	)
	(via
		(at 233.895138 -97.19564)
		(size 0.508)
		(drill 0.254)
		(layers "F.Cu" "B.Cu")
		(net "GND")
	)
	(via
		(at 446.511934 9.084056)
		(size 0.5588)
		(drill 0.3048)
		(layers "F.Cu" "B.Cu")
		(net "GND")
	)
	(via
		(at 337.0072 -26.4795)
		(size 0.508)
		(drill 0.254)
		(layers "F.Cu" "B.Cu")
		(net "GND")
	)
	(via
		(at 69.753226 -64.010286)
		(size 0.508)
		(drill 0.254)
		(layers "F.Cu" "B.Cu")
		(net "GND")
	)
	(via
		(at 281.361896 -11.916156)
		(size 0.508)
		(drill 0.254)
		(layers "F.Cu" "B.Cu")
		(net "GND")
	)
	(via
		(at 469.6206 -138.557)
		(size 0.508)
		(drill 0.254)
		(layers "F.Cu" "B.Cu")
		(net "GND")
	)
	(via
		(at 90.357198 -56.085486)
		(size 0.508)
		(drill 0.254)
		(layers "F.Cu" "B.Cu")
		(net "GND")
	)
	(via
		(at 249.348244 -71.44004)
		(size 0.508)
		(drill 0.254)
		(layers "F.Cu" "B.Cu")
		(net "GND")
	)
	(via
		(at 355.071934 9.084056)
		(size 0.5588)
		(drill 0.3048)
		(layers "F.Cu" "B.Cu")
		(net "GND")
	)
	(via
		(at 53.448712 -134.4041)
		(size 0.508)
		(drill 0.254)
		(layers "F.Cu" "B.Cu")
		(net "GND")
	)
	(via
		(at 196.908928 -73.058782)
		(size 0.508)
		(drill 0.254)
		(layers "F.Cu" "B.Cu")
		(net "GND")
	)
	(via
		(at 84.910168 -149.8092)
		(size 0.508)
		(drill 0.254)
		(layers "F.Cu" "B.Cu")
		(net "GND")
	)
	(via
		(at 34.991802 -70.920864)
		(size 0.508)
		(drill 0.254)
		(layers "F.Cu" "B.Cu")
		(net "GND")
	)
	(via
		(at 56.049418 -155.612846)
		(size 0.508)
		(drill 0.254)
		(layers "F.Cu" "B.Cu")
		(net "GND")
	)
	(via
		(at 451.866 -152.1206)
		(size 0.508)
		(drill 0.254)
		(layers "F.Cu" "B.Cu")
		(net "GND")
	)
	(via
		(at 81.772252 -95.709486)
		(size 0.508)
		(drill 0.254)
		(layers "F.Cu" "B.Cu")
		(net "GND")
	)
	(via
		(at 82.630772 -96.20504)
		(size 0.508)
		(drill 0.254)
		(layers "F.Cu" "B.Cu")
		(net "GND")
	)
	(via
		(at 232.563924 -162.243262)
		(size 0.5588)
		(drill 0.3048)
		(layers "F.Cu" "B.Cu")
		(net "GND")
	)
	(via
		(at 303.038002 -126.722886)
		(size 0.508)
		(drill 0.254)
		(layers "F.Cu" "B.Cu")
		(net "GND")
	)
	(via
		(at 146.098768 -144.0053)
		(size 0.508)
		(drill 0.254)
		(layers "F.Cu" "B.Cu")
		(net "GND")
	)
	(via
		(at 75.762866 -55.59044)
		(size 0.508)
		(drill 0.254)
		(layers "F.Cu" "B.Cu")
		(net "GND")
	)
	(via
		(at 4.00558 -149.2758)
		(size 0.508)
		(drill 0.254)
		(layers "F.Cu" "B.Cu")
		(net "GND")
	)
	(via
		(at 131.699508 -136.410446)
		(size 0.508)
		(drill 0.254)
		(layers "F.Cu" "B.Cu")
		(net "GND")
	)
	(via
		(at 349.2246 -78.77302)
		(size 0.508)
		(drill 0.254)
		(layers "F.Cu" "B.Cu")
		(net "GND")
	)
	(via
		(at 383.72796 -141.69644)
		(size 0.508)
		(drill 0.254)
		(layers "F.Cu" "B.Cu")
		(net "GND")
	)
	(via
		(at 287.21812 -78.688438)
		(size 0.508)
		(drill 0.254)
		(layers "F.Cu" "B.Cu")
		(net "GND")
	)
	(via
		(at 36.031424 -139.1666)
		(size 0.508)
		(drill 0.254)
		(layers "F.Cu" "B.Cu")
		(net "GND")
	)
	(via
		(at 103.678736 -3.3528)
		(size 0.508)
		(drill 0.254)
		(layers "F.Cu" "B.Cu")
		(net "GND")
	)
	(via
		(at 64.090804 -134.349744)
		(size 0.508)
		(drill 0.254)
		(layers "F.Cu" "B.Cu")
		(net "GND")
	)
	(via
		(at 58.599324 -144.462246)
		(size 0.508)
		(drill 0.254)
		(layers "F.Cu" "B.Cu")
		(net "GND")
	)
	(via
		(at 42.781982 -78.449678)
		(size 0.5588)
		(drill 0.3048)
		(layers "F.Cu" "B.Cu")
		(net "GND")
	)
	(via
		(at 4.577334 -163.361624)
		(size 0.5588)
		(drill 0.3048)
		(layers "F.Cu" "B.Cu")
		(net "GND")
	)
	(via
		(at 291.51072 -59.371484)
		(size 0.508)
		(drill 0.254)
		(layers "F.Cu" "B.Cu")
		(net "GND")
	)
	(via
		(at 292.36924 -75.716384)
		(size 0.508)
		(drill 0.254)
		(layers "F.Cu" "B.Cu")
		(net "GND")
	)
	(via
		(at 82.630772 -74.411586)
		(size 0.508)
		(drill 0.254)
		(layers "F.Cu" "B.Cu")
		(net "GND")
	)
	(via
		(at 184.193942 -151.935434)
		(size 0.508)
		(drill 0.254)
		(layers "F.Cu" "B.Cu")
		(net "GND")
	)
	(via
		(at 45.191934 14.926056)
		(size 0.5588)
		(drill 0.3048)
		(layers "F.Cu" "B.Cu")
		(net "GND")
	)
	(via
		(at 393.18565 -119.528844)
		(size 0.508)
		(drill 0.254)
		(layers "F.Cu" "B.Cu")
		(net "GND")
	)
	(via
		(at 30.549342 2.514854)
		(size 0.508)
		(drill 0.254)
		(layers "F.Cu" "B.Cu")
		(net "GND")
	)
	(via
		(at 73.440798 -153.552144)
		(size 0.508)
		(drill 0.254)
		(layers "F.Cu" "B.Cu")
		(net "GND")
	)
	(via
		(at 274.914614 -54.418738)
		(size 0.508)
		(drill 0.254)
		(layers "F.Cu" "B.Cu")
		(net "GND")
	)
	(via
		(at 34.991802 -62.792864)
		(size 0.508)
		(drill 0.254)
		(layers "F.Cu" "B.Cu")
		(net "GND")
	)
	(via
		(at 108.481876 -91.565984)
		(size 0.508)
		(drill 0.254)
		(layers "F.Cu" "B.Cu")
		(net "GND")
	)
	(via
		(at 120.500902 -86.612984)
		(size 0.508)
		(drill 0.254)
		(layers "F.Cu" "B.Cu")
		(net "GND")
	)
	(via
		(at 5.832856 12.491466)
		(size 0.5588)
		(drill 0.3048)
		(layers "F.Cu" "B.Cu")
		(net "GND")
	)
	(via
		(at 39.049452 -9.156446)
		(size 0.508)
		(drill 0.254)
		(layers "F.Cu" "B.Cu")
		(net "GND")
	)
	(via
		(at 181.7751 -137.7315)
		(size 0.508)
		(drill 0.254)
		(layers "F.Cu" "B.Cu")
		(net "GND")
	)
	(via
		(at 499.282466 -20.439126)
		(size 0.508)
		(drill 0.254)
		(layers "F.Cu" "B.Cu")
		(net "GND")
	)
	(via
		(at 340.3854 -113.665)
		(size 0.508)
		(drill 0.254)
		(layers "F.Cu" "B.Cu")
		(net "GND")
	)
	(via
		(at 167.907462 -29.456634)
		(size 0.508)
		(drill 0.254)
		(layers "F.Cu" "B.Cu")
		(net "GND")
	)
	(via
		(at 135.061452 -2.314956)
		(size 0.508)
		(drill 0.254)
		(layers "F.Cu" "B.Cu")
		(net "GND")
	)
	(via
		(at 454.265792 -25.10028)
		(size 0.508)
		(drill 0.254)
		(layers "F.Cu" "B.Cu")
		(net "GND")
	)
	(via
		(at 424.210734 -163.361624)
		(size 0.5588)
		(drill 0.3048)
		(layers "F.Cu" "B.Cu")
		(net "GND")
	)
	(via
		(at 291.51072 -98.005138)
		(size 0.508)
		(drill 0.254)
		(layers "F.Cu" "B.Cu")
		(net "GND")
	)
	(via
		(at 375.793 -60.579)
		(size 0.508)
		(drill 0.254)
		(layers "F.Cu" "B.Cu")
		(net "GND")
	)
	(via
		(at 268.679168 -145.0086)
		(size 0.508)
		(drill 0.254)
		(layers "F.Cu" "B.Cu")
		(net "GND")
	)
	(via
		(at 290.6522 -68.782184)
		(size 0.508)
		(drill 0.254)
		(layers "F.Cu" "B.Cu")
		(net "GND")
	)
	(via
		(at 389.71855 -123.821444)
		(size 0.508)
		(drill 0.254)
		(layers "F.Cu" "B.Cu")
		(net "GND")
	)
	(via
		(at 165.177978 -29.341572)
		(size 0.508)
		(drill 0.254)
		(layers "F.Cu" "B.Cu")
		(net "GND")
	)
	(via
		(at 47.549308 -3.762756)
		(size 0.508)
		(drill 0.254)
		(layers "F.Cu" "B.Cu")
		(net "GND")
	)
	(via
		(at 138.031474 -148.7678)
		(size 0.508)
		(drill 0.254)
		(layers "F.Cu" "B.Cu")
		(net "GND")
	)
	(via
		(at 346.7354 -114.935)
		(size 0.508)
		(drill 0.254)
		(layers "F.Cu" "B.Cu")
		(net "GND")
	)
	(via
		(at 370.594382 -100.414836)
		(size 0.508)
		(drill 0.254)
		(layers "F.Cu" "B.Cu")
		(net "GND")
	)
	(via
		(at 39.049452 -129.568956)
		(size 0.508)
		(drill 0.254)
		(layers "F.Cu" "B.Cu")
		(net "GND")
	)
	(via
		(at 270.571468 -56.894984)
		(size 0.508)
		(drill 0.254)
		(layers "F.Cu" "B.Cu")
		(net "GND")
	)
	(via
		(at 397.111728 -144.61236)
		(size 0.508)
		(drill 0.254)
		(layers "F.Cu" "B.Cu")
		(net "GND")
	)
	(via
		(at 239.904778 -100.662486)
		(size 0.508)
		(drill 0.254)
		(layers "F.Cu" "B.Cu")
		(net "GND")
	)
	(via
		(at 125.673358 -125.955298)
		(size 0.508)
		(drill 0.254)
		(layers "F.Cu" "B.Cu")
		(net "GND")
	)
	(via
		(at 439.450734 -166.714424)
		(size 0.5588)
		(drill 0.3048)
		(layers "F.Cu" "B.Cu")
		(net "GND")
	)
	(via
		(at 474.451934 10.354056)
		(size 0.5588)
		(drill 0.3048)
		(layers "F.Cu" "B.Cu")
		(net "GND")
	)
	(via
		(at 53.436012 -131.5466)
		(size 0.508)
		(drill 0.254)
		(layers "F.Cu" "B.Cu")
		(net "GND")
	)
	(via
		(at 136.74217 0.457454)
		(size 0.508)
		(drill 0.254)
		(layers "F.Cu" "B.Cu")
		(net "GND")
	)
	(via
		(at 449.051934 14.926056)
		(size 0.5588)
		(drill 0.3048)
		(layers "F.Cu" "B.Cu")
		(net "GND")
	)
	(via
		(at 136.812274 -85.127338)
		(size 0.508)
		(drill 0.254)
		(layers "F.Cu" "B.Cu")
		(net "GND")
	)
	(via
		(at 123.650248 -54.418738)
		(size 0.508)
		(drill 0.254)
		(layers "F.Cu" "B.Cu")
		(net "GND")
	)
	(via
		(at 433.100734 -164.479224)
		(size 0.5588)
		(drill 0.3048)
		(layers "F.Cu" "B.Cu")
		(net "GND")
	)
	(via
		(at 244.197124 -91.25204)
		(size 0.508)
		(drill 0.254)
		(layers "F.Cu" "B.Cu")
		(net "GND")
	)
	(via
		(at 64.094106 -145.9357)
		(size 0.508)
		(drill 0.254)
		(layers "F.Cu" "B.Cu")
		(net "GND")
	)
	(via
		(at 134.236714 -75.716384)
		(size 0.508)
		(drill 0.254)
		(layers "F.Cu" "B.Cu")
		(net "GND")
	)
	(via
		(at 118.035832 -150.749)
		(size 0.508)
		(drill 0.254)
		(layers "F.Cu" "B.Cu")
		(net "GND")
	)
	(via
		(at 232.94975 -17.208246)
		(size 0.508)
		(drill 0.254)
		(layers "F.Cu" "B.Cu")
		(net "GND")
	)
	(via
		(at 310.122062 -131.016756)
		(size 0.508)
		(drill 0.254)
		(layers "F.Cu" "B.Cu")
		(net "GND")
	)
	(via
		(at 50.851308 -154.063446)
		(size 0.508)
		(drill 0.254)
		(layers "F.Cu" "B.Cu")
		(net "GND")
	)
	(via
		(at 284.341062 -7.095744)
		(size 0.508)
		(drill 0.254)
		(layers "F.Cu" "B.Cu")
		(net "GND")
	)
	(via
		(at 316.249812 -22.965156)
		(size 0.508)
		(drill 0.254)
		(layers "F.Cu" "B.Cu")
		(net "GND")
	)
	(via
		(at 70.461378 -2.314956)
		(size 0.508)
		(drill 0.254)
		(layers "F.Cu" "B.Cu")
		(net "GND")
	)
	(via
		(at 428.020734 -167.832024)
		(size 0.5588)
		(drill 0.3048)
		(layers "F.Cu" "B.Cu")
		(net "GND")
	)
	(via
		(at 207.566514 -78.475078)
		(size 0.5588)
		(drill 0.3048)
		(layers "F.Cu" "B.Cu")
		(net "GND")
	)
	(via
		(at 160.703768 -63.035688)
		(size 0.508)
		(drill 0.254)
		(layers "F.Cu" "B.Cu")
		(net "GND")
	)
	(via
		(at 206.982314 -70.321678)
		(size 0.5588)
		(drill 0.3048)
		(layers "F.Cu" "B.Cu")
		(net "GND")
	)
	(via
		(at 38.199314 -3.762756)
		(size 0.508)
		(drill 0.254)
		(layers "F.Cu" "B.Cu")
		(net "GND")
	)
	(via
		(at 475.006924 -162.243262)
		(size 0.5588)
		(drill 0.3048)
		(layers "F.Cu" "B.Cu")
		(net "GND")
	)
	(via
		(at 235.46181 -21.517356)
		(size 0.508)
		(drill 0.254)
		(layers "F.Cu" "B.Cu")
		(net "GND")
	)
	(via
		(at 161.8742 -111.0488)
		(size 0.508)
		(drill 0.254)
		(layers "F.Cu" "B.Cu")
		(net "GND")
	)
	(via
		(at 359.973118 -96.298766)
		(size 0.508)
		(drill 0.254)
		(layers "F.Cu" "B.Cu")
		(net "GND")
	)
	(via
		(at 288.65068 -55.409338)
		(size 0.508)
		(drill 0.254)
		(layers "F.Cu" "B.Cu")
		(net "GND")
	)
	(via
		(at 276.154134 -167.832024)
		(size 0.5588)
		(drill 0.3048)
		(layers "F.Cu" "B.Cu")
		(net "GND")
	)
	(via
		(at 181.31282 -21.01342)
		(size 0.508)
		(drill 0.254)
		(layers "F.Cu" "B.Cu")
		(net "GND")
	)
	(via
		(at 172.72 -71.6026)
		(size 0.508)
		(drill 0.254)
		(layers "F.Cu" "B.Cu")
		(net "GND")
	)
	(via
		(at 251.923804 -65.000886)
		(size 0.508)
		(drill 0.254)
		(layers "F.Cu" "B.Cu")
		(net "GND")
	)
	(via
		(at 206.904082 -60.869322)
		(size 0.5588)
		(drill 0.3048)
		(layers "F.Cu" "B.Cu")
		(net "GND")
	)
	(via
		(at 457.142596 -8.86206)
		(size 0.508)
		(drill 0.254)
		(layers "F.Cu" "B.Cu")
		(net "GND")
	)
	(via
		(at 359.6132 -125.7808)
		(size 0.508)
		(drill 0.254)
		(layers "F.Cu" "B.Cu")
		(net "GND")
	)
	(via
		(at 494.060734 -163.361624)
		(size 0.5588)
		(drill 0.3048)
		(layers "F.Cu" "B.Cu")
		(net "GND")
	)
	(via
		(at 127.392176 -155.600146)
		(size 0.508)
		(drill 0.254)
		(layers "F.Cu" "B.Cu")
		(net "GND")
	)
	(via
		(at 200.515728 -72.1868)
		(size 0.508)
		(drill 0.254)
		(layers "F.Cu" "B.Cu")
		(net "GND")
	)
	(via
		(at 416.781234 -59.74334)
		(size 0.508)
		(drill 0.254)
		(layers "F.Cu" "B.Cu")
		(net "GND")
	)
	(via
		(at 442.522356 -25.0317)
		(size 0.4572)
		(drill 0.2032)
		(layers "F.Cu" "B.Cu")
		(net "GND")
	)
	(via
		(at 237.142528 -139.166092)
		(size 0.508)
		(drill 0.254)
		(layers "F.Cu" "B.Cu")
		(net "GND")
	)
	(via
		(at 120.803924 -162.243262)
		(size 0.5588)
		(drill 0.3048)
		(layers "F.Cu" "B.Cu")
		(net "GND")
	)
	(via
		(at 421.111934 14.926056)
		(size 0.5588)
		(drill 0.3048)
		(layers "F.Cu" "B.Cu")
		(net "GND")
	)
	(via
		(at 172.327316 -70.612)
		(size 0.508)
		(drill 0.254)
		(layers "F.Cu" "B.Cu")
		(net "GND")
	)
	(via
		(at 10.20699 -122.661172)
		(size 0.508)
		(drill 0.254)
		(layers "F.Cu" "B.Cu")
		(net "GND")
	)
	(via
		(at 320.781934 14.926056)
		(size 0.5588)
		(drill 0.3048)
		(layers "F.Cu" "B.Cu")
		(net "GND")
	)
	(via
		(at 493.653318 -56.803798)
		(size 0.508)
		(drill 0.254)
		(layers "F.Cu" "B.Cu")
		(net "GND")
	)
	(via
		(at 488.421934 14.926056)
		(size 0.5588)
		(drill 0.3048)
		(layers "F.Cu" "B.Cu")
		(net "GND")
	)
	(via
		(at 72.142096 -2.310892)
		(size 0.508)
		(drill 0.254)
		(layers "F.Cu" "B.Cu")
		(net "GND")
	)
	(via
		(at 80.751934 14.926056)
		(size 0.5588)
		(drill 0.3048)
		(layers "F.Cu" "B.Cu")
		(net "GND")
	)
	(via
		(at -3.463544 13.634466)
		(size 0.5588)
		(drill 0.3048)
		(layers "F.Cu" "B.Cu")
		(net "GND")
	)
	(via
		(at 11.811 -151.17826)
		(size 0.508)
		(drill 0.254)
		(layers "F.Cu" "B.Cu")
		(net "GND")
	)
	(via
		(at 124.793248 -96.023938)
		(size 0.508)
		(drill 0.254)
		(layers "F.Cu" "B.Cu")
		(net "GND")
	)
	(via
		(at 381.29845 -119.528844)
		(size 0.508)
		(drill 0.254)
		(layers "F.Cu" "B.Cu")
		(net "GND")
	)
	(via
		(at 31.908496 -72.423782)
		(size 0.508)
		(drill 0.254)
		(layers "F.Cu" "B.Cu")
		(net "GND")
	)
	(via
		(at 281.742134 -167.832024)
		(size 0.5588)
		(drill 0.3048)
		(layers "F.Cu" "B.Cu")
		(net "GND")
	)
	(via
		(at 44.807124 -162.243262)
		(size 0.5588)
		(drill 0.3048)
		(layers "F.Cu" "B.Cu")
		(net "GND")
	)
	(via
		(at 207.751934 14.926056)
		(size 0.5588)
		(drill 0.3048)
		(layers "F.Cu" "B.Cu")
		(net "GND")
	)
	(via
		(at 26.759408 -151.07158)
		(size 0.508)
		(drill 0.254)
		(layers "F.Cu" "B.Cu")
		(net "GND")
	)
	(via
		(at 289.810952 -125.410976)
		(size 0.508)
		(drill 0.254)
		(layers "F.Cu" "B.Cu")
		(net "GND")
	)
	(via
		(at 455.50328 -141.723872)
		(size 0.508)
		(drill 0.254)
		(layers "F.Cu" "B.Cu")
		(net "GND")
	)
	(via
		(at 239.046258 -55.59044)
		(size 0.508)
		(drill 0.254)
		(layers "F.Cu" "B.Cu")
		(net "GND")
	)
	(via
		(at 247.631204 -68.46824)
		(size 0.508)
		(drill 0.254)
		(layers "F.Cu" "B.Cu")
		(net "GND")
	)
	(via
		(at 354.509324 -162.268662)
		(size 0.5588)
		(drill 0.3048)
		(layers "F.Cu" "B.Cu")
		(net "GND")
	)
	(via
		(at 129.999486 -21.517356)
		(size 0.508)
		(drill 0.254)
		(layers "F.Cu" "B.Cu")
		(net "GND")
	)
	(via
		(at 385.75615 -118.670324)
		(size 0.508)
		(drill 0.254)
		(layers "F.Cu" "B.Cu")
		(net "GND")
	)
	(via
		(at 470.16162 4.289806)
		(size 0.5588)
		(drill 0.3048)
		(layers "F.Cu" "B.Cu")
		(net "GND")
	)
	(via
		(at 226.822 -27.821636)
		(size 0.508)
		(drill 0.254)
		(layers "F.Cu" "B.Cu")
		(net "GND")
	)
	(via
		(at 35.8648 -66.4464)
		(size 0.508)
		(drill 0.254)
		(layers "F.Cu" "B.Cu")
		(net "GND")
	)
	(via
		(at 15.855188 -27.790902)
		(size 0.508)
		(drill 0.254)
		(layers "F.Cu" "B.Cu")
		(net "GND")
	)
	(via
		(at 201.031856 -129.5654)
		(size 0.508)
		(drill 0.254)
		(layers "F.Cu" "B.Cu")
		(net "GND")
	)
	(via
		(at 350.006666 -136.580118)
		(size 0.508)
		(drill 0.254)
		(layers "F.Cu" "B.Cu")
		(net "GND")
	)
	(via
		(at 171.9326 -124.3076)
		(size 0.508)
		(drill 0.254)
		(layers "F.Cu" "B.Cu")
		(net "GND")
	)
	(via
		(at 42.088054 -85.89391)
		(size 0.5588)
		(drill 0.3048)
		(layers "F.Cu" "B.Cu")
		(net "GND")
	)
	(via
		(at 16.7132 -3.6068)
		(size 0.508)
		(drill 0.254)
		(layers "F.Cu" "B.Cu")
		(net "GND")
	)
	(via
		(at 68.036186 -98.681286)
		(size 0.508)
		(drill 0.254)
		(layers "F.Cu" "B.Cu")
		(net "GND")
	)
	(via
		(at 43.12158 -7.6454)
		(size 0.508)
		(drill 0.254)
		(layers "F.Cu" "B.Cu")
		(net "GND")
	)
	(via
		(at 239.046258 -90.26144)
		(size 0.508)
		(drill 0.254)
		(layers "F.Cu" "B.Cu")
		(net "GND")
	)
	(via
		(at 442.204602 -113.912904)
		(size 0.508)
		(drill 0.254)
		(layers "F.Cu" "B.Cu")
		(net "GND")
	)
	(via
		(at 295.849802 -22.965156)
		(size 0.508)
		(drill 0.254)
		(layers "F.Cu" "B.Cu")
		(net "GND")
	)
	(via
		(at 300.954186 -81.659984)
		(size 0.508)
		(drill 0.254)
		(layers "F.Cu" "B.Cu")
		(net "GND")
	)
	(via
		(at 56.899302 -134.861046)
		(size 0.508)
		(drill 0.254)
		(layers "F.Cu" "B.Cu")
		(net "GND")
	)
	(via
		(at 458.500734 -163.361624)
		(size 0.5588)
		(drill 0.3048)
		(layers "F.Cu" "B.Cu")
		(net "GND")
	)
	(via
		(at 130.84937 -154.063446)
		(size 0.508)
		(drill 0.254)
		(layers "F.Cu" "B.Cu")
		(net "GND")
	)
	(via
		(at 32.15132 -7.607046)
		(size 0.508)
		(drill 0.254)
		(layers "F.Cu" "B.Cu")
		(net "GND")
	)
	(via
		(at 165.13048 -31.1658)
		(size 0.508)
		(drill 0.254)
		(layers "F.Cu" "B.Cu")
		(net "GND")
	)
	(via
		(at 53.436012 -13.8938)
		(size 0.508)
		(drill 0.254)
		(layers "F.Cu" "B.Cu")
		(net "GND")
	)
	(via
		(at 113.337086 -74.381868)
		(size 0.5588)
		(drill 0.3048)
		(layers "F.Cu" "B.Cu")
		(net "GND")
	)
	(via
		(at 235.612178 -54.59984)
		(size 0.508)
		(drill 0.254)
		(layers "F.Cu" "B.Cu")
		(net "GND")
	)
	(via
		(at 77.479906 -94.223586)
		(size 0.508)
		(drill 0.254)
		(layers "F.Cu" "B.Cu")
		(net "GND")
	)
	(via
		(at 133.384036 -26.495756)
		(size 0.508)
		(drill 0.254)
		(layers "F.Cu" "B.Cu")
		(net "GND")
	)
	(via
		(at 366.21847 -145.005298)
		(size 0.508)
		(drill 0.254)
		(layers "F.Cu" "B.Cu")
		(net "GND")
	)
	(via
		(at 259.224018 -75.148186)
		(size 0.5588)
		(drill 0.3048)
		(layers "F.Cu" "B.Cu")
		(net "GND")
	)
	(via
		(at 396.65275 -101.039676)
		(size 0.508)
		(drill 0.254)
		(layers "F.Cu" "B.Cu")
		(net "GND")
	)
	(via
		(at 69.753226 -62.029086)
		(size 0.508)
		(drill 0.254)
		(layers "F.Cu" "B.Cu")
		(net "GND")
	)
	(via
		(at 299.160946 -22.939756)
		(size 0.508)
		(drill 0.254)
		(layers "F.Cu" "B.Cu")
		(net "GND")
	)
	(via
		(at 109.914182 -58.381138)
		(size 0.508)
		(drill 0.254)
		(layers "F.Cu" "B.Cu")
		(net "GND")
	)
	(via
		(at 143.159734 -167.832024)
		(size 0.5588)
		(drill 0.3048)
		(layers "F.Cu" "B.Cu")
		(net "GND")
	)
	(via
		(at 312.3946 -145.9357)
		(size 0.508)
		(drill 0.254)
		(layers "F.Cu" "B.Cu")
		(net "GND")
	)
	(via
		(at 164.571934 9.084056)
		(size 0.5588)
		(drill 0.3048)
		(layers "F.Cu" "B.Cu")
		(net "GND")
	)
	(via
		(at 294.08628 -55.904384)
		(size 0.508)
		(drill 0.254)
		(layers "F.Cu" "B.Cu")
		(net "GND")
	)
	(via
		(at 138.044174 -18.6817)
		(size 0.508)
		(drill 0.254)
		(layers "F.Cu" "B.Cu")
		(net "GND")
	)
	(via
		(at 77.221334 -167.832024)
		(size 0.5588)
		(drill 0.3048)
		(layers "F.Cu" "B.Cu")
		(net "GND")
	)
	(via
		(at 392.609324 -162.243262)
		(size 0.5588)
		(drill 0.3048)
		(layers "F.Cu" "B.Cu")
		(net "GND")
	)
	(via
		(at 449.895722 -63.5254)
		(size 0.508)
		(drill 0.254)
		(layers "F.Cu" "B.Cu")
		(net "GND")
	)
	(via
		(at 20.792694 -23.721568)
		(size 0.508)
		(drill 0.254)
		(layers "F.Cu" "B.Cu")
		(net "GND")
	)
	(via
		(at 287.21812 -96.518984)
		(size 0.508)
		(drill 0.254)
		(layers "F.Cu" "B.Cu")
		(net "GND")
	)
	(via
		(at 489.691934 14.926056)
		(size 0.5588)
		(drill 0.3048)
		(layers "F.Cu" "B.Cu")
		(net "GND")
	)
	(via
		(at 348.0308 -85.9536)
		(size 0.508)
		(drill 0.254)
		(layers "F.Cu" "B.Cu")
		(net "GND")
	)
	(via
		(at 266.091924 -162.243262)
		(size 0.5588)
		(drill 0.3048)
		(layers "F.Cu" "B.Cu")
		(net "GND")
	)
	(via
		(at 54.74081 -153.552144)
		(size 0.508)
		(drill 0.254)
		(layers "F.Cu" "B.Cu")
		(net "GND")
	)
	(via
		(at 234.753658 -69.953886)
		(size 0.508)
		(drill 0.254)
		(layers "F.Cu" "B.Cu")
		(net "GND")
	)
	(via
		(at 139.1412 -51.1556)
		(size 0.508)
		(drill 0.254)
		(layers "F.Cu" "B.Cu")
		(net "GND")
	)
	(via
		(at 202.349862 -155.612846)
		(size 0.508)
		(drill 0.254)
		(layers "F.Cu" "B.Cu")
		(net "GND")
	)
	(via
		(at 111.631222 -59.371484)
		(size 0.508)
		(drill 0.254)
		(layers "F.Cu" "B.Cu")
		(net "GND")
	)
	(via
		(at 70.611746 -100.167186)
		(size 0.508)
		(drill 0.254)
		(layers "F.Cu" "B.Cu")
		(net "GND")
	)
	(via
		(at 204.049884 -11.916156)
		(size 0.508)
		(drill 0.254)
		(layers "F.Cu" "B.Cu")
		(net "GND")
	)
	(via
		(at 39.899336 -150.219156)
		(size 0.508)
		(drill 0.254)
		(layers "F.Cu" "B.Cu")
		(net "GND")
	)
	(via
		(at 15.881096 -31.34233)
		(size 0.508)
		(drill 0.254)
		(layers "F.Cu" "B.Cu")
		(net "GND")
	)
	(via
		(at 469.371934 14.926056)
		(size 0.5588)
		(drill 0.3048)
		(layers "F.Cu" "B.Cu")
		(net "GND")
	)
	(via
		(at 194.7164 -150.0378)
		(size 0.508)
		(drill 0.254)
		(layers "F.Cu" "B.Cu")
		(net "GND")
	)
	(via
		(at 343.701116 4.676394)
		(size 0.508)
		(drill 0.254)
		(layers "F.Cu" "B.Cu")
		(net "GND")
	)
	(via
		(at 371.945154 -75.094846)
		(size 0.4572)
		(drill 0.2032)
		(layers "F.Cu" "B.Cu")
		(net "GND")
	)
	(via
		(at 455.357992 -43.671998)
		(size 0.508)
		(drill 0.254)
		(layers "F.Cu" "B.Cu")
		(net "GND")
	)
	(via
		(at 38.9382 -70.3072)
		(size 0.5588)
		(drill 0.3048)
		(layers "F.Cu" "B.Cu")
		(net "GND")
	)
	(via
		(at 289.810952 -140.592556)
		(size 0.508)
		(drill 0.254)
		(layers "F.Cu" "B.Cu")
		(net "GND")
	)
	(via
		(at 252.782324 -91.25204)
		(size 0.508)
		(drill 0.254)
		(layers "F.Cu" "B.Cu")
		(net "GND")
	)
	(via
		(at 388.72795 -120.387364)
		(size 0.508)
		(drill 0.254)
		(layers "F.Cu" "B.Cu")
		(net "GND")
	)
	(via
		(at 12.3698 -24.257)
		(size 0.508)
		(drill 0.254)
		(layers "F.Cu" "B.Cu")
		(net "GND")
	)
	(via
		(at 345.948 -143.6624)
		(size 0.508)
		(drill 0.254)
		(layers "F.Cu" "B.Cu")
		(net "GND")
	)
	(via
		(at 312.3692 -2.3622)
		(size 0.508)
		(drill 0.254)
		(layers "F.Cu" "B.Cu")
		(net "GND")
	)
	(via
		(at 349.2754 -39.37)
		(size 0.508)
		(drill 0.254)
		(layers "F.Cu" "B.Cu")
		(net "GND")
	)
	(via
		(at 463.580734 -164.479224)
		(size 0.5588)
		(drill 0.3048)
		(layers "F.Cu" "B.Cu")
		(net "GND")
	)
	(via
		(at 290.74999 -9.156446)
		(size 0.508)
		(drill 0.254)
		(layers "F.Cu" "B.Cu")
		(net "GND")
	)
	(via
		(at 268.376908 -70.84314)
		(size 0.5588)
		(drill 0.3048)
		(layers "F.Cu" "B.Cu")
		(net "GND")
	)
	(via
		(at 216.761822 -11.916156)
		(size 0.508)
		(drill 0.254)
		(layers "F.Cu" "B.Cu")
		(net "GND")
	)
	(via
		(at 34.287968 -102.3366)
		(size 0.5588)
		(drill 0.3048)
		(layers "F.Cu" "B.Cu")
		(net "GND")
	)
	(via
		(at 430.001934 10.354056)
		(size 0.5588)
		(drill 0.3048)
		(layers "F.Cu" "B.Cu")
		(net "GND")
	)
	(via
		(at 312.3819 -129.5654)
		(size 0.508)
		(drill 0.254)
		(layers "F.Cu" "B.Cu")
		(net "GND")
	)
	(via
		(at 196.908928 -64.295782)
		(size 0.508)
		(drill 0.254)
		(layers "F.Cu" "B.Cu")
		(net "GND")
	)
	(via
		(at 199.7202 -52.6796)
		(size 0.5588)
		(drill 0.3048)
		(layers "F.Cu" "B.Cu")
		(net "GND")
	)
	(via
		(at 411.49016 -26.934668)
		(size 0.4572)
		(drill 0.2032)
		(layers "F.Cu" "B.Cu")
		(net "GND")
	)
	(via
		(at 304.103532 -100.976684)
		(size 0.508)
		(drill 0.254)
		(layers "F.Cu" "B.Cu")
		(net "GND")
	)
	(via
		(at 160.761934 9.084056)
		(size 0.5588)
		(drill 0.3048)
		(layers "F.Cu" "B.Cu")
		(net "GND")
	)
	(via
		(at 284.358334 -72.744584)
		(size 0.508)
		(drill 0.254)
		(layers "F.Cu" "B.Cu")
		(net "GND")
	)
	(via
		(at 13.335 -14.6558)
		(size 0.508)
		(drill 0.254)
		(layers "F.Cu" "B.Cu")
		(net "GND")
	)
	(via
		(at 164.571934 14.926056)
		(size 0.5588)
		(drill 0.3048)
		(layers "F.Cu" "B.Cu")
		(net "GND")
	)
	(via
		(at 31.221934 9.084056)
		(size 0.5588)
		(drill 0.3048)
		(layers "F.Cu" "B.Cu")
		(net "GND")
	)
	(via
		(at 465.561934 10.354056)
		(size 0.5588)
		(drill 0.3048)
		(layers "F.Cu" "B.Cu")
		(net "GND")
	)
	(via
		(at 96.216724 -162.243262)
		(size 0.5588)
		(drill 0.3048)
		(layers "F.Cu" "B.Cu")
		(net "GND")
	)
	(via
		(at 273.791934 9.084056)
		(size 0.5588)
		(drill 0.3048)
		(layers "F.Cu" "B.Cu")
		(net "GND")
	)
	(via
		(at 455.971656 -121.007124)
		(size 0.508)
		(drill 0.254)
		(layers "F.Cu" "B.Cu")
		(net "GND")
	)
	(via
		(at 438.846722 -150.454868)
		(size 0.508)
		(drill 0.254)
		(layers "F.Cu" "B.Cu")
		(net "GND")
	)
	(via
		(at 140.199364 -13.363956)
		(size 0.508)
		(drill 0.254)
		(layers "F.Cu" "B.Cu")
		(net "GND")
	)
	(via
		(at 469.97366 -123.59894)
		(size 0.508)
		(drill 0.254)
		(layers "F.Cu" "B.Cu")
		(net "GND")
	)
	(via
		(at 313.699906 -11.916156)
		(size 0.508)
		(drill 0.254)
		(layers "F.Cu" "B.Cu")
		(net "GND")
	)
	(via
		(at 170.7642 -68.3768)
		(size 0.508)
		(drill 0.254)
		(layers "F.Cu" "B.Cu")
		(net "GND")
	)
	(via
		(at 243.149882 -139.2428)
		(size 0.508)
		(drill 0.254)
		(layers "F.Cu" "B.Cu")
		(net "GND")
	)
	(via
		(at 72.328786 -64.50584)
		(size 0.508)
		(drill 0.254)
		(layers "F.Cu" "B.Cu")
		(net "GND")
	)
	(via
		(at 115.349782 -89.584784)
		(size 0.508)
		(drill 0.254)
		(layers "F.Cu" "B.Cu")
		(net "GND")
	)
	(via
		(at 145.12163 -134.8994)
		(size 0.508)
		(drill 0.254)
		(layers "F.Cu" "B.Cu")
		(net "GND")
	)
	(via
		(at 355.107748 -80.198722)
		(size 0.508)
		(drill 0.254)
		(layers "F.Cu" "B.Cu")
		(net "GND")
	)
	(via
		(at 280.624534 -167.832024)
		(size 0.5588)
		(drill 0.3048)
		(layers "F.Cu" "B.Cu")
		(net "GND")
	)
	(via
		(at 44.092114 -139.166092)
		(size 0.508)
		(drill 0.254)
		(layers "F.Cu" "B.Cu")
		(net "GND")
	)
	(via
		(at 195.5038 -143.9926)
		(size 0.508)
		(drill 0.254)
		(layers "F.Cu" "B.Cu")
		(net "GND")
	)
	(via
		(at 265.659616 -95.709486)
		(size 0.508)
		(drill 0.254)
		(layers "F.Cu" "B.Cu")
		(net "GND")
	)
	(via
		(at 239.046258 -84.31784)
		(size 0.508)
		(drill 0.254)
		(layers "F.Cu" "B.Cu")
		(net "GND")
	)
	(via
		(at 160.92932 -31.89224)
		(size 0.508)
		(drill 0.254)
		(layers "F.Cu" "B.Cu")
		(net "GND")
	)
	(via
		(at 87.781892 -69.45884)
		(size 0.508)
		(drill 0.254)
		(layers "F.Cu" "B.Cu")
		(net "GND")
	)
	(via
		(at 204.4954 -76.5048)
		(size 0.5588)
		(drill 0.3048)
		(layers "F.Cu" "B.Cu")
		(net "GND")
	)
	(via
		(at 76.621386 -69.953886)
		(size 0.508)
		(drill 0.254)
		(layers "F.Cu" "B.Cu")
		(net "GND")
	)
	(via
		(at 130.802888 -56.894984)
		(size 0.508)
		(drill 0.254)
		(layers "F.Cu" "B.Cu")
		(net "GND")
	)
	(via
		(at 75.762866 -80.35544)
		(size 0.508)
		(drill 0.254)
		(layers "F.Cu" "B.Cu")
		(net "GND")
	)
	(via
		(at 251.923804 -87.784686)
		(size 0.508)
		(drill 0.254)
		(layers "F.Cu" "B.Cu")
		(net "GND")
	)
	(via
		(at 299.237146 -59.866784)
		(size 0.508)
		(drill 0.254)
		(layers "F.Cu" "B.Cu")
		(net "GND")
	)
	(via
		(at 118.499382 -67.296538)
		(size 0.508)
		(drill 0.254)
		(layers "F.Cu" "B.Cu")
		(net "GND")
	)
	(via
		(at 183.621934 14.926056)
		(size 0.5588)
		(drill 0.3048)
		(layers "F.Cu" "B.Cu")
		(net "GND")
	)
	(via
		(at 434.132482 -149.5298)
		(size 0.508)
		(drill 0.254)
		(layers "F.Cu" "B.Cu")
		(net "GND")
	)
	(via
		(at 166.8526 -122.50166)
		(size 0.508)
		(drill 0.254)
		(layers "F.Cu" "B.Cu")
		(net "GND")
	)
	(via
		(at 76.621386 -93.72854)
		(size 0.508)
		(drill 0.254)
		(layers "F.Cu" "B.Cu")
		(net "GND")
	)
	(via
		(at 138.031474 -139.1666)
		(size 0.508)
		(drill 0.254)
		(layers "F.Cu" "B.Cu")
		(net "GND")
	)
	(via
		(at 207.202786 -92.60205)
		(size 0.5588)
		(drill 0.3048)
		(layers "F.Cu" "B.Cu")
		(net "GND")
	)
	(via
		(at 386.5372 -113.8555)
		(size 0.508)
		(drill 0.254)
		(layers "F.Cu" "B.Cu")
		(net "GND")
	)
	(via
		(at 136.812274 -63.334138)
		(size 0.508)
		(drill 0.254)
		(layers "F.Cu" "B.Cu")
		(net "GND")
	)
	(via
		(at 129.999486 -146.011646)
		(size 0.508)
		(drill 0.254)
		(layers "F.Cu" "B.Cu")
		(net "GND")
	)
	(via
		(at 443.260734 -166.714424)
		(size 0.5588)
		(drill 0.3048)
		(layers "F.Cu" "B.Cu")
		(net "GND")
	)
	(via
		(at 101.517704 -63.51524)
		(size 0.508)
		(drill 0.254)
		(layers "F.Cu" "B.Cu")
		(net "GND")
	)
	(via
		(at 41.461182 -76.468478)
		(size 0.5588)
		(drill 0.3048)
		(layers "F.Cu" "B.Cu")
		(net "GND")
	)
	(via
		(at 121.391934 9.084056)
		(size 0.5588)
		(drill 0.3048)
		(layers "F.Cu" "B.Cu")
		(net "GND")
	)
	(via
		(at 356.3874 -81.6229)
		(size 0.508)
		(drill 0.254)
		(layers "F.Cu" "B.Cu")
		(net "GND")
	)
	(via
		(at 94.649798 -91.25204)
		(size 0.508)
		(drill 0.254)
		(layers "F.Cu" "B.Cu")
		(net "GND")
	)
	(via
		(at 53.448712 -16.7513)
		(size 0.508)
		(drill 0.254)
		(layers "F.Cu" "B.Cu")
		(net "GND")
	)
	(via
		(at 71.861934 14.926056)
		(size 0.5588)
		(drill 0.3048)
		(layers "F.Cu" "B.Cu")
		(net "GND")
	)
	(via
		(at 294.08628 -91.565984)
		(size 0.508)
		(drill 0.254)
		(layers "F.Cu" "B.Cu")
		(net "GND")
	)
	(via
		(at 61.821568 1.9558)
		(size 0.508)
		(drill 0.254)
		(layers "F.Cu" "B.Cu")
		(net "GND")
	)
	(via
		(at 135.099552 0.444754)
		(size 0.508)
		(drill 0.254)
		(layers "F.Cu" "B.Cu")
		(net "GND")
	)
	(via
		(at 2.342134 -163.361624)
		(size 0.5588)
		(drill 0.3048)
		(layers "F.Cu" "B.Cu")
		(net "GND")
	)
	(via
		(at 479.3742 -29.3878)
		(size 0.508)
		(drill 0.254)
		(layers "F.Cu" "B.Cu")
		(net "GND")
	)
	(via
		(at 347.86316 -78.77175)
		(size 0.508)
		(drill 0.254)
		(layers "F.Cu" "B.Cu")
		(net "GND")
	)
	(via
		(at 348.9579 -31.3563)
		(size 0.508)
		(drill 0.254)
		(layers "F.Cu" "B.Cu")
		(net "GND")
	)
	(via
		(at 119.343932 -155.5369)
		(size 0.508)
		(drill 0.254)
		(layers "F.Cu" "B.Cu")
		(net "GND")
	)
	(via
		(at 356.29215 -103.666544)
		(size 0.508)
		(drill 0.254)
		(layers "F.Cu" "B.Cu")
		(net "GND")
	)
	(via
		(at 425.480734 -167.832024)
		(size 0.5588)
		(drill 0.3048)
		(layers "F.Cu" "B.Cu")
		(net "GND")
	)
	(via
		(at 238.151924 -162.243262)
		(size 0.5588)
		(drill 0.3048)
		(layers "F.Cu" "B.Cu")
		(net "GND")
	)
	(via
		(at 475.413832 -54.214268)
		(size 0.508)
		(drill 0.254)
		(layers "F.Cu" "B.Cu")
		(net "GND")
	)
	(via
		(at 415.316924 -162.243262)
		(size 0.5588)
		(drill 0.3048)
		(layers "F.Cu" "B.Cu")
		(net "GND")
	)
	(via
		(at 389.217916 -146.629882)
		(size 0.508)
		(drill 0.254)
		(layers "F.Cu" "B.Cu")
		(net "GND")
	)
	(via
		(at 320.167 -29.845)
		(size 0.508)
		(drill 0.254)
		(layers "F.Cu" "B.Cu")
		(net "GND")
	)
	(via
		(at 48.777398 -84.44992)
		(size 0.508)
		(drill 0.254)
		(layers "F.Cu" "B.Cu")
		(net "GND")
	)
	(via
		(at 472.228418 -142.0749)
		(size 0.508)
		(drill 0.254)
		(layers "F.Cu" "B.Cu")
		(net "GND")
	)
	(via
		(at 413.266128 -129.597404)
		(size 0.508)
		(drill 0.254)
		(layers "F.Cu" "B.Cu")
		(net "GND")
	)
	(via
		(at 275.111464 -17.7546)
		(size 0.508)
		(drill 0.254)
		(layers "F.Cu" "B.Cu")
		(net "GND")
	)
	(via
		(at 301.731934 14.926056)
		(size 0.5588)
		(drill 0.3048)
		(layers "F.Cu" "B.Cu")
		(net "GND")
	)
	(via
		(at 473.740734 -166.714424)
		(size 0.5588)
		(drill 0.3048)
		(layers "F.Cu" "B.Cu")
		(net "GND")
	)
	(via
		(at 271.683734 -167.832024)
		(size 0.5588)
		(drill 0.3048)
		(layers "F.Cu" "B.Cu")
		(net "GND")
	)
	(via
		(at 160.655 -59.69)
		(size 0.508)
		(drill 0.254)
		(layers "F.Cu" "B.Cu")
		(net "GND")
	)
	(via
		(at 86.158324 -162.243262)
		(size 0.5588)
		(drill 0.3048)
		(layers "F.Cu" "B.Cu")
		(net "GND")
	)
	(via
		(at 246.565674 -140.208)
		(size 0.508)
		(drill 0.254)
		(layers "F.Cu" "B.Cu")
		(net "GND")
	)
	(via
		(at 427.022768 -115.388644)
		(size 0.508)
		(drill 0.254)
		(layers "F.Cu" "B.Cu")
		(net "GND")
	)
	(via
		(at 358.881934 14.926056)
		(size 0.5588)
		(drill 0.3048)
		(layers "F.Cu" "B.Cu")
		(net "GND")
	)
	(via
		(at 69.753226 -66.982086)
		(size 0.508)
		(drill 0.254)
		(layers "F.Cu" "B.Cu")
		(net "GND")
	)
	(via
		(at -4.248404 -127.927354)
		(size 0.508)
		(drill 0.254)
		(layers "F.Cu" "B.Cu")
		(net "GND")
	)
	(via
		(at 74.401934 14.926056)
		(size 0.5588)
		(drill 0.3048)
		(layers "F.Cu" "B.Cu")
		(net "GND")
	)
	(via
		(at 0.381 -137.9474)
		(size 0.508)
		(drill 0.254)
		(layers "F.Cu" "B.Cu")
		(net "GND")
	)
	(via
		(at 3.459734 -164.479224)
		(size 0.5588)
		(drill 0.3048)
		(layers "F.Cu" "B.Cu")
		(net "GND")
	)
	(via
		(at 500.6848 -38.735)
		(size 0.508)
		(drill 0.254)
		(layers "F.Cu" "B.Cu")
		(net "GND")
	)
	(via
		(at 153.141934 9.084056)
		(size 0.5588)
		(drill 0.3048)
		(layers "F.Cu" "B.Cu")
		(net "GND")
	)
	(via
		(at 134.160514 -22.939756)
		(size 0.508)
		(drill 0.254)
		(layers "F.Cu" "B.Cu")
		(net "GND")
	)
	(via
		(at 431.830734 -164.479224)
		(size 0.5588)
		(drill 0.3048)
		(layers "F.Cu" "B.Cu")
		(net "GND")
	)
	(via
		(at 72.142096 -126.655576)
		(size 0.508)
		(drill 0.254)
		(layers "F.Cu" "B.Cu")
		(net "GND")
	)
	(via
		(at 61.149484 -136.410446)
		(size 0.508)
		(drill 0.254)
		(layers "F.Cu" "B.Cu")
		(net "GND")
	)
	(via
		(at 319.736724 -162.243262)
		(size 0.5588)
		(drill 0.3048)
		(layers "F.Cu" "B.Cu")
		(net "GND")
	)
	(via
		(at 209.092546 -2.310892)
		(size 0.508)
		(drill 0.254)
		(layers "F.Cu" "B.Cu")
		(net "GND")
	)
	(via
		(at 297.520106 -76.706984)
		(size 0.508)
		(drill 0.254)
		(layers "F.Cu" "B.Cu")
		(net "GND")
	)
	(via
		(at 74.749406 -146.011646)
		(size 0.508)
		(drill 0.254)
		(layers "F.Cu" "B.Cu")
		(net "GND")
	)
	(via
		(at 122.349514 -139.170156)
		(size 0.508)
		(drill 0.254)
		(layers "F.Cu" "B.Cu")
		(net "GND")
	)
	(via
		(at 142.898114 -55.904384)
		(size 0.508)
		(drill 0.254)
		(layers "F.Cu" "B.Cu")
		(net "GND")
	)
	(via
		(at 124.81052 -22.939756)
		(size 0.508)
		(drill 0.254)
		(layers "F.Cu" "B.Cu")
		(net "GND")
	)
	(via
		(at 119.337328 -23.549356)
		(size 0.508)
		(drill 0.254)
		(layers "F.Cu" "B.Cu")
		(net "GND")
	)
	(via
		(at 300.954186 -73.735184)
		(size 0.508)
		(drill 0.254)
		(layers "F.Cu" "B.Cu")
		(net "GND")
	)
	(via
		(at 43.12158 1.9558)
		(size 0.508)
		(drill 0.254)
		(layers "F.Cu" "B.Cu")
		(net "GND")
	)
	(via
		(at 282.354274 -68.9102)
		(size 0.508)
		(drill 0.254)
		(layers "F.Cu" "B.Cu")
		(net "GND")
	)
	(via
		(at 345.379294 -8.208518)
		(size 0.508)
		(drill 0.254)
		(layers "F.Cu" "B.Cu")
		(net "GND")
	)
	(via
		(at 358.1781 -13.426186)
		(size 0.508)
		(drill 0.254)
		(layers "F.Cu" "B.Cu")
		(net "GND")
	)
	(via
		(at 446.1764 -50.4952)
		(size 0.508)
		(drill 0.254)
		(layers "F.Cu" "B.Cu")
		(net "GND")
	)
	(via
		(at 335.7372 -134.0739)
		(size 0.508)
		(drill 0.254)
		(layers "F.Cu" "B.Cu")
		(net "GND")
	)
	(via
		(at 314.54979 -131.016756)
		(size 0.508)
		(drill 0.254)
		(layers "F.Cu" "B.Cu")
		(net "GND")
	)
	(via
		(at 292.36924 -67.791584)
		(size 0.508)
		(drill 0.254)
		(layers "F.Cu" "B.Cu")
		(net "GND")
	)
	(via
		(at 171.15282 -21.0947)
		(size 0.508)
		(drill 0.254)
		(layers "F.Cu" "B.Cu")
		(net "GND")
	)
	(via
		(at 117.071648 -150.193756)
		(size 0.508)
		(drill 0.254)
		(layers "F.Cu" "B.Cu")
		(net "GND")
	)
	(via
		(at 350.7994 -77.30744)
		(size 0.508)
		(drill 0.254)
		(layers "F.Cu" "B.Cu")
		(net "GND")
	)
	(via
		(at 117.640862 -61.847984)
		(size 0.508)
		(drill 0.254)
		(layers "F.Cu" "B.Cu")
		(net "GND")
	)
	(via
		(at 134.236714 -92.556584)
		(size 0.508)
		(drill 0.254)
		(layers "F.Cu" "B.Cu")
		(net "GND")
	)
	(via
		(at 262.361934 14.926056)
		(size 0.5588)
		(drill 0.3048)
		(layers "F.Cu" "B.Cu")
		(net "GND")
	)
	(via
		(at 420.400734 -163.361624)
		(size 0.5588)
		(drill 0.3048)
		(layers "F.Cu" "B.Cu")
		(net "GND")
	)
	(via
		(at 152.949402 -134.340346)
		(size 0.508)
		(drill 0.254)
		(layers "F.Cu" "B.Cu")
		(net "GND")
	)
	(via
		(at 388.0358 -1.768602)
		(size 0.508)
		(drill 0.254)
		(layers "F.Cu" "B.Cu")
		(net "GND")
	)
	(via
		(at 237.142528 -124.623576)
		(size 0.508)
		(drill 0.254)
		(layers "F.Cu" "B.Cu")
		(net "GND")
	)
	(via
		(at 436.910734 -164.479224)
		(size 0.5588)
		(drill 0.3048)
		(layers "F.Cu" "B.Cu")
		(net "GND")
	)
	(via
		(at 272.624042 -100.977192)
		(size 0.508)
		(drill 0.254)
		(layers "F.Cu" "B.Cu")
		(net "GND")
	)
	(via
		(at 68.894706 -67.47764)
		(size 0.508)
		(drill 0.254)
		(layers "F.Cu" "B.Cu")
		(net "GND")
	)
	(via
		(at 11.2268 -29.6672)
		(size 0.508)
		(drill 0.254)
		(layers "F.Cu" "B.Cu")
		(net "GND")
	)
	(via
		(at 388.22884 -62.070234)
		(size 0.508)
		(drill 0.254)
		(layers "F.Cu" "B.Cu")
		(net "GND")
	)
	(via
		(at 475.010734 -166.714424)
		(size 0.5588)
		(drill 0.3048)
		(layers "F.Cu" "B.Cu")
		(net "GND")
	)
	(via
		(at 421.670734 -165.596824)
		(size 0.5588)
		(drill 0.3048)
		(layers "F.Cu" "B.Cu")
		(net "GND")
	)
	(via
		(at 315.399928 -139.170156)
		(size 0.508)
		(drill 0.254)
		(layers "F.Cu" "B.Cu")
		(net "GND")
	)
	(via
		(at 478.261934 12.894056)
		(size 0.5588)
		(drill 0.3048)
		(layers "F.Cu" "B.Cu")
		(net "GND")
	)
	(via
		(at 439.976006 -40.5257)
		(size 0.508)
		(drill 0.254)
		(layers "F.Cu" "B.Cu")
		(net "GND")
	)
	(via
		(at 140.246354 -61.352938)
		(size 0.508)
		(drill 0.254)
		(layers "F.Cu" "B.Cu")
		(net "GND")
	)
	(via
		(at 152.099518 -9.156446)
		(size 0.508)
		(drill 0.254)
		(layers "F.Cu" "B.Cu")
		(net "GND")
	)
	(via
		(at 77.217524 -162.243262)
		(size 0.5588)
		(drill 0.3048)
		(layers "F.Cu" "B.Cu")
		(net "GND")
	)
	(via
		(at 237.149132 -144.0053)
		(size 0.508)
		(drill 0.254)
		(layers "F.Cu" "B.Cu")
		(net "GND")
	)
	(via
		(at 70.611746 -87.28964)
		(size 0.508)
		(drill 0.254)
		(layers "F.Cu" "B.Cu")
		(net "GND")
	)
	(via
		(at 42.781982 -77.789278)
		(size 0.5588)
		(drill 0.3048)
		(layers "F.Cu" "B.Cu")
		(net "GND")
	)
	(via
		(at 36.838382 -76.468478)
		(size 0.5588)
		(drill 0.3048)
		(layers "F.Cu" "B.Cu")
		(net "GND")
	)
	(via
		(at 345.0082 -87.4268)
		(size 0.508)
		(drill 0.254)
		(layers "F.Cu" "B.Cu")
		(net "GND")
	)
	(via
		(at 200.8886 -96.7994)
		(size 0.508)
		(drill 0.254)
		(layers "F.Cu" "B.Cu")
		(net "GND")
	)
	(via
		(at 276.331934 14.926056)
		(size 0.5588)
		(drill 0.3048)
		(layers "F.Cu" "B.Cu")
		(net "GND")
	)
	(via
		(at 81.618836 -17.7546)
		(size 0.508)
		(drill 0.254)
		(layers "F.Cu" "B.Cu")
		(net "GND")
	)
	(via
		(at 482.071934 11.624056)
		(size 0.5588)
		(drill 0.3048)
		(layers "F.Cu" "B.Cu")
		(net "GND")
	)
	(via
		(at 445.77 -123.19)
		(size 0.508)
		(drill 0.254)
		(layers "F.Cu" "B.Cu")
		(net "GND")
	)
	(via
		(at 373.1641 -61.704474)
		(size 0.508)
		(drill 0.254)
		(layers "F.Cu" "B.Cu")
		(net "GND")
	)
	(via
		(at 124.793248 -97.014538)
		(size 0.508)
		(drill 0.254)
		(layers "F.Cu" "B.Cu")
		(net "GND")
	)
	(via
		(at 491.516924 -162.243262)
		(size 0.5588)
		(drill 0.3048)
		(layers "F.Cu" "B.Cu")
		(net "GND")
	)
	(via
		(at 478.820734 -167.832024)
		(size 0.5588)
		(drill 0.3048)
		(layers "F.Cu" "B.Cu")
		(net "GND")
	)
	(via
		(at 143.501364 -144.462246)
		(size 0.508)
		(drill 0.254)
		(layers "F.Cu" "B.Cu")
		(net "GND")
	)
	(via
		(at 140.199364 -131.016756)
		(size 0.508)
		(drill 0.254)
		(layers "F.Cu" "B.Cu")
		(net "GND")
	)
	(via
		(at 169.84091 -30.01899)
		(size 0.508)
		(drill 0.254)
		(layers "F.Cu" "B.Cu")
		(net "GND")
	)
	(via
		(at 478.261934 9.084056)
		(size 0.5588)
		(drill 0.3048)
		(layers "F.Cu" "B.Cu")
		(net "GND")
	)
	(via
		(at 179.2097 -40.35552)
		(size 0.508)
		(drill 0.254)
		(layers "F.Cu" "B.Cu")
		(net "GND")
	)
	(via
		(at 97.225358 -56.085486)
		(size 0.508)
		(drill 0.254)
		(layers "F.Cu" "B.Cu")
		(net "GND")
	)
	(via
		(at 183.4007 -56.1721)
		(size 0.508)
		(drill 0.254)
		(layers "F.Cu" "B.Cu")
		(net "GND")
	)
	(via
		(at 139.34948 -148.771356)
		(size 0.508)
		(drill 0.254)
		(layers "F.Cu" "B.Cu")
		(net "GND")
	)
	(via
		(at 260.731 -138.7856)
		(size 0.508)
		(drill 0.254)
		(layers "F.Cu" "B.Cu")
		(net "GND")
	)
	(via
		(at 125.201934 9.084056)
		(size 0.5588)
		(drill 0.3048)
		(layers "F.Cu" "B.Cu")
		(net "GND")
	)
	(via
		(at 7.930134 -167.832024)
		(size 0.5588)
		(drill 0.3048)
		(layers "F.Cu" "B.Cu")
		(net "GND")
	)
	(via
		(at 431.826924 -162.243262)
		(size 0.5588)
		(drill 0.3048)
		(layers "F.Cu" "B.Cu")
		(net "GND")
	)
	(via
		(at 162.570922 -29.902912)
		(size 0.508)
		(drill 0.254)
		(layers "F.Cu" "B.Cu")
		(net "GND")
	)
	(via
		(at 381.8128 -134.747)
		(size 0.508)
		(drill 0.254)
		(layers "F.Cu" "B.Cu")
		(net "GND")
	)
	(via
		(at 111.057182 -95.033084)
		(size 0.508)
		(drill 0.254)
		(layers "F.Cu" "B.Cu")
		(net "GND")
	)
	(via
		(at 4.3434 -138.5316)
		(size 0.508)
		(drill 0.254)
		(layers "F.Cu" "B.Cu")
		(net "GND")
	)
	(via
		(at 74.045826 -67.47764)
		(size 0.508)
		(drill 0.254)
		(layers "F.Cu" "B.Cu")
		(net "GND")
	)
	(via
		(at 177.76952 -16.97736)
		(size 0.508)
		(drill 0.254)
		(layers "F.Cu" "B.Cu")
		(net "GND")
	)
	(via
		(at 72.328786 -101.15804)
		(size 0.508)
		(drill 0.254)
		(layers "F.Cu" "B.Cu")
		(net "GND")
	)
	(via
		(at 292.392608 -9.143746)
		(size 0.508)
		(drill 0.254)
		(layers "F.Cu" "B.Cu")
		(net "GND")
	)
	(via
		(at 220.270324 -162.243262)
		(size 0.5588)
		(drill 0.3048)
		(layers "F.Cu" "B.Cu")
		(net "GND")
	)
	(via
		(at 366.724438 -145.410428)
		(size 0.508)
		(drill 0.254)
		(layers "F.Cu" "B.Cu")
		(net "GND")
	)
	(via
		(at 392.1379 -108.2548)
		(size 0.508)
		(drill 0.254)
		(layers "F.Cu" "B.Cu")
		(net "GND")
	)
	(via
		(at 132.519674 -59.866784)
		(size 0.508)
		(drill 0.254)
		(layers "F.Cu" "B.Cu")
		(net "GND")
	)
	(via
		(at 54.731412 -129.5654)
		(size 0.508)
		(drill 0.254)
		(layers "F.Cu" "B.Cu")
		(net "GND")
	)
	(via
		(at 129.944368 -84.136738)
		(size 0.508)
		(drill 0.254)
		(layers "F.Cu" "B.Cu")
		(net "GND")
	)
	(via
		(at 301.746412 -124.614686)
		(size 0.508)
		(drill 0.254)
		(layers "F.Cu" "B.Cu")
		(net "GND")
	)
	(via
		(at 72.142096 -155.600146)
		(size 0.508)
		(drill 0.254)
		(layers "F.Cu" "B.Cu")
		(net "GND")
	)
	(via
		(at 271.48028 -82.340196)
		(size 0.5588)
		(drill 0.3048)
		(layers "F.Cu" "B.Cu")
		(net "GND")
	)
	(via
		(at 373.485156 -8.84682)
		(size 0.508)
		(drill 0.254)
		(layers "F.Cu" "B.Cu")
		(net "GND")
	)
	(via
		(at 221.04985 -146.011646)
		(size 0.508)
		(drill 0.254)
		(layers "F.Cu" "B.Cu")
		(net "GND")
	)
	(via
		(at 0.271272 -6.307074)
		(size 0.508)
		(drill 0.254)
		(layers "F.Cu" "B.Cu")
		(net "GND")
	)
	(via
		(at 433.100734 -163.361624)
		(size 0.5588)
		(drill 0.3048)
		(layers "F.Cu" "B.Cu")
		(net "GND")
	)
	(via
		(at 401.8788 -115.8748)
		(size 0.508)
		(drill 0.254)
		(layers "F.Cu" "B.Cu")
		(net "GND")
	)
	(via
		(at 345.506294 -147.033742)
		(size 0.508)
		(drill 0.254)
		(layers "F.Cu" "B.Cu")
		(net "GND")
	)
	(via
		(at 240.763298 -80.35544)
		(size 0.508)
		(drill 0.254)
		(layers "F.Cu" "B.Cu")
		(net "GND")
	)
	(via
		(at 40.699182 -78.449678)
		(size 0.5588)
		(drill 0.3048)
		(layers "F.Cu" "B.Cu")
		(net "GND")
	)
	(via
		(at 283.0576 -7.1374)
		(size 0.508)
		(drill 0.254)
		(layers "F.Cu" "B.Cu")
		(net "GND")
	)
	(via
		(at 75.762866 -64.50584)
		(size 0.508)
		(drill 0.254)
		(layers "F.Cu" "B.Cu")
		(net "GND")
	)
	(via
		(at 67.079368 -56.56834)
		(size 0.508)
		(drill 0.254)
		(layers "F.Cu" "B.Cu")
		(net "GND")
	)
	(via
		(at 136.454134 -167.832024)
		(size 0.5588)
		(drill 0.3048)
		(layers "F.Cu" "B.Cu")
		(net "GND")
	)
	(via
		(at 495.91976 -25.02408)
		(size 0.508)
		(drill 0.254)
		(layers "F.Cu" "B.Cu")
		(net "GND")
	)
	(via
		(at 142.740634 -80.59928)
		(size 0.508)
		(drill 0.254)
		(layers "F.Cu" "B.Cu")
		(net "GND")
	)
	(via
		(at 483.87254 -121.77014)
		(size 0.508)
		(drill 0.254)
		(layers "F.Cu" "B.Cu")
		(net "GND")
	)
	(via
		(at 177.165 -135.8265)
		(size 0.508)
		(drill 0.254)
		(layers "F.Cu" "B.Cu")
		(net "GND")
	)
	(via
		(at 388.091934 9.084056)
		(size 0.5588)
		(drill 0.3048)
		(layers "F.Cu" "B.Cu")
		(net "GND")
	)
	(via
		(at 216.799922 -9.156446)
		(size 0.508)
		(drill 0.254)
		(layers "F.Cu" "B.Cu")
		(net "GND")
	)
	(via
		(at 124.82322 -27.829256)
		(size 0.508)
		(drill 0.254)
		(layers "F.Cu" "B.Cu")
		(net "GND")
	)
	(via
		(at 410.428948 -153.798778)
		(size 0.508)
		(drill 0.254)
		(layers "F.Cu" "B.Cu")
		(net "GND")
	)
	(via
		(at 86.064852 -80.35544)
		(size 0.508)
		(drill 0.254)
		(layers "F.Cu" "B.Cu")
		(net "GND")
	)
	(via
		(at 346.510102 -77.138276)
		(size 0.508)
		(drill 0.254)
		(layers "F.Cu" "B.Cu")
		(net "GND")
	)
	(via
		(at 498.581934 13.910056)
		(size 0.5588)
		(drill 0.3048)
		(layers "F.Cu" "B.Cu")
		(net "GND")
	)
	(via
		(at 294.999918 -148.771356)
		(size 0.508)
		(drill 0.254)
		(layers "F.Cu" "B.Cu")
		(net "GND")
	)
	(via
		(at 270.571468 -53.923184)
		(size 0.508)
		(drill 0.254)
		(layers "F.Cu" "B.Cu")
		(net "GND")
	)
	(via
		(at 237.329218 -99.17684)
		(size 0.508)
		(drill 0.254)
		(layers "F.Cu" "B.Cu")
		(net "GND")
	)
	(via
		(at 354.477574 -133.440678)
		(size 0.508)
		(drill 0.254)
		(layers "F.Cu" "B.Cu")
		(net "GND")
	)
	(via
		(at 155.681934 14.926056)
		(size 0.5588)
		(drill 0.3048)
		(layers "F.Cu" "B.Cu")
		(net "GND")
	)
	(via
		(at 169.982134 -167.832024)
		(size 0.5588)
		(drill 0.3048)
		(layers "F.Cu" "B.Cu")
		(net "GND")
	)
	(via
		(at 400.080734 -164.479224)
		(size 0.5588)
		(drill 0.3048)
		(layers "F.Cu" "B.Cu")
		(net "GND")
	)
	(via
		(at 491.520734 -167.832024)
		(size 0.5588)
		(drill 0.3048)
		(layers "F.Cu" "B.Cu")
		(net "GND")
	)
	(via
		(at 441.722256 -27.432)
		(size 0.4572)
		(drill 0.2032)
		(layers "F.Cu" "B.Cu")
		(net "GND")
	)
	(via
		(at 384.281934 9.084056)
		(size 0.5588)
		(drill 0.3048)
		(layers "F.Cu" "B.Cu")
		(net "GND")
	)
	(via
		(at 290.6522 -61.847984)
		(size 0.508)
		(drill 0.254)
		(layers "F.Cu" "B.Cu")
		(net "GND")
	)
	(via
		(at 116.782342 -59.371484)
		(size 0.508)
		(drill 0.254)
		(layers "F.Cu" "B.Cu")
		(net "GND")
	)
	(via
		(at 49.412398 -76.1365)
		(size 0.508)
		(drill 0.254)
		(layers "F.Cu" "B.Cu")
		(net "GND")
	)
	(via
		(at 280.924254 -58.876438)
		(size 0.508)
		(drill 0.254)
		(layers "F.Cu" "B.Cu")
		(net "GND")
	)
	(via
		(at 132.549392 -131.016756)
		(size 0.508)
		(drill 0.254)
		(layers "F.Cu" "B.Cu")
		(net "GND")
	)
	(via
		(at 389.7376 -112.2553)
		(size 0.508)
		(drill 0.254)
		(layers "F.Cu" "B.Cu")
		(net "GND")
	)
	(via
		(at 340.7156 -11.7094)
		(size 0.508)
		(drill 0.254)
		(layers "F.Cu" "B.Cu")
		(net "GND")
	)
	(via
		(at 394.032486 -3.249168)
		(size 0.508)
		(drill 0.254)
		(layers "F.Cu" "B.Cu")
		(net "GND")
	)
	(via
		(at 379.81255 -107.907836)
		(size 0.508)
		(drill 0.254)
		(layers "F.Cu" "B.Cu")
		(net "GND")
	)
	(via
		(at 394.9192 -157.71114)
		(size 0.508)
		(drill 0.254)
		(layers "F.Cu" "B.Cu")
		(net "GND")
	)
	(via
		(at 207.411828 -155.612846)
		(size 0.508)
		(drill 0.254)
		(layers "F.Cu" "B.Cu")
		(net "GND")
	)
	(via
		(at 446.511934 11.624056)
		(size 0.5588)
		(drill 0.3048)
		(layers "F.Cu" "B.Cu")
		(net "GND")
	)
	(via
		(at 6.883908 -6.447282)
		(size 0.508)
		(drill 0.254)
		(layers "F.Cu" "B.Cu")
		(net "GND")
	)
	(via
		(at 379.674882 -45.188378)
		(size 0.508)
		(drill 0.254)
		(layers "F.Cu" "B.Cu")
		(net "GND")
	)
	(via
		(at 234.753658 -82.83194)
		(size 0.508)
		(drill 0.254)
		(layers "F.Cu" "B.Cu")
		(net "GND")
	)
	(via
		(at 130.802888 -62.838584)
		(size 0.508)
		(drill 0.254)
		(layers "F.Cu" "B.Cu")
		(net "GND")
	)
	(via
		(at 124.793248 -76.211938)
		(size 0.508)
		(drill 0.254)
		(layers "F.Cu" "B.Cu")
		(net "GND")
	)
	(via
		(at 246.772684 -83.822286)
		(size 0.508)
		(drill 0.254)
		(layers "F.Cu" "B.Cu")
		(net "GND")
	)
	(via
		(at 399.542 -99.354894)
		(size 0.508)
		(drill 0.254)
		(layers "F.Cu" "B.Cu")
		(net "GND")
	)
	(via
		(at 311.0992 -153.6065)
		(size 0.508)
		(drill 0.254)
		(layers "F.Cu" "B.Cu")
		(net "GND")
	)
	(via
		(at 300.061884 -2.314956)
		(size 0.508)
		(drill 0.254)
		(layers "F.Cu" "B.Cu")
		(net "GND")
	)
	(via
		(at 247.631204 -79.36484)
		(size 0.508)
		(drill 0.254)
		(layers "F.Cu" "B.Cu")
		(net "GND")
	)
	(via
		(at 407.12136 -9.495028)
		(size 0.508)
		(drill 0.254)
		(layers "F.Cu" "B.Cu")
		(net "GND")
	)
	(via
		(at 17.432528 -35.0012)
		(size 0.508)
		(drill 0.254)
		(layers "F.Cu" "B.Cu")
		(net "GND")
	)
	(via
		(at 286.212534 -167.832024)
		(size 0.5588)
		(drill 0.3048)
		(layers "F.Cu" "B.Cu")
		(net "GND")
	)
	(via
		(at 283.036264 -23.495)
		(size 0.508)
		(drill 0.254)
		(layers "F.Cu" "B.Cu")
		(net "GND")
	)
	(via
		(at 239.749838 -124.572776)
		(size 0.508)
		(drill 0.254)
		(layers "F.Cu" "B.Cu")
		(net "GND")
	)
	(via
		(at 114.761264 -75.159616)
		(size 0.5588)
		(drill 0.3048)
		(layers "F.Cu" "B.Cu")
		(net "GND")
	)
	(via
		(at 311.092596 -18.744946)
		(size 0.508)
		(drill 0.254)
		(layers "F.Cu" "B.Cu")
		(net "GND")
	)
	(via
		(at 282.067254 -100.48113)
		(size 0.508)
		(drill 0.254)
		(layers "F.Cu" "B.Cu")
		(net "GND")
	)
	(via
		(at 286.491934 14.926056)
		(size 0.5588)
		(drill 0.3048)
		(layers "F.Cu" "B.Cu")
		(net "GND")
	)
	(via
		(at 260.50875 -53.113686)
		(size 0.508)
		(drill 0.254)
		(layers "F.Cu" "B.Cu")
		(net "GND")
	)
	(via
		(at 283.0322 -13.8938)
		(size 0.508)
		(drill 0.254)
		(layers "F.Cu" "B.Cu")
		(net "GND")
	)
	(via
		(at 405.262588 -32.328612)
		(size 0.508)
		(drill 0.254)
		(layers "F.Cu" "B.Cu")
		(net "GND")
	)
	(via
		(at 396.65275 -99.322636)
		(size 0.508)
		(drill 0.254)
		(layers "F.Cu" "B.Cu")
		(net "GND")
	)
	(via
		(at 242.480338 -63.51524)
		(size 0.508)
		(drill 0.254)
		(layers "F.Cu" "B.Cu")
		(net "GND")
	)
	(via
		(at 352.841052 -14.858746)
		(size 0.508)
		(drill 0.254)
		(layers "F.Cu" "B.Cu")
		(net "GND")
	)
	(via
		(at 243.338604 -92.737686)
		(size 0.508)
		(drill 0.254)
		(layers "F.Cu" "B.Cu")
		(net "GND")
	)
	(via
		(at 498.581934 10.354056)
		(size 0.5588)
		(drill 0.3048)
		(layers "F.Cu" "B.Cu")
		(net "GND")
	)
	(via
		(at 484.611934 13.910056)
		(size 0.5588)
		(drill 0.3048)
		(layers "F.Cu" "B.Cu")
		(net "GND")
	)
	(via
		(at 400.080734 -165.596824)
		(size 0.5588)
		(drill 0.3048)
		(layers "F.Cu" "B.Cu")
		(net "GND")
	)
	(via
		(at 82.630772 -88.28024)
		(size 0.508)
		(drill 0.254)
		(layers "F.Cu" "B.Cu")
		(net "GND")
	)
	(via
		(at 207.502252 -81.251552)
		(size 0.5588)
		(drill 0.3048)
		(layers "F.Cu" "B.Cu")
		(net "GND")
	)
	(via
		(at 244.197124 -68.46824)
		(size 0.508)
		(drill 0.254)
		(layers "F.Cu" "B.Cu")
		(net "GND")
	)
	(via
		(at 248.489724 -84.812886)
		(size 0.508)
		(drill 0.254)
		(layers "F.Cu" "B.Cu")
		(net "GND")
	)
	(via
		(at 15.753334 -167.832024)
		(size 0.5588)
		(drill 0.3048)
		(layers "F.Cu" "B.Cu")
		(net "GND")
	)
	(via
		(at 405.8158 -2.286)
		(size 0.508)
		(drill 0.254)
		(layers "F.Cu" "B.Cu")
		(net "GND")
	)
	(via
		(at 282.855924 -162.243262)
		(size 0.5588)
		(drill 0.3048)
		(layers "F.Cu" "B.Cu")
		(net "GND")
	)
	(via
		(at 45.390816 2.505456)
		(size 0.508)
		(drill 0.254)
		(layers "F.Cu" "B.Cu")
		(net "GND")
	)
	(via
		(at 229.081838 -11.9126)
		(size 0.508)
		(drill 0.254)
		(layers "F.Cu" "B.Cu")
		(net "GND")
	)
	(via
		(at 305.246786 -72.249538)
		(size 0.508)
		(drill 0.254)
		(layers "F.Cu" "B.Cu")
		(net "GND")
	)
	(via
		(at 47.549308 -7.607046)
		(size 0.508)
		(drill 0.254)
		(layers "F.Cu" "B.Cu")
		(net "GND")
	)
	(via
		(at 43.921934 9.084056)
		(size 0.5588)
		(drill 0.3048)
		(layers "F.Cu" "B.Cu")
		(net "GND")
	)
	(via
		(at 352.7806 -133.40842)
		(size 0.508)
		(drill 0.254)
		(layers "F.Cu" "B.Cu")
		(net "GND")
	)
	(via
		(at 86.064852 -90.26144)
		(size 0.508)
		(drill 0.254)
		(layers "F.Cu" "B.Cu")
		(net "GND")
	)
	(via
		(at 497.311934 14.926056)
		(size 0.5588)
		(drill 0.3048)
		(layers "F.Cu" "B.Cu")
		(net "GND")
	)
	(via
		(at 419.7858 -150.1902)
		(size 0.508)
		(drill 0.254)
		(layers "F.Cu" "B.Cu")
		(net "GND")
	)
	(via
		(at 360.505502 -151.67102)
		(size 0.5588)
		(drill 0.3048)
		(layers "F.Cu" "B.Cu")
		(net "GND")
	)
	(via
		(at 398.251934 9.084056)
		(size 0.5588)
		(drill 0.3048)
		(layers "F.Cu" "B.Cu")
		(net "GND")
	)
	(via
		(at 292.399212 -144.0053)
		(size 0.508)
		(drill 0.254)
		(layers "F.Cu" "B.Cu")
		(net "GND")
	)
	(via
		(at 246.772684 -63.019686)
		(size 0.508)
		(drill 0.254)
		(layers "F.Cu" "B.Cu")
		(net "GND")
	)
	(via
		(at 83.489292 -92.737686)
		(size 0.508)
		(drill 0.254)
		(layers "F.Cu" "B.Cu")
		(net "GND")
	)
	(via
		(at 278.633174 -93.547184)
		(size 0.508)
		(drill 0.254)
		(layers "F.Cu" "B.Cu")
		(net "GND")
	)
	(via
		(at 281.782774 -59.371484)
		(size 0.508)
		(drill 0.254)
		(layers "F.Cu" "B.Cu")
		(net "GND")
	)
	(via
		(at 1.542796 -52.913534)
		(size 0.5588)
		(drill 0.3048)
		(layers "F.Cu" "B.Cu")
		(net "GND")
	)
	(via
		(at 384.281934 14.926056)
		(size 0.5588)
		(drill 0.3048)
		(layers "F.Cu" "B.Cu")
		(net "GND")
	)
	(via
		(at 453.0598 -147.1168)
		(size 0.508)
		(drill 0.254)
		(layers "F.Cu" "B.Cu")
		(net "GND")
	)
	(via
		(at 175.42764 -67.056)
		(size 0.508)
		(drill 0.254)
		(layers "F.Cu" "B.Cu")
		(net "GND")
	)
	(via
		(at 404.158196 -57.154318)
		(size 0.508)
		(drill 0.254)
		(layers "F.Cu" "B.Cu")
		(net "GND")
	)
	(via
		(at 107.421934 14.926056)
		(size 0.5588)
		(drill 0.3048)
		(layers "F.Cu" "B.Cu")
		(net "GND")
	)
	(via
		(at 387.477 -147.999196)
		(size 0.508)
		(drill 0.254)
		(layers "F.Cu" "B.Cu")
		(net "GND")
	)
	(via
		(at 45.387514 -4.346956)
		(size 0.508)
		(drill 0.254)
		(layers "F.Cu" "B.Cu")
		(net "GND")
	)
	(via
		(at 285.501334 -89.584784)
		(size 0.508)
		(drill 0.254)
		(layers "F.Cu" "B.Cu")
		(net "GND")
	)
	(via
		(at 133.378194 -97.014538)
		(size 0.508)
		(drill 0.254)
		(layers "F.Cu" "B.Cu")
		(net "GND")
	)
	(via
		(at 450.321934 11.624056)
		(size 0.5588)
		(drill 0.3048)
		(layers "F.Cu" "B.Cu")
		(net "GND")
	)
	(via
		(at 206.4766 -76.5048)
		(size 0.5588)
		(drill 0.3048)
		(layers "F.Cu" "B.Cu")
		(net "GND")
	)
	(via
		(at 431.8762 -24.054562)
		(size 0.508)
		(drill 0.254)
		(layers "F.Cu" "B.Cu")
		(net "GND")
	)
	(via
		(at 304.388266 -72.744584)
		(size 0.508)
		(drill 0.254)
		(layers "F.Cu" "B.Cu")
		(net "GND")
	)
	(via
		(at 39.899336 -22.965156)
		(size 0.508)
		(drill 0.254)
		(layers "F.Cu" "B.Cu")
		(net "GND")
	)
	(via
		(at 464.850734 -163.361624)
		(size 0.5588)
		(drill 0.3048)
		(layers "F.Cu" "B.Cu")
		(net "GND")
	)
	(via
		(at 75.762866 -101.15804)
		(size 0.508)
		(drill 0.254)
		(layers "F.Cu" "B.Cu")
		(net "GND")
	)
	(via
		(at 286.3596 -77.202538)
		(size 0.508)
		(drill 0.254)
		(layers "F.Cu" "B.Cu")
		(net "GND")
	)
	(via
		(at 214.6554 -92.202)
		(size 0.508)
		(drill 0.254)
		(layers "F.Cu" "B.Cu")
		(net "GND")
	)
	(via
		(at 346.988384 -137.131806)
		(size 0.508)
		(drill 0.254)
		(layers "F.Cu" "B.Cu")
		(net "GND")
	)
	(via
		(at 423.490136 -34.934398)
		(size 0.4572)
		(drill 0.2032)
		(layers "F.Cu" "B.Cu")
		(net "GND")
	)
	(via
		(at 264.901934 14.926056)
		(size 0.5588)
		(drill 0.3048)
		(layers "F.Cu" "B.Cu")
		(net "GND")
	)
	(via
		(at 35.499802 -90.2208)
		(size 0.508)
		(drill 0.254)
		(layers "F.Cu" "B.Cu")
		(net "GND")
	)
	(via
		(at 89.498678 -60.54344)
		(size 0.508)
		(drill 0.254)
		(layers "F.Cu" "B.Cu")
		(net "GND")
	)
	(via
		(at 121.359168 -69.277738)
		(size 0.508)
		(drill 0.254)
		(layers "F.Cu" "B.Cu")
		(net "GND")
	)
	(via
		(at 494.771934 12.894056)
		(size 0.5588)
		(drill 0.3048)
		(layers "F.Cu" "B.Cu")
		(net "GND")
	)
	(via
		(at 454.2028 -23.622)
		(size 0.508)
		(drill 0.254)
		(layers "F.Cu" "B.Cu")
		(net "GND")
	)
	(via
		(at 371.221 -137.16)
		(size 0.508)
		(drill 0.254)
		(layers "F.Cu" "B.Cu")
		(net "GND")
	)
	(via
		(at 299.237146 -62.838584)
		(size 0.508)
		(drill 0.254)
		(layers "F.Cu" "B.Cu")
		(net "GND")
	)
	(via
		(at -3.245866 -166.714424)
		(size 0.5588)
		(drill 0.3048)
		(layers "F.Cu" "B.Cu")
		(net "GND")
	)
	(via
		(at 312.3946 -18.6817)
		(size 0.508)
		(drill 0.254)
		(layers "F.Cu" "B.Cu")
		(net "GND")
	)
	(via
		(at 229.081838 -148.7678)
		(size 0.508)
		(drill 0.254)
		(layers "F.Cu" "B.Cu")
		(net "GND")
	)
	(via
		(at 242.480338 -72.43064)
		(size 0.508)
		(drill 0.254)
		(layers "F.Cu" "B.Cu")
		(net "GND")
	)
	(via
		(at 241.4778 -124.6378)
		(size 0.508)
		(drill 0.254)
		(layers "F.Cu" "B.Cu")
		(net "GND")
	)
	(via
		(at 6.562852 5.196332)
		(size 0.508)
		(drill 0.254)
		(layers "F.Cu" "B.Cu")
		(net "GND")
	)
	(via
		(at 42.77995 -62.164722)
		(size 0.5588)
		(drill 0.3048)
		(layers "F.Cu" "B.Cu")
		(net "GND")
	)
	(via
		(at 35.499802 -83.2612)
		(size 0.508)
		(drill 0.254)
		(layers "F.Cu" "B.Cu")
		(net "GND")
	)
	(via
		(at 92.074238 -53.113686)
		(size 0.508)
		(drill 0.254)
		(layers "F.Cu" "B.Cu")
		(net "GND")
	)
	(via
		(at 344.309192 -142.229586)
		(size 0.508)
		(drill 0.254)
		(layers "F.Cu" "B.Cu")
		(net "GND")
	)
	(via
		(at 110.111032 -140.208)
		(size 0.508)
		(drill 0.254)
		(layers "F.Cu" "B.Cu")
		(net "GND")
	)
	(via
		(at 365.231934 9.084056)
		(size 0.5588)
		(drill 0.3048)
		(layers "F.Cu" "B.Cu")
		(net "GND")
	)
	(via
		(at 284.344364 -145.9357)
		(size 0.508)
		(drill 0.254)
		(layers "F.Cu" "B.Cu")
		(net "GND")
	)
	(via
		(at 472.480132 -114.381788)
		(size 0.508)
		(drill 0.254)
		(layers "F.Cu" "B.Cu")
		(net "GND")
	)
	(via
		(at 144.251934 14.926056)
		(size 0.5588)
		(drill 0.3048)
		(layers "F.Cu" "B.Cu")
		(net "GND")
	)
	(via
		(at 62.792102 -18.744946)
		(size 0.508)
		(drill 0.254)
		(layers "F.Cu" "B.Cu")
		(net "GND")
	)
	(via
		(at 164.76726 -31.89986)
		(size 0.508)
		(drill 0.254)
		(layers "F.Cu" "B.Cu")
		(net "GND")
	)
	(via
		(at 293.688008 -141.202156)
		(size 0.508)
		(drill 0.254)
		(layers "F.Cu" "B.Cu")
		(net "GND")
	)
	(via
		(at 360.151934 14.926056)
		(size 0.5588)
		(drill 0.3048)
		(layers "F.Cu" "B.Cu")
		(net "GND")
	)
	(via
		(at 443.971934 14.926056)
		(size 0.5588)
		(drill 0.3048)
		(layers "F.Cu" "B.Cu")
		(net "GND")
	)
	(via
		(at -1.332484 -59.017154)
		(size 0.5588)
		(drill 0.3048)
		(layers "F.Cu" "B.Cu")
		(net "GND")
	)
	(via
		(at 265.659616 -98.681286)
		(size 0.508)
		(drill 0.254)
		(layers "F.Cu" "B.Cu")
		(net "GND")
	)
	(via
		(at 380.418594 -8.744458)
		(size 0.508)
		(drill 0.254)
		(layers "F.Cu" "B.Cu")
		(net "GND")
	)
	(via
		(at 247.631204 -94.223586)
		(size 0.508)
		(drill 0.254)
		(layers "F.Cu" "B.Cu")
		(net "GND")
	)
	(via
		(at 51.76139 -21.517356)
		(size 0.508)
		(drill 0.254)
		(layers "F.Cu" "B.Cu")
		(net "GND")
	)
	(via
		(at 186.8424 -41.8846)
		(size 0.508)
		(drill 0.254)
		(layers "F.Cu" "B.Cu")
		(net "GND")
	)
	(via
		(at 331.216 -15.748)
		(size 0.508)
		(drill 0.254)
		(layers "F.Cu" "B.Cu")
		(net "GND")
	)
	(via
		(at 6.112256 -15.721076)
		(size 0.508)
		(drill 0.254)
		(layers "F.Cu" "B.Cu")
		(net "GND")
	)
	(via
		(at 232.0798 -56.56834)
		(size 0.508)
		(drill 0.254)
		(layers "F.Cu" "B.Cu")
		(net "GND")
	)
	(via
		(at 347.829632 -12.821666)
		(size 0.508)
		(drill 0.254)
		(layers "F.Cu" "B.Cu")
		(net "GND")
	)
	(via
		(at 18.669 -48.641)
		(size 0.508)
		(drill 0.254)
		(layers "F.Cu" "B.Cu")
		(net "GND")
	)
	(via
		(at 166.629334 -167.832024)
		(size 0.5588)
		(drill 0.3048)
		(layers "F.Cu" "B.Cu")
		(net "GND")
	)
	(via
		(at 396.981934 9.084056)
		(size 0.5588)
		(drill 0.3048)
		(layers "F.Cu" "B.Cu")
		(net "GND")
	)
	(via
		(at 215.860884 -22.939756)
		(size 0.508)
		(drill 0.254)
		(layers "F.Cu" "B.Cu")
		(net "GND")
	)
	(via
		(at 175.478694 -52.861718)
		(size 0.508)
		(drill 0.254)
		(layers "F.Cu" "B.Cu")
		(net "GND")
	)
	(via
		(at 197.612 -96.1898)
		(size 0.508)
		(drill 0.254)
		(layers "F.Cu" "B.Cu")
		(net "GND")
	)
	(via
		(at 219.731844 -11.9126)
		(size 0.508)
		(drill 0.254)
		(layers "F.Cu" "B.Cu")
		(net "GND")
	)
	(via
		(at 58.599324 -3.762756)
		(size 0.508)
		(drill 0.254)
		(layers "F.Cu" "B.Cu")
		(net "GND")
	)
	(via
		(at 380.30785 -100.181156)
		(size 0.508)
		(drill 0.254)
		(layers "F.Cu" "B.Cu")
		(net "GND")
	)
	(via
		(at 109.914182 -62.343538)
		(size 0.508)
		(drill 0.254)
		(layers "F.Cu" "B.Cu")
		(net "GND")
	)
	(via
		(at 126.510288 -91.070938)
		(size 0.508)
		(drill 0.254)
		(layers "F.Cu" "B.Cu")
		(net "GND")
	)
	(via
		(at 210.39455 -18.6817)
		(size 0.508)
		(drill 0.254)
		(layers "F.Cu" "B.Cu")
		(net "GND")
	)
	(via
		(at 62.792102 0.457454)
		(size 0.508)
		(drill 0.254)
		(layers "F.Cu" "B.Cu")
		(net "GND")
	)
	(via
		(at 72.328786 -50.63744)
		(size 0.508)
		(drill 0.254)
		(layers "F.Cu" "B.Cu")
		(net "GND")
	)
	(via
		(at 216.799922 -146.011646)
		(size 0.508)
		(drill 0.254)
		(layers "F.Cu" "B.Cu")
		(net "GND")
	)
	(via
		(at 244.197124 -95.21444)
		(size 0.508)
		(drill 0.254)
		(layers "F.Cu" "B.Cu")
		(net "GND")
	)
	(via
		(at 288.19983 -150.219156)
		(size 0.508)
		(drill 0.254)
		(layers "F.Cu" "B.Cu")
		(net "GND")
	)
	(via
		(at 347.7514 -67.437)
		(size 0.508)
		(drill 0.254)
		(layers "F.Cu" "B.Cu")
		(net "GND")
	)
	(via
		(at 341.394542 -129.098802)
		(size 0.508)
		(drill 0.254)
		(layers "F.Cu" "B.Cu")
		(net "GND")
	)
	(via
		(at 255.830578 -135.670798)
		(size 0.508)
		(drill 0.254)
		(layers "F.Cu" "B.Cu")
		(net "GND")
	)
	(via
		(at 415.320734 -167.832024)
		(size 0.5588)
		(drill 0.3048)
		(layers "F.Cu" "B.Cu")
		(net "GND")
	)
	(via
		(at 435.490112 -48.308006)
		(size 0.508)
		(drill 0.254)
		(layers "F.Cu" "B.Cu")
		(net "GND")
	)
	(via
		(at 207.642714 -69.661278)
		(size 0.5588)
		(drill 0.3048)
		(layers "F.Cu" "B.Cu")
		(net "GND")
	)
	(via
		(at 5.5118 -135.2042)
		(size 0.508)
		(drill 0.254)
		(layers "F.Cu" "B.Cu")
		(net "GND")
	)
	(via
		(at 13.335 -38.608)
		(size 0.508)
		(drill 0.254)
		(layers "F.Cu" "B.Cu")
		(net "GND")
	)
	(via
		(at 82.412332 -101.577394)
		(size 0.508)
		(drill 0.254)
		(layers "F.Cu" "B.Cu")
		(net "GND")
	)
	(via
		(at 128.227328 -93.052138)
		(size 0.508)
		(drill 0.254)
		(layers "F.Cu" "B.Cu")
		(net "GND")
	)
	(via
		(at 340.493604 -143.087598)
		(size 0.508)
		(drill 0.254)
		(layers "F.Cu" "B.Cu")
		(net "GND")
	)
	(via
		(at 67.949318 -22.965156)
		(size 0.508)
		(drill 0.254)
		(layers "F.Cu" "B.Cu")
		(net "GND")
	)
	(via
		(at 243.338604 -62.029086)
		(size 0.508)
		(drill 0.254)
		(layers "F.Cu" "B.Cu")
		(net "GND")
	)
	(via
		(at 352.11131 -77.29474)
		(size 0.508)
		(drill 0.254)
		(layers "F.Cu" "B.Cu")
		(net "GND")
	)
	(via
		(at 86.923372 -82.83194)
		(size 0.508)
		(drill 0.254)
		(layers "F.Cu" "B.Cu")
		(net "GND")
	)
	(via
		(at 142.898114 -64.819784)
		(size 0.508)
		(drill 0.254)
		(layers "F.Cu" "B.Cu")
		(net "GND")
	)
	(via
		(at 294.999918 -9.156446)
		(size 0.508)
		(drill 0.254)
		(layers "F.Cu" "B.Cu")
		(net "GND")
	)
	(via
		(at 90.357198 -85.803486)
		(size 0.508)
		(drill 0.254)
		(layers "F.Cu" "B.Cu")
		(net "GND")
	)
	(via
		(at 213.399878 -155.612846)
		(size 0.508)
		(drill 0.254)
		(layers "F.Cu" "B.Cu")
		(net "GND")
	)
	(via
		(at 284.358334 -68.782184)
		(size 0.508)
		(drill 0.254)
		(layers "F.Cu" "B.Cu")
		(net "GND")
	)
	(via
		(at 141.104874 -98.500438)
		(size 0.508)
		(drill 0.254)
		(layers "F.Cu" "B.Cu")
		(net "GND")
	)
	(via
		(at 73.187306 -91.747086)
		(size 0.508)
		(drill 0.254)
		(layers "F.Cu" "B.Cu")
		(net "GND")
	)
	(via
		(at 206.194914 -85.688678)
		(size 0.5588)
		(drill 0.3048)
		(layers "F.Cu" "B.Cu")
		(net "GND")
	)
	(via
		(at 398.63395 -104.473756)
		(size 0.508)
		(drill 0.254)
		(layers "F.Cu" "B.Cu")
		(net "GND")
	)
	(via
		(at 275.111464 -12.954)
		(size 0.508)
		(drill 0.254)
		(layers "F.Cu" "B.Cu")
		(net "GND")
	)
	(via
		(at 420.7764 -1.6002)
		(size 0.508)
		(drill 0.254)
		(layers "F.Cu" "B.Cu")
		(net "GND")
	)
	(via
		(at 130.802888 -81.659984)
		(size 0.508)
		(drill 0.254)
		(layers "F.Cu" "B.Cu")
		(net "GND")
	)
	(via
		(at 196.399912 -11.916156)
		(size 0.508)
		(drill 0.254)
		(layers "F.Cu" "B.Cu")
		(net "GND")
	)
	(via
		(at 199.742552 -18.744946)
		(size 0.508)
		(drill 0.254)
		(layers "F.Cu" "B.Cu")
		(net "GND")
	)
	(via
		(at 178.943 -130.2639)
		(size 0.508)
		(drill 0.254)
		(layers "F.Cu" "B.Cu")
		(net "GND")
	)
	(via
		(at 132.821934 14.926056)
		(size 0.5588)
		(drill 0.3048)
		(layers "F.Cu" "B.Cu")
		(net "GND")
	)
	(via
		(at 114.491262 -89.089738)
		(size 0.508)
		(drill 0.254)
		(layers "F.Cu" "B.Cu")
		(net "GND")
	)
	(via
		(at 394.17625 -117.811804)
		(size 0.508)
		(drill 0.254)
		(layers "F.Cu" "B.Cu")
		(net "GND")
	)
	(via
		(at 352.054414 -125.405642)
		(size 0.508)
		(drill 0.254)
		(layers "F.Cu" "B.Cu")
		(net "GND")
	)
	(via
		(at 70.499478 0.444754)
		(size 0.508)
		(drill 0.254)
		(layers "F.Cu" "B.Cu")
		(net "GND")
	)
	(via
		(at 346.558362 -104.265984)
		(size 0.508)
		(drill 0.254)
		(layers "F.Cu" "B.Cu")
		(net "GND")
	)
	(via
		(at 440.604402 -118.61927)
		(size 0.508)
		(drill 0.254)
		(layers "F.Cu" "B.Cu")
		(net "GND")
	)
	(via
		(at 67.959986 -91.747086)
		(size 0.508)
		(drill 0.254)
		(layers "F.Cu" "B.Cu")
		(net "GND")
	)
	(via
		(at 298.502324 -162.243262)
		(size 0.5588)
		(drill 0.3048)
		(layers "F.Cu" "B.Cu")
		(net "GND")
	)
	(via
		(at 465.7344 -37.0586)
		(size 0.5588)
		(drill 0.3048)
		(layers "F.Cu" "B.Cu")
		(net "GND")
	)
	(via
		(at 484.505 -110.6424)
		(size 0.508)
		(drill 0.254)
		(layers "F.Cu" "B.Cu")
		(net "GND")
	)
	(via
		(at 390.5377 -114.6556)
		(size 0.508)
		(drill 0.254)
		(layers "F.Cu" "B.Cu")
		(net "GND")
	)
	(via
		(at 239.904778 -69.953886)
		(size 0.508)
		(drill 0.254)
		(layers "F.Cu" "B.Cu")
		(net "GND")
	)
	(via
		(at 288.07664 -68.287138)
		(size 0.508)
		(drill 0.254)
		(layers "F.Cu" "B.Cu")
		(net "GND")
	)
	(via
		(at 193.74104 -86.233)
		(size 0.508)
		(drill 0.254)
		(layers "F.Cu" "B.Cu")
		(net "GND")
	)
	(via
		(at 109.340396 -90.080338)
		(size 0.508)
		(drill 0.254)
		(layers "F.Cu" "B.Cu")
		(net "GND")
	)
	(via
		(at 226.822 1.9558)
		(size 0.508)
		(drill 0.254)
		(layers "F.Cu" "B.Cu")
		(net "GND")
	)
	(via
		(at 148.699474 -11.916156)
		(size 0.508)
		(drill 0.254)
		(layers "F.Cu" "B.Cu")
		(net "GND")
	)
	(via
		(at 72.328786 -99.17684)
		(size 0.508)
		(drill 0.254)
		(layers "F.Cu" "B.Cu")
		(net "GND")
	)
	(via
		(at 240.599722 -154.063446)
		(size 0.508)
		(drill 0.254)
		(layers "F.Cu" "B.Cu")
		(net "GND")
	)
	(via
		(at 310.122062 1.9558)
		(size 0.508)
		(drill 0.254)
		(layers "F.Cu" "B.Cu")
		(net "GND")
	)
	(via
		(at 383.955036 -30.78353)
		(size 0.508)
		(drill 0.254)
		(layers "F.Cu" "B.Cu")
		(net "GND")
	)
	(via
		(at 395.16685 -100.181156)
		(size 0.508)
		(drill 0.254)
		(layers "F.Cu" "B.Cu")
		(net "GND")
	)
	(via
		(at 253.640844 -84.812886)
		(size 0.508)
		(drill 0.254)
		(layers "F.Cu" "B.Cu")
		(net "GND")
	)
	(via
		(at 224.449894 0.457454)
		(size 0.508)
		(drill 0.254)
		(layers "F.Cu" "B.Cu")
		(net "GND")
	)
	(via
		(at 186.6646 -135.0772)
		(size 0.508)
		(drill 0.254)
		(layers "F.Cu" "B.Cu")
		(net "GND")
	)
	(via
		(at 7.930134 -163.361624)
		(size 0.5588)
		(drill 0.3048)
		(layers "F.Cu" "B.Cu")
		(net "GND")
	)
	(via
		(at 311.0992 -134.4041)
		(size 0.508)
		(drill 0.254)
		(layers "F.Cu" "B.Cu")
		(net "GND")
	)
	(via
		(at 461.751934 12.894056)
		(size 0.5588)
		(drill 0.3048)
		(layers "F.Cu" "B.Cu")
		(net "GND")
	)
	(via
		(at 47.549308 -154.063446)
		(size 0.508)
		(drill 0.254)
		(layers "F.Cu" "B.Cu")
		(net "GND")
	)
	(via
		(at 201.037952 -131.600956)
		(size 0.508)
		(drill 0.254)
		(layers "F.Cu" "B.Cu")
		(net "GND")
	)
	(via
		(at 127.38608 -23.495)
		(size 0.508)
		(drill 0.254)
		(layers "F.Cu" "B.Cu")
		(net "GND")
	)
	(via
		(at 214.249762 -17.208246)
		(size 0.508)
		(drill 0.254)
		(layers "F.Cu" "B.Cu")
		(net "GND")
	)
	(via
		(at 119.642382 -91.070938)
		(size 0.508)
		(drill 0.254)
		(layers "F.Cu" "B.Cu")
		(net "GND")
	)
	(via
		(at 384.0226 -73.025)
		(size 0.508)
		(drill 0.254)
		(layers "F.Cu" "B.Cu")
		(net "GND")
	)
	(via
		(at 459.204314 -15.79372)
		(size 0.5588)
		(drill 0.3048)
		(layers "F.Cu" "B.Cu")
		(net "GND")
	)
	(via
		(at 176.367694 -56.087518)
		(size 0.508)
		(drill 0.254)
		(layers "F.Cu" "B.Cu")
		(net "GND")
	)
	(via
		(at 109.955076 -75.159616)
		(size 0.5588)
		(drill 0.3048)
		(layers "F.Cu" "B.Cu")
		(net "GND")
	)
	(via
		(at 466.120734 -166.714424)
		(size 0.5588)
		(drill 0.3048)
		(layers "F.Cu" "B.Cu")
		(net "GND")
	)
	(via
		(at 208.122012 -22.952456)
		(size 0.508)
		(drill 0.254)
		(layers "F.Cu" "B.Cu")
		(net "GND")
	)
	(via
		(at 342.9254 -112.395)
		(size 0.508)
		(drill 0.254)
		(layers "F.Cu" "B.Cu")
		(net "GND")
	)
	(via
		(at 170.8658 -78.1558)
		(size 0.508)
		(drill 0.254)
		(layers "F.Cu" "B.Cu")
		(net "GND")
	)
	(via
		(at 401.350734 -165.596824)
		(size 0.5588)
		(drill 0.3048)
		(layers "F.Cu" "B.Cu")
		(net "GND")
	)
	(via
		(at 77.479906 -58.561986)
		(size 0.508)
		(drill 0.254)
		(layers "F.Cu" "B.Cu")
		(net "GND")
	)
	(via
		(at 165.4302 -4.445)
		(size 0.508)
		(drill 0.254)
		(layers "F.Cu" "B.Cu")
		(net "GND")
	)
	(via
		(at 306.049934 -136.410446)
		(size 0.508)
		(drill 0.254)
		(layers "F.Cu" "B.Cu")
		(net "GND")
	)
	(via
		(at 226.822 -17.2466)
		(size 0.508)
		(drill 0.254)
		(layers "F.Cu" "B.Cu")
		(net "GND")
	)
	(via
		(at 78.2574 -140.208)
		(size 0.508)
		(drill 0.254)
		(layers "F.Cu" "B.Cu")
		(net "GND")
	)
	(via
		(at 43.865038 -103.427784)
		(size 0.508)
		(drill 0.254)
		(layers "F.Cu" "B.Cu")
		(net "GND")
	)
	(via
		(at 175.055022 -145.667222)
		(size 0.508)
		(drill 0.254)
		(layers "F.Cu" "B.Cu")
		(net "GND")
	)
	(via
		(at 248.489724 -95.709486)
		(size 0.508)
		(drill 0.254)
		(layers "F.Cu" "B.Cu")
		(net "GND")
	)
	(via
		(at 239.046258 -68.46824)
		(size 0.508)
		(drill 0.254)
		(layers "F.Cu" "B.Cu")
		(net "GND")
	)
	(via
		(at 396.981934 14.926056)
		(size 0.5588)
		(drill 0.3048)
		(layers "F.Cu" "B.Cu")
		(net "GND")
	)
	(via
		(at 236.470698 -59.057286)
		(size 0.508)
		(drill 0.254)
		(layers "F.Cu" "B.Cu")
		(net "GND")
	)
	(via
		(at 64.081406 -2.3114)
		(size 0.508)
		(drill 0.254)
		(layers "F.Cu" "B.Cu")
		(net "GND")
	)
	(via
		(at 298.378626 -80.174338)
		(size 0.508)
		(drill 0.254)
		(layers "F.Cu" "B.Cu")
		(net "GND")
	)
	(via
		(at 337.21675 -70.096634)
		(size 0.508)
		(drill 0.254)
		(layers "F.Cu" "B.Cu")
		(net "GND")
	)
	(via
		(at 78.338172 -58.06694)
		(size 0.508)
		(drill 0.254)
		(layers "F.Cu" "B.Cu")
		(net "GND")
	)
	(via
		(at 79.481172 -52.12334)
		(size 0.508)
		(drill 0.254)
		(layers "F.Cu" "B.Cu")
		(net "GND")
	)
	(via
		(at 462.368646 -53.234844)
		(size 0.508)
		(drill 0.254)
		(layers "F.Cu" "B.Cu")
		(net "GND")
	)
	(via
		(at 285.501334 -92.556584)
		(size 0.508)
		(drill 0.254)
		(layers "F.Cu" "B.Cu")
		(net "GND")
	)
	(via
		(at 353.801934 14.926056)
		(size 0.5588)
		(drill 0.3048)
		(layers "F.Cu" "B.Cu")
		(net "GND")
	)
	(via
		(at 292.392608 -148.767292)
		(size 0.508)
		(drill 0.254)
		(layers "F.Cu" "B.Cu")
		(net "GND")
	)
	(via
		(at 455.927968 -15.580868)
		(size 0.5588)
		(drill 0.3048)
		(layers "F.Cu" "B.Cu")
		(net "GND")
	)
	(via
		(at 234.753658 -65.000886)
		(size 0.508)
		(drill 0.254)
		(layers "F.Cu" "B.Cu")
		(net "GND")
	)
	(via
		(at 46.699424 -11.916156)
		(size 0.508)
		(drill 0.254)
		(layers "F.Cu" "B.Cu")
		(net "GND")
	)
	(via
		(at 184.778396 -93.335602)
		(size 0.508)
		(drill 0.254)
		(layers "F.Cu" "B.Cu")
		(net "GND")
	)
	(via
		(at 179.2859 -105.941622)
		(size 0.508)
		(drill 0.254)
		(layers "F.Cu" "B.Cu")
		(net "GND")
	)
	(via
		(at 472.470734 -165.596824)
		(size 0.5588)
		(drill 0.3048)
		(layers "F.Cu" "B.Cu")
		(net "GND")
	)
	(via
		(at 433.811934 13.910056)
		(size 0.5588)
		(drill 0.3048)
		(layers "F.Cu" "B.Cu")
		(net "GND")
	)
	(via
		(at 79.196692 -60.54344)
		(size 0.508)
		(drill 0.254)
		(layers "F.Cu" "B.Cu")
		(net "GND")
	)
	(via
		(at 428.625 -9.398)
		(size 0.508)
		(drill 0.254)
		(layers "F.Cu" "B.Cu")
		(net "GND")
	)
	(via
		(at 210.38185 -148.7678)
		(size 0.508)
		(drill 0.254)
		(layers "F.Cu" "B.Cu")
		(net "GND")
	)
	(via
		(at 52.811934 9.084056)
		(size 0.5588)
		(drill 0.3048)
		(layers "F.Cu" "B.Cu")
		(net "GND")
	)
	(via
		(at 303.038002 -124.690886)
		(size 0.508)
		(drill 0.254)
		(layers "F.Cu" "B.Cu")
		(net "GND")
	)
	(via
		(at 113.94694 -21.665184)
		(size 0.508)
		(drill 0.254)
		(layers "F.Cu" "B.Cu")
		(net "GND")
	)
	(via
		(at 345.27744 -101.29774)
		(size 0.508)
		(drill 0.254)
		(layers "F.Cu" "B.Cu")
		(net "GND")
	)
	(via
		(at 289.810952 -130.991356)
		(size 0.508)
		(drill 0.254)
		(layers "F.Cu" "B.Cu")
		(net "GND")
	)
	(via
		(at 126.510288 -98.005138)
		(size 0.508)
		(drill 0.254)
		(layers "F.Cu" "B.Cu")
		(net "GND")
	)
	(via
		(at 49.001934 9.084056)
		(size 0.5588)
		(drill 0.3048)
		(layers "F.Cu" "B.Cu")
		(net "GND")
	)
	(via
		(at 251.065284 -88.28024)
		(size 0.508)
		(drill 0.254)
		(layers "F.Cu" "B.Cu")
		(net "GND")
	)
	(via
		(at 493.501934 11.624056)
		(size 0.5588)
		(drill 0.3048)
		(layers "F.Cu" "B.Cu")
		(net "GND")
	)
	(via
		(at 197.591934 9.084056)
		(size 0.5588)
		(drill 0.3048)
		(layers "F.Cu" "B.Cu")
		(net "GND")
	)
	(via
		(at 36.040822 -134.349744)
		(size 0.508)
		(drill 0.254)
		(layers "F.Cu" "B.Cu")
		(net "GND")
	)
	(via
		(at 196.893434 -63.656464)
		(size 0.508)
		(drill 0.254)
		(layers "F.Cu" "B.Cu")
		(net "GND")
	)
	(via
		(at 65.399412 -18.757646)
		(size 0.508)
		(drill 0.254)
		(layers "F.Cu" "B.Cu")
		(net "GND")
	)
	(via
		(at 186.487054 -8.51154)
		(size 0.508)
		(drill 0.254)
		(layers "F.Cu" "B.Cu")
		(net "GND")
	)
	(via
		(at 491.0074 -110.7948)
		(size 0.508)
		(drill 0.254)
		(layers "F.Cu" "B.Cu")
		(net "GND")
	)
	(via
		(at 246.772684 -96.700086)
		(size 0.508)
		(drill 0.254)
		(layers "F.Cu" "B.Cu")
		(net "GND")
	)
	(via
		(at 386.985002 -23.76551)
		(size 0.508)
		(drill 0.254)
		(layers "F.Cu" "B.Cu")
		(net "GND")
	)
	(via
		(at -5.2578 -12.3952)
		(size 0.508)
		(drill 0.254)
		(layers "F.Cu" "B.Cu")
		(net "GND")
	)
	(via
		(at 469.0872 -24.2316)
		(size 0.508)
		(drill 0.254)
		(layers "F.Cu" "B.Cu")
		(net "GND")
	)
	(via
		(at 184.891934 9.084056)
		(size 0.5588)
		(drill 0.3048)
		(layers "F.Cu" "B.Cu")
		(net "GND")
	)
	(via
		(at 133.378194 -60.362338)
		(size 0.508)
		(drill 0.254)
		(layers "F.Cu" "B.Cu")
		(net "GND")
	)
	(via
		(at 156.951934 9.084056)
		(size 0.5588)
		(drill 0.3048)
		(layers "F.Cu" "B.Cu")
		(net "GND")
	)
	(via
		(at 457.5048 -134.5692)
		(size 0.508)
		(drill 0.254)
		(layers "F.Cu" "B.Cu")
		(net "GND")
	)
	(via
		(at 280.451814 -134.861046)
		(size 0.508)
		(drill 0.254)
		(layers "F.Cu" "B.Cu")
		(net "GND")
	)
	(via
		(at 279.699974 -148.771356)
		(size 0.508)
		(drill 0.254)
		(layers "F.Cu" "B.Cu")
		(net "GND")
	)
	(via
		(at 222.749872 -21.517356)
		(size 0.508)
		(drill 0.254)
		(layers "F.Cu" "B.Cu")
		(net "GND")
	)
	(via
		(at 330.941934 9.084056)
		(size 0.5588)
		(drill 0.3048)
		(layers "F.Cu" "B.Cu")
		(net "GND")
	)
	(via
		(at 199.992234 -87.176864)
		(size 0.508)
		(drill 0.254)
		(layers "F.Cu" "B.Cu")
		(net "GND")
	)
	(via
		(at 35.5092 -60.198)
		(size 0.5588)
		(drill 0.3048)
		(layers "F.Cu" "B.Cu")
		(net "GND")
	)
	(via
		(at 44.092114 -2.310892)
		(size 0.508)
		(drill 0.254)
		(layers "F.Cu" "B.Cu")
		(net "GND")
	)
	(via
		(at 239.046258 -54.59984)
		(size 0.508)
		(drill 0.254)
		(layers "F.Cu" "B.Cu")
		(net "GND")
	)
	(via
		(at 386.5372 -112.2553)
		(size 0.508)
		(drill 0.254)
		(layers "F.Cu" "B.Cu")
		(net "GND")
	)
	(via
		(at 169.651934 9.084056)
		(size 0.5588)
		(drill 0.3048)
		(layers "F.Cu" "B.Cu")
		(net "GND")
	)
	(via
		(at 344.881962 -5.6388)
		(size 0.508)
		(drill 0.254)
		(layers "F.Cu" "B.Cu")
		(net "GND")
	)
	(via
		(at 317.949834 -4.317746)
		(size 0.508)
		(drill 0.254)
		(layers "F.Cu" "B.Cu")
		(net "GND")
	)
	(via
		(at 239.046258 -58.561986)
		(size 0.508)
		(drill 0.254)
		(layers "F.Cu" "B.Cu")
		(net "GND")
	)
	(via
		(at 318.619124 -162.243262)
		(size 0.5588)
		(drill 0.3048)
		(layers "F.Cu" "B.Cu")
		(net "GND")
	)
	(via
		(at 312.400188 0.508)
		(size 0.508)
		(drill 0.254)
		(layers "F.Cu" "B.Cu")
		(net "GND")
	)
	(via
		(at 289.79368 -86.117938)
		(size 0.508)
		(drill 0.254)
		(layers "F.Cu" "B.Cu")
		(net "GND")
	)
	(via
		(at 309.449978 -155.612846)
		(size 0.508)
		(drill 0.254)
		(layers "F.Cu" "B.Cu")
		(net "GND")
	)
	(via
		(at 143.501364 -154.063446)
		(size 0.508)
		(drill 0.254)
		(layers "F.Cu" "B.Cu")
		(net "GND")
	)
	(via
		(at 30.549342 -4.277106)
		(size 0.508)
		(drill 0.254)
		(layers "F.Cu" "B.Cu")
		(net "GND")
	)
	(via
		(at 300.095666 -78.193138)
		(size 0.508)
		(drill 0.254)
		(layers "F.Cu" "B.Cu")
		(net "GND")
	)
	(via
		(at 18.521934 9.084056)
		(size 0.5588)
		(drill 0.3048)
		(layers "F.Cu" "B.Cu")
		(net "GND")
	)
	(via
		(at 352.531934 14.926056)
		(size 0.5588)
		(drill 0.3048)
		(layers "F.Cu" "B.Cu")
		(net "GND")
	)
	(via
		(at 88.640412 -66.982086)
		(size 0.508)
		(drill 0.254)
		(layers "F.Cu" "B.Cu")
		(net "GND")
	)
	(via
		(at 398.13865 -116.094764)
		(size 0.508)
		(drill 0.254)
		(layers "F.Cu" "B.Cu")
		(net "GND")
	)
	(via
		(at 70.461378 -26.488136)
		(size 0.508)
		(drill 0.254)
		(layers "F.Cu" "B.Cu")
		(net "GND")
	)
	(via
		(at 434.813202 -3.372104)
		(size 0.508)
		(drill 0.254)
		(layers "F.Cu" "B.Cu")
		(net "GND")
	)
	(via
		(at 247.631204 -95.21444)
		(size 0.508)
		(drill 0.254)
		(layers "F.Cu" "B.Cu")
		(net "GND")
	)
	(via
		(at 338.588604 -143.087598)
		(size 0.508)
		(drill 0.254)
		(layers "F.Cu" "B.Cu")
		(net "GND")
	)
	(via
		(at 13.441934 14.926056)
		(size 0.5588)
		(drill 0.3048)
		(layers "F.Cu" "B.Cu")
		(net "GND")
	)
	(via
		(at 225.201734 -17.208246)
		(size 0.508)
		(drill 0.254)
		(layers "F.Cu" "B.Cu")
		(net "GND")
	)
	(via
		(at 7.0612 -21.3106)
		(size 0.508)
		(drill 0.254)
		(layers "F.Cu" "B.Cu")
		(net "GND")
	)
	(via
		(at 135.771636 -124.661676)
		(size 0.508)
		(drill 0.254)
		(layers "F.Cu" "B.Cu")
		(net "GND")
	)
	(via
		(at 351.670874 -97.271078)
		(size 0.508)
		(drill 0.254)
		(layers "F.Cu" "B.Cu")
		(net "GND")
	)
	(via
		(at 383.6543 -151.7142)
		(size 0.508)
		(drill 0.254)
		(layers "F.Cu" "B.Cu")
		(net "GND")
	)
	(via
		(at 377.83135 -102.756716)
		(size 0.508)
		(drill 0.254)
		(layers "F.Cu" "B.Cu")
		(net "GND")
	)
	(via
		(at 85.206332 -96.700086)
		(size 0.508)
		(drill 0.254)
		(layers "F.Cu" "B.Cu")
		(net "GND")
	)
	(via
		(at 313.161934 9.084056)
		(size 0.5588)
		(drill 0.3048)
		(layers "F.Cu" "B.Cu")
		(net "GND")
	)
	(via
		(at 79.452724 -162.243262)
		(size 0.5588)
		(drill 0.3048)
		(layers "F.Cu" "B.Cu")
		(net "GND")
	)
	(via
		(at 64.081406 -11.9126)
		(size 0.508)
		(drill 0.254)
		(layers "F.Cu" "B.Cu")
		(net "GND")
	)
	(via
		(at 390.631934 14.926056)
		(size 0.5588)
		(drill 0.3048)
		(layers "F.Cu" "B.Cu")
		(net "GND")
	)
	(via
		(at 478.820734 -165.596824)
		(size 0.5588)
		(drill 0.3048)
		(layers "F.Cu" "B.Cu")
		(net "GND")
	)
	(via
		(at 129.744724 -162.243262)
		(size 0.5588)
		(drill 0.3048)
		(layers "F.Cu" "B.Cu")
		(net "GND")
	)
	(via
		(at 71.171562 -27.821636)
		(size 0.508)
		(drill 0.254)
		(layers "F.Cu" "B.Cu")
		(net "GND")
	)
	(via
		(at 424.210734 -166.714424)
		(size 0.5588)
		(drill 0.3048)
		(layers "F.Cu" "B.Cu")
		(net "GND")
	)
	(via
		(at 232.94975 -7.607046)
		(size 0.508)
		(drill 0.254)
		(layers "F.Cu" "B.Cu")
		(net "GND")
	)
	(via
		(at 109.914182 -54.418738)
		(size 0.508)
		(drill 0.254)
		(layers "F.Cu" "B.Cu")
		(net "GND")
	)
	(via
		(at 315.270134 -167.832024)
		(size 0.5588)
		(drill 0.3048)
		(layers "F.Cu" "B.Cu")
		(net "GND")
	)
	(via
		(at 262.153908 -70.841616)
		(size 0.5588)
		(drill 0.3048)
		(layers "F.Cu" "B.Cu")
		(net "GND")
	)
	(via
		(at 420.400734 -166.714424)
		(size 0.5588)
		(drill 0.3048)
		(layers "F.Cu" "B.Cu")
		(net "GND")
	)
	(via
		(at 306.963826 -67.296538)
		(size 0.508)
		(drill 0.254)
		(layers "F.Cu" "B.Cu")
		(net "GND")
	)
	(via
		(at 13.441934 9.084056)
		(size 0.5588)
		(drill 0.3048)
		(layers "F.Cu" "B.Cu")
		(net "GND")
	)
	(via
		(at 461.18018 -53.270912)
		(size 0.508)
		(drill 0.254)
		(layers "F.Cu" "B.Cu")
		(net "GND")
	)
	(via
		(at 380.415546 -28.48356)
		(size 0.508)
		(drill 0.254)
		(layers "F.Cu" "B.Cu")
		(net "GND")
	)
	(via
		(at 477.770444 -13.537946)
		(size 0.508)
		(drill 0.254)
		(layers "F.Cu" "B.Cu")
		(net "GND")
	)
	(via
		(at 405.871934 14.926056)
		(size 0.5588)
		(drill 0.3048)
		(layers "F.Cu" "B.Cu")
		(net "GND")
	)
	(via
		(at 134.218934 -167.832024)
		(size 0.5588)
		(drill 0.3048)
		(layers "F.Cu" "B.Cu")
		(net "GND")
	)
	(via
		(at 182.351934 9.084056)
		(size 0.5588)
		(drill 0.3048)
		(layers "F.Cu" "B.Cu")
		(net "GND")
	)
	(via
		(at 77.286612 -140.617956)
		(size 0.508)
		(drill 0.254)
		(layers "F.Cu" "B.Cu")
		(net "GND")
	)
	(via
		(at 291.51072 -56.399938)
		(size 0.508)
		(drill 0.254)
		(layers "F.Cu" "B.Cu")
		(net "GND")
	)
	(via
		(at 375.283222 -145.36801)
		(size 0.508)
		(drill 0.254)
		(layers "F.Cu" "B.Cu")
		(net "GND")
	)
	(via
		(at 78.338172 -97.690686)
		(size 0.508)
		(drill 0.254)
		(layers "F.Cu" "B.Cu")
		(net "GND")
	)
	(via
		(at 492.231934 13.910056)
		(size 0.5588)
		(drill 0.3048)
		(layers "F.Cu" "B.Cu")
		(net "GND")
	)
	(via
		(at 283.784294 -86.612984)
		(size 0.508)
		(drill 0.254)
		(layers "F.Cu" "B.Cu")
		(net "GND")
	)
	(via
		(at 71.470266 -90.756486)
		(size 0.508)
		(drill 0.254)
		(layers "F.Cu" "B.Cu")
		(net "GND")
	)
	(via
		(at 406.66924 -101.85654)
		(size 0.508)
		(drill 0.254)
		(layers "F.Cu" "B.Cu")
		(net "GND")
	)
	(via
		(at 368.6556 -115.3414)
		(size 0.508)
		(drill 0.254)
		(layers "F.Cu" "B.Cu")
		(net "GND")
	)
	(via
		(at 132.549392 -134.861046)
		(size 0.508)
		(drill 0.254)
		(layers "F.Cu" "B.Cu")
		(net "GND")
	)
	(via
		(at 138.685524 -162.243262)
		(size 0.5588)
		(drill 0.3048)
		(layers "F.Cu" "B.Cu")
		(net "GND")
	)
	(via
		(at 113.944146 -18.691606)
		(size 0.508)
		(drill 0.254)
		(layers "F.Cu" "B.Cu")
		(net "GND")
	)
	(via
		(at 78.338172 -89.765886)
		(size 0.508)
		(drill 0.254)
		(layers "F.Cu" "B.Cu")
		(net "GND")
	)
	(via
		(at 33.061402 -11.916156)
		(size 0.508)
		(drill 0.254)
		(layers "F.Cu" "B.Cu")
		(net "GND")
	)
	(via
		(at 313.161934 14.926056)
		(size 0.5588)
		(drill 0.3048)
		(layers "F.Cu" "B.Cu")
		(net "GND")
	)
	(via
		(at 433.86756 -139.074652)
		(size 0.508)
		(drill 0.254)
		(layers "F.Cu" "B.Cu")
		(net "GND")
	)
	(via
		(at 294.9448 -81.164938)
		(size 0.508)
		(drill 0.254)
		(layers "F.Cu" "B.Cu")
		(net "GND")
	)
	(via
		(at 346.6338 -21.9837)
		(size 0.508)
		(drill 0.254)
		(layers "F.Cu" "B.Cu")
		(net "GND")
	)
	(via
		(at 266.518136 -63.51524)
		(size 0.508)
		(drill 0.254)
		(layers "F.Cu" "B.Cu")
		(net "GND")
	)
	(via
		(at 133.378194 -52.437538)
		(size 0.508)
		(drill 0.254)
		(layers "F.Cu" "B.Cu")
		(net "GND")
	)
	(via
		(at 454.025 -151.838914)
		(size 0.508)
		(drill 0.254)
		(layers "F.Cu" "B.Cu")
		(net "GND")
	)
	(via
		(at 29.810202 -106.023664)
		(size 0.508)
		(drill 0.254)
		(layers "F.Cu" "B.Cu")
		(net "GND")
	)
	(via
		(at 460.481934 9.084056)
		(size 0.5588)
		(drill 0.3048)
		(layers "F.Cu" "B.Cu")
		(net "GND")
	)
	(via
		(at 438.478676 -25.85339)
		(size 0.4572)
		(drill 0.2032)
		(layers "F.Cu" "B.Cu")
		(net "GND")
	)
	(via
		(at 348.0308 -87.3506)
		(size 0.508)
		(drill 0.254)
		(layers "F.Cu" "B.Cu")
		(net "GND")
	)
	(via
		(at 272.623788 -95.033084)
		(size 0.508)
		(drill 0.254)
		(layers "F.Cu" "B.Cu")
		(net "GND")
	)
	(via
		(at 82.630772 -69.45884)
		(size 0.508)
		(drill 0.254)
		(layers "F.Cu" "B.Cu")
		(net "GND")
	)
	(via
		(at 454.757282 -63.626492)
		(size 0.508)
		(drill 0.254)
		(layers "F.Cu" "B.Cu")
		(net "GND")
	)
	(via
		(at 245.914164 -89.27084)
		(size 0.508)
		(drill 0.254)
		(layers "F.Cu" "B.Cu")
		(net "GND")
	)
	(via
		(at 273.482308 -91.565984)
		(size 0.508)
		(drill 0.254)
		(layers "F.Cu" "B.Cu")
		(net "GND")
	)
	(via
		(at 233.036618 -98.681286)
		(size 0.508)
		(drill 0.254)
		(layers "F.Cu" "B.Cu")
		(net "GND")
	)
	(via
		(at 124.793248 -100.976684)
		(size 0.508)
		(drill 0.254)
		(layers "F.Cu" "B.Cu")
		(net "GND")
	)
	(via
		(at 68.894706 -97.19564)
		(size 0.508)
		(drill 0.254)
		(layers "F.Cu" "B.Cu")
		(net "GND")
	)
	(via
		(at 180.485288 -62.172342)
		(size 0.508)
		(drill 0.254)
		(layers "F.Cu" "B.Cu")
		(net "GND")
	)
	(via
		(at 72.328786 -92.24264)
		(size 0.508)
		(drill 0.254)
		(layers "F.Cu" "B.Cu")
		(net "GND")
	)
	(via
		(at 23.601934 14.926056)
		(size 0.5588)
		(drill 0.3048)
		(layers "F.Cu" "B.Cu")
		(net "GND")
	)
	(via
		(at 175.7426 -135.8519)
		(size 0.508)
		(drill 0.254)
		(layers "F.Cu" "B.Cu")
		(net "GND")
	)
	(via
		(at 82.630772 -56.58104)
		(size 0.508)
		(drill 0.254)
		(layers "F.Cu" "B.Cu")
		(net "GND")
	)
	(via
		(at 66.249296 -7.607046)
		(size 0.508)
		(drill 0.254)
		(layers "F.Cu" "B.Cu")
		(net "GND")
	)
	(via
		(at 238.444532 -18.6817)
		(size 0.508)
		(drill 0.254)
		(layers "F.Cu" "B.Cu")
		(net "GND")
	)
	(via
		(at 395.711934 9.084056)
		(size 0.5588)
		(drill 0.3048)
		(layers "F.Cu" "B.Cu")
		(net "GND")
	)
	(via
		(at 141.899386 -154.063446)
		(size 0.508)
		(drill 0.254)
		(layers "F.Cu" "B.Cu")
		(net "GND")
	)
	(via
		(at 375.673366 -151.417528)
		(size 0.508)
		(drill 0.254)
		(layers "F.Cu" "B.Cu")
		(net "GND")
	)
	(via
		(at 18.91792 -128.13792)
		(size 0.508)
		(drill 0.254)
		(layers "F.Cu" "B.Cu")
		(net "GND")
	)
	(via
		(at 219.741242 -7.095744)
		(size 0.508)
		(drill 0.254)
		(layers "F.Cu" "B.Cu")
		(net "GND")
	)
	(via
		(at 480.086924 -162.243262)
		(size 0.5588)
		(drill 0.3048)
		(layers "F.Cu" "B.Cu")
		(net "GND")
	)
	(via
		(at 212.54974 -3.762756)
		(size 0.508)
		(drill 0.254)
		(layers "F.Cu" "B.Cu")
		(net "GND")
	)
	(via
		(at 241.44986 -18.757646)
		(size 0.508)
		(drill 0.254)
		(layers "F.Cu" "B.Cu")
		(net "GND")
	)
	(via
		(at 242.2652 -26.67)
		(size 0.508)
		(drill 0.254)
		(layers "F.Cu" "B.Cu")
		(net "GND")
	)
	(via
		(at 500.552466 -19.143726)
		(size 0.508)
		(drill 0.254)
		(layers "F.Cu" "B.Cu")
		(net "GND")
	)
	(via
		(at 47.549308 -17.208246)
		(size 0.508)
		(drill 0.254)
		(layers "F.Cu" "B.Cu")
		(net "GND")
	)
	(via
		(at 227.792534 -9.143746)
		(size 0.508)
		(drill 0.254)
		(layers "F.Cu" "B.Cu")
		(net "GND")
	)
	(via
		(at 49.24933 -7.607046)
		(size 0.508)
		(drill 0.254)
		(layers "F.Cu" "B.Cu")
		(net "GND")
	)
	(via
		(at 60.201302 -17.208246)
		(size 0.508)
		(drill 0.254)
		(layers "F.Cu" "B.Cu")
		(net "GND")
	)
	(via
		(at 78.338172 -87.784686)
		(size 0.508)
		(drill 0.254)
		(layers "F.Cu" "B.Cu")
		(net "GND")
	)
	(via
		(at 84.347812 -63.51524)
		(size 0.508)
		(drill 0.254)
		(layers "F.Cu" "B.Cu")
		(net "GND")
	)
	(via
		(at 112.774222 -101.967538)
		(size 0.508)
		(drill 0.254)
		(layers "F.Cu" "B.Cu")
		(net "GND")
	)
	(via
		(at 451.591934 13.910056)
		(size 0.5588)
		(drill 0.3048)
		(layers "F.Cu" "B.Cu")
		(net "GND")
	)
	(via
		(at 426.750734 -163.361624)
		(size 0.5588)
		(drill 0.3048)
		(layers "F.Cu" "B.Cu")
		(net "GND")
	)
	(via
		(at 77.286612 -150.219156)
		(size 0.508)
		(drill 0.254)
		(layers "F.Cu" "B.Cu")
		(net "GND")
	)
	(via
		(at 204.049884 -139.170156)
		(size 0.508)
		(drill 0.254)
		(layers "F.Cu" "B.Cu")
		(net "GND")
	)
	(via
		(at 136.450324 -162.243262)
		(size 0.5588)
		(drill 0.3048)
		(layers "F.Cu" "B.Cu")
		(net "GND")
	)
	(via
		(at 1.397 -55.499)
		(size 0.5588)
		(drill 0.3048)
		(layers "F.Cu" "B.Cu")
		(net "GND")
	)
	(via
		(at 37.34943 -11.916156)
		(size 0.508)
		(drill 0.254)
		(layers "F.Cu" "B.Cu")
		(net "GND")
	)
	(via
		(at 50.099468 -139.170156)
		(size 0.508)
		(drill 0.254)
		(layers "F.Cu" "B.Cu")
		(net "GND")
	)
	(via
		(at 117.066822 -92.556584)
		(size 0.508)
		(drill 0.254)
		(layers "F.Cu" "B.Cu")
		(net "GND")
	)
	(via
		(at 419.22192 -93.52661)
		(size 0.508)
		(drill 0.254)
		(layers "F.Cu" "B.Cu")
		(net "GND")
	)
	(via
		(at 478.261934 11.624056)
		(size 0.5588)
		(drill 0.3048)
		(layers "F.Cu" "B.Cu")
		(net "GND")
	)
	(via
		(at 216.799922 -155.612846)
		(size 0.508)
		(drill 0.254)
		(layers "F.Cu" "B.Cu")
		(net "GND")
	)
	(via
		(at 292.36924 -86.612984)
		(size 0.508)
		(drill 0.254)
		(layers "F.Cu" "B.Cu")
		(net "GND")
	)
	(via
		(at 467.386924 -162.243262)
		(size 0.5588)
		(drill 0.3048)
		(layers "F.Cu" "B.Cu")
		(net "GND")
	)
	(via
		(at 69.753226 -82.83194)
		(size 0.508)
		(drill 0.254)
		(layers "F.Cu" "B.Cu")
		(net "GND")
	)
	(via
		(at 81.772252 -63.019686)
		(size 0.508)
		(drill 0.254)
		(layers "F.Cu" "B.Cu")
		(net "GND")
	)
	(via
		(at 68.276724 -162.243262)
		(size 0.5588)
		(drill 0.3048)
		(layers "F.Cu" "B.Cu")
		(net "GND")
	)
	(via
		(at 50.851308 1.994154)
		(size 0.508)
		(drill 0.254)
		(layers "F.Cu" "B.Cu")
		(net "GND")
	)
	(via
		(at 358.7115 -16.601186)
		(size 0.508)
		(drill 0.254)
		(layers "F.Cu" "B.Cu")
		(net "GND")
	)
	(via
		(at 374.20677 -95.568516)
		(size 0.508)
		(drill 0.254)
		(layers "F.Cu" "B.Cu")
		(net "GND")
	)
	(via
		(at 206.321914 -68.340478)
		(size 0.5588)
		(drill 0.3048)
		(layers "F.Cu" "B.Cu")
		(net "GND")
	)
	(via
		(at 379.096524 -162.268662)
		(size 0.5588)
		(drill 0.3048)
		(layers "F.Cu" "B.Cu")
		(net "GND")
	)
	(via
		(at 4.8514 -135.2042)
		(size 0.508)
		(drill 0.254)
		(layers "F.Cu" "B.Cu")
		(net "GND")
	)
	(via
		(at 131.551934 9.084056)
		(size 0.5588)
		(drill 0.3048)
		(layers "F.Cu" "B.Cu")
		(net "GND")
	)
	(via
		(at 230.399844 -11.916156)
		(size 0.508)
		(drill 0.254)
		(layers "F.Cu" "B.Cu")
		(net "GND")
	)
	(via
		(at 82.630772 -76.39304)
		(size 0.508)
		(drill 0.254)
		(layers "F.Cu" "B.Cu")
		(net "GND")
	)
	(via
		(at 214.249762 -154.063446)
		(size 0.508)
		(drill 0.254)
		(layers "F.Cu" "B.Cu")
		(net "GND")
	)
	(via
		(at 141.899386 -22.965156)
		(size 0.508)
		(drill 0.254)
		(layers "F.Cu" "B.Cu")
		(net "GND")
	)
	(via
		(at 196.399912 -145.998946)
		(size 0.508)
		(drill 0.254)
		(layers "F.Cu" "B.Cu")
		(net "GND")
	)
	(via
		(at 215.85174 -144.462246)
		(size 0.508)
		(drill 0.254)
		(layers "F.Cu" "B.Cu")
		(net "GND")
	)
	(via
		(at 301.742602 -136.397746)
		(size 0.508)
		(drill 0.254)
		(layers "F.Cu" "B.Cu")
		(net "GND")
	)
	(via
		(at 346.181934 14.926056)
		(size 0.5588)
		(drill 0.3048)
		(layers "F.Cu" "B.Cu")
		(net "GND")
	)
	(via
		(at 141.899386 -140.617956)
		(size 0.508)
		(drill 0.254)
		(layers "F.Cu" "B.Cu")
		(net "GND")
	)
	(via
		(at 387.025134 -167.832024)
		(size 0.5588)
		(drill 0.3048)
		(layers "F.Cu" "B.Cu")
		(net "GND")
	)
	(via
		(at 346.346272 -139.849606)
		(size 0.508)
		(drill 0.254)
		(layers "F.Cu" "B.Cu")
		(net "GND")
	)
	(via
		(at 391.901934 14.926056)
		(size 0.5588)
		(drill 0.3048)
		(layers "F.Cu" "B.Cu")
		(net "GND")
	)
	(via
		(at 292.386512 -131.5466)
		(size 0.508)
		(drill 0.254)
		(layers "F.Cu" "B.Cu")
		(net "GND")
	)
	(via
		(at 249.327924 -162.243262)
		(size 0.5588)
		(drill 0.3048)
		(layers "F.Cu" "B.Cu")
		(net "GND")
	)
	(via
		(at 390.21385 -122.962924)
		(size 0.508)
		(drill 0.254)
		(layers "F.Cu" "B.Cu")
		(net "GND")
	)
	(via
		(at 207.518 -65.4558)
		(size 0.5588)
		(drill 0.3048)
		(layers "F.Cu" "B.Cu")
		(net "GND")
	)
	(via
		(at 189.560962 -61.752988)
		(size 0.508)
		(drill 0.254)
		(layers "F.Cu" "B.Cu")
		(net "GND")
	)
	(via
		(at 303.529746 -88.099138)
		(size 0.508)
		(drill 0.254)
		(layers "F.Cu" "B.Cu")
		(net "GND")
	)
	(via
		(at 348.2848 -102.1334)
		(size 0.508)
		(drill 0.254)
		(layers "F.Cu" "B.Cu")
		(net "GND")
	)
	(via
		(at 245.055644 -56.085486)
		(size 0.508)
		(drill 0.254)
		(layers "F.Cu" "B.Cu")
		(net "GND")
	)
	(via
		(at 67.099434 -155.562046)
		(size 0.508)
		(drill 0.254)
		(layers "F.Cu" "B.Cu")
		(net "GND")
	)
	(via
		(at 233.895138 -69.45884)
		(size 0.508)
		(drill 0.254)
		(layers "F.Cu" "B.Cu")
		(net "GND")
	)
	(via
		(at 172.191934 9.084056)
		(size 0.5588)
		(drill 0.3048)
		(layers "F.Cu" "B.Cu")
		(net "GND")
	)
	(via
		(at 168.3512 -63.1444)
		(size 0.508)
		(drill 0.254)
		(layers "F.Cu" "B.Cu")
		(net "GND")
	)
	(via
		(at 152.099518 -146.011646)
		(size 0.508)
		(drill 0.254)
		(layers "F.Cu" "B.Cu")
		(net "GND")
	)
	(via
		(at 239.046258 -83.32724)
		(size 0.508)
		(drill 0.254)
		(layers "F.Cu" "B.Cu")
		(net "GND")
	)
	(via
		(at 487.151934 9.084056)
		(size 0.5588)
		(drill 0.3048)
		(layers "F.Cu" "B.Cu")
		(net "GND")
	)
	(via
		(at 113.967768 -22.8346)
		(size 0.508)
		(drill 0.254)
		(layers "F.Cu" "B.Cu")
		(net "GND")
	)
	(via
		(at 284.358334 -62.838584)
		(size 0.508)
		(drill 0.254)
		(layers "F.Cu" "B.Cu")
		(net "GND")
	)
	(via
		(at 283.977334 -167.832024)
		(size 0.5588)
		(drill 0.3048)
		(layers "F.Cu" "B.Cu")
		(net "GND")
	)
	(via
		(at 55.351934 14.926056)
		(size 0.5588)
		(drill 0.3048)
		(layers "F.Cu" "B.Cu")
		(net "GND")
	)
	(via
		(at 40.699182 -77.789278)
		(size 0.5588)
		(drill 0.3048)
		(layers "F.Cu" "B.Cu")
		(net "GND")
	)
	(via
		(at 40.009572 -85.189314)
		(size 0.5588)
		(drill 0.3048)
		(layers "F.Cu" "B.Cu")
		(net "GND")
	)
	(via
		(at 388.23265 -119.528844)
		(size 0.508)
		(drill 0.254)
		(layers "F.Cu" "B.Cu")
		(net "GND")
	)
	(via
		(at 395.7574 -24.9428)
		(size 0.508)
		(drill 0.254)
		(layers "F.Cu" "B.Cu")
		(net "GND")
	)
	(via
		(at 36.031424 -11.9126)
		(size 0.508)
		(drill 0.254)
		(layers "F.Cu" "B.Cu")
		(net "GND")
	)
	(via
		(at 64.087502 -23.549356)
		(size 0.508)
		(drill 0.254)
		(layers "F.Cu" "B.Cu")
		(net "GND")
	)
	(via
		(at 477.901 -29.3878)
		(size 0.508)
		(drill 0.254)
		(layers "F.Cu" "B.Cu")
		(net "GND")
	)
	(via
		(at 136.74598 -126.646686)
		(size 0.508)
		(drill 0.254)
		(layers "F.Cu" "B.Cu")
		(net "GND")
	)
	(via
		(at 420.400734 -164.479224)
		(size 0.5588)
		(drill 0.3048)
		(layers "F.Cu" "B.Cu")
		(net "GND")
	)
	(via
		(at 242.299744 -13.363956)
		(size 0.508)
		(drill 0.254)
		(layers "F.Cu" "B.Cu")
		(net "GND")
	)
	(via
		(at 234.753658 -93.72854)
		(size 0.508)
		(drill 0.254)
		(layers "F.Cu" "B.Cu")
		(net "GND")
	)
	(via
		(at 185.5724 -39.365936)
		(size 0.508)
		(drill 0.254)
		(layers "F.Cu" "B.Cu")
		(net "GND")
	)
	(via
		(at 205.749906 -136.397746)
		(size 0.508)
		(drill 0.254)
		(layers "F.Cu" "B.Cu")
		(net "GND")
	)
	(via
		(at 435.081934 12.894056)
		(size 0.5588)
		(drill 0.3048)
		(layers "F.Cu" "B.Cu")
		(net "GND")
	)
	(via
		(at 381.79375 -107.907836)
		(size 0.508)
		(drill 0.254)
		(layers "F.Cu" "B.Cu")
		(net "GND")
	)
	(via
		(at 13.18006 -106.41838)
		(size 0.508)
		(drill 0.254)
		(layers "F.Cu" "B.Cu")
		(net "GND")
	)
	(via
		(at 443.804548 -118.61927)
		(size 0.508)
		(drill 0.254)
		(layers "F.Cu" "B.Cu")
		(net "GND")
	)
	(via
		(at 121.933208 -60.362338)
		(size 0.508)
		(drill 0.254)
		(layers "F.Cu" "B.Cu")
		(net "GND")
	)
	(via
		(at 329.704954 -51.915568)
		(size 0.6604)
		(drill 0.3302)
		(layers "F.Cu" "B.Cu")
		(net "GND")
	)
	(via
		(at 282.925774 -98.005138)
		(size 0.508)
		(drill 0.254)
		(layers "F.Cu" "B.Cu")
		(net "GND")
	)
	(via
		(at 93.495876 -75.159616)
		(size 0.5588)
		(drill 0.3048)
		(layers "F.Cu" "B.Cu")
		(net "GND")
	)
	(via
		(at 69.551296 1.994154)
		(size 0.508)
		(drill 0.254)
		(layers "F.Cu" "B.Cu")
		(net "GND")
	)
	(via
		(at 297.520106 -69.772784)
		(size 0.508)
		(drill 0.254)
		(layers "F.Cu" "B.Cu")
		(net "GND")
	)
	(via
		(at 239.046258 -87.28964)
		(size 0.508)
		(drill 0.254)
		(layers "F.Cu" "B.Cu")
		(net "GND")
	)
	(via
		(at 395.16685 -117.811804)
		(size 0.508)
		(drill 0.254)
		(layers "F.Cu" "B.Cu")
		(net "GND")
	)
	(via
		(at 226.822 -125.245876)
		(size 0.508)
		(drill 0.254)
		(layers "F.Cu" "B.Cu")
		(net "GND")
	)
	(via
		(at 356.42804 -78.898242)
		(size 0.508)
		(drill 0.254)
		(layers "F.Cu" "B.Cu")
		(net "GND")
	)
	(via
		(at 368.6556 -118.237)
		(size 0.508)
		(drill 0.254)
		(layers "F.Cu" "B.Cu")
		(net "GND")
	)
	(via
		(at 44.086018 -131.5466)
		(size 0.508)
		(drill 0.254)
		(layers "F.Cu" "B.Cu")
		(net "GND")
	)
	(via
		(at 221.899734 -150.219156)
		(size 0.508)
		(drill 0.254)
		(layers "F.Cu" "B.Cu")
		(net "GND")
	)
	(via
		(at 305.246786 -59.371484)
		(size 0.508)
		(drill 0.254)
		(layers "F.Cu" "B.Cu")
		(net "GND")
	)
	(via
		(at 422.684702 -139.28852)
		(size 0.508)
		(drill 0.254)
		(layers "F.Cu" "B.Cu")
		(net "GND")
	)
	(via
		(at 205.745334 -167.832024)
		(size 0.5588)
		(drill 0.3048)
		(layers "F.Cu" "B.Cu")
		(net "GND")
	)
	(via
		(at 96.366838 -63.51524)
		(size 0.508)
		(drill 0.254)
		(layers "F.Cu" "B.Cu")
		(net "GND")
	)
	(via
		(at 7.001256 -15.086076)
		(size 0.508)
		(drill 0.254)
		(layers "F.Cu" "B.Cu")
		(net "GND")
	)
	(via
		(at 221.899734 -140.617956)
		(size 0.508)
		(drill 0.254)
		(layers "F.Cu" "B.Cu")
		(net "GND")
	)
	(via
		(at 239.904778 -89.765886)
		(size 0.508)
		(drill 0.254)
		(layers "F.Cu" "B.Cu")
		(net "GND")
	)
	(via
		(at 411.49016 -41.33469)
		(size 0.4572)
		(drill 0.2032)
		(layers "F.Cu" "B.Cu")
		(net "GND")
	)
	(via
		(at 28.7274 -68.367402)
		(size 0.508)
		(drill 0.254)
		(layers "F.Cu" "B.Cu")
		(net "GND")
	)
	(via
		(at 36.03752 -131.600956)
		(size 0.508)
		(drill 0.254)
		(layers "F.Cu" "B.Cu")
		(net "GND")
	)
	(via
		(at 281.399996 -146.011646)
		(size 0.508)
		(drill 0.254)
		(layers "F.Cu" "B.Cu")
		(net "GND")
	)
	(via
		(at 121.359168 -78.194154)
		(size 0.508)
		(drill 0.254)
		(layers "F.Cu" "B.Cu")
		(net "GND")
	)
	(via
		(at 108.888276 -75.159616)
		(size 0.5588)
		(drill 0.3048)
		(layers "F.Cu" "B.Cu")
		(net "GND")
	)
	(via
		(at 44.086018 -4.2926)
		(size 0.508)
		(drill 0.254)
		(layers "F.Cu" "B.Cu")
		(net "GND")
	)
	(via
		(at 395.711934 14.926056)
		(size 0.5588)
		(drill 0.3048)
		(layers "F.Cu" "B.Cu")
		(net "GND")
	)
	(via
		(at 123.199398 -3.762756)
		(size 0.508)
		(drill 0.254)
		(layers "F.Cu" "B.Cu")
		(net "GND")
	)
	(via
		(at 289.79368 -98.995738)
		(size 0.508)
		(drill 0.254)
		(layers "F.Cu" "B.Cu")
		(net "GND")
	)
	(via
		(at 166.116 -88.392)
		(size 0.508)
		(drill 0.254)
		(layers "F.Cu" "B.Cu")
		(net "GND")
	)
	(via
		(at 128.227328 -90.080338)
		(size 0.508)
		(drill 0.254)
		(layers "F.Cu" "B.Cu")
		(net "GND")
	)
	(via
		(at 301.742602 -21.513292)
		(size 0.508)
		(drill 0.254)
		(layers "F.Cu" "B.Cu")
		(net "GND")
	)
	(via
		(at 384.307842 -35.72002)
		(size 0.508)
		(drill 0.254)
		(layers "F.Cu" "B.Cu")
		(net "GND")
	)
	(via
		(at 494.771934 14.926056)
		(size 0.5588)
		(drill 0.3048)
		(layers "F.Cu" "B.Cu")
		(net "GND")
	)
	(via
		(at 463.799936 -113.79962)
		(size 0.508)
		(drill 0.254)
		(layers "F.Cu" "B.Cu")
		(net "GND")
	)
	(via
		(at 439.626756 -144.478756)
		(size 0.508)
		(drill 0.254)
		(layers "F.Cu" "B.Cu")
		(net "GND")
	)
	(via
		(at 245.055644 -79.859886)
		(size 0.508)
		(drill 0.254)
		(layers "F.Cu" "B.Cu")
		(net "GND")
	)
	(via
		(at 37.549582 -92.572078)
		(size 0.5588)
		(drill 0.3048)
		(layers "F.Cu" "B.Cu")
		(net "GND")
	)
	(via
		(at 280.065734 -65.315338)
		(size 0.508)
		(drill 0.254)
		(layers "F.Cu" "B.Cu")
		(net "GND")
	)
	(via
		(at 120.500902 -89.584784)
		(size 0.508)
		(drill 0.254)
		(layers "F.Cu" "B.Cu")
		(net "GND")
	)
	(via
		(at 239.046258 -92.24264)
		(size 0.508)
		(drill 0.254)
		(layers "F.Cu" "B.Cu")
		(net "GND")
	)
	(via
		(at 117.071648 1.9558)
		(size 0.508)
		(drill 0.254)
		(layers "F.Cu" "B.Cu")
		(net "GND")
	)
	(via
		(at 243.338604 -90.756486)
		(size 0.508)
		(drill 0.254)
		(layers "F.Cu" "B.Cu")
		(net "GND")
	)
	(via
		(at 397.56334 -129.32664)
		(size 0.508)
		(drill 0.254)
		(layers "F.Cu" "B.Cu")
		(net "GND")
	)
	(via
		(at 249.9106 -8.1534)
		(size 0.508)
		(drill 0.254)
		(layers "F.Cu" "B.Cu")
		(net "GND")
	)
	(via
		(at 381.79375 -97.605596)
		(size 0.508)
		(drill 0.254)
		(layers "F.Cu" "B.Cu")
		(net "GND")
	)
	(via
		(at 109.914182 -55.409338)
		(size 0.508)
		(drill 0.254)
		(layers "F.Cu" "B.Cu")
		(net "GND")
	)
	(via
		(at 196.1642 -102.49408)
		(size 0.508)
		(drill 0.254)
		(layers "F.Cu" "B.Cu")
		(net "GND")
	)
	(via
		(at 80.913732 -76.39304)
		(size 0.508)
		(drill 0.254)
		(layers "F.Cu" "B.Cu")
		(net "GND")
	)
	(via
		(at 204.049884 -18.757646)
		(size 0.508)
		(drill 0.254)
		(layers "F.Cu" "B.Cu")
		(net "GND")
	)
	(via
		(at 255.627124 -149.444964)
		(size 0.508)
		(drill 0.254)
		(layers "F.Cu" "B.Cu")
		(net "GND")
	)
	(via
		(at 57.74944 -139.170156)
		(size 0.508)
		(drill 0.254)
		(layers "F.Cu" "B.Cu")
		(net "GND")
	)
	(via
		(at 57.531 -165.0746)
		(size 0.5588)
		(drill 0.3048)
		(layers "F.Cu" "B.Cu")
		(net "GND")
	)
	(via
		(at 120.649492 -2.314956)
		(size 0.508)
		(drill 0.254)
		(layers "F.Cu" "B.Cu")
		(net "GND")
	)
	(via
		(at 241.4524 -28.5242)
		(size 0.508)
		(drill 0.254)
		(layers "F.Cu" "B.Cu")
		(net "GND")
	)
	(via
		(at 158.623 -32.8676)
		(size 0.508)
		(drill 0.254)
		(layers "F.Cu" "B.Cu")
		(net "GND")
	)
	(via
		(at 67.099434 -21.517356)
		(size 0.508)
		(drill 0.254)
		(layers "F.Cu" "B.Cu")
		(net "GND")
	)
	(via
		(at 372.390924 -162.268662)
		(size 0.5588)
		(drill 0.3048)
		(layers "F.Cu" "B.Cu")
		(net "GND")
	)
	(via
		(at 61.821568 -13.363956)
		(size 0.508)
		(drill 0.254)
		(layers "F.Cu" "B.Cu")
		(net "GND")
	)
	(via
		(at 189.971934 14.926056)
		(size 0.5588)
		(drill 0.3048)
		(layers "F.Cu" "B.Cu")
		(net "GND")
	)
	(via
		(at 376.744738 -70.295262)
		(size 0.4572)
		(drill 0.2032)
		(layers "F.Cu" "B.Cu")
		(net "GND")
	)
	(via
		(at 345.3892 -9.4742)
		(size 0.508)
		(drill 0.254)
		(layers "F.Cu" "B.Cu")
		(net "GND")
	)
	(via
		(at 69.753226 -88.775286)
		(size 0.508)
		(drill 0.254)
		(layers "F.Cu" "B.Cu")
		(net "GND")
	)
	(via
		(at 370.6368 -118.237)
		(size 0.508)
		(drill 0.254)
		(layers "F.Cu" "B.Cu")
		(net "GND")
	)
	(via
		(at 184.277 -70.9422)
		(size 0.508)
		(drill 0.254)
		(layers "F.Cu" "B.Cu")
		(net "GND")
	)
	(via
		(at 215.85174 1.994154)
		(size 0.508)
		(drill 0.254)
		(layers "F.Cu" "B.Cu")
		(net "GND")
	)
	(via
		(at 233.799888 -145.998946)
		(size 0.508)
		(drill 0.254)
		(layers "F.Cu" "B.Cu")
		(net "GND")
	)
	(via
		(at 251.923804 -66.982086)
		(size 0.508)
		(drill 0.254)
		(layers "F.Cu" "B.Cu")
		(net "GND")
	)
	(via
		(at 309.1688 -68.707)
		(size 0.508)
		(drill 0.254)
		(layers "F.Cu" "B.Cu")
		(net "GND")
	)
	(via
		(at 205.211934 9.084056)
		(size 0.5588)
		(drill 0.3048)
		(layers "F.Cu" "B.Cu")
		(net "GND")
	)
	(via
		(at 423.490136 -38.134544)
		(size 0.4572)
		(drill 0.2032)
		(layers "F.Cu" "B.Cu")
		(net "GND")
	)
	(via
		(at 238.44123 -143.950944)
		(size 0.508)
		(drill 0.254)
		(layers "F.Cu" "B.Cu")
		(net "GND")
	)
	(via
		(at 317.09995 -129.579878)
		(size 0.508)
		(drill 0.254)
		(layers "F.Cu" "B.Cu")
		(net "GND")
	)
	(via
		(at 410.690314 -37.334698)
		(size 0.4572)
		(drill 0.2032)
		(layers "F.Cu" "B.Cu")
		(net "GND")
	)
	(via
		(at 477.4692 -147.066)
		(size 0.508)
		(drill 0.254)
		(layers "F.Cu" "B.Cu")
		(net "GND")
	)
	(via
		(at 254.741934 14.926056)
		(size 0.5588)
		(drill 0.3048)
		(layers "F.Cu" "B.Cu")
		(net "GND")
	)
	(via
		(at 306.049934 -155.612846)
		(size 0.508)
		(drill 0.254)
		(layers "F.Cu" "B.Cu")
		(net "GND")
	)
	(via
		(at 42.8244 -54.0766)
		(size 0.5588)
		(drill 0.3048)
		(layers "F.Cu" "B.Cu")
		(net "GND")
	)
	(via
		(at 207.642714 -68.340478)
		(size 0.5588)
		(drill 0.3048)
		(layers "F.Cu" "B.Cu")
		(net "GND")
	)
	(via
		(at 152.099518 -7.086346)
		(size 0.508)
		(drill 0.254)
		(layers "F.Cu" "B.Cu")
		(net "GND")
	)
	(via
		(at 74.045826 -60.54344)
		(size 0.508)
		(drill 0.254)
		(layers "F.Cu" "B.Cu")
		(net "GND")
	)
	(via
		(at 73.440798 -7.095744)
		(size 0.508)
		(drill 0.254)
		(layers "F.Cu" "B.Cu")
		(net "GND")
	)
	(via
		(at 176.683924 -162.243262)
		(size 0.5588)
		(drill 0.3048)
		(layers "F.Cu" "B.Cu")
		(net "GND")
	)
	(via
		(at 351.261934 9.084056)
		(size 0.5588)
		(drill 0.3048)
		(layers "F.Cu" "B.Cu")
		(net "GND")
	)
	(via
		(at 420.28999 -37.334698)
		(size 0.4572)
		(drill 0.2032)
		(layers "F.Cu" "B.Cu")
		(net "GND")
	)
	(via
		(at 293.677848 -2.3622)
		(size 0.508)
		(drill 0.254)
		(layers "F.Cu" "B.Cu")
		(net "GND")
	)
	(via
		(at 66.249296 -150.219156)
		(size 0.508)
		(drill 0.254)
		(layers "F.Cu" "B.Cu")
		(net "GND")
	)
	(via
		(at 238.187738 -69.953886)
		(size 0.508)
		(drill 0.254)
		(layers "F.Cu" "B.Cu")
		(net "GND")
	)
	(via
		(at 295.80332 -90.575384)
		(size 0.508)
		(drill 0.254)
		(layers "F.Cu" "B.Cu")
		(net "GND")
	)
	(via
		(at 7.701534 9.084056)
		(size 0.5588)
		(drill 0.3048)
		(layers "F.Cu" "B.Cu")
		(net "GND")
	)
	(via
		(at 213.399878 -136.410446)
		(size 0.508)
		(drill 0.254)
		(layers "F.Cu" "B.Cu")
		(net "GND")
	)
	(via
		(at 343.206324 -162.243262)
		(size 0.5588)
		(drill 0.3048)
		(layers "F.Cu" "B.Cu")
		(net "GND")
	)
	(via
		(at 186.670188 -133.809232)
		(size 0.508)
		(drill 0.254)
		(layers "F.Cu" "B.Cu")
		(net "GND")
	)
	(via
		(at 192.0494 -9.1948)
		(size 0.508)
		(drill 0.254)
		(layers "F.Cu" "B.Cu")
		(net "GND")
	)
	(via
		(at 210.38185 -21.5138)
		(size 0.508)
		(drill 0.254)
		(layers "F.Cu" "B.Cu")
		(net "GND")
	)
	(via
		(at 193.117216 -59.900058)
		(size 0.508)
		(drill 0.254)
		(layers "F.Cu" "B.Cu")
		(net "GND")
	)
	(via
		(at 295.381934 14.926056)
		(size 0.5588)
		(drill 0.3048)
		(layers "F.Cu" "B.Cu")
		(net "GND")
	)
	(via
		(at 201.32294 -92.664534)
		(size 0.5588)
		(drill 0.3048)
		(layers "F.Cu" "B.Cu")
		(net "GND")
	)
	(via
		(at 291.422074 -22.965156)
		(size 0.508)
		(drill 0.254)
		(layers "F.Cu" "B.Cu")
		(net "GND")
	)
	(via
		(at 81.772252 -81.841086)
		(size 0.508)
		(drill 0.254)
		(layers "F.Cu" "B.Cu")
		(net "GND")
	)
	(via
		(at 289.031934 9.084056)
		(size 0.5588)
		(drill 0.3048)
		(layers "F.Cu" "B.Cu")
		(net "GND")
	)
	(via
		(at 109.961934 14.926056)
		(size 0.5588)
		(drill 0.3048)
		(layers "F.Cu" "B.Cu")
		(net "GND")
	)
	(via
		(at 289.801808 -7.607046)
		(size 0.508)
		(drill 0.254)
		(layers "F.Cu" "B.Cu")
		(net "GND")
	)
	(via
		(at 75.762866 -83.32724)
		(size 0.508)
		(drill 0.254)
		(layers "F.Cu" "B.Cu")
		(net "GND")
	)
	(via
		(at 80.913732 -57.57164)
		(size 0.508)
		(drill 0.254)
		(layers "F.Cu" "B.Cu")
		(net "GND")
	)
	(via
		(at 23.572724 -162.243262)
		(size 0.5588)
		(drill 0.3048)
		(layers "F.Cu" "B.Cu")
		(net "GND")
	)
	(via
		(at 442.701934 11.624056)
		(size 0.5588)
		(drill 0.3048)
		(layers "F.Cu" "B.Cu")
		(net "GND")
	)
	(via
		(at 295.80332 -59.866784)
		(size 0.508)
		(drill 0.254)
		(layers "F.Cu" "B.Cu")
		(net "GND")
	)
	(via
		(at 497.311934 13.910056)
		(size 0.5588)
		(drill 0.3048)
		(layers "F.Cu" "B.Cu")
		(net "GND")
	)
	(via
		(at 65.399412 -155.612846)
		(size 0.508)
		(drill 0.254)
		(layers "F.Cu" "B.Cu")
		(net "GND")
	)
	(via
		(at 345.8464 -142.0876)
		(size 0.508)
		(drill 0.254)
		(layers "F.Cu" "B.Cu")
		(net "GND")
	)
	(via
		(at 242.299744 -3.762756)
		(size 0.508)
		(drill 0.254)
		(layers "F.Cu" "B.Cu")
		(net "GND")
	)
	(via
		(at 195.5038 -153.6446)
		(size 0.508)
		(drill 0.254)
		(layers "F.Cu" "B.Cu")
		(net "GND")
	)
	(via
		(at 215.0999 -139.170156)
		(size 0.508)
		(drill 0.254)
		(layers "F.Cu" "B.Cu")
		(net "GND")
	)
	(via
		(at 414.050734 -163.361624)
		(size 0.5588)
		(drill 0.3048)
		(layers "F.Cu" "B.Cu")
		(net "GND")
	)
	(via
		(at 39.683182 -92.572078)
		(size 0.5588)
		(drill 0.3048)
		(layers "F.Cu" "B.Cu")
		(net "GND")
	)
	(via
		(at 73.864724 -162.243262)
		(size 0.5588)
		(drill 0.3048)
		(layers "F.Cu" "B.Cu")
		(net "GND")
	)
	(via
		(at 311.891934 9.084056)
		(size 0.5588)
		(drill 0.3048)
		(layers "F.Cu" "B.Cu")
		(net "GND")
	)
	(via
		(at 298.399962 -11.916156)
		(size 0.508)
		(drill 0.254)
		(layers "F.Cu" "B.Cu")
		(net "GND")
	)
	(via
		(at 38.199314 -140.617956)
		(size 0.508)
		(drill 0.254)
		(layers "F.Cu" "B.Cu")
		(net "GND")
	)
	(via
		(at 249.348244 -86.29904)
		(size 0.508)
		(drill 0.254)
		(layers "F.Cu" "B.Cu")
		(net "GND")
	)
	(via
		(at 86.923372 -68.963286)
		(size 0.508)
		(drill 0.254)
		(layers "F.Cu" "B.Cu")
		(net "GND")
	)
	(via
		(at 476.991934 10.354056)
		(size 0.5588)
		(drill 0.3048)
		(layers "F.Cu" "B.Cu")
		(net "GND")
	)
	(via
		(at 75.762866 -92.24264)
		(size 0.508)
		(drill 0.254)
		(layers "F.Cu" "B.Cu")
		(net "GND")
	)
	(via
		(at 381.79375 -111.802164)
		(size 0.508)
		(drill 0.254)
		(layers "F.Cu" "B.Cu")
		(net "GND")
	)
	(via
		(at 42.9641 -73.0504)
		(size 0.5588)
		(drill 0.3048)
		(layers "F.Cu" "B.Cu")
		(net "GND")
	)
	(via
		(at 346.76842 -32.131)
		(size 0.508)
		(drill 0.254)
		(layers "F.Cu" "B.Cu")
		(net "GND")
	)
	(via
		(at 206.982314 -68.340478)
		(size 0.5588)
		(drill 0.3048)
		(layers "F.Cu" "B.Cu")
		(net "GND")
	)
	(via
		(at 267.441934 14.926056)
		(size 0.5588)
		(drill 0.3048)
		(layers "F.Cu" "B.Cu")
		(net "GND")
	)
	(via
		(at 298.399962 -9.143746)
		(size 0.508)
		(drill 0.254)
		(layers "F.Cu" "B.Cu")
		(net "GND")
	)
	(via
		(at 185.888122 -11.067034)
		(size 0.508)
		(drill 0.254)
		(layers "F.Cu" "B.Cu")
		(net "GND")
	)
	(via
		(at 416.031934 9.084056)
		(size 0.5588)
		(drill 0.3048)
		(layers "F.Cu" "B.Cu")
		(net "GND")
	)
	(via
		(at 377.83135 -120.387364)
		(size 0.508)
		(drill 0.254)
		(layers "F.Cu" "B.Cu")
		(net "GND")
	)
	(via
		(at 429.290734 -163.361624)
		(size 0.5588)
		(drill 0.3048)
		(layers "F.Cu" "B.Cu")
		(net "GND")
	)
	(via
		(at 376.428 -105.354882)
		(size 0.508)
		(drill 0.254)
		(layers "F.Cu" "B.Cu")
		(net "GND")
	)
	(via
		(at 130.802888 -90.575384)
		(size 0.508)
		(drill 0.254)
		(layers "F.Cu" "B.Cu")
		(net "GND")
	)
	(via
		(at 334.0354 -108.585)
		(size 0.508)
		(drill 0.254)
		(layers "F.Cu" "B.Cu")
		(net "GND")
	)
	(via
		(at 149.549358 -144.462246)
		(size 0.508)
		(drill 0.254)
		(layers "F.Cu" "B.Cu")
		(net "GND")
	)
	(via
		(at 291.5793 -53.3146)
		(size 0.508)
		(drill 0.254)
		(layers "F.Cu" "B.Cu")
		(net "GND")
	)
	(via
		(at 175.014382 -49.942496)
		(size 0.508)
		(drill 0.254)
		(layers "F.Cu" "B.Cu")
		(net "GND")
	)
	(via
		(at 385.26085 -119.528844)
		(size 0.508)
		(drill 0.254)
		(layers "F.Cu" "B.Cu")
		(net "GND")
	)
	(via
		(at 342.9254 -111.125)
		(size 0.508)
		(drill 0.254)
		(layers "F.Cu" "B.Cu")
		(net "GND")
	)
	(via
		(at 69.551296 -134.861046)
		(size 0.508)
		(drill 0.254)
		(layers "F.Cu" "B.Cu")
		(net "GND")
	)
	(via
		(at 80.913732 -68.46824)
		(size 0.508)
		(drill 0.254)
		(layers "F.Cu" "B.Cu")
		(net "GND")
	)
	(via
		(at 318.522096 -32.515302)
		(size 0.508)
		(drill 0.254)
		(layers "F.Cu" "B.Cu")
		(net "GND")
	)
	(via
		(at 26.6192 -47.1678)
		(size 0.508)
		(drill 0.254)
		(layers "F.Cu" "B.Cu")
		(net "GND")
	)
	(via
		(at 148.699474 -146.011646)
		(size 0.508)
		(drill 0.254)
		(layers "F.Cu" "B.Cu")
		(net "GND")
	)
	(via
		(at -3.463544 11.399266)
		(size 0.5588)
		(drill 0.3048)
		(layers "F.Cu" "B.Cu")
		(net "GND")
	)
	(via
		(at 222.749872 -148.771356)
		(size 0.508)
		(drill 0.254)
		(layers "F.Cu" "B.Cu")
		(net "GND")
	)
	(via
		(at 299.237146 -80.669384)
		(size 0.508)
		(drill 0.254)
		(layers "F.Cu" "B.Cu")
		(net "GND")
	)
	(via
		(at 150.399496 -18.757646)
		(size 0.508)
		(drill 0.254)
		(layers "F.Cu" "B.Cu")
		(net "GND")
	)
	(via
		(at 145.762218 -116.815362)
		(size 0.508)
		(drill 0.254)
		(layers "F.Cu" "B.Cu")
		(net "GND")
	)
	(via
		(at 251.065284 -61.53404)
		(size 0.508)
		(drill 0.254)
		(layers "F.Cu" "B.Cu")
		(net "GND")
	)
	(via
		(at 56.899302 -22.965156)
		(size 0.508)
		(drill 0.254)
		(layers "F.Cu" "B.Cu")
		(net "GND")
	)
	(via
		(at 6.58495 -19.270218)
		(size 0.508)
		(drill 0.254)
		(layers "F.Cu" "B.Cu")
		(net "GND")
	)
	(via
		(at 446.5574 -9.398)
		(size 0.508)
		(drill 0.254)
		(layers "F.Cu" "B.Cu")
		(net "GND")
	)
	(via
		(at 117.640862 -54.913784)
		(size 0.508)
		(drill 0.254)
		(layers "F.Cu" "B.Cu")
		(net "GND")
	)
	(via
		(at 345.18092 -103.13924)
		(size 0.508)
		(drill 0.254)
		(layers "F.Cu" "B.Cu")
		(net "GND")
	)
	(via
		(at 344.1954 -112.395)
		(size 0.508)
		(drill 0.254)
		(layers "F.Cu" "B.Cu")
		(net "GND")
	)
	(via
		(at 408.96032 -142.587218)
		(size 0.508)
		(drill 0.254)
		(layers "F.Cu" "B.Cu")
		(net "GND")
	)
	(via
		(at 414.761934 14.926056)
		(size 0.5588)
		(drill 0.3048)
		(layers "F.Cu" "B.Cu")
		(net "GND")
	)
	(via
		(at 169.898314 -149.5806)
		(size 0.508)
		(drill 0.254)
		(layers "F.Cu" "B.Cu")
		(net "GND")
	)
	(via
		(at 123.650248 -58.381138)
		(size 0.508)
		(drill 0.254)
		(layers "F.Cu" "B.Cu")
		(net "GND")
	)
	(via
		(at 73.187306 -69.953886)
		(size 0.508)
		(drill 0.254)
		(layers "F.Cu" "B.Cu")
		(net "GND")
	)
	(via
		(at 19.6596 -103.5812)
		(size 0.5588)
		(drill 0.3048)
		(layers "F.Cu" "B.Cu")
		(net "GND")
	)
	(via
		(at 273.769328 -103.5812)
		(size 0.508)
		(drill 0.254)
		(layers "F.Cu" "B.Cu")
		(net "GND")
	)
	(via
		(at 361.421934 9.084056)
		(size 0.5588)
		(drill 0.3048)
		(layers "F.Cu" "B.Cu")
		(net "GND")
	)
	(via
		(at 104.881934 9.084056)
		(size 0.5588)
		(drill 0.3048)
		(layers "F.Cu" "B.Cu")
		(net "GND")
	)
	(via
		(at 103.611934 14.926056)
		(size 0.5588)
		(drill 0.3048)
		(layers "F.Cu" "B.Cu")
		(net "GND")
	)
	(via
		(at 85.206332 -64.010286)
		(size 0.508)
		(drill 0.254)
		(layers "F.Cu" "B.Cu")
		(net "GND")
	)
	(via
		(at 419.859714 -82.281014)
		(size 0.508)
		(drill 0.254)
		(layers "F.Cu" "B.Cu")
		(net "GND")
	)
	(via
		(at 351.243646 -104.259634)
		(size 0.508)
		(drill 0.254)
		(layers "F.Cu" "B.Cu")
		(net "GND")
	)
	(via
		(at 396.266924 -162.243262)
		(size 0.5588)
		(drill 0.3048)
		(layers "F.Cu" "B.Cu")
		(net "GND")
	)
	(via
		(at 75.59929 -154.063446)
		(size 0.508)
		(drill 0.254)
		(layers "F.Cu" "B.Cu")
		(net "GND")
	)
	(via
		(at 35.880802 -87.176864)
		(size 0.508)
		(drill 0.254)
		(layers "F.Cu" "B.Cu")
		(net "GND")
	)
	(via
		(at 318.868552 -122.823478)
		(size 0.508)
		(drill 0.254)
		(layers "F.Cu" "B.Cu")
		(net "GND")
	)
	(via
		(at 122.217688 -87.603584)
		(size 0.508)
		(drill 0.254)
		(layers "F.Cu" "B.Cu")
		(net "GND")
	)
	(via
		(at 34.991802 -79.048864)
		(size 0.508)
		(drill 0.254)
		(layers "F.Cu" "B.Cu")
		(net "GND")
	)
	(via
		(at 123.934728 -70.763384)
		(size 0.508)
		(drill 0.254)
		(layers "F.Cu" "B.Cu")
		(net "GND")
	)
	(via
		(at 300.095666 -77.202538)
		(size 0.508)
		(drill 0.254)
		(layers "F.Cu" "B.Cu")
		(net "GND")
	)
	(via
		(at -5.2578 -6.4008)
		(size 0.508)
		(drill 0.254)
		(layers "F.Cu" "B.Cu")
		(net "GND")
	)
	(via
		(at 500.507 -127.69088)
		(size 0.508)
		(drill 0.254)
		(layers "F.Cu" "B.Cu")
		(net "GND")
	)
	(via
		(at 249.9106 -17.7546)
		(size 0.508)
		(drill 0.254)
		(layers "F.Cu" "B.Cu")
		(net "GND")
	)
	(via
		(at 455.490072 -41.344596)
		(size 0.5588)
		(drill 0.3048)
		(layers "F.Cu" "B.Cu")
		(net "GND")
	)
	(via
		(at 200.8886 -72.6948)
		(size 0.508)
		(drill 0.254)
		(layers "F.Cu" "B.Cu")
		(net "GND")
	)
	(via
		(at 260.50875 -87.784686)
		(size 0.508)
		(drill 0.254)
		(layers "F.Cu" "B.Cu")
		(net "GND")
	)
	(via
		(at 60.201302 -134.861046)
		(size 0.508)
		(drill 0.254)
		(layers "F.Cu" "B.Cu")
		(net "GND")
	)
	(via
		(at 98.942398 -53.113686)
		(size 0.508)
		(drill 0.254)
		(layers "F.Cu" "B.Cu")
		(net "GND")
	)
	(via
		(at 295.054528 -26.495756)
		(size 0.508)
		(drill 0.254)
		(layers "F.Cu" "B.Cu")
		(net "GND")
	)
	(via
		(at 12.3444 -26.6446)
		(size 0.508)
		(drill 0.254)
		(layers "F.Cu" "B.Cu")
		(net "GND")
	)
	(via
		(at 242.480338 -57.57164)
		(size 0.508)
		(drill 0.254)
		(layers "F.Cu" "B.Cu")
		(net "GND")
	)
	(via
		(at 372.685056 -3.437382)
		(size 0.508)
		(drill 0.254)
		(layers "F.Cu" "B.Cu")
		(net "GND")
	)
	(via
		(at 223.599756 -13.363956)
		(size 0.508)
		(drill 0.254)
		(layers "F.Cu" "B.Cu")
		(net "GND")
	)
	(via
		(at 118.499382 -65.315338)
		(size 0.508)
		(drill 0.254)
		(layers "F.Cu" "B.Cu")
		(net "GND")
	)
	(via
		(at 14.711934 9.084056)
		(size 0.5588)
		(drill 0.3048)
		(layers "F.Cu" "B.Cu")
		(net "GND")
	)
	(via
		(at 216.761822 -139.170156)
		(size 0.508)
		(drill 0.254)
		(layers "F.Cu" "B.Cu")
		(net "GND")
	)
	(via
		(at 69.56044 -27.910536)
		(size 0.508)
		(drill 0.254)
		(layers "F.Cu" "B.Cu")
		(net "GND")
	)
	(via
		(at 278.957786 -18.007584)
		(size 0.508)
		(drill 0.254)
		(layers "F.Cu" "B.Cu")
		(net "GND")
	)
	(via
		(at 403.226016 -154.430984)
		(size 0.508)
		(drill 0.254)
		(layers "F.Cu" "B.Cu")
		(net "GND")
	)
	(via
		(at 20.223734 -167.832024)
		(size 0.5588)
		(drill 0.3048)
		(layers "F.Cu" "B.Cu")
		(net "GND")
	)
	(via
		(at 242.622324 -162.243262)
		(size 0.5588)
		(drill 0.3048)
		(layers "F.Cu" "B.Cu")
		(net "GND")
	)
	(via
		(at 405.160734 -165.596824)
		(size 0.5588)
		(drill 0.3048)
		(layers "F.Cu" "B.Cu")
		(net "GND")
	)
	(via
		(at 461.331564 -50.488088)
		(size 0.508)
		(drill 0.254)
		(layers "F.Cu" "B.Cu")
		(net "GND")
	)
	(via
		(at 285.2166 -54.418738)
		(size 0.508)
		(drill 0.254)
		(layers "F.Cu" "B.Cu")
		(net "GND")
	)
	(via
		(at 317.949834 -153.542746)
		(size 0.508)
		(drill 0.254)
		(layers "F.Cu" "B.Cu")
		(net "GND")
	)
	(via
		(at 306.899818 1.994154)
		(size 0.508)
		(drill 0.254)
		(layers "F.Cu" "B.Cu")
		(net "GND")
	)
	(via
		(at 332.211934 9.084056)
		(size 0.5588)
		(drill 0.3048)
		(layers "F.Cu" "B.Cu")
		(net "GND")
	)
	(via
		(at 341.6554 -36.83)
		(size 0.508)
		(drill 0.254)
		(layers "F.Cu" "B.Cu")
		(net "GND")
	)
	(via
		(at 197.5358 -63.6524)
		(size 0.508)
		(drill 0.254)
		(layers "F.Cu" "B.Cu")
		(net "GND")
	)
	(via
		(at 321.971924 -162.243262)
		(size 0.5588)
		(drill 0.3048)
		(layers "F.Cu" "B.Cu")
		(net "GND")
	)
	(via
		(at 294.08628 -74.725784)
		(size 0.508)
		(drill 0.254)
		(layers "F.Cu" "B.Cu")
		(net "GND")
	)
	(via
		(at 465.561934 9.084056)
		(size 0.5588)
		(drill 0.3048)
		(layers "F.Cu" "B.Cu")
		(net "GND")
	)
	(via
		(at 60.210446 -140.592556)
		(size 0.508)
		(drill 0.254)
		(layers "F.Cu" "B.Cu")
		(net "GND")
	)
	(via
		(at 306.329334 -167.832024)
		(size 0.5588)
		(drill 0.3048)
		(layers "F.Cu" "B.Cu")
		(net "GND")
	)
	(via
		(at 141.478 -52.5272)
		(size 0.508)
		(drill 0.254)
		(layers "F.Cu" "B.Cu")
		(net "GND")
	)
	(via
		(at 40.749474 -145.998946)
		(size 0.508)
		(drill 0.254)
		(layers "F.Cu" "B.Cu")
		(net "GND")
	)
	(via
		(at 449.051934 13.910056)
		(size 0.5588)
		(drill 0.3048)
		(layers "F.Cu" "B.Cu")
		(net "GND")
	)
	(via
		(at 198.772018 -140.617956)
		(size 0.508)
		(drill 0.254)
		(layers "F.Cu" "B.Cu")
		(net "GND")
	)
	(via
		(at 175.438816 -68.916296)
		(size 0.508)
		(drill 0.254)
		(layers "F.Cu" "B.Cu")
		(net "GND")
	)
	(via
		(at 244.197124 -98.18624)
		(size 0.508)
		(drill 0.254)
		(layers "F.Cu" "B.Cu")
		(net "GND")
	)
	(via
		(at 376.809 -92.837)
		(size 0.508)
		(drill 0.254)
		(layers "F.Cu" "B.Cu")
		(net "GND")
	)
	(via
		(at 336.1944 -32.1183)
		(size 0.508)
		(drill 0.254)
		(layers "F.Cu" "B.Cu")
		(net "GND")
	)
	(via
		(at 26.141934 14.926056)
		(size 0.5588)
		(drill 0.3048)
		(layers "F.Cu" "B.Cu")
		(net "GND")
	)
	(via
		(at 352.9203 -94.5515)
		(size 0.508)
		(drill 0.254)
		(layers "F.Cu" "B.Cu")
		(net "GND")
	)
	(via
		(at 405.21509 -24.92629)
		(size 0.508)
		(drill 0.254)
		(layers "F.Cu" "B.Cu")
		(net "GND")
	)
	(via
		(at 33.771586 -22.965156)
		(size 0.508)
		(drill 0.254)
		(layers "F.Cu" "B.Cu")
		(net "GND")
	)
	(via
		(at 431.830734 -166.714424)
		(size 0.5588)
		(drill 0.3048)
		(layers "F.Cu" "B.Cu")
		(net "GND")
	)
	(via
		(at 64.090804 -143.950944)
		(size 0.508)
		(drill 0.254)
		(layers "F.Cu" "B.Cu")
		(net "GND")
	)
	(via
		(at 293.69131 2.505456)
		(size 0.508)
		(drill 0.254)
		(layers "F.Cu" "B.Cu")
		(net "GND")
	)
	(via
		(at 143.277336 -59.86399)
		(size 0.508)
		(drill 0.254)
		(layers "F.Cu" "B.Cu")
		(net "GND")
	)
	(via
		(at 113.307876 -82.271616)
		(size 0.5588)
		(drill 0.3048)
		(layers "F.Cu" "B.Cu")
		(net "GND")
	)
	(via
		(at 143.383 -67.2592)
		(size 0.508)
		(drill 0.254)
		(layers "F.Cu" "B.Cu")
		(net "GND")
	)
	(via
		(at 71.470266 -61.038486)
		(size 0.508)
		(drill 0.254)
		(layers "F.Cu" "B.Cu")
		(net "GND")
	)
	(via
		(at 113.632742 -93.547184)
		(size 0.508)
		(drill 0.254)
		(layers "F.Cu" "B.Cu")
		(net "GND")
	)
	(via
		(at 198.099934 -146.011646)
		(size 0.508)
		(drill 0.254)
		(layers "F.Cu" "B.Cu")
		(net "GND")
	)
	(via
		(at 448.5513 -53.2384)
		(size 0.508)
		(drill 0.254)
		(layers "F.Cu" "B.Cu")
		(net "GND")
	)
	(via
		(at 141.104874 -84.631784)
		(size 0.508)
		(drill 0.254)
		(layers "F.Cu" "B.Cu")
		(net "GND")
	)
	(via
		(at 330.2254 -112.395)
		(size 0.508)
		(drill 0.254)
		(layers "F.Cu" "B.Cu")
		(net "GND")
	)
	(via
		(at 37.34943 -148.771356)
		(size 0.508)
		(drill 0.254)
		(layers "F.Cu" "B.Cu")
		(net "GND")
	)
	(via
		(at 119.331232 -148.7678)
		(size 0.508)
		(drill 0.254)
		(layers "F.Cu" "B.Cu")
		(net "GND")
	)
	(via
		(at 206.321914 -69.000878)
		(size 0.5588)
		(drill 0.3048)
		(layers "F.Cu" "B.Cu")
		(net "GND")
	)
	(via
		(at 426.822108 -32.677608)
		(size 0.4572)
		(drill 0.2032)
		(layers "F.Cu" "B.Cu")
		(net "GND")
	)
	(via
		(at 310.122062 -140.617956)
		(size 0.508)
		(drill 0.254)
		(layers "F.Cu" "B.Cu")
		(net "GND")
	)
	(via
		(at 124.793248 -98.005138)
		(size 0.508)
		(drill 0.254)
		(layers "F.Cu" "B.Cu")
		(net "GND")
	)
	(via
		(at 33.771586 -131.016756)
		(size 0.508)
		(drill 0.254)
		(layers "F.Cu" "B.Cu")
		(net "GND")
	)
	(via
		(at 236.171994 -140.617956)
		(size 0.508)
		(drill 0.254)
		(layers "F.Cu" "B.Cu")
		(net "GND")
	)
	(via
		(at 292.386512 -23.495)
		(size 0.508)
		(drill 0.254)
		(layers "F.Cu" "B.Cu")
		(net "GND")
	)
	(via
		(at 451.591934 14.926056)
		(size 0.5588)
		(drill 0.3048)
		(layers "F.Cu" "B.Cu")
		(net "GND")
	)
	(via
		(at 62.786006 -141.1478)
		(size 0.508)
		(drill 0.254)
		(layers "F.Cu" "B.Cu")
		(net "GND")
	)
	(via
		(at 240.763298 -96.20504)
		(size 0.508)
		(drill 0.254)
		(layers "F.Cu" "B.Cu")
		(net "GND")
	)
	(via
		(at 380.80315 -122.104404)
		(size 0.508)
		(drill 0.254)
		(layers "F.Cu" "B.Cu")
		(net "GND")
	)
	(via
		(at 40.0812 -52.6542)
		(size 0.5588)
		(drill 0.3048)
		(layers "F.Cu" "B.Cu")
		(net "GND")
	)
	(via
		(at 195.549774 -23.495)
		(size 0.508)
		(drill 0.254)
		(layers "F.Cu" "B.Cu")
		(net "GND")
	)
	(via
		(at 349.048578 -97.781872)
		(size 0.508)
		(drill 0.254)
		(layers "F.Cu" "B.Cu")
		(net "GND")
	)
	(via
		(at 138.529314 -88.099138)
		(size 0.508)
		(drill 0.254)
		(layers "F.Cu" "B.Cu")
		(net "GND")
	)
	(via
		(at 172.217334 -167.832024)
		(size 0.5588)
		(drill 0.3048)
		(layers "F.Cu" "B.Cu")
		(net "GND")
	)
	(via
		(at 413.893762 -86.397084)
		(size 0.508)
		(drill 0.254)
		(layers "F.Cu" "B.Cu")
		(net "GND")
	)
	(via
		(at 387.8453 -151.7142)
		(size 0.508)
		(drill 0.254)
		(layers "F.Cu" "B.Cu")
		(net "GND")
	)
	(via
		(at 4.353306 -145.588482)
		(size 0.508)
		(drill 0.254)
		(layers "F.Cu" "B.Cu")
		(net "GND")
	)
	(via
		(at 394.17625 -105.332276)
		(size 0.508)
		(drill 0.254)
		(layers "F.Cu" "B.Cu")
		(net "GND")
	)
	(via
		(at 174.731934 9.084056)
		(size 0.5588)
		(drill 0.3048)
		(layers "F.Cu" "B.Cu")
		(net "GND")
	)
	(via
		(at 458.500734 -166.714424)
		(size 0.5588)
		(drill 0.3048)
		(layers "F.Cu" "B.Cu")
		(net "GND")
	)
	(via
		(at 148.743924 -162.243262)
		(size 0.5588)
		(drill 0.3048)
		(layers "F.Cu" "B.Cu")
		(net "GND")
	)
	(via
		(at 292.36924 -88.594184)
		(size 0.508)
		(drill 0.254)
		(layers "F.Cu" "B.Cu")
		(net "GND")
	)
	(via
		(at 287.349946 -129.568956)
		(size 0.508)
		(drill 0.254)
		(layers "F.Cu" "B.Cu")
		(net "GND")
	)
	(via
		(at 342.13038 -131.8641)
		(size 0.508)
		(drill 0.254)
		(layers "F.Cu" "B.Cu")
		(net "GND")
	)
	(via
		(at 34.736024 -131.5466)
		(size 0.508)
		(drill 0.254)
		(layers "F.Cu" "B.Cu")
		(net "GND")
	)
	(via
		(at 20.8534 -93.5482)
		(size 0.508)
		(drill 0.254)
		(layers "F.Cu" "B.Cu")
		(net "GND")
	)
	(via
		(at 54.737508 -4.346956)
		(size 0.508)
		(drill 0.254)
		(layers "F.Cu" "B.Cu")
		(net "GND")
	)
	(via
		(at 424.434 -26.162)
		(size 0.4572)
		(drill 0.2032)
		(layers "F.Cu" "B.Cu")
		(net "GND")
	)
	(via
		(at 394.441934 14.926056)
		(size 0.5588)
		(drill 0.3048)
		(layers "F.Cu" "B.Cu")
		(net "GND")
	)
	(via
		(at 82.630772 -93.23324)
		(size 0.508)
		(drill 0.254)
		(layers "F.Cu" "B.Cu")
		(net "GND")
	)
	(via
		(at 283.036264 -141.1478)
		(size 0.508)
		(drill 0.254)
		(layers "F.Cu" "B.Cu")
		(net "GND")
	)
	(via
		(at 209.08645 -13.8938)
		(size 0.508)
		(drill 0.254)
		(layers "F.Cu" "B.Cu")
		(net "GND")
	)
	(via
		(at 250.931934 14.926056)
		(size 0.5588)
		(drill 0.3048)
		(layers "F.Cu" "B.Cu")
		(net "GND")
	)
	(via
		(at 301.754794 2.4638)
		(size 0.508)
		(drill 0.254)
		(layers "F.Cu" "B.Cu")
		(net "GND")
	)
	(via
		(at 280.451814 -154.063446)
		(size 0.508)
		(drill 0.254)
		(layers "F.Cu" "B.Cu")
		(net "GND")
	)
	(via
		(at 157.684724 -162.243262)
		(size 0.5588)
		(drill 0.3048)
		(layers "F.Cu" "B.Cu")
		(net "GND")
	)
	(via
		(at 417.547298 -46.187614)
		(size 0.508)
		(drill 0.254)
		(layers "F.Cu" "B.Cu")
		(net "GND")
	)
	(via
		(at 36.340542 -100.887276)
		(size 0.5588)
		(drill 0.3048)
		(layers "F.Cu" "B.Cu")
		(net "GND")
	)
	(via
		(at 330.912724 -162.243262)
		(size 0.5588)
		(drill 0.3048)
		(layers "F.Cu" "B.Cu")
		(net "GND")
	)
	(via
		(at 121.074688 -56.894984)
		(size 0.508)
		(drill 0.254)
		(layers "F.Cu" "B.Cu")
		(net "GND")
	)
	(via
		(at 439.74004 -53.2384)
		(size 0.508)
		(drill 0.254)
		(layers "F.Cu" "B.Cu")
		(net "GND")
	)
	(via
		(at 306.049934 -148.771356)
		(size 0.508)
		(drill 0.254)
		(layers "F.Cu" "B.Cu")
		(net "GND")
	)
	(via
		(at 466.120734 -167.832024)
		(size 0.5588)
		(drill 0.3048)
		(layers "F.Cu" "B.Cu")
		(net "GND")
	)
	(via
		(at 152.949402 -131.571746)
		(size 0.508)
		(drill 0.254)
		(layers "F.Cu" "B.Cu")
		(net "GND")
	)
	(via
		(at 378.82195 -95.888556)
		(size 0.508)
		(drill 0.254)
		(layers "F.Cu" "B.Cu")
		(net "GND")
	)
	(via
		(at 249.9106 -145.0086)
		(size 0.508)
		(drill 0.254)
		(layers "F.Cu" "B.Cu")
		(net "GND")
	)
	(via
		(at 64.087502 -131.600956)
		(size 0.508)
		(drill 0.254)
		(layers "F.Cu" "B.Cu")
		(net "GND")
	)
	(via
		(at 235.46181 -155.562046)
		(size 0.508)
		(drill 0.254)
		(layers "F.Cu" "B.Cu")
		(net "GND")
	)
	(via
		(at 243.149882 -136.387078)
		(size 0.508)
		(drill 0.254)
		(layers "F.Cu" "B.Cu")
		(net "GND")
	)
	(via
		(at 200.5076 -101.449886)
		(size 0.5588)
		(drill 0.3048)
		(layers "F.Cu" "B.Cu")
		(net "GND")
	)
	(via
		(at 113.348262 -55.409338)
		(size 0.508)
		(drill 0.254)
		(layers "F.Cu" "B.Cu")
		(net "GND")
	)
	(via
		(at 138.040872 2.505456)
		(size 0.508)
		(drill 0.254)
		(layers "F.Cu" "B.Cu")
		(net "GND")
	)
	(via
		(at 54.731412 -148.7678)
		(size 0.508)
		(drill 0.254)
		(layers "F.Cu" "B.Cu")
		(net "GND")
	)
	(via
		(at 97.915476 -75.159616)
		(size 0.5588)
		(drill 0.3048)
		(layers "F.Cu" "B.Cu")
		(net "GND")
	)
	(via
		(at 421.670734 -166.714424)
		(size 0.5588)
		(drill 0.3048)
		(layers "F.Cu" "B.Cu")
		(net "GND")
	)
	(via
		(at 361.48518 -9.30529)
		(size 0.508)
		(drill 0.254)
		(layers "F.Cu" "B.Cu")
		(net "GND")
	)
	(via
		(at 227.792534 -28.730956)
		(size 0.508)
		(drill 0.254)
		(layers "F.Cu" "B.Cu")
		(net "GND")
	)
	(via
		(at 281.208734 -98.995738)
		(size 0.508)
		(drill 0.254)
		(layers "F.Cu" "B.Cu")
		(net "GND")
	)
	(via
		(at -0.006604 -56.891428)
		(size 0.5588)
		(drill 0.3048)
		(layers "F.Cu" "B.Cu")
		(net "GND")
	)
	(via
		(at 70.461378 -139.170156)
		(size 0.508)
		(drill 0.254)
		(layers "F.Cu" "B.Cu")
		(net "GND")
	)
	(via
		(at 282.641294 -65.810384)
		(size 0.508)
		(drill 0.254)
		(layers "F.Cu" "B.Cu")
		(net "GND")
	)
	(via
		(at 146.096228 -4.2926)
		(size 0.508)
		(drill 0.254)
		(layers "F.Cu" "B.Cu")
		(net "GND")
	)
	(via
		(at 306.899818 -27.943556)
		(size 0.508)
		(drill 0.254)
		(layers "F.Cu" "B.Cu")
		(net "GND")
	)
	(via
		(at 470.5604 -24.765)
		(size 0.508)
		(drill 0.254)
		(layers "F.Cu" "B.Cu")
		(net "GND")
	)
	(via
		(at 387.73735 -118.670324)
		(size 0.508)
		(drill 0.254)
		(layers "F.Cu" "B.Cu")
		(net "GND")
	)
	(via
		(at 381.741934 9.084056)
		(size 0.5588)
		(drill 0.3048)
		(layers "F.Cu" "B.Cu")
		(net "GND")
	)
	(via
		(at 130.054096 -26.495756)
		(size 0.508)
		(drill 0.254)
		(layers "F.Cu" "B.Cu")
		(net "GND")
	)
	(via
		(at 364.611666 -107.469178)
		(size 0.508)
		(drill 0.254)
		(layers "F.Cu" "B.Cu")
		(net "GND")
	)
	(via
		(at 464.850734 -164.479224)
		(size 0.5588)
		(drill 0.3048)
		(layers "F.Cu" "B.Cu")
		(net "GND")
	)
	(via
		(at 24.690324 -162.243262)
		(size 0.5588)
		(drill 0.3048)
		(layers "F.Cu" "B.Cu")
		(net "GND")
	)
	(via
		(at 395.9352 -143.2306)
		(size 0.508)
		(drill 0.254)
		(layers "F.Cu" "B.Cu")
		(net "GND")
	)
	(via
		(at 186.01309 -1.524)
		(size 0.508)
		(drill 0.254)
		(layers "F.Cu" "B.Cu")
		(net "GND")
	)
	(via
		(at 462.142078 -50.513488)
		(size 0.508)
		(drill 0.254)
		(layers "F.Cu" "B.Cu")
		(net "GND")
	)
	(via
		(at 417.7792 -135.3312)
		(size 0.508)
		(drill 0.254)
		(layers "F.Cu" "B.Cu")
		(net "GND")
	)
	(via
		(at 117.066822 -99.490784)
		(size 0.508)
		(drill 0.254)
		(layers "F.Cu" "B.Cu")
		(net "GND")
	)
	(via
		(at 134.160514 -27.918156)
		(size 0.508)
		(drill 0.254)
		(layers "F.Cu" "B.Cu")
		(net "GND")
	)
	(via
		(at 108.126276 -75.159616)
		(size 0.5588)
		(drill 0.3048)
		(layers "F.Cu" "B.Cu")
		(net "GND")
	)
	(via
		(at 95.70339 -136.72947)
		(size 0.508)
		(drill 0.254)
		(layers "F.Cu" "B.Cu")
		(net "GND")
	)
	(via
		(at 465.680552 -45.593)
		(size 0.508)
		(drill 0.254)
		(layers "F.Cu" "B.Cu")
		(net "GND")
	)
	(via
		(at 440.227212 -45.611796)
		(size 0.508)
		(drill 0.254)
		(layers "F.Cu" "B.Cu")
		(net "GND")
	)
	(via
		(at 127.392176 -129.564892)
		(size 0.508)
		(drill 0.254)
		(layers "F.Cu" "B.Cu")
		(net "GND")
	)
	(via
		(at 240.763298 -100.167186)
		(size 0.508)
		(drill 0.254)
		(layers "F.Cu" "B.Cu")
		(net "GND")
	)
	(via
		(at 288.19983 -144.462246)
		(size 0.508)
		(drill 0.254)
		(layers "F.Cu" "B.Cu")
		(net "GND")
	)
	(via
		(at 118.035832 -131.5466)
		(size 0.508)
		(drill 0.254)
		(layers "F.Cu" "B.Cu")
		(net "GND")
	)
	(via
		(at 7.186676 -20.545806)
		(size 0.508)
		(drill 0.254)
		(layers "F.Cu" "B.Cu")
		(net "GND")
	)
	(via
		(at 13.208 -90.043)
		(size 0.508)
		(drill 0.254)
		(layers "F.Cu" "B.Cu")
		(net "GND")
	)
	(via
		(at 461.040734 -166.714424)
		(size 0.5588)
		(drill 0.3048)
		(layers "F.Cu" "B.Cu")
		(net "GND")
	)
	(via
		(at 132.519674 -76.706984)
		(size 0.508)
		(drill 0.254)
		(layers "F.Cu" "B.Cu")
		(net "GND")
	)
	(via
		(at 288.07664 -76.211938)
		(size 0.508)
		(drill 0.254)
		(layers "F.Cu" "B.Cu")
		(net "GND")
	)
	(via
		(at 276.916134 -100.48113)
		(size 0.508)
		(drill 0.254)
		(layers "F.Cu" "B.Cu")
		(net "GND")
	)
	(via
		(at 234.753658 -88.775286)
		(size 0.508)
		(drill 0.254)
		(layers "F.Cu" "B.Cu")
		(net "GND")
	)
	(via
		(at 135.095234 -56.399938)
		(size 0.508)
		(drill 0.254)
		(layers "F.Cu" "B.Cu")
		(net "GND")
	)
	(via
		(at 457.267056 -36.522406)
		(size 0.508)
		(drill 0.254)
		(layers "F.Cu" "B.Cu")
		(net "GND")
	)
	(via
		(at 246.772684 -85.803486)
		(size 0.508)
		(drill 0.254)
		(layers "F.Cu" "B.Cu")
		(net "GND")
	)
	(via
		(at 278.947372 -21.665184)
		(size 0.508)
		(drill 0.254)
		(layers "F.Cu" "B.Cu")
		(net "GND")
	)
	(via
		(at 115.923822 -53.923184)
		(size 0.508)
		(drill 0.254)
		(layers "F.Cu" "B.Cu")
		(net "GND")
	)
	(via
		(at 114.699542 -129.568956)
		(size 0.508)
		(drill 0.254)
		(layers "F.Cu" "B.Cu")
		(net "GND")
	)
	(via
		(at 281.208734 -97.014538)
		(size 0.508)
		(drill 0.254)
		(layers "F.Cu" "B.Cu")
		(net "GND")
	)
	(via
		(at 88.371934 14.926056)
		(size 0.5588)
		(drill 0.3048)
		(layers "F.Cu" "B.Cu")
		(net "GND")
	)
	(via
		(at 393.43457 -25.744932)
		(size 0.508)
		(drill 0.254)
		(layers "F.Cu" "B.Cu")
		(net "GND")
	)
	(via
		(at 277.774654 -96.023938)
		(size 0.508)
		(drill 0.254)
		(layers "F.Cu" "B.Cu")
		(net "GND")
	)
	(via
		(at 492.231934 10.354056)
		(size 0.5588)
		(drill 0.3048)
		(layers "F.Cu" "B.Cu")
		(net "GND")
	)
	(via
		(at 306.963826 -86.117938)
		(size 0.508)
		(drill 0.254)
		(layers "F.Cu" "B.Cu")
		(net "GND")
	)
	(via
		(at 120.825768 -50.7746)
		(size 0.508)
		(drill 0.254)
		(layers "F.Cu" "B.Cu")
		(net "GND")
	)
	(via
		(at 127.392176 -21.513292)
		(size 0.508)
		(drill 0.254)
		(layers "F.Cu" "B.Cu")
		(net "GND")
	)
	(via
		(at 304.349912 -26.495756)
		(size 0.508)
		(drill 0.254)
		(layers "F.Cu" "B.Cu")
		(net "GND")
	)
	(via
		(at 141.899386 -125.334776)
		(size 0.508)
		(drill 0.254)
		(layers "F.Cu" "B.Cu")
		(net "GND")
	)
	(via
		(at 241.621818 -63.019686)
		(size 0.508)
		(drill 0.254)
		(layers "F.Cu" "B.Cu")
		(net "GND")
	)
	(via
		(at 441.431934 13.910056)
		(size 0.5588)
		(drill 0.3048)
		(layers "F.Cu" "B.Cu")
		(net "GND")
	)
	(via
		(at 126.421642 -13.363956)
		(size 0.508)
		(drill 0.254)
		(layers "F.Cu" "B.Cu")
		(net "GND")
	)
	(via
		(at 492.790734 -163.361624)
		(size 0.5588)
		(drill 0.3048)
		(layers "F.Cu" "B.Cu")
		(net "GND")
	)
	(via
		(at 391.713466 -10.08253)
		(size 0.508)
		(drill 0.254)
		(layers "F.Cu" "B.Cu")
		(net "GND")
	)
	(via
		(at 299.151802 -144.462246)
		(size 0.508)
		(drill 0.254)
		(layers "F.Cu" "B.Cu")
		(net "GND")
	)
	(via
		(at 120.649492 -146.011646)
		(size 0.508)
		(drill 0.254)
		(layers "F.Cu" "B.Cu")
		(net "GND")
	)
	(via
		(at 360.006646 -97.062798)
		(size 0.508)
		(drill 0.254)
		(layers "F.Cu" "B.Cu")
		(net "GND")
	)
	(via
		(at 200.533 -91.4908)
		(size 0.508)
		(drill 0.254)
		(layers "F.Cu" "B.Cu")
		(net "GND")
	)
	(via
		(at 204.049884 -2.314956)
		(size 0.508)
		(drill 0.254)
		(layers "F.Cu" "B.Cu")
		(net "GND")
	)
	(via
		(at 397.3322 -152.2476)
		(size 0.508)
		(drill 0.254)
		(layers "F.Cu" "B.Cu")
		(net "GND")
	)
	(via
		(at 6.285992 -143.9418)
		(size 0.508)
		(drill 0.254)
		(layers "F.Cu" "B.Cu")
		(net "GND")
	)
	(via
		(at 67.949318 -150.219156)
		(size 0.508)
		(drill 0.254)
		(layers "F.Cu" "B.Cu")
		(net "GND")
	)
	(via
		(at 484.251 -43.9674)
		(size 0.508)
		(drill 0.254)
		(layers "F.Cu" "B.Cu")
		(net "GND")
	)
	(via
		(at 441.990734 -167.832024)
		(size 0.5588)
		(drill 0.3048)
		(layers "F.Cu" "B.Cu")
		(net "GND")
	)
	(via
		(at 82.630772 -95.21444)
		(size 0.508)
		(drill 0.254)
		(layers "F.Cu" "B.Cu")
		(net "GND")
	)
	(via
		(at 19.102324 -162.243262)
		(size 0.5588)
		(drill 0.3048)
		(layers "F.Cu" "B.Cu")
		(net "GND")
	)
	(via
		(at 264.901934 9.084056)
		(size 0.5588)
		(drill 0.3048)
		(layers "F.Cu" "B.Cu")
		(net "GND")
	)
	(via
		(at 453.420734 -163.361624)
		(size 0.5588)
		(drill 0.3048)
		(layers "F.Cu" "B.Cu")
		(net "GND")
	)
	(via
		(at 279.699974 -155.600146)
		(size 0.508)
		(drill 0.254)
		(layers "F.Cu" "B.Cu")
		(net "GND")
	)
	(via
		(at 84.347812 -74.411586)
		(size 0.508)
		(drill 0.254)
		(layers "F.Cu" "B.Cu")
		(net "GND")
	)
	(via
		(at 336.9564 -31.3563)
		(size 0.508)
		(drill 0.254)
		(layers "F.Cu" "B.Cu")
		(net "GND")
	)
	(via
		(at 347.734636 -116.35105)
		(size 0.508)
		(drill 0.254)
		(layers "F.Cu" "B.Cu")
		(net "GND")
	)
	(via
		(at 214.249762 -144.462246)
		(size 0.508)
		(drill 0.254)
		(layers "F.Cu" "B.Cu")
		(net "GND")
	)
	(via
		(at 285.221934 9.084056)
		(size 0.5588)
		(drill 0.3048)
		(layers "F.Cu" "B.Cu")
		(net "GND")
	)
	(via
		(at 132.519674 -58.876438)
		(size 0.508)
		(drill 0.254)
		(layers "F.Cu" "B.Cu")
		(net "GND")
	)
	(via
		(at 113.968276 -82.283046)
		(size 0.5588)
		(drill 0.3048)
		(layers "F.Cu" "B.Cu")
		(net "GND")
	)
	(via
		(at 438.891934 9.084056)
		(size 0.5588)
		(drill 0.3048)
		(layers "F.Cu" "B.Cu")
		(net "GND")
	)
	(via
		(at 467.047072 -115.34648)
		(size 0.508)
		(drill 0.254)
		(layers "F.Cu" "B.Cu")
		(net "GND")
	)
	(via
		(at 82.630772 -63.51524)
		(size 0.508)
		(drill 0.254)
		(layers "F.Cu" "B.Cu")
		(net "GND")
	)
	(via
		(at 130.76428 -27.829256)
		(size 0.508)
		(drill 0.254)
		(layers "F.Cu" "B.Cu")
		(net "GND")
	)
	(via
		(at 383.6543 -152.6032)
		(size 0.508)
		(drill 0.254)
		(layers "F.Cu" "B.Cu")
		(net "GND")
	)
	(via
		(at 435.2544 -130.302)
		(size 0.508)
		(drill 0.254)
		(layers "F.Cu" "B.Cu")
		(net "GND")
	)
	(via
		(at 62.792102 -11.912092)
		(size 0.508)
		(drill 0.254)
		(layers "F.Cu" "B.Cu")
		(net "GND")
	)
	(via
		(at 492.0234 -52.5272)
		(size 0.508)
		(drill 0.254)
		(layers "F.Cu" "B.Cu")
		(net "GND")
	)
	(via
		(at 80.055212 -79.859886)
		(size 0.508)
		(drill 0.254)
		(layers "F.Cu" "B.Cu")
		(net "GND")
	)
	(via
		(at 307.141626 -94.042738)
		(size 0.508)
		(drill 0.254)
		(layers "F.Cu" "B.Cu")
		(net "GND")
	)
	(via
		(at 379.81255 -113.519204)
		(size 0.508)
		(drill 0.254)
		(layers "F.Cu" "B.Cu")
		(net "GND")
	)
	(via
		(at 327.279 -34.163)
		(size 0.508)
		(drill 0.254)
		(layers "F.Cu" "B.Cu")
		(net "GND")
	)
	(via
		(at 329.7936 -36.703)
		(size 0.508)
		(drill 0.254)
		(layers "F.Cu" "B.Cu")
		(net "GND")
	)
	(via
		(at 398.810734 -164.479224)
		(size 0.5588)
		(drill 0.3048)
		(layers "F.Cu" "B.Cu")
		(net "GND")
	)
	(via
		(at 424.796458 -2.4638)
		(size 0.508)
		(drill 0.254)
		(layers "F.Cu" "B.Cu")
		(net "GND")
	)
	(via
		(at 184.4548 -140.1445)
		(size 0.508)
		(drill 0.254)
		(layers "F.Cu" "B.Cu")
		(net "GND")
	)
	(via
		(at 72.1487 -16.7513)
		(size 0.508)
		(drill 0.254)
		(layers "F.Cu" "B.Cu")
		(net "GND")
	)
	(via
		(at 129.085848 -56.894984)
		(size 0.508)
		(drill 0.254)
		(layers "F.Cu" "B.Cu")
		(net "GND")
	)
	(via
		(at 343.4588 -27.5336)
		(size 0.508)
		(drill 0.254)
		(layers "F.Cu" "B.Cu")
		(net "GND")
	)
	(via
		(at 383.27965 -96.747076)
		(size 0.508)
		(drill 0.254)
		(layers "F.Cu" "B.Cu")
		(net "GND")
	)
	(via
		(at 303.025048 -11.938)
		(size 0.508)
		(drill 0.254)
		(layers "F.Cu" "B.Cu")
		(net "GND")
	)
	(via
		(at 70.461378 -148.771356)
		(size 0.508)
		(drill 0.254)
		(layers "F.Cu" "B.Cu")
		(net "GND")
	)
	(via
		(at 260.50875 -63.019686)
		(size 0.508)
		(drill 0.254)
		(layers "F.Cu" "B.Cu")
		(net "GND")
	)
	(via
		(at 96.721168 -7.064248)
		(size 0.508)
		(drill 0.254)
		(layers "F.Cu" "B.Cu")
		(net "GND")
	)
	(via
		(at 175.478694 -56.722518)
		(size 0.508)
		(drill 0.254)
		(layers "F.Cu" "B.Cu")
		(net "GND")
	)
	(via
		(at 298.399962 0.457454)
		(size 0.508)
		(drill 0.254)
		(layers "F.Cu" "B.Cu")
		(net "GND")
	)
	(via
		(at 201.8284 -84.4804)
		(size 0.5588)
		(drill 0.3048)
		(layers "F.Cu" "B.Cu")
		(net "GND")
	)
	(via
		(at 251.065284 -86.29904)
		(size 0.508)
		(drill 0.254)
		(layers "F.Cu" "B.Cu")
		(net "GND")
	)
	(via
		(at 487.151934 14.926056)
		(size 0.5588)
		(drill 0.3048)
		(layers "F.Cu" "B.Cu")
		(net "GND")
	)
	(via
		(at 24.447246 -51.999388)
		(size 0.5588)
		(drill 0.3048)
		(layers "F.Cu" "B.Cu")
		(net "GND")
	)
	(via
		(at 141.181074 -78.688438)
		(size 0.508)
		(drill 0.254)
		(layers "F.Cu" "B.Cu")
		(net "GND")
	)
	(via
		(at 406.908 -143.6878)
		(size 0.508)
		(drill 0.254)
		(layers "F.Cu" "B.Cu")
		(net "GND")
	)
	(via
		(at 36.174934 -92.686632)
		(size 0.5588)
		(drill 0.3048)
		(layers "F.Cu" "B.Cu")
		(net "GND")
	)
	(via
		(at 287.349946 -9.156446)
		(size 0.508)
		(drill 0.254)
		(layers "F.Cu" "B.Cu")
		(net "GND")
	)
	(via
		(at 256.21615 -65.49644)
		(size 0.508)
		(drill 0.254)
		(layers "F.Cu" "B.Cu")
		(net "GND")
	)
	(via
		(at 463.580734 -167.832024)
		(size 0.5588)
		(drill 0.3048)
		(layers "F.Cu" "B.Cu")
		(net "GND")
	)
	(via
		(at 184.684924 -148.9837)
		(size 0.508)
		(drill 0.254)
		(layers "F.Cu" "B.Cu")
		(net "GND")
	)
	(via
		(at 201.041254 -134.349744)
		(size 0.508)
		(drill 0.254)
		(layers "F.Cu" "B.Cu")
		(net "GND")
	)
	(via
		(at 314.431934 14.926056)
		(size 0.5588)
		(drill 0.3048)
		(layers "F.Cu" "B.Cu")
		(net "GND")
	)
	(via
		(at 477.934528 -155.10002)
		(size 0.5588)
		(drill 0.3048)
		(layers "F.Cu" "B.Cu")
		(net "GND")
	)
	(via
		(at 72.136 -23.495)
		(size 0.508)
		(drill 0.254)
		(layers "F.Cu" "B.Cu")
		(net "GND")
	)
	(via
		(at 416.290252 -27.734768)
		(size 0.4572)
		(drill 0.2032)
		(layers "F.Cu" "B.Cu")
		(net "GND")
	)
	(via
		(at 328.677524 -162.243262)
		(size 0.5588)
		(drill 0.3048)
		(layers "F.Cu" "B.Cu")
		(net "GND")
	)
	(via
		(at 238.155734 -167.832024)
		(size 0.5588)
		(drill 0.3048)
		(layers "F.Cu" "B.Cu")
		(net "GND")
	)
	(via
		(at 106.297476 -75.159616)
		(size 0.5588)
		(drill 0.3048)
		(layers "F.Cu" "B.Cu")
		(net "GND")
	)
	(via
		(at 391.3378 -112.2553)
		(size 0.508)
		(drill 0.254)
		(layers "F.Cu" "B.Cu")
		(net "GND")
	)
	(via
		(at 461.440022 -3.386074)
		(size 0.508)
		(drill 0.254)
		(layers "F.Cu" "B.Cu")
		(net "GND")
	)
	(via
		(at 416.590734 -167.832024)
		(size 0.5588)
		(drill 0.3048)
		(layers "F.Cu" "B.Cu")
		(net "GND")
	)
	(via
		(at 311.092596 -139.166092)
		(size 0.508)
		(drill 0.254)
		(layers "F.Cu" "B.Cu")
		(net "GND")
	)
	(via
		(at 179.811934 9.084056)
		(size 0.5588)
		(drill 0.3048)
		(layers "F.Cu" "B.Cu")
		(net "GND")
	)
	(via
		(at 225.210878 -27.910536)
		(size 0.508)
		(drill 0.254)
		(layers "F.Cu" "B.Cu")
		(net "GND")
	)
	(via
		(at 184.778396 -85.944202)
		(size 0.508)
		(drill 0.254)
		(layers "F.Cu" "B.Cu")
		(net "GND")
	)
	(via
		(at 443.971934 10.354056)
		(size 0.5588)
		(drill 0.3048)
		(layers "F.Cu" "B.Cu")
		(net "GND")
	)
	(via
		(at 227.786438 -150.749)
		(size 0.508)
		(drill 0.254)
		(layers "F.Cu" "B.Cu")
		(net "GND")
	)
	(via
		(at 32.639 -55.5498)
		(size 0.508)
		(drill 0.254)
		(layers "F.Cu" "B.Cu")
		(net "GND")
	)
	(via
		(at 175.938942 -52.3748)
		(size 0.508)
		(drill 0.254)
		(layers "F.Cu" "B.Cu")
		(net "GND")
	)
	(via
		(at 44.092114 -148.767292)
		(size 0.508)
		(drill 0.254)
		(layers "F.Cu" "B.Cu")
		(net "GND")
	)
	(via
		(at 21.1582 -67.9196)
		(size 0.508)
		(drill 0.254)
		(layers "F.Cu" "B.Cu")
		(net "GND")
	)
	(via
		(at 351.8154 -36.83)
		(size 0.508)
		(drill 0.254)
		(layers "F.Cu" "B.Cu")
		(net "GND")
	)
	(via
		(at 248.774204 -54.599332)
		(size 0.508)
		(drill 0.254)
		(layers "F.Cu" "B.Cu")
		(net "GND")
	)
	(via
		(at 204.899768 -3.762756)
		(size 0.508)
		(drill 0.254)
		(layers "F.Cu" "B.Cu")
		(net "GND")
	)
	(via
		(at 431.271934 10.354056)
		(size 0.5588)
		(drill 0.3048)
		(layers "F.Cu" "B.Cu")
		(net "GND")
	)
	(via
		(at 445.399922 -113.8174)
		(size 0.508)
		(drill 0.254)
		(layers "F.Cu" "B.Cu")
		(net "GND")
	)
	(via
		(at 27.432 -63.32982)
		(size 0.508)
		(drill 0.254)
		(layers "F.Cu" "B.Cu")
		(net "GND")
	)
	(via
		(at 452.0438 -119.9134)
		(size 0.508)
		(drill 0.254)
		(layers "F.Cu" "B.Cu")
		(net "GND")
	)
	(via
		(at 296.69994 -136.410446)
		(size 0.508)
		(drill 0.254)
		(layers "F.Cu" "B.Cu")
		(net "GND")
	)
	(via
		(at 323.29882 -119.80164)
		(size 0.508)
		(drill 0.254)
		(layers "F.Cu" "B.Cu")
		(net "GND")
	)
	(via
		(at 313.699906 -9.156446)
		(size 0.508)
		(drill 0.254)
		(layers "F.Cu" "B.Cu")
		(net "GND")
	)
	(via
		(at 368.633756 -158.317692)
		(size 0.508)
		(drill 0.254)
		(layers "F.Cu" "B.Cu")
		(net "GND")
	)
	(via
		(at 407.7335 -50.1015)
		(size 0.508)
		(drill 0.254)
		(layers "F.Cu" "B.Cu")
		(net "GND")
	)
	(via
		(at 86.923372 -78.869286)
		(size 0.508)
		(drill 0.254)
		(layers "F.Cu" "B.Cu")
		(net "GND")
	)
	(via
		(at 145.52422 -57.94502)
		(size 0.508)
		(drill 0.254)
		(layers "F.Cu" "B.Cu")
		(net "GND")
	)
	(via
		(at 6.808724 -162.243262)
		(size 0.5588)
		(drill 0.3048)
		(layers "F.Cu" "B.Cu")
		(net "GND")
	)
	(via
		(at 21.337524 -162.243262)
		(size 0.5588)
		(drill 0.3048)
		(layers "F.Cu" "B.Cu")
		(net "GND")
	)
	(via
		(at 239.046258 -74.411586)
		(size 0.508)
		(drill 0.254)
		(layers "F.Cu" "B.Cu")
		(net "GND")
	)
	(via
		(at 139.34948 0.444754)
		(size 0.508)
		(drill 0.254)
		(layers "F.Cu" "B.Cu")
		(net "GND")
	)
	(via
		(at 251.065284 -89.27084)
		(size 0.508)
		(drill 0.254)
		(layers "F.Cu" "B.Cu")
		(net "GND")
	)
	(via
		(at 177.165 -12.319)
		(size 0.508)
		(drill 0.254)
		(layers "F.Cu" "B.Cu")
		(net "GND")
	)
	(via
		(at 218.436444 -141.1478)
		(size 0.508)
		(drill 0.254)
		(layers "F.Cu" "B.Cu")
		(net "GND")
	)
	(via
		(at 202.388724 -162.243262)
		(size 0.5588)
		(drill 0.3048)
		(layers "F.Cu" "B.Cu")
		(net "GND")
	)
	(via
		(at 142.749524 -129.568956)
		(size 0.508)
		(drill 0.254)
		(layers "F.Cu" "B.Cu")
		(net "GND")
	)
	(via
		(at 123.076208 -102.958138)
		(size 0.508)
		(drill 0.254)
		(layers "F.Cu" "B.Cu")
		(net "GND")
	)
	(via
		(at 241.621818 -61.038486)
		(size 0.508)
		(drill 0.254)
		(layers "F.Cu" "B.Cu")
		(net "GND")
	)
	(via
		(at 280.924254 -56.894984)
		(size 0.508)
		(drill 0.254)
		(layers "F.Cu" "B.Cu")
		(net "GND")
	)
	(via
		(at 465.561934 11.624056)
		(size 0.5588)
		(drill 0.3048)
		(layers "F.Cu" "B.Cu")
		(net "GND")
	)
	(via
		(at 201.041254 -143.950944)
		(size 0.508)
		(drill 0.254)
		(layers "F.Cu" "B.Cu")
		(net "GND")
	)
	(via
		(at 232.099866 -2.314956)
		(size 0.508)
		(drill 0.254)
		(layers "F.Cu" "B.Cu")
		(net "GND")
	)
	(via
		(at 345.5543 -102.1334)
		(size 0.508)
		(drill 0.254)
		(layers "F.Cu" "B.Cu")
		(net "GND")
	)
	(via
		(at 121.933208 -52.437538)
		(size 0.508)
		(drill 0.254)
		(layers "F.Cu" "B.Cu")
		(net "GND")
	)
	(via
		(at 100.659184 -56.085486)
		(size 0.508)
		(drill 0.254)
		(layers "F.Cu" "B.Cu")
		(net "GND")
	)
	(via
		(at 331.515974 -108.669836)
		(size 0.508)
		(drill 0.254)
		(layers "F.Cu" "B.Cu")
		(net "GND")
	)
	(via
		(at 449.948554 -60.378848)
		(size 0.508)
		(drill 0.254)
		(layers "F.Cu" "B.Cu")
		(net "GND")
	)
	(via
		(at 257.884422 -79.23657)
		(size 0.5588)
		(drill 0.3048)
		(layers "F.Cu" "B.Cu")
		(net "GND")
	)
	(via
		(at 42.9641 -56.7944)
		(size 0.508)
		(drill 0.254)
		(layers "F.Cu" "B.Cu")
		(net "GND")
	)
	(via
		(at 162.25266 -83.693)
		(size 0.508)
		(drill 0.254)
		(layers "F.Cu" "B.Cu")
		(net "GND")
	)
	(via
		(at 279.207214 -53.923184)
		(size 0.508)
		(drill 0.254)
		(layers "F.Cu" "B.Cu")
		(net "GND")
	)
	(via
		(at 249.661934 14.926056)
		(size 0.5588)
		(drill 0.3048)
		(layers "F.Cu" "B.Cu")
		(net "GND")
	)
	(via
		(at 289.049968 -2.314956)
		(size 0.508)
		(drill 0.254)
		(layers "F.Cu" "B.Cu")
		(net "GND")
	)
	(via
		(at 97.153476 -75.159616)
		(size 0.5588)
		(drill 0.3048)
		(layers "F.Cu" "B.Cu")
		(net "GND")
	)
	(via
		(at 8.47598 -1.31699)
		(size 0.508)
		(drill 0.254)
		(layers "F.Cu" "B.Cu")
		(net "GND")
	)
	(via
		(at 287.21812 -99.490784)
		(size 0.508)
		(drill 0.254)
		(layers "F.Cu" "B.Cu")
		(net "GND")
	)
	(via
		(at 399.674334 -92.837)
		(size 0.508)
		(drill 0.254)
		(layers "F.Cu" "B.Cu")
		(net "GND")
	)
	(via
		(at 275.036534 -167.832024)
		(size 0.5588)
		(drill 0.3048)
		(layers "F.Cu" "B.Cu")
		(net "GND")
	)
	(via
		(at 275.486114 -50.528474)
		(size 0.508)
		(drill 0.254)
		(layers "F.Cu" "B.Cu")
		(net "GND")
	)
	(via
		(at 396.270734 -166.714424)
		(size 0.5588)
		(drill 0.3048)
		(layers "F.Cu" "B.Cu")
		(net "GND")
	)
	(via
		(at 430.560734 -165.596824)
		(size 0.5588)
		(drill 0.3048)
		(layers "F.Cu" "B.Cu")
		(net "GND")
	)
	(via
		(at -3.474466 9.084056)
		(size 0.5588)
		(drill 0.3048)
		(layers "F.Cu" "B.Cu")
		(net "GND")
	)
	(via
		(at 349.911924 -162.243262)
		(size 0.5588)
		(drill 0.3048)
		(layers "F.Cu" "B.Cu")
		(net "GND")
	)
	(via
		(at 272.339308 -63.829184)
		(size 0.508)
		(drill 0.254)
		(layers "F.Cu" "B.Cu")
		(net "GND")
	)
	(via
		(at 199.749156 -16.7513)
		(size 0.508)
		(drill 0.254)
		(layers "F.Cu" "B.Cu")
		(net "GND")
	)
	(via
		(at 199.736456 -23.495)
		(size 0.508)
		(drill 0.254)
		(layers "F.Cu" "B.Cu")
		(net "GND")
	)
	(via
		(at 479.3742 -30.861)
		(size 0.508)
		(drill 0.254)
		(layers "F.Cu" "B.Cu")
		(net "GND")
	)
	(via
		(at 3.4798 -126.619)
		(size 0.508)
		(drill 0.254)
		(layers "F.Cu" "B.Cu")
		(net "GND")
	)
	(via
		(at 72.328786 -97.19564)
		(size 0.508)
		(drill 0.254)
		(layers "F.Cu" "B.Cu")
		(net "GND")
	)
	(via
		(at 389.7376 -106.6546)
		(size 0.508)
		(drill 0.254)
		(layers "F.Cu" "B.Cu")
		(net "GND")
	)
	(via
		(at 416.223196 -141.269212)
		(size 0.508)
		(drill 0.254)
		(layers "F.Cu" "B.Cu")
		(net "GND")
	)
	(via
		(at 129.999486 -9.156446)
		(size 0.508)
		(drill 0.254)
		(layers "F.Cu" "B.Cu")
		(net "GND")
	)
	(via
		(at 273.482308 -90.575384)
		(size 0.508)
		(drill 0.254)
		(layers "F.Cu" "B.Cu")
		(net "GND")
	)
	(via
		(at 144.449546 0.444754)
		(size 0.508)
		(drill 0.254)
		(layers "F.Cu" "B.Cu")
		(net "GND")
	)
	(via
		(at 379.201934 9.084056)
		(size 0.5588)
		(drill 0.3048)
		(layers "F.Cu" "B.Cu")
		(net "GND")
	)
	(via
		(at 77.286612 -131.016756)
		(size 0.508)
		(drill 0.254)
		(layers "F.Cu" "B.Cu")
		(net "GND")
	)
	(via
		(at 353.0854 -43.18)
		(size 0.508)
		(drill 0.254)
		(layers "F.Cu" "B.Cu")
		(net "GND")
	)
	(via
		(at 367.771934 14.926056)
		(size 0.5588)
		(drill 0.3048)
		(layers "F.Cu" "B.Cu")
		(net "GND")
	)
	(via
		(at 217.472006 -154.1018)
		(size 0.508)
		(drill 0.254)
		(layers "F.Cu" "B.Cu")
		(net "GND")
	)
	(via
		(at 139.387834 -67.791584)
		(size 0.508)
		(drill 0.254)
		(layers "F.Cu" "B.Cu")
		(net "GND")
	)
	(via
		(at 345.1606 -59.679586)
		(size 0.508)
		(drill 0.254)
		(layers "F.Cu" "B.Cu")
		(net "GND")
	)
	(via
		(at 136.74217 -21.513292)
		(size 0.508)
		(drill 0.254)
		(layers "F.Cu" "B.Cu")
		(net "GND")
	)
	(via
		(at 35.8902 -80.645)
		(size 0.508)
		(drill 0.254)
		(layers "F.Cu" "B.Cu")
		(net "GND")
	)
	(via
		(at 246.772684 -88.775286)
		(size 0.508)
		(drill 0.254)
		(layers "F.Cu" "B.Cu")
		(net "GND")
	)
	(via
		(at 457.399898 -113.777522)
		(size 0.508)
		(drill 0.254)
		(layers "F.Cu" "B.Cu")
		(net "GND")
	)
	(via
		(at 300.095666 -83.146138)
		(size 0.508)
		(drill 0.254)
		(layers "F.Cu" "B.Cu")
		(net "GND")
	)
	(via
		(at 294.9448 -72.249538)
		(size 0.508)
		(drill 0.254)
		(layers "F.Cu" "B.Cu")
		(net "GND")
	)
	(via
		(at 123.199398 -154.23642)
		(size 0.508)
		(drill 0.254)
		(layers "F.Cu" "B.Cu")
		(net "GND")
	)
	(via
		(at 290.679124 -162.243262)
		(size 0.5588)
		(drill 0.3048)
		(layers "F.Cu" "B.Cu")
		(net "GND")
	)
	(via
		(at 78.338172 -80.850486)
		(size 0.508)
		(drill 0.254)
		(layers "F.Cu" "B.Cu")
		(net "GND")
	)
	(via
		(at 168.522904 -11.505184)
		(size 0.508)
		(drill 0.254)
		(layers "F.Cu" "B.Cu")
		(net "GND")
	)
	(via
		(at 419.735 -146.2024)
		(size 0.508)
		(drill 0.254)
		(layers "F.Cu" "B.Cu")
		(net "GND")
	)
	(via
		(at 435.640734 -164.479224)
		(size 0.5588)
		(drill 0.3048)
		(layers "F.Cu" "B.Cu")
		(net "GND")
	)
	(via
		(at 118.499382 -58.381138)
		(size 0.508)
		(drill 0.254)
		(layers "F.Cu" "B.Cu")
		(net "GND")
	)
	(via
		(at 350.7486 -59.679586)
		(size 0.508)
		(drill 0.254)
		(layers "F.Cu" "B.Cu")
		(net "GND")
	)
	(via
		(at 200.881234 -92.002864)
		(size 0.508)
		(drill 0.254)
		(layers "F.Cu" "B.Cu")
		(net "GND")
	)
	(via
		(at 325.861934 14.926056)
		(size 0.5588)
		(drill 0.3048)
		(layers "F.Cu" "B.Cu")
		(net "GND")
	)
	(via
		(at 192.6336 -40.4368)
		(size 0.508)
		(drill 0.254)
		(layers "F.Cu" "B.Cu")
		(net "GND")
	)
	(via
		(at 198.772018 -7.6454)
		(size 0.508)
		(drill 0.254)
		(layers "F.Cu" "B.Cu")
		(net "GND")
	)
	(via
		(at 138.529314 -90.080338)
		(size 0.508)
		(drill 0.254)
		(layers "F.Cu" "B.Cu")
		(net "GND")
	)
	(via
		(at 301.858934 -167.832024)
		(size 0.5588)
		(drill 0.3048)
		(layers "F.Cu" "B.Cu")
		(net "GND")
	)
	(via
		(at 300.772068 -134.8994)
		(size 0.508)
		(drill 0.254)
		(layers "F.Cu" "B.Cu")
		(net "GND")
	)
	(via
		(at 238.187738 -86.794086)
		(size 0.508)
		(drill 0.254)
		(layers "F.Cu" "B.Cu")
		(net "GND")
	)
	(via
		(at 456.653392 -43.697398)
		(size 0.508)
		(drill 0.254)
		(layers "F.Cu" "B.Cu")
		(net "GND")
	)
	(via
		(at 352.2218 -32.6263)
		(size 0.508)
		(drill 0.254)
		(layers "F.Cu" "B.Cu")
		(net "GND")
	)
	(via
		(at 170.586146 -145.667222)
		(size 0.508)
		(drill 0.254)
		(layers "F.Cu" "B.Cu")
		(net "GND")
	)
	(via
		(at 303.044606 -145.9357)
		(size 0.508)
		(drill 0.254)
		(layers "F.Cu" "B.Cu")
		(net "GND")
	)
	(via
		(at 395.9352 -152.2222)
		(size 0.508)
		(drill 0.254)
		(layers "F.Cu" "B.Cu")
		(net "GND")
	)
	(via
		(at 219.731844 -2.3114)
		(size 0.508)
		(drill 0.254)
		(layers "F.Cu" "B.Cu")
		(net "GND")
	)
	(via
		(at 7.7216 -22.0472)
		(size 0.508)
		(drill 0.254)
		(layers "F.Cu" "B.Cu")
		(net "GND")
	)
	(via
		(at 46.699424 0.444754)
		(size 0.508)
		(drill 0.254)
		(layers "F.Cu" "B.Cu")
		(net "GND")
	)
	(via
		(at 2.276856 11.373866)
		(size 0.5588)
		(drill 0.3048)
		(layers "F.Cu" "B.Cu")
		(net "GND")
	)
	(via
		(at 499.851934 12.894056)
		(size 0.5588)
		(drill 0.3048)
		(layers "F.Cu" "B.Cu")
		(net "GND")
	)
	(via
		(at 20.3454 -107.95)
		(size 0.5588)
		(drill 0.3048)
		(layers "F.Cu" "B.Cu")
		(net "GND")
	)
	(via
		(at 348.258384 -137.131806)
		(size 0.508)
		(drill 0.254)
		(layers "F.Cu" "B.Cu")
		(net "GND")
	)
	(via
		(at 133.378194 -55.409338)
		(size 0.508)
		(drill 0.254)
		(layers "F.Cu" "B.Cu")
		(net "GND")
	)
	(via
		(at 390.824466 -156.372814)
		(size 0.508)
		(drill 0.254)
		(layers "F.Cu" "B.Cu")
		(net "GND")
	)
	(via
		(at 6.80212 -124.18314)
		(size 0.508)
		(drill 0.254)
		(layers "F.Cu" "B.Cu")
		(net "GND")
	)
	(via
		(at 301.742602 -11.912092)
		(size 0.508)
		(drill 0.254)
		(layers "F.Cu" "B.Cu")
		(net "GND")
	)
	(via
		(at 292.36924 -73.735184)
		(size 0.508)
		(drill 0.254)
		(layers "F.Cu" "B.Cu")
		(net "GND")
	)
	(via
		(at 219.744544 -155.5369)
		(size 0.508)
		(drill 0.254)
		(layers "F.Cu" "B.Cu")
		(net "GND")
	)
	(via
		(at 370.5352 -64.740028)
		(size 0.508)
		(drill 0.254)
		(layers "F.Cu" "B.Cu")
		(net "GND")
	)
	(via
		(at 107.059476 -75.159616)
		(size 0.5588)
		(drill 0.3048)
		(layers "F.Cu" "B.Cu")
		(net "GND")
	)
	(via
		(at 101.555296 -158.383986)
		(size 0.508)
		(drill 0.254)
		(layers "F.Cu" "B.Cu")
		(net "GND")
	)
	(via
		(at 213.7156 -61.1632)
		(size 0.508)
		(drill 0.254)
		(layers "F.Cu" "B.Cu")
		(net "GND")
	)
	(via
		(at 311.917334 -167.832024)
		(size 0.5588)
		(drill 0.3048)
		(layers "F.Cu" "B.Cu")
		(net "GND")
	)
	(via
		(at 215.0999 -2.314956)
		(size 0.508)
		(drill 0.254)
		(layers "F.Cu" "B.Cu")
		(net "GND")
	)
	(via
		(at 239.046258 -65.49644)
		(size 0.508)
		(drill 0.254)
		(layers "F.Cu" "B.Cu")
		(net "GND")
	)
	(via
		(at 215.0999 -21.517356)
		(size 0.508)
		(drill 0.254)
		(layers "F.Cu" "B.Cu")
		(net "GND")
	)
	(via
		(at 88.371934 9.084056)
		(size 0.5588)
		(drill 0.3048)
		(layers "F.Cu" "B.Cu")
		(net "GND")
	)
	(via
		(at 479.861372 -13.59662)
		(size 0.508)
		(drill 0.254)
		(layers "F.Cu" "B.Cu")
		(net "GND")
	)
	(via
		(at 490.961934 14.926056)
		(size 0.5588)
		(drill 0.3048)
		(layers "F.Cu" "B.Cu")
		(net "GND")
	)
	(via
		(at 35.499802 -65.9384)
		(size 0.508)
		(drill 0.254)
		(layers "F.Cu" "B.Cu")
		(net "GND")
	)
	(via
		(at 78.338172 -54.104286)
		(size 0.508)
		(drill 0.254)
		(layers "F.Cu" "B.Cu")
		(net "GND")
	)
	(via
		(at 432.541934 9.084056)
		(size 0.5588)
		(drill 0.3048)
		(layers "F.Cu" "B.Cu")
		(net "GND")
	)
	(via
		(at 461.899 -40.513)
		(size 0.508)
		(drill 0.254)
		(layers "F.Cu" "B.Cu")
		(net "GND")
	)
	(via
		(at 50.860452 -22.939756)
		(size 0.508)
		(drill 0.254)
		(layers "F.Cu" "B.Cu")
		(net "GND")
	)
	(via
		(at 203.1746 -76.5048)
		(size 0.5588)
		(drill 0.3048)
		(layers "F.Cu" "B.Cu")
		(net "GND")
	)
	(via
		(at 347.03131 -136.508998)
		(size 0.508)
		(drill 0.254)
		(layers "F.Cu" "B.Cu")
		(net "GND")
	)
	(via
		(at 415.0868 -2.4638)
		(size 0.508)
		(drill 0.254)
		(layers "F.Cu" "B.Cu")
		(net "GND")
	)
	(via
		(at 479.531934 14.926056)
		(size 0.5588)
		(drill 0.3048)
		(layers "F.Cu" "B.Cu")
		(net "GND")
	)
	(via
		(at 71.171562 -7.6454)
		(size 0.508)
		(drill 0.254)
		(layers "F.Cu" "B.Cu")
		(net "GND")
	)
	(via
		(at 42.11955 -61.504322)
		(size 0.5588)
		(drill 0.3048)
		(layers "F.Cu" "B.Cu")
		(net "GND")
	)
	(via
		(at 81.582768 -12.954)
		(size 0.508)
		(drill 0.254)
		(layers "F.Cu" "B.Cu")
		(net "GND")
	)
	(via
		(at 45.394118 -18.6817)
		(size 0.508)
		(drill 0.254)
		(layers "F.Cu" "B.Cu")
		(net "GND")
	)
	(via
		(at 339.1154 -113.665)
		(size 0.508)
		(drill 0.254)
		(layers "F.Cu" "B.Cu")
		(net "GND")
	)
	(via
		(at 236.171994 -144.5006)
		(size 0.508)
		(drill 0.254)
		(layers "F.Cu" "B.Cu")
		(net "GND")
	)
	(via
		(at 292.36924 -87.603584)
		(size 0.508)
		(drill 0.254)
		(layers "F.Cu" "B.Cu")
		(net "GND")
	)
	(via
		(at 412.221934 9.084056)
		(size 0.5588)
		(drill 0.3048)
		(layers "F.Cu" "B.Cu")
		(net "GND")
	)
	(via
		(at 197.918324 -162.243262)
		(size 0.5588)
		(drill 0.3048)
		(layers "F.Cu" "B.Cu")
		(net "GND")
	)
	(via
		(at 94.244668 -11.9126)
		(size 0.508)
		(drill 0.254)
		(layers "F.Cu" "B.Cu")
		(net "GND")
	)
	(via
		(at 216.761822 -21.517356)
		(size 0.508)
		(drill 0.254)
		(layers "F.Cu" "B.Cu")
		(net "GND")
	)
	(via
		(at 181.3306 -89.6112)
		(size 0.508)
		(drill 0.254)
		(layers "F.Cu" "B.Cu")
		(net "GND")
	)
	(via
		(at 281.399996 -9.156446)
		(size 0.508)
		(drill 0.254)
		(layers "F.Cu" "B.Cu")
		(net "GND")
	)
	(via
		(at 449.276978 -5.464048)
		(size 0.508)
		(drill 0.254)
		(layers "F.Cu" "B.Cu")
		(net "GND")
	)
	(via
		(at 28.6004 -93.0402)
		(size 0.508)
		(drill 0.254)
		(layers "F.Cu" "B.Cu")
		(net "GND")
	)
	(via
		(at 304.388266 -59.866784)
		(size 0.508)
		(drill 0.254)
		(layers "F.Cu" "B.Cu")
		(net "GND")
	)
	(via
		(at 292.36924 -90.575384)
		(size 0.508)
		(drill 0.254)
		(layers "F.Cu" "B.Cu")
		(net "GND")
	)
	(via
		(at 416.586924 -162.243262)
		(size 0.5588)
		(drill 0.3048)
		(layers "F.Cu" "B.Cu")
		(net "GND")
	)
	(via
		(at 445.241934 13.910056)
		(size 0.5588)
		(drill 0.3048)
		(layers "F.Cu" "B.Cu")
		(net "GND")
	)
	(via
		(at 442.214 -5.3848)
		(size 0.508)
		(drill 0.254)
		(layers "F.Cu" "B.Cu")
		(net "GND")
	)
	(via
		(at 246.772684 -65.991486)
		(size 0.508)
		(drill 0.254)
		(layers "F.Cu" "B.Cu")
		(net "GND")
	)
	(via
		(at 64.090804 -16.696944)
		(size 0.508)
		(drill 0.254)
		(layers "F.Cu" "B.Cu")
		(net "GND")
	)
	(via
		(at 184.658 -154.0764)
		(size 0.508)
		(drill 0.254)
		(layers "F.Cu" "B.Cu")
		(net "GND")
	)
	(via
		(at 8.9154 -115.2906)
		(size 0.508)
		(drill 0.254)
		(layers "F.Cu" "B.Cu")
		(net "GND")
	)
	(via
		(at 419.130734 -167.832024)
		(size 0.5588)
		(drill 0.3048)
		(layers "F.Cu" "B.Cu")
		(net "GND")
	)
	(via
		(at 66.249296 -154.063446)
		(size 0.508)
		(drill 0.254)
		(layers "F.Cu" "B.Cu")
		(net "GND")
	)
	(via
		(at 84.910168 -3.3528)
		(size 0.508)
		(drill 0.254)
		(layers "F.Cu" "B.Cu")
		(net "GND")
	)
	(via
		(at 239.046258 -99.17684)
		(size 0.508)
		(drill 0.254)
		(layers "F.Cu" "B.Cu")
		(net "GND")
	)
	(via
		(at 123.934728 -71.753984)
		(size 0.508)
		(drill 0.254)
		(layers "F.Cu" "B.Cu")
		(net "GND")
	)
	(via
		(at 483.338886 -56.69153)
		(size 0.508)
		(drill 0.254)
		(layers "F.Cu" "B.Cu")
		(net "GND")
	)
	(via
		(at 201.836528 -60.198)
		(size 0.5588)
		(drill 0.3048)
		(layers "F.Cu" "B.Cu")
		(net "GND")
	)
	(via
		(at 33.099502 0.444754)
		(size 0.508)
		(drill 0.254)
		(layers "F.Cu" "B.Cu")
		(net "GND")
	)
	(via
		(at 309.682134 -167.832024)
		(size 0.5588)
		(drill 0.3048)
		(layers "F.Cu" "B.Cu")
		(net "GND")
	)
	(via
		(at 267.376656 -95.709486)
		(size 0.508)
		(drill 0.254)
		(layers "F.Cu" "B.Cu")
		(net "GND")
	)
	(via
		(at 343.698068 -78.679294)
		(size 0.508)
		(drill 0.254)
		(layers "F.Cu" "B.Cu")
		(net "GND")
	)
	(via
		(at 235.612178 -74.411586)
		(size 0.508)
		(drill 0.254)
		(layers "F.Cu" "B.Cu")
		(net "GND")
	)
	(via
		(at 232.099866 -139.170156)
		(size 0.508)
		(drill 0.254)
		(layers "F.Cu" "B.Cu")
		(net "GND")
	)
	(via
		(at 4.41452 -23.53818)
		(size 0.508)
		(drill 0.254)
		(layers "F.Cu" "B.Cu")
		(net "GND")
	)
	(via
		(at 417.860734 -166.714424)
		(size 0.5588)
		(drill 0.3048)
		(layers "F.Cu" "B.Cu")
		(net "GND")
	)
	(via
		(at 289.049968 -18.744946)
		(size 0.508)
		(drill 0.254)
		(layers "F.Cu" "B.Cu")
		(net "GND")
	)
	(via
		(at 204.627734 -167.832024)
		(size 0.5588)
		(drill 0.3048)
		(layers "F.Cu" "B.Cu")
		(net "GND")
	)
	(via
		(at 200.8886 -82.804)
		(size 0.508)
		(drill 0.254)
		(layers "F.Cu" "B.Cu")
		(net "GND")
	)
	(via
		(at 33.099502 -155.612846)
		(size 0.508)
		(drill 0.254)
		(layers "F.Cu" "B.Cu")
		(net "GND")
	)
	(via
		(at 122.217688 -76.706984)
		(size 0.508)
		(drill 0.254)
		(layers "F.Cu" "B.Cu")
		(net "GND")
	)
	(via
		(at 234.753658 -65.991486)
		(size 0.508)
		(drill 0.254)
		(layers "F.Cu" "B.Cu")
		(net "GND")
	)
	(via
		(at 80.055212 -54.104286)
		(size 0.508)
		(drill 0.254)
		(layers "F.Cu" "B.Cu")
		(net "GND")
	)
	(via
		(at 134.236714 -72.744584)
		(size 0.508)
		(drill 0.254)
		(layers "F.Cu" "B.Cu")
		(net "GND")
	)
	(via
		(at 257.429 -134.4168)
		(size 0.508)
		(drill 0.254)
		(layers "F.Cu" "B.Cu")
		(net "GND")
	)
	(via
		(at 43.12158 -154.1018)
		(size 0.508)
		(drill 0.254)
		(layers "F.Cu" "B.Cu")
		(net "GND")
	)
	(via
		(at 346.0115 -101.38664)
		(size 0.508)
		(drill 0.254)
		(layers "F.Cu" "B.Cu")
		(net "GND")
	)
	(via
		(at 479.3742 -32.3342)
		(size 0.508)
		(drill 0.254)
		(layers "F.Cu" "B.Cu")
		(net "GND")
	)
	(via
		(at 131.544568 -125.9332)
		(size 0.508)
		(drill 0.254)
		(layers "F.Cu" "B.Cu")
		(net "GND")
	)
	(via
		(at 280.350214 -88.594184)
		(size 0.508)
		(drill 0.254)
		(layers "F.Cu" "B.Cu")
		(net "GND")
	)
	(via
		(at 305.246786 -73.240138)
		(size 0.508)
		(drill 0.254)
		(layers "F.Cu" "B.Cu")
		(net "GND")
	)
	(via
		(at 252.782324 -99.17684)
		(size 0.508)
		(drill 0.254)
		(layers "F.Cu" "B.Cu")
		(net "GND")
	)
	(via
		(at 368.745262 -70.295262)
		(size 0.4572)
		(drill 0.2032)
		(layers "F.Cu" "B.Cu")
		(net "GND")
	)
	(via
		(at 306.899818 -17.208246)
		(size 0.508)
		(drill 0.254)
		(layers "F.Cu" "B.Cu")
		(net "GND")
	)
	(via
		(at 130.802888 -82.650584)
		(size 0.508)
		(drill 0.254)
		(layers "F.Cu" "B.Cu")
		(net "GND")
	)
	(via
		(at 129.944368 -53.427884)
		(size 0.508)
		(drill 0.254)
		(layers "F.Cu" "B.Cu")
		(net "GND")
	)
	(via
		(at 258.551934 14.926056)
		(size 0.5588)
		(drill 0.3048)
		(layers "F.Cu" "B.Cu")
		(net "GND")
	)
	(via
		(at 44.086018 -150.749)
		(size 0.508)
		(drill 0.254)
		(layers "F.Cu" "B.Cu")
		(net "GND")
	)
	(via
		(at 358.15524 -152.546558)
		(size 0.5588)
		(drill 0.3048)
		(layers "F.Cu" "B.Cu")
		(net "GND")
	)
	(via
		(at 28.977336 -101.583998)
		(size 0.5588)
		(drill 0.3048)
		(layers "F.Cu" "B.Cu")
		(net "GND")
	)
	(via
		(at 358.155494 -0.553212)
		(size 0.5588)
		(drill 0.3048)
		(layers "F.Cu" "B.Cu")
		(net "GND")
	)
	(via
		(at 381.402082 -86.204806)
		(size 0.508)
		(drill 0.254)
		(layers "F.Cu" "B.Cu")
		(net "GND")
	)
	(via
		(at 469.371934 12.894056)
		(size 0.5588)
		(drill 0.3048)
		(layers "F.Cu" "B.Cu")
		(net "GND")
	)
	(via
		(at 159.491934 9.084056)
		(size 0.5588)
		(drill 0.3048)
		(layers "F.Cu" "B.Cu")
		(net "GND")
	)
	(via
		(at 251.923804 -70.94474)
		(size 0.508)
		(drill 0.254)
		(layers "F.Cu" "B.Cu")
		(net "GND")
	)
	(via
		(at 348.0054 -112.395)
		(size 0.508)
		(drill 0.254)
		(layers "F.Cu" "B.Cu")
		(net "GND")
	)
	(via
		(at 130.802888 -84.631784)
		(size 0.508)
		(drill 0.254)
		(layers "F.Cu" "B.Cu")
		(net "GND")
	)
	(via
		(at 239.046258 -62.52464)
		(size 0.508)
		(drill 0.254)
		(layers "F.Cu" "B.Cu")
		(net "GND")
	)
	(via
		(at 289.801808 -134.861046)
		(size 0.508)
		(drill 0.254)
		(layers "F.Cu" "B.Cu")
		(net "GND")
	)
	(via
		(at 421.09009 -31.73476)
		(size 0.4572)
		(drill 0.2032)
		(layers "F.Cu" "B.Cu")
		(net "GND")
	)
	(via
		(at 200.131934 9.084056)
		(size 0.5588)
		(drill 0.3048)
		(layers "F.Cu" "B.Cu")
		(net "GND")
	)
	(via
		(at 265.99388 -82.340196)
		(size 0.5588)
		(drill 0.3048)
		(layers "F.Cu" "B.Cu")
		(net "GND")
	)
	(via
		(at 431.271934 14.926056)
		(size 0.5588)
		(drill 0.3048)
		(layers "F.Cu" "B.Cu")
		(net "GND")
	)
	(via
		(at 309.411878 -2.314956)
		(size 0.508)
		(drill 0.254)
		(layers "F.Cu" "B.Cu")
		(net "GND")
	)
	(via
		(at 303.529746 -56.399938)
		(size 0.508)
		(drill 0.254)
		(layers "F.Cu" "B.Cu")
		(net "GND")
	)
	(via
		(at 416.406076 -128.980692)
		(size 0.508)
		(drill 0.254)
		(layers "F.Cu" "B.Cu")
		(net "GND")
	)
	(via
		(at 215.0999 -129.568956)
		(size 0.508)
		(drill 0.254)
		(layers "F.Cu" "B.Cu")
		(net "GND")
	)
	(via
		(at 129.011934 9.084056)
		(size 0.5588)
		(drill 0.3048)
		(layers "F.Cu" "B.Cu")
		(net "GND")
	)
	(via
		(at 110.33633 -135.357616)
		(size 0.508)
		(drill 0.254)
		(layers "F.Cu" "B.Cu")
		(net "GND")
	)
	(via
		(at 69.753226 -93.72854)
		(size 0.508)
		(drill 0.254)
		(layers "F.Cu" "B.Cu")
		(net "GND")
	)
	(via
		(at 200.153524 -162.243262)
		(size 0.5588)
		(drill 0.3048)
		(layers "F.Cu" "B.Cu")
		(net "GND")
	)
	(via
		(at 449.203064 -63.495682)
		(size 0.508)
		(drill 0.254)
		(layers "F.Cu" "B.Cu")
		(net "GND")
	)
	(via
		(at 403.861016 -154.430984)
		(size 0.508)
		(drill 0.254)
		(layers "F.Cu" "B.Cu")
		(net "GND")
	)
	(via
		(at 296.69994 -129.568956)
		(size 0.508)
		(drill 0.254)
		(layers "F.Cu" "B.Cu")
		(net "GND")
	)
	(via
		(at 199.039734 -167.832024)
		(size 0.5588)
		(drill 0.3048)
		(layers "F.Cu" "B.Cu")
		(net "GND")
	)
	(via
		(at 415.5186 -21.082)
		(size 0.508)
		(drill 0.254)
		(layers "F.Cu" "B.Cu")
		(net "GND")
	)
	(via
		(at 17.420336 -31.4706)
		(size 0.508)
		(drill 0.254)
		(layers "F.Cu" "B.Cu")
		(net "GND")
	)
	(via
		(at 294.9448 -96.023938)
		(size 0.508)
		(drill 0.254)
		(layers "F.Cu" "B.Cu")
		(net "GND")
	)
	(via
		(at 344.802206 1.555496)
		(size 0.508)
		(drill 0.254)
		(layers "F.Cu" "B.Cu")
		(net "GND")
	)
	(via
		(at 497.311934 12.894056)
		(size 0.5588)
		(drill 0.3048)
		(layers "F.Cu" "B.Cu")
		(net "GND")
	)
	(via
		(at 443.322456 -30.6324)
		(size 0.4572)
		(drill 0.2032)
		(layers "F.Cu" "B.Cu")
		(net "GND")
	)
	(via
		(at 374.015 -86.632796)
		(size 0.508)
		(drill 0.254)
		(layers "F.Cu" "B.Cu")
		(net "GND")
	)
	(via
		(at 182.9308 -140.9065)
		(size 0.508)
		(drill 0.254)
		(layers "F.Cu" "B.Cu")
		(net "GND")
	)
	(via
		(at 131.699508 -9.156446)
		(size 0.508)
		(drill 0.254)
		(layers "F.Cu" "B.Cu")
		(net "GND")
	)
	(via
		(at 248.210324 -162.243262)
		(size 0.5588)
		(drill 0.3048)
		(layers "F.Cu" "B.Cu")
		(net "GND")
	)
	(via
		(at 348.62389 -104.270048)
		(size 0.508)
		(drill 0.254)
		(layers "F.Cu" "B.Cu")
		(net "GND")
	)
	(via
		(at 71.470266 -51.132486)
		(size 0.508)
		(drill 0.254)
		(layers "F.Cu" "B.Cu")
		(net "GND")
	)
	(via
		(at 366.802924 -162.268662)
		(size 0.5588)
		(drill 0.3048)
		(layers "F.Cu" "B.Cu")
		(net "GND")
	)
	(via
		(at 276.916134 -94.538038)
		(size 0.508)
		(drill 0.254)
		(layers "F.Cu" "B.Cu")
		(net "GND")
	)
	(via
		(at 33.771586 -17.2466)
		(size 0.508)
		(drill 0.254)
		(layers "F.Cu" "B.Cu")
		(net "GND")
	)
	(via
		(at 414.528 -21.082)
		(size 0.508)
		(drill 0.254)
		(layers "F.Cu" "B.Cu")
		(net "GND")
	)
	(via
		(at 303.529746 -78.193138)
		(size 0.508)
		(drill 0.254)
		(layers "F.Cu" "B.Cu")
		(net "GND")
	)
	(via
		(at 163.296346 -29.746448)
		(size 0.508)
		(drill 0.254)
		(layers "F.Cu" "B.Cu")
		(net "GND")
	)
	(via
		(at 32.5374 -88.0618)
		(size 0.508)
		(drill 0.254)
		(layers "F.Cu" "B.Cu")
		(net "GND")
	)
	(via
		(at 0.60452 -23.53818)
		(size 0.508)
		(drill 0.254)
		(layers "F.Cu" "B.Cu")
		(net "GND")
	)
	(via
		(at 110.198916 -93.547184)
		(size 0.508)
		(drill 0.254)
		(layers "F.Cu" "B.Cu")
		(net "GND")
	)
	(via
		(at 80.913732 -71.44004)
		(size 0.508)
		(drill 0.254)
		(layers "F.Cu" "B.Cu")
		(net "GND")
	)
	(via
		(at 412.780734 -167.832024)
		(size 0.5588)
		(drill 0.3048)
		(layers "F.Cu" "B.Cu")
		(net "GND")
	)
	(via
		(at 190.40856 -109.676438)
		(size 0.508)
		(drill 0.254)
		(layers "F.Cu" "B.Cu")
		(net "GND")
	)
	(via
		(at 286.93364 -54.418738)
		(size 0.508)
		(drill 0.254)
		(layers "F.Cu" "B.Cu")
		(net "GND")
	)
	(via
		(at 276.916134 -99.490784)
		(size 0.508)
		(drill 0.254)
		(layers "F.Cu" "B.Cu")
		(net "GND")
	)
	(via
		(at 175.898302 -54.3052)
		(size 0.508)
		(drill 0.254)
		(layers "F.Cu" "B.Cu")
		(net "GND")
	)
	(via
		(at 9.047734 -166.714424)
		(size 0.5588)
		(drill 0.3048)
		(layers "F.Cu" "B.Cu")
		(net "GND")
	)
	(via
		(at 16.870934 -167.832024)
		(size 0.5588)
		(drill 0.3048)
		(layers "F.Cu" "B.Cu")
		(net "GND")
	)
	(via
		(at 485.170734 -167.832024)
		(size 0.5588)
		(drill 0.3048)
		(layers "F.Cu" "B.Cu")
		(net "GND")
	)
	(via
		(at -4.363466 -165.596824)
		(size 0.5588)
		(drill 0.3048)
		(layers "F.Cu" "B.Cu")
		(net "GND")
	)
	(via
		(at 477.550734 -165.596824)
		(size 0.5588)
		(drill 0.3048)
		(layers "F.Cu" "B.Cu")
		(net "GND")
	)
	(via
		(at 34.74212 -11.912092)
		(size 0.508)
		(drill 0.254)
		(layers "F.Cu" "B.Cu")
		(net "GND")
	)
	(via
		(at 343.753186 -77.156818)
		(size 0.508)
		(drill 0.254)
		(layers "F.Cu" "B.Cu")
		(net "GND")
	)
	(via
		(at 113.849404 -7.1374)
		(size 0.508)
		(drill 0.254)
		(layers "F.Cu" "B.Cu")
		(net "GND")
	)
	(via
		(at 265.659616 -56.085486)
		(size 0.508)
		(drill 0.254)
		(layers "F.Cu" "B.Cu")
		(net "GND")
	)
	(via
		(at 132.346192 -124.750576)
		(size 0.508)
		(drill 0.254)
		(layers "F.Cu" "B.Cu")
		(net "GND")
	)
	(via
		(at 224.261934 9.084056)
		(size 0.5588)
		(drill 0.3048)
		(layers "F.Cu" "B.Cu")
		(net "GND")
	)
	(via
		(at 402.620734 -167.832024)
		(size 0.5588)
		(drill 0.3048)
		(layers "F.Cu" "B.Cu")
		(net "GND")
	)
	(via
		(at 138.03757 -124.690886)
		(size 0.508)
		(drill 0.254)
		(layers "F.Cu" "B.Cu")
		(net "GND")
	)
	(via
		(at 123.934728 -80.669384)
		(size 0.508)
		(drill 0.254)
		(layers "F.Cu" "B.Cu")
		(net "GND")
	)
	(via
		(at 219.731844 -139.1666)
		(size 0.508)
		(drill 0.254)
		(layers "F.Cu" "B.Cu")
		(net "GND")
	)
	(via
		(at 357.611934 9.084056)
		(size 0.5588)
		(drill 0.3048)
		(layers "F.Cu" "B.Cu")
		(net "GND")
	)
	(via
		(at 56.899302 -140.617956)
		(size 0.508)
		(drill 0.254)
		(layers "F.Cu" "B.Cu")
		(net "GND")
	)
	(via
		(at 133.378194 -71.258938)
		(size 0.508)
		(drill 0.254)
		(layers "F.Cu" "B.Cu")
		(net "GND")
	)
	(via
		(at 471.200734 -167.832024)
		(size 0.5588)
		(drill 0.3048)
		(layers "F.Cu" "B.Cu")
		(net "GND")
	)
	(via
		(at 54.731412 -2.3114)
		(size 0.508)
		(drill 0.254)
		(layers "F.Cu" "B.Cu")
		(net "GND")
	)
	(via
		(at 353.0854 -40.64)
		(size 0.508)
		(drill 0.254)
		(layers "F.Cu" "B.Cu")
		(net "GND")
	)
	(via
		(at 288.93516 -101.471984)
		(size 0.508)
		(drill 0.254)
		(layers "F.Cu" "B.Cu")
		(net "GND")
	)
	(via
		(at 229.087934 -131.600956)
		(size 0.508)
		(drill 0.254)
		(layers "F.Cu" "B.Cu")
		(net "GND")
	)
	(via
		(at 177.927 -141.1605)
		(size 0.508)
		(drill 0.254)
		(layers "F.Cu" "B.Cu")
		(net "GND")
	)
	(via
		(at 101.804724 -162.243262)
		(size 0.5588)
		(drill 0.3048)
		(layers "F.Cu" "B.Cu")
		(net "GND")
	)
	(via
		(at 245.914164 -79.36484)
		(size 0.508)
		(drill 0.254)
		(layers "F.Cu" "B.Cu")
		(net "GND")
	)
	(via
		(at 368.662458 -42.625772)
		(size 0.508)
		(drill 0.254)
		(layers "F.Cu" "B.Cu")
		(net "GND")
	)
	(via
		(at 237.329218 -89.27084)
		(size 0.508)
		(drill 0.254)
		(layers "F.Cu" "B.Cu")
		(net "GND")
	)
	(via
		(at 459.211934 10.354056)
		(size 0.5588)
		(drill 0.3048)
		(layers "F.Cu" "B.Cu")
		(net "GND")
	)
	(via
		(at 371.581934 14.926056)
		(size 0.5588)
		(drill 0.3048)
		(layers "F.Cu" "B.Cu")
		(net "GND")
	)
	(via
		(at 339.858604 -143.087598)
		(size 0.508)
		(drill 0.254)
		(layers "F.Cu" "B.Cu")
		(net "GND")
	)
	(via
		(at 35.031934 9.084056)
		(size 0.5588)
		(drill 0.3048)
		(layers "F.Cu" "B.Cu")
		(net "GND")
	)
	(via
		(at 494.060734 -165.596824)
		(size 0.5588)
		(drill 0.3048)
		(layers "F.Cu" "B.Cu")
		(net "GND")
	)
	(via
		(at 126.510288 -92.061538)
		(size 0.508)
		(drill 0.254)
		(layers "F.Cu" "B.Cu")
		(net "GND")
	)
	(via
		(at 318.241934 9.084056)
		(size 0.5588)
		(drill 0.3048)
		(layers "F.Cu" "B.Cu")
		(net "GND")
	)
	(via
		(at 54.744112 -155.5369)
		(size 0.508)
		(drill 0.254)
		(layers "F.Cu" "B.Cu")
		(net "GND")
	)
	(via
		(at 221.04985 -155.612846)
		(size 0.508)
		(drill 0.254)
		(layers "F.Cu" "B.Cu")
		(net "GND")
	)
	(via
		(at 201.796396 -53.711602)
		(size 0.5588)
		(drill 0.3048)
		(layers "F.Cu" "B.Cu")
		(net "GND")
	)
	(via
		(at 138.529314 -100.976684)
		(size 0.508)
		(drill 0.254)
		(layers "F.Cu" "B.Cu")
		(net "GND")
	)
	(via
		(at 435.081934 10.354056)
		(size 0.5588)
		(drill 0.3048)
		(layers "F.Cu" "B.Cu")
		(net "GND")
	)
	(via
		(at 135.771636 -131.016756)
		(size 0.508)
		(drill 0.254)
		(layers "F.Cu" "B.Cu")
		(net "GND")
	)
	(via
		(at 38.199314 -22.965156)
		(size 0.508)
		(drill 0.254)
		(layers "F.Cu" "B.Cu")
		(net "GND")
	)
	(via
		(at 449.610734 -165.596824)
		(size 0.5588)
		(drill 0.3048)
		(layers "F.Cu" "B.Cu")
		(net "GND")
	)
	(via
		(at 177.96256 -17.653)
		(size 0.508)
		(drill 0.254)
		(layers "F.Cu" "B.Cu")
		(net "GND")
	)
	(via
		(at 38.841934 9.084056)
		(size 0.5588)
		(drill 0.3048)
		(layers "F.Cu" "B.Cu")
		(net "GND")
	)
	(via
		(at 55.986934 -167.832024)
		(size 0.5588)
		(drill 0.3048)
		(layers "F.Cu" "B.Cu")
		(net "GND")
	)
	(via
		(at 300.772068 -131.016756)
		(size 0.508)
		(drill 0.254)
		(layers "F.Cu" "B.Cu")
		(net "GND")
	)
	(via
		(at 196.743828 -53.856382)
		(size 0.508)
		(drill 0.254)
		(layers "F.Cu" "B.Cu")
		(net "GND")
	)
	(via
		(at 107.623356 -98.005138)
		(size 0.508)
		(drill 0.254)
		(layers "F.Cu" "B.Cu")
		(net "GND")
	)
	(via
		(at 406.690068 -43.73499)
		(size 0.4572)
		(drill 0.2032)
		(layers "F.Cu" "B.Cu")
		(net "GND")
	)
	(via
		(at 477.2533 -34.8996)
		(size 0.508)
		(drill 0.254)
		(layers "F.Cu" "B.Cu")
		(net "GND")
	)
	(via
		(at 211.699856 -11.916156)
		(size 0.508)
		(drill 0.254)
		(layers "F.Cu" "B.Cu")
		(net "GND")
	)
	(via
		(at 130.84937 -150.219156)
		(size 0.508)
		(drill 0.254)
		(layers "F.Cu" "B.Cu")
		(net "GND")
	)
	(via
		(at 17.984724 -162.243262)
		(size 0.5588)
		(drill 0.3048)
		(layers "F.Cu" "B.Cu")
		(net "GND")
	)
	(via
		(at 288.93516 -94.538038)
		(size 0.508)
		(drill 0.254)
		(layers "F.Cu" "B.Cu")
		(net "GND")
	)
	(via
		(at 98.455734 -167.832024)
		(size 0.5588)
		(drill 0.3048)
		(layers "F.Cu" "B.Cu")
		(net "GND")
	)
	(via
		(at 284.358334 -63.829184)
		(size 0.508)
		(drill 0.254)
		(layers "F.Cu" "B.Cu")
		(net "GND")
	)
	(via
		(at 428.731934 13.910056)
		(size 0.5588)
		(drill 0.3048)
		(layers "F.Cu" "B.Cu")
		(net "GND")
	)
	(via
		(at 217.472006 -22.965156)
		(size 0.508)
		(drill 0.254)
		(layers "F.Cu" "B.Cu")
		(net "GND")
	)
	(via
		(at 75.762866 -67.47764)
		(size 0.508)
		(drill 0.254)
		(layers "F.Cu" "B.Cu")
		(net "GND")
	)
	(via
		(at 158.802324 -162.243262)
		(size 0.5588)
		(drill 0.3048)
		(layers "F.Cu" "B.Cu")
		(net "GND")
	)
	(via
		(at 344.802206 2.673096)
		(size 0.508)
		(drill 0.254)
		(layers "F.Cu" "B.Cu")
		(net "GND")
	)
	(via
		(at 458.541628 -14.44752)
		(size 0.5588)
		(drill 0.3048)
		(layers "F.Cu" "B.Cu")
		(net "GND")
	)
	(via
		(at 35.499802 -64.9478)
		(size 0.508)
		(drill 0.254)
		(layers "F.Cu" "B.Cu")
		(net "GND")
	)
	(via
		(at 39.231316 -49.027334)
		(size 0.508)
		(drill 0.254)
		(layers "F.Cu" "B.Cu")
		(net "GND")
	)
	(via
		(at 365.485172 -3.437382)
		(size 0.508)
		(drill 0.254)
		(layers "F.Cu" "B.Cu")
		(net "GND")
	)
	(via
		(at 232.099866 -155.562046)
		(size 0.508)
		(drill 0.254)
		(layers "F.Cu" "B.Cu")
		(net "GND")
	)
	(via
		(at 259.65023 -60.54344)
		(size 0.508)
		(drill 0.254)
		(layers "F.Cu" "B.Cu")
		(net "GND")
	)
	(via
		(at 166.5986 -80.391)
		(size 0.508)
		(drill 0.254)
		(layers "F.Cu" "B.Cu")
		(net "GND")
	)
	(via
		(at 246.565674 -149.8092)
		(size 0.508)
		(drill 0.254)
		(layers "F.Cu" "B.Cu")
		(net "GND")
	)
	(via
		(at 232.94975 1.994154)
		(size 0.508)
		(drill 0.254)
		(layers "F.Cu" "B.Cu")
		(net "GND")
	)
	(via
		(at 484.989124 -19.50466)
		(size 0.508)
		(drill 0.254)
		(layers "F.Cu" "B.Cu")
		(net "GND")
	)
	(via
		(at 113.901728 -136.327642)
		(size 0.508)
		(drill 0.254)
		(layers "F.Cu" "B.Cu")
		(net "GND")
	)
	(via
		(at 466.2297 -118.58498)
		(size 0.508)
		(drill 0.254)
		(layers "F.Cu" "B.Cu")
		(net "GND")
	)
	(via
		(at 40.038782 -68.256658)
		(size 0.5588)
		(drill 0.3048)
		(layers "F.Cu" "B.Cu")
		(net "GND")
	)
	(via
		(at 339.852 -143.8402)
		(size 0.508)
		(drill 0.254)
		(layers "F.Cu" "B.Cu")
		(net "GND")
	)
	(via
		(at 72.1487 -134.4041)
		(size 0.508)
		(drill 0.254)
		(layers "F.Cu" "B.Cu")
		(net "GND")
	)
	(via
		(at 115.451382 -134.861046)
		(size 0.508)
		(drill 0.254)
		(layers "F.Cu" "B.Cu")
		(net "GND")
	)
	(via
		(at 74.904346 -84.812886)
		(size 0.508)
		(drill 0.254)
		(layers "F.Cu" "B.Cu")
		(net "GND")
	)
	(via
		(at 215.85174 -7.607046)
		(size 0.508)
		(drill 0.254)
		(layers "F.Cu" "B.Cu")
		(net "GND")
	)
	(via
		(at 448.8815 -25.273)
		(size 0.508)
		(drill 0.254)
		(layers "F.Cu" "B.Cu")
		(net "GND")
	)
	(via
		(at 103.401876 -70.84314)
		(size 0.5588)
		(drill 0.3048)
		(layers "F.Cu" "B.Cu")
		(net "GND")
	)
	(via
		(at 6.9088 -7.7724)
		(size 0.508)
		(drill 0.254)
		(layers "F.Cu" "B.Cu")
		(net "GND")
	)
	(via
		(at 272.027904 -145.0086)
		(size 0.508)
		(drill 0.254)
		(layers "F.Cu" "B.Cu")
		(net "GND")
	)
	(via
		(at 307.749956 -18.744946)
		(size 0.508)
		(drill 0.254)
		(layers "F.Cu" "B.Cu")
		(net "GND")
	)
	(via
		(at 62.782958 -126.622556)
		(size 0.508)
		(drill 0.254)
		(layers "F.Cu" "B.Cu")
		(net "GND")
	)
	(via
		(at 124.793248 -86.117938)
		(size 0.508)
		(drill 0.254)
		(layers "F.Cu" "B.Cu")
		(net "GND")
	)
	(via
		(at 214.101934 14.926056)
		(size 0.5588)
		(drill 0.3048)
		(layers "F.Cu" "B.Cu")
		(net "GND")
	)
	(via
		(at 493.501934 9.084056)
		(size 0.5588)
		(drill 0.3048)
		(layers "F.Cu" "B.Cu")
		(net "GND")
	)
	(via
		(at 375.495566 -155.364434)
		(size 0.508)
		(drill 0.254)
		(layers "F.Cu" "B.Cu")
		(net "GND")
	)
	(via
		(at 125.651768 -92.556584)
		(size 0.508)
		(drill 0.254)
		(layers "F.Cu" "B.Cu")
		(net "GND")
	)
	(via
		(at 78.338934 -167.832024)
		(size 0.5588)
		(drill 0.3048)
		(layers "F.Cu" "B.Cu")
		(net "GND")
	)
	(via
		(at 349.377 -136.580118)
		(size 0.508)
		(drill 0.254)
		(layers "F.Cu" "B.Cu")
		(net "GND")
	)
	(via
		(at 279.039574 -13.940282)
		(size 0.508)
		(drill 0.254)
		(layers "F.Cu" "B.Cu")
		(net "GND")
	)
	(via
		(at 289.79368 -94.042738)
		(size 0.508)
		(drill 0.254)
		(layers "F.Cu" "B.Cu")
		(net "GND")
	)
	(via
		(at 138.031474 -21.5138)
		(size 0.508)
		(drill 0.254)
		(layers "F.Cu" "B.Cu")
		(net "GND")
	)
	(via
		(at 305.047396 -124.648976)
		(size 0.508)
		(drill 0.254)
		(layers "F.Cu" "B.Cu")
		(net "GND")
	)
	(via
		(at 76.449428 -21.517356)
		(size 0.508)
		(drill 0.254)
		(layers "F.Cu" "B.Cu")
		(net "GND")
	)
	(via
		(at 303.529746 -68.287138)
		(size 0.508)
		(drill 0.254)
		(layers "F.Cu" "B.Cu")
		(net "GND")
	)
	(via
		(at 349.991934 9.084056)
		(size 0.5588)
		(drill 0.3048)
		(layers "F.Cu" "B.Cu")
		(net "GND")
	)
	(via
		(at 349.048578 -98.416872)
		(size 0.508)
		(drill 0.254)
		(layers "F.Cu" "B.Cu")
		(net "GND")
	)
	(via
		(at 95.324676 -75.159616)
		(size 0.5588)
		(drill 0.3048)
		(layers "F.Cu" "B.Cu")
		(net "GND")
	)
	(via
		(at 366.9792 -112.395)
		(size 0.508)
		(drill 0.254)
		(layers "F.Cu" "B.Cu")
		(net "GND")
	)
	(via
		(at 74.045826 -95.21444)
		(size 0.508)
		(drill 0.254)
		(layers "F.Cu" "B.Cu")
		(net "GND")
	)
	(via
		(at 276.631654 -61.352938)
		(size 0.508)
		(drill 0.254)
		(layers "F.Cu" "B.Cu")
		(net "GND")
	)
	(via
		(at 169.6974 -58.9788)
		(size 0.508)
		(drill 0.254)
		(layers "F.Cu" "B.Cu")
		(net "GND")
	)
	(via
		(at 372.851934 9.084056)
		(size 0.5588)
		(drill 0.3048)
		(layers "F.Cu" "B.Cu")
		(net "GND")
	)
	(via
		(at 197.5104 -88.0364)
		(size 0.508)
		(drill 0.254)
		(layers "F.Cu" "B.Cu")
		(net "GND")
	)
	(via
		(at 250.931934 9.084056)
		(size 0.5588)
		(drill 0.3048)
		(layers "F.Cu" "B.Cu")
		(net "GND")
	)
	(via
		(at 263.860534 -167.832024)
		(size 0.5588)
		(drill 0.3048)
		(layers "F.Cu" "B.Cu")
		(net "GND")
	)
	(via
		(at 35.500818 -92.680282)
		(size 0.5588)
		(drill 0.3048)
		(layers "F.Cu" "B.Cu")
		(net "GND")
	)
	(via
		(at 298.378626 -76.211938)
		(size 0.508)
		(drill 0.254)
		(layers "F.Cu" "B.Cu")
		(net "GND")
	)
	(via
		(at 321.0052 -154.1272)
		(size 0.508)
		(drill 0.254)
		(layers "F.Cu" "B.Cu")
		(net "GND")
	)
	(via
		(at 300.099984 -136.410446)
		(size 0.508)
		(drill 0.254)
		(layers "F.Cu" "B.Cu")
		(net "GND")
	)
	(via
		(at 103.859076 -82.339942)
		(size 0.5588)
		(drill 0.3048)
		(layers "F.Cu" "B.Cu")
		(net "GND")
	)
	(via
		(at 113.923318 -11.93165)
		(size 0.508)
		(drill 0.254)
		(layers "F.Cu" "B.Cu")
		(net "GND")
	)
	(via
		(at 46.699424 -136.410446)
		(size 0.508)
		(drill 0.254)
		(layers "F.Cu" "B.Cu")
		(net "GND")
	)
	(via
		(at 210.38185 -139.1666)
		(size 0.508)
		(drill 0.254)
		(layers "F.Cu" "B.Cu")
		(net "GND")
	)
	(via
		(at 237.329218 -70.44944)
		(size 0.508)
		(drill 0.254)
		(layers "F.Cu" "B.Cu")
		(net "GND")
	)
	(via
		(at 354.26904 -100.25888)
		(size 0.508)
		(drill 0.254)
		(layers "F.Cu" "B.Cu")
		(net "GND")
	)
	(via
		(at 121.359168 -91.070938)
		(size 0.508)
		(drill 0.254)
		(layers "F.Cu" "B.Cu")
		(net "GND")
	)
	(via
		(at 291.51072 -83.146138)
		(size 0.508)
		(drill 0.254)
		(layers "F.Cu" "B.Cu")
		(net "GND")
	)
	(via
		(at 403.5298 -23.949152)
		(size 0.508)
		(drill 0.254)
		(layers "F.Cu" "B.Cu")
		(net "GND")
	)
	(via
		(at 59.161934 9.084056)
		(size 0.5588)
		(drill 0.3048)
		(layers "F.Cu" "B.Cu")
		(net "GND")
	)
	(via
		(at 300.061884 -148.771356)
		(size 0.508)
		(drill 0.254)
		(layers "F.Cu" "B.Cu")
		(net "GND")
	)
	(via
		(at 286.3596 -92.061538)
		(size 0.508)
		(drill 0.254)
		(layers "F.Cu" "B.Cu")
		(net "GND")
	)
	(via
		(at 237.149132 -134.4041)
		(size 0.508)
		(drill 0.254)
		(layers "F.Cu" "B.Cu")
		(net "GND")
	)
	(via
		(at 176.7332 -78.232)
		(size 0.508)
		(drill 0.254)
		(layers "F.Cu" "B.Cu")
		(net "GND")
	)
	(via
		(at 19.366738 -0.302006)
		(size 0.508)
		(drill 0.254)
		(layers "F.Cu" "B.Cu")
		(net "GND")
	)
	(via
		(at 181.158134 -167.832024)
		(size 0.5588)
		(drill 0.3048)
		(layers "F.Cu" "B.Cu")
		(net "GND")
	)
	(via
		(at 377.298966 -151.783034)
		(size 0.508)
		(drill 0.254)
		(layers "F.Cu" "B.Cu")
		(net "GND")
	)
	(via
		(at 298.378626 -60.362338)
		(size 0.508)
		(drill 0.254)
		(layers "F.Cu" "B.Cu")
		(net "GND")
	)
	(via
		(at 193.781934 14.926056)
		(size 0.5588)
		(drill 0.3048)
		(layers "F.Cu" "B.Cu")
		(net "GND")
	)
	(via
		(at 44.092114 -18.744946)
		(size 0.508)
		(drill 0.254)
		(layers "F.Cu" "B.Cu")
		(net "GND")
	)
	(via
		(at 374.0912 -106.855006)
		(size 0.508)
		(drill 0.254)
		(layers "F.Cu" "B.Cu")
		(net "GND")
	)
	(via
		(at 83.489292 -87.784686)
		(size 0.508)
		(drill 0.254)
		(layers "F.Cu" "B.Cu")
		(net "GND")
	)
	(via
		(at 178.2572 -62.60592)
		(size 0.508)
		(drill 0.254)
		(layers "F.Cu" "B.Cu")
		(net "GND")
	)
	(via
		(at 295.80332 -94.538038)
		(size 0.508)
		(drill 0.254)
		(layers "F.Cu" "B.Cu")
		(net "GND")
	)
	(via
		(at 200.284588 -51.903122)
		(size 0.5588)
		(drill 0.3048)
		(layers "F.Cu" "B.Cu")
		(net "GND")
	)
	(via
		(at 44.092114 -11.912092)
		(size 0.508)
		(drill 0.254)
		(layers "F.Cu" "B.Cu")
		(net "GND")
	)
	(via
		(at 267.948156 -88.138)
		(size 0.508)
		(drill 0.254)
		(layers "F.Cu" "B.Cu")
		(net "GND")
	)
	(via
		(at 67.949318 1.994154)
		(size 0.508)
		(drill 0.254)
		(layers "F.Cu" "B.Cu")
		(net "GND")
	)
	(via
		(at 124.793248 -91.070938)
		(size 0.508)
		(drill 0.254)
		(layers "F.Cu" "B.Cu")
		(net "GND")
	)
	(via
		(at 117.581934 14.926056)
		(size 0.5588)
		(drill 0.3048)
		(layers "F.Cu" "B.Cu")
		(net "GND")
	)
	(via
		(at 52.471574 -17.2466)
		(size 0.508)
		(drill 0.254)
		(layers "F.Cu" "B.Cu")
		(net "GND")
	)
	(via
		(at 46.699424 -2.314956)
		(size 0.508)
		(drill 0.254)
		(layers "F.Cu" "B.Cu")
		(net "GND")
	)
	(via
		(at 484.599996 -115.423188)
		(size 0.508)
		(drill 0.254)
		(layers "F.Cu" "B.Cu")
		(net "GND")
	)
	(via
		(at 311.0992 -7.1374)
		(size 0.508)
		(drill 0.254)
		(layers "F.Cu" "B.Cu")
		(net "GND")
	)
	(via
		(at 108.540296 -158.379414)
		(size 0.508)
		(drill 0.254)
		(layers "F.Cu" "B.Cu")
		(net "GND")
	)
	(via
		(at 134.15137 1.994154)
		(size 0.508)
		(drill 0.254)
		(layers "F.Cu" "B.Cu")
		(net "GND")
	)
	(via
		(at 386.74675 -123.821444)
		(size 0.508)
		(drill 0.254)
		(layers "F.Cu" "B.Cu")
		(net "GND")
	)
	(via
		(at 412.780734 -166.714424)
		(size 0.5588)
		(drill 0.3048)
		(layers "F.Cu" "B.Cu")
		(net "GND")
	)
	(via
		(at 234.753658 -84.812886)
		(size 0.508)
		(drill 0.254)
		(layers "F.Cu" "B.Cu")
		(net "GND")
	)
	(via
		(at 198.061834 -11.916156)
		(size 0.508)
		(drill 0.254)
		(layers "F.Cu" "B.Cu")
		(net "GND")
	)
	(via
		(at 334.858614 -15.24)
		(size 0.508)
		(drill 0.254)
		(layers "F.Cu" "B.Cu")
		(net "GND")
	)
	(via
		(at 35.880802 -92.002864)
		(size 0.508)
		(drill 0.254)
		(layers "F.Cu" "B.Cu")
		(net "GND")
	)
	(via
		(at 40.749474 -18.744946)
		(size 0.508)
		(drill 0.254)
		(layers "F.Cu" "B.Cu")
		(net "GND")
	)
	(via
		(at 200.8886 -97.8662)
		(size 0.508)
		(drill 0.254)
		(layers "F.Cu" "B.Cu")
		(net "GND")
	)
	(via
		(at 265.659616 -53.113686)
		(size 0.508)
		(drill 0.254)
		(layers "F.Cu" "B.Cu")
		(net "GND")
	)
	(via
		(at 60.210446 -13.338556)
		(size 0.508)
		(drill 0.254)
		(layers "F.Cu" "B.Cu")
		(net "GND")
	)
	(via
		(at 80.055212 -90.756486)
		(size 0.508)
		(drill 0.254)
		(layers "F.Cu" "B.Cu")
		(net "GND")
	)
	(via
		(at 67.099434 -11.916156)
		(size 0.508)
		(drill 0.254)
		(layers "F.Cu" "B.Cu")
		(net "GND")
	)
	(via
		(at 494.771934 9.084056)
		(size 0.5588)
		(drill 0.3048)
		(layers "F.Cu" "B.Cu")
		(net "GND")
	)
	(via
		(at 383.011934 9.084056)
		(size 0.5588)
		(drill 0.3048)
		(layers "F.Cu" "B.Cu")
		(net "GND")
	)
	(via
		(at 5.434838 -111.595916)
		(size 0.508)
		(drill 0.254)
		(layers "F.Cu" "B.Cu")
		(net "GND")
	)
	(via
		(at 49.24933 1.994154)
		(size 0.508)
		(drill 0.254)
		(layers "F.Cu" "B.Cu")
		(net "GND")
	)
	(via
		(at 295.80332 -72.744584)
		(size 0.508)
		(drill 0.254)
		(layers "F.Cu" "B.Cu")
		(net "GND")
	)
	(via
		(at 135.953754 -67.791584)
		(size 0.508)
		(drill 0.254)
		(layers "F.Cu" "B.Cu")
		(net "GND")
	)
	(via
		(at 380.214124 -162.268662)
		(size 0.5588)
		(drill 0.3048)
		(layers "F.Cu" "B.Cu")
		(net "GND")
	)
	(via
		(at 234.753658 -57.076086)
		(size 0.508)
		(drill 0.254)
		(layers "F.Cu" "B.Cu")
		(net "GND")
	)
	(via
		(at 140.246354 -59.371484)
		(size 0.508)
		(drill 0.254)
		(layers "F.Cu" "B.Cu")
		(net "GND")
	)
	(via
		(at 123.076208 -92.061538)
		(size 0.508)
		(drill 0.254)
		(layers "F.Cu" "B.Cu")
		(net "GND")
	)
	(via
		(at 83.489292 -84.812886)
		(size 0.508)
		(drill 0.254)
		(layers "F.Cu" "B.Cu")
		(net "GND")
	)
	(via
		(at 384.82778 -133.90118)
		(size 0.6604)
		(drill 0.3302)
		(layers "F.Cu" "B.Cu")
		(net "GND")
	)
	(via
		(at 66.249296 -134.861046)
		(size 0.508)
		(drill 0.254)
		(layers "F.Cu" "B.Cu")
		(net "GND")
	)
	(via
		(at 45.381418 -139.1666)
		(size 0.508)
		(drill 0.254)
		(layers "F.Cu" "B.Cu")
		(net "GND")
	)
	(via
		(at 31.399734 -167.832024)
		(size 0.5588)
		(drill 0.3048)
		(layers "F.Cu" "B.Cu")
		(net "GND")
	)
	(via
		(at 69.56044 -130.991356)
		(size 0.508)
		(drill 0.254)
		(layers "F.Cu" "B.Cu")
		(net "GND")
	)
	(via
		(at 58.218324 -162.243262)
		(size 0.5588)
		(drill 0.3048)
		(layers "F.Cu" "B.Cu")
		(net "GND")
	)
	(via
		(at 117.451124 -162.243262)
		(size 0.5588)
		(drill 0.3048)
		(layers "F.Cu" "B.Cu")
		(net "GND")
	)
	(via
		(at 178.541934 14.926056)
		(size 0.5588)
		(drill 0.3048)
		(layers "F.Cu" "B.Cu")
		(net "GND")
	)
	(via
		(at 366.806734 -167.857424)
		(size 0.5588)
		(drill 0.3048)
		(layers "F.Cu" "B.Cu")
		(net "GND")
	)
	(via
		(at 243.149882 -145.988278)
		(size 0.508)
		(drill 0.254)
		(layers "F.Cu" "B.Cu")
		(net "GND")
	)
	(via
		(at 371.9322 -102.8446)
		(size 0.508)
		(drill 0.254)
		(layers "F.Cu" "B.Cu")
		(net "GND")
	)
	(via
		(at 282.57881 -80.103726)
		(size 0.5588)
		(drill 0.3048)
		(layers "F.Cu" "B.Cu")
		(net "GND")
	)
	(via
		(at 287.21812 -87.603584)
		(size 0.508)
		(drill 0.254)
		(layers "F.Cu" "B.Cu")
		(net "GND")
	)
	(via
		(at 128.690878 -134.349744)
		(size 0.508)
		(drill 0.254)
		(layers "F.Cu" "B.Cu")
		(net "GND")
	)
	(via
		(at 31.39948 -21.517356)
		(size 0.508)
		(drill 0.254)
		(layers "F.Cu" "B.Cu")
		(net "GND")
	)
	(via
		(at -2.438146 -155.10002)
		(size 0.5588)
		(drill 0.3048)
		(layers "F.Cu" "B.Cu")
		(net "GND")
	)
	(via
		(at 178.569112 -125.8824)
		(size 0.508)
		(drill 0.254)
		(layers "F.Cu" "B.Cu")
		(net "GND")
	)
	(via
		(at 249.348244 -92.24264)
		(size 0.508)
		(drill 0.254)
		(layers "F.Cu" "B.Cu")
		(net "GND")
	)
	(via
		(at 376.71121 -115.412266)
		(size 0.508)
		(drill 0.254)
		(layers "F.Cu" "B.Cu")
		(net "GND")
	)
	(via
		(at 378.817378 -65.621662)
		(size 0.508)
		(drill 0.254)
		(layers "F.Cu" "B.Cu")
		(net "GND")
	)
	(via
		(at 147.399756 0.508)
		(size 0.508)
		(drill 0.254)
		(layers "F.Cu" "B.Cu")
		(net "GND")
	)
	(via
		(at 121.921524 -162.243262)
		(size 0.5588)
		(drill 0.3048)
		(layers "F.Cu" "B.Cu")
		(net "GND")
	)
	(via
		(at 292.918134 -167.832024)
		(size 0.5588)
		(drill 0.3048)
		(layers "F.Cu" "B.Cu")
		(net "GND")
	)
	(via
		(at 92.932758 -87.28964)
		(size 0.508)
		(drill 0.254)
		(layers "F.Cu" "B.Cu")
		(net "GND")
	)
	(via
		(at 292.396672 -124.680218)
		(size 0.508)
		(drill 0.254)
		(layers "F.Cu" "B.Cu")
		(net "GND")
	)
	(via
		(at 339.1154 -112.395)
		(size 0.508)
		(drill 0.254)
		(layers "F.Cu" "B.Cu")
		(net "GND")
	)
	(via
		(at 78.14945 -136.387078)
		(size 0.508)
		(drill 0.254)
		(layers "F.Cu" "B.Cu")
		(net "GND")
	)
	(via
		(at 451.591934 12.894056)
		(size 0.5588)
		(drill 0.3048)
		(layers "F.Cu" "B.Cu")
		(net "GND")
	)
	(via
		(at 224.449894 -145.998946)
		(size 0.508)
		(drill 0.254)
		(layers "F.Cu" "B.Cu")
		(net "GND")
	)
	(via
		(at 131.699508 0.444754)
		(size 0.508)
		(drill 0.254)
		(layers "F.Cu" "B.Cu")
		(net "GND")
	)
	(via
		(at 129.085848 -98.500184)
		(size 0.508)
		(drill 0.254)
		(layers "F.Cu" "B.Cu")
		(net "GND")
	)
	(via
		(at 22.331934 9.084056)
		(size 0.5588)
		(drill 0.3048)
		(layers "F.Cu" "B.Cu")
		(net "GND")
	)
	(via
		(at 68.894706 -53.60924)
		(size 0.508)
		(drill 0.254)
		(layers "F.Cu" "B.Cu")
		(net "GND")
	)
	(via
		(at 276.057614 -98.995738)
		(size 0.508)
		(drill 0.254)
		(layers "F.Cu" "B.Cu")
		(net "GND")
	)
	(via
		(at 395.639036 -44.690792)
		(size 0.508)
		(drill 0.254)
		(layers "F.Cu" "B.Cu")
		(net "GND")
	)
	(via
		(at 443.971934 11.624056)
		(size 0.5588)
		(drill 0.3048)
		(layers "F.Cu" "B.Cu")
		(net "GND")
	)
	(via
		(at 239.046258 -61.53404)
		(size 0.508)
		(drill 0.254)
		(layers "F.Cu" "B.Cu")
		(net "GND")
	)
	(via
		(at 376.708416 -151.402288)
		(size 0.508)
		(drill 0.254)
		(layers "F.Cu" "B.Cu")
		(net "GND")
	)
	(via
		(at 340.3854 -39.37)
		(size 0.508)
		(drill 0.254)
		(layers "F.Cu" "B.Cu")
		(net "GND")
	)
	(via
		(at 316.249812 -140.617956)
		(size 0.508)
		(drill 0.254)
		(layers "F.Cu" "B.Cu")
		(net "GND")
	)
	(via
		(at 114.206782 -53.923184)
		(size 0.508)
		(drill 0.254)
		(layers "F.Cu" "B.Cu")
		(net "GND")
	)
	(via
		(at 268.330934 -167.832024)
		(size 0.5588)
		(drill 0.3048)
		(layers "F.Cu" "B.Cu")
		(net "GND")
	)
	(via
		(at 42.77995 -61.504322)
		(size 0.5588)
		(drill 0.3048)
		(layers "F.Cu" "B.Cu")
		(net "GND")
	)
	(via
		(at 490.961934 11.624056)
		(size 0.5588)
		(drill 0.3048)
		(layers "F.Cu" "B.Cu")
		(net "GND")
	)
	(via
		(at 180.499258 -61.483494)
		(size 0.508)
		(drill 0.254)
		(layers "F.Cu" "B.Cu")
		(net "GND")
	)
	(via
		(at 374.17756 -133.453378)
		(size 0.508)
		(drill 0.254)
		(layers "F.Cu" "B.Cu")
		(net "GND")
	)
	(via
		(at 337.622134 -167.832024)
		(size 0.5588)
		(drill 0.3048)
		(layers "F.Cu" "B.Cu")
		(net "GND")
	)
	(via
		(at 235.612178 -87.28964)
		(size 0.508)
		(drill 0.254)
		(layers "F.Cu" "B.Cu")
		(net "GND")
	)
	(via
		(at 345.948 -145.4912)
		(size 0.508)
		(drill 0.254)
		(layers "F.Cu" "B.Cu")
		(net "GND")
	)
	(via
		(at 206.501746 -144.462246)
		(size 0.508)
		(drill 0.254)
		(layers "F.Cu" "B.Cu")
		(net "GND")
	)
	(via
		(at 138.529314 -59.371484)
		(size 0.508)
		(drill 0.254)
		(layers "F.Cu" "B.Cu")
		(net "GND")
	)
	(via
		(at 324.52564 -27.8003)
		(size 0.508)
		(drill 0.254)
		(layers "F.Cu" "B.Cu")
		(net "GND")
	)
	(via
		(at 152.099518 -153.542746)
		(size 0.508)
		(drill 0.254)
		(layers "F.Cu" "B.Cu")
		(net "GND")
	)
	(via
		(at 303.038002 -23.549356)
		(size 0.508)
		(drill 0.254)
		(layers "F.Cu" "B.Cu")
		(net "GND")
	)
	(via
		(at 131.661408 -82.155284)
		(size 0.508)
		(drill 0.254)
		(layers "F.Cu" "B.Cu")
		(net "GND")
	)
	(via
		(at 38.199314 -144.462246)
		(size 0.508)
		(drill 0.254)
		(layers "F.Cu" "B.Cu")
		(net "GND")
	)
	(via
		(at 36.983924 -162.243262)
		(size 0.5588)
		(drill 0.3048)
		(layers "F.Cu" "B.Cu")
		(net "GND")
	)
	(via
		(at 455.260202 -16.302228)
		(size 0.5588)
		(drill 0.3048)
		(layers "F.Cu" "B.Cu")
		(net "GND")
	)
	(via
		(at 356.615492 -110.43285)
		(size 0.508)
		(drill 0.254)
		(layers "F.Cu" "B.Cu")
		(net "GND")
	)
	(via
		(at 275.111464 -145.0086)
		(size 0.508)
		(drill 0.254)
		(layers "F.Cu" "B.Cu")
		(net "GND")
	)
	(via
		(at 356.757732 -105.81005)
		(size 0.508)
		(drill 0.254)
		(layers "F.Cu" "B.Cu")
		(net "GND")
	)
	(via
		(at 147.390866 -134.349744)
		(size 0.508)
		(drill 0.254)
		(layers "F.Cu" "B.Cu")
		(net "GND")
	)
	(via
		(at 205.741524 -162.243262)
		(size 0.5588)
		(drill 0.3048)
		(layers "F.Cu" "B.Cu")
		(net "GND")
	)
	(via
		(at 231.249728 1.994154)
		(size 0.508)
		(drill 0.254)
		(layers "F.Cu" "B.Cu")
		(net "GND")
	)
	(via
		(at 459.237334 -15.113254)
		(size 0.5588)
		(drill 0.3048)
		(layers "F.Cu" "B.Cu")
		(net "GND")
	)
	(via
		(at 351.8154 -43.18)
		(size 0.508)
		(drill 0.254)
		(layers "F.Cu" "B.Cu")
		(net "GND")
	)
	(via
		(at 346.562934 -167.832024)
		(size 0.5588)
		(drill 0.3048)
		(layers "F.Cu" "B.Cu")
		(net "GND")
	)
	(via
		(at 96.086676 -70.841616)
		(size 0.5588)
		(drill 0.3048)
		(layers "F.Cu" "B.Cu")
		(net "GND")
	)
	(via
		(at 1.155192 -152.546558)
		(size 0.5588)
		(drill 0.3048)
		(layers "F.Cu" "B.Cu")
		(net "GND")
	)
	(via
		(at 461.352392 -39.506398)
		(size 0.508)
		(drill 0.254)
		(layers "F.Cu" "B.Cu")
		(net "GND")
	)
	(via
		(at 59.449462 -145.998946)
		(size 0.508)
		(drill 0.254)
		(layers "F.Cu" "B.Cu")
		(net "GND")
	)
	(via
		(at 185.628534 -167.832024)
		(size 0.5588)
		(drill 0.3048)
		(layers "F.Cu" "B.Cu")
		(net "GND")
	)
	(via
		(at 39.14902 -48.307244)
		(size 0.508)
		(drill 0.254)
		(layers "F.Cu" "B.Cu")
		(net "GND")
	)
	(via
		(at 103.557324 -63.019686)
		(size 0.508)
		(drill 0.254)
		(layers "F.Cu" "B.Cu")
		(net "GND")
	)
	(via
		(at 210.387946 -141.202156)
		(size 0.508)
		(drill 0.254)
		(layers "F.Cu" "B.Cu")
		(net "GND")
	)
	(via
		(at 452.861934 14.926056)
		(size 0.5588)
		(drill 0.3048)
		(layers "F.Cu" "B.Cu")
		(net "GND")
	)
	(via
		(at 254.49911 -53.60924)
		(size 0.508)
		(drill 0.254)
		(layers "F.Cu" "B.Cu")
		(net "GND")
	)
	(via
		(at 199.749156 2.4511)
		(size 0.508)
		(drill 0.254)
		(layers "F.Cu" "B.Cu")
		(net "GND")
	)
	(via
		(at 233.799888 -26.488136)
		(size 0.508)
		(drill 0.254)
		(layers "F.Cu" "B.Cu")
		(net "GND")
	)
	(via
		(at 33.061402 -2.314956)
		(size 0.508)
		(drill 0.254)
		(layers "F.Cu" "B.Cu")
		(net "GND")
	)
	(via
		(at 138.529314 -68.287138)
		(size 0.508)
		(drill 0.254)
		(layers "F.Cu" "B.Cu")
		(net "GND")
	)
	(via
		(at 298.378626 -85.127338)
		(size 0.508)
		(drill 0.254)
		(layers "F.Cu" "B.Cu")
		(net "GND")
	)
	(via
		(at 215.0999 -148.771356)
		(size 0.508)
		(drill 0.254)
		(layers "F.Cu" "B.Cu")
		(net "GND")
	)
	(via
		(at 456.863704 -2.978404)
		(size 0.508)
		(drill 0.254)
		(layers "F.Cu" "B.Cu")
		(net "GND")
	)
	(via
		(at 20.219924 -162.243262)
		(size 0.5588)
		(drill 0.3048)
		(layers "F.Cu" "B.Cu")
		(net "GND")
	)
	(via
		(at 278.849836 -144.5768)
		(size 0.508)
		(drill 0.254)
		(layers "F.Cu" "B.Cu")
		(net "GND")
	)
	(via
		(at 39.049452 -11.916156)
		(size 0.508)
		(drill 0.254)
		(layers "F.Cu" "B.Cu")
		(net "GND")
	)
	(via
		(at 375.885202 -8.84682)
		(size 0.508)
		(drill 0.254)
		(layers "F.Cu" "B.Cu")
		(net "GND")
	)
	(via
		(at 214.249762 -134.861046)
		(size 0.508)
		(drill 0.254)
		(layers "F.Cu" "B.Cu")
		(net "GND")
	)
	(via
		(at 114.206782 -64.819784)
		(size 0.508)
		(drill 0.254)
		(layers "F.Cu" "B.Cu")
		(net "GND")
	)
	(via
		(at 169.4434 -78.1558)
		(size 0.508)
		(drill 0.254)
		(layers "F.Cu" "B.Cu")
		(net "GND")
	)
	(via
		(at 449.606924 -162.243262)
		(size 0.5588)
		(drill 0.3048)
		(layers "F.Cu" "B.Cu")
		(net "GND")
	)
	(via
		(at 346.892626 -126.37643)
		(size 0.508)
		(drill 0.254)
		(layers "F.Cu" "B.Cu")
		(net "GND")
	)
	(via
		(at 142.981934 14.926056)
		(size 0.5588)
		(drill 0.3048)
		(layers "F.Cu" "B.Cu")
		(net "GND")
	)
	(via
		(at 348.0054 -20.955)
		(size 0.508)
		(drill 0.254)
		(layers "F.Cu" "B.Cu")
		(net "GND")
	)
	(via
		(at 115.349782 -96.518984)
		(size 0.508)
		(drill 0.254)
		(layers "F.Cu" "B.Cu")
		(net "GND")
	)
	(via
		(at 284.358334 -77.697584)
		(size 0.508)
		(drill 0.254)
		(layers "F.Cu" "B.Cu")
		(net "GND")
	)
	(via
		(at 118.572534 -167.832024)
		(size 0.5588)
		(drill 0.3048)
		(layers "F.Cu" "B.Cu")
		(net "GND")
	)
	(via
		(at 22.458934 -167.832024)
		(size 0.5588)
		(drill 0.3048)
		(layers "F.Cu" "B.Cu")
		(net "GND")
	)
	(via
		(at 203.506324 -162.243262)
		(size 0.5588)
		(drill 0.3048)
		(layers "F.Cu" "B.Cu")
		(net "GND")
	)
	(via
		(at 98.982276 -70.841616)
		(size 0.5588)
		(drill 0.3048)
		(layers "F.Cu" "B.Cu")
		(net "GND")
	)
	(via
		(at 77.299312 -134.861046)
		(size 0.508)
		(drill 0.254)
		(layers "F.Cu" "B.Cu")
		(net "GND")
	)
	(via
		(at 125.651768 -94.538038)
		(size 0.508)
		(drill 0.254)
		(layers "F.Cu" "B.Cu")
		(net "GND")
	)
	(via
		(at 121.359168 -98.005138)
		(size 0.508)
		(drill 0.254)
		(layers "F.Cu" "B.Cu")
		(net "GND")
	)
	(via
		(at 403.890734 -165.596824)
		(size 0.5588)
		(drill 0.3048)
		(layers "F.Cu" "B.Cu")
		(net "GND")
	)
	(via
		(at 169.6974 -17.4244)
		(size 0.508)
		(drill 0.254)
		(layers "F.Cu" "B.Cu")
		(net "GND")
	)
	(via
		(at 6.918706 -11.944858)
		(size 0.508)
		(drill 0.254)
		(layers "F.Cu" "B.Cu")
		(net "GND")
	)
	(via
		(at 99.800664 -63.51524)
		(size 0.508)
		(drill 0.254)
		(layers "F.Cu" "B.Cu")
		(net "GND")
	)
	(via
		(at 134.236714 -59.866784)
		(size 0.508)
		(drill 0.254)
		(layers "F.Cu" "B.Cu")
		(net "GND")
	)
	(via
		(at 422.381934 14.926056)
		(size 0.5588)
		(drill 0.3048)
		(layers "F.Cu" "B.Cu")
		(net "GND")
	)
	(via
		(at 376.814842 -45.9994)
		(size 0.508)
		(drill 0.254)
		(layers "F.Cu" "B.Cu")
		(net "GND")
	)
	(via
		(at 175.505364 -1.429004)
		(size 0.5588)
		(drill 0.3048)
		(layers "F.Cu" "B.Cu")
		(net "GND")
	)
	(via
		(at -2.0066 -50.848514)
		(size 0.5588)
		(drill 0.3048)
		(layers "F.Cu" "B.Cu")
		(net "GND")
	)
	(via
		(at 15.4178 -132.5626)
		(size 0.508)
		(drill 0.254)
		(layers "F.Cu" "B.Cu")
		(net "GND")
	)
	(via
		(at 363.961934 14.926056)
		(size 0.5588)
		(drill 0.3048)
		(layers "F.Cu" "B.Cu")
		(net "GND")
	)
	(via
		(at 296.69994 -21.517356)
		(size 0.508)
		(drill 0.254)
		(layers "F.Cu" "B.Cu")
		(net "GND")
	)
	(via
		(at 298.378626 -90.080338)
		(size 0.508)
		(drill 0.254)
		(layers "F.Cu" "B.Cu")
		(net "GND")
	)
	(via
		(at 395.16685 -98.464116)
		(size 0.508)
		(drill 0.254)
		(layers "F.Cu" "B.Cu")
		(net "GND")
	)
	(via
		(at 391.20445 -121.245884)
		(size 0.508)
		(drill 0.254)
		(layers "F.Cu" "B.Cu")
		(net "GND")
	)
	(via
		(at 472.155266 4.553458)
		(size 0.5588)
		(drill 0.3048)
		(layers "F.Cu" "B.Cu")
		(net "GND")
	)
	(via
		(at 251.065284 -80.35544)
		(size 0.508)
		(drill 0.254)
		(layers "F.Cu" "B.Cu")
		(net "GND")
	)
	(via
		(at 205.221586 -92.60205)
		(size 0.5588)
		(drill 0.3048)
		(layers "F.Cu" "B.Cu")
		(net "GND")
	)
	(via
		(at 74.045826 -96.20504)
		(size 0.508)
		(drill 0.254)
		(layers "F.Cu" "B.Cu")
		(net "GND")
	)
	(via
		(at 74.904346 -81.841086)
		(size 0.508)
		(drill 0.254)
		(layers "F.Cu" "B.Cu")
		(net "GND")
	)
	(via
		(at 0.26416 -134.929372)
		(size 0.508)
		(drill 0.254)
		(layers "F.Cu" "B.Cu")
		(net "GND")
	)
	(via
		(at 75.762866 -50.63744)
		(size 0.508)
		(drill 0.254)
		(layers "F.Cu" "B.Cu")
		(net "GND")
	)
	(via
		(at 282.067254 -94.538038)
		(size 0.508)
		(drill 0.254)
		(layers "F.Cu" "B.Cu")
		(net "GND")
	)
	(via
		(at 453.027288 -45.611796)
		(size 0.508)
		(drill 0.254)
		(layers "F.Cu" "B.Cu")
		(net "GND")
	)
	(via
		(at 286.3596 -90.080338)
		(size 0.508)
		(drill 0.254)
		(layers "F.Cu" "B.Cu")
		(net "GND")
	)
	(via
		(at 120.649492 -148.771356)
		(size 0.508)
		(drill 0.254)
		(layers "F.Cu" "B.Cu")
		(net "GND")
	)
	(via
		(at 39.049452 -155.612846)
		(size 0.508)
		(drill 0.254)
		(layers "F.Cu" "B.Cu")
		(net "GND")
	)
	(via
		(at 348.30131 -136.508998)
		(size 0.508)
		(drill 0.254)
		(layers "F.Cu" "B.Cu")
		(net "GND")
	)
	(via
		(at 135.095234 -76.211938)
		(size 0.508)
		(drill 0.254)
		(layers "F.Cu" "B.Cu")
		(net "GND")
	)
	(via
		(at 358.761538 -105.757472)
		(size 0.508)
		(drill 0.254)
		(layers "F.Cu" "B.Cu")
		(net "GND")
	)
	(via
		(at 368.972592 -26.362152)
		(size 0.508)
		(drill 0.254)
		(layers "F.Cu" "B.Cu")
		(net "GND")
	)
	(via
		(at 153.214324 -162.243262)
		(size 0.5588)
		(drill 0.3048)
		(layers "F.Cu" "B.Cu")
		(net "GND")
	)
	(via
		(at 444.687706 -157.154372)
		(size 0.508)
		(drill 0.254)
		(layers "F.Cu" "B.Cu")
		(net "GND")
	)
	(via
		(at 111.866934 -167.832024)
		(size 0.5588)
		(drill 0.3048)
		(layers "F.Cu" "B.Cu")
		(net "GND")
	)
	(via
		(at 237.142528 -155.600146)
		(size 0.508)
		(drill 0.254)
		(layers "F.Cu" "B.Cu")
		(net "GND")
	)
	(via
		(at 136.812274 -79.183738)
		(size 0.508)
		(drill 0.254)
		(layers "F.Cu" "B.Cu")
		(net "GND")
	)
	(via
		(at 50.099468 -18.744946)
		(size 0.508)
		(drill 0.254)
		(layers "F.Cu" "B.Cu")
		(net "GND")
	)
	(via
		(at 247.34393 -126.947422)
		(size 0.508)
		(drill 0.254)
		(layers "F.Cu" "B.Cu")
		(net "GND")
	)
	(via
		(at 304.349912 -136.410446)
		(size 0.508)
		(drill 0.254)
		(layers "F.Cu" "B.Cu")
		(net "GND")
	)
	(via
		(at 287.349946 -155.612846)
		(size 0.508)
		(drill 0.254)
		(layers "F.Cu" "B.Cu")
		(net "GND")
	)
	(via
		(at 126.510288 -90.080338)
		(size 0.508)
		(drill 0.254)
		(layers "F.Cu" "B.Cu")
		(net "GND")
	)
	(via
		(at 306.049934 -18.757646)
		(size 0.508)
		(drill 0.254)
		(layers "F.Cu" "B.Cu")
		(net "GND")
	)
	(via
		(at 240.763298 -55.59044)
		(size 0.508)
		(drill 0.254)
		(layers "F.Cu" "B.Cu")
		(net "GND")
	)
	(via
		(at 41.842182 -94.578678)
		(size 0.5588)
		(drill 0.3048)
		(layers "F.Cu" "B.Cu")
		(net "GND")
	)
	(via
		(at 300.099984 -155.612846)
		(size 0.508)
		(drill 0.254)
		(layers "F.Cu" "B.Cu")
		(net "GND")
	)
	(via
		(at 168.860724 -162.243262)
		(size 0.5588)
		(drill 0.3048)
		(layers "F.Cu" "B.Cu")
		(net "GND")
	)
	(via
		(at 93.51391 -79.376016)
		(size 0.508)
		(drill 0.254)
		(layers "F.Cu" "B.Cu")
		(net "GND")
	)
	(via
		(at 82.630772 -59.55284)
		(size 0.508)
		(drill 0.254)
		(layers "F.Cu" "B.Cu")
		(net "GND")
	)
	(via
		(at 147.387564 -141.202156)
		(size 0.508)
		(drill 0.254)
		(layers "F.Cu" "B.Cu")
		(net "GND")
	)
	(via
		(at 36.03752 -13.948156)
		(size 0.508)
		(drill 0.254)
		(layers "F.Cu" "B.Cu")
		(net "GND")
	)
	(via
		(at 305.199796 -154.063446)
		(size 0.508)
		(drill 0.254)
		(layers "F.Cu" "B.Cu")
		(net "GND")
	)
	(via
		(at 245.914164 -74.411586)
		(size 0.508)
		(drill 0.254)
		(layers "F.Cu" "B.Cu")
		(net "GND")
	)
	(via
		(at 97.225358 -53.113686)
		(size 0.508)
		(drill 0.254)
		(layers "F.Cu" "B.Cu")
		(net "GND")
	)
	(via
		(at 78.338172 -98.681286)
		(size 0.508)
		(drill 0.254)
		(layers "F.Cu" "B.Cu")
		(net "GND")
	)
	(via
		(at 385.75615 -123.821444)
		(size 0.508)
		(drill 0.254)
		(layers "F.Cu" "B.Cu")
		(net "GND")
	)
	(via
		(at 443.484 -145.796)
		(size 0.508)
		(drill 0.254)
		(layers "F.Cu" "B.Cu")
		(net "GND")
	)
	(via
		(at 283.04236 -129.564892)
		(size 0.508)
		(drill 0.254)
		(layers "F.Cu" "B.Cu")
		(net "GND")
	)
	(via
		(at 9.047734 -165.596824)
		(size 0.5588)
		(drill 0.3048)
		(layers "F.Cu" "B.Cu")
		(net "GND")
	)
	(via
		(at 115.451382 -7.607046)
		(size 0.508)
		(drill 0.254)
		(layers "F.Cu" "B.Cu")
		(net "GND")
	)
	(via
		(at 150.982934 -167.832024)
		(size 0.5588)
		(drill 0.3048)
		(layers "F.Cu" "B.Cu")
		(net "GND")
	)
	(via
		(at 77.264768 -26.67)
		(size 0.508)
		(drill 0.254)
		(layers "F.Cu" "B.Cu")
		(net "GND")
	)
	(via
		(at 147.41144 -58.43524)
		(size 0.508)
		(drill 0.254)
		(layers "F.Cu" "B.Cu")
		(net "GND")
	)
	(via
		(at 206.165196 -54.067202)
		(size 0.5588)
		(drill 0.3048)
		(layers "F.Cu" "B.Cu")
		(net "GND")
	)
	(via
		(at 413.385 -2.9718)
		(size 0.508)
		(drill 0.254)
		(layers "F.Cu" "B.Cu")
		(net "GND")
	)
	(via
		(at 193.447924 -162.243262)
		(size 0.5588)
		(drill 0.3048)
		(layers "F.Cu" "B.Cu")
		(net "GND")
	)
	(via
		(at 393.68095 -113.519204)
		(size 0.508)
		(drill 0.254)
		(layers "F.Cu" "B.Cu")
		(net "GND")
	)
	(via
		(at 0.106934 -167.832024)
		(size 0.5588)
		(drill 0.3048)
		(layers "F.Cu" "B.Cu")
		(net "GND")
	)
	(via
		(at 287.349946 -2.314956)
		(size 0.508)
		(drill 0.254)
		(layers "F.Cu" "B.Cu")
		(net "GND")
	)
	(via
		(at 241.44986 -136.410446)
		(size 0.508)
		(drill 0.254)
		(layers "F.Cu" "B.Cu")
		(net "GND")
	)
	(via
		(at 235.612178 -80.35544)
		(size 0.508)
		(drill 0.254)
		(layers "F.Cu" "B.Cu")
		(net "GND")
	)
	(via
		(at 152.099518 -155.612846)
		(size 0.508)
		(drill 0.254)
		(layers "F.Cu" "B.Cu")
		(net "GND")
	)
	(via
		(at 303.529746 -74.230738)
		(size 0.508)
		(drill 0.254)
		(layers "F.Cu" "B.Cu")
		(net "GND")
	)
	(via
		(at 281.495754 -86.041484)
		(size 0.508)
		(drill 0.254)
		(layers "F.Cu" "B.Cu")
		(net "GND")
	)
	(via
		(at 290.67379 -125.955298)
		(size 0.508)
		(drill 0.254)
		(layers "F.Cu" "B.Cu")
		(net "GND")
	)
	(via
		(at 178.308 -140.5255)
		(size 0.508)
		(drill 0.254)
		(layers "F.Cu" "B.Cu")
		(net "GND")
	)
	(via
		(at 405.160734 -167.832024)
		(size 0.5588)
		(drill 0.3048)
		(layers "F.Cu" "B.Cu")
		(net "GND")
	)
	(via
		(at 76.621386 -90.756486)
		(size 0.508)
		(drill 0.254)
		(layers "F.Cu" "B.Cu")
		(net "GND")
	)
	(via
		(at 82.630772 -94.223586)
		(size 0.508)
		(drill 0.254)
		(layers "F.Cu" "B.Cu")
		(net "GND")
	)
	(via
		(at 206.753714 -93.943678)
		(size 0.5588)
		(drill 0.3048)
		(layers "F.Cu" "B.Cu")
		(net "GND")
	)
	(via
		(at 15.494 -97.282)
		(size 0.508)
		(drill 0.254)
		(layers "F.Cu" "B.Cu")
		(net "GND")
	)
	(via
		(at 136.74217 -129.564892)
		(size 0.508)
		(drill 0.254)
		(layers "F.Cu" "B.Cu")
		(net "GND")
	)
	(via
		(at 105.571036 -59.866784)
		(size 0.508)
		(drill 0.254)
		(layers "F.Cu" "B.Cu")
		(net "GND")
	)
	(via
		(at 128.227328 -85.127338)
		(size 0.508)
		(drill 0.254)
		(layers "F.Cu" "B.Cu")
		(net "GND")
	)
	(via
		(at 70.611746 -83.32724)
		(size 0.508)
		(drill 0.254)
		(layers "F.Cu" "B.Cu")
		(net "GND")
	)
	(via
		(at 34.74212 -148.767292)
		(size 0.508)
		(drill 0.254)
		(layers "F.Cu" "B.Cu")
		(net "GND")
	)
	(via
		(at 450.880734 -164.479224)
		(size 0.5588)
		(drill 0.3048)
		(layers "F.Cu" "B.Cu")
		(net "GND")
	)
	(via
		(at 454.930764 -50.488088)
		(size 0.508)
		(drill 0.254)
		(layers "F.Cu" "B.Cu")
		(net "GND")
	)
	(via
		(at 75.762866 -62.52464)
		(size 0.508)
		(drill 0.254)
		(layers "F.Cu" "B.Cu")
		(net "GND")
	)
	(via
		(at 97.225358 -88.775286)
		(size 0.508)
		(drill 0.254)
		(layers "F.Cu" "B.Cu")
		(net "GND")
	)
	(via
		(at 65.399412 -26.488136)
		(size 0.508)
		(drill 0.254)
		(layers "F.Cu" "B.Cu")
		(net "GND")
	)
	(via
		(at 150.399496 -148.771356)
		(size 0.508)
		(drill 0.254)
		(layers "F.Cu" "B.Cu")
		(net "GND")
	)
	(via
		(at 131.699508 -146.011646)
		(size 0.508)
		(drill 0.254)
		(layers "F.Cu" "B.Cu")
		(net "GND")
	)
	(via
		(at 250.206764 -67.972686)
		(size 0.508)
		(drill 0.254)
		(layers "F.Cu" "B.Cu")
		(net "GND")
	)
	(via
		(at 200.515728 -74.2696)
		(size 0.508)
		(drill 0.254)
		(layers "F.Cu" "B.Cu")
		(net "GND")
	)
	(via
		(at 435.081934 9.084056)
		(size 0.5588)
		(drill 0.3048)
		(layers "F.Cu" "B.Cu")
		(net "GND")
	)
	(via
		(at 281.782774 -60.362338)
		(size 0.508)
		(drill 0.254)
		(layers "F.Cu" "B.Cu")
		(net "GND")
	)
	(via
		(at 290.71189 -139.170156)
		(size 0.508)
		(drill 0.254)
		(layers "F.Cu" "B.Cu")
		(net "GND")
	)
	(via
		(at 199.742552 -2.310892)
		(size 0.508)
		(drill 0.254)
		(layers "F.Cu" "B.Cu")
		(net "GND")
	)
	(via
		(at 494.060734 -166.714424)
		(size 0.5588)
		(drill 0.3048)
		(layers "F.Cu" "B.Cu")
		(net "GND")
	)
	(via
		(at 253.640844 -88.775286)
		(size 0.508)
		(drill 0.254)
		(layers "F.Cu" "B.Cu")
		(net "GND")
	)
	(via
		(at 137.670794 -74.725784)
		(size 0.508)
		(drill 0.254)
		(layers "F.Cu" "B.Cu")
		(net "GND")
	)
	(via
		(at 48.650398 -61.719206)
		(size 0.508)
		(drill 0.254)
		(layers "F.Cu" "B.Cu")
		(net "GND")
	)
	(via
		(at 216.917524 -162.243262)
		(size 0.5588)
		(drill 0.3048)
		(layers "F.Cu" "B.Cu")
		(net "GND")
	)
	(via
		(at 236.470698 -65.991486)
		(size 0.508)
		(drill 0.254)
		(layers "F.Cu" "B.Cu")
		(net "GND")
	)
	(via
		(at 175.8696 -55.3974)
		(size 0.508)
		(drill 0.254)
		(layers "F.Cu" "B.Cu")
		(net "GND")
	)
	(via
		(at 9.828784 -141.647672)
		(size 0.508)
		(drill 0.254)
		(layers "F.Cu" "B.Cu")
		(net "GND")
	)
	(via
		(at 86.064852 -61.53404)
		(size 0.508)
		(drill 0.254)
		(layers "F.Cu" "B.Cu")
		(net "GND")
	)
	(via
		(at 35.49142 -72.1868)
		(size 0.508)
		(drill 0.254)
		(layers "F.Cu" "B.Cu")
		(net "GND")
	)
	(via
		(at 146.092164 -145.998946)
		(size 0.508)
		(drill 0.254)
		(layers "F.Cu" "B.Cu")
		(net "GND")
	)
	(via
		(at 31.908496 -97.442782)
		(size 0.508)
		(drill 0.254)
		(layers "F.Cu" "B.Cu")
		(net "GND")
	)
	(via
		(at 135.061452 -148.771356)
		(size 0.508)
		(drill 0.254)
		(layers "F.Cu" "B.Cu")
		(net "GND")
	)
	(via
		(at 458.496924 -162.243262)
		(size 0.5588)
		(drill 0.3048)
		(layers "F.Cu" "B.Cu")
		(net "GND")
	)
	(via
		(at 245.055644 -90.756486)
		(size 0.508)
		(drill 0.254)
		(layers "F.Cu" "B.Cu")
		(net "GND")
	)
	(via
		(at 239.749838 -129.568956)
		(size 0.508)
		(drill 0.254)
		(layers "F.Cu" "B.Cu")
		(net "GND")
	)
	(via
		(at 46.461934 9.084056)
		(size 0.5588)
		(drill 0.3048)
		(layers "F.Cu" "B.Cu")
		(net "GND")
	)
	(via
		(at 456.60183 -16.294862)
		(size 0.5588)
		(drill 0.3048)
		(layers "F.Cu" "B.Cu")
		(net "GND")
	)
	(via
		(at 129.944368 -78.193138)
		(size 0.508)
		(drill 0.254)
		(layers "F.Cu" "B.Cu")
		(net "GND")
	)
	(via
		(at 365.506 -107.442)
		(size 0.508)
		(drill 0.254)
		(layers "F.Cu" "B.Cu")
		(net "GND")
	)
	(via
		(at 153.141934 14.926056)
		(size 0.5588)
		(drill 0.3048)
		(layers "F.Cu" "B.Cu")
		(net "GND")
	)
	(via
		(at 28.677616 -60.253372)
		(size 0.508)
		(drill 0.254)
		(layers "F.Cu" "B.Cu")
		(net "GND")
	)
	(via
		(at 74.904346 -100.662486)
		(size 0.508)
		(drill 0.254)
		(layers "F.Cu" "B.Cu")
		(net "GND")
	)
	(via
		(at 74.904346 -80.850486)
		(size 0.508)
		(drill 0.254)
		(layers "F.Cu" "B.Cu")
		(net "GND")
	)
	(via
		(at 69.753226 -69.953886)
		(size 0.508)
		(drill 0.254)
		(layers "F.Cu" "B.Cu")
		(net "GND")
	)
	(via
		(at 210.391248 -143.950944)
		(size 0.508)
		(drill 0.254)
		(layers "F.Cu" "B.Cu")
		(net "GND")
	)
	(via
		(at 41.359582 -70.237858)
		(size 0.5588)
		(drill 0.3048)
		(layers "F.Cu" "B.Cu")
		(net "GND")
	)
	(via
		(at 226.975924 -162.243262)
		(size 0.5588)
		(drill 0.3048)
		(layers "F.Cu" "B.Cu")
		(net "GND")
	)
	(via
		(at 1.340358 -56.16194)
		(size 0.5588)
		(drill 0.3048)
		(layers "F.Cu" "B.Cu")
		(net "GND")
	)
	(via
		(at 496.041934 13.910056)
		(size 0.5588)
		(drill 0.3048)
		(layers "F.Cu" "B.Cu")
		(net "GND")
	)
	(via
		(at 349.371666 -137.189718)
		(size 0.508)
		(drill 0.254)
		(layers "F.Cu" "B.Cu")
		(net "GND")
	)
	(via
		(at 200.881234 -87.811864)
		(size 0.508)
		(drill 0.254)
		(layers "F.Cu" "B.Cu")
		(net "GND")
	)
	(via
		(at 339.1154 -116.205)
		(size 0.508)
		(drill 0.254)
		(layers "F.Cu" "B.Cu")
		(net "GND")
	)
	(via
		(at 226.149916 -146.011646)
		(size 0.508)
		(drill 0.254)
		(layers "F.Cu" "B.Cu")
		(net "GND")
	)
	(via
		(at 286.3596 -87.108538)
		(size 0.508)
		(drill 0.254)
		(layers "F.Cu" "B.Cu")
		(net "GND")
	)
	(via
		(at 68.036186 -83.822286)
		(size 0.508)
		(drill 0.254)
		(layers "F.Cu" "B.Cu")
		(net "GND")
	)
	(via
		(at -3.245866 -167.832024)
		(size 0.5588)
		(drill 0.3048)
		(layers "F.Cu" "B.Cu")
		(net "GND")
	)
	(via
		(at 33.771586 -154.1018)
		(size 0.508)
		(drill 0.254)
		(layers "F.Cu" "B.Cu")
		(net "GND")
	)
	(via
		(at 219.744544 -9.0805)
		(size 0.508)
		(drill 0.254)
		(layers "F.Cu" "B.Cu")
		(net "GND")
	)
	(via
		(at 14.126464 -93.725492)
		(size 0.508)
		(drill 0.254)
		(layers "F.Cu" "B.Cu")
		(net "GND")
	)
	(via
		(at 286.499808 -131.016756)
		(size 0.508)
		(drill 0.254)
		(layers "F.Cu" "B.Cu")
		(net "GND")
	)
	(via
		(at 409.822396 -99.34067)
		(size 0.508)
		(drill 0.254)
		(layers "F.Cu" "B.Cu")
		(net "GND")
	)
	(via
		(at 306.049934 -146.011646)
		(size 0.508)
		(drill 0.254)
		(layers "F.Cu" "B.Cu")
		(net "GND")
	)
	(via
		(at 463.580734 -163.361624)
		(size 0.5588)
		(drill 0.3048)
		(layers "F.Cu" "B.Cu")
		(net "GND")
	)
	(via
		(at 175.8188 -21.2852)
		(size 0.508)
		(drill 0.254)
		(layers "F.Cu" "B.Cu")
		(net "GND")
	)
	(via
		(at 408.970734 -165.596824)
		(size 0.5588)
		(drill 0.3048)
		(layers "F.Cu" "B.Cu")
		(net "GND")
	)
	(via
		(at 483.341934 11.624056)
		(size 0.5588)
		(drill 0.3048)
		(layers "F.Cu" "B.Cu")
		(net "GND")
	)
	(via
		(at 77.479906 -72.43064)
		(size 0.508)
		(drill 0.254)
		(layers "F.Cu" "B.Cu")
		(net "GND")
	)
	(via
		(at 135.095234 -77.202538)
		(size 0.508)
		(drill 0.254)
		(layers "F.Cu" "B.Cu")
		(net "GND")
	)
	(via
		(at 201.041254 -16.696944)
		(size 0.508)
		(drill 0.254)
		(layers "F.Cu" "B.Cu")
		(net "GND")
	)
	(via
		(at 364.571534 -167.857424)
		(size 0.5588)
		(drill 0.3048)
		(layers "F.Cu" "B.Cu")
		(net "GND")
	)
	(via
		(at 327.559924 -162.243262)
		(size 0.5588)
		(drill 0.3048)
		(layers "F.Cu" "B.Cu")
		(net "GND")
	)
	(via
		(at -3.747262 -113.944654)
		(size 0.5588)
		(drill 0.3048)
		(layers "F.Cu" "B.Cu")
		(net "GND")
	)
	(via
		(at 252.782324 -85.30844)
		(size 0.508)
		(drill 0.254)
		(layers "F.Cu" "B.Cu")
		(net "GND")
	)
	(via
		(at 322.051934 9.084056)
		(size 0.5588)
		(drill 0.3048)
		(layers "F.Cu" "B.Cu")
		(net "GND")
	)
	(via
		(at 205.798928 -60.198)
		(size 0.5588)
		(drill 0.3048)
		(layers "F.Cu" "B.Cu")
		(net "GND")
	)
	(via
		(at 288.93516 -70.763384)
		(size 0.508)
		(drill 0.254)
		(layers "F.Cu" "B.Cu")
		(net "GND")
	)
	(via
		(at 345.929204 -148.345398)
		(size 0.508)
		(drill 0.254)
		(layers "F.Cu" "B.Cu")
		(net "GND")
	)
	(via
		(at 252.201934 14.926056)
		(size 0.5588)
		(drill 0.3048)
		(layers "F.Cu" "B.Cu")
		(net "GND")
	)
	(via
		(at 454.2028 -22.606)
		(size 0.508)
		(drill 0.254)
		(layers "F.Cu" "B.Cu")
		(net "GND")
	)
	(via
		(at 59.449462 -9.143746)
		(size 0.508)
		(drill 0.254)
		(layers "F.Cu" "B.Cu")
		(net "GND")
	)
	(via
		(at 292.36924 -99.490784)
		(size 0.508)
		(drill 0.254)
		(layers "F.Cu" "B.Cu")
		(net "GND")
	)
	(via
		(at 248.391934 14.926056)
		(size 0.5588)
		(drill 0.3048)
		(layers "F.Cu" "B.Cu")
		(net "GND")
	)
	(via
		(at 195.6308 -52.9844)
		(size 0.508)
		(drill 0.254)
		(layers "F.Cu" "B.Cu")
		(net "GND")
	)
	(via
		(at 209.08645 -150.749)
		(size 0.508)
		(drill 0.254)
		(layers "F.Cu" "B.Cu")
		(net "GND")
	)
	(via
		(at 345.09837 -96.355408)
		(size 0.508)
		(drill 0.254)
		(layers "F.Cu" "B.Cu")
		(net "GND")
	)
	(via
		(at 111.057182 -98.995738)
		(size 0.508)
		(drill 0.254)
		(layers "F.Cu" "B.Cu")
		(net "GND")
	)
	(via
		(at 376.428 -119.355108)
		(size 0.508)
		(drill 0.254)
		(layers "F.Cu" "B.Cu")
		(net "GND")
	)
	(via
		(at 266.171934 9.084056)
		(size 0.5588)
		(drill 0.3048)
		(layers "F.Cu" "B.Cu")
		(net "GND")
	)
	(via
		(at 127.392176 -136.397746)
		(size 0.508)
		(drill 0.254)
		(layers "F.Cu" "B.Cu")
		(net "GND")
	)
	(via
		(at 314.54979 -13.363956)
		(size 0.508)
		(drill 0.254)
		(layers "F.Cu" "B.Cu")
		(net "GND")
	)
	(via
		(at 3.02895 -17.223994)
		(size 0.508)
		(drill 0.254)
		(layers "F.Cu" "B.Cu")
		(net "GND")
	)
	(via
		(at 229.087934 -141.202156)
		(size 0.508)
		(drill 0.254)
		(layers "F.Cu" "B.Cu")
		(net "GND")
	)
	(via
		(at 139.387834 -78.688438)
		(size 0.508)
		(drill 0.254)
		(layers "F.Cu" "B.Cu")
		(net "GND")
	)
	(via
		(at 373.315738 -37.662104)
		(size 0.508)
		(drill 0.254)
		(layers "F.Cu" "B.Cu")
		(net "GND")
	)
	(via
		(at 241.862864 -102.214934)
		(size 0.508)
		(drill 0.254)
		(layers "F.Cu" "B.Cu")
		(net "GND")
	)
	(via
		(at 284.33776 -23.549356)
		(size 0.508)
		(drill 0.254)
		(layers "F.Cu" "B.Cu")
		(net "GND")
	)
	(via
		(at 309.884318 -55.962042)
		(size 0.508)
		(drill 0.254)
		(layers "F.Cu" "B.Cu")
		(net "GND")
	)
	(via
		(at 72.142096 -21.513292)
		(size 0.508)
		(drill 0.254)
		(layers "F.Cu" "B.Cu")
		(net "GND")
	)
	(via
		(at 92.39504 -134.440422)
		(size 0.508)
		(drill 0.254)
		(layers "F.Cu" "B.Cu")
		(net "GND")
	)
	(via
		(at 136.812274 -81.164938)
		(size 0.508)
		(drill 0.254)
		(layers "F.Cu" "B.Cu")
		(net "GND")
	)
	(via
		(at 122.217688 -78.688438)
		(size 0.508)
		(drill 0.254)
		(layers "F.Cu" "B.Cu")
		(net "GND")
	)
	(via
		(at 135.095234 -52.437538)
		(size 0.508)
		(drill 0.254)
		(layers "F.Cu" "B.Cu")
		(net "GND")
	)
	(via
		(at 494.63452 -122.5423)
		(size 0.508)
		(drill 0.254)
		(layers "F.Cu" "B.Cu")
		(net "GND")
	)
	(via
		(at 317.949834 2.514854)
		(size 0.508)
		(drill 0.254)
		(layers "F.Cu" "B.Cu")
		(net "GND")
	)
	(via
		(at 136.75741 -7.1374)
		(size 0.508)
		(drill 0.254)
		(layers "F.Cu" "B.Cu")
		(net "GND")
	)
	(via
		(at 331.4954 -112.395)
		(size 0.508)
		(drill 0.254)
		(layers "F.Cu" "B.Cu")
		(net "GND")
	)
	(via
		(at 375.145046 -71.894954)
		(size 0.4572)
		(drill 0.2032)
		(layers "F.Cu" "B.Cu")
		(net "GND")
	)
	(via
		(at 396.15745 -110.943644)
		(size 0.508)
		(drill 0.254)
		(layers "F.Cu" "B.Cu")
		(net "GND")
	)
	(via
		(at 421.666924 -162.243262)
		(size 0.5588)
		(drill 0.3048)
		(layers "F.Cu" "B.Cu")
		(net "GND")
	)
	(via
		(at 479.2472 -53.4924)
		(size 0.508)
		(drill 0.254)
		(layers "F.Cu" "B.Cu")
		(net "GND")
	)
	(via
		(at 300.061884 -26.495756)
		(size 0.508)
		(drill 0.254)
		(layers "F.Cu" "B.Cu")
		(net "GND")
	)
	(via
		(at 268.557756 -56.085486)
		(size 0.508)
		(drill 0.254)
		(layers "F.Cu" "B.Cu")
		(net "GND")
	)
	(via
		(at 235.612178 -51.62804)
		(size 0.508)
		(drill 0.254)
		(layers "F.Cu" "B.Cu")
		(net "GND")
	)
	(via
		(at 296.66184 -58.381138)
		(size 0.508)
		(drill 0.254)
		(layers "F.Cu" "B.Cu")
		(net "GND")
	)
	(via
		(at 103.678736 -8.1534)
		(size 0.508)
		(drill 0.254)
		(layers "F.Cu" "B.Cu")
		(net "GND")
	)
	(via
		(at 475.721934 12.894056)
		(size 0.5588)
		(drill 0.3048)
		(layers "F.Cu" "B.Cu")
		(net "GND")
	)
	(via
		(at 138.031474 -129.5654)
		(size 0.508)
		(drill 0.254)
		(layers "F.Cu" "B.Cu")
		(net "GND")
	)
	(via
		(at 67.099434 -129.568956)
		(size 0.508)
		(drill 0.254)
		(layers "F.Cu" "B.Cu")
		(net "GND")
	)
	(via
		(at 366.5474 -93.7133)
		(size 0.508)
		(drill 0.254)
		(layers "F.Cu" "B.Cu")
		(net "GND")
	)
	(via
		(at 120.216168 -65.315338)
		(size 0.508)
		(drill 0.254)
		(layers "F.Cu" "B.Cu")
		(net "GND")
	)
	(via
		(at 114.083592 -74.381614)
		(size 0.5588)
		(drill 0.3048)
		(layers "F.Cu" "B.Cu")
		(net "GND")
	)
	(via
		(at 308.501796 1.994154)
		(size 0.508)
		(drill 0.254)
		(layers "F.Cu" "B.Cu")
		(net "GND")
	)
	(via
		(at 433.811934 14.926056)
		(size 0.5588)
		(drill 0.3048)
		(layers "F.Cu" "B.Cu")
		(net "GND")
	)
	(via
		(at 179.451 -55.2196)
		(size 0.508)
		(drill 0.254)
		(layers "F.Cu" "B.Cu")
		(net "GND")
	)
	(via
		(at 167.8178 -78.1558)
		(size 0.508)
		(drill 0.254)
		(layers "F.Cu" "B.Cu")
		(net "GND")
	)
	(via
		(at 39.899336 -17.208246)
		(size 0.508)
		(drill 0.254)
		(layers "F.Cu" "B.Cu")
		(net "GND")
	)
	(via
		(at 242.480338 -58.561986)
		(size 0.508)
		(drill 0.254)
		(layers "F.Cu" "B.Cu")
		(net "GND")
	)
	(via
		(at 204.049884 -155.612846)
		(size 0.508)
		(drill 0.254)
		(layers "F.Cu" "B.Cu")
		(net "GND")
	)
	(via
		(at 140.199364 -134.861046)
		(size 0.508)
		(drill 0.254)
		(layers "F.Cu" "B.Cu")
		(net "GND")
	)
	(via
		(at 240.763298 -101.15804)
		(size 0.508)
		(drill 0.254)
		(layers "F.Cu" "B.Cu")
		(net "GND")
	)
	(via
		(at 37.49675 -60.183522)
		(size 0.5588)
		(drill 0.3048)
		(layers "F.Cu" "B.Cu")
		(net "GND")
	)
	(via
		(at -2.356866 14.926056)
		(size 0.5588)
		(drill 0.3048)
		(layers "F.Cu" "B.Cu")
		(net "GND")
	)
	(via
		(at 90.871548 -12.613386)
		(size 0.508)
		(drill 0.254)
		(layers "F.Cu" "B.Cu")
		(net "GND")
	)
	(via
		(at 56.049418 -136.410446)
		(size 0.508)
		(drill 0.254)
		(layers "F.Cu" "B.Cu")
		(net "GND")
	)
	(via
		(at 453.26935 -124.92482)
		(size 0.508)
		(drill 0.254)
		(layers "F.Cu" "B.Cu")
		(net "GND")
	)
	(via
		(at 198.099934 -18.757646)
		(size 0.508)
		(drill 0.254)
		(layers "F.Cu" "B.Cu")
		(net "GND")
	)
	(via
		(at 122.217688 -100.481384)
		(size 0.508)
		(drill 0.254)
		(layers "F.Cu" "B.Cu")
		(net "GND")
	)
	(via
		(at 230.399844 0.444754)
		(size 0.508)
		(drill 0.254)
		(layers "F.Cu" "B.Cu")
		(net "GND")
	)
	(via
		(at 442.262006 -40.5257)
		(size 0.508)
		(drill 0.254)
		(layers "F.Cu" "B.Cu")
		(net "GND")
	)
	(via
		(at 121.359168 -87.108538)
		(size 0.508)
		(drill 0.254)
		(layers "F.Cu" "B.Cu")
		(net "GND")
	)
	(via
		(at 78.338172 -92.737686)
		(size 0.508)
		(drill 0.254)
		(layers "F.Cu" "B.Cu")
		(net "GND")
	)
	(via
		(at 290.301934 9.084056)
		(size 0.5588)
		(drill 0.3048)
		(layers "F.Cu" "B.Cu")
		(net "GND")
	)
	(via
		(at 124.793248 -88.099138)
		(size 0.508)
		(drill 0.254)
		(layers "F.Cu" "B.Cu")
		(net "GND")
	)
	(via
		(at 133.39953 -11.916156)
		(size 0.508)
		(drill 0.254)
		(layers "F.Cu" "B.Cu")
		(net "GND")
	)
	(via
		(at 433.100734 -167.832024)
		(size 0.5588)
		(drill 0.3048)
		(layers "F.Cu" "B.Cu")
		(net "GND")
	)
	(via
		(at 286.499808 -154.063446)
		(size 0.508)
		(drill 0.254)
		(layers "F.Cu" "B.Cu")
		(net "GND")
	)
	(via
		(at 453.420734 -166.714424)
		(size 0.5588)
		(drill 0.3048)
		(layers "F.Cu" "B.Cu")
		(net "GND")
	)
	(via
		(at 149.861524 -162.243262)
		(size 0.5588)
		(drill 0.3048)
		(layers "F.Cu" "B.Cu")
		(net "GND")
	)
	(via
		(at 483.341934 12.894056)
		(size 0.5588)
		(drill 0.3048)
		(layers "F.Cu" "B.Cu")
		(net "GND")
	)
	(via
		(at 12.3698 -23.0378)
		(size 0.508)
		(drill 0.254)
		(layers "F.Cu" "B.Cu")
		(net "GND")
	)
	(via
		(at 166.624 -83.7692)
		(size 0.508)
		(drill 0.254)
		(layers "F.Cu" "B.Cu")
		(net "GND")
	)
	(via
		(at 80.055212 -59.057286)
		(size 0.508)
		(drill 0.254)
		(layers "F.Cu" "B.Cu")
		(net "GND")
	)
	(via
		(at 371.273324 -162.268662)
		(size 0.5588)
		(drill 0.3048)
		(layers "F.Cu" "B.Cu")
		(net "GND")
	)
	(via
		(at 309.449978 -136.410446)
		(size 0.508)
		(drill 0.254)
		(layers "F.Cu" "B.Cu")
		(net "GND")
	)
	(via
		(at 90.628724 -162.243262)
		(size 0.5588)
		(drill 0.3048)
		(layers "F.Cu" "B.Cu")
		(net "GND")
	)
	(via
		(at 242.480338 -88.28024)
		(size 0.508)
		(drill 0.254)
		(layers "F.Cu" "B.Cu")
		(net "GND")
	)
	(via
		(at 148.699474 -21.517356)
		(size 0.508)
		(drill 0.254)
		(layers "F.Cu" "B.Cu")
		(net "GND")
	)
	(via
		(at 447.781934 14.926056)
		(size 0.5588)
		(drill 0.3048)
		(layers "F.Cu" "B.Cu")
		(net "GND")
	)
	(via
		(at 1.53162 -24.08936)
		(size 0.508)
		(drill 0.254)
		(layers "F.Cu" "B.Cu")
		(net "GND")
	)
	(via
		(at 231.881934 14.926056)
		(size 0.5588)
		(drill 0.3048)
		(layers "F.Cu" "B.Cu")
		(net "GND")
	)
	(via
		(at 335.3816 -59.679586)
		(size 0.508)
		(drill 0.254)
		(layers "F.Cu" "B.Cu")
		(net "GND")
	)
	(via
		(at 386.9436 -55.3466)
		(size 0.508)
		(drill 0.254)
		(layers "F.Cu" "B.Cu")
		(net "GND")
	)
	(via
		(at 64.087502 -126.622556)
		(size 0.508)
		(drill 0.254)
		(layers "F.Cu" "B.Cu")
		(net "GND")
	)
	(via
		(at 306.049934 -26.495756)
		(size 0.508)
		(drill 0.254)
		(layers "F.Cu" "B.Cu")
		(net "GND")
	)
	(via
		(at 116.399564 -9.156446)
		(size 0.508)
		(drill 0.254)
		(layers "F.Cu" "B.Cu")
		(net "GND")
	)
	(via
		(at 246.772684 -69.953886)
		(size 0.508)
		(drill 0.254)
		(layers "F.Cu" "B.Cu")
		(net "GND")
	)
	(via
		(at 201.5744 -62.0776)
		(size 0.5588)
		(drill 0.3048)
		(layers "F.Cu" "B.Cu")
		(net "GND")
	)
	(via
		(at 284.071314 -69.849238)
		(size 0.508)
		(drill 0.254)
		(layers "F.Cu" "B.Cu")
		(net "GND")
	)
	(via
		(at 304.349912 -2.314956)
		(size 0.508)
		(drill 0.254)
		(layers "F.Cu" "B.Cu")
		(net "GND")
	)
	(via
		(at 254.49911 -85.30844)
		(size 0.508)
		(drill 0.254)
		(layers "F.Cu" "B.Cu")
		(net "GND")
	)
	(via
		(at 218.44254 -9.143746)
		(size 0.508)
		(drill 0.254)
		(layers "F.Cu" "B.Cu")
		(net "GND")
	)
	(via
		(at 356.72268 -146.38782)
		(size 0.508)
		(drill 0.254)
		(layers "F.Cu" "B.Cu")
		(net "GND")
	)
	(via
		(at 339.5726 -59.679586)
		(size 0.508)
		(drill 0.254)
		(layers "F.Cu" "B.Cu")
		(net "GND")
	)
	(via
		(at 459.1304 -140.219938)
		(size 0.508)
		(drill 0.254)
		(layers "F.Cu" "B.Cu")
		(net "GND")
	)
	(via
		(at 415.417762 -86.397084)
		(size 0.508)
		(drill 0.254)
		(layers "F.Cu" "B.Cu")
		(net "GND")
	)
	(via
		(at 115.923822 -65.810384)
		(size 0.508)
		(drill 0.254)
		(layers "F.Cu" "B.Cu")
		(net "GND")
	)
	(via
		(at 221.04985 -11.916156)
		(size 0.508)
		(drill 0.254)
		(layers "F.Cu" "B.Cu")
		(net "GND")
	)
	(via
		(at 124.793248 -98.995738)
		(size 0.508)
		(drill 0.254)
		(layers "F.Cu" "B.Cu")
		(net "GND")
	)
	(via
		(at 36.8808 -86.6902)
		(size 0.5588)
		(drill 0.3048)
		(layers "F.Cu" "B.Cu")
		(net "GND")
	)
	(via
		(at 31.908496 -80.551782)
		(size 0.508)
		(drill 0.254)
		(layers "F.Cu" "B.Cu")
		(net "GND")
	)
	(via
		(at 486.440734 -165.596824)
		(size 0.5588)
		(drill 0.3048)
		(layers "F.Cu" "B.Cu")
		(net "GND")
	)
	(via
		(at 291.422074 -140.617956)
		(size 0.508)
		(drill 0.254)
		(layers "F.Cu" "B.Cu")
		(net "GND")
	)
	(via
		(at 482.999796 -113.77422)
		(size 0.508)
		(drill 0.254)
		(layers "F.Cu" "B.Cu")
		(net "GND")
	)
	(via
		(at 484.877618 -51.208686)
		(size 0.508)
		(drill 0.254)
		(layers "F.Cu" "B.Cu")
		(net "GND")
	)
	(via
		(at 310.122062 -154.1018)
		(size 0.508)
		(drill 0.254)
		(layers "F.Cu" "B.Cu")
		(net "GND")
	)
	(via
		(at 242.041934 14.926056)
		(size 0.5588)
		(drill 0.3048)
		(layers "F.Cu" "B.Cu")
		(net "GND")
	)
	(via
		(at 459.83779 -144.480534)
		(size 0.508)
		(drill 0.254)
		(layers "F.Cu" "B.Cu")
		(net "GND")
	)
	(via
		(at 349.4786 -153.455624)
		(size 0.508)
		(drill 0.254)
		(layers "F.Cu" "B.Cu")
		(net "GND")
	)
	(via
		(at 312.391298 -153.552144)
		(size 0.508)
		(drill 0.254)
		(layers "F.Cu" "B.Cu")
		(net "GND")
	)
	(via
		(at 262.22579 -98.681286)
		(size 0.508)
		(drill 0.254)
		(layers "F.Cu" "B.Cu")
		(net "GND")
	)
	(via
		(at 101.813868 -70.844156)
		(size 0.5588)
		(drill 0.3048)
		(layers "F.Cu" "B.Cu")
		(net "GND")
	)
	(via
		(at 383.77495 -122.104404)
		(size 0.508)
		(drill 0.254)
		(layers "F.Cu" "B.Cu")
		(net "GND")
	)
	(via
		(at 411.4927 -9.0297)
		(size 0.508)
		(drill 0.254)
		(layers "F.Cu" "B.Cu")
		(net "GND")
	)
	(via
		(at 330.454 -117.0686)
		(size 0.508)
		(drill 0.254)
		(layers "F.Cu" "B.Cu")
		(net "GND")
	)
	(via
		(at 181.2671 -138.8745)
		(size 0.508)
		(drill 0.254)
		(layers "F.Cu" "B.Cu")
		(net "GND")
	)
	(via
		(at 355.06152 -77.37856)
		(size 0.508)
		(drill 0.254)
		(layers "F.Cu" "B.Cu")
		(net "GND")
	)
	(via
		(at 388.142734 -167.832024)
		(size 0.5588)
		(drill 0.3048)
		(layers "F.Cu" "B.Cu")
		(net "GND")
	)
	(via
		(at 421.09009 -34.134806)
		(size 0.4572)
		(drill 0.2032)
		(layers "F.Cu" "B.Cu")
		(net "GND")
	)
	(via
		(at 373.320818 -151.473662)
		(size 0.508)
		(drill 0.254)
		(layers "F.Cu" "B.Cu")
		(net "GND")
	)
	(via
		(at 133.39953 -136.397746)
		(size 0.508)
		(drill 0.254)
		(layers "F.Cu" "B.Cu")
		(net "GND")
	)
	(via
		(at 446.62725 -45.611796)
		(size 0.508)
		(drill 0.254)
		(layers "F.Cu" "B.Cu")
		(net "GND")
	)
	(via
		(at 333.481934 9.084056)
		(size 0.5588)
		(drill 0.3048)
		(layers "F.Cu" "B.Cu")
		(net "GND")
	)
	(via
		(at 181.2671 -137.3505)
		(size 0.508)
		(drill 0.254)
		(layers "F.Cu" "B.Cu")
		(net "GND")
	)
	(via
		(at 258.79171 -87.784686)
		(size 0.508)
		(drill 0.254)
		(layers "F.Cu" "B.Cu")
		(net "GND")
	)
	(via
		(at 85.206332 -88.775286)
		(size 0.508)
		(drill 0.254)
		(layers "F.Cu" "B.Cu")
		(net "GND")
	)
	(via
		(at 128.68148 -148.7678)
		(size 0.508)
		(drill 0.254)
		(layers "F.Cu" "B.Cu")
		(net "GND")
	)
	(via
		(at 301.736506 -141.1478)
		(size 0.508)
		(drill 0.254)
		(layers "F.Cu" "B.Cu")
		(net "GND")
	)
	(via
		(at 246.772684 -71.935086)
		(size 0.508)
		(drill 0.254)
		(layers "F.Cu" "B.Cu")
		(net "GND")
	)
	(via
		(at 64.081406 -21.5138)
		(size 0.508)
		(drill 0.254)
		(layers "F.Cu" "B.Cu")
		(net "GND")
	)
	(via
		(at 263.94283 -98.681286)
		(size 0.508)
		(drill 0.254)
		(layers "F.Cu" "B.Cu")
		(net "GND")
	)
	(via
		(at 62.792102 -136.397746)
		(size 0.508)
		(drill 0.254)
		(layers "F.Cu" "B.Cu")
		(net "GND")
	)
	(via
		(at 464.846924 -162.243262)
		(size 0.5588)
		(drill 0.3048)
		(layers "F.Cu" "B.Cu")
		(net "GND")
	)
	(via
		(at 237.136432 -150.749)
		(size 0.508)
		(drill 0.254)
		(layers "F.Cu" "B.Cu")
		(net "GND")
	)
	(via
		(at 357.862124 -162.268662)
		(size 0.5588)
		(drill 0.3048)
		(layers "F.Cu" "B.Cu")
		(net "GND")
	)
	(via
		(at 157.49778 -12.923012)
		(size 0.508)
		(drill 0.254)
		(layers "F.Cu" "B.Cu")
		(net "GND")
	)
	(via
		(at 394.67155 -120.387364)
		(size 0.508)
		(drill 0.254)
		(layers "F.Cu" "B.Cu")
		(net "GND")
	)
	(via
		(at 127.392176 -148.767292)
		(size 0.508)
		(drill 0.254)
		(layers "F.Cu" "B.Cu")
		(net "GND")
	)
	(via
		(at 256.21615 -60.54344)
		(size 0.508)
		(drill 0.254)
		(layers "F.Cu" "B.Cu")
		(net "GND")
	)
	(via
		(at 469.930734 -165.596824)
		(size 0.5588)
		(drill 0.3048)
		(layers "F.Cu" "B.Cu")
		(net "GND")
	)
	(via
		(at 435.081934 14.926056)
		(size 0.5588)
		(drill 0.3048)
		(layers "F.Cu" "B.Cu")
		(net "GND")
	)
	(via
		(at 131.661408 -86.117938)
		(size 0.508)
		(drill 0.254)
		(layers "F.Cu" "B.Cu")
		(net "GND")
	)
	(via
		(at 74.904346 -69.953886)
		(size 0.508)
		(drill 0.254)
		(layers "F.Cu" "B.Cu")
		(net "GND")
	)
	(via
		(at 489.691934 10.354056)
		(size 0.5588)
		(drill 0.3048)
		(layers "F.Cu" "B.Cu")
		(net "GND")
	)
	(via
		(at 389.361934 14.926056)
		(size 0.5588)
		(drill 0.3048)
		(layers "F.Cu" "B.Cu")
		(net "GND")
	)
	(via
		(at 356.051358 -141.638528)
		(size 0.508)
		(drill 0.254)
		(layers "F.Cu" "B.Cu")
		(net "GND")
	)
	(via
		(at 251.563124 -162.243262)
		(size 0.5588)
		(drill 0.3048)
		(layers "F.Cu" "B.Cu")
		(net "GND")
	)
	(via
		(at 116.361464 -139.170156)
		(size 0.508)
		(drill 0.254)
		(layers "F.Cu" "B.Cu")
		(net "GND")
	)
	(via
		(at 121.074688 -61.847984)
		(size 0.508)
		(drill 0.254)
		(layers "F.Cu" "B.Cu")
		(net "GND")
	)
	(via
		(at 204.049884 -9.156446)
		(size 0.508)
		(drill 0.254)
		(layers "F.Cu" "B.Cu")
		(net "GND")
	)
	(via
		(at 200.6346 -78.3336)
		(size 0.5588)
		(drill 0.3048)
		(layers "F.Cu" "B.Cu")
		(net "GND")
	)
	(via
		(at 41.501314 -154.063446)
		(size 0.508)
		(drill 0.254)
		(layers "F.Cu" "B.Cu")
		(net "GND")
	)
	(via
		(at 13.108178 -129.983738)
		(size 0.508)
		(drill 0.254)
		(layers "F.Cu" "B.Cu")
		(net "GND")
	)
	(via
		(at 192.024 -136.398)
		(size 0.508)
		(drill 0.254)
		(layers "F.Cu" "B.Cu")
		(net "GND")
	)
	(via
		(at 188.981334 -167.832024)
		(size 0.5588)
		(drill 0.3048)
		(layers "F.Cu" "B.Cu")
		(net "GND")
	)
	(via
		(at 443.971934 13.910056)
		(size 0.5588)
		(drill 0.3048)
		(layers "F.Cu" "B.Cu")
		(net "GND")
	)
	(via
		(at 485.70642 -42.50182)
		(size 0.508)
		(drill 0.254)
		(layers "F.Cu" "B.Cu")
		(net "GND")
	)
	(via
		(at 251.923804 -81.841086)
		(size 0.508)
		(drill 0.254)
		(layers "F.Cu" "B.Cu")
		(net "GND")
	)
	(via
		(at 375.145046 -76.695046)
		(size 0.4572)
		(drill 0.2032)
		(layers "F.Cu" "B.Cu")
		(net "GND")
	)
	(via
		(at 418.571934 14.926056)
		(size 0.5588)
		(drill 0.3048)
		(layers "F.Cu" "B.Cu")
		(net "GND")
	)
	(via
		(at 210.387946 -131.600956)
		(size 0.508)
		(drill 0.254)
		(layers "F.Cu" "B.Cu")
		(net "GND")
	)
	(via
		(at 145.521934 9.084056)
		(size 0.5588)
		(drill 0.3048)
		(layers "F.Cu" "B.Cu")
		(net "GND")
	)
	(via
		(at 481.360734 -165.596824)
		(size 0.5588)
		(drill 0.3048)
		(layers "F.Cu" "B.Cu")
		(net "GND")
	)
	(via
		(at 123.931934 9.084056)
		(size 0.5588)
		(drill 0.3048)
		(layers "F.Cu" "B.Cu")
		(net "GND")
	)
	(via
		(at 356.747826 -141.57452)
		(size 0.508)
		(drill 0.254)
		(layers "F.Cu" "B.Cu")
		(net "GND")
	)
	(via
		(at 136.74217 -155.600146)
		(size 0.508)
		(drill 0.254)
		(layers "F.Cu" "B.Cu")
		(net "GND")
	)
	(via
		(at 112.774222 -98.005138)
		(size 0.508)
		(drill 0.254)
		(layers "F.Cu" "B.Cu")
		(net "GND")
	)
	(via
		(at 254.915924 -162.243262)
		(size 0.5588)
		(drill 0.3048)
		(layers "F.Cu" "B.Cu")
		(net "GND")
	)
	(via
		(at 85.206332 -60.047886)
		(size 0.508)
		(drill 0.254)
		(layers "F.Cu" "B.Cu")
		(net "GND")
	)
	(via
		(at 274.056348 -63.829184)
		(size 0.508)
		(drill 0.254)
		(layers "F.Cu" "B.Cu")
		(net "GND")
	)
	(via
		(at 59.449462 -21.517356)
		(size 0.508)
		(drill 0.254)
		(layers "F.Cu" "B.Cu")
		(net "GND")
	)
	(via
		(at 348.0054 -36.83)
		(size 0.508)
		(drill 0.254)
		(layers "F.Cu" "B.Cu")
		(net "GND")
	)
	(via
		(at 170.4594 -58.9788)
		(size 0.508)
		(drill 0.254)
		(layers "F.Cu" "B.Cu")
		(net "GND")
	)
	(via
		(at 201.176128 -60.198)
		(size 0.5588)
		(drill 0.3048)
		(layers "F.Cu" "B.Cu")
		(net "GND")
	)
	(via
		(at 30.278324 -162.243262)
		(size 0.5588)
		(drill 0.3048)
		(layers "F.Cu" "B.Cu")
		(net "GND")
	)
	(via
		(at 49.281334 -167.832024)
		(size 0.5588)
		(drill 0.3048)
		(layers "F.Cu" "B.Cu")
		(net "GND")
	)
	(via
		(at 69.753226 -61.038486)
		(size 0.508)
		(drill 0.254)
		(layers "F.Cu" "B.Cu")
		(net "GND")
	)
	(via
		(at 422.381934 9.084056)
		(size 0.5588)
		(drill 0.3048)
		(layers "F.Cu" "B.Cu")
		(net "GND")
	)
	(via
		(at 282.859734 -167.832024)
		(size 0.5588)
		(drill 0.3048)
		(layers "F.Cu" "B.Cu")
		(net "GND")
	)
	(via
		(at 199.9488 -70.2056)
		(size 0.5588)
		(drill 0.3048)
		(layers "F.Cu" "B.Cu")
		(net "GND")
	)
	(via
		(at 397.540734 -166.714424)
		(size 0.5588)
		(drill 0.3048)
		(layers "F.Cu" "B.Cu")
		(net "GND")
	)
	(via
		(at 363.085126 -3.420364)
		(size 0.508)
		(drill 0.254)
		(layers "F.Cu" "B.Cu")
		(net "GND")
	)
	(via
		(at 318.90462 -120.59158)
		(size 0.508)
		(drill 0.254)
		(layers "F.Cu" "B.Cu")
		(net "GND")
	)
	(via
		(at 128.69418 -18.6817)
		(size 0.508)
		(drill 0.254)
		(layers "F.Cu" "B.Cu")
		(net "GND")
	)
	(via
		(at 114.206782 -55.904384)
		(size 0.508)
		(drill 0.254)
		(layers "F.Cu" "B.Cu")
		(net "GND")
	)
	(via
		(at 237.329218 -50.63744)
		(size 0.508)
		(drill 0.254)
		(layers "F.Cu" "B.Cu")
		(net "GND")
	)
	(via
		(at 280.924254 -53.923184)
		(size 0.508)
		(drill 0.254)
		(layers "F.Cu" "B.Cu")
		(net "GND")
	)
	(via
		(at 245.055644 -59.057286)
		(size 0.508)
		(drill 0.254)
		(layers "F.Cu" "B.Cu")
		(net "GND")
	)
	(via
		(at 193.781934 9.084056)
		(size 0.5588)
		(drill 0.3048)
		(layers "F.Cu" "B.Cu")
		(net "GND")
	)
	(via
		(at 293.688008 -23.549356)
		(size 0.508)
		(drill 0.254)
		(layers "F.Cu" "B.Cu")
		(net "GND")
	)
	(via
		(at 202.349862 -2.314956)
		(size 0.508)
		(drill 0.254)
		(layers "F.Cu" "B.Cu")
		(net "GND")
	)
	(via
		(at 344.802206 3.663696)
		(size 0.508)
		(drill 0.254)
		(layers "F.Cu" "B.Cu")
		(net "GND")
	)
	(via
		(at 306.811934 14.926056)
		(size 0.5588)
		(drill 0.3048)
		(layers "F.Cu" "B.Cu")
		(net "GND")
	)
	(via
		(at 136.74598 -124.614686)
		(size 0.508)
		(drill 0.254)
		(layers "F.Cu" "B.Cu")
		(net "GND")
	)
	(via
		(at 257.93319 -60.54344)
		(size 0.508)
		(drill 0.254)
		(layers "F.Cu" "B.Cu")
		(net "GND")
	)
	(via
		(at 486.194608 -29.445712)
		(size 0.508)
		(drill 0.254)
		(layers "F.Cu" "B.Cu")
		(net "GND")
	)
	(via
		(at 463.021934 11.624056)
		(size 0.5588)
		(drill 0.3048)
		(layers "F.Cu" "B.Cu")
		(net "GND")
	)
	(via
		(at 185.6994 -68.4022)
		(size 0.508)
		(drill 0.254)
		(layers "F.Cu" "B.Cu")
		(net "GND")
	)
	(via
		(at 233.036618 -64.010286)
		(size 0.508)
		(drill 0.254)
		(layers "F.Cu" "B.Cu")
		(net "GND")
	)
	(via
		(at 425.476924 -162.243262)
		(size 0.5588)
		(drill 0.3048)
		(layers "F.Cu" "B.Cu")
		(net "GND")
	)
	(via
		(at 51.79949 -9.156446)
		(size 0.508)
		(drill 0.254)
		(layers "F.Cu" "B.Cu")
		(net "GND")
	)
	(via
		(at 455.47407 -42.044874)
		(size 0.5588)
		(drill 0.3048)
		(layers "F.Cu" "B.Cu")
		(net "GND")
	)
	(via
		(at 30.503368 -153.6446)
		(size 0.508)
		(drill 0.254)
		(layers "F.Cu" "B.Cu")
		(net "GND")
	)
	(via
		(at 4.0132 -147.193)
		(size 0.508)
		(drill 0.254)
		(layers "F.Cu" "B.Cu")
		(net "GND")
	)
	(via
		(at 336.5754 -112.395)
		(size 0.508)
		(drill 0.254)
		(layers "F.Cu" "B.Cu")
		(net "GND")
	)
	(via
		(at 6.65099 -17.022318)
		(size 0.508)
		(drill 0.254)
		(layers "F.Cu" "B.Cu")
		(net "GND")
	)
	(via
		(at 44.092114 -155.600146)
		(size 0.508)
		(drill 0.254)
		(layers "F.Cu" "B.Cu")
		(net "GND")
	)
	(via
		(at 344.8558 -26.6573)
		(size 0.508)
		(drill 0.254)
		(layers "F.Cu" "B.Cu")
		(net "GND")
	)
	(via
		(at 252.782324 -60.54344)
		(size 0.508)
		(drill 0.254)
		(layers "F.Cu" "B.Cu")
		(net "GND")
	)
	(via
		(at 287.21812 -79.678784)
		(size 0.508)
		(drill 0.254)
		(layers "F.Cu" "B.Cu")
		(net "GND")
	)
	(via
		(at 296.69994 -11.916156)
		(size 0.508)
		(drill 0.254)
		(layers "F.Cu" "B.Cu")
		(net "GND")
	)
	(via
		(at 295.80332 -62.838584)
		(size 0.508)
		(drill 0.254)
		(layers "F.Cu" "B.Cu")
		(net "GND")
	)
	(via
		(at 445.106806 -33.5915)
		(size 0.4572)
		(drill 0.2032)
		(layers "F.Cu" "B.Cu")
		(net "GND")
	)
	(via
		(at 390.70915 -102.756716)
		(size 0.508)
		(drill 0.254)
		(layers "F.Cu" "B.Cu")
		(net "GND")
	)
	(via
		(at 238.44123 -134.349744)
		(size 0.508)
		(drill 0.254)
		(layers "F.Cu" "B.Cu")
		(net "GND")
	)
	(via
		(at 55.351934 9.084056)
		(size 0.5588)
		(drill 0.3048)
		(layers "F.Cu" "B.Cu")
		(net "GND")
	)
	(via
		(at 441.431934 14.926056)
		(size 0.5588)
		(drill 0.3048)
		(layers "F.Cu" "B.Cu")
		(net "GND")
	)
	(via
		(at 307.041804 -81.164176)
		(size 0.508)
		(drill 0.254)
		(layers "F.Cu" "B.Cu")
		(net "GND")
	)
	(via
		(at 91.750134 -167.832024)
		(size 0.5588)
		(drill 0.3048)
		(layers "F.Cu" "B.Cu")
		(net "GND")
	)
	(via
		(at 379.81255 -115.236244)
		(size 0.508)
		(drill 0.254)
		(layers "F.Cu" "B.Cu")
		(net "GND")
	)
	(via
		(at 134.236714 -62.838584)
		(size 0.508)
		(drill 0.254)
		(layers "F.Cu" "B.Cu")
		(net "GND")
	)
	(via
		(at 391.78865 -128.1176)
		(size 0.508)
		(drill 0.254)
		(layers "F.Cu" "B.Cu")
		(net "GND")
	)
	(via
		(at -1.3462 -50.848514)
		(size 0.5588)
		(drill 0.3048)
		(layers "F.Cu" "B.Cu")
		(net "GND")
	)
	(via
		(at 279.084024 -74.381614)
		(size 0.5588)
		(drill 0.3048)
		(layers "F.Cu" "B.Cu")
		(net "GND")
	)
	(via
		(at 235.46181 -11.916156)
		(size 0.508)
		(drill 0.254)
		(layers "F.Cu" "B.Cu")
		(net "GND")
	)
	(via
		(at 30.3022 -101.8286)
		(size 0.508)
		(drill 0.254)
		(layers "F.Cu" "B.Cu")
		(net "GND")
	)
	(via
		(at 338.739734 -167.832024)
		(size 0.5588)
		(drill 0.3048)
		(layers "F.Cu" "B.Cu")
		(net "GND")
	)
	(via
		(at 232.94975 -144.462246)
		(size 0.508)
		(drill 0.254)
		(layers "F.Cu" "B.Cu")
		(net "GND")
	)
	(via
		(at 303.031906 -129.5654)
		(size 0.508)
		(drill 0.254)
		(layers "F.Cu" "B.Cu")
		(net "GND")
	)
	(via
		(at 293.22776 -87.108538)
		(size 0.508)
		(drill 0.254)
		(layers "F.Cu" "B.Cu")
		(net "GND")
	)
	(via
		(at 135.061452 -21.517356)
		(size 0.508)
		(drill 0.254)
		(layers "F.Cu" "B.Cu")
		(net "GND")
	)
	(via
		(at 212.54974 -150.219156)
		(size 0.508)
		(drill 0.254)
		(layers "F.Cu" "B.Cu")
		(net "GND")
	)
	(via
		(at 40.767254 -84.57311)
		(size 0.5588)
		(drill 0.3048)
		(layers "F.Cu" "B.Cu")
		(net "GND")
	)
	(via
		(at 302.976534 -167.832024)
		(size 0.5588)
		(drill 0.3048)
		(layers "F.Cu" "B.Cu")
		(net "GND")
	)
	(via
		(at 283.0322 -4.2926)
		(size 0.508)
		(drill 0.254)
		(layers "F.Cu" "B.Cu")
		(net "GND")
	)
	(via
		(at 367.145316 -68.695316)
		(size 0.4572)
		(drill 0.2032)
		(layers "F.Cu" "B.Cu")
		(net "GND")
	)
	(via
		(at 232.099866 -136.410446)
		(size 0.508)
		(drill 0.254)
		(layers "F.Cu" "B.Cu")
		(net "GND")
	)
	(via
		(at 444.485014 -5.375402)
		(size 0.508)
		(drill 0.254)
		(layers "F.Cu" "B.Cu")
		(net "GND")
	)
	(via
		(at 345.059 -85.9536)
		(size 0.508)
		(drill 0.254)
		(layers "F.Cu" "B.Cu")
		(net "GND")
	)
	(via
		(at 443.427358 -45.611796)
		(size 0.508)
		(drill 0.254)
		(layers "F.Cu" "B.Cu")
		(net "GND")
	)
	(via
		(at 53.448712 -7.1501)
		(size 0.508)
		(drill 0.254)
		(layers "F.Cu" "B.Cu")
		(net "GND")
	)
	(via
		(at 354.418138 -26.93416)
		(size 0.508)
		(drill 0.254)
		(layers "F.Cu" "B.Cu")
		(net "GND")
	)
	(via
		(at 204.899768 -134.861046)
		(size 0.508)
		(drill 0.254)
		(layers "F.Cu" "B.Cu")
		(net "GND")
	)
	(via
		(at 337.291934 9.084056)
		(size 0.5588)
		(drill 0.3048)
		(layers "F.Cu" "B.Cu")
		(net "GND")
	)
	(via
		(at 167.4368 -8.001)
		(size 0.508)
		(drill 0.254)
		(layers "F.Cu" "B.Cu")
		(net "GND")
	)
	(via
		(at 76.099924 -162.243262)
		(size 0.5588)
		(drill 0.3048)
		(layers "F.Cu" "B.Cu")
		(net "GND")
	)
	(via
		(at 290.6522 -86.612984)
		(size 0.508)
		(drill 0.254)
		(layers "F.Cu" "B.Cu")
		(net "GND")
	)
	(via
		(at 357.9495 -16.601186)
		(size 0.508)
		(drill 0.254)
		(layers "F.Cu" "B.Cu")
		(net "GND")
	)
	(via
		(at 190.430404 -52.714398)
		(size 0.508)
		(drill 0.254)
		(layers "F.Cu" "B.Cu")
		(net "GND")
	)
	(via
		(at 413.1056 -1.1684)
		(size 0.508)
		(drill 0.254)
		(layers "F.Cu" "B.Cu")
		(net "GND")
	)
	(via
		(at 160.655 -60.579)
		(size 0.508)
		(drill 0.254)
		(layers "F.Cu" "B.Cu")
		(net "GND")
	)
	(via
		(at 198.099934 -136.410446)
		(size 0.508)
		(drill 0.254)
		(layers "F.Cu" "B.Cu")
		(net "GND")
	)
	(via
		(at 301.742602 0.457454)
		(size 0.508)
		(drill 0.254)
		(layers "F.Cu" "B.Cu")
		(net "GND")
	)
	(via
		(at 121.074688 -53.923184)
		(size 0.508)
		(drill 0.254)
		(layers "F.Cu" "B.Cu")
		(net "GND")
	)
	(via
		(at 177.14976 -16.9926)
		(size 0.508)
		(drill 0.254)
		(layers "F.Cu" "B.Cu")
		(net "GND")
	)
	(via
		(at 84.910168 -140.208)
		(size 0.508)
		(drill 0.254)
		(layers "F.Cu" "B.Cu")
		(net "GND")
	)
	(via
		(at 200.8886 -64.4906)
		(size 0.508)
		(drill 0.254)
		(layers "F.Cu" "B.Cu")
		(net "GND")
	)
	(via
		(at 202.349862 -18.757646)
		(size 0.508)
		(drill 0.254)
		(layers "F.Cu" "B.Cu")
		(net "GND")
	)
	(via
		(at 386.947664 -145.783046)
		(size 0.508)
		(drill 0.254)
		(layers "F.Cu" "B.Cu")
		(net "GND")
	)
	(via
		(at 45.387514 -23.549356)
		(size 0.508)
		(drill 0.254)
		(layers "F.Cu" "B.Cu")
		(net "GND")
	)
	(via
		(at 311.0865 -23.495)
		(size 0.508)
		(drill 0.254)
		(layers "F.Cu" "B.Cu")
		(net "GND")
	)
	(via
		(at 78.14945 -2.3622)
		(size 0.508)
		(drill 0.254)
		(layers "F.Cu" "B.Cu")
		(net "GND")
	)
	(via
		(at 67.099434 -139.170156)
		(size 0.508)
		(drill 0.254)
		(layers "F.Cu" "B.Cu")
		(net "GND")
	)
	(via
		(at 141.963394 -85.127338)
		(size 0.508)
		(drill 0.254)
		(layers "F.Cu" "B.Cu")
		(net "GND")
	)
	(via
		(at 438.872122 -151.674068)
		(size 0.508)
		(drill 0.254)
		(layers "F.Cu" "B.Cu")
		(net "GND")
	)
	(via
		(at 73.4441 -9.0805)
		(size 0.508)
		(drill 0.254)
		(layers "F.Cu" "B.Cu")
		(net "GND")
	)
	(via
		(at 438.176924 -162.243262)
		(size 0.5588)
		(drill 0.3048)
		(layers "F.Cu" "B.Cu")
		(net "GND")
	)
	(via
		(at 82.420968 -26.289)
		(size 0.508)
		(drill 0.254)
		(layers "F.Cu" "B.Cu")
		(net "GND")
	)
	(via
		(at 385.75615 -122.104404)
		(size 0.508)
		(drill 0.254)
		(layers "F.Cu" "B.Cu")
		(net "GND")
	)
	(via
		(at 286.3596 -98.995738)
		(size 0.508)
		(drill 0.254)
		(layers "F.Cu" "B.Cu")
		(net "GND")
	)
	(via
		(at 240.763298 -84.31784)
		(size 0.508)
		(drill 0.254)
		(layers "F.Cu" "B.Cu")
		(net "GND")
	)
	(via
		(at 75.762866 -57.57164)
		(size 0.508)
		(drill 0.254)
		(layers "F.Cu" "B.Cu")
		(net "GND")
	)
	(via
		(at 332.7654 -112.395)
		(size 0.508)
		(drill 0.254)
		(layers "F.Cu" "B.Cu")
		(net "GND")
	)
	(via
		(at 129.999486 -148.771356)
		(size 0.508)
		(drill 0.254)
		(layers "F.Cu" "B.Cu")
		(net "GND")
	)
	(via
		(at 344.4113 0.001778)
		(size 0.508)
		(drill 0.254)
		(layers "F.Cu" "B.Cu")
		(net "GND")
	)
	(via
		(at 303.044606 -155.5369)
		(size 0.508)
		(drill 0.254)
		(layers "F.Cu" "B.Cu")
		(net "GND")
	)
	(via
		(at 199.992234 -79.048864)
		(size 0.508)
		(drill 0.254)
		(layers "F.Cu" "B.Cu")
		(net "GND")
	)
	(via
		(at 102.376224 -95.709486)
		(size 0.508)
		(drill 0.254)
		(layers "F.Cu" "B.Cu")
		(net "GND")
	)
	(via
		(at 290.6522 -74.725784)
		(size 0.508)
		(drill 0.254)
		(layers "F.Cu" "B.Cu")
		(net "GND")
	)
	(via
		(at 13.518134 -167.832024)
		(size 0.5588)
		(drill 0.3048)
		(layers "F.Cu" "B.Cu")
		(net "GND")
	)
	(via
		(at 346.38742 -32.766)
		(size 0.508)
		(drill 0.254)
		(layers "F.Cu" "B.Cu")
		(net "GND")
	)
	(via
		(at 183.621934 9.084056)
		(size 0.5588)
		(drill 0.3048)
		(layers "F.Cu" "B.Cu")
		(net "GND")
	)
	(via
		(at 225.201734 -154.063446)
		(size 0.508)
		(drill 0.254)
		(layers "F.Cu" "B.Cu")
		(net "GND")
	)
	(via
		(at 209.092546 -155.600146)
		(size 0.508)
		(drill 0.254)
		(layers "F.Cu" "B.Cu")
		(net "GND")
	)
	(via
		(at 85.831934 9.084056)
		(size 0.5588)
		(drill 0.3048)
		(layers "F.Cu" "B.Cu")
		(net "GND")
	)
	(via
		(at 300.772068 -3.762756)
		(size 0.508)
		(drill 0.254)
		(layers "F.Cu" "B.Cu")
		(net "GND")
	)
	(via
		(at 37.7952 -47.0662)
		(size 0.508)
		(drill 0.254)
		(layers "F.Cu" "B.Cu")
		(net "GND")
	)
	(via
		(at 427.965108 -3.421888)
		(size 0.508)
		(drill 0.254)
		(layers "F.Cu" "B.Cu")
		(net "GND")
	)
	(via
		(at 1.155446 -157.653228)
		(size 0.5588)
		(drill 0.3048)
		(layers "F.Cu" "B.Cu")
		(net "GND")
	)
	(via
		(at 349.5294 -31.7373)
		(size 0.508)
		(drill 0.254)
		(layers "F.Cu" "B.Cu")
		(net "GND")
	)
	(via
		(at 67.099434 -2.314956)
		(size 0.508)
		(drill 0.254)
		(layers "F.Cu" "B.Cu")
		(net "GND")
	)
	(via
		(at 468.660734 -166.714424)
		(size 0.5588)
		(drill 0.3048)
		(layers "F.Cu" "B.Cu")
		(net "GND")
	)
	(via
		(at 278.90216 -136.327642)
		(size 0.508)
		(drill 0.254)
		(layers "F.Cu" "B.Cu")
		(net "GND")
	)
	(via
		(at 18.9484 -127.524256)
		(size 0.508)
		(drill 0.254)
		(layers "F.Cu" "B.Cu")
		(net "GND")
	)
	(via
		(at 272.027904 -3.3528)
		(size 0.508)
		(drill 0.254)
		(layers "F.Cu" "B.Cu")
		(net "GND")
	)
	(via
		(at 191.700404 -52.714398)
		(size 0.508)
		(drill 0.254)
		(layers "F.Cu" "B.Cu")
		(net "GND")
	)
	(via
		(at 212.831934 14.926056)
		(size 0.5588)
		(drill 0.3048)
		(layers "F.Cu" "B.Cu")
		(net "GND")
	)
	(via
		(at 457.941934 14.926056)
		(size 0.5588)
		(drill 0.3048)
		(layers "F.Cu" "B.Cu")
		(net "GND")
	)
	(via
		(at 49.24933 -3.762756)
		(size 0.508)
		(drill 0.254)
		(layers "F.Cu" "B.Cu")
		(net "GND")
	)
	(via
		(at 496.600734 -167.832024)
		(size 0.5588)
		(drill 0.3048)
		(layers "F.Cu" "B.Cu")
		(net "GND")
	)
	(via
		(at 35.453828 -88.3412)
		(size 0.508)
		(drill 0.254)
		(layers "F.Cu" "B.Cu")
		(net "GND")
	)
	(via
		(at 3.464306 -136.444482)
		(size 0.508)
		(drill 0.254)
		(layers "F.Cu" "B.Cu")
		(net "GND")
	)
	(via
		(at 408.43708 -90.551)
		(size 0.508)
		(drill 0.254)
		(layers "F.Cu" "B.Cu")
		(net "GND")
	)
	(via
		(at 69.753226 -99.67214)
		(size 0.508)
		(drill 0.254)
		(layers "F.Cu" "B.Cu")
		(net "GND")
	)
	(via
		(at 42.411396 -129.568956)
		(size 0.508)
		(drill 0.254)
		(layers "F.Cu" "B.Cu")
		(net "GND")
	)
	(via
		(at 229.091236 -7.095744)
		(size 0.508)
		(drill 0.254)
		(layers "F.Cu" "B.Cu")
		(net "GND")
	)
	(via
		(at 237.038134 -167.832024)
		(size 0.5588)
		(drill 0.3048)
		(layers "F.Cu" "B.Cu")
		(net "GND")
	)
	(via
		(at 345.2114 -148.8948)
		(size 0.508)
		(drill 0.254)
		(layers "F.Cu" "B.Cu")
		(net "GND")
	)
	(via
		(at 14.151102 1.29413)
		(size 0.508)
		(drill 0.254)
		(layers "F.Cu" "B.Cu")
		(net "GND")
	)
	(via
		(at 297.520106 -82.650584)
		(size 0.508)
		(drill 0.254)
		(layers "F.Cu" "B.Cu")
		(net "GND")
	)
	(via
		(at 11.2014 -24.8412)
		(size 0.508)
		(drill 0.254)
		(layers "F.Cu" "B.Cu")
		(net "GND")
	)
	(via
		(at 250.206764 -57.076086)
		(size 0.508)
		(drill 0.254)
		(layers "F.Cu" "B.Cu")
		(net "GND")
	)
	(via
		(at 204.049884 -129.568956)
		(size 0.508)
		(drill 0.254)
		(layers "F.Cu" "B.Cu")
		(net "GND")
	)
	(via
		(at 301.729648 -13.8938)
		(size 0.508)
		(drill 0.254)
		(layers "F.Cu" "B.Cu")
		(net "GND")
	)
	(via
		(at 431.4444 -148.5392)
		(size 0.508)
		(drill 0.254)
		(layers "F.Cu" "B.Cu")
		(net "GND")
	)
	(via
		(at 140.199364 -7.607046)
		(size 0.508)
		(drill 0.254)
		(layers "F.Cu" "B.Cu")
		(net "GND")
	)
	(via
		(at 207.449928 -9.156446)
		(size 0.508)
		(drill 0.254)
		(layers "F.Cu" "B.Cu")
		(net "GND")
	)
	(via
		(at 303.041304 -16.696944)
		(size 0.508)
		(drill 0.254)
		(layers "F.Cu" "B.Cu")
		(net "GND")
	)
	(via
		(at 42.781982 -77.128878)
		(size 0.5588)
		(drill 0.3048)
		(layers "F.Cu" "B.Cu")
		(net "GND")
	)
	(via
		(at 281.399996 -18.757646)
		(size 0.508)
		(drill 0.254)
		(layers "F.Cu" "B.Cu")
		(net "GND")
	)
	(via
		(at 200.881234 -71.555864)
		(size 0.508)
		(drill 0.254)
		(layers "F.Cu" "B.Cu")
		(net "GND")
	)
	(via
		(at 137.567924 -162.243262)
		(size 0.5588)
		(drill 0.3048)
		(layers "F.Cu" "B.Cu")
		(net "GND")
	)
	(via
		(at 292.392608 -155.600146)
		(size 0.508)
		(drill 0.254)
		(layers "F.Cu" "B.Cu")
		(net "GND")
	)
	(via
		(at 498.581934 12.894056)
		(size 0.5588)
		(drill 0.3048)
		(layers "F.Cu" "B.Cu")
		(net "GND")
	)
	(via
		(at 439.903362 -33.962848)
		(size 0.4572)
		(drill 0.2032)
		(layers "F.Cu" "B.Cu")
		(net "GND")
	)
	(via
		(at 464.549744 -63.4746)
		(size 0.508)
		(drill 0.254)
		(layers "F.Cu" "B.Cu")
		(net "GND")
	)
	(via
		(at 492.786924 -162.243262)
		(size 0.5588)
		(drill 0.3048)
		(layers "F.Cu" "B.Cu")
		(net "GND")
	)
	(via
		(at 247.631204 -69.45884)
		(size 0.508)
		(drill 0.254)
		(layers "F.Cu" "B.Cu")
		(net "GND")
	)
	(via
		(at 303.529746 -75.221338)
		(size 0.508)
		(drill 0.254)
		(layers "F.Cu" "B.Cu")
		(net "GND")
	)
	(via
		(at 53.442108 -148.767292)
		(size 0.508)
		(drill 0.254)
		(layers "F.Cu" "B.Cu")
		(net "GND")
	)
	(via
		(at 49.412398 -84.44992)
		(size 0.508)
		(drill 0.254)
		(layers "F.Cu" "B.Cu")
		(net "GND")
	)
	(via
		(at 41.458134 -167.832024)
		(size 0.5588)
		(drill 0.3048)
		(layers "F.Cu" "B.Cu")
		(net "GND")
	)
	(via
		(at 151.24938 -131.016756)
		(size 0.508)
		(drill 0.254)
		(layers "F.Cu" "B.Cu")
		(net "GND")
	)
	(via
		(at 392.176 -67.691)
		(size 0.508)
		(drill 0.254)
		(layers "F.Cu" "B.Cu")
		(net "GND")
	)
	(via
		(at 171.161456 4.289806)
		(size 0.5588)
		(drill 0.3048)
		(layers "F.Cu" "B.Cu")
		(net "GND")
	)
	(via
		(at 144.449546 -146.011646)
		(size 0.508)
		(drill 0.254)
		(layers "F.Cu" "B.Cu")
		(net "GND")
	)
	(via
		(at 201.031856 -11.9126)
		(size 0.508)
		(drill 0.254)
		(layers "F.Cu" "B.Cu")
		(net "GND")
	)
	(via
		(at 206.501746 -7.607046)
		(size 0.508)
		(drill 0.254)
		(layers "F.Cu" "B.Cu")
		(net "GND")
	)
	(via
		(at 441.431934 11.624056)
		(size 0.5588)
		(drill 0.3048)
		(layers "F.Cu" "B.Cu")
		(net "GND")
	)
	(via
		(at 106.151934 9.084056)
		(size 0.5588)
		(drill 0.3048)
		(layers "F.Cu" "B.Cu")
		(net "GND")
	)
	(via
		(at 119.337328 0.520954)
		(size 0.508)
		(drill 0.254)
		(layers "F.Cu" "B.Cu")
		(net "GND")
	)
	(via
		(at 196.399912 -139.170156)
		(size 0.508)
		(drill 0.254)
		(layers "F.Cu" "B.Cu")
		(net "GND")
	)
	(via
		(at 68.280534 -167.832024)
		(size 0.5588)
		(drill 0.3048)
		(layers "F.Cu" "B.Cu")
		(net "GND")
	)
	(via
		(at 13.335 -9.5758)
		(size 0.508)
		(drill 0.254)
		(layers "F.Cu" "B.Cu")
		(net "GND")
	)
	(via
		(at 183.6928 -140.9065)
		(size 0.508)
		(drill 0.254)
		(layers "F.Cu" "B.Cu")
		(net "GND")
	)
	(via
		(at 344.678 -15.367)
		(size 0.508)
		(drill 0.254)
		(layers "F.Cu" "B.Cu")
		(net "GND")
	)
	(via
		(at 436.921656 -33.8328)
		(size 0.4572)
		(drill 0.2032)
		(layers "F.Cu" "B.Cu")
		(net "GND")
	)
	(via
		(at 42.748454 -85.23351)
		(size 0.5588)
		(drill 0.3048)
		(layers "F.Cu" "B.Cu")
		(net "GND")
	)
	(via
		(at -2.356866 9.084056)
		(size 0.5588)
		(drill 0.3048)
		(layers "F.Cu" "B.Cu")
		(net "GND")
	)
	(via
		(at 203.199746 -140.617956)
		(size 0.508)
		(drill 0.254)
		(layers "F.Cu" "B.Cu")
		(net "GND")
	)
	(via
		(at 107.338876 -54.913784)
		(size 0.508)
		(drill 0.254)
		(layers "F.Cu" "B.Cu")
		(net "GND")
	)
	(via
		(at 421.111934 9.084056)
		(size 0.5588)
		(drill 0.3048)
		(layers "F.Cu" "B.Cu")
		(net "GND")
	)
	(via
		(at 196.908928 -56.802782)
		(size 0.508)
		(drill 0.254)
		(layers "F.Cu" "B.Cu")
		(net "GND")
	)
	(via
		(at 469.18499 -115.409472)
		(size 0.508)
		(drill 0.254)
		(layers "F.Cu" "B.Cu")
		(net "GND")
	)
	(via
		(at 214.0204 -68.1228)
		(size 0.508)
		(drill 0.254)
		(layers "F.Cu" "B.Cu")
		(net "GND")
	)
	(via
		(at 484.611934 10.354056)
		(size 0.5588)
		(drill 0.3048)
		(layers "F.Cu" "B.Cu")
		(net "GND")
	)
	(via
		(at 377.83135 -123.821444)
		(size 0.508)
		(drill 0.254)
		(layers "F.Cu" "B.Cu")
		(net "GND")
	)
	(via
		(at 136.812274 -54.418738)
		(size 0.508)
		(drill 0.254)
		(layers "F.Cu" "B.Cu")
		(net "GND")
	)
	(via
		(at 207.780128 -60.198)
		(size 0.5588)
		(drill 0.3048)
		(layers "F.Cu" "B.Cu")
		(net "GND")
	)
	(via
		(at 376.428 -122.355102)
		(size 0.508)
		(drill 0.254)
		(layers "F.Cu" "B.Cu")
		(net "GND")
	)
	(via
		(at 120.216168 -60.362338)
		(size 0.508)
		(drill 0.254)
		(layers "F.Cu" "B.Cu")
		(net "GND")
	)
	(via
		(at 136.812274 -74.23023)
		(size 0.508)
		(drill 0.254)
		(layers "F.Cu" "B.Cu")
		(net "GND")
	)
	(via
		(at 72.328786 -57.57164)
		(size 0.508)
		(drill 0.254)
		(layers "F.Cu" "B.Cu")
		(net "GND")
	)
	(via
		(at 221.899734 -154.063446)
		(size 0.508)
		(drill 0.254)
		(layers "F.Cu" "B.Cu")
		(net "GND")
	)
	(via
		(at 189.565534 -61.104526)
		(size 0.508)
		(drill 0.254)
		(layers "F.Cu" "B.Cu")
		(net "GND")
	)
	(via
		(at 472.155266 -152.546558)
		(size 0.5588)
		(drill 0.3048)
		(layers "F.Cu" "B.Cu")
		(net "GND")
	)
	(via
		(at 132.549392 -150.219156)
		(size 0.508)
		(drill 0.254)
		(layers "F.Cu" "B.Cu")
		(net "GND")
	)
	(via
		(at 323.093334 -167.832024)
		(size 0.5588)
		(drill 0.3048)
		(layers "F.Cu" "B.Cu")
		(net "GND")
	)
	(via
		(at 179.03952 -16.9545)
		(size 0.508)
		(drill 0.254)
		(layers "F.Cu" "B.Cu")
		(net "GND")
	)
	(via
		(at 249.348244 -79.36484)
		(size 0.508)
		(drill 0.254)
		(layers "F.Cu" "B.Cu")
		(net "GND")
	)
	(via
		(at 231.249728 -144.462246)
		(size 0.508)
		(drill 0.254)
		(layers "F.Cu" "B.Cu")
		(net "GND")
	)
	(via
		(at 257.93319 -87.28964)
		(size 0.508)
		(drill 0.254)
		(layers "F.Cu" "B.Cu")
		(net "GND")
	)
	(via
		(at 433.811934 12.894056)
		(size 0.5588)
		(drill 0.3048)
		(layers "F.Cu" "B.Cu")
		(net "GND")
	)
	(via
		(at 128.687576 -13.948156)
		(size 0.508)
		(drill 0.254)
		(layers "F.Cu" "B.Cu")
		(net "GND")
	)
	(via
		(at 390.473692 -41.326562)
		(size 0.508)
		(drill 0.254)
		(layers "F.Cu" "B.Cu")
		(net "GND")
	)
	(via
		(at 147.387564 -23.549356)
		(size 0.508)
		(drill 0.254)
		(layers "F.Cu" "B.Cu")
		(net "GND")
	)
	(via
		(at 346.4814 -88.9508)
		(size 0.508)
		(drill 0.254)
		(layers "F.Cu" "B.Cu")
		(net "GND")
	)
	(via
		(at 263.08431 -91.25204)
		(size 0.508)
		(drill 0.254)
		(layers "F.Cu" "B.Cu")
		(net "GND")
	)
	(via
		(at 466.3948 -38.969696)
		(size 0.5588)
		(drill 0.3048)
		(layers "F.Cu" "B.Cu")
		(net "GND")
	)
	(via
		(at 118.035832 -23.495)
		(size 0.508)
		(drill 0.254)
		(layers "F.Cu" "B.Cu")
		(net "GND")
	)
	(via
		(at 121.359168 -90.080338)
		(size 0.508)
		(drill 0.254)
		(layers "F.Cu" "B.Cu")
		(net "GND")
	)
	(via
		(at 73.440798 -143.950944)
		(size 0.508)
		(drill 0.254)
		(layers "F.Cu" "B.Cu")
		(net "GND")
	)
	(via
		(at 115.451382 1.994154)
		(size 0.508)
		(drill 0.254)
		(layers "F.Cu" "B.Cu")
		(net "GND")
	)
	(via
		(at 313.699906 -148.771356)
		(size 0.508)
		(drill 0.254)
		(layers "F.Cu" "B.Cu")
		(net "GND")
	)
	(via
		(at 10.541 -135.5852)
		(size 0.508)
		(drill 0.254)
		(layers "F.Cu" "B.Cu")
		(net "GND")
	)
	(via
		(at 209.09915 -144.0053)
		(size 0.508)
		(drill 0.254)
		(layers "F.Cu" "B.Cu")
		(net "GND")
	)
	(via
		(at 42.121582 -77.789278)
		(size 0.5588)
		(drill 0.3048)
		(layers "F.Cu" "B.Cu")
		(net "GND")
	)
	(via
		(at 71.470266 -56.085486)
		(size 0.508)
		(drill 0.254)
		(layers "F.Cu" "B.Cu")
		(net "GND")
	)
	(via
		(at 175.768 -11.43)
		(size 0.508)
		(drill 0.254)
		(layers "F.Cu" "B.Cu")
		(net "GND")
	)
	(via
		(at 13.514324 -162.243262)
		(size 0.5588)
		(drill 0.3048)
		(layers "F.Cu" "B.Cu")
		(net "GND")
	)
	(via
		(at 415.759392 -135.583676)
		(size 0.508)
		(drill 0.254)
		(layers "F.Cu" "B.Cu")
		(net "GND")
	)
	(via
		(at 398.8308 -3.2766)
		(size 0.508)
		(drill 0.254)
		(layers "F.Cu" "B.Cu")
		(net "GND")
	)
	(via
		(at 325.324724 -162.243262)
		(size 0.5588)
		(drill 0.3048)
		(layers "F.Cu" "B.Cu")
		(net "GND")
	)
	(via
		(at 352.2218 -31.8643)
		(size 0.508)
		(drill 0.254)
		(layers "F.Cu" "B.Cu")
		(net "GND")
	)
	(via
		(at 476.276924 -162.243262)
		(size 0.5588)
		(drill 0.3048)
		(layers "F.Cu" "B.Cu")
		(net "GND")
	)
	(via
		(at 256.21615 -86.29904)
		(size 0.508)
		(drill 0.254)
		(layers "F.Cu" "B.Cu")
		(net "GND")
	)
	(via
		(at 293.22776 -84.136738)
		(size 0.508)
		(drill 0.254)
		(layers "F.Cu" "B.Cu")
		(net "GND")
	)
	(via
		(at 426.244258 -29.792422)
		(size 0.4572)
		(drill 0.2032)
		(layers "F.Cu" "B.Cu")
		(net "GND")
	)
	(via
		(at 177.546 -140.5255)
		(size 0.508)
		(drill 0.254)
		(layers "F.Cu" "B.Cu")
		(net "GND")
	)
	(via
		(at 142.749524 -155.600146)
		(size 0.508)
		(drill 0.254)
		(layers "F.Cu" "B.Cu")
		(net "GND")
	)
	(via
		(at 0.106934 -166.714424)
		(size 0.5588)
		(drill 0.3048)
		(layers "F.Cu" "B.Cu")
		(net "GND")
	)
	(via
		(at 51.79949 0.444754)
		(size 0.508)
		(drill 0.254)
		(layers "F.Cu" "B.Cu")
		(net "GND")
	)
	(via
		(at 125.651768 -90.575384)
		(size 0.508)
		(drill 0.254)
		(layers "F.Cu" "B.Cu")
		(net "GND")
	)
	(via
		(at 123.199398 -131.016756)
		(size 0.508)
		(drill 0.254)
		(layers "F.Cu" "B.Cu")
		(net "GND")
	)
	(via
		(at 121.499376 -140.617956)
		(size 0.508)
		(drill 0.254)
		(layers "F.Cu" "B.Cu")
		(net "GND")
	)
	(via
		(at 38.199314 -134.861046)
		(size 0.508)
		(drill 0.254)
		(layers "F.Cu" "B.Cu")
		(net "GND")
	)
	(via
		(at 499.2116 -38.0238)
		(size 0.508)
		(drill 0.254)
		(layers "F.Cu" "B.Cu")
		(net "GND")
	)
	(via
		(at 251.923804 -82.83194)
		(size 0.508)
		(drill 0.254)
		(layers "F.Cu" "B.Cu")
		(net "GND")
	)
	(via
		(at 345.3003 -0.633222)
		(size 0.508)
		(drill 0.254)
		(layers "F.Cu" "B.Cu")
		(net "GND")
	)
	(via
		(at 178.40452 -16.97736)
		(size 0.508)
		(drill 0.254)
		(layers "F.Cu" "B.Cu")
		(net "GND")
	)
	(via
		(at 203.199746 -13.363956)
		(size 0.508)
		(drill 0.254)
		(layers "F.Cu" "B.Cu")
		(net "GND")
	)
	(via
		(at 293.694612 -136.3345)
		(size 0.508)
		(drill 0.254)
		(layers "F.Cu" "B.Cu")
		(net "GND")
	)
	(via
		(at 132.519674 -101.471984)
		(size 0.508)
		(drill 0.254)
		(layers "F.Cu" "B.Cu")
		(net "GND")
	)
	(via
		(at 110.111032 -12.954)
		(size 0.508)
		(drill 0.254)
		(layers "F.Cu" "B.Cu")
		(net "GND")
	)
	(via
		(at 221.899734 -131.016756)
		(size 0.508)
		(drill 0.254)
		(layers "F.Cu" "B.Cu")
		(net "GND")
	)
	(via
		(at 172.6946 -32.5628)
		(size 0.508)
		(drill 0.254)
		(layers "F.Cu" "B.Cu")
		(net "GND")
	)
	(via
		(at 416.031934 14.926056)
		(size 0.5588)
		(drill 0.3048)
		(layers "F.Cu" "B.Cu")
		(net "GND")
	)
	(via
		(at 278.92375 -11.93165)
		(size 0.508)
		(drill 0.254)
		(layers "F.Cu" "B.Cu")
		(net "GND")
	)
	(via
		(at 499.851934 14.926056)
		(size 0.5588)
		(drill 0.3048)
		(layers "F.Cu" "B.Cu")
		(net "GND")
	)
	(via
		(at 75.762866 -76.39304)
		(size 0.508)
		(drill 0.254)
		(layers "F.Cu" "B.Cu")
		(net "GND")
	)
	(via
		(at 116.337334 -167.832024)
		(size 0.5588)
		(drill 0.3048)
		(layers "F.Cu" "B.Cu")
		(net "GND")
	)
	(via
		(at 169.9006 -5.8674)
		(size 0.508)
		(drill 0.254)
		(layers "F.Cu" "B.Cu")
		(net "GND")
	)
	(via
		(at 114.699542 -155.600146)
		(size 0.508)
		(drill 0.254)
		(layers "F.Cu" "B.Cu")
		(net "GND")
	)
	(via
		(at 195.051934 14.926056)
		(size 0.5588)
		(drill 0.3048)
		(layers "F.Cu" "B.Cu")
		(net "GND")
	)
	(via
		(at 242.480338 -94.223586)
		(size 0.508)
		(drill 0.254)
		(layers "F.Cu" "B.Cu")
		(net "GND")
	)
	(via
		(at 484.7336 -141.4272)
		(size 0.508)
		(drill 0.254)
		(layers "F.Cu" "B.Cu")
		(net "GND")
	)
	(via
		(at 390.70915 -99.322636)
		(size 0.508)
		(drill 0.254)
		(layers "F.Cu" "B.Cu")
		(net "GND")
	)
	(via
		(at 451.401688 -45.560996)
		(size 0.508)
		(drill 0.254)
		(layers "F.Cu" "B.Cu")
		(net "GND")
	)
	(via
		(at 135.771636 -144.5006)
		(size 0.508)
		(drill 0.254)
		(layers "F.Cu" "B.Cu")
		(net "GND")
	)
	(via
		(at 290.74999 -136.410446)
		(size 0.508)
		(drill 0.254)
		(layers "F.Cu" "B.Cu")
		(net "GND")
	)
	(via
		(at 6.57098 -20.54352)
		(size 0.508)
		(drill 0.254)
		(layers "F.Cu" "B.Cu")
		(net "GND")
	)
	(via
		(at 201.037952 -13.948156)
		(size 0.508)
		(drill 0.254)
		(layers "F.Cu" "B.Cu")
		(net "GND")
	)
	(via
		(at 293.22776 -64.324738)
		(size 0.508)
		(drill 0.254)
		(layers "F.Cu" "B.Cu")
		(net "GND")
	)
	(via
		(at 484.933244 -53.824124)
		(size 0.508)
		(drill 0.254)
		(layers "F.Cu" "B.Cu")
		(net "GND")
	)
	(via
		(at 331.4954 -109.855)
		(size 0.508)
		(drill 0.254)
		(layers "F.Cu" "B.Cu")
		(net "GND")
	)
	(via
		(at 141.899386 -3.762756)
		(size 0.508)
		(drill 0.254)
		(layers "F.Cu" "B.Cu")
		(net "GND")
	)
	(via
		(at 247.631204 -63.51524)
		(size 0.508)
		(drill 0.254)
		(layers "F.Cu" "B.Cu")
		(net "GND")
	)
	(via
		(at 36.287202 -102.318566)
		(size 0.5588)
		(drill 0.3048)
		(layers "F.Cu" "B.Cu")
		(net "GND")
	)
	(via
		(at 268.368018 -75.148186)
		(size 0.5588)
		(drill 0.3048)
		(layers "F.Cu" "B.Cu")
		(net "GND")
	)
	(via
		(at 114.699542 -139.170156)
		(size 0.508)
		(drill 0.254)
		(layers "F.Cu" "B.Cu")
		(net "GND")
	)
	(via
		(at 172.213524 -162.243262)
		(size 0.5588)
		(drill 0.3048)
		(layers "F.Cu" "B.Cu")
		(net "GND")
	)
	(via
		(at 75.762866 -94.223586)
		(size 0.508)
		(drill 0.254)
		(layers "F.Cu" "B.Cu")
		(net "GND")
	)
	(via
		(at 213.399878 -146.011646)
		(size 0.508)
		(drill 0.254)
		(layers "F.Cu" "B.Cu")
		(net "GND")
	)
	(via
		(at 48.399446 0.444754)
		(size 0.508)
		(drill 0.254)
		(layers "F.Cu" "B.Cu")
		(net "GND")
	)
	(via
		(at 245.978934 -167.832024)
		(size 0.5588)
		(drill 0.3048)
		(layers "F.Cu" "B.Cu")
		(net "GND")
	)
	(via
		(at 118.499382 -62.343538)
		(size 0.508)
		(drill 0.254)
		(layers "F.Cu" "B.Cu")
		(net "GND")
	)
	(via
		(at 92.932758 -91.25204)
		(size 0.508)
		(drill 0.254)
		(layers "F.Cu" "B.Cu")
		(net "GND")
	)
	(via
		(at 237.149132 2.4511)
		(size 0.508)
		(drill 0.254)
		(layers "F.Cu" "B.Cu")
		(net "GND")
	)
	(via
		(at 114.699542 -18.744946)
		(size 0.508)
		(drill 0.254)
		(layers "F.Cu" "B.Cu")
		(net "GND")
	)
	(via
		(at 470.641934 10.354056)
		(size 0.5588)
		(drill 0.3048)
		(layers "F.Cu" "B.Cu")
		(net "GND")
	)
	(via
		(at 84.347812 -68.46824)
		(size 0.508)
		(drill 0.254)
		(layers "F.Cu" "B.Cu")
		(net "GND")
	)
	(via
		(at 275.199348 -93.547184)
		(size 0.508)
		(drill 0.254)
		(layers "F.Cu" "B.Cu")
		(net "GND")
	)
	(via
		(at 280.460958 -3.737356)
		(size 0.508)
		(drill 0.254)
		(layers "F.Cu" "B.Cu")
		(net "GND")
	)
	(via
		(at 390.70915 -101.039676)
		(size 0.508)
		(drill 0.254)
		(layers "F.Cu" "B.Cu")
		(net "GND")
	)
	(via
		(at 124.049536 -11.916156)
		(size 0.508)
		(drill 0.254)
		(layers "F.Cu" "B.Cu")
		(net "GND")
	)
	(via
		(at 110.198916 -89.584784)
		(size 0.508)
		(drill 0.254)
		(layers "F.Cu" "B.Cu")
		(net "GND")
	)
	(via
		(at 281.320494 -68.335652)
		(size 0.508)
		(drill 0.254)
		(layers "F.Cu" "B.Cu")
		(net "GND")
	)
	(via
		(at 391.901934 9.084056)
		(size 0.5588)
		(drill 0.3048)
		(layers "F.Cu" "B.Cu")
		(net "GND")
	)
	(via
		(at -0.30226 -13.52296)
		(size 0.508)
		(drill 0.254)
		(layers "F.Cu" "B.Cu")
		(net "GND")
	)
	(via
		(at 48.399446 -21.517356)
		(size 0.508)
		(drill 0.254)
		(layers "F.Cu" "B.Cu")
		(net "GND")
	)
	(via
		(at 389.645906 -127.738124)
		(size 0.508)
		(drill 0.254)
		(layers "F.Cu" "B.Cu")
		(net "GND")
	)
	(via
		(at 144.273524 -162.243262)
		(size 0.5588)
		(drill 0.3048)
		(layers "F.Cu" "B.Cu")
		(net "GND")
	)
	(via
		(at 287.326324 -162.243262)
		(size 0.5588)
		(drill 0.3048)
		(layers "F.Cu" "B.Cu")
		(net "GND")
	)
	(via
		(at 64.081406 -139.1666)
		(size 0.508)
		(drill 0.254)
		(layers "F.Cu" "B.Cu")
		(net "GND")
	)
	(via
		(at 460.481934 10.354056)
		(size 0.5588)
		(drill 0.3048)
		(layers "F.Cu" "B.Cu")
		(net "GND")
	)
	(via
		(at 425.36999 -34.091118)
		(size 0.4572)
		(drill 0.2032)
		(layers "F.Cu" "B.Cu")
		(net "GND")
	)
	(via
		(at 303.038002 -4.346956)
		(size 0.508)
		(drill 0.254)
		(layers "F.Cu" "B.Cu")
		(net "GND")
	)
	(via
		(at 473.181934 14.926056)
		(size 0.5588)
		(drill 0.3048)
		(layers "F.Cu" "B.Cu")
		(net "GND")
	)
	(via
		(at 478.663 -20.1422)
		(size 0.508)
		(drill 0.254)
		(layers "F.Cu" "B.Cu")
		(net "GND")
	)
	(via
		(at 294.9448 -52.437284)
		(size 0.508)
		(drill 0.254)
		(layers "F.Cu" "B.Cu")
		(net "GND")
	)
	(via
		(at 200.881234 -70.920864)
		(size 0.508)
		(drill 0.254)
		(layers "F.Cu" "B.Cu")
		(net "GND")
	)
	(via
		(at 461.352392 -41.512998)
		(size 0.508)
		(drill 0.254)
		(layers "F.Cu" "B.Cu")
		(net "GND")
	)
	(via
		(at 442.701934 13.910056)
		(size 0.5588)
		(drill 0.3048)
		(layers "F.Cu" "B.Cu")
		(net "GND")
	)
	(via
		(at 402.620734 -165.596824)
		(size 0.5588)
		(drill 0.3048)
		(layers "F.Cu" "B.Cu")
		(net "GND")
	)
	(via
		(at 136.736074 -131.5466)
		(size 0.508)
		(drill 0.254)
		(layers "F.Cu" "B.Cu")
		(net "GND")
	)
	(via
		(at 232.101898 -67.47764)
		(size 0.508)
		(drill 0.254)
		(layers "F.Cu" "B.Cu")
		(net "GND")
	)
	(via
		(at 139.34948 -136.410446)
		(size 0.508)
		(drill 0.254)
		(layers "F.Cu" "B.Cu")
		(net "GND")
	)
	(via
		(at 482.071934 12.894056)
		(size 0.5588)
		(drill 0.3048)
		(layers "F.Cu" "B.Cu")
		(net "GND")
	)
	(via
		(at 90.632534 -167.832024)
		(size 0.5588)
		(drill 0.3048)
		(layers "F.Cu" "B.Cu")
		(net "GND")
	)
	(via
		(at 351.798382 -131.279392)
		(size 0.508)
		(drill 0.254)
		(layers "F.Cu" "B.Cu")
		(net "GND")
	)
	(via
		(at 477.57842 -19.51228)
		(size 0.508)
		(drill 0.254)
		(layers "F.Cu" "B.Cu")
		(net "GND")
	)
	(via
		(at 426.750734 -164.479224)
		(size 0.5588)
		(drill 0.3048)
		(layers "F.Cu" "B.Cu")
		(net "GND")
	)
	(via
		(at 495.330734 -166.714424)
		(size 0.5588)
		(drill 0.3048)
		(layers "F.Cu" "B.Cu")
		(net "GND")
	)
	(via
		(at 425.480734 -166.714424)
		(size 0.5588)
		(drill 0.3048)
		(layers "F.Cu" "B.Cu")
		(net "GND")
	)
	(via
		(at 225.210878 -22.939756)
		(size 0.508)
		(drill 0.254)
		(layers "F.Cu" "B.Cu")
		(net "GND")
	)
	(via
		(at 79.196692 -91.25204)
		(size 0.508)
		(drill 0.254)
		(layers "F.Cu" "B.Cu")
		(net "GND")
	)
	(via
		(at 166.5986 -81.407)
		(size 0.508)
		(drill 0.254)
		(layers "F.Cu" "B.Cu")
		(net "GND")
	)
	(via
		(at 351.032318 -93.366336)
		(size 0.508)
		(drill 0.254)
		(layers "F.Cu" "B.Cu")
		(net "GND")
	)
	(via
		(at 222.509334 -167.832024)
		(size 0.5588)
		(drill 0.3048)
		(layers "F.Cu" "B.Cu")
		(net "GND")
	)
	(via
		(at 461.040734 -167.832024)
		(size 0.5588)
		(drill 0.3048)
		(layers "F.Cu" "B.Cu")
		(net "GND")
	)
	(via
		(at 349.915734 -167.832024)
		(size 0.5588)
		(drill 0.3048)
		(layers "F.Cu" "B.Cu")
		(net "GND")
	)
	(via
		(at 435.6354 -11.7094)
		(size 0.508)
		(drill 0.254)
		(layers "F.Cu" "B.Cu")
		(net "GND")
	)
	(via
		(at 187.859924 -162.243262)
		(size 0.5588)
		(drill 0.3048)
		(layers "F.Cu" "B.Cu")
		(net "GND")
	)
	(via
		(at 399.12925 -107.049316)
		(size 0.508)
		(drill 0.254)
		(layers "F.Cu" "B.Cu")
		(net "GND")
	)
	(via
		(at 253.640844 -56.085486)
		(size 0.508)
		(drill 0.254)
		(layers "F.Cu" "B.Cu")
		(net "GND")
	)
	(via
		(at 357.9495 -17.363186)
		(size 0.508)
		(drill 0.254)
		(layers "F.Cu" "B.Cu")
		(net "GND")
	)
	(via
		(at 294.9448 -84.136738)
		(size 0.508)
		(drill 0.254)
		(layers "F.Cu" "B.Cu")
		(net "GND")
	)
	(via
		(at 243.338604 -61.038486)
		(size 0.508)
		(drill 0.254)
		(layers "F.Cu" "B.Cu")
		(net "GND")
	)
	(via
		(at 235.612178 -97.19564)
		(size 0.508)
		(drill 0.254)
		(layers "F.Cu" "B.Cu")
		(net "GND")
	)
	(via
		(at 146.512534 -167.832024)
		(size 0.5588)
		(drill 0.3048)
		(layers "F.Cu" "B.Cu")
		(net "GND")
	)
	(via
		(at 132.549392 -22.965156)
		(size 0.508)
		(drill 0.254)
		(layers "F.Cu" "B.Cu")
		(net "GND")
	)
	(via
		(at -4.339336 -118.777004)
		(size 0.508)
		(drill 0.254)
		(layers "F.Cu" "B.Cu")
		(net "GND")
	)
	(via
		(at 393.18565 -116.094764)
		(size 0.508)
		(drill 0.254)
		(layers "F.Cu" "B.Cu")
		(net "GND")
	)
	(via
		(at 60.201302 1.994154)
		(size 0.508)
		(drill 0.254)
		(layers "F.Cu" "B.Cu")
		(net "GND")
	)
	(via
		(at 337.0072 -27.2415)
		(size 0.508)
		(drill 0.254)
		(layers "F.Cu" "B.Cu")
		(net "GND")
	)
	(via
		(at 485.170734 -163.361624)
		(size 0.5588)
		(drill 0.3048)
		(layers "F.Cu" "B.Cu")
		(net "GND")
	)
	(via
		(at 287.349946 -136.410446)
		(size 0.508)
		(drill 0.254)
		(layers "F.Cu" "B.Cu")
		(net "GND")
	)
	(via
		(at 443.260734 -164.479224)
		(size 0.5588)
		(drill 0.3048)
		(layers "F.Cu" "B.Cu")
		(net "GND")
	)
	(via
		(at 269.80388 -82.340196)
		(size 0.5588)
		(drill 0.3048)
		(layers "F.Cu" "B.Cu")
		(net "GND")
	)
	(via
		(at 284.358334 -54.913784)
		(size 0.508)
		(drill 0.254)
		(layers "F.Cu" "B.Cu")
		(net "GND")
	)
	(via
		(at 53.436012 -150.749)
		(size 0.508)
		(drill 0.254)
		(layers "F.Cu" "B.Cu")
		(net "GND")
	)
	(via
		(at 206.194914 -85.028278)
		(size 0.5588)
		(drill 0.3048)
		(layers "F.Cu" "B.Cu")
		(net "GND")
	)
	(via
		(at 380.902972 -31.62808)
		(size 0.508)
		(drill 0.254)
		(layers "F.Cu" "B.Cu")
		(net "GND")
	)
	(via
		(at 73.4314 -2.3114)
		(size 0.508)
		(drill 0.254)
		(layers "F.Cu" "B.Cu")
		(net "GND")
	)
	(via
		(at 70.611746 -68.46824)
		(size 0.508)
		(drill 0.254)
		(layers "F.Cu" "B.Cu")
		(net "GND")
	)
	(via
		(at 440.436 -123.9774)
		(size 0.508)
		(drill 0.254)
		(layers "F.Cu" "B.Cu")
		(net "GND")
	)
	(via
		(at 205.138528 -60.198)
		(size 0.5588)
		(drill 0.3048)
		(layers "F.Cu" "B.Cu")
		(net "GND")
	)
	(via
		(at 150.601934 14.926056)
		(size 0.5588)
		(drill 0.3048)
		(layers "F.Cu" "B.Cu")
		(net "GND")
	)
	(via
		(at 59.449462 -136.397746)
		(size 0.508)
		(drill 0.254)
		(layers "F.Cu" "B.Cu")
		(net "GND")
	)
	(via
		(at 146.092164 -129.564892)
		(size 0.508)
		(drill 0.254)
		(layers "F.Cu" "B.Cu")
		(net "GND")
	)
	(via
		(at 418.2618 -121.9962)
		(size 0.508)
		(drill 0.254)
		(layers "F.Cu" "B.Cu")
		(net "GND")
	)
	(via
		(at 79.196692 -96.20504)
		(size 0.508)
		(drill 0.254)
		(layers "F.Cu" "B.Cu")
		(net "GND")
	)
	(via
		(at 293.22776 -82.155284)
		(size 0.508)
		(drill 0.254)
		(layers "F.Cu" "B.Cu")
		(net "GND")
	)
	(via
		(at 369.038124 -162.268662)
		(size 0.5588)
		(drill 0.3048)
		(layers "F.Cu" "B.Cu")
		(net "GND")
	)
	(via
		(at 221.899734 -3.762756)
		(size 0.508)
		(drill 0.254)
		(layers "F.Cu" "B.Cu")
		(net "GND")
	)
	(via
		(at 31.908496 -56.802782)
		(size 0.508)
		(drill 0.254)
		(layers "F.Cu" "B.Cu")
		(net "GND")
	)
	(via
		(at 481.360734 -164.479224)
		(size 0.5588)
		(drill 0.3048)
		(layers "F.Cu" "B.Cu")
		(net "GND")
	)
	(via
		(at 478.261934 10.354056)
		(size 0.5588)
		(drill 0.3048)
		(layers "F.Cu" "B.Cu")
		(net "GND")
	)
	(via
		(at 393.730734 -167.832024)
		(size 0.5588)
		(drill 0.3048)
		(layers "F.Cu" "B.Cu")
		(net "GND")
	)
	(via
		(at 301.742602 -129.564892)
		(size 0.508)
		(drill 0.254)
		(layers "F.Cu" "B.Cu")
		(net "GND")
	)
	(via
		(at 460.24165 -124.87402)
		(size 0.508)
		(drill 0.254)
		(layers "F.Cu" "B.Cu")
		(net "GND")
	)
	(via
		(at 421.0304 -77.343)
		(size 0.508)
		(drill 0.254)
		(layers "F.Cu" "B.Cu")
		(net "GND")
	)
	(via
		(at 354.965 -12.954)
		(size 0.508)
		(drill 0.254)
		(layers "F.Cu" "B.Cu")
		(net "GND")
	)
	(via
		(at 403.671786 -2.601214)
		(size 0.508)
		(drill 0.254)
		(layers "F.Cu" "B.Cu")
		(net "GND")
	)
	(via
		(at 139.34948 -9.156446)
		(size 0.508)
		(drill 0.254)
		(layers "F.Cu" "B.Cu")
		(net "GND")
	)
	(via
		(at 304.349912 -9.156446)
		(size 0.508)
		(drill 0.254)
		(layers "F.Cu" "B.Cu")
		(net "GND")
	)
	(via
		(at 285.2166 -62.343538)
		(size 0.508)
		(drill 0.254)
		(layers "F.Cu" "B.Cu")
		(net "GND")
	)
	(via
		(at 31.893002 -79.912464)
		(size 0.508)
		(drill 0.254)
		(layers "F.Cu" "B.Cu")
		(net "GND")
	)
	(via
		(at 301.812706 -63.334138)
		(size 0.508)
		(drill 0.254)
		(layers "F.Cu" "B.Cu")
		(net "GND")
	)
	(via
		(at 461.751934 11.624056)
		(size 0.5588)
		(drill 0.3048)
		(layers "F.Cu" "B.Cu")
		(net "GND")
	)
	(via
		(at 199.742552 -129.564892)
		(size 0.508)
		(drill 0.254)
		(layers "F.Cu" "B.Cu")
		(net "GND")
	)
	(via
		(at 389.22325 -100.181156)
		(size 0.508)
		(drill 0.254)
		(layers "F.Cu" "B.Cu")
		(net "GND")
	)
	(via
		(at 168.81094 -130.25374)
		(size 0.508)
		(drill 0.254)
		(layers "F.Cu" "B.Cu")
		(net "GND")
	)
	(via
		(at 19.3802 -91.0336)
		(size 0.508)
		(drill 0.254)
		(layers "F.Cu" "B.Cu")
		(net "GND")
	)
	(via
		(at 38.199314 -17.208246)
		(size 0.508)
		(drill 0.254)
		(layers "F.Cu" "B.Cu")
		(net "GND")
	)
	(via
		(at 386.821934 9.084056)
		(size 0.5588)
		(drill 0.3048)
		(layers "F.Cu" "B.Cu")
		(net "GND")
	)
	(via
		(at 283.04236 -148.767292)
		(size 0.508)
		(drill 0.254)
		(layers "F.Cu" "B.Cu")
		(net "GND")
	)
	(via
		(at 438.180734 -167.832024)
		(size 0.5588)
		(drill 0.3048)
		(layers "F.Cu" "B.Cu")
		(net "GND")
	)
	(via
		(at 377.721622 -145.36801)
		(size 0.508)
		(drill 0.254)
		(layers "F.Cu" "B.Cu")
		(net "GND")
	)
	(via
		(at 114.039142 -13.940282)
		(size 0.508)
		(drill 0.254)
		(layers "F.Cu" "B.Cu")
		(net "GND")
	)
	(via
		(at 417.860734 -163.361624)
		(size 0.5588)
		(drill 0.3048)
		(layers "F.Cu" "B.Cu")
		(net "GND")
	)
	(via
		(at 151.24938 -13.363956)
		(size 0.508)
		(drill 0.254)
		(layers "F.Cu" "B.Cu")
		(net "GND")
	)
	(via
		(at 290.682934 -167.832024)
		(size 0.5588)
		(drill 0.3048)
		(layers "F.Cu" "B.Cu")
		(net "GND")
	)
	(via
		(at 182.081932 3.669792)
		(size 0.508)
		(drill 0.254)
		(layers "F.Cu" "B.Cu")
		(net "GND")
	)
	(via
		(at 6.112256 -15.086076)
		(size 0.508)
		(drill 0.254)
		(layers "F.Cu" "B.Cu")
		(net "GND")
	)
	(via
		(at 141.049502 -26.495756)
		(size 0.508)
		(drill 0.254)
		(layers "F.Cu" "B.Cu")
		(net "GND")
	)
	(via
		(at 239.046258 -78.37424)
		(size 0.508)
		(drill 0.254)
		(layers "F.Cu" "B.Cu")
		(net "GND")
	)
	(via
		(at 106.841036 -149.8092)
		(size 0.508)
		(drill 0.254)
		(layers "F.Cu" "B.Cu")
		(net "GND")
	)
	(via
		(at 192.334134 -167.832024)
		(size 0.5588)
		(drill 0.3048)
		(layers "F.Cu" "B.Cu")
		(net "GND")
	)
	(via
		(at 293.22776 -62.343538)
		(size 0.508)
		(drill 0.254)
		(layers "F.Cu" "B.Cu")
		(net "GND")
	)
	(via
		(at 118.783862 -95.528384)
		(size 0.508)
		(drill 0.254)
		(layers "F.Cu" "B.Cu")
		(net "GND")
	)
	(via
		(at 129.974848 -125.9332)
		(size 0.508)
		(drill 0.254)
		(layers "F.Cu" "B.Cu")
		(net "GND")
	)
	(via
		(at -3.81 -66.7258)
		(size 0.508)
		(drill 0.254)
		(layers "F.Cu" "B.Cu")
		(net "GND")
	)
	(via
		(at 39.698676 -47.65675)
		(size 0.508)
		(drill 0.254)
		(layers "F.Cu" "B.Cu")
		(net "GND")
	)
	(via
		(at 131.661408 -92.061538)
		(size 0.508)
		(drill 0.254)
		(layers "F.Cu" "B.Cu")
		(net "GND")
	)
	(via
		(at 322.0212 -150.7744)
		(size 0.508)
		(drill 0.254)
		(layers "F.Cu" "B.Cu")
		(net "GND")
	)
	(via
		(at 461.040734 -165.596824)
		(size 0.5588)
		(drill 0.3048)
		(layers "F.Cu" "B.Cu")
		(net "GND")
	)
	(via
		(at 35.880294 -98.012504)
		(size 0.508)
		(drill 0.254)
		(layers "F.Cu" "B.Cu")
		(net "GND")
	)
	(via
		(at 395.16685 -121.245884)
		(size 0.508)
		(drill 0.254)
		(layers "F.Cu" "B.Cu")
		(net "GND")
	)
	(via
		(at 89.641934 9.084056)
		(size 0.5588)
		(drill 0.3048)
		(layers "F.Cu" "B.Cu")
		(net "GND")
	)
	(via
		(at 204.049884 -21.517356)
		(size 0.508)
		(drill 0.254)
		(layers "F.Cu" "B.Cu")
		(net "GND")
	)
	(via
		(at 236.470698 -61.038486)
		(size 0.508)
		(drill 0.254)
		(layers "F.Cu" "B.Cu")
		(net "GND")
	)
	(via
		(at 276.750018 -75.148186)
		(size 0.5588)
		(drill 0.3048)
		(layers "F.Cu" "B.Cu")
		(net "GND")
	)
	(via
		(at 186.742324 -162.243262)
		(size 0.5588)
		(drill 0.3048)
		(layers "F.Cu" "B.Cu")
		(net "GND")
	)
	(via
		(at 231.249728 -150.219156)
		(size 0.508)
		(drill 0.254)
		(layers "F.Cu" "B.Cu")
		(net "GND")
	)
	(via
		(at 136.812274 -93.052138)
		(size 0.508)
		(drill 0.254)
		(layers "F.Cu" "B.Cu")
		(net "GND")
	)
	(via
		(at 54.744112 -145.9357)
		(size 0.508)
		(drill 0.254)
		(layers "F.Cu" "B.Cu")
		(net "GND")
	)
	(via
		(at 201.422 -86.4616)
		(size 0.5588)
		(drill 0.3048)
		(layers "F.Cu" "B.Cu")
		(net "GND")
	)
	(via
		(at 360.2482 -50.7746)
		(size 0.508)
		(drill 0.254)
		(layers "F.Cu" "B.Cu")
		(net "GND")
	)
	(via
		(at 395.181328 -130.121152)
		(size 0.508)
		(drill 0.254)
		(layers "F.Cu" "B.Cu")
		(net "GND")
	)
	(via
		(at 3.505454 -158.52902)
		(size 0.5588)
		(drill 0.3048)
		(layers "F.Cu" "B.Cu")
		(net "GND")
	)
	(via
		(at 356.757732 -107.08005)
		(size 0.508)
		(drill 0.254)
		(layers "F.Cu" "B.Cu")
		(net "GND")
	)
	(via
		(at 139.34948 -21.517356)
		(size 0.508)
		(drill 0.254)
		(layers "F.Cu" "B.Cu")
		(net "GND")
	)
	(via
		(at 36.040822 -143.950944)
		(size 0.508)
		(drill 0.254)
		(layers "F.Cu" "B.Cu")
		(net "GND")
	)
	(via
		(at 447.781934 13.910056)
		(size 0.5588)
		(drill 0.3048)
		(layers "F.Cu" "B.Cu")
		(net "GND")
	)
	(via
		(at 389.876792 -155.778708)
		(size 0.508)
		(drill 0.254)
		(layers "F.Cu" "B.Cu")
		(net "GND")
	)
	(via
		(at 207.414114 -94.604078)
		(size 0.5588)
		(drill 0.3048)
		(layers "F.Cu" "B.Cu")
		(net "GND")
	)
	(via
		(at 211.561934 9.084056)
		(size 0.5588)
		(drill 0.3048)
		(layers "F.Cu" "B.Cu")
		(net "GND")
	)
	(via
		(at 169.147744 -94.023434)
		(size 0.508)
		(drill 0.254)
		(layers "F.Cu" "B.Cu")
		(net "GND")
	)
	(via
		(at 177.227738 -18.334736)
		(size 0.508)
		(drill 0.254)
		(layers "F.Cu" "B.Cu")
		(net "GND")
	)
	(via
		(at 428.731934 14.926056)
		(size 0.5588)
		(drill 0.3048)
		(layers "F.Cu" "B.Cu")
		(net "GND")
	)
	(via
		(at 387.73735 -97.605596)
		(size 0.508)
		(drill 0.254)
		(layers "F.Cu" "B.Cu")
		(net "GND")
	)
	(via
		(at 300.061884 -139.170156)
		(size 0.508)
		(drill 0.254)
		(layers "F.Cu" "B.Cu")
		(net "GND")
	)
	(via
		(at 289.049968 -155.600146)
		(size 0.508)
		(drill 0.254)
		(layers "F.Cu" "B.Cu")
		(net "GND")
	)
	(via
		(at 454.686924 -162.243262)
		(size 0.5588)
		(drill 0.3048)
		(layers "F.Cu" "B.Cu")
		(net "GND")
	)
	(via
		(at 169.3418 -16.6624)
		(size 0.508)
		(drill 0.254)
		(layers "F.Cu" "B.Cu")
		(net "GND")
	)
	(via
		(at 393.68095 -101.039676)
		(size 0.508)
		(drill 0.254)
		(layers "F.Cu" "B.Cu")
		(net "GND")
	)
	(via
		(at -0.254 -20.701)
		(size 0.508)
		(drill 0.254)
		(layers "F.Cu" "B.Cu")
		(net "GND")
	)
	(via
		(at 251.065284 -60.54344)
		(size 0.508)
		(drill 0.254)
		(layers "F.Cu" "B.Cu")
		(net "GND")
	)
	(via
		(at 315.399928 -146.011646)
		(size 0.508)
		(drill 0.254)
		(layers "F.Cu" "B.Cu")
		(net "GND")
	)
	(via
		(at 41.427654 -84.57311)
		(size 0.5588)
		(drill 0.3048)
		(layers "F.Cu" "B.Cu")
		(net "GND")
	)
	(via
		(at 199.815196 -53.711602)
		(size 0.5588)
		(drill 0.3048)
		(layers "F.Cu" "B.Cu")
		(net "GND")
	)
	(via
		(at 278.633174 -94.538038)
		(size 0.508)
		(drill 0.254)
		(layers "F.Cu" "B.Cu")
		(net "GND")
	)
	(via
		(at 206.51089 -3.737356)
		(size 0.508)
		(drill 0.254)
		(layers "F.Cu" "B.Cu")
		(net "GND")
	)
	(via
		(at 199.742552 0.457454)
		(size 0.508)
		(drill 0.254)
		(layers "F.Cu" "B.Cu")
		(net "GND")
	)
	(via
		(at 116.399564 -18.757646)
		(size 0.508)
		(drill 0.254)
		(layers "F.Cu" "B.Cu")
		(net "GND")
	)
	(via
		(at 300.095666 -56.399938)
		(size 0.508)
		(drill 0.254)
		(layers "F.Cu" "B.Cu")
		(net "GND")
	)
	(via
		(at 215.2904 -92.202)
		(size 0.508)
		(drill 0.254)
		(layers "F.Cu" "B.Cu")
		(net "GND")
	)
	(via
		(at 267.209524 -162.243262)
		(size 0.5588)
		(drill 0.3048)
		(layers "F.Cu" "B.Cu")
		(net "GND")
	)
	(via
		(at 226.149916 -136.410446)
		(size 0.508)
		(drill 0.254)
		(layers "F.Cu" "B.Cu")
		(net "GND")
	)
	(via
		(at 301.757842 -7.1374)
		(size 0.508)
		(drill 0.254)
		(layers "F.Cu" "B.Cu")
		(net "GND")
	)
	(via
		(at 308.501796 -134.861046)
		(size 0.508)
		(drill 0.254)
		(layers "F.Cu" "B.Cu")
		(net "GND")
	)
	(via
		(at 273.197828 -52.437284)
		(size 0.508)
		(drill 0.254)
		(layers "F.Cu" "B.Cu")
		(net "GND")
	)
	(via
		(at 41.427654 -85.89391)
		(size 0.5588)
		(drill 0.3048)
		(layers "F.Cu" "B.Cu")
		(net "GND")
	)
	(via
		(at 336.5754 -108.585)
		(size 0.508)
		(drill 0.254)
		(layers "F.Cu" "B.Cu")
		(net "GND")
	)
	(via
		(at 345.8464 -152.3746)
		(size 0.508)
		(drill 0.254)
		(layers "F.Cu" "B.Cu")
		(net "GND")
	)
	(via
		(at 249.348244 -96.20504)
		(size 0.508)
		(drill 0.254)
		(layers "F.Cu" "B.Cu")
		(net "GND")
	)
	(via
		(at 291.800534 -167.832024)
		(size 0.5588)
		(drill 0.3048)
		(layers "F.Cu" "B.Cu")
		(net "GND")
	)
	(via
		(at 282.067254 -92.556584)
		(size 0.508)
		(drill 0.254)
		(layers "F.Cu" "B.Cu")
		(net "GND")
	)
	(via
		(at 10.983214 -136.13511)
		(size 0.508)
		(drill 0.254)
		(layers "F.Cu" "B.Cu")
		(net "GND")
	)
	(via
		(at 219.744544 -136.3345)
		(size 0.508)
		(drill 0.254)
		(layers "F.Cu" "B.Cu")
		(net "GND")
	)
	(via
		(at 307.749956 -11.916156)
		(size 0.508)
		(drill 0.254)
		(layers "F.Cu" "B.Cu")
		(net "GND")
	)
	(via
		(at 7.001256 -15.721076)
		(size 0.508)
		(drill 0.254)
		(layers "F.Cu" "B.Cu")
		(net "GND")
	)
	(via
		(at 11.279124 -162.243262)
		(size 0.5588)
		(drill 0.3048)
		(layers "F.Cu" "B.Cu")
		(net "GND")
	)
	(via
		(at 14.4526 -50.2412)
		(size 0.5588)
		(drill 0.3048)
		(layers "F.Cu" "B.Cu")
		(net "GND")
	)
	(via
		(at 166.624 -82.5754)
		(size 0.508)
		(drill 0.254)
		(layers "F.Cu" "B.Cu")
		(net "GND")
	)
	(via
		(at 245.914164 -71.44004)
		(size 0.508)
		(drill 0.254)
		(layers "F.Cu" "B.Cu")
		(net "GND")
	)
	(via
		(at 488.5944 -140.7668)
		(size 0.508)
		(drill 0.254)
		(layers "F.Cu" "B.Cu")
		(net "GND")
	)
	(via
		(at 440.39282 -127.6731)
		(size 0.508)
		(drill 0.254)
		(layers "F.Cu" "B.Cu")
		(net "GND")
	)
	(via
		(at 346.9894 -20.955)
		(size 0.508)
		(drill 0.254)
		(layers "F.Cu" "B.Cu")
		(net "GND")
	)
	(via
		(at 54.744112 -9.0805)
		(size 0.508)
		(drill 0.254)
		(layers "F.Cu" "B.Cu")
		(net "GND")
	)
	(via
		(at 48.399446 -129.568956)
		(size 0.508)
		(drill 0.254)
		(layers "F.Cu" "B.Cu")
		(net "GND")
	)
	(via
		(at 440.720734 -163.361624)
		(size 0.5588)
		(drill 0.3048)
		(layers "F.Cu" "B.Cu")
		(net "GND")
	)
	(via
		(at -5.264404 -9.515602)
		(size 0.508)
		(drill 0.254)
		(layers "F.Cu" "B.Cu")
		(net "GND")
	)
	(via
		(at 304.388266 -61.847984)
		(size 0.508)
		(drill 0.254)
		(layers "F.Cu" "B.Cu")
		(net "GND")
	)
	(via
		(at 454.949814 -58.954924)
		(size 0.508)
		(drill 0.254)
		(layers "F.Cu" "B.Cu")
		(net "GND")
	)
	(via
		(at 71.629524 -162.243262)
		(size 0.5588)
		(drill 0.3048)
		(layers "F.Cu" "B.Cu")
		(net "GND")
	)
	(via
		(at 344.395806 2.165096)
		(size 0.508)
		(drill 0.254)
		(layers "F.Cu" "B.Cu")
		(net "GND")
	)
	(via
		(at 108.481876 -89.584784)
		(size 0.508)
		(drill 0.254)
		(layers "F.Cu" "B.Cu")
		(net "GND")
	)
	(via
		(at 485.399842 -113.8936)
		(size 0.508)
		(drill 0.254)
		(layers "F.Cu" "B.Cu")
		(net "GND")
	)
	(via
		(at 297.520106 -58.876438)
		(size 0.508)
		(drill 0.254)
		(layers "F.Cu" "B.Cu")
		(net "GND")
	)
	(via
		(at 177.165 -134.9375)
		(size 0.508)
		(drill 0.254)
		(layers "F.Cu" "B.Cu")
		(net "GND")
	)
	(via
		(at 403.759416 -149.909784)
		(size 0.508)
		(drill 0.254)
		(layers "F.Cu" "B.Cu")
		(net "GND")
	)
	(via
		(at 185.438796 -94.859602)
		(size 0.508)
		(drill 0.254)
		(layers "F.Cu" "B.Cu")
		(net "GND")
	)
	(via
		(at 209.09915 -134.4041)
		(size 0.508)
		(drill 0.254)
		(layers "F.Cu" "B.Cu")
		(net "GND")
	)
	(via
		(at 360.505502 -1.429004)
		(size 0.5588)
		(drill 0.3048)
		(layers "F.Cu" "B.Cu")
		(net "GND")
	)
	(via
		(at 194.569334 -167.832024)
		(size 0.5588)
		(drill 0.3048)
		(layers "F.Cu" "B.Cu")
		(net "GND")
	)
	(via
		(at 1.006856 10.256266)
		(size 0.5588)
		(drill 0.3048)
		(layers "F.Cu" "B.Cu")
		(net "GND")
	)
	(via
		(at 118.031768 -13.8938)
		(size 0.508)
		(drill 0.254)
		(layers "F.Cu" "B.Cu")
		(net "GND")
	)
	(via
		(at 232.099866 0.444754)
		(size 0.508)
		(drill 0.254)
		(layers "F.Cu" "B.Cu")
		(net "GND")
	)
	(via
		(at 215.2904 -61.1886)
		(size 0.508)
		(drill 0.254)
		(layers "F.Cu" "B.Cu")
		(net "GND")
	)
	(via
		(at 388.605776 -145.98015)
		(size 0.508)
		(drill 0.254)
		(layers "F.Cu" "B.Cu")
		(net "GND")
	)
	(via
		(at 314.54979 -140.617956)
		(size 0.508)
		(drill 0.254)
		(layers "F.Cu" "B.Cu")
		(net "GND")
	)
	(via
		(at 32.160464 -130.991356)
		(size 0.508)
		(drill 0.254)
		(layers "F.Cu" "B.Cu")
		(net "GND")
	)
	(via
		(at 147.381468 -129.5654)
		(size 0.508)
		(drill 0.254)
		(layers "F.Cu" "B.Cu")
		(net "GND")
	)
	(via
		(at 249.348244 -88.28024)
		(size 0.508)
		(drill 0.254)
		(layers "F.Cu" "B.Cu")
		(net "GND")
	)
	(via
		(at 236.470698 -68.963286)
		(size 0.508)
		(drill 0.254)
		(layers "F.Cu" "B.Cu")
		(net "GND")
	)
	(via
		(at 10.165334 -167.832024)
		(size 0.5588)
		(drill 0.3048)
		(layers "F.Cu" "B.Cu")
		(net "GND")
	)
	(via
		(at 384.1496 -115.443)
		(size 0.508)
		(drill 0.254)
		(layers "F.Cu" "B.Cu")
		(net "GND")
	)
	(via
		(at 118.783862 -103.453184)
		(size 0.508)
		(drill 0.254)
		(layers "F.Cu" "B.Cu")
		(net "GND")
	)
	(via
		(at 123.199398 -17.208246)
		(size 0.508)
		(drill 0.254)
		(layers "F.Cu" "B.Cu")
		(net "GND")
	)
	(via
		(at 39.049452 -136.410446)
		(size 0.508)
		(drill 0.254)
		(layers "F.Cu" "B.Cu")
		(net "GND")
	)
	(via
		(at 296.66184 -52.437538)
		(size 0.508)
		(drill 0.254)
		(layers "F.Cu" "B.Cu")
		(net "GND")
	)
	(via
		(at 206.906114 -77.814678)
		(size 0.5588)
		(drill 0.3048)
		(layers "F.Cu" "B.Cu")
		(net "GND")
	)
	(via
		(at 42.680382 -69.577458)
		(size 0.5588)
		(drill 0.3048)
		(layers "F.Cu" "B.Cu")
		(net "GND")
	)
	(via
		(at 421.004492 -70.4342)
		(size 0.508)
		(drill 0.254)
		(layers "F.Cu" "B.Cu")
		(net "GND")
	)
	(via
		(at 280.065734 -54.418738)
		(size 0.508)
		(drill 0.254)
		(layers "F.Cu" "B.Cu")
		(net "GND")
	)
	(via
		(at 136.74217 -148.767292)
		(size 0.508)
		(drill 0.254)
		(layers "F.Cu" "B.Cu")
		(net "GND")
	)
	(via
		(at 59.449462 -11.916156)
		(size 0.508)
		(drill 0.254)
		(layers "F.Cu" "B.Cu")
		(net "GND")
	)
	(via
		(at 24.871934 14.926056)
		(size 0.5588)
		(drill 0.3048)
		(layers "F.Cu" "B.Cu")
		(net "GND")
	)
	(via
		(at 50.194718 -61.744606)
		(size 0.508)
		(drill 0.254)
		(layers "F.Cu" "B.Cu")
		(net "GND")
	)
	(via
		(at 423.651934 9.084056)
		(size 0.5588)
		(drill 0.3048)
		(layers "F.Cu" "B.Cu")
		(net "GND")
	)
	(via
		(at 86.923372 -71.935086)
		(size 0.508)
		(drill 0.254)
		(layers "F.Cu" "B.Cu")
		(net "GND")
	)
	(via
		(at 108.514134 -167.832024)
		(size 0.5588)
		(drill 0.3048)
		(layers "F.Cu" "B.Cu")
		(net "GND")
	)
	(via
		(at 474.726 -39.0906)
		(size 0.508)
		(drill 0.254)
		(layers "F.Cu" "B.Cu")
		(net "GND")
	)
	(via
		(at 398.13865 -100.181156)
		(size 0.508)
		(drill 0.254)
		(layers "F.Cu" "B.Cu")
		(net "GND")
	)
	(via
		(at 140.199364 1.994154)
		(size 0.508)
		(drill 0.254)
		(layers "F.Cu" "B.Cu")
		(net "GND")
	)
	(via
		(at 345.441524 -162.243262)
		(size 0.5588)
		(drill 0.3048)
		(layers "F.Cu" "B.Cu")
		(net "GND")
	)
	(via
		(at 358.2797 -81.4832)
		(size 0.508)
		(drill 0.254)
		(layers "F.Cu" "B.Cu")
		(net "GND")
	)
	(via
		(at 269.04188 -82.340196)
		(size 0.5588)
		(drill 0.3048)
		(layers "F.Cu" "B.Cu")
		(net "GND")
	)
	(via
		(at 488.421934 12.894056)
		(size 0.5588)
		(drill 0.3048)
		(layers "F.Cu" "B.Cu")
		(net "GND")
	)
	(via
		(at 69.753226 -96.700086)
		(size 0.508)
		(drill 0.254)
		(layers "F.Cu" "B.Cu")
		(net "GND")
	)
	(via
		(at 165.4302 -5.08)
		(size 0.508)
		(drill 0.254)
		(layers "F.Cu" "B.Cu")
		(net "GND")
	)
	(via
		(at 211.699856 -9.156446)
		(size 0.508)
		(drill 0.254)
		(layers "F.Cu" "B.Cu")
		(net "GND")
	)
	(via
		(at 440.182 -142.24)
		(size 0.508)
		(drill 0.254)
		(layers "F.Cu" "B.Cu")
		(net "GND")
	)
	(via
		(at 413.890206 -33.334706)
		(size 0.4572)
		(drill 0.2032)
		(layers "F.Cu" "B.Cu")
		(net "GND")
	)
	(via
		(at 65.399412 -136.410446)
		(size 0.508)
		(drill 0.254)
		(layers "F.Cu" "B.Cu")
		(net "GND")
	)
	(via
		(at 132.519674 -88.594184)
		(size 0.508)
		(drill 0.254)
		(layers "F.Cu" "B.Cu")
		(net "GND")
	)
	(via
		(at 446.024 -53.34)
		(size 0.508)
		(drill 0.254)
		(layers "F.Cu" "B.Cu")
		(net "GND")
	)
	(via
		(at 102.639876 -70.84314)
		(size 0.5588)
		(drill 0.3048)
		(layers "F.Cu" "B.Cu")
		(net "GND")
	)
	(via
		(at 298.399962 -148.771356)
		(size 0.508)
		(drill 0.254)
		(layers "F.Cu" "B.Cu")
		(net "GND")
	)
	(via
		(at 40.800782 -76.468478)
		(size 0.5588)
		(drill 0.3048)
		(layers "F.Cu" "B.Cu")
		(net "GND")
	)
	(via
		(at 311.0992 -144.0053)
		(size 0.508)
		(drill 0.254)
		(layers "F.Cu" "B.Cu")
		(net "GND")
	)
	(via
		(at 112.774222 -102.958138)
		(size 0.508)
		(drill 0.254)
		(layers "F.Cu" "B.Cu")
		(net "GND")
	)
	(via
		(at 301.812706 -73.240138)
		(size 0.508)
		(drill 0.254)
		(layers "F.Cu" "B.Cu")
		(net "GND")
	)
	(via
		(at 284.33776 -4.346956)
		(size 0.508)
		(drill 0.254)
		(layers "F.Cu" "B.Cu")
		(net "GND")
	)
	(via
		(at 70.611746 -93.23324)
		(size 0.508)
		(drill 0.254)
		(layers "F.Cu" "B.Cu")
		(net "GND")
	)
	(via
		(at 56.899302 -131.016756)
		(size 0.508)
		(drill 0.254)
		(layers "F.Cu" "B.Cu")
		(net "GND")
	)
	(via
		(at 296.267124 -162.243262)
		(size 0.5588)
		(drill 0.3048)
		(layers "F.Cu" "B.Cu")
		(net "GND")
	)
	(via
		(at 199.742552 -155.600146)
		(size 0.508)
		(drill 0.254)
		(layers "F.Cu" "B.Cu")
		(net "GND")
	)
	(via
		(at 408.463242 -3.378708)
		(size 0.508)
		(drill 0.254)
		(layers "F.Cu" "B.Cu")
		(net "GND")
	)
	(via
		(at 69.753226 -90.756486)
		(size 0.508)
		(drill 0.254)
		(layers "F.Cu" "B.Cu")
		(net "GND")
	)
	(via
		(at 68.894706 -60.54344)
		(size 0.508)
		(drill 0.254)
		(layers "F.Cu" "B.Cu")
		(net "GND")
	)
	(via
		(at 420.400734 -167.832024)
		(size 0.5588)
		(drill 0.3048)
		(layers "F.Cu" "B.Cu")
		(net "GND")
	)
	(via
		(at 470.16162 -0.289306)
		(size 0.5588)
		(drill 0.3048)
		(layers "F.Cu" "B.Cu")
		(net "GND")
	)
	(via
		(at 234.753658 -81.841086)
		(size 0.508)
		(drill 0.254)
		(layers "F.Cu" "B.Cu")
		(net "GND")
	)
	(via
		(at 343.641934 14.926056)
		(size 0.5588)
		(drill 0.3048)
		(layers "F.Cu" "B.Cu")
		(net "GND")
	)
	(via
		(at 298.384468 -26.495756)
		(size 0.508)
		(drill 0.254)
		(layers "F.Cu" "B.Cu")
		(net "GND")
	)
	(via
		(at -1.550416 -117.14226)
		(size 0.508)
		(drill 0.254)
		(layers "F.Cu" "B.Cu")
		(net "GND")
	)
	(via
		(at 249.348244 -63.51524)
		(size 0.508)
		(drill 0.254)
		(layers "F.Cu" "B.Cu")
		(net "GND")
	)
	(via
		(at 226.801934 14.926056)
		(size 0.5588)
		(drill 0.3048)
		(layers "F.Cu" "B.Cu")
		(net "GND")
	)
	(via
		(at 385.75615 -120.387364)
		(size 0.508)
		(drill 0.254)
		(layers "F.Cu" "B.Cu")
		(net "GND")
	)
	(via
		(at 45.928534 -167.832024)
		(size 0.5588)
		(drill 0.3048)
		(layers "F.Cu" "B.Cu")
		(net "GND")
	)
	(via
		(at 312.387996 -13.948156)
		(size 0.508)
		(drill 0.254)
		(layers "F.Cu" "B.Cu")
		(net "GND")
	)
	(via
		(at 295.80332 -83.641184)
		(size 0.508)
		(drill 0.254)
		(layers "F.Cu" "B.Cu")
		(net "GND")
	)
	(via
		(at 338.1756 -59.679586)
		(size 0.508)
		(drill 0.254)
		(layers "F.Cu" "B.Cu")
		(net "GND")
	)
	(via
		(at 76.621386 -67.972686)
		(size 0.508)
		(drill 0.254)
		(layers "F.Cu" "B.Cu")
		(net "GND")
	)
	(via
		(at 244.581934 14.926056)
		(size 0.5588)
		(drill 0.3048)
		(layers "F.Cu" "B.Cu")
		(net "GND")
	)
	(via
		(at 126.510288 -77.202538)
		(size 0.508)
		(drill 0.254)
		(layers "F.Cu" "B.Cu")
		(net "GND")
	)
	(via
		(at 146.092164 -139.166092)
		(size 0.508)
		(drill 0.254)
		(layers "F.Cu" "B.Cu")
		(net "GND")
	)
	(via
		(at 67.949318 -7.607046)
		(size 0.508)
		(drill 0.254)
		(layers "F.Cu" "B.Cu")
		(net "GND")
	)
	(via
		(at 226.822 -154.1018)
		(size 0.508)
		(drill 0.254)
		(layers "F.Cu" "B.Cu")
		(net "GND")
	)
	(via
		(at 118.783862 -86.612984)
		(size 0.508)
		(drill 0.254)
		(layers "F.Cu" "B.Cu")
		(net "GND")
	)
	(via
		(at 296.66184 -83.146138)
		(size 0.508)
		(drill 0.254)
		(layers "F.Cu" "B.Cu")
		(net "GND")
	)
	(via
		(at 350.006666 -137.189718)
		(size 0.508)
		(drill 0.254)
		(layers "F.Cu" "B.Cu")
		(net "GND")
	)
	(via
		(at 442.597286 -151.350726)
		(size 0.508)
		(drill 0.254)
		(layers "F.Cu" "B.Cu")
		(net "GND")
	)
	(via
		(at 117.925342 -98.005138)
		(size 0.508)
		(drill 0.254)
		(layers "F.Cu" "B.Cu")
		(net "GND")
	)
	(via
		(at 225.8314 -126.619)
		(size 0.508)
		(drill 0.254)
		(layers "F.Cu" "B.Cu")
		(net "GND")
	)
	(via
		(at 245.914164 -98.18624)
		(size 0.508)
		(drill 0.254)
		(layers "F.Cu" "B.Cu")
		(net "GND")
	)
	(via
		(at 351.542096 -81.33715)
		(size 0.508)
		(drill 0.254)
		(layers "F.Cu" "B.Cu")
		(net "GND")
	)
	(via
		(at 213.564724 -162.243262)
		(size 0.5588)
		(drill 0.3048)
		(layers "F.Cu" "B.Cu")
		(net "GND")
	)
	(via
		(at 124.049536 -155.600146)
		(size 0.508)
		(drill 0.254)
		(layers "F.Cu" "B.Cu")
		(net "GND")
	)
	(via
		(at 83.489292 -78.869286)
		(size 0.508)
		(drill 0.254)
		(layers "F.Cu" "B.Cu")
		(net "GND")
	)
	(via
		(at 17.9832 -38.4556)
		(size 0.508)
		(drill 0.254)
		(layers "F.Cu" "B.Cu")
		(net "GND")
	)
	(via
		(at 117.071648 -3.762756)
		(size 0.508)
		(drill 0.254)
		(layers "F.Cu" "B.Cu")
		(net "GND")
	)
	(via
		(at 285.221934 14.926056)
		(size 0.5588)
		(drill 0.3048)
		(layers "F.Cu" "B.Cu")
		(net "GND")
	)
	(via
		(at 33.061402 -129.568956)
		(size 0.508)
		(drill 0.254)
		(layers "F.Cu" "B.Cu")
		(net "GND")
	)
	(via
		(at 429.290734 -164.479224)
		(size 0.5588)
		(drill 0.3048)
		(layers "F.Cu" "B.Cu")
		(net "GND")
	)
	(via
		(at 344.61704 -16.93164)
		(size 0.508)
		(drill 0.254)
		(layers "F.Cu" "B.Cu")
		(net "GND")
	)
	(via
		(at 53.751734 -167.832024)
		(size 0.5588)
		(drill 0.3048)
		(layers "F.Cu" "B.Cu")
		(net "GND")
	)
	(via
		(at 311.092596 0.457454)
		(size 0.508)
		(drill 0.254)
		(layers "F.Cu" "B.Cu")
		(net "GND")
	)
	(via
		(at 305.199796 -3.762756)
		(size 0.508)
		(drill 0.254)
		(layers "F.Cu" "B.Cu")
		(net "GND")
	)
	(via
		(at 95.451168 -1.651)
		(size 0.508)
		(drill 0.254)
		(layers "F.Cu" "B.Cu")
		(net "GND")
	)
	(via
		(at 207.564482 -60.869322)
		(size 0.5588)
		(drill 0.3048)
		(layers "F.Cu" "B.Cu")
		(net "GND")
	)
	(via
		(at 215.0999 -155.600146)
		(size 0.508)
		(drill 0.254)
		(layers "F.Cu" "B.Cu")
		(net "GND")
	)
	(via
		(at 157.325568 -130.7338)
		(size 0.508)
		(drill 0.254)
		(layers "F.Cu" "B.Cu")
		(net "GND")
	)
	(via
		(at 430.001934 9.084056)
		(size 0.5588)
		(drill 0.3048)
		(layers "F.Cu" "B.Cu")
		(net "GND")
	)
	(via
		(at 293.694612 -155.5369)
		(size 0.508)
		(drill 0.254)
		(layers "F.Cu" "B.Cu")
		(net "GND")
	)
	(via
		(at 72.142096 -11.912092)
		(size 0.508)
		(drill 0.254)
		(layers "F.Cu" "B.Cu")
		(net "GND")
	)
	(via
		(at 74.045826 -55.59044)
		(size 0.508)
		(drill 0.254)
		(layers "F.Cu" "B.Cu")
		(net "GND")
	)
	(via
		(at 237.142528 -9.143746)
		(size 0.508)
		(drill 0.254)
		(layers "F.Cu" "B.Cu")
		(net "GND")
	)
	(via
		(at 402.620734 -163.361624)
		(size 0.5588)
		(drill 0.3048)
		(layers "F.Cu" "B.Cu")
		(net "GND")
	)
	(via
		(at 251.065284 -67.47764)
		(size 0.508)
		(drill 0.254)
		(layers "F.Cu" "B.Cu")
		(net "GND")
	)
	(via
		(at 373.5832 -102.1715)
		(size 0.508)
		(drill 0.254)
		(layers "F.Cu" "B.Cu")
		(net "GND")
	)
	(via
		(at 358.671622 -142.327122)
		(size 0.508)
		(drill 0.254)
		(layers "F.Cu" "B.Cu")
		(net "GND")
	)
	(via
		(at 117.925342 -102.958138)
		(size 0.508)
		(drill 0.254)
		(layers "F.Cu" "B.Cu")
		(net "GND")
	)
	(via
		(at 112.202722 -50.759614)
		(size 0.508)
		(drill 0.254)
		(layers "F.Cu" "B.Cu")
		(net "GND")
	)
	(via
		(at 279.491694 -100.976938)
		(size 0.508)
		(drill 0.254)
		(layers "F.Cu" "B.Cu")
		(net "GND")
	)
	(via
		(at 332.030324 -162.243262)
		(size 0.5588)
		(drill 0.3048)
		(layers "F.Cu" "B.Cu")
		(net "GND")
	)
	(via
		(at 32.15132 -144.462246)
		(size 0.508)
		(drill 0.254)
		(layers "F.Cu" "B.Cu")
		(net "GND")
	)
	(via
		(at 126.510288 -88.099138)
		(size 0.508)
		(drill 0.254)
		(layers "F.Cu" "B.Cu")
		(net "GND")
	)
	(via
		(at 476.280734 -164.479224)
		(size 0.5588)
		(drill 0.3048)
		(layers "F.Cu" "B.Cu")
		(net "GND")
	)
	(via
		(at 412.883096 -46.870874)
		(size 0.508)
		(drill 0.254)
		(layers "F.Cu" "B.Cu")
		(net "GND")
	)
	(via
		(at 40.749474 -9.143746)
		(size 0.508)
		(drill 0.254)
		(layers "F.Cu" "B.Cu")
		(net "GND")
	)
	(via
		(at 175.27016 -104.65562)
		(size 0.508)
		(drill 0.254)
		(layers "F.Cu" "B.Cu")
		(net "GND")
	)
	(via
		(at 53.442108 -2.310892)
		(size 0.508)
		(drill 0.254)
		(layers "F.Cu" "B.Cu")
		(net "GND")
	)
	(via
		(at 138.529314 -85.127338)
		(size 0.508)
		(drill 0.254)
		(layers "F.Cu" "B.Cu")
		(net "GND")
	)
	(via
		(at 245.851934 9.084056)
		(size 0.5588)
		(drill 0.3048)
		(layers "F.Cu" "B.Cu")
		(net "GND")
	)
	(via
		(at 127.392176 -145.998946)
		(size 0.508)
		(drill 0.254)
		(layers "F.Cu" "B.Cu")
		(net "GND")
	)
	(via
		(at 75.762866 -51.62804)
		(size 0.508)
		(drill 0.254)
		(layers "F.Cu" "B.Cu")
		(net "GND")
	)
	(via
		(at 111.915702 -92.556584)
		(size 0.508)
		(drill 0.254)
		(layers "F.Cu" "B.Cu")
		(net "GND")
	)
	(via
		(at 301.742602 -139.166092)
		(size 0.508)
		(drill 0.254)
		(layers "F.Cu" "B.Cu")
		(net "GND")
	)
	(via
		(at 303.041304 -143.950944)
		(size 0.508)
		(drill 0.254)
		(layers "F.Cu" "B.Cu")
		(net "GND")
	)
	(via
		(at 388.9375 -114.6556)
		(size 0.508)
		(drill 0.254)
		(layers "F.Cu" "B.Cu")
		(net "GND")
	)
	(via
		(at 278.897588 -9.083294)
		(size 0.508)
		(drill 0.254)
		(layers "F.Cu" "B.Cu")
		(net "GND")
	)
	(via
		(at 376.5042 -126.7206)
		(size 0.508)
		(drill 0.254)
		(layers "F.Cu" "B.Cu")
		(net "GND")
	)
	(via
		(at 289.801808 -144.462246)
		(size 0.508)
		(drill 0.254)
		(layers "F.Cu" "B.Cu")
		(net "GND")
	)
	(via
		(at 395.66215 -120.387364)
		(size 0.508)
		(drill 0.254)
		(layers "F.Cu" "B.Cu")
		(net "GND")
	)
	(via
		(at 60.201302 -7.607046)
		(size 0.508)
		(drill 0.254)
		(layers "F.Cu" "B.Cu")
		(net "GND")
	)
	(via
		(at 412.221934 14.926056)
		(size 0.5588)
		(drill 0.3048)
		(layers "F.Cu" "B.Cu")
		(net "GND")
	)
	(via
		(at 398.13865 -119.528844)
		(size 0.508)
		(drill 0.254)
		(layers "F.Cu" "B.Cu")
		(net "GND")
	)
	(via
		(at 218.449144 -134.4041)
		(size 0.508)
		(drill 0.254)
		(layers "F.Cu" "B.Cu")
		(net "GND")
	)
	(via
		(at 294.08628 -79.678784)
		(size 0.508)
		(drill 0.254)
		(layers "F.Cu" "B.Cu")
		(net "GND")
	)
	(via
		(at 56.049418 -9.156446)
		(size 0.508)
		(drill 0.254)
		(layers "F.Cu" "B.Cu")
		(net "GND")
	)
	(via
		(at 375.944892 -77.494892)
		(size 0.4572)
		(drill 0.2032)
		(layers "F.Cu" "B.Cu")
		(net "GND")
	)
	(via
		(at 398.63395 -106.190796)
		(size 0.508)
		(drill 0.254)
		(layers "F.Cu" "B.Cu")
		(net "GND")
	)
	(via
		(at 393.726924 -162.243262)
		(size 0.5588)
		(drill 0.3048)
		(layers "F.Cu" "B.Cu")
		(net "GND")
	)
	(via
		(at 40.749474 -148.771356)
		(size 0.508)
		(drill 0.254)
		(layers "F.Cu" "B.Cu")
		(net "GND")
	)
	(via
		(at 335.256124 -85.85835)
		(size 0.508)
		(drill 0.254)
		(layers "F.Cu" "B.Cu")
		(net "GND")
	)
	(via
		(at 358.013 -136.652)
		(size 0.508)
		(drill 0.254)
		(layers "F.Cu" "B.Cu")
		(net "GND")
	)
	(via
		(at 61.149484 -146.011646)
		(size 0.508)
		(drill 0.254)
		(layers "F.Cu" "B.Cu")
		(net "GND")
	)
	(via
		(at 287.349946 0.444754)
		(size 0.508)
		(drill 0.254)
		(layers "F.Cu" "B.Cu")
		(net "GND")
	)
	(via
		(at 352.938842 -1.261364)
		(size 0.508)
		(drill 0.254)
		(layers "F.Cu" "B.Cu")
		(net "GND")
	)
	(via
		(at 435.2417 -14.224)
		(size 0.508)
		(drill 0.254)
		(layers "F.Cu" "B.Cu")
		(net "GND")
	)
	(via
		(at 233.681524 -162.243262)
		(size 0.5588)
		(drill 0.3048)
		(layers "F.Cu" "B.Cu")
		(net "GND")
	)
	(via
		(at 147.387564 -13.948156)
		(size 0.508)
		(drill 0.254)
		(layers "F.Cu" "B.Cu")
		(net "GND")
	)
	(via
		(at 175.014382 -50.831496)
		(size 0.508)
		(drill 0.254)
		(layers "F.Cu" "B.Cu")
		(net "GND")
	)
	(via
		(at 58.222134 -167.832024)
		(size 0.5588)
		(drill 0.3048)
		(layers "F.Cu" "B.Cu")
		(net "GND")
	)
	(via
		(at 43.12158 -13.363956)
		(size 0.508)
		(drill 0.254)
		(layers "F.Cu" "B.Cu")
		(net "GND")
	)
	(via
		(at 25.527 -47.9044)
		(size 0.508)
		(drill 0.254)
		(layers "F.Cu" "B.Cu")
		(net "GND")
	)
	(via
		(at 66.249296 -131.016756)
		(size 0.508)
		(drill 0.254)
		(layers "F.Cu" "B.Cu")
		(net "GND")
	)
	(via
		(at 39.243 -52.197)
		(size 0.5588)
		(drill 0.3048)
		(layers "F.Cu" "B.Cu")
		(net "GND")
	)
	(via
		(at 73.437496 -150.803356)
		(size 0.508)
		(drill 0.254)
		(layers "F.Cu" "B.Cu")
		(net "GND")
	)
	(via
		(at 383.985008 -126.69012)
		(size 0.508)
		(drill 0.254)
		(layers "F.Cu" "B.Cu")
		(net "GND")
	)
	(via
		(at 482.071934 14.926056)
		(size 0.5588)
		(drill 0.3048)
		(layers "F.Cu" "B.Cu")
		(net "GND")
	)
	(via
		(at 401.4216 -144.272)
		(size 0.508)
		(drill 0.254)
		(layers "F.Cu" "B.Cu")
		(net "GND")
	)
	(via
		(at 240.599722 -134.861046)
		(size 0.508)
		(drill 0.254)
		(layers "F.Cu" "B.Cu")
		(net "GND")
	)
	(via
		(at 259.65023 -91.25204)
		(size 0.508)
		(drill 0.254)
		(layers "F.Cu" "B.Cu")
		(net "GND")
	)
	(via
		(at 457.581 -119.64797)
		(size 0.508)
		(drill 0.254)
		(layers "F.Cu" "B.Cu")
		(net "GND")
	)
	(via
		(at 183.922924 -154.8257)
		(size 0.508)
		(drill 0.254)
		(layers "F.Cu" "B.Cu")
		(net "GND")
	)
	(via
		(at 82.3468 -51.132232)
		(size 0.508)
		(drill 0.254)
		(layers "F.Cu" "B.Cu")
		(net "GND")
	)
	(via
		(at 296.66184 -86.117938)
		(size 0.508)
		(drill 0.254)
		(layers "F.Cu" "B.Cu")
		(net "GND")
	)
	(via
		(at 133.39953 -21.517356)
		(size 0.508)
		(drill 0.254)
		(layers "F.Cu" "B.Cu")
		(net "GND")
	)
	(via
		(at 458.0636 -28.956)
		(size 0.508)
		(drill 0.254)
		(layers "F.Cu" "B.Cu")
		(net "GND")
	)
	(via
		(at 440.161934 12.894056)
		(size 0.5588)
		(drill 0.3048)
		(layers "F.Cu" "B.Cu")
		(net "GND")
	)
	(via
		(at 116.399564 -155.612846)
		(size 0.508)
		(drill 0.254)
		(layers "F.Cu" "B.Cu")
		(net "GND")
	)
	(via
		(at 293.688008 -126.712218)
		(size 0.508)
		(drill 0.254)
		(layers "F.Cu" "B.Cu")
		(net "GND")
	)
	(via
		(at 389.3312 -19.96186)
		(size 0.508)
		(drill 0.254)
		(layers "F.Cu" "B.Cu")
		(net "GND")
	)
	(via
		(at 199.742552 -136.397746)
		(size 0.508)
		(drill 0.254)
		(layers "F.Cu" "B.Cu")
		(net "GND")
	)
	(via
		(at 376.428 -98.354896)
		(size 0.508)
		(drill 0.254)
		(layers "F.Cu" "B.Cu")
		(net "GND")
	)
	(via
		(at 56.899302 -7.607046)
		(size 0.508)
		(drill 0.254)
		(layers "F.Cu" "B.Cu")
		(net "GND")
	)
	(via
		(at 71.171562 -134.8994)
		(size 0.508)
		(drill 0.254)
		(layers "F.Cu" "B.Cu")
		(net "GND")
	)
	(via
		(at 397.3322 -155.321)
		(size 0.508)
		(drill 0.254)
		(layers "F.Cu" "B.Cu")
		(net "GND")
	)
	(via
		(at 75.59929 -17.208246)
		(size 0.508)
		(drill 0.254)
		(layers "F.Cu" "B.Cu")
		(net "GND")
	)
	(via
		(at 344.7542 -9.4742)
		(size 0.508)
		(drill 0.254)
		(layers "F.Cu" "B.Cu")
		(net "GND")
	)
	(via
		(at 37.8206 -48.2854)
		(size 0.508)
		(drill 0.254)
		(layers "F.Cu" "B.Cu")
		(net "GND")
	)
	(via
		(at 52.471574 -13.363956)
		(size 0.508)
		(drill 0.254)
		(layers "F.Cu" "B.Cu")
		(net "GND")
	)
	(via
		(at 199.4916 -94.5896)
		(size 0.5588)
		(drill 0.3048)
		(layers "F.Cu" "B.Cu")
		(net "GND")
	)
	(via
		(at 468.122 -128.27)
		(size 0.508)
		(drill 0.254)
		(layers "F.Cu" "B.Cu")
		(net "GND")
	)
	(via
		(at 87.781892 -91.25204)
		(size 0.508)
		(drill 0.254)
		(layers "F.Cu" "B.Cu")
		(net "GND")
	)
	(via
		(at 124.049536 -9.143746)
		(size 0.508)
		(drill 0.254)
		(layers "F.Cu" "B.Cu")
		(net "GND")
	)
	(via
		(at 50.395124 -162.243262)
		(size 0.5588)
		(drill 0.3048)
		(layers "F.Cu" "B.Cu")
		(net "GND")
	)
	(via
		(at 312.391298 2.505456)
		(size 0.508)
		(drill 0.254)
		(layers "F.Cu" "B.Cu")
		(net "GND")
	)
	(via
		(at 134.15137 -144.462246)
		(size 0.508)
		(drill 0.254)
		(layers "F.Cu" "B.Cu")
		(net "GND")
	)
	(via
		(at 470.16162 -157.389322)
		(size 0.5588)
		(drill 0.3048)
		(layers "F.Cu" "B.Cu")
		(net "GND")
	)
	(via
		(at 75.671934 14.926056)
		(size 0.5588)
		(drill 0.3048)
		(layers "F.Cu" "B.Cu")
		(net "GND")
	)
	(via
		(at 74.045826 -88.28024)
		(size 0.508)
		(drill 0.254)
		(layers "F.Cu" "B.Cu")
		(net "GND")
	)
	(via
		(at 127.38608 -131.5466)
		(size 0.508)
		(drill 0.254)
		(layers "F.Cu" "B.Cu")
		(net "GND")
	)
	(via
		(at 279.503124 -162.243262)
		(size 0.5588)
		(drill 0.3048)
		(layers "F.Cu" "B.Cu")
		(net "GND")
	)
	(via
		(at 109.055916 -62.838584)
		(size 0.508)
		(drill 0.254)
		(layers "F.Cu" "B.Cu")
		(net "GND")
	)
	(via
		(at 74.045826 -74.411586)
		(size 0.508)
		(drill 0.254)
		(layers "F.Cu" "B.Cu")
		(net "GND")
	)
	(via
		(at 66.781934 9.084056)
		(size 0.5588)
		(drill 0.3048)
		(layers "F.Cu" "B.Cu")
		(net "GND")
	)
	(via
		(at 89.511124 -162.243262)
		(size 0.5588)
		(drill 0.3048)
		(layers "F.Cu" "B.Cu")
		(net "GND")
	)
	(via
		(at 61.149484 -155.612846)
		(size 0.508)
		(drill 0.254)
		(layers "F.Cu" "B.Cu")
		(net "GND")
	)
	(via
		(at 293.22776 -80.174338)
		(size 0.508)
		(drill 0.254)
		(layers "F.Cu" "B.Cu")
		(net "GND")
	)
	(via
		(at 231.249728 -22.965156)
		(size 0.508)
		(drill 0.254)
		(layers "F.Cu" "B.Cu")
		(net "GND")
	)
	(via
		(at 294.999918 -21.517356)
		(size 0.508)
		(drill 0.254)
		(layers "F.Cu" "B.Cu")
		(net "GND")
	)
	(via
		(at 492.35614 -124.6251)
		(size 0.508)
		(drill 0.254)
		(layers "F.Cu" "B.Cu")
		(net "GND")
	)
	(via
		(at 391.0076 -81.3308)
		(size 0.508)
		(drill 0.254)
		(layers "F.Cu" "B.Cu")
		(net "GND")
	)
	(via
		(at 52.471574 -131.016756)
		(size 0.508)
		(drill 0.254)
		(layers "F.Cu" "B.Cu")
		(net "GND")
	)
	(via
		(at 170.634914 -149.58568)
		(size 0.508)
		(drill 0.254)
		(layers "F.Cu" "B.Cu")
		(net "GND")
	)
	(via
		(at 73.437496 -4.346956)
		(size 0.508)
		(drill 0.254)
		(layers "F.Cu" "B.Cu")
		(net "GND")
	)
	(via
		(at 199.736456 -13.8938)
		(size 0.508)
		(drill 0.254)
		(layers "F.Cu" "B.Cu")
		(net "GND")
	)
	(via
		(at 282.925774 -91.070938)
		(size 0.508)
		(drill 0.254)
		(layers "F.Cu" "B.Cu")
		(net "GND")
	)
	(via
		(at 19.791934 14.926056)
		(size 0.5588)
		(drill 0.3048)
		(layers "F.Cu" "B.Cu")
		(net "GND")
	)
	(via
		(at 234.560872 -27.910536)
		(size 0.508)
		(drill 0.254)
		(layers "F.Cu" "B.Cu")
		(net "GND")
	)
	(via
		(at 71.171562 -13.363956)
		(size 0.508)
		(drill 0.254)
		(layers "F.Cu" "B.Cu")
		(net "GND")
	)
	(via
		(at 343.20226 -13.89634)
		(size 0.508)
		(drill 0.254)
		(layers "F.Cu" "B.Cu")
		(net "GND")
	)
	(via
		(at 127.378968 -13.8938)
		(size 0.508)
		(drill 0.254)
		(layers "F.Cu" "B.Cu")
		(net "GND")
	)
	(via
		(at 232.101898 -57.57164)
		(size 0.508)
		(drill 0.254)
		(layers "F.Cu" "B.Cu")
		(net "GND")
	)
	(via
		(at 435.404006 -40.5257)
		(size 0.508)
		(drill 0.254)
		(layers "F.Cu" "B.Cu")
		(net "GND")
	)
	(via
		(at 459.211934 14.926056)
		(size 0.5588)
		(drill 0.3048)
		(layers "F.Cu" "B.Cu")
		(net "GND")
	)
	(via
		(at 150.399496 -2.314956)
		(size 0.508)
		(drill 0.254)
		(layers "F.Cu" "B.Cu")
		(net "GND")
	)
	(via
		(at 146.205956 -117.270276)
		(size 0.508)
		(drill 0.254)
		(layers "F.Cu" "B.Cu")
		(net "GND")
	)
	(via
		(at 191.77 -145.9992)
		(size 0.508)
		(drill 0.254)
		(layers "F.Cu" "B.Cu")
		(net "GND")
	)
	(via
		(at 283.048964 -134.4041)
		(size 0.508)
		(drill 0.254)
		(layers "F.Cu" "B.Cu")
		(net "GND")
	)
	(via
		(at 239.046258 -95.21444)
		(size 0.508)
		(drill 0.254)
		(layers "F.Cu" "B.Cu")
		(net "GND")
	)
	(via
		(at 41.381934 14.926056)
		(size 0.5588)
		(drill 0.3048)
		(layers "F.Cu" "B.Cu")
		(net "GND")
	)
	(via
		(at 230.399844 -21.517356)
		(size 0.508)
		(drill 0.254)
		(layers "F.Cu" "B.Cu")
		(net "GND")
	)
	(via
		(at 281.208734 -92.061538)
		(size 0.508)
		(drill 0.254)
		(layers "F.Cu" "B.Cu")
		(net "GND")
	)
	(via
		(at 397.74876 -145.57248)
		(size 0.508)
		(drill 0.254)
		(layers "F.Cu" "B.Cu")
		(net "GND")
	)
	(via
		(at 306.963826 -59.371484)
		(size 0.508)
		(drill 0.254)
		(layers "F.Cu" "B.Cu")
		(net "GND")
	)
	(via
		(at 43.12158 -22.952456)
		(size 0.508)
		(drill 0.254)
		(layers "F.Cu" "B.Cu")
		(net "GND")
	)
	(via
		(at 239.904778 -97.690686)
		(size 0.508)
		(drill 0.254)
		(layers "F.Cu" "B.Cu")
		(net "GND")
	)
	(via
		(at 199.992234 -63.427864)
		(size 0.508)
		(drill 0.254)
		(layers "F.Cu" "B.Cu")
		(net "GND")
	)
	(via
		(at 237.142528 -129.564892)
		(size 0.508)
		(drill 0.254)
		(layers "F.Cu" "B.Cu")
		(net "GND")
	)
	(via
		(at 233.036618 -88.775286)
		(size 0.508)
		(drill 0.254)
		(layers "F.Cu" "B.Cu")
		(net "GND")
	)
	(via
		(at 274.056348 -55.904384)
		(size 0.508)
		(drill 0.254)
		(layers "F.Cu" "B.Cu")
		(net "GND")
	)
	(via
		(at 430.560734 -166.714424)
		(size 0.5588)
		(drill 0.3048)
		(layers "F.Cu" "B.Cu")
		(net "GND")
	)
	(via
		(at 245.627144 -49.150778)
		(size 0.508)
		(drill 0.254)
		(layers "F.Cu" "B.Cu")
		(net "GND")
	)
	(via
		(at 42.411396 -136.410446)
		(size 0.508)
		(drill 0.254)
		(layers "F.Cu" "B.Cu")
		(net "GND")
	)
	(via
		(at 159.2326 -32.5882)
		(size 0.508)
		(drill 0.254)
		(layers "F.Cu" "B.Cu")
		(net "GND")
	)
	(via
		(at 141.049502 -136.410446)
		(size 0.508)
		(drill 0.254)
		(layers "F.Cu" "B.Cu")
		(net "GND")
	)
	(via
		(at 75.762866 -84.31784)
		(size 0.508)
		(drill 0.254)
		(layers "F.Cu" "B.Cu")
		(net "GND")
	)
	(via
		(at 179.07 -140.5255)
		(size 0.508)
		(drill 0.254)
		(layers "F.Cu" "B.Cu")
		(net "GND")
	)
	(via
		(at 243.338604 -84.812886)
		(size 0.508)
		(drill 0.254)
		(layers "F.Cu" "B.Cu")
		(net "GND")
	)
	(via
		(at 414.050734 -165.596824)
		(size 0.5588)
		(drill 0.3048)
		(layers "F.Cu" "B.Cu")
		(net "GND")
	)
	(via
		(at 127.513334 -167.832024)
		(size 0.5588)
		(drill 0.3048)
		(layers "F.Cu" "B.Cu")
		(net "GND")
	)
	(via
		(at 407.090118 -25.96896)
		(size 0.4572)
		(drill 0.2032)
		(layers "F.Cu" "B.Cu")
		(net "GND")
	)
	(via
		(at 443.129162 -59.052206)
		(size 0.508)
		(drill 0.254)
		(layers "F.Cu" "B.Cu")
		(net "GND")
	)
	(via
		(at 422.29532 -150.6728)
		(size 0.508)
		(drill 0.254)
		(layers "F.Cu" "B.Cu")
		(net "GND")
	)
	(via
		(at 72.142096 -129.564892)
		(size 0.508)
		(drill 0.254)
		(layers "F.Cu" "B.Cu")
		(net "GND")
	)
	(via
		(at 398.13865 -96.747076)
		(size 0.508)
		(drill 0.254)
		(layers "F.Cu" "B.Cu")
		(net "GND")
	)
	(via
		(at 296.651934 9.084056)
		(size 0.5588)
		(drill 0.3048)
		(layers "F.Cu" "B.Cu")
		(net "GND")
	)
	(via
		(at 80.055212 -81.841086)
		(size 0.508)
		(drill 0.254)
		(layers "F.Cu" "B.Cu")
		(net "GND")
	)
	(via
		(at 99.800664 -91.25204)
		(size 0.508)
		(drill 0.254)
		(layers "F.Cu" "B.Cu")
		(net "GND")
	)
	(via
		(at 481.360734 -166.714424)
		(size 0.5588)
		(drill 0.3048)
		(layers "F.Cu" "B.Cu")
		(net "GND")
	)
	(via
		(at 366.285018 -8.84682)
		(size 0.508)
		(drill 0.254)
		(layers "F.Cu" "B.Cu")
		(net "GND")
	)
	(via
		(at 347.676724 -162.243262)
		(size 0.5588)
		(drill 0.3048)
		(layers "F.Cu" "B.Cu")
		(net "GND")
	)
	(via
		(at 42.651934 14.926056)
		(size 0.5588)
		(drill 0.3048)
		(layers "F.Cu" "B.Cu")
		(net "GND")
	)
	(via
		(at 115.460526 -3.737356)
		(size 0.508)
		(drill 0.254)
		(layers "F.Cu" "B.Cu")
		(net "GND")
	)
	(via
		(at 448.336924 -162.243262)
		(size 0.5588)
		(drill 0.3048)
		(layers "F.Cu" "B.Cu")
		(net "GND")
	)
	(via
		(at 371.259862 -147.513548)
		(size 0.508)
		(drill 0.254)
		(layers "F.Cu" "B.Cu")
		(net "GND")
	)
	(via
		(at 277.774654 -102.958138)
		(size 0.508)
		(drill 0.254)
		(layers "F.Cu" "B.Cu")
		(net "GND")
	)
	(via
		(at 40.699182 -77.128878)
		(size 0.5588)
		(drill 0.3048)
		(layers "F.Cu" "B.Cu")
		(net "GND")
	)
	(via
		(at 483.900734 -167.832024)
		(size 0.5588)
		(drill 0.3048)
		(layers "F.Cu" "B.Cu")
		(net "GND")
	)
	(via
		(at 84.347812 -79.36484)
		(size 0.508)
		(drill 0.254)
		(layers "F.Cu" "B.Cu")
		(net "GND")
	)
	(via
		(at 394.9192 -73.8124)
		(size 0.508)
		(drill 0.254)
		(layers "F.Cu" "B.Cu")
		(net "GND")
	)
	(via
		(at 17.427194 -0.294132)
		(size 0.508)
		(drill 0.254)
		(layers "F.Cu" "B.Cu")
		(net "GND")
	)
	(via
		(at 3.43662 -24.08936)
		(size 0.508)
		(drill 0.254)
		(layers "F.Cu" "B.Cu")
		(net "GND")
	)
	(via
		(at 73.187306 -60.047886)
		(size 0.508)
		(drill 0.254)
		(layers "F.Cu" "B.Cu")
		(net "GND")
	)
	(via
		(at 158.0388 -28.4988)
		(size 0.508)
		(drill 0.254)
		(layers "F.Cu" "B.Cu")
		(net "GND")
	)
	(via
		(at 493.501934 10.354056)
		(size 0.5588)
		(drill 0.3048)
		(layers "F.Cu" "B.Cu")
		(net "GND")
	)
	(via
		(at 444.599822 -113.801398)
		(size 0.508)
		(drill 0.254)
		(layers "F.Cu" "B.Cu")
		(net "GND")
	)
	(via
		(at 385.26085 -122.962924)
		(size 0.508)
		(drill 0.254)
		(layers "F.Cu" "B.Cu")
		(net "GND")
	)
	(via
		(at 131.699508 -148.771356)
		(size 0.508)
		(drill 0.254)
		(layers "F.Cu" "B.Cu")
		(net "GND")
	)
	(via
		(at 232.101898 -63.51524)
		(size 0.508)
		(drill 0.254)
		(layers "F.Cu" "B.Cu")
		(net "GND")
	)
	(via
		(at 360.7308 -132.207)
		(size 0.508)
		(drill 0.254)
		(layers "F.Cu" "B.Cu")
		(net "GND")
	)
	(via
		(at 221.721934 9.084056)
		(size 0.5588)
		(drill 0.3048)
		(layers "F.Cu" "B.Cu")
		(net "GND")
	)
	(via
		(at 285.649924 -129.568956)
		(size 0.508)
		(drill 0.254)
		(layers "F.Cu" "B.Cu")
		(net "GND")
	)
	(via
		(at 81.772252 -69.953886)
		(size 0.508)
		(drill 0.254)
		(layers "F.Cu" "B.Cu")
		(net "GND")
	)
	(via
		(at 481.360734 -167.832024)
		(size 0.5588)
		(drill 0.3048)
		(layers "F.Cu" "B.Cu")
		(net "GND")
	)
	(via
		(at 368.261138 -51.389788)
		(size 0.508)
		(drill 0.254)
		(layers "F.Cu" "B.Cu")
		(net "GND")
	)
	(via
		(at 192.511934 9.084056)
		(size 0.5588)
		(drill 0.3048)
		(layers "F.Cu" "B.Cu")
		(net "GND")
	)
	(via
		(at 42.411396 -21.517356)
		(size 0.508)
		(drill 0.254)
		(layers "F.Cu" "B.Cu")
		(net "GND")
	)
	(via
		(at 136.74217 -11.912092)
		(size 0.508)
		(drill 0.254)
		(layers "F.Cu" "B.Cu")
		(net "GND")
	)
	(via
		(at 75.601068 -27.3558)
		(size 0.508)
		(drill 0.254)
		(layers "F.Cu" "B.Cu")
		(net "GND")
	)
	(via
		(at 329.798934 -167.832024)
		(size 0.5588)
		(drill 0.3048)
		(layers "F.Cu" "B.Cu")
		(net "GND")
	)
	(via
		(at 324.591934 14.926056)
		(size 0.5588)
		(drill 0.3048)
		(layers "F.Cu" "B.Cu")
		(net "GND")
	)
	(via
		(at 234.753658 -62.029086)
		(size 0.508)
		(drill 0.254)
		(layers "F.Cu" "B.Cu")
		(net "GND")
	)
	(via
		(at 74.045826 -84.31784)
		(size 0.508)
		(drill 0.254)
		(layers "F.Cu" "B.Cu")
		(net "GND")
	)
	(via
		(at 2.276856 10.256266)
		(size 0.5588)
		(drill 0.3048)
		(layers "F.Cu" "B.Cu")
		(net "GND")
	)
	(via
		(at 279.4508 -69.4182)
		(size 0.508)
		(drill 0.254)
		(layers "F.Cu" "B.Cu")
		(net "GND")
	)
	(via
		(at 278.322024 -74.381614)
		(size 0.5588)
		(drill 0.3048)
		(layers "F.Cu" "B.Cu")
		(net "GND")
	)
	(via
		(at 199.9234 -77.1906)
		(size 0.5588)
		(drill 0.3048)
		(layers "F.Cu" "B.Cu")
		(net "GND")
	)
	(via
		(at 68.799456 -26.488136)
		(size 0.508)
		(drill 0.254)
		(layers "F.Cu" "B.Cu")
		(net "GND")
	)
	(via
		(at 435.640734 -165.596824)
		(size 0.5588)
		(drill 0.3048)
		(layers "F.Cu" "B.Cu")
		(net "GND")
	)
	(via
		(at 65.399412 -2.314956)
		(size 0.508)
		(drill 0.254)
		(layers "F.Cu" "B.Cu")
		(net "GND")
	)
	(via
		(at 270.56588 -82.340196)
		(size 0.5588)
		(drill 0.3048)
		(layers "F.Cu" "B.Cu")
		(net "GND")
	)
	(via
		(at 310.799734 -167.832024)
		(size 0.5588)
		(drill 0.3048)
		(layers "F.Cu" "B.Cu")
		(net "GND")
	)
	(via
		(at 271.679924 -162.243262)
		(size 0.5588)
		(drill 0.3048)
		(layers "F.Cu" "B.Cu")
		(net "GND")
	)
	(via
		(at 201.271124 -162.243262)
		(size 0.5588)
		(drill 0.3048)
		(layers "F.Cu" "B.Cu")
		(net "GND")
	)
	(via
		(at 34.736024 -23.495)
		(size 0.508)
		(drill 0.254)
		(layers "F.Cu" "B.Cu")
		(net "GND")
	)
	(via
		(at 285.094934 -167.832024)
		(size 0.5588)
		(drill 0.3048)
		(layers "F.Cu" "B.Cu")
		(net "GND")
	)
	(via
		(at 353.801934 9.084056)
		(size 0.5588)
		(drill 0.3048)
		(layers "F.Cu" "B.Cu")
		(net "GND")
	)
	(via
		(at 303.529746 -85.127338)
		(size 0.508)
		(drill 0.254)
		(layers "F.Cu" "B.Cu")
		(net "GND")
	)
	(via
		(at 88.640412 -56.085486)
		(size 0.508)
		(drill 0.254)
		(layers "F.Cu" "B.Cu")
		(net "GND")
	)
	(via
		(at 382.550924 -162.243262)
		(size 0.5588)
		(drill 0.3048)
		(layers "F.Cu" "B.Cu")
		(net "GND")
	)
	(via
		(at 240.599722 -131.016756)
		(size 0.508)
		(drill 0.254)
		(layers "F.Cu" "B.Cu")
		(net "GND")
	)
	(via
		(at 29.715968 -150.0378)
		(size 0.508)
		(drill 0.254)
		(layers "F.Cu" "B.Cu")
		(net "GND")
	)
	(via
		(at 135.953754 -76.706984)
		(size 0.508)
		(drill 0.254)
		(layers "F.Cu" "B.Cu")
		(net "GND")
	)
	(via
		(at -3.81 -62.8396)
		(size 0.508)
		(drill 0.254)
		(layers "F.Cu" "B.Cu")
		(net "GND")
	)
	(via
		(at 313.699906 -2.314956)
		(size 0.508)
		(drill 0.254)
		(layers "F.Cu" "B.Cu")
		(net "GND")
	)
	(via
		(at 377.544838 -69.495162)
		(size 0.4572)
		(drill 0.2032)
		(layers "F.Cu" "B.Cu")
		(net "GND")
	)
	(via
		(at 150.399496 -136.410446)
		(size 0.508)
		(drill 0.254)
		(layers "F.Cu" "B.Cu")
		(net "GND")
	)
	(via
		(at 392.19505 -96.747076)
		(size 0.508)
		(drill 0.254)
		(layers "F.Cu" "B.Cu")
		(net "GND")
	)
	(via
		(at 422.11752 -148.3106)
		(size 0.508)
		(drill 0.254)
		(layers "F.Cu" "B.Cu")
		(net "GND")
	)
	(via
		(at 70.591934 14.926056)
		(size 0.5588)
		(drill 0.3048)
		(layers "F.Cu" "B.Cu")
		(net "GND")
	)
	(via
		(at 242.480338 -78.37424)
		(size 0.508)
		(drill 0.254)
		(layers "F.Cu" "B.Cu")
		(net "GND")
	)
	(via
		(at 170.053 -123.0884)
		(size 0.508)
		(drill 0.254)
		(layers "F.Cu" "B.Cu")
		(net "GND")
	)
	(via
		(at 195.904612 -78.211172)
		(size 0.508)
		(drill 0.254)
		(layers "F.Cu" "B.Cu")
		(net "GND")
	)
	(via
		(at 399.521934 14.926056)
		(size 0.5588)
		(drill 0.3048)
		(layers "F.Cu" "B.Cu")
		(net "GND")
	)
	(via
		(at 66.045334 -167.832024)
		(size 0.5588)
		(drill 0.3048)
		(layers "F.Cu" "B.Cu")
		(net "GND")
	)
	(via
		(at 459.869032 -131.0386)
		(size 0.508)
		(drill 0.254)
		(layers "F.Cu" "B.Cu")
		(net "GND")
	)
	(via
		(at 5.466334 9.084056)
		(size 0.5588)
		(drill 0.3048)
		(layers "F.Cu" "B.Cu")
		(net "GND")
	)
	(via
		(at 413.890206 -36.534598)
		(size 0.4572)
		(drill 0.2032)
		(layers "F.Cu" "B.Cu")
		(net "GND")
	)
	(via
		(at 434.1876 -130.302)
		(size 0.508)
		(drill 0.254)
		(layers "F.Cu" "B.Cu")
		(net "GND")
	)
	(via
		(at 186.073796 -94.859602)
		(size 0.508)
		(drill 0.254)
		(layers "F.Cu" "B.Cu")
		(net "GND")
	)
	(via
		(at 279.207214 -54.913784)
		(size 0.508)
		(drill 0.254)
		(layers "F.Cu" "B.Cu")
		(net "GND")
	)
	(via
		(at 245.914164 -60.54344)
		(size 0.508)
		(drill 0.254)
		(layers "F.Cu" "B.Cu")
		(net "GND")
	)
	(via
		(at 47.549308 -22.965156)
		(size 0.508)
		(drill 0.254)
		(layers "F.Cu" "B.Cu")
		(net "GND")
	)
	(via
		(at 93.495876 -70.841616)
		(size 0.5588)
		(drill 0.3048)
		(layers "F.Cu" "B.Cu")
		(net "GND")
	)
	(via
		(at 324.591934 9.084056)
		(size 0.5588)
		(drill 0.3048)
		(layers "F.Cu" "B.Cu")
		(net "GND")
	)
	(via
		(at 115.349782 -94.538038)
		(size 0.508)
		(drill 0.254)
		(layers "F.Cu" "B.Cu")
		(net "GND")
	)
	(via
		(at 64.094106 -155.5369)
		(size 0.508)
		(drill 0.254)
		(layers "F.Cu" "B.Cu")
		(net "GND")
	)
	(via
		(at 241.44986 -9.156446)
		(size 0.508)
		(drill 0.254)
		(layers "F.Cu" "B.Cu")
		(net "GND")
	)
	(via
		(at 401.9169 -95.140018)
		(size 0.508)
		(drill 0.254)
		(layers "F.Cu" "B.Cu")
		(net "GND")
	)
	(via
		(at 437.690006 -40.5257)
		(size 0.508)
		(drill 0.254)
		(layers "F.Cu" "B.Cu")
		(net "GND")
	)
	(via
		(at 47.549308 -131.016756)
		(size 0.508)
		(drill 0.254)
		(layers "F.Cu" "B.Cu")
		(net "GND")
	)
	(via
		(at 81.691734 -167.832024)
		(size 0.5588)
		(drill 0.3048)
		(layers "F.Cu" "B.Cu")
		(net "GND")
	)
	(via
		(at 282.641294 -61.847984)
		(size 0.508)
		(drill 0.254)
		(layers "F.Cu" "B.Cu")
		(net "GND")
	)
	(via
		(at 387.73735 -99.322636)
		(size 0.508)
		(drill 0.254)
		(layers "F.Cu" "B.Cu")
		(net "GND")
	)
	(via
		(at 431.271934 9.084056)
		(size 0.5588)
		(drill 0.3048)
		(layers "F.Cu" "B.Cu")
		(net "GND")
	)
	(via
		(at 196.955918 -110.692946)
		(size 0.508)
		(drill 0.254)
		(layers "F.Cu" "B.Cu")
		(net "GND")
	)
	(via
		(at 131.661408 -58.381138)
		(size 0.508)
		(drill 0.254)
		(layers "F.Cu" "B.Cu")
		(net "GND")
	)
	(via
		(at 307.749956 -129.568956)
		(size 0.508)
		(drill 0.254)
		(layers "F.Cu" "B.Cu")
		(net "GND")
	)
	(via
		(at 273.482308 -93.547184)
		(size 0.508)
		(drill 0.254)
		(layers "F.Cu" "B.Cu")
		(net "GND")
	)
	(via
		(at 322.077588 -13.828522)
		(size 0.508)
		(drill 0.254)
		(layers "F.Cu" "B.Cu")
		(net "GND")
	)
	(via
		(at 264.744708 -70.841616)
		(size 0.5588)
		(drill 0.3048)
		(layers "F.Cu" "B.Cu")
		(net "GND")
	)
	(via
		(at 203.835 -76.5048)
		(size 0.5588)
		(drill 0.3048)
		(layers "F.Cu" "B.Cu")
		(net "GND")
	)
	(via
		(at 210.391248 -16.696944)
		(size 0.508)
		(drill 0.254)
		(layers "F.Cu" "B.Cu")
		(net "GND")
	)
	(via
		(at 90.626692 -149.444964)
		(size 0.508)
		(drill 0.254)
		(layers "F.Cu" "B.Cu")
		(net "GND")
	)
	(via
		(at 231.249728 -131.016756)
		(size 0.508)
		(drill 0.254)
		(layers "F.Cu" "B.Cu")
		(net "GND")
	)
	(via
		(at 292.36924 -65.810384)
		(size 0.508)
		(drill 0.254)
		(layers "F.Cu" "B.Cu")
		(net "GND")
	)
	(via
		(at 475.010734 -167.832024)
		(size 0.5588)
		(drill 0.3048)
		(layers "F.Cu" "B.Cu")
		(net "GND")
	)
	(via
		(at 138.529314 -78.193138)
		(size 0.508)
		(drill 0.254)
		(layers "F.Cu" "B.Cu")
		(net "GND")
	)
	(via
		(at 243.743734 -167.832024)
		(size 0.5588)
		(drill 0.3048)
		(layers "F.Cu" "B.Cu")
		(net "GND")
	)
	(via
		(at 305.541934 9.084056)
		(size 0.5588)
		(drill 0.3048)
		(layers "F.Cu" "B.Cu")
		(net "GND")
	)
	(via
		(at 262.119618 -75.148186)
		(size 0.5588)
		(drill 0.3048)
		(layers "F.Cu" "B.Cu")
		(net "GND")
	)
	(via
		(at 277.774654 -101.967538)
		(size 0.508)
		(drill 0.254)
		(layers "F.Cu" "B.Cu")
		(net "GND")
	)
	(via
		(at 490.250734 -165.596824)
		(size 0.5588)
		(drill 0.3048)
		(layers "F.Cu" "B.Cu")
		(net "GND")
	)
	(via
		(at 416.290252 -30.134814)
		(size 0.4572)
		(drill 0.2032)
		(layers "F.Cu" "B.Cu")
		(net "GND")
	)
	(via
		(at 233.799888 0.457454)
		(size 0.508)
		(drill 0.254)
		(layers "F.Cu" "B.Cu")
		(net "GND")
	)
	(via
		(at 225.531934 14.926056)
		(size 0.5588)
		(drill 0.3048)
		(layers "F.Cu" "B.Cu")
		(net "GND")
	)
	(via
		(at 280.065734 -62.343538)
		(size 0.508)
		(drill 0.254)
		(layers "F.Cu" "B.Cu")
		(net "GND")
	)
	(via
		(at 275.199348 -95.528384)
		(size 0.508)
		(drill 0.254)
		(layers "F.Cu" "B.Cu")
		(net "GND")
	)
	(via
		(at 4.009898 -140.1318)
		(size 0.508)
		(drill 0.254)
		(layers "F.Cu" "B.Cu")
		(net "GND")
	)
	(via
		(at 459.886812 -14.443964)
		(size 0.5588)
		(drill 0.3048)
		(layers "F.Cu" "B.Cu")
		(net "GND")
	)
	(via
		(at 279.506934 -167.832024)
		(size 0.5588)
		(drill 0.3048)
		(layers "F.Cu" "B.Cu")
		(net "GND")
	)
	(via
		(at 302.972724 -162.243262)
		(size 0.5588)
		(drill 0.3048)
		(layers "F.Cu" "B.Cu")
		(net "GND")
	)
	(via
		(at 227.792534 -139.166092)
		(size 0.508)
		(drill 0.254)
		(layers "F.Cu" "B.Cu")
		(net "GND")
	)
	(via
		(at 206.243682 -61.529722)
		(size 0.5588)
		(drill 0.3048)
		(layers "F.Cu" "B.Cu")
		(net "GND")
	)
	(via
		(at 13.335 -8.8138)
		(size 0.508)
		(drill 0.254)
		(layers "F.Cu" "B.Cu")
		(net "GND")
	)
	(via
		(at 27.242516 -32.522414)
		(size 0.508)
		(drill 0.254)
		(layers "F.Cu" "B.Cu")
		(net "GND")
	)
	(via
		(at 237.149132 -153.6065)
		(size 0.508)
		(drill 0.254)
		(layers "F.Cu" "B.Cu")
		(net "GND")
	)
	(via
		(at 466.831934 9.084056)
		(size 0.5588)
		(drill 0.3048)
		(layers "F.Cu" "B.Cu")
		(net "GND")
	)
	(via
		(at 31.908496 -89.314782)
		(size 0.508)
		(drill 0.254)
		(layers "F.Cu" "B.Cu")
		(net "GND")
	)
	(via
		(at 279.491694 -93.052138)
		(size 0.508)
		(drill 0.254)
		(layers "F.Cu" "B.Cu")
		(net "GND")
	)
	(via
		(at 1.006856 13.609066)
		(size 0.5588)
		(drill 0.3048)
		(layers "F.Cu" "B.Cu")
		(net "GND")
	)
	(via
		(at 176.6316 -83.312)
		(size 0.508)
		(drill 0.254)
		(layers "F.Cu" "B.Cu")
		(net "GND")
	)
	(via
		(at 12.3698 -27.8384)
		(size 0.508)
		(drill 0.254)
		(layers "F.Cu" "B.Cu")
		(net "GND")
	)
	(via
		(at 138.529314 -67.296538)
		(size 0.508)
		(drill 0.254)
		(layers "F.Cu" "B.Cu")
		(net "GND")
	)
	(via
		(at 48.777398 -76.1365)
		(size 0.508)
		(drill 0.254)
		(layers "F.Cu" "B.Cu")
		(net "GND")
	)
	(via
		(at 26.769568 -145.9992)
		(size 0.508)
		(drill 0.254)
		(layers "F.Cu" "B.Cu")
		(net "GND")
	)
	(via
		(at 76.621386 -61.038486)
		(size 0.508)
		(drill 0.254)
		(layers "F.Cu" "B.Cu")
		(net "GND")
	)
	(via
		(at 176.806352 -75.455526)
		(size 0.508)
		(drill 0.254)
		(layers "F.Cu" "B.Cu")
		(net "GND")
	)
	(via
		(at 142.898114 -63.829184)
		(size 0.508)
		(drill 0.254)
		(layers "F.Cu" "B.Cu")
		(net "GND")
	)
	(via
		(at 282.925774 -101.967538)
		(size 0.508)
		(drill 0.254)
		(layers "F.Cu" "B.Cu")
		(net "GND")
	)
	(via
		(at 51.76139 -148.771356)
		(size 0.508)
		(drill 0.254)
		(layers "F.Cu" "B.Cu")
		(net "GND")
	)
	(via
		(at 141.049502 0.444754)
		(size 0.508)
		(drill 0.254)
		(layers "F.Cu" "B.Cu")
		(net "GND")
	)
	(via
		(at 230.399844 -129.568956)
		(size 0.508)
		(drill 0.254)
		(layers "F.Cu" "B.Cu")
		(net "GND")
	)
	(via
		(at 352.442272 -131.290568)
		(size 0.508)
		(drill 0.254)
		(layers "F.Cu" "B.Cu")
		(net "GND")
	)
	(via
		(at 146.092164 -2.310892)
		(size 0.508)
		(drill 0.254)
		(layers "F.Cu" "B.Cu")
		(net "GND")
	)
	(via
		(at 176.53 -17.018)
		(size 0.508)
		(drill 0.254)
		(layers "F.Cu" "B.Cu")
		(net "GND")
	)
	(via
		(at 421.386 -21.717)
		(size 0.508)
		(drill 0.254)
		(layers "F.Cu" "B.Cu")
		(net "GND")
	)
	(via
		(at 5.04952 -23.53818)
		(size 0.508)
		(drill 0.254)
		(layers "F.Cu" "B.Cu")
		(net "GND")
	)
	(via
		(at 82.630772 -86.29904)
		(size 0.508)
		(drill 0.254)
		(layers "F.Cu" "B.Cu")
		(net "GND")
	)
	(via
		(at 207.4672 -59.5122)
		(size 0.5588)
		(drill 0.3048)
		(layers "F.Cu" "B.Cu")
		(net "GND")
	)
	(via
		(at 188.1251 -41.8592)
		(size 0.508)
		(drill 0.254)
		(layers "F.Cu" "B.Cu")
		(net "GND")
	)
	(via
		(at 230.399844 -26.488136)
		(size 0.508)
		(drill 0.254)
		(layers "F.Cu" "B.Cu")
		(net "GND")
	)
	(via
		(at 132.549392 -7.607046)
		(size 0.508)
		(drill 0.254)
		(layers "F.Cu" "B.Cu")
		(net "GND")
	)
	(via
		(at 447.070734 -166.714424)
		(size 0.5588)
		(drill 0.3048)
		(layers "F.Cu" "B.Cu")
		(net "GND")
	)
	(via
		(at 392.19505 -98.464116)
		(size 0.508)
		(drill 0.254)
		(layers "F.Cu" "B.Cu")
		(net "GND")
	)
	(via
		(at 249.9106 -12.954)
		(size 0.508)
		(drill 0.254)
		(layers "F.Cu" "B.Cu")
		(net "GND")
	)
	(via
		(at 231.450134 -167.832024)
		(size 0.5588)
		(drill 0.3048)
		(layers "F.Cu" "B.Cu")
		(net "GND")
	)
	(via
		(at 236.470698 -82.83194)
		(size 0.508)
		(drill 0.254)
		(layers "F.Cu" "B.Cu")
		(net "GND")
	)
	(via
		(at 491.520734 -164.479224)
		(size 0.5588)
		(drill 0.3048)
		(layers "F.Cu" "B.Cu")
		(net "GND")
	)
	(via
		(at 62.798706 -7.1501)
		(size 0.508)
		(drill 0.254)
		(layers "F.Cu" "B.Cu")
		(net "GND")
	)
	(via
		(at 150.399496 -9.156446)
		(size 0.508)
		(drill 0.254)
		(layers "F.Cu" "B.Cu")
		(net "GND")
	)
	(via
		(at 452.861934 9.084056)
		(size 0.5588)
		(drill 0.3048)
		(layers "F.Cu" "B.Cu")
		(net "GND")
	)
	(via
		(at 281.782774 -61.352938)
		(size 0.508)
		(drill 0.254)
		(layers "F.Cu" "B.Cu")
		(net "GND")
	)
	(via
		(at 53.442108 -129.564892)
		(size 0.508)
		(drill 0.254)
		(layers "F.Cu" "B.Cu")
		(net "GND")
	)
	(via
		(at 244.197124 -53.60924)
		(size 0.508)
		(drill 0.254)
		(layers "F.Cu" "B.Cu")
		(net "GND")
	)
	(via
		(at 367.885218 -3.437382)
		(size 0.508)
		(drill 0.254)
		(layers "F.Cu" "B.Cu")
		(net "GND")
	)
	(via
		(at 237.329218 -80.35544)
		(size 0.508)
		(drill 0.254)
		(layers "F.Cu" "B.Cu")
		(net "GND")
	)
	(via
		(at 48.399446 -136.410446)
		(size 0.508)
		(drill 0.254)
		(layers "F.Cu" "B.Cu")
		(net "GND")
	)
	(via
		(at 139.34948 -2.314956)
		(size 0.508)
		(drill 0.254)
		(layers "F.Cu" "B.Cu")
		(net "GND")
	)
	(via
		(at 149.865334 -167.832024)
		(size 0.5588)
		(drill 0.3048)
		(layers "F.Cu" "B.Cu")
		(net "GND")
	)
	(via
		(at -4.555744 12.542266)
		(size 0.5588)
		(drill 0.3048)
		(layers "F.Cu" "B.Cu")
		(net "GND")
	)
	(via
		(at 165.5445 -148.3741)
		(size 0.508)
		(drill 0.254)
		(layers "F.Cu" "B.Cu")
		(net "GND")
	)
	(via
		(at 86.064852 -89.27084)
		(size 0.508)
		(drill 0.254)
		(layers "F.Cu" "B.Cu")
		(net "GND")
	)
	(via
		(at 111.231934 9.084056)
		(size 0.5588)
		(drill 0.3048)
		(layers "F.Cu" "B.Cu")
		(net "GND")
	)
	(via
		(at 210.387946 -23.549356)
		(size 0.508)
		(drill 0.254)
		(layers "F.Cu" "B.Cu")
		(net "GND")
	)
	(via
		(at 457.551536 -63.626492)
		(size 0.508)
		(drill 0.254)
		(layers "F.Cu" "B.Cu")
		(net "GND")
	)
	(via
		(at 292.392608 -139.166092)
		(size 0.508)
		(drill 0.254)
		(layers "F.Cu" "B.Cu")
		(net "GND")
	)
	(via
		(at 296.66184 -94.042738)
		(size 0.508)
		(drill 0.254)
		(layers "F.Cu" "B.Cu")
		(net "GND")
	)
	(via
		(at 53.442108 -145.998946)
		(size 0.508)
		(drill 0.254)
		(layers "F.Cu" "B.Cu")
		(net "GND")
	)
	(via
		(at 61.821568 -154.1018)
		(size 0.508)
		(drill 0.254)
		(layers "F.Cu" "B.Cu")
		(net "GND")
	)
	(via
		(at 136.812274 -57.390538)
		(size 0.508)
		(drill 0.254)
		(layers "F.Cu" "B.Cu")
		(net "GND")
	)
	(via
		(at 296.66184 -80.174338)
		(size 0.508)
		(drill 0.254)
		(layers "F.Cu" "B.Cu")
		(net "GND")
	)
	(via
		(at 287.21812 -100.481384)
		(size 0.508)
		(drill 0.254)
		(layers "F.Cu" "B.Cu")
		(net "GND")
	)
	(via
		(at 310.122062 -13.363956)
		(size 0.508)
		(drill 0.254)
		(layers "F.Cu" "B.Cu")
		(net "GND")
	)
	(via
		(at 42.019982 -68.256658)
		(size 0.5588)
		(drill 0.3048)
		(layers "F.Cu" "B.Cu")
		(net "GND")
	)
	(via
		(at 233.036618 -86.794086)
		(size 0.508)
		(drill 0.254)
		(layers "F.Cu" "B.Cu")
		(net "GND")
	)
	(via
		(at 152.099518 -16.687546)
		(size 0.508)
		(drill 0.254)
		(layers "F.Cu" "B.Cu")
		(net "GND")
	)
	(via
		(at 238.444532 -145.9357)
		(size 0.508)
		(drill 0.254)
		(layers "F.Cu" "B.Cu")
		(net "GND")
	)
	(via
		(at 110.772702 -63.829184)
		(size 0.508)
		(drill 0.254)
		(layers "F.Cu" "B.Cu")
		(net "GND")
	)
	(via
		(at 145.12163 -144.5006)
		(size 0.508)
		(drill 0.254)
		(layers "F.Cu" "B.Cu")
		(net "GND")
	)
	(via
		(at 118.783862 -88.594184)
		(size 0.508)
		(drill 0.254)
		(layers "F.Cu" "B.Cu")
		(net "GND")
	)
	(via
		(at 420.396924 -162.243262)
		(size 0.5588)
		(drill 0.3048)
		(layers "F.Cu" "B.Cu")
		(net "GND")
	)
	(via
		(at 71.470266 -100.662486)
		(size 0.508)
		(drill 0.254)
		(layers "F.Cu" "B.Cu")
		(net "GND")
	)
	(via
		(at 62.782958 -124.590556)
		(size 0.508)
		(drill 0.254)
		(layers "F.Cu" "B.Cu")
		(net "GND")
	)
	(via
		(at 16.227552 -35.576256)
		(size 0.508)
		(drill 0.254)
		(layers "F.Cu" "B.Cu")
		(net "GND")
	)
	(via
		(at 187.104274 -9.174988)
		(size 0.508)
		(drill 0.254)
		(layers "F.Cu" "B.Cu")
		(net "GND")
	)
	(via
		(at 31.39948 -148.771356)
		(size 0.508)
		(drill 0.254)
		(layers "F.Cu" "B.Cu")
		(net "GND")
	)
	(via
		(at 386.96138 -61.61532)
		(size 0.508)
		(drill 0.254)
		(layers "F.Cu" "B.Cu")
		(net "GND")
	)
	(via
		(at 218.436444 -4.2926)
		(size 0.508)
		(drill 0.254)
		(layers "F.Cu" "B.Cu")
		(net "GND")
	)
	(via
		(at 99.800664 -60.54344)
		(size 0.508)
		(drill 0.254)
		(layers "F.Cu" "B.Cu")
		(net "GND")
	)
	(via
		(at 253.640844 -53.113686)
		(size 0.508)
		(drill 0.254)
		(layers "F.Cu" "B.Cu")
		(net "GND")
	)
	(via
		(at 278.348694 -55.409338)
		(size 0.508)
		(drill 0.254)
		(layers "F.Cu" "B.Cu")
		(net "GND")
	)
	(via
		(at 376.886216 -129.521712)
		(size 0.508)
		(drill 0.254)
		(layers "F.Cu" "B.Cu")
		(net "GND")
	)
	(via
		(at 210.387946 -150.803356)
		(size 0.508)
		(drill 0.254)
		(layers "F.Cu" "B.Cu")
		(net "GND")
	)
	(via
		(at 64.090804 -153.552144)
		(size 0.508)
		(drill 0.254)
		(layers "F.Cu" "B.Cu")
		(net "GND")
	)
	(via
		(at 346.7354 -40.64)
		(size 0.508)
		(drill 0.254)
		(layers "F.Cu" "B.Cu")
		(net "GND")
	)
	(via
		(at 219.744544 -145.9357)
		(size 0.508)
		(drill 0.254)
		(layers "F.Cu" "B.Cu")
		(net "GND")
	)
	(via
		(at 116.782342 -54.418738)
		(size 0.508)
		(drill 0.254)
		(layers "F.Cu" "B.Cu")
		(net "GND")
	)
	(via
		(at 185.413396 -85.944202)
		(size 0.508)
		(drill 0.254)
		(layers "F.Cu" "B.Cu")
		(net "GND")
	)
	(via
		(at 477.901 -32.3342)
		(size 0.508)
		(drill 0.254)
		(layers "F.Cu" "B.Cu")
		(net "GND")
	)
	(via
		(at 129.944368 -55.409338)
		(size 0.508)
		(drill 0.254)
		(layers "F.Cu" "B.Cu")
		(net "GND")
	)
	(via
		(at 120.649492 -155.612846)
		(size 0.508)
		(drill 0.254)
		(layers "F.Cu" "B.Cu")
		(net "GND")
	)
	(via
		(at 149.549358 -22.965156)
		(size 0.508)
		(drill 0.254)
		(layers "F.Cu" "B.Cu")
		(net "GND")
	)
	(via
		(at 279.699974 0.457454)
		(size 0.508)
		(drill 0.254)
		(layers "F.Cu" "B.Cu")
		(net "GND")
	)
	(via
		(at 290.71189 -129.568956)
		(size 0.508)
		(drill 0.254)
		(layers "F.Cu" "B.Cu")
		(net "GND")
	)
	(via
		(at 407.517854 -54.229)
		(size 0.508)
		(drill 0.254)
		(layers "F.Cu" "B.Cu")
		(net "GND")
	)
	(via
		(at 293.688008 -13.948156)
		(size 0.508)
		(drill 0.254)
		(layers "F.Cu" "B.Cu")
		(net "GND")
	)
	(via
		(at 186.0804 -0.9144)
		(size 0.508)
		(drill 0.254)
		(layers "F.Cu" "B.Cu")
		(net "GND")
	)
	(via
		(at 348.4626 -7.2644)
		(size 0.508)
		(drill 0.254)
		(layers "F.Cu" "B.Cu")
		(net "GND")
	)
	(via
		(at 438.180734 -166.714424)
		(size 0.5588)
		(drill 0.3048)
		(layers "F.Cu" "B.Cu")
		(net "GND")
	)
	(via
		(at 200.3044 -77.7494)
		(size 0.5588)
		(drill 0.3048)
		(layers "F.Cu" "B.Cu")
		(net "GND")
	)
	(via
		(at 388.628382 -86.562946)
		(size 0.508)
		(drill 0.254)
		(layers "F.Cu" "B.Cu")
		(net "GND")
	)
	(via
		(at 426.191934 10.354056)
		(size 0.5588)
		(drill 0.3048)
		(layers "F.Cu" "B.Cu")
		(net "GND")
	)
	(via
		(at 398.63395 -116.953284)
		(size 0.508)
		(drill 0.254)
		(layers "F.Cu" "B.Cu")
		(net "GND")
	)
	(via
		(at 312.387996 -23.549356)
		(size 0.508)
		(drill 0.254)
		(layers "F.Cu" "B.Cu")
		(net "GND")
	)
	(via
		(at 356.341934 14.926056)
		(size 0.5588)
		(drill 0.3048)
		(layers "F.Cu" "B.Cu")
		(net "GND")
	)
	(via
		(at 130.802888 -73.735184)
		(size 0.508)
		(drill 0.254)
		(layers "F.Cu" "B.Cu")
		(net "GND")
	)
	(via
		(at 135.953754 -78.688438)
		(size 0.508)
		(drill 0.254)
		(layers "F.Cu" "B.Cu")
		(net "GND")
	)
	(via
		(at 282.07208 -130.991356)
		(size 0.508)
		(drill 0.254)
		(layers "F.Cu" "B.Cu")
		(net "GND")
	)
	(via
		(at 467.390734 -167.832024)
		(size 0.5588)
		(drill 0.3048)
		(layers "F.Cu" "B.Cu")
		(net "GND")
	)
	(via
		(at 346.7354 -36.83)
		(size 0.508)
		(drill 0.254)
		(layers "F.Cu" "B.Cu")
		(net "GND")
	)
	(via
		(at 56.049418 -11.916156)
		(size 0.508)
		(drill 0.254)
		(layers "F.Cu" "B.Cu")
		(net "GND")
	)
	(via
		(at 419.130734 -164.479224)
		(size 0.5588)
		(drill 0.3048)
		(layers "F.Cu" "B.Cu")
		(net "GND")
	)
	(via
		(at 346.370148 -123.605544)
		(size 0.508)
		(drill 0.254)
		(layers "F.Cu" "B.Cu")
		(net "GND")
	)
	(via
		(at 345.4908 -154.0002)
		(size 0.508)
		(drill 0.254)
		(layers "F.Cu" "B.Cu")
		(net "GND")
	)
	(via
		(at 181.7751 -138.4935)
		(size 0.508)
		(drill 0.254)
		(layers "F.Cu" "B.Cu")
		(net "GND")
	)
	(via
		(at 378.05614 -131.52374)
		(size 0.508)
		(drill 0.254)
		(layers "F.Cu" "B.Cu")
		(net "GND")
	)
	(via
		(at 278.561546 -103.576628)
		(size 0.508)
		(drill 0.254)
		(layers "F.Cu" "B.Cu")
		(net "GND")
	)
	(via
		(at 286.491934 9.084056)
		(size 0.5588)
		(drill 0.3048)
		(layers "F.Cu" "B.Cu")
		(net "GND")
	)
	(via
		(at 403.331934 9.084056)
		(size 0.5588)
		(drill 0.3048)
		(layers "F.Cu" "B.Cu")
		(net "GND")
	)
	(via
		(at 35.499802 -89.2556)
		(size 0.508)
		(drill 0.254)
		(layers "F.Cu" "B.Cu")
		(net "GND")
	)
	(via
		(at 459.75016 -58.954924)
		(size 0.508)
		(drill 0.254)
		(layers "F.Cu" "B.Cu")
		(net "GND")
	)
	(via
		(at 52.471574 1.9558)
		(size 0.508)
		(drill 0.254)
		(layers "F.Cu" "B.Cu")
		(net "GND")
	)
	(via
		(at 132.519674 -65.810384)
		(size 0.508)
		(drill 0.254)
		(layers "F.Cu" "B.Cu")
		(net "GND")
	)
	(via
		(at 152.949402 -153.542746)
		(size 0.508)
		(drill 0.254)
		(layers "F.Cu" "B.Cu")
		(net "GND")
	)
	(via
		(at 294.08628 -60.857384)
		(size 0.508)
		(drill 0.254)
		(layers "F.Cu" "B.Cu")
		(net "GND")
	)
	(via
		(at 355.630734 -167.857424)
		(size 0.5588)
		(drill 0.3048)
		(layers "F.Cu" "B.Cu")
		(net "GND")
	)
	(via
		(at 379.5268 -134.7724)
		(size 0.508)
		(drill 0.254)
		(layers "F.Cu" "B.Cu")
		(net "GND")
	)
	(via
		(at 177.805334 -167.832024)
		(size 0.5588)
		(drill 0.3048)
		(layers "F.Cu" "B.Cu")
		(net "GND")
	)
	(via
		(at 175.662082 -50.831496)
		(size 0.508)
		(drill 0.254)
		(layers "F.Cu" "B.Cu")
		(net "GND")
	)
	(via
		(at 171.423584 -30.249622)
		(size 0.508)
		(drill 0.254)
		(layers "F.Cu" "B.Cu")
		(net "GND")
	)
	(via
		(at 144.449546 -136.410446)
		(size 0.508)
		(drill 0.254)
		(layers "F.Cu" "B.Cu")
		(net "GND")
	)
	(via
		(at 246.619268 -135.4074)
		(size 0.508)
		(drill 0.254)
		(layers "F.Cu" "B.Cu")
		(net "GND")
	)
	(via
		(at 312.3692 -9.0805)
		(size 0.508)
		(drill 0.254)
		(layers "F.Cu" "B.Cu")
		(net "GND")
	)
	(via
		(at 67.942968 -96.700086)
		(size 0.508)
		(drill 0.254)
		(layers "F.Cu" "B.Cu")
		(net "GND")
	)
	(via
		(at 238.187738 -65.000886)
		(size 0.508)
		(drill 0.254)
		(layers "F.Cu" "B.Cu")
		(net "GND")
	)
	(via
		(at 202.5142 -76.5048)
		(size 0.5588)
		(drill 0.3048)
		(layers "F.Cu" "B.Cu")
		(net "GND")
	)
	(via
		(at 421.004492 -67.8434)
		(size 0.508)
		(drill 0.254)
		(layers "F.Cu" "B.Cu")
		(net "GND")
	)
	(via
		(at 57.74944 -2.314956)
		(size 0.508)
		(drill 0.254)
		(layers "F.Cu" "B.Cu")
		(net "GND")
	)
	(via
		(at 378.82195 -106.190796)
		(size 0.508)
		(drill 0.254)
		(layers "F.Cu" "B.Cu")
		(net "GND")
	)
	(via
		(at 78.229968 -3.3528)
		(size 0.508)
		(drill 0.254)
		(layers "F.Cu" "B.Cu")
		(net "GND")
	)
	(via
		(at 337.8454 -108.585)
		(size 0.508)
		(drill 0.254)
		(layers "F.Cu" "B.Cu")
		(net "GND")
	)
	(via
		(at 42.553382 -94.578678)
		(size 0.5588)
		(drill 0.3048)
		(layers "F.Cu" "B.Cu")
		(net "GND")
	)
	(via
		(at 31.20136 -101.810058)
		(size 0.5588)
		(drill 0.3048)
		(layers "F.Cu" "B.Cu")
		(net "GND")
	)
	(via
		(at 245.055644 -92.737686)
		(size 0.508)
		(drill 0.254)
		(layers "F.Cu" "B.Cu")
		(net "GND")
	)
	(via
		(at 125.651768 -91.565984)
		(size 0.508)
		(drill 0.254)
		(layers "F.Cu" "B.Cu")
		(net "GND")
	)
	(via
		(at 106.480356 -63.334138)
		(size 0.508)
		(drill 0.254)
		(layers "F.Cu" "B.Cu")
		(net "GND")
	)
	(via
		(at 247.631204 -53.60924)
		(size 0.508)
		(drill 0.254)
		(layers "F.Cu" "B.Cu")
		(net "GND")
	)
	(via
		(at 170.0022 -2.501138)
		(size 0.508)
		(drill 0.254)
		(layers "F.Cu" "B.Cu")
		(net "GND")
	)
	(via
		(at 228.071934 14.926056)
		(size 0.5588)
		(drill 0.3048)
		(layers "F.Cu" "B.Cu")
		(net "GND")
	)
	(via
		(at 124.801376 -17.208246)
		(size 0.508)
		(drill 0.254)
		(layers "F.Cu" "B.Cu")
		(net "GND")
	)
	(via
		(at 297.520106 -101.471984)
		(size 0.508)
		(drill 0.254)
		(layers "F.Cu" "B.Cu")
		(net "GND")
	)
	(via
		(at 111.915702 -96.518984)
		(size 0.508)
		(drill 0.254)
		(layers "F.Cu" "B.Cu")
		(net "GND")
	)
	(via
		(at 266.095734 -167.832024)
		(size 0.5588)
		(drill 0.3048)
		(layers "F.Cu" "B.Cu")
		(net "GND")
	)
	(via
		(at 284.3276 -2.3622)
		(size 0.508)
		(drill 0.254)
		(layers "F.Cu" "B.Cu")
		(net "GND")
	)
	(via
		(at 345.3003 0.001778)
		(size 0.508)
		(drill 0.254)
		(layers "F.Cu" "B.Cu")
		(net "GND")
	)
	(via
		(at 286.93364 -60.362338)
		(size 0.508)
		(drill 0.254)
		(layers "F.Cu" "B.Cu")
		(net "GND")
	)
	(via
		(at 247.631204 -96.20504)
		(size 0.508)
		(drill 0.254)
		(layers "F.Cu" "B.Cu")
		(net "GND")
	)
	(via
		(at 112.774222 -99.986338)
		(size 0.508)
		(drill 0.254)
		(layers "F.Cu" "B.Cu")
		(net "GND")
	)
	(via
		(at 180.040534 -167.832024)
		(size 0.5588)
		(drill 0.3048)
		(layers "F.Cu" "B.Cu")
		(net "GND")
	)
	(via
		(at 152.099518 -21.528278)
		(size 0.508)
		(drill 0.254)
		(layers "F.Cu" "B.Cu")
		(net "GND")
	)
	(via
		(at 391.69975 -102.756716)
		(size 0.508)
		(drill 0.254)
		(layers "F.Cu" "B.Cu")
		(net "GND")
	)
	(via
		(at 41.427654 -86.55431)
		(size 0.5588)
		(drill 0.3048)
		(layers "F.Cu" "B.Cu")
		(net "GND")
	)
	(via
		(at 80.913732 -79.36484)
		(size 0.508)
		(drill 0.254)
		(layers "F.Cu" "B.Cu")
		(net "GND")
	)
	(via
		(at 86.923372 -69.953886)
		(size 0.508)
		(drill 0.254)
		(layers "F.Cu" "B.Cu")
		(net "GND")
	)
	(via
		(at 75.762866 -89.27084)
		(size 0.508)
		(drill 0.254)
		(layers "F.Cu" "B.Cu")
		(net "GND")
	)
	(via
		(at 343.250266 -101.403658)
		(size 0.508)
		(drill 0.254)
		(layers "F.Cu" "B.Cu")
		(net "GND")
	)
	(via
		(at 37.34943 -146.011646)
		(size 0.508)
		(drill 0.254)
		(layers "F.Cu" "B.Cu")
		(net "GND")
	)
	(via
		(at 196.880734 -96.168464)
		(size 0.508)
		(drill 0.254)
		(layers "F.Cu" "B.Cu")
		(net "GND")
	)
	(via
		(at 436.372 -149.281642)
		(size 0.508)
		(drill 0.254)
		(layers "F.Cu" "B.Cu")
		(net "GND")
	)
	(via
		(at 282.07208 -140.592556)
		(size 0.508)
		(drill 0.254)
		(layers "F.Cu" "B.Cu")
		(net "GND")
	)
	(via
		(at 387.731 -128.6256)
		(size 0.508)
		(drill 0.254)
		(layers "F.Cu" "B.Cu")
		(net "GND")
	)
	(via
		(at 100.811076 -82.339942)
		(size 0.5588)
		(drill 0.3048)
		(layers "F.Cu" "B.Cu")
		(net "GND")
	)
	(via
		(at 387.2992 -152.089612)
		(size 0.508)
		(drill 0.254)
		(layers "F.Cu" "B.Cu")
		(net "GND")
	)
	(via
		(at 371.273578 -148.123148)
		(size 0.508)
		(drill 0.254)
		(layers "F.Cu" "B.Cu")
		(net "GND")
	)
	(via
		(at 293.69131 -26.682954)
		(size 0.508)
		(drill 0.254)
		(layers "F.Cu" "B.Cu")
		(net "GND")
	)
	(via
		(at 251.065284 -84.31784)
		(size 0.508)
		(drill 0.254)
		(layers "F.Cu" "B.Cu")
		(net "GND")
	)
	(via
		(at 232.9434 -96.700086)
		(size 0.508)
		(drill 0.254)
		(layers "F.Cu" "B.Cu")
		(net "GND")
	)
	(via
		(at 129.944368 -82.155284)
		(size 0.508)
		(drill 0.254)
		(layers "F.Cu" "B.Cu")
		(net "GND")
	)
	(via
		(at 122.349514 -2.314956)
		(size 0.508)
		(drill 0.254)
		(layers "F.Cu" "B.Cu")
		(net "GND")
	)
	(via
		(at 235.46181 -148.771356)
		(size 0.508)
		(drill 0.254)
		(layers "F.Cu" "B.Cu")
		(net "GND")
	)
	(via
		(at 405.422354 -96.872298)
		(size 0.508)
		(drill 0.254)
		(layers "F.Cu" "B.Cu")
		(net "GND")
	)
	(via
		(at 436.910734 -165.596824)
		(size 0.5588)
		(drill 0.3048)
		(layers "F.Cu" "B.Cu")
		(net "GND")
	)
	(via
		(at 100.049076 -82.339942)
		(size 0.5588)
		(drill 0.3048)
		(layers "F.Cu" "B.Cu")
		(net "GND")
	)
	(via
		(at 76.621386 -63.019686)
		(size 0.508)
		(drill 0.254)
		(layers "F.Cu" "B.Cu")
		(net "GND")
	)
	(via
		(at 449.7959 -27.813)
		(size 0.508)
		(drill 0.254)
		(layers "F.Cu" "B.Cu")
		(net "GND")
	)
	(via
		(at 104.468676 -75.159616)
		(size 0.5588)
		(drill 0.3048)
		(layers "F.Cu" "B.Cu")
		(net "GND")
	)
	(via
		(at 285.649924 -148.771356)
		(size 0.508)
		(drill 0.254)
		(layers "F.Cu" "B.Cu")
		(net "GND")
	)
	(via
		(at 294.9448 -85.127338)
		(size 0.508)
		(drill 0.254)
		(layers "F.Cu" "B.Cu")
		(net "GND")
	)
	(via
		(at 280.460958 -13.338556)
		(size 0.508)
		(drill 0.254)
		(layers "F.Cu" "B.Cu")
		(net "GND")
	)
	(via
		(at 212.831934 9.084056)
		(size 0.5588)
		(drill 0.3048)
		(layers "F.Cu" "B.Cu")
		(net "GND")
	)
	(via
		(at 412.776924 -162.243262)
		(size 0.5588)
		(drill 0.3048)
		(layers "F.Cu" "B.Cu")
		(net "GND")
	)
	(via
		(at 74.045826 -57.57164)
		(size 0.508)
		(drill 0.254)
		(layers "F.Cu" "B.Cu")
		(net "GND")
	)
	(via
		(at 437.0324 -17.8308)
		(size 0.508)
		(drill 0.254)
		(layers "F.Cu" "B.Cu")
		(net "GND")
	)
	(via
		(at 200.533 -83.312)
		(size 0.508)
		(drill 0.254)
		(layers "F.Cu" "B.Cu")
		(net "GND")
	)
	(via
		(at 275.773134 -53.923184)
		(size 0.508)
		(drill 0.254)
		(layers "F.Cu" "B.Cu")
		(net "GND")
	)
	(via
		(at 4.353306 -140.635482)
		(size 0.508)
		(drill 0.254)
		(layers "F.Cu" "B.Cu")
		(net "GND")
	)
	(via
		(at 65.511934 14.926056)
		(size 0.5588)
		(drill 0.3048)
		(layers "F.Cu" "B.Cu")
		(net "GND")
	)
	(via
		(at 440.161934 13.910056)
		(size 0.5588)
		(drill 0.3048)
		(layers "F.Cu" "B.Cu")
		(net "GND")
	)
	(via
		(at 237.329218 -84.31784)
		(size 0.508)
		(drill 0.254)
		(layers "F.Cu" "B.Cu")
		(net "GND")
	)
	(via
		(at 300.772068 -124.661676)
		(size 0.508)
		(drill 0.254)
		(layers "F.Cu" "B.Cu")
		(net "GND")
	)
	(via
		(at 400.080734 -167.832024)
		(size 0.5588)
		(drill 0.3048)
		(layers "F.Cu" "B.Cu")
		(net "GND")
	)
	(via
		(at 344.5002 -5.1054)
		(size 0.508)
		(drill 0.254)
		(layers "F.Cu" "B.Cu")
		(net "GND")
	)
	(via
		(at 125.711458 -21.517356)
		(size 0.508)
		(drill 0.254)
		(layers "F.Cu" "B.Cu")
		(net "GND")
	)
	(via
		(at 350.981518 -11.806936)
		(size 0.508)
		(drill 0.254)
		(layers "F.Cu" "B.Cu")
		(net "GND")
	)
	(via
		(at 118.048532 -134.4041)
		(size 0.508)
		(drill 0.254)
		(layers "F.Cu" "B.Cu")
		(net "GND")
	)
	(via
		(at 358.652826 -141.57452)
		(size 0.508)
		(drill 0.254)
		(layers "F.Cu" "B.Cu")
		(net "GND")
	)
	(via
		(at 128.227328 -88.099138)
		(size 0.508)
		(drill 0.254)
		(layers "F.Cu" "B.Cu")
		(net "GND")
	)
	(via
		(at 243.149882 0.468122)
		(size 0.508)
		(drill 0.254)
		(layers "F.Cu" "B.Cu")
		(net "GND")
	)
	(via
		(at 42.121582 -77.128878)
		(size 0.5588)
		(drill 0.3048)
		(layers "F.Cu" "B.Cu")
		(net "GND")
	)
	(via
		(at 331.174852 -43.160188)
		(size 0.508)
		(drill 0.254)
		(layers "F.Cu" "B.Cu")
		(net "GND")
	)
	(via
		(at 16.4338 -54.0512)
		(size 0.5588)
		(drill 0.3048)
		(layers "F.Cu" "B.Cu")
		(net "GND")
	)
	(via
		(at 238.44123 2.505456)
		(size 0.508)
		(drill 0.254)
		(layers "F.Cu" "B.Cu")
		(net "GND")
	)
	(via
		(at 464.521296 -141.646402)
		(size 0.508)
		(drill 0.254)
		(layers "F.Cu" "B.Cu")
		(net "GND")
	)
	(via
		(at 209.09915 -16.7513)
		(size 0.508)
		(drill 0.254)
		(layers "F.Cu" "B.Cu")
		(net "GND")
	)
	(via
		(at 463.021934 13.910056)
		(size 0.5588)
		(drill 0.3048)
		(layers "F.Cu" "B.Cu")
		(net "GND")
	)
	(via
		(at 79.481934 14.926056)
		(size 0.5588)
		(drill 0.3048)
		(layers "F.Cu" "B.Cu")
		(net "GND")
	)
	(via
		(at 0.365506 -136.673082)
		(size 0.508)
		(drill 0.254)
		(layers "F.Cu" "B.Cu")
		(net "GND")
	)
	(via
		(at 42.411396 -18.757646)
		(size 0.508)
		(drill 0.254)
		(layers "F.Cu" "B.Cu")
		(net "GND")
	)
	(via
		(at 215.0999 -18.744946)
		(size 0.508)
		(drill 0.254)
		(layers "F.Cu" "B.Cu")
		(net "GND")
	)
	(via
		(at 102.947724 -88.165686)
		(size 0.508)
		(drill 0.254)
		(layers "F.Cu" "B.Cu")
		(net "GND")
	)
	(via
		(at 239.749838 -136.410446)
		(size 0.508)
		(drill 0.254)
		(layers "F.Cu" "B.Cu")
		(net "GND")
	)
	(via
		(at 133.101334 -167.832024)
		(size 0.5588)
		(drill 0.3048)
		(layers "F.Cu" "B.Cu")
		(net "GND")
	)
	(via
		(at 128.227328 -97.014538)
		(size 0.508)
		(drill 0.254)
		(layers "F.Cu" "B.Cu")
		(net "GND")
	)
	(via
		(at 236.470698 -95.709486)
		(size 0.508)
		(drill 0.254)
		(layers "F.Cu" "B.Cu")
		(net "GND")
	)
	(via
		(at 80.055212 -71.935086)
		(size 0.508)
		(drill 0.254)
		(layers "F.Cu" "B.Cu")
		(net "GND")
	)
	(via
		(at 373.304054 -152.286716)
		(size 0.508)
		(drill 0.254)
		(layers "F.Cu" "B.Cu")
		(net "GND")
	)
	(via
		(at 484.613966 -21.537422)
		(size 0.508)
		(drill 0.254)
		(layers "F.Cu" "B.Cu")
		(net "GND")
	)
	(via
		(at 372.394734 -167.857424)
		(size 0.5588)
		(drill 0.3048)
		(layers "F.Cu" "B.Cu")
		(net "GND")
	)
	(via
		(at 111.915702 -99.490784)
		(size 0.508)
		(drill 0.254)
		(layers "F.Cu" "B.Cu")
		(net "GND")
	)
	(via
		(at 200.515728 -88.4174)
		(size 0.508)
		(drill 0.254)
		(layers "F.Cu" "B.Cu")
		(net "GND")
	)
	(via
		(at 12.396724 -162.243262)
		(size 0.5588)
		(drill 0.3048)
		(layers "F.Cu" "B.Cu")
		(net "GND")
	)
	(via
		(at 50.099468 -136.397746)
		(size 0.508)
		(drill 0.254)
		(layers "F.Cu" "B.Cu")
		(net "GND")
	)
	(via
		(at 362.336334 -167.857424)
		(size 0.5588)
		(drill 0.3048)
		(layers "F.Cu" "B.Cu")
		(net "GND")
	)
	(via
		(at 378.0409 -37.9603)
		(size 0.508)
		(drill 0.254)
		(layers "F.Cu" "B.Cu")
		(net "GND")
	)
	(via
		(at 72.328786 -59.55284)
		(size 0.508)
		(drill 0.254)
		(layers "F.Cu" "B.Cu")
		(net "GND")
	)
	(via
		(at 237.329218 -59.55284)
		(size 0.508)
		(drill 0.254)
		(layers "F.Cu" "B.Cu")
		(net "GND")
	)
	(via
		(at 1.224534 -165.596824)
		(size 0.5588)
		(drill 0.3048)
		(layers "F.Cu" "B.Cu")
		(net "GND")
	)
	(via
		(at 182.4482 -57.7596)
		(size 0.508)
		(drill 0.254)
		(layers "F.Cu" "B.Cu")
		(net "GND")
	)
	(via
		(at 3.4544 -128.0922)
		(size 0.508)
		(drill 0.254)
		(layers "F.Cu" "B.Cu")
		(net "GND")
	)
	(via
		(at 33.771586 1.9558)
		(size 0.508)
		(drill 0.254)
		(layers "F.Cu" "B.Cu")
		(net "GND")
	)
	(via
		(at 409.141422 -27.73426)
		(size 0.4572)
		(drill 0.2032)
		(layers "F.Cu" "B.Cu")
		(net "GND")
	)
	(via
		(at 237.142528 -28.730956)
		(size 0.508)
		(drill 0.254)
		(layers "F.Cu" "B.Cu")
		(net "GND")
	)
	(via
		(at 252.782324 -82.33664)
		(size 0.508)
		(drill 0.254)
		(layers "F.Cu" "B.Cu")
		(net "GND")
	)
	(via
		(at 9.936734 14.926056)
		(size 0.5588)
		(drill 0.3048)
		(layers "F.Cu" "B.Cu")
		(net "GND")
	)
	(via
		(at 206.321914 -70.321678)
		(size 0.5588)
		(drill 0.3048)
		(layers "F.Cu" "B.Cu")
		(net "GND")
	)
	(via
		(at 113.561114 -103.576628)
		(size 0.508)
		(drill 0.254)
		(layers "F.Cu" "B.Cu")
		(net "GND")
	)
	(via
		(at 138.689334 -167.832024)
		(size 0.5588)
		(drill 0.3048)
		(layers "F.Cu" "B.Cu")
		(net "GND")
	)
	(via
		(at 396.6718 -152.9588)
		(size 0.508)
		(drill 0.254)
		(layers "F.Cu" "B.Cu")
		(net "GND")
	)
	(via
		(at 333.481934 14.926056)
		(size 0.5588)
		(drill 0.3048)
		(layers "F.Cu" "B.Cu")
		(net "GND")
	)
	(via
		(at 284.358334 -64.819784)
		(size 0.508)
		(drill 0.254)
		(layers "F.Cu" "B.Cu")
		(net "GND")
	)
	(via
		(at 11.60018 -1.31699)
		(size 0.508)
		(drill 0.254)
		(layers "F.Cu" "B.Cu")
		(net "GND")
	)
	(via
		(at 130.84937 -3.762756)
		(size 0.508)
		(drill 0.254)
		(layers "F.Cu" "B.Cu")
		(net "GND")
	)
	(via
		(at 163.8173 -31.9405)
		(size 0.508)
		(drill 0.254)
		(layers "F.Cu" "B.Cu")
		(net "GND")
	)
	(via
		(at 233.895138 -68.46824)
		(size 0.508)
		(drill 0.254)
		(layers "F.Cu" "B.Cu")
		(net "GND")
	)
	(via
		(at 299.8216 -125.929898)
		(size 0.508)
		(drill 0.254)
		(layers "F.Cu" "B.Cu")
		(net "GND")
	)
	(via
		(at 248.489724 -64.010286)
		(size 0.508)
		(drill 0.254)
		(layers "F.Cu" "B.Cu")
		(net "GND")
	)
	(via
		(at 209.092546 -129.564892)
		(size 0.508)
		(drill 0.254)
		(layers "F.Cu" "B.Cu")
		(net "GND")
	)
	(via
		(at 15.875508 -26.6954)
		(size 0.508)
		(drill 0.254)
		(layers "F.Cu" "B.Cu")
		(net "GND")
	)
	(via
		(at 15.24 -133.731)
		(size 0.508)
		(drill 0.254)
		(layers "F.Cu" "B.Cu")
		(net "GND")
	)
	(via
		(at 47.042324 -162.243262)
		(size 0.5588)
		(drill 0.3048)
		(layers "F.Cu" "B.Cu")
		(net "GND")
	)
	(via
		(at 371.277134 -167.857424)
		(size 0.5588)
		(drill 0.3048)
		(layers "F.Cu" "B.Cu")
		(net "GND")
	)
	(via
		(at 191.241934 9.084056)
		(size 0.5588)
		(drill 0.3048)
		(layers "F.Cu" "B.Cu")
		(net "GND")
	)
	(via
		(at 129.085848 -83.641184)
		(size 0.508)
		(drill 0.254)
		(layers "F.Cu" "B.Cu")
		(net "GND")
	)
	(via
		(at 334.3402 -71.628)
		(size 0.508)
		(drill 0.254)
		(layers "F.Cu" "B.Cu")
		(net "GND")
	)
	(via
		(at 49.412398 -68.7705)
		(size 0.508)
		(drill 0.254)
		(layers "F.Cu" "B.Cu")
		(net "GND")
	)
	(via
		(at 302.671226 -81.659984)
		(size 0.508)
		(drill 0.254)
		(layers "F.Cu" "B.Cu")
		(net "GND")
	)
	(via
		(at 134.160514 -3.737356)
		(size 0.508)
		(drill 0.254)
		(layers "F.Cu" "B.Cu")
		(net "GND")
	)
	(via
		(at 130.84937 -134.861046)
		(size 0.508)
		(drill 0.254)
		(layers "F.Cu" "B.Cu")
		(net "GND")
	)
	(via
		(at 355.81082 -143.27886)
		(size 0.508)
		(drill 0.254)
		(layers "F.Cu" "B.Cu")
		(net "GND")
	)
	(via
		(at 290.6522 -88.594184)
		(size 0.508)
		(drill 0.254)
		(layers "F.Cu" "B.Cu")
		(net "GND")
	)
	(via
		(at 146.092164 -18.744946)
		(size 0.508)
		(drill 0.254)
		(layers "F.Cu" "B.Cu")
		(net "GND")
	)
	(via
		(at 342.9254 -38.1)
		(size 0.508)
		(drill 0.254)
		(layers "F.Cu" "B.Cu")
		(net "GND")
	)
	(via
		(at 244.481604 -52.12334)
		(size 0.508)
		(drill 0.254)
		(layers "F.Cu" "B.Cu")
		(net "GND")
	)
	(via
		(at 317.949834 -134.340346)
		(size 0.508)
		(drill 0.254)
		(layers "F.Cu" "B.Cu")
		(net "GND")
	)
	(via
		(at 38.9128 -54.0766)
		(size 0.5588)
		(drill 0.3048)
		(layers "F.Cu" "B.Cu")
		(net "GND")
	)
	(via
		(at 445.3636 -53.3146)
		(size 0.508)
		(drill 0.254)
		(layers "F.Cu" "B.Cu")
		(net "GND")
	)
	(via
		(at 133.378194 -80.174338)
		(size 0.508)
		(drill 0.254)
		(layers "F.Cu" "B.Cu")
		(net "GND")
	)
	(via
		(at 73.4314 -129.5654)
		(size 0.508)
		(drill 0.254)
		(layers "F.Cu" "B.Cu")
		(net "GND")
	)
	(via
		(at 345.821 -153.4668)
		(size 0.508)
		(drill 0.254)
		(layers "F.Cu" "B.Cu")
		(net "GND")
	)
	(via
		(at 273.888708 -70.84314)
		(size 0.5588)
		(drill 0.3048)
		(layers "F.Cu" "B.Cu")
		(net "GND")
	)
	(via
		(at 429.290734 -165.596824)
		(size 0.5588)
		(drill 0.3048)
		(layers "F.Cu" "B.Cu")
		(net "GND")
	)
	(via
		(at 196.893434 -55.528464)
		(size 0.508)
		(drill 0.254)
		(layers "F.Cu" "B.Cu")
		(net "GND")
	)
	(via
		(at 244.857524 -162.243262)
		(size 0.5588)
		(drill 0.3048)
		(layers "F.Cu" "B.Cu")
		(net "GND")
	)
	(via
		(at 403.331934 14.926056)
		(size 0.5588)
		(drill 0.3048)
		(layers "F.Cu" "B.Cu")
		(net "GND")
	)
	(via
		(at 62.786006 -131.5466)
		(size 0.508)
		(drill 0.254)
		(layers "F.Cu" "B.Cu")
		(net "GND")
	)
	(via
		(at 206.855314 -85.028278)
		(size 0.5588)
		(drill 0.3048)
		(layers "F.Cu" "B.Cu")
		(net "GND")
	)
	(via
		(at 149.549358 -13.363956)
		(size 0.508)
		(drill 0.254)
		(layers "F.Cu" "B.Cu")
		(net "GND")
	)
	(via
		(at 74.904346 -66.982086)
		(size 0.508)
		(drill 0.254)
		(layers "F.Cu" "B.Cu")
		(net "GND")
	)
	(via
		(at 381.407162 -27.559)
		(size 0.508)
		(drill 0.254)
		(layers "F.Cu" "B.Cu")
		(net "GND")
	)
	(via
		(at 293.677594 -9.0932)
		(size 0.508)
		(drill 0.254)
		(layers "F.Cu" "B.Cu")
		(net "GND")
	)
	(via
		(at 111.057182 -91.070938)
		(size 0.508)
		(drill 0.254)
		(layers "F.Cu" "B.Cu")
		(net "GND")
	)
	(via
		(at 232.099866 -146.011646)
		(size 0.508)
		(drill 0.254)
		(layers "F.Cu" "B.Cu")
		(net "GND")
	)
	(via
		(at 478.820734 -164.479224)
		(size 0.5588)
		(drill 0.3048)
		(layers "F.Cu" "B.Cu")
		(net "GND")
	)
	(via
		(at 210.291934 14.926056)
		(size 0.5588)
		(drill 0.3048)
		(layers "F.Cu" "B.Cu")
		(net "GND")
	)
	(via
		(at 134.236714 -85.622384)
		(size 0.508)
		(drill 0.254)
		(layers "F.Cu" "B.Cu")
		(net "GND")
	)
	(via
		(at 378.8918 -61.381894)
		(size 0.508)
		(drill 0.254)
		(layers "F.Cu" "B.Cu")
		(net "GND")
	)
	(via
		(at 251.065284 -79.36484)
		(size 0.508)
		(drill 0.254)
		(layers "F.Cu" "B.Cu")
		(net "GND")
	)
	(via
		(at 141.899386 -144.462246)
		(size 0.508)
		(drill 0.254)
		(layers "F.Cu" "B.Cu")
		(net "GND")
	)
	(via
		(at 483.495096 -52.871624)
		(size 0.508)
		(drill 0.254)
		(layers "F.Cu" "B.Cu")
		(net "GND")
	)
	(via
		(at 380.2126 -145.796)
		(size 0.508)
		(drill 0.254)
		(layers "F.Cu" "B.Cu")
		(net "GND")
	)
	(via
		(at 344.1954 -40.64)
		(size 0.508)
		(drill 0.254)
		(layers "F.Cu" "B.Cu")
		(net "GND")
	)
	(via
		(at 345.059 -95.123)
		(size 0.508)
		(drill 0.254)
		(layers "F.Cu" "B.Cu")
		(net "GND")
	)
	(via
		(at 387.048502 -30.618684)
		(size 0.508)
		(drill 0.254)
		(layers "F.Cu" "B.Cu")
		(net "GND")
	)
	(via
		(at 205.749906 0.457454)
		(size 0.508)
		(drill 0.254)
		(layers "F.Cu" "B.Cu")
		(net "GND")
	)
	(via
		(at 234.421934 14.926056)
		(size 0.5588)
		(drill 0.3048)
		(layers "F.Cu" "B.Cu")
		(net "GND")
	)
	(via
		(at 211.699856 -2.314956)
		(size 0.508)
		(drill 0.254)
		(layers "F.Cu" "B.Cu")
		(net "GND")
	)
	(via
		(at 42.411396 -148.771356)
		(size 0.508)
		(drill 0.254)
		(layers "F.Cu" "B.Cu")
		(net "GND")
	)
	(via
		(at 141.963394 -56.399938)
		(size 0.508)
		(drill 0.254)
		(layers "F.Cu" "B.Cu")
		(net "GND")
	)
	(via
		(at 464.53425 -143.173196)
		(size 0.508)
		(drill 0.254)
		(layers "F.Cu" "B.Cu")
		(net "GND")
	)
	(via
		(at 393.68095 -97.605596)
		(size 0.508)
		(drill 0.254)
		(layers "F.Cu" "B.Cu")
		(net "GND")
	)
	(via
		(at 94.649798 -60.54344)
		(size 0.508)
		(drill 0.254)
		(layers "F.Cu" "B.Cu")
		(net "GND")
	)
	(via
		(at 136.812274 -52.437538)
		(size 0.508)
		(drill 0.254)
		(layers "F.Cu" "B.Cu")
		(net "GND")
	)
	(via
		(at 70.611746 -88.28024)
		(size 0.508)
		(drill 0.254)
		(layers "F.Cu" "B.Cu")
		(net "GND")
	)
	(via
		(at 9.047734 -164.479224)
		(size 0.5588)
		(drill 0.3048)
		(layers "F.Cu" "B.Cu")
		(net "GND")
	)
	(via
		(at 265.659616 -89.765886)
		(size 0.508)
		(drill 0.254)
		(layers "F.Cu" "B.Cu")
		(net "GND")
	)
	(via
		(at 171.85894 -19.80438)
		(size 0.508)
		(drill 0.254)
		(layers "F.Cu" "B.Cu")
		(net "GND")
	)
	(via
		(at 292.399212 -16.7513)
		(size 0.508)
		(drill 0.254)
		(layers "F.Cu" "B.Cu")
		(net "GND")
	)
	(via
		(at 59.449462 -148.771356)
		(size 0.508)
		(drill 0.254)
		(layers "F.Cu" "B.Cu")
		(net "GND")
	)
	(via
		(at 292.36924 -93.547184)
		(size 0.508)
		(drill 0.254)
		(layers "F.Cu" "B.Cu")
		(net "GND")
	)
	(via
		(at 346.7354 -38.1)
		(size 0.508)
		(drill 0.254)
		(layers "F.Cu" "B.Cu")
		(net "GND")
	)
	(via
		(at 401.350734 -163.361624)
		(size 0.5588)
		(drill 0.3048)
		(layers "F.Cu" "B.Cu")
		(net "GND")
	)
	(via
		(at 68.036186 -65.991486)
		(size 0.508)
		(drill 0.254)
		(layers "F.Cu" "B.Cu")
		(net "GND")
	)
	(via
		(at 464.5152 -146.2024)
		(size 0.508)
		(drill 0.254)
		(layers "F.Cu" "B.Cu")
		(net "GND")
	)
	(via
		(at 238.437928 -141.202156)
		(size 0.508)
		(drill 0.254)
		(layers "F.Cu" "B.Cu")
		(net "GND")
	)
	(via
		(at 156.951934 14.926056)
		(size 0.5588)
		(drill 0.3048)
		(layers "F.Cu" "B.Cu")
		(net "GND")
	)
	(via
		(at 59.449462 -18.744946)
		(size 0.508)
		(drill 0.254)
		(layers "F.Cu" "B.Cu")
		(net "GND")
	)
	(via
		(at 402.717 -25.654)
		(size 0.508)
		(drill 0.254)
		(layers "F.Cu" "B.Cu")
		(net "GND")
	)
	(via
		(at 339.223604 -143.087598)
		(size 0.508)
		(drill 0.254)
		(layers "F.Cu" "B.Cu")
		(net "GND")
	)
	(via
		(at 116.361464 -129.568956)
		(size 0.508)
		(drill 0.254)
		(layers "F.Cu" "B.Cu")
		(net "GND")
	)
	(via
		(at 69.56044 -140.592556)
		(size 0.508)
		(drill 0.254)
		(layers "F.Cu" "B.Cu")
		(net "GND")
	)
	(via
		(at 250.445524 -162.243262)
		(size 0.5588)
		(drill 0.3048)
		(layers "F.Cu" "B.Cu")
		(net "GND")
	)
	(via
		(at 403.977856 -19.802348)
		(size 0.508)
		(drill 0.254)
		(layers "F.Cu" "B.Cu")
		(net "GND")
	)
	(via
		(at 285.501334 -96.518984)
		(size 0.508)
		(drill 0.254)
		(layers "F.Cu" "B.Cu")
		(net "GND")
	)
	(via
		(at 237.142528 0.457454)
		(size 0.508)
		(drill 0.254)
		(layers "F.Cu" "B.Cu")
		(net "GND")
	)
	(via
		(at 106.275124 -162.243262)
		(size 0.5588)
		(drill 0.3048)
		(layers "F.Cu" "B.Cu")
		(net "GND")
	)
	(via
		(at 99.800664 -89.27084)
		(size 0.508)
		(drill 0.254)
		(layers "F.Cu" "B.Cu")
		(net "GND")
	)
	(via
		(at 459.211934 9.084056)
		(size 0.5588)
		(drill 0.3048)
		(layers "F.Cu" "B.Cu")
		(net "GND")
	)
	(via
		(at 181.2671 -139.6365)
		(size 0.508)
		(drill 0.254)
		(layers "F.Cu" "B.Cu")
		(net "GND")
	)
	(via
		(at 34.991802 -87.176864)
		(size 0.508)
		(drill 0.254)
		(layers "F.Cu" "B.Cu")
		(net "GND")
	)
	(via
		(at 74.045826 -63.51524)
		(size 0.508)
		(drill 0.254)
		(layers "F.Cu" "B.Cu")
		(net "GND")
	)
	(via
		(at 166.625524 -162.243262)
		(size 0.5588)
		(drill 0.3048)
		(layers "F.Cu" "B.Cu")
		(net "GND")
	)
	(via
		(at 109.955076 -70.84314)
		(size 0.5588)
		(drill 0.3048)
		(layers "F.Cu" "B.Cu")
		(net "GND")
	)
	(via
		(at 71.470266 -69.953886)
		(size 0.508)
		(drill 0.254)
		(layers "F.Cu" "B.Cu")
		(net "GND")
	)
	(via
		(at 244.197124 -97.19564)
		(size 0.508)
		(drill 0.254)
		(layers "F.Cu" "B.Cu")
		(net "GND")
	)
	(via
		(at 384.683 -151.7142)
		(size 0.508)
		(drill 0.254)
		(layers "F.Cu" "B.Cu")
		(net "GND")
	)
	(via
		(at 260.50875 -56.085486)
		(size 0.508)
		(drill 0.254)
		(layers "F.Cu" "B.Cu")
		(net "GND")
	)
	(via
		(at 33.099502 -136.410446)
		(size 0.508)
		(drill 0.254)
		(layers "F.Cu" "B.Cu")
		(net "GND")
	)
	(via
		(at 276.150324 -162.243262)
		(size 0.5588)
		(drill 0.3048)
		(layers "F.Cu" "B.Cu")
		(net "GND")
	)
	(via
		(at 162.031934 14.926056)
		(size 0.5588)
		(drill 0.3048)
		(layers "F.Cu" "B.Cu")
		(net "GND")
	)
	(via
		(at 135.061452 -26.495756)
		(size 0.508)
		(drill 0.254)
		(layers "F.Cu" "B.Cu")
		(net "GND")
	)
	(via
		(at 336.2452 -26.4795)
		(size 0.508)
		(drill 0.254)
		(layers "F.Cu" "B.Cu")
		(net "GND")
	)
	(via
		(at 287.330134 -167.832024)
		(size 0.5588)
		(drill 0.3048)
		(layers "F.Cu" "B.Cu")
		(net "GND")
	)
	(via
		(at 124.801376 -154.063446)
		(size 0.508)
		(drill 0.254)
		(layers "F.Cu" "B.Cu")
		(net "GND")
	)
	(via
		(at 487.710734 -167.832024)
		(size 0.5588)
		(drill 0.3048)
		(layers "F.Cu" "B.Cu")
		(net "GND")
	)
	(via
		(at 390.5377 -112.2553)
		(size 0.508)
		(drill 0.254)
		(layers "F.Cu" "B.Cu")
		(net "GND")
	)
	(via
		(at 300.099984 -146.011646)
		(size 0.508)
		(drill 0.254)
		(layers "F.Cu" "B.Cu")
		(net "GND")
	)
	(via
		(at 32.15132 -134.861046)
		(size 0.508)
		(drill 0.254)
		(layers "F.Cu" "B.Cu")
		(net "GND")
	)
	(via
		(at 111.057182 -97.014538)
		(size 0.508)
		(drill 0.254)
		(layers "F.Cu" "B.Cu")
		(net "GND")
	)
	(via
		(at 65.399412 -11.916156)
		(size 0.508)
		(drill 0.254)
		(layers "F.Cu" "B.Cu")
		(net "GND")
	)
	(via
		(at 270.571468 -52.932838)
		(size 0.508)
		(drill 0.254)
		(layers "F.Cu" "B.Cu")
		(net "GND")
	)
	(via
		(at 244.197124 -78.37424)
		(size 0.508)
		(drill 0.254)
		(layers "F.Cu" "B.Cu")
		(net "GND")
	)
	(via
		(at 172.2628 -79.6798)
		(size 0.508)
		(drill 0.254)
		(layers "F.Cu" "B.Cu")
		(net "GND")
	)
	(via
		(at 67.101466 -87.28964)
		(size 0.508)
		(drill 0.254)
		(layers "F.Cu" "B.Cu")
		(net "GND")
	)
	(via
		(at 111.783876 -70.841616)
		(size 0.5588)
		(drill 0.3048)
		(layers "F.Cu" "B.Cu")
		(net "GND")
	)
	(via
		(at 472.15552 -0.553212)
		(size 0.5588)
		(drill 0.3048)
		(layers "F.Cu" "B.Cu")
		(net "GND")
	)
	(via
		(at 64.087502 -13.948156)
		(size 0.508)
		(drill 0.254)
		(layers "F.Cu" "B.Cu")
		(net "GND")
	)
	(via
		(at 206.51089 -150.193756)
		(size 0.508)
		(drill 0.254)
		(layers "F.Cu" "B.Cu")
		(net "GND")
	)
	(via
		(at 326.446134 -167.832024)
		(size 0.5588)
		(drill 0.3048)
		(layers "F.Cu" "B.Cu")
		(net "GND")
	)
	(via
		(at 484.628444 -20.927822)
		(size 0.508)
		(drill 0.254)
		(layers "F.Cu" "B.Cu")
		(net "GND")
	)
	(via
		(at 276.631654 -53.427884)
		(size 0.508)
		(drill 0.254)
		(layers "F.Cu" "B.Cu")
		(net "GND")
	)
	(via
		(at 308.59984 -13.427456)
		(size 0.508)
		(drill 0.254)
		(layers "F.Cu" "B.Cu")
		(net "GND")
	)
	(via
		(at 236.961934 14.926056)
		(size 0.5588)
		(drill 0.3048)
		(layers "F.Cu" "B.Cu")
		(net "GND")
	)
	(via
		(at 64.241934 14.926056)
		(size 0.5588)
		(drill 0.3048)
		(layers "F.Cu" "B.Cu")
		(net "GND")
	)
	(via
		(at 135.099552 -9.156446)
		(size 0.508)
		(drill 0.254)
		(layers "F.Cu" "B.Cu")
		(net "GND")
	)
	(via
		(at 96.74479 -68.802504)
		(size 0.5588)
		(drill 0.3048)
		(layers "F.Cu" "B.Cu")
		(net "GND")
	)
	(via
		(at 278.725122 -130.249676)
		(size 0.508)
		(drill 0.254)
		(layers "F.Cu" "B.Cu")
		(net "GND")
	)
	(via
		(at 260.0706 -19.6088)
		(size 0.508)
		(drill 0.254)
		(layers "F.Cu" "B.Cu")
		(net "GND")
	)
	(via
		(at 256.011934 9.084056)
		(size 0.5588)
		(drill 0.3048)
		(layers "F.Cu" "B.Cu")
		(net "GND")
	)
	(via
		(at 293.69131 -143.950944)
		(size 0.508)
		(drill 0.254)
		(layers "F.Cu" "B.Cu")
		(net "GND")
	)
	(via
		(at 238.437928 -124.623576)
		(size 0.508)
		(drill 0.254)
		(layers "F.Cu" "B.Cu")
		(net "GND")
	)
	(via
		(at 200.533 -67.0306)
		(size 0.508)
		(drill 0.254)
		(layers "F.Cu" "B.Cu")
		(net "GND")
	)
	(via
		(at 12.400534 -167.832024)
		(size 0.5588)
		(drill 0.3048)
		(layers "F.Cu" "B.Cu")
		(net "GND")
	)
	(via
		(at 296.69105 -26.495756)
		(size 0.508)
		(drill 0.254)
		(layers "F.Cu" "B.Cu")
		(net "GND")
	)
	(via
		(at 136.812274 -53.427884)
		(size 0.508)
		(drill 0.254)
		(layers "F.Cu" "B.Cu")
		(net "GND")
	)
	(via
		(at 326.644 -34.798)
		(size 0.508)
		(drill 0.254)
		(layers "F.Cu" "B.Cu")
		(net "GND")
	)
	(via
		(at 323.089524 -162.243262)
		(size 0.5588)
		(drill 0.3048)
		(layers "F.Cu" "B.Cu")
		(net "GND")
	)
	(via
		(at 121.933208 -61.352938)
		(size 0.508)
		(drill 0.254)
		(layers "F.Cu" "B.Cu")
		(net "GND")
	)
	(via
		(at 42.019982 -68.917058)
		(size 0.5588)
		(drill 0.3048)
		(layers "F.Cu" "B.Cu")
		(net "GND")
	)
	(via
		(at 245.055644 -70.94474)
		(size 0.508)
		(drill 0.254)
		(layers "F.Cu" "B.Cu")
		(net "GND")
	)
	(via
		(at 122.349514 -136.410446)
		(size 0.508)
		(drill 0.254)
		(layers "F.Cu" "B.Cu")
		(net "GND")
	)
	(via
		(at 463.004408 -118.61927)
		(size 0.508)
		(drill 0.254)
		(layers "F.Cu" "B.Cu")
		(net "GND")
	)
	(via
		(at 36.03752 -150.803356)
		(size 0.508)
		(drill 0.254)
		(layers "F.Cu" "B.Cu")
		(net "GND")
	)
	(via
		(at 4.357624 -147.696174)
		(size 0.508)
		(drill 0.254)
		(layers "F.Cu" "B.Cu")
		(net "GND")
	)
	(via
		(at 299.160946 -140.592556)
		(size 0.508)
		(drill 0.254)
		(layers "F.Cu" "B.Cu")
		(net "GND")
	)
	(via
		(at 383.77495 -116.953284)
		(size 0.508)
		(drill 0.254)
		(layers "F.Cu" "B.Cu")
		(net "GND")
	)
	(via
		(at 404.345648 -99.327208)
		(size 0.508)
		(drill 0.254)
		(layers "F.Cu" "B.Cu")
		(net "GND")
	)
	(via
		(at 478.261934 13.910056)
		(size 0.5588)
		(drill 0.3048)
		(layers "F.Cu" "B.Cu")
		(net "GND")
	)
	(via
		(at 367.0808 -158.3436)
		(size 0.508)
		(drill 0.254)
		(layers "F.Cu" "B.Cu")
		(net "GND")
	)
	(via
		(at 385.2672 -152.054306)
		(size 0.508)
		(drill 0.254)
		(layers "F.Cu" "B.Cu")
		(net "GND")
	)
	(via
		(at 109.055916 -55.904384)
		(size 0.508)
		(drill 0.254)
		(layers "F.Cu" "B.Cu")
		(net "GND")
	)
	(via
		(at 424.688 -13.081)
		(size 0.508)
		(drill 0.254)
		(layers "F.Cu" "B.Cu")
		(net "GND")
	)
	(via
		(at 363.895894 -1.32588)
		(size 0.508)
		(drill 0.254)
		(layers "F.Cu" "B.Cu")
		(net "GND")
	)
	(via
		(at 378.82195 -120.387364)
		(size 0.508)
		(drill 0.254)
		(layers "F.Cu" "B.Cu")
		(net "GND")
	)
	(via
		(at 472.0336 -63.8048)
		(size 0.508)
		(drill 0.254)
		(layers "F.Cu" "B.Cu")
		(net "GND")
	)
	(via
		(at 403.207982 -124.56795)
		(size 0.508)
		(drill 0.254)
		(layers "F.Cu" "B.Cu")
		(net "GND")
	)
	(via
		(at 0.365506 -145.817082)
		(size 0.508)
		(drill 0.254)
		(layers "F.Cu" "B.Cu")
		(net "GND")
	)
	(via
		(at 254.49911 -60.54344)
		(size 0.508)
		(drill 0.254)
		(layers "F.Cu" "B.Cu")
		(net "GND")
	)
	(via
		(at 17.422368 -33.6804)
		(size 0.508)
		(drill 0.254)
		(layers "F.Cu" "B.Cu")
		(net "GND")
	)
	(via
		(at 84.919312 -50.573432)
		(size 0.508)
		(drill 0.254)
		(layers "F.Cu" "B.Cu")
		(net "GND")
	)
	(via
		(at 79.481934 9.084056)
		(size 0.5588)
		(drill 0.3048)
		(layers "F.Cu" "B.Cu")
		(net "GND")
	)
	(via
		(at 239.046258 -64.50584)
		(size 0.508)
		(drill 0.254)
		(layers "F.Cu" "B.Cu")
		(net "GND")
	)
	(via
		(at 46.699424 -155.612846)
		(size 0.508)
		(drill 0.254)
		(layers "F.Cu" "B.Cu")
		(net "GND")
	)
	(via
		(at 78.193392 -149.436836)
		(size 0.508)
		(drill 0.254)
		(layers "F.Cu" "B.Cu")
		(net "GND")
	)
	(via
		(at 87.781892 -67.47764)
		(size 0.508)
		(drill 0.254)
		(layers "F.Cu" "B.Cu")
		(net "GND")
	)
	(via
		(at 455.956924 -162.243262)
		(size 0.5588)
		(drill 0.3048)
		(layers "F.Cu" "B.Cu")
		(net "GND")
	)
	(via
		(at 138.03757 -13.948156)
		(size 0.508)
		(drill 0.254)
		(layers "F.Cu" "B.Cu")
		(net "GND")
	)
	(via
		(at 227.786438 -4.2926)
		(size 0.508)
		(drill 0.254)
		(layers "F.Cu" "B.Cu")
		(net "GND")
	)
	(via
		(at 448.93357 -145.21053)
		(size 0.508)
		(drill 0.254)
		(layers "F.Cu" "B.Cu")
		(net "GND")
	)
	(via
		(at 126.421642 -22.965156)
		(size 0.508)
		(drill 0.254)
		(layers "F.Cu" "B.Cu")
		(net "GND")
	)
	(via
		(at 172.21708 -17.74698)
		(size 0.508)
		(drill 0.254)
		(layers "F.Cu" "B.Cu")
		(net "GND")
	)
	(via
		(at 305.9176 -125.955298)
		(size 0.508)
		(drill 0.254)
		(layers "F.Cu" "B.Cu")
		(net "GND")
	)
	(via
		(at 397.7132 -144.9324)
		(size 0.508)
		(drill 0.254)
		(layers "F.Cu" "B.Cu")
		(net "GND")
	)
	(via
		(at 281.208734 -91.070938)
		(size 0.508)
		(drill 0.254)
		(layers "F.Cu" "B.Cu")
		(net "GND")
	)
	(via
		(at 39.049452 -146.011646)
		(size 0.508)
		(drill 0.254)
		(layers "F.Cu" "B.Cu")
		(net "GND")
	)
	(via
		(at 238.444532 -28.66771)
		(size 0.508)
		(drill 0.254)
		(layers "F.Cu" "B.Cu")
		(net "GND")
	)
	(via
		(at 140.199364 -154.063446)
		(size 0.508)
		(drill 0.254)
		(layers "F.Cu" "B.Cu")
		(net "GND")
	)
	(via
		(at 86.064852 -86.29904)
		(size 0.508)
		(drill 0.254)
		(layers "F.Cu" "B.Cu")
		(net "GND")
	)
	(via
		(at 288.19983 -7.607046)
		(size 0.508)
		(drill 0.254)
		(layers "F.Cu" "B.Cu")
		(net "GND")
	)
	(via
		(at 121.074688 -54.913784)
		(size 0.508)
		(drill 0.254)
		(layers "F.Cu" "B.Cu")
		(net "GND")
	)
	(via
		(at 56.049418 -129.568956)
		(size 0.508)
		(drill 0.254)
		(layers "F.Cu" "B.Cu")
		(net "GND")
	)
	(via
		(at 117.925342 -89.089738)
		(size 0.508)
		(drill 0.254)
		(layers "F.Cu" "B.Cu")
		(net "GND")
	)
	(via
		(at 378.82195 -101.039676)
		(size 0.508)
		(drill 0.254)
		(layers "F.Cu" "B.Cu")
		(net "GND")
	)
	(via
		(at 306.899818 -7.607046)
		(size 0.508)
		(drill 0.254)
		(layers "F.Cu" "B.Cu")
		(net "GND")
	)
	(via
		(at 454.690734 -165.596824)
		(size 0.5588)
		(drill 0.3048)
		(layers "F.Cu" "B.Cu")
		(net "GND")
	)
	(via
		(at 98.531934 9.084056)
		(size 0.5588)
		(drill 0.3048)
		(layers "F.Cu" "B.Cu")
		(net "GND")
	)
	(via
		(at 465.397596 -53.272436)
		(size 0.508)
		(drill 0.254)
		(layers "F.Cu" "B.Cu")
		(net "GND")
	)
	(via
		(at 115.349782 -88.594184)
		(size 0.508)
		(drill 0.254)
		(layers "F.Cu" "B.Cu")
		(net "GND")
	)
	(via
		(at 279.7048 -82.299302)
		(size 0.5588)
		(drill 0.3048)
		(layers "F.Cu" "B.Cu")
		(net "GND")
	)
	(via
		(at 460.594202 -15.791688)
		(size 0.5588)
		(drill 0.3048)
		(layers "F.Cu" "B.Cu")
		(net "GND")
	)
	(via
		(at 441.986924 -162.243262)
		(size 0.5588)
		(drill 0.3048)
		(layers "F.Cu" "B.Cu")
		(net "GND")
	)
	(via
		(at 262.22579 -95.709486)
		(size 0.508)
		(drill 0.254)
		(layers "F.Cu" "B.Cu")
		(net "GND")
	)
	(via
		(at 201.135996 -53.711602)
		(size 0.5588)
		(drill 0.3048)
		(layers "F.Cu" "B.Cu")
		(net "GND")
	)
	(via
		(at 130.281934 9.084056)
		(size 0.5588)
		(drill 0.3048)
		(layers "F.Cu" "B.Cu")
		(net "GND")
	)
	(via
		(at 139.316968 -125.9332)
		(size 0.508)
		(drill 0.254)
		(layers "F.Cu" "B.Cu")
		(net "GND")
	)
	(via
		(at 7.701534 14.926056)
		(size 0.5588)
		(drill 0.3048)
		(layers "F.Cu" "B.Cu")
		(net "GND")
	)
	(via
		(at 75.762866 -74.411586)
		(size 0.508)
		(drill 0.254)
		(layers "F.Cu" "B.Cu")
		(net "GND")
	)
	(via
		(at 344.1954 -36.83)
		(size 0.508)
		(drill 0.254)
		(layers "F.Cu" "B.Cu")
		(net "GND")
	)
	(via
		(at 123.076208 -93.052138)
		(size 0.508)
		(drill 0.254)
		(layers "F.Cu" "B.Cu")
		(net "GND")
	)
	(via
		(at 176.784 -140.5255)
		(size 0.508)
		(drill 0.254)
		(layers "F.Cu" "B.Cu")
		(net "GND")
	)
	(via
		(at 278.274018 -75.143614)
		(size 0.5588)
		(drill 0.3048)
		(layers "F.Cu" "B.Cu")
		(net "GND")
	)
	(via
		(at 146.086068 -141.1478)
		(size 0.508)
		(drill 0.254)
		(layers "F.Cu" "B.Cu")
		(net "GND")
	)
	(via
		(at -0.070866 13.783056)
		(size 0.5588)
		(drill 0.3048)
		(layers "F.Cu" "B.Cu")
		(net "GND")
	)
	(via
		(at 90.845894 -135.012684)
		(size 0.508)
		(drill 0.254)
		(layers "F.Cu" "B.Cu")
		(net "GND")
	)
	(via
		(at 301.749206 -144.0053)
		(size 0.508)
		(drill 0.254)
		(layers "F.Cu" "B.Cu")
		(net "GND")
	)
	(via
		(at 357.295196 -11.71448)
		(size 0.508)
		(drill 0.254)
		(layers "F.Cu" "B.Cu")
		(net "GND")
	)
	(via
		(at 179.451 -54.5846)
		(size 0.508)
		(drill 0.254)
		(layers "F.Cu" "B.Cu")
		(net "GND")
	)
	(via
		(at 35.8902 -56.3118)
		(size 0.508)
		(drill 0.254)
		(layers "F.Cu" "B.Cu")
		(net "GND")
	)
	(via
		(at 474.451934 13.910056)
		(size 0.5588)
		(drill 0.3048)
		(layers "F.Cu" "B.Cu")
		(net "GND")
	)
	(via
		(at 108.481876 -93.547184)
		(size 0.508)
		(drill 0.254)
		(layers "F.Cu" "B.Cu")
		(net "GND")
	)
	(via
		(at 116.495322 -86.041484)
		(size 0.508)
		(drill 0.254)
		(layers "F.Cu" "B.Cu")
		(net "GND")
	)
	(via
		(at 376.661934 9.084056)
		(size 0.5588)
		(drill 0.3048)
		(layers "F.Cu" "B.Cu")
		(net "GND")
	)
	(via
		(at 133.378194 -99.986338)
		(size 0.508)
		(drill 0.254)
		(layers "F.Cu" "B.Cu")
		(net "GND")
	)
	(via
		(at 197.151752 -144.462246)
		(size 0.508)
		(drill 0.254)
		(layers "F.Cu" "B.Cu")
		(net "GND")
	)
	(via
		(at 318.622934 -167.832024)
		(size 0.5588)
		(drill 0.3048)
		(layers "F.Cu" "B.Cu")
		(net "GND")
	)
	(via
		(at 53.442108 -18.744946)
		(size 0.508)
		(drill 0.254)
		(layers "F.Cu" "B.Cu")
		(net "GND")
	)
	(via
		(at 168.864534 -167.832024)
		(size 0.5588)
		(drill 0.3048)
		(layers "F.Cu" "B.Cu")
		(net "GND")
	)
	(via
		(at 200.7362 -86.4362)
		(size 0.5588)
		(drill 0.3048)
		(layers "F.Cu" "B.Cu")
		(net "GND")
	)
	(via
		(at 456.671934 9.084056)
		(size 0.5588)
		(drill 0.3048)
		(layers "F.Cu" "B.Cu")
		(net "GND")
	)
	(via
		(at 207.5434 -80.518)
		(size 0.5588)
		(drill 0.3048)
		(layers "F.Cu" "B.Cu")
		(net "GND")
	)
	(via
		(at 135.095234 -70.268084)
		(size 0.508)
		(drill 0.254)
		(layers "F.Cu" "B.Cu")
		(net "GND")
	)
	(via
		(at 76.449428 -18.757646)
		(size 0.508)
		(drill 0.254)
		(layers "F.Cu" "B.Cu")
		(net "GND")
	)
	(via
		(at 300.095666 -70.268084)
		(size 0.508)
		(drill 0.254)
		(layers "F.Cu" "B.Cu")
		(net "GND")
	)
	(via
		(at 480.090734 -164.479224)
		(size 0.5588)
		(drill 0.3048)
		(layers "F.Cu" "B.Cu")
		(net "GND")
	)
	(via
		(at 454.131934 13.910056)
		(size 0.5588)
		(drill 0.3048)
		(layers "F.Cu" "B.Cu")
		(net "GND")
	)
	(via
		(at 131.699508 -21.517356)
		(size 0.508)
		(drill 0.254)
		(layers "F.Cu" "B.Cu")
		(net "GND")
	)
	(via
		(at 167.8686 -31.4071)
		(size 0.508)
		(drill 0.254)
		(layers "F.Cu" "B.Cu")
		(net "GND")
	)
	(via
		(at 143.599408 -13.427456)
		(size 0.508)
		(drill 0.254)
		(layers "F.Cu" "B.Cu")
		(net "GND")
	)
	(via
		(at 484.235252 4.055872)
		(size 0.508)
		(drill 0.254)
		(layers "F.Cu" "B.Cu")
		(net "GND")
	)
	(via
		(at 246.619268 -145.0086)
		(size 0.508)
		(drill 0.254)
		(layers "F.Cu" "B.Cu")
		(net "GND")
	)
	(via
		(at 81.618836 -8.1534)
		(size 0.508)
		(drill 0.254)
		(layers "F.Cu" "B.Cu")
		(net "GND")
	)
	(via
		(at 150.399496 -21.517356)
		(size 0.508)
		(drill 0.254)
		(layers "F.Cu" "B.Cu")
		(net "GND")
	)
	(via
		(at 172.3136 -56.9214)
		(size 0.508)
		(drill 0.254)
		(layers "F.Cu" "B.Cu")
		(net "GND")
	)
	(via
		(at 292.36924 -91.565984)
		(size 0.508)
		(drill 0.254)
		(layers "F.Cu" "B.Cu")
		(net "GND")
	)
	(via
		(at 243.2304 -17.8816)
		(size 0.508)
		(drill 0.254)
		(layers "F.Cu" "B.Cu")
		(net "GND")
	)
	(via
		(at 287.79216 -63.829184)
		(size 0.508)
		(drill 0.254)
		(layers "F.Cu" "B.Cu")
		(net "GND")
	)
	(via
		(at 459.766924 -162.243262)
		(size 0.5588)
		(drill 0.3048)
		(layers "F.Cu" "B.Cu")
		(net "GND")
	)
	(via
		(at 186.048396 -88.306402)
		(size 0.508)
		(drill 0.254)
		(layers "F.Cu" "B.Cu")
		(net "GND")
	)
	(via
		(at 456.198986 -26.518108)
		(size 0.508)
		(drill 0.254)
		(layers "F.Cu" "B.Cu")
		(net "GND")
	)
	(via
		(at 340.98992 -77.178408)
		(size 0.508)
		(drill 0.254)
		(layers "F.Cu" "B.Cu")
		(net "GND")
	)
	(via
		(at 496.1128 -49.66462)
		(size 0.508)
		(drill 0.254)
		(layers "F.Cu" "B.Cu")
		(net "GND")
	)
	(via
		(at 441.39993 -113.8174)
		(size 0.508)
		(drill 0.254)
		(layers "F.Cu" "B.Cu")
		(net "GND")
	)
	(via
		(at 393.2682 -126.746)
		(size 0.508)
		(drill 0.254)
		(layers "F.Cu" "B.Cu")
		(net "GND")
	)
	(via
		(at 229.087934 -124.590556)
		(size 0.508)
		(drill 0.254)
		(layers "F.Cu" "B.Cu")
		(net "GND")
	)
	(via
		(at 394.861542 -9.452864)
		(size 0.508)
		(drill 0.254)
		(layers "F.Cu" "B.Cu")
		(net "GND")
	)
	(via
		(at 456.22718 -45.611796)
		(size 0.508)
		(drill 0.254)
		(layers "F.Cu" "B.Cu")
		(net "GND")
	)
	(via
		(at 200.8632 -80.6958)
		(size 0.508)
		(drill 0.254)
		(layers "F.Cu" "B.Cu")
		(net "GND")
	)
	(via
		(at 207.129888 -99.172268)
		(size 0.5588)
		(drill 0.3048)
		(layers "F.Cu" "B.Cu")
		(net "GND")
	)
	(via
		(at 206.982314 -69.000878)
		(size 0.5588)
		(drill 0.3048)
		(layers "F.Cu" "B.Cu")
		(net "GND")
	)
	(via
		(at 78.338172 -82.83194)
		(size 0.508)
		(drill 0.254)
		(layers "F.Cu" "B.Cu")
		(net "GND")
	)
	(via
		(at 304.349912 -148.771356)
		(size 0.508)
		(drill 0.254)
		(layers "F.Cu" "B.Cu")
		(net "GND")
	)
	(via
		(at 138.529314 -73.240138)
		(size 0.508)
		(drill 0.254)
		(layers "F.Cu" "B.Cu")
		(net "GND")
	)
	(via
		(at 431.251106 -138.622786)
		(size 0.508)
		(drill 0.254)
		(layers "F.Cu" "B.Cu")
		(net "GND")
	)
	(via
		(at 127.368808 -92.556584)
		(size 0.508)
		(drill 0.254)
		(layers "F.Cu" "B.Cu")
		(net "GND")
	)
	(via
		(at 218.449144 -16.7513)
		(size 0.508)
		(drill 0.254)
		(layers "F.Cu" "B.Cu")
		(net "GND")
	)
	(via
		(at 151.24938 -22.965156)
		(size 0.508)
		(drill 0.254)
		(layers "F.Cu" "B.Cu")
		(net "GND")
	)
	(via
		(at 124.793248 -92.061538)
		(size 0.508)
		(drill 0.254)
		(layers "F.Cu" "B.Cu")
		(net "GND")
	)
	(via
		(at 222.991934 14.926056)
		(size 0.5588)
		(drill 0.3048)
		(layers "F.Cu" "B.Cu")
		(net "GND")
	)
	(via
		(at 263.09828 -82.340196)
		(size 0.5588)
		(drill 0.3048)
		(layers "F.Cu" "B.Cu")
		(net "GND")
	)
	(via
		(at 196.908928 -56.167782)
		(size 0.508)
		(drill 0.254)
		(layers "F.Cu" "B.Cu")
		(net "GND")
	)
	(via
		(at 479.531934 13.910056)
		(size 0.5588)
		(drill 0.3048)
		(layers "F.Cu" "B.Cu")
		(net "GND")
	)
	(via
		(at 285.2166 -55.409338)
		(size 0.508)
		(drill 0.254)
		(layers "F.Cu" "B.Cu")
		(net "GND")
	)
	(via
		(at 110.198916 -91.565984)
		(size 0.508)
		(drill 0.254)
		(layers "F.Cu" "B.Cu")
		(net "GND")
	)
	(via
		(at 4.0132 -137.9982)
		(size 0.508)
		(drill 0.254)
		(layers "F.Cu" "B.Cu")
		(net "GND")
	)
	(via
		(at 225.210878 -13.338556)
		(size 0.508)
		(drill 0.254)
		(layers "F.Cu" "B.Cu")
		(net "GND")
	)
	(via
		(at 287.349946 -21.517356)
		(size 0.508)
		(drill 0.254)
		(layers "F.Cu" "B.Cu")
		(net "GND")
	)
	(via
		(at 356.748334 -167.857424)
		(size 0.5588)
		(drill 0.3048)
		(layers "F.Cu" "B.Cu")
		(net "GND")
	)
	(via
		(at 115.923822 -63.829184)
		(size 0.508)
		(drill 0.254)
		(layers "F.Cu" "B.Cu")
		(net "GND")
	)
	(via
		(at 285.501334 -94.538038)
		(size 0.508)
		(drill 0.254)
		(layers "F.Cu" "B.Cu")
		(net "GND")
	)
	(via
		(at 497.1034 -127.75946)
		(size 0.508)
		(drill 0.254)
		(layers "F.Cu" "B.Cu")
		(net "GND")
	)
	(via
		(at 385.401312 -47.296832)
		(size 0.508)
		(drill 0.254)
		(layers "F.Cu" "B.Cu")
		(net "GND")
	)
	(via
		(at 240.599722 -3.762756)
		(size 0.508)
		(drill 0.254)
		(layers "F.Cu" "B.Cu")
		(net "GND")
	)
	(via
		(at 130.802888 -74.725784)
		(size 0.508)
		(drill 0.254)
		(layers "F.Cu" "B.Cu")
		(net "GND")
	)
	(via
		(at 391.414 -68.453)
		(size 0.508)
		(drill 0.254)
		(layers "F.Cu" "B.Cu")
		(net "GND")
	)
	(via
		(at 446.20434 -118.61927)
		(size 0.508)
		(drill 0.254)
		(layers "F.Cu" "B.Cu")
		(net "GND")
	)
	(via
		(at 34.748724 -134.4041)
		(size 0.508)
		(drill 0.254)
		(layers "F.Cu" "B.Cu")
		(net "GND")
	)
	(via
		(at 148.699474 0.444754)
		(size 0.508)
		(drill 0.254)
		(layers "F.Cu" "B.Cu")
		(net "GND")
	)
	(via
		(at 259.386324 -162.243262)
		(size 0.5588)
		(drill 0.3048)
		(layers "F.Cu" "B.Cu")
		(net "GND")
	)
	(via
		(at 125.711458 -139.170156)
		(size 0.508)
		(drill 0.254)
		(layers "F.Cu" "B.Cu")
		(net "GND")
	)
	(via
		(at 204.899768 -22.965156)
		(size 0.508)
		(drill 0.254)
		(layers "F.Cu" "B.Cu")
		(net "GND")
	)
	(via
		(at 402.9456 -99.7966)
		(size 0.508)
		(drill 0.254)
		(layers "F.Cu" "B.Cu")
		(net "GND")
	)
	(via
		(at 221.391734 -167.832024)
		(size 0.5588)
		(drill 0.3048)
		(layers "F.Cu" "B.Cu")
		(net "GND")
	)
	(via
		(at 334.269334 -167.832024)
		(size 0.5588)
		(drill 0.3048)
		(layers "F.Cu" "B.Cu")
		(net "GND")
	)
	(via
		(at -4.363466 -164.479224)
		(size 0.5588)
		(drill 0.3048)
		(layers "F.Cu" "B.Cu")
		(net "GND")
	)
	(via
		(at 10.193528 -126.9492)
		(size 0.508)
		(drill 0.254)
		(layers "F.Cu" "B.Cu")
		(net "GND")
	)
	(via
		(at 336.500724 -162.243262)
		(size 0.5588)
		(drill 0.3048)
		(layers "F.Cu" "B.Cu")
		(net "GND")
	)
	(via
		(at 36.301934 9.084056)
		(size 0.5588)
		(drill 0.3048)
		(layers "F.Cu" "B.Cu")
		(net "GND")
	)
	(via
		(at 255.35763 -56.085486)
		(size 0.508)
		(drill 0.254)
		(layers "F.Cu" "B.Cu")
		(net "GND")
	)
	(via
		(at 382.382268 -112.7506)
		(size 0.508)
		(drill 0.254)
		(layers "F.Cu" "B.Cu")
		(net "GND")
	)
	(via
		(at 250.206764 -64.010286)
		(size 0.508)
		(drill 0.254)
		(layers "F.Cu" "B.Cu")
		(net "GND")
	)
	(via
		(at 1.224534 -167.832024)
		(size 0.5588)
		(drill 0.3048)
		(layers "F.Cu" "B.Cu")
		(net "GND")
	)
	(via
		(at 15.749524 -162.243262)
		(size 0.5588)
		(drill 0.3048)
		(layers "F.Cu" "B.Cu")
		(net "GND")
	)
	(via
		(at 45.191934 9.084056)
		(size 0.5588)
		(drill 0.3048)
		(layers "F.Cu" "B.Cu")
		(net "GND")
	)
	(via
		(at 11.6078 -0.01016)
		(size 0.508)
		(drill 0.254)
		(layers "F.Cu" "B.Cu")
		(net "GND")
	)
	(via
		(at 27.3685 -60.63742)
		(size 0.508)
		(drill 0.254)
		(layers "F.Cu" "B.Cu")
		(net "GND")
	)
	(via
		(at 418.6936 -54.3814)
		(size 0.508)
		(drill 0.254)
		(layers "F.Cu" "B.Cu")
		(net "GND")
	)
	(via
		(at 41.510458 -22.939756)
		(size 0.508)
		(drill 0.254)
		(layers "F.Cu" "B.Cu")
		(net "GND")
	)
	(via
		(at 125.651768 -85.622384)
		(size 0.508)
		(drill 0.254)
		(layers "F.Cu" "B.Cu")
		(net "GND")
	)
	(via
		(at 310.122062 -150.219156)
		(size 0.508)
		(drill 0.254)
		(layers "F.Cu" "B.Cu")
		(net "GND")
	)
	(via
		(at 290.6522 -99.490784)
		(size 0.508)
		(drill 0.254)
		(layers "F.Cu" "B.Cu")
		(net "GND")
	)
	(via
		(at 31.39948 -11.916156)
		(size 0.508)
		(drill 0.254)
		(layers "F.Cu" "B.Cu")
		(net "GND")
	)
	(via
		(at 482.7778 -43.93946)
		(size 0.508)
		(drill 0.254)
		(layers "F.Cu" "B.Cu")
		(net "GND")
	)
	(via
		(at 278.95169 -17.29486)
		(size 0.508)
		(drill 0.254)
		(layers "F.Cu" "B.Cu")
		(net "GND")
	)
	(via
		(at 15.981934 9.084056)
		(size 0.5588)
		(drill 0.3048)
		(layers "F.Cu" "B.Cu")
		(net "GND")
	)
	(via
		(at 407.700734 -167.832024)
		(size 0.5588)
		(drill 0.3048)
		(layers "F.Cu" "B.Cu")
		(net "GND")
	)
	(via
		(at 84.347812 -55.59044)
		(size 0.508)
		(drill 0.254)
		(layers "F.Cu" "B.Cu")
		(net "GND")
	)
	(via
		(at 192.773808 -97.5614)
		(size 0.508)
		(drill 0.254)
		(layers "F.Cu" "B.Cu")
		(net "GND")
	)
	(via
		(at 243.149882 -155.3464)
		(size 0.508)
		(drill 0.254)
		(layers "F.Cu" "B.Cu")
		(net "GND")
	)
	(via
		(at 233.151934 14.926056)
		(size 0.5588)
		(drill 0.3048)
		(layers "F.Cu" "B.Cu")
		(net "GND")
	)
	(via
		(at 127.38608 -141.1478)
		(size 0.508)
		(drill 0.254)
		(layers "F.Cu" "B.Cu")
		(net "GND")
	)
	(via
		(at 207.751934 9.084056)
		(size 0.5588)
		(drill 0.3048)
		(layers "F.Cu" "B.Cu")
		(net "GND")
	)
	(via
		(at 53.747924 -162.243262)
		(size 0.5588)
		(drill 0.3048)
		(layers "F.Cu" "B.Cu")
		(net "GND")
	)
	(via
		(at 440.161934 14.926056)
		(size 0.5588)
		(drill 0.3048)
		(layers "F.Cu" "B.Cu")
		(net "GND")
	)
	(via
		(at 398.795748 -123.707906)
		(size 0.508)
		(drill 0.254)
		(layers "F.Cu" "B.Cu")
		(net "GND")
	)
	(via
		(at 81.479136 -51.617626)
		(size 0.4572)
		(drill 0.2032)
		(layers "F.Cu" "B.Cu")
		(net "GND")
	)
	(via
		(at 380.471934 9.084056)
		(size 0.5588)
		(drill 0.3048)
		(layers "F.Cu" "B.Cu")
		(net "GND")
	)
	(via
		(at 342.3158 -140.7414)
		(size 0.508)
		(drill 0.254)
		(layers "F.Cu" "B.Cu")
		(net "GND")
	)
	(via
		(at 167.623744 -92.499434)
		(size 0.508)
		(drill 0.254)
		(layers "F.Cu" "B.Cu")
		(net "GND")
	)
	(via
		(at 120.500902 -99.490784)
		(size 0.508)
		(drill 0.254)
		(layers "F.Cu" "B.Cu")
		(net "GND")
	)
	(via
		(at 259.390134 -167.832024)
		(size 0.5588)
		(drill 0.3048)
		(layers "F.Cu" "B.Cu")
		(net "GND")
	)
	(via
		(at 230.399844 -2.314956)
		(size 0.508)
		(drill 0.254)
		(layers "F.Cu" "B.Cu")
		(net "GND")
	)
	(via
		(at 221.04985 -21.517356)
		(size 0.508)
		(drill 0.254)
		(layers "F.Cu" "B.Cu")
		(net "GND")
	)
	(via
		(at 302.671226 -88.594184)
		(size 0.508)
		(drill 0.254)
		(layers "F.Cu" "B.Cu")
		(net "GND")
	)
	(via
		(at 387.067806 -25.154382)
		(size 0.508)
		(drill 0.254)
		(layers "F.Cu" "B.Cu")
		(net "GND")
	)
	(via
		(at 101.517704 -89.27084)
		(size 0.508)
		(drill 0.254)
		(layers "F.Cu" "B.Cu")
		(net "GND")
	)
	(via
		(at 3.459734 -166.714424)
		(size 0.5588)
		(drill 0.3048)
		(layers "F.Cu" "B.Cu")
		(net "GND")
	)
	(via
		(at 15.3162 -129.1971)
		(size 0.508)
		(drill 0.254)
		(layers "F.Cu" "B.Cu")
		(net "GND")
	)
	(via
		(at 330.454 -118.491)
		(size 0.508)
		(drill 0.254)
		(layers "F.Cu" "B.Cu")
		(net "GND")
	)
	(via
		(at 18.0086 -91.0082)
		(size 0.508)
		(drill 0.254)
		(layers "F.Cu" "B.Cu")
		(net "GND")
	)
	(via
		(at 285.649924 -155.612846)
		(size 0.508)
		(drill 0.254)
		(layers "F.Cu" "B.Cu")
		(net "GND")
	)
	(via
		(at 344.1954 -109.855)
		(size 0.508)
		(drill 0.254)
		(layers "F.Cu" "B.Cu")
		(net "GND")
	)
	(via
		(at 257.07467 -86.794086)
		(size 0.508)
		(drill 0.254)
		(layers "F.Cu" "B.Cu")
		(net "GND")
	)
	(via
		(at 260.731 -146.685)
		(size 0.508)
		(drill 0.254)
		(layers "F.Cu" "B.Cu")
		(net "GND")
	)
	(via
		(at 305.246786 -61.352938)
		(size 0.508)
		(drill 0.254)
		(layers "F.Cu" "B.Cu")
		(net "GND")
	)
	(via
		(at 107.623356 -92.061538)
		(size 0.508)
		(drill 0.254)
		(layers "F.Cu" "B.Cu")
		(net "GND")
	)
	(via
		(at 91.215718 -60.54344)
		(size 0.508)
		(drill 0.254)
		(layers "F.Cu" "B.Cu")
		(net "GND")
	)
	(via
		(at 283.499814 -58.381138)
		(size 0.508)
		(drill 0.254)
		(layers "F.Cu" "B.Cu")
		(net "GND")
	)
	(via
		(at 140.246354 -72.249538)
		(size 0.508)
		(drill 0.254)
		(layers "F.Cu" "B.Cu")
		(net "GND")
	)
	(via
		(at 45.394118 -155.5369)
		(size 0.508)
		(drill 0.254)
		(layers "F.Cu" "B.Cu")
		(net "GND")
	)
	(via
		(at 135.953754 -51.941984)
		(size 0.508)
		(drill 0.254)
		(layers "F.Cu" "B.Cu")
		(net "GND")
	)
	(via
		(at 476.991934 12.894056)
		(size 0.5588)
		(drill 0.3048)
		(layers "F.Cu" "B.Cu")
		(net "GND")
	)
	(via
		(at 327.279 -34.798)
		(size 0.508)
		(drill 0.254)
		(layers "F.Cu" "B.Cu")
		(net "GND")
	)
	(via
		(at 237.329218 -72.43064)
		(size 0.508)
		(drill 0.254)
		(layers "F.Cu" "B.Cu")
		(net "GND")
	)
	(via
		(at 409.103068 -95.28429)
		(size 0.508)
		(drill 0.254)
		(layers "F.Cu" "B.Cu")
		(net "GND")
	)
	(via
		(at 410.1338 -151.638)
		(size 0.508)
		(drill 0.254)
		(layers "F.Cu" "B.Cu")
		(net "GND")
	)
	(via
		(at 35.880802 -100.130864)
		(size 0.508)
		(drill 0.254)
		(layers "F.Cu" "B.Cu")
		(net "GND")
	)
	(via
		(at 172.2628 -78.1812)
		(size 0.508)
		(drill 0.254)
		(layers "F.Cu" "B.Cu")
		(net "GND")
	)
	(via
		(at 136.74217 -18.744946)
		(size 0.508)
		(drill 0.254)
		(layers "F.Cu" "B.Cu")
		(net "GND")
	)
	(via
		(at 131.661408 -80.174338)
		(size 0.508)
		(drill 0.254)
		(layers "F.Cu" "B.Cu")
		(net "GND")
	)
	(via
		(at 297.520106 -62.838584)
		(size 0.508)
		(drill 0.254)
		(layers "F.Cu" "B.Cu")
		(net "GND")
	)
	(via
		(at 228.097334 -167.832024)
		(size 0.5588)
		(drill 0.3048)
		(layers "F.Cu" "B.Cu")
		(net "GND")
	)
	(via
		(at 367.754408 -146.224498)
		(size 0.508)
		(drill 0.254)
		(layers "F.Cu" "B.Cu")
		(net "GND")
	)
	(via
		(at 367.03 -110.998)
		(size 0.508)
		(drill 0.254)
		(layers "F.Cu" "B.Cu")
		(net "GND")
	)
	(via
		(at 238.231934 9.084056)
		(size 0.5588)
		(drill 0.3048)
		(layers "F.Cu" "B.Cu")
		(net "GND")
	)
	(via
		(at 372.897654 -145.786602)
		(size 0.508)
		(drill 0.254)
		(layers "F.Cu" "B.Cu")
		(net "GND")
	)
	(via
		(at 146.508724 -162.243262)
		(size 0.5588)
		(drill 0.3048)
		(layers "F.Cu" "B.Cu")
		(net "GND")
	)
	(via
		(at 94.783148 -79.3496)
		(size 0.508)
		(drill 0.254)
		(layers "F.Cu" "B.Cu")
		(net "GND")
	)
	(via
		(at 243.338604 -54.104286)
		(size 0.508)
		(drill 0.254)
		(layers "F.Cu" "B.Cu")
		(net "GND")
	)
	(via
		(at 2.16662 -24.08936)
		(size 0.508)
		(drill 0.254)
		(layers "F.Cu" "B.Cu")
		(net "GND")
	)
	(via
		(at 134.236714 -55.904384)
		(size 0.508)
		(drill 0.254)
		(layers "F.Cu" "B.Cu")
		(net "GND")
	)
	(via
		(at 335.1022 -133.4643)
		(size 0.508)
		(drill 0.254)
		(layers "F.Cu" "B.Cu")
		(net "GND")
	)
	(via
		(at 461.751934 13.910056)
		(size 0.5588)
		(drill 0.3048)
		(layers "F.Cu" "B.Cu")
		(net "GND")
	)
	(via
		(at 32.494728 -108.857034)
		(size 0.5588)
		(drill 0.3048)
		(layers "F.Cu" "B.Cu")
		(net "GND")
	)
	(via
		(at 293.681912 -129.5654)
		(size 0.508)
		(drill 0.254)
		(layers "F.Cu" "B.Cu")
		(net "GND")
	)
	(via
		(at 426.750734 -165.596824)
		(size 0.5588)
		(drill 0.3048)
		(layers "F.Cu" "B.Cu")
		(net "GND")
	)
	(via
		(at 149.549358 1.994154)
		(size 0.508)
		(drill 0.254)
		(layers "F.Cu" "B.Cu")
		(net "GND")
	)
	(via
		(at 96.366838 -91.25204)
		(size 0.508)
		(drill 0.254)
		(layers "F.Cu" "B.Cu")
		(net "GND")
	)
	(via
		(at 119.331232 -139.1666)
		(size 0.508)
		(drill 0.254)
		(layers "F.Cu" "B.Cu")
		(net "GND")
	)
	(via
		(at 464.291934 9.084056)
		(size 0.5588)
		(drill 0.3048)
		(layers "F.Cu" "B.Cu")
		(net "GND")
	)
	(via
		(at 72.328786 -94.223586)
		(size 0.508)
		(drill 0.254)
		(layers "F.Cu" "B.Cu")
		(net "GND")
	)
	(via
		(at 476.933514 -0.423672)
		(size 0.5588)
		(drill 0.3048)
		(layers "F.Cu" "B.Cu")
		(net "GND")
	)
	(via
		(at 203.199746 -144.462246)
		(size 0.508)
		(drill 0.254)
		(layers "F.Cu" "B.Cu")
		(net "GND")
	)
	(via
		(at 113.866168 -8.1026)
		(size 0.508)
		(drill 0.254)
		(layers "F.Cu" "B.Cu")
		(net "GND")
	)
	(via
		(at 49.277524 -162.243262)
		(size 0.5588)
		(drill 0.3048)
		(layers "F.Cu" "B.Cu")
		(net "GND")
	)
	(via
		(at 136.74217 -9.143746)
		(size 0.508)
		(drill 0.254)
		(layers "F.Cu" "B.Cu")
		(net "GND")
	)
	(via
		(at 181.154324 -162.243262)
		(size 0.5588)
		(drill 0.3048)
		(layers "F.Cu" "B.Cu")
		(net "GND")
	)
	(via
		(at 5.09905 -107.9119)
		(size 0.508)
		(drill 0.254)
		(layers "F.Cu" "B.Cu")
		(net "GND")
	)
	(via
		(at 309.922418 -49.379378)
		(size 0.508)
		(drill 0.254)
		(layers "F.Cu" "B.Cu")
		(net "GND")
	)
	(via
		(at 402.134832 -104.85501)
		(size 0.508)
		(drill 0.254)
		(layers "F.Cu" "B.Cu")
		(net "GND")
	)
	(via
		(at 292.36924 -92.556584)
		(size 0.508)
		(drill 0.254)
		(layers "F.Cu" "B.Cu")
		(net "GND")
	)
	(via
		(at 247.631204 -56.58104)
		(size 0.508)
		(drill 0.254)
		(layers "F.Cu" "B.Cu")
		(net "GND")
	)
	(via
		(at 379.31725 -117.811804)
		(size 0.508)
		(drill 0.254)
		(layers "F.Cu" "B.Cu")
		(net "GND")
	)
	(via
		(at 89.498678 -85.30844)
		(size 0.508)
		(drill 0.254)
		(layers "F.Cu" "B.Cu")
		(net "GND")
	)
	(via
		(at 95.730568 -146.685)
		(size 0.508)
		(drill 0.254)
		(layers "F.Cu" "B.Cu")
		(net "GND")
	)
	(via
		(at 401.859496 -96.815656)
		(size 0.508)
		(drill 0.254)
		(layers "F.Cu" "B.Cu")
		(net "GND")
	)
	(via
		(at 44.810934 -167.832024)
		(size 0.5588)
		(drill 0.3048)
		(layers "F.Cu" "B.Cu")
		(net "GND")
	)
	(via
		(at 271.251934 14.926056)
		(size 0.5588)
		(drill 0.3048)
		(layers "F.Cu" "B.Cu")
		(net "GND")
	)
	(via
		(at 214.0204 -92.202)
		(size 0.508)
		(drill 0.254)
		(layers "F.Cu" "B.Cu")
		(net "GND")
	)
	(via
		(at 301.812706 -72.249538)
		(size 0.508)
		(drill 0.254)
		(layers "F.Cu" "B.Cu")
		(net "GND")
	)
	(via
		(at 293.681912 -21.5138)
		(size 0.508)
		(drill 0.254)
		(layers "F.Cu" "B.Cu")
		(net "GND")
	)
	(via
		(at 116.208302 -91.070938)
		(size 0.508)
		(drill 0.254)
		(layers "F.Cu" "B.Cu")
		(net "GND")
	)
	(via
		(at 452.5518 -53.2638)
		(size 0.508)
		(drill 0.254)
		(layers "F.Cu" "B.Cu")
		(net "GND")
	)
	(via
		(at 485.267 -110.6424)
		(size 0.508)
		(drill 0.254)
		(layers "F.Cu" "B.Cu")
		(net "GND")
	)
	(via
		(at 41.501314 -7.607046)
		(size 0.508)
		(drill 0.254)
		(layers "F.Cu" "B.Cu")
		(net "GND")
	)
	(via
		(at 380.30785 -101.898196)
		(size 0.508)
		(drill 0.254)
		(layers "F.Cu" "B.Cu")
		(net "GND")
	)
	(via
		(at 479.861372 -11.05662)
		(size 0.508)
		(drill 0.254)
		(layers "F.Cu" "B.Cu")
		(net "GND")
	)
	(via
		(at 196.321934 9.084056)
		(size 0.5588)
		(drill 0.3048)
		(layers "F.Cu" "B.Cu")
		(net "GND")
	)
	(via
		(at 396.15745 -105.332276)
		(size 0.508)
		(drill 0.254)
		(layers "F.Cu" "B.Cu")
		(net "GND")
	)
	(via
		(at 141.049502 -18.757646)
		(size 0.508)
		(drill 0.254)
		(layers "F.Cu" "B.Cu")
		(net "GND")
	)
	(via
		(at 280.350214 -96.518984)
		(size 0.508)
		(drill 0.254)
		(layers "F.Cu" "B.Cu")
		(net "GND")
	)
	(via
		(at 345.567 -145.9738)
		(size 0.508)
		(drill 0.254)
		(layers "F.Cu" "B.Cu")
		(net "GND")
	)
	(via
		(at 348.9579 -30.5943)
		(size 0.508)
		(drill 0.254)
		(layers "F.Cu" "B.Cu")
		(net "GND")
	)
	(via
		(at 331.816202 -43.161712)
		(size 0.508)
		(drill 0.254)
		(layers "F.Cu" "B.Cu")
		(net "GND")
	)
	(via
		(at 26.896568 -2.2098)
		(size 0.508)
		(drill 0.254)
		(layers "F.Cu" "B.Cu")
		(net "GND")
	)
	(via
		(at 273.197828 -55.409338)
		(size 0.508)
		(drill 0.254)
		(layers "F.Cu" "B.Cu")
		(net "GND")
	)
	(via
		(at 498.5512 -36.4998)
		(size 0.508)
		(drill 0.254)
		(layers "F.Cu" "B.Cu")
		(net "GND")
	)
	(via
		(at 120.649492 -136.410446)
		(size 0.508)
		(drill 0.254)
		(layers "F.Cu" "B.Cu")
		(net "GND")
	)
	(via
		(at 345.063572 -137.178542)
		(size 0.508)
		(drill 0.254)
		(layers "F.Cu" "B.Cu")
		(net "GND")
	)
	(via
		(at 42.680382 -70.237858)
		(size 0.5588)
		(drill 0.3048)
		(layers "F.Cu" "B.Cu")
		(net "GND")
	)
	(via
		(at 136.631934 9.084056)
		(size 0.5588)
		(drill 0.3048)
		(layers "F.Cu" "B.Cu")
		(net "GND")
	)
	(via
		(at 431.7746 -130.1242)
		(size 0.508)
		(drill 0.254)
		(layers "F.Cu" "B.Cu")
		(net "GND")
	)
	(via
		(at 74.904346 -94.718886)
		(size 0.508)
		(drill 0.254)
		(layers "F.Cu" "B.Cu")
		(net "GND")
	)
	(via
		(at 209.09915 -153.6065)
		(size 0.508)
		(drill 0.254)
		(layers "F.Cu" "B.Cu")
		(net "GND")
	)
	(via
		(at 342.371934 9.084056)
		(size 0.5588)
		(drill 0.3048)
		(layers "F.Cu" "B.Cu")
		(net "GND")
	)
	(via
		(at 233.036618 -83.822286)
		(size 0.508)
		(drill 0.254)
		(layers "F.Cu" "B.Cu")
		(net "GND")
	)
	(via
		(at 213.7156 -61.7982)
		(size 0.508)
		(drill 0.254)
		(layers "F.Cu" "B.Cu")
		(net "GND")
	)
	(via
		(at 282.925774 -99.986338)
		(size 0.508)
		(drill 0.254)
		(layers "F.Cu" "B.Cu")
		(net "GND")
	)
	(via
		(at 425.6532 -1.0414)
		(size 0.508)
		(drill 0.254)
		(layers "F.Cu" "B.Cu")
		(net "GND")
	)
	(via
		(at 236.171994 -27.821636)
		(size 0.508)
		(drill 0.254)
		(layers "F.Cu" "B.Cu")
		(net "GND")
	)
	(via
		(at 24.871934 9.084056)
		(size 0.5588)
		(drill 0.3048)
		(layers "F.Cu" "B.Cu")
		(net "GND")
	)
	(via
		(at 310.122062 -3.762756)
		(size 0.508)
		(drill 0.254)
		(layers "F.Cu" "B.Cu")
		(net "GND")
	)
	(via
		(at 187.431934 9.084056)
		(size 0.5588)
		(drill 0.3048)
		(layers "F.Cu" "B.Cu")
		(net "GND")
	)
	(via
		(at 372.719854 -104.535478)
		(size 0.508)
		(drill 0.254)
		(layers "F.Cu" "B.Cu")
		(net "GND")
	)
	(via
		(at 286.3596 -91.070938)
		(size 0.508)
		(drill 0.254)
		(layers "F.Cu" "B.Cu")
		(net "GND")
	)
	(via
		(at 333.825088 -127.254)
		(size 0.508)
		(drill 0.254)
		(layers "F.Cu" "B.Cu")
		(net "GND")
	)
	(via
		(at 62.792102 -155.600146)
		(size 0.508)
		(drill 0.254)
		(layers "F.Cu" "B.Cu")
		(net "GND")
	)
	(via
		(at 94.1451 -79.360014)
		(size 0.508)
		(drill 0.254)
		(layers "F.Cu" "B.Cu")
		(net "GND")
	)
	(via
		(at 233.036618 -66.982086)
		(size 0.508)
		(drill 0.254)
		(layers "F.Cu" "B.Cu")
		(net "GND")
	)
	(via
		(at 104.621076 -82.339942)
		(size 0.5588)
		(drill 0.3048)
		(layers "F.Cu" "B.Cu")
		(net "GND")
	)
	(via
		(at 474.505528 -1.429004)
		(size 0.5588)
		(drill 0.3048)
		(layers "F.Cu" "B.Cu")
		(net "GND")
	)
	(via
		(at 98.531934 14.926056)
		(size 0.5588)
		(drill 0.3048)
		(layers "F.Cu" "B.Cu")
		(net "GND")
	)
	(via
		(at 188.695838 -58.311542)
		(size 0.508)
		(drill 0.254)
		(layers "F.Cu" "B.Cu")
		(net "GND")
	)
	(via
		(at 492.506 -121.7676)
		(size 0.508)
		(drill 0.254)
		(layers "F.Cu" "B.Cu")
		(net "GND")
	)
	(via
		(at 98.652076 -82.339942)
		(size 0.5588)
		(drill 0.3048)
		(layers "F.Cu" "B.Cu")
		(net "GND")
	)
	(via
		(at 125.749558 -9.156446)
		(size 0.508)
		(drill 0.254)
		(layers "F.Cu" "B.Cu")
		(net "GND")
	)
	(via
		(at 200.525634 -57.846468)
		(size 0.508)
		(drill 0.254)
		(layers "F.Cu" "B.Cu")
		(net "GND")
	)
	(via
		(at 135.095234 -81.164938)
		(size 0.508)
		(drill 0.254)
		(layers "F.Cu" "B.Cu")
		(net "GND")
	)
	(via
		(at 345.18346 -104.40416)
		(size 0.508)
		(drill 0.254)
		(layers "F.Cu" "B.Cu")
		(net "GND")
	)
	(via
		(at 446.659 -125.4252)
		(size 0.508)
		(drill 0.254)
		(layers "F.Cu" "B.Cu")
		(net "GND")
	)
	(via
		(at 287.79216 -65.810384)
		(size 0.508)
		(drill 0.254)
		(layers "F.Cu" "B.Cu")
		(net "GND")
	)
	(via
		(at 386.286502 -152.021032)
		(size 0.508)
		(drill 0.254)
		(layers "F.Cu" "B.Cu")
		(net "GND")
	)
	(via
		(at 98.083878 -91.25204)
		(size 0.508)
		(drill 0.254)
		(layers "F.Cu" "B.Cu")
		(net "GND")
	)
	(via
		(at 130.74777 -124.725176)
		(size 0.508)
		(drill 0.254)
		(layers "F.Cu" "B.Cu")
		(net "GND")
	)
	(via
		(at 135.099552 -136.410446)
		(size 0.508)
		(drill 0.254)
		(layers "F.Cu" "B.Cu")
		(net "GND")
	)
	(via
		(at 92.181934 14.926056)
		(size 0.5588)
		(drill 0.3048)
		(layers "F.Cu" "B.Cu")
		(net "GND")
	)
	(via
		(at 445.6684 -27.7368)
		(size 0.508)
		(drill 0.254)
		(layers "F.Cu" "B.Cu")
		(net "GND")
	)
	(via
		(at 129.085848 -68.782184)
		(size 0.508)
		(drill 0.254)
		(layers "F.Cu" "B.Cu")
		(net "GND")
	)
	(via
		(at 182.8546 -68.4022)
		(size 0.508)
		(drill 0.254)
		(layers "F.Cu" "B.Cu")
		(net "GND")
	)
	(via
		(at 113.348262 -65.315338)
		(size 0.508)
		(drill 0.254)
		(layers "F.Cu" "B.Cu")
		(net "GND")
	)
	(via
		(at 169.951146 -145.667222)
		(size 0.508)
		(drill 0.254)
		(layers "F.Cu" "B.Cu")
		(net "GND")
	)
	(via
		(at 34.932366 -101.675184)
		(size 0.5588)
		(drill 0.3048)
		(layers "F.Cu" "B.Cu")
		(net "GND")
	)
	(via
		(at 239.046258 -91.25204)
		(size 0.508)
		(drill 0.254)
		(layers "F.Cu" "B.Cu")
		(net "GND")
	)
	(via
		(at 203.199746 -7.607046)
		(size 0.508)
		(drill 0.254)
		(layers "F.Cu" "B.Cu")
		(net "GND")
	)
	(via
		(at 453.771 -142.7988)
		(size 0.508)
		(drill 0.254)
		(layers "F.Cu" "B.Cu")
		(net "GND")
	)
	(via
		(at 13.589 -78.0542)
		(size 0.508)
		(drill 0.254)
		(layers "F.Cu" "B.Cu")
		(net "GND")
	)
	(via
		(at 275.111464 -140.208)
		(size 0.508)
		(drill 0.254)
		(layers "F.Cu" "B.Cu")
		(net "GND")
	)
	(via
		(at 242.480338 -74.411586)
		(size 0.508)
		(drill 0.254)
		(layers "F.Cu" "B.Cu")
		(net "GND")
	)
	(via
		(at 305.199796 -140.617956)
		(size 0.508)
		(drill 0.254)
		(layers "F.Cu" "B.Cu")
		(net "GND")
	)
	(via
		(at 43.12158 -140.605256)
		(size 0.508)
		(drill 0.254)
		(layers "F.Cu" "B.Cu")
		(net "GND")
	)
	(via
		(at 92.074238 -95.709486)
		(size 0.508)
		(drill 0.254)
		(layers "F.Cu" "B.Cu")
		(net "GND")
	)
	(via
		(at 121.933208 -54.418738)
		(size 0.508)
		(drill 0.254)
		(layers "F.Cu" "B.Cu")
		(net "GND")
	)
	(via
		(at 357.376222 -142.327122)
		(size 0.508)
		(drill 0.254)
		(layers "F.Cu" "B.Cu")
		(net "GND")
	)
	(via
		(at 362.691934 14.926056)
		(size 0.5588)
		(drill 0.3048)
		(layers "F.Cu" "B.Cu")
		(net "GND")
	)
	(via
		(at 443.405006 -40.5257)
		(size 0.508)
		(drill 0.254)
		(layers "F.Cu" "B.Cu")
		(net "GND")
	)
	(via
		(at 292.36924 -71.753984)
		(size 0.508)
		(drill 0.254)
		(layers "F.Cu" "B.Cu")
		(net "GND")
	)
	(via
		(at 283.499814 -55.409338)
		(size 0.508)
		(drill 0.254)
		(layers "F.Cu" "B.Cu")
		(net "GND")
	)
	(via
		(at 408.290014 -30.13456)
		(size 0.4572)
		(drill 0.2032)
		(layers "F.Cu" "B.Cu")
		(net "GND")
	)
	(via
		(at 228.071934 9.084056)
		(size 0.5588)
		(drill 0.3048)
		(layers "F.Cu" "B.Cu")
		(net "GND")
	)
	(via
		(at 86.923372 -84.812886)
		(size 0.508)
		(drill 0.254)
		(layers "F.Cu" "B.Cu")
		(net "GND")
	)
	(via
		(at 222.749872 -146.011646)
		(size 0.508)
		(drill 0.254)
		(layers "F.Cu" "B.Cu")
		(net "GND")
	)
	(via
		(at 458.574394 -15.118588)
		(size 0.5588)
		(drill 0.3048)
		(layers "F.Cu" "B.Cu")
		(net "GND")
	)
	(via
		(at 285.649924 -139.170156)
		(size 0.508)
		(drill 0.254)
		(layers "F.Cu" "B.Cu")
		(net "GND")
	)
	(via
		(at 253.471934 9.084056)
		(size 0.5588)
		(drill 0.3048)
		(layers "F.Cu" "B.Cu")
		(net "GND")
	)
	(via
		(at 67.104768 -125.9332)
		(size 0.508)
		(drill 0.254)
		(layers "F.Cu" "B.Cu")
		(net "GND")
	)
	(via
		(at 129.999486 -129.568956)
		(size 0.508)
		(drill 0.254)
		(layers "F.Cu" "B.Cu")
		(net "GND")
	)
	(via
		(at 6.5786 -10.2362)
		(size 0.508)
		(drill 0.254)
		(layers "F.Cu" "B.Cu")
		(net "GND")
	)
	(via
		(at 359.151682 -77.37983)
		(size 0.508)
		(drill 0.254)
		(layers "F.Cu" "B.Cu")
		(net "GND")
	)
	(via
		(at 70.461378 -21.517356)
		(size 0.508)
		(drill 0.254)
		(layers "F.Cu" "B.Cu")
		(net "GND")
	)
	(via
		(at 74.045826 -72.43064)
		(size 0.508)
		(drill 0.254)
		(layers "F.Cu" "B.Cu")
		(net "GND")
	)
	(via
		(at 489.691934 11.624056)
		(size 0.5588)
		(drill 0.3048)
		(layers "F.Cu" "B.Cu")
		(net "GND")
	)
	(via
		(at 346.5576 -59.679586)
		(size 0.508)
		(drill 0.254)
		(layers "F.Cu" "B.Cu")
		(net "GND")
	)
	(via
		(at 492.790734 -165.596824)
		(size 0.5588)
		(drill 0.3048)
		(layers "F.Cu" "B.Cu")
		(net "GND")
	)
	(via
		(at 164.543486 -29.494734)
		(size 0.508)
		(drill 0.254)
		(layers "F.Cu" "B.Cu")
		(net "GND")
	)
	(via
		(at 81.772252 -65.000886)
		(size 0.508)
		(drill 0.254)
		(layers "F.Cu" "B.Cu")
		(net "GND")
	)
	(via
		(at 408.970734 -167.832024)
		(size 0.5588)
		(drill 0.3048)
		(layers "F.Cu" "B.Cu")
		(net "GND")
	)
	(via
		(at 212.450934 -167.832024)
		(size 0.5588)
		(drill 0.3048)
		(layers "F.Cu" "B.Cu")
		(net "GND")
	)
	(via
		(at 307.8988 -84.631784)
		(size 0.508)
		(drill 0.254)
		(layers "F.Cu" "B.Cu")
		(net "GND")
	)
	(via
		(at 218.449144 -153.6065)
		(size 0.508)
		(drill 0.254)
		(layers "F.Cu" "B.Cu")
		(net "GND")
	)
	(via
		(at 127.368808 -89.584784)
		(size 0.508)
		(drill 0.254)
		(layers "F.Cu" "B.Cu")
		(net "GND")
	)
	(via
		(at 200.527412 -80.180434)
		(size 0.508)
		(drill 0.254)
		(layers "F.Cu" "B.Cu")
		(net "GND")
	)
	(via
		(at 136.812274 -73.240138)
		(size 0.508)
		(drill 0.254)
		(layers "F.Cu" "B.Cu")
		(net "GND")
	)
	(via
		(at 253.471934 14.926056)
		(size 0.5588)
		(drill 0.3048)
		(layers "F.Cu" "B.Cu")
		(net "GND")
	)
	(via
		(at 81.772252 -91.747086)
		(size 0.508)
		(drill 0.254)
		(layers "F.Cu" "B.Cu")
		(net "GND")
	)
	(via
		(at 17.19834 -102.11816)
		(size 0.508)
		(drill 0.254)
		(layers "F.Cu" "B.Cu")
		(net "GND")
	)
	(via
		(at 460.481934 13.910056)
		(size 0.5588)
		(drill 0.3048)
		(layers "F.Cu" "B.Cu")
		(net "GND")
	)
	(via
		(at 311.092596 -21.513292)
		(size 0.508)
		(drill 0.254)
		(layers "F.Cu" "B.Cu")
		(net "GND")
	)
	(via
		(at 198.061834 -21.517356)
		(size 0.508)
		(drill 0.254)
		(layers "F.Cu" "B.Cu")
		(net "GND")
	)
	(via
		(at 74.045826 -56.58104)
		(size 0.508)
		(drill 0.254)
		(layers "F.Cu" "B.Cu")
		(net "GND")
	)
	(via
		(at 291.571934 9.084056)
		(size 0.5588)
		(drill 0.3048)
		(layers "F.Cu" "B.Cu")
		(net "GND")
	)
	(via
		(at 479.50882 -25.965658)
		(size 0.508)
		(drill 0.254)
		(layers "F.Cu" "B.Cu")
		(net "GND")
	)
	(via
		(at 204.478128 -60.198)
		(size 0.5588)
		(drill 0.3048)
		(layers "F.Cu" "B.Cu")
		(net "GND")
	)
	(via
		(at 449.827142 -45.611796)
		(size 0.508)
		(drill 0.254)
		(layers "F.Cu" "B.Cu")
		(net "GND")
	)
	(via
		(at 315.266324 -162.243262)
		(size 0.5588)
		(drill 0.3048)
		(layers "F.Cu" "B.Cu")
		(net "GND")
	)
	(via
		(at 54.744112 -18.6817)
		(size 0.508)
		(drill 0.254)
		(layers "F.Cu" "B.Cu")
		(net "GND")
	)
	(via
		(at 400.791934 9.084056)
		(size 0.5588)
		(drill 0.3048)
		(layers "F.Cu" "B.Cu")
		(net "GND")
	)
	(via
		(at 197.151752 -134.861046)
		(size 0.508)
		(drill 0.254)
		(layers "F.Cu" "B.Cu")
		(net "GND")
	)
	(via
		(at 38.2778 -70.3072)
		(size 0.5588)
		(drill 0.3048)
		(layers "F.Cu" "B.Cu")
		(net "GND")
	)
	(via
		(at 35.880802 -54.664864)
		(size 0.508)
		(drill 0.254)
		(layers "F.Cu" "B.Cu")
		(net "GND")
	)
	(via
		(at 292.36924 -96.518984)
		(size 0.508)
		(drill 0.254)
		(layers "F.Cu" "B.Cu")
		(net "GND")
	)
	(via
		(at 351.8154 -41.91)
		(size 0.508)
		(drill 0.254)
		(layers "F.Cu" "B.Cu")
		(net "GND")
	)
	(via
		(at 18.697194 -0.294132)
		(size 0.508)
		(drill 0.254)
		(layers "F.Cu" "B.Cu")
		(net "GND")
	)
	(via
		(at 118.499382 -55.409338)
		(size 0.508)
		(drill 0.254)
		(layers "F.Cu" "B.Cu")
		(net "GND")
	)
	(via
		(at 42.11955 -60.183522)
		(size 0.5588)
		(drill 0.3048)
		(layers "F.Cu" "B.Cu")
		(net "GND")
	)
	(via
		(at 147.381468 -148.7678)
		(size 0.508)
		(drill 0.254)
		(layers "F.Cu" "B.Cu")
		(net "GND")
	)
	(via
		(at 419.130734 -163.361624)
		(size 0.5588)
		(drill 0.3048)
		(layers "F.Cu" "B.Cu")
		(net "GND")
	)
	(via
		(at 288.93516 -78.688438)
		(size 0.508)
		(drill 0.254)
		(layers "F.Cu" "B.Cu")
		(net "GND")
	)
	(via
		(at 74.749406 -18.757646)
		(size 0.508)
		(drill 0.254)
		(layers "F.Cu" "B.Cu")
		(net "GND")
	)
	(via
		(at 137.571734 -167.832024)
		(size 0.5588)
		(drill 0.3048)
		(layers "F.Cu" "B.Cu")
		(net "GND")
	)
	(via
		(at 340.3854 -38.1)
		(size 0.508)
		(drill 0.254)
		(layers "F.Cu" "B.Cu")
		(net "GND")
	)
	(via
		(at 375.743724 -162.268662)
		(size 0.5588)
		(drill 0.3048)
		(layers "F.Cu" "B.Cu")
		(net "GND")
	)
	(via
		(at 56.049418 -21.517356)
		(size 0.508)
		(drill 0.254)
		(layers "F.Cu" "B.Cu")
		(net "GND")
	)
	(via
		(at 142.042134 -167.832024)
		(size 0.5588)
		(drill 0.3048)
		(layers "F.Cu" "B.Cu")
		(net "GND")
	)
	(via
		(at 178.922934 -167.832024)
		(size 0.5588)
		(drill 0.3048)
		(layers "F.Cu" "B.Cu")
		(net "GND")
	)
	(via
		(at 139.387834 -53.923184)
		(size 0.508)
		(drill 0.254)
		(layers "F.Cu" "B.Cu")
		(net "GND")
	)
	(via
		(at 134.160514 -150.193756)
		(size 0.508)
		(drill 0.254)
		(layers "F.Cu" "B.Cu")
		(net "GND")
	)
	(via
		(at 15.291308 -125.816868)
		(size 0.508)
		(drill 0.254)
		(layers "F.Cu" "B.Cu")
		(net "GND")
	)
	(via
		(at 257.07467 -56.085486)
		(size 0.508)
		(drill 0.254)
		(layers "F.Cu" "B.Cu")
		(net "GND")
	)
	(via
		(at 306.049934 -11.916156)
		(size 0.508)
		(drill 0.254)
		(layers "F.Cu" "B.Cu")
		(net "GND")
	)
	(via
		(at 428.117 -0.762)
		(size 0.508)
		(drill 0.254)
		(layers "F.Cu" "B.Cu")
		(net "GND")
	)
	(via
		(at 80.055212 -61.038486)
		(size 0.508)
		(drill 0.254)
		(layers "F.Cu" "B.Cu")
		(net "GND")
	)
	(via
		(at 296.69994 -155.612846)
		(size 0.508)
		(drill 0.254)
		(layers "F.Cu" "B.Cu")
		(net "GND")
	)
	(via
		(at 359.141522 -78.899512)
		(size 0.508)
		(drill 0.254)
		(layers "F.Cu" "B.Cu")
		(net "GND")
	)
	(via
		(at 108.691934 14.926056)
		(size 0.5588)
		(drill 0.3048)
		(layers "F.Cu" "B.Cu")
		(net "GND")
	)
	(via
		(at 130.84937 -144.462246)
		(size 0.508)
		(drill 0.254)
		(layers "F.Cu" "B.Cu")
		(net "GND")
	)
	(via
		(at 371.094 -158.3436)
		(size 0.508)
		(drill 0.254)
		(layers "F.Cu" "B.Cu")
		(net "GND")
	)
	(via
		(at 435.640734 -167.832024)
		(size 0.5588)
		(drill 0.3048)
		(layers "F.Cu" "B.Cu")
		(net "GND")
	)
	(via
		(at 348.5896 -9.59739)
		(size 0.508)
		(drill 0.254)
		(layers "F.Cu" "B.Cu")
		(net "GND")
	)
	(via
		(at 53.442108 0.457454)
		(size 0.508)
		(drill 0.254)
		(layers "F.Cu" "B.Cu")
		(net "GND")
	)
	(via
		(at 227.799138 -7.1501)
		(size 0.508)
		(drill 0.254)
		(layers "F.Cu" "B.Cu")
		(net "GND")
	)
	(via
		(at 10.97026 -151.99614)
		(size 0.508)
		(drill 0.254)
		(layers "F.Cu" "B.Cu")
		(net "GND")
	)
	(via
		(at 122.217688 -91.565984)
		(size 0.508)
		(drill 0.254)
		(layers "F.Cu" "B.Cu")
		(net "GND")
	)
	(via
		(at 163.449 -69.154548)
		(size 0.508)
		(drill 0.254)
		(layers "F.Cu" "B.Cu")
		(net "GND")
	)
	(via
		(at 336.169 -17.272)
		(size 0.508)
		(drill 0.254)
		(layers "F.Cu" "B.Cu")
		(net "GND")
	)
	(via
		(at 181.3306 -87.7062)
		(size 0.508)
		(drill 0.254)
		(layers "F.Cu" "B.Cu")
		(net "GND")
	)
	(via
		(at 31.893002 -96.168464)
		(size 0.508)
		(drill 0.254)
		(layers "F.Cu" "B.Cu")
		(net "GND")
	)
	(via
		(at 303.529746 -90.080338)
		(size 0.508)
		(drill 0.254)
		(layers "F.Cu" "B.Cu")
		(net "GND")
	)
	(via
		(at 107.051856 -50.694082)
		(size 0.508)
		(drill 0.254)
		(layers "F.Cu" "B.Cu")
		(net "GND")
	)
	(via
		(at 455.676 -144.4752)
		(size 0.508)
		(drill 0.254)
		(layers "F.Cu" "B.Cu")
		(net "GND")
	)
	(via
		(at 178.943 -6.6802)
		(size 0.508)
		(drill 0.254)
		(layers "F.Cu" "B.Cu")
		(net "GND")
	)
	(via
		(at 290.6522 -90.575384)
		(size 0.508)
		(drill 0.254)
		(layers "F.Cu" "B.Cu")
		(net "GND")
	)
	(via
		(at 32.513524 -162.243262)
		(size 0.5588)
		(drill 0.3048)
		(layers "F.Cu" "B.Cu")
		(net "GND")
	)
	(via
		(at 138.529314 -75.221338)
		(size 0.508)
		(drill 0.254)
		(layers "F.Cu" "B.Cu")
		(net "GND")
	)
	(via
		(at 236.171994 -124.623576)
		(size 0.508)
		(drill 0.254)
		(layers "F.Cu" "B.Cu")
		(net "GND")
	)
	(via
		(at 218.44254 -136.397746)
		(size 0.508)
		(drill 0.254)
		(layers "F.Cu" "B.Cu")
		(net "GND")
	)
	(via
		(at 349.645224 -156.402024)
		(size 0.508)
		(drill 0.254)
		(layers "F.Cu" "B.Cu")
		(net "GND")
	)
	(via
		(at 407.9748 -123.7234)
		(size 0.508)
		(drill 0.254)
		(layers "F.Cu" "B.Cu")
		(net "GND")
	)
	(via
		(at 248.489724 -82.83194)
		(size 0.508)
		(drill 0.254)
		(layers "F.Cu" "B.Cu")
		(net "GND")
	)
	(via
		(at 428.731934 12.894056)
		(size 0.5588)
		(drill 0.3048)
		(layers "F.Cu" "B.Cu")
		(net "GND")
	)
	(via
		(at 220.451934 14.926056)
		(size 0.5588)
		(drill 0.3048)
		(layers "F.Cu" "B.Cu")
		(net "GND")
	)
	(via
		(at 150.399496 0.444754)
		(size 0.508)
		(drill 0.254)
		(layers "F.Cu" "B.Cu")
		(net "GND")
	)
	(via
		(at 416.179 -24.511)
		(size 0.508)
		(drill 0.254)
		(layers "F.Cu" "B.Cu")
		(net "GND")
	)
	(via
		(at 251.923804 -67.972686)
		(size 0.508)
		(drill 0.254)
		(layers "F.Cu" "B.Cu")
		(net "GND")
	)
	(via
		(at 290.6522 -59.866784)
		(size 0.508)
		(drill 0.254)
		(layers "F.Cu" "B.Cu")
		(net "GND")
	)
	(via
		(at 186.040268 -134.4422)
		(size 0.508)
		(drill 0.254)
		(layers "F.Cu" "B.Cu")
		(net "GND")
	)
	(via
		(at 481.151946 -141.67866)
		(size 0.508)
		(drill 0.254)
		(layers "F.Cu" "B.Cu")
		(net "GND")
	)
	(via
		(at 315.399928 -148.771356)
		(size 0.508)
		(drill 0.254)
		(layers "F.Cu" "B.Cu")
		(net "GND")
	)
	(via
		(at 490.246924 -162.243262)
		(size 0.5588)
		(drill 0.3048)
		(layers "F.Cu" "B.Cu")
		(net "GND")
	)
	(via
		(at 146.092164 -21.513292)
		(size 0.508)
		(drill 0.254)
		(layers "F.Cu" "B.Cu")
		(net "GND")
	)
	(via
		(at 178.784504 -105.397046)
		(size 0.508)
		(drill 0.254)
		(layers "F.Cu" "B.Cu")
		(net "GND")
	)
	(via
		(at 282.104592 -70.332346)
		(size 0.508)
		(drill 0.254)
		(layers "F.Cu" "B.Cu")
		(net "GND")
	)
	(via
		(at 154.331924 -162.243262)
		(size 0.5588)
		(drill 0.3048)
		(layers "F.Cu" "B.Cu")
		(net "GND")
	)
	(via
		(at -3.463544 10.281666)
		(size 0.5588)
		(drill 0.3048)
		(layers "F.Cu" "B.Cu")
		(net "GND")
	)
	(via
		(at 402.062442 -9.452864)
		(size 0.508)
		(drill 0.254)
		(layers "F.Cu" "B.Cu")
		(net "GND")
	)
	(via
		(at 304.271934 14.926056)
		(size 0.5588)
		(drill 0.3048)
		(layers "F.Cu" "B.Cu")
		(net "GND")
	)
	(via
		(at 184.7596 -145.1102)
		(size 0.508)
		(drill 0.254)
		(layers "F.Cu" "B.Cu")
		(net "GND")
	)
	(via
		(at 98.118168 -25.0952)
		(size 0.508)
		(drill 0.254)
		(layers "F.Cu" "B.Cu")
		(net "GND")
	)
	(via
		(at 75.762866 -70.44944)
		(size 0.508)
		(drill 0.254)
		(layers "F.Cu" "B.Cu")
		(net "GND")
	)
	(via
		(at 186.048396 -92.675202)
		(size 0.508)
		(drill 0.254)
		(layers "F.Cu" "B.Cu")
		(net "GND")
	)
	(via
		(at 384.175 -152.054306)
		(size 0.508)
		(drill 0.254)
		(layers "F.Cu" "B.Cu")
		(net "GND")
	)
	(via
		(at 346.00642 -32.131)
		(size 0.508)
		(drill 0.254)
		(layers "F.Cu" "B.Cu")
		(net "GND")
	)
	(via
		(at 167.111934 14.926056)
		(size 0.5588)
		(drill 0.3048)
		(layers "F.Cu" "B.Cu")
		(net "GND")
	)
	(via
		(at 87.781892 -85.30844)
		(size 0.508)
		(drill 0.254)
		(layers "F.Cu" "B.Cu")
		(net "GND")
	)
	(via
		(at 426.212 -9.398)
		(size 0.508)
		(drill 0.254)
		(layers "F.Cu" "B.Cu")
		(net "GND")
	)
	(via
		(at 41.45915 -60.843922)
		(size 0.5588)
		(drill 0.3048)
		(layers "F.Cu" "B.Cu")
		(net "GND")
	)
	(via
		(at 162.031934 9.084056)
		(size 0.5588)
		(drill 0.3048)
		(layers "F.Cu" "B.Cu")
		(net "GND")
	)
	(via
		(at 18.052796 0.364998)
		(size 0.508)
		(drill 0.254)
		(layers "F.Cu" "B.Cu")
		(net "GND")
	)
	(via
		(at 280.065734 -55.409338)
		(size 0.508)
		(drill 0.254)
		(layers "F.Cu" "B.Cu")
		(net "GND")
	)
	(via
		(at 394.67155 -122.104404)
		(size 0.508)
		(drill 0.254)
		(layers "F.Cu" "B.Cu")
		(net "GND")
	)
	(via
		(at 45.394118 -145.9357)
		(size 0.508)
		(drill 0.254)
		(layers "F.Cu" "B.Cu")
		(net "GND")
	)
	(via
		(at 400.076924 -162.243262)
		(size 0.5588)
		(drill 0.3048)
		(layers "F.Cu" "B.Cu")
		(net "GND")
	)
	(via
		(at 53.442108 -139.166092)
		(size 0.508)
		(drill 0.254)
		(layers "F.Cu" "B.Cu")
		(net "GND")
	)
	(via
		(at 87.781892 -82.33664)
		(size 0.508)
		(drill 0.254)
		(layers "F.Cu" "B.Cu")
		(net "GND")
	)
	(via
		(at 181.25186 -13.52804)
		(size 0.508)
		(drill 0.254)
		(layers "F.Cu" "B.Cu")
		(net "GND")
	)
	(via
		(at 298.378626 -52.437538)
		(size 0.508)
		(drill 0.254)
		(layers "F.Cu" "B.Cu")
		(net "GND")
	)
	(via
		(at 127.392176 -28.730956)
		(size 0.508)
		(drill 0.254)
		(layers "F.Cu" "B.Cu")
		(net "GND")
	)
	(via
		(at 49.24933 -150.219156)
		(size 0.508)
		(drill 0.254)
		(layers "F.Cu" "B.Cu")
		(net "GND")
	)
	(via
		(at 274.914614 -55.409338)
		(size 0.508)
		(drill 0.254)
		(layers "F.Cu" "B.Cu")
		(net "GND")
	)
	(via
		(at 196.399912 -21.517356)
		(size 0.508)
		(drill 0.254)
		(layers "F.Cu" "B.Cu")
		(net "GND")
	)
	(via
		(at 40.336724 -162.243262)
		(size 0.5588)
		(drill 0.3048)
		(layers "F.Cu" "B.Cu")
		(net "GND")
	)
	(via
		(at 495.330734 -165.596824)
		(size 0.5588)
		(drill 0.3048)
		(layers "F.Cu" "B.Cu")
		(net "GND")
	)
	(via
		(at 460.362808 -136.779254)
		(size 0.508)
		(drill 0.254)
		(layers "F.Cu" "B.Cu")
		(net "GND")
	)
	(via
		(at 161.666174 -31.737554)
		(size 0.508)
		(drill 0.254)
		(layers "F.Cu" "B.Cu")
		(net "GND")
	)
	(via
		(at 342.3666 -59.679586)
		(size 0.508)
		(drill 0.254)
		(layers "F.Cu" "B.Cu")
		(net "GND")
	)
	(via
		(at 3.9624 -136.9314)
		(size 0.508)
		(drill 0.254)
		(layers "F.Cu" "B.Cu")
		(net "GND")
	)
	(via
		(at 206.243682 -60.869322)
		(size 0.5588)
		(drill 0.3048)
		(layers "F.Cu" "B.Cu")
		(net "GND")
	)
	(via
		(at 135.095234 -66.305938)
		(size 0.508)
		(drill 0.254)
		(layers "F.Cu" "B.Cu")
		(net "GND")
	)
	(via
		(at 294.999918 -129.568956)
		(size 0.508)
		(drill 0.254)
		(layers "F.Cu" "B.Cu")
		(net "GND")
	)
	(via
		(at 69.753226 -92.737686)
		(size 0.508)
		(drill 0.254)
		(layers "F.Cu" "B.Cu")
		(net "GND")
	)
	(via
		(at 124.049536 0.457454)
		(size 0.508)
		(drill 0.254)
		(layers "F.Cu" "B.Cu")
		(net "GND")
	)
	(via
		(at 49.24933 -134.861046)
		(size 0.508)
		(drill 0.254)
		(layers "F.Cu" "B.Cu")
		(net "GND")
	)
	(via
		(at 74.045826 -70.44944)
		(size 0.508)
		(drill 0.254)
		(layers "F.Cu" "B.Cu")
		(net "GND")
	)
	(via
		(at 78.14945 -139.2428)
		(size 0.508)
		(drill 0.254)
		(layers "F.Cu" "B.Cu")
		(net "GND")
	)
	(via
		(at 124.049536 -145.998946)
		(size 0.508)
		(drill 0.254)
		(layers "F.Cu" "B.Cu")
		(net "GND")
	)
	(via
		(at 377.83135 -106.190796)
		(size 0.508)
		(drill 0.254)
		(layers "F.Cu" "B.Cu")
		(net "GND")
	)
	(via
		(at 294.08628 -70.763384)
		(size 0.508)
		(drill 0.254)
		(layers "F.Cu" "B.Cu")
		(net "GND")
	)
	(via
		(at 104.467152 -70.84314)
		(size 0.5588)
		(drill 0.3048)
		(layers "F.Cu" "B.Cu")
		(net "GND")
	)
	(via
		(at 468.101934 11.624056)
		(size 0.5588)
		(drill 0.3048)
		(layers "F.Cu" "B.Cu")
		(net "GND")
	)
	(via
		(at 213.399878 -21.517356)
		(size 0.508)
		(drill 0.254)
		(layers "F.Cu" "B.Cu")
		(net "GND")
	)
	(via
		(at 283.04236 0.457454)
		(size 0.508)
		(drill 0.254)
		(layers "F.Cu" "B.Cu")
		(net "GND")
	)
	(via
		(at 291.796724 -162.243262)
		(size 0.5588)
		(drill 0.3048)
		(layers "F.Cu" "B.Cu")
		(net "GND")
	)
	(via
		(at 483.341934 10.354056)
		(size 0.5588)
		(drill 0.3048)
		(layers "F.Cu" "B.Cu")
		(net "GND")
	)
	(via
		(at 110.198916 -96.518984)
		(size 0.508)
		(drill 0.254)
		(layers "F.Cu" "B.Cu")
		(net "GND")
	)
	(via
		(at 336.1944 -31.3563)
		(size 0.508)
		(drill 0.254)
		(layers "F.Cu" "B.Cu")
		(net "GND")
	)
	(via
		(at 260.0706 -18.8214)
		(size 0.508)
		(drill 0.254)
		(layers "F.Cu" "B.Cu")
		(net "GND")
	)
	(via
		(at 51.541934 9.084056)
		(size 0.5588)
		(drill 0.3048)
		(layers "F.Cu" "B.Cu")
		(net "GND")
	)
	(via
		(at 200.552304 -56.829198)
		(size 0.508)
		(drill 0.254)
		(layers "F.Cu" "B.Cu")
		(net "GND")
	)
	(via
		(at 410.690314 -34.134806)
		(size 0.4572)
		(drill 0.2032)
		(layers "F.Cu" "B.Cu")
		(net "GND")
	)
	(via
		(at 268.679168 -135.4074)
		(size 0.508)
		(drill 0.254)
		(layers "F.Cu" "B.Cu")
		(net "GND")
	)
	(via
		(at 4.577334 -167.832024)
		(size 0.5588)
		(drill 0.3048)
		(layers "F.Cu" "B.Cu")
		(net "GND")
	)
	(via
		(at 239.046258 -93.23324)
		(size 0.508)
		(drill 0.254)
		(layers "F.Cu" "B.Cu")
		(net "GND")
	)
	(via
		(at 297.520106 -88.594184)
		(size 0.508)
		(drill 0.254)
		(layers "F.Cu" "B.Cu")
		(net "GND")
	)
	(via
		(at 433.100734 -166.714424)
		(size 0.5588)
		(drill 0.3048)
		(layers "F.Cu" "B.Cu")
		(net "GND")
	)
	(via
		(at 463.021934 12.894056)
		(size 0.5588)
		(drill 0.3048)
		(layers "F.Cu" "B.Cu")
		(net "GND")
	)
	(via
		(at 443.971934 12.894056)
		(size 0.5588)
		(drill 0.3048)
		(layers "F.Cu" "B.Cu")
		(net "GND")
	)
	(via
		(at 206.666592 -100.471478)
		(size 0.5588)
		(drill 0.3048)
		(layers "F.Cu" "B.Cu")
		(net "GND")
	)
	(via
		(at 207.411828 -129.568956)
		(size 0.508)
		(drill 0.254)
		(layers "F.Cu" "B.Cu")
		(net "GND")
	)
	(via
		(at 73.4441 -155.5369)
		(size 0.508)
		(drill 0.254)
		(layers "F.Cu" "B.Cu")
		(net "GND")
	)
	(via
		(at 277.490174 -61.847984)
		(size 0.508)
		(drill 0.254)
		(layers "F.Cu" "B.Cu")
		(net "GND")
	)
	(via
		(at 280.637234 -86.537038)
		(size 0.508)
		(drill 0.254)
		(layers "F.Cu" "B.Cu")
		(net "GND")
	)
	(via
		(at 145.5928 -66.7004)
		(size 0.508)
		(drill 0.254)
		(layers "F.Cu" "B.Cu")
		(net "GND")
	)
	(via
		(at 241.44986 -155.511246)
		(size 0.508)
		(drill 0.254)
		(layers "F.Cu" "B.Cu")
		(net "GND")
	)
	(via
		(at 67.101466 -60.54344)
		(size 0.508)
		(drill 0.254)
		(layers "F.Cu" "B.Cu")
		(net "GND")
	)
	(via
		(at 199.992234 -79.683864)
		(size 0.508)
		(drill 0.254)
		(layers "F.Cu" "B.Cu")
		(net "GND")
	)
	(via
		(at 453.416924 -162.243262)
		(size 0.5588)
		(drill 0.3048)
		(layers "F.Cu" "B.Cu")
		(net "GND")
	)
	(via
		(at 255.87452 -17.35709)
		(size 0.508)
		(drill 0.254)
		(layers "F.Cu" "B.Cu")
		(net "GND")
	)
	(via
		(at 200.515728 -89.4334)
		(size 0.508)
		(drill 0.254)
		(layers "F.Cu" "B.Cu")
		(net "GND")
	)
	(via
		(at 413.893762 -87.921084)
		(size 0.508)
		(drill 0.254)
		(layers "F.Cu" "B.Cu")
		(net "GND")
	)
	(via
		(at 349.504 -145.530824)
		(size 0.508)
		(drill 0.254)
		(layers "F.Cu" "B.Cu")
		(net "GND")
	)
	(via
		(at 82.630772 -64.50584)
		(size 0.508)
		(drill 0.254)
		(layers "F.Cu" "B.Cu")
		(net "GND")
	)
	(via
		(at 60.201302 -154.063446)
		(size 0.508)
		(drill 0.254)
		(layers "F.Cu" "B.Cu")
		(net "GND")
	)
	(via
		(at 460.082392 -36.435792)
		(size 0.508)
		(drill 0.254)
		(layers "F.Cu" "B.Cu")
		(net "GND")
	)
	(via
		(at 72.136 -131.5466)
		(size 0.508)
		(drill 0.254)
		(layers "F.Cu" "B.Cu")
		(net "GND")
	)
	(via
		(at 115.065302 -54.418738)
		(size 0.508)
		(drill 0.254)
		(layers "F.Cu" "B.Cu")
		(net "GND")
	)
	(via
		(at 31.39948 -155.600146)
		(size 0.508)
		(drill 0.254)
		(layers "F.Cu" "B.Cu")
		(net "GND")
	)
	(via
		(at 108.197396 -63.334138)
		(size 0.508)
		(drill 0.254)
		(layers "F.Cu" "B.Cu")
		(net "GND")
	)
	(via
		(at 310.795924 -162.243262)
		(size 0.5588)
		(drill 0.3048)
		(layers "F.Cu" "B.Cu")
		(net "GND")
	)
	(via
		(at 476.280734 -165.596824)
		(size 0.5588)
		(drill 0.3048)
		(layers "F.Cu" "B.Cu")
		(net "GND")
	)
	(via
		(at 300.772068 1.9558)
		(size 0.508)
		(drill 0.254)
		(layers "F.Cu" "B.Cu")
		(net "GND")
	)
	(via
		(at 332.7654 -109.855)
		(size 0.508)
		(drill 0.254)
		(layers "F.Cu" "B.Cu")
		(net "GND")
	)
	(via
		(at 349.993712 -104.254554)
		(size 0.508)
		(drill 0.254)
		(layers "F.Cu" "B.Cu")
		(net "GND")
	)
	(via
		(at 200.5584 -100.789486)
		(size 0.5588)
		(drill 0.3048)
		(layers "F.Cu" "B.Cu")
		(net "GND")
	)
	(via
		(at 299.191934 9.084056)
		(size 0.5588)
		(drill 0.3048)
		(layers "F.Cu" "B.Cu")
		(net "GND")
	)
	(via
		(at 161.041334 -167.832024)
		(size 0.5588)
		(drill 0.3048)
		(layers "F.Cu" "B.Cu")
		(net "GND")
	)
	(via
		(at 72.1487 -26.73731)
		(size 0.508)
		(drill 0.254)
		(layers "F.Cu" "B.Cu")
		(net "GND")
	)
	(via
		(at 236.470698 -69.953886)
		(size 0.508)
		(drill 0.254)
		(layers "F.Cu" "B.Cu")
		(net "GND")
	)
	(via
		(at -3.769106 -113.179352)
		(size 0.5588)
		(drill 0.3048)
		(layers "F.Cu" "B.Cu")
		(net "GND")
	)
	(via
		(at 288.447734 -167.832024)
		(size 0.5588)
		(drill 0.3048)
		(layers "F.Cu" "B.Cu")
		(net "GND")
	)
	(via
		(at 64.087502 -4.346956)
		(size 0.508)
		(drill 0.254)
		(layers "F.Cu" "B.Cu")
		(net "GND")
	)
	(via
		(at 53.436012 -23.495)
		(size 0.508)
		(drill 0.254)
		(layers "F.Cu" "B.Cu")
		(net "GND")
	)
	(via
		(at 50.047398 -68.7705)
		(size 0.508)
		(drill 0.254)
		(layers "F.Cu" "B.Cu")
		(net "GND")
	)
	(via
		(at 243.338604 -69.953886)
		(size 0.508)
		(drill 0.254)
		(layers "F.Cu" "B.Cu")
		(net "GND")
	)
	(via
		(at 431.830734 -165.596824)
		(size 0.5588)
		(drill 0.3048)
		(layers "F.Cu" "B.Cu")
		(net "GND")
	)
	(via
		(at 431.271934 12.894056)
		(size 0.5588)
		(drill 0.3048)
		(layers "F.Cu" "B.Cu")
		(net "GND")
	)
	(via
		(at 63.806324 -162.243262)
		(size 0.5588)
		(drill 0.3048)
		(layers "F.Cu" "B.Cu")
		(net "GND")
	)
	(via
		(at 480.801934 11.624056)
		(size 0.5588)
		(drill 0.3048)
		(layers "F.Cu" "B.Cu")
		(net "GND")
	)
	(via
		(at 394.17625 -116.094764)
		(size 0.508)
		(drill 0.254)
		(layers "F.Cu" "B.Cu")
		(net "GND")
	)
	(via
		(at 36.5506 -51.9684)
		(size 0.5588)
		(drill 0.3048)
		(layers "F.Cu" "B.Cu")
		(net "GND")
	)
	(via
		(at 138.529314 -69.277738)
		(size 0.508)
		(drill 0.254)
		(layers "F.Cu" "B.Cu")
		(net "GND")
	)
	(via
		(at 444.974472 -125.48743)
		(size 0.508)
		(drill 0.254)
		(layers "F.Cu" "B.Cu")
		(net "GND")
	)
	(via
		(at 240.599722 1.994154)
		(size 0.508)
		(drill 0.254)
		(layers "F.Cu" "B.Cu")
		(net "GND")
	)
	(via
		(at 68.799456 -21.517356)
		(size 0.508)
		(drill 0.254)
		(layers "F.Cu" "B.Cu")
		(net "GND")
	)
	(via
		(at 131.551934 14.926056)
		(size 0.5588)
		(drill 0.3048)
		(layers "F.Cu" "B.Cu")
		(net "GND")
	)
	(via
		(at 243.2558 -8.1534)
		(size 0.508)
		(drill 0.254)
		(layers "F.Cu" "B.Cu")
		(net "GND")
	)
	(via
		(at 142.898114 -87.603584)
		(size 0.508)
		(drill 0.254)
		(layers "F.Cu" "B.Cu")
		(net "GND")
	)
	(via
		(at 8.91159 -150.271734)
		(size 0.508)
		(drill 0.254)
		(layers "F.Cu" "B.Cu")
		(net "GND")
	)
	(via
		(at 58.599324 -7.607046)
		(size 0.508)
		(drill 0.254)
		(layers "F.Cu" "B.Cu")
		(net "GND")
	)
	(via
		(at 249.919744 -50.573432)
		(size 0.508)
		(drill 0.254)
		(layers "F.Cu" "B.Cu")
		(net "GND")
	)
	(via
		(at 490.961934 10.354056)
		(size 0.5588)
		(drill 0.3048)
		(layers "F.Cu" "B.Cu")
		(net "GND")
	)
	(via
		(at 141.049502 -146.011646)
		(size 0.508)
		(drill 0.254)
		(layers "F.Cu" "B.Cu")
		(net "GND")
	)
	(via
		(at 335.747614 -16.002)
		(size 0.508)
		(drill 0.254)
		(layers "F.Cu" "B.Cu")
		(net "GND")
	)
	(via
		(at 245.914164 -61.53404)
		(size 0.508)
		(drill 0.254)
		(layers "F.Cu" "B.Cu")
		(net "GND")
	)
	(via
		(at 304.388266 -70.763384)
		(size 0.508)
		(drill 0.254)
		(layers "F.Cu" "B.Cu")
		(net "GND")
	)
	(via
		(at 348.9579 -29.0703)
		(size 0.508)
		(drill 0.254)
		(layers "F.Cu" "B.Cu")
		(net "GND")
	)
	(via
		(at 259.182616 -79.351632)
		(size 0.508)
		(drill 0.254)
		(layers "F.Cu" "B.Cu")
		(net "GND")
	)
	(via
		(at 75.59929 -7.607046)
		(size 0.508)
		(drill 0.254)
		(layers "F.Cu" "B.Cu")
		(net "GND")
	)
	(via
		(at 300.741334 -167.832024)
		(size 0.5588)
		(drill 0.3048)
		(layers "F.Cu" "B.Cu")
		(net "GND")
	)
	(via
		(at 410.236924 -162.243262)
		(size 0.5588)
		(drill 0.3048)
		(layers "F.Cu" "B.Cu")
		(net "GND")
	)
	(via
		(at 398.13865 -98.464116)
		(size 0.508)
		(drill 0.254)
		(layers "F.Cu" "B.Cu")
		(net "GND")
	)
	(via
		(at 349.2754 -36.83)
		(size 0.508)
		(drill 0.254)
		(layers "F.Cu" "B.Cu")
		(net "GND")
	)
	(via
		(at 226.822 -131.016756)
		(size 0.508)
		(drill 0.254)
		(layers "F.Cu" "B.Cu")
		(net "GND")
	)
	(via
		(at 173.155102 4.553458)
		(size 0.5588)
		(drill 0.3048)
		(layers "F.Cu" "B.Cu")
		(net "GND")
	)
	(via
		(at 235.612178 -83.32724)
		(size 0.508)
		(drill 0.254)
		(layers "F.Cu" "B.Cu")
		(net "GND")
	)
	(via
		(at 365.231934 14.926056)
		(size 0.5588)
		(drill 0.3048)
		(layers "F.Cu" "B.Cu")
		(net "GND")
	)
	(via
		(at 397.540734 -164.479224)
		(size 0.5588)
		(drill 0.3048)
		(layers "F.Cu" "B.Cu")
		(net "GND")
	)
	(via
		(at 238.187738 -92.737686)
		(size 0.508)
		(drill 0.254)
		(layers "F.Cu" "B.Cu")
		(net "GND")
	)
	(via
		(at 256.089658 -8.468868)
		(size 0.508)
		(drill 0.254)
		(layers "F.Cu" "B.Cu")
		(net "GND")
	)
	(via
		(at 384.789934 -167.832024)
		(size 0.5588)
		(drill 0.3048)
		(layers "F.Cu" "B.Cu")
		(net "GND")
	)
	(via
		(at 217.472006 -144.5006)
		(size 0.508)
		(drill 0.254)
		(layers "F.Cu" "B.Cu")
		(net "GND")
	)
	(via
		(at 173.8122 -23.52802)
		(size 0.508)
		(drill 0.254)
		(layers "F.Cu" "B.Cu")
		(net "GND")
	)
	(via
		(at 113.957354 -18.007584)
		(size 0.508)
		(drill 0.254)
		(layers "F.Cu" "B.Cu")
		(net "GND")
	)
	(via
		(at 1.224534 -163.361624)
		(size 0.5588)
		(drill 0.3048)
		(layers "F.Cu" "B.Cu")
		(net "GND")
	)
	(via
		(at 1.27 -119.126)
		(size 0.508)
		(drill 0.254)
		(layers "F.Cu" "B.Cu")
		(net "GND")
	)
	(via
		(at 74.045826 -87.28964)
		(size 0.508)
		(drill 0.254)
		(layers "F.Cu" "B.Cu")
		(net "GND")
	)
	(via
		(at 75.59929 -3.762756)
		(size 0.508)
		(drill 0.254)
		(layers "F.Cu" "B.Cu")
		(net "GND")
	)
	(via
		(at 123.934728 -102.462584)
		(size 0.508)
		(drill 0.254)
		(layers "F.Cu" "B.Cu")
		(net "GND")
	)
	(via
		(at 294.9448 -63.334138)
		(size 0.508)
		(drill 0.254)
		(layers "F.Cu" "B.Cu")
		(net "GND")
	)
	(via
		(at 386.983478 -29.50591)
		(size 0.508)
		(drill 0.254)
		(layers "F.Cu" "B.Cu")
		(net "GND")
	)
	(via
		(at 433.451 -9.398)
		(size 0.508)
		(drill 0.254)
		(layers "F.Cu" "B.Cu")
		(net "GND")
	)
	(via
		(at 240.763298 -51.62804)
		(size 0.508)
		(drill 0.254)
		(layers "F.Cu" "B.Cu")
		(net "GND")
	)
	(via
		(at 115.215924 -162.243262)
		(size 0.5588)
		(drill 0.3048)
		(layers "F.Cu" "B.Cu")
		(net "GND")
	)
	(via
		(at 305.199796 -27.943556)
		(size 0.508)
		(drill 0.254)
		(layers "F.Cu" "B.Cu")
		(net "GND")
	)
	(via
		(at 212.54974 -140.617956)
		(size 0.508)
		(drill 0.254)
		(layers "F.Cu" "B.Cu")
		(net "GND")
	)
	(via
		(at 201.044556 -9.0805)
		(size 0.508)
		(drill 0.254)
		(layers "F.Cu" "B.Cu")
		(net "GND")
	)
	(via
		(at 39.049452 0.444754)
		(size 0.508)
		(drill 0.254)
		(layers "F.Cu" "B.Cu")
		(net "GND")
	)
	(via
		(at 310.621934 14.926056)
		(size 0.5588)
		(drill 0.3048)
		(layers "F.Cu" "B.Cu")
		(net "GND")
	)
	(via
		(at 125.278134 -167.832024)
		(size 0.5588)
		(drill 0.3048)
		(layers "F.Cu" "B.Cu")
		(net "GND")
	)
	(via
		(at 212.54974 -131.016756)
		(size 0.508)
		(drill 0.254)
		(layers "F.Cu" "B.Cu")
		(net "GND")
	)
	(via
		(at 248.214134 -167.832024)
		(size 0.5588)
		(drill 0.3048)
		(layers "F.Cu" "B.Cu")
		(net "GND")
	)
	(via
		(at 82.805524 -162.243262)
		(size 0.5588)
		(drill 0.3048)
		(layers "F.Cu" "B.Cu")
		(net "GND")
	)
	(via
		(at 248.489724 -65.991486)
		(size 0.508)
		(drill 0.254)
		(layers "F.Cu" "B.Cu")
		(net "GND")
	)
	(via
		(at 134.236714 -102.462584)
		(size 0.508)
		(drill 0.254)
		(layers "F.Cu" "B.Cu")
		(net "GND")
	)
	(via
		(at 19.791934 9.084056)
		(size 0.5588)
		(drill 0.3048)
		(layers "F.Cu" "B.Cu")
		(net "GND")
	)
	(via
		(at 306.049934 -9.156446)
		(size 0.508)
		(drill 0.254)
		(layers "F.Cu" "B.Cu")
		(net "GND")
	)
	(via
		(at 454.602596 -121.006362)
		(size 0.508)
		(drill 0.254)
		(layers "F.Cu" "B.Cu")
		(net "GND")
	)
	(via
		(at 50.398934 -167.832024)
		(size 0.5588)
		(drill 0.3048)
		(layers "F.Cu" "B.Cu")
		(net "GND")
	)
	(via
		(at 359.6894 -122.809)
		(size 0.508)
		(drill 0.254)
		(layers "F.Cu" "B.Cu")
		(net "GND")
	)
	(via
		(at 379.583188 -145.796)
		(size 0.508)
		(drill 0.254)
		(layers "F.Cu" "B.Cu")
		(net "GND")
	)
	(via
		(at 201.044556 -18.6817)
		(size 0.508)
		(drill 0.254)
		(layers "F.Cu" "B.Cu")
		(net "GND")
	)
	(via
		(at 49.24933 -154.063446)
		(size 0.508)
		(drill 0.254)
		(layers "F.Cu" "B.Cu")
		(net "GND")
	)
	(via
		(at 78.338172 -65.000886)
		(size 0.508)
		(drill 0.254)
		(layers "F.Cu" "B.Cu")
		(net "GND")
	)
	(via
		(at 139.387834 -64.819784)
		(size 0.508)
		(drill 0.254)
		(layers "F.Cu" "B.Cu")
		(net "GND")
	)
	(via
		(at 34.991802 -95.304864)
		(size 0.508)
		(drill 0.254)
		(layers "F.Cu" "B.Cu")
		(net "GND")
	)
	(via
		(at 382.554734 -167.832024)
		(size 0.5588)
		(drill 0.3048)
		(layers "F.Cu" "B.Cu")
		(net "GND")
	)
	(via
		(at 135.095234 -74.23023)
		(size 0.508)
		(drill 0.254)
		(layers "F.Cu" "B.Cu")
		(net "GND")
	)
	(via
		(at 401.41144 -143.643096)
		(size 0.508)
		(drill 0.254)
		(layers "F.Cu" "B.Cu")
		(net "GND")
	)
	(via
		(at 291.51072 -87.108538)
		(size 0.508)
		(drill 0.254)
		(layers "F.Cu" "B.Cu")
		(net "GND")
	)
	(via
		(at 169.909744 -92.499434)
		(size 0.508)
		(drill 0.254)
		(layers "F.Cu" "B.Cu")
		(net "GND")
	)
	(via
		(at 370.155724 -162.268662)
		(size 0.5588)
		(drill 0.3048)
		(layers "F.Cu" "B.Cu")
		(net "GND")
	)
	(via
		(at 308.501796 -7.607046)
		(size 0.508)
		(drill 0.254)
		(layers "F.Cu" "B.Cu")
		(net "GND")
	)
	(via
		(at 54.081934 14.926056)
		(size 0.5588)
		(drill 0.3048)
		(layers "F.Cu" "B.Cu")
		(net "GND")
	)
	(via
		(at 402.061934 14.926056)
		(size 0.5588)
		(drill 0.3048)
		(layers "F.Cu" "B.Cu")
		(net "GND")
	)
	(via
		(at 200.477628 -96.3168)
		(size 0.508)
		(drill 0.254)
		(layers "F.Cu" "B.Cu")
		(net "GND")
	)
	(via
		(at 162.3314 -81.153)
		(size 0.508)
		(drill 0.254)
		(layers "F.Cu" "B.Cu")
		(net "GND")
	)
	(via
		(at 133.39953 -18.744946)
		(size 0.508)
		(drill 0.254)
		(layers "F.Cu" "B.Cu")
		(net "GND")
	)
	(via
		(at 115.460526 -130.991356)
		(size 0.508)
		(drill 0.254)
		(layers "F.Cu" "B.Cu")
		(net "GND")
	)
	(via
		(at 127.368808 -87.603584)
		(size 0.508)
		(drill 0.254)
		(layers "F.Cu" "B.Cu")
		(net "GND")
	)
	(via
		(at 34.8742 -51.943)
		(size 0.5588)
		(drill 0.3048)
		(layers "F.Cu" "B.Cu")
		(net "GND")
	)
	(via
		(at 146.086068 -150.749)
		(size 0.508)
		(drill 0.254)
		(layers "F.Cu" "B.Cu")
		(net "GND")
	)
	(via
		(at 249.348244 -76.39304)
		(size 0.508)
		(drill 0.254)
		(layers "F.Cu" "B.Cu")
		(net "GND")
	)
	(via
		(at 282.067254 -96.518984)
		(size 0.508)
		(drill 0.254)
		(layers "F.Cu" "B.Cu")
		(net "GND")
	)
	(via
		(at 237.329218 -101.15804)
		(size 0.508)
		(drill 0.254)
		(layers "F.Cu" "B.Cu")
		(net "GND")
	)
	(via
		(at 280.460958 -22.939756)
		(size 0.508)
		(drill 0.254)
		(layers "F.Cu" "B.Cu")
		(net "GND")
	)
	(via
		(at 242.480338 -93.23324)
		(size 0.508)
		(drill 0.254)
		(layers "F.Cu" "B.Cu")
		(net "GND")
	)
	(via
		(at 90.357198 -98.681286)
		(size 0.508)
		(drill 0.254)
		(layers "F.Cu" "B.Cu")
		(net "GND")
	)
	(via
		(at 34.95421 -53.857906)
		(size 0.5588)
		(drill 0.3048)
		(layers "F.Cu" "B.Cu")
		(net "GND")
	)
	(via
		(at 377.806204 -83.8454)
		(size 0.508)
		(drill 0.254)
		(layers "F.Cu" "B.Cu")
		(net "GND")
	)
	(via
		(at 70.461378 -11.916156)
		(size 0.508)
		(drill 0.254)
		(layers "F.Cu" "B.Cu")
		(net "GND")
	)
	(via
		(at 317.09995 -16.687546)
		(size 0.508)
		(drill 0.254)
		(layers "F.Cu" "B.Cu")
		(net "GND")
	)
	(via
		(at 50.047398 -76.1365)
		(size 0.508)
		(drill 0.254)
		(layers "F.Cu" "B.Cu")
		(net "GND")
	)
	(via
		(at 293.694612 -18.6817)
		(size 0.508)
		(drill 0.254)
		(layers "F.Cu" "B.Cu")
		(net "GND")
	)
	(via
		(at 168.385744 -92.499434)
		(size 0.508)
		(drill 0.254)
		(layers "F.Cu" "B.Cu")
		(net "GND")
	)
	(via
		(at 452.550022 -58.954924)
		(size 0.508)
		(drill 0.254)
		(layers "F.Cu" "B.Cu")
		(net "GND")
	)
	(via
		(at 74.045826 -85.30844)
		(size 0.508)
		(drill 0.254)
		(layers "F.Cu" "B.Cu")
		(net "GND")
	)
	(via
		(at 121.391934 14.926056)
		(size 0.5588)
		(drill 0.3048)
		(layers "F.Cu" "B.Cu")
		(net "GND")
	)
	(via
		(at 293.69131 -7.095744)
		(size 0.508)
		(drill 0.254)
		(layers "F.Cu" "B.Cu")
		(net "GND")
	)
	(via
		(at 124.793248 -95.033084)
		(size 0.508)
		(drill 0.254)
		(layers "F.Cu" "B.Cu")
		(net "GND")
	)
	(via
		(at 366.331754 -45.927772)
		(size 0.508)
		(drill 0.254)
		(layers "F.Cu" "B.Cu")
		(net "GND")
	)
	(via
		(at 53.436012 -4.2926)
		(size 0.508)
		(drill 0.254)
		(layers "F.Cu" "B.Cu")
		(net "GND")
	)
	(via
		(at 74.904346 -62.029086)
		(size 0.508)
		(drill 0.254)
		(layers "F.Cu" "B.Cu")
		(net "GND")
	)
	(via
		(at 173.155356 -0.553212)
		(size 0.5588)
		(drill 0.3048)
		(layers "F.Cu" "B.Cu")
		(net "GND")
	)
	(via
		(at 78.338172 -51.132486)
		(size 0.508)
		(drill 0.254)
		(layers "F.Cu" "B.Cu")
		(net "GND")
	)
	(via
		(at 261.052818 -75.148186)
		(size 0.5588)
		(drill 0.3048)
		(layers "F.Cu" "B.Cu")
		(net "GND")
	)
	(via
		(at 14.635734 -167.832024)
		(size 0.5588)
		(drill 0.3048)
		(layers "F.Cu" "B.Cu")
		(net "GND")
	)
	(via
		(at 283.04236 -21.513292)
		(size 0.508)
		(drill 0.254)
		(layers "F.Cu" "B.Cu")
		(net "GND")
	)
	(via
		(at 7.930134 -166.714424)
		(size 0.5588)
		(drill 0.3048)
		(layers "F.Cu" "B.Cu")
		(net "GND")
	)
	(via
		(at 141.181074 -77.697584)
		(size 0.508)
		(drill 0.254)
		(layers "F.Cu" "B.Cu")
		(net "GND")
	)
	(via
		(at 116.782342 -60.362338)
		(size 0.508)
		(drill 0.254)
		(layers "F.Cu" "B.Cu")
		(net "GND")
	)
	(via
		(at 267.376656 -98.681286)
		(size 0.508)
		(drill 0.254)
		(layers "F.Cu" "B.Cu")
		(net "GND")
	)
	(via
		(at 54.744112 0.5207)
		(size 0.508)
		(drill 0.254)
		(layers "F.Cu" "B.Cu")
		(net "GND")
	)
	(via
		(at 101.071934 14.926056)
		(size 0.5588)
		(drill 0.3048)
		(layers "F.Cu" "B.Cu")
		(net "GND")
	)
	(via
		(at 328.401934 9.084056)
		(size 0.5588)
		(drill 0.3048)
		(layers "F.Cu" "B.Cu")
		(net "GND")
	)
	(via
		(at 302.8188 -104.0257)
		(size 0.508)
		(drill 0.254)
		(layers "F.Cu" "B.Cu")
		(net "GND")
	)
	(via
		(at 301.812706 -74.230738)
		(size 0.508)
		(drill 0.254)
		(layers "F.Cu" "B.Cu")
		(net "GND")
	)
	(via
		(at 270.571468 -59.866784)
		(size 0.508)
		(drill 0.254)
		(layers "F.Cu" "B.Cu")
		(net "GND")
	)
	(via
		(at 294.08628 -53.923184)
		(size 0.508)
		(drill 0.254)
		(layers "F.Cu" "B.Cu")
		(net "GND")
	)
	(via
		(at 251.923804 -95.709486)
		(size 0.508)
		(drill 0.254)
		(layers "F.Cu" "B.Cu")
		(net "GND")
	)
	(via
		(at 199.9234 -61.2394)
		(size 0.5588)
		(drill 0.3048)
		(layers "F.Cu" "B.Cu")
		(net "GND")
	)
	(via
		(at 6.812534 -167.832024)
		(size 0.5588)
		(drill 0.3048)
		(layers "F.Cu" "B.Cu")
		(net "GND")
	)
	(via
		(at 247.631204 -90.26144)
		(size 0.508)
		(drill 0.254)
		(layers "F.Cu" "B.Cu")
		(net "GND")
	)
	(via
		(at 50.860452 -13.338556)
		(size 0.508)
		(drill 0.254)
		(layers "F.Cu" "B.Cu")
		(net "GND")
	)
	(via
		(at 185.413396 -92.675202)
		(size 0.508)
		(drill 0.254)
		(layers "F.Cu" "B.Cu")
		(net "GND")
	)
	(via
		(at 234.753658 -89.765886)
		(size 0.508)
		(drill 0.254)
		(layers "F.Cu" "B.Cu")
		(net "GND")
	)
	(via
		(at 78.14945 -155.3464)
		(size 0.508)
		(drill 0.254)
		(layers "F.Cu" "B.Cu")
		(net "GND")
	)
	(via
		(at 266.75588 -82.340196)
		(size 0.5588)
		(drill 0.3048)
		(layers "F.Cu" "B.Cu")
		(net "GND")
	)
	(via
		(at 162.3314 -31.5468)
		(size 0.508)
		(drill 0.254)
		(layers "F.Cu" "B.Cu")
		(net "GND")
	)
	(via
		(at 207.414114 -95.264478)
		(size 0.5588)
		(drill 0.3048)
		(layers "F.Cu" "B.Cu")
		(net "GND")
	)
	(via
		(at 311.092596 -9.143746)
		(size 0.508)
		(drill 0.254)
		(layers "F.Cu" "B.Cu")
		(net "GND")
	)
	(via
		(at 72.142096 -148.767292)
		(size 0.508)
		(drill 0.254)
		(layers "F.Cu" "B.Cu")
		(net "GND")
	)
	(via
		(at 279.491694 -98.005138)
		(size 0.508)
		(drill 0.254)
		(layers "F.Cu" "B.Cu")
		(net "GND")
	)
	(via
		(at 95.099124 -162.243262)
		(size 0.5588)
		(drill 0.3048)
		(layers "F.Cu" "B.Cu")
		(net "GND")
	)
	(via
		(at 69.321934 9.084056)
		(size 0.5588)
		(drill 0.3048)
		(layers "F.Cu" "B.Cu")
		(net "GND")
	)
	(via
		(at 362.933488 -157.523688)
		(size 0.5588)
		(drill 0.3048)
		(layers "F.Cu" "B.Cu")
		(net "GND")
	)
	(via
		(at 427.461934 9.084056)
		(size 0.5588)
		(drill 0.3048)
		(layers "F.Cu" "B.Cu")
		(net "GND")
	)
	(via
		(at 384.786124 -162.243262)
		(size 0.5588)
		(drill 0.3048)
		(layers "F.Cu" "B.Cu")
		(net "GND")
	)
	(via
		(at 152.099518 -139.181078)
		(size 0.508)
		(drill 0.254)
		(layers "F.Cu" "B.Cu")
		(net "GND")
	)
	(via
		(at 255.8034 -3.635756)
		(size 0.508)
		(drill 0.254)
		(layers "F.Cu" "B.Cu")
		(net "GND")
	)
	(via
		(at 289.565334 -167.832024)
		(size 0.5588)
		(drill 0.3048)
		(layers "F.Cu" "B.Cu")
		(net "GND")
	)
	(via
		(at -2.128266 -166.714424)
		(size 0.5588)
		(drill 0.3048)
		(layers "F.Cu" "B.Cu")
		(net "GND")
	)
	(via
		(at 391.20445 -116.094764)
		(size 0.508)
		(drill 0.254)
		(layers "F.Cu" "B.Cu")
		(net "GND")
	)
	(via
		(at 346.24518 -13.78712)
		(size 0.508)
		(drill 0.254)
		(layers "F.Cu" "B.Cu")
		(net "GND")
	)
	(via
		(at 180.4797 -40.35552)
		(size 0.508)
		(drill 0.254)
		(layers "F.Cu" "B.Cu")
		(net "GND")
	)
	(via
		(at 54.74081 2.505456)
		(size 0.508)
		(drill 0.254)
		(layers "F.Cu" "B.Cu")
		(net "GND")
	)
	(via
		(at 152.781 -164.973)
		(size 0.5588)
		(drill 0.3048)
		(layers "F.Cu" "B.Cu")
		(net "GND")
	)
	(via
		(at 455.80427 -118.61927)
		(size 0.508)
		(drill 0.254)
		(layers "F.Cu" "B.Cu")
		(net "GND")
	)
	(via
		(at 452.150734 -166.714424)
		(size 0.5588)
		(drill 0.3048)
		(layers "F.Cu" "B.Cu")
		(net "GND")
	)
	(via
		(at 110.198916 -99.490784)
		(size 0.508)
		(drill 0.254)
		(layers "F.Cu" "B.Cu")
		(net "GND")
	)
	(via
		(at 326.644 -35.433)
		(size 0.508)
		(drill 0.254)
		(layers "F.Cu" "B.Cu")
		(net "GND")
	)
	(via
		(at 124.81052 -3.737356)
		(size 0.508)
		(drill 0.254)
		(layers "F.Cu" "B.Cu")
		(net "GND")
	)
	(via
		(at 86.064852 -74.411586)
		(size 0.508)
		(drill 0.254)
		(layers "F.Cu" "B.Cu")
		(net "GND")
	)
	(via
		(at 241.44986 -11.916156)
		(size 0.508)
		(drill 0.254)
		(layers "F.Cu" "B.Cu")
		(net "GND")
	)
	(via
		(at 392.69035 -118.670324)
		(size 0.508)
		(drill 0.254)
		(layers "F.Cu" "B.Cu")
		(net "GND")
	)
	(via
		(at 399.662142 -9.452864)
		(size 0.508)
		(drill 0.254)
		(layers "F.Cu" "B.Cu")
		(net "GND")
	)
	(via
		(at 459.770734 -164.479224)
		(size 0.5588)
		(drill 0.3048)
		(layers "F.Cu" "B.Cu")
		(net "GND")
	)
	(via
		(at 289.561524 -162.243262)
		(size 0.5588)
		(drill 0.3048)
		(layers "F.Cu" "B.Cu")
		(net "GND")
	)
	(via
		(at 80.055212 -98.681286)
		(size 0.508)
		(drill 0.254)
		(layers "F.Cu" "B.Cu")
		(net "GND")
	)
	(via
		(at 49.5808 -95.9612)
		(size 0.508)
		(drill 0.254)
		(layers "F.Cu" "B.Cu")
		(net "GND")
	)
	(via
		(at 95.908368 2.76352)
		(size 0.508)
		(drill 0.254)
		(layers "F.Cu" "B.Cu")
		(net "GND")
	)
	(via
		(at 393.730734 -164.479224)
		(size 0.5588)
		(drill 0.3048)
		(layers "F.Cu" "B.Cu")
		(net "GND")
	)
	(via
		(at 133.378194 -85.127338)
		(size 0.508)
		(drill 0.254)
		(layers "F.Cu" "B.Cu")
		(net "GND")
	)
	(via
		(at 202.496928 -60.198)
		(size 0.5588)
		(drill 0.3048)
		(layers "F.Cu" "B.Cu")
		(net "GND")
	)
	(via
		(at 125.201934 14.926056)
		(size 0.5588)
		(drill 0.3048)
		(layers "F.Cu" "B.Cu")
		(net "GND")
	)
	(via
		(at 128.690878 -7.095744)
		(size 0.508)
		(drill 0.254)
		(layers "F.Cu" "B.Cu")
		(net "GND")
	)
	(via
		(at 186.073796 -95.520002)
		(size 0.508)
		(drill 0.254)
		(layers "F.Cu" "B.Cu")
		(net "GND")
	)
	(via
		(at 192.6336 -39.6748)
		(size 0.508)
		(drill 0.254)
		(layers "F.Cu" "B.Cu")
		(net "GND")
	)
	(via
		(at 130.802888 -96.518984)
		(size 0.508)
		(drill 0.254)
		(layers "F.Cu" "B.Cu")
		(net "GND")
	)
	(via
		(at 360.497882 -77.36078)
		(size 0.508)
		(drill 0.254)
		(layers "F.Cu" "B.Cu")
		(net "GND")
	)
	(via
		(at 373.469662 -150.400512)
		(size 0.508)
		(drill 0.254)
		(layers "F.Cu" "B.Cu")
		(net "GND")
	)
	(via
		(at 309.678324 -162.243262)
		(size 0.5588)
		(drill 0.3048)
		(layers "F.Cu" "B.Cu")
		(net "GND")
	)
	(via
		(at 48.650398 -60.449206)
		(size 0.508)
		(drill 0.254)
		(layers "F.Cu" "B.Cu")
		(net "GND")
	)
	(via
		(at 271.480788 -54.418738)
		(size 0.508)
		(drill 0.254)
		(layers "F.Cu" "B.Cu")
		(net "GND")
	)
	(via
		(at 96.578928 2.7686)
		(size 0.508)
		(drill 0.254)
		(layers "F.Cu" "B.Cu")
		(net "GND")
	)
	(via
		(at 299.151802 -154.063446)
		(size 0.508)
		(drill 0.254)
		(layers "F.Cu" "B.Cu")
		(net "GND")
	)
	(via
		(at 218.44254 -139.166092)
		(size 0.508)
		(drill 0.254)
		(layers "F.Cu" "B.Cu")
		(net "GND")
	)
	(via
		(at 8.2423 -115.3287)
		(size 0.508)
		(drill 0.254)
		(layers "F.Cu" "B.Cu")
		(net "GND")
	)
	(via
		(at 335.37906 -55.073296)
		(size 0.508)
		(drill 0.254)
		(layers "F.Cu" "B.Cu")
		(net "GND")
	)
	(via
		(at 336.9564 -32.1183)
		(size 0.508)
		(drill 0.254)
		(layers "F.Cu" "B.Cu")
		(net "GND")
	)
	(via
		(at 191.4144 1.0922)
		(size 0.508)
		(drill 0.254)
		(layers "F.Cu" "B.Cu")
		(net "GND")
	)
	(via
		(at 307.898546 -69.772784)
		(size 0.508)
		(drill 0.254)
		(layers "F.Cu" "B.Cu")
		(net "GND")
	)
	(via
		(at 414.050734 -167.832024)
		(size 0.5588)
		(drill 0.3048)
		(layers "F.Cu" "B.Cu")
		(net "GND")
	)
	(via
		(at 477.550734 -167.832024)
		(size 0.5588)
		(drill 0.3048)
		(layers "F.Cu" "B.Cu")
		(net "GND")
	)
	(via
		(at 74.045826 -76.39304)
		(size 0.508)
		(drill 0.254)
		(layers "F.Cu" "B.Cu")
		(net "GND")
	)
	(via
		(at 36.031424 -148.7678)
		(size 0.508)
		(drill 0.254)
		(layers "F.Cu" "B.Cu")
		(net "GND")
	)
	(via
		(at 444.530734 -164.479224)
		(size 0.5588)
		(drill 0.3048)
		(layers "F.Cu" "B.Cu")
		(net "GND")
	)
	(via
		(at 39.899336 -154.063446)
		(size 0.508)
		(drill 0.254)
		(layers "F.Cu" "B.Cu")
		(net "GND")
	)
	(via
		(at 319.46088 -125.23724)
		(size 0.508)
		(drill 0.254)
		(layers "F.Cu" "B.Cu")
		(net "GND")
	)
	(via
		(at 29.160724 -162.243262)
		(size 0.5588)
		(drill 0.3048)
		(layers "F.Cu" "B.Cu")
		(net "GND")
	)
	(via
		(at 374.856248 -155.379928)
		(size 0.508)
		(drill 0.254)
		(layers "F.Cu" "B.Cu")
		(net "GND")
	)
	(via
		(at 199.749156 -144.0053)
		(size 0.508)
		(drill 0.254)
		(layers "F.Cu" "B.Cu")
		(net "GND")
	)
	(via
		(at 133.39953 -155.600146)
		(size 0.508)
		(drill 0.254)
		(layers "F.Cu" "B.Cu")
		(net "GND")
	)
	(via
		(at 234.753658 -61.038486)
		(size 0.508)
		(drill 0.254)
		(layers "F.Cu" "B.Cu")
		(net "GND")
	)
	(via
		(at -4.363466 -163.361624)
		(size 0.5588)
		(drill 0.3048)
		(layers "F.Cu" "B.Cu")
		(net "GND")
	)
	(via
		(at 437.919368 -157.1498)
		(size 0.508)
		(drill 0.254)
		(layers "F.Cu" "B.Cu")
		(net "GND")
	)
	(via
		(at 376.9106 -137.0838)
		(size 0.508)
		(drill 0.254)
		(layers "F.Cu" "B.Cu")
		(net "GND")
	)
	(via
		(at 135.095234 -88.099138)
		(size 0.508)
		(drill 0.254)
		(layers "F.Cu" "B.Cu")
		(net "GND")
	)
	(via
		(at 402.2344 -52.70373)
		(size 0.508)
		(drill 0.254)
		(layers "F.Cu" "B.Cu")
		(net "GND")
	)
	(via
		(at 301.812706 -79.183738)
		(size 0.508)
		(drill 0.254)
		(layers "F.Cu" "B.Cu")
		(net "GND")
	)
	(via
		(at 145.394934 -167.832024)
		(size 0.5588)
		(drill 0.3048)
		(layers "F.Cu" "B.Cu")
		(net "GND")
	)
	(via
		(at 235.49991 -9.156446)
		(size 0.508)
		(drill 0.254)
		(layers "F.Cu" "B.Cu")
		(net "GND")
	)
	(via
		(at 426.191934 11.624056)
		(size 0.5588)
		(drill 0.3048)
		(layers "F.Cu" "B.Cu")
		(net "GND")
	)
	(via
		(at -2.306066 12.741656)
		(size 0.5588)
		(drill 0.3048)
		(layers "F.Cu" "B.Cu")
		(net "GND")
	)
	(via
		(at 294.532812 -67.339718)
		(size 0.508)
		(drill 0.254)
		(layers "F.Cu" "B.Cu")
		(net "GND")
	)
	(via
		(at 61.111384 -26.488136)
		(size 0.508)
		(drill 0.254)
		(layers "F.Cu" "B.Cu")
		(net "GND")
	)
	(via
		(at 201.037952 -150.803356)
		(size 0.508)
		(drill 0.254)
		(layers "F.Cu" "B.Cu")
		(net "GND")
	)
	(via
		(at 70.611746 -99.17684)
		(size 0.508)
		(drill 0.254)
		(layers "F.Cu" "B.Cu")
		(net "GND")
	)
	(via
		(at 113.916968 -12.954)
		(size 0.508)
		(drill 0.254)
		(layers "F.Cu" "B.Cu")
		(net "GND")
	)
	(via
		(at 222.749872 -129.568956)
		(size 0.508)
		(drill 0.254)
		(layers "F.Cu" "B.Cu")
		(net "GND")
	)
	(via
		(at 325.861934 9.084056)
		(size 0.5588)
		(drill 0.3048)
		(layers "F.Cu" "B.Cu")
		(net "GND")
	)
	(via
		(at 310.122062 -144.5006)
		(size 0.508)
		(drill 0.254)
		(layers "F.Cu" "B.Cu")
		(net "GND")
	)
	(via
		(at 375.892822 -145.36801)
		(size 0.508)
		(drill 0.254)
		(layers "F.Cu" "B.Cu")
		(net "GND")
	)
	(via
		(at 354.9396 -59.679586)
		(size 0.508)
		(drill 0.254)
		(layers "F.Cu" "B.Cu")
		(net "GND")
	)
	(via
		(at 36.031424 -129.5654)
		(size 0.508)
		(drill 0.254)
		(layers "F.Cu" "B.Cu")
		(net "GND")
	)
	(via
		(at 195.549774 2.514854)
		(size 0.508)
		(drill 0.254)
		(layers "F.Cu" "B.Cu")
		(net "GND")
	)
	(via
		(at 383.77495 -102.756716)
		(size 0.508)
		(drill 0.254)
		(layers "F.Cu" "B.Cu")
		(net "GND")
	)
	(via
		(at 329.7174 -149.86)
		(size 0.508)
		(drill 0.254)
		(layers "F.Cu" "B.Cu")
		(net "GND")
	)
	(via
		(at 272.339308 -61.847984)
		(size 0.508)
		(drill 0.254)
		(layers "F.Cu" "B.Cu")
		(net "GND")
	)
	(via
		(at 284.358334 -81.659984)
		(size 0.508)
		(drill 0.254)
		(layers "F.Cu" "B.Cu")
		(net "GND")
	)
	(via
		(at 107.396534 -167.832024)
		(size 0.5588)
		(drill 0.3048)
		(layers "F.Cu" "B.Cu")
		(net "GND")
	)
	(via
		(at 306.049934 0.444754)
		(size 0.508)
		(drill 0.254)
		(layers "F.Cu" "B.Cu")
		(net "GND")
	)
	(via
		(at 80.913732 -60.54344)
		(size 0.508)
		(drill 0.254)
		(layers "F.Cu" "B.Cu")
		(net "GND")
	)
	(via
		(at 147.387564 -150.803356)
		(size 0.508)
		(drill 0.254)
		(layers "F.Cu" "B.Cu")
		(net "GND")
	)
	(via
		(at 306.105306 -84.631784)
		(size 0.508)
		(drill 0.254)
		(layers "F.Cu" "B.Cu")
		(net "GND")
	)
	(via
		(at 191.065404 -52.079398)
		(size 0.508)
		(drill 0.254)
		(layers "F.Cu" "B.Cu")
		(net "GND")
	)
	(via
		(at 173.334934 -167.832024)
		(size 0.5588)
		(drill 0.3048)
		(layers "F.Cu" "B.Cu")
		(net "GND")
	)
	(via
		(at 104.043734 -167.832024)
		(size 0.5588)
		(drill 0.3048)
		(layers "F.Cu" "B.Cu")
		(net "GND")
	)
	(via
		(at 396.270734 -165.596824)
		(size 0.5588)
		(drill 0.3048)
		(layers "F.Cu" "B.Cu")
		(net "GND")
	)
	(via
		(at 59.449462 0.457454)
		(size 0.508)
		(drill 0.254)
		(layers "F.Cu" "B.Cu")
		(net "GND")
	)
	(via
		(at 40.79875 -60.183522)
		(size 0.5588)
		(drill 0.3048)
		(layers "F.Cu" "B.Cu")
		(net "GND")
	)
	(via
		(at 77.479906 -78.37424)
		(size 0.508)
		(drill 0.254)
		(layers "F.Cu" "B.Cu")
		(net "GND")
	)
	(via
		(at 415.490152 -33.334706)
		(size 0.4572)
		(drill 0.2032)
		(layers "F.Cu" "B.Cu")
		(net "GND")
	)
	(via
		(at 499.851934 9.084056)
		(size 0.5588)
		(drill 0.3048)
		(layers "F.Cu" "B.Cu")
		(net "GND")
	)
	(via
		(at 415.9758 -17.1196)
		(size 0.508)
		(drill 0.254)
		(layers "F.Cu" "B.Cu")
		(net "GND")
	)
	(via
		(at -0.838454 -152.81021)
		(size 0.5588)
		(drill 0.3048)
		(layers "F.Cu" "B.Cu")
		(net "GND")
	)
	(via
		(at 288.07664 -98.005138)
		(size 0.508)
		(drill 0.254)
		(layers "F.Cu" "B.Cu")
		(net "GND")
	)
	(via
		(at 296.69994 0.444754)
		(size 0.508)
		(drill 0.254)
		(layers "F.Cu" "B.Cu")
		(net "GND")
	)
	(via
		(at 235.612178 -59.55284)
		(size 0.508)
		(drill 0.254)
		(layers "F.Cu" "B.Cu")
		(net "GND")
	)
	(via
		(at 293.22776 -97.014538)
		(size 0.508)
		(drill 0.254)
		(layers "F.Cu" "B.Cu")
		(net "GND")
	)
	(via
		(at 305.199796 -150.219156)
		(size 0.508)
		(drill 0.254)
		(layers "F.Cu" "B.Cu")
		(net "GND")
	)
	(via
		(at 42.164 -54.0766)
		(size 0.5588)
		(drill 0.3048)
		(layers "F.Cu" "B.Cu")
		(net "GND")
	)
	(via
		(at 469.84793 -125.318266)
		(size 0.508)
		(drill 0.254)
		(layers "F.Cu" "B.Cu")
		(net "GND")
	)
	(via
		(at 46.699424 -18.757646)
		(size 0.508)
		(drill 0.254)
		(layers "F.Cu" "B.Cu")
		(net "GND")
	)
	(via
		(at 218.436444 -13.8938)
		(size 0.508)
		(drill 0.254)
		(layers "F.Cu" "B.Cu")
		(net "GND")
	)
	(via
		(at 107.62361 -101.968046)
		(size 0.508)
		(drill 0.254)
		(layers "F.Cu" "B.Cu")
		(net "GND")
	)
	(via
		(at 337.291934 14.926056)
		(size 0.5588)
		(drill 0.3048)
		(layers "F.Cu" "B.Cu")
		(net "GND")
	)
	(via
		(at 312.3819 -148.7678)
		(size 0.508)
		(drill 0.254)
		(layers "F.Cu" "B.Cu")
		(net "GND")
	)
	(via
		(at 244.197124 -80.35544)
		(size 0.508)
		(drill 0.254)
		(layers "F.Cu" "B.Cu")
		(net "GND")
	)
	(via
		(at 41.816782 -92.572078)
		(size 0.5588)
		(drill 0.3048)
		(layers "F.Cu" "B.Cu")
		(net "GND")
	)
	(via
		(at 249.9106 -140.208)
		(size 0.508)
		(drill 0.254)
		(layers "F.Cu" "B.Cu")
		(net "GND")
	)
	(via
		(at 107.027472 -135.4074)
		(size 0.508)
		(drill 0.254)
		(layers "F.Cu" "B.Cu")
		(net "GND")
	)
	(via
		(at 241.621818 -65.991486)
		(size 0.508)
		(drill 0.254)
		(layers "F.Cu" "B.Cu")
		(net "GND")
	)
	(via
		(at 402.616924 -162.243262)
		(size 0.5588)
		(drill 0.3048)
		(layers "F.Cu" "B.Cu")
		(net "GND")
	)
	(via
		(at 42.121582 -76.468478)
		(size 0.5588)
		(drill 0.3048)
		(layers "F.Cu" "B.Cu")
		(net "GND")
	)
	(via
		(at 31.260796 -70.090792)
		(size 0.508)
		(drill 0.254)
		(layers "F.Cu" "B.Cu")
		(net "GND")
	)
	(via
		(at 246.485664 -102.093014)
		(size 0.508)
		(drill 0.254)
		(layers "F.Cu" "B.Cu")
		(net "GND")
	)
	(via
		(at 111.057182 -90.080338)
		(size 0.508)
		(drill 0.254)
		(layers "F.Cu" "B.Cu")
		(net "GND")
	)
	(via
		(at 118.031768 -4.2926)
		(size 0.508)
		(drill 0.254)
		(layers "F.Cu" "B.Cu")
		(net "GND")
	)
	(via
		(at 35.499802 -56.8198)
		(size 0.508)
		(drill 0.254)
		(layers "F.Cu" "B.Cu")
		(net "GND")
	)
	(via
		(at 396.4178 -3.302)
		(size 0.508)
		(drill 0.254)
		(layers "F.Cu" "B.Cu")
		(net "GND")
	)
	(via
		(at 240.763298 -59.55284)
		(size 0.508)
		(drill 0.254)
		(layers "F.Cu" "B.Cu")
		(net "GND")
	)
	(via
		(at 69.753226 -55.094886)
		(size 0.508)
		(drill 0.254)
		(layers "F.Cu" "B.Cu")
		(net "GND")
	)
	(via
		(at 393.68095 -123.821444)
		(size 0.508)
		(drill 0.254)
		(layers "F.Cu" "B.Cu")
		(net "GND")
	)
	(via
		(at 146.092164 -155.600146)
		(size 0.508)
		(drill 0.254)
		(layers "F.Cu" "B.Cu")
		(net "GND")
	)
	(via
		(at 388.9375 -106.6546)
		(size 0.508)
		(drill 0.254)
		(layers "F.Cu" "B.Cu")
		(net "GND")
	)
	(via
		(at 198.772018 -154.1018)
		(size 0.508)
		(drill 0.254)
		(layers "F.Cu" "B.Cu")
		(net "GND")
	)
	(via
		(at 67.949318 -17.208246)
		(size 0.508)
		(drill 0.254)
		(layers "F.Cu" "B.Cu")
		(net "GND")
	)
	(via
		(at 297.549824 -144.462246)
		(size 0.508)
		(drill 0.254)
		(layers "F.Cu" "B.Cu")
		(net "GND")
	)
	(via
		(at 296.66184 -87.108538)
		(size 0.508)
		(drill 0.254)
		(layers "F.Cu" "B.Cu")
		(net "GND")
	)
	(via
		(at 369.2398 -127.4064)
		(size 0.508)
		(drill 0.254)
		(layers "F.Cu" "B.Cu")
		(net "GND")
	)
	(via
		(at 273.915124 -162.243262)
		(size 0.5588)
		(drill 0.3048)
		(layers "F.Cu" "B.Cu")
		(net "GND")
	)
	(via
		(at 60.457334 -167.832024)
		(size 0.5588)
		(drill 0.3048)
		(layers "F.Cu" "B.Cu")
		(net "GND")
	)
	(via
		(at 52.471574 -144.5006)
		(size 0.508)
		(drill 0.254)
		(layers "F.Cu" "B.Cu")
		(net "GND")
	)
	(via
		(at 236.470698 -54.104286)
		(size 0.508)
		(drill 0.254)
		(layers "F.Cu" "B.Cu")
		(net "GND")
	)
	(via
		(at 218.436444 -23.495)
		(size 0.508)
		(drill 0.254)
		(layers "F.Cu" "B.Cu")
		(net "GND")
	)
	(via
		(at 222.749872 -155.612846)
		(size 0.508)
		(drill 0.254)
		(layers "F.Cu" "B.Cu")
		(net "GND")
	)
	(via
		(at 135.771636 -7.6454)
		(size 0.508)
		(drill 0.254)
		(layers "F.Cu" "B.Cu")
		(net "GND")
	)
	(via
		(at 344.802206 0.488696)
		(size 0.508)
		(drill 0.254)
		(layers "F.Cu" "B.Cu")
		(net "GND")
	)
	(via
		(at 184.803796 -94.859602)
		(size 0.508)
		(drill 0.254)
		(layers "F.Cu" "B.Cu")
		(net "GND")
	)
	(via
		(at 226.111816 -148.771356)
		(size 0.508)
		(drill 0.254)
		(layers "F.Cu" "B.Cu")
		(net "GND")
	)
	(via
		(at 125.711458 -129.568956)
		(size 0.508)
		(drill 0.254)
		(layers "F.Cu" "B.Cu")
		(net "GND")
	)
	(via
		(at 406.430734 -164.479224)
		(size 0.5588)
		(drill 0.3048)
		(layers "F.Cu" "B.Cu")
		(net "GND")
	)
	(via
		(at 322.06184 -7.237476)
		(size 0.508)
		(drill 0.254)
		(layers "F.Cu" "B.Cu")
		(net "GND")
	)
	(via
		(at 345.506294 -142.842742)
		(size 0.508)
		(drill 0.254)
		(layers "F.Cu" "B.Cu")
		(net "GND")
	)
	(via
		(at 475.0435 -137.6553)
		(size 0.508)
		(drill 0.254)
		(layers "F.Cu" "B.Cu")
		(net "GND")
	)
	(via
		(at 378.82195 -110.085124)
		(size 0.508)
		(drill 0.254)
		(layers "F.Cu" "B.Cu")
		(net "GND")
	)
	(via
		(at 17.251934 9.084056)
		(size 0.5588)
		(drill 0.3048)
		(layers "F.Cu" "B.Cu")
		(net "GND")
	)
	(via
		(at 17.07642 -100.93452)
		(size 0.508)
		(drill 0.254)
		(layers "F.Cu" "B.Cu")
		(net "GND")
	)
	(via
		(at 216.761822 -129.568956)
		(size 0.508)
		(drill 0.254)
		(layers "F.Cu" "B.Cu")
		(net "GND")
	)
	(via
		(at 78.338172 -57.076086)
		(size 0.508)
		(drill 0.254)
		(layers "F.Cu" "B.Cu")
		(net "GND")
	)
	(via
		(at 82.809334 -167.832024)
		(size 0.5588)
		(drill 0.3048)
		(layers "F.Cu" "B.Cu")
		(net "GND")
	)
	(via
		(at 147.390866 -7.095744)
		(size 0.508)
		(drill 0.254)
		(layers "F.Cu" "B.Cu")
		(net "GND")
	)
	(via
		(at 139.171934 9.084056)
		(size 0.5588)
		(drill 0.3048)
		(layers "F.Cu" "B.Cu")
		(net "GND")
	)
	(via
		(at 78.335124 -162.243262)
		(size 0.5588)
		(drill 0.3048)
		(layers "F.Cu" "B.Cu")
		(net "GND")
	)
	(via
		(at 373.512334 -167.857424)
		(size 0.5588)
		(drill 0.3048)
		(layers "F.Cu" "B.Cu")
		(net "GND")
	)
	(via
		(at 127.368808 -86.612984)
		(size 0.508)
		(drill 0.254)
		(layers "F.Cu" "B.Cu")
		(net "GND")
	)
	(via
		(at 351.4598 -31.8643)
		(size 0.508)
		(drill 0.254)
		(layers "F.Cu" "B.Cu")
		(net "GND")
	)
	(via
		(at 79.196692 -54.59984)
		(size 0.508)
		(drill 0.254)
		(layers "F.Cu" "B.Cu")
		(net "GND")
	)
	(via
		(at 173.155102 -152.546558)
		(size 0.5588)
		(drill 0.3048)
		(layers "F.Cu" "B.Cu")
		(net "GND")
	)
	(via
		(at 240.763298 -94.223586)
		(size 0.508)
		(drill 0.254)
		(layers "F.Cu" "B.Cu")
		(net "GND")
	)
	(via
		(at 209.092546 -11.912092)
		(size 0.508)
		(drill 0.254)
		(layers "F.Cu" "B.Cu")
		(net "GND")
	)
	(via
		(at 237.142528 -2.310892)
		(size 0.508)
		(drill 0.254)
		(layers "F.Cu" "B.Cu")
		(net "GND")
	)
	(via
		(at 287.79216 -61.847984)
		(size 0.508)
		(drill 0.254)
		(layers "F.Cu" "B.Cu")
		(net "GND")
	)
	(via
		(at 303.529746 -76.211938)
		(size 0.508)
		(drill 0.254)
		(layers "F.Cu" "B.Cu")
		(net "GND")
	)
	(via
		(at 418.1348 -1.3462)
		(size 0.508)
		(drill 0.254)
		(layers "F.Cu" "B.Cu")
		(net "GND")
	)
	(via
		(at 16.1544 -108.966)
		(size 0.508)
		(drill 0.254)
		(layers "F.Cu" "B.Cu")
		(net "GND")
	)
	(via
		(at 127.741934 9.084056)
		(size 0.5588)
		(drill 0.3048)
		(layers "F.Cu" "B.Cu")
		(net "GND")
	)
	(via
		(at 214.249762 -3.762756)
		(size 0.508)
		(drill 0.254)
		(layers "F.Cu" "B.Cu")
		(net "GND")
	)
	(via
		(at 361.218734 -167.857424)
		(size 0.5588)
		(drill 0.3048)
		(layers "F.Cu" "B.Cu")
		(net "GND")
	)
	(via
		(at 484.2256 -42.49166)
		(size 0.508)
		(drill 0.254)
		(layers "F.Cu" "B.Cu")
		(net "GND")
	)
	(via
		(at 233.895138 -99.17684)
		(size 0.508)
		(drill 0.254)
		(layers "F.Cu" "B.Cu")
		(net "GND")
	)
	(via
		(at 308.501796 -154.063446)
		(size 0.508)
		(drill 0.254)
		(layers "F.Cu" "B.Cu")
		(net "GND")
	)
	(via
		(at 196.908928 -88.679782)
		(size 0.508)
		(drill 0.254)
		(layers "F.Cu" "B.Cu")
		(net "GND")
	)
	(via
		(at 405.160734 -164.479224)
		(size 0.5588)
		(drill 0.3048)
		(layers "F.Cu" "B.Cu")
		(net "GND")
	)
	(via
		(at 54.731412 -139.1666)
		(size 0.508)
		(drill 0.254)
		(layers "F.Cu" "B.Cu")
		(net "GND")
	)
	(via
		(at 6.31952 -23.53818)
		(size 0.508)
		(drill 0.254)
		(layers "F.Cu" "B.Cu")
		(net "GND")
	)
	(via
		(at 245.914164 -97.19564)
		(size 0.508)
		(drill 0.254)
		(layers "F.Cu" "B.Cu")
		(net "GND")
	)
	(via
		(at 198.861934 14.926056)
		(size 0.5588)
		(drill 0.3048)
		(layers "F.Cu" "B.Cu")
		(net "GND")
	)
	(via
		(at 71.470266 -97.690686)
		(size 0.508)
		(drill 0.254)
		(layers "F.Cu" "B.Cu")
		(net "GND")
	)
	(via
		(at 94.8436 -150.8252)
		(size 0.508)
		(drill 0.254)
		(layers "F.Cu" "B.Cu")
		(net "GND")
	)
	(via
		(at 413.491934 14.926056)
		(size 0.5588)
		(drill 0.3048)
		(layers "F.Cu" "B.Cu")
		(net "GND")
	)
	(via
		(at 238.444532 -9.0805)
		(size 0.508)
		(drill 0.254)
		(layers "F.Cu" "B.Cu")
		(net "GND")
	)
	(via
		(at 200.881234 -79.683864)
		(size 0.508)
		(drill 0.254)
		(layers "F.Cu" "B.Cu")
		(net "GND")
	)
	(via
		(at 238.437928 -131.600956)
		(size 0.508)
		(drill 0.254)
		(layers "F.Cu" "B.Cu")
		(net "GND")
	)
	(via
		(at 221.899734 1.994154)
		(size 0.508)
		(drill 0.254)
		(layers "F.Cu" "B.Cu")
		(net "GND")
	)
	(via
		(at 480.090734 -165.596824)
		(size 0.5588)
		(drill 0.3048)
		(layers "F.Cu" "B.Cu")
		(net "GND")
	)
	(via
		(at 233.8578 -125.969776)
		(size 0.508)
		(drill 0.254)
		(layers "F.Cu" "B.Cu")
		(net "GND")
	)
	(via
		(at 445.792606 -38.2905)
		(size 0.4572)
		(drill 0.2032)
		(layers "F.Cu" "B.Cu")
		(net "GND")
	)
	(via
		(at 381.79375 -95.888556)
		(size 0.508)
		(drill 0.254)
		(layers "F.Cu" "B.Cu")
		(net "GND")
	)
	(via
		(at 315.399928 -2.314956)
		(size 0.508)
		(drill 0.254)
		(layers "F.Cu" "B.Cu")
		(net "GND")
	)
	(via
		(at 135.061452 -139.170156)
		(size 0.508)
		(drill 0.254)
		(layers "F.Cu" "B.Cu")
		(net "GND")
	)
	(via
		(at 234.753658 -83.822286)
		(size 0.508)
		(drill 0.254)
		(layers "F.Cu" "B.Cu")
		(net "GND")
	)
	(via
		(at 262.881618 -75.148186)
		(size 0.5588)
		(drill 0.3048)
		(layers "F.Cu" "B.Cu")
		(net "GND")
	)
	(via
		(at 35.499802 -91.313)
		(size 0.508)
		(drill 0.254)
		(layers "F.Cu" "B.Cu")
		(net "GND")
	)
	(via
		(at 284.33776 -13.948156)
		(size 0.508)
		(drill 0.254)
		(layers "F.Cu" "B.Cu")
		(net "GND")
	)
	(via
		(at 181.081934 9.084056)
		(size 0.5588)
		(drill 0.3048)
		(layers "F.Cu" "B.Cu")
		(net "GND")
	)
	(via
		(at -3.1623 -150.10511)
		(size 0.508)
		(drill 0.254)
		(layers "F.Cu" "B.Cu")
		(net "GND")
	)
	(via
		(at 126.421642 -131.016756)
		(size 0.508)
		(drill 0.254)
		(layers "F.Cu" "B.Cu")
		(net "GND")
	)
	(via
		(at 405.43988 -27.80538)
		(size 0.4572)
		(drill 0.2032)
		(layers "F.Cu" "B.Cu")
		(net "GND")
	)
	(via
		(at 242.480338 -62.52464)
		(size 0.508)
		(drill 0.254)
		(layers "F.Cu" "B.Cu")
		(net "GND")
	)
	(via
		(at 297.520106 -80.669384)
		(size 0.508)
		(drill 0.254)
		(layers "F.Cu" "B.Cu")
		(net "GND")
	)
	(via
		(at 291.51072 -77.202538)
		(size 0.508)
		(drill 0.254)
		(layers "F.Cu" "B.Cu")
		(net "GND")
	)
	(via
		(at 345.929204 -148.980398)
		(size 0.508)
		(drill 0.254)
		(layers "F.Cu" "B.Cu")
		(net "GND")
	)
	(via
		(at 51.79949 -136.410446)
		(size 0.508)
		(drill 0.254)
		(layers "F.Cu" "B.Cu")
		(net "GND")
	)
	(via
		(at 175.478694 -51.896518)
		(size 0.508)
		(drill 0.254)
		(layers "F.Cu" "B.Cu")
		(net "GND")
	)
	(via
		(at 75.762866 -87.28964)
		(size 0.508)
		(drill 0.254)
		(layers "F.Cu" "B.Cu")
		(net "GND")
	)
	(via
		(at 341.101934 9.084056)
		(size 0.5588)
		(drill 0.3048)
		(layers "F.Cu" "B.Cu")
		(net "GND")
	)
	(via
		(at 407.3271 -105.529126)
		(size 0.508)
		(drill 0.254)
		(layers "F.Cu" "B.Cu")
		(net "GND")
	)
	(via
		(at 302.671226 -91.565984)
		(size 0.508)
		(drill 0.254)
		(layers "F.Cu" "B.Cu")
		(net "GND")
	)
	(via
		(at 237.149132 -7.1501)
		(size 0.508)
		(drill 0.254)
		(layers "F.Cu" "B.Cu")
		(net "GND")
	)
	(via
		(at 119.357902 -81.659984)
		(size 0.508)
		(drill 0.254)
		(layers "F.Cu" "B.Cu")
		(net "GND")
	)
	(via
		(at 198.772018 -13.363956)
		(size 0.508)
		(drill 0.254)
		(layers "F.Cu" "B.Cu")
		(net "GND")
	)
	(via
		(at 205.749906 -129.568956)
		(size 0.508)
		(drill 0.254)
		(layers "F.Cu" "B.Cu")
		(net "GND")
	)
	(via
		(at 286.3596 -81.164938)
		(size 0.508)
		(drill 0.254)
		(layers "F.Cu" "B.Cu")
		(net "GND")
	)
	(via
		(at 403.890734 -166.714424)
		(size 0.5588)
		(drill 0.3048)
		(layers "F.Cu" "B.Cu")
		(net "GND")
	)
	(via
		(at 48.399446 -11.916156)
		(size 0.508)
		(drill 0.254)
		(layers "F.Cu" "B.Cu")
		(net "GND")
	)
	(via
		(at 263.94283 -56.085486)
		(size 0.508)
		(drill 0.254)
		(layers "F.Cu" "B.Cu")
		(net "GND")
	)
	(via
		(at 335.7372 -133.4643)
		(size 0.508)
		(drill 0.254)
		(layers "F.Cu" "B.Cu")
		(net "GND")
	)
	(via
		(at 86.064852 -79.36484)
		(size 0.508)
		(drill 0.254)
		(layers "F.Cu" "B.Cu")
		(net "GND")
	)
	(via
		(at 286.208724 -162.243262)
		(size 0.5588)
		(drill 0.3048)
		(layers "F.Cu" "B.Cu")
		(net "GND")
	)
	(via
		(at 232.94975 -22.965156)
		(size 0.508)
		(drill 0.254)
		(layers "F.Cu" "B.Cu")
		(net "GND")
	)
	(via
		(at 494.31067 -58.507376)
		(size 0.508)
		(drill 0.254)
		(layers "F.Cu" "B.Cu")
		(net "GND")
	)
	(via
		(at 341.376 -21.082)
		(size 0.508)
		(drill 0.254)
		(layers "F.Cu" "B.Cu")
		(net "GND")
	)
	(via
		(at 395.000734 -167.832024)
		(size 0.5588)
		(drill 0.3048)
		(layers "F.Cu" "B.Cu")
		(net "GND")
	)
	(via
		(at 105.571036 -56.894984)
		(size 0.508)
		(drill 0.254)
		(layers "F.Cu" "B.Cu")
		(net "GND")
	)
	(via
		(at 335.7372 -135.3185)
		(size 0.508)
		(drill 0.254)
		(layers "F.Cu" "B.Cu")
		(net "GND")
	)
	(via
		(at 290.6522 -92.556584)
		(size 0.508)
		(drill 0.254)
		(layers "F.Cu" "B.Cu")
		(net "GND")
	)
	(via
		(at 232.960418 -93.72854)
		(size 0.508)
		(drill 0.254)
		(layers "F.Cu" "B.Cu")
		(net "GND")
	)
	(via
		(at 14.732 -52.451)
		(size 0.5588)
		(drill 0.3048)
		(layers "F.Cu" "B.Cu")
		(net "GND")
	)
	(via
		(at 51.76139 -2.314956)
		(size 0.508)
		(drill 0.254)
		(layers "F.Cu" "B.Cu")
		(net "GND")
	)
	(via
		(at 176.001934 9.084056)
		(size 0.5588)
		(drill 0.3048)
		(layers "F.Cu" "B.Cu")
		(net "GND")
	)
	(via
		(at 319.511934 14.926056)
		(size 0.5588)
		(drill 0.3048)
		(layers "F.Cu" "B.Cu")
		(net "GND")
	)
	(via
		(at 74.045826 -83.32724)
		(size 0.508)
		(drill 0.254)
		(layers "F.Cu" "B.Cu")
		(net "GND")
	)
	(via
		(at 180.093112 -125.8824)
		(size 0.508)
		(drill 0.254)
		(layers "F.Cu" "B.Cu")
		(net "GND")
	)
	(via
		(at 249.061224 -51.119532)
		(size 0.4572)
		(drill 0.2032)
		(layers "F.Cu" "B.Cu")
		(net "GND")
	)
	(via
		(at 340.579964 -68.27393)
		(size 0.508)
		(drill 0.254)
		(layers "F.Cu" "B.Cu")
		(net "GND")
	)
	(via
		(at 67.099434 0.444754)
		(size 0.508)
		(drill 0.254)
		(layers "F.Cu" "B.Cu")
		(net "GND")
	)
	(via
		(at 455.401934 13.910056)
		(size 0.5588)
		(drill 0.3048)
		(layers "F.Cu" "B.Cu")
		(net "GND")
	)
	(via
		(at 245.914164 -91.25204)
		(size 0.508)
		(drill 0.254)
		(layers "F.Cu" "B.Cu")
		(net "GND")
	)
	(via
		(at 117.071648 -22.939756)
		(size 0.508)
		(drill 0.254)
		(layers "F.Cu" "B.Cu")
		(net "GND")
	)
	(via
		(at 438.833006 -40.5257)
		(size 0.508)
		(drill 0.254)
		(layers "F.Cu" "B.Cu")
		(net "GND")
	)
	(via
		(at 91.089226 -8.468868)
		(size 0.508)
		(drill 0.254)
		(layers "F.Cu" "B.Cu")
		(net "GND")
	)
	(via
		(at 239.749838 0.444754)
		(size 0.508)
		(drill 0.254)
		(layers "F.Cu" "B.Cu")
		(net "GND")
	)
	(via
		(at 436.921656 -30.6324)
		(size 0.4572)
		(drill 0.2032)
		(layers "F.Cu" "B.Cu")
		(net "GND")
	)
	(via
		(at 195.051934 9.084056)
		(size 0.5588)
		(drill 0.3048)
		(layers "F.Cu" "B.Cu")
		(net "GND")
	)
	(via
		(at 261.2136 -1.651)
		(size 0.508)
		(drill 0.254)
		(layers "F.Cu" "B.Cu")
		(net "GND")
	)
	(via
		(at 334.751934 14.926056)
		(size 0.5588)
		(drill 0.3048)
		(layers "F.Cu" "B.Cu")
		(net "GND")
	)
	(via
		(at 45.381418 -11.9126)
		(size 0.508)
		(drill 0.254)
		(layers "F.Cu" "B.Cu")
		(net "GND")
	)
	(via
		(at 283.499814 -52.437284)
		(size 0.508)
		(drill 0.254)
		(layers "F.Cu" "B.Cu")
		(net "GND")
	)
	(via
		(at 469.371934 10.354056)
		(size 0.5588)
		(drill 0.3048)
		(layers "F.Cu" "B.Cu")
		(net "GND")
	)
	(via
		(at 499.140734 -163.361624)
		(size 0.5588)
		(drill 0.3048)
		(layers "F.Cu" "B.Cu")
		(net "GND")
	)
	(via
		(at 15.981934 14.926056)
		(size 0.5588)
		(drill 0.3048)
		(layers "F.Cu" "B.Cu")
		(net "GND")
	)
	(via
		(at 74.749406 -11.916156)
		(size 0.508)
		(drill 0.254)
		(layers "F.Cu" "B.Cu")
		(net "GND")
	)
	(via
		(at 205.881986 -92.60205)
		(size 0.5588)
		(drill 0.3048)
		(layers "F.Cu" "B.Cu")
		(net "GND")
	)
	(via
		(at 284.341062 -153.552144)
		(size 0.508)
		(drill 0.254)
		(layers "F.Cu" "B.Cu")
		(net "GND")
	)
	(via
		(at 464.5533 -53.2384)
		(size 0.508)
		(drill 0.254)
		(layers "F.Cu" "B.Cu")
		(net "GND")
	)
	(via
		(at 15.001494 -0.120904)
		(size 0.508)
		(drill 0.254)
		(layers "F.Cu" "B.Cu")
		(net "GND")
	)
	(via
		(at 180.447442 -106.025442)
		(size 0.508)
		(drill 0.254)
		(layers "F.Cu" "B.Cu")
		(net "GND")
	)
	(via
		(at 280.924254 -63.829184)
		(size 0.508)
		(drill 0.254)
		(layers "F.Cu" "B.Cu")
		(net "GND")
	)
	(via
		(at 426.750734 -167.832024)
		(size 0.5588)
		(drill 0.3048)
		(layers "F.Cu" "B.Cu")
		(net "GND")
	)
	(via
		(at 74.045826 -80.35544)
		(size 0.508)
		(drill 0.254)
		(layers "F.Cu" "B.Cu")
		(net "GND")
	)
	(via
		(at 148.747734 -167.832024)
		(size 0.5588)
		(drill 0.3048)
		(layers "F.Cu" "B.Cu")
		(net "GND")
	)
	(via
		(at 75.762866 -78.37424)
		(size 0.508)
		(drill 0.254)
		(layers "F.Cu" "B.Cu")
		(net "GND")
	)
	(via
		(at 175.505364 -151.67102)
		(size 0.5588)
		(drill 0.3048)
		(layers "F.Cu" "B.Cu")
		(net "GND")
	)
	(via
		(at 355.00056 -78.900274)
		(size 0.508)
		(drill 0.254)
		(layers "F.Cu" "B.Cu")
		(net "GND")
	)
	(via
		(at 279.207214 -62.838584)
		(size 0.508)
		(drill 0.254)
		(layers "F.Cu" "B.Cu")
		(net "GND")
	)
	(via
		(at 373.330978 -0.753618)
		(size 0.508)
		(drill 0.254)
		(layers "F.Cu" "B.Cu")
		(net "GND")
	)
	(via
		(at 167.743124 -162.243262)
		(size 0.5588)
		(drill 0.3048)
		(layers "F.Cu" "B.Cu")
		(net "GND")
	)
	(via
		(at 62.792102 -139.166092)
		(size 0.508)
		(drill 0.254)
		(layers "F.Cu" "B.Cu")
		(net "GND")
	)
	(via
		(at 237.142528 -126.655576)
		(size 0.508)
		(drill 0.254)
		(layers "F.Cu" "B.Cu")
		(net "GND")
	)
	(via
		(at 249.348244 -90.26144)
		(size 0.508)
		(drill 0.254)
		(layers "F.Cu" "B.Cu")
		(net "GND")
	)
	(via
		(at 87.781892 -81.34604)
		(size 0.508)
		(drill 0.254)
		(layers "F.Cu" "B.Cu")
		(net "GND")
	)
	(via
		(at 368.6556 -116.7892)
		(size 0.508)
		(drill 0.254)
		(layers "F.Cu" "B.Cu")
		(net "GND")
	)
	(via
		(at 231.249728 -7.607046)
		(size 0.508)
		(drill 0.254)
		(layers "F.Cu" "B.Cu")
		(net "GND")
	)
	(via
		(at 190.430404 -52.079398)
		(size 0.508)
		(drill 0.254)
		(layers "F.Cu" "B.Cu")
		(net "GND")
	)
	(via
		(at 249.348244 -74.411586)
		(size 0.508)
		(drill 0.254)
		(layers "F.Cu" "B.Cu")
		(net "GND")
	)
	(via
		(at 283.036264 -131.5466)
		(size 0.508)
		(drill 0.254)
		(layers "F.Cu" "B.Cu")
		(net "GND")
	)
	(via
		(at 445.340994 -50.4698)
		(size 0.508)
		(drill 0.254)
		(layers "F.Cu" "B.Cu")
		(net "GND")
	)
	(via
		(at 445.796924 -162.243262)
		(size 0.5588)
		(drill 0.3048)
		(layers "F.Cu" "B.Cu")
		(net "GND")
	)
	(via
		(at 226.979734 -167.832024)
		(size 0.5588)
		(drill 0.3048)
		(layers "F.Cu" "B.Cu")
		(net "GND")
	)
	(via
		(at 129.944368 -80.174338)
		(size 0.508)
		(drill 0.254)
		(layers "F.Cu" "B.Cu")
		(net "GND")
	)
	(via
		(at 12.3952 -71.7804)
		(size 0.508)
		(drill 0.254)
		(layers "F.Cu" "B.Cu")
		(net "GND")
	)
	(via
		(at 245.055644 -83.822286)
		(size 0.508)
		(drill 0.254)
		(layers "F.Cu" "B.Cu")
		(net "GND")
	)
	(via
		(at -1.010666 -166.714424)
		(size 0.5588)
		(drill 0.3048)
		(layers "F.Cu" "B.Cu")
		(net "GND")
	)
	(via
		(at 432.541934 10.354056)
		(size 0.5588)
		(drill 0.3048)
		(layers "F.Cu" "B.Cu")
		(net "GND")
	)
	(via
		(at 289.801808 -17.208246)
		(size 0.508)
		(drill 0.254)
		(layers "F.Cu" "B.Cu")
		(net "GND")
	)
	(via
		(at 119.343932 -136.3345)
		(size 0.508)
		(drill 0.254)
		(layers "F.Cu" "B.Cu")
		(net "GND")
	)
	(via
		(at 254.919734 -167.832024)
		(size 0.5588)
		(drill 0.3048)
		(layers "F.Cu" "B.Cu")
		(net "GND")
	)
	(via
		(at 317.09995 -9.156446)
		(size 0.508)
		(drill 0.254)
		(layers "F.Cu" "B.Cu")
		(net "GND")
	)
	(via
		(at 170.28922 -7.430262)
		(size 0.508)
		(drill 0.254)
		(layers "F.Cu" "B.Cu")
		(net "GND")
	)
	(via
		(at 133.39953 -139.170156)
		(size 0.508)
		(drill 0.254)
		(layers "F.Cu" "B.Cu")
		(net "GND")
	)
	(via
		(at 255.862328 -145.29054)
		(size 0.508)
		(drill 0.254)
		(layers "F.Cu" "B.Cu")
		(net "GND")
	)
	(via
		(at 264.710418 -75.148186)
		(size 0.5588)
		(drill 0.3048)
		(layers "F.Cu" "B.Cu")
		(net "GND")
	)
	(via
		(at 241.621818 -53.113686)
		(size 0.508)
		(drill 0.254)
		(layers "F.Cu" "B.Cu")
		(net "GND")
	)
	(via
		(at 186.048396 -85.944202)
		(size 0.508)
		(drill 0.254)
		(layers "F.Cu" "B.Cu")
		(net "GND")
	)
	(via
		(at 411.510734 -163.361624)
		(size 0.5588)
		(drill 0.3048)
		(layers "F.Cu" "B.Cu")
		(net "GND")
	)
	(via
		(at 78.338172 -61.038486)
		(size 0.508)
		(drill 0.254)
		(layers "F.Cu" "B.Cu")
		(net "GND")
	)
	(via
		(at 123.076208 -98.005138)
		(size 0.508)
		(drill 0.254)
		(layers "F.Cu" "B.Cu")
		(net "GND")
	)
	(via
		(at 455.7522 -53.2638)
		(size 0.508)
		(drill 0.254)
		(layers "F.Cu" "B.Cu")
		(net "GND")
	)
	(via
		(at 196.908928 -89.314782)
		(size 0.508)
		(drill 0.254)
		(layers "F.Cu" "B.Cu")
		(net "GND")
	)
	(via
		(at 357.4161 -13.426186)
		(size 0.508)
		(drill 0.254)
		(layers "F.Cu" "B.Cu")
		(net "GND")
	)
	(via
		(at 317.09995 -134.340346)
		(size 0.508)
		(drill 0.254)
		(layers "F.Cu" "B.Cu")
		(net "GND")
	)
	(via
		(at 41.7322 -52.79898)
		(size 0.5588)
		(drill 0.3048)
		(layers "F.Cu" "B.Cu")
		(net "GND")
	)
	(via
		(at 395.16685 -119.528844)
		(size 0.508)
		(drill 0.254)
		(layers "F.Cu" "B.Cu")
		(net "GND")
	)
	(via
		(at 344.1954 -111.125)
		(size 0.508)
		(drill 0.254)
		(layers "F.Cu" "B.Cu")
		(net "GND")
	)
	(via
		(at 203.941934 14.926056)
		(size 0.5588)
		(drill 0.3048)
		(layers "F.Cu" "B.Cu")
		(net "GND")
	)
	(via
		(at 217.911934 14.926056)
		(size 0.5588)
		(drill 0.3048)
		(layers "F.Cu" "B.Cu")
		(net "GND")
	)
	(via
		(at 206.245714 -77.814678)
		(size 0.5588)
		(drill 0.3048)
		(layers "F.Cu" "B.Cu")
		(net "GND")
	)
	(via
		(at 303.001934 14.926056)
		(size 0.5588)
		(drill 0.3048)
		(layers "F.Cu" "B.Cu")
		(net "GND")
	)
	(via
		(at 234.5944 -124.750576)
		(size 0.508)
		(drill 0.254)
		(layers "F.Cu" "B.Cu")
		(net "GND")
	)
	(via
		(at 120.121934 14.926056)
		(size 0.5588)
		(drill 0.3048)
		(layers "F.Cu" "B.Cu")
		(net "GND")
	)
	(via
		(at 442.564774 -148.72462)
		(size 0.508)
		(drill 0.254)
		(layers "F.Cu" "B.Cu")
		(net "GND")
	)
	(via
		(at 75.762866 -98.18624)
		(size 0.508)
		(drill 0.254)
		(layers "F.Cu" "B.Cu")
		(net "GND")
	)
	(via
		(at 86.923372 -70.94474)
		(size 0.508)
		(drill 0.254)
		(layers "F.Cu" "B.Cu")
		(net "GND")
	)
	(via
		(at 421.670734 -163.361624)
		(size 0.5588)
		(drill 0.3048)
		(layers "F.Cu" "B.Cu")
		(net "GND")
	)
	(via
		(at 201.274934 -167.832024)
		(size 0.5588)
		(drill 0.3048)
		(layers "F.Cu" "B.Cu")
		(net "GND")
	)
	(via
		(at 375.084848 -3.420364)
		(size 0.508)
		(drill 0.254)
		(layers "F.Cu" "B.Cu")
		(net "GND")
	)
	(via
		(at 307.749956 0.457454)
		(size 0.508)
		(drill 0.254)
		(layers "F.Cu" "B.Cu")
		(net "GND")
	)
	(via
		(at 200.914 -62.0776)
		(size 0.5588)
		(drill 0.3048)
		(layers "F.Cu" "B.Cu")
		(net "GND")
	)
	(via
		(at 79.196692 -97.19564)
		(size 0.508)
		(drill 0.254)
		(layers "F.Cu" "B.Cu")
		(net "GND")
	)
	(via
		(at 1.016 -129.413)
		(size 0.508)
		(drill 0.254)
		(layers "F.Cu" "B.Cu")
		(net "GND")
	)
	(via
		(at 27.411934 14.926056)
		(size 0.5588)
		(drill 0.3048)
		(layers "F.Cu" "B.Cu")
		(net "GND")
	)
	(via
		(at 292.399212 -26.73731)
		(size 0.508)
		(drill 0.254)
		(layers "F.Cu" "B.Cu")
		(net "GND")
	)
	(via
		(at 345.0336 -88.9254)
		(size 0.508)
		(drill 0.254)
		(layers "F.Cu" "B.Cu")
		(net "GND")
	)
	(via
		(at 239.904778 -51.132486)
		(size 0.508)
		(drill 0.254)
		(layers "F.Cu" "B.Cu")
		(net "GND")
	)
	(via
		(at 145.5674 -65.6844)
		(size 0.508)
		(drill 0.254)
		(layers "F.Cu" "B.Cu")
		(net "GND")
	)
	(via
		(at 128.227328 -86.117938)
		(size 0.508)
		(drill 0.254)
		(layers "F.Cu" "B.Cu")
		(net "GND")
	)
	(via
		(at 206.093314 -94.604078)
		(size 0.5588)
		(drill 0.3048)
		(layers "F.Cu" "B.Cu")
		(net "GND")
	)
	(via
		(at 86.923372 -66.982086)
		(size 0.508)
		(drill 0.254)
		(layers "F.Cu" "B.Cu")
		(net "GND")
	)
	(via
		(at 346.07754 -91.622118)
		(size 0.508)
		(drill 0.254)
		(layers "F.Cu" "B.Cu")
		(net "GND")
	)
	(via
		(at 285.2166 -65.315338)
		(size 0.508)
		(drill 0.254)
		(layers "F.Cu" "B.Cu")
		(net "GND")
	)
	(via
		(at 21.387308 2.89433)
		(size 0.508)
		(drill 0.254)
		(layers "F.Cu" "B.Cu")
		(net "GND")
	)
	(via
		(at 229.094538 -145.9357)
		(size 0.508)
		(drill 0.254)
		(layers "F.Cu" "B.Cu")
		(net "GND")
	)
	(via
		(at 232.101898 -90.26144)
		(size 0.508)
		(drill 0.254)
		(layers "F.Cu" "B.Cu")
		(net "GND")
	)
	(via
		(at 352.711258 -8.898128)
		(size 0.508)
		(drill 0.254)
		(layers "F.Cu" "B.Cu")
		(net "GND")
	)
	(via
		(at 150.601934 9.084056)
		(size 0.5588)
		(drill 0.3048)
		(layers "F.Cu" "B.Cu")
		(net "GND")
	)
	(via
		(at 272.015204 -70.84314)
		(size 0.5588)
		(drill 0.3048)
		(layers "F.Cu" "B.Cu")
		(net "GND")
	)
	(via
		(at 465.9122 -10.4394)
		(size 0.508)
		(drill 0.254)
		(layers "F.Cu" "B.Cu")
		(net "GND")
	)
	(via
		(at 376.555 -110.3884)
		(size 0.508)
		(drill 0.254)
		(layers "F.Cu" "B.Cu")
		(net "GND")
	)
	(via
		(at 434.366924 -162.243262)
		(size 0.5588)
		(drill 0.3048)
		(layers "F.Cu" "B.Cu")
		(net "GND")
	)
	(via
		(at 247.631204 -86.29904)
		(size 0.508)
		(drill 0.254)
		(layers "F.Cu" "B.Cu")
		(net "GND")
	)
	(via
		(at 350.5454 -40.64)
		(size 0.508)
		(drill 0.254)
		(layers "F.Cu" "B.Cu")
		(net "GND")
	)
	(via
		(at 447.781934 10.354056)
		(size 0.5588)
		(drill 0.3048)
		(layers "F.Cu" "B.Cu")
		(net "GND")
	)
	(via
		(at 31.19628 -62.009782)
		(size 0.508)
		(drill 0.254)
		(layers "F.Cu" "B.Cu")
		(net "GND")
	)
	(via
		(at 257.281934 9.084056)
		(size 0.5588)
		(drill 0.3048)
		(layers "F.Cu" "B.Cu")
		(net "GND")
	)
	(via
		(at 42.121582 -78.449678)
		(size 0.5588)
		(drill 0.3048)
		(layers "F.Cu" "B.Cu")
		(net "GND")
	)
	(via
		(at 383.672334 -167.832024)
		(size 0.5588)
		(drill 0.3048)
		(layers "F.Cu" "B.Cu")
		(net "GND")
	)
	(via
		(at 238.431832 -148.7678)
		(size 0.508)
		(drill 0.254)
		(layers "F.Cu" "B.Cu")
		(net "GND")
	)
	(via
		(at 397.536924 -162.243262)
		(size 0.5588)
		(drill 0.3048)
		(layers "F.Cu" "B.Cu")
		(net "GND")
	)
	(via
		(at 109.055916 -56.894984)
		(size 0.508)
		(drill 0.254)
		(layers "F.Cu" "B.Cu")
		(net "GND")
	)
	(via
		(at 180.1368 -50.4698)
		(size 0.508)
		(drill 0.254)
		(layers "F.Cu" "B.Cu")
		(net "GND")
	)
	(via
		(at 138.03757 -126.722886)
		(size 0.508)
		(drill 0.254)
		(layers "F.Cu" "B.Cu")
		(net "GND")
	)
	(via
		(at 45.394118 -9.0805)
		(size 0.508)
		(drill 0.254)
		(layers "F.Cu" "B.Cu")
		(net "GND")
	)
	(via
		(at 80.055212 -56.085486)
		(size 0.508)
		(drill 0.254)
		(layers "F.Cu" "B.Cu")
		(net "GND")
	)
	(via
		(at 408.966924 -162.243262)
		(size 0.5588)
		(drill 0.3048)
		(layers "F.Cu" "B.Cu")
		(net "GND")
	)
	(via
		(at 489.8136 -53.975)
		(size 0.508)
		(drill 0.254)
		(layers "F.Cu" "B.Cu")
		(net "GND")
	)
	(via
		(at 437.621934 10.354056)
		(size 0.5588)
		(drill 0.3048)
		(layers "F.Cu" "B.Cu")
		(net "GND")
	)
	(via
		(at 126.421642 -140.617956)
		(size 0.508)
		(drill 0.254)
		(layers "F.Cu" "B.Cu")
		(net "GND")
	)
	(via
		(at 414.050734 -166.714424)
		(size 0.5588)
		(drill 0.3048)
		(layers "F.Cu" "B.Cu")
		(net "GND")
	)
	(via
		(at 281.208734 -98.005138)
		(size 0.508)
		(drill 0.254)
		(layers "F.Cu" "B.Cu")
		(net "GND")
	)
	(via
		(at 48.650398 -61.084206)
		(size 0.508)
		(drill 0.254)
		(layers "F.Cu" "B.Cu")
		(net "GND")
	)
	(via
		(at 349.494094 -154.729942)
		(size 0.508)
		(drill 0.254)
		(layers "F.Cu" "B.Cu")
		(net "GND")
	)
	(via
		(at 107.027472 -12.954)
		(size 0.508)
		(drill 0.254)
		(layers "F.Cu" "B.Cu")
		(net "GND")
	)
	(via
		(at 474.505528 -151.67102)
		(size 0.5588)
		(drill 0.3048)
		(layers "F.Cu" "B.Cu")
		(net "GND")
	)
	(via
		(at 231.881934 9.084056)
		(size 0.5588)
		(drill 0.3048)
		(layers "F.Cu" "B.Cu")
		(net "GND")
	)
	(via
		(at 207.4926 -58.6486)
		(size 0.5588)
		(drill 0.3048)
		(layers "F.Cu" "B.Cu")
		(net "GND")
	)
	(via
		(at 113.381282 -75.143614)
		(size 0.5588)
		(drill 0.3048)
		(layers "F.Cu" "B.Cu")
		(net "GND")
	)
	(via
		(at 77.479906 -55.59044)
		(size 0.508)
		(drill 0.254)
		(layers "F.Cu" "B.Cu")
		(net "GND")
	)
	(via
		(at 238.431832 -2.3114)
		(size 0.508)
		(drill 0.254)
		(layers "F.Cu" "B.Cu")
		(net "GND")
	)
	(via
		(at 310.122062 -7.6454)
		(size 0.508)
		(drill 0.254)
		(layers "F.Cu" "B.Cu")
		(net "GND")
	)
	(via
		(at 291.51072 -81.164938)
		(size 0.508)
		(drill 0.254)
		(layers "F.Cu" "B.Cu")
		(net "GND")
	)
	(via
		(at 19.317208 -106.91749)
		(size 0.5588)
		(drill 0.3048)
		(layers "F.Cu" "B.Cu")
		(net "GND")
	)
	(via
		(at 303.67097 -103.066342)
		(size 0.508)
		(drill 0.254)
		(layers "F.Cu" "B.Cu")
		(net "GND")
	)
	(via
		(at 76.449428 -2.314956)
		(size 0.508)
		(drill 0.254)
		(layers "F.Cu" "B.Cu")
		(net "GND")
	)
	(via
		(at 305.246786 -96.023938)
		(size 0.508)
		(drill 0.254)
		(layers "F.Cu" "B.Cu")
		(net "GND")
	)
	(via
		(at 245.914164 -55.59044)
		(size 0.508)
		(drill 0.254)
		(layers "F.Cu" "B.Cu")
		(net "GND")
	)
	(via
		(at 295.80332 -57.885584)
		(size 0.508)
		(drill 0.254)
		(layers "F.Cu" "B.Cu")
		(net "GND")
	)
	(via
		(at 95.508318 -53.113686)
		(size 0.508)
		(drill 0.254)
		(layers "F.Cu" "B.Cu")
		(net "GND")
	)
	(via
		(at 250.206764 -63.019686)
		(size 0.508)
		(drill 0.254)
		(layers "F.Cu" "B.Cu")
		(net "GND")
	)
	(via
		(at 118.041928 -139.166092)
		(size 0.508)
		(drill 0.254)
		(layers "F.Cu" "B.Cu")
		(net "GND")
	)
	(via
		(at 357.82504 -77.377798)
		(size 0.508)
		(drill 0.254)
		(layers "F.Cu" "B.Cu")
		(net "GND")
	)
	(via
		(at 127.368808 -67.791584)
		(size 0.508)
		(drill 0.254)
		(layers "F.Cu" "B.Cu")
		(net "GND")
	)
	(via
		(at 245.055644 -61.038486)
		(size 0.508)
		(drill 0.254)
		(layers "F.Cu" "B.Cu")
		(net "GND")
	)
	(via
		(at -3.245866 -163.361624)
		(size 0.5588)
		(drill 0.3048)
		(layers "F.Cu" "B.Cu")
		(net "GND")
	)
	(via
		(at 115.550188 -75.143614)
		(size 0.5588)
		(drill 0.3048)
		(layers "F.Cu" "B.Cu")
		(net "GND")
	)
	(via
		(at 60.431934 9.084056)
		(size 0.5588)
		(drill 0.3048)
		(layers "F.Cu" "B.Cu")
		(net "GND")
	)
	(via
		(at 396.132558 -60.0202)
		(size 0.508)
		(drill 0.254)
		(layers "F.Cu" "B.Cu")
		(net "GND")
	)
	(via
		(at 127.39624 -126.712218)
		(size 0.508)
		(drill 0.254)
		(layers "F.Cu" "B.Cu")
		(net "GND")
	)
	(via
		(at 355.673152 -144.805146)
		(size 0.508)
		(drill 0.254)
		(layers "F.Cu" "B.Cu")
		(net "GND")
	)
	(via
		(at 85.206332 -63.019686)
		(size 0.508)
		(drill 0.254)
		(layers "F.Cu" "B.Cu")
		(net "GND")
	)
	(via
		(at 238.437928 -23.549356)
		(size 0.508)
		(drill 0.254)
		(layers "F.Cu" "B.Cu")
		(net "GND")
	)
	(via
		(at 157.528768 -135.376412)
		(size 0.508)
		(drill 0.254)
		(layers "F.Cu" "B.Cu")
		(net "GND")
	)
	(via
		(at 297.549824 -154.063446)
		(size 0.508)
		(drill 0.254)
		(layers "F.Cu" "B.Cu")
		(net "GND")
	)
	(via
		(at 339.545422 -77.161136)
		(size 0.508)
		(drill 0.254)
		(layers "F.Cu" "B.Cu")
		(net "GND")
	)
	(via
		(at 391.5156 -3.175)
		(size 0.508)
		(drill 0.254)
		(layers "F.Cu" "B.Cu")
		(net "GND")
	)
	(via
		(at 416.9664 -24.511)
		(size 0.508)
		(drill 0.254)
		(layers "F.Cu" "B.Cu")
		(net "GND")
	)
	(via
		(at 457.941934 13.910056)
		(size 0.5588)
		(drill 0.3048)
		(layers "F.Cu" "B.Cu")
		(net "GND")
	)
	(via
		(at 433.811934 11.624056)
		(size 0.5588)
		(drill 0.3048)
		(layers "F.Cu" "B.Cu")
		(net "GND")
	)
	(via
		(at 383.668524 -162.243262)
		(size 0.5588)
		(drill 0.3048)
		(layers "F.Cu" "B.Cu")
		(net "GND")
	)
	(via
		(at 272.797524 -162.243262)
		(size 0.5588)
		(drill 0.3048)
		(layers "F.Cu" "B.Cu")
		(net "GND")
	)
	(via
		(at 293.688008 -4.346956)
		(size 0.508)
		(drill 0.254)
		(layers "F.Cu" "B.Cu")
		(net "GND")
	)
	(via
		(at 36.186364 -68.321428)
		(size 0.5588)
		(drill 0.3048)
		(layers "F.Cu" "B.Cu")
		(net "GND")
	)
	(via
		(at 384.1242 -71.335138)
		(size 0.508)
		(drill 0.254)
		(layers "F.Cu" "B.Cu")
		(net "GND")
	)
	(via
		(at 483.900734 -164.479224)
		(size 0.5588)
		(drill 0.3048)
		(layers "F.Cu" "B.Cu")
		(net "GND")
	)
	(via
		(at 62.798706 -16.7513)
		(size 0.508)
		(drill 0.254)
		(layers "F.Cu" "B.Cu")
		(net "GND")
	)
	(via
		(at 35.499802 -75.184)
		(size 0.508)
		(drill 0.254)
		(layers "F.Cu" "B.Cu")
		(net "GND")
	)
	(via
		(at 130.802888 -80.669384)
		(size 0.508)
		(drill 0.254)
		(layers "F.Cu" "B.Cu")
		(net "GND")
	)
	(via
		(at 158.40964 -118.553484)
		(size 0.508)
		(drill 0.254)
		(layers "F.Cu" "B.Cu")
		(net "GND")
	)
	(via
		(at 286.3596 -83.146138)
		(size 0.508)
		(drill 0.254)
		(layers "F.Cu" "B.Cu")
		(net "GND")
	)
	(via
		(at 273.197828 -62.343538)
		(size 0.508)
		(drill 0.254)
		(layers "F.Cu" "B.Cu")
		(net "GND")
	)
	(via
		(at 105.571036 -51.941984)
		(size 0.508)
		(drill 0.254)
		(layers "F.Cu" "B.Cu")
		(net "GND")
	)
	(via
		(at 128.69418 -145.9357)
		(size 0.508)
		(drill 0.254)
		(layers "F.Cu" "B.Cu")
		(net "GND")
	)
	(via
		(at 68.894706 -69.45884)
		(size 0.508)
		(drill 0.254)
		(layers "F.Cu" "B.Cu")
		(net "GND")
	)
	(via
		(at 125.651768 -86.612984)
		(size 0.508)
		(drill 0.254)
		(layers "F.Cu" "B.Cu")
		(net "GND")
	)
	(via
		(at 287.761934 14.926056)
		(size 0.5588)
		(drill 0.3048)
		(layers "F.Cu" "B.Cu")
		(net "GND")
	)
	(via
		(at 234.753658 -55.094886)
		(size 0.508)
		(drill 0.254)
		(layers "F.Cu" "B.Cu")
		(net "GND")
	)
	(via
		(at 337.8454 -109.855)
		(size 0.508)
		(drill 0.254)
		(layers "F.Cu" "B.Cu")
		(net "GND")
	)
	(via
		(at 335.915 -53.149754)
		(size 0.508)
		(drill 0.254)
		(layers "F.Cu" "B.Cu")
		(net "GND")
	)
	(via
		(at 145.52422 -59.1185)
		(size 0.508)
		(drill 0.254)
		(layers "F.Cu" "B.Cu")
		(net "GND")
	)
	(via
		(at 245.914164 -81.34604)
		(size 0.508)
		(drill 0.254)
		(layers "F.Cu" "B.Cu")
		(net "GND")
	)
	(via
		(at 176.054004 -147.67052)
		(size 0.508)
		(drill 0.254)
		(layers "F.Cu" "B.Cu")
		(net "GND")
	)
	(via
		(at 360.151934 9.084056)
		(size 0.5588)
		(drill 0.3048)
		(layers "F.Cu" "B.Cu")
		(net "GND")
	)
	(via
		(at 7.0612 -22.8346)
		(size 0.508)
		(drill 0.254)
		(layers "F.Cu" "B.Cu")
		(net "GND")
	)
	(via
		(at 45.390816 -7.095744)
		(size 0.508)
		(drill 0.254)
		(layers "F.Cu" "B.Cu")
		(net "GND")
	)
	(via
		(at 141.899386 -13.363956)
		(size 0.508)
		(drill 0.254)
		(layers "F.Cu" "B.Cu")
		(net "GND")
	)
	(via
		(at 144.411446 -139.170156)
		(size 0.508)
		(drill 0.254)
		(layers "F.Cu" "B.Cu")
		(net "GND")
	)
	(via
		(at 461.751934 9.084056)
		(size 0.5588)
		(drill 0.3048)
		(layers "F.Cu" "B.Cu")
		(net "GND")
	)
	(via
		(at 137.670794 -95.528384)
		(size 0.508)
		(drill 0.254)
		(layers "F.Cu" "B.Cu")
		(net "GND")
	)
	(via
		(at 138.529314 -74.23023)
		(size 0.508)
		(drill 0.254)
		(layers "F.Cu" "B.Cu")
		(net "GND")
	)
	(via
		(at 341.6554 -40.64)
		(size 0.508)
		(drill 0.254)
		(layers "F.Cu" "B.Cu")
		(net "GND")
	)
	(via
		(at 78.2193 -12.885166)
		(size 0.508)
		(drill 0.254)
		(layers "F.Cu" "B.Cu")
		(net "GND")
	)
	(via
		(at 221.04985 -139.170156)
		(size 0.508)
		(drill 0.254)
		(layers "F.Cu" "B.Cu")
		(net "GND")
	)
	(via
		(at 130.802888 -68.782184)
		(size 0.508)
		(drill 0.254)
		(layers "F.Cu" "B.Cu")
		(net "GND")
	)
	(via
		(at 351.4344 -122.556016)
		(size 0.508)
		(drill 0.254)
		(layers "F.Cu" "B.Cu")
		(net "GND")
	)
	(via
		(at 419.885114 -84.230972)
		(size 0.508)
		(drill 0.254)
		(layers "F.Cu" "B.Cu")
		(net "GND")
	)
	(via
		(at 278.348694 -62.343538)
		(size 0.508)
		(drill 0.254)
		(layers "F.Cu" "B.Cu")
		(net "GND")
	)
	(via
		(at 340.974934 -167.832024)
		(size 0.5588)
		(drill 0.3048)
		(layers "F.Cu" "B.Cu")
		(net "GND")
	)
	(via
		(at 326.644 -34.163)
		(size 0.508)
		(drill 0.254)
		(layers "F.Cu" "B.Cu")
		(net "GND")
	)
	(via
		(at 66.781934 14.926056)
		(size 0.5588)
		(drill 0.3048)
		(layers "F.Cu" "B.Cu")
		(net "GND")
	)
	(via
		(at 114.098324 -162.243262)
		(size 0.5588)
		(drill 0.3048)
		(layers "F.Cu" "B.Cu")
		(net "GND")
	)
	(via
		(at 437.721756 -29.8323)
		(size 0.4572)
		(drill 0.2032)
		(layers "F.Cu" "B.Cu")
		(net "GND")
	)
	(via
		(at 219.156534 -167.832024)
		(size 0.5588)
		(drill 0.3048)
		(layers "F.Cu" "B.Cu")
		(net "GND")
	)
	(via
		(at 32.160464 -13.338556)
		(size 0.508)
		(drill 0.254)
		(layers "F.Cu" "B.Cu")
		(net "GND")
	)
	(via
		(at 296.66184 -64.324738)
		(size 0.508)
		(drill 0.254)
		(layers "F.Cu" "B.Cu")
		(net "GND")
	)
	(via
		(at 74.045826 -61.53404)
		(size 0.508)
		(drill 0.254)
		(layers "F.Cu" "B.Cu")
		(net "GND")
	)
	(via
		(at 233.036618 -65.991486)
		(size 0.508)
		(drill 0.254)
		(layers "F.Cu" "B.Cu")
		(net "GND")
	)
	(via
		(at 346.564204 -148.370798)
		(size 0.508)
		(drill 0.254)
		(layers "F.Cu" "B.Cu")
		(net "GND")
	)
	(via
		(at 449.3006 -132.365496)
		(size 0.508)
		(drill 0.254)
		(layers "F.Cu" "B.Cu")
		(net "GND")
	)
	(via
		(at 237.329218 -52.618386)
		(size 0.508)
		(drill 0.254)
		(layers "F.Cu" "B.Cu")
		(net "GND")
	)
	(via
		(at 247.631204 -93.23324)
		(size 0.508)
		(drill 0.254)
		(layers "F.Cu" "B.Cu")
		(net "GND")
	)
	(via
		(at 377.931934 14.926056)
		(size 0.5588)
		(drill 0.3048)
		(layers "F.Cu" "B.Cu")
		(net "GND")
	)
	(via
		(at 48.399446 -18.757646)
		(size 0.508)
		(drill 0.254)
		(layers "F.Cu" "B.Cu")
		(net "GND")
	)
	(via
		(at 140.246354 -96.023938)
		(size 0.508)
		(drill 0.254)
		(layers "F.Cu" "B.Cu")
		(net "GND")
	)
	(via
		(at 16.16202 -107.76712)
		(size 0.508)
		(drill 0.254)
		(layers "F.Cu" "B.Cu")
		(net "GND")
	)
	(via
		(at 179.705 -149.3012)
		(size 0.508)
		(drill 0.254)
		(layers "F.Cu" "B.Cu")
		(net "GND")
	)
	(via
		(at 133.39953 -129.568956)
		(size 0.508)
		(drill 0.254)
		(layers "F.Cu" "B.Cu")
		(net "GND")
	)
	(via
		(at 241.44986 -21.517356)
		(size 0.508)
		(drill 0.254)
		(layers "F.Cu" "B.Cu")
		(net "GND")
	)
	(via
		(at 470.641934 11.624056)
		(size 0.5588)
		(drill 0.3048)
		(layers "F.Cu" "B.Cu")
		(net "GND")
	)
	(via
		(at 463.553556 -150.79853)
		(size 0.508)
		(drill 0.254)
		(layers "F.Cu" "B.Cu")
		(net "GND")
	)
	(via
		(at 70.611746 -58.561986)
		(size 0.508)
		(drill 0.254)
		(layers "F.Cu" "B.Cu")
		(net "GND")
	)
	(via
		(at 259.821934 9.084056)
		(size 0.5588)
		(drill 0.3048)
		(layers "F.Cu" "B.Cu")
		(net "GND")
	)
	(via
		(at 4.3434 -137.4648)
		(size 0.508)
		(drill 0.254)
		(layers "F.Cu" "B.Cu")
		(net "GND")
	)
	(via
		(at 175.498506 -67.72402)
		(size 0.508)
		(drill 0.254)
		(layers "F.Cu" "B.Cu")
		(net "GND")
	)
	(via
		(at 427.461934 11.624056)
		(size 0.5588)
		(drill 0.3048)
		(layers "F.Cu" "B.Cu")
		(net "GND")
	)
	(via
		(at 3.02895 -16.588994)
		(size 0.508)
		(drill 0.254)
		(layers "F.Cu" "B.Cu")
		(net "GND")
	)
	(via
		(at 398.810734 -166.714424)
		(size 0.5588)
		(drill 0.3048)
		(layers "F.Cu" "B.Cu")
		(net "GND")
	)
	(via
		(at 242.287044 -140.617956)
		(size 0.508)
		(drill 0.254)
		(layers "F.Cu" "B.Cu")
		(net "GND")
	)
	(via
		(at 468.656924 -162.243262)
		(size 0.5588)
		(drill 0.3048)
		(layers "F.Cu" "B.Cu")
		(net "GND")
	)
	(via
		(at 111.231934 14.926056)
		(size 0.5588)
		(drill 0.3048)
		(layers "F.Cu" "B.Cu")
		(net "GND")
	)
	(via
		(at 179.743862 -57.492138)
		(size 0.508)
		(drill 0.254)
		(layers "F.Cu" "B.Cu")
		(net "GND")
	)
	(via
		(at 241.621818 -93.72854)
		(size 0.508)
		(drill 0.254)
		(layers "F.Cu" "B.Cu")
		(net "GND")
	)
	(via
		(at 378.079 -126.7206)
		(size 0.508)
		(drill 0.254)
		(layers "F.Cu" "B.Cu")
		(net "GND")
	)
	(via
		(at 109.891322 -67.185032)
		(size 0.5588)
		(drill 0.3048)
		(layers "F.Cu" "B.Cu")
		(net "GND")
	)
	(via
		(at 366.903 -113.792)
		(size 0.508)
		(drill 0.254)
		(layers "F.Cu" "B.Cu")
		(net "GND")
	)
	(via
		(at 354.140262 -29.715206)
		(size 0.508)
		(drill 0.254)
		(layers "F.Cu" "B.Cu")
		(net "GND")
	)
	(via
		(at 146.098768 -16.7513)
		(size 0.508)
		(drill 0.254)
		(layers "F.Cu" "B.Cu")
		(net "GND")
	)
	(via
		(at 93.791278 -87.784686)
		(size 0.508)
		(drill 0.254)
		(layers "F.Cu" "B.Cu")
		(net "GND")
	)
	(via
		(at 226.822 -144.5006)
		(size 0.508)
		(drill 0.254)
		(layers "F.Cu" "B.Cu")
		(net "GND")
	)
	(via
		(at 103.678736 -145.0086)
		(size 0.508)
		(drill 0.254)
		(layers "F.Cu" "B.Cu")
		(net "GND")
	)
	(via
		(at 213.7156 -60.5282)
		(size 0.508)
		(drill 0.254)
		(layers "F.Cu" "B.Cu")
		(net "GND")
	)
	(via
		(at 312.3946 -155.5369)
		(size 0.508)
		(drill 0.254)
		(layers "F.Cu" "B.Cu")
		(net "GND")
	)
	(via
		(at 377.2662 -126.736348)
		(size 0.508)
		(drill 0.254)
		(layers "F.Cu" "B.Cu")
		(net "GND")
	)
	(via
		(at 158.221934 14.926056)
		(size 0.5588)
		(drill 0.3048)
		(layers "F.Cu" "B.Cu")
		(net "GND")
	)
	(via
		(at 258.79171 -64.010286)
		(size 0.508)
		(drill 0.254)
		(layers "F.Cu" "B.Cu")
		(net "GND")
	)
	(via
		(at 298.399962 -129.568956)
		(size 0.508)
		(drill 0.254)
		(layers "F.Cu" "B.Cu")
		(net "GND")
	)
	(via
		(at 203.157328 -60.198)
		(size 0.5588)
		(drill 0.3048)
		(layers "F.Cu" "B.Cu")
		(net "GND")
	)
	(via
		(at 179.331112 -125.8824)
		(size 0.508)
		(drill 0.254)
		(layers "F.Cu" "B.Cu")
		(net "GND")
	)
	(via
		(at 280.481024 -74.127614)
		(size 0.5588)
		(drill 0.3048)
		(layers "F.Cu" "B.Cu")
		(net "GND")
	)
	(via
		(at 263.94283 -89.765886)
		(size 0.508)
		(drill 0.254)
		(layers "F.Cu" "B.Cu")
		(net "GND")
	)
	(via
		(at 300.772068 -27.829256)
		(size 0.508)
		(drill 0.254)
		(layers "F.Cu" "B.Cu")
		(net "GND")
	)
	(via
		(at 463.021934 14.926056)
		(size 0.5588)
		(drill 0.3048)
		(layers "F.Cu" "B.Cu")
		(net "GND")
	)
	(via
		(at 310.122062 -134.8994)
		(size 0.508)
		(drill 0.254)
		(layers "F.Cu" "B.Cu")
		(net "GND")
	)
	(via
		(at 288.19983 -3.762756)
		(size 0.508)
		(drill 0.254)
		(layers "F.Cu" "B.Cu")
		(net "GND")
	)
	(via
		(at 215.85174 -134.861046)
		(size 0.508)
		(drill 0.254)
		(layers "F.Cu" "B.Cu")
		(net "GND")
	)
	(via
		(at 205.749906 -2.314956)
		(size 0.508)
		(drill 0.254)
		(layers "F.Cu" "B.Cu")
		(net "GND")
	)
	(via
		(at 285.649924 -9.156446)
		(size 0.508)
		(drill 0.254)
		(layers "F.Cu" "B.Cu")
		(net "GND")
	)
	(via
		(at 439.728864 -50.513488)
		(size 0.508)
		(drill 0.254)
		(layers "F.Cu" "B.Cu")
		(net "GND")
	)
	(via
		(at 356.161594 -0.289306)
		(size 0.5588)
		(drill 0.3048)
		(layers "F.Cu" "B.Cu")
		(net "GND")
	)
	(via
		(at 35.615626 -102.335076)
		(size 0.5588)
		(drill 0.3048)
		(layers "F.Cu" "B.Cu")
		(net "GND")
	)
	(via
		(at 142.039848 -97.014538)
		(size 0.508)
		(drill 0.254)
		(layers "F.Cu" "B.Cu")
		(net "GND")
	)
	(via
		(at 482.630734 -167.832024)
		(size 0.5588)
		(drill 0.3048)
		(layers "F.Cu" "B.Cu")
		(net "GND")
	)
	(via
		(at 476.82658 -16.122142)
		(size 0.508)
		(drill 0.254)
		(layers "F.Cu" "B.Cu")
		(net "GND")
	)
	(via
		(at 313.699906 -136.410446)
		(size 0.508)
		(drill 0.254)
		(layers "F.Cu" "B.Cu")
		(net "GND")
	)
	(via
		(at 72.142096 -136.397746)
		(size 0.508)
		(drill 0.254)
		(layers "F.Cu" "B.Cu")
		(net "GND")
	)
	(via
		(at 126.421642 -150.219156)
		(size 0.508)
		(drill 0.254)
		(layers "F.Cu" "B.Cu")
		(net "GND")
	)
	(via
		(at 117.925342 -96.023938)
		(size 0.508)
		(drill 0.254)
		(layers "F.Cu" "B.Cu")
		(net "GND")
	)
	(via
		(at 206.825596 -54.067202)
		(size 0.5588)
		(drill 0.3048)
		(layers "F.Cu" "B.Cu")
		(net "GND")
	)
	(via
		(at 170.7388 -65.2272)
		(size 0.508)
		(drill 0.254)
		(layers "F.Cu" "B.Cu")
		(net "GND")
	)
	(via
		(at 56.899302 -13.363956)
		(size 0.508)
		(drill 0.254)
		(layers "F.Cu" "B.Cu")
		(net "GND")
	)
	(via
		(at 432.541934 12.894056)
		(size 0.5588)
		(drill 0.3048)
		(layers "F.Cu" "B.Cu")
		(net "GND")
	)
	(via
		(at 20.117308 2.89433)
		(size 0.508)
		(drill 0.254)
		(layers "F.Cu" "B.Cu")
		(net "GND")
	)
	(via
		(at 48.399446 -155.612846)
		(size 0.508)
		(drill 0.254)
		(layers "F.Cu" "B.Cu")
		(net "GND")
	)
	(via
		(at 158.806134 -167.832024)
		(size 0.5588)
		(drill 0.3048)
		(layers "F.Cu" "B.Cu")
		(net "GND")
	)
	(via
		(at 457.230734 -166.714424)
		(size 0.5588)
		(drill 0.3048)
		(layers "F.Cu" "B.Cu")
		(net "GND")
	)
	(via
		(at 38.105334 -167.832024)
		(size 0.5588)
		(drill 0.3048)
		(layers "F.Cu" "B.Cu")
		(net "GND")
	)
	(via
		(at 243.338604 -64.010286)
		(size 0.508)
		(drill 0.254)
		(layers "F.Cu" "B.Cu")
		(net "GND")
	)
	(via
		(at 201.041254 -7.095744)
		(size 0.508)
		(drill 0.254)
		(layers "F.Cu" "B.Cu")
		(net "GND")
	)
	(via
		(at 359.547414 -124.338842)
		(size 0.508)
		(drill 0.254)
		(layers "F.Cu" "B.Cu")
		(net "GND")
	)
	(via
		(at 499.140734 -166.714424)
		(size 0.5588)
		(drill 0.3048)
		(layers "F.Cu" "B.Cu")
		(net "GND")
	)
	(via
		(at 268.679168 -12.954)
		(size 0.508)
		(drill 0.254)
		(layers "F.Cu" "B.Cu")
		(net "GND")
	)
	(via
		(at 175.570134 -167.832024)
		(size 0.5588)
		(drill 0.3048)
		(layers "F.Cu" "B.Cu")
		(net "GND")
	)
	(via
		(at 183.831992 -126.769114)
		(size 0.508)
		(drill 0.254)
		(layers "F.Cu" "B.Cu")
		(net "GND")
	)
	(via
		(at 141.899386 -134.861046)
		(size 0.508)
		(drill 0.254)
		(layers "F.Cu" "B.Cu")
		(net "GND")
	)
	(via
		(at 116.399564 -146.011646)
		(size 0.508)
		(drill 0.254)
		(layers "F.Cu" "B.Cu")
		(net "GND")
	)
	(via
		(at 345.965272 -99.28479)
		(size 0.508)
		(drill 0.254)
		(layers "F.Cu" "B.Cu")
		(net "GND")
	)
	(via
		(at 58.599324 -13.363956)
		(size 0.508)
		(drill 0.254)
		(layers "F.Cu" "B.Cu")
		(net "GND")
	)
	(via
		(at 146.092164 -11.912092)
		(size 0.508)
		(drill 0.254)
		(layers "F.Cu" "B.Cu")
		(net "GND")
	)
	(via
		(at 86.923372 -98.681286)
		(size 0.508)
		(drill 0.254)
		(layers "F.Cu" "B.Cu")
		(net "GND")
	)
	(via
		(at 17.417796 0.364998)
		(size 0.508)
		(drill 0.254)
		(layers "F.Cu" "B.Cu")
		(net "GND")
	)
	(via
		(at 116.361464 -148.771356)
		(size 0.508)
		(drill 0.254)
		(layers "F.Cu" "B.Cu")
		(net "GND")
	)
	(via
		(at 12.171934 14.926056)
		(size 0.5588)
		(drill 0.3048)
		(layers "F.Cu" "B.Cu")
		(net "GND")
	)
	(via
		(at 455.265028 -15.586202)
		(size 0.5588)
		(drill 0.3048)
		(layers "F.Cu" "B.Cu")
		(net "GND")
	)
	(via
		(at 426.746924 -162.243262)
		(size 0.5588)
		(drill 0.3048)
		(layers "F.Cu" "B.Cu")
		(net "GND")
	)
	(via
		(at 200.533 -76.5048)
		(size 0.5588)
		(drill 0.3048)
		(layers "F.Cu" "B.Cu")
		(net "GND")
	)
	(via
		(at 207.515714 -85.688678)
		(size 0.5588)
		(drill 0.3048)
		(layers "F.Cu" "B.Cu")
		(net "GND")
	)
	(via
		(at 80.913732 -62.52464)
		(size 0.508)
		(drill 0.254)
		(layers "F.Cu" "B.Cu")
		(net "GND")
	)
	(via
		(at 363.934502 1.999996)
		(size 0.5588)
		(drill 0.3048)
		(layers "F.Cu" "B.Cu")
		(net "GND")
	)
	(via
		(at 218.035124 -162.243262)
		(size 0.5588)
		(drill 0.3048)
		(layers "F.Cu" "B.Cu")
		(net "GND")
	)
	(via
		(at 241.621818 -88.775286)
		(size 0.508)
		(drill 0.254)
		(layers "F.Cu" "B.Cu")
		(net "GND")
	)
	(via
		(at 95.508318 -63.019686)
		(size 0.508)
		(drill 0.254)
		(layers "F.Cu" "B.Cu")
		(net "GND")
	)
	(via
		(at 396.5702 -143.256)
		(size 0.508)
		(drill 0.254)
		(layers "F.Cu" "B.Cu")
		(net "GND")
	)
	(via
		(at 176.687734 -167.832024)
		(size 0.5588)
		(drill 0.3048)
		(layers "F.Cu" "B.Cu")
		(net "GND")
	)
	(via
		(at 357.9241 -18.099786)
		(size 0.508)
		(drill 0.254)
		(layers "F.Cu" "B.Cu")
		(net "GND")
	)
	(via
		(at 141.049502 -21.517356)
		(size 0.508)
		(drill 0.254)
		(layers "F.Cu" "B.Cu")
		(net "GND")
	)
	(via
		(at 499.3386 -46.8884)
		(size 0.508)
		(drill 0.254)
		(layers "F.Cu" "B.Cu")
		(net "GND")
	)
	(via
		(at 456.60437 -118.61927)
		(size 0.508)
		(drill 0.254)
		(layers "F.Cu" "B.Cu")
		(net "GND")
	)
	(via
		(at 268.327124 -162.243262)
		(size 0.5588)
		(drill 0.3048)
		(layers "F.Cu" "B.Cu")
		(net "GND")
	)
	(via
		(at 13.081 -103.124)
		(size 0.508)
		(drill 0.254)
		(layers "F.Cu" "B.Cu")
		(net "GND")
	)
	(via
		(at 291.422074 -7.6454)
		(size 0.508)
		(drill 0.254)
		(layers "F.Cu" "B.Cu")
		(net "GND")
	)
	(via
		(at 470.0778 -39.624)
		(size 0.508)
		(drill 0.254)
		(layers "F.Cu" "B.Cu")
		(net "GND")
	)
	(via
		(at 231.249728 -140.617956)
		(size 0.508)
		(drill 0.254)
		(layers "F.Cu" "B.Cu")
		(net "GND")
	)
	(via
		(at 350.483678 -116.359432)
		(size 0.508)
		(drill 0.254)
		(layers "F.Cu" "B.Cu")
		(net "GND")
	)
	(via
		(at 199.736456 -141.1478)
		(size 0.508)
		(drill 0.254)
		(layers "F.Cu" "B.Cu")
		(net "GND")
	)
	(via
		(at 199.992234 -70.920864)
		(size 0.508)
		(drill 0.254)
		(layers "F.Cu" "B.Cu")
		(net "GND")
	)
	(via
		(at 91.746324 -162.243262)
		(size 0.5588)
		(drill 0.3048)
		(layers "F.Cu" "B.Cu")
		(net "GND")
	)
	(via
		(at 37.34943 -129.568956)
		(size 0.508)
		(drill 0.254)
		(layers "F.Cu" "B.Cu")
		(net "GND")
	)
	(via
		(at 401.752816 -149.909784)
		(size 0.508)
		(drill 0.254)
		(layers "F.Cu" "B.Cu")
		(net "GND")
	)
	(via
		(at 361.421934 14.926056)
		(size 0.5588)
		(drill 0.3048)
		(layers "F.Cu" "B.Cu")
		(net "GND")
	)
	(via
		(at 483.896924 -162.243262)
		(size 0.5588)
		(drill 0.3048)
		(layers "F.Cu" "B.Cu")
		(net "GND")
	)
	(via
		(at 169.978324 -162.243262)
		(size 0.5588)
		(drill 0.3048)
		(layers "F.Cu" "B.Cu")
		(net "GND")
	)
	(via
		(at 309.351934 9.084056)
		(size 0.5588)
		(drill 0.3048)
		(layers "F.Cu" "B.Cu")
		(net "GND")
	)
	(via
		(at 35.466274 -63.9826)
		(size 0.508)
		(drill 0.254)
		(layers "F.Cu" "B.Cu")
		(net "GND")
	)
	(via
		(at 2.80162 -24.08936)
		(size 0.508)
		(drill 0.254)
		(layers "F.Cu" "B.Cu")
		(net "GND")
	)
	(via
		(at 51.76139 -129.568956)
		(size 0.508)
		(drill 0.254)
		(layers "F.Cu" "B.Cu")
		(net "GND")
	)
	(via
		(at 278.871934 14.926056)
		(size 0.5588)
		(drill 0.3048)
		(layers "F.Cu" "B.Cu")
		(net "GND")
	)
	(via
		(at 239.904778 -93.72854)
		(size 0.508)
		(drill 0.254)
		(layers "F.Cu" "B.Cu")
		(net "GND")
	)
	(via
		(at 374.313196 -0.750062)
		(size 0.508)
		(drill 0.254)
		(layers "F.Cu" "B.Cu")
		(net "GND")
	)
	(via
		(at 221.899734 -7.607046)
		(size 0.508)
		(drill 0.254)
		(layers "F.Cu" "B.Cu")
		(net "GND")
	)
	(via
		(at 119.327168 -9.0932)
		(size 0.508)
		(drill 0.254)
		(layers "F.Cu" "B.Cu")
		(net "GND")
	)
	(via
		(at 148.699474 -155.612846)
		(size 0.508)
		(drill 0.254)
		(layers "F.Cu" "B.Cu")
		(net "GND")
	)
	(via
		(at 27.411934 9.084056)
		(size 0.5588)
		(drill 0.3048)
		(layers "F.Cu" "B.Cu")
		(net "GND")
	)
	(via
		(at 33.771586 -3.762756)
		(size 0.508)
		(drill 0.254)
		(layers "F.Cu" "B.Cu")
		(net "GND")
	)
	(via
		(at 68.036186 -66.982086)
		(size 0.508)
		(drill 0.254)
		(layers "F.Cu" "B.Cu")
		(net "GND")
	)
	(via
		(at 263.1186 -25.0952)
		(size 0.508)
		(drill 0.254)
		(layers "F.Cu" "B.Cu")
		(net "GND")
	)
	(via
		(at 108.481876 -95.528384)
		(size 0.508)
		(drill 0.254)
		(layers "F.Cu" "B.Cu")
		(net "GND")
	)
	(via
		(at 124.049536 -136.397746)
		(size 0.508)
		(drill 0.254)
		(layers "F.Cu" "B.Cu")
		(net "GND")
	)
	(via
		(at 278.348694 -52.437284)
		(size 0.508)
		(drill 0.254)
		(layers "F.Cu" "B.Cu")
		(net "GND")
	)
	(via
		(at 493.501934 14.926056)
		(size 0.5588)
		(drill 0.3048)
		(layers "F.Cu" "B.Cu")
		(net "GND")
	)
	(via
		(at 442.1886 -50.4952)
		(size 0.508)
		(drill 0.254)
		(layers "F.Cu" "B.Cu")
		(net "GND")
	)
	(via
		(at 227.786438 -13.8938)
		(size 0.508)
		(drill 0.254)
		(layers "F.Cu" "B.Cu")
		(net "GND")
	)
	(via
		(at 110.749334 -167.832024)
		(size 0.5588)
		(drill 0.3048)
		(layers "F.Cu" "B.Cu")
		(net "GND")
	)
	(via
		(at 397.14805 -103.615236)
		(size 0.508)
		(drill 0.254)
		(layers "F.Cu" "B.Cu")
		(net "GND")
	)
	(via
		(at 92.074238 -56.085486)
		(size 0.508)
		(drill 0.254)
		(layers "F.Cu" "B.Cu")
		(net "GND")
	)
	(via
		(at 143.501364 -134.861046)
		(size 0.508)
		(drill 0.254)
		(layers "F.Cu" "B.Cu")
		(net "GND")
	)
	(via
		(at 226.149916 -18.757646)
		(size 0.508)
		(drill 0.254)
		(layers "F.Cu" "B.Cu")
		(net "GND")
	)
	(via
		(at 437.275986 -3.429)
		(size 0.508)
		(drill 0.254)
		(layers "F.Cu" "B.Cu")
		(net "GND")
	)
	(via
		(at 115.219734 -167.832024)
		(size 0.5588)
		(drill 0.3048)
		(layers "F.Cu" "B.Cu")
		(net "GND")
	)
	(via
		(at 35.893502 -65.413382)
		(size 0.508)
		(drill 0.254)
		(layers "F.Cu" "B.Cu")
		(net "GND")
	)
	(via
		(at 155.453334 -167.832024)
		(size 0.5588)
		(drill 0.3048)
		(layers "F.Cu" "B.Cu")
		(net "GND")
	)
	(via
		(at 6.910832 -10.747502)
		(size 0.508)
		(drill 0.254)
		(layers "F.Cu" "B.Cu")
		(net "GND")
	)
	(via
		(at 239.749838 -11.916156)
		(size 0.508)
		(drill 0.254)
		(layers "F.Cu" "B.Cu")
		(net "GND")
	)
	(via
		(at 67.949318 -13.363956)
		(size 0.508)
		(drill 0.254)
		(layers "F.Cu" "B.Cu")
		(net "GND")
	)
	(via
		(at 147.394168 -145.9357)
		(size 0.508)
		(drill 0.254)
		(layers "F.Cu" "B.Cu")
		(net "GND")
	)
	(via
		(at 35.880802 -70.920864)
		(size 0.508)
		(drill 0.254)
		(layers "F.Cu" "B.Cu")
		(net "GND")
	)
	(via
		(at 280.065734 -66.305938)
		(size 0.508)
		(drill 0.254)
		(layers "F.Cu" "B.Cu")
		(net "GND")
	)
	(via
		(at 74.045826 -62.52464)
		(size 0.508)
		(drill 0.254)
		(layers "F.Cu" "B.Cu")
		(net "GND")
	)
	(via
		(at 349.2754 -112.395)
		(size 0.508)
		(drill 0.254)
		(layers "F.Cu" "B.Cu")
		(net "GND")
	)
	(via
		(at 215.0999 -11.916156)
		(size 0.508)
		(drill 0.254)
		(layers "F.Cu" "B.Cu")
		(net "GND")
	)
	(via
		(at 320.858134 -167.832024)
		(size 0.5588)
		(drill 0.3048)
		(layers "F.Cu" "B.Cu")
		(net "GND")
	)
	(via
		(at 278.633174 -95.528384)
		(size 0.508)
		(drill 0.254)
		(layers "F.Cu" "B.Cu")
		(net "GND")
	)
	(via
		(at 57.74944 -9.156446)
		(size 0.508)
		(drill 0.254)
		(layers "F.Cu" "B.Cu")
		(net "GND")
	)
	(via
		(at -0.838454 -157.389322)
		(size 0.5588)
		(drill 0.3048)
		(layers "F.Cu" "B.Cu")
		(net "GND")
	)
	(via
		(at 351.7138 -91.3638)
		(size 0.508)
		(drill 0.254)
		(layers "F.Cu" "B.Cu")
		(net "GND")
	)
	(via
		(at 450.880734 -165.596824)
		(size 0.5588)
		(drill 0.3048)
		(layers "F.Cu" "B.Cu")
		(net "GND")
	)
	(via
		(at 34.955226 -102.3366)
		(size 0.5588)
		(drill 0.3048)
		(layers "F.Cu" "B.Cu")
		(net "GND")
	)
	(via
		(at 83.489292 -67.972686)
		(size 0.508)
		(drill 0.254)
		(layers "F.Cu" "B.Cu")
		(net "GND")
	)
	(via
		(at 149.331934 9.084056)
		(size 0.5588)
		(drill 0.3048)
		(layers "F.Cu" "B.Cu")
		(net "GND")
	)
	(via
		(at 245.055644 -54.104286)
		(size 0.508)
		(drill 0.254)
		(layers "F.Cu" "B.Cu")
		(net "GND")
	)
	(via
		(at 152.100534 -167.832024)
		(size 0.5588)
		(drill 0.3048)
		(layers "F.Cu" "B.Cu")
		(net "GND")
	)
	(via
		(at 255.35763 -98.681286)
		(size 0.508)
		(drill 0.254)
		(layers "F.Cu" "B.Cu")
		(net "GND")
	)
	(via
		(at 2.342134 -165.596824)
		(size 0.5588)
		(drill 0.3048)
		(layers "F.Cu" "B.Cu")
		(net "GND")
	)
	(via
		(at 201.044556 -155.5369)
		(size 0.508)
		(drill 0.254)
		(layers "F.Cu" "B.Cu")
		(net "GND")
	)
	(via
		(at 487.710734 -166.714424)
		(size 0.5588)
		(drill 0.3048)
		(layers "F.Cu" "B.Cu")
		(net "GND")
	)
	(via
		(at 41.510458 -140.592556)
		(size 0.508)
		(drill 0.254)
		(layers "F.Cu" "B.Cu")
		(net "GND")
	)
	(via
		(at 358.6226 -109.16285)
		(size 0.508)
		(drill 0.254)
		(layers "F.Cu" "B.Cu")
		(net "GND")
	)
	(via
		(at 369.49761 -0.707136)
		(size 0.508)
		(drill 0.254)
		(layers "F.Cu" "B.Cu")
		(net "GND")
	)
	(via
		(at 16.9164 -25.99944)
		(size 0.508)
		(drill 0.254)
		(layers "F.Cu" "B.Cu")
		(net "GND")
	)
	(via
		(at 152.099518 2.514854)
		(size 0.508)
		(drill 0.254)
		(layers "F.Cu" "B.Cu")
		(net "GND")
	)
	(via
		(at 206.906114 -77.154278)
		(size 0.5588)
		(drill 0.3048)
		(layers "F.Cu" "B.Cu")
		(net "GND")
	)
	(via
		(at 383.27965 -121.245884)
		(size 0.508)
		(drill 0.254)
		(layers "F.Cu" "B.Cu")
		(net "GND")
	)
	(via
		(at 275.683218 -75.148186)
		(size 0.5588)
		(drill 0.3048)
		(layers "F.Cu" "B.Cu")
		(net "GND")
	)
	(via
		(at 74.749406 -2.314956)
		(size 0.508)
		(drill 0.254)
		(layers "F.Cu" "B.Cu")
		(net "GND")
	)
	(via
		(at 32.5628 -79.9592)
		(size 0.508)
		(drill 0.254)
		(layers "F.Cu" "B.Cu")
		(net "GND")
	)
	(via
		(at 347.213936 -104.262174)
		(size 0.508)
		(drill 0.254)
		(layers "F.Cu" "B.Cu")
		(net "GND")
	)
	(via
		(at 138.529314 -84.136738)
		(size 0.508)
		(drill 0.254)
		(layers "F.Cu" "B.Cu")
		(net "GND")
	)
	(via
		(at 232.099866 -129.568956)
		(size 0.508)
		(drill 0.254)
		(layers "F.Cu" "B.Cu")
		(net "GND")
	)
	(via
		(at 6.99135 -17.619218)
		(size 0.508)
		(drill 0.254)
		(layers "F.Cu" "B.Cu")
		(net "GND")
	)
	(via
		(at 311.092596 -129.564892)
		(size 0.508)
		(drill 0.254)
		(layers "F.Cu" "B.Cu")
		(net "GND")
	)
	(via
		(at 248.489724 -67.972686)
		(size 0.508)
		(drill 0.254)
		(layers "F.Cu" "B.Cu")
		(net "GND")
	)
	(via
		(at 251.923804 -65.991486)
		(size 0.508)
		(drill 0.254)
		(layers "F.Cu" "B.Cu")
		(net "GND")
	)
	(via
		(at 322.326 -130.7338)
		(size 0.508)
		(drill 0.254)
		(layers "F.Cu" "B.Cu")
		(net "GND")
	)
	(via
		(at 272.623788 -90.080338)
		(size 0.508)
		(drill 0.254)
		(layers "F.Cu" "B.Cu")
		(net "GND")
	)
	(via
		(at 3.546856 12.491466)
		(size 0.5588)
		(drill 0.3048)
		(layers "F.Cu" "B.Cu")
		(net "GND")
	)
	(via
		(at 110.772702 -54.913784)
		(size 0.508)
		(drill 0.254)
		(layers "F.Cu" "B.Cu")
		(net "GND")
	)
	(via
		(at 70.611746 -51.62804)
		(size 0.508)
		(drill 0.254)
		(layers "F.Cu" "B.Cu")
		(net "GND")
	)
	(via
		(at 244.197124 -56.58104)
		(size 0.508)
		(drill 0.254)
		(layers "F.Cu" "B.Cu")
		(net "GND")
	)
	(via
		(at 438.180734 -163.361624)
		(size 0.5588)
		(drill 0.3048)
		(layers "F.Cu" "B.Cu")
		(net "GND")
	)
	(via
		(at 347.918278 -131.43611)
		(size 0.508)
		(drill 0.254)
		(layers "F.Cu" "B.Cu")
		(net "GND")
	)
	(via
		(at 332.1304 -157.5054)
		(size 0.508)
		(drill 0.254)
		(layers "F.Cu" "B.Cu")
		(net "GND")
	)
	(via
		(at 315.399928 -155.612846)
		(size 0.508)
		(drill 0.254)
		(layers "F.Cu" "B.Cu")
		(net "GND")
	)
	(via
		(at 208.122012 -144.5006)
		(size 0.508)
		(drill 0.254)
		(layers "F.Cu" "B.Cu")
		(net "GND")
	)
	(via
		(at 358.3559 -143.30934)
		(size 0.508)
		(drill 0.254)
		(layers "F.Cu" "B.Cu")
		(net "GND")
	)
	(via
		(at 388.5184 -147.9042)
		(size 0.508)
		(drill 0.254)
		(layers "F.Cu" "B.Cu")
		(net "GND")
	)
	(via
		(at 110.111032 -8.1534)
		(size 0.508)
		(drill 0.254)
		(layers "F.Cu" "B.Cu")
		(net "GND")
	)
	(via
		(at 390.70915 -95.888556)
		(size 0.508)
		(drill 0.254)
		(layers "F.Cu" "B.Cu")
		(net "GND")
	)
	(via
		(at 197.5612 -79.9338)
		(size 0.508)
		(drill 0.254)
		(layers "F.Cu" "B.Cu")
		(net "GND")
	)
	(via
		(at 207.411828 -139.170156)
		(size 0.508)
		(drill 0.254)
		(layers "F.Cu" "B.Cu")
		(net "GND")
	)
	(via
		(at 199.992234 -62.792864)
		(size 0.508)
		(drill 0.254)
		(layers "F.Cu" "B.Cu")
		(net "GND")
	)
	(via
		(at 287.21812 -73.735184)
		(size 0.508)
		(drill 0.254)
		(layers "F.Cu" "B.Cu")
		(net "GND")
	)
	(via
		(at 397.3576 -153.797)
		(size 0.508)
		(drill 0.254)
		(layers "F.Cu" "B.Cu")
		(net "GND")
	)
	(via
		(at 444.530734 -166.714424)
		(size 0.5588)
		(drill 0.3048)
		(layers "F.Cu" "B.Cu")
		(net "GND")
	)
	(via
		(at 128.227328 -81.164938)
		(size 0.508)
		(drill 0.254)
		(layers "F.Cu" "B.Cu")
		(net "GND")
	)
	(via
		(at 10.97026 -152.88514)
		(size 0.508)
		(drill 0.254)
		(layers "F.Cu" "B.Cu")
		(net "GND")
	)
	(via
		(at 298.378626 -99.986338)
		(size 0.508)
		(drill 0.254)
		(layers "F.Cu" "B.Cu")
		(net "GND")
	)
	(via
		(at 293.7002 0.508)
		(size 0.508)
		(drill 0.254)
		(layers "F.Cu" "B.Cu")
		(net "GND")
	)
	(via
		(at 218.449144 -7.1501)
		(size 0.508)
		(drill 0.254)
		(layers "F.Cu" "B.Cu")
		(net "GND")
	)
	(via
		(at 249.348244 -84.31784)
		(size 0.508)
		(drill 0.254)
		(layers "F.Cu" "B.Cu")
		(net "GND")
	)
	(via
		(at 138.044174 -28.66771)
		(size 0.508)
		(drill 0.254)
		(layers "F.Cu" "B.Cu")
		(net "GND")
	)
	(via
		(at 106.278934 -167.832024)
		(size 0.5588)
		(drill 0.3048)
		(layers "F.Cu" "B.Cu")
		(net "GND")
	)
	(via
		(at 42.9641 -65.90538)
		(size 0.5588)
		(drill 0.3048)
		(layers "F.Cu" "B.Cu")
		(net "GND")
	)
	(via
		(at 235.612178 -63.51524)
		(size 0.508)
		(drill 0.254)
		(layers "F.Cu" "B.Cu")
		(net "GND")
	)
	(via
		(at 127.392176 -139.166092)
		(size 0.508)
		(drill 0.254)
		(layers "F.Cu" "B.Cu")
		(net "GND")
	)
	(via
		(at 95.508318 -95.709486)
		(size 0.508)
		(drill 0.254)
		(layers "F.Cu" "B.Cu")
		(net "GND")
	)
	(via
		(at 19.431 -93.5482)
		(size 0.508)
		(drill 0.254)
		(layers "F.Cu" "B.Cu")
		(net "GND")
	)
	(via
		(at 146.092164 0.457454)
		(size 0.508)
		(drill 0.254)
		(layers "F.Cu" "B.Cu")
		(net "GND")
	)
	(via
		(at 266.666218 -70.865746)
		(size 0.5588)
		(drill 0.3048)
		(layers "F.Cu" "B.Cu")
		(net "GND")
	)
	(via
		(at 483.87 -135.6106)
		(size 0.508)
		(drill 0.254)
		(layers "F.Cu" "B.Cu")
		(net "GND")
	)
	(via
		(at 374.627648 -152.281128)
		(size 0.508)
		(drill 0.254)
		(layers "F.Cu" "B.Cu")
		(net "GND")
	)
	(via
		(at 279.81021 -74.281538)
		(size 0.5588)
		(drill 0.3048)
		(layers "F.Cu" "B.Cu")
		(net "GND")
	)
	(via
		(at 206.093314 -93.943678)
		(size 0.5588)
		(drill 0.3048)
		(layers "F.Cu" "B.Cu")
		(net "GND")
	)
	(via
		(at 12.3952 -72.4154)
		(size 0.508)
		(drill 0.254)
		(layers "F.Cu" "B.Cu")
		(net "GND")
	)
	(via
		(at 232.94975 -140.617956)
		(size 0.508)
		(drill 0.254)
		(layers "F.Cu" "B.Cu")
		(net "GND")
	)
	(via
		(at 385.907534 -167.832024)
		(size 0.5588)
		(drill 0.3048)
		(layers "F.Cu" "B.Cu")
		(net "GND")
	)
	(via
		(at 322.5292 -135.376412)
		(size 0.508)
		(drill 0.254)
		(layers "F.Cu" "B.Cu")
		(net "GND")
	)
	(via
		(at 42.575734 -167.832024)
		(size 0.5588)
		(drill 0.3048)
		(layers "F.Cu" "B.Cu")
		(net "GND")
	)
	(via
		(at 376.7328 -114.41557)
		(size 0.508)
		(drill 0.254)
		(layers "F.Cu" "B.Cu")
		(net "GND")
	)
	(via
		(at 165.6334 -73.2282)
		(size 0.508)
		(drill 0.254)
		(layers "F.Cu" "B.Cu")
		(net "GND")
	)
	(via
		(at 255.862328 -144.63014)
		(size 0.508)
		(drill 0.254)
		(layers "F.Cu" "B.Cu")
		(net "GND")
	)
	(via
		(at 311.092596 -136.397746)
		(size 0.508)
		(drill 0.254)
		(layers "F.Cu" "B.Cu")
		(net "GND")
	)
	(via
		(at 303.529746 -81.164938)
		(size 0.508)
		(drill 0.254)
		(layers "F.Cu" "B.Cu")
		(net "GND")
	)
	(via
		(at 379.201934 14.926056)
		(size 0.5588)
		(drill 0.3048)
		(layers "F.Cu" "B.Cu")
		(net "GND")
	)
	(via
		(at 244.197124 -76.39304)
		(size 0.508)
		(drill 0.254)
		(layers "F.Cu" "B.Cu")
		(net "GND")
	)
	(via
		(at 332.034134 -167.832024)
		(size 0.5588)
		(drill 0.3048)
		(layers "F.Cu" "B.Cu")
		(net "GND")
	)
	(via
		(at 197.5358 -55.5244)
		(size 0.508)
		(drill 0.254)
		(layers "F.Cu" "B.Cu")
		(net "GND")
	)
	(via
		(at 181.8132 -14.478)
		(size 0.508)
		(drill 0.254)
		(layers "F.Cu" "B.Cu")
		(net "GND")
	)
	(via
		(at 445.241934 10.354056)
		(size 0.5588)
		(drill 0.3048)
		(layers "F.Cu" "B.Cu")
		(net "GND")
	)
	(via
		(at 384.76555 -120.387364)
		(size 0.508)
		(drill 0.254)
		(layers "F.Cu" "B.Cu")
		(net "GND")
	)
	(via
		(at 38.55974 -48.93818)
		(size 0.508)
		(drill 0.254)
		(layers "F.Cu" "B.Cu")
		(net "GND")
	)
	(via
		(at 345.4654 -38.1)
		(size 0.508)
		(drill 0.254)
		(layers "F.Cu" "B.Cu")
		(net "GND")
	)
	(via
		(at 284.642814 -96.023938)
		(size 0.508)
		(drill 0.254)
		(layers "F.Cu" "B.Cu")
		(net "GND")
	)
	(via
		(at 187.12561 -8.505698)
		(size 0.508)
		(drill 0.254)
		(layers "F.Cu" "B.Cu")
		(net "GND")
	)
	(via
		(at 119.34063 -153.552144)
		(size 0.508)
		(drill 0.254)
		(layers "F.Cu" "B.Cu")
		(net "GND")
	)
	(via
		(at 372.618 -116.7892)
		(size 0.508)
		(drill 0.254)
		(layers "F.Cu" "B.Cu")
		(net "GND")
	)
	(via
		(at 232.94975 -150.219156)
		(size 0.508)
		(drill 0.254)
		(layers "F.Cu" "B.Cu")
		(net "GND")
	)
	(via
		(at 204.366114 -70.245478)
		(size 0.5588)
		(drill 0.3048)
		(layers "F.Cu" "B.Cu")
		(net "GND")
	)
	(via
		(at 81.772252 -60.047886)
		(size 0.508)
		(drill 0.254)
		(layers "F.Cu" "B.Cu")
		(net "GND")
	)
	(via
		(at 303.001934 9.084056)
		(size 0.5588)
		(drill 0.3048)
		(layers "F.Cu" "B.Cu")
		(net "GND")
	)
	(via
		(at 75.59929 -134.861046)
		(size 0.508)
		(drill 0.254)
		(layers "F.Cu" "B.Cu")
		(net "GND")
	)
	(via
		(at 200.2282 -94.5896)
		(size 0.5588)
		(drill 0.3048)
		(layers "F.Cu" "B.Cu")
		(net "GND")
	)
	(via
		(at 457.941934 9.084056)
		(size 0.5588)
		(drill 0.3048)
		(layers "F.Cu" "B.Cu")
		(net "GND")
	)
	(via
		(at 35.880802 -79.048864)
		(size 0.508)
		(drill 0.254)
		(layers "F.Cu" "B.Cu")
		(net "GND")
	)
	(via
		(at 342.41232 -78.69555)
		(size 0.508)
		(drill 0.254)
		(layers "F.Cu" "B.Cu")
		(net "GND")
	)
	(via
		(at 311.092596 -2.310892)
		(size 0.508)
		(drill 0.254)
		(layers "F.Cu" "B.Cu")
		(net "GND")
	)
	(via
		(at 436.121556 -27.432)
		(size 0.4572)
		(drill 0.2032)
		(layers "F.Cu" "B.Cu")
		(net "GND")
	)
	(via
		(at 428.020734 -163.361624)
		(size 0.5588)
		(drill 0.3048)
		(layers "F.Cu" "B.Cu")
		(net "GND")
	)
	(via
		(at 237.142528 -145.998946)
		(size 0.508)
		(drill 0.254)
		(layers "F.Cu" "B.Cu")
		(net "GND")
	)
	(via
		(at 77.315568 -126.3142)
		(size 0.508)
		(drill 0.254)
		(layers "F.Cu" "B.Cu")
		(net "GND")
	)
	(via
		(at 39.1668 -86.6394)
		(size 0.5588)
		(drill 0.3048)
		(layers "F.Cu" "B.Cu")
		(net "GND")
	)
	(via
		(at 199.736456 -150.749)
		(size 0.508)
		(drill 0.254)
		(layers "F.Cu" "B.Cu")
		(net "GND")
	)
	(via
		(at 239.749838 -139.170156)
		(size 0.508)
		(drill 0.254)
		(layers "F.Cu" "B.Cu")
		(net "GND")
	)
	(via
		(at 64.094106 -9.0805)
		(size 0.508)
		(drill 0.254)
		(layers "F.Cu" "B.Cu")
		(net "GND")
	)
	(via
		(at 391.3378 -106.6546)
		(size 0.508)
		(drill 0.254)
		(layers "F.Cu" "B.Cu")
		(net "GND")
	)
	(via
		(at 251.065284 -64.50584)
		(size 0.508)
		(drill 0.254)
		(layers "F.Cu" "B.Cu")
		(net "GND")
	)
	(via
		(at 216.799922 -136.410446)
		(size 0.508)
		(drill 0.254)
		(layers "F.Cu" "B.Cu")
		(net "GND")
	)
	(via
		(at 199.742552 -9.143746)
		(size 0.508)
		(drill 0.254)
		(layers "F.Cu" "B.Cu")
		(net "GND")
	)
	(via
		(at 440.161934 9.084056)
		(size 0.5588)
		(drill 0.3048)
		(layers "F.Cu" "B.Cu")
		(net "GND")
	)
	(via
		(at 67.949318 -144.462246)
		(size 0.508)
		(drill 0.254)
		(layers "F.Cu" "B.Cu")
		(net "GND")
	)
	(via
		(at 74.045826 -78.37424)
		(size 0.508)
		(drill 0.254)
		(layers "F.Cu" "B.Cu")
		(net "GND")
	)
	(via
		(at 110.843568 5.27304)
		(size 0.508)
		(drill 0.254)
		(layers "F.Cu" "B.Cu")
		(net "GND")
	)
	(via
		(at 390.374124 -162.243262)
		(size 0.5588)
		(drill 0.3048)
		(layers "F.Cu" "B.Cu")
		(net "GND")
	)
	(via
		(at 500.410734 -167.832024)
		(size 0.5588)
		(drill 0.3048)
		(layers "F.Cu" "B.Cu")
		(net "GND")
	)
	(via
		(at 322.5038 -3.321812)
		(size 0.508)
		(drill 0.254)
		(layers "F.Cu" "B.Cu")
		(net "GND")
	)
	(via
		(at 171.2722 -2.501138)
		(size 0.508)
		(drill 0.254)
		(layers "F.Cu" "B.Cu")
		(net "GND")
	)
	(via
		(at 230.399844 -18.757646)
		(size 0.508)
		(drill 0.254)
		(layers "F.Cu" "B.Cu")
		(net "GND")
	)
	(via
		(at 2.276856 12.491466)
		(size 0.5588)
		(drill 0.3048)
		(layers "F.Cu" "B.Cu")
		(net "GND")
	)
	(via
		(at 171.61002 -24.126952)
		(size 0.508)
		(drill 0.254)
		(layers "F.Cu" "B.Cu")
		(net "GND")
	)
	(via
		(at 400.812 -28.702)
		(size 0.508)
		(drill 0.254)
		(layers "F.Cu" "B.Cu")
		(net "GND")
	)
	(via
		(at 315.399928 -21.517356)
		(size 0.508)
		(drill 0.254)
		(layers "F.Cu" "B.Cu")
		(net "GND")
	)
	(via
		(at 56.899302 -154.063446)
		(size 0.508)
		(drill 0.254)
		(layers "F.Cu" "B.Cu")
		(net "GND")
	)
	(via
		(at 143.2052 -70.0786)
		(size 0.508)
		(drill 0.254)
		(layers "F.Cu" "B.Cu")
		(net "GND")
	)
	(via
		(at 376.428 -106.35488)
		(size 0.508)
		(drill 0.254)
		(layers "F.Cu" "B.Cu")
		(net "GND")
	)
	(via
		(at 70.611746 -52.618386)
		(size 0.508)
		(drill 0.254)
		(layers "F.Cu" "B.Cu")
		(net "GND")
	)
	(via
		(at 469.371934 11.624056)
		(size 0.5588)
		(drill 0.3048)
		(layers "F.Cu" "B.Cu")
		(net "GND")
	)
	(via
		(at 452.530464 -50.513488)
		(size 0.508)
		(drill 0.254)
		(layers "F.Cu" "B.Cu")
		(net "GND")
	)
	(via
		(at 347.14942 -32.766)
		(size 0.508)
		(drill 0.254)
		(layers "F.Cu" "B.Cu")
		(net "GND")
	)
	(via
		(at 253.798324 -162.243262)
		(size 0.5588)
		(drill 0.3048)
		(layers "F.Cu" "B.Cu")
		(net "GND")
	)
	(via
		(at 0.381 -137.3124)
		(size 0.508)
		(drill 0.254)
		(layers "F.Cu" "B.Cu")
		(net "GND")
	)
	(via
		(at 127.368808 -73.735184)
		(size 0.508)
		(drill 0.254)
		(layers "F.Cu" "B.Cu")
		(net "GND")
	)
	(via
		(at 495.330734 -167.832024)
		(size 0.5588)
		(drill 0.3048)
		(layers "F.Cu" "B.Cu")
		(net "GND")
	)
	(via
		(at 218.44254 -18.744946)
		(size 0.508)
		(drill 0.254)
		(layers "F.Cu" "B.Cu")
		(net "GND")
	)
	(via
		(at 467.390734 -165.596824)
		(size 0.5588)
		(drill 0.3048)
		(layers "F.Cu" "B.Cu")
		(net "GND")
	)
	(via
		(at 282.354274 -50.375058)
		(size 0.4572)
		(drill 0.2032)
		(layers "F.Cu" "B.Cu")
		(net "GND")
	)
	(via
		(at 18.687796 0.364998)
		(size 0.508)
		(drill 0.254)
		(layers "F.Cu" "B.Cu")
		(net "GND")
	)
	(via
		(at 7.0612 -22.0726)
		(size 0.508)
		(drill 0.254)
		(layers "F.Cu" "B.Cu")
		(net "GND")
	)
	(via
		(at 50.194718 -61.109606)
		(size 0.508)
		(drill 0.254)
		(layers "F.Cu" "B.Cu")
		(net "GND")
	)
	(via
		(at 53.436012 -141.1478)
		(size 0.508)
		(drill 0.254)
		(layers "F.Cu" "B.Cu")
		(net "GND")
	)
	(via
		(at 203.199746 1.994154)
		(size 0.508)
		(drill 0.254)
		(layers "F.Cu" "B.Cu")
		(net "GND")
	)
	(via
		(at 54.74081 -143.950944)
		(size 0.508)
		(drill 0.254)
		(layers "F.Cu" "B.Cu")
		(net "GND")
	)
	(via
		(at 4.345432 -148.720302)
		(size 0.508)
		(drill 0.254)
		(layers "F.Cu" "B.Cu")
		(net "GND")
	)
	(via
		(at 171.831 -20.447)
		(size 0.508)
		(drill 0.254)
		(layers "F.Cu" "B.Cu")
		(net "GND")
	)
	(via
		(at 185.413396 -93.335602)
		(size 0.508)
		(drill 0.254)
		(layers "F.Cu" "B.Cu")
		(net "GND")
	)
	(via
		(at 383.3368 -113.0554)
		(size 0.508)
		(drill 0.254)
		(layers "F.Cu" "B.Cu")
		(net "GND")
	)
	(via
		(at 229.094538 0.5207)
		(size 0.508)
		(drill 0.254)
		(layers "F.Cu" "B.Cu")
		(net "GND")
	)
	(via
		(at 348.0562 -88.9508)
		(size 0.508)
		(drill 0.254)
		(layers "F.Cu" "B.Cu")
		(net "GND")
	)
	(via
		(at 286.93364 -66.305938)
		(size 0.508)
		(drill 0.254)
		(layers "F.Cu" "B.Cu")
		(net "GND")
	)
	(via
		(at 293.69131 -16.696944)
		(size 0.508)
		(drill 0.254)
		(layers "F.Cu" "B.Cu")
		(net "GND")
	)
	(via
		(at 303.044606 -136.3345)
		(size 0.508)
		(drill 0.254)
		(layers "F.Cu" "B.Cu")
		(net "GND")
	)
	(via
		(at 484.611934 14.926056)
		(size 0.5588)
		(drill 0.3048)
		(layers "F.Cu" "B.Cu")
		(net "GND")
	)
	(via
		(at 78.338172 -69.953886)
		(size 0.508)
		(drill 0.254)
		(layers "F.Cu" "B.Cu")
		(net "GND")
	)
	(via
		(at 187.099448 -60.428632)
		(size 0.508)
		(drill 0.254)
		(layers "F.Cu" "B.Cu")
		(net "GND")
	)
	(via
		(at 445.491362 -5.617464)
		(size 0.508)
		(drill 0.254)
		(layers "F.Cu" "B.Cu")
		(net "GND")
	)
	(via
		(at -4.363466 -166.714424)
		(size 0.5588)
		(drill 0.3048)
		(layers "F.Cu" "B.Cu")
		(net "GND")
	)
	(via
		(at 3.838194 -15.888462)
		(size 0.508)
		(drill 0.254)
		(layers "F.Cu" "B.Cu")
		(net "GND")
	)
	(via
		(at 281.361896 -2.314956)
		(size 0.508)
		(drill 0.254)
		(layers "F.Cu" "B.Cu")
		(net "GND")
	)
	(via
		(at 232.099866 -9.156446)
		(size 0.508)
		(drill 0.254)
		(layers "F.Cu" "B.Cu")
		(net "GND")
	)
	(via
		(at 61.111384 -21.517356)
		(size 0.508)
		(drill 0.254)
		(layers "F.Cu" "B.Cu")
		(net "GND")
	)
	(via
		(at 74.045826 -50.63744)
		(size 0.508)
		(drill 0.254)
		(layers "F.Cu" "B.Cu")
		(net "GND")
	)
	(via
		(at 243.338604 -82.83194)
		(size 0.508)
		(drill 0.254)
		(layers "F.Cu" "B.Cu")
		(net "GND")
	)
	(via
		(at 163.908994 -29.647896)
		(size 0.508)
		(drill 0.254)
		(layers "F.Cu" "B.Cu")
		(net "GND")
	)
	(via
		(at 170.671744 -94.785434)
		(size 0.508)
		(drill 0.254)
		(layers "F.Cu" "B.Cu")
		(net "GND")
	)
	(via
		(at 117.071648 -144.5006)
		(size 0.508)
		(drill 0.254)
		(layers "F.Cu" "B.Cu")
		(net "GND")
	)
	(via
		(at 426.191934 9.084056)
		(size 0.5588)
		(drill 0.3048)
		(layers "F.Cu" "B.Cu")
		(net "GND")
	)
	(via
		(at 442.564774 -150.24862)
		(size 0.508)
		(drill 0.254)
		(layers "F.Cu" "B.Cu")
		(net "GND")
	)
	(via
		(at 22.455124 -162.243262)
		(size 0.5588)
		(drill 0.3048)
		(layers "F.Cu" "B.Cu")
		(net "GND")
	)
	(via
		(at 344.6653 -13.80998)
		(size 0.508)
		(drill 0.254)
		(layers "F.Cu" "B.Cu")
		(net "GND")
	)
	(via
		(at 147.390866 -143.950944)
		(size 0.508)
		(drill 0.254)
		(layers "F.Cu" "B.Cu")
		(net "GND")
	)
	(via
		(at 128.227328 -80.174338)
		(size 0.508)
		(drill 0.254)
		(layers "F.Cu" "B.Cu")
		(net "GND")
	)
	(via
		(at 345.16314 -103.75392)
		(size 0.508)
		(drill 0.254)
		(layers "F.Cu" "B.Cu")
		(net "GND")
	)
	(via
		(at 187.0202 -137.541)
		(size 0.508)
		(drill 0.254)
		(layers "F.Cu" "B.Cu")
		(net "GND")
	)
	(via
		(at 261.7343 -5.8801)
		(size 0.508)
		(drill 0.254)
		(layers "F.Cu" "B.Cu")
		(net "GND")
	)
	(via
		(at 111.863124 -162.243262)
		(size 0.5588)
		(drill 0.3048)
		(layers "F.Cu" "B.Cu")
		(net "GND")
	)
	(via
		(at 459.169008 -136.779254)
		(size 0.508)
		(drill 0.254)
		(layers "F.Cu" "B.Cu")
		(net "GND")
	)
	(via
		(at 140.246354 -58.381138)
		(size 0.508)
		(drill 0.254)
		(layers "F.Cu" "B.Cu")
		(net "GND")
	)
	(via
		(at 148.699474 -136.410446)
		(size 0.508)
		(drill 0.254)
		(layers "F.Cu" "B.Cu")
		(net "GND")
	)
	(via
		(at 409.322524 -120.591072)
		(size 0.508)
		(drill 0.254)
		(layers "F.Cu" "B.Cu")
		(net "GND")
	)
	(via
		(at 77.299312 -144.462246)
		(size 0.508)
		(drill 0.254)
		(layers "F.Cu" "B.Cu")
		(net "GND")
	)
	(via
		(at 90.845894 -135.636)
		(size 0.508)
		(drill 0.254)
		(layers "F.Cu" "B.Cu")
		(net "GND")
	)
	(via
		(at 74.045826 -101.15804)
		(size 0.508)
		(drill 0.254)
		(layers "F.Cu" "B.Cu")
		(net "GND")
	)
	(via
		(at 261.091934 14.926056)
		(size 0.5588)
		(drill 0.3048)
		(layers "F.Cu" "B.Cu")
		(net "GND")
	)
	(via
		(at 278.727408 1.82372)
		(size 0.508)
		(drill 0.254)
		(layers "F.Cu" "B.Cu")
		(net "GND")
	)
	(via
		(at 344.428572 -137.178542)
		(size 0.508)
		(drill 0.254)
		(layers "F.Cu" "B.Cu")
		(net "GND")
	)
	(via
		(at 351.444306 -80.079596)
		(size 0.508)
		(drill 0.254)
		(layers "F.Cu" "B.Cu")
		(net "GND")
	)
	(via
		(at 129.085848 -80.669384)
		(size 0.508)
		(drill 0.254)
		(layers "F.Cu" "B.Cu")
		(net "GND")
	)
	(via
		(at 469.281256 -5.495544)
		(size 0.5588)
		(drill 0.3048)
		(layers "F.Cu" "B.Cu")
		(net "GND")
	)
	(via
		(at 68.036186 -62.029086)
		(size 0.508)
		(drill 0.254)
		(layers "F.Cu" "B.Cu")
		(net "GND")
	)
	(via
		(at 129.999486 -11.916156)
		(size 0.508)
		(drill 0.254)
		(layers "F.Cu" "B.Cu")
		(net "GND")
	)
	(via
		(at 345.506294 -150.767542)
		(size 0.508)
		(drill 0.254)
		(layers "F.Cu" "B.Cu")
		(net "GND")
	)
	(via
		(at 439.405776 -63.582296)
		(size 0.508)
		(drill 0.254)
		(layers "F.Cu" "B.Cu")
		(net "GND")
	)
	(via
		(at 77.299312 1.994154)
		(size 0.508)
		(drill 0.254)
		(layers "F.Cu" "B.Cu")
		(net "GND")
	)
	(via
		(at 436.921656 -32.2072)
		(size 0.4572)
		(drill 0.2032)
		(layers "F.Cu" "B.Cu")
		(net "GND")
	)
	(via
		(at 426.11167 -43.176444)
		(size 0.508)
		(drill 0.254)
		(layers "F.Cu" "B.Cu")
		(net "GND")
	)
	(via
		(at 21.061934 9.084056)
		(size 0.5588)
		(drill 0.3048)
		(layers "F.Cu" "B.Cu")
		(net "GND")
	)
	(via
		(at 480.845876 2.576068)
		(size 0.508)
		(drill 0.254)
		(layers "F.Cu" "B.Cu")
		(net "GND")
	)
	(via
		(at 71.470266 -82.83194)
		(size 0.508)
		(drill 0.254)
		(layers "F.Cu" "B.Cu")
		(net "GND")
	)
	(via
		(at 393.684252 -115.243356)
		(size 0.508)
		(drill 0.254)
		(layers "F.Cu" "B.Cu")
		(net "GND")
	)
	(via
		(at 206.51089 -22.939756)
		(size 0.508)
		(drill 0.254)
		(layers "F.Cu" "B.Cu")
		(net "GND")
	)
	(via
		(at 272.623788 -92.061538)
		(size 0.508)
		(drill 0.254)
		(layers "F.Cu" "B.Cu")
		(net "GND")
	)
	(via
		(at 261.36727 -88.28024)
		(size 0.508)
		(drill 0.254)
		(layers "F.Cu" "B.Cu")
		(net "GND")
	)
	(via
		(at 245.055644 -53.113686)
		(size 0.508)
		(drill 0.254)
		(layers "F.Cu" "B.Cu")
		(net "GND")
	)
	(via
		(at 356.161594 -157.389322)
		(size 0.5588)
		(drill 0.3048)
		(layers "F.Cu" "B.Cu")
		(net "GND")
	)
	(via
		(at 129.748534 -167.832024)
		(size 0.5588)
		(drill 0.3048)
		(layers "F.Cu" "B.Cu")
		(net "GND")
	)
	(via
		(at 459.211934 12.894056)
		(size 0.5588)
		(drill 0.3048)
		(layers "F.Cu" "B.Cu")
		(net "GND")
	)
	(via
		(at 105.230676 -75.159616)
		(size 0.5588)
		(drill 0.3048)
		(layers "F.Cu" "B.Cu")
		(net "GND")
	)
	(via
		(at 119.337328 -141.202156)
		(size 0.508)
		(drill 0.254)
		(layers "F.Cu" "B.Cu")
		(net "GND")
	)
	(via
		(at 67.959986 -93.72854)
		(size 0.508)
		(drill 0.254)
		(layers "F.Cu" "B.Cu")
		(net "GND")
	)
	(via
		(at 289.79368 -84.136738)
		(size 0.508)
		(drill 0.254)
		(layers "F.Cu" "B.Cu")
		(net "GND")
	)
	(via
		(at 115.065302 -58.381138)
		(size 0.508)
		(drill 0.254)
		(layers "F.Cu" "B.Cu")
		(net "GND")
	)
	(via
		(at 69.753226 -58.06694)
		(size 0.508)
		(drill 0.254)
		(layers "F.Cu" "B.Cu")
		(net "GND")
	)
	(via
		(at 391.3378 -104.2543)
		(size 0.508)
		(drill 0.254)
		(layers "F.Cu" "B.Cu")
		(net "GND")
	)
	(via
		(at 81.565242 -140.208)
		(size 0.508)
		(drill 0.254)
		(layers "F.Cu" "B.Cu")
		(net "GND")
	)
	(via
		(at 240.599722 -22.965156)
		(size 0.508)
		(drill 0.254)
		(layers "F.Cu" "B.Cu")
		(net "GND")
	)
	(via
		(at 230.399844 -139.170156)
		(size 0.508)
		(drill 0.254)
		(layers "F.Cu" "B.Cu")
		(net "GND")
	)
	(via
		(at 31.893002 -71.784464)
		(size 0.508)
		(drill 0.254)
		(layers "F.Cu" "B.Cu")
		(net "GND")
	)
	(via
		(at 423.490136 -32.534606)
		(size 0.4572)
		(drill 0.2032)
		(layers "F.Cu" "B.Cu")
		(net "GND")
	)
	(via
		(at 307.443124 -162.243262)
		(size 0.5588)
		(drill 0.3048)
		(layers "F.Cu" "B.Cu")
		(net "GND")
	)
	(via
		(at 51.512724 -162.243262)
		(size 0.5588)
		(drill 0.3048)
		(layers "F.Cu" "B.Cu")
		(net "GND")
	)
	(via
		(at 306.963826 -69.277738)
		(size 0.508)
		(drill 0.254)
		(layers "F.Cu" "B.Cu")
		(net "GND")
	)
	(via
		(at 285.649924 -146.011646)
		(size 0.508)
		(drill 0.254)
		(layers "F.Cu" "B.Cu")
		(net "GND")
	)
	(via
		(at 439.278776 -31.440628)
		(size 0.4572)
		(drill 0.2032)
		(layers "F.Cu" "B.Cu")
		(net "GND")
	)
	(via
		(at 389.260334 -167.832024)
		(size 0.5588)
		(drill 0.3048)
		(layers "F.Cu" "B.Cu")
		(net "GND")
	)
	(via
		(at 358.458516 -11.688572)
		(size 0.508)
		(drill 0.254)
		(layers "F.Cu" "B.Cu")
		(net "GND")
	)
	(via
		(at 295.849802 -134.861046)
		(size 0.508)
		(drill 0.254)
		(layers "F.Cu" "B.Cu")
		(net "GND")
	)
	(via
		(at 397.14805 -108.766356)
		(size 0.508)
		(drill 0.254)
		(layers "F.Cu" "B.Cu")
		(net "GND")
	)
	(via
		(at 289.79368 -95.033084)
		(size 0.508)
		(drill 0.254)
		(layers "F.Cu" "B.Cu")
		(net "GND")
	)
	(via
		(at 218.44254 0.457454)
		(size 0.508)
		(drill 0.254)
		(layers "F.Cu" "B.Cu")
		(net "GND")
	)
	(via
		(at 288.93516 -100.481638)
		(size 0.508)
		(drill 0.254)
		(layers "F.Cu" "B.Cu")
		(net "GND")
	)
	(via
		(at 5.694934 -166.714424)
		(size 0.5588)
		(drill 0.3048)
		(layers "F.Cu" "B.Cu")
		(net "GND")
	)
	(via
		(at 498.213888 -42.10304)
		(size 0.508)
		(drill 0.254)
		(layers "F.Cu" "B.Cu")
		(net "GND")
	)
	(via
		(at 21.567902 -110.355634)
		(size 0.5588)
		(drill 0.3048)
		(layers "F.Cu" "B.Cu")
		(net "GND")
	)
	(via
		(at 149.549358 -154.063446)
		(size 0.508)
		(drill 0.254)
		(layers "F.Cu" "B.Cu")
		(net "GND")
	)
	(via
		(at 403.8346 -21.443188)
		(size 0.508)
		(drill 0.254)
		(layers "F.Cu" "B.Cu")
		(net "GND")
	)
	(via
		(at 278.9682 -22.8346)
		(size 0.508)
		(drill 0.254)
		(layers "F.Cu" "B.Cu")
		(net "GND")
	)
	(via
		(at 72.136 -4.2926)
		(size 0.508)
		(drill 0.254)
		(layers "F.Cu" "B.Cu")
		(net "GND")
	)
	(via
		(at 491.93958 -154.23134)
		(size 0.508)
		(drill 0.254)
		(layers "F.Cu" "B.Cu")
		(net "GND")
	)
	(via
		(at 444.526924 -162.243262)
		(size 0.5588)
		(drill 0.3048)
		(layers "F.Cu" "B.Cu")
		(net "GND")
	)
	(via
		(at 276.057614 -92.061538)
		(size 0.508)
		(drill 0.254)
		(layers "F.Cu" "B.Cu")
		(net "GND")
	)
	(via
		(at 494.771934 11.624056)
		(size 0.5588)
		(drill 0.3048)
		(layers "F.Cu" "B.Cu")
		(net "GND")
	)
	(via
		(at 198.061834 -2.314956)
		(size 0.508)
		(drill 0.254)
		(layers "F.Cu" "B.Cu")
		(net "GND")
	)
	(via
		(at 201.401934 14.926056)
		(size 0.5588)
		(drill 0.3048)
		(layers "F.Cu" "B.Cu")
		(net "GND")
	)
	(via
		(at 123.199398 1.994154)
		(size 0.508)
		(drill 0.254)
		(layers "F.Cu" "B.Cu")
		(net "GND")
	)
	(via
		(at 168.6814 -88.392)
		(size 0.508)
		(drill 0.254)
		(layers "F.Cu" "B.Cu")
		(net "GND")
	)
	(via
		(at 300.095666 -74.230738)
		(size 0.508)
		(drill 0.254)
		(layers "F.Cu" "B.Cu")
		(net "GND")
	)
	(via
		(at 470.641934 14.926056)
		(size 0.5588)
		(drill 0.3048)
		(layers "F.Cu" "B.Cu")
		(net "GND")
	)
	(via
		(at 206.51089 -130.991356)
		(size 0.508)
		(drill 0.254)
		(layers "F.Cu" "B.Cu")
		(net "GND")
	)
	(via
		(at 135.095234 -73.240138)
		(size 0.508)
		(drill 0.254)
		(layers "F.Cu" "B.Cu")
		(net "GND")
	)
	(via
		(at 376.428 -101.35489)
		(size 0.508)
		(drill 0.254)
		(layers "F.Cu" "B.Cu")
		(net "GND")
	)
	(via
		(at 142.749524 -136.397746)
		(size 0.508)
		(drill 0.254)
		(layers "F.Cu" "B.Cu")
		(net "GND")
	)
	(via
		(at 232.94975 -131.016756)
		(size 0.508)
		(drill 0.254)
		(layers "F.Cu" "B.Cu")
		(net "GND")
	)
	(via
		(at 341.761572 4.692904)
		(size 0.508)
		(drill 0.254)
		(layers "F.Cu" "B.Cu")
		(net "GND")
	)
	(via
		(at 175.478694 -56.087518)
		(size 0.508)
		(drill 0.254)
		(layers "F.Cu" "B.Cu")
		(net "GND")
	)
	(via
		(at 285.2166 -58.381138)
		(size 0.508)
		(drill 0.254)
		(layers "F.Cu" "B.Cu")
		(net "GND")
	)
	(via
		(at 134.236714 -52.932838)
		(size 0.508)
		(drill 0.254)
		(layers "F.Cu" "B.Cu")
		(net "GND")
	)
	(via
		(at 208.122012 -3.762756)
		(size 0.508)
		(drill 0.254)
		(layers "F.Cu" "B.Cu")
		(net "GND")
	)
	(via
		(at 475.721934 10.354056)
		(size 0.5588)
		(drill 0.3048)
		(layers "F.Cu" "B.Cu")
		(net "GND")
	)
	(via
		(at 295.849802 -154.063446)
		(size 0.508)
		(drill 0.254)
		(layers "F.Cu" "B.Cu")
		(net "GND")
	)
	(via
		(at 284.642814 -101.967538)
		(size 0.508)
		(drill 0.254)
		(layers "F.Cu" "B.Cu")
		(net "GND")
	)
	(via
		(at 131.661408 -81.164938)
		(size 0.508)
		(drill 0.254)
		(layers "F.Cu" "B.Cu")
		(net "GND")
	)
	(via
		(at 38.260782 -92.572078)
		(size 0.5588)
		(drill 0.3048)
		(layers "F.Cu" "B.Cu")
		(net "GND")
	)
	(via
		(at 4.348734 14.926056)
		(size 0.5588)
		(drill 0.3048)
		(layers "F.Cu" "B.Cu")
		(net "GND")
	)
	(via
		(at 241.621818 -83.822286)
		(size 0.508)
		(drill 0.254)
		(layers "F.Cu" "B.Cu")
		(net "GND")
	)
	(via
		(at 289.801808 -154.063446)
		(size 0.508)
		(drill 0.254)
		(layers "F.Cu" "B.Cu")
		(net "GND")
	)
	(via
		(at 35.525964 -84.586064)
		(size 0.5588)
		(drill 0.3048)
		(layers "F.Cu" "B.Cu")
		(net "GND")
	)
	(via
		(at 183.6928 -140.1445)
		(size 0.508)
		(drill 0.254)
		(layers "F.Cu" "B.Cu")
		(net "GND")
	)
	(via
		(at 206.904082 -62.190122)
		(size 0.5588)
		(drill 0.3048)
		(layers "F.Cu" "B.Cu")
		(net "GND")
	)
	(via
		(at 78.128368 -18.7452)
		(size 0.508)
		(drill 0.254)
		(layers "F.Cu" "B.Cu")
		(net "GND")
	)
	(via
		(at 39.479982 -76.468478)
		(size 0.5588)
		(drill 0.3048)
		(layers "F.Cu" "B.Cu")
		(net "GND")
	)
	(via
		(at 344.519504 -6.138418)
		(size 0.508)
		(drill 0.254)
		(layers "F.Cu" "B.Cu")
		(net "GND")
	)
	(via
		(at 114.491262 -96.023938)
		(size 0.508)
		(drill 0.254)
		(layers "F.Cu" "B.Cu")
		(net "GND")
	)
	(via
		(at 452.722234 -6.815328)
		(size 0.508)
		(drill 0.254)
		(layers "F.Cu" "B.Cu")
		(net "GND")
	)
	(via
		(at 126.395734 -167.832024)
		(size 0.5588)
		(drill 0.3048)
		(layers "F.Cu" "B.Cu")
		(net "GND")
	)
	(via
		(at 227.78339 -124.590556)
		(size 0.508)
		(drill 0.254)
		(layers "F.Cu" "B.Cu")
		(net "GND")
	)
	(via
		(at 20.22602 -128.16332)
		(size 0.508)
		(drill 0.254)
		(layers "F.Cu" "B.Cu")
		(net "GND")
	)
	(via
		(at 43.12158 -144.5006)
		(size 0.508)
		(drill 0.254)
		(layers "F.Cu" "B.Cu")
		(net "GND")
	)
	(via
		(at 69.753226 -87.784686)
		(size 0.508)
		(drill 0.254)
		(layers "F.Cu" "B.Cu")
		(net "GND")
	)
	(via
		(at 468.561928 -155.10002)
		(size 0.5588)
		(drill 0.3048)
		(layers "F.Cu" "B.Cu")
		(net "GND")
	)
	(via
		(at 240.763298 -62.52464)
		(size 0.508)
		(drill 0.254)
		(layers "F.Cu" "B.Cu")
		(net "GND")
	)
	(via
		(at 35.880802 -55.299864)
		(size 0.508)
		(drill 0.254)
		(layers "F.Cu" "B.Cu")
		(net "GND")
	)
	(via
		(at 92.074238 -86.794086)
		(size 0.508)
		(drill 0.254)
		(layers "F.Cu" "B.Cu")
		(net "GND")
	)
	(via
		(at 375.190766 -151.804624)
		(size 0.508)
		(drill 0.254)
		(layers "F.Cu" "B.Cu")
		(net "GND")
	)
	(via
		(at 263.631934 9.084056)
		(size 0.5588)
		(drill 0.3048)
		(layers "F.Cu" "B.Cu")
		(net "GND")
	)
	(via
		(at 201.031856 -2.3114)
		(size 0.508)
		(drill 0.254)
		(layers "F.Cu" "B.Cu")
		(net "GND")
	)
	(via
		(at 242.287044 -150.219156)
		(size 0.508)
		(drill 0.254)
		(layers "F.Cu" "B.Cu")
		(net "GND")
	)
	(via
		(at 114.699542 -11.9126)
		(size 0.508)
		(drill 0.254)
		(layers "F.Cu" "B.Cu")
		(net "GND")
	)
	(via
		(at 168.529 -12.192)
		(size 0.508)
		(drill 0.254)
		(layers "F.Cu" "B.Cu")
		(net "GND")
	)
	(via
		(at 216.761822 -2.314956)
		(size 0.508)
		(drill 0.254)
		(layers "F.Cu" "B.Cu")
		(net "GND")
	)
	(via
		(at 0.882396 -52.898802)
		(size 0.5588)
		(drill 0.3048)
		(layers "F.Cu" "B.Cu")
		(net "GND")
	)
	(via
		(at 347.86316 -77.25029)
		(size 0.508)
		(drill 0.254)
		(layers "F.Cu" "B.Cu")
		(net "GND")
	)
	(via
		(at 223.599756 -154.063446)
		(size 0.508)
		(drill 0.254)
		(layers "F.Cu" "B.Cu")
		(net "GND")
	)
	(via
		(at 229.091236 -16.696944)
		(size 0.508)
		(drill 0.254)
		(layers "F.Cu" "B.Cu")
		(net "GND")
	)
	(via
		(at 475.010734 -164.479224)
		(size 0.5588)
		(drill 0.3048)
		(layers "F.Cu" "B.Cu")
		(net "GND")
	)
	(via
		(at 446.129918 -143.21536)
		(size 0.508)
		(drill 0.254)
		(layers "F.Cu" "B.Cu")
		(net "GND")
	)
	(via
		(at 204.899768 -131.016756)
		(size 0.508)
		(drill 0.254)
		(layers "F.Cu" "B.Cu")
		(net "GND")
	)
	(via
		(at 135.953754 -81.659984)
		(size 0.508)
		(drill 0.254)
		(layers "F.Cu" "B.Cu")
		(net "GND")
	)
	(via
		(at 171.161456 -0.289306)
		(size 0.5588)
		(drill 0.3048)
		(layers "F.Cu" "B.Cu")
		(net "GND")
	)
	(via
		(at 233.895138 -90.26144)
		(size 0.508)
		(drill 0.254)
		(layers "F.Cu" "B.Cu")
		(net "GND")
	)
	(via
		(at 376.428 -117.355112)
		(size 0.508)
		(drill 0.254)
		(layers "F.Cu" "B.Cu")
		(net "GND")
	)
	(via
		(at 289.810952 -22.939756)
		(size 0.508)
		(drill 0.254)
		(layers "F.Cu" "B.Cu")
		(net "GND")
	)
	(via
		(at 299.237146 -75.716384)
		(size 0.508)
		(drill 0.254)
		(layers "F.Cu" "B.Cu")
		(net "GND")
	)
	(via
		(at 136.74217 -2.310892)
		(size 0.508)
		(drill 0.254)
		(layers "F.Cu" "B.Cu")
		(net "GND")
	)
	(via
		(at 112.501934 9.084056)
		(size 0.5588)
		(drill 0.3048)
		(layers "F.Cu" "B.Cu")
		(net "GND")
	)
	(via
		(at 488.421934 9.084056)
		(size 0.5588)
		(drill 0.3048)
		(layers "F.Cu" "B.Cu")
		(net "GND")
	)
	(via
		(at 300.954186 -59.866784)
		(size 0.508)
		(drill 0.254)
		(layers "F.Cu" "B.Cu")
		(net "GND")
	)
	(via
		(at 469.930734 -167.832024)
		(size 0.5588)
		(drill 0.3048)
		(layers "F.Cu" "B.Cu")
		(net "GND")
	)
	(via
		(at 422.940734 -165.596824)
		(size 0.5588)
		(drill 0.3048)
		(layers "F.Cu" "B.Cu")
		(net "GND")
	)
	(via
		(at 35.880802 -75.746864)
		(size 0.508)
		(drill 0.254)
		(layers "F.Cu" "B.Cu")
		(net "GND")
	)
	(via
		(at 226.149916 -155.612846)
		(size 0.508)
		(drill 0.254)
		(layers "F.Cu" "B.Cu")
		(net "GND")
	)
	(via
		(at 447.070734 -164.479224)
		(size 0.5588)
		(drill 0.3048)
		(layers "F.Cu" "B.Cu")
		(net "GND")
	)
	(via
		(at 446.453006 -31.4579)
		(size 0.4572)
		(drill 0.2032)
		(layers "F.Cu" "B.Cu")
		(net "GND")
	)
	(via
		(at 399.521934 9.084056)
		(size 0.5588)
		(drill 0.3048)
		(layers "F.Cu" "B.Cu")
		(net "GND")
	)
	(via
		(at 219.741242 2.505456)
		(size 0.508)
		(drill 0.254)
		(layers "F.Cu" "B.Cu")
		(net "GND")
	)
	(via
		(at 227.792534 -148.767292)
		(size 0.508)
		(drill 0.254)
		(layers "F.Cu" "B.Cu")
		(net "GND")
	)
	(via
		(at 199.9488 -62.0268)
		(size 0.5588)
		(drill 0.3048)
		(layers "F.Cu" "B.Cu")
		(net "GND")
	)
	(via
		(at 199.736456 -4.2926)
		(size 0.508)
		(drill 0.254)
		(layers "F.Cu" "B.Cu")
		(net "GND")
	)
	(via
		(at 438.180734 -164.479224)
		(size 0.5588)
		(drill 0.3048)
		(layers "F.Cu" "B.Cu")
		(net "GND")
	)
	(via
		(at 465.404454 -118.61927)
		(size 0.508)
		(drill 0.254)
		(layers "F.Cu" "B.Cu")
		(net "GND")
	)
	(via
		(at 300.954186 -97.509584)
		(size 0.508)
		(drill 0.254)
		(layers "F.Cu" "B.Cu")
		(net "GND")
	)
	(via
		(at 445.350138 -58.954924)
		(size 0.508)
		(drill 0.254)
		(layers "F.Cu" "B.Cu")
		(net "GND")
	)
	(via
		(at 229.211124 -162.243262)
		(size 0.5588)
		(drill 0.3048)
		(layers "F.Cu" "B.Cu")
		(net "GND")
	)
	(via
		(at 405.369522 -18.166588)
		(size 0.508)
		(drill 0.254)
		(layers "F.Cu" "B.Cu")
		(net "GND")
	)
	(via
		(at 193.761868 -76.818236)
		(size 0.508)
		(drill 0.254)
		(layers "F.Cu" "B.Cu")
		(net "GND")
	)
	(via
		(at 136.748774 -144.0053)
		(size 0.508)
		(drill 0.254)
		(layers "F.Cu" "B.Cu")
		(net "GND")
	)
	(via
		(at 398.048734 -92.917518)
		(size 0.508)
		(drill 0.254)
		(layers "F.Cu" "B.Cu")
		(net "GND")
	)
	(via
		(at 77.286612 -22.965156)
		(size 0.508)
		(drill 0.254)
		(layers "F.Cu" "B.Cu")
		(net "GND")
	)
	(via
		(at 86.923372 -79.859886)
		(size 0.508)
		(drill 0.254)
		(layers "F.Cu" "B.Cu")
		(net "GND")
	)
	(via
		(at 113.967768 -140.4874)
		(size 0.508)
		(drill 0.254)
		(layers "F.Cu" "B.Cu")
		(net "GND")
	)
	(via
		(at 248.489724 -56.085486)
		(size 0.508)
		(drill 0.254)
		(layers "F.Cu" "B.Cu")
		(net "GND")
	)
	(via
		(at -2.959608 -113.92662)
		(size 0.5588)
		(drill 0.3048)
		(layers "F.Cu" "B.Cu")
		(net "GND")
	)
	(via
		(at 321.6148 -31.115)
		(size 0.508)
		(drill 0.254)
		(layers "F.Cu" "B.Cu")
		(net "GND")
	)
	(via
		(at 419.841934 9.084056)
		(size 0.5588)
		(drill 0.3048)
		(layers "F.Cu" "B.Cu")
		(net "GND")
	)
	(via
		(at 123.650248 -59.371484)
		(size 0.508)
		(drill 0.254)
		(layers "F.Cu" "B.Cu")
		(net "GND")
	)
	(via
		(at 292.841934 14.926056)
		(size 0.5588)
		(drill 0.3048)
		(layers "F.Cu" "B.Cu")
		(net "GND")
	)
	(via
		(at 214.682324 -162.243262)
		(size 0.5588)
		(drill 0.3048)
		(layers "F.Cu" "B.Cu")
		(net "GND")
	)
	(via
		(at 125.749558 -136.410446)
		(size 0.508)
		(drill 0.254)
		(layers "F.Cu" "B.Cu")
		(net "GND")
	)
	(via
		(at 435.636924 -162.243262)
		(size 0.5588)
		(drill 0.3048)
		(layers "F.Cu" "B.Cu")
		(net "GND")
	)
	(via
		(at 71.470266 -92.737686)
		(size 0.508)
		(drill 0.254)
		(layers "F.Cu" "B.Cu")
		(net "GND")
	)
	(via
		(at 67.099434 -26.488136)
		(size 0.508)
		(drill 0.254)
		(layers "F.Cu" "B.Cu")
		(net "GND")
	)
	(via
		(at 275.199348 -96.518984)
		(size 0.508)
		(drill 0.254)
		(layers "F.Cu" "B.Cu")
		(net "GND")
	)
	(via
		(at 273.092418 -75.148186)
		(size 0.5588)
		(drill 0.3048)
		(layers "F.Cu" "B.Cu")
		(net "GND")
	)
	(via
		(at 458.500734 -167.832024)
		(size 0.5588)
		(drill 0.3048)
		(layers "F.Cu" "B.Cu")
		(net "GND")
	)
	(via
		(at -3.474466 14.926056)
		(size 0.5588)
		(drill 0.3048)
		(layers "F.Cu" "B.Cu")
		(net "GND")
	)
	(via
		(at 232.101898 -83.32724)
		(size 0.508)
		(drill 0.254)
		(layers "F.Cu" "B.Cu")
		(net "GND")
	)
	(via
		(at 387.24205 -101.898196)
		(size 0.508)
		(drill 0.254)
		(layers "F.Cu" "B.Cu")
		(net "GND")
	)
	(via
		(at 306.105306 -91.565984)
		(size 0.508)
		(drill 0.254)
		(layers "F.Cu" "B.Cu")
		(net "GND")
	)
	(via
		(at 293.69131 -153.552144)
		(size 0.508)
		(drill 0.254)
		(layers "F.Cu" "B.Cu")
		(net "GND")
	)
	(via
		(at 278.871934 9.084056)
		(size 0.5588)
		(drill 0.3048)
		(layers "F.Cu" "B.Cu")
		(net "GND")
	)
	(via
		(at 4.348734 9.084056)
		(size 0.5588)
		(drill 0.3048)
		(layers "F.Cu" "B.Cu")
		(net "GND")
	)
	(via
		(at 327.563734 -167.832024)
		(size 0.5588)
		(drill 0.3048)
		(layers "F.Cu" "B.Cu")
		(net "GND")
	)
	(via
		(at 202.349862 -21.517356)
		(size 0.508)
		(drill 0.254)
		(layers "F.Cu" "B.Cu")
		(net "GND")
	)
	(via
		(at 203.900786 -92.60205)
		(size 0.5588)
		(drill 0.3048)
		(layers "F.Cu" "B.Cu")
		(net "GND")
	)
	(via
		(at 307.749956 -9.143746)
		(size 0.508)
		(drill 0.254)
		(layers "F.Cu" "B.Cu")
		(net "GND")
	)
	(via
		(at 172.2628 -81.1022)
		(size 0.508)
		(drill 0.254)
		(layers "F.Cu" "B.Cu")
		(net "GND")
	)
	(via
		(at 306.899818 -13.363956)
		(size 0.508)
		(drill 0.254)
		(layers "F.Cu" "B.Cu")
		(net "GND")
	)
	(via
		(at 11.282934 -167.832024)
		(size 0.5588)
		(drill 0.3048)
		(layers "F.Cu" "B.Cu")
		(net "GND")
	)
	(via
		(at 341.531702 -141.319504)
		(size 0.508)
		(drill 0.254)
		(layers "F.Cu" "B.Cu")
		(net "GND")
	)
	(via
		(at 226.149916 -9.156446)
		(size 0.508)
		(drill 0.254)
		(layers "F.Cu" "B.Cu")
		(net "GND")
	)
	(via
		(at 194.49542 -85.106256)
		(size 0.508)
		(drill 0.254)
		(layers "F.Cu" "B.Cu")
		(net "GND")
	)
	(via
		(at 278.9682 -130.8862)
		(size 0.508)
		(drill 0.254)
		(layers "F.Cu" "B.Cu")
		(net "GND")
	)
	(via
		(at 144.449546 -155.612846)
		(size 0.508)
		(drill 0.254)
		(layers "F.Cu" "B.Cu")
		(net "GND")
	)
	(via
		(at 476.280734 -167.832024)
		(size 0.5588)
		(drill 0.3048)
		(layers "F.Cu" "B.Cu")
		(net "GND")
	)
	(via
		(at 120.500902 -96.518984)
		(size 0.508)
		(drill 0.254)
		(layers "F.Cu" "B.Cu")
		(net "GND")
	)
	(via
		(at 61.821568 -3.762756)
		(size 0.508)
		(drill 0.254)
		(layers "F.Cu" "B.Cu")
		(net "GND")
	)
	(via
		(at 34.74212 -129.564892)
		(size 0.508)
		(drill 0.254)
		(layers "F.Cu" "B.Cu")
		(net "GND")
	)
	(via
		(at 468.660734 -165.596824)
		(size 0.5588)
		(drill 0.3048)
		(layers "F.Cu" "B.Cu")
		(net "GND")
	)
	(via
		(at 365.743236 -102.54742)
		(size 0.508)
		(drill 0.254)
		(layers "F.Cu" "B.Cu")
		(net "GND")
	)
	(via
		(at 315.399928 -11.916156)
		(size 0.508)
		(drill 0.254)
		(layers "F.Cu" "B.Cu")
		(net "GND")
	)
	(via
		(at 477.550734 -164.479224)
		(size 0.5588)
		(drill 0.3048)
		(layers "F.Cu" "B.Cu")
		(net "GND")
	)
	(via
		(at 116.208302 -92.061538)
		(size 0.508)
		(drill 0.254)
		(layers "F.Cu" "B.Cu")
		(net "GND")
	)
	(via
		(at 141.181074 -75.716384)
		(size 0.508)
		(drill 0.254)
		(layers "F.Cu" "B.Cu")
		(net "GND")
	)
	(via
		(at 330.454 -15.748)
		(size 0.508)
		(drill 0.254)
		(layers "F.Cu" "B.Cu")
		(net "GND")
	)
	(via
		(at 4.939792 -143.9418)
		(size 0.508)
		(drill 0.254)
		(layers "F.Cu" "B.Cu")
		(net "GND")
	)
	(via
		(at 77.479906 -67.47764)
		(size 0.508)
		(drill 0.254)
		(layers "F.Cu" "B.Cu")
		(net "GND")
	)
	(via
		(at 117.071648 -140.592556)
		(size 0.508)
		(drill 0.254)
		(layers "F.Cu" "B.Cu")
		(net "GND")
	)
	(via
		(at 412.570422 -142.683738)
		(size 0.508)
		(drill 0.254)
		(layers "F.Cu" "B.Cu")
		(net "GND")
	)
	(via
		(at 212.54974 -144.462246)
		(size 0.508)
		(drill 0.254)
		(layers "F.Cu" "B.Cu")
		(net "GND")
	)
	(via
		(at 181.3306 -88.9762)
		(size 0.508)
		(drill 0.254)
		(layers "F.Cu" "B.Cu")
		(net "GND")
	)
	(via
		(at 303.529746 -77.202538)
		(size 0.508)
		(drill 0.254)
		(layers "F.Cu" "B.Cu")
		(net "GND")
	)
	(via
		(at 305.199796 -134.861046)
		(size 0.508)
		(drill 0.254)
		(layers "F.Cu" "B.Cu")
		(net "GND")
	)
	(via
		(at 172.2374 -82.4992)
		(size 0.508)
		(drill 0.254)
		(layers "F.Cu" "B.Cu")
		(net "GND")
	)
	(via
		(at 214.6554 -68.1228)
		(size 0.508)
		(drill 0.254)
		(layers "F.Cu" "B.Cu")
		(net "GND")
	)
	(via
		(at 125.651768 -61.847984)
		(size 0.508)
		(drill 0.254)
		(layers "F.Cu" "B.Cu")
		(net "GND")
	)
	(via
		(at 68.036186 -88.775286)
		(size 0.508)
		(drill 0.254)
		(layers "F.Cu" "B.Cu")
		(net "GND")
	)
	(via
		(at 2.113534 9.084056)
		(size 0.5588)
		(drill 0.3048)
		(layers "F.Cu" "B.Cu")
		(net "GND")
	)
	(via
		(at 394.9192 -24.9428)
		(size 0.508)
		(drill 0.254)
		(layers "F.Cu" "B.Cu")
		(net "GND")
	)
	(via
		(at 355.090476 -26.2509)
		(size 0.508)
		(drill 0.254)
		(layers "F.Cu" "B.Cu")
		(net "GND")
	)
	(via
		(at 193.973958 -139.136882)
		(size 0.508)
		(drill 0.254)
		(layers "F.Cu" "B.Cu")
		(net "GND")
	)
	(via
		(at 496.600734 -166.714424)
		(size 0.5588)
		(drill 0.3048)
		(layers "F.Cu" "B.Cu")
		(net "GND")
	)
	(via
		(at 21.6662 -85.2805)
		(size 0.508)
		(drill 0.254)
		(layers "F.Cu" "B.Cu")
		(net "GND")
	)
	(via
		(at 112.489742 -64.819784)
		(size 0.508)
		(drill 0.254)
		(layers "F.Cu" "B.Cu")
		(net "GND")
	)
	(via
		(at 35.499802 -81.1276)
		(size 0.508)
		(drill 0.254)
		(layers "F.Cu" "B.Cu")
		(net "GND")
	)
	(via
		(at 225.201734 -134.861046)
		(size 0.508)
		(drill 0.254)
		(layers "F.Cu" "B.Cu")
		(net "GND")
	)
	(via
		(at 451.730364 -50.488088)
		(size 0.508)
		(drill 0.254)
		(layers "F.Cu" "B.Cu")
		(net "GND")
	)
	(via
		(at 172.2882 -24.16302)
		(size 0.508)
		(drill 0.254)
		(layers "F.Cu" "B.Cu")
		(net "GND")
	)
	(via
		(at 130.802888 -72.744584)
		(size 0.508)
		(drill 0.254)
		(layers "F.Cu" "B.Cu")
		(net "GND")
	)
	(via
		(at 300.095666 -68.287138)
		(size 0.508)
		(drill 0.254)
		(layers "F.Cu" "B.Cu")
		(net "GND")
	)
	(via
		(at 233.895138 -67.47764)
		(size 0.508)
		(drill 0.254)
		(layers "F.Cu" "B.Cu")
		(net "GND")
	)
	(via
		(at 303.038002 -141.202156)
		(size 0.508)
		(drill 0.254)
		(layers "F.Cu" "B.Cu")
		(net "GND")
	)
	(via
		(at 143.507968 -3.737356)
		(size 0.508)
		(drill 0.254)
		(layers "F.Cu" "B.Cu")
		(net "GND")
	)
	(via
		(at 284.33776 -141.202156)
		(size 0.508)
		(drill 0.254)
		(layers "F.Cu" "B.Cu")
		(net "GND")
	)
	(via
		(at 290.6522 -63.829184)
		(size 0.508)
		(drill 0.254)
		(layers "F.Cu" "B.Cu")
		(net "GND")
	)
	(via
		(at 339.5726 -22.833584)
		(size 0.508)
		(drill 0.254)
		(layers "F.Cu" "B.Cu")
		(net "GND")
	)
	(via
		(at 122.349514 0.444754)
		(size 0.508)
		(drill 0.254)
		(layers "F.Cu" "B.Cu")
		(net "GND")
	)
	(via
		(at 32.15132 -17.208246)
		(size 0.508)
		(drill 0.254)
		(layers "F.Cu" "B.Cu")
		(net "GND")
	)
	(via
		(at 201.031856 -148.7678)
		(size 0.508)
		(drill 0.254)
		(layers "F.Cu" "B.Cu")
		(net "GND")
	)
	(via
		(at 370.159534 -167.857424)
		(size 0.5588)
		(drill 0.3048)
		(layers "F.Cu" "B.Cu")
		(net "GND")
	)
	(via
		(at 489.4834 -110.7948)
		(size 0.508)
		(drill 0.254)
		(layers "F.Cu" "B.Cu")
		(net "GND")
	)
	(via
		(at 114.491262 -93.052138)
		(size 0.508)
		(drill 0.254)
		(layers "F.Cu" "B.Cu")
		(net "GND")
	)
	(via
		(at 47.549308 -140.617956)
		(size 0.508)
		(drill 0.254)
		(layers "F.Cu" "B.Cu")
		(net "GND")
	)
	(via
		(at 73.131934 14.926056)
		(size 0.5588)
		(drill 0.3048)
		(layers "F.Cu" "B.Cu")
		(net "GND")
	)
	(via
		(at 200.546716 -55.809642)
		(size 0.508)
		(drill 0.254)
		(layers "F.Cu" "B.Cu")
		(net "GND")
	)
	(via
		(at 72.328786 -76.39304)
		(size 0.508)
		(drill 0.254)
		(layers "F.Cu" "B.Cu")
		(net "GND")
	)
	(via
		(at 70.591934 9.084056)
		(size 0.5588)
		(drill 0.3048)
		(layers "F.Cu" "B.Cu")
		(net "GND")
	)
	(via
		(at 387.477 -147.366736)
		(size 0.508)
		(drill 0.254)
		(layers "F.Cu" "B.Cu")
		(net "GND")
	)
	(via
		(at 2.113534 14.926056)
		(size 0.5588)
		(drill 0.3048)
		(layers "F.Cu" "B.Cu")
		(net "GND")
	)
	(via
		(at 40.948864 -52.560982)
		(size 0.5588)
		(drill 0.3048)
		(layers "F.Cu" "B.Cu")
		(net "GND")
	)
	(via
		(at 485.6734 -36.2204)
		(size 0.508)
		(drill 0.254)
		(layers "F.Cu" "B.Cu")
		(net "GND")
	)
	(via
		(at 366.501934 14.926056)
		(size 0.5588)
		(drill 0.3048)
		(layers "F.Cu" "B.Cu")
		(net "GND")
	)
	(via
		(at 291.422074 1.9558)
		(size 0.508)
		(drill 0.254)
		(layers "F.Cu" "B.Cu")
		(net "GND")
	)
	(via
		(at 54.081934 9.084056)
		(size 0.5588)
		(drill 0.3048)
		(layers "F.Cu" "B.Cu")
		(net "GND")
	)
	(via
		(at 44.092114 -145.998946)
		(size 0.508)
		(drill 0.254)
		(layers "F.Cu" "B.Cu")
		(net "GND")
	)
	(via
		(at 300.061884 -21.517356)
		(size 0.508)
		(drill 0.254)
		(layers "F.Cu" "B.Cu")
		(net "GND")
	)
	(via
		(at 423.651934 14.926056)
		(size 0.5588)
		(drill 0.3048)
		(layers "F.Cu" "B.Cu")
		(net "GND")
	)
	(via
		(at 65.399412 -146.011646)
		(size 0.508)
		(drill 0.254)
		(layers "F.Cu" "B.Cu")
		(net "GND")
	)
	(via
		(at 251.923804 -98.681286)
		(size 0.508)
		(drill 0.254)
		(layers "F.Cu" "B.Cu")
		(net "GND")
	)
	(via
		(at 78.338172 -93.72854)
		(size 0.508)
		(drill 0.254)
		(layers "F.Cu" "B.Cu")
		(net "GND")
	)
	(via
		(at 381.79375 -115.261644)
		(size 0.508)
		(drill 0.254)
		(layers "F.Cu" "B.Cu")
		(net "GND")
	)
	(via
		(at 354.561902 1.999996)
		(size 0.5588)
		(drill 0.3048)
		(layers "F.Cu" "B.Cu")
		(net "GND")
	)
	(via
		(at 484.345234 -26.936446)
		(size 0.508)
		(drill 0.254)
		(layers "F.Cu" "B.Cu")
		(net "GND")
	)
	(via
		(at 394.17625 -103.615236)
		(size 0.508)
		(drill 0.254)
		(layers "F.Cu" "B.Cu")
		(net "GND")
	)
	(via
		(at 196.684138 -86.355682)
		(size 0.508)
		(drill 0.254)
		(layers "F.Cu" "B.Cu")
		(net "GND")
	)
	(via
		(at 215.860884 -140.592556)
		(size 0.508)
		(drill 0.254)
		(layers "F.Cu" "B.Cu")
		(net "GND")
	)
	(via
		(at 370.6368 -116.7892)
		(size 0.508)
		(drill 0.254)
		(layers "F.Cu" "B.Cu")
		(net "GND")
	)
	(via
		(at 127.368808 -99.490784)
		(size 0.508)
		(drill 0.254)
		(layers "F.Cu" "B.Cu")
		(net "GND")
	)
	(via
		(at 338.561934 9.084056)
		(size 0.5588)
		(drill 0.3048)
		(layers "F.Cu" "B.Cu")
		(net "GND")
	)
	(via
		(at 20.837398 -91.069668)
		(size 0.508)
		(drill 0.254)
		(layers "F.Cu" "B.Cu")
		(net "GND")
	)
	(via
		(at 372.237 -100.4316)
		(size 0.508)
		(drill 0.254)
		(layers "F.Cu" "B.Cu")
		(net "GND")
	)
	(via
		(at 305.246786 -65.315338)
		(size 0.508)
		(drill 0.254)
		(layers "F.Cu" "B.Cu")
		(net "GND")
	)
	(via
		(at 76.618592 -49.489614)
		(size 0.508)
		(drill 0.254)
		(layers "F.Cu" "B.Cu")
		(net "GND")
	)
	(via
		(at 75.762866 -52.618386)
		(size 0.508)
		(drill 0.254)
		(layers "F.Cu" "B.Cu")
		(net "GND")
	)
	(via
		(at 406.430734 -163.361624)
		(size 0.5588)
		(drill 0.3048)
		(layers "F.Cu" "B.Cu")
		(net "GND")
	)
	(via
		(at 237.329218 -74.411586)
		(size 0.508)
		(drill 0.254)
		(layers "F.Cu" "B.Cu")
		(net "GND")
	)
	(via
		(at 47.731934 9.084056)
		(size 0.5588)
		(drill 0.3048)
		(layers "F.Cu" "B.Cu")
		(net "GND")
	)
	(via
		(at 482.071934 10.354056)
		(size 0.5588)
		(drill 0.3048)
		(layers "F.Cu" "B.Cu")
		(net "GND")
	)
	(via
		(at 260.731 -136.779)
		(size 0.508)
		(drill 0.254)
		(layers "F.Cu" "B.Cu")
		(net "GND")
	)
	(via
		(at 395.984984 -92.917518)
		(size 0.508)
		(drill 0.254)
		(layers "F.Cu" "B.Cu")
		(net "GND")
	)
	(via
		(at 122.791728 -65.810384)
		(size 0.508)
		(drill 0.254)
		(layers "F.Cu" "B.Cu")
		(net "GND")
	)
	(via
		(at 307.749956 -2.314956)
		(size 0.508)
		(drill 0.254)
		(layers "F.Cu" "B.Cu")
		(net "GND")
	)
	(via
		(at 351.473262 -67.449192)
		(size 0.508)
		(drill 0.254)
		(layers "F.Cu" "B.Cu")
		(net "GND")
	)
	(via
		(at 459.883002 -15.791688)
		(size 0.5588)
		(drill 0.3048)
		(layers "F.Cu" "B.Cu")
		(net "GND")
	)
	(via
		(at 72.328786 -82.33664)
		(size 0.508)
		(drill 0.254)
		(layers "F.Cu" "B.Cu")
		(net "GND")
	)
	(via
		(at 292.407594 -7.1374)
		(size 0.508)
		(drill 0.254)
		(layers "F.Cu" "B.Cu")
		(net "GND")
	)
	(via
		(at 35.880802 -87.811864)
		(size 0.508)
		(drill 0.254)
		(layers "F.Cu" "B.Cu")
		(net "GND")
	)
	(via
		(at 372.618 -118.237)
		(size 0.508)
		(drill 0.254)
		(layers "F.Cu" "B.Cu")
		(net "GND")
	)
	(via
		(at 179.451 -141.1605)
		(size 0.508)
		(drill 0.254)
		(layers "F.Cu" "B.Cu")
		(net "GND")
	)
	(via
		(at 424.921934 11.624056)
		(size 0.5588)
		(drill 0.3048)
		(layers "F.Cu" "B.Cu")
		(net "GND")
	)
	(via
		(at 3.459734 -163.361624)
		(size 0.5588)
		(drill 0.3048)
		(layers "F.Cu" "B.Cu")
		(net "GND")
	)
	(via
		(at 276.784308 -70.841616)
		(size 0.5588)
		(drill 0.3048)
		(layers "F.Cu" "B.Cu")
		(net "GND")
	)
	(via
		(at 239.046258 -76.39304)
		(size 0.508)
		(drill 0.254)
		(layers "F.Cu" "B.Cu")
		(net "GND")
	)
	(via
		(at 1.23952 -23.53818)
		(size 0.508)
		(drill 0.254)
		(layers "F.Cu" "B.Cu")
		(net "GND")
	)
	(via
		(at 247.121934 14.926056)
		(size 0.5588)
		(drill 0.3048)
		(layers "F.Cu" "B.Cu")
		(net "GND")
	)
	(via
		(at 130.802888 -59.866784)
		(size 0.508)
		(drill 0.254)
		(layers "F.Cu" "B.Cu")
		(net "GND")
	)
	(via
		(at 72.328786 -54.59984)
		(size 0.508)
		(drill 0.254)
		(layers "F.Cu" "B.Cu")
		(net "GND")
	)
	(via
		(at 214.249762 -131.016756)
		(size 0.508)
		(drill 0.254)
		(layers "F.Cu" "B.Cu")
		(net "GND")
	)
	(via
		(at 233.036618 -62.029086)
		(size 0.508)
		(drill 0.254)
		(layers "F.Cu" "B.Cu")
		(net "GND")
	)
	(via
		(at 374.06072 -96.68002)
		(size 0.508)
		(drill 0.254)
		(layers "F.Cu" "B.Cu")
		(net "GND")
	)
	(via
		(at 75.59929 -22.965156)
		(size 0.508)
		(drill 0.254)
		(layers "F.Cu" "B.Cu")
		(net "GND")
	)
	(via
		(at 183.50484 -17.6657)
		(size 0.508)
		(drill 0.254)
		(layers "F.Cu" "B.Cu")
		(net "GND")
	)
	(via
		(at 162.3949 -86.35492)
		(size 0.508)
		(drill 0.254)
		(layers "F.Cu" "B.Cu")
		(net "GND")
	)
	(via
		(at 244.197124 -66.48704)
		(size 0.508)
		(drill 0.254)
		(layers "F.Cu" "B.Cu")
		(net "GND")
	)
	(via
		(at 423.726102 -43.842432)
		(size 0.4572)
		(drill 0.2032)
		(layers "F.Cu" "B.Cu")
		(net "GND")
	)
	(via
		(at 74.904346 -89.765886)
		(size 0.508)
		(drill 0.254)
		(layers "F.Cu" "B.Cu")
		(net "GND")
	)
	(via
		(at 226.822 -22.965156)
		(size 0.508)
		(drill 0.254)
		(layers "F.Cu" "B.Cu")
		(net "GND")
	)
	(via
		(at 471.911934 14.926056)
		(size 0.5588)
		(drill 0.3048)
		(layers "F.Cu" "B.Cu")
		(net "GND")
	)
	(via
		(at 314.54979 -17.208246)
		(size 0.508)
		(drill 0.254)
		(layers "F.Cu" "B.Cu")
		(net "GND")
	)
	(via
		(at 122.217688 -70.763384)
		(size 0.508)
		(drill 0.254)
		(layers "F.Cu" "B.Cu")
		(net "GND")
	)
	(via
		(at 69.753226 -65.991486)
		(size 0.508)
		(drill 0.254)
		(layers "F.Cu" "B.Cu")
		(net "GND")
	)
	(via
		(at 367.728246 -123.29033)
		(size 0.508)
		(drill 0.254)
		(layers "F.Cu" "B.Cu")
		(net "GND")
	)
	(via
		(at 348.4626 -7.8994)
		(size 0.508)
		(drill 0.254)
		(layers "F.Cu" "B.Cu")
		(net "GND")
	)
	(via
		(at 269.416276 -89.27084)
		(size 0.508)
		(drill 0.254)
		(layers "F.Cu" "B.Cu")
		(net "GND")
	)
	(via
		(at 353.391724 -162.268662)
		(size 0.5588)
		(drill 0.3048)
		(layers "F.Cu" "B.Cu")
		(net "GND")
	)
	(via
		(at 371.945154 -73.495154)
		(size 0.4572)
		(drill 0.2032)
		(layers "F.Cu" "B.Cu")
		(net "GND")
	)
	(via
		(at 301.749206 -16.7513)
		(size 0.508)
		(drill 0.254)
		(layers "F.Cu" "B.Cu")
		(net "GND")
	)
	(via
		(at 70.499478 -125.969776)
		(size 0.508)
		(drill 0.254)
		(layers "F.Cu" "B.Cu")
		(net "GND")
	)
	(via
		(at 243.338604 -60.047886)
		(size 0.508)
		(drill 0.254)
		(layers "F.Cu" "B.Cu")
		(net "GND")
	)
	(via
		(at 190.098934 -167.832024)
		(size 0.5588)
		(drill 0.3048)
		(layers "F.Cu" "B.Cu")
		(net "GND")
	)
	(via
		(at 289.049968 -145.998946)
		(size 0.508)
		(drill 0.254)
		(layers "F.Cu" "B.Cu")
		(net "GND")
	)
	(via
		(at 396.65275 -97.605596)
		(size 0.508)
		(drill 0.254)
		(layers "F.Cu" "B.Cu")
		(net "GND")
	)
	(via
		(at 270.571468 -51.941984)
		(size 0.508)
		(drill 0.254)
		(layers "F.Cu" "B.Cu")
		(net "GND")
	)
	(via
		(at 80.570324 -162.243262)
		(size 0.5588)
		(drill 0.3048)
		(layers "F.Cu" "B.Cu")
		(net "GND")
	)
	(via
		(at 74.904346 -58.06694)
		(size 0.508)
		(drill 0.254)
		(layers "F.Cu" "B.Cu")
		(net "GND")
	)
	(via
		(at 115.636802 -86.537038)
		(size 0.508)
		(drill 0.254)
		(layers "F.Cu" "B.Cu")
		(net "GND")
	)
	(via
		(at 481.287836 -35.378644)
		(size 0.508)
		(drill 0.254)
		(layers "F.Cu" "B.Cu")
		(net "GND")
	)
	(via
		(at 38.354 -86.6902)
		(size 0.5588)
		(drill 0.3048)
		(layers "F.Cu" "B.Cu")
		(net "GND")
	)
	(via
		(at 56.049418 0.444754)
		(size 0.508)
		(drill 0.254)
		(layers "F.Cu" "B.Cu")
		(net "GND")
	)
	(via
		(at 35.499802 -57.8104)
		(size 0.508)
		(drill 0.254)
		(layers "F.Cu" "B.Cu")
		(net "GND")
	)
	(via
		(at 69.551296 -17.208246)
		(size 0.508)
		(drill 0.254)
		(layers "F.Cu" "B.Cu")
		(net "GND")
	)
	(via
		(at 438.891934 10.354056)
		(size 0.5588)
		(drill 0.3048)
		(layers "F.Cu" "B.Cu")
		(net "GND")
	)
	(via
		(at 381.79375 -102.756716)
		(size 0.508)
		(drill 0.254)
		(layers "F.Cu" "B.Cu")
		(net "GND")
	)
	(via
		(at 407.696924 -162.243262)
		(size 0.5588)
		(drill 0.3048)
		(layers "F.Cu" "B.Cu")
		(net "GND")
	)
	(via
		(at 279.699974 -139.170156)
		(size 0.508)
		(drill 0.254)
		(layers "F.Cu" "B.Cu")
		(net "GND")
	)
	(via
		(at 413.511492 -43.904916)
		(size 0.4572)
		(drill 0.2032)
		(layers "F.Cu" "B.Cu")
		(net "GND")
	)
	(via
		(at 187.431934 14.926056)
		(size 0.5588)
		(drill 0.3048)
		(layers "F.Cu" "B.Cu")
		(net "GND")
	)
	(via
		(at 285.649924 -18.757646)
		(size 0.508)
		(drill 0.254)
		(layers "F.Cu" "B.Cu")
		(net "GND")
	)
	(via
		(at 31.908496 -64.930782)
		(size 0.508)
		(drill 0.254)
		(layers "F.Cu" "B.Cu")
		(net "GND")
	)
	(via
		(at 33.099502 -146.011646)
		(size 0.508)
		(drill 0.254)
		(layers "F.Cu" "B.Cu")
		(net "GND")
	)
	(via
		(at 257.93319 -91.25204)
		(size 0.508)
		(drill 0.254)
		(layers "F.Cu" "B.Cu")
		(net "GND")
	)
	(via
		(at 369.041934 9.084056)
		(size 0.5588)
		(drill 0.3048)
		(layers "F.Cu" "B.Cu")
		(net "GND")
	)
	(via
		(at 226.822 -134.8994)
		(size 0.508)
		(drill 0.254)
		(layers "F.Cu" "B.Cu")
		(net "GND")
	)
	(via
		(at 244.197124 -74.411586)
		(size 0.508)
		(drill 0.254)
		(layers "F.Cu" "B.Cu")
		(net "GND")
	)
	(via
		(at 69.321934 14.926056)
		(size 0.5588)
		(drill 0.3048)
		(layers "F.Cu" "B.Cu")
		(net "GND")
	)
	(via
		(at 130.84937 -140.617956)
		(size 0.508)
		(drill 0.254)
		(layers "F.Cu" "B.Cu")
		(net "GND")
	)
	(via
		(at 442.140086 -53.2384)
		(size 0.508)
		(drill 0.254)
		(layers "F.Cu" "B.Cu")
		(net "GND")
	)
	(via
		(at 459.916022 -15.111222)
		(size 0.5588)
		(drill 0.3048)
		(layers "F.Cu" "B.Cu")
		(net "GND")
	)
	(via
		(at 152.949402 -16.687546)
		(size 0.508)
		(drill 0.254)
		(layers "F.Cu" "B.Cu")
		(net "GND")
	)
	(via
		(at 204.049884 0.444754)
		(size 0.508)
		(drill 0.254)
		(layers "F.Cu" "B.Cu")
		(net "GND")
	)
	(via
		(at 197.606666 -110.875064)
		(size 0.508)
		(drill 0.254)
		(layers "F.Cu" "B.Cu")
		(net "GND")
	)
	(via
		(at 227.792534 -18.744946)
		(size 0.508)
		(drill 0.254)
		(layers "F.Cu" "B.Cu")
		(net "GND")
	)
	(via
		(at 473.181934 12.894056)
		(size 0.5588)
		(drill 0.3048)
		(layers "F.Cu" "B.Cu")
		(net "GND")
	)
	(via
		(at 293.6748 -11.938)
		(size 0.508)
		(drill 0.254)
		(layers "F.Cu" "B.Cu")
		(net "GND")
	)
	(via
		(at 201.044556 -145.9357)
		(size 0.508)
		(drill 0.254)
		(layers "F.Cu" "B.Cu")
		(net "GND")
	)
	(via
		(at 199.742552 -139.166092)
		(size 0.508)
		(drill 0.254)
		(layers "F.Cu" "B.Cu")
		(net "GND")
	)
	(via
		(at 235.612178 -88.28024)
		(size 0.508)
		(drill 0.254)
		(layers "F.Cu" "B.Cu")
		(net "GND")
	)
	(via
		(at 367.945162 -69.495162)
		(size 0.4572)
		(drill 0.2032)
		(layers "F.Cu" "B.Cu")
		(net "GND")
	)
	(via
		(at 451.591934 9.084056)
		(size 0.5588)
		(drill 0.3048)
		(layers "F.Cu" "B.Cu")
		(net "GND")
	)
	(via
		(at 120.216168 -55.409338)
		(size 0.508)
		(drill 0.254)
		(layers "F.Cu" "B.Cu")
		(net "GND")
	)
	(via
		(at 377.781566 -151.392128)
		(size 0.508)
		(drill 0.254)
		(layers "F.Cu" "B.Cu")
		(net "GND")
	)
	(via
		(at 130.802888 -60.857384)
		(size 0.508)
		(drill 0.254)
		(layers "F.Cu" "B.Cu")
		(net "GND")
	)
	(via
		(at 73.868534 -167.832024)
		(size 0.5588)
		(drill 0.3048)
		(layers "F.Cu" "B.Cu")
		(net "GND")
	)
	(via
		(at 292.392608 -18.744946)
		(size 0.508)
		(drill 0.254)
		(layers "F.Cu" "B.Cu")
		(net "GND")
	)
	(via
		(at 209.092546 -139.166092)
		(size 0.508)
		(drill 0.254)
		(layers "F.Cu" "B.Cu")
		(net "GND")
	)
	(via
		(at 89.498678 -98.18624)
		(size 0.508)
		(drill 0.254)
		(layers "F.Cu" "B.Cu")
		(net "GND")
	)
	(via
		(at 340.3854 -116.205)
		(size 0.508)
		(drill 0.254)
		(layers "F.Cu" "B.Cu")
		(net "GND")
	)
	(via
		(at 46.699424 -129.568956)
		(size 0.508)
		(drill 0.254)
		(layers "F.Cu" "B.Cu")
		(net "GND")
	)
	(via
		(at 74.045826 -86.29904)
		(size 0.508)
		(drill 0.254)
		(layers "F.Cu" "B.Cu")
		(net "GND")
	)
	(via
		(at 280.451814 1.994154)
		(size 0.508)
		(drill 0.254)
		(layers "F.Cu" "B.Cu")
		(net "GND")
	)
	(via
		(at 223.623124 -162.243262)
		(size 0.5588)
		(drill 0.3048)
		(layers "F.Cu" "B.Cu")
		(net "GND")
	)
	(via
		(at 12.6492 -133.1722)
		(size 0.508)
		(drill 0.254)
		(layers "F.Cu" "B.Cu")
		(net "GND")
	)
	(via
		(at 44.086018 -141.1478)
		(size 0.508)
		(drill 0.254)
		(layers "F.Cu" "B.Cu")
		(net "GND")
	)
	(via
		(at 348.721934 14.926056)
		(size 0.5588)
		(drill 0.3048)
		(layers "F.Cu" "B.Cu")
		(net "GND")
	)
	(via
		(at 424.921934 10.354056)
		(size 0.5588)
		(drill 0.3048)
		(layers "F.Cu" "B.Cu")
		(net "GND")
	)
	(via
		(at 116.782342 -66.305938)
		(size 0.508)
		(drill 0.254)
		(layers "F.Cu" "B.Cu")
		(net "GND")
	)
	(via
		(at 139.387834 -86.612984)
		(size 0.508)
		(drill 0.254)
		(layers "F.Cu" "B.Cu")
		(net "GND")
	)
	(via
		(at 137.670794 -93.547184)
		(size 0.508)
		(drill 0.254)
		(layers "F.Cu" "B.Cu")
		(net "GND")
	)
	(via
		(at 157.528768 1.478788)
		(size 0.508)
		(drill 0.254)
		(layers "F.Cu" "B.Cu")
		(net "GND")
	)
	(via
		(at 263.94283 -53.113686)
		(size 0.508)
		(drill 0.254)
		(layers "F.Cu" "B.Cu")
		(net "GND")
	)
	(via
		(at 251.065284 -53.608732)
		(size 0.508)
		(drill 0.254)
		(layers "F.Cu" "B.Cu")
		(net "GND")
	)
	(via
		(at 238.187738 -91.747086)
		(size 0.508)
		(drill 0.254)
		(layers "F.Cu" "B.Cu")
		(net "GND")
	)
	(via
		(at 62.792102 -145.998946)
		(size 0.508)
		(drill 0.254)
		(layers "F.Cu" "B.Cu")
		(net "GND")
	)
	(via
		(at 123.934728 -100.481638)
		(size 0.508)
		(drill 0.254)
		(layers "F.Cu" "B.Cu")
		(net "GND")
	)
	(via
		(at 64.081406 -129.5654)
		(size 0.508)
		(drill 0.254)
		(layers "F.Cu" "B.Cu")
		(net "GND")
	)
	(via
		(at 127.39878 -134.4041)
		(size 0.508)
		(drill 0.254)
		(layers "F.Cu" "B.Cu")
		(net "GND")
	)
	(via
		(at 77.479906 -100.167186)
		(size 0.508)
		(drill 0.254)
		(layers "F.Cu" "B.Cu")
		(net "GND")
	)
	(via
		(at 480.801934 12.894056)
		(size 0.5588)
		(drill 0.3048)
		(layers "F.Cu" "B.Cu")
		(net "GND")
	)
	(via
		(at 444.346584 -125.468126)
		(size 0.508)
		(drill 0.254)
		(layers "F.Cu" "B.Cu")
		(net "GND")
	)
	(via
		(at 136.74217 -139.166092)
		(size 0.508)
		(drill 0.254)
		(layers "F.Cu" "B.Cu")
		(net "GND")
	)
	(via
		(at 403.890734 -167.832024)
		(size 0.5588)
		(drill 0.3048)
		(layers "F.Cu" "B.Cu")
		(net "GND")
	)
	(via
		(at 185.438796 -95.520002)
		(size 0.508)
		(drill 0.254)
		(layers "F.Cu" "B.Cu")
		(net "GND")
	)
	(via
		(at 207.4926 -54.9402)
		(size 0.5588)
		(drill 0.3048)
		(layers "F.Cu" "B.Cu")
		(net "GND")
	)
	(via
		(at 169.47896 -62.6364)
		(size 0.508)
		(drill 0.254)
		(layers "F.Cu" "B.Cu")
		(net "GND")
	)
	(via
		(at 350.6978 -32.6263)
		(size 0.508)
		(drill 0.254)
		(layers "F.Cu" "B.Cu")
		(net "GND")
	)
	(via
		(at 207.564482 -62.190122)
		(size 0.5588)
		(drill 0.3048)
		(layers "F.Cu" "B.Cu")
		(net "GND")
	)
	(via
		(at 456.671934 13.910056)
		(size 0.5588)
		(drill 0.3048)
		(layers "F.Cu" "B.Cu")
		(net "GND")
	)
	(via
		(at 41.45915 -60.183522)
		(size 0.5588)
		(drill 0.3048)
		(layers "F.Cu" "B.Cu")
		(net "GND")
	)
	(via
		(at 255.35763 -65.991486)
		(size 0.508)
		(drill 0.254)
		(layers "F.Cu" "B.Cu")
		(net "GND")
	)
	(via
		(at 352.531934 9.084056)
		(size 0.5588)
		(drill 0.3048)
		(layers "F.Cu" "B.Cu")
		(net "GND")
	)
	(via
		(at 112.984534 -167.832024)
		(size 0.5588)
		(drill 0.3048)
		(layers "F.Cu" "B.Cu")
		(net "GND")
	)
	(via
		(at 217.472006 -3.762756)
		(size 0.508)
		(drill 0.254)
		(layers "F.Cu" "B.Cu")
		(net "GND")
	)
	(via
		(at 457.48575 -124.92482)
		(size 0.508)
		(drill 0.254)
		(layers "F.Cu" "B.Cu")
		(net "GND")
	)
	(via
		(at 297.346624 -124.750576)
		(size 0.508)
		(drill 0.254)
		(layers "F.Cu" "B.Cu")
		(net "GND")
	)
	(via
		(at 219.73794 -4.346956)
		(size 0.508)
		(drill 0.254)
		(layers "F.Cu" "B.Cu")
		(net "GND")
	)
	(via
		(at 184.7342 -76.93914)
		(size 0.508)
		(drill 0.254)
		(layers "F.Cu" "B.Cu")
		(net "GND")
	)
	(via
		(at 38.4302 -48.3108)
		(size 0.508)
		(drill 0.254)
		(layers "F.Cu" "B.Cu")
		(net "GND")
	)
	(via
		(at 230.399844 -136.410446)
		(size 0.508)
		(drill 0.254)
		(layers "F.Cu" "B.Cu")
		(net "GND")
	)
	(via
		(at 395.000734 -163.361624)
		(size 0.5588)
		(drill 0.3048)
		(layers "F.Cu" "B.Cu")
		(net "GND")
	)
	(via
		(at 37.465 -52.197)
		(size 0.5588)
		(drill 0.3048)
		(layers "F.Cu" "B.Cu")
		(net "GND")
	)
	(via
		(at 129.085848 -55.904384)
		(size 0.508)
		(drill 0.254)
		(layers "F.Cu" "B.Cu")
		(net "GND")
	)
	(via
		(at 105.208578 -70.84314)
		(size 0.5588)
		(drill 0.3048)
		(layers "F.Cu" "B.Cu")
		(net "GND")
	)
	(via
		(at 344.323924 -162.243262)
		(size 0.5588)
		(drill 0.3048)
		(layers "F.Cu" "B.Cu")
		(net "GND")
	)
	(via
		(at 46.461934 14.926056)
		(size 0.5588)
		(drill 0.3048)
		(layers "F.Cu" "B.Cu")
		(net "GND")
	)
	(via
		(at 88.640412 -95.709486)
		(size 0.508)
		(drill 0.254)
		(layers "F.Cu" "B.Cu")
		(net "GND")
	)
	(via
		(at 316.383924 -162.243262)
		(size 0.5588)
		(drill 0.3048)
		(layers "F.Cu" "B.Cu")
		(net "GND")
	)
	(via
		(at 448.340734 -163.361624)
		(size 0.5588)
		(drill 0.3048)
		(layers "F.Cu" "B.Cu")
		(net "GND")
	)
	(via
		(at 234.799124 -162.243262)
		(size 0.5588)
		(drill 0.3048)
		(layers "F.Cu" "B.Cu")
		(net "GND")
	)
	(via
		(at 118.499382 -52.437284)
		(size 0.508)
		(drill 0.254)
		(layers "F.Cu" "B.Cu")
		(net "GND")
	)
	(via
		(at 278.348694 -65.315338)
		(size 0.508)
		(drill 0.254)
		(layers "F.Cu" "B.Cu")
		(net "GND")
	)
	(via
		(at 307.898546 -61.847984)
		(size 0.508)
		(drill 0.254)
		(layers "F.Cu" "B.Cu")
		(net "GND")
	)
	(via
		(at 201.216514 -68.351654)
		(size 0.5588)
		(drill 0.3048)
		(layers "F.Cu" "B.Cu")
		(net "GND")
	)
	(via
		(at 82.630772 -90.26144)
		(size 0.508)
		(drill 0.254)
		(layers "F.Cu" "B.Cu")
		(net "GND")
	)
	(via
		(at 240.6015 -27.3558)
		(size 0.508)
		(drill 0.254)
		(layers "F.Cu" "B.Cu")
		(net "GND")
	)
	(via
		(at 482.630734 -165.596824)
		(size 0.5588)
		(drill 0.3048)
		(layers "F.Cu" "B.Cu")
		(net "GND")
	)
	(via
		(at 88.640412 -84.812886)
		(size 0.508)
		(drill 0.254)
		(layers "F.Cu" "B.Cu")
		(net "GND")
	)
	(via
		(at 448.226942 -45.560996)
		(size 0.508)
		(drill 0.254)
		(layers "F.Cu" "B.Cu")
		(net "GND")
	)
	(via
		(at 384.585972 -134.724394)
		(size 0.508)
		(drill 0.254)
		(layers "F.Cu" "B.Cu")
		(net "GND")
	)
	(via
		(at 371.357906 -149.949916)
		(size 0.508)
		(drill 0.254)
		(layers "F.Cu" "B.Cu")
		(net "GND")
	)
	(via
		(at 73.187306 -101.653086)
		(size 0.508)
		(drill 0.254)
		(layers "F.Cu" "B.Cu")
		(net "GND")
	)
	(via
		(at 424.575224 -52.928266)
		(size 0.508)
		(drill 0.254)
		(layers "F.Cu" "B.Cu")
		(net "GND")
	)
	(via
		(at 485.70642 -43.94962)
		(size 0.508)
		(drill 0.254)
		(layers "F.Cu" "B.Cu")
		(net "GND")
	)
	(via
		(at 259.82041 -79.342488)
		(size 0.508)
		(drill 0.254)
		(layers "F.Cu" "B.Cu")
		(net "GND")
	)
	(via
		(at 114.699542 -136.397746)
		(size 0.508)
		(drill 0.254)
		(layers "F.Cu" "B.Cu")
		(net "GND")
	)
	(via
		(at -4.3942 -134.8232)
		(size 0.508)
		(drill 0.254)
		(layers "F.Cu" "B.Cu")
		(net "GND")
	)
	(via
		(at 344.4113 4.192778)
		(size 0.508)
		(drill 0.254)
		(layers "F.Cu" "B.Cu")
		(net "GND")
	)
	(via
		(at 289.810952 -150.193756)
		(size 0.508)
		(drill 0.254)
		(layers "F.Cu" "B.Cu")
		(net "GND")
	)
	(via
		(at 113.92154 -139.660122)
		(size 0.508)
		(drill 0.254)
		(layers "F.Cu" "B.Cu")
		(net "GND")
	)
	(via
		(at 171.5008 -56.9214)
		(size 0.508)
		(drill 0.254)
		(layers "F.Cu" "B.Cu")
		(net "GND")
	)
	(via
		(at 448.39255 -124.52477)
		(size 0.508)
		(drill 0.254)
		(layers "F.Cu" "B.Cu")
		(net "GND")
	)
	(via
		(at 92.867734 -167.832024)
		(size 0.5588)
		(drill 0.3048)
		(layers "F.Cu" "B.Cu")
		(net "GND")
	)
	(via
		(at 18.0467 -22.7584)
		(size 0.508)
		(drill 0.254)
		(layers "F.Cu" "B.Cu")
		(net "GND")
	)
	(via
		(at 307.749956 -21.517356)
		(size 0.508)
		(drill 0.254)
		(layers "F.Cu" "B.Cu")
		(net "GND")
	)
	(via
		(at 16.225012 -36.7792)
		(size 0.508)
		(drill 0.254)
		(layers "F.Cu" "B.Cu")
		(net "GND")
	)
	(via
		(at 420.288212 -34.93262)
		(size 0.4572)
		(drill 0.2032)
		(layers "F.Cu" "B.Cu")
		(net "GND")
	)
	(via
		(at 168.385744 -93.261434)
		(size 0.508)
		(drill 0.254)
		(layers "F.Cu" "B.Cu")
		(net "GND")
	)
	(via
		(at -5.207 -14.5542)
		(size 0.508)
		(drill 0.254)
		(layers "F.Cu" "B.Cu")
		(net "GND")
	)
	(via
		(at 462.310734 -167.832024)
		(size 0.5588)
		(drill 0.3048)
		(layers "F.Cu" "B.Cu")
		(net "GND")
	)
	(via
		(at 5.97662 -24.08936)
		(size 0.508)
		(drill 0.254)
		(layers "F.Cu" "B.Cu")
		(net "GND")
	)
	(via
		(at 482.071934 13.910056)
		(size 0.5588)
		(drill 0.3048)
		(layers "F.Cu" "B.Cu")
		(net "GND")
	)
	(via
		(at 210.391248 -153.552144)
		(size 0.508)
		(drill 0.254)
		(layers "F.Cu" "B.Cu")
		(net "GND")
	)
	(via
		(at 356.747826 -142.31112)
		(size 0.508)
		(drill 0.254)
		(layers "F.Cu" "B.Cu")
		(net "GND")
	)
	(via
		(at 352.8314 -18.9484)
		(size 0.508)
		(drill 0.254)
		(layers "F.Cu" "B.Cu")
		(net "GND")
	)
	(via
		(at 67.101466 -83.32724)
		(size 0.508)
		(drill 0.254)
		(layers "F.Cu" "B.Cu")
		(net "GND")
	)
	(via
		(at 137.670794 -91.565984)
		(size 0.508)
		(drill 0.254)
		(layers "F.Cu" "B.Cu")
		(net "GND")
	)
	(via
		(at 383.9718 -21.4884)
		(size 0.508)
		(drill 0.254)
		(layers "F.Cu" "B.Cu")
		(net "GND")
	)
	(via
		(at 106.480356 -54.418738)
		(size 0.508)
		(drill 0.254)
		(layers "F.Cu" "B.Cu")
		(net "GND")
	)
	(via
		(at 239.046258 -94.223586)
		(size 0.508)
		(drill 0.254)
		(layers "F.Cu" "B.Cu")
		(net "GND")
	)
	(via
		(at 195.330826 -70.2056)
		(size 0.508)
		(drill 0.254)
		(layers "F.Cu" "B.Cu")
		(net "GND")
	)
	(via
		(at 237.136432 -13.8938)
		(size 0.508)
		(drill 0.254)
		(layers "F.Cu" "B.Cu")
		(net "GND")
	)
	(via
		(at 235.46181 -18.757646)
		(size 0.508)
		(drill 0.254)
		(layers "F.Cu" "B.Cu")
		(net "GND")
	)
	(via
		(at 64.090804 -7.095744)
		(size 0.508)
		(drill 0.254)
		(layers "F.Cu" "B.Cu")
		(net "GND")
	)
	(via
		(at 231.446324 -162.243262)
		(size 0.5588)
		(drill 0.3048)
		(layers "F.Cu" "B.Cu")
		(net "GND")
	)
	(via
		(at 300.095666 -98.995738)
		(size 0.508)
		(drill 0.254)
		(layers "F.Cu" "B.Cu")
		(net "GND")
	)
	(via
		(at 399.13306 -117.97792)
		(size 0.508)
		(drill 0.254)
		(layers "F.Cu" "B.Cu")
		(net "GND")
	)
	(via
		(at 255.87452 -18.01749)
		(size 0.508)
		(drill 0.254)
		(layers "F.Cu" "B.Cu")
		(net "GND")
	)
	(via
		(at 454.690734 -164.479224)
		(size 0.5588)
		(drill 0.3048)
		(layers "F.Cu" "B.Cu")
		(net "GND")
	)
	(via
		(at 49.5808 -96.5962)
		(size 0.508)
		(drill 0.254)
		(layers "F.Cu" "B.Cu")
		(net "GND")
	)
	(via
		(at 177.7492 -22.6314)
		(size 0.508)
		(drill 0.254)
		(layers "F.Cu" "B.Cu")
		(net "GND")
	)
	(via
		(at 218.44254 -21.513292)
		(size 0.508)
		(drill 0.254)
		(layers "F.Cu" "B.Cu")
		(net "GND")
	)
	(via
		(at 345.4908 -151.8412)
		(size 0.508)
		(drill 0.254)
		(layers "F.Cu" "B.Cu")
		(net "GND")
	)
	(via
		(at 142.749524 -139.170156)
		(size 0.508)
		(drill 0.254)
		(layers "F.Cu" "B.Cu")
		(net "GND")
	)
	(via
		(at 13.335 -10.3378)
		(size 0.508)
		(drill 0.254)
		(layers "F.Cu" "B.Cu")
		(net "GND")
	)
	(via
		(at 28.7274 -84.608924)
		(size 0.508)
		(drill 0.254)
		(layers "F.Cu" "B.Cu")
		(net "GND")
	)
	(via
		(at -3.463544 12.516866)
		(size 0.5588)
		(drill 0.3048)
		(layers "F.Cu" "B.Cu")
		(net "GND")
	)
	(via
		(at 129.944368 -63.334138)
		(size 0.508)
		(drill 0.254)
		(layers "F.Cu" "B.Cu")
		(net "GND")
	)
	(via
		(at 399.12925 -105.332276)
		(size 0.508)
		(drill 0.254)
		(layers "F.Cu" "B.Cu")
		(net "GND")
	)
	(via
		(at 237.329218 -54.59984)
		(size 0.508)
		(drill 0.254)
		(layers "F.Cu" "B.Cu")
		(net "GND")
	)
	(via
		(at 242.299744 -144.462246)
		(size 0.508)
		(drill 0.254)
		(layers "F.Cu" "B.Cu")
		(net "GND")
	)
	(via
		(at 72.328786 -69.45884)
		(size 0.508)
		(drill 0.254)
		(layers "F.Cu" "B.Cu")
		(net "GND")
	)
	(via
		(at 224.449894 -9.143746)
		(size 0.508)
		(drill 0.254)
		(layers "F.Cu" "B.Cu")
		(net "GND")
	)
	(via
		(at 285.8262 -50.7746)
		(size 0.508)
		(drill 0.254)
		(layers "F.Cu" "B.Cu")
		(net "GND")
	)
	(via
		(at 62.798706 2.4511)
		(size 0.508)
		(drill 0.254)
		(layers "F.Cu" "B.Cu")
		(net "GND")
	)
	(via
		(at 196.896228 -96.807782)
		(size 0.508)
		(drill 0.254)
		(layers "F.Cu" "B.Cu")
		(net "GND")
	)
	(via
		(at 27.101292 -54.76494)
		(size 0.508)
		(drill 0.254)
		(layers "F.Cu" "B.Cu")
		(net "GND")
	)
	(via
		(at 464.4644 -114.3254)
		(size 0.508)
		(drill 0.254)
		(layers "F.Cu" "B.Cu")
		(net "GND")
	)
	(via
		(at 471.200734 -164.479224)
		(size 0.5588)
		(drill 0.3048)
		(layers "F.Cu" "B.Cu")
		(net "GND")
	)
	(via
		(at 139.387834 -93.547184)
		(size 0.508)
		(drill 0.254)
		(layers "F.Cu" "B.Cu")
		(net "GND")
	)
	(via
		(at 133.378194 -87.108538)
		(size 0.508)
		(drill 0.254)
		(layers "F.Cu" "B.Cu")
		(net "GND")
	)
	(via
		(at 351.798382 -138.243818)
		(size 0.508)
		(drill 0.254)
		(layers "F.Cu" "B.Cu")
		(net "GND")
	)
	(via
		(at 404.4188 -9.5758)
		(size 0.508)
		(drill 0.254)
		(layers "F.Cu" "B.Cu")
		(net "GND")
	)
	(via
		(at 401.346924 -162.243262)
		(size 0.5588)
		(drill 0.3048)
		(layers "F.Cu" "B.Cu")
		(net "GND")
	)
	(via
		(at 257.93319 -64.50584)
		(size 0.508)
		(drill 0.254)
		(layers "F.Cu" "B.Cu")
		(net "GND")
	)
	(via
		(at 311.891934 14.926056)
		(size 0.5588)
		(drill 0.3048)
		(layers "F.Cu" "B.Cu")
		(net "GND")
	)
	(via
		(at 41.359582 -69.577458)
		(size 0.5588)
		(drill 0.3048)
		(layers "F.Cu" "B.Cu")
		(net "GND")
	)
	(via
		(at 93.791278 -95.709486)
		(size 0.508)
		(drill 0.254)
		(layers "F.Cu" "B.Cu")
		(net "GND")
	)
	(via
		(at 122.791728 -61.847984)
		(size 0.508)
		(drill 0.254)
		(layers "F.Cu" "B.Cu")
		(net "GND")
	)
	(via
		(at 360.684826 -3.420364)
		(size 0.508)
		(drill 0.254)
		(layers "F.Cu" "B.Cu")
		(net "GND")
	)
	(via
		(at 439.450734 -167.832024)
		(size 0.5588)
		(drill 0.3048)
		(layers "F.Cu" "B.Cu")
		(net "GND")
	)
	(via
		(at 115.451382 -17.208246)
		(size 0.508)
		(drill 0.254)
		(layers "F.Cu" "B.Cu")
		(net "GND")
	)
	(via
		(at 465.111592 -36.726368)
		(size 0.5588)
		(drill 0.3048)
		(layers "F.Cu" "B.Cu")
		(net "GND")
	)
	(via
		(at 200.881234 -87.176864)
		(size 0.508)
		(drill 0.254)
		(layers "F.Cu" "B.Cu")
		(net "GND")
	)
	(via
		(at 449.326 -146.400012)
		(size 0.508)
		(drill 0.254)
		(layers "F.Cu" "B.Cu")
		(net "GND")
	)
	(via
		(at 73.4314 -11.9126)
		(size 0.508)
		(drill 0.254)
		(layers "F.Cu" "B.Cu")
		(net "GND")
	)
	(via
		(at 62.792102 -28.730956)
		(size 0.508)
		(drill 0.254)
		(layers "F.Cu" "B.Cu")
		(net "GND")
	)
	(via
		(at 206.978758 -99.857052)
		(size 0.5588)
		(drill 0.3048)
		(layers "F.Cu" "B.Cu")
		(net "GND")
	)
	(via
		(at 151.24938 -17.208246)
		(size 0.508)
		(drill 0.254)
		(layers "F.Cu" "B.Cu")
		(net "GND")
	)
	(via
		(at 264.801096 -60.54344)
		(size 0.508)
		(drill 0.254)
		(layers "F.Cu" "B.Cu")
		(net "GND")
	)
	(via
		(at 114.206782 -62.838584)
		(size 0.508)
		(drill 0.254)
		(layers "F.Cu" "B.Cu")
		(net "GND")
	)
	(via
		(at 123.076208 -74.23023)
		(size 0.508)
		(drill 0.254)
		(layers "F.Cu" "B.Cu")
		(net "GND")
	)
	(via
		(at 54.744112 -136.3345)
		(size 0.508)
		(drill 0.254)
		(layers "F.Cu" "B.Cu")
		(net "GND")
	)
	(via
		(at 285.501334 -86.612984)
		(size 0.508)
		(drill 0.254)
		(layers "F.Cu" "B.Cu")
		(net "GND")
	)
	(via
		(at 209.09915 -7.1501)
		(size 0.508)
		(drill 0.254)
		(layers "F.Cu" "B.Cu")
		(net "GND")
	)
	(via
		(at 208.122012 -7.6454)
		(size 0.508)
		(drill 0.254)
		(layers "F.Cu" "B.Cu")
		(net "GND")
	)
	(via
		(at 73.187306 -86.794086)
		(size 0.508)
		(drill 0.254)
		(layers "F.Cu" "B.Cu")
		(net "GND")
	)
	(via
		(at 499.140734 -167.832024)
		(size 0.5588)
		(drill 0.3048)
		(layers "F.Cu" "B.Cu")
		(net "GND")
	)
	(via
		(at 387.3373 -106.6546)
		(size 0.508)
		(drill 0.254)
		(layers "F.Cu" "B.Cu")
		(net "GND")
	)
	(via
		(at 259.821934 14.926056)
		(size 0.5588)
		(drill 0.3048)
		(layers "F.Cu" "B.Cu")
		(net "GND")
	)
	(via
		(at 108.197396 -55.409338)
		(size 0.508)
		(drill 0.254)
		(layers "F.Cu" "B.Cu")
		(net "GND")
	)
	(via
		(at 86.923372 -81.841086)
		(size 0.508)
		(drill 0.254)
		(layers "F.Cu" "B.Cu")
		(net "GND")
	)
	(via
		(at 46.699424 -148.771356)
		(size 0.508)
		(drill 0.254)
		(layers "F.Cu" "B.Cu")
		(net "GND")
	)
	(via
		(at 116.399564 -136.410446)
		(size 0.508)
		(drill 0.254)
		(layers "F.Cu" "B.Cu")
		(net "GND")
	)
	(via
		(at 391.414 -66.929)
		(size 0.508)
		(drill 0.254)
		(layers "F.Cu" "B.Cu")
		(net "GND")
	)
	(via
		(at 136.812274 -65.315338)
		(size 0.508)
		(drill 0.254)
		(layers "F.Cu" "B.Cu")
		(net "GND")
	)
	(via
		(at 275.13788 -82.340196)
		(size 0.5588)
		(drill 0.3048)
		(layers "F.Cu" "B.Cu")
		(net "GND")
	)
	(via
		(at 260.50875 -95.709486)
		(size 0.508)
		(drill 0.254)
		(layers "F.Cu" "B.Cu")
		(net "GND")
	)
	(via
		(at 37.34943 0.444754)
		(size 0.508)
		(drill 0.254)
		(layers "F.Cu" "B.Cu")
		(net "GND")
	)
	(via
		(at 131.661408 -87.108538)
		(size 0.508)
		(drill 0.254)
		(layers "F.Cu" "B.Cu")
		(net "GND")
	)
	(via
		(at 136.729216 -13.8938)
		(size 0.508)
		(drill 0.254)
		(layers "F.Cu" "B.Cu")
		(net "GND")
	)
	(via
		(at 308.307232 -67.2592)
		(size 0.508)
		(drill 0.254)
		(layers "F.Cu" "B.Cu")
		(net "GND")
	)
	(via
		(at 196.321934 14.926056)
		(size 0.5588)
		(drill 0.3048)
		(layers "F.Cu" "B.Cu")
		(net "GND")
	)
	(via
		(at 45.390816 -134.349744)
		(size 0.508)
		(drill 0.254)
		(layers "F.Cu" "B.Cu")
		(net "GND")
	)
	(via
		(at 290.6522 -70.763384)
		(size 0.508)
		(drill 0.254)
		(layers "F.Cu" "B.Cu")
		(net "GND")
	)
	(via
		(at 128.227328 -64.324738)
		(size 0.508)
		(drill 0.254)
		(layers "F.Cu" "B.Cu")
		(net "GND")
	)
	(via
		(at 129.085848 -85.622384)
		(size 0.508)
		(drill 0.254)
		(layers "F.Cu" "B.Cu")
		(net "GND")
	)
	(via
		(at 251.065284 -76.39304)
		(size 0.508)
		(drill 0.254)
		(layers "F.Cu" "B.Cu")
		(net "GND")
	)
	(via
		(at 370.422678 -132.910834)
		(size 0.508)
		(drill 0.254)
		(layers "F.Cu" "B.Cu")
		(net "GND")
	)
	(via
		(at 358.22636 -144.87398)
		(size 0.508)
		(drill 0.254)
		(layers "F.Cu" "B.Cu")
		(net "GND")
	)
	(via
		(at 82.630772 -85.30844)
		(size 0.508)
		(drill 0.254)
		(layers "F.Cu" "B.Cu")
		(net "GND")
	)
	(via
		(at 2.930906 -7.982458)
		(size 0.508)
		(drill 0.254)
		(layers "F.Cu" "B.Cu")
		(net "GND")
	)
	(via
		(at 123.199398 -22.965156)
		(size 0.508)
		(drill 0.254)
		(layers "F.Cu" "B.Cu")
		(net "GND")
	)
	(via
		(at 157.528768 -17.723612)
		(size 0.508)
		(drill 0.254)
		(layers "F.Cu" "B.Cu")
		(net "GND")
	)
	(via
		(at 128.68148 -129.5654)
		(size 0.508)
		(drill 0.254)
		(layers "F.Cu" "B.Cu")
		(net "GND")
	)
	(via
		(at 119.331232 -21.5138)
		(size 0.508)
		(drill 0.254)
		(layers "F.Cu" "B.Cu")
		(net "GND")
	)
	(via
		(at 67.949318 -154.063446)
		(size 0.508)
		(drill 0.254)
		(layers "F.Cu" "B.Cu")
		(net "GND")
	)
	(via
		(at 455.923142 -16.296894)
		(size 0.5588)
		(drill 0.3048)
		(layers "F.Cu" "B.Cu")
		(net "GND")
	)
	(via
		(at 26.67 -156.091382)
		(size 0.508)
		(drill 0.254)
		(layers "F.Cu" "B.Cu")
		(net "GND")
	)
	(via
		(at 134.236714 -61.847984)
		(size 0.508)
		(drill 0.254)
		(layers "F.Cu" "B.Cu")
		(net "GND")
	)
	(via
		(at 199.742552 -145.998946)
		(size 0.508)
		(drill 0.254)
		(layers "F.Cu" "B.Cu")
		(net "GND")
	)
	(via
		(at 42.411396 -11.916156)
		(size 0.508)
		(drill 0.254)
		(layers "F.Cu" "B.Cu")
		(net "GND")
	)
	(via
		(at 250.206764 -55.094886)
		(size 0.508)
		(drill 0.254)
		(layers "F.Cu" "B.Cu")
		(net "GND")
	)
	(via
		(at 134.160514 -130.991356)
		(size 0.508)
		(drill 0.254)
		(layers "F.Cu" "B.Cu")
		(net "GND")
	)
	(via
		(at 465.442046 2.2733)
		(size 0.508)
		(drill 0.254)
		(layers "F.Cu" "B.Cu")
		(net "GND")
	)
	(via
		(at 358.017826 -141.57452)
		(size 0.508)
		(drill 0.254)
		(layers "F.Cu" "B.Cu")
		(net "GND")
	)
	(via
		(at 100.659184 -89.765886)
		(size 0.508)
		(drill 0.254)
		(layers "F.Cu" "B.Cu")
		(net "GND")
	)
	(via
		(at 348.798134 -167.832024)
		(size 0.5588)
		(drill 0.3048)
		(layers "F.Cu" "B.Cu")
		(net "GND")
	)
	(via
		(at 138.044174 -136.3345)
		(size 0.508)
		(drill 0.254)
		(layers "F.Cu" "B.Cu")
		(net "GND")
	)
	(via
		(at 469.926924 -162.243262)
		(size 0.5588)
		(drill 0.3048)
		(layers "F.Cu" "B.Cu")
		(net "GND")
	)
	(via
		(at 310.771032 -66.7004)
		(size 0.508)
		(drill 0.254)
		(layers "F.Cu" "B.Cu")
		(net "GND")
	)
	(via
		(at 229.081838 -21.5138)
		(size 0.508)
		(drill 0.254)
		(layers "F.Cu" "B.Cu")
		(net "GND")
	)
	(via
		(at 437.721756 -28.2321)
		(size 0.4572)
		(drill 0.2032)
		(layers "F.Cu" "B.Cu")
		(net "GND")
	)
	(via
		(at 130.802888 -94.538038)
		(size 0.508)
		(drill 0.254)
		(layers "F.Cu" "B.Cu")
		(net "GND")
	)
	(via
		(at 200.5076 -69.5198)
		(size 0.5588)
		(drill 0.3048)
		(layers "F.Cu" "B.Cu")
		(net "GND")
	)
	(via
		(at 163.301934 9.084056)
		(size 0.5588)
		(drill 0.3048)
		(layers "F.Cu" "B.Cu")
		(net "GND")
	)
	(via
		(at 69.753226 -60.047886)
		(size 0.508)
		(drill 0.254)
		(layers "F.Cu" "B.Cu")
		(net "GND")
	)
	(via
		(at 301.742602 -28.730956)
		(size 0.508)
		(drill 0.254)
		(layers "F.Cu" "B.Cu")
		(net "GND")
	)
	(via
		(at 317.09995 -139.181078)
		(size 0.508)
		(drill 0.254)
		(layers "F.Cu" "B.Cu")
		(net "GND")
	)
	(via
		(at 371.1194 -132.9944)
		(size 0.508)
		(drill 0.254)
		(layers "F.Cu" "B.Cu")
		(net "GND")
	)
	(via
		(at 398.63395 -102.756716)
		(size 0.508)
		(drill 0.254)
		(layers "F.Cu" "B.Cu")
		(net "GND")
	)
	(via
		(at 391.495534 -167.832024)
		(size 0.5588)
		(drill 0.3048)
		(layers "F.Cu" "B.Cu")
		(net "GND")
	)
	(via
		(at 346.395294 -155.593542)
		(size 0.508)
		(drill 0.254)
		(layers "F.Cu" "B.Cu")
		(net "GND")
	)
	(via
		(at 275.773134 -54.913784)
		(size 0.508)
		(drill 0.254)
		(layers "F.Cu" "B.Cu")
		(net "GND")
	)
	(via
		(at 119.343932 -18.6817)
		(size 0.508)
		(drill 0.254)
		(layers "F.Cu" "B.Cu")
		(net "GND")
	)
	(via
		(at 304.388266 -78.688438)
		(size 0.508)
		(drill 0.254)
		(layers "F.Cu" "B.Cu")
		(net "GND")
	)
	(via
		(at 164.394134 -167.832024)
		(size 0.5588)
		(drill 0.3048)
		(layers "F.Cu" "B.Cu")
		(net "GND")
	)
	(via
		(at 151.24938 -7.607046)
		(size 0.508)
		(drill 0.254)
		(layers "F.Cu" "B.Cu")
		(net "GND")
	)
	(via
		(at 200.8886 -90.9828)
		(size 0.508)
		(drill 0.254)
		(layers "F.Cu" "B.Cu")
		(net "GND")
	)
	(via
		(at 407.700734 -163.361624)
		(size 0.5588)
		(drill 0.3048)
		(layers "F.Cu" "B.Cu")
		(net "GND")
	)
	(via
		(at 107.066842 -70.851776)
		(size 0.5588)
		(drill 0.3048)
		(layers "F.Cu" "B.Cu")
		(net "GND")
	)
	(via
		(at 164.418518 0.33274)
		(size 0.508)
		(drill 0.254)
		(layers "F.Cu" "B.Cu")
		(net "GND")
	)
	(via
		(at 247.631204 -74.411586)
		(size 0.508)
		(drill 0.254)
		(layers "F.Cu" "B.Cu")
		(net "GND")
	)
	(via
		(at 41.501314 -17.208246)
		(size 0.508)
		(drill 0.254)
		(layers "F.Cu" "B.Cu")
		(net "GND")
	)
	(via
		(at 206.459328 -60.198)
		(size 0.5588)
		(drill 0.3048)
		(layers "F.Cu" "B.Cu")
		(net "GND")
	)
	(via
		(at 392.19505 -121.245884)
		(size 0.508)
		(drill 0.254)
		(layers "F.Cu" "B.Cu")
		(net "GND")
	)
	(via
		(at 116.208302 -98.995738)
		(size 0.508)
		(drill 0.254)
		(layers "F.Cu" "B.Cu")
		(net "GND")
	)
	(via
		(at 362.966 -113.792)
		(size 0.508)
		(drill 0.254)
		(layers "F.Cu" "B.Cu")
		(net "GND")
	)
	(via
		(at 429.286924 -162.243262)
		(size 0.5588)
		(drill 0.3048)
		(layers "F.Cu" "B.Cu")
		(net "GND")
	)
	(via
		(at 170.1546 -56.896)
		(size 0.508)
		(drill 0.254)
		(layers "F.Cu" "B.Cu")
		(net "GND")
	)
	(via
		(at 37.34943 -139.170156)
		(size 0.508)
		(drill 0.254)
		(layers "F.Cu" "B.Cu")
		(net "GND")
	)
	(via
		(at 316.249812 -3.762756)
		(size 0.508)
		(drill 0.254)
		(layers "F.Cu" "B.Cu")
		(net "GND")
	)
	(via
		(at 164.846 -86.2076)
		(size 0.508)
		(drill 0.254)
		(layers "F.Cu" "B.Cu")
		(net "GND")
	)
	(via
		(at 397.540734 -165.596824)
		(size 0.5588)
		(drill 0.3048)
		(layers "F.Cu" "B.Cu")
		(net "GND")
	)
	(via
		(at 367.9952 -108.6612)
		(size 0.508)
		(drill 0.254)
		(layers "F.Cu" "B.Cu")
		(net "GND")
	)
	(via
		(at 45.924724 -162.243262)
		(size 0.5588)
		(drill 0.3048)
		(layers "F.Cu" "B.Cu")
		(net "GND")
	)
	(via
		(at 92.074238 -65.000886)
		(size 0.508)
		(drill 0.254)
		(layers "F.Cu" "B.Cu")
		(net "GND")
	)
	(via
		(at 482.78796 -45.39488)
		(size 0.508)
		(drill 0.254)
		(layers "F.Cu" "B.Cu")
		(net "GND")
	)
	(via
		(at 499.282466 -21.074126)
		(size 0.508)
		(drill 0.254)
		(layers "F.Cu" "B.Cu")
		(net "GND")
	)
	(via
		(at 229.087934 -126.622556)
		(size 0.508)
		(drill 0.254)
		(layers "F.Cu" "B.Cu")
		(net "GND")
	)
	(via
		(at 306.899818 -125.334776)
		(size 0.508)
		(drill 0.254)
		(layers "F.Cu" "B.Cu")
		(net "GND")
	)
	(via
		(at 57.74944 -21.517356)
		(size 0.508)
		(drill 0.254)
		(layers "F.Cu" "B.Cu")
		(net "GND")
	)
	(via
		(at 100.659184 -98.681286)
		(size 0.508)
		(drill 0.254)
		(layers "F.Cu" "B.Cu")
		(net "GND")
	)
	(via
		(at 394.97 -35.306)
		(size 0.508)
		(drill 0.254)
		(layers "F.Cu" "B.Cu")
		(net "GND")
	)
	(via
		(at 120.216168 -54.418738)
		(size 0.508)
		(drill 0.254)
		(layers "F.Cu" "B.Cu")
		(net "GND")
	)
	(via
		(at -2.5908 -141.7828)
		(size 0.508)
		(drill 0.254)
		(layers "F.Cu" "B.Cu")
		(net "GND")
	)
	(via
		(at 200.8886 -94.5642)
		(size 0.5588)
		(drill 0.3048)
		(layers "F.Cu" "B.Cu")
		(net "GND")
	)
	(via
		(at 139.34948 -18.757646)
		(size 0.508)
		(drill 0.254)
		(layers "F.Cu" "B.Cu")
		(net "GND")
	)
	(via
		(at 394.9446 -154.2034)
		(size 0.508)
		(drill 0.254)
		(layers "F.Cu" "B.Cu")
		(net "GND")
	)
	(via
		(at 142.749524 -21.517356)
		(size 0.508)
		(drill 0.254)
		(layers "F.Cu" "B.Cu")
		(net "GND")
	)
	(via
		(at 345.133168 -78.67904)
		(size 0.508)
		(drill 0.254)
		(layers "F.Cu" "B.Cu")
		(net "GND")
	)
	(via
		(at 121.499376 -7.607046)
		(size 0.508)
		(drill 0.254)
		(layers "F.Cu" "B.Cu")
		(net "GND")
	)
	(via
		(at 77.299312 -3.762756)
		(size 0.508)
		(drill 0.254)
		(layers "F.Cu" "B.Cu")
		(net "GND")
	)
	(via
		(at 152.099518 -129.579878)
		(size 0.508)
		(drill 0.254)
		(layers "F.Cu" "B.Cu")
		(net "GND")
	)
	(via
		(at 493.5982 -136.0678)
		(size 0.508)
		(drill 0.254)
		(layers "F.Cu" "B.Cu")
		(net "GND")
	)
	(via
		(at 23.601934 9.084056)
		(size 0.5588)
		(drill 0.3048)
		(layers "F.Cu" "B.Cu")
		(net "GND")
	)
	(via
		(at 123.199398 -134.861046)
		(size 0.508)
		(drill 0.254)
		(layers "F.Cu" "B.Cu")
		(net "GND")
	)
	(via
		(at 296.69994 -139.170156)
		(size 0.508)
		(drill 0.254)
		(layers "F.Cu" "B.Cu")
		(net "GND")
	)
	(via
		(at 286.499808 1.994154)
		(size 0.508)
		(drill 0.254)
		(layers "F.Cu" "B.Cu")
		(net "GND")
	)
	(via
		(at 397.14805 -116.094764)
		(size 0.508)
		(drill 0.254)
		(layers "F.Cu" "B.Cu")
		(net "GND")
	)
	(via
		(at 335.3054 -109.855)
		(size 0.508)
		(drill 0.254)
		(layers "F.Cu" "B.Cu")
		(net "GND")
	)
	(via
		(at 80.913732 -81.34604)
		(size 0.508)
		(drill 0.254)
		(layers "F.Cu" "B.Cu")
		(net "GND")
	)
	(via
		(at 53.442108 -155.600146)
		(size 0.508)
		(drill 0.254)
		(layers "F.Cu" "B.Cu")
		(net "GND")
	)
	(via
		(at 245.851934 14.926056)
		(size 0.5588)
		(drill 0.3048)
		(layers "F.Cu" "B.Cu")
		(net "GND")
	)
	(via
		(at 36.040822 2.505456)
		(size 0.508)
		(drill 0.254)
		(layers "F.Cu" "B.Cu")
		(net "GND")
	)
	(via
		(at 135.361934 9.084056)
		(size 0.5588)
		(drill 0.3048)
		(layers "F.Cu" "B.Cu")
		(net "GND")
	)
	(via
		(at 70.611746 -54.59984)
		(size 0.508)
		(drill 0.254)
		(layers "F.Cu" "B.Cu")
		(net "GND")
	)
	(via
		(at 184.891934 14.926056)
		(size 0.5588)
		(drill 0.3048)
		(layers "F.Cu" "B.Cu")
		(net "GND")
	)
	(via
		(at 288.19983 -13.363956)
		(size 0.508)
		(drill 0.254)
		(layers "F.Cu" "B.Cu")
		(net "GND")
	)
	(via
		(at 140.046964 -124.648976)
		(size 0.508)
		(drill 0.254)
		(layers "F.Cu" "B.Cu")
		(net "GND")
	)
	(via
		(at 132.821934 9.084056)
		(size 0.5588)
		(drill 0.3048)
		(layers "F.Cu" "B.Cu")
		(net "GND")
	)
	(via
		(at 95.070168 -18.8214)
		(size 0.508)
		(drill 0.254)
		(layers "F.Cu" "B.Cu")
		(net "GND")
	)
	(via
		(at 129.999486 -136.410446)
		(size 0.508)
		(drill 0.254)
		(layers "F.Cu" "B.Cu")
		(net "GND")
	)
	(via
		(at 406.778206 -153.114248)
		(size 0.508)
		(drill 0.254)
		(layers "F.Cu" "B.Cu")
		(net "GND")
	)
	(via
		(at 319.511934 9.084056)
		(size 0.5588)
		(drill 0.3048)
		(layers "F.Cu" "B.Cu")
		(net "GND")
	)
	(via
		(at 296.66184 -92.061538)
		(size 0.508)
		(drill 0.254)
		(layers "F.Cu" "B.Cu")
		(net "GND")
	)
	(via
		(at 48.777398 -68.7705)
		(size 0.508)
		(drill 0.254)
		(layers "F.Cu" "B.Cu")
		(net "GND")
	)
	(via
		(at 336.2452 -27.2415)
		(size 0.508)
		(drill 0.254)
		(layers "F.Cu" "B.Cu")
		(net "GND")
	)
	(via
		(at 442.701934 12.894056)
		(size 0.5588)
		(drill 0.3048)
		(layers "F.Cu" "B.Cu")
		(net "GND")
	)
	(via
		(at 204.899768 -7.607046)
		(size 0.508)
		(drill 0.254)
		(layers "F.Cu" "B.Cu")
		(net "GND")
	)
	(via
		(at 217.472006 -134.8994)
		(size 0.508)
		(drill 0.254)
		(layers "F.Cu" "B.Cu")
		(net "GND")
	)
	(via
		(at 317.09995 -136.410446)
		(size 0.508)
		(drill 0.254)
		(layers "F.Cu" "B.Cu")
		(net "GND")
	)
	(via
		(at 77.479906 -76.39304)
		(size 0.508)
		(drill 0.254)
		(layers "F.Cu" "B.Cu")
		(net "GND")
	)
	(via
		(at 117.071648 -13.363956)
		(size 0.508)
		(drill 0.254)
		(layers "F.Cu" "B.Cu")
		(net "GND")
	)
	(via
		(at 291.51072 -57.390538)
		(size 0.508)
		(drill 0.254)
		(layers "F.Cu" "B.Cu")
		(net "GND")
	)
	(via
		(at 114.491262 -91.070938)
		(size 0.508)
		(drill 0.254)
		(layers "F.Cu" "B.Cu")
		(net "GND")
	)
	(via
		(at 476.991934 9.084056)
		(size 0.5588)
		(drill 0.3048)
		(layers "F.Cu" "B.Cu")
		(net "GND")
	)
	(via
		(at 434.370734 -163.361624)
		(size 0.5588)
		(drill 0.3048)
		(layers "F.Cu" "B.Cu")
		(net "GND")
	)
	(via
		(at 383.9591 -27.7876)
		(size 0.508)
		(drill 0.254)
		(layers "F.Cu" "B.Cu")
		(net "GND")
	)
	(via
		(at 235.49991 -125.969776)
		(size 0.508)
		(drill 0.254)
		(layers "F.Cu" "B.Cu")
		(net "GND")
	)
	(via
		(at 6.246114 -121.701306)
		(size 0.508)
		(drill 0.254)
		(layers "F.Cu" "B.Cu")
		(net "GND")
	)
	(via
		(at 293.22776 -96.023938)
		(size 0.508)
		(drill 0.254)
		(layers "F.Cu" "B.Cu")
		(net "GND")
	)
	(via
		(at 301.812706 -86.117938)
		(size 0.508)
		(drill 0.254)
		(layers "F.Cu" "B.Cu")
		(net "GND")
	)
	(via
		(at 200.131934 14.926056)
		(size 0.5588)
		(drill 0.3048)
		(layers "F.Cu" "B.Cu")
		(net "GND")
	)
	(via
		(at 126.510288 -57.390538)
		(size 0.508)
		(drill 0.254)
		(layers "F.Cu" "B.Cu")
		(net "GND")
	)
	(via
		(at 12.3952 -34.9504)
		(size 0.508)
		(drill 0.254)
		(layers "F.Cu" "B.Cu")
		(net "GND")
	)
	(via
		(at 61.149484 0.444754)
		(size 0.508)
		(drill 0.254)
		(layers "F.Cu" "B.Cu")
		(net "GND")
	)
	(via
		(at 122.349514 -148.771356)
		(size 0.508)
		(drill 0.254)
		(layers "F.Cu" "B.Cu")
		(net "GND")
	)
	(via
		(at 221.04985 -2.314956)
		(size 0.508)
		(drill 0.254)
		(layers "F.Cu" "B.Cu")
		(net "GND")
	)
	(via
		(at 129.085848 -82.650584)
		(size 0.508)
		(drill 0.254)
		(layers "F.Cu" "B.Cu")
		(net "GND")
	)
	(via
		(at 141.963394 -87.108538)
		(size 0.508)
		(drill 0.254)
		(layers "F.Cu" "B.Cu")
		(net "GND")
	)
	(via
		(at 103.678736 -149.8092)
		(size 0.508)
		(drill 0.254)
		(layers "F.Cu" "B.Cu")
		(net "GND")
	)
	(via
		(at 381.79375 -116.953284)
		(size 0.508)
		(drill 0.254)
		(layers "F.Cu" "B.Cu")
		(net "GND")
	)
	(via
		(at 204.899768 -17.208246)
		(size 0.508)
		(drill 0.254)
		(layers "F.Cu" "B.Cu")
		(net "GND")
	)
	(via
		(at 449.051934 12.894056)
		(size 0.5588)
		(drill 0.3048)
		(layers "F.Cu" "B.Cu")
		(net "GND")
	)
	(via
		(at 173.461934 14.926056)
		(size 0.5588)
		(drill 0.3048)
		(layers "F.Cu" "B.Cu")
		(net "GND")
	)
	(via
		(at 111.057182 -98.005138)
		(size 0.508)
		(drill 0.254)
		(layers "F.Cu" "B.Cu")
		(net "GND")
	)
	(via
		(at 200.533 -99.3902)
		(size 0.508)
		(drill 0.254)
		(layers "F.Cu" "B.Cu")
		(net "GND")
	)
	(via
		(at 300.772068 -17.2466)
		(size 0.508)
		(drill 0.254)
		(layers "F.Cu" "B.Cu")
		(net "GND")
	)
	(via
		(at 358.7115 -17.363186)
		(size 0.508)
		(drill 0.254)
		(layers "F.Cu" "B.Cu")
		(net "GND")
	)
	(via
		(at 247.631204 -82.33664)
		(size 0.508)
		(drill 0.254)
		(layers "F.Cu" "B.Cu")
		(net "GND")
	)
	(via
		(at 372.5672 -114.299238)
		(size 0.508)
		(drill 0.254)
		(layers "F.Cu" "B.Cu")
		(net "GND")
	)
	(via
		(at 196.399912 -129.568956)
		(size 0.508)
		(drill 0.254)
		(layers "F.Cu" "B.Cu")
		(net "GND")
	)
	(via
		(at 288.07664 -93.052138)
		(size 0.508)
		(drill 0.254)
		(layers "F.Cu" "B.Cu")
		(net "GND")
	)
	(via
		(at 312.387996 -4.346956)
		(size 0.508)
		(drill 0.254)
		(layers "F.Cu" "B.Cu")
		(net "GND")
	)
	(via
		(at 234.753658 -59.057286)
		(size 0.508)
		(drill 0.254)
		(layers "F.Cu" "B.Cu")
		(net "GND")
	)
	(via
		(at 243.338604 -91.747086)
		(size 0.508)
		(drill 0.254)
		(layers "F.Cu" "B.Cu")
		(net "GND")
	)
	(via
		(at 370.284756 -3.420364)
		(size 0.508)
		(drill 0.254)
		(layers "F.Cu" "B.Cu")
		(net "GND")
	)
	(via
		(at 196.399912 -136.397746)
		(size 0.508)
		(drill 0.254)
		(layers "F.Cu" "B.Cu")
		(net "GND")
	)
	(via
		(at 114.699542 -145.998946)
		(size 0.508)
		(drill 0.254)
		(layers "F.Cu" "B.Cu")
		(net "GND")
	)
	(via
		(at 199.979534 -95.838264)
		(size 0.508)
		(drill 0.254)
		(layers "F.Cu" "B.Cu")
		(net "GND")
	)
	(via
		(at 424.2435 -22.319742)
		(size 0.508)
		(drill 0.254)
		(layers "F.Cu" "B.Cu")
		(net "GND")
	)
	(via
		(at 242.299744 -154.063446)
		(size 0.508)
		(drill 0.254)
		(layers "F.Cu" "B.Cu")
		(net "GND")
	)
	(via
		(at 27.84856 -95.52178)
		(size 0.508)
		(drill 0.254)
		(layers "F.Cu" "B.Cu")
		(net "GND")
	)
	(via
		(at 409.681934 14.926056)
		(size 0.5588)
		(drill 0.3048)
		(layers "F.Cu" "B.Cu")
		(net "GND")
	)
	(via
		(at 121.499376 -144.462246)
		(size 0.508)
		(drill 0.254)
		(layers "F.Cu" "B.Cu")
		(net "GND")
	)
	(via
		(at 239.749838 -18.757646)
		(size 0.508)
		(drill 0.254)
		(layers "F.Cu" "B.Cu")
		(net "GND")
	)
	(via
		(at 35.5346 -76.8096)
		(size 0.5588)
		(drill 0.3048)
		(layers "F.Cu" "B.Cu")
		(net "GND")
	)
	(via
		(at 391.69975 -120.387364)
		(size 0.508)
		(drill 0.254)
		(layers "F.Cu" "B.Cu")
		(net "GND")
	)
	(via
		(at 303.038002 -131.600956)
		(size 0.508)
		(drill 0.254)
		(layers "F.Cu" "B.Cu")
		(net "GND")
	)
	(via
		(at 406.18918 -145.48612)
		(size 0.508)
		(drill 0.254)
		(layers "F.Cu" "B.Cu")
		(net "GND")
	)
	(via
		(at 165.608 -72.263)
		(size 0.508)
		(drill 0.254)
		(layers "F.Cu" "B.Cu")
		(net "GND")
	)
	(via
		(at 497.870734 -166.714424)
		(size 0.5588)
		(drill 0.3048)
		(layers "F.Cu" "B.Cu")
		(net "GND")
	)
	(via
		(at 346.673424 -93.133164)
		(size 0.508)
		(drill 0.254)
		(layers "F.Cu" "B.Cu")
		(net "GND")
	)
	(via
		(at 340.84768 -78.67777)
		(size 0.508)
		(drill 0.254)
		(layers "F.Cu" "B.Cu")
		(net "GND")
	)
	(via
		(at 75.762866 -72.43064)
		(size 0.508)
		(drill 0.254)
		(layers "F.Cu" "B.Cu")
		(net "GND")
	)
	(via
		(at 235.612178 -93.23324)
		(size 0.508)
		(drill 0.254)
		(layers "F.Cu" "B.Cu")
		(net "GND")
	)
	(via
		(at 200.515728 -82.2706)
		(size 0.508)
		(drill 0.254)
		(layers "F.Cu" "B.Cu")
		(net "GND")
	)
	(via
		(at 42.527982 -93.892878)
		(size 0.5588)
		(drill 0.3048)
		(layers "F.Cu" "B.Cu")
		(net "GND")
	)
	(via
		(at 268.679168 -149.8092)
		(size 0.508)
		(drill 0.254)
		(layers "F.Cu" "B.Cu")
		(net "GND")
	)
	(via
		(at 282.681934 14.926056)
		(size 0.5588)
		(drill 0.3048)
		(layers "F.Cu" "B.Cu")
		(net "GND")
	)
	(via
		(at 316.249812 -131.016756)
		(size 0.508)
		(drill 0.254)
		(layers "F.Cu" "B.Cu")
		(net "GND")
	)
	(via
		(at 15.767304 -1.41605)
		(size 0.508)
		(drill 0.254)
		(layers "F.Cu" "B.Cu")
		(net "GND")
	)
	(via
		(at 460.464408 -150.266654)
		(size 0.508)
		(drill 0.254)
		(layers "F.Cu" "B.Cu")
		(net "GND")
	)
	(via
		(at 234.753658 -91.747086)
		(size 0.508)
		(drill 0.254)
		(layers "F.Cu" "B.Cu")
		(net "GND")
	)
	(via
		(at 336.534252 -53.149754)
		(size 0.508)
		(drill 0.254)
		(layers "F.Cu" "B.Cu")
		(net "GND")
	)
	(via
		(at 312.391298 -7.095744)
		(size 0.508)
		(drill 0.254)
		(layers "F.Cu" "B.Cu")
		(net "GND")
	)
	(via
		(at 491.4265 -61.0362)
		(size 0.508)
		(drill 0.254)
		(layers "F.Cu" "B.Cu")
		(net "GND")
	)
	(via
		(at 200.874884 -57.346596)
		(size 0.508)
		(drill 0.254)
		(layers "F.Cu" "B.Cu")
		(net "GND")
	)
	(via
		(at 283.973524 -162.243262)
		(size 0.5588)
		(drill 0.3048)
		(layers "F.Cu" "B.Cu")
		(net "GND")
	)
	(via
		(at 306.325524 -162.243262)
		(size 0.5588)
		(drill 0.3048)
		(layers "F.Cu" "B.Cu")
		(net "GND")
	)
	(via
		(at 186.161934 9.084056)
		(size 0.5588)
		(drill 0.3048)
		(layers "F.Cu" "B.Cu")
		(net "GND")
	)
	(via
		(at 341.6554 -111.125)
		(size 0.508)
		(drill 0.254)
		(layers "F.Cu" "B.Cu")
		(net "GND")
	)
	(via
		(at 303.041304 -7.095744)
		(size 0.508)
		(drill 0.254)
		(layers "F.Cu" "B.Cu")
		(net "GND")
	)
	(via
		(at 236.171994 -134.8994)
		(size 0.508)
		(drill 0.254)
		(layers "F.Cu" "B.Cu")
		(net "GND")
	)
	(via
		(at 464.907376 -3.402838)
		(size 0.508)
		(drill 0.254)
		(layers "F.Cu" "B.Cu")
		(net "GND")
	)
	(via
		(at 175.895 -53.3654)
		(size 0.508)
		(drill 0.254)
		(layers "F.Cu" "B.Cu")
		(net "GND")
	)
	(via
		(at 203.705714 -70.245478)
		(size 0.5588)
		(drill 0.3048)
		(layers "F.Cu" "B.Cu")
		(net "GND")
	)
	(via
		(at 107.414568 5.280406)
		(size 0.508)
		(drill 0.254)
		(layers "F.Cu" "B.Cu")
		(net "GND")
	)
	(via
		(at 234.753658 -64.010286)
		(size 0.508)
		(drill 0.254)
		(layers "F.Cu" "B.Cu")
		(net "GND")
	)
	(via
		(at 206.245714 -78.475078)
		(size 0.5588)
		(drill 0.3048)
		(layers "F.Cu" "B.Cu")
		(net "GND")
	)
	(via
		(at 438.180734 -165.596824)
		(size 0.5588)
		(drill 0.3048)
		(layers "F.Cu" "B.Cu")
		(net "GND")
	)
	(via
		(at 173.331124 -162.243262)
		(size 0.5588)
		(drill 0.3048)
		(layers "F.Cu" "B.Cu")
		(net "GND")
	)
	(via
		(at 258.272534 -167.832024)
		(size 0.5588)
		(drill 0.3048)
		(layers "F.Cu" "B.Cu")
		(net "GND")
	)
	(via
		(at 238.187738 -55.094886)
		(size 0.508)
		(drill 0.254)
		(layers "F.Cu" "B.Cu")
		(net "GND")
	)
	(via
		(at 5.931408 -152.674066)
		(size 0.5588)
		(drill 0.3048)
		(layers "F.Cu" "B.Cu")
		(net "GND")
	)
	(via
		(at 453.420734 -164.479224)
		(size 0.5588)
		(drill 0.3048)
		(layers "F.Cu" "B.Cu")
		(net "GND")
	)
	(via
		(at 380.30785 -98.464116)
		(size 0.508)
		(drill 0.254)
		(layers "F.Cu" "B.Cu")
		(net "GND")
	)
	(via
		(at 184.778396 -87.544402)
		(size 0.508)
		(drill 0.254)
		(layers "F.Cu" "B.Cu")
		(net "GND")
	)
	(via
		(at 485.170734 -164.479224)
		(size 0.5588)
		(drill 0.3048)
		(layers "F.Cu" "B.Cu")
		(net "GND")
	)
	(via
		(at 277.490174 -58.876438)
		(size 0.508)
		(drill 0.254)
		(layers "F.Cu" "B.Cu")
		(net "GND")
	)
	(via
		(at 288.19983 -140.617956)
		(size 0.508)
		(drill 0.254)
		(layers "F.Cu" "B.Cu")
		(net "GND")
	)
	(via
		(at 188.701934 9.084056)
		(size 0.5588)
		(drill 0.3048)
		(layers "F.Cu" "B.Cu")
		(net "GND")
	)
	(via
		(at 135.771636 -150.219156)
		(size 0.508)
		(drill 0.254)
		(layers "F.Cu" "B.Cu")
		(net "GND")
	)
	(via
		(at 254.49911 -91.25204)
		(size 0.508)
		(drill 0.254)
		(layers "F.Cu" "B.Cu")
		(net "GND")
	)
	(via
		(at 351.944432 4.44119)
		(size 0.508)
		(drill 0.254)
		(layers "F.Cu" "B.Cu")
		(net "GND")
	)
	(via
		(at 240.763298 -92.24264)
		(size 0.508)
		(drill 0.254)
		(layers "F.Cu" "B.Cu")
		(net "GND")
	)
	(via
		(at 433.096924 -162.243262)
		(size 0.5588)
		(drill 0.3048)
		(layers "F.Cu" "B.Cu")
		(net "GND")
	)
	(via
		(at 345.24442 -32.131)
		(size 0.508)
		(drill 0.254)
		(layers "F.Cu" "B.Cu")
		(net "GND")
	)
	(via
		(at 147.381468 -21.5138)
		(size 0.508)
		(drill 0.254)
		(layers "F.Cu" "B.Cu")
		(net "GND")
	)
	(via
		(at 421.9448 -152.7302)
		(size 0.508)
		(drill 0.254)
		(layers "F.Cu" "B.Cu")
		(net "GND")
	)
	(via
		(at 336.963004 -117.9576)
		(size 0.508)
		(drill 0.254)
		(layers "F.Cu" "B.Cu")
		(net "GND")
	)
	(via
		(at 312.3819 -139.1666)
		(size 0.508)
		(drill 0.254)
		(layers "F.Cu" "B.Cu")
		(net "GND")
	)
	(via
		(at 108.888276 -70.84314)
		(size 0.5588)
		(drill 0.3048)
		(layers "F.Cu" "B.Cu")
		(net "GND")
	)
	(via
		(at 296.66184 -82.155284)
		(size 0.508)
		(drill 0.254)
		(layers "F.Cu" "B.Cu")
		(net "GND")
	)
	(via
		(at 134.173214 -124.699776)
		(size 0.508)
		(drill 0.254)
		(layers "F.Cu" "B.Cu")
		(net "GND")
	)
	(via
		(at 299.237146 -92.556584)
		(size 0.508)
		(drill 0.254)
		(layers "F.Cu" "B.Cu")
		(net "GND")
	)
	(via
		(at 5.34162 -24.08936)
		(size 0.508)
		(drill 0.254)
		(layers "F.Cu" "B.Cu")
		(net "GND")
	)
	(via
		(at 179.4002 -80.8736)
		(size 0.508)
		(drill 0.254)
		(layers "F.Cu" "B.Cu")
		(net "GND")
	)
	(via
		(at 301.742602 -148.767292)
		(size 0.508)
		(drill 0.254)
		(layers "F.Cu" "B.Cu")
		(net "GND")
	)
	(via
		(at 24.82342 -47.900336)
		(size 0.5588)
		(drill 0.3048)
		(layers "F.Cu" "B.Cu")
		(net "GND")
	)
	(via
		(at 250.206764 -96.700086)
		(size 0.508)
		(drill 0.254)
		(layers "F.Cu" "B.Cu")
		(net "GND")
	)
	(via
		(at 384.76555 -116.953284)
		(size 0.508)
		(drill 0.254)
		(layers "F.Cu" "B.Cu")
		(net "GND")
	)
	(via
		(at 244.197124 -70.44944)
		(size 0.508)
		(drill 0.254)
		(layers "F.Cu" "B.Cu")
		(net "GND")
	)
	(via
		(at 385.75615 -116.953284)
		(size 0.508)
		(drill 0.254)
		(layers "F.Cu" "B.Cu")
		(net "GND")
	)
	(via
		(at 119.357902 -54.913784)
		(size 0.508)
		(drill 0.254)
		(layers "F.Cu" "B.Cu")
		(net "GND")
	)
	(via
		(at 346.559124 -162.243262)
		(size 0.5588)
		(drill 0.3048)
		(layers "F.Cu" "B.Cu")
		(net "GND")
	)
	(via
		(at 358.6226 -110.43285)
		(size 0.508)
		(drill 0.254)
		(layers "F.Cu" "B.Cu")
		(net "GND")
	)
	(via
		(at 247.631204 -59.55284)
		(size 0.508)
		(drill 0.254)
		(layers "F.Cu" "B.Cu")
		(net "GND")
	)
	(via
		(at 203.199746 -22.965156)
		(size 0.508)
		(drill 0.254)
		(layers "F.Cu" "B.Cu")
		(net "GND")
	)
	(via
		(at 309.449978 0.444754)
		(size 0.508)
		(drill 0.254)
		(layers "F.Cu" "B.Cu")
		(net "GND")
	)
	(via
		(at 421.119046 -65.33896)
		(size 0.508)
		(drill 0.254)
		(layers "F.Cu" "B.Cu")
		(net "GND")
	)
	(via
		(at 286.499808 -144.462246)
		(size 0.508)
		(drill 0.254)
		(layers "F.Cu" "B.Cu")
		(net "GND")
	)
	(via
		(at 1.78435 -108.6866)
		(size 0.508)
		(drill 0.254)
		(layers "F.Cu" "B.Cu")
		(net "GND")
	)
	(via
		(at 130.84937 1.994154)
		(size 0.508)
		(drill 0.254)
		(layers "F.Cu" "B.Cu")
		(net "GND")
	)
	(via
		(at 166.37 -130.5306)
		(size 0.508)
		(drill 0.254)
		(layers "F.Cu" "B.Cu")
		(net "GND")
	)
	(via
		(at 480.801934 13.910056)
		(size 0.5588)
		(drill 0.3048)
		(layers "F.Cu" "B.Cu")
		(net "GND")
	)
	(via
		(at 130.84937 -22.965156)
		(size 0.508)
		(drill 0.254)
		(layers "F.Cu" "B.Cu")
		(net "GND")
	)
	(via
		(at 35.880802 -79.683864)
		(size 0.508)
		(drill 0.254)
		(layers "F.Cu" "B.Cu")
		(net "GND")
	)
	(via
		(at 206.862934 -167.832024)
		(size 0.5588)
		(drill 0.3048)
		(layers "F.Cu" "B.Cu")
		(net "GND")
	)
	(via
		(at 152.949402 -23.520146)
		(size 0.508)
		(drill 0.254)
		(layers "F.Cu" "B.Cu")
		(net "GND")
	)
	(via
		(at 140.199364 -27.943556)
		(size 0.508)
		(drill 0.254)
		(layers "F.Cu" "B.Cu")
		(net "GND")
	)
	(via
		(at 139.34948 -155.612846)
		(size 0.508)
		(drill 0.254)
		(layers "F.Cu" "B.Cu")
		(net "GND")
	)
	(via
		(at 229.341934 14.926056)
		(size 0.5588)
		(drill 0.3048)
		(layers "F.Cu" "B.Cu")
		(net "GND")
	)
	(via
		(at 2.77495 -14.266418)
		(size 0.508)
		(drill 0.254)
		(layers "F.Cu" "B.Cu")
		(net "GND")
	)
	(via
		(at 296.545 -125.9332)
		(size 0.508)
		(drill 0.254)
		(layers "F.Cu" "B.Cu")
		(net "GND")
	)
	(via
		(at 221.387924 -162.243262)
		(size 0.5588)
		(drill 0.3048)
		(layers "F.Cu" "B.Cu")
		(net "GND")
	)
	(via
		(at 397.6624 -143.6878)
		(size 0.508)
		(drill 0.254)
		(layers "F.Cu" "B.Cu")
		(net "GND")
	)
	(via
		(at 407.4668 -117.954298)
		(size 0.508)
		(drill 0.254)
		(layers "F.Cu" "B.Cu")
		(net "GND")
	)
	(via
		(at 34.748724 -162.243262)
		(size 0.5588)
		(drill 0.3048)
		(layers "F.Cu" "B.Cu")
		(net "GND")
	)
	(via
		(at 336.169 -19.05)
		(size 0.508)
		(drill 0.254)
		(layers "F.Cu" "B.Cu")
		(net "GND")
	)
	(via
		(at 310.122062 -22.965156)
		(size 0.508)
		(drill 0.254)
		(layers "F.Cu" "B.Cu")
		(net "GND")
	)
	(via
		(at 458.500734 -164.479224)
		(size 0.5588)
		(drill 0.3048)
		(layers "F.Cu" "B.Cu")
		(net "GND")
	)
	(via
		(at 114.206782 -56.894984)
		(size 0.508)
		(drill 0.254)
		(layers "F.Cu" "B.Cu")
		(net "GND")
	)
	(via
		(at 283.951934 14.926056)
		(size 0.5588)
		(drill 0.3048)
		(layers "F.Cu" "B.Cu")
		(net "GND")
	)
	(via
		(at 300.954186 -83.641184)
		(size 0.508)
		(drill 0.254)
		(layers "F.Cu" "B.Cu")
		(net "GND")
	)
	(via
		(at 389.68172 -126.63932)
		(size 0.508)
		(drill 0.254)
		(layers "F.Cu" "B.Cu")
		(net "GND")
	)
	(via
		(at 365.724694 -137.286238)
		(size 0.508)
		(drill 0.254)
		(layers "F.Cu" "B.Cu")
		(net "GND")
	)
	(via
		(at 113.967768 -150.0886)
		(size 0.508)
		(drill 0.254)
		(layers "F.Cu" "B.Cu")
		(net "GND")
	)
	(via
		(at 26.0096 -47.1678)
		(size 0.508)
		(drill 0.254)
		(layers "F.Cu" "B.Cu")
		(net "GND")
	)
	(via
		(at 134.215124 -162.243262)
		(size 0.5588)
		(drill 0.3048)
		(layers "F.Cu" "B.Cu")
		(net "GND")
	)
	(via
		(at 277.267924 -162.243262)
		(size 0.5588)
		(drill 0.3048)
		(layers "F.Cu" "B.Cu")
		(net "GND")
	)
	(via
		(at 464.87588 -121.9073)
		(size 0.508)
		(drill 0.254)
		(layers "F.Cu" "B.Cu")
		(net "GND")
	)
	(via
		(at 141.711934 9.084056)
		(size 0.5588)
		(drill 0.3048)
		(layers "F.Cu" "B.Cu")
		(net "GND")
	)
	(via
		(at 136.736074 -23.495)
		(size 0.508)
		(drill 0.254)
		(layers "F.Cu" "B.Cu")
		(net "GND")
	)
	(via
		(at 263.982708 -70.841616)
		(size 0.5588)
		(drill 0.3048)
		(layers "F.Cu" "B.Cu")
		(net "GND")
	)
	(via
		(at 283.951934 9.084056)
		(size 0.5588)
		(drill 0.3048)
		(layers "F.Cu" "B.Cu")
		(net "GND")
	)
	(via
		(at 102.639876 -75.159616)
		(size 0.5588)
		(drill 0.3048)
		(layers "F.Cu" "B.Cu")
		(net "GND")
	)
	(via
		(at 87.781892 -99.17684)
		(size 0.508)
		(drill 0.254)
		(layers "F.Cu" "B.Cu")
		(net "GND")
	)
	(via
		(at 56.049418 -146.011646)
		(size 0.508)
		(drill 0.254)
		(layers "F.Cu" "B.Cu")
		(net "GND")
	)
	(via
		(at 175.35652 -64.06896)
		(size 0.508)
		(drill 0.254)
		(layers "F.Cu" "B.Cu")
		(net "GND")
	)
	(via
		(at 274.91182 -70.84314)
		(size 0.5588)
		(drill 0.3048)
		(layers "F.Cu" "B.Cu")
		(net "GND")
	)
	(via
		(at 473.3925 -41.5925)
		(size 0.508)
		(drill 0.254)
		(layers "F.Cu" "B.Cu")
		(net "GND")
	)
	(via
		(at 126.510288 -59.371484)
		(size 0.508)
		(drill 0.254)
		(layers "F.Cu" "B.Cu")
		(net "GND")
	)
	(via
		(at 292.36924 -84.631784)
		(size 0.508)
		(drill 0.254)
		(layers "F.Cu" "B.Cu")
		(net "GND")
	)
	(via
		(at 282.067254 -99.490784)
		(size 0.508)
		(drill 0.254)
		(layers "F.Cu" "B.Cu")
		(net "GND")
	)
	(via
		(at 386.74675 -118.670324)
		(size 0.508)
		(drill 0.254)
		(layers "F.Cu" "B.Cu")
		(net "GND")
	)
	(via
		(at 374.626124 -162.268662)
		(size 0.5588)
		(drill 0.3048)
		(layers "F.Cu" "B.Cu")
		(net "GND")
	)
	(via
		(at 119.357902 -72.744584)
		(size 0.508)
		(drill 0.254)
		(layers "F.Cu" "B.Cu")
		(net "GND")
	)
	(via
		(at 37.34943 -18.757646)
		(size 0.508)
		(drill 0.254)
		(layers "F.Cu" "B.Cu")
		(net "GND")
	)
	(via
		(at 174.452534 -167.832024)
		(size 0.5588)
		(drill 0.3048)
		(layers "F.Cu" "B.Cu")
		(net "GND")
	)
	(via
		(at 162.2552 -32.1818)
		(size 0.508)
		(drill 0.254)
		(layers "F.Cu" "B.Cu")
		(net "GND")
	)
	(via
		(at 133.378194 -90.080338)
		(size 0.508)
		(drill 0.254)
		(layers "F.Cu" "B.Cu")
		(net "GND")
	)
	(via
		(at 414.761934 9.084056)
		(size 0.5588)
		(drill 0.3048)
		(layers "F.Cu" "B.Cu")
		(net "GND")
	)
	(via
		(at 69.753226 -94.718886)
		(size 0.508)
		(drill 0.254)
		(layers "F.Cu" "B.Cu")
		(net "GND")
	)
	(via
		(at 412.780734 -164.479224)
		(size 0.5588)
		(drill 0.3048)
		(layers "F.Cu" "B.Cu")
		(net "GND")
	)
	(via
		(at 334.0354 -112.395)
		(size 0.508)
		(drill 0.254)
		(layers "F.Cu" "B.Cu")
		(net "GND")
	)
	(via
		(at 282.641294 -58.876438)
		(size 0.508)
		(drill 0.254)
		(layers "F.Cu" "B.Cu")
		(net "GND")
	)
	(via
		(at 138.529314 -56.399938)
		(size 0.508)
		(drill 0.254)
		(layers "F.Cu" "B.Cu")
		(net "GND")
	)
	(via
		(at 494.069624 -40.699944)
		(size 0.508)
		(drill 0.254)
		(layers "F.Cu" "B.Cu")
		(net "GND")
	)
	(via
		(at 285.501334 -85.622384)
		(size 0.508)
		(drill 0.254)
		(layers "F.Cu" "B.Cu")
		(net "GND")
	)
	(via
		(at 209.092546 -9.143746)
		(size 0.508)
		(drill 0.254)
		(layers "F.Cu" "B.Cu")
		(net "GND")
	)
	(via
		(at 356.161594 -152.81021)
		(size 0.5588)
		(drill 0.3048)
		(layers "F.Cu" "B.Cu")
		(net "GND")
	)
	(via
		(at 207.411828 -146.011646)
		(size 0.508)
		(drill 0.254)
		(layers "F.Cu" "B.Cu")
		(net "GND")
	)
	(via
		(at 499.417848 -18.515838)
		(size 0.508)
		(drill 0.254)
		(layers "F.Cu" "B.Cu")
		(net "GND")
	)
	(via
		(at 149.549358 -3.762756)
		(size 0.508)
		(drill 0.254)
		(layers "F.Cu" "B.Cu")
		(net "GND")
	)
	(via
		(at 276.631654 -54.418738)
		(size 0.508)
		(drill 0.254)
		(layers "F.Cu" "B.Cu")
		(net "GND")
	)
	(via
		(at 286.3596 -97.014538)
		(size 0.508)
		(drill 0.254)
		(layers "F.Cu" "B.Cu")
		(net "GND")
	)
	(via
		(at 139.387834 -82.650584)
		(size 0.508)
		(drill 0.254)
		(layers "F.Cu" "B.Cu")
		(net "GND")
	)
	(via
		(at 139.171934 14.926056)
		(size 0.5588)
		(drill 0.3048)
		(layers "F.Cu" "B.Cu")
		(net "GND")
	)
	(via
		(at 26.925524 -162.243262)
		(size 0.5588)
		(drill 0.3048)
		(layers "F.Cu" "B.Cu")
		(net "GND")
	)
	(via
		(at 125.651768 -62.838584)
		(size 0.508)
		(drill 0.254)
		(layers "F.Cu" "B.Cu")
		(net "GND")
	)
	(via
		(at 127.509524 -162.243262)
		(size 0.5588)
		(drill 0.3048)
		(layers "F.Cu" "B.Cu")
		(net "GND")
	)
	(via
		(at 70.611746 -98.18624)
		(size 0.508)
		(drill 0.254)
		(layers "F.Cu" "B.Cu")
		(net "GND")
	)
	(via
		(at 194.565524 -162.243262)
		(size 0.5588)
		(drill 0.3048)
		(layers "F.Cu" "B.Cu")
		(net "GND")
	)
	(via
		(at 52.471574 -7.6454)
		(size 0.508)
		(drill 0.254)
		(layers "F.Cu" "B.Cu")
		(net "GND")
	)
	(via
		(at 114.699542 -148.771356)
		(size 0.508)
		(drill 0.254)
		(layers "F.Cu" "B.Cu")
		(net "GND")
	)
	(via
		(at 395.077696 -128.170686)
		(size 0.508)
		(drill 0.254)
		(layers "F.Cu" "B.Cu")
		(net "GND")
	)
	(via
		(at 291.51072 -99.986338)
		(size 0.508)
		(drill 0.254)
		(layers "F.Cu" "B.Cu")
		(net "GND")
	)
	(via
		(at 245.055644 -71.935086)
		(size 0.508)
		(drill 0.254)
		(layers "F.Cu" "B.Cu")
		(net "GND")
	)
	(via
		(at 50.860452 -130.991356)
		(size 0.508)
		(drill 0.254)
		(layers "F.Cu" "B.Cu")
		(net "GND")
	)
	(via
		(at 385.572 -142.83182)
		(size 0.508)
		(drill 0.254)
		(layers "F.Cu" "B.Cu")
		(net "GND")
	)
	(via
		(at 42.9641 -64.88938)
		(size 0.5588)
		(drill 0.3048)
		(layers "F.Cu" "B.Cu")
		(net "GND")
	)
	(via
		(at 437.621934 9.084056)
		(size 0.5588)
		(drill 0.3048)
		(layers "F.Cu" "B.Cu")
		(net "GND")
	)
	(via
		(at 56.049418 -2.314956)
		(size 0.508)
		(drill 0.254)
		(layers "F.Cu" "B.Cu")
		(net "GND")
	)
	(via
		(at 264.53338 -82.340196)
		(size 0.5588)
		(drill 0.3048)
		(layers "F.Cu" "B.Cu")
		(net "GND")
	)
	(via
		(at 353.5426 -59.679586)
		(size 0.508)
		(drill 0.254)
		(layers "F.Cu" "B.Cu")
		(net "GND")
	)
	(via
		(at 471.200734 -166.714424)
		(size 0.5588)
		(drill 0.3048)
		(layers "F.Cu" "B.Cu")
		(net "GND")
	)
	(via
		(at 123.650248 -56.399938)
		(size 0.508)
		(drill 0.254)
		(layers "F.Cu" "B.Cu")
		(net "GND")
	)
	(via
		(at 42.748454 -85.89391)
		(size 0.5588)
		(drill 0.3048)
		(layers "F.Cu" "B.Cu")
		(net "GND")
	)
	(via
		(at 195.686934 -167.832024)
		(size 0.5588)
		(drill 0.3048)
		(layers "F.Cu" "B.Cu")
		(net "GND")
	)
	(via
		(at 349.673926 -30.165802)
		(size 0.508)
		(drill 0.254)
		(layers "F.Cu" "B.Cu")
		(net "GND")
	)
	(via
		(at 134.821168 -125.929898)
		(size 0.508)
		(drill 0.254)
		(layers "F.Cu" "B.Cu")
		(net "GND")
	)
	(via
		(at 207.411828 -21.517356)
		(size 0.508)
		(drill 0.254)
		(layers "F.Cu" "B.Cu")
		(net "GND")
	)
	(via
		(at 379.81255 -110.085124)
		(size 0.508)
		(drill 0.254)
		(layers "F.Cu" "B.Cu")
		(net "GND")
	)
	(via
		(at 136.812274 -96.023938)
		(size 0.508)
		(drill 0.254)
		(layers "F.Cu" "B.Cu")
		(net "GND")
	)
	(via
		(at 322.219574 -23.547324)
		(size 0.508)
		(drill 0.254)
		(layers "F.Cu" "B.Cu")
		(net "GND")
	)
	(via
		(at 78.338172 -84.812886)
		(size 0.508)
		(drill 0.254)
		(layers "F.Cu" "B.Cu")
		(net "GND")
	)
	(via
		(at 95.005906 -155.241244)
		(size 0.508)
		(drill 0.254)
		(layers "F.Cu" "B.Cu")
		(net "GND")
	)
	(via
		(at 316.249812 -17.208246)
		(size 0.508)
		(drill 0.254)
		(layers "F.Cu" "B.Cu")
		(net "GND")
	)
	(via
		(at 209.021934 14.926056)
		(size 0.5588)
		(drill 0.3048)
		(layers "F.Cu" "B.Cu")
		(net "GND")
	)
	(via
		(at 292.399212 -153.6065)
		(size 0.508)
		(drill 0.254)
		(layers "F.Cu" "B.Cu")
		(net "GND")
	)
	(via
		(at 14.597634 -104.330246)
		(size 0.508)
		(drill 0.254)
		(layers "F.Cu" "B.Cu")
		(net "GND")
	)
	(via
		(at 377.83135 -115.236244)
		(size 0.508)
		(drill 0.254)
		(layers "F.Cu" "B.Cu")
		(net "GND")
	)
	(via
		(at 350.5454 -36.83)
		(size 0.508)
		(drill 0.254)
		(layers "F.Cu" "B.Cu")
		(net "GND")
	)
	(via
		(at 74.045826 -97.19564)
		(size 0.508)
		(drill 0.254)
		(layers "F.Cu" "B.Cu")
		(net "GND")
	)
	(via
		(at 374.629934 -167.857424)
		(size 0.5588)
		(drill 0.3048)
		(layers "F.Cu" "B.Cu")
		(net "GND")
	)
	(via
		(at 61.149484 -18.757646)
		(size 0.508)
		(drill 0.254)
		(layers "F.Cu" "B.Cu")
		(net "GND")
	)
	(via
		(at 433.811934 10.354056)
		(size 0.5588)
		(drill 0.3048)
		(layers "F.Cu" "B.Cu")
		(net "GND")
	)
	(via
		(at 447.00444 -118.61927)
		(size 0.508)
		(drill 0.254)
		(layers "F.Cu" "B.Cu")
		(net "GND")
	)
	(via
		(at 252.782324 -86.29904)
		(size 0.508)
		(drill 0.254)
		(layers "F.Cu" "B.Cu")
		(net "GND")
	)
	(via
		(at 35.499802 -97.536)
		(size 0.508)
		(drill 0.254)
		(layers "F.Cu" "B.Cu")
		(net "GND")
	)
	(via
		(at 388.209536 -7.12216)
		(size 0.508)
		(drill 0.254)
		(layers "F.Cu" "B.Cu")
		(net "GND")
	)
	(via
		(at 474.56725 -43.6626)
		(size 0.508)
		(drill 0.254)
		(layers "F.Cu" "B.Cu")
		(net "GND")
	)
	(via
		(at 147.390866 2.505456)
		(size 0.508)
		(drill 0.254)
		(layers "F.Cu" "B.Cu")
		(net "GND")
	)
	(via
		(at 463.32775 -124.92482)
		(size 0.508)
		(drill 0.254)
		(layers "F.Cu" "B.Cu")
		(net "GND")
	)
	(via
		(at 69.753226 -91.747086)
		(size 0.508)
		(drill 0.254)
		(layers "F.Cu" "B.Cu")
		(net "GND")
	)
	(via
		(at 50.099468 -2.314956)
		(size 0.508)
		(drill 0.254)
		(layers "F.Cu" "B.Cu")
		(net "GND")
	)
	(via
		(at 248.489724 -59.057286)
		(size 0.508)
		(drill 0.254)
		(layers "F.Cu" "B.Cu")
		(net "GND")
	)
	(via
		(at 125.711458 -11.916156)
		(size 0.508)
		(drill 0.254)
		(layers "F.Cu" "B.Cu")
		(net "GND")
	)
	(via
		(at 235.612178 -100.167186)
		(size 0.508)
		(drill 0.254)
		(layers "F.Cu" "B.Cu")
		(net "GND")
	)
	(via
		(at 413.90062 -126.078996)
		(size 0.508)
		(drill 0.254)
		(layers "F.Cu" "B.Cu")
		(net "GND")
	)
	(via
		(at 211.699856 -21.517356)
		(size 0.508)
		(drill 0.254)
		(layers "F.Cu" "B.Cu")
		(net "GND")
	)
	(via
		(at 98.083878 -89.27084)
		(size 0.508)
		(drill 0.254)
		(layers "F.Cu" "B.Cu")
		(net "GND")
	)
	(via
		(at 34.74212 -139.166092)
		(size 0.508)
		(drill 0.254)
		(layers "F.Cu" "B.Cu")
		(net "GND")
	)
	(via
		(at 387.0833 -26.4287)
		(size 0.508)
		(drill 0.254)
		(layers "F.Cu" "B.Cu")
		(net "GND")
	)
	(via
		(at 295.849802 -131.016756)
		(size 0.508)
		(drill 0.254)
		(layers "F.Cu" "B.Cu")
		(net "GND")
	)
	(via
		(at 371.708426 -154.155648)
		(size 0.508)
		(drill 0.254)
		(layers "F.Cu" "B.Cu")
		(net "GND")
	)
	(via
		(at -4.363466 -167.832024)
		(size 0.5588)
		(drill 0.3048)
		(layers "F.Cu" "B.Cu")
		(net "GND")
	)
	(via
		(at 295.80332 -68.782184)
		(size 0.508)
		(drill 0.254)
		(layers "F.Cu" "B.Cu")
		(net "GND")
	)
	(via
		(at 408.970734 -164.479224)
		(size 0.5588)
		(drill 0.3048)
		(layers "F.Cu" "B.Cu")
		(net "GND")
	)
	(via
		(at 175.478694 -53.826918)
		(size 0.508)
		(drill 0.254)
		(layers "F.Cu" "B.Cu")
		(net "GND")
	)
	(via
		(at 42.9641 -57.8104)
		(size 0.508)
		(drill 0.254)
		(layers "F.Cu" "B.Cu")
		(net "GND")
	)
	(via
		(at 236.171994 -7.6454)
		(size 0.508)
		(drill 0.254)
		(layers "F.Cu" "B.Cu")
		(net "GND")
	)
	(via
		(at 13.18006 -107.81538)
		(size 0.508)
		(drill 0.254)
		(layers "F.Cu" "B.Cu")
		(net "GND")
	)
	(via
		(at 258.462018 -75.148186)
		(size 0.5588)
		(drill 0.3048)
		(layers "F.Cu" "B.Cu")
		(net "GND")
	)
	(via
		(at 74.045826 -91.25204)
		(size 0.508)
		(drill 0.254)
		(layers "F.Cu" "B.Cu")
		(net "GND")
	)
	(via
		(at 294.97528 -125.9332)
		(size 0.508)
		(drill 0.254)
		(layers "F.Cu" "B.Cu")
		(net "GND")
	)
	(via
		(at 74.749406 -124.572776)
		(size 0.508)
		(drill 0.254)
		(layers "F.Cu" "B.Cu")
		(net "GND")
	)
	(via
		(at 110.111032 -17.7546)
		(size 0.508)
		(drill 0.254)
		(layers "F.Cu" "B.Cu")
		(net "GND")
	)
	(via
		(at 191.065404 -52.714398)
		(size 0.508)
		(drill 0.254)
		(layers "F.Cu" "B.Cu")
		(net "GND")
	)
	(via
		(at 200.881234 -62.792864)
		(size 0.508)
		(drill 0.254)
		(layers "F.Cu" "B.Cu")
		(net "GND")
	)
	(via
		(at 406.430734 -167.832024)
		(size 0.5588)
		(drill 0.3048)
		(layers "F.Cu" "B.Cu")
		(net "GND")
	)
	(via
		(at 442.9506 -53.2638)
		(size 0.508)
		(drill 0.254)
		(layers "F.Cu" "B.Cu")
		(net "GND")
	)
	(via
		(at 210.39455 -145.9357)
		(size 0.508)
		(drill 0.254)
		(layers "F.Cu" "B.Cu")
		(net "GND")
	)
	(via
		(at 344.4113 -0.633222)
		(size 0.508)
		(drill 0.254)
		(layers "F.Cu" "B.Cu")
		(net "GND")
	)
	(via
		(at 35.8902 -96.9772)
		(size 0.508)
		(drill 0.254)
		(layers "F.Cu" "B.Cu")
		(net "GND")
	)
	(via
		(at 348.4626 -6.6294)
		(size 0.508)
		(drill 0.254)
		(layers "F.Cu" "B.Cu")
		(net "GND")
	)
	(via
		(at 152.949402 2.514854)
		(size 0.508)
		(drill 0.254)
		(layers "F.Cu" "B.Cu")
		(net "GND")
	)
	(via
		(at 498.581934 11.624056)
		(size 0.5588)
		(drill 0.3048)
		(layers "F.Cu" "B.Cu")
		(net "GND")
	)
	(via
		(at 108.691934 9.084056)
		(size 0.5588)
		(drill 0.3048)
		(layers "F.Cu" "B.Cu")
		(net "GND")
	)
	(via
		(at 94.721934 9.084056)
		(size 0.5588)
		(drill 0.3048)
		(layers "F.Cu" "B.Cu")
		(net "GND")
	)
	(via
		(at 6.886956 -141.621002)
		(size 0.508)
		(drill 0.254)
		(layers "F.Cu" "B.Cu")
		(net "GND")
	)
	(via
		(at 421.250364 -139.28852)
		(size 0.508)
		(drill 0.254)
		(layers "F.Cu" "B.Cu")
		(net "GND")
	)
	(via
		(at 93.451934 9.084056)
		(size 0.5588)
		(drill 0.3048)
		(layers "F.Cu" "B.Cu")
		(net "GND")
	)
	(via
		(at 124.049536 -129.568956)
		(size 0.508)
		(drill 0.254)
		(layers "F.Cu" "B.Cu")
		(net "GND")
	)
	(via
		(at 396.3416 -155.3464)
		(size 0.508)
		(drill 0.254)
		(layers "F.Cu" "B.Cu")
		(net "GND")
	)
	(via
		(at 294.9448 -53.427884)
		(size 0.508)
		(drill 0.254)
		(layers "F.Cu" "B.Cu")
		(net "GND")
	)
	(via
		(at 182.005478 -50.433478)
		(size 0.508)
		(drill 0.254)
		(layers "F.Cu" "B.Cu")
		(net "GND")
	)
	(via
		(at 448.340734 -166.714424)
		(size 0.5588)
		(drill 0.3048)
		(layers "F.Cu" "B.Cu")
		(net "GND")
	)
	(via
		(at 79.196692 -68.46824)
		(size 0.508)
		(drill 0.254)
		(layers "F.Cu" "B.Cu")
		(net "GND")
	)
	(via
		(at 464.850734 -167.832024)
		(size 0.5588)
		(drill 0.3048)
		(layers "F.Cu" "B.Cu")
		(net "GND")
	)
	(via
		(at 247.631204 -71.44004)
		(size 0.508)
		(drill 0.254)
		(layers "F.Cu" "B.Cu")
		(net "GND")
	)
	(via
		(at 61.821568 -140.617956)
		(size 0.508)
		(drill 0.254)
		(layers "F.Cu" "B.Cu")
		(net "GND")
	)
	(via
		(at 140.199364 -144.462246)
		(size 0.508)
		(drill 0.254)
		(layers "F.Cu" "B.Cu")
		(net "GND")
	)
	(via
		(at 289.801808 1.994154)
		(size 0.508)
		(drill 0.254)
		(layers "F.Cu" "B.Cu")
		(net "GND")
	)
	(via
		(at 445.800734 -164.479224)
		(size 0.5588)
		(drill 0.3048)
		(layers "F.Cu" "B.Cu")
		(net "GND")
	)
	(via
		(at 44.092114 -9.143746)
		(size 0.508)
		(drill 0.254)
		(layers "F.Cu" "B.Cu")
		(net "GND")
	)
	(via
		(at 235.46181 -129.568956)
		(size 0.508)
		(drill 0.254)
		(layers "F.Cu" "B.Cu")
		(net "GND")
	)
	(via
		(at 118.048532 -16.7513)
		(size 0.508)
		(drill 0.254)
		(layers "F.Cu" "B.Cu")
		(net "GND")
	)
	(via
		(at 224.449894 -129.568956)
		(size 0.508)
		(drill 0.254)
		(layers "F.Cu" "B.Cu")
		(net "GND")
	)
	(via
		(at 205.211934 14.926056)
		(size 0.5588)
		(drill 0.3048)
		(layers "F.Cu" "B.Cu")
		(net "GND")
	)
	(via
		(at 75.762866 -99.17684)
		(size 0.508)
		(drill 0.254)
		(layers "F.Cu" "B.Cu")
		(net "GND")
	)
	(via
		(at 87.781892 -86.29904)
		(size 0.508)
		(drill 0.254)
		(layers "F.Cu" "B.Cu")
		(net "GND")
	)
	(via
		(at 454.9521 -53.2384)
		(size 0.508)
		(drill 0.254)
		(layers "F.Cu" "B.Cu")
		(net "GND")
	)
	(via
		(at 447.799968 -113.776252)
		(size 0.508)
		(drill 0.254)
		(layers "F.Cu" "B.Cu")
		(net "GND")
	)
	(via
		(at 71.171562 -150.219156)
		(size 0.508)
		(drill 0.254)
		(layers "F.Cu" "B.Cu")
		(net "GND")
	)
	(via
		(at 72.142096 -28.730956)
		(size 0.508)
		(drill 0.254)
		(layers "F.Cu" "B.Cu")
		(net "GND")
	)
	(via
		(at 352.9584 -81.3054)
		(size 0.508)
		(drill 0.254)
		(layers "F.Cu" "B.Cu")
		(net "GND")
	)
	(via
		(at 277.490174 -64.819784)
		(size 0.508)
		(drill 0.254)
		(layers "F.Cu" "B.Cu")
		(net "GND")
	)
	(via
		(at 247.092724 -162.243262)
		(size 0.5588)
		(drill 0.3048)
		(layers "F.Cu" "B.Cu")
		(net "GND")
	)
	(via
		(at 285.501334 -99.490784)
		(size 0.508)
		(drill 0.254)
		(layers "F.Cu" "B.Cu")
		(net "GND")
	)
	(via
		(at 208.122012 -13.363956)
		(size 0.508)
		(drill 0.254)
		(layers "F.Cu" "B.Cu")
		(net "GND")
	)
	(via
		(at 482.071934 9.084056)
		(size 0.5588)
		(drill 0.3048)
		(layers "F.Cu" "B.Cu")
		(net "GND")
	)
	(via
		(at 79.196692 -56.58104)
		(size 0.508)
		(drill 0.254)
		(layers "F.Cu" "B.Cu")
		(net "GND")
	)
	(via
		(at 113.72469 -130.249676)
		(size 0.508)
		(drill 0.254)
		(layers "F.Cu" "B.Cu")
		(net "GND")
	)
	(via
		(at 2.652522 -124.624846)
		(size 0.508)
		(drill 0.254)
		(layers "F.Cu" "B.Cu")
		(net "GND")
	)
	(via
		(at 298.378626 -87.108538)
		(size 0.508)
		(drill 0.254)
		(layers "F.Cu" "B.Cu")
		(net "GND")
	)
	(via
		(at 478.261934 14.926056)
		(size 0.5588)
		(drill 0.3048)
		(layers "F.Cu" "B.Cu")
		(net "GND")
	)
	(via
		(at 437.388 -130.302)
		(size 0.508)
		(drill 0.254)
		(layers "F.Cu" "B.Cu")
		(net "GND")
	)
	(via
		(at 145.12163 -150.219156)
		(size 0.508)
		(drill 0.254)
		(layers "F.Cu" "B.Cu")
		(net "GND")
	)
	(via
		(at 191.241934 14.926056)
		(size 0.5588)
		(drill 0.3048)
		(layers "F.Cu" "B.Cu")
		(net "GND")
	)
	(via
		(at 130.84937 -131.016756)
		(size 0.508)
		(drill 0.254)
		(layers "F.Cu" "B.Cu")
		(net "GND")
	)
	(via
		(at 376.428 -107.355132)
		(size 0.508)
		(drill 0.254)
		(layers "F.Cu" "B.Cu")
		(net "GND")
	)
	(via
		(at 287.21812 -91.565984)
		(size 0.508)
		(drill 0.254)
		(layers "F.Cu" "B.Cu")
		(net "GND")
	)
	(via
		(at 94.721934 14.926056)
		(size 0.5588)
		(drill 0.3048)
		(layers "F.Cu" "B.Cu")
		(net "GND")
	)
	(via
		(at 213.399878 -2.314956)
		(size 0.508)
		(drill 0.254)
		(layers "F.Cu" "B.Cu")
		(net "GND")
	)
	(via
		(at 403.226016 -153.795984)
		(size 0.508)
		(drill 0.254)
		(layers "F.Cu" "B.Cu")
		(net "GND")
	)
	(via
		(at 380.305818 -128.352042)
		(size 0.508)
		(drill 0.254)
		(layers "F.Cu" "B.Cu")
		(net "GND")
	)
	(via
		(at -5.2578 -5.6642)
		(size 0.508)
		(drill 0.254)
		(layers "F.Cu" "B.Cu")
		(net "GND")
	)
	(via
		(at 358.285034 -3.34518)
		(size 0.508)
		(drill 0.254)
		(layers "F.Cu" "B.Cu")
		(net "GND")
	)
	(via
		(at 169.291 -123.8504)
		(size 0.508)
		(drill 0.254)
		(layers "F.Cu" "B.Cu")
		(net "GND")
	)
	(via
		(at 293.22776 -86.117938)
		(size 0.508)
		(drill 0.254)
		(layers "F.Cu" "B.Cu")
		(net "GND")
	)
	(via
		(at 206.12481 -100.911406)
		(size 0.5588)
		(drill 0.3048)
		(layers "F.Cu" "B.Cu")
		(net "GND")
	)
	(via
		(at 281.399996 0.444754)
		(size 0.508)
		(drill 0.254)
		(layers "F.Cu" "B.Cu")
		(net "GND")
	)
	(via
		(at 170.053 -122.3264)
		(size 0.508)
		(drill 0.254)
		(layers "F.Cu" "B.Cu")
		(net "GND")
	)
	(via
		(at 281.782774 -66.305938)
		(size 0.508)
		(drill 0.254)
		(layers "F.Cu" "B.Cu")
		(net "GND")
	)
	(via
		(at 252.782324 -84.31784)
		(size 0.508)
		(drill 0.254)
		(layers "F.Cu" "B.Cu")
		(net "GND")
	)
	(via
		(at 290.6522 -94.538038)
		(size 0.508)
		(drill 0.254)
		(layers "F.Cu" "B.Cu")
		(net "GND")
	)
	(via
		(at 110.772702 -61.847984)
		(size 0.508)
		(drill 0.254)
		(layers "F.Cu" "B.Cu")
		(net "GND")
	)
	(via
		(at 164.36848 -31.1658)
		(size 0.508)
		(drill 0.254)
		(layers "F.Cu" "B.Cu")
		(net "GND")
	)
	(via
		(at 296.66184 -55.409338)
		(size 0.508)
		(drill 0.254)
		(layers "F.Cu" "B.Cu")
		(net "GND")
	)
	(via
		(at 70.611746 -80.35544)
		(size 0.508)
		(drill 0.254)
		(layers "F.Cu" "B.Cu")
		(net "GND")
	)
	(via
		(at 207.411828 -2.314956)
		(size 0.508)
		(drill 0.254)
		(layers "F.Cu" "B.Cu")
		(net "GND")
	)
	(via
		(at 343.53246 -130.92938)
		(size 0.508)
		(drill 0.254)
		(layers "F.Cu" "B.Cu")
		(net "GND")
	)
	(via
		(at 16.189198 -33.172908)
		(size 0.508)
		(drill 0.254)
		(layers "F.Cu" "B.Cu")
		(net "GND")
	)
	(via
		(at 234.560872 -140.592556)
		(size 0.508)
		(drill 0.254)
		(layers "F.Cu" "B.Cu")
		(net "GND")
	)
	(via
		(at 152.099518 -143.941546)
		(size 0.508)
		(drill 0.254)
		(layers "F.Cu" "B.Cu")
		(net "GND")
	)
	(via
		(at 238.431832 -139.1666)
		(size 0.508)
		(drill 0.254)
		(layers "F.Cu" "B.Cu")
		(net "GND")
	)
	(via
		(at 443.004448 -118.61927)
		(size 0.508)
		(drill 0.254)
		(layers "F.Cu" "B.Cu")
		(net "GND")
	)
	(via
		(at 119.642382 -101.967538)
		(size 0.508)
		(drill 0.254)
		(layers "F.Cu" "B.Cu")
		(net "GND")
	)
	(via
		(at 36.040822 -153.552144)
		(size 0.508)
		(drill 0.254)
		(layers "F.Cu" "B.Cu")
		(net "GND")
	)
	(via
		(at 191.212724 -162.243262)
		(size 0.5588)
		(drill 0.3048)
		(layers "F.Cu" "B.Cu")
		(net "GND")
	)
	(via
		(at 70.611746 -92.24264)
		(size 0.508)
		(drill 0.254)
		(layers "F.Cu" "B.Cu")
		(net "GND")
	)
	(via
		(at 493.429798 -25.622758)
		(size 0.508)
		(drill 0.254)
		(layers "F.Cu" "B.Cu")
		(net "GND")
	)
	(via
		(at 124.156724 -162.243262)
		(size 0.5588)
		(drill 0.3048)
		(layers "F.Cu" "B.Cu")
		(net "GND")
	)
	(via
		(at 61.821568 -22.965156)
		(size 0.508)
		(drill 0.254)
		(layers "F.Cu" "B.Cu")
		(net "GND")
	)
	(via
		(at 46.699424 -21.517356)
		(size 0.508)
		(drill 0.254)
		(layers "F.Cu" "B.Cu")
		(net "GND")
	)
	(via
		(at 289.810952 -3.737356)
		(size 0.508)
		(drill 0.254)
		(layers "F.Cu" "B.Cu")
		(net "GND")
	)
	(via
		(at 95.324676 -70.841616)
		(size 0.5588)
		(drill 0.3048)
		(layers "F.Cu" "B.Cu")
		(net "GND")
	)
	(via
		(at 482.19995 -113.77422)
		(size 0.508)
		(drill 0.254)
		(layers "F.Cu" "B.Cu")
		(net "GND")
	)
	(via
		(at 124.801376 -134.861046)
		(size 0.508)
		(drill 0.254)
		(layers "F.Cu" "B.Cu")
		(net "GND")
	)
	(via
		(at 342.9254 -36.83)
		(size 0.508)
		(drill 0.254)
		(layers "F.Cu" "B.Cu")
		(net "GND")
	)
	(via
		(at 200.881234 -63.427864)
		(size 0.508)
		(drill 0.254)
		(layers "F.Cu" "B.Cu")
		(net "GND")
	)
	(via
		(at 346.895674 -91.617292)
		(size 0.508)
		(drill 0.254)
		(layers "F.Cu" "B.Cu")
		(net "GND")
	)
	(via
		(at 489.966 -113.2332)
		(size 0.508)
		(drill 0.254)
		(layers "F.Cu" "B.Cu")
		(net "GND")
	)
	(via
		(at 367.771934 9.084056)
		(size 0.5588)
		(drill 0.3048)
		(layers "F.Cu" "B.Cu")
		(net "GND")
	)
	(via
		(at 295.80332 -76.706984)
		(size 0.508)
		(drill 0.254)
		(layers "F.Cu" "B.Cu")
		(net "GND")
	)
	(via
		(at 184.904126 -60.13958)
		(size 0.508)
		(drill 0.254)
		(layers "F.Cu" "B.Cu")
		(net "GND")
	)
	(via
		(at 460.572612 -14.443964)
		(size 0.5588)
		(drill 0.3048)
		(layers "F.Cu" "B.Cu")
		(net "GND")
	)
	(via
		(at 269.483332 -70.84314)
		(size 0.5588)
		(drill 0.3048)
		(layers "F.Cu" "B.Cu")
		(net "GND")
	)
	(via
		(at 431.98034 -18.616168)
		(size 0.508)
		(drill 0.254)
		(layers "F.Cu" "B.Cu")
		(net "GND")
	)
	(via
		(at 381.4318 -26.2382)
		(size 0.508)
		(drill 0.254)
		(layers "F.Cu" "B.Cu")
		(net "GND")
	)
	(via
		(at 240.763298 -72.43064)
		(size 0.508)
		(drill 0.254)
		(layers "F.Cu" "B.Cu")
		(net "GND")
	)
	(via
		(at 83.923124 -162.243262)
		(size 0.5588)
		(drill 0.3048)
		(layers "F.Cu" "B.Cu")
		(net "GND")
	)
	(via
		(at 139.34948 -129.568956)
		(size 0.508)
		(drill 0.254)
		(layers "F.Cu" "B.Cu")
		(net "GND")
	)
	(via
		(at -0.121666 14.926056)
		(size 0.5588)
		(drill 0.3048)
		(layers "F.Cu" "B.Cu")
		(net "GND")
	)
	(via
		(at 18.062194 -0.294132)
		(size 0.508)
		(drill 0.254)
		(layers "F.Cu" "B.Cu")
		(net "GND")
	)
	(via
		(at 31.39948 -129.568956)
		(size 0.508)
		(drill 0.254)
		(layers "F.Cu" "B.Cu")
		(net "GND")
	)
	(via
		(at 447.2686 -120.0912)
		(size 0.508)
		(drill 0.254)
		(layers "F.Cu" "B.Cu")
		(net "GND")
	)
	(via
		(at 307.040026 -97.001838)
		(size 0.508)
		(drill 0.254)
		(layers "F.Cu" "B.Cu")
		(net "GND")
	)
	(via
		(at 393.730734 -163.361624)
		(size 0.5588)
		(drill 0.3048)
		(layers "F.Cu" "B.Cu")
		(net "GND")
	)
	(via
		(at 305.246786 -82.155284)
		(size 0.508)
		(drill 0.254)
		(layers "F.Cu" "B.Cu")
		(net "GND")
	)
	(via
		(at 305.207924 -162.243262)
		(size 0.5588)
		(drill 0.3048)
		(layers "F.Cu" "B.Cu")
		(net "GND")
	)
	(via
		(at 72.328786 -87.28964)
		(size 0.508)
		(drill 0.254)
		(layers "F.Cu" "B.Cu")
		(net "GND")
	)
	(via
		(at 246.772684 -81.841086)
		(size 0.508)
		(drill 0.254)
		(layers "F.Cu" "B.Cu")
		(net "GND")
	)
	(via
		(at 380.9492 -50.6222)
		(size 0.508)
		(drill 0.254)
		(layers "F.Cu" "B.Cu")
		(net "GND")
	)
	(via
		(at 462.310734 -165.596824)
		(size 0.5588)
		(drill 0.3048)
		(layers "F.Cu" "B.Cu")
		(net "GND")
	)
	(via
		(at 168.9354 -17.4244)
		(size 0.508)
		(drill 0.254)
		(layers "F.Cu" "B.Cu")
		(net "GND")
	)
	(via
		(at 383.962656 -33.935162)
		(size 0.508)
		(drill 0.254)
		(layers "F.Cu" "B.Cu")
		(net "GND")
	)
	(via
		(at 39.049452 -148.771356)
		(size 0.508)
		(drill 0.254)
		(layers "F.Cu" "B.Cu")
		(net "GND")
	)
	(via
		(at 56.899302 -144.462246)
		(size 0.508)
		(drill 0.254)
		(layers "F.Cu" "B.Cu")
		(net "GND")
	)
	(via
		(at 74.045826 -64.50584)
		(size 0.508)
		(drill 0.254)
		(layers "F.Cu" "B.Cu")
		(net "GND")
	)
	(via
		(at 345.9226 -154.4828)
		(size 0.508)
		(drill 0.254)
		(layers "F.Cu" "B.Cu")
		(net "GND")
	)
	(via
		(at 70.611746 -78.37424)
		(size 0.508)
		(drill 0.254)
		(layers "F.Cu" "B.Cu")
		(net "GND")
	)
	(via
		(at 383.0193 -151.7142)
		(size 0.508)
		(drill 0.254)
		(layers "F.Cu" "B.Cu")
		(net "GND")
	)
	(via
		(at 115.041934 14.926056)
		(size 0.5588)
		(drill 0.3048)
		(layers "F.Cu" "B.Cu")
		(net "GND")
	)
	(via
		(at 390.5377 -110.6551)
		(size 0.508)
		(drill 0.254)
		(layers "F.Cu" "B.Cu")
		(net "GND")
	)
	(via
		(at 372.851934 14.926056)
		(size 0.5588)
		(drill 0.3048)
		(layers "F.Cu" "B.Cu")
		(net "GND")
	)
	(via
		(at 445.241934 14.926056)
		(size 0.5588)
		(drill 0.3048)
		(layers "F.Cu" "B.Cu")
		(net "GND")
	)
	(via
		(at 41.359582 -68.256658)
		(size 0.5588)
		(drill 0.3048)
		(layers "F.Cu" "B.Cu")
		(net "GND")
	)
	(via
		(at 74.904346 -93.72854)
		(size 0.508)
		(drill 0.254)
		(layers "F.Cu" "B.Cu")
		(net "GND")
	)
	(via
		(at 34.991802 -95.939864)
		(size 0.508)
		(drill 0.254)
		(layers "F.Cu" "B.Cu")
		(net "GND")
	)
	(via
		(at 418.864542 -9.7028)
		(size 0.508)
		(drill 0.254)
		(layers "F.Cu" "B.Cu")
		(net "GND")
	)
	(via
		(at 129.999486 0.444754)
		(size 0.508)
		(drill 0.254)
		(layers "F.Cu" "B.Cu")
		(net "GND")
	)
	(via
		(at 190.095124 -162.243262)
		(size 0.5588)
		(drill 0.3048)
		(layers "F.Cu" "B.Cu")
		(net "GND")
	)
	(via
		(at 279.019 -4.318)
		(size 0.508)
		(drill 0.254)
		(layers "F.Cu" "B.Cu")
		(net "GND")
	)
	(via
		(at 110.109 -149.8092)
		(size 0.508)
		(drill 0.254)
		(layers "F.Cu" "B.Cu")
		(net "GND")
	)
	(via
		(at 136.74217 -136.397746)
		(size 0.508)
		(drill 0.254)
		(layers "F.Cu" "B.Cu")
		(net "GND")
	)
	(via
		(at 122.1613 -155.55722)
		(size 0.508)
		(drill 0.254)
		(layers "F.Cu" "B.Cu")
		(net "GND")
	)
	(via
		(at 110.717076 -70.850252)
		(size 0.5588)
		(drill 0.3048)
		(layers "F.Cu" "B.Cu")
		(net "GND")
	)
	(via
		(at 196.399912 -155.600146)
		(size 0.508)
		(drill 0.254)
		(layers "F.Cu" "B.Cu")
		(net "GND")
	)
	(via
		(at 304.349912 -146.011646)
		(size 0.508)
		(drill 0.254)
		(layers "F.Cu" "B.Cu")
		(net "GND")
	)
	(via
		(at 51.76139 -11.916156)
		(size 0.508)
		(drill 0.254)
		(layers "F.Cu" "B.Cu")
		(net "GND")
	)
	(via
		(at 50.099468 0.457454)
		(size 0.508)
		(drill 0.254)
		(layers "F.Cu" "B.Cu")
		(net "GND")
	)
	(via
		(at 124.113036 -26.495756)
		(size 0.508)
		(drill 0.254)
		(layers "F.Cu" "B.Cu")
		(net "GND")
	)
	(via
		(at 245.914164 -70.44944)
		(size 0.508)
		(drill 0.254)
		(layers "F.Cu" "B.Cu")
		(net "GND")
	)
	(via
		(at 11.3284 -39.1414)
		(size 0.508)
		(drill 0.254)
		(layers "F.Cu" "B.Cu")
		(net "GND")
	)
	(via
		(at 147.630134 -167.832024)
		(size 0.5588)
		(drill 0.3048)
		(layers "F.Cu" "B.Cu")
		(net "GND")
	)
	(via
		(at 62.792102 -148.767292)
		(size 0.508)
		(drill 0.254)
		(layers "F.Cu" "B.Cu")
		(net "GND")
	)
	(via
		(at 317.09995 -21.528278)
		(size 0.508)
		(drill 0.254)
		(layers "F.Cu" "B.Cu")
		(net "GND")
	)
	(via
		(at 236.171994 -3.762756)
		(size 0.508)
		(drill 0.254)
		(layers "F.Cu" "B.Cu")
		(net "GND")
	)
	(via
		(at 218.449144 -144.0053)
		(size 0.508)
		(drill 0.254)
		(layers "F.Cu" "B.Cu")
		(net "GND")
	)
	(via
		(at 215.799924 -162.243262)
		(size 0.5588)
		(drill 0.3048)
		(layers "F.Cu" "B.Cu")
		(net "GND")
	)
	(via
		(at 255.815338 -140.490194)
		(size 0.508)
		(drill 0.254)
		(layers "F.Cu" "B.Cu")
		(net "GND")
	)
	(via
		(at 466.831934 11.624056)
		(size 0.5588)
		(drill 0.3048)
		(layers "F.Cu" "B.Cu")
		(net "GND")
	)
	(via
		(at 116.208302 -97.014538)
		(size 0.508)
		(drill 0.254)
		(layers "F.Cu" "B.Cu")
		(net "GND")
	)
	(via
		(at 181.081934 14.926056)
		(size 0.5588)
		(drill 0.3048)
		(layers "F.Cu" "B.Cu")
		(net "GND")
	)
	(via
		(at 78.229968 -17.8816)
		(size 0.508)
		(drill 0.254)
		(layers "F.Cu" "B.Cu")
		(net "GND")
	)
	(via
		(at 78.338172 -94.718886)
		(size 0.508)
		(drill 0.254)
		(layers "F.Cu" "B.Cu")
		(net "GND")
	)
	(via
		(at 382.7526 -0.889)
		(size 0.508)
		(drill 0.254)
		(layers "F.Cu" "B.Cu")
		(net "GND")
	)
	(via
		(at 140.246354 -75.221338)
		(size 0.508)
		(drill 0.254)
		(layers "F.Cu" "B.Cu")
		(net "GND")
	)
	(via
		(at 236.470698 -80.850486)
		(size 0.508)
		(drill 0.254)
		(layers "F.Cu" "B.Cu")
		(net "GND")
	)
	(via
		(at 303.038002 -13.948156)
		(size 0.508)
		(drill 0.254)
		(layers "F.Cu" "B.Cu")
		(net "GND")
	)
	(via
		(at 141.963394 -67.296538)
		(size 0.508)
		(drill 0.254)
		(layers "F.Cu" "B.Cu")
		(net "GND")
	)
	(via
		(at 34.736024 -4.2926)
		(size 0.508)
		(drill 0.254)
		(layers "F.Cu" "B.Cu")
		(net "GND")
	)
	(via
		(at 184.4548 -140.9065)
		(size 0.508)
		(drill 0.254)
		(layers "F.Cu" "B.Cu")
		(net "GND")
	)
	(via
		(at 116.495322 -68.363084)
		(size 0.508)
		(drill 0.254)
		(layers "F.Cu" "B.Cu")
		(net "GND")
	)
	(via
		(at 313.699906 -155.612846)
		(size 0.508)
		(drill 0.254)
		(layers "F.Cu" "B.Cu")
		(net "GND")
	)
	(via
		(at 35.615372 -101.641402)
		(size 0.5588)
		(drill 0.3048)
		(layers "F.Cu" "B.Cu")
		(net "GND")
	)
	(via
		(at 112.202722 -88.518238)
		(size 0.508)
		(drill 0.254)
		(layers "F.Cu" "B.Cu")
		(net "GND")
	)
	(via
		(at 214.249762 1.994154)
		(size 0.508)
		(drill 0.254)
		(layers "F.Cu" "B.Cu")
		(net "GND")
	)
	(via
		(at 278.348694 -58.381138)
		(size 0.508)
		(drill 0.254)
		(layers "F.Cu" "B.Cu")
		(net "GND")
	)
	(via
		(at 300.095666 -88.099138)
		(size 0.508)
		(drill 0.254)
		(layers "F.Cu" "B.Cu")
		(net "GND")
	)
	(via
		(at 40.111934 9.084056)
		(size 0.5588)
		(drill 0.3048)
		(layers "F.Cu" "B.Cu")
		(net "GND")
	)
	(via
		(at 41.130982 -94.578678)
		(size 0.5588)
		(drill 0.3048)
		(layers "F.Cu" "B.Cu")
		(net "GND")
	)
	(via
		(at 305.199796 1.994154)
		(size 0.508)
		(drill 0.254)
		(layers "F.Cu" "B.Cu")
		(net "GND")
	)
	(via
		(at 74.982324 -162.243262)
		(size 0.5588)
		(drill 0.3048)
		(layers "F.Cu" "B.Cu")
		(net "GND")
	)
	(via
		(at 360.114342 -95.023178)
		(size 0.508)
		(drill 0.254)
		(layers "F.Cu" "B.Cu")
		(net "GND")
	)
	(via
		(at 430.697132 -123.68403)
		(size 0.508)
		(drill 0.254)
		(layers "F.Cu" "B.Cu")
		(net "GND")
	)
	(via
		(at 232.099866 -148.771356)
		(size 0.508)
		(drill 0.254)
		(layers "F.Cu" "B.Cu")
		(net "GND")
	)
	(via
		(at 378.695966 -128.804416)
		(size 0.508)
		(drill 0.254)
		(layers "F.Cu" "B.Cu")
		(net "GND")
	)
	(via
		(at 408.290522 -101.256846)
		(size 0.508)
		(drill 0.254)
		(layers "F.Cu" "B.Cu")
		(net "GND")
	)
	(via
		(at 84.347812 -90.26144)
		(size 0.508)
		(drill 0.254)
		(layers "F.Cu" "B.Cu")
		(net "GND")
	)
	(via
		(at 97.225358 -63.019686)
		(size 0.508)
		(drill 0.254)
		(layers "F.Cu" "B.Cu")
		(net "GND")
	)
	(via
		(at 485.50576 -32.72536)
		(size 0.508)
		(drill 0.254)
		(layers "F.Cu" "B.Cu")
		(net "GND")
	)
	(via
		(at 86.064852 -71.44004)
		(size 0.508)
		(drill 0.254)
		(layers "F.Cu" "B.Cu")
		(net "GND")
	)
	(via
		(at 279.207214 -63.829184)
		(size 0.508)
		(drill 0.254)
		(layers "F.Cu" "B.Cu")
		(net "GND")
	)
	(via
		(at 125.749558 -18.757646)
		(size 0.508)
		(drill 0.254)
		(layers "F.Cu" "B.Cu")
		(net "GND")
	)
	(via
		(at 238.187738 -87.784686)
		(size 0.508)
		(drill 0.254)
		(layers "F.Cu" "B.Cu")
		(net "GND")
	)
	(via
		(at 467.2076 -114.41176)
		(size 0.508)
		(drill 0.254)
		(layers "F.Cu" "B.Cu")
		(net "GND")
	)
	(via
		(at 371.5258 -56.3118)
		(size 0.508)
		(drill 0.254)
		(layers "F.Cu" "B.Cu")
		(net "GND")
	)
	(via
		(at 368.429032 -0.700024)
		(size 0.508)
		(drill 0.254)
		(layers "F.Cu" "B.Cu")
		(net "GND")
	)
	(via
		(at 475.721934 11.624056)
		(size 0.5588)
		(drill 0.3048)
		(layers "F.Cu" "B.Cu")
		(net "GND")
	)
	(via
		(at 416.289998 -34.934652)
		(size 0.4572)
		(drill 0.2032)
		(layers "F.Cu" "B.Cu")
		(net "GND")
	)
	(via
		(at 396.270734 -163.361624)
		(size 0.5588)
		(drill 0.3048)
		(layers "F.Cu" "B.Cu")
		(net "GND")
	)
	(via
		(at 365.791496 -42.20972)
		(size 0.508)
		(drill 0.254)
		(layers "F.Cu" "B.Cu")
		(net "GND")
	)
	(via
		(at 69.394324 -162.243262)
		(size 0.5588)
		(drill 0.3048)
		(layers "F.Cu" "B.Cu")
		(net "GND")
	)
	(via
		(at 461.040734 -163.361624)
		(size 0.5588)
		(drill 0.3048)
		(layers "F.Cu" "B.Cu")
		(net "GND")
	)
	(via
		(at 345.567 -145.0086)
		(size 0.508)
		(drill 0.254)
		(layers "F.Cu" "B.Cu")
		(net "GND")
	)
	(via
		(at 82.630772 -57.57164)
		(size 0.508)
		(drill 0.254)
		(layers "F.Cu" "B.Cu")
		(net "GND")
	)
	(via
		(at 28.681934 9.084056)
		(size 0.5588)
		(drill 0.3048)
		(layers "F.Cu" "B.Cu")
		(net "GND")
	)
	(via
		(at 362.691934 9.084056)
		(size 0.5588)
		(drill 0.3048)
		(layers "F.Cu" "B.Cu")
		(net "GND")
	)
	(via
		(at 305.246786 -89.089738)
		(size 0.508)
		(drill 0.254)
		(layers "F.Cu" "B.Cu")
		(net "GND")
	)
	(via
		(at 267.578586 -70.84314)
		(size 0.5588)
		(drill 0.3048)
		(layers "F.Cu" "B.Cu")
		(net "GND")
	)
	(via
		(at 209.08645 -23.495)
		(size 0.508)
		(drill 0.254)
		(layers "F.Cu" "B.Cu")
		(net "GND")
	)
	(via
		(at 428.020734 -166.714424)
		(size 0.5588)
		(drill 0.3048)
		(layers "F.Cu" "B.Cu")
		(net "GND")
	)
	(via
		(at 386.541518 -84.057998)
		(size 0.508)
		(drill 0.254)
		(layers "F.Cu" "B.Cu")
		(net "GND")
	)
	(via
		(at 291.422074 -144.5006)
		(size 0.508)
		(drill 0.254)
		(layers "F.Cu" "B.Cu")
		(net "GND")
	)
	(via
		(at 201.137266 -84.530692)
		(size 0.5588)
		(drill 0.3048)
		(layers "F.Cu" "B.Cu")
		(net "GND")
	)
	(via
		(at 125.651768 -59.866784)
		(size 0.508)
		(drill 0.254)
		(layers "F.Cu" "B.Cu")
		(net "GND")
	)
	(via
		(at 83.773772 -54.599332)
		(size 0.508)
		(drill 0.254)
		(layers "F.Cu" "B.Cu")
		(net "GND")
	)
	(via
		(at 181.7497 -40.35552)
		(size 0.508)
		(drill 0.254)
		(layers "F.Cu" "B.Cu")
		(net "GND")
	)
	(via
		(at 477.546924 -162.243262)
		(size 0.5588)
		(drill 0.3048)
		(layers "F.Cu" "B.Cu")
		(net "GND")
	)
	(via
		(at 387.731 -126.662434)
		(size 0.508)
		(drill 0.254)
		(layers "F.Cu" "B.Cu")
		(net "GND")
	)
	(via
		(at 345.043506 -142.229586)
		(size 0.508)
		(drill 0.254)
		(layers "F.Cu" "B.Cu")
		(net "GND")
	)
	(via
		(at 0.07112 -133.1849)
		(size 0.508)
		(drill 0.254)
		(layers "F.Cu" "B.Cu")
		(net "GND")
	)
	(via
		(at 280.472134 -75.106784)
		(size 0.5588)
		(drill 0.3048)
		(layers "F.Cu" "B.Cu")
		(net "GND")
	)
	(via
		(at 181.25948 -14.80058)
		(size 0.508)
		(drill 0.254)
		(layers "F.Cu" "B.Cu")
		(net "GND")
	)
	(via
		(at 469.392 -14.351)
		(size 0.508)
		(drill 0.254)
		(layers "F.Cu" "B.Cu")
		(net "GND")
	)
	(via
		(at 121.499376 -134.861046)
		(size 0.508)
		(drill 0.254)
		(layers "F.Cu" "B.Cu")
		(net "GND")
	)
	(via
		(at 114.102134 -167.832024)
		(size 0.5588)
		(drill 0.3048)
		(layers "F.Cu" "B.Cu")
		(net "GND")
	)
	(via
		(at 196.804534 -167.832024)
		(size 0.5588)
		(drill 0.3048)
		(layers "F.Cu" "B.Cu")
		(net "GND")
	)
	(via
		(at 471.911934 9.084056)
		(size 0.5588)
		(drill 0.3048)
		(layers "F.Cu" "B.Cu")
		(net "GND")
	)
	(via
		(at 276.331934 9.084056)
		(size 0.5588)
		(drill 0.3048)
		(layers "F.Cu" "B.Cu")
		(net "GND")
	)
	(via
		(at 385.7752 -151.6888)
		(size 0.508)
		(drill 0.254)
		(layers "F.Cu" "B.Cu")
		(net "GND")
	)
	(via
		(at 170.671744 -94.023434)
		(size 0.508)
		(drill 0.254)
		(layers "F.Cu" "B.Cu")
		(net "GND")
	)
	(via
		(at 70.611746 -74.411586)
		(size 0.508)
		(drill 0.254)
		(layers "F.Cu" "B.Cu")
		(net "GND")
	)
	(via
		(at 67.159124 -162.243262)
		(size 0.5588)
		(drill 0.3048)
		(layers "F.Cu" "B.Cu")
		(net "GND")
	)
	(via
		(at 221.899734 -13.363956)
		(size 0.508)
		(drill 0.254)
		(layers "F.Cu" "B.Cu")
		(net "GND")
	)
	(via
		(at 123.931934 14.926056)
		(size 0.5588)
		(drill 0.3048)
		(layers "F.Cu" "B.Cu")
		(net "GND")
	)
	(via
		(at 299.237146 -61.847984)
		(size 0.508)
		(drill 0.254)
		(layers "F.Cu" "B.Cu")
		(net "GND")
	)
	(via
		(at 40.340534 -167.832024)
		(size 0.5588)
		(drill 0.3048)
		(layers "F.Cu" "B.Cu")
		(net "GND")
	)
	(via
		(at 390.737598 -152.678638)
		(size 0.508)
		(drill 0.254)
		(layers "F.Cu" "B.Cu")
		(net "GND")
	)
	(via
		(at -3.577336 -58.98261)
		(size 0.5588)
		(drill 0.3048)
		(layers "F.Cu" "B.Cu")
		(net "GND")
	)
	(via
		(at 401.179538 1.702308)
		(size 0.508)
		(drill 0.254)
		(layers "F.Cu" "B.Cu")
		(net "GND")
	)
	(via
		(at 375.391934 14.926056)
		(size 0.5588)
		(drill 0.3048)
		(layers "F.Cu" "B.Cu")
		(net "GND")
	)
	(via
		(at 121.499376 -154.063446)
		(size 0.508)
		(drill 0.254)
		(layers "F.Cu" "B.Cu")
		(net "GND")
	)
	(via
		(at 430.560734 -164.479224)
		(size 0.5588)
		(drill 0.3048)
		(layers "F.Cu" "B.Cu")
		(net "GND")
	)
	(via
		(at 140.199364 -22.965156)
		(size 0.508)
		(drill 0.254)
		(layers "F.Cu" "B.Cu")
		(net "GND")
	)
	(via
		(at 452.150734 -167.832024)
		(size 0.5588)
		(drill 0.3048)
		(layers "F.Cu" "B.Cu")
		(net "GND")
	)
	(via
		(at 70.611746 -64.50584)
		(size 0.508)
		(drill 0.254)
		(layers "F.Cu" "B.Cu")
		(net "GND")
	)
	(via
		(at 488.5944 -145.3642)
		(size 0.508)
		(drill 0.254)
		(layers "F.Cu" "B.Cu")
		(net "GND")
	)
	(via
		(at 483.900734 -163.361624)
		(size 0.5588)
		(drill 0.3048)
		(layers "F.Cu" "B.Cu")
		(net "GND")
	)
	(via
		(at 370.6368 -115.3414)
		(size 0.508)
		(drill 0.254)
		(layers "F.Cu" "B.Cu")
		(net "GND")
	)
	(via
		(at 196.399912 -18.744946)
		(size 0.508)
		(drill 0.254)
		(layers "F.Cu" "B.Cu")
		(net "GND")
	)
	(via
		(at 344.9066 -7.6708)
		(size 0.508)
		(drill 0.254)
		(layers "F.Cu" "B.Cu")
		(net "GND")
	)
	(via
		(at 99.744276 -75.159616)
		(size 0.5588)
		(drill 0.3048)
		(layers "F.Cu" "B.Cu")
		(net "GND")
	)
	(via
		(at 376.861324 -162.268662)
		(size 0.5588)
		(drill 0.3048)
		(layers "F.Cu" "B.Cu")
		(net "GND")
	)
	(via
		(at 171.829476 -29.70276)
		(size 0.508)
		(drill 0.254)
		(layers "F.Cu" "B.Cu")
		(net "GND")
	)
	(via
		(at 376.705622 -33.222184)
		(size 0.508)
		(drill 0.254)
		(layers "F.Cu" "B.Cu")
		(net "GND")
	)
	(via
		(at 137.670794 -60.857384)
		(size 0.508)
		(drill 0.254)
		(layers "F.Cu" "B.Cu")
		(net "GND")
	)
	(via
		(at 417.100004 -90.905076)
		(size 0.508)
		(drill 0.254)
		(layers "F.Cu" "B.Cu")
		(net "GND")
	)
	(via
		(at 71.470266 -87.784686)
		(size 0.508)
		(drill 0.254)
		(layers "F.Cu" "B.Cu")
		(net "GND")
	)
	(via
		(at 178.943 -74.6252)
		(size 0.508)
		(drill 0.254)
		(layers "F.Cu" "B.Cu")
		(net "GND")
	)
	(via
		(at 420.1414 -156.41066)
		(size 0.508)
		(drill 0.254)
		(layers "F.Cu" "B.Cu")
		(net "GND")
	)
	(via
		(at 199.992234 -55.299864)
		(size 0.508)
		(drill 0.254)
		(layers "F.Cu" "B.Cu")
		(net "GND")
	)
	(via
		(at 76.449428 -11.916156)
		(size 0.508)
		(drill 0.254)
		(layers "F.Cu" "B.Cu")
		(net "GND")
	)
	(via
		(at 278.385524 -162.243262)
		(size 0.5588)
		(drill 0.3048)
		(layers "F.Cu" "B.Cu")
		(net "GND")
	)
	(via
		(at 54.74081 -7.095744)
		(size 0.508)
		(drill 0.254)
		(layers "F.Cu" "B.Cu")
		(net "GND")
	)
	(via
		(at 262.22579 -56.085486)
		(size 0.508)
		(drill 0.254)
		(layers "F.Cu" "B.Cu")
		(net "GND")
	)
	(via
		(at 271.480788 -60.362338)
		(size 0.508)
		(drill 0.254)
		(layers "F.Cu" "B.Cu")
		(net "GND")
	)
	(via
		(at 459.770734 -167.832024)
		(size 0.5588)
		(drill 0.3048)
		(layers "F.Cu" "B.Cu")
		(net "GND")
	)
	(via
		(at 195.549774 -131.5466)
		(size 0.508)
		(drill 0.254)
		(layers "F.Cu" "B.Cu")
		(net "GND")
	)
	(via
		(at 80.913732 -70.44944)
		(size 0.508)
		(drill 0.254)
		(layers "F.Cu" "B.Cu")
		(net "GND")
	)
	(via
		(at 339.1154 -36.83)
		(size 0.508)
		(drill 0.254)
		(layers "F.Cu" "B.Cu")
		(net "GND")
	)
	(via
		(at 178.541934 9.084056)
		(size 0.5588)
		(drill 0.3048)
		(layers "F.Cu" "B.Cu")
		(net "GND")
	)
	(via
		(at 255.35763 -53.113686)
		(size 0.508)
		(drill 0.254)
		(layers "F.Cu" "B.Cu")
		(net "GND")
	)
	(via
		(at 96.5708 0.3048)
		(size 0.508)
		(drill 0.254)
		(layers "F.Cu" "B.Cu")
		(net "GND")
	)
	(via
		(at 307.749956 -155.600146)
		(size 0.508)
		(drill 0.254)
		(layers "F.Cu" "B.Cu")
		(net "GND")
	)
	(via
		(at 241.44986 0.444754)
		(size 0.508)
		(drill 0.254)
		(layers "F.Cu" "B.Cu")
		(net "GND")
	)
	(via
		(at 354.887022 -28.600908)
		(size 0.508)
		(drill 0.254)
		(layers "F.Cu" "B.Cu")
		(net "GND")
	)
	(via
		(at 138.03757 -4.346956)
		(size 0.508)
		(drill 0.254)
		(layers "F.Cu" "B.Cu")
		(net "GND")
	)
	(via
		(at 392.19505 -100.181156)
		(size 0.508)
		(drill 0.254)
		(layers "F.Cu" "B.Cu")
		(net "GND")
	)
	(via
		(at 452.146924 -162.243262)
		(size 0.5588)
		(drill 0.3048)
		(layers "F.Cu" "B.Cu")
		(net "GND")
	)
	(via
		(at 206.245714 -77.154278)
		(size 0.5588)
		(drill 0.3048)
		(layers "F.Cu" "B.Cu")
		(net "GND")
	)
	(via
		(at 96.213168 -1.651)
		(size 0.508)
		(drill 0.254)
		(layers "F.Cu" "B.Cu")
		(net "GND")
	)
	(via
		(at 239.904778 -57.076086)
		(size 0.508)
		(drill 0.254)
		(layers "F.Cu" "B.Cu")
		(net "GND")
	)
	(via
		(at 338.588604 -143.824198)
		(size 0.508)
		(drill 0.254)
		(layers "F.Cu" "B.Cu")
		(net "GND")
	)
	(via
		(at 207.642714 -70.321678)
		(size 0.5588)
		(drill 0.3048)
		(layers "F.Cu" "B.Cu")
		(net "GND")
	)
	(via
		(at 392.43 -150.1394)
		(size 0.508)
		(drill 0.254)
		(layers "F.Cu" "B.Cu")
		(net "GND")
	)
	(via
		(at 221.04985 -18.757646)
		(size 0.508)
		(drill 0.254)
		(layers "F.Cu" "B.Cu")
		(net "GND")
	)
	(via
		(at 296.66184 -100.976938)
		(size 0.508)
		(drill 0.254)
		(layers "F.Cu" "B.Cu")
		(net "GND")
	)
	(via
		(at 241.621818 -80.850486)
		(size 0.508)
		(drill 0.254)
		(layers "F.Cu" "B.Cu")
		(net "GND")
	)
	(via
		(at 345.5162 -96.7994)
		(size 0.508)
		(drill 0.254)
		(layers "F.Cu" "B.Cu")
		(net "GND")
	)
	(via
		(at 187.11037 -9.786874)
		(size 0.508)
		(drill 0.254)
		(layers "F.Cu" "B.Cu")
		(net "GND")
	)
	(via
		(at 129.085848 -73.735184)
		(size 0.508)
		(drill 0.254)
		(layers "F.Cu" "B.Cu")
		(net "GND")
	)
	(via
		(at 314.2996 -26.1874)
		(size 0.508)
		(drill 0.254)
		(layers "F.Cu" "B.Cu")
		(net "GND")
	)
	(via
		(at 42.58818 -97.534222)
		(size 0.5588)
		(drill 0.3048)
		(layers "F.Cu" "B.Cu")
		(net "GND")
	)
	(via
		(at 374.593104 -145.36801)
		(size 0.508)
		(drill 0.254)
		(layers "F.Cu" "B.Cu")
		(net "GND")
	)
	(via
		(at 229.094538 -9.0805)
		(size 0.508)
		(drill 0.254)
		(layers "F.Cu" "B.Cu")
		(net "GND")
	)
	(via
		(at 289.79368 -98.005138)
		(size 0.508)
		(drill 0.254)
		(layers "F.Cu" "B.Cu")
		(net "GND")
	)
	(via
		(at 480.801934 10.354056)
		(size 0.5588)
		(drill 0.3048)
		(layers "F.Cu" "B.Cu")
		(net "GND")
	)
	(via
		(at 307.749956 -139.170156)
		(size 0.508)
		(drill 0.254)
		(layers "F.Cu" "B.Cu")
		(net "GND")
	)
	(via
		(at 110.111032 -145.0086)
		(size 0.508)
		(drill 0.254)
		(layers "F.Cu" "B.Cu")
		(net "GND")
	)
	(via
		(at 239.046258 -66.48704)
		(size 0.508)
		(drill 0.254)
		(layers "F.Cu" "B.Cu")
		(net "GND")
	)
	(via
		(at 133.378194 -64.324738)
		(size 0.508)
		(drill 0.254)
		(layers "F.Cu" "B.Cu")
		(net "GND")
	)
	(via
		(at 167.1066 -31.4071)
		(size 0.508)
		(drill 0.254)
		(layers "F.Cu" "B.Cu")
		(net "GND")
	)
	(via
		(at 250.206764 -91.747086)
		(size 0.508)
		(drill 0.254)
		(layers "F.Cu" "B.Cu")
		(net "GND")
	)
	(via
		(at 157.688534 -167.832024)
		(size 0.5588)
		(drill 0.3048)
		(layers "F.Cu" "B.Cu")
		(net "GND")
	)
	(via
		(at 52.471574 -3.762756)
		(size 0.508)
		(drill 0.254)
		(layers "F.Cu" "B.Cu")
		(net "GND")
	)
	(via
		(at 109.627924 -162.243262)
		(size 0.5588)
		(drill 0.3048)
		(layers "F.Cu" "B.Cu")
		(net "GND")
	)
	(via
		(at 171.6024 -38.1)
		(size 0.508)
		(drill 0.254)
		(layers "F.Cu" "B.Cu")
		(net "GND")
	)
	(via
		(at 341.531702 -140.684504)
		(size 0.508)
		(drill 0.254)
		(layers "F.Cu" "B.Cu")
		(net "GND")
	)
	(via
		(at 345.1352 -77.1398)
		(size 0.508)
		(drill 0.254)
		(layers "F.Cu" "B.Cu")
		(net "GND")
	)
	(via
		(at 385.551934 9.084056)
		(size 0.5588)
		(drill 0.3048)
		(layers "F.Cu" "B.Cu")
		(net "GND")
	)
	(via
		(at 460.481934 11.624056)
		(size 0.5588)
		(drill 0.3048)
		(layers "F.Cu" "B.Cu")
		(net "GND")
	)
	(via
		(at 415.671 -1.1684)
		(size 0.508)
		(drill 0.254)
		(layers "F.Cu" "B.Cu")
		(net "GND")
	)
	(via
		(at 384.1496 -131.83108)
		(size 0.508)
		(drill 0.254)
		(layers "F.Cu" "B.Cu")
		(net "GND")
	)
	(via
		(at 274.340828 -90.080338)
		(size 0.508)
		(drill 0.254)
		(layers "F.Cu" "B.Cu")
		(net "GND")
	)
	(via
		(at 217.472006 -150.219156)
		(size 0.508)
		(drill 0.254)
		(layers "F.Cu" "B.Cu")
		(net "GND")
	)
	(via
		(at 17.9324 -93.5736)
		(size 0.508)
		(drill 0.254)
		(layers "F.Cu" "B.Cu")
		(net "GND")
	)
	(via
		(at 280.451814 -144.462246)
		(size 0.508)
		(drill 0.254)
		(layers "F.Cu" "B.Cu")
		(net "GND")
	)
	(via
		(at 160.0708 -63.0174)
		(size 0.508)
		(drill 0.254)
		(layers "F.Cu" "B.Cu")
		(net "GND")
	)
	(via
		(at 142.039594 -81.164938)
		(size 0.508)
		(drill 0.254)
		(layers "F.Cu" "B.Cu")
		(net "GND")
	)
	(via
		(at 5.694934 -165.596824)
		(size 0.5588)
		(drill 0.3048)
		(layers "F.Cu" "B.Cu")
		(net "GND")
	)
	(via
		(at 46.699424 -146.011646)
		(size 0.508)
		(drill 0.254)
		(layers "F.Cu" "B.Cu")
		(net "GND")
	)
	(via
		(at 385.157218 -155.686506)
		(size 0.508)
		(drill 0.254)
		(layers "F.Cu" "B.Cu")
		(net "GND")
	)
	(via
		(at 197.151752 -154.063446)
		(size 0.508)
		(drill 0.254)
		(layers "F.Cu" "B.Cu")
		(net "GND")
	)
	(via
		(at 378.344684 -68.695316)
		(size 0.4572)
		(drill 0.2032)
		(layers "F.Cu" "B.Cu")
		(net "GND")
	)
	(via
		(at 376.889772 -109.371638)
		(size 0.508)
		(drill 0.254)
		(layers "F.Cu" "B.Cu")
		(net "GND")
	)
	(via
		(at 225.201734 -144.462246)
		(size 0.508)
		(drill 0.254)
		(layers "F.Cu" "B.Cu")
		(net "GND")
	)
	(via
		(at 482.19995 -115.423188)
		(size 0.508)
		(drill 0.254)
		(layers "F.Cu" "B.Cu")
		(net "GND")
	)
	(via
		(at 460.464408 -151.485854)
		(size 0.508)
		(drill 0.254)
		(layers "F.Cu" "B.Cu")
		(net "GND")
	)
	(via
		(at 304.349912 -129.568956)
		(size 0.508)
		(drill 0.254)
		(layers "F.Cu" "B.Cu")
		(net "GND")
	)
	(via
		(at 110.717076 -82.339942)
		(size 0.5588)
		(drill 0.3048)
		(layers "F.Cu" "B.Cu")
		(net "GND")
	)
	(via
		(at 135.953754 -65.810384)
		(size 0.508)
		(drill 0.254)
		(layers "F.Cu" "B.Cu")
		(net "GND")
	)
	(via
		(at 222.991934 9.084056)
		(size 0.5588)
		(drill 0.3048)
		(layers "F.Cu" "B.Cu")
		(net "GND")
	)
	(via
		(at 207.502252 -82.267552)
		(size 0.5588)
		(drill 0.3048)
		(layers "F.Cu" "B.Cu")
		(net "GND")
	)
	(via
		(at 371.9068 -58.7756)
		(size 0.508)
		(drill 0.254)
		(layers "F.Cu" "B.Cu")
		(net "GND")
	)
	(via
		(at 57.100724 -162.243262)
		(size 0.5588)
		(drill 0.3048)
		(layers "F.Cu" "B.Cu")
		(net "GND")
	)
	(via
		(at 302.671226 -74.725784)
		(size 0.508)
		(drill 0.254)
		(layers "F.Cu" "B.Cu")
		(net "GND")
	)
	(via
		(at 272.027904 -8.1534)
		(size 0.508)
		(drill 0.254)
		(layers "F.Cu" "B.Cu")
		(net "GND")
	)
	(via
		(at 283.784294 -103.453184)
		(size 0.508)
		(drill 0.254)
		(layers "F.Cu" "B.Cu")
		(net "GND")
	)
	(via
		(at 123.650248 -60.362338)
		(size 0.508)
		(drill 0.254)
		(layers "F.Cu" "B.Cu")
		(net "GND")
	)
	(via
		(at 432.438302 -20.29079)
		(size 0.508)
		(drill 0.254)
		(layers "F.Cu" "B.Cu")
		(net "GND")
	)
	(via
		(at 5.68452 -23.53818)
		(size 0.508)
		(drill 0.254)
		(layers "F.Cu" "B.Cu")
		(net "GND")
	)
	(via
		(at 484.1748 -154.3812)
		(size 0.508)
		(drill 0.254)
		(layers "F.Cu" "B.Cu")
		(net "GND")
	)
	(via
		(at 394.3096 -154.3304)
		(size 0.508)
		(drill 0.254)
		(layers "F.Cu" "B.Cu")
		(net "GND")
	)
	(via
		(at 179.61102 -78.7781)
		(size 0.508)
		(drill 0.254)
		(layers "F.Cu" "B.Cu")
		(net "GND")
	)
	(via
		(at 334.43545 -127.249682)
		(size 0.508)
		(drill 0.254)
		(layers "F.Cu" "B.Cu")
		(net "GND")
	)
	(via
		(at 227.799138 -153.6065)
		(size 0.508)
		(drill 0.254)
		(layers "F.Cu" "B.Cu")
		(net "GND")
	)
	(via
		(at 151.24938 -154.063446)
		(size 0.508)
		(drill 0.254)
		(layers "F.Cu" "B.Cu")
		(net "GND")
	)
	(via
		(at 289.79368 -96.023938)
		(size 0.508)
		(drill 0.254)
		(layers "F.Cu" "B.Cu")
		(net "GND")
	)
	(via
		(at 68.799456 -129.568956)
		(size 0.508)
		(drill 0.254)
		(layers "F.Cu" "B.Cu")
		(net "GND")
	)
	(via
		(at 476.280734 -163.361624)
		(size 0.5588)
		(drill 0.3048)
		(layers "F.Cu" "B.Cu")
		(net "GND")
	)
	(via
		(at 139.34948 -139.170156)
		(size 0.508)
		(drill 0.254)
		(layers "F.Cu" "B.Cu")
		(net "GND")
	)
	(via
		(at 171.6024 -36.8046)
		(size 0.508)
		(drill 0.254)
		(layers "F.Cu" "B.Cu")
		(net "GND")
	)
	(via
		(at 61.111384 -148.771356)
		(size 0.508)
		(drill 0.254)
		(layers "F.Cu" "B.Cu")
		(net "GND")
	)
	(via
		(at 358.881934 9.084056)
		(size 0.5588)
		(drill 0.3048)
		(layers "F.Cu" "B.Cu")
		(net "GND")
	)
	(via
		(at 405.426672 -95.28429)
		(size 0.508)
		(drill 0.254)
		(layers "F.Cu" "B.Cu")
		(net "GND")
	)
	(via
		(at 114.491262 -100.976938)
		(size 0.508)
		(drill 0.254)
		(layers "F.Cu" "B.Cu")
		(net "GND")
	)
	(via
		(at 62.798706 -26.73731)
		(size 0.508)
		(drill 0.254)
		(layers "F.Cu" "B.Cu")
		(net "GND")
	)
	(via
		(at 202.349862 -129.568956)
		(size 0.508)
		(drill 0.254)
		(layers "F.Cu" "B.Cu")
		(net "GND")
	)
	(via
		(at 261.744206 -69.567806)
		(size 0.5588)
		(drill 0.3048)
		(layers "F.Cu" "B.Cu")
		(net "GND")
	)
	(via
		(at 283.499814 -62.343538)
		(size 0.508)
		(drill 0.254)
		(layers "F.Cu" "B.Cu")
		(net "GND")
	)
	(via
		(at 246.772684 -65.000886)
		(size 0.508)
		(drill 0.254)
		(layers "F.Cu" "B.Cu")
		(net "GND")
	)
	(via
		(at 312.387996 -141.202156)
		(size 0.508)
		(drill 0.254)
		(layers "F.Cu" "B.Cu")
		(net "GND")
	)
	(via
		(at 490.146594 -39.562786)
		(size 0.508)
		(drill 0.254)
		(layers "F.Cu" "B.Cu")
		(net "GND")
	)
	(via
		(at 346.370402 -137.173208)
		(size 0.508)
		(drill 0.254)
		(layers "F.Cu" "B.Cu")
		(net "GND")
	)
	(via
		(at 281.494992 -50.951384)
		(size 0.4572)
		(drill 0.2032)
		(layers "F.Cu" "B.Cu")
		(net "GND")
	)
	(via
		(at 50.851308 -144.462246)
		(size 0.508)
		(drill 0.254)
		(layers "F.Cu" "B.Cu")
		(net "GND")
	)
	(via
		(at 186.469274 -9.174988)
		(size 0.508)
		(drill 0.254)
		(layers "F.Cu" "B.Cu")
		(net "GND")
	)
	(via
		(at 122.217688 -99.490784)
		(size 0.508)
		(drill 0.254)
		(layers "F.Cu" "B.Cu")
		(net "GND")
	)
	(via
		(at 85.040724 -162.243262)
		(size 0.5588)
		(drill 0.3048)
		(layers "F.Cu" "B.Cu")
		(net "GND")
	)
	(via
		(at 492.231934 9.084056)
		(size 0.5588)
		(drill 0.3048)
		(layers "F.Cu" "B.Cu")
		(net "GND")
	)
	(via
		(at 182.271924 -162.243262)
		(size 0.5588)
		(drill 0.3048)
		(layers "F.Cu" "B.Cu")
		(net "GND")
	)
	(via
		(at 410.240734 -164.479224)
		(size 0.5588)
		(drill 0.3048)
		(layers "F.Cu" "B.Cu")
		(net "GND")
	)
	(via
		(at 367.2205 -136.906)
		(size 0.508)
		(drill 0.254)
		(layers "F.Cu" "B.Cu")
		(net "GND")
	)
	(via
		(at 117.071648 -154.1018)
		(size 0.508)
		(drill 0.254)
		(layers "F.Cu" "B.Cu")
		(net "GND")
	)
	(via
		(at 78.338172 -62.029086)
		(size 0.508)
		(drill 0.254)
		(layers "F.Cu" "B.Cu")
		(net "GND")
	)
	(via
		(at 298.378626 -97.014538)
		(size 0.508)
		(drill 0.254)
		(layers "F.Cu" "B.Cu")
		(net "GND")
	)
	(via
		(at 371.98935 -106.683556)
		(size 0.508)
		(drill 0.254)
		(layers "F.Cu" "B.Cu")
		(net "GND")
	)
	(via
		(at 499.124478 -44.817538)
		(size 0.508)
		(drill 0.254)
		(layers "F.Cu" "B.Cu")
		(net "GND")
	)
	(via
		(at 409.885134 -150.45055)
		(size 0.508)
		(drill 0.254)
		(layers "F.Cu" "B.Cu")
		(net "GND")
	)
	(via
		(at 380.9746 -145.796)
		(size 0.508)
		(drill 0.254)
		(layers "F.Cu" "B.Cu")
		(net "GND")
	)
	(via
		(at 275.336762 -135.357616)
		(size 0.508)
		(drill 0.254)
		(layers "F.Cu" "B.Cu")
		(net "GND")
	)
	(via
		(at 268.679168 -140.208)
		(size 0.508)
		(drill 0.254)
		(layers "F.Cu" "B.Cu")
		(net "GND")
	)
	(via
		(at 80.913732 -61.53404)
		(size 0.508)
		(drill 0.254)
		(layers "F.Cu" "B.Cu")
		(net "GND")
	)
	(via
		(at 152.099518 -18.757646)
		(size 0.508)
		(drill 0.254)
		(layers "F.Cu" "B.Cu")
		(net "GND")
	)
	(via
		(at 295.381934 9.084056)
		(size 0.5588)
		(drill 0.3048)
		(layers "F.Cu" "B.Cu")
		(net "GND")
	)
	(via
		(at 168.8338 -36.2712)
		(size 0.508)
		(drill 0.254)
		(layers "F.Cu" "B.Cu")
		(net "GND")
	)
	(via
		(at 207.411828 -18.757646)
		(size 0.508)
		(drill 0.254)
		(layers "F.Cu" "B.Cu")
		(net "GND")
	)
	(via
		(at 276.057614 -95.033084)
		(size 0.508)
		(drill 0.254)
		(layers "F.Cu" "B.Cu")
		(net "GND")
	)
	(via
		(at 276.057614 -90.080338)
		(size 0.508)
		(drill 0.254)
		(layers "F.Cu" "B.Cu")
		(net "GND")
	)
	(via
		(at 299.191934 14.926056)
		(size 0.5588)
		(drill 0.3048)
		(layers "F.Cu" "B.Cu")
		(net "GND")
	)
	(via
		(at 54.737508 -150.803356)
		(size 0.508)
		(drill 0.254)
		(layers "F.Cu" "B.Cu")
		(net "GND")
	)
	(via
		(at 138.02741 -9.0932)
		(size 0.508)
		(drill 0.254)
		(layers "F.Cu" "B.Cu")
		(net "GND")
	)
	(via
		(at 151.24938 -3.762756)
		(size 0.508)
		(drill 0.254)
		(layers "F.Cu" "B.Cu")
		(net "GND")
	)
	(via
		(at 48.399446 -146.011646)
		(size 0.508)
		(drill 0.254)
		(layers "F.Cu" "B.Cu")
		(net "GND")
	)
	(via
		(at 469.371934 9.084056)
		(size 0.5588)
		(drill 0.3048)
		(layers "F.Cu" "B.Cu")
		(net "GND")
	)
	(via
		(at 476.933514 -157.523688)
		(size 0.5588)
		(drill 0.3048)
		(layers "F.Cu" "B.Cu")
		(net "GND")
	)
	(via
		(at 173.0502 -24.16302)
		(size 0.508)
		(drill 0.254)
		(layers "F.Cu" "B.Cu")
		(net "GND")
	)
	(via
		(at 306.181506 -75.716384)
		(size 0.508)
		(drill 0.254)
		(layers "F.Cu" "B.Cu")
		(net "GND")
	)
	(via
		(at 292.3794 -13.8938)
		(size 0.508)
		(drill 0.254)
		(layers "F.Cu" "B.Cu")
		(net "GND")
	)
	(via
		(at 116.311934 9.084056)
		(size 0.5588)
		(drill 0.3048)
		(layers "F.Cu" "B.Cu")
		(net "GND")
	)
	(via
		(at 30.1752 -75.7936)
		(size 0.508)
		(drill 0.254)
		(layers "F.Cu" "B.Cu")
		(net "GND")
	)
	(via
		(at 72.328786 -80.35544)
		(size 0.508)
		(drill 0.254)
		(layers "F.Cu" "B.Cu")
		(net "GND")
	)
	(via
		(at 451.79996 -113.8174)
		(size 0.508)
		(drill 0.254)
		(layers "F.Cu" "B.Cu")
		(net "GND")
	)
	(via
		(at 176.15662 -66.35496)
		(size 0.508)
		(drill 0.254)
		(layers "F.Cu" "B.Cu")
		(net "GND")
	)
	(via
		(at 97.261934 9.084056)
		(size 0.5588)
		(drill 0.3048)
		(layers "F.Cu" "B.Cu")
		(net "GND")
	)
	(via
		(at 439.615072 -3.381502)
		(size 0.508)
		(drill 0.254)
		(layers "F.Cu" "B.Cu")
		(net "GND")
	)
	(via
		(at 339.46592 -78.67777)
		(size 0.508)
		(drill 0.254)
		(layers "F.Cu" "B.Cu")
		(net "GND")
	)
	(via
		(at 19.812 -107.4674)
		(size 0.5588)
		(drill 0.3048)
		(layers "F.Cu" "B.Cu")
		(net "GND")
	)
	(via
		(at 226.822 -150.219156)
		(size 0.508)
		(drill 0.254)
		(layers "F.Cu" "B.Cu")
		(net "GND")
	)
	(via
		(at 86.064852 -67.47764)
		(size 0.508)
		(drill 0.254)
		(layers "F.Cu" "B.Cu")
		(net "GND")
	)
	(via
		(at 204.899768 -154.063446)
		(size 0.508)
		(drill 0.254)
		(layers "F.Cu" "B.Cu")
		(net "GND")
	)
	(via
		(at 336.169 -18.161)
		(size 0.508)
		(drill 0.254)
		(layers "F.Cu" "B.Cu")
		(net "GND")
	)
	(via
		(at 427.461934 14.926056)
		(size 0.5588)
		(drill 0.3048)
		(layers "F.Cu" "B.Cu")
		(net "GND")
	)
	(via
		(at 138.529314 -80.174338)
		(size 0.508)
		(drill 0.254)
		(layers "F.Cu" "B.Cu")
		(net "GND")
	)
	(via
		(at 8.819134 14.926056)
		(size 0.5588)
		(drill 0.3048)
		(layers "F.Cu" "B.Cu")
		(net "GND")
	)
	(via
		(at 476.931482 -152.674066)
		(size 0.5588)
		(drill 0.3048)
		(layers "F.Cu" "B.Cu")
		(net "GND")
	)
	(via
		(at 245.975124 -162.243262)
		(size 0.5588)
		(drill 0.3048)
		(layers "F.Cu" "B.Cu")
		(net "GND")
	)
	(via
		(at 75.65009 -126.401576)
		(size 0.508)
		(drill 0.254)
		(layers "F.Cu" "B.Cu")
		(net "GND")
	)
	(via
		(at 246.772684 -66.982086)
		(size 0.508)
		(drill 0.254)
		(layers "F.Cu" "B.Cu")
		(net "GND")
	)
	(via
		(at 28.9052 -45.847)
		(size 0.508)
		(drill 0.254)
		(layers "F.Cu" "B.Cu")
		(net "GND")
	)
	(via
		(at 39.049452 -18.757646)
		(size 0.508)
		(drill 0.254)
		(layers "F.Cu" "B.Cu")
		(net "GND")
	)
	(via
		(at 405.683212 -119.945404)
		(size 0.508)
		(drill 0.254)
		(layers "F.Cu" "B.Cu")
		(net "GND")
	)
	(via
		(at 57.74944 -155.612846)
		(size 0.508)
		(drill 0.254)
		(layers "F.Cu" "B.Cu")
		(net "GND")
	)
	(via
		(at 85.206332 -55.094886)
		(size 0.508)
		(drill 0.254)
		(layers "F.Cu" "B.Cu")
		(net "GND")
	)
	(via
		(at 11.65352 -140.89634)
		(size 0.508)
		(drill 0.254)
		(layers "F.Cu" "B.Cu")
		(net "GND")
	)
	(via
		(at 13.5636 -69.723)
		(size 0.508)
		(drill 0.254)
		(layers "F.Cu" "B.Cu")
		(net "GND")
	)
	(via
		(at 153.218134 -167.832024)
		(size 0.5588)
		(drill 0.3048)
		(layers "F.Cu" "B.Cu")
		(net "GND")
	)
	(via
		(at 22.331934 14.926056)
		(size 0.5588)
		(drill 0.3048)
		(layers "F.Cu" "B.Cu")
		(net "GND")
	)
	(via
		(at 233.799888 -155.549346)
		(size 0.508)
		(drill 0.254)
		(layers "F.Cu" "B.Cu")
		(net "GND")
	)
	(via
		(at 69.753226 -83.822286)
		(size 0.508)
		(drill 0.254)
		(layers "F.Cu" "B.Cu")
		(net "GND")
	)
	(via
		(at 42.58818 -98.550222)
		(size 0.5588)
		(drill 0.3048)
		(layers "F.Cu" "B.Cu")
		(net "GND")
	)
	(via
		(at 239.046258 -70.44944)
		(size 0.508)
		(drill 0.254)
		(layers "F.Cu" "B.Cu")
		(net "GND")
	)
	(via
		(at 405.156924 -162.243262)
		(size 0.5588)
		(drill 0.3048)
		(layers "F.Cu" "B.Cu")
		(net "GND")
	)
	(via
		(at 389.871712 -155.075128)
		(size 0.508)
		(drill 0.254)
		(layers "F.Cu" "B.Cu")
		(net "GND")
	)
	(via
		(at 35.8902 -81.661)
		(size 0.508)
		(drill 0.254)
		(layers "F.Cu" "B.Cu")
		(net "GND")
	)
	(via
		(at 327.131934 14.926056)
		(size 0.5588)
		(drill 0.3048)
		(layers "F.Cu" "B.Cu")
		(net "GND")
	)
	(via
		(at 143.501364 -17.208246)
		(size 0.508)
		(drill 0.254)
		(layers "F.Cu" "B.Cu")
		(net "GND")
	)
	(via
		(at 207.411828 -148.771356)
		(size 0.508)
		(drill 0.254)
		(layers "F.Cu" "B.Cu")
		(net "GND")
	)
	(via
		(at 496.77066 -126.94666)
		(size 0.508)
		(drill 0.254)
		(layers "F.Cu" "B.Cu")
		(net "GND")
	)
	(via
		(at 476.2754 -13.0302)
		(size 0.508)
		(drill 0.254)
		(layers "F.Cu" "B.Cu")
		(net "GND")
	)
	(via
		(at 95.555816 -150.7871)
		(size 0.508)
		(drill 0.254)
		(layers "F.Cu" "B.Cu")
		(net "GND")
	)
	(via
		(at 431.830734 -167.832024)
		(size 0.5588)
		(drill 0.3048)
		(layers "F.Cu" "B.Cu")
		(net "GND")
	)
	(via
		(at 186.0296 -135.0772)
		(size 0.508)
		(drill 0.254)
		(layers "F.Cu" "B.Cu")
		(net "GND")
	)
	(via
		(at 174.731934 14.926056)
		(size 0.5588)
		(drill 0.3048)
		(layers "F.Cu" "B.Cu")
		(net "GND")
	)
	(via
		(at 6.812534 -166.714424)
		(size 0.5588)
		(drill 0.3048)
		(layers "F.Cu" "B.Cu")
		(net "GND")
	)
	(via
		(at 349.064072 -99.05619)
		(size 0.508)
		(drill 0.254)
		(layers "F.Cu" "B.Cu")
		(net "GND")
	)
	(via
		(at 54.737508 -13.948156)
		(size 0.508)
		(drill 0.254)
		(layers "F.Cu" "B.Cu")
		(net "GND")
	)
	(via
		(at 460.481934 14.926056)
		(size 0.5588)
		(drill 0.3048)
		(layers "F.Cu" "B.Cu")
		(net "GND")
	)
	(via
		(at 144.411446 -11.916156)
		(size 0.508)
		(drill 0.254)
		(layers "F.Cu" "B.Cu")
		(net "GND")
	)
	(via
		(at 419.841934 14.926056)
		(size 0.5588)
		(drill 0.3048)
		(layers "F.Cu" "B.Cu")
		(net "GND")
	)
	(via
		(at 132.519674 -67.791584)
		(size 0.508)
		(drill 0.254)
		(layers "F.Cu" "B.Cu")
		(net "GND")
	)
	(via
		(at 132.362702 -27.829256)
		(size 0.508)
		(drill 0.254)
		(layers "F.Cu" "B.Cu")
		(net "GND")
	)
	(via
		(at 248.391934 9.084056)
		(size 0.5588)
		(drill 0.3048)
		(layers "F.Cu" "B.Cu")
		(net "GND")
	)
	(via
		(at 447.781934 12.894056)
		(size 0.5588)
		(drill 0.3048)
		(layers "F.Cu" "B.Cu")
		(net "GND")
	)
	(via
		(at 452.861934 10.354056)
		(size 0.5588)
		(drill 0.3048)
		(layers "F.Cu" "B.Cu")
		(net "GND")
	)
	(via
		(at 387.73735 -102.756716)
		(size 0.508)
		(drill 0.254)
		(layers "F.Cu" "B.Cu")
		(net "GND")
	)
	(via
		(at 210.391248 2.505456)
		(size 0.508)
		(drill 0.254)
		(layers "F.Cu" "B.Cu")
		(net "GND")
	)
	(via
		(at 167.767 -124.968)
		(size 0.508)
		(drill 0.254)
		(layers "F.Cu" "B.Cu")
		(net "GND")
	)
	(via
		(at 186.746134 -167.832024)
		(size 0.5588)
		(drill 0.3048)
		(layers "F.Cu" "B.Cu")
		(net "GND")
	)
	(via
		(at 388.6708 -65.3288)
		(size 0.508)
		(drill 0.254)
		(layers "F.Cu" "B.Cu")
		(net "GND")
	)
	(via
		(at 419.258496 -90.902536)
		(size 0.508)
		(drill 0.254)
		(layers "F.Cu" "B.Cu")
		(net "GND")
	)
	(via
		(at 424.210734 -165.596824)
		(size 0.5588)
		(drill 0.3048)
		(layers "F.Cu" "B.Cu")
		(net "GND")
	)
	(via
		(at 42.9641 -74.0664)
		(size 0.5588)
		(drill 0.3048)
		(layers "F.Cu" "B.Cu")
		(net "GND")
	)
	(via
		(at 390.631934 9.084056)
		(size 0.5588)
		(drill 0.3048)
		(layers "F.Cu" "B.Cu")
		(net "GND")
	)
	(via
		(at 222.749872 -18.757646)
		(size 0.508)
		(drill 0.254)
		(layers "F.Cu" "B.Cu")
		(net "GND")
	)
	(via
		(at 222.749872 -139.170156)
		(size 0.508)
		(drill 0.254)
		(layers "F.Cu" "B.Cu")
		(net "GND")
	)
	(via
		(at 41.461182 -77.128878)
		(size 0.5588)
		(drill 0.3048)
		(layers "F.Cu" "B.Cu")
		(net "GND")
	)
	(via
		(at 80.055212 -83.822286)
		(size 0.508)
		(drill 0.254)
		(layers "F.Cu" "B.Cu")
		(net "GND")
	)
	(via
		(at 486.440734 -167.832024)
		(size 0.5588)
		(drill 0.3048)
		(layers "F.Cu" "B.Cu")
		(net "GND")
	)
	(via
		(at 469.052402 -39.051992)
		(size 0.508)
		(drill 0.254)
		(layers "F.Cu" "B.Cu")
		(net "GND")
	)
	(via
		(at 36.83635 -60.183522)
		(size 0.5588)
		(drill 0.3048)
		(layers "F.Cu" "B.Cu")
		(net "GND")
	)
	(via
		(at 227.78339 -126.622556)
		(size 0.508)
		(drill 0.254)
		(layers "F.Cu" "B.Cu")
		(net "GND")
	)
	(via
		(at 54.74081 -134.349744)
		(size 0.508)
		(drill 0.254)
		(layers "F.Cu" "B.Cu")
		(net "GND")
	)
	(via
		(at 277.774654 -98.005138)
		(size 0.508)
		(drill 0.254)
		(layers "F.Cu" "B.Cu")
		(net "GND")
	)
	(via
		(at 422.7068 -1.3716)
		(size 0.508)
		(drill 0.254)
		(layers "F.Cu" "B.Cu")
		(net "GND")
	)
	(via
		(at 417.926012 -32.608012)
		(size 0.4572)
		(drill 0.2032)
		(layers "F.Cu" "B.Cu")
		(net "GND")
	)
	(via
		(at 67.949318 -3.762756)
		(size 0.508)
		(drill 0.254)
		(layers "F.Cu" "B.Cu")
		(net "GND")
	)
	(via
		(at 49.24933 -144.462246)
		(size 0.508)
		(drill 0.254)
		(layers "F.Cu" "B.Cu")
		(net "GND")
	)
	(via
		(at 495.935 -129.032)
		(size 0.508)
		(drill 0.254)
		(layers "F.Cu" "B.Cu")
		(net "GND")
	)
	(via
		(at 234.753658 -86.794086)
		(size 0.508)
		(drill 0.254)
		(layers "F.Cu" "B.Cu")
		(net "GND")
	)
	(via
		(at 249.348244 -59.55284)
		(size 0.508)
		(drill 0.254)
		(layers "F.Cu" "B.Cu")
		(net "GND")
	)
	(via
		(at 169.561764 1.999996)
		(size 0.5588)
		(drill 0.3048)
		(layers "F.Cu" "B.Cu")
		(net "GND")
	)
	(via
		(at 5.694934 -167.832024)
		(size 0.5588)
		(drill 0.3048)
		(layers "F.Cu" "B.Cu")
		(net "GND")
	)
	(via
		(at 259.65023 -88.28024)
		(size 0.508)
		(drill 0.254)
		(layers "F.Cu" "B.Cu")
		(net "GND")
	)
	(via
		(at 210.391248 -134.349744)
		(size 0.508)
		(drill 0.254)
		(layers "F.Cu" "B.Cu")
		(net "GND")
	)
	(via
		(at 32.517334 -167.832024)
		(size 0.5588)
		(drill 0.3048)
		(layers "F.Cu" "B.Cu")
		(net "GND")
	)
	(via
		(at 424.921934 13.910056)
		(size 0.5588)
		(drill 0.3048)
		(layers "F.Cu" "B.Cu")
		(net "GND")
	)
	(via
		(at 443.497208 -156.158184)
		(size 0.508)
		(drill 0.254)
		(layers "F.Cu" "B.Cu")
		(net "GND")
	)
	(via
		(at 185.6994 -70.9422)
		(size 0.508)
		(drill 0.254)
		(layers "F.Cu" "B.Cu")
		(net "GND")
	)
	(via
		(at 16.867124 -162.243262)
		(size 0.5588)
		(drill 0.3048)
		(layers "F.Cu" "B.Cu")
		(net "GND")
	)
	(via
		(at 198.772018 -144.5006)
		(size 0.508)
		(drill 0.254)
		(layers "F.Cu" "B.Cu")
		(net "GND")
	)
	(via
		(at 246.772684 -56.085486)
		(size 0.508)
		(drill 0.254)
		(layers "F.Cu" "B.Cu")
		(net "GND")
	)
	(via
		(at 35.8902 -89.7382)
		(size 0.508)
		(drill 0.254)
		(layers "F.Cu" "B.Cu")
		(net "GND")
	)
	(via
		(at 212.54974 -22.965156)
		(size 0.508)
		(drill 0.254)
		(layers "F.Cu" "B.Cu")
		(net "GND")
	)
	(via
		(at 398.810734 -163.361624)
		(size 0.5588)
		(drill 0.3048)
		(layers "F.Cu" "B.Cu")
		(net "GND")
	)
	(via
		(at 198.772018 -150.219156)
		(size 0.508)
		(drill 0.254)
		(layers "F.Cu" "B.Cu")
		(net "GND")
	)
	(via
		(at 122.217688 -94.538038)
		(size 0.508)
		(drill 0.254)
		(layers "F.Cu" "B.Cu")
		(net "GND")
	)
	(via
		(at 285.501334 -88.594184)
		(size 0.508)
		(drill 0.254)
		(layers "F.Cu" "B.Cu")
		(net "GND")
	)
	(via
		(at 174.9044 -92.7354)
		(size 0.508)
		(drill 0.254)
		(layers "F.Cu" "B.Cu")
		(net "GND")
	)
	(via
		(at 229.214934 -167.832024)
		(size 0.5588)
		(drill 0.3048)
		(layers "F.Cu" "B.Cu")
		(net "GND")
	)
	(via
		(at 268.557756 -53.113686)
		(size 0.508)
		(drill 0.254)
		(layers "F.Cu" "B.Cu")
		(net "GND")
	)
	(via
		(at 263.948418 -75.148186)
		(size 0.5588)
		(drill 0.3048)
		(layers "F.Cu" "B.Cu")
		(net "GND")
	)
	(via
		(at 5.574792 -143.9418)
		(size 0.508)
		(drill 0.254)
		(layers "F.Cu" "B.Cu")
		(net "GND")
	)
	(via
		(at 294.9448 -80.174338)
		(size 0.508)
		(drill 0.254)
		(layers "F.Cu" "B.Cu")
		(net "GND")
	)
	(via
		(at 257.07467 -95.709486)
		(size 0.508)
		(drill 0.254)
		(layers "F.Cu" "B.Cu")
		(net "GND")
	)
	(via
		(at 28.040838 -102.261162)
		(size 0.508)
		(drill 0.254)
		(layers "F.Cu" "B.Cu")
		(net "GND")
	)
	(via
		(at 124.81052 -140.592556)
		(size 0.508)
		(drill 0.254)
		(layers "F.Cu" "B.Cu")
		(net "GND")
	)
	(via
		(at -3.249676 -162.243262)
		(size 0.5588)
		(drill 0.3048)
		(layers "F.Cu" "B.Cu")
		(net "GND")
	)
	(via
		(at 308.5084 -3.737356)
		(size 0.508)
		(drill 0.254)
		(layers "F.Cu" "B.Cu")
		(net "GND")
	)
	(via
		(at 46.699424 -139.170156)
		(size 0.508)
		(drill 0.254)
		(layers "F.Cu" "B.Cu")
		(net "GND")
	)
	(via
		(at 342.10498 -130.9243)
		(size 0.508)
		(drill 0.254)
		(layers "F.Cu" "B.Cu")
		(net "GND")
	)
	(via
		(at 191.74714 -141.3256)
		(size 0.508)
		(drill 0.254)
		(layers "F.Cu" "B.Cu")
		(net "GND")
	)
	(via
		(at 301.812706 -81.164938)
		(size 0.508)
		(drill 0.254)
		(layers "F.Cu" "B.Cu")
		(net "GND")
	)
	(via
		(at 419.859714 -80.960214)
		(size 0.508)
		(drill 0.254)
		(layers "F.Cu" "B.Cu")
		(net "GND")
	)
	(via
		(at 416.590734 -163.361624)
		(size 0.5588)
		(drill 0.3048)
		(layers "F.Cu" "B.Cu")
		(net "GND")
	)
	(via
		(at 172.191934 14.926056)
		(size 0.5588)
		(drill 0.3048)
		(layers "F.Cu" "B.Cu")
		(net "GND")
	)
	(via
		(at 40.140382 -76.468478)
		(size 0.5588)
		(drill 0.3048)
		(layers "F.Cu" "B.Cu")
		(net "GND")
	)
	(via
		(at 131.661408 -83.146138)
		(size 0.508)
		(drill 0.254)
		(layers "F.Cu" "B.Cu")
		(net "GND")
	)
	(via
		(at 123.199398 -7.607046)
		(size 0.508)
		(drill 0.254)
		(layers "F.Cu" "B.Cu")
		(net "GND")
	)
	(via
		(at 183.8198 -17.1196)
		(size 0.508)
		(drill 0.254)
		(layers "F.Cu" "B.Cu")
		(net "GND")
	)
	(via
		(at 167.111934 9.084056)
		(size 0.5588)
		(drill 0.3048)
		(layers "F.Cu" "B.Cu")
		(net "GND")
	)
	(via
		(at 261.087108 -70.841616)
		(size 0.5588)
		(drill 0.3048)
		(layers "F.Cu" "B.Cu")
		(net "GND")
	)
	(via
		(at 283.048964 -144.0053)
		(size 0.508)
		(drill 0.254)
		(layers "F.Cu" "B.Cu")
		(net "GND")
	)
	(via
		(at 196.399912 -9.139682)
		(size 0.508)
		(drill 0.254)
		(layers "F.Cu" "B.Cu")
		(net "GND")
	)
	(via
		(at 142.039848 -95.033084)
		(size 0.508)
		(drill 0.254)
		(layers "F.Cu" "B.Cu")
		(net "GND")
	)
	(via
		(at 93.791278 -98.681286)
		(size 0.508)
		(drill 0.254)
		(layers "F.Cu" "B.Cu")
		(net "GND")
	)
	(via
		(at 163.0553 -31.9405)
		(size 0.508)
		(drill 0.254)
		(layers "F.Cu" "B.Cu")
		(net "GND")
	)
	(via
		(at 458.500734 -165.596824)
		(size 0.5588)
		(drill 0.3048)
		(layers "F.Cu" "B.Cu")
		(net "GND")
	)
	(via
		(at 350.5454 -113.665)
		(size 0.508)
		(drill 0.254)
		(layers "F.Cu" "B.Cu")
		(net "GND")
	)
	(via
		(at 249.348244 -55.59044)
		(size 0.508)
		(drill 0.254)
		(layers "F.Cu" "B.Cu")
		(net "GND")
	)
	(via
		(at 3.464306 -135.809482)
		(size 0.508)
		(drill 0.254)
		(layers "F.Cu" "B.Cu")
		(net "GND")
	)
	(via
		(at 457.941934 12.894056)
		(size 0.5588)
		(drill 0.3048)
		(layers "F.Cu" "B.Cu")
		(net "GND")
	)
	(via
		(at 76.449428 -146.011646)
		(size 0.508)
		(drill 0.254)
		(layers "F.Cu" "B.Cu")
		(net "GND")
	)
	(via
		(at 234.753658 -94.718886)
		(size 0.508)
		(drill 0.254)
		(layers "F.Cu" "B.Cu")
		(net "GND")
	)
	(via
		(at 175.478694 -54.792118)
		(size 0.508)
		(drill 0.254)
		(layers "F.Cu" "B.Cu")
		(net "GND")
	)
	(via
		(at 100.659184 -53.113686)
		(size 0.508)
		(drill 0.254)
		(layers "F.Cu" "B.Cu")
		(net "GND")
	)
	(via
		(at 417.860734 -167.832024)
		(size 0.5588)
		(drill 0.3048)
		(layers "F.Cu" "B.Cu")
		(net "GND")
	)
	(via
		(at 206.906114 -78.475078)
		(size 0.5588)
		(drill 0.3048)
		(layers "F.Cu" "B.Cu")
		(net "GND")
	)
	(via
		(at 243.311934 9.084056)
		(size 0.5588)
		(drill 0.3048)
		(layers "F.Cu" "B.Cu")
		(net "GND")
	)
	(via
		(at 383.27965 -101.898196)
		(size 0.508)
		(drill 0.254)
		(layers "F.Cu" "B.Cu")
		(net "GND")
	)
	(via
		(at 68.799456 -18.744946)
		(size 0.508)
		(drill 0.254)
		(layers "F.Cu" "B.Cu")
		(net "GND")
	)
	(via
		(at 64.081406 -148.7678)
		(size 0.508)
		(drill 0.254)
		(layers "F.Cu" "B.Cu")
		(net "GND")
	)
	(via
		(at 178.569112 -125.1204)
		(size 0.508)
		(drill 0.254)
		(layers "F.Cu" "B.Cu")
		(net "GND")
	)
	(via
		(at 76.103734 -167.832024)
		(size 0.5588)
		(drill 0.3048)
		(layers "F.Cu" "B.Cu")
		(net "GND")
	)
	(via
		(at 380.264924 -134.967472)
		(size 0.508)
		(drill 0.254)
		(layers "F.Cu" "B.Cu")
		(net "GND")
	)
	(via
		(at 464.058 -22.098)
		(size 0.508)
		(drill 0.254)
		(layers "F.Cu" "B.Cu")
		(net "GND")
	)
	(via
		(at 81.618836 -145.0086)
		(size 0.508)
		(drill 0.254)
		(layers "F.Cu" "B.Cu")
		(net "GND")
	)
	(via
		(at 388.149084 -88.859868)
		(size 0.508)
		(drill 0.254)
		(layers "F.Cu" "B.Cu")
		(net "GND")
	)
	(via
		(at 371.33022 -149.340824)
		(size 0.508)
		(drill 0.254)
		(layers "F.Cu" "B.Cu")
		(net "GND")
	)
	(via
		(at 285.649924 -21.517356)
		(size 0.508)
		(drill 0.254)
		(layers "F.Cu" "B.Cu")
		(net "GND")
	)
	(via
		(at 298.399962 -139.170156)
		(size 0.508)
		(drill 0.254)
		(layers "F.Cu" "B.Cu")
		(net "GND")
	)
	(via
		(at 367.9952 -105.791)
		(size 0.508)
		(drill 0.254)
		(layers "F.Cu" "B.Cu")
		(net "GND")
	)
	(via
		(at 72.328786 -67.47764)
		(size 0.508)
		(drill 0.254)
		(layers "F.Cu" "B.Cu")
		(net "GND")
	)
	(via
		(at 449.330064 -50.513488)
		(size 0.508)
		(drill 0.254)
		(layers "F.Cu" "B.Cu")
		(net "GND")
	)
	(via
		(at 60.170568 -125.3236)
		(size 0.508)
		(drill 0.254)
		(layers "F.Cu" "B.Cu")
		(net "GND")
	)
	(via
		(at 118.041928 -2.310892)
		(size 0.508)
		(drill 0.254)
		(layers "F.Cu" "B.Cu")
		(net "GND")
	)
	(via
		(at 436.910734 -167.832024)
		(size 0.5588)
		(drill 0.3048)
		(layers "F.Cu" "B.Cu")
		(net "GND")
	)
	(via
		(at 30.549342 -7.086346)
		(size 0.508)
		(drill 0.254)
		(layers "F.Cu" "B.Cu")
		(net "GND")
	)
	(via
		(at 408.970734 -166.714424)
		(size 0.5588)
		(drill 0.3048)
		(layers "F.Cu" "B.Cu")
		(net "GND")
	)
	(via
		(at 335.1022 -134.6835)
		(size 0.508)
		(drill 0.254)
		(layers "F.Cu" "B.Cu")
		(net "GND")
	)
	(via
		(at 290.6522 -72.744584)
		(size 0.508)
		(drill 0.254)
		(layers "F.Cu" "B.Cu")
		(net "GND")
	)
	(via
		(at 57.74944 -11.916156)
		(size 0.508)
		(drill 0.254)
		(layers "F.Cu" "B.Cu")
		(net "GND")
	)
	(via
		(at 133.097524 -162.243262)
		(size 0.5588)
		(drill 0.3048)
		(layers "F.Cu" "B.Cu")
		(net "GND")
	)
	(via
		(at 411.99816 -140.926058)
		(size 0.508)
		(drill 0.254)
		(layers "F.Cu" "B.Cu")
		(net "GND")
	)
	(via
		(at 435.640734 -166.714424)
		(size 0.5588)
		(drill 0.3048)
		(layers "F.Cu" "B.Cu")
		(net "GND")
	)
	(via
		(at 349.377 -19.304)
		(size 0.508)
		(drill 0.254)
		(layers "F.Cu" "B.Cu")
		(net "GND")
	)
	(via
		(at 219.73794 -23.549356)
		(size 0.508)
		(drill 0.254)
		(layers "F.Cu" "B.Cu")
		(net "GND")
	)
	(via
		(at 376.661934 14.926056)
		(size 0.5588)
		(drill 0.3048)
		(layers "F.Cu" "B.Cu")
		(net "GND")
	)
	(via
		(at 84.347812 -59.55284)
		(size 0.508)
		(drill 0.254)
		(layers "F.Cu" "B.Cu")
		(net "GND")
	)
	(via
		(at 367.8428 -158.3436)
		(size 0.508)
		(drill 0.254)
		(layers "F.Cu" "B.Cu")
		(net "GND")
	)
	(via
		(at 409.0543 -9.4742)
		(size 0.508)
		(drill 0.254)
		(layers "F.Cu" "B.Cu")
		(net "GND")
	)
	(via
		(at 83.489292 -71.935086)
		(size 0.508)
		(drill 0.254)
		(layers "F.Cu" "B.Cu")
		(net "GND")
	)
	(via
		(at 135.953754 -97.509584)
		(size 0.508)
		(drill 0.254)
		(layers "F.Cu" "B.Cu")
		(net "GND")
	)
	(via
		(at 198.099934 -9.139682)
		(size 0.508)
		(drill 0.254)
		(layers "F.Cu" "B.Cu")
		(net "GND")
	)
	(via
		(at 98.083878 -60.54344)
		(size 0.508)
		(drill 0.254)
		(layers "F.Cu" "B.Cu")
		(net "GND")
	)
	(via
		(at 383.95529 -29.09189)
		(size 0.508)
		(drill 0.254)
		(layers "F.Cu" "B.Cu")
		(net "GND")
	)
	(via
		(at 288.19983 -154.063446)
		(size 0.508)
		(drill 0.254)
		(layers "F.Cu" "B.Cu")
		(net "GND")
	)
	(via
		(at 147.582128 -118.669308)
		(size 0.508)
		(drill 0.254)
		(layers "F.Cu" "B.Cu")
		(net "GND")
	)
	(via
		(at 77.479906 -74.411586)
		(size 0.508)
		(drill 0.254)
		(layers "F.Cu" "B.Cu")
		(net "GND")
	)
	(via
		(at 73.187306 -59.057286)
		(size 0.508)
		(drill 0.254)
		(layers "F.Cu" "B.Cu")
		(net "GND")
	)
	(via
		(at 337.618324 -162.243262)
		(size 0.5588)
		(drill 0.3048)
		(layers "F.Cu" "B.Cu")
		(net "GND")
	)
	(via
		(at 145.12163 -7.6454)
		(size 0.508)
		(drill 0.254)
		(layers "F.Cu" "B.Cu")
		(net "GND")
	)
	(via
		(at 34.74212 -145.998946)
		(size 0.508)
		(drill 0.254)
		(layers "F.Cu" "B.Cu")
		(net "GND")
	)
	(via
		(at 84.910168 -8.1534)
		(size 0.508)
		(drill 0.254)
		(layers "F.Cu" "B.Cu")
		(net "GND")
	)
	(via
		(at 223.626934 -167.832024)
		(size 0.5588)
		(drill 0.3048)
		(layers "F.Cu" "B.Cu")
		(net "GND")
	)
	(via
		(at 25.807924 -162.243262)
		(size 0.5588)
		(drill 0.3048)
		(layers "F.Cu" "B.Cu")
		(net "GND")
	)
	(via
		(at 461.036924 -162.243262)
		(size 0.5588)
		(drill 0.3048)
		(layers "F.Cu" "B.Cu")
		(net "GND")
	)
	(via
		(at 275.109432 -149.8092)
		(size 0.508)
		(drill 0.254)
		(layers "F.Cu" "B.Cu")
		(net "GND")
	)
	(via
		(at 99.573334 -167.832024)
		(size 0.5588)
		(drill 0.3048)
		(layers "F.Cu" "B.Cu")
		(net "GND")
	)
	(via
		(at 209.094324 -162.243262)
		(size 0.5588)
		(drill 0.3048)
		(layers "F.Cu" "B.Cu")
		(net "GND")
	)
	(via
		(at 233.799888 -18.744946)
		(size 0.508)
		(drill 0.254)
		(layers "F.Cu" "B.Cu")
		(net "GND")
	)
	(via
		(at 319.05702 -118.82628)
		(size 0.508)
		(drill 0.254)
		(layers "F.Cu" "B.Cu")
		(net "GND")
	)
	(via
		(at -1.188466 12.741656)
		(size 0.5588)
		(drill 0.3048)
		(layers "F.Cu" "B.Cu")
		(net "GND")
	)
	(via
		(at 200.897998 -74.74458)
		(size 0.508)
		(drill 0.254)
		(layers "F.Cu" "B.Cu")
		(net "GND")
	)
	(via
		(at 209.09915 2.4511)
		(size 0.508)
		(drill 0.254)
		(layers "F.Cu" "B.Cu")
		(net "GND")
	)
	(via
		(at 100.690934 -167.832024)
		(size 0.5588)
		(drill 0.3048)
		(layers "F.Cu" "B.Cu")
		(net "GND")
	)
	(via
		(at 485.170734 -166.714424)
		(size 0.5588)
		(drill 0.3048)
		(layers "F.Cu" "B.Cu")
		(net "GND")
	)
	(via
		(at 197.922134 -167.832024)
		(size 0.5588)
		(drill 0.3048)
		(layers "F.Cu" "B.Cu")
		(net "GND")
	)
	(via
		(at 310.6674 -65.6844)
		(size 0.508)
		(drill 0.254)
		(layers "F.Cu" "B.Cu")
		(net "GND")
	)
	(via
		(at 440.720734 -165.596824)
		(size 0.5588)
		(drill 0.3048)
		(layers "F.Cu" "B.Cu")
		(net "GND")
	)
	(via
		(at 195.683124 -162.243262)
		(size 0.5588)
		(drill 0.3048)
		(layers "F.Cu" "B.Cu")
		(net "GND")
	)
	(via
		(at 8.541512 -0.033274)
		(size 0.508)
		(drill 0.254)
		(layers "F.Cu" "B.Cu")
		(net "GND")
	)
	(via
		(at 303.529746 -67.296538)
		(size 0.508)
		(drill 0.254)
		(layers "F.Cu" "B.Cu")
		(net "GND")
	)
	(via
		(at 125.651768 -78.688438)
		(size 0.508)
		(drill 0.254)
		(layers "F.Cu" "B.Cu")
		(net "GND")
	)
	(via
		(at 442.701934 10.354056)
		(size 0.5588)
		(drill 0.3048)
		(layers "F.Cu" "B.Cu")
		(net "GND")
	)
	(via
		(at 28.681934 14.926056)
		(size 0.5588)
		(drill 0.3048)
		(layers "F.Cu" "B.Cu")
		(net "GND")
	)
	(via
		(at 284.341062 -16.696944)
		(size 0.508)
		(drill 0.254)
		(layers "F.Cu" "B.Cu")
		(net "GND")
	)
	(via
		(at 460.121 -153.289)
		(size 0.508)
		(drill 0.254)
		(layers "F.Cu" "B.Cu")
		(net "GND")
	)
	(via
		(at 383.27965 -98.464116)
		(size 0.508)
		(drill 0.254)
		(layers "F.Cu" "B.Cu")
		(net "GND")
	)
	(via
		(at 140.246354 -54.418738)
		(size 0.508)
		(drill 0.254)
		(layers "F.Cu" "B.Cu")
		(net "GND")
	)
	(via
		(at 430.001934 11.624056)
		(size 0.5588)
		(drill 0.3048)
		(layers "F.Cu" "B.Cu")
		(net "GND")
	)
	(via
		(at 251.923804 -56.085486)
		(size 0.508)
		(drill 0.254)
		(layers "F.Cu" "B.Cu")
		(net "GND")
	)
	(via
		(at 251.065284 -71.44004)
		(size 0.508)
		(drill 0.254)
		(layers "F.Cu" "B.Cu")
		(net "GND")
	)
	(via
		(at 439.2168 -131.826)
		(size 0.508)
		(drill 0.254)
		(layers "F.Cu" "B.Cu")
		(net "GND")
	)
	(via
		(at 357.4161 -14.950186)
		(size 0.508)
		(drill 0.254)
		(layers "F.Cu" "B.Cu")
		(net "GND")
	)
	(via
		(at 30.549342 -13.929106)
		(size 0.508)
		(drill 0.254)
		(layers "F.Cu" "B.Cu")
		(net "GND")
	)
	(via
		(at 30.549342 -23.495)
		(size 0.508)
		(drill 0.254)
		(layers "F.Cu" "B.Cu")
		(net "GND")
	)
	(via
		(at 235.612178 -58.561986)
		(size 0.508)
		(drill 0.254)
		(layers "F.Cu" "B.Cu")
		(net "GND")
	)
	(via
		(at 42.9641 -90.3224)
		(size 0.5588)
		(drill 0.3048)
		(layers "F.Cu" "B.Cu")
		(net "GND")
	)
	(via
		(at 345.076272 -99.91979)
		(size 0.508)
		(drill 0.254)
		(layers "F.Cu" "B.Cu")
		(net "GND")
	)
	(via
		(at 337.026758 -119.196866)
		(size 0.508)
		(drill 0.254)
		(layers "F.Cu" "B.Cu")
		(net "GND")
	)
	(via
		(at 152.096724 -162.243262)
		(size 0.5588)
		(drill 0.3048)
		(layers "F.Cu" "B.Cu")
		(net "GND")
	)
	(via
		(at 240.763298 -64.50584)
		(size 0.508)
		(drill 0.254)
		(layers "F.Cu" "B.Cu")
		(net "GND")
	)
	(via
		(at 401.828 -100.6475)
		(size 0.508)
		(drill 0.254)
		(layers "F.Cu" "B.Cu")
		(net "GND")
	)
	(via
		(at 59.335924 -162.243262)
		(size 0.5588)
		(drill 0.3048)
		(layers "F.Cu" "B.Cu")
		(net "GND")
	)
	(via
		(at 126.510288 -87.108538)
		(size 0.508)
		(drill 0.254)
		(layers "F.Cu" "B.Cu")
		(net "GND")
	)
	(via
		(at 339.831934 9.084056)
		(size 0.5588)
		(drill 0.3048)
		(layers "F.Cu" "B.Cu")
		(net "GND")
	)
	(via
		(at 78.14945 -145.988278)
		(size 0.508)
		(drill 0.254)
		(layers "F.Cu" "B.Cu")
		(net "GND")
	)
	(via
		(at 203.199746 -154.063446)
		(size 0.508)
		(drill 0.254)
		(layers "F.Cu" "B.Cu")
		(net "GND")
	)
	(via
		(at 68.857368 -125.969776)
		(size 0.508)
		(drill 0.254)
		(layers "F.Cu" "B.Cu")
		(net "GND")
	)
	(via
		(at 139.34948 -26.495756)
		(size 0.508)
		(drill 0.254)
		(layers "F.Cu" "B.Cu")
		(net "GND")
	)
	(via
		(at 41.105582 -93.892878)
		(size 0.5588)
		(drill 0.3048)
		(layers "F.Cu" "B.Cu")
		(net "GND")
	)
	(via
		(at 118.041928 -21.513292)
		(size 0.508)
		(drill 0.254)
		(layers "F.Cu" "B.Cu")
		(net "GND")
	)
	(via
		(at 235.46181 -26.488136)
		(size 0.508)
		(drill 0.254)
		(layers "F.Cu" "B.Cu")
		(net "GND")
	)
	(via
		(at 482.630734 -166.714424)
		(size 0.5588)
		(drill 0.3048)
		(layers "F.Cu" "B.Cu")
		(net "GND")
	)
	(via
		(at 95.991934 14.926056)
		(size 0.5588)
		(drill 0.3048)
		(layers "F.Cu" "B.Cu")
		(net "GND")
	)
	(via
		(at 190.631572 -132.615432)
		(size 0.508)
		(drill 0.254)
		(layers "F.Cu" "B.Cu")
		(net "GND")
	)
	(via
		(at 72.328786 -62.52464)
		(size 0.508)
		(drill 0.254)
		(layers "F.Cu" "B.Cu")
		(net "GND")
	)
	(via
		(at 223.599756 -150.219156)
		(size 0.508)
		(drill 0.254)
		(layers "F.Cu" "B.Cu")
		(net "GND")
	)
	(via
		(at 118.057168 -7.1374)
		(size 0.508)
		(drill 0.254)
		(layers "F.Cu" "B.Cu")
		(net "GND")
	)
	(via
		(at 2.342134 -166.714424)
		(size 0.5588)
		(drill 0.3048)
		(layers "F.Cu" "B.Cu")
		(net "GND")
	)
	(via
		(at 321.975734 -167.832024)
		(size 0.5588)
		(drill 0.3048)
		(layers "F.Cu" "B.Cu")
		(net "GND")
	)
	(via
		(at 264.801096 -89.27084)
		(size 0.508)
		(drill 0.254)
		(layers "F.Cu" "B.Cu")
		(net "GND")
	)
	(via
		(at 269.434818 -75.148186)
		(size 0.5588)
		(drill 0.3048)
		(layers "F.Cu" "B.Cu")
		(net "GND")
	)
	(via
		(at 466.831934 14.926056)
		(size 0.5588)
		(drill 0.3048)
		(layers "F.Cu" "B.Cu")
		(net "GND")
	)
	(via
		(at 278.866346 -145.992342)
		(size 0.508)
		(drill 0.254)
		(layers "F.Cu" "B.Cu")
		(net "GND")
	)
	(via
		(at 303.027842 -9.0932)
		(size 0.508)
		(drill 0.254)
		(layers "F.Cu" "B.Cu")
		(net "GND")
	)
	(via
		(at 289.79368 -93.052138)
		(size 0.508)
		(drill 0.254)
		(layers "F.Cu" "B.Cu")
		(net "GND")
	)
	(via
		(at 233.799888 -2.314956)
		(size 0.508)
		(drill 0.254)
		(layers "F.Cu" "B.Cu")
		(net "GND")
	)
	(via
		(at 200.881234 -67.618864)
		(size 0.508)
		(drill 0.254)
		(layers "F.Cu" "B.Cu")
		(net "GND")
	)
	(via
		(at 304.271934 9.084056)
		(size 0.5588)
		(drill 0.3048)
		(layers "F.Cu" "B.Cu")
		(net "GND")
	)
	(via
		(at 335.1022 -135.2931)
		(size 0.508)
		(drill 0.254)
		(layers "F.Cu" "B.Cu")
		(net "GND")
	)
	(via
		(at 300.954186 -63.829184)
		(size 0.508)
		(drill 0.254)
		(layers "F.Cu" "B.Cu")
		(net "GND")
	)
	(via
		(at 361.315 -147.2692)
		(size 0.508)
		(drill 0.254)
		(layers "F.Cu" "B.Cu")
		(net "GND")
	)
	(via
		(at 238.444532 -155.5369)
		(size 0.508)
		(drill 0.254)
		(layers "F.Cu" "B.Cu")
		(net "GND")
	)
	(via
		(at 297.549824 -7.607046)
		(size 0.508)
		(drill 0.254)
		(layers "F.Cu" "B.Cu")
		(net "GND")
	)
	(via
		(at 481.41382 -16.35506)
		(size 0.508)
		(drill 0.254)
		(layers "F.Cu" "B.Cu")
		(net "GND")
	)
	(via
		(at 90.357198 -95.709486)
		(size 0.508)
		(drill 0.254)
		(layers "F.Cu" "B.Cu")
		(net "GND")
	)
	(via
		(at 400.40052 -92.17406)
		(size 0.508)
		(drill 0.254)
		(layers "F.Cu" "B.Cu")
		(net "GND")
	)
	(via
		(at 284.341062 2.505456)
		(size 0.508)
		(drill 0.254)
		(layers "F.Cu" "B.Cu")
		(net "GND")
	)
	(via
		(at 201.3966 -78.3336)
		(size 0.5588)
		(drill 0.3048)
		(layers "F.Cu" "B.Cu")
		(net "GND")
	)
	(via
		(at 342.0237 -81.8769)
		(size 0.508)
		(drill 0.254)
		(layers "F.Cu" "B.Cu")
		(net "GND")
	)
	(via
		(at 180.036724 -162.243262)
		(size 0.5588)
		(drill 0.3048)
		(layers "F.Cu" "B.Cu")
		(net "GND")
	)
	(via
		(at 204.899768 -150.219156)
		(size 0.508)
		(drill 0.254)
		(layers "F.Cu" "B.Cu")
		(net "GND")
	)
	(via
		(at 378.763784 -55.505858)
		(size 0.508)
		(drill 0.254)
		(layers "F.Cu" "B.Cu")
		(net "GND")
	)
	(via
		(at 219.731844 -129.5654)
		(size 0.508)
		(drill 0.254)
		(layers "F.Cu" "B.Cu")
		(net "GND")
	)
	(via
		(at 311.092596 -155.600146)
		(size 0.508)
		(drill 0.254)
		(layers "F.Cu" "B.Cu")
		(net "GND")
	)
	(via
		(at 186.47537 -9.786874)
		(size 0.508)
		(drill 0.254)
		(layers "F.Cu" "B.Cu")
		(net "GND")
	)
	(via
		(at 69.753226 -65.000886)
		(size 0.508)
		(drill 0.254)
		(layers "F.Cu" "B.Cu")
		(net "GND")
	)
	(via
		(at 34.736024 -13.8938)
		(size 0.508)
		(drill 0.254)
		(layers "F.Cu" "B.Cu")
		(net "GND")
	)
	(via
		(at 121.499376 1.994154)
		(size 0.508)
		(drill 0.254)
		(layers "F.Cu" "B.Cu")
		(net "GND")
	)
	(via
		(at 263.096756 -70.80885)
		(size 0.5588)
		(drill 0.3048)
		(layers "F.Cu" "B.Cu")
		(net "GND")
	)
	(via
		(at 222.749872 -2.314956)
		(size 0.508)
		(drill 0.254)
		(layers "F.Cu" "B.Cu")
		(net "GND")
	)
	(via
		(at 493.7252 -61.4172)
		(size 0.508)
		(drill 0.254)
		(layers "F.Cu" "B.Cu")
		(net "GND")
	)
	(via
		(at 254.49911 -98.18624)
		(size 0.508)
		(drill 0.254)
		(layers "F.Cu" "B.Cu")
		(net "GND")
	)
	(via
		(at 477.934528 1.999996)
		(size 0.5588)
		(drill 0.3048)
		(layers "F.Cu" "B.Cu")
		(net "GND")
	)
	(via
		(at 472.71432 -136.42086)
		(size 0.508)
		(drill 0.254)
		(layers "F.Cu" "B.Cu")
		(net "GND")
	)
	(via
		(at -2.128266 -167.832024)
		(size 0.5588)
		(drill 0.3048)
		(layers "F.Cu" "B.Cu")
		(net "GND")
	)
	(via
		(at 374.730264 -133.907276)
		(size 0.508)
		(drill 0.254)
		(layers "F.Cu" "B.Cu")
		(net "GND")
	)
	(via
		(at 457.230734 -167.832024)
		(size 0.5588)
		(drill 0.3048)
		(layers "F.Cu" "B.Cu")
		(net "GND")
	)
	(via
		(at 448.5894 -113.7666)
		(size 0.508)
		(drill 0.254)
		(layers "F.Cu" "B.Cu")
		(net "GND")
	)
	(via
		(at 372.0084 -108.712)
		(size 0.508)
		(drill 0.254)
		(layers "F.Cu" "B.Cu")
		(net "GND")
	)
	(via
		(at 125.651768 -63.829184)
		(size 0.508)
		(drill 0.254)
		(layers "F.Cu" "B.Cu")
		(net "GND")
	)
	(via
		(at 291.51072 -92.061538)
		(size 0.508)
		(drill 0.254)
		(layers "F.Cu" "B.Cu")
		(net "GND")
	)
	(via
		(at 35.499802 -82.1944)
		(size 0.508)
		(drill 0.254)
		(layers "F.Cu" "B.Cu")
		(net "GND")
	)
	(via
		(at 142.039848 -94.042738)
		(size 0.508)
		(drill 0.254)
		(layers "F.Cu" "B.Cu")
		(net "GND")
	)
	(via
		(at 351.174812 -131.26847)
		(size 0.508)
		(drill 0.254)
		(layers "F.Cu" "B.Cu")
		(net "GND")
	)
	(via
		(at 185.790078 -2.151634)
		(size 0.508)
		(drill 0.254)
		(layers "F.Cu" "B.Cu")
		(net "GND")
	)
	(via
		(at 140.246354 -55.409338)
		(size 0.508)
		(drill 0.254)
		(layers "F.Cu" "B.Cu")
		(net "GND")
	)
	(via
		(at 313.031124 -162.243262)
		(size 0.5588)
		(drill 0.3048)
		(layers "F.Cu" "B.Cu")
		(net "GND")
	)
	(via
		(at 261.121906 -79.353156)
		(size 0.508)
		(drill 0.254)
		(layers "F.Cu" "B.Cu")
		(net "GND")
	)
	(via
		(at 175.505364 5.428996)
		(size 0.5588)
		(drill 0.3048)
		(layers "F.Cu" "B.Cu")
		(net "GND")
	)
	(via
		(at 390.578594 -155.802838)
		(size 0.508)
		(drill 0.254)
		(layers "F.Cu" "B.Cu")
		(net "GND")
	)
	(via
		(at 127.392176 -11.912092)
		(size 0.508)
		(drill 0.254)
		(layers "F.Cu" "B.Cu")
		(net "GND")
	)
	(via
		(at 181.441598 -1.994408)
		(size 0.508)
		(drill 0.254)
		(layers "F.Cu" "B.Cu")
		(net "GND")
	)
	(via
		(at 491.520734 -163.361624)
		(size 0.5588)
		(drill 0.3048)
		(layers "F.Cu" "B.Cu")
		(net "GND")
	)
	(via
		(at 373.544846 -75.094846)
		(size 0.4572)
		(drill 0.2032)
		(layers "F.Cu" "B.Cu")
		(net "GND")
	)
	(via
		(at 217.472006 -7.6454)
		(size 0.508)
		(drill 0.254)
		(layers "F.Cu" "B.Cu")
		(net "GND")
	)
	(via
		(at 68.799456 -136.397746)
		(size 0.508)
		(drill 0.254)
		(layers "F.Cu" "B.Cu")
		(net "GND")
	)
	(via
		(at 352.9584 -80.0608)
		(size 0.508)
		(drill 0.254)
		(layers "F.Cu" "B.Cu")
		(net "GND")
	)
	(via
		(at 374.121934 14.926056)
		(size 0.5588)
		(drill 0.3048)
		(layers "F.Cu" "B.Cu")
		(net "GND")
	)
	(via
		(at 207.411828 -136.410446)
		(size 0.508)
		(drill 0.254)
		(layers "F.Cu" "B.Cu")
		(net "GND")
	)
	(via
		(at 459.557374 -63.626492)
		(size 0.508)
		(drill 0.254)
		(layers "F.Cu" "B.Cu")
		(net "GND")
	)
	(via
		(at 20.1676 -127.5461)
		(size 0.508)
		(drill 0.254)
		(layers "F.Cu" "B.Cu")
		(net "GND")
	)
	(via
		(at 230.399844 -9.156446)
		(size 0.508)
		(drill 0.254)
		(layers "F.Cu" "B.Cu")
		(net "GND")
	)
	(via
		(at 3.546856 13.609066)
		(size 0.5588)
		(drill 0.3048)
		(layers "F.Cu" "B.Cu")
		(net "GND")
	)
	(via
		(at 468.4014 -139.954)
		(size 0.508)
		(drill 0.254)
		(layers "F.Cu" "B.Cu")
		(net "GND")
	)
	(via
		(at 348.234 -81.8896)
		(size 0.508)
		(drill 0.254)
		(layers "F.Cu" "B.Cu")
		(net "GND")
	)
	(via
		(at 210.387946 -4.346956)
		(size 0.508)
		(drill 0.254)
		(layers "F.Cu" "B.Cu")
		(net "GND")
	)
	(via
		(at 136.812274 -99.986338)
		(size 0.508)
		(drill 0.254)
		(layers "F.Cu" "B.Cu")
		(net "GND")
	)
	(via
		(at 229.091236 -26.682954)
		(size 0.508)
		(drill 0.254)
		(layers "F.Cu" "B.Cu")
		(net "GND")
	)
	(via
		(at 206.855314 -86.349078)
		(size 0.5588)
		(drill 0.3048)
		(layers "F.Cu" "B.Cu")
		(net "GND")
	)
	(via
		(at 264.801096 -91.25204)
		(size 0.508)
		(drill 0.254)
		(layers "F.Cu" "B.Cu")
		(net "GND")
	)
	(via
		(at 261.36727 -60.54344)
		(size 0.508)
		(drill 0.254)
		(layers "F.Cu" "B.Cu")
		(net "GND")
	)
	(via
		(at 90.911934 14.926056)
		(size 0.5588)
		(drill 0.3048)
		(layers "F.Cu" "B.Cu")
		(net "GND")
	)
	(via
		(at 226.149916 0.444754)
		(size 0.508)
		(drill 0.254)
		(layers "F.Cu" "B.Cu")
		(net "GND")
	)
	(via
		(at 107.027472 -140.208)
		(size 0.508)
		(drill 0.254)
		(layers "F.Cu" "B.Cu")
		(net "GND")
	)
	(via
		(at 238.437928 -13.948156)
		(size 0.508)
		(drill 0.254)
		(layers "F.Cu" "B.Cu")
		(net "GND")
	)
	(via
		(at 344.815668 -101.950774)
		(size 0.508)
		(drill 0.254)
		(layers "F.Cu" "B.Cu")
		(net "GND")
	)
	(via
		(at 124.049536 -21.517356)
		(size 0.508)
		(drill 0.254)
		(layers "F.Cu" "B.Cu")
		(net "GND")
	)
	(via
		(at 121.499376 -131.016756)
		(size 0.508)
		(drill 0.254)
		(layers "F.Cu" "B.Cu")
		(net "GND")
	)
	(via
		(at 499.282466 -19.143726)
		(size 0.508)
		(drill 0.254)
		(layers "F.Cu" "B.Cu")
		(net "GND")
	)
	(via
		(at 398.950688 -91.982036)
		(size 0.508)
		(drill 0.254)
		(layers "F.Cu" "B.Cu")
		(net "GND")
	)
	(via
		(at 49.24933 -17.208246)
		(size 0.508)
		(drill 0.254)
		(layers "F.Cu" "B.Cu")
		(net "GND")
	)
	(via
		(at 241.621818 -98.681286)
		(size 0.508)
		(drill 0.254)
		(layers "F.Cu" "B.Cu")
		(net "GND")
	)
	(via
		(at 449.051934 10.354056)
		(size 0.5588)
		(drill 0.3048)
		(layers "F.Cu" "B.Cu")
		(net "GND")
	)
	(via
		(at 462.444592 -39.506398)
		(size 0.508)
		(drill 0.254)
		(layers "F.Cu" "B.Cu")
		(net "GND")
	)
	(via
		(at 401.93468 -95.96882)
		(size 0.508)
		(drill 0.254)
		(layers "F.Cu" "B.Cu")
		(net "GND")
	)
	(via
		(at 40.749474 0.457454)
		(size 0.508)
		(drill 0.254)
		(layers "F.Cu" "B.Cu")
		(net "GND")
	)
	(via
		(at 408.411934 14.926056)
		(size 0.5588)
		(drill 0.3048)
		(layers "F.Cu" "B.Cu")
		(net "GND")
	)
	(via
		(at 418.571934 9.084056)
		(size 0.5588)
		(drill 0.3048)
		(layers "F.Cu" "B.Cu")
		(net "GND")
	)
	(via
		(at 108.888276 -82.339942)
		(size 0.5588)
		(drill 0.3048)
		(layers "F.Cu" "B.Cu")
		(net "GND")
	)
	(via
		(at 118.783862 -94.538038)
		(size 0.508)
		(drill 0.254)
		(layers "F.Cu" "B.Cu")
		(net "GND")
	)
	(via
		(at 362.933488 -0.423672)
		(size 0.5588)
		(drill 0.3048)
		(layers "F.Cu" "B.Cu")
		(net "GND")
	)
	(via
		(at 109.340396 -99.986338)
		(size 0.508)
		(drill 0.254)
		(layers "F.Cu" "B.Cu")
		(net "GND")
	)
	(via
		(at 336.7786 -59.679586)
		(size 0.508)
		(drill 0.254)
		(layers "F.Cu" "B.Cu")
		(net "GND")
	)
	(via
		(at 236.470698 -51.132486)
		(size 0.508)
		(drill 0.254)
		(layers "F.Cu" "B.Cu")
		(net "GND")
	)
	(via
		(at 473.50553 -21.465286)
		(size 0.508)
		(drill 0.254)
		(layers "F.Cu" "B.Cu")
		(net "GND")
	)
	(via
		(at 376.744738 -78.294738)
		(size 0.4572)
		(drill 0.2032)
		(layers "F.Cu" "B.Cu")
		(net "GND")
	)
	(via
		(at 473.5322 -113.7666)
		(size 0.508)
		(drill 0.254)
		(layers "F.Cu" "B.Cu")
		(net "GND")
	)
	(via
		(at 171.3484 -88.392)
		(size 0.508)
		(drill 0.254)
		(layers "F.Cu" "B.Cu")
		(net "GND")
	)
	(via
		(at 294.999918 -155.612846)
		(size 0.508)
		(drill 0.254)
		(layers "F.Cu" "B.Cu")
		(net "GND")
	)
	(via
		(at 462.310734 -163.361624)
		(size 0.5588)
		(drill 0.3048)
		(layers "F.Cu" "B.Cu")
		(net "GND")
	)
	(via
		(at 218.44254 -145.998946)
		(size 0.508)
		(drill 0.254)
		(layers "F.Cu" "B.Cu")
		(net "GND")
	)
	(via
		(at 61.821568 -125.245876)
		(size 0.508)
		(drill 0.254)
		(layers "F.Cu" "B.Cu")
		(net "GND")
	)
	(via
		(at 414.655762 -87.159084)
		(size 0.508)
		(drill 0.254)
		(layers "F.Cu" "B.Cu")
		(net "GND")
	)
	(via
		(at 240.763298 -83.32724)
		(size 0.508)
		(drill 0.254)
		(layers "F.Cu" "B.Cu")
		(net "GND")
	)
	(via
		(at 382.4224 -134.747)
		(size 0.508)
		(drill 0.254)
		(layers "F.Cu" "B.Cu")
		(net "GND")
	)
	(via
		(at 307.749956 -145.998946)
		(size 0.508)
		(drill 0.254)
		(layers "F.Cu" "B.Cu")
		(net "GND")
	)
	(via
		(at 299.151802 -7.607046)
		(size 0.508)
		(drill 0.254)
		(layers "F.Cu" "B.Cu")
		(net "GND")
	)
	(via
		(at 313.699906 -146.011646)
		(size 0.508)
		(drill 0.254)
		(layers "F.Cu" "B.Cu")
		(net "GND")
	)
	(via
		(at 35.880802 -63.427864)
		(size 0.508)
		(drill 0.254)
		(layers "F.Cu" "B.Cu")
		(net "GND")
	)
	(via
		(at -4.367276 -162.243262)
		(size 0.5588)
		(drill 0.3048)
		(layers "F.Cu" "B.Cu")
		(net "GND")
	)
	(via
		(at 227.799138 -16.7513)
		(size 0.508)
		(drill 0.254)
		(layers "F.Cu" "B.Cu")
		(net "GND")
	)
	(via
		(at 240.771934 9.084056)
		(size 0.5588)
		(drill 0.3048)
		(layers "F.Cu" "B.Cu")
		(net "GND")
	)
	(via
		(at 111.783876 -75.159616)
		(size 0.5588)
		(drill 0.3048)
		(layers "F.Cu" "B.Cu")
		(net "GND")
	)
	(via
		(at 118.041928 -145.998946)
		(size 0.508)
		(drill 0.254)
		(layers "F.Cu" "B.Cu")
		(net "GND")
	)
	(via
		(at 246.5832 -3.3528)
		(size 0.508)
		(drill 0.254)
		(layers "F.Cu" "B.Cu")
		(net "GND")
	)
	(via
		(at 199.898 -78.3082)
		(size 0.5588)
		(drill 0.3048)
		(layers "F.Cu" "B.Cu")
		(net "GND")
	)
	(via
		(at -2.942844 -50.035206)
		(size 0.5588)
		(drill 0.3048)
		(layers "F.Cu" "B.Cu")
		(net "GND")
	)
	(via
		(at 243.274596 -130.249676)
		(size 0.508)
		(drill 0.254)
		(layers "F.Cu" "B.Cu")
		(net "GND")
	)
	(via
		(at 430.98593 -9.71804)
		(size 0.508)
		(drill 0.254)
		(layers "F.Cu" "B.Cu")
		(net "GND")
	)
	(via
		(at 232.9434 -164.9222)
		(size 0.5588)
		(drill 0.3048)
		(layers "F.Cu" "B.Cu")
		(net "GND")
	)
	(via
		(at 237.136432 -4.2926)
		(size 0.508)
		(drill 0.254)
		(layers "F.Cu" "B.Cu")
		(net "GND")
	)
	(via
		(at 7.598156 -141.621002)
		(size 0.508)
		(drill 0.254)
		(layers "F.Cu" "B.Cu")
		(net "GND")
	)
	(via
		(at 450.876924 -162.243262)
		(size 0.5588)
		(drill 0.3048)
		(layers "F.Cu" "B.Cu")
		(net "GND")
	)
	(via
		(at 462.306924 -162.243262)
		(size 0.5588)
		(drill 0.3048)
		(layers "F.Cu" "B.Cu")
		(net "GND")
	)
	(via
		(at 226.111816 -26.488136)
		(size 0.508)
		(drill 0.254)
		(layers "F.Cu" "B.Cu")
		(net "GND")
	)
	(via
		(at 51.541934 14.926056)
		(size 0.5588)
		(drill 0.3048)
		(layers "F.Cu" "B.Cu")
		(net "GND")
	)
	(via
		(at 317.09995 -11.927078)
		(size 0.508)
		(drill 0.254)
		(layers "F.Cu" "B.Cu")
		(net "GND")
	)
	(via
		(at 317.505334 -167.832024)
		(size 0.5588)
		(drill 0.3048)
		(layers "F.Cu" "B.Cu")
		(net "GND")
	)
	(via
		(at 42.748454 -84.57311)
		(size 0.5588)
		(drill 0.3048)
		(layers "F.Cu" "B.Cu")
		(net "GND")
	)
	(via
		(at 227.792534 -11.912092)
		(size 0.508)
		(drill 0.254)
		(layers "F.Cu" "B.Cu")
		(net "GND")
	)
	(via
		(at 241.621818 -90.756486)
		(size 0.508)
		(drill 0.254)
		(layers "F.Cu" "B.Cu")
		(net "GND")
	)
	(via
		(at 247.631204 -58.561986)
		(size 0.508)
		(drill 0.254)
		(layers "F.Cu" "B.Cu")
		(net "GND")
	)
	(via
		(at 427.461934 12.894056)
		(size 0.5588)
		(drill 0.3048)
		(layers "F.Cu" "B.Cu")
		(net "GND")
	)
	(via
		(at 89.498678 -91.25204)
		(size 0.508)
		(drill 0.254)
		(layers "F.Cu" "B.Cu")
		(net "GND")
	)
	(via
		(at 472.7702 -118.5672)
		(size 0.508)
		(drill 0.254)
		(layers "F.Cu" "B.Cu")
		(net "GND")
	)
	(via
		(at 498.581934 14.926056)
		(size 0.5588)
		(drill 0.3048)
		(layers "F.Cu" "B.Cu")
		(net "GND")
	)
	(via
		(at 255.830578 -135.010398)
		(size 0.508)
		(drill 0.254)
		(layers "F.Cu" "B.Cu")
		(net "GND")
	)
	(via
		(at 315.399928 -129.568956)
		(size 0.508)
		(drill 0.254)
		(layers "F.Cu" "B.Cu")
		(net "GND")
	)
	(via
		(at 243.338604 -58.06694)
		(size 0.508)
		(drill 0.254)
		(layers "F.Cu" "B.Cu")
		(net "GND")
	)
	(via
		(at 499.917466 -19.804126)
		(size 0.508)
		(drill 0.254)
		(layers "F.Cu" "B.Cu")
		(net "GND")
	)
	(via
		(at 181.27472 -15.47114)
		(size 0.508)
		(drill 0.254)
		(layers "F.Cu" "B.Cu")
		(net "GND")
	)
	(via
		(at 80.055212 -78.869286)
		(size 0.508)
		(drill 0.254)
		(layers "F.Cu" "B.Cu")
		(net "GND")
	)
	(via
		(at 61.821568 -7.6454)
		(size 0.508)
		(drill 0.254)
		(layers "F.Cu" "B.Cu")
		(net "GND")
	)
	(via
		(at 128.699768 0.508)
		(size 0.508)
		(drill 0.254)
		(layers "F.Cu" "B.Cu")
		(net "GND")
	)
	(via
		(at 346.2655 -102.0318)
		(size 0.508)
		(drill 0.254)
		(layers "F.Cu" "B.Cu")
		(net "GND")
	)
	(via
		(at 135.336534 -167.832024)
		(size 0.5588)
		(drill 0.3048)
		(layers "F.Cu" "B.Cu")
		(net "GND")
	)
	(via
		(at 468.660734 -163.361624)
		(size 0.5588)
		(drill 0.3048)
		(layers "F.Cu" "B.Cu")
		(net "GND")
	)
	(via
		(at 404.601934 14.926056)
		(size 0.5588)
		(drill 0.3048)
		(layers "F.Cu" "B.Cu")
		(net "GND")
	)
	(via
		(at 448.340734 -164.479224)
		(size 0.5588)
		(drill 0.3048)
		(layers "F.Cu" "B.Cu")
		(net "GND")
	)
	(via
		(at 178.59248 -17.62252)
		(size 0.508)
		(drill 0.254)
		(layers "F.Cu" "B.Cu")
		(net "GND")
	)
	(via
		(at 232.1052 -125.9332)
		(size 0.508)
		(drill 0.254)
		(layers "F.Cu" "B.Cu")
		(net "GND")
	)
	(via
		(at 316.387734 -167.832024)
		(size 0.5588)
		(drill 0.3048)
		(layers "F.Cu" "B.Cu")
		(net "GND")
	)
	(via
		(at 36.040822 -16.696944)
		(size 0.508)
		(drill 0.254)
		(layers "F.Cu" "B.Cu")
		(net "GND")
	)
	(via
		(at 35.880802 -95.939864)
		(size 0.508)
		(drill 0.254)
		(layers "F.Cu" "B.Cu")
		(net "GND")
	)
	(via
		(at 408.411934 9.084056)
		(size 0.5588)
		(drill 0.3048)
		(layers "F.Cu" "B.Cu")
		(net "GND")
	)
	(via
		(at 117.454934 -167.832024)
		(size 0.5588)
		(drill 0.3048)
		(layers "F.Cu" "B.Cu")
		(net "GND")
	)
	(via
		(at 456.671934 12.894056)
		(size 0.5588)
		(drill 0.3048)
		(layers "F.Cu" "B.Cu")
		(net "GND")
	)
	(via
		(at 70.611746 -59.55284)
		(size 0.508)
		(drill 0.254)
		(layers "F.Cu" "B.Cu")
		(net "GND")
	)
	(via
		(at 358.979724 -162.268662)
		(size 0.5588)
		(drill 0.3048)
		(layers "F.Cu" "B.Cu")
		(net "GND")
	)
	(via
		(at 206.194914 -86.349078)
		(size 0.5588)
		(drill 0.3048)
		(layers "F.Cu" "B.Cu")
		(net "GND")
	)
	(via
		(at 487.984546 -35.686746)
		(size 0.508)
		(drill 0.254)
		(layers "F.Cu" "B.Cu")
		(net "GND")
	)
	(via
		(at 457.2 -33.687258)
		(size 0.508)
		(drill 0.254)
		(layers "F.Cu" "B.Cu")
		(net "GND")
	)
	(via
		(at 167.259 -130.5306)
		(size 0.508)
		(drill 0.254)
		(layers "F.Cu" "B.Cu")
		(net "GND")
	)
	(via
		(at 178.689 -141.1605)
		(size 0.508)
		(drill 0.254)
		(layers "F.Cu" "B.Cu")
		(net "GND")
	)
	(via
		(at 443.260734 -167.832024)
		(size 0.5588)
		(drill 0.3048)
		(layers "F.Cu" "B.Cu")
		(net "GND")
	)
	(via
		(at 288.93516 -93.547184)
		(size 0.508)
		(drill 0.254)
		(layers "F.Cu" "B.Cu")
		(net "GND")
	)
	(via
		(at 241.621818 -85.803486)
		(size 0.508)
		(drill 0.254)
		(layers "F.Cu" "B.Cu")
		(net "GND")
	)
	(via
		(at 381.79375 -101.039676)
		(size 0.508)
		(drill 0.254)
		(layers "F.Cu" "B.Cu")
		(net "GND")
	)
	(via
		(at 148.061934 9.084056)
		(size 0.5588)
		(drill 0.3048)
		(layers "F.Cu" "B.Cu")
		(net "GND")
	)
	(via
		(at 477.550734 -163.361624)
		(size 0.5588)
		(drill 0.3048)
		(layers "F.Cu" "B.Cu")
		(net "GND")
	)
	(via
		(at 356.96525 -115.204494)
		(size 0.508)
		(drill 0.254)
		(layers "F.Cu" "B.Cu")
		(net "GND")
	)
	(via
		(at 440.7281 -15.4051)
		(size 0.508)
		(drill 0.254)
		(layers "F.Cu" "B.Cu")
		(net "GND")
	)
	(via
		(at 128.690878 -153.552144)
		(size 0.508)
		(drill 0.254)
		(layers "F.Cu" "B.Cu")
		(net "GND")
	)
	(via
		(at 188.977524 -162.243262)
		(size 0.5588)
		(drill 0.3048)
		(layers "F.Cu" "B.Cu")
		(net "GND")
	)
	(via
		(at 84.347812 -76.39304)
		(size 0.508)
		(drill 0.254)
		(layers "F.Cu" "B.Cu")
		(net "GND")
	)
	(via
		(at 393.171934 14.926056)
		(size 0.5588)
		(drill 0.3048)
		(layers "F.Cu" "B.Cu")
		(net "GND")
	)
	(via
		(at 240.763298 -74.411586)
		(size 0.508)
		(drill 0.254)
		(layers "F.Cu" "B.Cu")
		(net "GND")
	)
	(via
		(at 39.859712 -48.273462)
		(size 0.508)
		(drill 0.254)
		(layers "F.Cu" "B.Cu")
		(net "GND")
	)
	(via
		(at 147.41144 -59.58586)
		(size 0.508)
		(drill 0.254)
		(layers "F.Cu" "B.Cu")
		(net "GND")
	)
	(via
		(at 74.904346 -88.775286)
		(size 0.508)
		(drill 0.254)
		(layers "F.Cu" "B.Cu")
		(net "GND")
	)
	(via
		(at 353.14382 -131.23926)
		(size 0.508)
		(drill 0.254)
		(layers "F.Cu" "B.Cu")
		(net "GND")
	)
	(via
		(at 370.332 -158.3436)
		(size 0.508)
		(drill 0.254)
		(layers "F.Cu" "B.Cu")
		(net "GND")
	)
	(via
		(at 323.321934 14.926056)
		(size 0.5588)
		(drill 0.3048)
		(layers "F.Cu" "B.Cu")
		(net "GND")
	)
	(via
		(at 313.699906 -18.757646)
		(size 0.508)
		(drill 0.254)
		(layers "F.Cu" "B.Cu")
		(net "GND")
	)
	(via
		(at 393.730734 -165.596824)
		(size 0.5588)
		(drill 0.3048)
		(layers "F.Cu" "B.Cu")
		(net "GND")
	)
	(via
		(at 315.701934 14.926056)
		(size 0.5588)
		(drill 0.3048)
		(layers "F.Cu" "B.Cu")
		(net "GND")
	)
	(via
		(at 397.64335 -111.802164)
		(size 0.508)
		(drill 0.254)
		(layers "F.Cu" "B.Cu")
		(net "GND")
	)
	(via
		(at 441.990734 -166.714424)
		(size 0.5588)
		(drill 0.3048)
		(layers "F.Cu" "B.Cu")
		(net "GND")
	)
	(via
		(at 286.3596 -78.193138)
		(size 0.508)
		(drill 0.254)
		(layers "F.Cu" "B.Cu")
		(net "GND")
	)
	(via
		(at 429.290734 -166.714424)
		(size 0.5588)
		(drill 0.3048)
		(layers "F.Cu" "B.Cu")
		(net "GND")
	)
	(via
		(at 471.645742 -23.1648)
		(size 0.508)
		(drill 0.254)
		(layers "F.Cu" "B.Cu")
		(net "GND")
	)
	(via
		(at 296.651934 14.926056)
		(size 0.5588)
		(drill 0.3048)
		(layers "F.Cu" "B.Cu")
		(net "GND")
	)
	(via
		(at 72.1487 -153.6065)
		(size 0.508)
		(drill 0.254)
		(layers "F.Cu" "B.Cu")
		(net "GND")
	)
	(via
		(at 449.051934 11.624056)
		(size 0.5588)
		(drill 0.3048)
		(layers "F.Cu" "B.Cu")
		(net "GND")
	)
	(via
		(at 441.431934 9.084056)
		(size 0.5588)
		(drill 0.3048)
		(layers "F.Cu" "B.Cu")
		(net "GND")
	)
	(via
		(at 148.699474 -2.314956)
		(size 0.508)
		(drill 0.254)
		(layers "F.Cu" "B.Cu")
		(net "GND")
	)
	(via
		(at 202.349862 -9.156446)
		(size 0.508)
		(drill 0.254)
		(layers "F.Cu" "B.Cu")
		(net "GND")
	)
	(via
		(at 304.388266 -53.923184)
		(size 0.508)
		(drill 0.254)
		(layers "F.Cu" "B.Cu")
		(net "GND")
	)
	(via
		(at 83.291934 14.926056)
		(size 0.5588)
		(drill 0.3048)
		(layers "F.Cu" "B.Cu")
		(net "GND")
	)
	(via
		(at 284.331664 -148.7678)
		(size 0.508)
		(drill 0.254)
		(layers "F.Cu" "B.Cu")
		(net "GND")
	)
	(via
		(at 13.335 -16.1798)
		(size 0.508)
		(drill 0.254)
		(layers "F.Cu" "B.Cu")
		(net "GND")
	)
	(via
		(at 288.07664 -102.958138)
		(size 0.508)
		(drill 0.254)
		(layers "F.Cu" "B.Cu")
		(net "GND")
	)
	(via
		(at 352.7679 -132.655564)
		(size 0.508)
		(drill 0.254)
		(layers "F.Cu" "B.Cu")
		(net "GND")
	)
	(via
		(at 259.65023 -63.51524)
		(size 0.508)
		(drill 0.254)
		(layers "F.Cu" "B.Cu")
		(net "GND")
	)
	(via
		(at 436.351934 13.910056)
		(size 0.5588)
		(drill 0.3048)
		(layers "F.Cu" "B.Cu")
		(net "GND")
	)
	(via
		(at 109.340396 -98.005138)
		(size 0.508)
		(drill 0.254)
		(layers "F.Cu" "B.Cu")
		(net "GND")
	)
	(via
		(at 260.290818 -75.148186)
		(size 0.5588)
		(drill 0.3048)
		(layers "F.Cu" "B.Cu")
		(net "GND")
	)
	(via
		(at 35.8902 -74.676)
		(size 0.508)
		(drill 0.254)
		(layers "F.Cu" "B.Cu")
		(net "GND")
	)
	(via
		(at 473.181934 10.354056)
		(size 0.5588)
		(drill 0.3048)
		(layers "F.Cu" "B.Cu")
		(net "GND")
	)
	(via
		(at 38.81755 -60.183522)
		(size 0.5588)
		(drill 0.3048)
		(layers "F.Cu" "B.Cu")
		(net "GND")
	)
	(via
		(at 297.384724 -162.243262)
		(size 0.5588)
		(drill 0.3048)
		(layers "F.Cu" "B.Cu")
		(net "GND")
	)
	(via
		(at 17.1196 -99.48926)
		(size 0.508)
		(drill 0.254)
		(layers "F.Cu" "B.Cu")
		(net "GND")
	)
	(via
		(at 150.979124 -162.243262)
		(size 0.5588)
		(drill 0.3048)
		(layers "F.Cu" "B.Cu")
		(net "GND")
	)
	(via
		(at 128.677162 -9.0932)
		(size 0.508)
		(drill 0.254)
		(layers "F.Cu" "B.Cu")
		(net "GND")
	)
	(via
		(at 390.70915 -97.605596)
		(size 0.508)
		(drill 0.254)
		(layers "F.Cu" "B.Cu")
		(net "GND")
	)
	(via
		(at 112.774222 -96.023938)
		(size 0.508)
		(drill 0.254)
		(layers "F.Cu" "B.Cu")
		(net "GND")
	)
	(via
		(at 172.2374 -83.7184)
		(size 0.508)
		(drill 0.254)
		(layers "F.Cu" "B.Cu")
		(net "GND")
	)
	(via
		(at 105.571036 -53.923184)
		(size 0.508)
		(drill 0.254)
		(layers "F.Cu" "B.Cu")
		(net "GND")
	)
	(via
		(at 344.088974 -101.966776)
		(size 0.508)
		(drill 0.254)
		(layers "F.Cu" "B.Cu")
		(net "GND")
	)
	(via
		(at 7.01675 -18.787618)
		(size 0.508)
		(drill 0.254)
		(layers "F.Cu" "B.Cu")
		(net "GND")
	)
	(via
		(at 234.551728 -17.208246)
		(size 0.508)
		(drill 0.254)
		(layers "F.Cu" "B.Cu")
		(net "GND")
	)
	(via
		(at 85.044534 -167.832024)
		(size 0.5588)
		(drill 0.3048)
		(layers "F.Cu" "B.Cu")
		(net "GND")
	)
	(via
		(at 286.93364 -59.371484)
		(size 0.508)
		(drill 0.254)
		(layers "F.Cu" "B.Cu")
		(net "GND")
	)
	(via
		(at 77.479906 -93.23324)
		(size 0.508)
		(drill 0.254)
		(layers "F.Cu" "B.Cu")
		(net "GND")
	)
	(via
		(at 454.690734 -166.714424)
		(size 0.5588)
		(drill 0.3048)
		(layers "F.Cu" "B.Cu")
		(net "GND")
	)
	(via
		(at 75.59929 1.994154)
		(size 0.508)
		(drill 0.254)
		(layers "F.Cu" "B.Cu")
		(net "GND")
	)
	(via
		(at 125.651768 -74.725784)
		(size 0.508)
		(drill 0.254)
		(layers "F.Cu" "B.Cu")
		(net "GND")
	)
	(via
		(at 73.437496 -13.948156)
		(size 0.508)
		(drill 0.254)
		(layers "F.Cu" "B.Cu")
		(net "GND")
	)
	(via
		(at 474.505528 -158.52902)
		(size 0.5588)
		(drill 0.3048)
		(layers "F.Cu" "B.Cu")
		(net "GND")
	)
	(via
		(at 119.642382 -98.005138)
		(size 0.508)
		(drill 0.254)
		(layers "F.Cu" "B.Cu")
		(net "GND")
	)
	(via
		(at 461.60055 -122.25528)
		(size 0.508)
		(drill 0.254)
		(layers "F.Cu" "B.Cu")
		(net "GND")
	)
	(via
		(at 385.7498 -103.251)
		(size 0.508)
		(drill 0.254)
		(layers "F.Cu" "B.Cu")
		(net "GND")
	)
	(via
		(at 281.208734 -88.099138)
		(size 0.508)
		(drill 0.254)
		(layers "F.Cu" "B.Cu")
		(net "GND")
	)
	(via
		(at 140.246354 -82.155284)
		(size 0.508)
		(drill 0.254)
		(layers "F.Cu" "B.Cu")
		(net "GND")
	)
	(via
		(at 235.612178 -53.60924)
		(size 0.508)
		(drill 0.254)
		(layers "F.Cu" "B.Cu")
		(net "GND")
	)
	(via
		(at 408.1018 -1.1684)
		(size 0.508)
		(drill 0.254)
		(layers "F.Cu" "B.Cu")
		(net "GND")
	)
	(via
		(at 203.510134 -167.832024)
		(size 0.5588)
		(drill 0.3048)
		(layers "F.Cu" "B.Cu")
		(net "GND")
	)
	(via
		(at 389.22325 -119.528844)
		(size 0.508)
		(drill 0.254)
		(layers "F.Cu" "B.Cu")
		(net "GND")
	)
	(via
		(at 70.611746 -81.34604)
		(size 0.508)
		(drill 0.254)
		(layers "F.Cu" "B.Cu")
		(net "GND")
	)
	(via
		(at 383.27965 -100.181156)
		(size 0.508)
		(drill 0.254)
		(layers "F.Cu" "B.Cu")
		(net "GND")
	)
	(via
		(at 299.237146 -54.913784)
		(size 0.508)
		(drill 0.254)
		(layers "F.Cu" "B.Cu")
		(net "GND")
	)
	(via
		(at 424.0149 -17.770348)
		(size 0.508)
		(drill 0.254)
		(layers "F.Cu" "B.Cu")
		(net "GND")
	)
	(via
		(at 50.860452 -150.193756)
		(size 0.508)
		(drill 0.254)
		(layers "F.Cu" "B.Cu")
		(net "GND")
	)
	(via
		(at 329.671934 9.084056)
		(size 0.5588)
		(drill 0.3048)
		(layers "F.Cu" "B.Cu")
		(net "GND")
	)
	(via
		(at 8.255 -20.774914)
		(size 0.508)
		(drill 0.254)
		(layers "F.Cu" "B.Cu")
		(net "GND")
	)
	(via
		(at 237.329218 -57.57164)
		(size 0.508)
		(drill 0.254)
		(layers "F.Cu" "B.Cu")
		(net "GND")
	)
	(via
		(at 19.106134 -167.832024)
		(size 0.5588)
		(drill 0.3048)
		(layers "F.Cu" "B.Cu")
		(net "GND")
	)
	(via
		(at 129.011934 14.926056)
		(size 0.5588)
		(drill 0.3048)
		(layers "F.Cu" "B.Cu")
		(net "GND")
	)
	(via
		(at 380.471934 14.926056)
		(size 0.5588)
		(drill 0.3048)
		(layers "F.Cu" "B.Cu")
		(net "GND")
	)
	(via
		(at 273.197828 -58.381138)
		(size 0.508)
		(drill 0.254)
		(layers "F.Cu" "B.Cu")
		(net "GND")
	)
	(via
		(at 343.79408 -136.51992)
		(size 0.508)
		(drill 0.254)
		(layers "F.Cu" "B.Cu")
		(net "GND")
	)
	(via
		(at 144.449546 -18.757646)
		(size 0.508)
		(drill 0.254)
		(layers "F.Cu" "B.Cu")
		(net "GND")
	)
	(via
		(at 125.711458 -2.314956)
		(size 0.508)
		(drill 0.254)
		(layers "F.Cu" "B.Cu")
		(net "GND")
	)
	(via
		(at 109.055916 -101.471984)
		(size 0.508)
		(drill 0.254)
		(layers "F.Cu" "B.Cu")
		(net "GND")
	)
	(via
		(at 76.449428 -148.771356)
		(size 0.508)
		(drill 0.254)
		(layers "F.Cu" "B.Cu")
		(net "GND")
	)
	(via
		(at 496.189 -140.1826)
		(size 0.508)
		(drill 0.254)
		(layers "F.Cu" "B.Cu")
		(net "GND")
	)
	(via
		(at 120.649492 -139.170156)
		(size 0.508)
		(drill 0.254)
		(layers "F.Cu" "B.Cu")
		(net "GND")
	)
	(via
		(at 287.21812 -70.763384)
		(size 0.508)
		(drill 0.254)
		(layers "F.Cu" "B.Cu")
		(net "GND")
	)
	(via
		(at 72.136 -13.8938)
		(size 0.508)
		(drill 0.254)
		(layers "F.Cu" "B.Cu")
		(net "GND")
	)
	(via
		(at 295.80332 -70.763384)
		(size 0.508)
		(drill 0.254)
		(layers "F.Cu" "B.Cu")
		(net "GND")
	)
	(via
		(at 31.39948 -18.744946)
		(size 0.508)
		(drill 0.254)
		(layers "F.Cu" "B.Cu")
		(net "GND")
	)
	(via
		(at 157.198568 -141.1732)
		(size 0.508)
		(drill 0.254)
		(layers "F.Cu" "B.Cu")
		(net "GND")
	)
	(via
		(at 186.649868 -134.4422)
		(size 0.508)
		(drill 0.254)
		(layers "F.Cu" "B.Cu")
		(net "GND")
	)
	(via
		(at 309.411878 -11.916156)
		(size 0.508)
		(drill 0.254)
		(layers "F.Cu" "B.Cu")
		(net "GND")
	)
	(via
		(at 77.479906 -62.52464)
		(size 0.508)
		(drill 0.254)
		(layers "F.Cu" "B.Cu")
		(net "GND")
	)
	(via
		(at 497.311934 9.084056)
		(size 0.5588)
		(drill 0.3048)
		(layers "F.Cu" "B.Cu")
		(net "GND")
	)
	(via
		(at 206.501746 1.994154)
		(size 0.508)
		(drill 0.254)
		(layers "F.Cu" "B.Cu")
		(net "GND")
	)
	(via
		(at 35.499802 -73.2028)
		(size 0.508)
		(drill 0.254)
		(layers "F.Cu" "B.Cu")
		(net "GND")
	)
	(via
		(at 234.551728 -7.607046)
		(size 0.508)
		(drill 0.254)
		(layers "F.Cu" "B.Cu")
		(net "GND")
	)
	(via
		(at 294.08628 -58.876438)
		(size 0.508)
		(drill 0.254)
		(layers "F.Cu" "B.Cu")
		(net "GND")
	)
	(via
		(at 392.19505 -116.094764)
		(size 0.508)
		(drill 0.254)
		(layers "F.Cu" "B.Cu")
		(net "GND")
	)
	(via
		(at 407.141934 14.926056)
		(size 0.5588)
		(drill 0.3048)
		(layers "F.Cu" "B.Cu")
		(net "GND")
	)
	(via
		(at 80.055212 -55.094886)
		(size 0.508)
		(drill 0.254)
		(layers "F.Cu" "B.Cu")
		(net "GND")
	)
	(via
		(at 19.6342 -99.2124)
		(size 0.508)
		(drill 0.254)
		(layers "F.Cu" "B.Cu")
		(net "GND")
	)
	(via
		(at 344.911934 9.084056)
		(size 0.5588)
		(drill 0.3048)
		(layers "F.Cu" "B.Cu")
		(net "GND")
	)
	(via
		(at 11.05027 -136.833356)
		(size 0.508)
		(drill 0.254)
		(layers "F.Cu" "B.Cu")
		(net "GND")
	)
	(via
		(at 422.940734 -167.832024)
		(size 0.5588)
		(drill 0.3048)
		(layers "F.Cu" "B.Cu")
		(net "GND")
	)
	(via
		(at 61.821568 -131.016756)
		(size 0.508)
		(drill 0.254)
		(layers "F.Cu" "B.Cu")
		(net "GND")
	)
	(via
		(at 146.098768 -134.4041)
		(size 0.508)
		(drill 0.254)
		(layers "F.Cu" "B.Cu")
		(net "GND")
	)
	(arc
		(start 307.250846 -66.800984)
		(mid 307.212442 -66.993584)
		(end 307.103272 -67.156838)
		(width 0.254)
		(layer "F.Cu")
		(net "GND")
	)
	(arc
		(start 142.250414 -66.800984)
		(mid 142.21201 -66.993584)
		(end 142.10284 -67.156838)
		(width 0.254)
		(layer "F.Cu")
		(net "GND")
	)
	(segment
		(start 247.4595 -12.954)
		(end 246.61876 -12.954)
		(width 0.4064)
		(layer "B.Cu")
		(net "GND")
	)
	(segment
		(start 313.699906 -139.170156)
		(end 313.699906 -137.877296)
		(width 0.4064)
		(layer "B.Cu")
		(net "GND")
	)
	(segment
		(start 244.3607 -8.1534)
		(end 243.2558 -8.1534)
		(width 0.4572)
		(layer "B.Cu")
		(net "GND")
	)
	(segment
		(start 282.250388 -142.477236)
		(end 282.24988 -142.476982)
		(width 0.254)
		(layer "B.Cu")
		(net "GND")
	)
	(segment
		(start 227.849938 -137.877296)
		(end 227.849938 -139.089892)
		(width 0.4064)
		(layer "B.Cu")
		(net "GND")
	)
	(segment
		(start 312.850276 -142.477236)
		(end 312.849768 -142.476982)
		(width 0.4064)
		(layer "B.Cu")
		(net "GND")
	)
	(segment
		(start 369.156488 -42.887138)
		(end 370.290852 -42.887138)
		(width 0.254)
		(layer "B.Cu")
		(net "GND")
	)
	(segment
		(start 95.70339 -136.72947)
		(end 96.27997 -136.15289)
		(width 0.4064)
		(layer "B.Cu")
		(net "GND")
	)
	(segment
		(start 448.7926 -147.955)
		(end 448.945 -147.8026)
		(width 0.254)
		(layer "B.Cu")
		(net "GND")
	)
	(segment
		(start 52.649374 -5.621782)
		(end 52.649374 -4.82346)
		(width 0.254)
		(layer "B.Cu")
		(net "GND")
	)
	(segment
		(start 77.299312 -13.363956)
		(end 77.299566 -13.36421)
		(width 0.4064)
		(layer "B.Cu")
		(net "GND")
	)
	(segment
		(start 315.399928 -9.156446)
		(end 315.399928 -10.623042)
		(width 0.4064)
		(layer "B.Cu")
		(net "GND")
	)
	(segment
		(start 218.44254 -129.546096)
		(end 218.44254 -129.564892)
		(width 0.4064)
		(layer "B.Cu")
		(net "GND")
	)
	(segment
		(start 408.10942 -21.39442)
		(end 408.16784 -21.336)
		(width 0.254)
		(layer "B.Cu")
		(net "GND")
	)
	(segment
		(start 374.2563 -101.1936)
		(end 374.0277 -100.965)
		(width 0.254)
		(layer "B.Cu")
		(net "GND")
	)
	(segment
		(start 162.31743 -76.08697)
		(end 163.407852 -76.08697)
		(width 0.381)
		(layer "B.Cu")
		(net "GND")
	)
	(segment
		(start 256.529586 -12.613386)
		(end 255.87198 -12.613386)
		(width 0.508)
		(layer "B.Cu")
		(net "GND")
	)
	(segment
		(start 368.623342 -37.82187)
		(end 369.187984 -38.386512)
		(width 0.254)
		(layer "B.Cu")
		(net "GND")
	)
	(segment
		(start 260.0706 -19.6088)
		(end 260.0706 -18.8214)
		(width 0.4064)
		(layer "B.Cu")
		(net "GND")
	)
	(segment
		(start 299.249846 -24.824182)
		(end 299.249846 -25.683718)
		(width 0.4064)
		(layer "B.Cu")
		(net "GND")
	)
	(segment
		(start 379.6792 -45.176948)
		(end 379.6792 -45.1485)
		(width 0.254)
		(layer "B.Cu")
		(net "GND")
	)
	(segment
		(start 112.397032 -149.8092)
		(end 112.9538 -149.8092)
		(width 0.4064)
		(layer "B.Cu")
		(net "GND")
	)
	(segment
		(start 196.40042 -137.877296)
		(end 196.399912 -137.877296)
		(width 0.4064)
		(layer "B.Cu")
		(net "GND")
	)
	(segment
		(start 242.299998 -15.222982)
		(end 242.299998 -13.36421)
		(width 0.4064)
		(layer "B.Cu")
		(net "GND")
	)
	(segment
		(start 410.6672 -88.265)
		(end 410.6672 -87.757)
		(width 0.254)
		(layer "B.Cu")
		(net "GND")
	)
	(segment
		(start 335.89722 -85.71484)
		(end 335.399634 -85.71484)
		(width 0.4064)
		(layer "B.Cu")
		(net "GND")
	)
	(segment
		(start 278.330152 -125.69444)
		(end 278.330152 -126.820168)
		(width 0.4064)
		(layer "B.Cu")
		(net "GND")
	)
	(segment
		(start 240.599976 -15.222982)
		(end 240.599976 -14.85265)
		(width 0.4064)
		(layer "B.Cu")
		(net "GND")
	)
	(segment
		(start 50.949352 -5.621782)
		(end 50.949352 -3.851656)
		(width 0.4064)
		(layer "B.Cu")
		(net "GND")
	)
	(segment
		(start 411.662118 -94.881446)
		(end 411.56636 -94.977204)
		(width 0.254)
		(layer "B.Cu")
		(net "GND")
	)
	(segment
		(start 61.149484 -148.758656)
		(end 61.136784 -148.771356)
		(width 0.4064)
		(layer "B.Cu")
		(net "GND")
	)
	(segment
		(start 444.701168 -147.693634)
		(end 444.02248 -147.693634)
		(width 0.254)
		(layer "B.Cu")
		(net "GND")
	)
	(segment
		(start 229.54996 -6.63702)
		(end 229.54996 -5.621782)
		(width 0.4064)
		(layer "B.Cu")
		(net "GND")
	)
	(segment
		(start 491.93958 -154.23134)
		(end 491.93958 -154.18816)
		(width 0.254)
		(layer "B.Cu")
		(net "GND")
	)
	(segment
		(start 68.799456 0.457454)
		(end 68.799456 -1.021842)
		(width 0.4064)
		(layer "B.Cu")
		(net "GND")
	)
	(segment
		(start 206.600298 -15.222982)
		(end 206.59979 -15.222982)
		(width 0.4064)
		(layer "B.Cu")
		(net "GND")
	)
	(segment
		(start 312.849768 -142.476982)
		(end 312.849768 -141.663928)
		(width 0.4064)
		(layer "B.Cu")
		(net "GND")
	)
	(segment
		(start 440.182 -142.24)
		(end 440.275726 -142.333726)
		(width 0.254)
		(layer "B.Cu")
		(net "GND")
	)
	(segment
		(start 217.650314 -152.078436)
		(end 217.649806 -152.078182)
		(width 0.254)
		(layer "B.Cu")
		(net "GND")
	)
	(segment
		(start 321.591432 -17.78)
		(end 322.065904 -18.254472)
		(width 0.4064)
		(layer "B.Cu")
		(net "GND")
	)
	(segment
		(start 42.449496 -137.877296)
		(end 42.449496 -139.157456)
		(width 0.4064)
		(layer "B.Cu")
		(net "GND")
	)
	(segment
		(start 72.1995 -10.623042)
		(end 72.1995 -11.835892)
		(width 0.4064)
		(layer "B.Cu")
		(net "GND")
	)
	(segment
		(start 288.200338 -24.824182)
		(end 288.19983 -24.824182)
		(width 0.4064)
		(layer "B.Cu")
		(net "GND")
	)
	(segment
		(start 56.049418 -147.478496)
		(end 56.049418 -148.771356)
		(width 0.4064)
		(layer "B.Cu")
		(net "GND")
	)
	(segment
		(start 309.437278 -11.916156)
		(end 309.449978 -11.903456)
		(width 0.4064)
		(layer "B.Cu")
		(net "GND")
	)
	(segment
		(start 488.5944 -140.7668)
		(end 488.5944 -140.7414)
		(width 0.254)
		(layer "B.Cu")
		(net "GND")
	)
	(segment
		(start 239.750346 -128.276096)
		(end 239.749838 -128.276096)
		(width 0.4064)
		(layer "B.Cu")
		(net "GND")
	)
	(segment
		(start 375.371106 -38.363906)
		(end 376.009916 -38.363906)
		(width 0.254)
		(layer "B.Cu")
		(net "GND")
	)
	(segment
		(start 32.160464 -14.026642)
		(end 32.160464 -13.338556)
		(width 0.4064)
		(layer "B.Cu")
		(net "GND")
	)
	(segment
		(start 206.59979 -152.078182)
		(end 206.59979 -150.282656)
		(width 0.4064)
		(layer "B.Cu")
		(net "GND")
	)
	(segment
		(start 62.849506 -20.224242)
		(end 62.849506 -21.437092)
		(width 0.4064)
		(layer "B.Cu")
		(net "GND")
	)
	(segment
		(start 410.616146 -35.683952)
		(end 410.616146 -34.934652)
		(width 0.4572)
		(layer "B.Cu")
		(net "GND")
	)
	(segment
		(start 208.299812 -24.095964)
		(end 208.0514 -23.847552)
		(width 0.254)
		(layer "B.Cu")
		(net "GND")
	)
	(segment
		(start 89.789 -140.208)
		(end 90.167206 -139.829794)
		(width 0.4064)
		(layer "B.Cu")
		(net "GND")
	)
	(segment
		(start 280.549858 -132.876036)
		(end 280.549858 -134.253478)
		(width 0.508)
		(layer "B.Cu")
		(net "GND")
	)
	(segment
		(start 307.749956 -128.276096)
		(end 307.750464 -128.276096)
		(width 0.4064)
		(layer "B.Cu")
		(net "GND")
	)
	(segment
		(start 126.353824 -151.053546)
		(end 126.353824 -150.9776)
		(width 0.254)
		(layer "B.Cu")
		(net "GND")
	)
	(segment
		(start 64.549528 -24.011382)
		(end 64.549528 -24.824182)
		(width 0.4064)
		(layer "B.Cu")
		(net "GND")
	)
	(segment
		(start 32.160464 -23.627842)
		(end 32.160464 -22.939756)
		(width 0.4064)
		(layer "B.Cu")
		(net "GND")
	)
	(segment
		(start 77.299566 -151.65705)
		(end 77.299312 -151.656796)
		(width 0.4064)
		(layer "B.Cu")
		(net "GND")
	)
	(segment
		(start 458.353414 -126.674118)
		(end 458.216 -126.536704)
		(width 0.254)
		(layer "B.Cu")
		(net "GND")
	)
	(segment
		(start 169.799 -84.1502)
		(end 169.799 -84.455)
		(width 0.254)
		(layer "B.Cu")
		(net "GND")
	)
	(segment
		(start 91.43365 -12.613386)
		(end 90.871548 -12.613386)
		(width 0.381)
		(layer "B.Cu")
		(net "GND")
	)
	(segment
		(start 113.849404 -18.786348)
		(end 113.849404 -20.224242)
		(width 0.4064)
		(layer "B.Cu")
		(net "GND")
	)
	(segment
		(start 26.67 -156.083)
		(end 26.896568 -155.856432)
		(width 0.4064)
		(layer "B.Cu")
		(net "GND")
	)
	(segment
		(start 278.849836 -142.476982)
		(end 278.849836 -141.176756)
		(width 0.4064)
		(layer "B.Cu")
		(net "GND")
	)
	(segment
		(start 466.598 -11.1252)
		(end 466.598 -12.319)
		(width 0.508)
		(layer "B.Cu")
		(net "GND")
	)
	(segment
		(start 235.49991 -10.623042)
		(end 235.49991 -11.878056)
		(width 0.4064)
		(layer "B.Cu")
		(net "GND")
	)
	(segment
		(start 112.701832 -18.0594)
		(end 113.905538 -18.0594)
		(width 0.381)
		(layer "B.Cu")
		(net "GND")
	)
	(segment
		(start 149.549358 -132.876036)
		(end 149.549358 -131.016756)
		(width 0.4064)
		(layer "B.Cu")
		(net "GND")
	)
	(segment
		(start 206.59979 -15.222982)
		(end 206.59979 -13.427456)
		(width 0.4064)
		(layer "B.Cu")
		(net "GND")
	)
	(segment
		(start 102.7938 -140.208)
		(end 103.678736 -140.208)
		(width 0.4064)
		(layer "B.Cu")
		(net "GND")
	)
	(segment
		(start 242.299998 -5.621782)
		(end 242.299998 -7.606792)
		(width 0.4064)
		(layer "B.Cu")
		(net "GND")
	)
	(segment
		(start 20.8534 -93.5482)
		(end 20.193 -94.2086)
		(width 0.4064)
		(layer "B.Cu")
		(net "GND")
	)
	(segment
		(start 221.900496 -152.078436)
		(end 221.899988 -152.078182)
		(width 0.4064)
		(layer "B.Cu")
		(net "GND")
	)
	(segment
		(start 494.281968 -40.4876)
		(end 494.8682 -40.4876)
		(width 0.254)
		(layer "B.Cu")
		(net "GND")
	)
	(segment
		(start 342.4555 -82.677)
		(end 342.9 -82.677)
		(width 0.254)
		(layer "B.Cu")
		(net "GND")
	)
	(segment
		(start 243.149882 -22.073362)
		(end 243.274596 -22.198076)
		(width 0.4064)
		(layer "B.Cu")
		(net "GND")
	)
	(segment
		(start 202.349862 -9.156446)
		(end 202.349862 -10.623042)
		(width 0.4064)
		(layer "B.Cu")
		(net "GND")
	)
	(segment
		(start 489.08589 -34.563812)
		(end 489.7374 -34.563812)
		(width 0.508)
		(layer "B.Cu")
		(net "GND")
	)
	(segment
		(start 255.830578 -135.010398)
		(end 255.830578 -135.670798)
		(width 0.4064)
		(layer "B.Cu")
		(net "GND")
	)
	(segment
		(start 134.160514 -150.219156)
		(end 134.160514 -150.193756)
		(width 0.4064)
		(layer "B.Cu")
		(net "GND")
	)
	(segment
		(start 464.41868 -141.6812)
		(end 464.372452 -141.727428)
		(width 0.254)
		(layer "B.Cu")
		(net "GND")
	)
	(segment
		(start 316.820804 -31.191708)
		(end 316.442598 -30.813502)
		(width 0.381)
		(layer "B.Cu")
		(net "GND")
	)
	(segment
		(start 222.749872 -128.276096)
		(end 222.75038 -128.276096)
		(width 0.4064)
		(layer "B.Cu")
		(net "GND")
	)
	(segment
		(start 240.599976 -5.621782)
		(end 240.599976 -5.25145)
		(width 0.4064)
		(layer "B.Cu")
		(net "GND")
	)
	(segment
		(start 53.442108 -2.292096)
		(end 53.442108 -2.310892)
		(width 0.4064)
		(layer "B.Cu")
		(net "GND")
	)
	(segment
		(start 371.945154 -75.018646)
		(end 372.2751 -74.6887)
		(width 0.254)
		(layer "B.Cu")
		(net "GND")
	)
	(segment
		(start 33.703768 -4.5212)
		(end 33.703768 -3.830574)
		(width 0.4064)
		(layer "B.Cu")
		(net "GND")
	)
	(segment
		(start 484.1367 -144.5514)
		(end 483.782624 -144.5514)
		(width 0.254)
		(layer "B.Cu")
		(net "GND")
	)
	(segment
		(start 57.74944 -2.314956)
		(end 57.74944 -1.021842)
		(width 0.4064)
		(layer "B.Cu")
		(net "GND")
	)
	(segment
		(start 239.749838 -128.276096)
		(end 239.749838 -129.568956)
		(width 0.4064)
		(layer "B.Cu")
		(net "GND")
	)
	(segment
		(start 166.66718 -147.74926)
		(end 166.16934 -147.74926)
		(width 0.254)
		(layer "B.Cu")
		(net "GND")
	)
	(segment
		(start 115.549426 -13.452856)
		(end 115.460526 -13.363956)
		(width 0.4064)
		(layer "B.Cu")
		(net "GND")
	)
	(segment
		(start 90.167206 -139.829794)
		(end 90.814906 -139.829794)
		(width 0.4064)
		(layer "B.Cu")
		(net "GND")
	)
	(segment
		(start 56.899302 -24.478996)
		(end 56.899302 -22.965156)
		(width 0.4064)
		(layer "B.Cu")
		(net "GND")
	)
	(segment
		(start 168.6814 -88.392)
		(end 168.9862 -88.392)
		(width 0.4064)
		(layer "B.Cu")
		(net "GND")
	)
	(segment
		(start 78.14945 -137.877042)
		(end 78.14945 -137.877296)
		(width 0.4064)
		(layer "B.Cu")
		(net "GND")
	)
	(segment
		(start 34.74212 -11.893296)
		(end 34.74212 -11.912092)
		(width 0.4064)
		(layer "B.Cu")
		(net "GND")
	)
	(segment
		(start 112.397032 -145.0086)
		(end 113.417604 -145.0086)
		(width 0.4572)
		(layer "B.Cu")
		(net "GND")
	)
	(segment
		(start 202.349862 -1.021842)
		(end 202.349862 0.444754)
		(width 0.4064)
		(layer "B.Cu")
		(net "GND")
	)
	(segment
		(start 201.500486 -5.621782)
		(end 201.499978 -5.621782)
		(width 0.4064)
		(layer "B.Cu")
		(net "GND")
	)
	(segment
		(start 60.299346 -150.308056)
		(end 60.210446 -150.219156)
		(width 0.4064)
		(layer "B.Cu")
		(net "GND")
	)
	(segment
		(start 261.4676 -1.905)
		(end 261.4676 -3.321812)
		(width 0.508)
		(layer "B.Cu")
		(net "GND")
	)
	(segment
		(start 232.94975 -142.182596)
		(end 232.94975 -140.617956)
		(width 0.4064)
		(layer "B.Cu")
		(net "GND")
	)
	(segment
		(start 22.637496 -31.679896)
		(end 22.6314 -31.6738)
		(width 0.508)
		(layer "B.Cu")
		(net "GND")
	)
	(segment
		(start 127.392176 -2.292096)
		(end 127.44958 -2.234692)
		(width 0.4064)
		(layer "B.Cu")
		(net "GND")
	)
	(segment
		(start 329.356466 -56.616346)
		(end 329.356466 -56.215534)
		(width 0.254)
		(layer "B.Cu")
		(net "GND")
	)
	(segment
		(start 280.549858 -13.452856)
		(end 280.460958 -13.363956)
		(width 0.4064)
		(layer "B.Cu")
		(net "GND")
	)
	(segment
		(start 91.454478 -18.01749)
		(end 90.874088 -18.01749)
		(width 0.4064)
		(layer "B.Cu")
		(net "GND")
	)
	(segment
		(start 233.799888 -11.916156)
		(end 233.799888 -10.623042)
		(width 0.4064)
		(layer "B.Cu")
		(net "GND")
	)
	(segment
		(start 274.258532 -135.4074)
		(end 275.286978 -135.4074)
		(width 0.4572)
		(layer "B.Cu")
		(net "GND")
	)
	(segment
		(start 72.1995 -2.234692)
		(end 72.1995 -1.021842)
		(width 0.4064)
		(layer "B.Cu")
		(net "GND")
	)
	(segment
		(start 312.850276 -5.621782)
		(end 312.849768 -5.621782)
		(width 0.4064)
		(layer "B.Cu")
		(net "GND")
	)
	(segment
		(start 129.999486 0.444754)
		(end 129.999486 -1.021842)
		(width 0.4064)
		(layer "B.Cu")
		(net "GND")
	)
	(segment
		(start 141.049502 -11.916156)
		(end 141.049502 -10.623042)
		(width 0.4064)
		(layer "B.Cu")
		(net "GND")
	)
	(segment
		(start 225.299778 -152.078182)
		(end 225.299778 -150.308056)
		(width 0.4064)
		(layer "B.Cu")
		(net "GND")
	)
	(segment
		(start 139.34948 -10.623042)
		(end 139.34948 -9.156446)
		(width 0.4064)
		(layer "B.Cu")
		(net "GND")
	)
	(segment
		(start 69.64934 -7.509002)
		(end 69.64934 -5.621782)
		(width 0.4064)
		(layer "B.Cu")
		(net "GND")
	)
	(segment
		(start 71.095362 -23.6982)
		(end 71.095362 -23.7998)
		(width 0.254)
		(layer "B.Cu")
		(net "GND")
	)
	(segment
		(start 215.85174 -7.607046)
		(end 215.949784 -7.509002)
		(width 0.4064)
		(layer "B.Cu")
		(net "GND")
	)
	(segment
		(start 331.45476 -8.2169)
		(end 331.31506 -8.3566)
		(width 0.254)
		(layer "B.Cu")
		(net "GND")
	)
	(segment
		(start 44.149518 -9.20115)
		(end 44.092114 -9.143746)
		(width 0.4064)
		(layer "B.Cu")
		(net "GND")
	)
	(segment
		(start 113.849404 -20.224242)
		(end 113.849404 -21.567648)
		(width 0.4064)
		(layer "B.Cu")
		(net "GND")
	)
	(segment
		(start 165.1127 3.6322)
		(end 164.00018 3.6322)
		(width 0.254)
		(layer "B.Cu")
		(net "GND")
	)
	(segment
		(start 289.93592 -150.344124)
		(end 289.810952 -150.219156)
		(width 0.4064)
		(layer "B.Cu")
		(net "GND")
	)
	(segment
		(start 391.3378 -112.2553)
		(end 390.93775 -112.65535)
		(width 0.254)
		(layer "B.Cu")
		(net "GND")
	)
	(segment
		(start 199.800464 -137.877296)
		(end 199.799956 -137.877296)
		(width 0.4064)
		(layer "B.Cu")
		(net "GND")
	)
	(segment
		(start 195.550282 -15.222982)
		(end 195.549774 -15.222982)
		(width 0.4064)
		(layer "B.Cu")
		(net "GND")
	)
	(segment
		(start 238.899954 -24.011382)
		(end 238.899954 -24.824182)
		(width 0.4064)
		(layer "B.Cu")
		(net "GND")
	)
	(segment
		(start 39.049452 -20.224242)
		(end 39.049452 -21.517356)
		(width 0.4064)
		(layer "B.Cu")
		(net "GND")
	)
	(segment
		(start 207.450436 -20.224242)
		(end 207.449928 -20.224242)
		(width 0.4064)
		(layer "B.Cu")
		(net "GND")
	)
	(segment
		(start 31.39948 -9.139682)
		(end 31.395416 -9.139682)
		(width 0.381)
		(layer "B.Cu")
		(net "GND")
	)
	(segment
		(start 314.760102 -30.227778)
		(end 314.760102 -29.511752)
		(width 0.381)
		(layer "B.Cu")
		(net "GND")
	)
	(segment
		(start 418.0205 -32.7025)
		(end 417.926012 -32.608012)
		(width 0.381)
		(layer "B.Cu")
		(net "GND")
	)
	(segment
		(start -4.36626 -119.72036)
		(end -4.36626 -118.803928)
		(width 0.254)
		(layer "B.Cu")
		(net "GND")
	)
	(segment
		(start 48.399446 -18.757646)
		(end 48.399446 -20.224242)
		(width 0.4064)
		(layer "B.Cu")
		(net "GND")
	)
	(segment
		(start 96.416368 1.47574)
		(end 96.578928 1.6383)
		(width 0.508)
		(layer "B.Cu")
		(net "GND")
	)
	(segment
		(start 46.699424 -1.021842)
		(end 46.699424 -2.314956)
		(width 0.4064)
		(layer "B.Cu")
		(net "GND")
	)
	(segment
		(start 217.3986 -23.7236)
		(end 217.3986 -23.038562)
		(width 0.4064)
		(layer "B.Cu")
		(net "GND")
	)
	(segment
		(start 191.314832 -18.3642)
		(end 190.933832 -18.7452)
		(width 0.4064)
		(layer "B.Cu")
		(net "GND")
	)
	(segment
		(start 58.599578 -24.824182)
		(end 58.599578 -25.638252)
		(width 0.4064)
		(layer "B.Cu")
		(net "GND")
	)
	(segment
		(start 227.000308 -142.477236)
		(end 226.9998 -142.476982)
		(width 0.254)
		(layer "B.Cu")
		(net "GND")
	)
	(segment
		(start 381.5842 -1.559814)
		(end 382.397 -1.559814)
		(width 0.254)
		(layer "B.Cu")
		(net "GND")
	)
	(segment
		(start 152.949402 -132.876036)
		(end 152.949402 -131.571746)
		(width 0.4064)
		(layer "B.Cu")
		(net "GND")
	)
	(segment
		(start 388.972806 -8.696452)
		(end 388.972806 -7.859014)
		(width 0.254)
		(layer "B.Cu")
		(net "GND")
	)
	(segment
		(start 74.749406 -128.276096)
		(end 74.749406 -129.568956)
		(width 0.4064)
		(layer "B.Cu")
		(net "GND")
	)
	(segment
		(start 407.517854 -54.229)
		(end 407.136854 -53.848)
		(width 0.254)
		(layer "B.Cu")
		(net "GND")
	)
	(segment
		(start 195.550282 -132.876036)
		(end 195.549774 -132.875782)
		(width 0.4064)
		(layer "B.Cu")
		(net "GND")
	)
	(segment
		(start 231.249982 -5.25145)
		(end 231.249728 -5.251196)
		(width 0.4064)
		(layer "B.Cu")
		(net "GND")
	)
	(segment
		(start 443.92596 -18.9738)
		(end 444.119 -19.16684)
		(width 0.254)
		(layer "B.Cu")
		(net "GND")
	)
	(segment
		(start 144.436846 -139.170156)
		(end 144.411446 -139.170156)
		(width 0.4064)
		(layer "B.Cu")
		(net "GND")
	)
	(segment
		(start 500.661686 -38.711886)
		(end 500.331232 -38.711886)
		(width 0.254)
		(layer "B.Cu")
		(net "GND")
	)
	(segment
		(start 75.59929 -151.707596)
		(end 75.59929 -150.219156)
		(width 0.4064)
		(layer "B.Cu")
		(net "GND")
	)
	(segment
		(start 197.160896 -23.627842)
		(end 197.160896 -22.939756)
		(width 0.4064)
		(layer "B.Cu")
		(net "GND")
	)
	(segment
		(start 51.79949 -137.877296)
		(end 51.79949 -139.157456)
		(width 0.4064)
		(layer "B.Cu")
		(net "GND")
	)
	(segment
		(start 444.26886 -130.50266)
		(end 444.26886 -129.836926)
		(width 0.254)
		(layer "B.Cu")
		(net "GND")
	)
	(segment
		(start 77.299312 -131.029456)
		(end 77.286612 -131.016756)
		(width 0.4064)
		(layer "B.Cu")
		(net "GND")
	)
	(segment
		(start 125.749558 -137.877296)
		(end 125.749558 -139.157456)
		(width 0.4064)
		(layer "B.Cu")
		(net "GND")
	)
	(segment
		(start 380.365 -20.193)
		(end 380.365 -20.810982)
		(width 0.254)
		(layer "B.Cu")
		(net "GND")
	)
	(segment
		(start 445.937132 -31.932626)
		(end 445.564006 -31.5595)
		(width 0.4064)
		(layer "B.Cu")
		(net "GND")
	)
	(segment
		(start 496.4557 -127.26162)
		(end 496.77066 -126.94666)
		(width 0.254)
		(layer "B.Cu")
		(net "GND")
	)
	(segment
		(start 298.40047 -147.478496)
		(end 298.399962 -147.478496)
		(width 0.4064)
		(layer "B.Cu")
		(net "GND")
	)
	(segment
		(start 284.799786 -141.664182)
		(end 284.33776 -141.202156)
		(width 0.4064)
		(layer "B.Cu")
		(net "GND")
	)
	(segment
		(start 310.054244 -23.799546)
		(end 310.299862 -24.045164)
		(width 0.254)
		(layer "B.Cu")
		(net "GND")
	)
	(segment
		(start -1.93421 -43.87596)
		(end -0.500126 -45.310044)
		(width 0.508)
		(layer "B.Cu")
		(net "GND")
	)
	(segment
		(start 220.199966 -142.476982)
		(end 220.199966 -141.664182)
		(width 0.4064)
		(layer "B.Cu")
		(net "GND")
	)
	(segment
		(start 72.142096 -2.310892)
		(end 72.142096 -2.292096)
		(width 0.4064)
		(layer "B.Cu")
		(net "GND")
	)
	(segment
		(start 237.199932 -137.877296)
		(end 237.199932 -139.089892)
		(width 0.4064)
		(layer "B.Cu")
		(net "GND")
	)
	(segment
		(start 205.750414 -1.021842)
		(end 205.749906 -1.021842)
		(width 0.4064)
		(layer "B.Cu")
		(net "GND")
	)
	(segment
		(start 278.849836 -137.877296)
		(end 278.849836 -137.877042)
		(width 0.4064)
		(layer "B.Cu")
		(net "GND")
	)
	(segment
		(start 467.995 -140.3604)
		(end 468.4014 -139.954)
		(width 0.254)
		(layer "B.Cu")
		(net "GND")
	)
	(segment
		(start 76.449428 -2.314956)
		(end 76.449428 -1.021842)
		(width 0.4064)
		(layer "B.Cu")
		(net "GND")
	)
	(segment
		(start 209.150458 -20.224242)
		(end 209.14995 -20.224242)
		(width 0.4064)
		(layer "B.Cu")
		(net "GND")
	)
	(segment
		(start 152.397968 -154.782012)
		(end 152.099518 -155.080462)
		(width 0.4064)
		(layer "B.Cu")
		(net "GND")
	)
	(segment
		(start 69.56044 -131.016756)
		(end 69.56044 -130.991356)
		(width 0.4064)
		(layer "B.Cu")
		(net "GND")
	)
	(segment
		(start 382.397 -1.559814)
		(end 382.397 -1.143)
		(width 0.254)
		(layer "B.Cu")
		(net "GND")
	)
	(segment
		(start 287.349946 0.444754)
		(end 287.349946 -1.021842)
		(width 0.4064)
		(layer "B.Cu")
		(net "GND")
	)
	(segment
		(start 51.79949 -1.021842)
		(end 51.79949 -2.302256)
		(width 0.4064)
		(layer "B.Cu")
		(net "GND")
	)
	(segment
		(start 308.59984 -5.621782)
		(end 308.59984 -3.82524)
		(width 0.254)
		(layer "B.Cu")
		(net "GND")
	)
	(segment
		(start 417.147248 -7.3025)
		(end 416.179 -8.270748)
		(width 0.254)
		(layer "B.Cu")
		(net "GND")
	)
	(segment
		(start 386.541518 -84.057998)
		(end 386.64642 -84.1629)
		(width 0.254)
		(layer "B.Cu")
		(net "GND")
	)
	(segment
		(start 152.099518 -134.849362)
		(end 152.099518 -134.340346)
		(width 0.4064)
		(layer "B.Cu")
		(net "GND")
	)
	(segment
		(start 492.8108 -135.2804)
		(end 493.5982 -136.0678)
		(width 0.254)
		(layer "B.Cu")
		(net "GND")
	)
	(segment
		(start 235.49991 -9.156446)
		(end 235.49991 -8.317484)
		(width 0.4064)
		(layer "B.Cu")
		(net "GND")
	)
	(segment
		(start 383.1844 -156.2608)
		(end 383.7432 -155.702)
		(width 0.4064)
		(layer "B.Cu")
		(net "GND")
	)
	(segment
		(start 77.299566 -3.76301)
		(end 77.299566 -5.621782)
		(width 0.4064)
		(layer "B.Cu")
		(net "GND")
	)
	(segment
		(start 52.398168 -23.774654)
		(end 52.398168 -23.7236)
		(width 0.254)
		(layer "B.Cu")
		(net "GND")
	)
	(segment
		(start 203.2 -17.207992)
		(end 203.2 -15.222982)
		(width 0.4064)
		(layer "B.Cu")
		(net "GND")
	)
	(segment
		(start 241.44986 -128.276096)
		(end 241.44986 -129.568956)
		(width 0.4064)
		(layer "B.Cu")
		(net "GND")
	)
	(segment
		(start 34.799524 -21.437092)
		(end 34.74212 -21.494496)
		(width 0.4064)
		(layer "B.Cu")
		(net "GND")
	)
	(segment
		(start 72.1995 -1.021842)
		(end 72.1995 0.40005)
		(width 0.4064)
		(layer "B.Cu")
		(net "GND")
	)
	(segment
		(start 195.549774 -5.621782)
		(end 195.549774 -7.086346)
		(width 0.4064)
		(layer "B.Cu")
		(net "GND")
	)
	(segment
		(start 198.772018 -13.363956)
		(end 198.7042 -13.431774)
		(width 0.254)
		(layer "B.Cu")
		(net "GND")
	)
	(segment
		(start 383.1844 -156.569664)
		(end 383.1844 -156.2608)
		(width 0.4064)
		(layer "B.Cu")
		(net "GND")
	)
	(segment
		(start 56.899302 -151.732996)
		(end 56.899302 -150.219156)
		(width 0.4064)
		(layer "B.Cu")
		(net "GND")
	)
	(segment
		(start 36.499546 -16.23822)
		(end 36.040822 -16.696944)
		(width 0.4064)
		(layer "B.Cu")
		(net "GND")
	)
	(segment
		(start 378.841 -61.247528)
		(end 378.489972 -60.8965)
		(width 0.254)
		(layer "B.Cu")
		(net "GND")
	)
	(segment
		(start 67.949572 -151.78405)
		(end 67.949318 -151.783796)
		(width 0.4064)
		(layer "B.Cu")
		(net "GND")
	)
	(segment
		(start 300.949868 -24.045164)
		(end 300.949868 -24.824182)
		(width 0.254)
		(layer "B.Cu")
		(net "GND")
	)
	(segment
		(start 152.146 -17.78)
		(end 152.146 -18.711164)
		(width 0.4064)
		(layer "B.Cu")
		(net "GND")
	)
	(segment
		(start 392.557 -27.686)
		(end 392.557 -26.622502)
		(width 0.254)
		(layer "B.Cu")
		(net "GND")
	)
	(segment
		(start 49.249584 -5.621782)
		(end 49.249584 -5.27685)
		(width 0.4064)
		(layer "B.Cu")
		(net "GND")
	)
	(segment
		(start 296.700448 -10.623042)
		(end 296.69994 -10.623042)
		(width 0.4064)
		(layer "B.Cu")
		(net "GND")
	)
	(segment
		(start 453.24141 -4.614672)
		(end 453.24141 -3.852672)
		(width 0.254)
		(layer "B.Cu")
		(net "GND")
	)
	(segment
		(start 309.437278 -148.771356)
		(end 309.411878 -148.771356)
		(width 0.4064)
		(layer "B.Cu")
		(net "GND")
	)
	(segment
		(start 210.849972 -14.410182)
		(end 210.387946 -13.948156)
		(width 0.4064)
		(layer "B.Cu")
		(net "GND")
	)
	(segment
		(start 243.149882 -145.988278)
		(end 243.149882 -147.478242)
		(width 0.508)
		(layer "B.Cu")
		(net "GND")
	)
	(segment
		(start 120.649492 -20.224242)
		(end 120.649492 -18.757646)
		(width 0.4064)
		(layer "B.Cu")
		(net "GND")
	)
	(segment
		(start 42.503344 -104.390952)
		(end 42.365168 -104.252776)
		(width 0.254)
		(layer "B.Cu")
		(net "GND")
	)
	(segment
		(start 292.45052 -10.623042)
		(end 292.450012 -10.623042)
		(width 0.4064)
		(layer "B.Cu")
		(net "GND")
	)
	(segment
		(start 75.59929 -24.453596)
		(end 75.59929 -22.965156)
		(width 0.4064)
		(layer "B.Cu")
		(net "GND")
	)
	(segment
		(start 77.299566 -132.875782)
		(end 77.299566 -132.45465)
		(width 0.4064)
		(layer "B.Cu")
		(net "GND")
	)
	(segment
		(start 267.794232 -12.954)
		(end 268.679168 -12.954)
		(width 0.381)
		(layer "B.Cu")
		(net "GND")
	)
	(segment
		(start 70.461378 -18.757646)
		(end 70.499478 -18.795746)
		(width 0.4064)
		(layer "B.Cu")
		(net "GND")
	)
	(segment
		(start 308.59984 -132.875782)
		(end 308.59984 -131.22656)
		(width 0.4064)
		(layer "B.Cu")
		(net "GND")
	)
	(segment
		(start 198.950326 -24.824182)
		(end 198.949818 -24.824182)
		(width 0.254)
		(layer "B.Cu")
		(net "GND")
	)
	(segment
		(start 206.600298 -24.824182)
		(end 206.59979 -24.824182)
		(width 0.4064)
		(layer "B.Cu")
		(net "GND")
	)
	(segment
		(start 418.719 -32.7025)
		(end 418.0205 -32.7025)
		(width 0.381)
		(layer "B.Cu")
		(net "GND")
	)
	(segment
		(start 91.708732 -12.888468)
		(end 91.43365 -12.613386)
		(width 0.381)
		(layer "B.Cu")
		(net "GND")
	)
	(segment
		(start 39.049452 -18.757646)
		(end 39.049452 -20.224242)
		(width 0.4064)
		(layer "B.Cu")
		(net "GND")
	)
	(segment
		(start 89.789 -149.8092)
		(end 90.153236 -149.444964)
		(width 0.4064)
		(layer "B.Cu")
		(net "GND")
	)
	(segment
		(start 196.399912 0.457454)
		(end 196.342 0.515366)
		(width 0.381)
		(layer "B.Cu")
		(net "GND")
	)
	(segment
		(start 136.799574 -148.691092)
		(end 136.74217 -148.748496)
		(width 0.4064)
		(layer "B.Cu")
		(net "GND")
	)
	(segment
		(start 47.549308 -24.529796)
		(end 47.549308 -22.965156)
		(width 0.4064)
		(layer "B.Cu")
		(net "GND")
	)
	(segment
		(start 322.5292 -135.376412)
		(end 321.59702 -135.376412)
		(width 0.4064)
		(layer "B.Cu")
		(net "GND")
	)
	(segment
		(start 299.249846 -5.621782)
		(end 299.249846 -7.509002)
		(width 0.4064)
		(layer "B.Cu")
		(net "GND")
	)
	(segment
		(start 198.100442 -147.478496)
		(end 198.099934 -147.478496)
		(width 0.4064)
		(layer "B.Cu")
		(net "GND")
	)
	(segment
		(start 458.4954 -144.145)
		(end 458.761592 -144.145)
		(width 0.381)
		(layer "B.Cu")
		(net "GND")
	)
	(segment
		(start 49.249584 -14.87805)
		(end 49.249584 -15.222982)
		(width 0.4064)
		(layer "B.Cu")
		(net "GND")
	)
	(segment
		(start 490.614208 -40.0304)
		(end 491.0455 -40.0304)
		(width 0.254)
		(layer "B.Cu")
		(net "GND")
	)
	(segment
		(start 148.699474 -1.021842)
		(end 148.699474 -2.314956)
		(width 0.4064)
		(layer "B.Cu")
		(net "GND")
	)
	(segment
		(start 490.9058 -52.53609)
		(end 492.01451 -52.53609)
		(width 0.254)
		(layer "B.Cu")
		(net "GND")
	)
	(segment
		(start 224.449894 -11.916156)
		(end 224.449894 -10.623042)
		(width 0.4064)
		(layer "B.Cu")
		(net "GND")
	)
	(segment
		(start 129.149348 -141.663928)
		(end 128.687576 -141.202156)
		(width 0.4064)
		(layer "B.Cu")
		(net "GND")
	)
	(segment
		(start 305.199796 -7.607046)
		(end 305.199796 -5.621782)
		(width 0.4064)
		(layer "B.Cu")
		(net "GND")
	)
	(segment
		(start 316.249812 -132.875782)
		(end 316.249812 -131.016756)
		(width 0.4064)
		(layer "B.Cu")
		(net "GND")
	)
	(segment
		(start 312.12409 -29.505148)
		(end 311.658 -29.971238)
		(width 0.381)
		(layer "B.Cu")
		(net "GND")
	)
	(segment
		(start 10.2108 -126.931928)
		(end 10.193528 -126.9492)
		(width 0.254)
		(layer "B.Cu")
		(net "GND")
	)
	(segment
		(start 291.354256 -131.7752)
		(end 291.354256 -131.084574)
		(width 0.4064)
		(layer "B.Cu")
		(net "GND")
	)
	(segment
		(start 275.111464 -8.1534)
		(end 274.258532 -8.1534)
		(width 0.381)
		(layer "B.Cu")
		(net "GND")
	)
	(segment
		(start 408.04338 -23.814786)
		(end 408.04338 -23.93188)
		(width 0.254)
		(layer "B.Cu")
		(net "GND")
	)
	(segment
		(start 295.85031 -5.621782)
		(end 295.849802 -5.621782)
		(width 0.4064)
		(layer "B.Cu")
		(net "GND")
	)
	(segment
		(start 69.551296 -7.607046)
		(end 69.64934 -7.509002)
		(width 0.4064)
		(layer "B.Cu")
		(net "GND")
	)
	(segment
		(start 33.099502 -139.157456)
		(end 33.086802 -139.170156)
		(width 0.4064)
		(layer "B.Cu")
		(net "GND")
	)
	(segment
		(start 310.054244 -4.5212)
		(end 310.054244 -3.830574)
		(width 0.4064)
		(layer "B.Cu")
		(net "GND")
	)
	(segment
		(start 263.3218 -27.4828)
		(end 260.741668 -27.4828)
		(width 0.381)
		(layer "B.Cu")
		(net "GND")
	)
	(segment
		(start 30.952948 -95.9104)
		(end 31.634938 -95.9104)
		(width 0.254)
		(layer "B.Cu")
		(net "GND")
	)
	(segment
		(start 283.04236 -21.494496)
		(end 283.04236 -21.513292)
		(width 0.4064)
		(layer "B.Cu")
		(net "GND")
	)
	(segment
		(start 418.0078 -17.201134)
		(end 417.7538 -16.947134)
		(width 0.254)
		(layer "B.Cu")
		(net "GND")
	)
	(segment
		(start 315.399928 -147.478496)
		(end 315.400436 -147.478496)
		(width 0.4064)
		(layer "B.Cu")
		(net "GND")
	)
	(segment
		(start 30.549342 -23.495)
		(end 30.549342 -24.824182)
		(width 0.4064)
		(layer "B.Cu")
		(net "GND")
	)
	(segment
		(start 234.65028 -5.621782)
		(end 234.649772 -5.621782)
		(width 0.4064)
		(layer "B.Cu")
		(net "GND")
	)
	(segment
		(start 145.053812 -14.198346)
		(end 145.29943 -14.443964)
		(width 0.254)
		(layer "B.Cu")
		(net "GND")
	)
	(segment
		(start 352.0186 -89.865962)
		(end 352.424492 -89.865962)
		(width 0.254)
		(layer "B.Cu")
		(net "GND")
	)
	(segment
		(start 374.744996 -72.295004)
		(end 375.145046 -71.894954)
		(width 0.254)
		(layer "B.Cu")
		(net "GND")
	)
	(segment
		(start 212.550502 -132.876036)
		(end 212.549994 -132.875782)
		(width 0.4064)
		(layer "B.Cu")
		(net "GND")
	)
	(segment
		(start 59.449462 -148.771356)
		(end 59.449462 -147.478496)
		(width 0.4064)
		(layer "B.Cu")
		(net "GND")
	)
	(segment
		(start 138.499342 -24.824182)
		(end 138.499342 -26.224484)
		(width 0.4064)
		(layer "B.Cu")
		(net "GND")
	)
	(segment
		(start 283.099764 -1.021842)
		(end 283.100272 -1.021842)
		(width 0.4064)
		(layer "B.Cu")
		(net "GND")
	)
	(segment
		(start 71.095362 -3.838956)
		(end 71.095362 -4.4958)
		(width 0.4064)
		(layer "B.Cu")
		(net "GND")
	)
	(segment
		(start 26.289 -76.7334)
		(end 26.0096 -76.7334)
		(width 0.254)
		(layer "B.Cu")
		(net "GND")
	)
	(segment
		(start 464.2612 -146.304)
		(end 462.788 -146.304)
		(width 0.4064)
		(layer "B.Cu")
		(net "GND")
	)
	(segment
		(start 197.250304 -5.621782)
		(end 197.249796 -5.621782)
		(width 0.4064)
		(layer "B.Cu")
		(net "GND")
	)
	(segment
		(start 197.249796 -141.369542)
		(end 197.160896 -141.280642)
		(width 0.4064)
		(layer "B.Cu")
		(net "GND")
	)
	(segment
		(start 78.193392 -149.436836)
		(end 78.193392 -149.371304)
		(width 0.4064)
		(layer "B.Cu")
		(net "GND")
	)
	(segment
		(start 416.223196 -141.269212)
		(end 416.585908 -140.9065)
		(width 0.381)
		(layer "B.Cu")
		(net "GND")
	)
	(segment
		(start 48.399446 -128.276096)
		(end 48.399446 -129.568956)
		(width 0.4064)
		(layer "B.Cu")
		(net "GND")
	)
	(segment
		(start 215.0999 -1.021842)
		(end 215.0999 -2.314956)
		(width 0.4064)
		(layer "B.Cu")
		(net "GND")
	)
	(segment
		(start 145.29943 -24.045164)
		(end 145.29943 -24.824182)
		(width 0.254)
		(layer "B.Cu")
		(net "GND")
	)
	(segment
		(start 256.656332 -8.468868)
		(end 257.048 -8.0772)
		(width 0.4064)
		(layer "B.Cu")
		(net "GND")
	)
	(segment
		(start 34.799524 -1.021842)
		(end 34.799524 0.40005)
		(width 0.4064)
		(layer "B.Cu")
		(net "GND")
	)
	(segment
		(start 378.356368 -68.707)
		(end 378.344684 -68.695316)
		(width 0.254)
		(layer "B.Cu")
		(net "GND")
	)
	(segment
		(start 231.249982 -24.45385)
		(end 231.249728 -24.453596)
		(width 0.4064)
		(layer "B.Cu")
		(net "GND")
	)
	(segment
		(start 243.1034 -27.2288)
		(end 243.1034 -27.813)
		(width 0.4064)
		(layer "B.Cu")
		(net "GND")
	)
	(segment
		(start 227.849938 0.40005)
		(end 227.792534 0.457454)
		(width 0.4064)
		(layer "B.Cu")
		(net "GND")
	)
	(segment
		(start 64.549528 -141.664182)
		(end 64.087502 -141.202156)
		(width 0.4064)
		(layer "B.Cu")
		(net "GND")
	)
	(segment
		(start 371.77218 -51.26228)
		(end 371.8306 -51.3207)
		(width 0.254)
		(layer "B.Cu")
		(net "GND")
	)
	(segment
		(start 281.400504 -10.623042)
		(end 281.399996 -10.623042)
		(width 0.4064)
		(layer "B.Cu")
		(net "GND")
	)
	(segment
		(start 254.789432 -135.4074)
		(end 255.186434 -135.010398)
		(width 0.4572)
		(layer "B.Cu")
		(net "GND")
	)
	(segment
		(start 243.149882 -147.478496)
		(end 243.149882 -149.327362)
		(width 0.4064)
		(layer "B.Cu")
		(net "GND")
	)
	(segment
		(start 286.500316 -5.621782)
		(end 286.499808 -5.621782)
		(width 0.4064)
		(layer "B.Cu")
		(net "GND")
	)
	(segment
		(start 49.249584 -24.824182)
		(end 49.249584 -24.47925)
		(width 0.4064)
		(layer "B.Cu")
		(net "GND")
	)
	(segment
		(start 452.8058 -128.6764)
		(end 452.4248 -129.0574)
		(width 0.254)
		(layer "B.Cu")
		(net "GND")
	)
	(segment
		(start 223.599756 -132.632196)
		(end 223.599756 -131.016756)
		(width 0.4064)
		(layer "B.Cu")
		(net "GND")
	)
	(segment
		(start 91.305126 -145.281142)
		(end 90.861896 -145.281142)
		(width 0.4064)
		(layer "B.Cu")
		(net "GND")
	)
	(segment
		(start 232.099866 -1.021842)
		(end 232.099866 0.444754)
		(width 0.4064)
		(layer "B.Cu")
		(net "GND")
	)
	(segment
		(start 317.09995 -11.927078)
		(end 317.09995 -10.623042)
		(width 0.4064)
		(layer "B.Cu")
		(net "GND")
	)
	(segment
		(start 294.999918 -21.517356)
		(end 294.999918 -20.224242)
		(width 0.4064)
		(layer "B.Cu")
		(net "GND")
	)
	(segment
		(start 229.54996 -24.011382)
		(end 229.087934 -23.549356)
		(width 0.4064)
		(layer "B.Cu")
		(net "GND")
	)
	(segment
		(start 435.2417 -13.9065)
		(end 434.94325 -13.60805)
		(width 0.254)
		(layer "B.Cu")
		(net "GND")
	)
	(segment
		(start 226.7458 -141.4526)
		(end 226.7458 -141.351)
		(width 0.254)
		(layer "B.Cu")
		(net "GND")
	)
	(segment
		(start 205.749906 -128.276096)
		(end 205.749906 -129.568956)
		(width 0.4064)
		(layer "B.Cu")
		(net "GND")
	)
	(segment
		(start 136.74217 -139.147296)
		(end 136.74217 -139.166092)
		(width 0.4064)
		(layer "B.Cu")
		(net "GND")
	)
	(segment
		(start 297.550332 -15.222982)
		(end 297.549824 -15.222982)
		(width 0.4064)
		(layer "B.Cu")
		(net "GND")
	)
	(segment
		(start 117.249448 -7.4676)
		(end 117.071648 -7.6454)
		(width 0.4064)
		(layer "B.Cu")
		(net "GND")
	)
	(segment
		(start 47.549562 -142.477236)
		(end 47.549562 -142.18285)
		(width 0.4064)
		(layer "B.Cu")
		(net "GND")
	)
	(segment
		(start 303.038002 -23.549356)
		(end 303.499774 -24.011128)
		(width 0.4064)
		(layer "B.Cu")
		(net "GND")
	)
	(segment
		(start 47.549562 -152.078436)
		(end 47.549562 -151.78405)
		(width 0.4064)
		(layer "B.Cu")
		(net "GND")
	)
	(segment
		(start 417.81222 -39.9288)
		(end 417.032694 -39.9288)
		(width 0.4572)
		(layer "B.Cu")
		(net "GND")
	)
	(segment
		(start 196.342 -144.977612)
		(end 196.342 -145.941034)
		(width 0.4064)
		(layer "B.Cu")
		(net "GND")
	)
	(segment
		(start 269.748 4.7752)
		(end 271.9578 4.7752)
		(width 0.381)
		(layer "B.Cu")
		(net "GND")
	)
	(segment
		(start 114.699542 -136.397746)
		(end 114.699542 -137.877296)
		(width 0.4064)
		(layer "B.Cu")
		(net "GND")
	)
	(segment
		(start 373.544846 -75.015598)
		(end 373.544846 -75.038458)
		(width 0.254)
		(layer "B.Cu")
		(net "GND")
	)
	(segment
		(start 94.68104 -157.02788)
		(end 93.420946 -157.02788)
		(width 0.508)
		(layer "B.Cu")
		(net "GND")
	)
	(segment
		(start 90.153236 -149.444964)
		(end 90.626692 -149.444964)
		(width 0.4064)
		(layer "B.Cu")
		(net "GND")
	)
	(segment
		(start 235.49991 -2.276856)
		(end 235.49991 -1.021842)
		(width 0.4064)
		(layer "B.Cu")
		(net "GND")
	)
	(segment
		(start 488.7468 -140.589)
		(end 489.189014 -140.589)
		(width 0.254)
		(layer "B.Cu")
		(net "GND")
	)
	(segment
		(start 215.949784 -131.105656)
		(end 215.860884 -131.016756)
		(width 0.4064)
		(layer "B.Cu")
		(net "GND")
	)
	(segment
		(start 234.649772 -131.105656)
		(end 234.560872 -131.016756)
		(width 0.4064)
		(layer "B.Cu")
		(net "GND")
	)
	(segment
		(start 232.100374 -147.478496)
		(end 232.099866 -147.478496)
		(width 0.4064)
		(layer "B.Cu")
		(net "GND")
	)
	(segment
		(start 175.36668 -81.12252)
		(end 175.7172 -80.772)
		(width 0.381)
		(layer "B.Cu")
		(net "GND")
	)
	(segment
		(start 272.027904 -17.7546)
		(end 270.956532 -17.7546)
		(width 0.381)
		(layer "B.Cu")
		(net "GND")
	)
	(segment
		(start 221.899988 -24.824182)
		(end 221.899988 -24.47925)
		(width 0.4064)
		(layer "B.Cu")
		(net "GND")
	)
	(segment
		(start 149.549358 -13.363956)
		(end 149.549358 -15.222982)
		(width 0.4064)
		(layer "B.Cu")
		(net "GND")
	)
	(segment
		(start 369.038632 -26.360882)
		(end 368.967004 -26.360882)
		(width 0.508)
		(layer "B.Cu")
		(net "GND")
	)
	(segment
		(start 175.511206 -85.8774)
		(end 176.6062 -85.8774)
		(width 0.4064)
		(layer "B.Cu")
		(net "GND")
	)
	(segment
		(start 235.49991 -147.478496)
		(end 235.49991 -148.733256)
		(width 0.4064)
		(layer "B.Cu")
		(net "GND")
	)
	(segment
		(start 275.685504 -157.9372)
		(end 274.709128 -156.960824)
		(width 0.381)
		(layer "B.Cu")
		(net "GND")
	)
	(segment
		(start 418.1094 -20.828)
		(end 418.1094 -19.8374)
		(width 0.254)
		(layer "B.Cu")
		(net "GND")
	)
	(segment
		(start 225.299778 -13.452856)
		(end 225.210878 -13.363956)
		(width 0.4064)
		(layer "B.Cu")
		(net "GND")
	)
	(segment
		(start 283.099764 -148.691092)
		(end 283.04236 -148.748496)
		(width 0.4064)
		(layer "B.Cu")
		(net "GND")
	)
	(segment
		(start 294.999918 -128.276096)
		(end 295.000426 -128.276096)
		(width 0.4064)
		(layer "B.Cu")
		(net "GND")
	)
	(segment
		(start 128.690878 -16.696944)
		(end 129.149348 -16.238474)
		(width 0.4064)
		(layer "B.Cu")
		(net "GND")
	)
	(segment
		(start 31.39948 -148.771356)
		(end 31.39948 -147.478496)
		(width 0.4064)
		(layer "B.Cu")
		(net "GND")
	)
	(segment
		(start 227.849938 -2.234692)
		(end 227.849938 -1.021842)
		(width 0.4064)
		(layer "B.Cu")
		(net "GND")
	)
	(segment
		(start 306.050442 -1.021842)
		(end 306.049934 -1.021842)
		(width 0.4064)
		(layer "B.Cu")
		(net "GND")
	)
	(segment
		(start 300.70425 -14.198346)
		(end 300.70425 -14.1224)
		(width 0.254)
		(layer "B.Cu")
		(net "GND")
	)
	(segment
		(start 306.899818 -15.222982)
		(end 306.899818 -13.363956)
		(width 0.4064)
		(layer "B.Cu")
		(net "GND")
	)
	(segment
		(start 313.699906 -147.478496)
		(end 313.699906 -148.771356)
		(width 0.4064)
		(layer "B.Cu")
		(net "GND")
	)
	(segment
		(start 277.702264 -18.0594)
		(end 277.397464 -17.7546)
		(width 0.381)
		(layer "B.Cu")
		(net "GND")
	)
	(segment
		(start 235.49991 -128.276096)
		(end 235.49991 -129.530856)
		(width 0.4064)
		(layer "B.Cu")
		(net "GND")
	)
	(segment
		(start 201.499978 -15.222982)
		(end 201.499978 -14.410182)
		(width 0.4064)
		(layer "B.Cu")
		(net "GND")
	)
	(segment
		(start 230.399844 -128.276096)
		(end 230.399844 -129.568956)
		(width 0.4064)
		(layer "B.Cu")
		(net "GND")
	)
	(segment
		(start 298.40047 -10.623042)
		(end 298.399962 -10.623042)
		(width 0.4064)
		(layer "B.Cu")
		(net "GND")
	)
	(segment
		(start 383.3368 -105.0544)
		(end 383.73685 -105.45445)
		(width 0.254)
		(layer "B.Cu")
		(net "GND")
	)
	(segment
		(start 443.188852 -155.849828)
		(end 443.497208 -156.158184)
		(width 0.254)
		(layer "B.Cu")
		(net "GND")
	)
	(segment
		(start 226.9998 -132.875782)
		(end 226.9998 -132.1054)
		(width 0.254)
		(layer "B.Cu")
		(net "GND")
	)
	(segment
		(start 286.500316 -132.876036)
		(end 286.499808 -132.875782)
		(width 0.4064)
		(layer "B.Cu")
		(net "GND")
	)
	(segment
		(start 237.142528 -148.748496)
		(end 237.142528 -148.767292)
		(width 0.4064)
		(layer "B.Cu")
		(net "GND")
	)
	(segment
		(start 45.84954 -24.824182)
		(end 45.84954 -24.011382)
		(width 0.4064)
		(layer "B.Cu")
		(net "GND")
	)
	(segment
		(start 64.549528 -4.808982)
		(end 64.549528 -5.621782)
		(width 0.4064)
		(layer "B.Cu")
		(net "GND")
	)
	(segment
		(start 444.45174 -21.74748)
		(end 444.45174 -22.82444)
		(width 0.254)
		(layer "B.Cu")
		(net "GND")
	)
	(segment
		(start 129.149348 -24.011128)
		(end 129.149348 -24.824182)
		(width 0.4064)
		(layer "B.Cu")
		(net "GND")
	)
	(segment
		(start 411.228794 -88.826594)
		(end 410.6672 -88.265)
		(width 0.254)
		(layer "B.Cu")
		(net "GND")
	)
	(segment
		(start 33.703768 -141.452346)
		(end 33.703768 -141.3764)
		(width 0.254)
		(layer "B.Cu")
		(net "GND")
	)
	(segment
		(start 134.249414 -13.728954)
		(end 135.061452 -12.916916)
		(width 0.4064)
		(layer "B.Cu")
		(net "GND")
	)
	(segment
		(start 441.071 -15.4051)
		(end 440.7281 -15.4051)
		(width 0.254)
		(layer "B.Cu")
		(net "GND")
	)
	(segment
		(start 384.74396 -81.06918)
		(end 385.19354 -81.51876)
		(width 0.254)
		(layer "B.Cu")
		(net "GND")
	)
	(segment
		(start 370.078 -25.7175)
		(end 369.682014 -25.7175)
		(width 0.508)
		(layer "B.Cu")
		(net "GND")
	)
	(segment
		(start 216.799922 -18.757646)
		(end 216.799922 -20.224242)
		(width 0.4064)
		(layer "B.Cu")
		(net "GND")
	)
	(segment
		(start 141.383512 -26.162)
		(end 141.049502 -26.495756)
		(width 0.4064)
		(layer "B.Cu")
		(net "GND")
	)
	(segment
		(start 134.160514 -22.965156)
		(end 134.249414 -23.054056)
		(width 0.4064)
		(layer "B.Cu")
		(net "GND")
	)
	(segment
		(start 242.300506 -142.477236)
		(end 242.299998 -142.477236)
		(width 0.508)
		(layer "B.Cu")
		(net "GND")
	)
	(segment
		(start 52.398168 -150.292562)
		(end 52.471574 -150.219156)
		(width 0.4064)
		(layer "B.Cu")
		(net "GND")
	)
	(segment
		(start 33.099502 -137.877296)
		(end 33.099502 -139.157456)
		(width 0.4064)
		(layer "B.Cu")
		(net "GND")
	)
	(segment
		(start 22.6314 -31.6738)
		(end 22.6314 -32.024574)
		(width 0.508)
		(layer "B.Cu")
		(net "GND")
	)
	(segment
		(start 146.092164 -21.494496)
		(end 146.092164 -21.513292)
		(width 0.4064)
		(layer "B.Cu")
		(net "GND")
	)
	(segment
		(start -1.93421 -46.744128)
		(end -0.500126 -45.310044)
		(width 0.508)
		(layer "B.Cu")
		(net "GND")
	)
	(segment
		(start 33.061402 -2.314956)
		(end 33.086802 -2.314956)
		(width 0.4064)
		(layer "B.Cu")
		(net "GND")
	)
	(segment
		(start 294.14978 -24.011128)
		(end 294.14978 -24.824182)
		(width 0.4064)
		(layer "B.Cu")
		(net "GND")
	)
	(segment
		(start 294.14978 -6.637274)
		(end 293.69131 -7.095744)
		(width 0.4064)
		(layer "B.Cu")
		(net "GND")
	)
	(segment
		(start 482.512116 -144.009872)
		(end 482.512116 -143.247872)
		(width 0.254)
		(layer "B.Cu")
		(net "GND")
	)
	(segment
		(start 208.122012 -7.6454)
		(end 208.299812 -7.4676)
		(width 0.4064)
		(layer "B.Cu")
		(net "GND")
	)
	(segment
		(start 113.967768 -23.405592)
		(end 113.967768 -22.8346)
		(width 0.4064)
		(layer "B.Cu")
		(net "GND")
	)
	(segment
		(start 213.399878 -137.877296)
		(end 213.399878 -139.170156)
		(width 0.4064)
		(layer "B.Cu")
		(net "GND")
	)
	(segment
		(start 53.499512 -139.089892)
		(end 53.442108 -139.147296)
		(width 0.4064)
		(layer "B.Cu")
		(net "GND")
	)
	(segment
		(start 374.744742 -72.295004)
		(end 374.744996 -72.295004)
		(width 0.254)
		(layer "B.Cu")
		(net "GND")
	)
	(segment
		(start 467.741 -140.3604)
		(end 467.995 -140.3604)
		(width 0.254)
		(layer "B.Cu")
		(net "GND")
	)
	(segment
		(start 292.450012 -137.877296)
		(end 292.450012 -139.089892)
		(width 0.4064)
		(layer "B.Cu")
		(net "GND")
	)
	(segment
		(start 298.40047 -1.021842)
		(end 298.399962 -1.021842)
		(width 0.4064)
		(layer "B.Cu")
		(net "GND")
	)
	(segment
		(start 211.700364 -1.021842)
		(end 211.699856 -1.021842)
		(width 0.4064)
		(layer "B.Cu")
		(net "GND")
	)
	(segment
		(start 378.210572 -99.322636)
		(end 378.82195 -99.322636)
		(width 0.2032)
		(layer "B.Cu")
		(net "GND")
	)
	(segment
		(start 34.74212 -21.494496)
		(end 34.74212 -21.513292)
		(width 0.4064)
		(layer "B.Cu")
		(net "GND")
	)
	(segment
		(start 199.800464 -1.021842)
		(end 199.799956 -1.021842)
		(width 0.4064)
		(layer "B.Cu")
		(net "GND")
	)
	(segment
		(start 299.249846 -15.222982)
		(end 299.249846 -17.110202)
		(width 0.4064)
		(layer "B.Cu")
		(net "GND")
	)
	(segment
		(start 52.398168 -131.090162)
		(end 52.471574 -131.016756)
		(width 0.4064)
		(layer "B.Cu")
		(net "GND")
	)
	(segment
		(start 199.800464 -147.478496)
		(end 199.799956 -147.478496)
		(width 0.4064)
		(layer "B.Cu")
		(net "GND")
	)
	(segment
		(start 292.450012 -139.089892)
		(end 292.392608 -139.147296)
		(width 0.4064)
		(layer "B.Cu")
		(net "GND")
	)
	(segment
		(start 230.399844 -137.877296)
		(end 230.400352 -137.877296)
		(width 0.4064)
		(layer "B.Cu")
		(net "GND")
	)
	(segment
		(start 419.4175 -7.239)
		(end 418.211 -7.239)
		(width 0.254)
		(layer "B.Cu")
		(net "GND")
	)
	(segment
		(start 378.8918 -61.3664)
		(end 378.841 -61.3156)
		(width 0.254)
		(layer "B.Cu")
		(net "GND")
	)
	(segment
		(start 373.207026 -84.775294)
		(end 373.207026 -86.301326)
		(width 0.254)
		(layer "B.Cu")
		(net "GND")
	)
	(segment
		(start 53.442108 -139.147296)
		(end 53.442108 -139.166092)
		(width 0.4064)
		(layer "B.Cu")
		(net "GND")
	)
	(segment
		(start 232.950004 -142.476982)
		(end 232.950004 -142.18285)
		(width 0.4064)
		(layer "B.Cu")
		(net "GND")
	)
	(segment
		(start 47.549562 -14.92885)
		(end 47.549308 -14.928596)
		(width 0.4064)
		(layer "B.Cu")
		(net "GND")
	)
	(segment
		(start 306.899818 -24.824182)
		(end 306.899818 -25.645872)
		(width 0.4064)
		(layer "B.Cu")
		(net "GND")
	)
	(segment
		(start 33.086802 -139.170156)
		(end 33.061402 -139.170156)
		(width 0.4064)
		(layer "B.Cu")
		(net "GND")
	)
	(segment
		(start 289.810952 -150.219156)
		(end 289.810952 -150.193756)
		(width 0.4064)
		(layer "B.Cu")
		(net "GND")
	)
	(segment
		(start 234.649772 -150.308056)
		(end 234.560872 -150.219156)
		(width 0.4064)
		(layer "B.Cu")
		(net "GND")
	)
	(segment
		(start 212.549994 -15.222982)
		(end 212.549994 -14.92885)
		(width 0.4064)
		(layer "B.Cu")
		(net "GND")
	)
	(segment
		(start 127.44958 -129.488692)
		(end 127.392176 -129.546096)
		(width 0.4064)
		(layer "B.Cu")
		(net "GND")
	)
	(segment
		(start 144.449546 -10.623042)
		(end 144.449546 -9.156446)
		(width 0.4064)
		(layer "B.Cu")
		(net "GND")
	)
	(segment
		(start 221.899988 -142.13205)
		(end 221.899734 -142.131796)
		(width 0.4064)
		(layer "B.Cu")
		(net "GND")
	)
	(segment
		(start 135.703818 -141.452346)
		(end 135.703818 -141.3764)
		(width 0.254)
		(layer "B.Cu")
		(net "GND")
	)
	(segment
		(start 196.342 -145.941034)
		(end 196.399912 -145.998946)
		(width 0.4064)
		(layer "B.Cu")
		(net "GND")
	)
	(segment
		(start 207.449928 -128.276096)
		(end 207.449928 -129.556256)
		(width 0.4064)
		(layer "B.Cu")
		(net "GND")
	)
	(segment
		(start 77.299312 -132.454396)
		(end 77.299312 -131.029456)
		(width 0.4064)
		(layer "B.Cu")
		(net "GND")
	)
	(segment
		(start 372.954804 -83.811364)
		(end 372.954804 -84.523072)
		(width 0.254)
		(layer "B.Cu")
		(net "GND")
	)
	(segment
		(start 125.749558 -21.504656)
		(end 125.736858 -21.517356)
		(width 0.4064)
		(layer "B.Cu")
		(net "GND")
	)
	(segment
		(start 217.649806 -152.078182)
		(end 217.649806 -151.27986)
		(width 0.254)
		(layer "B.Cu")
		(net "GND")
	)
	(segment
		(start 316.25032 -15.222982)
		(end 316.249812 -15.222982)
		(width 0.4064)
		(layer "B.Cu")
		(net "GND")
	)
	(segment
		(start 227.792534 -2.310892)
		(end 227.792534 -2.292096)
		(width 0.4064)
		(layer "B.Cu")
		(net "GND")
	)
	(segment
		(start 394.95984 -39.497)
		(end 395.28877 -39.82593)
		(width 0.254)
		(layer "B.Cu")
		(net "GND")
	)
	(segment
		(start 134.249414 -150.308056)
		(end 134.160514 -150.219156)
		(width 0.4064)
		(layer "B.Cu")
		(net "GND")
	)
	(segment
		(start 486.32872 -29.3116)
		(end 486.194608 -29.445712)
		(width 0.254)
		(layer "B.Cu")
		(net "GND")
	)
	(segment
		(start 453.24141 -4.94919)
		(end 453.24141 -4.614672)
		(width 0.254)
		(layer "B.Cu")
		(net "GND")
	)
	(segment
		(start 57.74944 -128.276096)
		(end 57.74944 -129.568956)
		(width 0.4064)
		(layer "B.Cu")
		(net "GND")
	)
	(segment
		(start 256.511806 -140.490194)
		(end 255.815338 -140.490194)
		(width 0.4064)
		(layer "B.Cu")
		(net "GND")
	)
	(segment
		(start 31.341568 -17.723612)
		(end 31.341568 -18.687034)
		(width 0.381)
		(layer "B.Cu")
		(net "GND")
	)
	(segment
		(start 166.751 -87.1982)
		(end 166.751 -88.1126)
		(width 0.4064)
		(layer "B.Cu")
		(net "GND")
	)
	(segment
		(start 322.06184 -7.7216)
		(end 321.65544 -8.128)
		(width 0.381)
		(layer "B.Cu")
		(net "GND")
	)
	(segment
		(start 440.275726 -142.333726)
		(end 440.275726 -143.589756)
		(width 0.254)
		(layer "B.Cu")
		(net "GND")
	)
	(segment
		(start 321.591432 -145.034)
		(end 322.0466 -145.489168)
		(width 0.508)
		(layer "B.Cu")
		(net "GND")
	)
	(segment
		(start 49.249584 -142.13205)
		(end 49.24933 -142.131796)
		(width 0.4064)
		(layer "B.Cu")
		(net "GND")
	)
	(segment
		(start 197.249796 -131.080256)
		(end 197.249796 -132.875782)
		(width 0.4064)
		(layer "B.Cu")
		(net "GND")
	)
	(segment
		(start 223.60001 -151.83485)
		(end 223.599756 -151.834596)
		(width 0.4064)
		(layer "B.Cu")
		(net "GND")
	)
	(segment
		(start 291.354256 -23.032974)
		(end 291.422074 -22.965156)
		(width 0.4064)
		(layer "B.Cu")
		(net "GND")
	)
	(segment
		(start 442.468 -155.849828)
		(end 443.188852 -155.849828)
		(width 0.254)
		(layer "B.Cu")
		(net "GND")
	)
	(segment
		(start 126.599442 -141.697964)
		(end 126.353824 -141.452346)
		(width 0.254)
		(layer "B.Cu")
		(net "GND")
	)
	(segment
		(start 134.249414 -132.876036)
		(end 134.249414 -131.105656)
		(width 0.4064)
		(layer "B.Cu")
		(net "GND")
	)
	(segment
		(start 134.249414 -17.110202)
		(end 134.15137 -17.208246)
		(width 0.4064)
		(layer "B.Cu")
		(net "GND")
	)
	(segment
		(start 495.549682 -37.425376)
		(end 495.746024 -37.425376)
		(width 0.254)
		(layer "B.Cu")
		(net "GND")
	)
	(segment
		(start 378.94895 -68.707)
		(end 378.356368 -68.707)
		(width 0.254)
		(layer "B.Cu")
		(net "GND")
	)
	(segment
		(start 312.387996 -23.549356)
		(end 312.849768 -24.011128)
		(width 0.4064)
		(layer "B.Cu")
		(net "GND")
	)
	(segment
		(start 234.560872 -140.617956)
		(end 234.560872 -140.592556)
		(width 0.4064)
		(layer "B.Cu")
		(net "GND")
	)
	(segment
		(start 209.092546 -148.748496)
		(end 209.092546 -148.767292)
		(width 0.4064)
		(layer "B.Cu")
		(net "GND")
	)
	(segment
		(start 138.03757 -23.549356)
		(end 138.499342 -24.011128)
		(width 0.4064)
		(layer "B.Cu")
		(net "GND")
	)
	(segment
		(start 138.040872 -16.696944)
		(end 138.499342 -16.238474)
		(width 0.4064)
		(layer "B.Cu")
		(net "GND")
	)
	(segment
		(start 90.127582 -13.292582)
		(end 90.871548 -13.292582)
		(width 0.4064)
		(layer "B.Cu")
		(net "GND")
	)
	(segment
		(start 436.372 -149.173946)
		(end 436.638446 -148.9075)
		(width 0.254)
		(layer "B.Cu")
		(net "GND")
	)
	(segment
		(start 67.949572 -15.222982)
		(end 67.949572 -14.92885)
		(width 0.4064)
		(layer "B.Cu")
		(net "GND")
	)
	(segment
		(start 204.899768 -17.208246)
		(end 204.899768 -15.222982)
		(width 0.4064)
		(layer "B.Cu")
		(net "GND")
	)
	(segment
		(start 209.14995 -10.623042)
		(end 209.14995 -9.20115)
		(width 0.4064)
		(layer "B.Cu")
		(net "GND")
	)
	(segment
		(start 139.34948 -1.021842)
		(end 139.34948 -2.314956)
		(width 0.4064)
		(layer "B.Cu")
		(net "GND")
	)
	(segment
		(start 114.5413 -126.08306)
		(end 113.8555 -126.08306)
		(width 0.508)
		(layer "B.Cu")
		(net "GND")
	)
	(segment
		(start 255.8034 -3.635756)
		(end 255.8034 -2.975356)
		(width 0.4064)
		(layer "B.Cu")
		(net "GND")
	)
	(segment
		(start 274.8534 4.8006)
		(end 273.1516 4.8006)
		(width 0.381)
		(layer "B.Cu")
		(net "GND")
	)
	(segment
		(start 55.199534 -24.011382)
		(end 54.737508 -23.549356)
		(width 0.4064)
		(layer "B.Cu")
		(net "GND")
	)
	(segment
		(start 60.210446 -22.965156)
		(end 60.299346 -23.054056)
		(width 0.4064)
		(layer "B.Cu")
		(net "GND")
	)
	(segment
		(start 374.856248 -155.521152)
		(end 374.856248 -155.379928)
		(width 0.4064)
		(layer "B.Cu")
		(net "GND")
	)
	(segment
		(start 47.549562 -132.58165)
		(end 47.549308 -132.581396)
		(width 0.4064)
		(layer "B.Cu")
		(net "GND")
	)
	(segment
		(start 138.499342 -141.663928)
		(end 138.03757 -141.202156)
		(width 0.4064)
		(layer "B.Cu")
		(net "GND")
	)
	(segment
		(start 127.44958 -1.021842)
		(end 127.44958 0.40005)
		(width 0.4064)
		(layer "B.Cu")
		(net "GND")
	)
	(segment
		(start 53.442108 -18.744946)
		(end 53.499512 -18.80235)
		(width 0.4064)
		(layer "B.Cu")
		(net "GND")
	)
	(segment
		(start 379.650752 -45.176948)
		(end 379.6792 -45.176948)
		(width 0.254)
		(layer "B.Cu")
		(net "GND")
	)
	(segment
		(start 204.899768 -132.875782)
		(end 204.899768 -131.016756)
		(width 0.4064)
		(layer "B.Cu")
		(net "GND")
	)
	(segment
		(start 207.449928 -2.302256)
		(end 207.437228 -2.314956)
		(width 0.4064)
		(layer "B.Cu")
		(net "GND")
	)
	(segment
		(start 287.349946 -137.877296)
		(end 287.349946 -139.170156)
		(width 0.4064)
		(layer "B.Cu")
		(net "GND")
	)
	(segment
		(start 68.799456 -137.877296)
		(end 68.799456 -139.170156)
		(width 0.4064)
		(layer "B.Cu")
		(net "GND")
	)
	(segment
		(start 197.249796 -24.824182)
		(end 197.249796 -23.716742)
		(width 0.4064)
		(layer "B.Cu")
		(net "GND")
	)
	(segment
		(start 331.343 -157.226)
		(end 331.851 -157.226)
		(width 0.508)
		(layer "B.Cu")
		(net "GND")
	)
	(segment
		(start 34.799524 -18.80235)
		(end 34.799524 -20.224242)
		(width 0.4064)
		(layer "B.Cu")
		(net "GND")
	)
	(segment
		(start 62.849506 -128.276096)
		(end 62.849506 -129.488692)
		(width 0.4064)
		(layer "B.Cu")
		(net "GND")
	)
	(segment
		(start 144.449546 -11.903456)
		(end 144.449546 -10.623042)
		(width 0.4064)
		(layer "B.Cu")
		(net "GND")
	)
	(segment
		(start 131.699508 -20.224242)
		(end 131.699508 -18.757646)
		(width 0.4064)
		(layer "B.Cu")
		(net "GND")
	)
	(segment
		(start 243.149882 -1.021842)
		(end 243.149882 0.468122)
		(width 0.4064)
		(layer "B.Cu")
		(net "GND")
	)
	(segment
		(start 282.24988 -14.443964)
		(end 282.004262 -14.198346)
		(width 0.254)
		(layer "B.Cu")
		(net "GND")
	)
	(segment
		(start 138.040872 -7.095744)
		(end 138.499342 -6.637274)
		(width 0.4064)
		(layer "B.Cu")
		(net "GND")
	)
	(segment
		(start 49.24933 -151.732996)
		(end 49.24933 -150.219156)
		(width 0.4064)
		(layer "B.Cu")
		(net "GND")
	)
	(segment
		(start 310.122062 -131.016756)
		(end 310.054244 -131.084574)
		(width 0.4064)
		(layer "B.Cu")
		(net "GND")
	)
	(segment
		(start 288.19983 -3.762756)
		(end 288.19983 -5.621782)
		(width 0.4064)
		(layer "B.Cu")
		(net "GND")
	)
	(segment
		(start 497.561108 -39.912798)
		(end 497.561108 -40.52443)
		(width 0.254)
		(layer "B.Cu")
		(net "GND")
	)
	(segment
		(start 295.849802 -24.824182)
		(end 295.849802 -25.654508)
		(width 0.4064)
		(layer "B.Cu")
		(net "GND")
	)
	(segment
		(start 466.548724 -8.010398)
		(end 466.182202 -8.37692)
		(width 0.254)
		(layer "B.Cu")
		(net "GND")
	)
	(segment
		(start 233.800396 -10.623042)
		(end 233.799888 -10.623042)
		(width 0.4064)
		(layer "B.Cu")
		(net "GND")
	)
	(segment
		(start 483.338886 -56.593486)
		(end 483.338886 -56.69153)
		(width 0.254)
		(layer "B.Cu")
		(net "GND")
	)
	(segment
		(start 374.06072 -96.68002)
		(end 374.1547 -96.58604)
		(width 0.254)
		(layer "B.Cu")
		(net "GND")
	)
	(segment
		(start 125.749558 -18.757646)
		(end 125.749558 -20.224242)
		(width 0.4064)
		(layer "B.Cu")
		(net "GND")
	)
	(segment
		(start 208.0514 -151.101552)
		(end 208.0514 -150.277068)
		(width 0.4064)
		(layer "B.Cu")
		(net "GND")
	)
	(segment
		(start 312.849768 -4.808728)
		(end 312.387996 -4.346956)
		(width 0.4064)
		(layer "B.Cu")
		(net "GND")
	)
	(segment
		(start 363.093 -58.928)
		(end 362.8136 -58.6486)
		(width 0.254)
		(layer "B.Cu")
		(net "GND")
	)
	(segment
		(start 242.299744 -22.977856)
		(end 242.299744 -24.402796)
		(width 0.4064)
		(layer "B.Cu")
		(net "GND")
	)
	(segment
		(start 61.136784 -129.568956)
		(end 61.111384 -129.568956)
		(width 0.4064)
		(layer "B.Cu")
		(net "GND")
	)
	(segment
		(start 77.299566 -142.05585)
		(end 77.299566 -142.476982)
		(width 0.4064)
		(layer "B.Cu")
		(net "GND")
	)
	(segment
		(start 224.450402 -20.224242)
		(end 224.449894 -20.224242)
		(width 0.4064)
		(layer "B.Cu")
		(net "GND")
	)
	(segment
		(start 78.14945 -18.766282)
		(end 78.14945 -20.224242)
		(width 0.4064)
		(layer "B.Cu")
		(net "GND")
	)
	(segment
		(start 437.919368 -157.1498)
		(end 438.58688 -157.1498)
		(width 0.254)
		(layer "B.Cu")
		(net "GND")
	)
	(segment
		(start 124.89942 -3.851656)
		(end 124.89942 -5.621782)
		(width 0.4064)
		(layer "B.Cu")
		(net "GND")
	)
	(segment
		(start 134.249414 -15.222982)
		(end 134.249414 -13.728954)
		(width 0.4064)
		(layer "B.Cu")
		(net "GND")
	)
	(segment
		(start 166.68877 -73.66)
		(end 167.102536 -73.246234)
		(width 0.254)
		(layer "B.Cu")
		(net "GND")
	)
	(segment
		(start 299.160946 -140.617956)
		(end 299.160946 -140.592556)
		(width 0.4064)
		(layer "B.Cu")
		(net "GND")
	)
	(segment
		(start 139.34948 -147.478496)
		(end 139.34948 -148.771356)
		(width 0.4064)
		(layer "B.Cu")
		(net "GND")
	)
	(segment
		(start 242.300506 -152.078436)
		(end 242.299998 -152.078182)
		(width 0.4064)
		(layer "B.Cu")
		(net "GND")
	)
	(segment
		(start 17.1704 -83.6168)
		(end 16.2052 -83.6168)
		(width 0.254)
		(layer "B.Cu")
		(net "GND")
	)
	(segment
		(start 236.095794 -131.7498)
		(end 236.095794 -131.092956)
		(width 0.4064)
		(layer "B.Cu")
		(net "GND")
	)
	(segment
		(start 112.778032 -135.4074)
		(end 113.228628 -135.4074)
		(width 0.4064)
		(layer "B.Cu")
		(net "GND")
	)
	(segment
		(start 166.497 -73.66)
		(end 166.68877 -73.66)
		(width 0.254)
		(layer "B.Cu")
		(net "GND")
	)
	(segment
		(start 62.849506 -10.623042)
		(end 62.849506 -11.835892)
		(width 0.4064)
		(layer "B.Cu")
		(net "GND")
	)
	(segment
		(start 33.949386 -141.697964)
		(end 33.703768 -141.452346)
		(width 0.254)
		(layer "B.Cu")
		(net "GND")
	)
	(segment
		(start 286.499808 -15.222982)
		(end 286.499808 -13.363956)
		(width 0.4064)
		(layer "B.Cu")
		(net "GND")
	)
	(segment
		(start 125.749558 0.444754)
		(end 125.749558 -1.021842)
		(width 0.4064)
		(layer "B.Cu")
		(net "GND")
	)
	(segment
		(start 225.201734 -7.607046)
		(end 225.299778 -7.509002)
		(width 0.4064)
		(layer "B.Cu")
		(net "GND")
	)
	(segment
		(start 147.849336 -16.238474)
		(end 147.849336 -15.222982)
		(width 0.4064)
		(layer "B.Cu")
		(net "GND")
	)
	(segment
		(start 346.732098 -89.9033)
		(end 346.732098 -91.453716)
		(width 0.2032)
		(layer "B.Cu")
		(net "GND")
	)
	(segment
		(start 175.26 -76.327)
		(end 175.26 -76.0476)
		(width 0.381)
		(layer "B.Cu")
		(net "GND")
	)
	(segment
		(start 45.84954 -6.63702)
		(end 45.390816 -7.095744)
		(width 0.4064)
		(layer "B.Cu")
		(net "GND")
	)
	(segment
		(start 124.049536 -20.224242)
		(end 124.049536 -21.517356)
		(width 0.4064)
		(layer "B.Cu")
		(net "GND")
	)
	(segment
		(start 113.905538 -18.0594)
		(end 113.957354 -18.007584)
		(width 0.381)
		(layer "B.Cu")
		(net "GND")
	)
	(segment
		(start 29.944568 -150.0378)
		(end 29.715968 -150.0378)
		(width 0.4064)
		(layer "B.Cu")
		(net "GND")
	)
	(segment
		(start 281.399996 -21.504656)
		(end 281.399996 -20.224242)
		(width 0.4064)
		(layer "B.Cu")
		(net "GND")
	)
	(segment
		(start 309.450486 -1.021842)
		(end 309.449978 -1.021842)
		(width 0.4064)
		(layer "B.Cu")
		(net "GND")
	)
	(segment
		(start 75.599544 -24.45385)
		(end 75.59929 -24.453596)
		(width 0.4064)
		(layer "B.Cu")
		(net "GND")
	)
	(segment
		(start 374.8278 -101.67239)
		(end 374.8278 -102.0826)
		(width 0.254)
		(layer "B.Cu")
		(net "GND")
	)
	(segment
		(start 226.7458 -131.092956)
		(end 226.822 -131.016756)
		(width 0.4064)
		(layer "B.Cu")
		(net "GND")
	)
	(segment
		(start 313.699906 -21.517356)
		(end 313.699906 -20.224242)
		(width 0.4064)
		(layer "B.Cu")
		(net "GND")
	)
	(segment
		(start 394.175234 -151.84374)
		(end 394.175234 -152.73274)
		(width 0.254)
		(layer "B.Cu")
		(net "GND")
	)
	(segment
		(start 460.248 -153.416)
		(end 460.248 -153.924)
		(width 0.4064)
		(layer "B.Cu")
		(net "GND")
	)
	(segment
		(start 424.2435 -22.319742)
		(end 424.2435 -22.0345)
		(width 0.254)
		(layer "B.Cu")
		(net "GND")
	)
	(segment
		(start 497.299996 -39.651686)
		(end 497.561108 -39.912798)
		(width 0.254)
		(layer "B.Cu")
		(net "GND")
	)
	(segment
		(start 317.09995 -154.814778)
		(end 317.09995 -155.612846)
		(width 0.4064)
		(layer "B.Cu")
		(net "GND")
	)
	(segment
		(start 145.12163 -13.363956)
		(end 145.053812 -13.431774)
		(width 0.4064)
		(layer "B.Cu")
		(net "GND")
	)
	(segment
		(start 289.801808 -17.208246)
		(end 289.899852 -17.110202)
		(width 0.4064)
		(layer "B.Cu")
		(net "GND")
	)
	(segment
		(start 483.241096 -144.009872)
		(end 482.512116 -144.009872)
		(width 0.254)
		(layer "B.Cu")
		(net "GND")
	)
	(segment
		(start 292.392608 -11.893296)
		(end 292.392608 -11.912092)
		(width 0.4064)
		(layer "B.Cu")
		(net "GND")
	)
	(segment
		(start 163.2458 -81.153)
		(end 162.3314 -81.153)
		(width 0.4064)
		(layer "B.Cu")
		(net "GND")
	)
	(segment
		(start 75.599544 -5.25145)
		(end 75.599544 -5.621782)
		(width 0.4064)
		(layer "B.Cu")
		(net "GND")
	)
	(segment
		(start 314.54979 -142.476982)
		(end 314.54979 -140.617956)
		(width 0.4064)
		(layer "B.Cu")
		(net "GND")
	)
	(segment
		(start 61.999368 -15.222982)
		(end 61.999368 -14.4526)
		(width 0.254)
		(layer "B.Cu")
		(net "GND")
	)
	(segment
		(start 67.949572 -14.92885)
		(end 67.949318 -14.928596)
		(width 0.4064)
		(layer "B.Cu")
		(net "GND")
	)
	(segment
		(start 61.745368 -23.7998)
		(end 61.999368 -24.0538)
		(width 0.254)
		(layer "B.Cu")
		(net "GND")
	)
	(segment
		(start 229.091236 -7.095744)
		(end 229.54996 -6.63702)
		(width 0.4064)
		(layer "B.Cu")
		(net "GND")
	)
	(segment
		(start 447.90233 -13.38453)
		(end 449.950586 -13.38453)
		(width 0.254)
		(layer "B.Cu")
		(net "GND")
	)
	(segment
		(start 89.789 -8.1534)
		(end 90.496644 -8.1534)
		(width 0.4064)
		(layer "B.Cu")
		(net "GND")
	)
	(segment
		(start 173.279816 -70.555104)
		(end 172.384212 -70.555104)
		(width 0.254)
		(layer "B.Cu")
		(net "GND")
	)
	(segment
		(start 133.39953 -20.224242)
		(end 133.39953 -18.744946)
		(width 0.4064)
		(layer "B.Cu")
		(net "GND")
	)
	(segment
		(start 282.24988 -17.0688)
		(end 282.24988 -15.222982)
		(width 0.4064)
		(layer "B.Cu")
		(net "GND")
	)
	(segment
		(start 310.122062 -150.219156)
		(end 308.809644 -150.219156)
		(width 0.4064)
		(layer "B.Cu")
		(net "GND")
	)
	(segment
		(start 209.14995 -128.276096)
		(end 209.14995 -129.488692)
		(width 0.4064)
		(layer "B.Cu")
		(net "GND")
	)
	(segment
		(start 226.137216 -139.170156)
		(end 226.111816 -139.170156)
		(width 0.4064)
		(layer "B.Cu")
		(net "GND")
	)
	(segment
		(start 484.418894 -122.214894)
		(end 484.850186 -122.214894)
		(width 0.254)
		(layer "B.Cu")
		(net "GND")
	)
	(segment
		(start 240.599722 -131.016756)
		(end 240.599976 -131.01701)
		(width 0.4064)
		(layer "B.Cu")
		(net "GND")
	)
	(segment
		(start 67.949318 -17.208246)
		(end 67.949572 -17.207992)
		(width 0.4064)
		(layer "B.Cu")
		(net "GND")
	)
	(segment
		(start 278.849836 -15.222982)
		(end 278.849836 -14.13002)
		(width 0.4064)
		(layer "B.Cu")
		(net "GND")
	)
	(segment
		(start 27.023568 -135.763)
		(end 27.023568 -136.398)
		(width 0.4064)
		(layer "B.Cu")
		(net "GND")
	)
	(segment
		(start 135.949436 -4.842764)
		(end 135.703818 -4.597146)
		(width 0.254)
		(layer "B.Cu")
		(net "GND")
	)
	(segment
		(start 290.74999 -10.623042)
		(end 290.750498 -10.623042)
		(width 0.4064)
		(layer "B.Cu")
		(net "GND")
	)
	(segment
		(start 51.79949 -147.478496)
		(end 51.79949 -148.758656)
		(width 0.4064)
		(layer "B.Cu")
		(net "GND")
	)
	(segment
		(start 457.7842 -22.624034)
		(end 457.7842 -22.733)
		(width 0.254)
		(layer "B.Cu")
		(net "GND")
	)
	(segment
		(start 79.334868 -149.8092)
		(end 78.9178 -149.8092)
		(width 0.508)
		(layer "B.Cu")
		(net "GND")
	)
	(segment
		(start 495.746024 -37.425376)
		(end 496.213638 -36.957762)
		(width 0.254)
		(layer "B.Cu")
		(net "GND")
	)
	(segment
		(start 286.499808 -17.208246)
		(end 286.499808 -15.222982)
		(width 0.4064)
		(layer "B.Cu")
		(net "GND")
	)
	(segment
		(start 317.09995 -128.276096)
		(end 317.09995 -129.579878)
		(width 0.4064)
		(layer "B.Cu")
		(net "GND")
	)
	(segment
		(start 61.149484 -1.021842)
		(end 61.149484 -2.302256)
		(width 0.4064)
		(layer "B.Cu")
		(net "GND")
	)
	(segment
		(start 234.649772 -25.676098)
		(end 234.649772 -24.824182)
		(width 0.4064)
		(layer "B.Cu")
		(net "GND")
	)
	(segment
		(start 396.74419 -63.373)
		(end 397.11376 -63.74257)
		(width 0.254)
		(layer "B.Cu")
		(net "GND")
	)
	(segment
		(start 222.749872 -10.623042)
		(end 222.749872 -11.916156)
		(width 0.4064)
		(layer "B.Cu")
		(net "GND")
	)
	(segment
		(start 136.74217 -11.912092)
		(end 136.74217 -11.893296)
		(width 0.4064)
		(layer "B.Cu")
		(net "GND")
	)
	(segment
		(start 399.49628 -77.64272)
		(end 400.14398 -77.64272)
		(width 0.254)
		(layer "B.Cu")
		(net "GND")
	)
	(segment
		(start 240.599976 -5.25145)
		(end 240.599722 -5.251196)
		(width 0.4064)
		(layer "B.Cu")
		(net "GND")
	)
	(segment
		(start 140.199364 -3.762756)
		(end 140.199364 -5.621782)
		(width 0.4064)
		(layer "B.Cu")
		(net "GND")
	)
	(segment
		(start 33.949386 -4.842764)
		(end 33.703768 -4.597146)
		(width 0.254)
		(layer "B.Cu")
		(net "GND")
	)
	(segment
		(start 389.33374 -19.95932)
		(end 389.33374 -17.35074)
		(width 0.254)
		(layer "B.Cu")
		(net "GND")
	)
	(segment
		(start 373.84228 -37.063426)
		(end 373.315738 -37.589968)
		(width 0.254)
		(layer "B.Cu")
		(net "GND")
	)
	(segment
		(start 129.149348 -16.238474)
		(end 129.149348 -15.222982)
		(width 0.4064)
		(layer "B.Cu")
		(net "GND")
	)
	(segment
		(start 61.745368 -150.295356)
		(end 61.821568 -150.219156)
		(width 0.4064)
		(layer "B.Cu")
		(net "GND")
	)
	(segment
		(start 282.004262 -4.5212)
		(end 282.004262 -4.597146)
		(width 0.254)
		(layer "B.Cu")
		(net "GND")
	)
	(segment
		(start 300.087284 -11.916156)
		(end 300.099984 -11.903456)
		(width 0.4064)
		(layer "B.Cu")
		(net "GND")
	)
	(segment
		(start 237.199932 -9.20115)
		(end 237.142528 -9.143746)
		(width 0.4064)
		(layer "B.Cu")
		(net "GND")
	)
	(segment
		(start 145.053812 -141.452346)
		(end 145.053812 -141.3764)
		(width 0.254)
		(layer "B.Cu")
		(net "GND")
	)
	(segment
		(start 50.949352 -150.308056)
		(end 50.860452 -150.219156)
		(width 0.4064)
		(layer "B.Cu")
		(net "GND")
	)
	(segment
		(start 416.179 -9.392158)
		(end 416.464242 -9.6774)
		(width 0.254)
		(layer "B.Cu")
		(net "GND")
	)
	(segment
		(start 117.00383 -23.7236)
		(end 117.00383 -23.007574)
		(width 0.4064)
		(layer "B.Cu")
		(net "GND")
	)
	(segment
		(start 464.372452 -141.727428)
		(end 461.1116 -141.727428)
		(width 0.254)
		(layer "B.Cu")
		(net "GND")
	)
	(segment
		(start 296.700448 -137.877296)
		(end 296.69994 -137.877296)
		(width 0.4064)
		(layer "B.Cu")
		(net "GND")
	)
	(segment
		(start 311.15 -9.20115)
		(end 311.092596 -9.143746)
		(width 0.4064)
		(layer "B.Cu")
		(net "GND")
	)
	(segment
		(start 274.709128 -156.960824)
		(end 273.758152 -157.9118)
		(width 0.381)
		(layer "B.Cu")
		(net "GND")
	)
	(segment
		(start 227.849938 -21.437092)
		(end 227.792534 -21.494496)
		(width 0.4064)
		(layer "B.Cu")
		(net "GND")
	)
	(segment
		(start 227.850446 -147.478496)
		(end 227.849938 -147.478496)
		(width 0.4064)
		(layer "B.Cu")
		(net "GND")
	)
	(segment
		(start 464.5152 -146.2024)
		(end 464.3628 -146.2024)
		(width 0.4064)
		(layer "B.Cu")
		(net "GND")
	)
	(segment
		(start 221.899988 -15.222982)
		(end 221.899988 -14.87805)
		(width 0.4064)
		(layer "B.Cu")
		(net "GND")
	)
	(segment
		(start 21.6662 -85.2424)
		(end 21.534374 -85.110574)
		(width 0.254)
		(layer "B.Cu")
		(net "GND")
	)
	(segment
		(start 203.2 -15.222982)
		(end 203.2 -13.36421)
		(width 0.4064)
		(layer "B.Cu")
		(net "GND")
	)
	(segment
		(start 147.849336 -152.078436)
		(end 147.849336 -151.265128)
		(width 0.4064)
		(layer "B.Cu")
		(net "GND")
	)
	(segment
		(start 381.764032 -157.484572)
		(end 381.762 -157.484572)
		(width 0.254)
		(layer "B.Cu")
		(net "GND")
	)
	(segment
		(start 171.568872 -86.868)
		(end 171.852844 -87.151972)
		(width 0.4064)
		(layer "B.Cu")
		(net "GND")
	)
	(segment
		(start 143.599408 -5.621782)
		(end 143.599408 -7.509002)
		(width 0.4064)
		(layer "B.Cu")
		(net "GND")
	)
	(segment
		(start 169.291 -88.0872)
		(end 169.291 -87.1982)
		(width 0.4064)
		(layer "B.Cu")
		(net "GND")
	)
	(segment
		(start 444.208916 -14.855698)
		(end 443.247018 -13.8938)
		(width 0.254)
		(layer "B.Cu")
		(net "GND")
	)
	(segment
		(start 223.60001 -152.078182)
		(end 223.60001 -151.83485)
		(width 0.4064)
		(layer "B.Cu")
		(net "GND")
	)
	(segment
		(start 229.54996 -26.22423)
		(end 229.54996 -24.824182)
		(width 0.4064)
		(layer "B.Cu")
		(net "GND")
	)
	(segment
		(start 163.42106 -83.693)
		(end 163.80206 -84.074)
		(width 0.3556)
		(layer "B.Cu")
		(net "GND")
	)
	(segment
		(start 175.5394 -78.232)
		(end 175.26 -77.9526)
		(width 0.381)
		(layer "B.Cu")
		(net "GND")
	)
	(segment
		(start 204.050392 -10.623042)
		(end 204.049884 -10.623042)
		(width 0.4064)
		(layer "B.Cu")
		(net "GND")
	)
	(segment
		(start 310.299862 -15.222982)
		(end 310.299862 -14.443964)
		(width 0.254)
		(layer "B.Cu")
		(net "GND")
	)
	(segment
		(start 36.499546 -142.477236)
		(end 36.499546 -141.664182)
		(width 0.4064)
		(layer "B.Cu")
		(net "GND")
	)
	(segment
		(start 475.51721 -148.454872)
		(end 475.51721 -148.874226)
		(width 0.254)
		(layer "B.Cu")
		(net "GND")
	)
	(segment
		(start 18.4785 -90.5383)
		(end 18.0086 -91.0082)
		(width 0.254)
		(layer "B.Cu")
		(net "GND")
	)
	(segment
		(start 232.950004 -142.18285)
		(end 232.94975 -142.182596)
		(width 0.4064)
		(layer "B.Cu")
		(net "GND")
	)
	(segment
		(start 198.950326 -15.222982)
		(end 198.949818 -15.222982)
		(width 0.4064)
		(layer "B.Cu")
		(net "GND")
	)
	(segment
		(start 62.849506 -18.80235)
		(end 62.849506 -20.224242)
		(width 0.4064)
		(layer "B.Cu")
		(net "GND")
	)
	(segment
		(start 263.7028 -26.543)
		(end 263.7028 -25.6794)
		(width 0.381)
		(layer "B.Cu")
		(net "GND")
	)
	(segment
		(start 342.0237 -82.2452)
		(end 342.4555 -82.677)
		(width 0.254)
		(layer "B.Cu")
		(net "GND")
	)
	(segment
		(start 146.149568 -137.877296)
		(end 146.149568 -139.089892)
		(width 0.4064)
		(layer "B.Cu")
		(net "GND")
	)
	(segment
		(start 309.449978 -2.302256)
		(end 309.437278 -2.314956)
		(width 0.4064)
		(layer "B.Cu")
		(net "GND")
	)
	(segment
		(start 38.199568 -13.36421)
		(end 38.199568 -15.222982)
		(width 0.4064)
		(layer "B.Cu")
		(net "GND")
	)
	(segment
		(start 306.049934 -147.478496)
		(end 306.050442 -147.478496)
		(width 0.4064)
		(layer "B.Cu")
		(net "GND")
	)
	(segment
		(start 34.799524 -147.478496)
		(end 34.799524 -148.691092)
		(width 0.4064)
		(layer "B.Cu")
		(net "GND")
	)
	(segment
		(start 53.442108 -21.494496)
		(end 53.442108 -21.513292)
		(width 0.4064)
		(layer "B.Cu")
		(net "GND")
	)
	(segment
		(start 58.599578 -151.83485)
		(end 58.599324 -151.834596)
		(width 0.4064)
		(layer "B.Cu")
		(net "GND")
	)
	(segment
		(start 201.037952 -4.346956)
		(end 201.499978 -4.808982)
		(width 0.4064)
		(layer "B.Cu")
		(net "GND")
	)
	(segment
		(start 236.095794 -13.440156)
		(end 236.171994 -13.363956)
		(width 0.4064)
		(layer "B.Cu")
		(net "GND")
	)
	(segment
		(start 416.9664 -21.336)
		(end 417.6014 -21.336)
		(width 0.254)
		(layer "B.Cu")
		(net "GND")
	)
	(segment
		(start 448.31 -147.955)
		(end 448.7926 -147.955)
		(width 0.254)
		(layer "B.Cu")
		(net "GND")
	)
	(segment
		(start 198.100442 -137.877296)
		(end 198.099934 -137.877296)
		(width 0.4064)
		(layer "B.Cu")
		(net "GND")
	)
	(segment
		(start 197.151752 -17.208246)
		(end 197.249796 -17.110202)
		(width 0.4064)
		(layer "B.Cu")
		(net "GND")
	)
	(segment
		(start 115.549426 -132.875782)
		(end 115.549426 -131.105656)
		(width 0.4064)
		(layer "B.Cu")
		(net "GND")
	)
	(segment
		(start 67.949318 -132.581396)
		(end 67.949318 -131.016756)
		(width 0.4064)
		(layer "B.Cu")
		(net "GND")
	)
	(segment
		(start 138.499342 -142.477236)
		(end 138.499342 -141.663928)
		(width 0.4064)
		(layer "B.Cu")
		(net "GND")
	)
	(segment
		(start 291.599874 -14.443964)
		(end 291.354256 -14.198346)
		(width 0.254)
		(layer "B.Cu")
		(net "GND")
	)
	(segment
		(start 217.3986 -141.427454)
		(end 217.3986 -141.3764)
		(width 0.254)
		(layer "B.Cu")
		(net "GND")
	)
	(segment
		(start 459.16723 -25.882854)
		(end 458.557376 -25.273)
		(width 0.508)
		(layer "B.Cu")
		(net "GND")
	)
	(segment
		(start 67.099434 0.444754)
		(end 67.099434 -1.021842)
		(width 0.4064)
		(layer "B.Cu")
		(net "GND")
	)
	(segment
		(start 314.550298 -152.078436)
		(end 314.54979 -152.078182)
		(width 0.4064)
		(layer "B.Cu")
		(net "GND")
	)
	(segment
		(start 108.540296 -156.910024)
		(end 108.540296 -158.379414)
		(width 0.4064)
		(layer "B.Cu")
		(net "GND")
	)
	(segment
		(start 388.493 -16.383)
		(end 389.255 -16.383)
		(width 0.254)
		(layer "B.Cu")
		(net "GND")
	)
	(segment
		(start 414.063942 -9.439656)
		(end 414.063942 -9.1821)
		(width 0.254)
		(layer "B.Cu")
		(net "GND")
	)
	(segment
		(start 374.934226 -37.063426)
		(end 375.2088 -37.338)
		(width 0.254)
		(layer "B.Cu")
		(net "GND")
	)
	(segment
		(start 243.668804 -86.794086)
		(end 243.338604 -86.794086)
		(width 0.254)
		(layer "B.Cu")
		(net "GND")
	)
	(segment
		(start 250.7615 -12.954)
		(end 249.9106 -12.954)
		(width 0.4064)
		(layer "B.Cu")
		(net "GND")
	)
	(segment
		(start 314.550298 -142.477236)
		(end 314.54979 -142.476982)
		(width 0.4064)
		(layer "B.Cu")
		(net "GND")
	)
	(segment
		(start 226.7458 -141.351)
		(end 226.7458 -140.694156)
		(width 0.4064)
		(layer "B.Cu")
		(net "GND")
	)
	(segment
		(start 67.099434 -128.276096)
		(end 67.099434 -129.568956)
		(width 0.4064)
		(layer "B.Cu")
		(net "GND")
	)
	(segment
		(start 268.859 3.81)
		(end 268.859 3.8862)
		(width 0.381)
		(layer "B.Cu")
		(net "GND")
	)
	(segment
		(start 283.04236 -2.310892)
		(end 283.04236 -2.292096)
		(width 0.4064)
		(layer "B.Cu")
		(net "GND")
	)
	(segment
		(start 52.398168 -23.038562)
		(end 52.471574 -22.965156)
		(width 0.4064)
		(layer "B.Cu")
		(net "GND")
	)
	(segment
		(start 62.792102 -18.744946)
		(end 62.849506 -18.80235)
		(width 0.4064)
		(layer "B.Cu")
		(net "GND")
	)
	(segment
		(start 135.099552 -21.479256)
		(end 135.099552 -20.224242)
		(width 0.4064)
		(layer "B.Cu")
		(net "GND")
	)
	(segment
		(start 391.3251 -66.8401)
		(end 391.414 -66.929)
		(width 0.254)
		(layer "B.Cu")
		(net "GND")
	)
	(segment
		(start 75.599544 -132.50545)
		(end 75.59929 -132.505196)
		(width 0.4064)
		(layer "B.Cu")
		(net "GND")
	)
	(segment
		(start 124.89942 -150.308056)
		(end 124.81052 -150.219156)
		(width 0.4064)
		(layer "B.Cu")
		(net "GND")
	)
	(segment
		(start 237.199932 -148.691092)
		(end 237.142528 -148.748496)
		(width 0.4064)
		(layer "B.Cu")
		(net "GND")
	)
	(segment
		(start 227.000308 -152.078436)
		(end 226.9998 -152.078182)
		(width 0.254)
		(layer "B.Cu")
		(net "GND")
	)
	(segment
		(start 295.000426 -1.021842)
		(end 294.999918 -1.021842)
		(width 0.4064)
		(layer "B.Cu")
		(net "GND")
	)
	(segment
		(start 233.800396 -147.478496)
		(end 233.799888 -147.478496)
		(width 0.4064)
		(layer "B.Cu")
		(net "GND")
	)
	(segment
		(start 163.6776 -80.7212)
		(end 163.2458 -81.153)
		(width 0.4064)
		(layer "B.Cu")
		(net "GND")
	)
	(segment
		(start 198.099934 -1.021842)
		(end 198.099934 0.444754)
		(width 0.4064)
		(layer "B.Cu")
		(net "GND")
	)
	(segment
		(start 300.099984 0.444754)
		(end 300.099984 -1.021842)
		(width 0.4064)
		(layer "B.Cu")
		(net "GND")
	)
	(segment
		(start 114.30254 -29.23032)
		(end 114.294412 -29.238448)
		(width 0.254)
		(layer "B.Cu")
		(net "GND")
	)
	(segment
		(start 306.899818 -17.208246)
		(end 306.899818 -15.222982)
		(width 0.4064)
		(layer "B.Cu")
		(net "GND")
	)
	(segment
		(start 207.449928 -139.157456)
		(end 207.437228 -139.170156)
		(width 0.4064)
		(layer "B.Cu")
		(net "GND")
	)
	(segment
		(start 278.8666 -8.1026)
		(end 278.8158 -8.1534)
		(width 0.381)
		(layer "B.Cu")
		(net "GND")
	)
	(segment
		(start 221.899734 -151.732996)
		(end 221.899734 -150.219156)
		(width 0.4064)
		(layer "B.Cu")
		(net "GND")
	)
	(segment
		(start 391.3251 -65.68186)
		(end 391.3251 -66.8401)
		(width 0.254)
		(layer "B.Cu")
		(net "GND")
	)
	(segment
		(start 414.073086 -9.552686)
		(end 414.073086 -9.4488)
		(width 0.254)
		(layer "B.Cu")
		(net "GND")
	)
	(segment
		(start 220.199966 -4.808982)
		(end 219.73794 -4.346956)
		(width 0.4064)
		(layer "B.Cu")
		(net "GND")
	)
	(segment
		(start 236.350302 -152.078436)
		(end 236.349794 -152.078182)
		(width 0.254)
		(layer "B.Cu")
		(net "GND")
	)
	(segment
		(start 232.099866 -2.314956)
		(end 232.099866 -1.021842)
		(width 0.4064)
		(layer "B.Cu")
		(net "GND")
	)
	(segment
		(start 389.151368 -44.874688)
		(end 389.90651 -44.874688)
		(width 0.254)
		(layer "B.Cu")
		(net "GND")
	)
	(segment
		(start 118.099332 -10.623042)
		(end 118.099332 -9.20115)
		(width 0.4064)
		(layer "B.Cu")
		(net "GND")
	)
	(segment
		(start 297.550332 -152.078436)
		(end 297.549824 -152.078182)
		(width 0.4064)
		(layer "B.Cu")
		(net "GND")
	)
	(segment
		(start 226.7458 -4.4958)
		(end 226.7458 -3.838956)
		(width 0.4064)
		(layer "B.Cu")
		(net "GND")
	)
	(segment
		(start 308.809644 -140.617956)
		(end 310.122062 -140.617956)
		(width 0.4064)
		(layer "B.Cu")
		(net "GND")
	)
	(segment
		(start 145.29943 -151.299164)
		(end 145.29943 -152.078436)
		(width 0.254)
		(layer "B.Cu")
		(net "GND")
	)
	(segment
		(start 37.34943 -10.623042)
		(end 37.34943 -9.156446)
		(width 0.4064)
		(layer "B.Cu")
		(net "GND")
	)
	(segment
		(start 294.999918 -20.224242)
		(end 294.999918 -18.757646)
		(width 0.4064)
		(layer "B.Cu")
		(net "GND")
	)
	(segment
		(start 115.549426 -131.105656)
		(end 115.460526 -131.016756)
		(width 0.4064)
		(layer "B.Cu")
		(net "GND")
	)
	(segment
		(start 156.690568 -8.122412)
		(end 157.528768 -8.122412)
		(width 0.4064)
		(layer "B.Cu")
		(net "GND")
	)
	(segment
		(start 238.900462 -5.621782)
		(end 238.899954 -5.621782)
		(width 0.4064)
		(layer "B.Cu")
		(net "GND")
	)
	(segment
		(start 282.004262 -14.1224)
		(end 282.004262 -13.431774)
		(width 0.4064)
		(layer "B.Cu")
		(net "GND")
	)
	(segment
		(start 205.749906 -10.623042)
		(end 205.749906 -9.143746)
		(width 0.4064)
		(layer "B.Cu")
		(net "GND")
	)
	(segment
		(start 135.949436 -5.621782)
		(end 135.949436 -4.842764)
		(width 0.254)
		(layer "B.Cu")
		(net "GND")
	)
	(segment
		(start 289.810952 -131.016756)
		(end 289.810952 -130.991356)
		(width 0.4064)
		(layer "B.Cu")
		(net "GND")
	)
	(segment
		(start 373.952262 -98.633026)
		(end 371.329712 -98.633026)
		(width 0.254)
		(layer "B.Cu")
		(net "GND")
	)
	(segment
		(start 41.599358 -24.824182)
		(end 41.599358 -23.028656)
		(width 0.4064)
		(layer "B.Cu")
		(net "GND")
	)
	(segment
		(start 61.745368 -131.8514)
		(end 61.745368 -131.7498)
		(width 0.254)
		(layer "B.Cu")
		(net "GND")
	)
	(segment
		(start 110.111032 -17.7546)
		(end 109.2581 -17.7546)
		(width 0.4064)
		(layer "B.Cu")
		(net "GND")
	)
	(segment
		(start 243.2304 -145.0086)
		(end 244.3607 -145.0086)
		(width 0.4572)
		(layer "B.Cu")
		(net "GND")
	)
	(segment
		(start 64.549528 -14.410182)
		(end 64.549528 -15.222982)
		(width 0.4064)
		(layer "B.Cu")
		(net "GND")
	)
	(segment
		(start 447.929 -152.5524)
		(end 448.6656 -153.289)
		(width 0.254)
		(layer "B.Cu")
		(net "GND")
	)
	(segment
		(start 226.9998 -7.4676)
		(end 226.9998 -5.621782)
		(width 0.4064)
		(layer "B.Cu")
		(net "GND")
	)
	(segment
		(start 197.250304 -15.222982)
		(end 197.249796 -15.222982)
		(width 0.4064)
		(layer "B.Cu")
		(net "GND")
	)
	(segment
		(start 143.599408 -7.509002)
		(end 143.501364 -7.607046)
		(width 0.4064)
		(layer "B.Cu")
		(net "GND")
	)
	(segment
		(start 314.54979 -5.621782)
		(end 314.54979 -3.762756)
		(width 0.4064)
		(layer "B.Cu")
		(net "GND")
	)
	(segment
		(start 232.101898 -67.47764)
		(end 231.33304 -67.47764)
		(width 0.254)
		(layer "B.Cu")
		(net "GND")
	)
	(segment
		(start 405.9174 -33.4264)
		(end 405.9174 -33.1216)
		(width 0.254)
		(layer "B.Cu")
		(net "GND")
	)
	(segment
		(start 71.349362 -15.222982)
		(end 71.349362 -17.0688)
		(width 0.4064)
		(layer "B.Cu")
		(net "GND")
	)
	(segment
		(start 285.649924 0.444754)
		(end 285.649924 -1.021842)
		(width 0.4064)
		(layer "B.Cu")
		(net "GND")
	)
	(segment
		(start 51.79949 -129.556256)
		(end 51.78679 -129.568956)
		(width 0.4064)
		(layer "B.Cu")
		(net "GND")
	)
	(segment
		(start 30.549342 -143.946626)
		(end 30.549342 -142.477236)
		(width 0.4064)
		(layer "B.Cu")
		(net "GND")
	)
	(segment
		(start 373.527828 -73.478136)
		(end 373.544846 -73.495154)
		(width 0.254)
		(layer "B.Cu")
		(net "GND")
	)
	(segment
		(start 74.749406 -20.224242)
		(end 74.749406 -21.517356)
		(width 0.4064)
		(layer "B.Cu")
		(net "GND")
	)
	(segment
		(start 212.549994 -151.78405)
		(end 212.54974 -151.783796)
		(width 0.4064)
		(layer "B.Cu")
		(net "GND")
	)
	(segment
		(start 120.649492 -147.478496)
		(end 120.649492 -148.771356)
		(width 0.4064)
		(layer "B.Cu")
		(net "GND")
	)
	(segment
		(start 198.950326 -152.078436)
		(end 198.949818 -152.078182)
		(width 0.254)
		(layer "B.Cu")
		(net "GND")
	)
	(segment
		(start 476.018098 -123.756928)
		(end 475.546928 -123.756928)
		(width 0.254)
		(layer "B.Cu")
		(net "GND")
	)
	(segment
		(start 149.549358 -142.477236)
		(end 149.549358 -140.617956)
		(width 0.4064)
		(layer "B.Cu")
		(net "GND")
	)
	(segment
		(start 427.9519 -17.272)
		(end 427.5836 -17.272)
		(width 0.254)
		(layer "B.Cu")
		(net "GND")
	)
	(segment
		(start 113.849404 -136.379966)
		(end 113.901728 -136.327642)
		(width 0.4064)
		(layer "B.Cu")
		(net "GND")
	)
	(segment
		(start 33.703768 -4.597146)
		(end 33.703768 -4.5212)
		(width 0.254)
		(layer "B.Cu")
		(net "GND")
	)
	(segment
		(start 487.160062 -29.3116)
		(end 486.32872 -29.3116)
		(width 0.254)
		(layer "B.Cu")
		(net "GND")
	)
	(segment
		(start 43.29938 -5.621782)
		(end 43.29938 -4.893564)
		(width 0.254)
		(layer "B.Cu")
		(net "GND")
	)
	(segment
		(start 146.149568 -148.691092)
		(end 146.092164 -148.748496)
		(width 0.4064)
		(layer "B.Cu")
		(net "GND")
	)
	(segment
		(start 472.233498 -135.684514)
		(end 472.241118 -135.676894)
		(width 0.254)
		(layer "B.Cu")
		(net "GND")
	)
	(segment
		(start 77.299566 -17.207992)
		(end 77.299312 -17.208246)
		(width 0.4064)
		(layer "B.Cu")
		(net "GND")
	)
	(segment
		(start 445.0715 -35.8775)
		(end 445.937132 -35.8775)
		(width 0.4064)
		(layer "B.Cu")
		(net "GND")
	)
	(segment
		(start 301.800006 -20.224242)
		(end 301.800006 -21.455888)
		(width 0.4064)
		(layer "B.Cu")
		(net "GND")
	)
	(segment
		(start 38.199568 -5.621782)
		(end 38.199568 -3.76301)
		(width 0.4064)
		(layer "B.Cu")
		(net "GND")
	)
	(segment
		(start 49.249584 -142.477236)
		(end 49.249584 -142.13205)
		(width 0.4064)
		(layer "B.Cu")
		(net "GND")
	)
	(segment
		(start 83.56727 -125.63983)
		(end 84.70138 -126.77394)
		(width 0.254)
		(layer "B.Cu")
		(net "GND")
	)
	(segment
		(start 289.049968 -9.143746)
		(end 289.049968 -10.623042)
		(width 0.4064)
		(layer "B.Cu")
		(net "GND")
	)
	(segment
		(start 150.399496 -137.877296)
		(end 150.399496 -139.170156)
		(width 0.4064)
		(layer "B.Cu")
		(net "GND")
	)
	(segment
		(start 445.352678 -37.028628)
		(end 445.933068 -37.028628)
		(width 0.4064)
		(layer "B.Cu")
		(net "GND")
	)
	(segment
		(start 44.149518 -148.691092)
		(end 44.092114 -148.748496)
		(width 0.4064)
		(layer "B.Cu")
		(net "GND")
	)
	(segment
		(start 278.727408 3.060192)
		(end 277.9776 3.81)
		(width 0.381)
		(layer "B.Cu")
		(net "GND")
	)
	(segment
		(start 119.799354 -14.410182)
		(end 119.799354 -15.222982)
		(width 0.4064)
		(layer "B.Cu")
		(net "GND")
	)
	(segment
		(start 113.967768 -150.0886)
		(end 113.967768 -150.659592)
		(width 0.4064)
		(layer "B.Cu")
		(net "GND")
	)
	(segment
		(start 310.299862 -141.697964)
		(end 310.299862 -142.476982)
		(width 0.254)
		(layer "B.Cu")
		(net "GND")
	)
	(segment
		(start 227.849938 -9.20115)
		(end 227.792534 -9.143746)
		(width 0.4064)
		(layer "B.Cu")
		(net "GND")
	)
	(segment
		(start 70.499478 -147.478496)
		(end 70.499478 -148.733256)
		(width 0.4064)
		(layer "B.Cu")
		(net "GND")
	)
	(segment
		(start 231.249982 -132.875782)
		(end 231.249982 -132.50545)
		(width 0.4064)
		(layer "B.Cu")
		(net "GND")
	)
	(segment
		(start 461.057244 -131.0386)
		(end 461.751172 -130.344672)
		(width 0.254)
		(layer "B.Cu")
		(net "GND")
	)
	(segment
		(start 291.599874 -141.697964)
		(end 291.354256 -141.452346)
		(width 0.254)
		(layer "B.Cu")
		(net "GND")
	)
	(segment
		(start 51.78679 -11.916156)
		(end 51.76139 -11.916156)
		(width 0.4064)
		(layer "B.Cu")
		(net "GND")
	)
	(segment
		(start 291.599874 -4.842764)
		(end 291.599874 -5.621782)
		(width 0.254)
		(layer "B.Cu")
		(net "GND")
	)
	(segment
		(start 60.210446 -3.737356)
		(end 60.210446 -3.762756)
		(width 0.4064)
		(layer "B.Cu")
		(net "GND")
	)
	(segment
		(start 308.59984 -23.17496)
		(end 308.809644 -22.965156)
		(width 0.4064)
		(layer "B.Cu")
		(net "GND")
	)
	(segment
		(start 78.14945 -22.073362)
		(end 78.274164 -22.198076)
		(width 0.4064)
		(layer "B.Cu")
		(net "GND")
	)
	(segment
		(start 373.498618 -88.235282)
		(end 374.015 -87.7189)
		(width 0.254)
		(layer "B.Cu")
		(net "GND")
	)
	(segment
		(start 289.90036 -132.876036)
		(end 289.899852 -132.875782)
		(width 0.4064)
		(layer "B.Cu")
		(net "GND")
	)
	(segment
		(start 67.949318 -151.783796)
		(end 67.949318 -150.219156)
		(width 0.4064)
		(layer "B.Cu")
		(net "GND")
	)
	(segment
		(start 226.7458 -150.9522)
		(end 226.7458 -150.295356)
		(width 0.4064)
		(layer "B.Cu")
		(net "GND")
	)
	(segment
		(start 317.949834 -24.824182)
		(end 317.949834 -23.520146)
		(width 0.4064)
		(layer "B.Cu")
		(net "GND")
	)
	(segment
		(start 221.04985 -147.478496)
		(end 221.04985 -148.771356)
		(width 0.4064)
		(layer "B.Cu")
		(net "GND")
	)
	(segment
		(start 114.83848 -124.655834)
		(end 114.83848 -125.78588)
		(width 0.508)
		(layer "B.Cu")
		(net "GND")
	)
	(segment
		(start 49.249584 -5.27685)
		(end 49.24933 -5.276596)
		(width 0.4064)
		(layer "B.Cu")
		(net "GND")
	)
	(segment
		(start 226.7458 -14.097)
		(end 226.7458 -13.440156)
		(width 0.4064)
		(layer "B.Cu")
		(net "GND")
	)
	(segment
		(start 31.908496 -56.802782)
		(end 31.174182 -56.802782)
		(width 0.254)
		(layer "B.Cu")
		(net "GND")
	)
	(segment
		(start 226.150424 -147.478496)
		(end 226.149916 -147.478496)
		(width 0.4064)
		(layer "B.Cu")
		(net "GND")
	)
	(segment
		(start 242.299998 -7.606792)
		(end 242.299744 -7.607046)
		(width 0.4064)
		(layer "B.Cu")
		(net "GND")
	)
	(segment
		(start 300.100492 -137.877296)
		(end 300.099984 -137.877296)
		(width 0.4064)
		(layer "B.Cu")
		(net "GND")
	)
	(segment
		(start 434.722524 -42.546778)
		(end 434.545994 -42.370248)
		(width 0.254)
		(layer "B.Cu")
		(net "GND")
	)
	(segment
		(start 78.14945 -149.327362)
		(end 78.14945 -147.478496)
		(width 0.4064)
		(layer "B.Cu")
		(net "GND")
	)
	(segment
		(start 421.004492 -70.4342)
		(end 420.8526 -70.4342)
		(width 0.254)
		(layer "B.Cu")
		(net "GND")
	)
	(segment
		(start 121.499376 -7.607046)
		(end 121.499376 -5.621782)
		(width 0.4064)
		(layer "B.Cu")
		(net "GND")
	)
	(segment
		(start 213.399878 -10.623042)
		(end 213.399878 -9.156446)
		(width 0.4064)
		(layer "B.Cu")
		(net "GND")
	)
	(segment
		(start 214.250016 -17.207992)
		(end 214.250016 -15.222982)
		(width 0.4064)
		(layer "B.Cu")
		(net "GND")
	)
	(segment
		(start 278.8158 -8.1534)
		(end 277.397464 -8.1534)
		(width 0.381)
		(layer "B.Cu")
		(net "GND")
	)
	(segment
		(start 71.349362 -17.0688)
		(end 71.171562 -17.2466)
		(width 0.4064)
		(layer "B.Cu")
		(net "GND")
	)
	(segment
		(start 353.367848 -90.87104)
		(end 353.367848 -91.153742)
		(width 0.254)
		(layer "B.Cu")
		(net "GND")
	)
	(segment
		(start 461.751172 -130.344672)
		(end 461.751172 -129.6924)
		(width 0.254)
		(layer "B.Cu")
		(net "GND")
	)
	(segment
		(start 117.00383 -14.1224)
		(end 117.00383 -13.431774)
		(width 0.4064)
		(layer "B.Cu")
		(net "GND")
	)
	(segment
		(start 246.619268 -17.7546)
		(end 247.4595 -17.7546)
		(width 0.4572)
		(layer "B.Cu")
		(net "GND")
	)
	(segment
		(start 298.40047 -128.276096)
		(end 298.399962 -128.276096)
		(width 0.4064)
		(layer "B.Cu")
		(net "GND")
	)
	(segment
		(start 463.32775 -124.92482)
		(end 463.32775 -126.33325)
		(width 0.254)
		(layer "B.Cu")
		(net "GND")
	)
	(segment
		(start 222.749872 -147.478496)
		(end 222.749872 -148.771356)
		(width 0.4064)
		(layer "B.Cu")
		(net "GND")
	)
	(segment
		(start 175.323754 -85.689948)
		(end 175.511206 -85.8774)
		(width 0.4064)
		(layer "B.Cu")
		(net "GND")
	)
	(segment
		(start 152.099518 -137.877296)
		(end 152.099518 -139.181078)
		(width 0.4064)
		(layer "B.Cu")
		(net "GND")
	)
	(segment
		(start 32.249364 -5.621782)
		(end 32.249364 -4.514342)
		(width 0.4064)
		(layer "B.Cu")
		(net "GND")
	)
	(segment
		(start 2.27076 -5.35686)
		(end 2.27076 -5.95376)
		(width 0.4064)
		(layer "B.Cu")
		(net "GND")
	)
	(segment
		(start 115.460526 -140.592556)
		(end 115.460526 -140.617956)
		(width 0.4064)
		(layer "B.Cu")
		(net "GND")
	)
	(segment
		(start 407.67 -0.7366)
		(end 408.1018 -1.1684)
		(width 0.254)
		(layer "B.Cu")
		(net "GND")
	)
	(segment
		(start 208.299812 -5.621782)
		(end 208.299812 -4.893564)
		(width 0.254)
		(layer "B.Cu")
		(net "GND")
	)
	(segment
		(start 56.899556 -142.477236)
		(end 56.899556 -142.13205)
		(width 0.4064)
		(layer "B.Cu")
		(net "GND")
	)
	(segment
		(start 196.399912 -10.623042)
		(end 196.399912 -11.916156)
		(width 0.4064)
		(layer "B.Cu")
		(net "GND")
	)
	(segment
		(start 135.703818 -3.830574)
		(end 135.771636 -3.762756)
		(width 0.4064)
		(layer "B.Cu")
		(net "GND")
	)
	(segment
		(start 303.500282 -132.876036)
		(end 303.499774 -132.875782)
		(width 0.4064)
		(layer "B.Cu")
		(net "GND")
	)
	(segment
		(start 310.299862 -4.842764)
		(end 310.054244 -4.597146)
		(width 0.254)
		(layer "B.Cu")
		(net "GND")
	)
	(segment
		(start 123.199398 -15.222982)
		(end 123.199398 -13.363956)
		(width 0.4064)
		(layer "B.Cu")
		(net "GND")
	)
	(segment
		(start 30.549342 -13.929106)
		(end 30.549342 -15.222982)
		(width 0.4064)
		(layer "B.Cu")
		(net "GND")
	)
	(segment
		(start 290.74999 -147.478496)
		(end 290.74999 -148.758656)
		(width 0.4064)
		(layer "B.Cu")
		(net "GND")
	)
	(segment
		(start 291.354256 -4.597146)
		(end 291.599874 -4.842764)
		(width 0.254)
		(layer "B.Cu")
		(net "GND")
	)
	(segment
		(start 443.2808 -141.062202)
		(end 443.908688 -141.062202)
		(width 0.254)
		(layer "B.Cu")
		(net "GND")
	)
	(segment
		(start 465.9122 -10.4394)
		(end 466.598 -11.1252)
		(width 0.508)
		(layer "B.Cu")
		(net "GND")
	)
	(segment
		(start 67.099434 -10.623042)
		(end 67.099434 -11.916156)
		(width 0.4064)
		(layer "B.Cu")
		(net "GND")
	)
	(segment
		(start 224.449894 -10.623042)
		(end 224.449894 -9.143746)
		(width 0.4064)
		(layer "B.Cu")
		(net "GND")
	)
	(segment
		(start 31.39948 -18.744946)
		(end 31.39948 -20.224242)
		(width 0.4064)
		(layer "B.Cu")
		(net "GND")
	)
	(segment
		(start 142.749524 -21.517356)
		(end 142.749524 -20.224242)
		(width 0.4064)
		(layer "B.Cu")
		(net "GND")
	)
	(segment
		(start 105.9561 -12.954)
		(end 107.027472 -12.954)
		(width 0.4064)
		(layer "B.Cu")
		(net "GND")
	)
	(segment
		(start 163.6776 -77.978)
		(end 163.6776 -78.359)
		(width 0.381)
		(layer "B.Cu")
		(net "GND")
	)
	(segment
		(start 213.399878 -11.916156)
		(end 213.399878 -10.623042)
		(width 0.4064)
		(layer "B.Cu")
		(net "GND")
	)
	(segment
		(start 69.64934 -132.876036)
		(end 69.64934 -131.105656)
		(width 0.4064)
		(layer "B.Cu")
		(net "GND")
	)
	(segment
		(start 135.949436 -15.222982)
		(end 135.949436 -14.443964)
		(width 0.254)
		(layer "B.Cu")
		(net "GND")
	)
	(segment
		(start 31.634938 -95.9104)
		(end 31.893002 -96.168464)
		(width 0.254)
		(layer "B.Cu")
		(net "GND")
	)
	(segment
		(start 47.549308 -17.208246)
		(end 47.549562 -17.207992)
		(width 0.4064)
		(layer "B.Cu")
		(net "GND")
	)
	(segment
		(start 370.284756 -3.420364)
		(end 370.323364 -3.420364)
		(width 0.381)
		(layer "B.Cu")
		(net "GND")
	)
	(segment
		(start 380.9492 -50.6095)
		(end 380.9492 -50.6222)
		(width 0.254)
		(layer "B.Cu")
		(net "GND")
	)
	(segment
		(start 443.552326 -148.140674)
		(end 442.96838 -148.72462)
		(width 0.254)
		(layer "B.Cu")
		(net "GND")
	)
	(segment
		(start 240.599722 -17.208246)
		(end 240.599976 -17.207992)
		(width 0.4064)
		(layer "B.Cu")
		(net "GND")
	)
	(segment
		(start 179.2986 -88.3412)
		(end 181.3306 -88.3412)
		(width 0.254)
		(layer "B.Cu")
		(net "GND")
	)
	(segment
		(start 151.24938 -7.607046)
		(end 151.24938 -5.621782)
		(width 0.4064)
		(layer "B.Cu")
		(net "GND")
	)
	(segment
		(start 418.719 -33.4645)
		(end 418.719 -32.7025)
		(width 0.381)
		(layer "B.Cu")
		(net "GND")
	)
	(segment
		(start 166.116 -86.868)
		(end 166.4208 -86.868)
		(width 0.4064)
		(layer "B.Cu")
		(net "GND")
	)
	(segment
		(start 134.249414 -7.509002)
		(end 134.249414 -5.621782)
		(width 0.4064)
		(layer "B.Cu")
		(net "GND")
	)
	(segment
		(start 395.097 -63.627)
		(end 395.5542 -63.627)
		(width 0.254)
		(layer "B.Cu")
		(net "GND")
	)
	(segment
		(start 308.600348 -142.477236)
		(end 308.59984 -142.476982)
		(width 0.4064)
		(layer "B.Cu")
		(net "GND")
	)
	(segment
		(start 495.45748 -129.63652)
		(end 495.45748 -129.48412)
		(width 0.254)
		(layer "B.Cu")
		(net "GND")
	)
	(segment
		(start 145.053812 -150.9776)
		(end 145.053812 -151.053546)
		(width 0.254)
		(layer "B.Cu")
		(net "GND")
	)
	(segment
		(start 437.0324 -18.212054)
		(end 435.864 -19.380454)
		(width 0.254)
		(layer "B.Cu")
		(net "GND")
	)
	(segment
		(start 121.499376 -132.876036)
		(end 121.499376 -131.016756)
		(width 0.4064)
		(layer "B.Cu")
		(net "GND")
	)
	(segment
		(start 45.84954 -14.410182)
		(end 45.84954 -15.222982)
		(width 0.4064)
		(layer "B.Cu")
		(net "GND")
	)
	(segment
		(start 232.94975 -17.208246)
		(end 232.950004 -17.207992)
		(width 0.4064)
		(layer "B.Cu")
		(net "GND")
	)
	(segment
		(start 135.099552 -11.903456)
		(end 135.099552 -10.623042)
		(width 0.4064)
		(layer "B.Cu")
		(net "GND")
	)
	(segment
		(start 226.149916 0.444754)
		(end 226.149916 -1.021842)
		(width 0.4064)
		(layer "B.Cu")
		(net "GND")
	)
	(segment
		(start 195.550282 -152.078436)
		(end 195.549774 -152.078182)
		(width 0.4064)
		(layer "B.Cu")
		(net "GND")
	)
	(segment
		(start 389.460232 -63.45809)
		(end 388.75589 -63.45809)
		(width 0.254)
		(layer "B.Cu")
		(net "GND")
	)
	(segment
		(start 144.449546 -1.021842)
		(end 144.449546 -2.302256)
		(width 0.4064)
		(layer "B.Cu")
		(net "GND")
	)
	(segment
		(start 116.399564 -128.276096)
		(end 116.399564 -129.556256)
		(width 0.4064)
		(layer "B.Cu")
		(net "GND")
	)
	(segment
		(start 323.194426 -124.564648)
		(end 323.629274 -124.1298)
		(width 0.254)
		(layer "B.Cu")
		(net "GND")
	)
	(segment
		(start 113.228628 -135.4074)
		(end 113.472722 -135.651494)
		(width 0.4064)
		(layer "B.Cu")
		(net "GND")
	)
	(segment
		(start 475.2086 -45.6438)
		(end 475.2086 -44.7548)
		(width 0.508)
		(layer "B.Cu")
		(net "GND")
	)
	(segment
		(start 242.299744 -24.402796)
		(end 242.299998 -24.40305)
		(width 0.4064)
		(layer "B.Cu")
		(net "GND")
	)
	(segment
		(start 493.95634 -123.06808)
		(end 494.48212 -122.5423)
		(width 0.254)
		(layer "B.Cu")
		(net "GND")
	)
	(segment
		(start 33.099502 -9.139682)
		(end 33.099502 -10.623042)
		(width 0.4064)
		(layer "B.Cu")
		(net "GND")
	)
	(segment
		(start 405.726646 -25.437846)
		(end 405.726646 -25.600152)
		(width 0.254)
		(layer "B.Cu")
		(net "GND")
	)
	(segment
		(start 304.349912 -148.771356)
		(end 304.349912 -147.478496)
		(width 0.4064)
		(layer "B.Cu")
		(net "GND")
	)
	(segment
		(start 279.699974 -2.314956)
		(end 279.699974 -1.021842)
		(width 0.4064)
		(layer "B.Cu")
		(net "GND")
	)
	(segment
		(start 377.7234 -83.29295)
		(end 377.7234 -82.7786)
		(width 0.254)
		(layer "B.Cu")
		(net "GND")
	)
	(segment
		(start 67.949318 -24.529796)
		(end 67.949572 -24.53005)
		(width 0.4064)
		(layer "B.Cu")
		(net "GND")
	)
	(segment
		(start 77.299312 -22.977856)
		(end 77.299312 -24.402796)
		(width 0.4064)
		(layer "B.Cu")
		(net "GND")
	)
	(segment
		(start 402.844 -22.225)
		(end 403.1234 -22.5044)
		(width 0.254)
		(layer "B.Cu")
		(net "GND")
	)
	(segment
		(start 244.3607 -17.7546)
		(end 244.2337 -17.8816)
		(width 0.508)
		(layer "B.Cu")
		(net "GND")
	)
	(segment
		(start 373.565166 -60.222892)
		(end 373.520716 -60.178442)
		(width 0.254)
		(layer "B.Cu")
		(net "GND")
	)
	(segment
		(start 73.899522 -141.664182)
		(end 73.437496 -141.202156)
		(width 0.4064)
		(layer "B.Cu")
		(net "GND")
	)
	(segment
		(start 198.7042 -131.7752)
		(end 198.7042 -131.084574)
		(width 0.4064)
		(layer "B.Cu")
		(net "GND")
	)
	(segment
		(start 38.199314 -13.363956)
		(end 38.199568 -13.36421)
		(width 0.4064)
		(layer "B.Cu")
		(net "GND")
	)
	(segment
		(start 346.732098 -91.453716)
		(end 346.895674 -91.617292)
		(width 0.2032)
		(layer "B.Cu")
		(net "GND")
	)
	(segment
		(start 204.049884 -20.224242)
		(end 204.049884 -21.517356)
		(width 0.4064)
		(layer "B.Cu")
		(net "GND")
	)
	(segment
		(start 49.249584 -17.207992)
		(end 49.24933 -17.208246)
		(width 0.4064)
		(layer "B.Cu")
		(net "GND")
	)
	(segment
		(start 374.777 -101.1936)
		(end 374.2563 -101.1936)
		(width 0.254)
		(layer "B.Cu")
		(net "GND")
	)
	(segment
		(start 244.129306 -65.1764)
		(end 244.129306 -64.2874)
		(width 0.254)
		(layer "B.Cu")
		(net "GND")
	)
	(segment
		(start 375.9835 -44.9072)
		(end 375.9835 -45.72)
		(width 0.254)
		(layer "B.Cu")
		(net "GND")
	)
	(segment
		(start 386.520182 -2.385568)
		(end 387.7818 -2.385568)
		(width 0.254)
		(layer "B.Cu")
		(net "GND")
	)
	(segment
		(start 31.908496 -73.058782)
		(end 31.900114 -73.0504)
		(width 0.254)
		(layer "B.Cu")
		(net "GND")
	)
	(segment
		(start 410.387292 -3.347212)
		(end 410.387292 -3.225292)
		(width 0.254)
		(layer "B.Cu")
		(net "GND")
	)
	(segment
		(start 312.850276 -132.876036)
		(end 312.849768 -132.875782)
		(width 0.4064)
		(layer "B.Cu")
		(net "GND")
	)
	(segment
		(start 71.171562 -22.965156)
		(end 71.095362 -23.041356)
		(width 0.4064)
		(layer "B.Cu")
		(net "GND")
	)
	(segment
		(start 204.050392 -1.021842)
		(end 204.049884 -1.021842)
		(width 0.4064)
		(layer "B.Cu")
		(net "GND")
	)
	(segment
		(start 166.5097 -3.68046)
		(end 166.19474 -3.68046)
		(width 0.254)
		(layer "B.Cu")
		(net "GND")
	)
	(segment
		(start 226.7458 -14.1986)
		(end 226.7458 -14.097)
		(width 0.254)
		(layer "B.Cu")
		(net "GND")
	)
	(segment
		(start 132.549392 -15.222982)
		(end 132.549392 -17.208246)
		(width 0.4064)
		(layer "B.Cu")
		(net "GND")
	)
	(segment
		(start 56.049418 0.444754)
		(end 56.049418 -1.021842)
		(width 0.4064)
		(layer "B.Cu")
		(net "GND")
	)
	(segment
		(start 118.041928 -2.292096)
		(end 118.041928 -2.310892)
		(width 0.4064)
		(layer "B.Cu")
		(net "GND")
	)
	(segment
		(start 107.027472 -135.4074)
		(end 105.9561 -135.4074)
		(width 0.4572)
		(layer "B.Cu")
		(net "GND")
	)
	(segment
		(start 452.4248 -129.0574)
		(end 451.9422 -129.0574)
		(width 0.254)
		(layer "B.Cu")
		(net "GND")
	)
	(segment
		(start 119.799354 -15.222982)
		(end 119.799354 -16.23822)
		(width 0.4064)
		(layer "B.Cu")
		(net "GND")
	)
	(segment
		(start 174.371 -87.1728)
		(end 174.0662 -86.868)
		(width 0.4064)
		(layer "B.Cu")
		(net "GND")
	)
	(segment
		(start 125.749558 -20.224242)
		(end 125.749558 -21.504656)
		(width 0.4064)
		(layer "B.Cu")
		(net "GND")
	)
	(segment
		(start 116.399564 -11.903456)
		(end 116.399564 -10.623042)
		(width 0.4064)
		(layer "B.Cu")
		(net "GND")
	)
	(segment
		(start 376.814842 -45.974)
		(end 376.814842 -45.9994)
		(width 0.254)
		(layer "B.Cu")
		(net "GND")
	)
	(segment
		(start 226.9998 -4.8514)
		(end 226.7458 -4.5974)
		(width 0.254)
		(layer "B.Cu")
		(net "GND")
	)
	(segment
		(start 286.499808 -3.762756)
		(end 286.499808 -5.621782)
		(width 0.4064)
		(layer "B.Cu")
		(net "GND")
	)
	(segment
		(start 285.649924 -9.156446)
		(end 285.649924 -10.623042)
		(width 0.4064)
		(layer "B.Cu")
		(net "GND")
	)
	(segment
		(start 33.099502 -148.758656)
		(end 33.086802 -148.771356)
		(width 0.4064)
		(layer "B.Cu")
		(net "GND")
	)
	(segment
		(start 485.053894 4.157472)
		(end 484.336852 4.157472)
		(width 0.508)
		(layer "B.Cu")
		(net "GND")
	)
	(segment
		(start 493.722914 -43.948858)
		(end 494.082578 -43.948858)
		(width 0.254)
		(layer "B.Cu")
		(net "GND")
	)
	(segment
		(start 53.442108 -9.143746)
		(end 53.499512 -9.20115)
		(width 0.4064)
		(layer "B.Cu")
		(net "GND")
	)
	(segment
		(start 147.849336 -4.808728)
		(end 147.849336 -5.621782)
		(width 0.4064)
		(layer "B.Cu")
		(net "GND")
	)
	(segment
		(start 203.2 -3.76301)
		(end 203.2 -5.621782)
		(width 0.4064)
		(layer "B.Cu")
		(net "GND")
	)
	(segment
		(start 281.399996 -20.224242)
		(end 281.399996 -18.757646)
		(width 0.4064)
		(layer "B.Cu")
		(net "GND")
	)
	(segment
		(start 414.073086 -9.4488)
		(end 414.063942 -9.439656)
		(width 0.254)
		(layer "B.Cu")
		(net "GND")
	)
	(segment
		(start 36.499546 -151.265382)
		(end 36.03752 -150.803356)
		(width 0.4064)
		(layer "B.Cu")
		(net "GND")
	)
	(segment
		(start 198.099934 -10.623042)
		(end 198.099934 -9.139682)
		(width 0.4064)
		(layer "B.Cu")
		(net "GND")
	)
	(segment
		(start 129.999486 -18.757646)
		(end 129.999486 -20.224242)
		(width 0.4064)
		(layer "B.Cu")
		(net "GND")
	)
	(segment
		(start 48.399446 -2.314956)
		(end 48.399446 -1.021842)
		(width 0.4064)
		(layer "B.Cu")
		(net "GND")
	)
	(segment
		(start 161.044382 -63.376302)
		(end 160.703768 -63.035688)
		(width 0.254)
		(layer "B.Cu")
		(net "GND")
	)
	(segment
		(start 69.64934 -24.824182)
		(end 69.64934 -25.676098)
		(width 0.4064)
		(layer "B.Cu")
		(net "GND")
	)
	(segment
		(start 196.893434 -71.784464)
		(end 196.439536 -71.784464)
		(width 0.254)
		(layer "B.Cu")
		(net "GND")
	)
	(segment
		(start 241.44986 -1.021842)
		(end 241.44986 -2.314956)
		(width 0.4064)
		(layer "B.Cu")
		(net "GND")
	)
	(segment
		(start 298.399962 -1.021842)
		(end 298.399962 -2.314956)
		(width 0.4064)
		(layer "B.Cu")
		(net "GND")
	)
	(segment
		(start 147.849336 -6.637274)
		(end 147.390866 -7.095744)
		(width 0.4064)
		(layer "B.Cu")
		(net "GND")
	)
	(segment
		(start 220.200474 -132.876036)
		(end 220.199966 -132.875782)
		(width 0.4064)
		(layer "B.Cu")
		(net "GND")
	)
	(segment
		(start 138.499342 -16.238474)
		(end 138.499342 -15.222982)
		(width 0.4064)
		(layer "B.Cu")
		(net "GND")
	)
	(segment
		(start 255.167892 -144.63014)
		(end 255.862328 -144.63014)
		(width 0.4572)
		(layer "B.Cu")
		(net "GND")
	)
	(segment
		(start 363.24032 -56.97728)
		(end 364.4265 -56.97728)
		(width 0.254)
		(layer "B.Cu")
		(net "GND")
	)
	(segment
		(start 449.6943 -131.971796)
		(end 449.3006 -132.365496)
		(width 0.254)
		(layer "B.Cu")
		(net "GND")
	)
	(segment
		(start 191.897 -155.956)
		(end 191.77 -156.083)
		(width 0.508)
		(layer "B.Cu")
		(net "GND")
	)
	(segment
		(start -0.4445 -145.8214)
		(end 0.361188 -145.8214)
		(width 0.254)
		(layer "B.Cu")
		(net "GND")
	)
	(segment
		(start 201.499978 -24.011382)
		(end 201.037952 -23.549356)
		(width 0.4064)
		(layer "B.Cu")
		(net "GND")
	)
	(segment
		(start 400.71675 -77.06995)
		(end 400.71675 -74.78522)
		(width 0.254)
		(layer "B.Cu")
		(net "GND")
	)
	(segment
		(start 300.099984 -148.733256)
		(end 300.061884 -148.771356)
		(width 0.4064)
		(layer "B.Cu")
		(net "GND")
	)
	(segment
		(start 314.760102 -29.511752)
		(end 314.760102 -29.10205)
		(width 0.254)
		(layer "B.Cu")
		(net "GND")
	)
	(segment
		(start 129.149348 -6.637274)
		(end 128.690878 -7.095744)
		(width 0.4064)
		(layer "B.Cu")
		(net "GND")
	)
	(segment
		(start 198.7042 -150.286974)
		(end 198.772018 -150.219156)
		(width 0.4064)
		(layer "B.Cu")
		(net "GND")
	)
	(segment
		(start 212.550502 -142.477236)
		(end 212.549994 -142.476982)
		(width 0.4064)
		(layer "B.Cu")
		(net "GND")
	)
	(segment
		(start 278.884126 -135.538972)
		(end 277.910036 -135.538972)
		(width 0.4572)
		(layer "B.Cu")
		(net "GND")
	)
	(segment
		(start 217.3986 -131.826254)
		(end 217.3986 -131.7752)
		(width 0.254)
		(layer "B.Cu")
		(net "GND")
	)
	(segment
		(start 48.399446 -137.877296)
		(end 48.399446 -139.170156)
		(width 0.4064)
		(layer "B.Cu")
		(net "GND")
	)
	(segment
		(start 278.849836 -10.623042)
		(end 278.849836 -11.857736)
		(width 0.4064)
		(layer "B.Cu")
		(net "GND")
	)
	(segment
		(start 22.225254 -32.43072)
		(end 21.6535 -32.43072)
		(width 0.508)
		(layer "B.Cu")
		(net "GND")
	)
	(segment
		(start 78.14945 -2.3622)
		(end 78.14945 -1.021842)
		(width 0.4064)
		(layer "B.Cu")
		(net "GND")
	)
	(segment
		(start 71.095362 -23.7998)
		(end 71.349362 -24.0538)
		(width 0.254)
		(layer "B.Cu")
		(net "GND")
	)
	(segment
		(start 300.087284 -129.568956)
		(end 300.061884 -129.568956)
		(width 0.4064)
		(layer "B.Cu")
		(net "GND")
	)
	(segment
		(start 230.399844 -147.478496)
		(end 230.399844 -148.771356)
		(width 0.4064)
		(layer "B.Cu")
		(net "GND")
	)
	(segment
		(start 64.549528 -24.824182)
		(end 64.549528 -26.22423)
		(width 0.4064)
		(layer "B.Cu")
		(net "GND")
	)
	(segment
		(start 60.299346 -152.078436)
		(end 60.299346 -150.308056)
		(width 0.4064)
		(layer "B.Cu")
		(net "GND")
	)
	(segment
		(start 226.149916 -137.877296)
		(end 226.149916 -139.157456)
		(width 0.4064)
		(layer "B.Cu")
		(net "GND")
	)
	(segment
		(start 315.399928 -1.021842)
		(end 315.399928 -2.314956)
		(width 0.4064)
		(layer "B.Cu")
		(net "GND")
	)
	(segment
		(start 82.116168 -26.5938)
		(end 82.116168 -26.6446)
		(width 0.381)
		(layer "B.Cu")
		(net "GND")
	)
	(segment
		(start 255.186942 -17.35709)
		(end 255.87452 -17.35709)
		(width 0.4572)
		(layer "B.Cu")
		(net "GND")
	)
	(segment
		(start 311.15 -139.089892)
		(end 311.092596 -139.147296)
		(width 0.4064)
		(layer "B.Cu")
		(net "GND")
	)
	(segment
		(start 240.600484 -15.222982)
		(end 240.599976 -15.222982)
		(width 0.4064)
		(layer "B.Cu")
		(net "GND")
	)
	(segment
		(start 135.086852 -139.170156)
		(end 135.061452 -139.170156)
		(width 0.4064)
		(layer "B.Cu")
		(net "GND")
	)
	(segment
		(start 43.29938 -4.893564)
		(end 43.050968 -4.645152)
		(width 0.254)
		(layer "B.Cu")
		(net "GND")
	)
	(segment
		(start 234.560872 -150.219156)
		(end 234.560872 -150.193756)
		(width 0.4064)
		(layer "B.Cu")
		(net "GND")
	)
	(segment
		(start 370.967 -4.064)
		(end 370.967 -5.207)
		(width 0.381)
		(layer "B.Cu")
		(net "GND")
	)
	(segment
		(start 300.949868 -141.697964)
		(end 300.949868 -142.476982)
		(width 0.254)
		(layer "B.Cu")
		(net "GND")
	)
	(segment
		(start 33.771586 -7.6454)
		(end 33.949386 -7.4676)
		(width 0.4064)
		(layer "B.Cu")
		(net "GND")
	)
	(segment
		(start 313.424062 -27.727148)
		(end 313.424062 -28.420822)
		(width 0.381)
		(layer "B.Cu")
		(net "GND")
	)
	(segment
		(start 71.095362 -4.5974)
		(end 71.349362 -4.8514)
		(width 0.254)
		(layer "B.Cu")
		(net "GND")
	)
	(segment
		(start 225.210878 -3.762756)
		(end 225.210878 -3.737356)
		(width 0.4064)
		(layer "B.Cu")
		(net "GND")
	)
	(segment
		(start 119.799354 -152.078436)
		(end 119.799354 -151.265382)
		(width 0.4064)
		(layer "B.Cu")
		(net "GND")
	)
	(segment
		(start 118.099332 0.40005)
		(end 118.099332 -1.021842)
		(width 0.4064)
		(layer "B.Cu")
		(net "GND")
	)
	(segment
		(start 131.699508 -128.276096)
		(end 131.699508 -129.568956)
		(width 0.4064)
		(layer "B.Cu")
		(net "GND")
	)
	(segment
		(start 60.299346 -3.851656)
		(end 60.299346 -5.621782)
		(width 0.4064)
		(layer "B.Cu")
		(net "GND")
	)
	(segment
		(start 275.111464 -145.0086)
		(end 274.258532 -145.0086)
		(width 0.4572)
		(layer "B.Cu")
		(net "GND")
	)
	(segment
		(start 290.74999 -21.504656)
		(end 290.74999 -20.224242)
		(width 0.4064)
		(layer "B.Cu")
		(net "GND")
	)
	(segment
		(start 310.054244 -23.032974)
		(end 310.054244 -23.7236)
		(width 0.4064)
		(layer "B.Cu")
		(net "GND")
	)
	(segment
		(start 290.73729 -129.568956)
		(end 290.71189 -129.568956)
		(width 0.4064)
		(layer "B.Cu")
		(net "GND")
	)
	(segment
		(start 212.549994 -24.53005)
		(end 212.54974 -24.529796)
		(width 0.4064)
		(layer "B.Cu")
		(net "GND")
	)
	(segment
		(start 364.321852 -42.887138)
		(end 365.114078 -42.887138)
		(width 0.254)
		(layer "B.Cu")
		(net "GND")
	)
	(segment
		(start 402.573998 -25.654)
		(end 401.992846 -26.235152)
		(width 0.254)
		(layer "B.Cu")
		(net "GND")
	)
	(segment
		(start 346.895674 -91.617292)
		(end 347.132148 -91.380818)
		(width 0.2032)
		(layer "B.Cu")
		(net "GND")
	)
	(segment
		(start 203.2 -140.61821)
		(end 203.199746 -140.617956)
		(width 0.4064)
		(layer "B.Cu")
		(net "GND")
	)
	(segment
		(start 272.027904 -145.0086)
		(end 270.956532 -145.0086)
		(width 0.4572)
		(layer "B.Cu")
		(net "GND")
	)
	(segment
		(start 41.510458 -13.338556)
		(end 41.599358 -13.427456)
		(width 0.4064)
		(layer "B.Cu")
		(net "GND")
	)
	(segment
		(start 387.368034 -62.070234)
		(end 388.22884 -62.070234)
		(width 0.254)
		(layer "B.Cu")
		(net "GND")
	)
	(segment
		(start 135.099552 -20.224242)
		(end 135.099552 -18.757646)
		(width 0.4064)
		(layer "B.Cu")
		(net "GND")
	)
	(segment
		(start 136.799574 -137.877296)
		(end 136.799574 -139.089892)
		(width 0.4064)
		(layer "B.Cu")
		(net "GND")
	)
	(segment
		(start 220.200474 -15.222982)
		(end 220.199966 -15.222982)
		(width 0.4064)
		(layer "B.Cu")
		(net "GND")
	)
	(segment
		(start 138.499342 -24.011128)
		(end 138.499342 -24.824182)
		(width 0.4064)
		(layer "B.Cu")
		(net "GND")
	)
	(segment
		(start 124.89942 -7.509002)
		(end 124.801376 -7.607046)
		(width 0.4064)
		(layer "B.Cu")
		(net "GND")
	)
	(segment
		(start 231.249728 -151.707596)
		(end 231.249728 -150.219156)
		(width 0.4064)
		(layer "B.Cu")
		(net "GND")
	)
	(segment
		(start 62.849506 -147.478496)
		(end 62.849506 -148.691092)
		(width 0.4064)
		(layer "B.Cu")
		(net "GND")
	)
	(segment
		(start 145.053812 -141.3764)
		(end 145.053812 -140.685774)
		(width 0.4064)
		(layer "B.Cu")
		(net "GND")
	)
	(segment
		(start 295.000426 -10.623042)
		(end 294.999918 -10.623042)
		(width 0.4064)
		(layer "B.Cu")
		(net "GND")
	)
	(segment
		(start 198.099934 -128.276096)
		(end 198.099934 -129.556256)
		(width 0.4064)
		(layer "B.Cu")
		(net "GND")
	)
	(segment
		(start 52.649374 -17.0688)
		(end 52.471574 -17.2466)
		(width 0.4064)
		(layer "B.Cu")
		(net "GND")
	)
	(segment
		(start 445.056006 -34.7345)
		(end 445.937132 -34.7345)
		(width 0.4064)
		(layer "B.Cu")
		(net "GND")
	)
	(segment
		(start 370.459 -63.246)
		(end 370.459 -64.008)
		(width 0.254)
		(layer "B.Cu")
		(net "GND")
	)
	(segment
		(start 32.160464 -141.280642)
		(end 32.160464 -140.592556)
		(width 0.4064)
		(layer "B.Cu")
		(net "GND")
	)
	(segment
		(start 309.449978 -20.224242)
		(end 309.449978 -18.757646)
		(width 0.4064)
		(layer "B.Cu")
		(net "GND")
	)
	(segment
		(start 49.24933 -13.363956)
		(end 49.24933 -14.877796)
		(width 0.4064)
		(layer "B.Cu")
		(net "GND")
	)
	(segment
		(start 474.56725 -44.11345)
		(end 474.56725 -43.6626)
		(width 0.508)
		(layer "B.Cu")
		(net "GND")
	)
	(segment
		(start 376.428 -100.354892)
		(end 376.428 -99.748086)
		(width 0.254)
		(layer "B.Cu")
		(net "GND")
	)
	(segment
		(start 295.849802 -5.621782)
		(end 295.849802 -7.607046)
		(width 0.4064)
		(layer "B.Cu")
		(net "GND")
	)
	(segment
		(start 37.34943 -137.877296)
		(end 37.34943 -139.170156)
		(width 0.4064)
		(layer "B.Cu")
		(net "GND")
	)
	(segment
		(start 303.499774 -26.224484)
		(end 303.041304 -26.682954)
		(width 0.4064)
		(layer "B.Cu")
		(net "GND")
	)
	(segment
		(start 490.146594 -39.562786)
		(end 490.614208 -40.0304)
		(width 0.254)
		(layer "B.Cu")
		(net "GND")
	)
	(segment
		(start 32.15132 -7.607046)
		(end 32.249364 -7.509002)
		(width 0.4064)
		(layer "B.Cu")
		(net "GND")
	)
	(segment
		(start 71.349362 -4.8514)
		(end 71.349362 -5.621782)
		(width 0.254)
		(layer "B.Cu")
		(net "GND")
	)
	(segment
		(start 303.500282 -5.621782)
		(end 303.499774 -5.621782)
		(width 0.4064)
		(layer "B.Cu")
		(net "GND")
	)
	(segment
		(start 492.4044 -114.0206)
		(end 492.4044 -115.637818)
		(width 0.254)
		(layer "B.Cu")
		(net "GND")
	)
	(segment
		(start 394.171932 -26.032714)
		(end 393.722352 -26.032714)
		(width 0.254)
		(layer "B.Cu")
		(net "GND")
	)
	(segment
		(start 50.099468 -148.771356)
		(end 50.099468 -147.478496)
		(width 0.4064)
		(layer "B.Cu")
		(net "GND")
	)
	(segment
		(start 78.14945 -1.021842)
		(end 78.14945 0.468122)
		(width 0.4064)
		(layer "B.Cu")
		(net "GND")
	)
	(segment
		(start 222.75038 -147.478496)
		(end 222.749872 -147.478496)
		(width 0.4064)
		(layer "B.Cu")
		(net "GND")
	)
	(segment
		(start 53.499512 0.40005)
		(end 53.499512 -1.021842)
		(width 0.4064)
		(layer "B.Cu")
		(net "GND")
	)
	(segment
		(start 254.789432 -8.1534)
		(end 255.4224 -8.1534)
		(width 0.4572)
		(layer "B.Cu")
		(net "GND")
	)
	(segment
		(start 236.349794 -132.1054)
		(end 236.095794 -131.8514)
		(width 0.254)
		(layer "B.Cu")
		(net "GND")
	)
	(segment
		(start 217.3986 -13.437362)
		(end 217.472006 -13.363956)
		(width 0.4064)
		(layer "B.Cu")
		(net "GND")
	)
	(segment
		(start 224.449894 -18.744946)
		(end 224.449894 -20.224242)
		(width 0.4064)
		(layer "B.Cu")
		(net "GND")
	)
	(segment
		(start 147.849336 -5.621782)
		(end 147.849336 -6.637274)
		(width 0.4064)
		(layer "B.Cu")
		(net "GND")
	)
	(segment
		(start 304.35042 -20.224242)
		(end 304.349912 -20.224242)
		(width 0.4064)
		(layer "B.Cu")
		(net "GND")
	)
	(segment
		(start 297.549824 -22.965156)
		(end 297.549824 -24.824182)
		(width 0.4064)
		(layer "B.Cu")
		(net "GND")
	)
	(segment
		(start 221.899734 -17.208246)
		(end 221.899988 -17.207992)
		(width 0.4064)
		(layer "B.Cu")
		(net "GND")
	)
	(segment
		(start 141.899386 -17.208246)
		(end 141.899386 -15.222982)
		(width 0.4064)
		(layer "B.Cu")
		(net "GND")
	)
	(segment
		(start 292.450012 -129.488692)
		(end 292.392608 -129.546096)
		(width 0.4064)
		(layer "B.Cu")
		(net "GND")
	)
	(segment
		(start 36.499546 -141.664182)
		(end 36.03752 -141.202156)
		(width 0.4064)
		(layer "B.Cu")
		(net "GND")
	)
	(segment
		(start 313.700414 -1.021842)
		(end 313.699906 -1.021842)
		(width 0.4064)
		(layer "B.Cu")
		(net "GND")
	)
	(segment
		(start 304.349912 -137.877296)
		(end 304.35042 -137.877296)
		(width 0.4064)
		(layer "B.Cu")
		(net "GND")
	)
	(segment
		(start 278.849836 -15.222982)
		(end 278.849836 -17.193006)
		(width 0.4064)
		(layer "B.Cu")
		(net "GND")
	)
	(segment
		(start 487.268266 -20.00758)
		(end 487.268266 -21.536152)
		(width 0.508)
		(layer "B.Cu")
		(net "GND")
	)
	(segment
		(start 350.284542 -154.729942)
		(end 349.494094 -154.729942)
		(width 0.254)
		(layer "B.Cu")
		(net "GND")
	)
	(segment
		(start 152.099518 -10.623042)
		(end 152.099518 -9.156446)
		(width 0.4064)
		(layer "B.Cu")
		(net "GND")
	)
	(segment
		(start 45.84954 -5.621782)
		(end 45.84954 -6.63702)
		(width 0.4064)
		(layer "B.Cu")
		(net "GND")
	)
	(segment
		(start 300.100492 -10.623042)
		(end 300.099984 -10.623042)
		(width 0.4064)
		(layer "B.Cu")
		(net "GND")
	)
	(segment
		(start 73.899522 -4.808982)
		(end 73.899522 -5.621782)
		(width 0.4064)
		(layer "B.Cu")
		(net "GND")
	)
	(segment
		(start 104.984296 -156.910024)
		(end 104.984296 -158.383986)
		(width 0.4064)
		(layer "B.Cu")
		(net "GND")
	)
	(segment
		(start 218.44254 -9.143746)
		(end 218.499944 -9.20115)
		(width 0.4064)
		(layer "B.Cu")
		(net "GND")
	)
	(segment
		(start 223.600518 -24.824182)
		(end 223.60001 -24.824182)
		(width 0.4064)
		(layer "B.Cu")
		(net "GND")
	)
	(segment
		(start 62.849506 -137.877296)
		(end 62.849506 -139.089892)
		(width 0.4064)
		(layer "B.Cu")
		(net "GND")
	)
	(segment
		(start 261.2644 -13.0556)
		(end 261.2644 -11.6586)
		(width 0.508)
		(layer "B.Cu")
		(net "GND")
	)
	(segment
		(start 217.3986 -4.572254)
		(end 217.3986 -4.5212)
		(width 0.254)
		(layer "B.Cu")
		(net "GND")
	)
	(segment
		(start 152.949402 -23.520146)
		(end 152.949402 -24.824182)
		(width 0.4064)
		(layer "B.Cu")
		(net "GND")
	)
	(segment
		(start 145.29943 -4.842764)
		(end 145.29943 -5.621782)
		(width 0.254)
		(layer "B.Cu")
		(net "GND")
	)
	(segment
		(start 215.100408 -10.623042)
		(end 215.0999 -10.623042)
		(width 0.4064)
		(layer "B.Cu")
		(net "GND")
	)
	(segment
		(start 294.184578 -152.044146)
		(end 294.184578 -151.299926)
		(width 0.4064)
		(layer "B.Cu")
		(net "GND")
	)
	(segment
		(start 308.600348 -15.222982)
		(end 308.59984 -15.222982)
		(width 0.254)
		(layer "B.Cu")
		(net "GND")
	)
	(segment
		(start 136.74217 -11.893296)
		(end 136.799574 -11.835892)
		(width 0.4064)
		(layer "B.Cu")
		(net "GND")
	)
	(segment
		(start 290.74999 -11.903456)
		(end 290.74999 -10.623042)
		(width 0.4064)
		(layer "B.Cu")
		(net "GND")
	)
	(segment
		(start 33.099502 -20.224242)
		(end 33.099502 -21.504656)
		(width 0.4064)
		(layer "B.Cu")
		(net "GND")
	)
	(segment
		(start 117.00383 -14.198346)
		(end 117.00383 -14.1224)
		(width 0.254)
		(layer "B.Cu")
		(net "GND")
	)
	(segment
		(start 387.7818 -2.385568)
		(end 388.0358 -2.131568)
		(width 0.254)
		(layer "B.Cu")
		(net "GND")
	)
	(segment
		(start 49.24933 -5.276596)
		(end 49.24933 -3.762756)
		(width 0.4064)
		(layer "B.Cu")
		(net "GND")
	)
	(segment
		(start 409.955746 -7.810754)
		(end 409.955746 -7.1882)
		(width 0.254)
		(layer "B.Cu")
		(net "GND")
	)
	(segment
		(start 126.353824 -4.5212)
		(end 126.353824 -4.597146)
		(width 0.254)
		(layer "B.Cu")
		(net "GND")
	)
	(segment
		(start 226.9998 -14.4526)
		(end 226.7458 -14.1986)
		(width 0.254)
		(layer "B.Cu")
		(net "GND")
	)
	(segment
		(start 216.799922 -128.276096)
		(end 216.799922 -129.556256)
		(width 0.4064)
		(layer "B.Cu")
		(net "GND")
	)
	(segment
		(start 117.00383 -141.452346)
		(end 117.00383 -140.660374)
		(width 0.254)
		(layer "B.Cu")
		(net "GND")
	)
	(segment
		(start 232.100374 -128.276096)
		(end 232.099866 -128.276096)
		(width 0.4064)
		(layer "B.Cu")
		(net "GND")
	)
	(segment
		(start 74.749406 -147.478496)
		(end 74.749406 -148.771356)
		(width 0.4064)
		(layer "B.Cu")
		(net "GND")
	)
	(segment
		(start 90.861896 -145.281142)
		(end 90.861896 -144.646396)
		(width 0.4064)
		(layer "B.Cu")
		(net "GND")
	)
	(segment
		(start 254.789432 -145.0086)
		(end 255.167892 -144.63014)
		(width 0.4572)
		(layer "B.Cu")
		(net "GND")
	)
	(segment
		(start 417.7538 -16.947134)
		(end 417.7538 -13.848334)
		(width 0.254)
		(layer "B.Cu")
		(net "GND")
	)
	(segment
		(start 141.899386 -5.621782)
		(end 141.899386 -7.607046)
		(width 0.4064)
		(layer "B.Cu")
		(net "GND")
	)
	(segment
		(start 312.849768 -24.011128)
		(end 312.849768 -24.824182)
		(width 0.4064)
		(layer "B.Cu")
		(net "GND")
	)
	(segment
		(start 227.792534 -129.546096)
		(end 227.792534 -129.564892)
		(width 0.4064)
		(layer "B.Cu")
		(net "GND")
	)
	(segment
		(start 231.249982 -7.606792)
		(end 231.249982 -5.621782)
		(width 0.4064)
		(layer "B.Cu")
		(net "GND")
	)
	(segment
		(start 283.04236 -2.292096)
		(end 283.099764 -2.234692)
		(width 0.4064)
		(layer "B.Cu")
		(net "GND")
	)
	(segment
		(start 278.849836 -4.487164)
		(end 279.019 -4.318)
		(width 0.4064)
		(layer "B.Cu")
		(net "GND")
	)
	(segment
		(start 406.7048 -53.848)
		(end 406.7048 -54.356)
		(width 0.254)
		(layer "B.Cu")
		(net "GND")
	)
	(segment
		(start 221.899988 -5.621782)
		(end 221.899988 -5.27685)
		(width 0.4064)
		(layer "B.Cu")
		(net "GND")
	)
	(segment
		(start 157.046168 -145.333212)
		(end 156.690568 -144.977612)
		(width 0.4064)
		(layer "B.Cu")
		(net "GND")
	)
	(segment
		(start 210.849972 -24.011382)
		(end 210.387946 -23.549356)
		(width 0.4064)
		(layer "B.Cu")
		(net "GND")
	)
	(segment
		(start 392.69035 -102.756716)
		(end 392.684 -102.763066)
		(width 0.3556)
		(layer "B.Cu")
		(net "GND")
	)
	(segment
		(start 475.2086 -44.7548)
		(end 474.56725 -44.11345)
		(width 0.508)
		(layer "B.Cu")
		(net "GND")
	)
	(segment
		(start 288.19983 -142.476982)
		(end 288.19983 -140.617956)
		(width 0.4064)
		(layer "B.Cu")
		(net "GND")
	)
	(segment
		(start 221.900496 -142.477236)
		(end 221.899988 -142.476982)
		(width 0.4064)
		(layer "B.Cu")
		(net "GND")
	)
	(segment
		(start 198.100442 -10.623042)
		(end 198.099934 -10.623042)
		(width 0.4064)
		(layer "B.Cu")
		(net "GND")
	)
	(segment
		(start 146.149568 -1.021842)
		(end 146.149568 -2.234692)
		(width 0.4064)
		(layer "B.Cu")
		(net "GND")
	)
	(segment
		(start 208.299812 -152.078182)
		(end 208.299812 -151.349964)
		(width 0.254)
		(layer "B.Cu")
		(net "GND")
	)
	(segment
		(start 42.90187 -104.390952)
		(end 42.503344 -104.390952)
		(width 0.254)
		(layer "B.Cu")
		(net "GND")
	)
	(segment
		(start 255.768856 -7.806944)
		(end 256.0828 -7.806944)
		(width 0.4572)
		(layer "B.Cu")
		(net "GND")
	)
	(segment
		(start 214.249762 -7.607046)
		(end 214.250016 -7.606792)
		(width 0.4064)
		(layer "B.Cu")
		(net "GND")
	)
	(segment
		(start 52.471574 -7.6454)
		(end 52.649374 -7.4676)
		(width 0.4064)
		(layer "B.Cu")
		(net "GND")
	)
	(segment
		(start 52.649374 -15.222982)
		(end 52.649374 -17.0688)
		(width 0.4064)
		(layer "B.Cu")
		(net "GND")
	)
	(segment
		(start 135.949436 -152.078436)
		(end 135.949436 -151.299164)
		(width 0.254)
		(layer "B.Cu")
		(net "GND")
	)
	(segment
		(start 82.459068 -149.8092)
		(end 81.582768 -149.8092)
		(width 0.4064)
		(layer "B.Cu")
		(net "GND")
	)
	(segment
		(start 118.099332 -20.224242)
		(end 118.099332 -21.437092)
		(width 0.4064)
		(layer "B.Cu")
		(net "GND")
	)
	(segment
		(start 131.699508 -137.877296)
		(end 131.699508 -139.170156)
		(width 0.4064)
		(layer "B.Cu")
		(net "GND")
	)
	(segment
		(start 221.899988 -142.476982)
		(end 221.899988 -142.13205)
		(width 0.4064)
		(layer "B.Cu")
		(net "GND")
	)
	(segment
		(start 51.79949 -139.157456)
		(end 51.78679 -139.170156)
		(width 0.4064)
		(layer "B.Cu")
		(net "GND")
	)
	(segment
		(start 226.7458 -4.5974)
		(end 226.7458 -4.4958)
		(width 0.254)
		(layer "B.Cu")
		(net "GND")
	)
	(segment
		(start 71.095362 -141.351)
		(end 71.095362 -140.694156)
		(width 0.4064)
		(layer "B.Cu")
		(net "GND")
	)
	(segment
		(start 304.349912 -1.021842)
		(end 304.349912 0.444754)
		(width 0.4064)
		(layer "B.Cu")
		(net "GND")
	)
	(segment
		(start 285.650432 -128.276096)
		(end 285.649924 -128.276096)
		(width 0.4064)
		(layer "B.Cu")
		(net "GND")
	)
	(segment
		(start 216.787222 -148.771356)
		(end 216.761822 -148.771356)
		(width 0.4064)
		(layer "B.Cu")
		(net "GND")
	)
	(segment
		(start 290.71189 -21.517356)
		(end 290.73729 -21.517356)
		(width 0.4064)
		(layer "B.Cu")
		(net "GND")
	)
	(segment
		(start 210.849972 -6.63702)
		(end 210.391248 -7.095744)
		(width 0.4064)
		(layer "B.Cu")
		(net "GND")
	)
	(segment
		(start 444.548006 -41.203626)
		(end 444.548006 -40.5257)
		(width 0.3556)
		(layer "B.Cu")
		(net "GND")
	)
	(segment
		(start 297.549824 -24.824182)
		(end 297.549824 -25.661112)
		(width 0.4064)
		(layer "B.Cu")
		(net "GND")
	)
	(segment
		(start 372.609618 -88.89111)
		(end 373.498618 -88.89111)
		(width 0.254)
		(layer "B.Cu")
		(net "GND")
	)
	(segment
		(start 208.30032 -152.078436)
		(end 208.299812 -152.078182)
		(width 0.254)
		(layer "B.Cu")
		(net "GND")
	)
	(segment
		(start 396.875 -75.1967)
		(end 396.875 -77.461872)
		(width 0.254)
		(layer "B.Cu")
		(net "GND")
	)
	(segment
		(start 144.436846 -129.568956)
		(end 144.411446 -129.568956)
		(width 0.4064)
		(layer "B.Cu")
		(net "GND")
	)
	(segment
		(start 310.30037 -15.222982)
		(end 310.299862 -15.222982)
		(width 0.254)
		(layer "B.Cu")
		(net "GND")
	)
	(segment
		(start 196.399912 -18.744946)
		(end 196.399912 -20.224242)
		(width 0.4064)
		(layer "B.Cu")
		(net "GND")
	)
	(segment
		(start 44.092114 -148.748496)
		(end 44.092114 -148.767292)
		(width 0.4064)
		(layer "B.Cu")
		(net "GND")
	)
	(segment
		(start 226.149916 -2.302256)
		(end 226.137216 -2.314956)
		(width 0.4064)
		(layer "B.Cu")
		(net "GND")
	)
	(segment
		(start 292.45052 -128.276096)
		(end 292.450012 -128.276096)
		(width 0.4064)
		(layer "B.Cu")
		(net "GND")
	)
	(segment
		(start 199.742552 -148.748496)
		(end 199.742552 -148.767292)
		(width 0.4064)
		(layer "B.Cu")
		(net "GND")
	)
	(segment
		(start 310.122062 -17.2466)
		(end 310.299862 -17.0688)
		(width 0.4064)
		(layer "B.Cu")
		(net "GND")
	)
	(segment
		(start 453.182228 -128.6764)
		(end 452.8058 -128.6764)
		(width 0.254)
		(layer "B.Cu")
		(net "GND")
	)
	(segment
		(start 226.149916 -128.276096)
		(end 226.149916 -129.556256)
		(width 0.4064)
		(layer "B.Cu")
		(net "GND")
	)
	(segment
		(start 6.511036 -121.436384)
		(end 6.246114 -121.701306)
		(width 0.254)
		(layer "B.Cu")
		(net "GND")
	)
	(segment
		(start 243.288566 -12.954)
		(end 243.219732 -12.885166)
		(width 0.381)
		(layer "B.Cu")
		(net "GND")
	)
	(segment
		(start 125.749558 -129.556256)
		(end 125.736858 -129.568956)
		(width 0.4064)
		(layer "B.Cu")
		(net "GND")
	)
	(segment
		(start 392.557 -26.622502)
		(end 393.43457 -25.744932)
		(width 0.254)
		(layer "B.Cu")
		(net "GND")
	)
	(segment
		(start 34.799524 -9.20115)
		(end 34.799524 -10.623042)
		(width 0.4064)
		(layer "B.Cu")
		(net "GND")
	)
	(segment
		(start 303.499774 -14.409928)
		(end 303.038002 -13.948156)
		(width 0.4064)
		(layer "B.Cu")
		(net "GND")
	)
	(segment
		(start 280.735024 -81.874614)
		(end 281.421586 -81.874614)
		(width 0.254)
		(layer "B.Cu")
		(net "GND")
	)
	(segment
		(start 240.599976 -132.875782)
		(end 240.600484 -132.876036)
		(width 0.4064)
		(layer "B.Cu")
		(net "GND")
	)
	(segment
		(start 225.299778 -5.621782)
		(end 225.299778 -3.851656)
		(width 0.4064)
		(layer "B.Cu")
		(net "GND")
	)
	(segment
		(start 388.12851 -43.574208)
		(end 388.12851 -42.745914)
		(width 0.254)
		(layer "B.Cu")
		(net "GND")
	)
	(segment
		(start 199.800464 -10.623042)
		(end 199.799956 -10.623042)
		(width 0.4064)
		(layer "B.Cu")
		(net "GND")
	)
	(segment
		(start 224.449894 -20.224242)
		(end 224.449894 -21.517356)
		(width 0.4064)
		(layer "B.Cu")
		(net "GND")
	)
	(segment
		(start 125.749558 -147.478496)
		(end 125.749558 -148.758656)
		(width 0.4064)
		(layer "B.Cu")
		(net "GND")
	)
	(segment
		(start 26.0096 -76.7334)
		(end 25.654 -77.089)
		(width 0.254)
		(layer "B.Cu")
		(net "GND")
	)
	(segment
		(start 274.258532 -140.208)
		(end 275.111464 -140.208)
		(width 0.4572)
		(layer "B.Cu")
		(net "GND")
	)
	(segment
		(start 216.799922 -9.156446)
		(end 216.799922 -10.623042)
		(width 0.4064)
		(layer "B.Cu")
		(net "GND")
	)
	(segment
		(start 96.721168 -6.332982)
		(end 96.721168 -7.064248)
		(width 0.4064)
		(layer "B.Cu")
		(net "GND")
	)
	(segment
		(start 113.849404 -132.876036)
		(end 113.849404 -132.875782)
		(width 0.508)
		(layer "B.Cu")
		(net "GND")
	)
	(segment
		(start 209.14995 -147.478496)
		(end 209.14995 -148.691092)
		(width 0.4064)
		(layer "B.Cu")
		(net "GND")
	)
	(segment
		(start 241.450368 -128.276096)
		(end 241.44986 -128.276096)
		(width 0.4064)
		(layer "B.Cu")
		(net "GND")
	)
	(segment
		(start 104.018588 5.27304)
		(end 104.018588 5.281676)
		(width 0.508)
		(layer "B.Cu")
		(net "GND")
	)
	(segment
		(start 199.799956 -20.224242)
		(end 199.799956 -18.80235)
		(width 0.4064)
		(layer "B.Cu")
		(net "GND")
	)
	(segment
		(start 207.449928 0.444754)
		(end 207.449928 -1.021842)
		(width 0.4064)
		(layer "B.Cu")
		(net "GND")
	)
	(segment
		(start 72.142096 -148.748496)
		(end 72.142096 -148.767292)
		(width 0.4064)
		(layer "B.Cu")
		(net "GND")
	)
	(segment
		(start 415.7726 -21.336)
		(end 416.179 -21.336)
		(width 0.254)
		(layer "B.Cu")
		(net "GND")
	)
	(segment
		(start 62.849506 -129.488692)
		(end 62.792102 -129.546096)
		(width 0.4064)
		(layer "B.Cu")
		(net "GND")
	)
	(segment
		(start 215.0999 -137.877296)
		(end 215.0999 -139.170156)
		(width 0.4064)
		(layer "B.Cu")
		(net "GND")
	)
	(segment
		(start 291.599874 -24.824182)
		(end 291.599874 -24.045164)
		(width 0.254)
		(layer "B.Cu")
		(net "GND")
	)
	(segment
		(start 222.749872 -129.568956)
		(end 222.749872 -128.276096)
		(width 0.4064)
		(layer "B.Cu")
		(net "GND")
	)
	(segment
		(start 196.515736 -63.656464)
		(end 196.1642 -64.008)
		(width 0.254)
		(layer "B.Cu")
		(net "GND")
	)
	(segment
		(start 214.250016 -142.13205)
		(end 214.249762 -142.131796)
		(width 0.4064)
		(layer "B.Cu")
		(net "GND")
	)
	(segment
		(start 221.04985 -137.877296)
		(end 221.04985 -139.170156)
		(width 0.4064)
		(layer "B.Cu")
		(net "GND")
	)
	(segment
		(start 237.199932 -20.224242)
		(end 237.199932 -21.437092)
		(width 0.4064)
		(layer "B.Cu")
		(net "GND")
	)
	(segment
		(start 67.949572 -5.32765)
		(end 67.949572 -5.621782)
		(width 0.4064)
		(layer "B.Cu")
		(net "GND")
	)
	(segment
		(start 498.030246 -40.52443)
		(end 498.792754 -39.761922)
		(width 0.254)
		(layer "B.Cu")
		(net "GND")
	)
	(segment
		(start 402.805646 -26.679652)
		(end 402.805646 -25.742646)
		(width 0.254)
		(layer "B.Cu")
		(net "GND")
	)
	(segment
		(start 207.449928 -21.504656)
		(end 207.437228 -21.517356)
		(width 0.4064)
		(layer "B.Cu")
		(net "GND")
	)
	(segment
		(start 51.78679 -21.517356)
		(end 51.76139 -21.517356)
		(width 0.4064)
		(layer "B.Cu")
		(net "GND")
	)
	(segment
		(start 409.985972 -12.602972)
		(end 410.483812 -13.100812)
		(width 0.254)
		(layer "B.Cu")
		(net "GND")
	)
	(segment
		(start 388.7089 -104.4702)
		(end 388.3279 -104.4702)
		(width 0.3556)
		(layer "B.Cu")
		(net "GND")
	)
	(segment
		(start 491.41253 -128.51384)
		(end 492.35106 -128.51384)
		(width 0.254)
		(layer "B.Cu")
		(net "GND")
	)
	(segment
		(start 325.4629 -124.1298)
		(end 325.4629 -123.8758)
		(width 0.254)
		(layer "B.Cu")
		(net "GND")
	)
	(segment
		(start 47.549308 -151.783796)
		(end 47.549308 -150.219156)
		(width 0.4064)
		(layer "B.Cu")
		(net "GND")
	)
	(segment
		(start 479.299016 -137.136632)
		(end 477.242632 -137.136632)
		(width 0.254)
		(layer "B.Cu")
		(net "GND")
	)
	(segment
		(start 398.298416 -77.724)
		(end 398.379696 -77.64272)
		(width 0.254)
		(layer "B.Cu")
		(net "GND")
	)
	(segment
		(start 124.89942 -5.621782)
		(end 124.89942 -7.509002)
		(width 0.4064)
		(layer "B.Cu")
		(net "GND")
	)
	(segment
		(start 237.142528 -11.912092)
		(end 237.142528 -11.893296)
		(width 0.4064)
		(layer "B.Cu")
		(net "GND")
	)
	(segment
		(start 434.2384 -11.7856)
		(end 434.2384 -11.6332)
		(width 0.254)
		(layer "B.Cu")
		(net "GND")
	)
	(segment
		(start 231.33304 -67.47764)
		(end 229.3747 -65.5193)
		(width 0.254)
		(layer "B.Cu")
		(net "GND")
	)
	(segment
		(start 300.949868 -25.937972)
		(end 301.749206 -26.73731)
		(width 0.4064)
		(layer "B.Cu")
		(net "GND")
	)
	(segment
		(start 223.599756 -14.979396)
		(end 223.599756 -13.363956)
		(width 0.4064)
		(layer "B.Cu")
		(net "GND")
	)
	(segment
		(start 64.549528 -132.876036)
		(end 64.549528 -132.062982)
		(width 0.4064)
		(layer "B.Cu")
		(net "GND")
	)
	(segment
		(start 233.800396 -20.224242)
		(end 233.799888 -20.224242)
		(width 0.4064)
		(layer "B.Cu")
		(net "GND")
	)
	(segment
		(start 261.777734 2.324608)
		(end 261.723378 2.270252)
		(width 0.508)
		(layer "B.Cu")
		(net "GND")
	)
	(segment
		(start 281.361896 -139.170156)
		(end 281.387296 -139.170156)
		(width 0.4064)
		(layer "B.Cu")
		(net "GND")
	)
	(segment
		(start 235.49991 -148.733256)
		(end 235.46181 -148.771356)
		(width 0.4064)
		(layer "B.Cu")
		(net "GND")
	)
	(segment
		(start 32.249364 -142.477236)
		(end 32.249364 -141.369542)
		(width 0.4064)
		(layer "B.Cu")
		(net "GND")
	)
	(segment
		(start 234.649772 -140.706856)
		(end 234.560872 -140.617956)
		(width 0.4064)
		(layer "B.Cu")
		(net "GND")
	)
	(segment
		(start 447.0146 -18.1102)
		(end 446.672716 -18.1102)
		(width 0.254)
		(layer "B.Cu")
		(net "GND")
	)
	(segment
		(start 407.136854 -53.848)
		(end 406.7048 -53.848)
		(width 0.254)
		(layer "B.Cu")
		(net "GND")
	)
	(segment
		(start 60.299346 -13.452856)
		(end 60.210446 -13.363956)
		(width 0.4064)
		(layer "B.Cu")
		(net "GND")
	)
	(segment
		(start 115.460526 -13.363956)
		(end 115.460526 -13.338556)
		(width 0.4064)
		(layer "B.Cu")
		(net "GND")
	)
	(segment
		(start 406.8064 3.9116)
		(end 406.8064 3.6322)
		(width 0.254)
		(layer "B.Cu")
		(net "GND")
	)
	(segment
		(start 232.950004 -17.207992)
		(end 232.950004 -15.222982)
		(width 0.4064)
		(layer "B.Cu")
		(net "GND")
	)
	(segment
		(start 66.24955 -7.606792)
		(end 66.249296 -7.607046)
		(width 0.4064)
		(layer "B.Cu")
		(net "GND")
	)
	(segment
		(start 383.7432 -155.702)
		(end 383.8829 -155.702)
		(width 0.4064)
		(layer "B.Cu")
		(net "GND")
	)
	(segment
		(start 208.0514 -3.833368)
		(end 208.122012 -3.762756)
		(width 0.4064)
		(layer "B.Cu")
		(net "GND")
	)
	(segment
		(start 94.8817 -150.7871)
		(end 95.555816 -150.7871)
		(width 0.4572)
		(layer "B.Cu")
		(net "GND")
	)
	(segment
		(start 33.949386 -14.443964)
		(end 33.703768 -14.198346)
		(width 0.254)
		(layer "B.Cu")
		(net "GND")
	)
	(segment
		(start 464.3628 -146.2024)
		(end 464.2612 -146.304)
		(width 0.4064)
		(layer "B.Cu")
		(net "GND")
	)
	(segment
		(start 134.249414 -3.851656)
		(end 134.160514 -3.762756)
		(width 0.4064)
		(layer "B.Cu")
		(net "GND")
	)
	(segment
		(start 402.166836 -22.225)
		(end 401.454874 -22.225)
		(width 0.254)
		(layer "B.Cu")
		(net "GND")
	)
	(segment
		(start 198.061834 -21.517356)
		(end 198.087234 -21.517356)
		(width 0.4064)
		(layer "B.Cu")
		(net "GND")
	)
	(segment
		(start 208.299812 -14.494764)
		(end 208.0514 -14.246352)
		(width 0.254)
		(layer "B.Cu")
		(net "GND")
	)
	(segment
		(start 199.799956 0.40005)
		(end 199.799956 -1.021842)
		(width 0.4064)
		(layer "B.Cu")
		(net "GND")
	)
	(segment
		(start 31.39948 -139.170156)
		(end 31.39948 -137.877296)
		(width 0.4064)
		(layer "B.Cu")
		(net "GND")
	)
	(segment
		(start 43.050968 -14.246352)
		(end 43.29938 -14.494764)
		(width 0.254)
		(layer "B.Cu")
		(net "GND")
	)
	(segment
		(start 278.849836 -130.124962)
		(end 278.725122 -130.249676)
		(width 0.4064)
		(layer "B.Cu")
		(net "GND")
	)
	(segment
		(start 277.9776 3.81)
		(end 275.844 3.81)
		(width 0.381)
		(layer "B.Cu")
		(net "GND")
	)
	(segment
		(start 129.149348 -15.222982)
		(end 129.149348 -14.409928)
		(width 0.4064)
		(layer "B.Cu")
		(net "GND")
	)
	(segment
		(start 2.159 -15.9512)
		(end 3.011932 -15.9512)
		(width 0.254)
		(layer "B.Cu")
		(net "GND")
	)
	(segment
		(start 389.02132 -130.58648)
		(end 389.02132 -129.74066)
		(width 0.254)
		(layer "B.Cu")
		(net "GND")
	)
	(segment
		(start 243.149882 -20.224242)
		(end 243.149882 -22.073362)
		(width 0.4064)
		(layer "B.Cu")
		(net "GND")
	)
	(segment
		(start 233.800396 -137.877296)
		(end 233.799888 -137.877296)
		(width 0.4064)
		(layer "B.Cu")
		(net "GND")
	)
	(segment
		(start 240.599976 -131.01701)
		(end 240.599976 -132.875782)
		(width 0.4064)
		(layer "B.Cu")
		(net "GND")
	)
	(segment
		(start 234.560872 -22.965156)
		(end 234.560872 -22.939756)
		(width 0.4064)
		(layer "B.Cu")
		(net "GND")
	)
	(segment
		(start 33.099502 -128.276096)
		(end 33.099502 -129.556256)
		(width 0.4064)
		(layer "B.Cu")
		(net "GND")
	)
	(segment
		(start 152.099518 -143.941546)
		(end 152.099518 -144.450562)
		(width 0.508)
		(layer "B.Cu")
		(net "GND")
	)
	(segment
		(start 499.12016 -54.405022)
		(end 498.32006 -53.604922)
		(width 0.508)
		(layer "B.Cu")
		(net "GND")
	)
	(segment
		(start 497.561108 -40.52443)
		(end 498.030246 -40.52443)
		(width 0.254)
		(layer "B.Cu")
		(net "GND")
	)
	(segment
		(start 395.28877 -39.82593)
		(end 395.28877 -40.55872)
		(width 0.254)
		(layer "B.Cu")
		(net "GND")
	)
	(segment
		(start 91.684348 -135.3312)
		(end 91.379548 -135.636)
		(width 0.381)
		(layer "B.Cu")
		(net "GND")
	)
	(segment
		(start 50.949352 -15.222982)
		(end 50.949352 -17.110202)
		(width 0.4064)
		(layer "B.Cu")
		(net "GND")
	)
	(segment
		(start 85.761068 -135.4074)
		(end 84.910168 -135.4074)
		(width 0.4064)
		(layer "B.Cu")
		(net "GND")
	)
	(segment
		(start 204.049884 -147.478496)
		(end 204.049884 -148.771356)
		(width 0.4064)
		(layer "B.Cu")
		(net "GND")
	)
	(segment
		(start 243.149882 -137.877296)
		(end 243.149882 -137.877042)
		(width 0.4064)
		(layer "B.Cu")
		(net "GND")
	)
	(segment
		(start 298.399962 -9.143746)
		(end 298.399962 -10.623042)
		(width 0.4064)
		(layer "B.Cu")
		(net "GND")
	)
	(segment
		(start 307.749956 -147.478496)
		(end 307.749956 -148.771356)
		(width 0.4064)
		(layer "B.Cu")
		(net "GND")
	)
	(segment
		(start 300.70425 -140.685774)
		(end 300.70425 -141.3764)
		(width 0.4064)
		(layer "B.Cu")
		(net "GND")
	)
	(segment
		(start 117.00383 -23.799546)
		(end 117.00383 -23.7236)
		(width 0.254)
		(layer "B.Cu")
		(net "GND")
	)
	(segment
		(start 255.815338 -140.490194)
		(end 255.815338 -139.829794)
		(width 0.4064)
		(layer "B.Cu")
		(net "GND")
	)
	(segment
		(start 64.549528 -6.63702)
		(end 64.090804 -7.095744)
		(width 0.4064)
		(layer "B.Cu")
		(net "GND")
	)
	(segment
		(start 58.599324 -151.834596)
		(end 58.599324 -150.219156)
		(width 0.4064)
		(layer "B.Cu")
		(net "GND")
	)
	(segment
		(start 223.60001 -5.621782)
		(end 223.60001 -5.37845)
		(width 0.4064)
		(layer "B.Cu")
		(net "GND")
	)
	(segment
		(start 374.21312 -98.372168)
		(end 373.952262 -98.633026)
		(width 0.254)
		(layer "B.Cu")
		(net "GND")
	)
	(segment
		(start 204.899768 -15.222982)
		(end 204.899768 -13.363956)
		(width 0.4064)
		(layer "B.Cu")
		(net "GND")
	)
	(segment
		(start 310.122062 -7.6454)
		(end 310.299862 -7.4676)
		(width 0.4064)
		(layer "B.Cu")
		(net "GND")
	)
	(segment
		(start 371.945154 -75.018646)
		(end 371.945154 -75.094846)
		(width 0.254)
		(layer "B.Cu")
		(net "GND")
	)
	(segment
		(start 152.146 -17.78)
		(end 152.099518 -17.733518)
		(width 0.4064)
		(layer "B.Cu")
		(net "GND")
	)
	(segment
		(start 78.14945 -130.124962)
		(end 78.274164 -130.249676)
		(width 0.4064)
		(layer "B.Cu")
		(net "GND")
	)
	(segment
		(start 294.150288 -5.621782)
		(end 294.14978 -5.621782)
		(width 0.4064)
		(layer "B.Cu")
		(net "GND")
	)
	(segment
		(start 490.951266 -55.330344)
		(end 490.951266 -56.147462)
		(width 0.4064)
		(layer "B.Cu")
		(net "GND")
	)
	(segment
		(start 77.299566 -26.635202)
		(end 77.299566 -24.824182)
		(width 0.4064)
		(layer "B.Cu")
		(net "GND")
	)
	(segment
		(start 317.09995 -1.021842)
		(end 317.09995 -2.325878)
		(width 0.4064)
		(layer "B.Cu")
		(net "GND")
	)
	(segment
		(start 202.35037 -147.478496)
		(end 202.349862 -147.478496)
		(width 0.4064)
		(layer "B.Cu")
		(net "GND")
	)
	(segment
		(start 89.789 -3.3528)
		(end 90.071956 -3.635756)
		(width 0.4064)
		(layer "B.Cu")
		(net "GND")
	)
	(segment
		(start 303.499774 -132.062728)
		(end 303.038002 -131.600956)
		(width 0.4064)
		(layer "B.Cu")
		(net "GND")
	)
	(segment
		(start 197.249796 -23.716742)
		(end 197.160896 -23.627842)
		(width 0.4064)
		(layer "B.Cu")
		(net "GND")
	)
	(segment
		(start 118.041928 -18.744946)
		(end 118.099332 -18.80235)
		(width 0.4064)
		(layer "B.Cu")
		(net "GND")
	)
	(segment
		(start 232.099866 -18.757646)
		(end 232.099866 -20.224242)
		(width 0.4064)
		(layer "B.Cu")
		(net "GND")
	)
	(segment
		(start 67.949572 -24.824182)
		(end 67.949572 -25.638252)
		(width 0.4064)
		(layer "B.Cu")
		(net "GND")
	)
	(segment
		(start 71.349362 -7.4676)
		(end 71.171562 -7.6454)
		(width 0.4064)
		(layer "B.Cu")
		(net "GND")
	)
	(segment
		(start 282.004262 -13.431774)
		(end 282.07208 -13.363956)
		(width 0.254)
		(layer "B.Cu")
		(net "GND")
	)
	(segment
		(start 316.249812 -142.476982)
		(end 316.249812 -140.617956)
		(width 0.4064)
		(layer "B.Cu")
		(net "GND")
	)
	(segment
		(start 244.3353 -140.208)
		(end 243.256054 -140.208)
		(width 0.508)
		(layer "B.Cu")
		(net "GND")
	)
	(segment
		(start 458.422756 -21.494242)
		(end 458.422756 -21.985478)
		(width 0.254)
		(layer "B.Cu")
		(net "GND")
	)
	(segment
		(start 289.049968 -139.170156)
		(end 289.049968 -137.877296)
		(width 0.4064)
		(layer "B.Cu")
		(net "GND")
	)
	(segment
		(start 472.487752 -136.42086)
		(end 472.233498 -136.166606)
		(width 0.254)
		(layer "B.Cu")
		(net "GND")
	)
	(segment
		(start 77.299566 -142.476982)
		(end 77.299566 -142.477236)
		(width 0.508)
		(layer "B.Cu")
		(net "GND")
	)
	(segment
		(start 494.069624 -40.699944)
		(end 494.281968 -40.4876)
		(width 0.254)
		(layer "B.Cu")
		(net "GND")
	)
	(segment
		(start 459.869032 -131.0386)
		(end 461.057244 -131.0386)
		(width 0.254)
		(layer "B.Cu")
		(net "GND")
	)
	(segment
		(start 152.099518 -155.080462)
		(end 152.099518 -155.612846)
		(width 0.4064)
		(layer "B.Cu")
		(net "GND")
	)
	(segment
		(start 278.727408 1.82372)
		(end 278.727408 3.060192)
		(width 0.381)
		(layer "B.Cu")
		(net "GND")
	)
	(segment
		(start 221.900496 -132.876036)
		(end 221.899988 -132.875782)
		(width 0.4064)
		(layer "B.Cu")
		(net "GND")
	)
	(segment
		(start 284.799786 -24.011382)
		(end 284.33776 -23.549356)
		(width 0.4064)
		(layer "B.Cu")
		(net "GND")
	)
	(segment
		(start 238.899954 -151.265382)
		(end 238.437928 -150.803356)
		(width 0.4064)
		(layer "B.Cu")
		(net "GND")
	)
	(segment
		(start 120.649492 -1.021842)
		(end 120.649492 0.444754)
		(width 0.4064)
		(layer "B.Cu")
		(net "GND")
	)
	(segment
		(start 495.615976 -49.66462)
		(end 496.1128 -49.66462)
		(width 0.254)
		(layer "B.Cu")
		(net "GND")
	)
	(segment
		(start 39.899336 -3.762756)
		(end 39.899336 -5.621782)
		(width 0.4064)
		(layer "B.Cu")
		(net "GND")
	)
	(segment
		(start 105.9561 -8.1534)
		(end 107.027472 -8.1534)
		(width 0.4064)
		(layer "B.Cu")
		(net "GND")
	)
	(segment
		(start 376.433842 -70.695566)
		(end 376.744738 -70.38467)
		(width 0.254)
		(layer "B.Cu")
		(net "GND")
	)
	(segment
		(start 480.845876 2.576068)
		(end 480.633532 2.576068)
		(width 0.254)
		(layer "B.Cu")
		(net "GND")
	)
	(segment
		(start 208.299812 -24.824182)
		(end 208.299812 -24.095964)
		(width 0.254)
		(layer "B.Cu")
		(net "GND")
	)
	(segment
		(start 432.438302 -21.618194)
		(end 432.0032 -22.053296)
		(width 0.254)
		(layer "B.Cu")
		(net "GND")
	)
	(segment
		(start 37.34943 -147.478496)
		(end 37.34943 -148.771356)
		(width 0.4064)
		(layer "B.Cu")
		(net "GND")
	)
	(segment
		(start 95.070168 -18.8214)
		(end 95.070168 -19.6088)
		(width 0.4064)
		(layer "B.Cu")
		(net "GND")
	)
	(segment
		(start 236.095794 -141.4526)
		(end 236.095794 -141.351)
		(width 0.254)
		(layer "B.Cu")
		(net "GND")
	)
	(segment
		(start 387.8326 -65.3288)
		(end 388.6708 -65.3288)
		(width 0.254)
		(layer "B.Cu")
		(net "GND")
	)
	(segment
		(start 432.498246 -18.095722)
		(end 432.498246 -17.585182)
		(width 0.381)
		(layer "B.Cu")
		(net "GND")
	)
	(segment
		(start 124.81052 -22.939756)
		(end 124.81052 -22.965156)
		(width 0.4064)
		(layer "B.Cu")
		(net "GND")
	)
	(segment
		(start 60.299346 -24.824182)
		(end 60.299346 -25.676098)
		(width 0.4064)
		(layer "B.Cu")
		(net "GND")
	)
	(segment
		(start 307.749956 -137.877296)
		(end 307.749956 -139.170156)
		(width 0.4064)
		(layer "B.Cu")
		(net "GND")
	)
	(segment
		(start 221.899734 -7.607046)
		(end 221.899988 -7.606792)
		(width 0.4064)
		(layer "B.Cu")
		(net "GND")
	)
	(segment
		(start 477.6978 -13.7414)
		(end 477.3803 -14.0589)
		(width 0.254)
		(layer "B.Cu")
		(net "GND")
	)
	(segment
		(start 199.742552 -21.494496)
		(end 199.799956 -21.437092)
		(width 0.4064)
		(layer "B.Cu")
		(net "GND")
	)
	(segment
		(start 71.349362 -141.7066)
		(end 71.095362 -141.4526)
		(width 0.254)
		(layer "B.Cu")
		(net "GND")
	)
	(segment
		(start 275.844 3.81)
		(end 274.8534 4.8006)
		(width 0.381)
		(layer "B.Cu")
		(net "GND")
	)
	(segment
		(start 216.799922 -148.758656)
		(end 216.787222 -148.771356)
		(width 0.4064)
		(layer "B.Cu")
		(net "GND")
	)
	(segment
		(start 289.049968 -10.623042)
		(end 289.049968 -11.916156)
		(width 0.4064)
		(layer "B.Cu")
		(net "GND")
	)
	(segment
		(start 197.250304 -152.078436)
		(end 197.249796 -152.078182)
		(width 0.4064)
		(layer "B.Cu")
		(net "GND")
	)
	(segment
		(start 232.950512 -24.824182)
		(end 232.950004 -24.824182)
		(width 0.4064)
		(layer "B.Cu")
		(net "GND")
	)
	(segment
		(start 56.899556 -15.222982)
		(end 56.899556 -17.207992)
		(width 0.4064)
		(layer "B.Cu")
		(net "GND")
	)
	(segment
		(start 209.14995 -20.224242)
		(end 209.14995 -18.80235)
		(width 0.4064)
		(layer "B.Cu")
		(net "GND")
	)
	(segment
		(start 211.699856 -1.021842)
		(end 211.699856 -2.314956)
		(width 0.4064)
		(layer "B.Cu")
		(net "GND")
	)
	(segment
		(start 43.865038 -103.427784)
		(end 42.90187 -104.390952)
		(width 0.254)
		(layer "B.Cu")
		(net "GND")
	)
	(segment
		(start 306.049934 -137.877296)
		(end 306.049934 -139.170156)
		(width 0.4064)
		(layer "B.Cu")
		(net "GND")
	)
	(segment
		(start 310.054244 -131.7752)
		(end 310.054244 -131.851146)
		(width 0.254)
		(layer "B.Cu")
		(net "GND")
	)
	(segment
		(start 117.00383 -4.597146)
		(end 117.249448 -4.842764)
		(width 0.254)
		(layer "B.Cu")
		(net "GND")
	)
	(segment
		(start 143.599408 -132.876036)
		(end 143.599408 -131.22656)
		(width 0.4064)
		(layer "B.Cu")
		(net "GND")
	)
	(segment
		(start 38.199568 -3.76301)
		(end 38.199314 -3.762756)
		(width 0.4064)
		(layer "B.Cu")
		(net "GND")
	)
	(segment
		(start 407.7208 -29.4132)
		(end 408.127454 -29.819854)
		(width 0.254)
		(layer "B.Cu")
		(net "GND")
	)
	(segment
		(start 369.527836 -97.476564)
		(end 370.0145 -96.9899)
		(width 0.254)
		(layer "B.Cu")
		(net "GND")
	)
	(segment
		(start 50.099468 -21.517356)
		(end 50.099468 -20.224242)
		(width 0.4064)
		(layer "B.Cu")
		(net "GND")
	)
	(segment
		(start 112.397032 -17.7546)
		(end 112.701832 -18.0594)
		(width 0.381)
		(layer "B.Cu")
		(net "GND")
	)
	(segment
		(start 43.29938 -132.876036)
		(end 43.29938 -132.147564)
		(width 0.254)
		(layer "B.Cu")
		(net "GND")
	)
	(segment
		(start 317.146432 -7.132828)
		(end 317.09995 -7.086346)
		(width 0.4064)
		(layer "B.Cu")
		(net "GND")
	)
	(segment
		(start 366.331754 -45.927772)
		(end 365.844328 -46.415198)
		(width 0.254)
		(layer "B.Cu")
		(net "GND")
	)
	(segment
		(start 145.29943 -141.697964)
		(end 145.053812 -141.452346)
		(width 0.254)
		(layer "B.Cu")
		(net "GND")
	)
	(segment
		(start 61.136784 -2.314956)
		(end 61.111384 -2.314956)
		(width 0.4064)
		(layer "B.Cu")
		(net "GND")
	)
	(segment
		(start 458.353414 -127.9144)
		(end 458.353414 -126.674118)
		(width 0.254)
		(layer "B.Cu")
		(net "GND")
	)
	(segment
		(start 61.149484 -139.157456)
		(end 61.136784 -139.170156)
		(width 0.4064)
		(layer "B.Cu")
		(net "GND")
	)
	(segment
		(start 381.635 -46.99)
		(end 381.635 -46.228)
		(width 0.254)
		(layer "B.Cu")
		(net "GND")
	)
	(segment
		(start 64.087502 -13.948156)
		(end 64.549528 -14.410182)
		(width 0.4064)
		(layer "B.Cu")
		(net "GND")
	)
	(segment
		(start 145.12163 -131.016756)
		(end 145.053812 -131.084574)
		(width 0.4064)
		(layer "B.Cu")
		(net "GND")
	)
	(segment
		(start 325.5264 -120.423178)
		(end 325.5264 -120.86844)
		(width 0.254)
		(layer "B.Cu")
		(net "GND")
	)
	(segment
		(start 483.310184 -19.391884)
		(end 482.128322 -18.210022)
		(width 0.254)
		(layer "B.Cu")
		(net "GND")
	)
	(segment
		(start 237.199932 -11.835892)
		(end 237.199932 -10.623042)
		(width 0.4064)
		(layer "B.Cu")
		(net "GND")
	)
	(segment
		(start 449.326 -149.3901)
		(end 449.3387 -149.3774)
		(width 0.254)
		(layer "B.Cu")
		(net "GND")
	)
	(segment
		(start 47.549562 -15.222982)
		(end 47.549562 -14.92885)
		(width 0.4064)
		(layer "B.Cu")
		(net "GND")
	)
	(segment
		(start 223.60001 -142.23365)
		(end 223.599756 -142.233396)
		(width 0.4064)
		(layer "B.Cu")
		(net "GND")
	)
	(segment
		(start 56.899556 -152.078436)
		(end 56.899556 -151.73325)
		(width 0.4064)
		(layer "B.Cu")
		(net "GND")
	)
	(segment
		(start 61.149484 -11.903456)
		(end 61.136784 -11.916156)
		(width 0.4064)
		(layer "B.Cu")
		(net "GND")
	)
	(segment
		(start 305.199796 -17.208246)
		(end 305.199796 -15.222982)
		(width 0.4064)
		(layer "B.Cu")
		(net "GND")
	)
	(segment
		(start 305.200304 -132.876036)
		(end 305.199796 -132.875782)
		(width 0.4064)
		(layer "B.Cu")
		(net "GND")
	)
	(segment
		(start 368.388646 -51.26228)
		(end 369.8875 -51.26228)
		(width 0.254)
		(layer "B.Cu")
		(net "GND")
	)
	(segment
		(start 391.3505 -10.445496)
		(end 391.3505 -11.049)
		(width 0.254)
		(layer "B.Cu")
		(net "GND")
	)
	(segment
		(start 285.649924 -18.757646)
		(end 285.649924 -20.224242)
		(width 0.4064)
		(layer "B.Cu")
		(net "GND")
	)
	(segment
		(start 301.800006 -1.021842)
		(end 301.800006 -2.234692)
		(width 0.4064)
		(layer "B.Cu")
		(net "GND")
	)
	(segment
		(start 434.06695 -13.60805)
		(end 433.705 -13.97)
		(width 0.254)
		(layer "B.Cu")
		(net "GND")
	)
	(segment
		(start 145.12163 -140.617956)
		(end 143.809212 -140.617956)
		(width 0.4064)
		(layer "B.Cu")
		(net "GND")
	)
	(segment
		(start 290.74999 -20.224242)
		(end 290.74999 -18.757646)
		(width 0.4064)
		(layer "B.Cu")
		(net "GND")
	)
	(segment
		(start 387.153404 -42.602404)
		(end 387.985 -42.602404)
		(width 0.254)
		(layer "B.Cu")
		(net "GND")
	)
	(segment
		(start 377.144788 -69.894958)
		(end 377.145042 -69.894958)
		(width 0.254)
		(layer "B.Cu")
		(net "GND")
	)
	(segment
		(start 306.899818 -5.621782)
		(end 306.899818 -3.762756)
		(width 0.4064)
		(layer "B.Cu")
		(net "GND")
	)
	(segment
		(start 408.456892 -21.39442)
		(end 408.10942 -21.39442)
		(width 0.254)
		(layer "B.Cu")
		(net "GND")
	)
	(segment
		(start 392.030458 -11.728958)
		(end 392.030458 -12.582144)
		(width 0.254)
		(layer "B.Cu")
		(net "GND")
	)
	(segment
		(start 492.01451 -52.53609)
		(end 492.0234 -52.5272)
		(width 0.254)
		(layer "B.Cu")
		(net "GND")
	)
	(segment
		(start 450.6595 -19.177)
		(end 450.6595 -19.043396)
		(width 0.254)
		(layer "B.Cu")
		(net "GND")
	)
	(segment
		(start 198.7042 -14.198346)
		(end 198.949818 -14.443964)
		(width 0.254)
		(layer "B.Cu")
		(net "GND")
	)
	(segment
		(start 44.149518 -18.80235)
		(end 44.149518 -20.224242)
		(width 0.4064)
		(layer "B.Cu")
		(net "GND")
	)
	(segment
		(start 300.949868 -132.875782)
		(end 300.950376 -132.876036)
		(width 0.254)
		(layer "B.Cu")
		(net "GND")
	)
	(segment
		(start 278.90597 -18.0594)
		(end 277.702264 -18.0594)
		(width 0.381)
		(layer "B.Cu")
		(net "GND")
	)
	(segment
		(start 149.549358 -152.078436)
		(end 149.549358 -150.219156)
		(width 0.4064)
		(layer "B.Cu")
		(net "GND")
	)
	(segment
		(start 387.21538 -128.6256)
		(end 386.80898 -128.2192)
		(width 0.4064)
		(layer "B.Cu")
		(net "GND")
	)
	(segment
		(start 369.945158 -77.240638)
		(end 369.945158 -77.096112)
		(width 0.254)
		(layer "B.Cu")
		(net "GND")
	)
	(segment
		(start 85.761068 -140.208)
		(end 84.910168 -140.208)
		(width 0.4064)
		(layer "B.Cu")
		(net "GND")
	)
	(segment
		(start 145.053812 -4.597146)
		(end 145.29943 -4.842764)
		(width 0.254)
		(layer "B.Cu")
		(net "GND")
	)
	(segment
		(start 117.249448 -14.443964)
		(end 117.00383 -14.198346)
		(width 0.254)
		(layer "B.Cu")
		(net "GND")
	)
	(segment
		(start 260.0198 -155.2448)
		(end 260.0198 -157.0228)
		(width 0.4064)
		(layer "B.Cu")
		(net "GND")
	)
	(segment
		(start 223.60001 -132.63245)
		(end 223.599756 -132.632196)
		(width 0.4064)
		(layer "B.Cu")
		(net "GND")
	)
	(segment
		(start 44.149518 -20.224242)
		(end 44.149518 -21.437092)
		(width 0.4064)
		(layer "B.Cu")
		(net "GND")
	)
	(segment
		(start 64.549528 -132.062982)
		(end 64.087502 -131.600956)
		(width 0.4064)
		(layer "B.Cu")
		(net "GND")
	)
	(segment
		(start 163.8808 0.870458)
		(end 164.418518 0.33274)
		(width 0.254)
		(layer "B.Cu")
		(net "GND")
	)
	(segment
		(start 387.917182 -10.418572)
		(end 387.917182 -9.135364)
		(width 0.254)
		(layer "B.Cu")
		(net "GND")
	)
	(segment
		(start 2.27076 -5.95376)
		(end 2.6924 -6.3754)
		(width 0.4064)
		(layer "B.Cu")
		(net "GND")
	)
	(segment
		(start 69.56044 -22.939756)
		(end 69.56044 -22.965156)
		(width 0.4064)
		(layer "B.Cu")
		(net "GND")
	)
	(segment
		(start 312.849768 -141.663928)
		(end 312.387996 -141.202156)
		(width 0.4064)
		(layer "B.Cu")
		(net "GND")
	)
	(segment
		(start 207.450436 -137.877296)
		(end 207.449928 -137.877296)
		(width 0.4064)
		(layer "B.Cu")
		(net "GND")
	)
	(segment
		(start 42.449496 -21.504656)
		(end 42.436796 -21.517356)
		(width 0.4064)
		(layer "B.Cu")
		(net "GND")
	)
	(segment
		(start 167.2082 1.2192)
		(end 167.7416 0.6858)
		(width 0.4064)
		(layer "B.Cu")
		(net "GND")
	)
	(segment
		(start 52.649374 -142.477236)
		(end 52.649374 -141.67866)
		(width 0.254)
		(layer "B.Cu")
		(net "GND")
	)
	(segment
		(start 235.46181 -18.757646)
		(end 235.49991 -18.795746)
		(width 0.4064)
		(layer "B.Cu")
		(net "GND")
	)
	(segment
		(start 316.249812 -3.762756)
		(end 316.249812 -5.621782)
		(width 0.4064)
		(layer "B.Cu")
		(net "GND")
	)
	(segment
		(start 195.1482 -134.4168)
		(end 194.691 -134.874)
		(width 0.4064)
		(layer "B.Cu")
		(net "GND")
	)
	(segment
		(start 126.353824 -14.198346)
		(end 126.599442 -14.443964)
		(width 0.254)
		(layer "B.Cu")
		(net "GND")
	)
	(segment
		(start 315.399928 -129.568956)
		(end 315.399928 -128.276096)
		(width 0.4064)
		(layer "B.Cu")
		(net "GND")
	)
	(segment
		(start 303.038002 -4.346956)
		(end 303.499774 -4.808728)
		(width 0.4064)
		(layer "B.Cu")
		(net "GND")
	)
	(segment
		(start 215.100408 -128.276096)
		(end 215.0999 -128.276096)
		(width 0.4064)
		(layer "B.Cu")
		(net "GND")
	)
	(segment
		(start 386.456936 -2.448814)
		(end 386.520182 -2.385568)
		(width 0.254)
		(layer "B.Cu")
		(net "GND")
	)
	(segment
		(start 278.849836 -136.379966)
		(end 278.90216 -136.327642)
		(width 0.508)
		(layer "B.Cu")
		(net "GND")
	)
	(segment
		(start 144.449546 -20.224242)
		(end 144.449546 -21.504656)
		(width 0.4064)
		(layer "B.Cu")
		(net "GND")
	)
	(segment
		(start 55.199534 -14.410182)
		(end 55.199534 -15.222982)
		(width 0.4064)
		(layer "B.Cu")
		(net "GND")
	)
	(segment
		(start 216.799922 -11.903456)
		(end 216.787222 -11.916156)
		(width 0.4064)
		(layer "B.Cu")
		(net "GND")
	)
	(segment
		(start 281.361896 -21.517356)
		(end 281.387296 -21.517356)
		(width 0.4064)
		(layer "B.Cu")
		(net "GND")
	)
	(segment
		(start 50.851308 -7.607046)
		(end 50.949352 -7.509002)
		(width 0.4064)
		(layer "B.Cu")
		(net "GND")
	)
	(segment
		(start 70.499478 -129.530856)
		(end 70.461378 -129.568956)
		(width 0.4064)
		(layer "B.Cu")
		(net "GND")
	)
	(segment
		(start 500.6594 -39.4208)
		(end 500.6594 -38.7604)
		(width 0.254)
		(layer "B.Cu")
		(net "GND")
	)
	(segment
		(start 50.860452 -131.016756)
		(end 50.860452 -130.991356)
		(width 0.4064)
		(layer "B.Cu")
		(net "GND")
	)
	(segment
		(start 115.549426 -152.078436)
		(end 115.549426 -150.308056)
		(width 0.4064)
		(layer "B.Cu")
		(net "GND")
	)
	(segment
		(start 392.930888 -115.840002)
		(end 392.930888 -115.315746)
		(width 0.4064)
		(layer "B.Cu")
		(net "GND")
	)
	(segment
		(start 296.69994 -20.224242)
		(end 296.69994 -21.517356)
		(width 0.4064)
		(layer "B.Cu")
		(net "GND")
	)
	(segment
		(start 217.650314 -142.477236)
		(end 217.649806 -142.476982)
		(width 0.254)
		(layer "B.Cu")
		(net "GND")
	)
	(segment
		(start 308.59984 -140.82776)
		(end 308.809644 -140.617956)
		(width 0.4064)
		(layer "B.Cu")
		(net "GND")
	)
	(segment
		(start 235.49991 -1.021842)
		(end 235.49991 0.444754)
		(width 0.4064)
		(layer "B.Cu")
		(net "GND")
	)
	(segment
		(start 197.160896 -4.425442)
		(end 197.160896 -3.737356)
		(width 0.4064)
		(layer "B.Cu")
		(net "GND")
	)
	(segment
		(start 411.48 1.579372)
		(end 412.770828 1.579372)
		(width 0.254)
		(layer "B.Cu")
		(net "GND")
	)
	(segment
		(start 226.7458 -3.838956)
		(end 226.822 -3.762756)
		(width 0.4064)
		(layer "B.Cu")
		(net "GND")
	)
	(segment
		(start 233.799888 -137.877296)
		(end 233.799888 -139.170156)
		(width 0.4064)
		(layer "B.Cu")
		(net "GND")
	)
	(segment
		(start 242.287044 -22.965156)
		(end 242.299744 -22.977856)
		(width 0.4064)
		(layer "B.Cu")
		(net "GND")
	)
	(segment
		(start 85.761068 -8.1534)
		(end 84.910168 -8.1534)
		(width 0.508)
		(layer "B.Cu")
		(net "GND")
	)
	(segment
		(start 49.24933 -14.877796)
		(end 49.249584 -14.87805)
		(width 0.4064)
		(layer "B.Cu")
		(net "GND")
	)
	(segment
		(start 312.849768 -14.409928)
		(end 312.387996 -13.948156)
		(width 0.4064)
		(layer "B.Cu")
		(net "GND")
	)
	(segment
		(start 280.460958 -3.762756)
		(end 280.460958 -3.737356)
		(width 0.4064)
		(layer "B.Cu")
		(net "GND")
	)
	(segment
		(start 216.787222 -2.314956)
		(end 216.761822 -2.314956)
		(width 0.4064)
		(layer "B.Cu")
		(net "GND")
	)
	(segment
		(start 331.80528 -6.015482)
		(end 330.869798 -5.08)
		(width 0.254)
		(layer "B.Cu")
		(net "GND")
	)
	(segment
		(start 69.56044 -3.762756)
		(end 69.56044 -3.737356)
		(width 0.4064)
		(layer "B.Cu")
		(net "GND")
	)
	(segment
		(start 393.68095 -113.519204)
		(end 393.296902 -113.903252)
		(width 0.4064)
		(layer "B.Cu")
		(net "GND")
	)
	(segment
		(start 365.549942 -44.837858)
		(end 365.7981 -44.5897)
		(width 0.254)
		(layer "B.Cu")
		(net "GND")
	)
	(segment
		(start 191.4144 1.0922)
		(end 191.314832 1.191768)
		(width 0.508)
		(layer "B.Cu")
		(net "GND")
	)
	(segment
		(start 388.356094 -8.696452)
		(end 388.972806 -8.696452)
		(width 0.254)
		(layer "B.Cu")
		(net "GND")
	)
	(segment
		(start 141.62024 -25.925272)
		(end 141.383512 -26.162)
		(width 0.4064)
		(layer "B.Cu")
		(net "GND")
	)
	(segment
		(start 498.953028 -148.1582)
		(end 498.3734 -148.1582)
		(width 0.254)
		(layer "B.Cu")
		(net "GND")
	)
	(segment
		(start 370.29009 -64.985138)
		(end 370.5352 -64.740028)
		(width 0.254)
		(layer "B.Cu")
		(net "GND")
	)
	(segment
		(start 492.35106 -128.51384)
		(end 492.7219 -128.88468)
		(width 0.254)
		(layer "B.Cu")
		(net "GND")
	)
	(segment
		(start 291.600382 -15.222982)
		(end 291.599874 -15.222982)
		(width 0.254)
		(layer "B.Cu")
		(net "GND")
	)
	(segment
		(start 212.54974 -151.783796)
		(end 212.54974 -150.219156)
		(width 0.4064)
		(layer "B.Cu")
		(net "GND")
	)
	(segment
		(start 40.749474 -1.021842)
		(end 40.749474 0.457454)
		(width 0.4064)
		(layer "B.Cu")
		(net "GND")
	)
	(segment
		(start 90.874088 -17.35709)
		(end 90.874088 -18.01749)
		(width 0.4064)
		(layer "B.Cu")
		(net "GND")
	)
	(segment
		(start 223.60001 -142.476982)
		(end 223.60001 -142.23365)
		(width 0.4064)
		(layer "B.Cu")
		(net "GND")
	)
	(segment
		(start 500.331232 -38.711886)
		(end 499.955566 -38.33622)
		(width 0.254)
		(layer "B.Cu")
		(net "GND")
	)
	(segment
		(start 285.650432 -147.478496)
		(end 285.649924 -147.478496)
		(width 0.4064)
		(layer "B.Cu")
		(net "GND")
	)
	(segment
		(start 202.349862 -10.623042)
		(end 202.349862 -11.916156)
		(width 0.4064)
		(layer "B.Cu")
		(net "GND")
	)
	(segment
		(start 283.04236 -18.744946)
		(end 283.099764 -18.80235)
		(width 0.4064)
		(layer "B.Cu")
		(net "GND")
	)
	(segment
		(start 221.899988 -132.53085)
		(end 221.899734 -132.530596)
		(width 0.4064)
		(layer "B.Cu")
		(net "GND")
	)
	(segment
		(start 215.0999 -21.517356)
		(end 215.0999 -20.224242)
		(width 0.4064)
		(layer "B.Cu")
		(net "GND")
	)
	(segment
		(start 139.34948 -128.276096)
		(end 139.34948 -129.568956)
		(width 0.4064)
		(layer "B.Cu")
		(net "GND")
	)
	(segment
		(start 26.3144 -18.3642)
		(end 25.9334 -18.7452)
		(width 0.254)
		(layer "B.Cu")
		(net "GND")
	)
	(segment
		(start 72.1995 0.40005)
		(end 72.142096 0.457454)
		(width 0.4064)
		(layer "B.Cu")
		(net "GND")
	)
	(segment
		(start 400.939 -74.4982)
		(end 400.6596 -74.4982)
		(width 0.254)
		(layer "B.Cu")
		(net "GND")
	)
	(segment
		(start 39.899336 -13.363956)
		(end 39.899336 -15.222982)
		(width 0.4064)
		(layer "B.Cu")
		(net "GND")
	)
	(segment
		(start 58.599324 -3.762756)
		(end 58.599324 -5.378196)
		(width 0.4064)
		(layer "B.Cu")
		(net "GND")
	)
	(segment
		(start 230.399844 -139.170156)
		(end 230.399844 -137.877296)
		(width 0.4064)
		(layer "B.Cu")
		(net "GND")
	)
	(segment
		(start 291.599874 -24.045164)
		(end 291.354256 -23.799546)
		(width 0.254)
		(layer "B.Cu")
		(net "GND")
	)
	(segment
		(start 278.849836 -5.621782)
		(end 278.849836 -4.487164)
		(width 0.4064)
		(layer "B.Cu")
		(net "GND")
	)
	(segment
		(start 36.499546 -132.876036)
		(end 36.499546 -132.062982)
		(width 0.4064)
		(layer "B.Cu")
		(net "GND")
	)
	(segment
		(start 66.24955 -152.078436)
		(end 66.24955 -151.70785)
		(width 0.4064)
		(layer "B.Cu")
		(net "GND")
	)
	(segment
		(start 60.299346 -17.110202)
		(end 60.299346 -15.222982)
		(width 0.4064)
		(layer "B.Cu")
		(net "GND")
	)
	(segment
		(start 221.899988 -24.47925)
		(end 221.899734 -24.478996)
		(width 0.4064)
		(layer "B.Cu")
		(net "GND")
	)
	(segment
		(start 303.499774 -141.663928)
		(end 303.038002 -141.202156)
		(width 0.4064)
		(layer "B.Cu")
		(net "GND")
	)
	(segment
		(start 208.299812 -17.0688)
		(end 208.299812 -15.222982)
		(width 0.4064)
		(layer "B.Cu")
		(net "GND")
	)
	(segment
		(start 45.84954 -24.011382)
		(end 45.387514 -23.549356)
		(width 0.4064)
		(layer "B.Cu")
		(net "GND")
	)
	(segment
		(start 49.24933 -7.607046)
		(end 49.249584 -7.606792)
		(width 0.4064)
		(layer "B.Cu")
		(net "GND")
	)
	(segment
		(start 135.949436 -141.697964)
		(end 135.703818 -141.452346)
		(width 0.254)
		(layer "B.Cu")
		(net "GND")
	)
	(segment
		(start 44.149518 -129.488692)
		(end 44.092114 -129.546096)
		(width 0.4064)
		(layer "B.Cu")
		(net "GND")
	)
	(segment
		(start 223.599756 -142.233396)
		(end 223.599756 -140.617956)
		(width 0.4064)
		(layer "B.Cu")
		(net "GND")
	)
	(segment
		(start 322.306188 1.7018)
		(end 321.591432 1.7018)
		(width 0.4064)
		(layer "B.Cu")
		(net "GND")
	)
	(segment
		(start 442.0362 -23.3934)
		(end 440.436 -23.3934)
		(width 0.254)
		(layer "B.Cu")
		(net "GND")
	)
	(segment
		(start 118.041928 -129.546096)
		(end 118.041928 -129.564892)
		(width 0.4064)
		(layer "B.Cu")
		(net "GND")
	)
	(segment
		(start 413.86252 -45.576744)
		(end 413.86252 -44.98848)
		(width 0.254)
		(layer "B.Cu")
		(net "GND")
	)
	(segment
		(start 157.528768 1.478788)
		(end 156.814012 1.478788)
		(width 0.4064)
		(layer "B.Cu")
		(net "GND")
	)
	(segment
		(start 290.74999 -129.556256)
		(end 290.73729 -129.568956)
		(width 0.4064)
		(layer "B.Cu")
		(net "GND")
	)
	(segment
		(start 147.387564 -4.346956)
		(end 147.849336 -4.808728)
		(width 0.4064)
		(layer "B.Cu")
		(net "GND")
	)
	(segment
		(start 388.366 -130.88874)
		(end 387.5278 -130.88874)
		(width 0.254)
		(layer "B.Cu")
		(net "GND")
	)
	(segment
		(start 126.599442 -142.477236)
		(end 126.599442 -141.697964)
		(width 0.254)
		(layer "B.Cu")
		(net "GND")
	)
	(segment
		(start 85.761068 -12.954)
		(end 84.910168 -12.954)
		(width 0.4064)
		(layer "B.Cu")
		(net "GND")
	)
	(segment
		(start 136.799574 -139.089892)
		(end 136.74217 -139.147296)
		(width 0.4064)
		(layer "B.Cu")
		(net "GND")
	)
	(segment
		(start 55.199534 -6.63702)
		(end 54.74081 -7.095744)
		(width 0.4064)
		(layer "B.Cu")
		(net "GND")
	)
	(segment
		(start 47.549562 -7.606792)
		(end 47.549308 -7.607046)
		(width 0.4064)
		(layer "B.Cu")
		(net "GND")
	)
	(segment
		(start 414.050734 -9.552686)
		(end 414.073086 -9.552686)
		(width 0.254)
		(layer "B.Cu")
		(net "GND")
	)
	(segment
		(start 50.099468 -129.568956)
		(end 50.099468 -128.276096)
		(width 0.4064)
		(layer "B.Cu")
		(net "GND")
	)
	(segment
		(start 408.520646 -22.996652)
		(end 408.04338 -23.473918)
		(width 0.254)
		(layer "B.Cu")
		(net "GND")
	)
	(segment
		(start 52.398168 -23.7236)
		(end 52.398168 -23.038562)
		(width 0.4064)
		(layer "B.Cu")
		(net "GND")
	)
	(segment
		(start 60.210446 -140.617956)
		(end 60.210446 -140.592556)
		(width 0.4064)
		(layer "B.Cu")
		(net "GND")
	)
	(segment
		(start 203.200508 -5.621782)
		(end 203.2 -5.621782)
		(width 0.4064)
		(layer "B.Cu")
		(net "GND")
	)
	(segment
		(start 237.199932 -21.437092)
		(end 237.142528 -21.494496)
		(width 0.4064)
		(layer "B.Cu")
		(net "GND")
	)
	(segment
		(start 148.699474 -11.916156)
		(end 148.699474 -10.623042)
		(width 0.4064)
		(layer "B.Cu")
		(net "GND")
	)
	(segment
		(start 117.00383 -150.261574)
		(end 117.071648 -150.193756)
		(width 0.254)
		(layer "B.Cu")
		(net "GND")
	)
	(segment
		(start 115.549426 -142.476982)
		(end 115.549426 -142.477236)
		(width 0.508)
		(layer "B.Cu")
		(net "GND")
	)
	(segment
		(start 221.050358 -1.021842)
		(end 221.04985 -1.021842)
		(width 0.4064)
		(layer "B.Cu")
		(net "GND")
	)
	(segment
		(start 135.949436 -142.477236)
		(end 135.949436 -141.697964)
		(width 0.254)
		(layer "B.Cu")
		(net "GND")
	)
	(segment
		(start 99.2886 3.299968)
		(end 100.124768 2.4638)
		(width 0.508)
		(layer "B.Cu")
		(net "GND")
	)
	(segment
		(start 175.323754 -83.525868)
		(end 175.323754 -83.947)
		(width 0.4064)
		(layer "B.Cu")
		(net "GND")
	)
	(segment
		(start 374.231916 -36.797234)
		(end 374.231916 -37.063426)
		(width 0.254)
		(layer "B.Cu")
		(net "GND")
	)
	(segment
		(start 225.299778 -142.476982)
		(end 225.299778 -140.706856)
		(width 0.4064)
		(layer "B.Cu")
		(net "GND")
	)
	(segment
		(start 310.054244 -14.1224)
		(end 310.054244 -13.431774)
		(width 0.4064)
		(layer "B.Cu")
		(net "GND")
	)
	(segment
		(start 408.43708 -90.517726)
		(end 408.761692 -90.193114)
		(width 0.254)
		(layer "B.Cu")
		(net "GND")
	)
	(segment
		(start 230.399844 -2.314956)
		(end 230.399844 -1.021842)
		(width 0.4064)
		(layer "B.Cu")
		(net "GND")
	)
	(segment
		(start 306.050442 -20.224242)
		(end 306.049934 -20.224242)
		(width 0.4064)
		(layer "B.Cu")
		(net "GND")
	)
	(segment
		(start 429.7172 -21.997924)
		(end 429.7172 -22.5298)
		(width 0.254)
		(layer "B.Cu")
		(net "GND")
	)
	(segment
		(start 226.149916 -21.504656)
		(end 226.149916 -20.224242)
		(width 0.4064)
		(layer "B.Cu")
		(net "GND")
	)
	(segment
		(start 221.04985 -128.276096)
		(end 221.04985 -129.568956)
		(width 0.4064)
		(layer "B.Cu")
		(net "GND")
	)
	(segment
		(start 295.849802 -15.222982)
		(end 295.849802 -13.363956)
		(width 0.4064)
		(layer "B.Cu")
		(net "GND")
	)
	(segment
		(start 261.3152 -136.1948)
		(end 260.731 -136.779)
		(width 0.4064)
		(layer "B.Cu")
		(net "GND")
	)
	(segment
		(start 196.342 -17.723612)
		(end 196.342 -18.687034)
		(width 0.381)
		(layer "B.Cu")
		(net "GND")
	)
	(segment
		(start 210.391248 -16.696944)
		(end 210.849972 -16.23822)
		(width 0.4064)
		(layer "B.Cu")
		(net "GND")
	)
	(segment
		(start 324.104 -123.1138)
		(end 324.104 -121.12244)
		(width 0.254)
		(layer "B.Cu")
		(net "GND")
	)
	(segment
		(start 282.24988 -141.697964)
		(end 282.004262 -141.452346)
		(width 0.254)
		(layer "B.Cu")
		(net "GND")
	)
	(segment
		(start 281.399996 -128.276096)
		(end 281.400504 -128.276096)
		(width 0.4064)
		(layer "B.Cu")
		(net "GND")
	)
	(segment
		(start 195.5038 -143.9926)
		(end 195.12153 -144.37487)
		(width 0.4064)
		(layer "B.Cu")
		(net "GND")
	)
	(segment
		(start 410.5275 -3.48742)
		(end 410.387292 -3.347212)
		(width 0.254)
		(layer "B.Cu")
		(net "GND")
	)
	(segment
		(start 43.050968 -23.023068)
		(end 43.12158 -22.952456)
		(width 0.254)
		(layer "B.Cu")
		(net "GND")
	)
	(segment
		(start 129.999486 -10.623042)
		(end 129.999486 -9.156446)
		(width 0.4064)
		(layer "B.Cu")
		(net "GND")
	)
	(segment
		(start 113.849404 -5.621782)
		(end 113.849404 -7.1374)
		(width 0.4064)
		(layer "B.Cu")
		(net "GND")
	)
	(segment
		(start 397.137128 -77.724)
		(end 398.298416 -77.724)
		(width 0.254)
		(layer "B.Cu")
		(net "GND")
	)
	(segment
		(start 75.59929 -14.852396)
		(end 75.599544 -14.85265)
		(width 0.4064)
		(layer "B.Cu")
		(net "GND")
	)
	(segment
		(start 198.087234 -2.314956)
		(end 198.099934 -2.302256)
		(width 0.4064)
		(layer "B.Cu")
		(net "GND")
	)
	(segment
		(start 285.649924 -128.276096)
		(end 285.649924 -129.568956)
		(width 0.4064)
		(layer "B.Cu")
		(net "GND")
	)
	(segment
		(start 293.688008 -23.549356)
		(end 294.14978 -24.011128)
		(width 0.4064)
		(layer "B.Cu")
		(net "GND")
	)
	(segment
		(start 175.852074 -75.455526)
		(end 176.806352 -75.455526)
		(width 0.4064)
		(layer "B.Cu")
		(net "GND")
	)
	(segment
		(start 231.249728 -7.607046)
		(end 231.249982 -7.606792)
		(width 0.4064)
		(layer "B.Cu")
		(net "GND")
	)
	(segment
		(start 232.950512 -142.477236)
		(end 232.950004 -142.476982)
		(width 0.4064)
		(layer "B.Cu")
		(net "GND")
	)
	(segment
		(start 59.449462 -1.021842)
		(end 59.449462 0.457454)
		(width 0.4064)
		(layer "B.Cu")
		(net "GND")
	)
	(segment
		(start 389.84555 -63.072772)
		(end 389.460232 -63.45809)
		(width 0.254)
		(layer "B.Cu")
		(net "GND")
	)
	(segment
		(start 240.600484 -24.824182)
		(end 240.599976 -24.824182)
		(width 0.4064)
		(layer "B.Cu")
		(net "GND")
	)
	(segment
		(start 374.4722 -156.337)
		(end 374.4722 -155.9052)
		(width 0.4064)
		(layer "B.Cu")
		(net "GND")
	)
	(segment
		(start 309.449978 -21.504656)
		(end 309.449978 -20.224242)
		(width 0.4064)
		(layer "B.Cu")
		(net "GND")
	)
	(segment
		(start 285.649924 -20.224242)
		(end 285.649924 -21.517356)
		(width 0.4064)
		(layer "B.Cu")
		(net "GND")
	)
	(segment
		(start 229.550468 -5.621782)
		(end 229.54996 -5.621782)
		(width 0.4064)
		(layer "B.Cu")
		(net "GND")
	)
	(segment
		(start 482.128322 -18.210022)
		(end 482.128322 -17.929606)
		(width 0.254)
		(layer "B.Cu")
		(net "GND")
	)
	(segment
		(start 209.092546 -139.147296)
		(end 209.092546 -139.166092)
		(width 0.4064)
		(layer "B.Cu")
		(net "GND")
	)
	(segment
		(start 301.742602 -129.546096)
		(end 301.742602 -129.564892)
		(width 0.4064)
		(layer "B.Cu")
		(net "GND")
	)
	(segment
		(start 71.349362 -142.477236)
		(end 71.349362 -141.7066)
		(width 0.254)
		(layer "B.Cu")
		(net "GND")
	)
	(segment
		(start 220.200474 -152.078436)
		(end 220.199966 -152.078182)
		(width 0.4064)
		(layer "B.Cu")
		(net "GND")
	)
	(segment
		(start 394.861542 -9.452864)
		(end 395.351254 -9.452864)
		(width 0.254)
		(layer "B.Cu")
		(net "GND")
	)
	(segment
		(start 499.357142 -42.21226)
		(end 499.357142 -43.04284)
		(width 0.254)
		(layer "B.Cu")
		(net "GND")
	)
	(segment
		(start 277.397464 -12.954)
		(end 278.9174 -12.954)
		(width 0.381)
		(layer "B.Cu")
		(net "GND")
	)
	(segment
		(start 316.249812 -24.824182)
		(end 316.249812 -22.965156)
		(width 0.4064)
		(layer "B.Cu")
		(net "GND")
	)
	(segment
		(start 30.53334 -134.4168)
		(end 30.147768 -134.4168)
		(width 0.4064)
		(layer "B.Cu")
		(net "GND")
	)
	(segment
		(start 191.897 -155.448)
		(end 191.897 -155.956)
		(width 0.508)
		(layer "B.Cu")
		(net "GND")
	)
	(segment
		(start 237.20044 -20.224242)
		(end 237.199932 -20.224242)
		(width 0.4064)
		(layer "B.Cu")
		(net "GND")
	)
	(segment
		(start 109.2581 -3.3528)
		(end 110.111032 -3.3528)
		(width 0.508)
		(layer "B.Cu")
		(net "GND")
	)
	(segment
		(start 432.0032 -22.053296)
		(end 432.0032 -22.5298)
		(width 0.254)
		(layer "B.Cu")
		(net "GND")
	)
	(segment
		(start 316.25032 -24.824182)
		(end 316.249812 -24.824182)
		(width 0.4064)
		(layer "B.Cu")
		(net "GND")
	)
	(segment
		(start 199.742552 -2.292096)
		(end 199.742552 -2.310892)
		(width 0.4064)
		(layer "B.Cu")
		(net "GND")
	)
	(segment
		(start 435.864 -19.380454)
		(end 435.864 -20.193)
		(width 0.254)
		(layer "B.Cu")
		(net "GND")
	)
	(segment
		(start 112.397032 -12.954)
		(end 113.916968 -12.954)
		(width 0.381)
		(layer "B.Cu")
		(net "GND")
	)
	(segment
		(start 289.050476 -20.224242)
		(end 289.049968 -20.224242)
		(width 0.4064)
		(layer "B.Cu")
		(net "GND")
	)
	(segment
		(start 66.24955 -24.824182)
		(end 66.24955 -25.638252)
		(width 0.4064)
		(layer "B.Cu")
		(net "GND")
	)
	(segment
		(start 71.095362 -4.4958)
		(end 71.095362 -4.5974)
		(width 0.254)
		(layer "B.Cu")
		(net "GND")
	)
	(segment
		(start 201.500486 -142.477236)
		(end 201.499978 -142.476982)
		(width 0.4064)
		(layer "B.Cu")
		(net "GND")
	)
	(segment
		(start 310.299862 -142.476982)
		(end 310.30037 -142.477236)
		(width 0.254)
		(layer "B.Cu")
		(net "GND")
	)
	(segment
		(start 118.041928 -148.748496)
		(end 118.041928 -148.767292)
		(width 0.4064)
		(layer "B.Cu")
		(net "GND")
	)
	(segment
		(start 224.449894 -137.877296)
		(end 224.449894 -139.170156)
		(width 0.4064)
		(layer "B.Cu")
		(net "GND")
	)
	(segment
		(start 443.247018 -13.8938)
		(end 442.722 -13.8938)
		(width 0.254)
		(layer "B.Cu")
		(net "GND")
	)
	(segment
		(start 114.018568 -4.318)
		(end 113.849404 -4.487164)
		(width 0.4064)
		(layer "B.Cu")
		(net "GND")
	)
	(segment
		(start 198.099934 -129.556256)
		(end 198.087234 -129.568956)
		(width 0.4064)
		(layer "B.Cu")
		(net "GND")
	)
	(segment
		(start 145.053812 -150.286974)
		(end 145.053812 -150.9776)
		(width 0.4064)
		(layer "B.Cu")
		(net "GND")
	)
	(segment
		(start 281.399996 -9.156446)
		(end 281.399996 -10.623042)
		(width 0.4064)
		(layer "B.Cu")
		(net "GND")
	)
	(segment
		(start 395.16685 -110.48365)
		(end 395.16685 -110.943644)
		(width 0.254)
		(layer "B.Cu")
		(net "GND")
	)
	(segment
		(start 231.249982 -132.50545)
		(end 231.249728 -132.505196)
		(width 0.4064)
		(layer "B.Cu")
		(net "GND")
	)
	(segment
		(start 493.719104 -43.945048)
		(end 493.722914 -43.948858)
		(width 0.254)
		(layer "B.Cu")
		(net "GND")
	)
	(segment
		(start 56.899302 -13.363956)
		(end 56.899302 -14.877796)
		(width 0.4064)
		(layer "B.Cu")
		(net "GND")
	)
	(segment
		(start 163.6776 -79.248)
		(end 163.6776 -78.867)
		(width 0.381)
		(layer "B.Cu")
		(net "GND")
	)
	(segment
		(start 368.7064 -6.2357)
		(end 369.5954 -6.2357)
		(width 0.4572)
		(layer "B.Cu")
		(net "GND")
	)
	(segment
		(start 90.626692 -149.444964)
		(end 90.626692 -150.098506)
		(width 0.4064)
		(layer "B.Cu")
		(net "GND")
	)
	(segment
		(start 353.367848 -91.153742)
		(end 353.77247 -91.558364)
		(width 0.254)
		(layer "B.Cu")
		(net "GND")
	)
	(segment
		(start 257.429 -134.4676)
		(end 257.429 -134.4168)
		(width 0.4064)
		(layer "B.Cu")
		(net "GND")
	)
	(segment
		(start 300.772068 -3.762756)
		(end 300.70425 -3.830574)
		(width 0.4064)
		(layer "B.Cu")
		(net "GND")
	)
	(segment
		(start 283.099764 -11.835892)
		(end 283.04236 -11.893296)
		(width 0.4064)
		(layer "B.Cu")
		(net "GND")
	)
	(segment
		(start 196.40042 -1.021842)
		(end 196.399912 -1.021842)
		(width 0.4064)
		(layer "B.Cu")
		(net "GND")
	)
	(segment
		(start 125.749558 -2.302256)
		(end 125.736858 -2.314956)
		(width 0.4064)
		(layer "B.Cu")
		(net "GND")
	)
	(segment
		(start 439.4073 -142.6083)
		(end 439.626756 -142.827756)
		(width 0.254)
		(layer "B.Cu")
		(net "GND")
	)
	(segment
		(start 482.835458 -56.090058)
		(end 483.338886 -56.593486)
		(width 0.254)
		(layer "B.Cu")
		(net "GND")
	)
	(segment
		(start 213.399878 0.444754)
		(end 213.399878 -1.021842)
		(width 0.4064)
		(layer "B.Cu")
		(net "GND")
	)
	(segment
		(start 74.749406 -9.156446)
		(end 74.749406 -10.623042)
		(width 0.4064)
		(layer "B.Cu")
		(net "GND")
	)
	(segment
		(start 315.399928 -148.771356)
		(end 315.399928 -147.478496)
		(width 0.4064)
		(layer "B.Cu")
		(net "GND")
	)
	(segment
		(start 317.146432 -17.78)
		(end 317.09995 -17.733518)
		(width 0.4064)
		(layer "B.Cu")
		(net "GND")
	)
	(segment
		(start 236.350302 -15.222982)
		(end 236.349794 -15.222982)
		(width 0.254)
		(layer "B.Cu")
		(net "GND")
	)
	(segment
		(start 290.74999 -137.877296)
		(end 290.750498 -137.877296)
		(width 0.4064)
		(layer "B.Cu")
		(net "GND")
	)
	(segment
		(start 223.60001 -24.58085)
		(end 223.599756 -24.580596)
		(width 0.4064)
		(layer "B.Cu")
		(net "GND")
	)
	(segment
		(start 144.449546 -21.504656)
		(end 144.436846 -21.517356)
		(width 0.4064)
		(layer "B.Cu")
		(net "GND")
	)
	(segment
		(start 256.921 -135.3312)
		(end 256.921 -134.9756)
		(width 0.4064)
		(layer "B.Cu")
		(net "GND")
	)
	(segment
		(start 126.353824 -150.286974)
		(end 126.421642 -150.219156)
		(width 0.4064)
		(layer "B.Cu")
		(net "GND")
	)
	(segment
		(start 26.9748 -6.731)
		(end 26.9748 -7.338568)
		(width 0.4064)
		(layer "B.Cu")
		(net "GND")
	)
	(segment
		(start 215.041226 -97.2312)
		(end 215.284558 -96.987868)
		(width 0.254)
		(layer "B.Cu")
		(net "GND")
	)
	(segment
		(start 236.350302 -142.477236)
		(end 236.349794 -142.476982)
		(width 0.254)
		(layer "B.Cu")
		(net "GND")
	)
	(segment
		(start 240.599722 -5.251196)
		(end 240.599722 -3.762756)
		(width 0.4064)
		(layer "B.Cu")
		(net "GND")
	)
	(segment
		(start 49.249584 -24.47925)
		(end 49.24933 -24.478996)
		(width 0.4064)
		(layer "B.Cu")
		(net "GND")
	)
	(segment
		(start 402.13026 -52.79644)
		(end 402.13026 -53.35778)
		(width 0.254)
		(layer "B.Cu")
		(net "GND")
	)
	(segment
		(start 31.39948 -10.623042)
		(end 31.39948 -9.139682)
		(width 0.4064)
		(layer "B.Cu")
		(net "GND")
	)
	(segment
		(start 112.397032 -140.208)
		(end 113.688368 -140.208)
		(width 0.4064)
		(layer "B.Cu")
		(net "GND")
	)
	(segment
		(start 257.048 -17.6276)
		(end 257.048 -18.0086)
		(width 0.4064)
		(layer "B.Cu")
		(net "GND")
	)
	(segment
		(start 388.22884 -62.93104)
		(end 388.22884 -62.070234)
		(width 0.254)
		(layer "B.Cu")
		(net "GND")
	)
	(segment
		(start 120.649492 -2.314956)
		(end 120.649492 -1.021842)
		(width 0.4064)
		(layer "B.Cu")
		(net "GND")
	)
	(segment
		(start 211.699856 -137.877296)
		(end 211.699856 -139.170156)
		(width 0.4064)
		(layer "B.Cu")
		(net "GND")
	)
	(segment
		(start 114.294412 -29.238448)
		(end 114.294412 -29.94152)
		(width 0.254)
		(layer "B.Cu")
		(net "GND")
	)
	(segment
		(start 443.992 -147.663154)
		(end 443.552326 -147.663154)
		(width 0.254)
		(layer "B.Cu")
		(net "GND")
	)
	(segment
		(start 214.250016 -14.87805)
		(end 214.249762 -14.877796)
		(width 0.4064)
		(layer "B.Cu")
		(net "GND")
	)
	(segment
		(start 238.899954 -24.824182)
		(end 238.899954 -26.22423)
		(width 0.4064)
		(layer "B.Cu")
		(net "GND")
	)
	(segment
		(start 226.7458 -140.694156)
		(end 226.822 -140.617956)
		(width 0.4064)
		(layer "B.Cu")
		(net "GND")
	)
	(segment
		(start 279.699974 -18.744946)
		(end 279.699974 -20.224242)
		(width 0.4064)
		(layer "B.Cu")
		(net "GND")
	)
	(segment
		(start 449.1863 -19.653504)
		(end 448.900804 -19.939)
		(width 0.254)
		(layer "B.Cu")
		(net "GND")
	)
	(segment
		(start 219.741242 -16.696944)
		(end 220.199966 -16.23822)
		(width 0.4064)
		(layer "B.Cu")
		(net "GND")
	)
	(segment
		(start 236.349794 -4.8514)
		(end 236.095794 -4.5974)
		(width 0.254)
		(layer "B.Cu")
		(net "GND")
	)
	(segment
		(start 312.849768 -132.875782)
		(end 312.849768 -132.062728)
		(width 0.4064)
		(layer "B.Cu")
		(net "GND")
	)
	(segment
		(start 227.000308 -15.222982)
		(end 226.9998 -15.222982)
		(width 0.4064)
		(layer "B.Cu")
		(net "GND")
	)
	(segment
		(start 117.00383 -13.431774)
		(end 117.071648 -13.363956)
		(width 0.254)
		(layer "B.Cu")
		(net "GND")
	)
	(segment
		(start 70.499478 -21.479256)
		(end 70.461378 -21.517356)
		(width 0.4064)
		(layer "B.Cu")
		(net "GND")
	)
	(segment
		(start 225.299778 -15.222982)
		(end 225.299778 -13.452856)
		(width 0.4064)
		(layer "B.Cu")
		(net "GND")
	)
	(segment
		(start 279.699974 -127.064262)
		(end 279.699974 -128.276096)
		(width 0.4064)
		(layer "B.Cu")
		(net "GND")
	)
	(segment
		(start 217.3986 -140.691362)
		(end 217.472006 -140.617956)
		(width 0.4064)
		(layer "B.Cu")
		(net "GND")
	)
	(segment
		(start 232.94975 -5.327396)
		(end 232.94975 -3.762756)
		(width 0.4064)
		(layer "B.Cu")
		(net "GND")
	)
	(segment
		(start 135.099552 -147.478496)
		(end 135.099552 -148.733256)
		(width 0.4064)
		(layer "B.Cu")
		(net "GND")
	)
	(segment
		(start 472.241118 -135.676894)
		(end 472.241118 -134.958074)
		(width 0.254)
		(layer "B.Cu")
		(net "GND")
	)
	(segment
		(start 147.849336 -24.011128)
		(end 147.387564 -23.549356)
		(width 0.4064)
		(layer "B.Cu")
		(net "GND")
	)
	(segment
		(start 168.9608 -86.868)
		(end 168.656 -86.868)
		(width 0.4064)
		(layer "B.Cu")
		(net "GND")
	)
	(segment
		(start 493.451388 -125.720348)
		(end 492.35614 -124.6251)
		(width 0.254)
		(layer "B.Cu")
		(net "GND")
	)
	(segment
		(start 426.5676 -18.288)
		(end 424.532552 -18.288)
		(width 0.254)
		(layer "B.Cu")
		(net "GND")
	)
	(segment
		(start 212.54974 -17.208246)
		(end 212.549994 -17.207992)
		(width 0.4064)
		(layer "B.Cu")
		(net "GND")
	)
	(segment
		(start 165.862 -84.5312)
		(end 165.862 -84.709)
		(width 0.254)
		(layer "B.Cu")
		(net "GND")
	)
	(segment
		(start 130.84937 -22.965156)
		(end 130.84937 -24.824182)
		(width 0.4064)
		(layer "B.Cu")
		(net "GND")
	)
	(segment
		(start 144.436846 -11.916156)
		(end 144.449546 -11.903456)
		(width 0.4064)
		(layer "B.Cu")
		(net "GND")
	)
	(segment
		(start 140.199364 -24.824182)
		(end 140.199364 -25.645872)
		(width 0.4064)
		(layer "B.Cu")
		(net "GND")
	)
	(segment
		(start 410.616146 -34.208974)
		(end 410.616146 -34.934652)
		(width 0.4572)
		(layer "B.Cu")
		(net "GND")
	)
	(segment
		(start 243.149882 -10.623042)
		(end 243.149882 -12.815316)
		(width 0.4064)
		(layer "B.Cu")
		(net "GND")
	)
	(segment
		(start 212.54974 -5.327396)
		(end 212.549994 -5.32765)
		(width 0.4064)
		(layer "B.Cu")
		(net "GND")
	)
	(segment
		(start 115.460526 -3.762756)
		(end 115.549426 -3.851656)
		(width 0.4064)
		(layer "B.Cu")
		(net "GND")
	)
	(segment
		(start 214.250016 -132.53085)
		(end 214.249762 -132.530596)
		(width 0.4064)
		(layer "B.Cu")
		(net "GND")
	)
	(segment
		(start 53.499512 -147.478496)
		(end 53.499512 -148.691092)
		(width 0.4064)
		(layer "B.Cu")
		(net "GND")
	)
	(segment
		(start 370.967 -5.207)
		(end 369.9383 -6.2357)
		(width 0.381)
		(layer "B.Cu")
		(net "GND")
	)
	(segment
		(start 215.949784 -15.222982)
		(end 215.949784 -13.452856)
		(width 0.4064)
		(layer "B.Cu")
		(net "GND")
	)
	(segment
		(start 285.649924 -1.021842)
		(end 285.649924 -2.314956)
		(width 0.4064)
		(layer "B.Cu")
		(net "GND")
	)
	(segment
		(start 144.449546 -147.478496)
		(end 144.449546 -148.758656)
		(width 0.4064)
		(layer "B.Cu")
		(net "GND")
	)
	(segment
		(start 118.099332 -147.478496)
		(end 118.099332 -148.691092)
		(width 0.4064)
		(layer "B.Cu")
		(net "GND")
	)
	(segment
		(start 360.2482 -50.7746)
		(end 360.73588 -51.26228)
		(width 0.254)
		(layer "B.Cu")
		(net "GND")
	)
	(segment
		(start 207.411828 -18.757646)
		(end 207.449928 -18.795746)
		(width 0.4064)
		(layer "B.Cu")
		(net "GND")
	)
	(segment
		(start 213.400386 -137.877296)
		(end 213.399878 -137.877296)
		(width 0.4064)
		(layer "B.Cu")
		(net "GND")
	)
	(segment
		(start 215.950292 -142.477236)
		(end 215.949784 -142.476982)
		(width 0.4064)
		(layer "B.Cu")
		(net "GND")
	)
	(segment
		(start 126.353824 -131.851146)
		(end 126.353824 -131.7752)
		(width 0.254)
		(layer "B.Cu")
		(net "GND")
	)
	(segment
		(start 198.7042 -131.851146)
		(end 198.7042 -131.7752)
		(width 0.254)
		(layer "B.Cu")
		(net "GND")
	)
	(segment
		(start 30.549342 -142.477236)
		(end 30.549342 -141.1478)
		(width 0.4064)
		(layer "B.Cu")
		(net "GND")
	)
	(segment
		(start 26.3144 -7.998968)
		(end 26.3144 -8.122412)
		(width 0.4064)
		(layer "B.Cu")
		(net "GND")
	)
	(segment
		(start 126.353824 -141.452346)
		(end 126.353824 -141.3764)
		(width 0.254)
		(layer "B.Cu")
		(net "GND")
	)
	(segment
		(start 237.199932 0.40005)
		(end 237.142528 0.457454)
		(width 0.4064)
		(layer "B.Cu")
		(net "GND")
	)
	(segment
		(start 205.749906 -20.224242)
		(end 205.749906 -21.517356)
		(width 0.4064)
		(layer "B.Cu")
		(net "GND")
	)
	(segment
		(start 218.499944 -147.478496)
		(end 218.499944 -148.691092)
		(width 0.4064)
		(layer "B.Cu")
		(net "GND")
	)
	(segment
		(start 31.893002 -88.040464)
		(end 31.685738 -87.8332)
		(width 0.254)
		(layer "B.Cu")
		(net "GND")
	)
	(segment
		(start 303.499774 -24.824182)
		(end 303.499774 -26.224484)
		(width 0.4064)
		(layer "B.Cu")
		(net "GND")
	)
	(segment
		(start 408.711146 -21.648674)
		(end 408.456892 -21.39442)
		(width 0.254)
		(layer "B.Cu")
		(net "GND")
	)
	(segment
		(start 240.599976 -142.10665)
		(end 240.599722 -142.106396)
		(width 0.4064)
		(layer "B.Cu")
		(net "GND")
	)
	(segment
		(start 311.15 -21.437092)
		(end 311.15 -20.224242)
		(width 0.4064)
		(layer "B.Cu")
		(net "GND")
	)
	(segment
		(start 147.849336 -15.222982)
		(end 147.849336 -14.409928)
		(width 0.4064)
		(layer "B.Cu")
		(net "GND")
	)
	(segment
		(start 286.499808 -142.476982)
		(end 286.499808 -140.617956)
		(width 0.4064)
		(layer "B.Cu")
		(net "GND")
	)
	(segment
		(start 236.095794 -3.838956)
		(end 236.171994 -3.762756)
		(width 0.4064)
		(layer "B.Cu")
		(net "GND")
	)
	(segment
		(start 247.4595 -140.208)
		(end 246.565674 -140.208)
		(width 0.4572)
		(layer "B.Cu")
		(net "GND")
	)
	(segment
		(start 135.086852 -129.568956)
		(end 135.061452 -129.568956)
		(width 0.4064)
		(layer "B.Cu")
		(net "GND")
	)
	(segment
		(start 196.439536 -71.784464)
		(end 196.0626 -72.1614)
		(width 0.254)
		(layer "B.Cu")
		(net "GND")
	)
	(segment
		(start 72.1995 -20.224242)
		(end 72.1995 -21.437092)
		(width 0.4064)
		(layer "B.Cu")
		(net "GND")
	)
	(segment
		(start 103.858568 3.81)
		(end 103.858568 5.11302)
		(width 0.508)
		(layer "B.Cu")
		(net "GND")
	)
	(segment
		(start 227.849938 -20.224242)
		(end 227.849938 -21.437092)
		(width 0.4064)
		(layer "B.Cu")
		(net "GND")
	)
	(segment
		(start 118.041928 -11.912092)
		(end 118.041928 -11.893296)
		(width 0.4064)
		(layer "B.Cu")
		(net "GND")
	)
	(segment
		(start 139.34948 0.444754)
		(end 139.34948 -1.021842)
		(width 0.4064)
		(layer "B.Cu")
		(net "GND")
	)
	(segment
		(start 197.249796 -150.970742)
		(end 197.160896 -150.881842)
		(width 0.4064)
		(layer "B.Cu")
		(net "GND")
	)
	(segment
		(start 33.703768 -131.084574)
		(end 33.771586 -131.016756)
		(width 0.4064)
		(layer "B.Cu")
		(net "GND")
	)
	(segment
		(start 236.095794 -150.9522)
		(end 236.095794 -150.295356)
		(width 0.4064)
		(layer "B.Cu")
		(net "GND")
	)
	(segment
		(start 124.81052 -3.762756)
		(end 124.89942 -3.851656)
		(width 0.4064)
		(layer "B.Cu")
		(net "GND")
	)
	(segment
		(start 215.85174 -17.208246)
		(end 215.949784 -17.110202)
		(width 0.4064)
		(layer "B.Cu")
		(net "GND")
	)
	(segment
		(start 254.789432 -149.8092)
		(end 255.153668 -149.444964)
		(width 0.4572)
		(layer "B.Cu")
		(net "GND")
	)
	(segment
		(start 301.742602 -148.748496)
		(end 301.800006 -148.691092)
		(width 0.4064)
		(layer "B.Cu")
		(net "GND")
	)
	(segment
		(start 223.599756 -17.208246)
		(end 223.60001 -17.207992)
		(width 0.4064)
		(layer "B.Cu")
		(net "GND")
	)
	(segment
		(start 373.520716 -60.178442)
		(end 372.631716 -60.178442)
		(width 0.254)
		(layer "B.Cu")
		(net "GND")
	)
	(segment
		(start 113.849404 -141.176756)
		(end 113.849404 -142.477236)
		(width 0.4064)
		(layer "B.Cu")
		(net "GND")
	)
	(segment
		(start 171.852844 -87.151972)
		(end 171.852844 -88.109044)
		(width 0.4064)
		(layer "B.Cu")
		(net "GND")
	)
	(segment
		(start 237.142528 -139.147296)
		(end 237.142528 -139.166092)
		(width 0.4064)
		(layer "B.Cu")
		(net "GND")
	)
	(segment
		(start 229.54996 -5.621782)
		(end 229.54996 -4.808982)
		(width 0.4064)
		(layer "B.Cu")
		(net "GND")
	)
	(segment
		(start 402.1963 -52.7304)
		(end 402.13026 -52.79644)
		(width 0.254)
		(layer "B.Cu")
		(net "GND")
	)
	(segment
		(start 204.050392 -20.224242)
		(end 204.049884 -20.224242)
		(width 0.4064)
		(layer "B.Cu")
		(net "GND")
	)
	(segment
		(start 390.737598 -152.678638)
		(end 390.737598 -152.625298)
		(width 0.254)
		(layer "B.Cu")
		(net "GND")
	)
	(segment
		(start 232.950004 -24.824182)
		(end 232.950004 -24.53005)
		(width 0.4064)
		(layer "B.Cu")
		(net "GND")
	)
	(segment
		(start 445.933068 -37.028628)
		(end 445.937132 -37.032692)
		(width 0.4064)
		(layer "B.Cu")
		(net "GND")
	)
	(segment
		(start 78.102968 -27.2288)
		(end 77.544168 -26.67)
		(width 0.4064)
		(layer "B.Cu")
		(net "GND")
	)
	(segment
		(start 66.24955 -15.222982)
		(end 66.24955 -14.85265)
		(width 0.4064)
		(layer "B.Cu")
		(net "GND")
	)
	(segment
		(start 295.85031 -24.824182)
		(end 295.849802 -24.824182)
		(width 0.4064)
		(layer "B.Cu")
		(net "GND")
	)
	(segment
		(start 69.64934 -140.706856)
		(end 69.56044 -140.617956)
		(width 0.4064)
		(layer "B.Cu")
		(net "GND")
	)
	(segment
		(start 201.499978 -151.265382)
		(end 201.037952 -150.803356)
		(width 0.4064)
		(layer "B.Cu")
		(net "GND")
	)
	(segment
		(start 490.203998 -37.448998)
		(end 490.823758 -38.068758)
		(width 0.254)
		(layer "B.Cu")
		(net "GND")
	)
	(segment
		(start 62.849506 -2.234692)
		(end 62.792102 -2.292096)
		(width 0.4064)
		(layer "B.Cu")
		(net "GND")
	)
	(segment
		(start 400.6596 -74.4982)
		(end 400.3294 -74.168)
		(width 0.254)
		(layer "B.Cu")
		(net "GND")
	)
	(segment
		(start 49.24933 -132.530596)
		(end 49.24933 -131.016756)
		(width 0.4064)
		(layer "B.Cu")
		(net "GND")
	)
	(segment
		(start 243.6114 -150.114)
		(end 243.205 -150.114)
		(width 0.4572)
		(layer "B.Cu")
		(net "GND")
	)
	(segment
		(start 451.9422 -126.301246)
		(end 451.942962 -126.300484)
		(width 0.254)
		(layer "B.Cu")
		(net "GND")
	)
	(segment
		(start 50.949352 -7.509002)
		(end 50.949352 -5.621782)
		(width 0.4064)
		(layer "B.Cu")
		(net "GND")
	)
	(segment
		(start 268.679168 -17.7546)
		(end 267.794232 -17.7546)
		(width 0.381)
		(layer "B.Cu")
		(net "GND")
	)
	(segment
		(start 446.803018 -151.676862)
		(end 446.803018 -150.810722)
		(width 0.254)
		(layer "B.Cu")
		(net "GND")
	)
	(segment
		(start 316.25032 -5.621782)
		(end 316.249812 -5.621782)
		(width 0.4064)
		(layer "B.Cu")
		(net "GND")
	)
	(segment
		(start 441.347606 -15.681706)
		(end 441.071 -15.4051)
		(width 0.254)
		(layer "B.Cu")
		(net "GND")
	)
	(segment
		(start 237.142528 -2.310892)
		(end 237.142528 -2.292096)
		(width 0.4064)
		(layer "B.Cu")
		(net "GND")
	)
	(segment
		(start 255.130046 -12.613386)
		(end 255.87198 -12.613386)
		(width 0.4572)
		(layer "B.Cu")
		(net "GND")
	)
	(segment
		(start 232.100374 -20.224242)
		(end 232.099866 -20.224242)
		(width 0.4064)
		(layer "B.Cu")
		(net "GND")
	)
	(segment
		(start 375.7041 -109.392212)
		(end 376.869198 -109.392212)
		(width 0.254)
		(layer "B.Cu")
		(net "GND")
	)
	(segment
		(start 282.24988 -4.842764)
		(end 282.24988 -5.621782)
		(width 0.254)
		(layer "B.Cu")
		(net "GND")
	)
	(segment
		(start 71.095362 -131.8514)
		(end 71.095362 -131.7498)
		(width 0.254)
		(layer "B.Cu")
		(net "GND")
	)
	(segment
		(start 283.099764 -18.80235)
		(end 283.099764 -20.224242)
		(width 0.4064)
		(layer "B.Cu")
		(net "GND")
	)
	(segment
		(start 216.799922 -2.302256)
		(end 216.787222 -2.314956)
		(width 0.4064)
		(layer "B.Cu")
		(net "GND")
	)
	(segment
		(start 208.0514 -23.847552)
		(end 208.0514 -23.023068)
		(width 0.4064)
		(layer "B.Cu")
		(net "GND")
	)
	(segment
		(start 419.50386 -30.920944)
		(end 419.490144 -30.93466)
		(width 0.254)
		(layer "B.Cu")
		(net "GND")
	)
	(segment
		(start 301.800006 -18.80235)
		(end 301.800006 -20.224242)
		(width 0.4064)
		(layer "B.Cu")
		(net "GND")
	)
	(segment
		(start 477.6978 -13.69568)
		(end 477.6978 -13.7414)
		(width 0.254)
		(layer "B.Cu")
		(net "GND")
	)
	(segment
		(start 223.60001 -5.37845)
		(end 223.599756 -5.378196)
		(width 0.4064)
		(layer "B.Cu")
		(net "GND")
	)
	(segment
		(start 494.8682 -40.4876)
		(end 495.025934 -40.329866)
		(width 0.254)
		(layer "B.Cu")
		(net "GND")
	)
	(segment
		(start 198.950326 -142.477236)
		(end 198.949818 -142.476982)
		(width 0.254)
		(layer "B.Cu")
		(net "GND")
	)
	(segment
		(start 402.2344 -52.70373)
		(end 402.2344 -52.6669)
		(width 0.254)
		(layer "B.Cu")
		(net "GND")
	)
	(segment
		(start 486.148888 -122.219212)
		(end 485.734868 -122.219212)
		(width 0.254)
		(layer "B.Cu")
		(net "GND")
	)
	(segment
		(start 7.2898 -121.436384)
		(end 6.511036 -121.436384)
		(width 0.254)
		(layer "B.Cu")
		(net "GND")
	)
	(segment
		(start 382.5875 -50.3555)
		(end 381.2032 -50.3555)
		(width 0.254)
		(layer "B.Cu")
		(net "GND")
	)
	(segment
		(start 115.549426 -17.110202)
		(end 115.451382 -17.208246)
		(width 0.4064)
		(layer "B.Cu")
		(net "GND")
	)
	(segment
		(start 135.949436 -17.0688)
		(end 135.949436 -15.222982)
		(width 0.4064)
		(layer "B.Cu")
		(net "GND")
	)
	(segment
		(start 39.899336 -15.222982)
		(end 39.899336 -17.208246)
		(width 0.4064)
		(layer "B.Cu")
		(net "GND")
	)
	(segment
		(start 300.099984 -128.276096)
		(end 300.099984 -129.556256)
		(width 0.4064)
		(layer "B.Cu")
		(net "GND")
	)
	(segment
		(start 75.599544 -151.70785)
		(end 75.59929 -151.707596)
		(width 0.4064)
		(layer "B.Cu")
		(net "GND")
	)
	(segment
		(start 440.284362 -33.073848)
		(end 440.284362 -33.581848)
		(width 0.254)
		(layer "B.Cu")
		(net "GND")
	)
	(segment
		(start 309.450486 -10.623042)
		(end 309.449978 -10.623042)
		(width 0.4064)
		(layer "B.Cu")
		(net "GND")
	)
	(segment
		(start 324.104 -121.12244)
		(end 324.358 -120.86844)
		(width 0.254)
		(layer "B.Cu")
		(net "GND")
	)
	(segment
		(start 124.049536 -139.170156)
		(end 124.049536 -137.877296)
		(width 0.4064)
		(layer "B.Cu")
		(net "GND")
	)
	(segment
		(start 209.14995 -1.021842)
		(end 209.14995 0.40005)
		(width 0.4064)
		(layer "B.Cu")
		(net "GND")
	)
	(segment
		(start 298.399962 -10.623042)
		(end 298.399962 -11.916156)
		(width 0.4064)
		(layer "B.Cu")
		(net "GND")
	)
	(segment
		(start 233.799888 -10.623042)
		(end 233.799888 -9.143746)
		(width 0.4064)
		(layer "B.Cu")
		(net "GND")
	)
	(segment
		(start 476.936816 -146.533616)
		(end 477.4692 -147.066)
		(width 0.254)
		(layer "B.Cu")
		(net "GND")
	)
	(segment
		(start 121.499376 -142.477236)
		(end 121.499376 -140.617956)
		(width 0.4064)
		(layer "B.Cu")
		(net "GND")
	)
	(segment
		(start 280.550366 -150.308564)
		(end 280.460958 -150.219156)
		(width 0.4064)
		(layer "B.Cu")
		(net "GND")
	)
	(segment
		(start 435.2417 -14.224)
		(end 435.2417 -13.9065)
		(width 0.254)
		(layer "B.Cu")
		(net "GND")
	)
	(segment
		(start 195.549774 -24.824182)
		(end 195.549774 -23.495)
		(width 0.4064)
		(layer "B.Cu")
		(net "GND")
	)
	(segment
		(start 401.412456 -29.603446)
		(end 401.412456 -29.302456)
		(width 0.381)
		(layer "B.Cu")
		(net "GND")
	)
	(segment
		(start 243.88953 -86.57336)
		(end 243.668804 -86.794086)
		(width 0.254)
		(layer "B.Cu")
		(net "GND")
	)
	(segment
		(start 10.2108 -125.913134)
		(end 10.2108 -126.931928)
		(width 0.254)
		(layer "B.Cu")
		(net "GND")
	)
	(segment
		(start 289.049968 -137.877296)
		(end 289.050476 -137.877296)
		(width 0.4064)
		(layer "B.Cu")
		(net "GND")
	)
	(segment
		(start 215.860884 -131.016756)
		(end 215.860884 -130.991356)
		(width 0.4064)
		(layer "B.Cu")
		(net "GND")
	)
	(segment
		(start 0.361188 -145.8214)
		(end 0.365506 -145.817082)
		(width 0.254)
		(layer "B.Cu")
		(net "GND")
	)
	(segment
		(start 56.899556 -24.47925)
		(end 56.899302 -24.478996)
		(width 0.4064)
		(layer "B.Cu")
		(net "GND")
	)
	(segment
		(start 60.210446 -22.939756)
		(end 60.210446 -22.965156)
		(width 0.4064)
		(layer "B.Cu")
		(net "GND")
	)
	(segment
		(start 404.483062 -0.635508)
		(end 404.063708 -0.635508)
		(width 0.254)
		(layer "B.Cu")
		(net "GND")
	)
	(segment
		(start 369.8875 -51.26228)
		(end 371.77218 -51.26228)
		(width 0.254)
		(layer "B.Cu")
		(net "GND")
	)
	(segment
		(start 292.45052 -137.877296)
		(end 292.450012 -137.877296)
		(width 0.4064)
		(layer "B.Cu")
		(net "GND")
	)
	(segment
		(start 409.208986 -11.857736)
		(end 409.208986 -12.13993)
		(width 0.254)
		(layer "B.Cu")
		(net "GND")
	)
	(segment
		(start 67.949572 -7.606792)
		(end 67.949318 -7.607046)
		(width 0.4064)
		(layer "B.Cu")
		(net "GND")
	)
	(segment
		(start 410.21 -3.048)
		(end 409.7655 -3.4925)
		(width 0.254)
		(layer "B.Cu")
		(net "GND")
	)
	(segment
		(start 299.249846 -13.728954)
		(end 299.249846 -15.222982)
		(width 0.4064)
		(layer "B.Cu")
		(net "GND")
	)
	(segment
		(start 283.099764 0.40005)
		(end 283.04236 0.457454)
		(width 0.4064)
		(layer "B.Cu")
		(net "GND")
	)
	(segment
		(start 91.46286 -149.77872)
		(end 91.143074 -150.098506)
		(width 0.381)
		(layer "B.Cu")
		(net "GND")
	)
	(segment
		(start 309.437278 -139.170156)
		(end 309.449978 -139.157456)
		(width 0.4064)
		(layer "B.Cu")
		(net "GND")
	)
	(segment
		(start 388.75589 -63.45809)
		(end 388.22884 -62.93104)
		(width 0.254)
		(layer "B.Cu")
		(net "GND")
	)
	(segment
		(start 471.14206 -128.83896)
		(end 471.0557 -128.7526)
		(width 0.254)
		(layer "B.Cu")
		(net "GND")
	)
	(segment
		(start 232.950512 -152.078436)
		(end 232.950004 -152.078182)
		(width 0.4064)
		(layer "B.Cu")
		(net "GND")
	)
	(segment
		(start 20.193 -94.2086)
		(end 20.193 -94.6404)
		(width 0.4064)
		(layer "B.Cu")
		(net "GND")
	)
	(segment
		(start 196.893434 -88.040464)
		(end 196.591936 -88.040464)
		(width 0.254)
		(layer "B.Cu")
		(net "GND")
	)
	(segment
		(start 34.799524 -2.234692)
		(end 34.799524 -1.021842)
		(width 0.4064)
		(layer "B.Cu")
		(net "GND")
	)
	(segment
		(start 237.142528 -18.744946)
		(end 237.199932 -18.80235)
		(width 0.4064)
		(layer "B.Cu")
		(net "GND")
	)
	(segment
		(start 408.04338 -23.93188)
		(end 408.4955 -24.384)
		(width 0.254)
		(layer "B.Cu")
		(net "GND")
	)
	(segment
		(start 62.849506 0.40005)
		(end 62.849506 -1.021842)
		(width 0.4064)
		(layer "B.Cu")
		(net "GND")
	)
	(segment
		(start 379.66015 -45.181774)
		(end 379.650752 -45.181774)
		(width 0.254)
		(layer "B.Cu")
		(net "GND")
	)
	(segment
		(start 390.67994 -152.56764)
		(end 390.67994 -152.00122)
		(width 0.254)
		(layer "B.Cu")
		(net "GND")
	)
	(segment
		(start 208.0514 -140.675868)
		(end 208.122012 -140.605256)
		(width 0.254)
		(layer "B.Cu")
		(net "GND")
	)
	(segment
		(start 62.849506 -21.437092)
		(end 62.792102 -21.494496)
		(width 0.4064)
		(layer "B.Cu")
		(net "GND")
	)
	(segment
		(start 278.9682 -150.659592)
		(end 278.9682 -150.0886)
		(width 0.4064)
		(layer "B.Cu")
		(net "GND")
	)
	(segment
		(start 243.149882 -2.3622)
		(end 243.149882 -1.021842)
		(width 0.4064)
		(layer "B.Cu")
		(net "GND")
	)
	(segment
		(start 196.388736 -79.912464)
		(end 196.0626 -80.2386)
		(width 0.254)
		(layer "B.Cu")
		(net "GND")
	)
	(segment
		(start 30.503368 -143.9926)
		(end 30.361128 -143.9926)
		(width 0.4064)
		(layer "B.Cu")
		(net "GND")
	)
	(segment
		(start 167.102536 -73.246234)
		(end 167.288718 -73.246234)
		(width 0.254)
		(layer "B.Cu")
		(net "GND")
	)
	(segment
		(start 225.300286 -132.876036)
		(end 225.299778 -132.875782)
		(width 0.4064)
		(layer "B.Cu")
		(net "GND")
	)
	(segment
		(start 401.931632 -148.9964)
		(end 401.752816 -148.817584)
		(width 0.4064)
		(layer "B.Cu")
		(net "GND")
	)
	(segment
		(start 129.149348 -4.808728)
		(end 129.149348 -5.621782)
		(width 0.4064)
		(layer "B.Cu")
		(net "GND")
	)
	(segment
		(start 444.119 -19.16684)
		(end 444.119 -20.193)
		(width 0.254)
		(layer "B.Cu")
		(net "GND")
	)
	(segment
		(start 363.9185 -53.213)
		(end 365.252 -53.213)
		(width 0.254)
		(layer "B.Cu")
		(net "GND")
	)
	(segment
		(start 60.210446 -150.219156)
		(end 60.210446 -150.193756)
		(width 0.4064)
		(layer "B.Cu")
		(net "GND")
	)
	(segment
		(start 215.949784 -24.824182)
		(end 215.949784 -23.054056)
		(width 0.4064)
		(layer "B.Cu")
		(net "GND")
	)
	(segment
		(start 229.54996 -15.222982)
		(end 229.54996 -14.410182)
		(width 0.4064)
		(layer "B.Cu")
		(net "GND")
	)
	(segment
		(start 278.849836 -137.877042)
		(end 278.849836 -136.379966)
		(width 0.508)
		(layer "B.Cu")
		(net "GND")
	)
	(segment
		(start 408.127454 -29.972)
		(end 408.290014 -30.13456)
		(width 0.254)
		(layer "B.Cu")
		(net "GND")
	)
	(segment
		(start 214.250016 -7.606792)
		(end 214.250016 -5.621782)
		(width 0.4064)
		(layer "B.Cu")
		(net "GND")
	)
	(segment
		(start 226.149916 -20.224242)
		(end 226.149916 -18.757646)
		(width 0.4064)
		(layer "B.Cu")
		(net "GND")
	)
	(segment
		(start 208.299812 -151.349964)
		(end 208.0514 -151.101552)
		(width 0.254)
		(layer "B.Cu")
		(net "GND")
	)
	(segment
		(start 304.35042 -1.021842)
		(end 304.349912 -1.021842)
		(width 0.4064)
		(layer "B.Cu")
		(net "GND")
	)
	(segment
		(start 368.345974 -69.895974)
		(end 367.945162 -69.495162)
		(width 0.254)
		(layer "B.Cu")
		(net "GND")
	)
	(segment
		(start 114.699542 -145.998946)
		(end 114.699542 -147.478242)
		(width 0.508)
		(layer "B.Cu")
		(net "GND")
	)
	(segment
		(start 212.550502 -24.824182)
		(end 212.549994 -24.824182)
		(width 0.4064)
		(layer "B.Cu")
		(net "GND")
	)
	(segment
		(start 209.14995 -11.835892)
		(end 209.14995 -10.623042)
		(width 0.4064)
		(layer "B.Cu")
		(net "GND")
	)
	(segment
		(start 38.199568 -152.078436)
		(end 38.199568 -150.21941)
		(width 0.4064)
		(layer "B.Cu")
		(net "GND")
	)
	(segment
		(start 197.249796 -142.476982)
		(end 197.249796 -141.369542)
		(width 0.4064)
		(layer "B.Cu")
		(net "GND")
	)
	(segment
		(start 210.85048 -132.876036)
		(end 210.849972 -132.875782)
		(width 0.4064)
		(layer "B.Cu")
		(net "GND")
	)
	(segment
		(start 71.349362 -151.3078)
		(end 71.095362 -151.0538)
		(width 0.254)
		(layer "B.Cu")
		(net "GND")
	)
	(segment
		(start 281.387296 -139.170156)
		(end 281.399996 -139.157456)
		(width 0.4064)
		(layer "B.Cu")
		(net "GND")
	)
	(segment
		(start 95.555816 -150.059644)
		(end 95.84436 -149.7711)
		(width 0.4572)
		(layer "B.Cu")
		(net "GND")
	)
	(segment
		(start 207.450436 -128.276096)
		(end 207.449928 -128.276096)
		(width 0.4064)
		(layer "B.Cu")
		(net "GND")
	)
	(segment
		(start 281.421586 -81.874614)
		(end 281.686 -81.6102)
		(width 0.254)
		(layer "B.Cu")
		(net "GND")
	)
	(segment
		(start 119.799354 -24.824182)
		(end 119.799354 -24.011382)
		(width 0.4064)
		(layer "B.Cu")
		(net "GND")
	)
	(segment
		(start 95.005906 -155.241244)
		(end 95.005906 -156.703014)
		(width 0.508)
		(layer "B.Cu")
		(net "GND")
	)
	(segment
		(start 330.5048 -8.6106)
		(end 330.5048 -9.1186)
		(width 0.254)
		(layer "B.Cu")
		(net "GND")
	)
	(segment
		(start 127.44958 -11.835892)
		(end 127.392176 -11.893296)
		(width 0.4064)
		(layer "B.Cu")
		(net "GND")
	)
	(segment
		(start 125.736858 -2.314956)
		(end 125.711458 -2.314956)
		(width 0.4064)
		(layer "B.Cu")
		(net "GND")
	)
	(segment
		(start 372.954804 -84.523072)
		(end 373.207026 -84.775294)
		(width 0.254)
		(layer "B.Cu")
		(net "GND")
	)
	(segment
		(start 416.464242 -10.314178)
		(end 412.68142 -14.097)
		(width 0.254)
		(layer "B.Cu")
		(net "GND")
	)
	(segment
		(start 451.781672 -28.897326)
		(end 452.278242 -28.897326)
		(width 0.4064)
		(layer "B.Cu")
		(net "GND")
	)
	(segment
		(start 136.799574 -128.276096)
		(end 136.799574 -129.488692)
		(width 0.4064)
		(layer "B.Cu")
		(net "GND")
	)
	(segment
		(start 400.71675 -74.78522)
		(end 400.97075 -74.53122)
		(width 0.254)
		(layer "B.Cu")
		(net "GND")
	)
	(segment
		(start 282.24988 -5.621782)
		(end 282.24988 -7.4676)
		(width 0.4064)
		(layer "B.Cu")
		(net "GND")
	)
	(segment
		(start 138.499342 -152.078436)
		(end 138.499342 -151.265128)
		(width 0.4064)
		(layer "B.Cu")
		(net "GND")
	)
	(segment
		(start 56.899556 -151.73325)
		(end 56.899302 -151.732996)
		(width 0.4064)
		(layer "B.Cu")
		(net "GND")
	)
	(segment
		(start 36.499546 -5.621782)
		(end 36.499546 -6.63702)
		(width 0.4064)
		(layer "B.Cu")
		(net "GND")
	)
	(segment
		(start 198.7042 -141.3764)
		(end 198.7042 -140.685774)
		(width 0.4064)
		(layer "B.Cu")
		(net "GND")
	)
	(segment
		(start 76.449428 -137.877296)
		(end 76.449428 -139.170156)
		(width 0.4064)
		(layer "B.Cu")
		(net "GND")
	)
	(segment
		(start 312.849768 -132.062728)
		(end 312.387996 -131.600956)
		(width 0.4064)
		(layer "B.Cu")
		(net "GND")
	)
	(segment
		(start 235.500418 -20.224242)
		(end 235.49991 -20.224242)
		(width 0.4064)
		(layer "B.Cu")
		(net "GND")
	)
	(segment
		(start 72.142096 -2.292096)
		(end 72.1995 -2.234692)
		(width 0.4064)
		(layer "B.Cu")
		(net "GND")
	)
	(segment
		(start 291.354256 -14.198346)
		(end 291.354256 -14.1224)
		(width 0.254)
		(layer "B.Cu")
		(net "GND")
	)
	(segment
		(start 198.949818 -14.443964)
		(end 198.949818 -15.222982)
		(width 0.254)
		(layer "B.Cu")
		(net "GND")
	)
	(segment
		(start 242.300506 -132.876036)
		(end 242.300506 -131.030218)
		(width 0.4064)
		(layer "B.Cu")
		(net "GND")
	)
	(segment
		(start 240.599976 -17.207992)
		(end 240.599976 -15.222982)
		(width 0.4064)
		(layer "B.Cu")
		(net "GND")
	)
	(segment
		(start 119.799354 -5.621782)
		(end 119.799354 -6.63702)
		(width 0.4064)
		(layer "B.Cu")
		(net "GND")
	)
	(segment
		(start 229.54996 -16.23822)
		(end 229.54996 -15.222982)
		(width 0.4064)
		(layer "B.Cu")
		(net "GND")
	)
	(segment
		(start 199.742552 -21.513292)
		(end 199.742552 -21.494496)
		(width 0.4064)
		(layer "B.Cu")
		(net "GND")
	)
	(segment
		(start 224.449894 -147.478496)
		(end 224.449894 -148.771356)
		(width 0.4064)
		(layer "B.Cu")
		(net "GND")
	)
	(segment
		(start 301.800514 -137.877296)
		(end 301.800006 -137.877296)
		(width 0.4064)
		(layer "B.Cu")
		(net "GND")
	)
	(segment
		(start 490.203998 -36.944808)
		(end 490.203998 -37.448998)
		(width 0.254)
		(layer "B.Cu")
		(net "GND")
	)
	(segment
		(start 34.799524 -129.488692)
		(end 34.74212 -129.546096)
		(width 0.4064)
		(layer "B.Cu")
		(net "GND")
	)
	(segment
		(start 224.450402 -128.276096)
		(end 224.449894 -128.276096)
		(width 0.4064)
		(layer "B.Cu")
		(net "GND")
	)
	(segment
		(start 126.421642 -22.965156)
		(end 126.353824 -23.032974)
		(width 0.4064)
		(layer "B.Cu")
		(net "GND")
	)
	(segment
		(start 314.550298 -15.222982)
		(end 314.54979 -15.222982)
		(width 0.4064)
		(layer "B.Cu")
		(net "GND")
	)
	(segment
		(start 413.511492 -44.637452)
		(end 413.511492 -43.904916)
		(width 0.254)
		(layer "B.Cu")
		(net "GND")
	)
	(segment
		(start 33.949386 -5.621782)
		(end 33.949386 -4.842764)
		(width 0.254)
		(layer "B.Cu")
		(net "GND")
	)
	(segment
		(start 50.860452 -150.219156)
		(end 50.860452 -150.193756)
		(width 0.4064)
		(layer "B.Cu")
		(net "GND")
	)
	(segment
		(start 116.399564 -18.757646)
		(end 116.399564 -20.224242)
		(width 0.4064)
		(layer "B.Cu")
		(net "GND")
	)
	(segment
		(start 408.16784 -21.336)
		(end 408.183588 -21.336)
		(width 0.254)
		(layer "B.Cu")
		(net "GND")
	)
	(segment
		(start 197.151752 -7.607046)
		(end 197.249796 -7.509002)
		(width 0.4064)
		(layer "B.Cu")
		(net "GND")
	)
	(segment
		(start 434.2384 -11.6332)
		(end 433.85232 -12.01928)
		(width 0.254)
		(layer "B.Cu")
		(net "GND")
	)
	(segment
		(start 409.7655 -3.4925)
		(end 409.7655 -4.572)
		(width 0.254)
		(layer "B.Cu")
		(net "GND")
	)
	(segment
		(start 182.43042 3.323844)
		(end 182.089298 3.664966)
		(width 0.254)
		(layer "B.Cu")
		(net "GND")
	)
	(segment
		(start 222.749872 -137.877296)
		(end 222.749872 -139.170156)
		(width 0.4064)
		(layer "B.Cu")
		(net "GND")
	)
	(segment
		(start 402.13026 -53.35778)
		(end 401.20824 -53.35778)
		(width 0.254)
		(layer "B.Cu")
		(net "GND")
	)
	(segment
		(start 199.742552 -11.893296)
		(end 199.799956 -11.835892)
		(width 0.4064)
		(layer "B.Cu")
		(net "GND")
	)
	(segment
		(start 60.210446 -13.363956)
		(end 60.210446 -13.338556)
		(width 0.4064)
		(layer "B.Cu")
		(net "GND")
	)
	(segment
		(start 226.149916 -147.478496)
		(end 226.149916 -148.758656)
		(width 0.4064)
		(layer "B.Cu")
		(net "GND")
	)
	(segment
		(start 444.45174 -22.82444)
		(end 445.02324 -23.39594)
		(width 0.254)
		(layer "B.Cu")
		(net "GND")
	)
	(segment
		(start 65.399412 -20.224242)
		(end 65.399412 -18.757646)
		(width 0.4064)
		(layer "B.Cu")
		(net "GND")
	)
	(segment
		(start 243.149882 -139.2428)
		(end 243.149882 -137.877296)
		(width 0.4064)
		(layer "B.Cu")
		(net "GND")
	)
	(segment
		(start 260.53415 -27.275282)
		(end 259.710682 -27.275282)
		(width 0.381)
		(layer "B.Cu")
		(net "GND")
	)
	(segment
		(start 439.4073 -141.986)
		(end 439.4073 -142.6083)
		(width 0.254)
		(layer "B.Cu")
		(net "GND")
	)
	(segment
		(start 204.900276 -152.078436)
		(end 204.899768 -152.078182)
		(width 0.4064)
		(layer "B.Cu")
		(net "GND")
	)
	(segment
		(start 309.449978 -148.758656)
		(end 309.437278 -148.771356)
		(width 0.4064)
		(layer "B.Cu")
		(net "GND")
	)
	(segment
		(start 305.200304 -152.078436)
		(end 305.199796 -152.078182)
		(width 0.4064)
		(layer "B.Cu")
		(net "GND")
	)
	(segment
		(start 373.944388 -73.095612)
		(end 373.944642 -73.095612)
		(width 0.254)
		(layer "B.Cu")
		(net "GND")
	)
	(segment
		(start 124.049536 -147.478496)
		(end 124.049536 -148.771356)
		(width 0.4064)
		(layer "B.Cu")
		(net "GND")
	)
	(segment
		(start 364.4265 -58.928)
		(end 363.093 -58.928)
		(width 0.254)
		(layer "B.Cu")
		(net "GND")
	)
	(segment
		(start 206.501746 -7.607046)
		(end 206.59979 -7.509002)
		(width 0.4064)
		(layer "B.Cu")
		(net "GND")
	)
	(segment
		(start 206.59979 -23.028656)
		(end 206.51089 -22.939756)
		(width 0.4064)
		(layer "B.Cu")
		(net "GND")
	)
	(segment
		(start 46.699424 -18.757646)
		(end 46.699424 -20.224242)
		(width 0.4064)
		(layer "B.Cu")
		(net "GND")
	)
	(segment
		(start 330.7588 -8.3566)
		(end 330.5048 -8.6106)
		(width 0.254)
		(layer "B.Cu")
		(net "GND")
	)
	(segment
		(start 113.849404 -126.089156)
		(end 113.8555 -126.08306)
		(width 0.508)
		(layer "B.Cu")
		(net "GND")
	)
	(segment
		(start 43.12158 -7.6454)
		(end 43.29938 -7.4676)
		(width 0.4064)
		(layer "B.Cu")
		(net "GND")
	)
	(segment
		(start 37.34943 -11.916156)
		(end 37.34943 -10.623042)
		(width 0.4064)
		(layer "B.Cu")
		(net "GND")
	)
	(segment
		(start 65.399412 -147.478496)
		(end 65.399412 -148.771356)
		(width 0.4064)
		(layer "B.Cu")
		(net "GND")
	)
	(segment
		(start 110.843568 3.81)
		(end 110.843568 5.27304)
		(width 0.508)
		(layer "B.Cu")
		(net "GND")
	)
	(segment
		(start 60.299346 -5.621782)
		(end 60.299346 -7.509002)
		(width 0.4064)
		(layer "B.Cu")
		(net "GND")
	)
	(segment
		(start 162.175952 -63.376302)
		(end 161.044382 -63.376302)
		(width 0.254)
		(layer "B.Cu")
		(net "GND")
	)
	(segment
		(start 212.549994 -5.621782)
		(end 212.549994 -7.606792)
		(width 0.4064)
		(layer "B.Cu")
		(net "GND")
	)
	(segment
		(start 440.968638 -151.602186)
		(end 440.112404 -151.602186)
		(width 0.254)
		(layer "B.Cu")
		(net "GND")
	)
	(segment
		(start 26.9748 -7.338568)
		(end 26.3144 -7.998968)
		(width 0.4064)
		(layer "B.Cu")
		(net "GND")
	)
	(segment
		(start 375.544842 -77.094334)
		(end 375.630694 -77.094334)
		(width 0.254)
		(layer "B.Cu")
		(net "GND")
	)
	(segment
		(start 372.980966 -73.478136)
		(end 373.527828 -73.478136)
		(width 0.254)
		(layer "B.Cu")
		(net "GND")
	)
	(segment
		(start 255.815338 -139.829794)
		(end 255.521206 -139.829794)
		(width 0.4064)
		(layer "B.Cu")
		(net "GND")
	)
	(segment
		(start 34.74212 -18.744946)
		(end 34.799524 -18.80235)
		(width 0.4064)
		(layer "B.Cu")
		(net "GND")
	)
	(segment
		(start 243.149882 -9.133078)
		(end 243.149882 -10.623042)
		(width 0.4064)
		(layer "B.Cu")
		(net "GND")
	)
	(segment
		(start 291.599874 -17.0688)
		(end 291.599874 -15.222982)
		(width 0.4064)
		(layer "B.Cu")
		(net "GND")
	)
	(segment
		(start 213.399878 -21.517356)
		(end 213.399878 -20.224242)
		(width 0.4064)
		(layer "B.Cu")
		(net "GND")
	)
	(segment
		(start 96.00692 -140.00988)
		(end 96.00692 -139.053316)
		(width 0.508)
		(layer "B.Cu")
		(net "GND")
	)
	(segment
		(start 311.150508 -128.276096)
		(end 311.15 -128.276096)
		(width 0.4064)
		(layer "B.Cu")
		(net "GND")
	)
	(segment
		(start 290.74999 -139.157456)
		(end 290.74999 -137.877296)
		(width 0.4064)
		(layer "B.Cu")
		(net "GND")
	)
	(segment
		(start 152.949402 2.514854)
		(end 152.626568 2.19202)
		(width 0.4064)
		(layer "B.Cu")
		(net "GND")
	)
	(segment
		(start 278.849836 -14.13002)
		(end 279.039574 -13.940282)
		(width 0.4064)
		(layer "B.Cu")
		(net "GND")
	)
	(segment
		(start 295.000426 -20.224242)
		(end 294.999918 -20.224242)
		(width 0.4064)
		(layer "B.Cu")
		(net "GND")
	)
	(segment
		(start 209.14995 -139.089892)
		(end 209.092546 -139.147296)
		(width 0.4064)
		(layer "B.Cu")
		(net "GND")
	)
	(segment
		(start 156.591 -8.128)
		(end 156.68498 -8.128)
		(width 0.254)
		(layer "B.Cu")
		(net "GND")
	)
	(segment
		(start 196.399912 -9.139682)
		(end 196.399912 -10.623042)
		(width 0.4064)
		(layer "B.Cu")
		(net "GND")
	)
	(segment
		(start 234.649772 -23.054056)
		(end 234.560872 -22.965156)
		(width 0.4064)
		(layer "B.Cu")
		(net "GND")
	)
	(segment
		(start 52.649374 -24.02586)
		(end 52.398168 -23.774654)
		(width 0.254)
		(layer "B.Cu")
		(net "GND")
	)
	(segment
		(start 78.14945 -9.133078)
		(end 78.14945 -10.623042)
		(width 0.4064)
		(layer "B.Cu")
		(net "GND")
	)
	(segment
		(start 209.150458 -10.623042)
		(end 209.14995 -10.623042)
		(width 0.4064)
		(layer "B.Cu")
		(net "GND")
	)
	(segment
		(start 45.84954 -142.477236)
		(end 45.84954 -141.664182)
		(width 0.4064)
		(layer "B.Cu")
		(net "GND")
	)
	(segment
		(start 51.79949 -10.623042)
		(end 51.79949 -11.903456)
		(width 0.4064)
		(layer "B.Cu")
		(net "GND")
	)
	(segment
		(start 400.812 -28.702)
		(end 400.409156 -29.104844)
		(width 0.381)
		(layer "B.Cu")
		(net "GND")
	)
	(segment
		(start 204.049884 -2.314956)
		(end 204.049884 -1.021842)
		(width 0.4064)
		(layer "B.Cu")
		(net "GND")
	)
	(segment
		(start 119.799354 -132.062982)
		(end 119.337328 -131.600956)
		(width 0.4064)
		(layer "B.Cu")
		(net "GND")
	)
	(segment
		(start 419.50386 -30.13456)
		(end 419.50386 -30.920944)
		(width 0.254)
		(layer "B.Cu")
		(net "GND")
	)
	(segment
		(start 129.149348 -132.876036)
		(end 129.149348 -132.062728)
		(width 0.4064)
		(layer "B.Cu")
		(net "GND")
	)
	(segment
		(start 145.053812 -13.431774)
		(end 145.053812 -14.1224)
		(width 0.4064)
		(layer "B.Cu")
		(net "GND")
	)
	(segment
		(start 217.649806 -15.222982)
		(end 217.649806 -14.42466)
		(width 0.254)
		(layer "B.Cu")
		(net "GND")
	)
	(segment
		(start 311.658 -35.987736)
		(end 315.022992 -39.352728)
		(width 0.381)
		(layer "B.Cu")
		(net "GND")
	)
	(segment
		(start 236.095794 -131.8514)
		(end 236.095794 -131.7498)
		(width 0.254)
		(layer "B.Cu")
		(net "GND")
	)
	(segment
		(start 130.84937 -17.208246)
		(end 130.84937 -15.222982)
		(width 0.4064)
		(layer "B.Cu")
		(net "GND")
	)
	(segment
		(start 231.7242 -84.8614)
		(end 231.8004 -84.7852)
		(width 0.1524)
		(layer "B.Cu")
		(net "GND")
	)
	(segment
		(start 113.967768 -141.058392)
		(end 113.849404 -141.176756)
		(width 0.4064)
		(layer "B.Cu")
		(net "GND")
	)
	(segment
		(start 243.149882 -12.815316)
		(end 243.219732 -12.885166)
		(width 0.4064)
		(layer "B.Cu")
		(net "GND")
	)
	(segment
		(start 296.69994 -128.276096)
		(end 296.700448 -128.276096)
		(width 0.4064)
		(layer "B.Cu")
		(net "GND")
	)
	(segment
		(start 227.000308 -24.824182)
		(end 226.9998 -24.824182)
		(width 0.254)
		(layer "B.Cu")
		(net "GND")
	)
	(segment
		(start 152.146 -7.132828)
		(end 152.099518 -7.086346)
		(width 0.4064)
		(layer "B.Cu")
		(net "GND")
	)
	(segment
		(start 306.049934 -20.224242)
		(end 306.049934 -18.757646)
		(width 0.4064)
		(layer "B.Cu")
		(net "GND")
	)
	(segment
		(start 51.79949 -11.903456)
		(end 51.78679 -11.916156)
		(width 0.4064)
		(layer "B.Cu")
		(net "GND")
	)
	(segment
		(start 118.041928 -21.494496)
		(end 118.041928 -21.513292)
		(width 0.4064)
		(layer "B.Cu")
		(net "GND")
	)
	(segment
		(start 238.900462 -152.078436)
		(end 238.899954 -152.078182)
		(width 0.4064)
		(layer "B.Cu")
		(net "GND")
	)
	(segment
		(start 229.0064 -87.5792)
		(end 229.50805 -87.5792)
		(width 0.254)
		(layer "B.Cu")
		(net "GND")
	)
	(segment
		(start 279.699974 -128.276096)
		(end 279.699974 -129.568956)
		(width 0.4064)
		(layer "B.Cu")
		(net "GND")
	)
	(segment
		(start 399.8595 -106.172)
		(end 399.3642 -106.172)
		(width 0.254)
		(layer "B.Cu")
		(net "GND")
	)
	(segment
		(start 306.049934 -21.517356)
		(end 306.049934 -20.224242)
		(width 0.4064)
		(layer "B.Cu")
		(net "GND")
	)
	(segment
		(start 73.899522 -14.410182)
		(end 73.437496 -13.948156)
		(width 0.4064)
		(layer "B.Cu")
		(net "GND")
	)
	(segment
		(start 82.459068 -135.4074)
		(end 81.618836 -135.4074)
		(width 0.4064)
		(layer "B.Cu")
		(net "GND")
	)
	(segment
		(start 62.792102 -21.494496)
		(end 62.792102 -21.513292)
		(width 0.4064)
		(layer "B.Cu")
		(net "GND")
	)
	(segment
		(start 300.772068 -22.965156)
		(end 300.70425 -23.032974)
		(width 0.4064)
		(layer "B.Cu")
		(net "GND")
	)
	(segment
		(start 220.199966 -14.410182)
		(end 219.73794 -13.948156)
		(width 0.4064)
		(layer "B.Cu")
		(net "GND")
	)
	(segment
		(start 43.050968 -141.500352)
		(end 43.050968 -140.675868)
		(width 0.4064)
		(layer "B.Cu")
		(net "GND")
	)
	(segment
		(start 290.74999 -128.276096)
		(end 290.74999 -129.556256)
		(width 0.4064)
		(layer "B.Cu")
		(net "GND")
	)
	(segment
		(start 303.499774 -16.238474)
		(end 303.499774 -15.222982)
		(width 0.4064)
		(layer "B.Cu")
		(net "GND")
	)
	(segment
		(start 61.149484 -2.302256)
		(end 61.136784 -2.314956)
		(width 0.4064)
		(layer "B.Cu")
		(net "GND")
	)
	(segment
		(start 296.700448 -147.478496)
		(end 296.69994 -147.478496)
		(width 0.4064)
		(layer "B.Cu")
		(net "GND")
	)
	(segment
		(start 210.849972 -151.265382)
		(end 210.387946 -150.803356)
		(width 0.4064)
		(layer "B.Cu")
		(net "GND")
	)
	(segment
		(start 212.549994 -132.875782)
		(end 212.549994 -132.58165)
		(width 0.4064)
		(layer "B.Cu")
		(net "GND")
	)
	(segment
		(start 221.899734 -14.877796)
		(end 221.899734 -13.363956)
		(width 0.4064)
		(layer "B.Cu")
		(net "GND")
	)
	(segment
		(start 300.950376 -5.621782)
		(end 300.949868 -5.621782)
		(width 0.4064)
		(layer "B.Cu")
		(net "GND")
	)
	(segment
		(start 75.599544 -7.606792)
		(end 75.59929 -7.607046)
		(width 0.4064)
		(layer "B.Cu")
		(net "GND")
	)
	(segment
		(start 236.349794 -151.3078)
		(end 236.095794 -151.0538)
		(width 0.254)
		(layer "B.Cu")
		(net "GND")
	)
	(segment
		(start 416.3695 -28.613862)
		(end 416.281108 -28.52547)
		(width 0.254)
		(layer "B.Cu")
		(net "GND")
	)
	(segment
		(start 402.488146 -23.949152)
		(end 402.043646 -24.393652)
		(width 0.254)
		(layer "B.Cu")
		(net "GND")
	)
	(segment
		(start 145.053812 -23.7236)
		(end 145.053812 -23.799546)
		(width 0.254)
		(layer "B.Cu")
		(net "GND")
	)
	(segment
		(start 61.136784 -148.771356)
		(end 61.111384 -148.771356)
		(width 0.4064)
		(layer "B.Cu")
		(net "GND")
	)
	(segment
		(start 196.591936 -88.040464)
		(end 196.1896 -88.4428)
		(width 0.254)
		(layer "B.Cu")
		(net "GND")
	)
	(segment
		(start 369.545108 -71.095108)
		(end 369.944904 -70.695312)
		(width 0.254)
		(layer "B.Cu")
		(net "GND")
	)
	(segment
		(start 56.899556 -24.824182)
		(end 56.899556 -24.47925)
		(width 0.4064)
		(layer "B.Cu")
		(net "GND")
	)
	(segment
		(start 75.59929 -13.363956)
		(end 75.59929 -14.852396)
		(width 0.4064)
		(layer "B.Cu")
		(net "GND")
	)
	(segment
		(start 439.976006 -41.203626)
		(end 439.976006 -40.5257)
		(width 0.3556)
		(layer "B.Cu")
		(net "GND")
	)
	(segment
		(start 207.449928 -147.478496)
		(end 207.449928 -148.758656)
		(width 0.4064)
		(layer "B.Cu")
		(net "GND")
	)
	(segment
		(start 282.250388 -151.299672)
		(end 282.004262 -151.053546)
		(width 0.254)
		(layer "B.Cu")
		(net "GND")
	)
	(segment
		(start 145.29943 -15.222982)
		(end 145.29943 -17.0688)
		(width 0.4064)
		(layer "B.Cu")
		(net "GND")
	)
	(segment
		(start 71.095362 -150.9522)
		(end 71.095362 -150.295356)
		(width 0.4064)
		(layer "B.Cu")
		(net "GND")
	)
	(segment
		(start 294.999918 -10.623042)
		(end 294.999918 -11.916156)
		(width 0.4064)
		(layer "B.Cu")
		(net "GND")
	)
	(segment
		(start 210.849972 -142.476982)
		(end 210.849972 -141.664182)
		(width 0.4064)
		(layer "B.Cu")
		(net "GND")
	)
	(segment
		(start 31.341568 -154.6352)
		(end 31.341568 -155.542234)
		(width 0.4064)
		(layer "B.Cu")
		(net "GND")
	)
	(segment
		(start 166.751 -88.1126)
		(end 167.0304 -88.392)
		(width 0.4064)
		(layer "B.Cu")
		(net "GND")
	)
	(segment
		(start 307.749956 -10.623042)
		(end 307.749956 -11.916156)
		(width 0.4064)
		(layer "B.Cu")
		(net "GND")
	)
	(segment
		(start 34.74212 -2.310892)
		(end 34.74212 -2.292096)
		(width 0.4064)
		(layer "B.Cu")
		(net "GND")
	)
	(segment
		(start 363.8042 -63.5889)
		(end 364.1725 -63.2206)
		(width 0.254)
		(layer "B.Cu")
		(net "GND")
	)
	(segment
		(start 198.949818 -132.875782)
		(end 198.949818 -132.096764)
		(width 0.254)
		(layer "B.Cu")
		(net "GND")
	)
	(segment
		(start 33.099502 -21.504656)
		(end 33.086802 -21.517356)
		(width 0.4064)
		(layer "B.Cu")
		(net "GND")
	)
	(segment
		(start 224.450402 -137.877296)
		(end 224.449894 -137.877296)
		(width 0.4064)
		(layer "B.Cu")
		(net "GND")
	)
	(segment
		(start 296.69994 -10.623042)
		(end 296.69994 -11.916156)
		(width 0.4064)
		(layer "B.Cu")
		(net "GND")
	)
	(segment
		(start 71.095362 -140.694156)
		(end 71.171562 -140.617956)
		(width 0.4064)
		(layer "B.Cu")
		(net "GND")
	)
	(segment
		(start 65.399412 -21.517356)
		(end 65.399412 -20.224242)
		(width 0.4064)
		(layer "B.Cu")
		(net "GND")
	)
	(segment
		(start 135.703818 -131.084574)
		(end 135.771636 -131.016756)
		(width 0.4064)
		(layer "B.Cu")
		(net "GND")
	)
	(segment
		(start 301.742602 -11.893296)
		(end 301.800006 -11.835892)
		(width 0.4064)
		(layer "B.Cu")
		(net "GND")
	)
	(segment
		(start 238.899954 -5.621782)
		(end 238.899954 -4.808982)
		(width 0.4064)
		(layer "B.Cu")
		(net "GND")
	)
	(segment
		(start 402.972524 -31.912052)
		(end 402.626576 -32.258)
		(width 0.254)
		(layer "B.Cu")
		(net "GND")
	)
	(segment
		(start 195.549774 -16.764)
		(end 195.549774 -15.222982)
		(width 0.4064)
		(layer "B.Cu")
		(net "GND")
	)
	(segment
		(start 90.8431 -7.806944)
		(end 91.082368 -7.806944)
		(width 0.4064)
		(layer "B.Cu")
		(net "GND")
	)
	(segment
		(start 229.54996 -14.410182)
		(end 229.087934 -13.948156)
		(width 0.4064)
		(layer "B.Cu")
		(net "GND")
	)
	(segment
		(start 392.557 -28.575)
		(end 392.557 -27.686)
		(width 0.254)
		(layer "B.Cu")
		(net "GND")
	)
	(segment
		(start 221.900496 -24.824182)
		(end 221.899988 -24.824182)
		(width 0.4064)
		(layer "B.Cu")
		(net "GND")
	)
	(segment
		(start 296.69994 -147.478496)
		(end 296.69994 -148.771356)
		(width 0.4064)
		(layer "B.Cu")
		(net "GND")
	)
	(segment
		(start 134.160514 -3.762756)
		(end 134.160514 -3.737356)
		(width 0.4064)
		(layer "B.Cu")
		(net "GND")
	)
	(segment
		(start 210.849972 -132.062982)
		(end 210.387946 -131.600956)
		(width 0.4064)
		(layer "B.Cu")
		(net "GND")
	)
	(segment
		(start 207.449928 -18.795746)
		(end 207.449928 -20.224242)
		(width 0.4064)
		(layer "B.Cu")
		(net "GND")
	)
	(segment
		(start 345.532202 -90.335354)
		(end 345.532202 -89.9033)
		(width 0.2032)
		(layer "B.Cu")
		(net "GND")
	)
	(segment
		(start 46.699424 -9.156446)
		(end 46.699424 -10.623042)
		(width 0.4064)
		(layer "B.Cu")
		(net "GND")
	)
	(segment
		(start 415.512504 -49.351184)
		(end 415.512504 -48.445674)
		(width 0.254)
		(layer "B.Cu")
		(net "GND")
	)
	(segment
		(start 147.849336 -142.477236)
		(end 147.849336 -141.663928)
		(width 0.4064)
		(layer "B.Cu")
		(net "GND")
	)
	(segment
		(start 350.2914 -146.812)
		(end 349.500952 -146.812)
		(width 0.254)
		(layer "B.Cu")
		(net "GND")
	)
	(segment
		(start 61.999368 -132.876036)
		(end 61.999368 -132.1054)
		(width 0.254)
		(layer "B.Cu")
		(net "GND")
	)
	(segment
		(start 304.349912 -18.757646)
		(end 304.349912 -20.224242)
		(width 0.4064)
		(layer "B.Cu")
		(net "GND")
	)
	(segment
		(start 299.160946 -22.965156)
		(end 299.249846 -23.054056)
		(width 0.4064)
		(layer "B.Cu")
		(net "GND")
	)
	(segment
		(start 491.210092 -55.043578)
		(end 491.21441 -55.043578)
		(width 0.4064)
		(layer "B.Cu")
		(net "GND")
	)
	(segment
		(start 150.399496 -11.916156)
		(end 150.399496 -10.623042)
		(width 0.4064)
		(layer "B.Cu")
		(net "GND")
	)
	(segment
		(start 238.899954 -15.222982)
		(end 238.899954 -14.410182)
		(width 0.4064)
		(layer "B.Cu")
		(net "GND")
	)
	(segment
		(start 74.749406 -1.021842)
		(end 74.749406 0.444754)
		(width 0.4064)
		(layer "B.Cu")
		(net "GND")
	)
	(segment
		(start 77.932788 -126.10338)
		(end 78.153768 -125.8824)
		(width 0.254)
		(layer "B.Cu")
		(net "GND")
	)
	(segment
		(start 221.899734 -142.131796)
		(end 221.899734 -140.617956)
		(width 0.4064)
		(layer "B.Cu")
		(net "GND")
	)
	(segment
		(start 300.099984 -18.757646)
		(end 300.099984 -20.224242)
		(width 0.4064)
		(layer "B.Cu")
		(net "GND")
	)
	(segment
		(start 217.649806 -17.0688)
		(end 217.649806 -15.222982)
		(width 0.4064)
		(layer "B.Cu")
		(net "GND")
	)
	(segment
		(start 222.749872 -9.156446)
		(end 222.749872 -10.623042)
		(width 0.4064)
		(layer "B.Cu")
		(net "GND")
	)
	(segment
		(start 58.599578 -14.97965)
		(end 58.599324 -14.979396)
		(width 0.4064)
		(layer "B.Cu")
		(net "GND")
	)
	(segment
		(start 218.499944 -137.877296)
		(end 218.499944 -139.089892)
		(width 0.4064)
		(layer "B.Cu")
		(net "GND")
	)
	(segment
		(start 306.900326 -132.876036)
		(end 306.899818 -132.875782)
		(width 0.4064)
		(layer "B.Cu")
		(net "GND")
	)
	(segment
		(start 199.799956 -147.478496)
		(end 199.799956 -148.691092)
		(width 0.4064)
		(layer "B.Cu")
		(net "GND")
	)
	(segment
		(start 380.746 -46.0883)
		(end 380.2507 -46.0883)
		(width 0.254)
		(layer "B.Cu")
		(net "GND")
	)
	(segment
		(start 232.94975 -14.928596)
		(end 232.94975 -13.363956)
		(width 0.4064)
		(layer "B.Cu")
		(net "GND")
	)
	(segment
		(start 235.49991 -137.877296)
		(end 235.49991 -139.132056)
		(width 0.4064)
		(layer "B.Cu")
		(net "GND")
	)
	(segment
		(start 50.949352 -17.110202)
		(end 50.851308 -17.208246)
		(width 0.4064)
		(layer "B.Cu")
		(net "GND")
	)
	(segment
		(start 278.849836 -134.35711)
		(end 278.849836 -132.876036)
		(width 0.508)
		(layer "B.Cu")
		(net "GND")
	)
	(segment
		(start 9.81583 -46.744128)
		(end 11.249914 -45.310044)
		(width 0.508)
		(layer "B.Cu")
		(net "GND")
	)
	(segment
		(start 45.84954 -141.664182)
		(end 45.387514 -141.202156)
		(width 0.4064)
		(layer "B.Cu")
		(net "GND")
	)
	(segment
		(start 212.549994 -142.18285)
		(end 212.54974 -142.182596)
		(width 0.4064)
		(layer "B.Cu")
		(net "GND")
	)
	(segment
		(start 110.111032 -145.0086)
		(end 109.2581 -145.0086)
		(width 0.4572)
		(layer "B.Cu")
		(net "GND")
	)
	(segment
		(start 304.349912 -11.916156)
		(end 304.349912 -10.623042)
		(width 0.4064)
		(layer "B.Cu")
		(net "GND")
	)
	(segment
		(start 410.614368 -39.63797)
		(end 410.614368 -38.991032)
		(width 0.254)
		(layer "B.Cu")
		(net "GND")
	)
	(segment
		(start 424.532552 -18.288)
		(end 424.0149 -17.770348)
		(width 0.254)
		(layer "B.Cu")
		(net "GND")
	)
	(segment
		(start 301.800006 -147.478496)
		(end 301.800514 -147.478496)
		(width 0.4064)
		(layer "B.Cu")
		(net "GND")
	)
	(segment
		(start 218.44254 -2.292096)
		(end 218.44254 -2.310892)
		(width 0.4064)
		(layer "B.Cu")
		(net "GND")
	)
	(segment
		(start 244.2337 -17.8816)
		(end 243.2304 -17.8816)
		(width 0.508)
		(layer "B.Cu")
		(net "GND")
	)
	(segment
		(start 140.199364 -132.876036)
		(end 140.199364 -131.016756)
		(width 0.4064)
		(layer "B.Cu")
		(net "GND")
	)
	(segment
		(start 278.849836 -132.875782)
		(end 278.849836 -131.575556)
		(width 0.4064)
		(layer "B.Cu")
		(net "GND")
	)
	(segment
		(start 214.249762 -151.732996)
		(end 214.249762 -150.219156)
		(width 0.4064)
		(layer "B.Cu")
		(net "GND")
	)
	(segment
		(start 483.310184 -20.27428)
		(end 483.310184 -19.391884)
		(width 0.254)
		(layer "B.Cu")
		(net "GND")
	)
	(segment
		(start 40.749474 -128.276096)
		(end 40.749474 -129.568956)
		(width 0.4064)
		(layer "B.Cu")
		(net "GND")
	)
	(segment
		(start 70.499478 -18.795746)
		(end 70.499478 -20.224242)
		(width 0.4064)
		(layer "B.Cu")
		(net "GND")
	)
	(segment
		(start 91.089226 -8.468868)
		(end 91.089226 -7.813802)
		(width 0.4064)
		(layer "B.Cu")
		(net "GND")
	)
	(segment
		(start 131.699508 -10.623042)
		(end 131.699508 -11.916156)
		(width 0.4064)
		(layer "B.Cu")
		(net "GND")
	)
	(segment
		(start 404.913846 -25.227534)
		(end 405.21509 -24.92629)
		(width 0.254)
		(layer "B.Cu")
		(net "GND")
	)
	(segment
		(start 461.397604 -34.9504)
		(end 460.9846 -34.9504)
		(width 0.254)
		(layer "B.Cu")
		(net "GND")
	)
	(segment
		(start 236.171994 -17.2466)
		(end 236.349794 -17.0688)
		(width 0.4064)
		(layer "B.Cu")
		(net "GND")
	)
	(segment
		(start 434.545994 -42.370248)
		(end 434.545994 -42.0116)
		(width 0.254)
		(layer "B.Cu")
		(net "GND")
	)
	(segment
		(start 204.900276 -5.621782)
		(end 204.899768 -5.621782)
		(width 0.4064)
		(layer "B.Cu")
		(net "GND")
	)
	(segment
		(start 52.649374 -141.67866)
		(end 52.398168 -141.427454)
		(width 0.254)
		(layer "B.Cu")
		(net "GND")
	)
	(segment
		(start 308.809644 -22.965156)
		(end 310.122062 -22.965156)
		(width 0.4064)
		(layer "B.Cu")
		(net "GND")
	)
	(segment
		(start 287.350454 -147.478496)
		(end 287.349946 -147.478496)
		(width 0.4064)
		(layer "B.Cu")
		(net "GND")
	)
	(segment
		(start 303.499774 -6.637274)
		(end 303.041304 -7.095744)
		(width 0.4064)
		(layer "B.Cu")
		(net "GND")
	)
	(segment
		(start 47.549308 -142.182596)
		(end 47.549308 -140.617956)
		(width 0.4064)
		(layer "B.Cu")
		(net "GND")
	)
	(segment
		(start 38.199568 -132.876036)
		(end 38.199568 -131.01701)
		(width 0.4064)
		(layer "B.Cu")
		(net "GND")
	)
	(segment
		(start 436.372 -149.281642)
		(end 436.372 -149.173946)
		(width 0.254)
		(layer "B.Cu")
		(net "GND")
	)
	(segment
		(start 379.3998 -47.0916)
		(end 378.8664 -47.625)
		(width 0.254)
		(layer "B.Cu")
		(net "GND")
	)
	(segment
		(start 226.7458 -23.6982)
		(end 226.7458 -23.041356)
		(width 0.4064)
		(layer "B.Cu")
		(net "GND")
	)
	(segment
		(start 26.8478 -32.268414)
		(end 27.1018 -32.522414)
		(width 0.254)
		(layer "B.Cu")
		(net "GND")
	)
	(segment
		(start 444.45174 -21.74748)
		(end 445.296544 -21.74748)
		(width 0.254)
		(layer "B.Cu")
		(net "GND")
	)
	(segment
		(start 322.0466 -145.489168)
		(end 322.0466 -145.8722)
		(width 0.508)
		(layer "B.Cu")
		(net "GND")
	)
	(segment
		(start 378.169678 -65.621662)
		(end 377.75642 -66.03492)
		(width 0.254)
		(layer "B.Cu")
		(net "GND")
	)
	(segment
		(start 236.095794 -4.5974)
		(end 236.095794 -4.4958)
		(width 0.254)
		(layer "B.Cu")
		(net "GND")
	)
	(segment
		(start 233.799888 -147.478496)
		(end 233.799888 -148.771356)
		(width 0.4064)
		(layer "B.Cu")
		(net "GND")
	)
	(segment
		(start 292.450012 -2.234692)
		(end 292.450012 -1.021842)
		(width 0.4064)
		(layer "B.Cu")
		(net "GND")
	)
	(segment
		(start 167.0304 -88.392)
		(end 167.3606 -88.392)
		(width 0.4064)
		(layer "B.Cu")
		(net "GND")
	)
	(segment
		(start 91.089226 -7.813802)
		(end 91.082368 -7.806944)
		(width 0.4064)
		(layer "B.Cu")
		(net "GND")
	)
	(segment
		(start 146.149568 -18.80235)
		(end 146.149568 -20.224242)
		(width 0.4064)
		(layer "B.Cu")
		(net "GND")
	)
	(segment
		(start 136.74217 -18.744946)
		(end 136.799574 -18.80235)
		(width 0.4064)
		(layer "B.Cu")
		(net "GND")
	)
	(segment
		(start 118.099332 -21.437092)
		(end 118.041928 -21.494496)
		(width 0.4064)
		(layer "B.Cu")
		(net "GND")
	)
	(segment
		(start 283.099764 -137.877296)
		(end 283.100272 -137.877296)
		(width 0.4064)
		(layer "B.Cu")
		(net "GND")
	)
	(segment
		(start 58.599324 -14.979396)
		(end 58.599324 -13.363956)
		(width 0.4064)
		(layer "B.Cu")
		(net "GND")
	)
	(segment
		(start 113.866168 -3.4798)
		(end 113.2078 -3.4798)
		(width 0.381)
		(layer "B.Cu")
		(net "GND")
	)
	(segment
		(start 237.199932 -128.276096)
		(end 237.199932 -129.488692)
		(width 0.4064)
		(layer "B.Cu")
		(net "GND")
	)
	(segment
		(start 460.24165 -124.87402)
		(end 460.8576 -125.48997)
		(width 0.254)
		(layer "B.Cu")
		(net "GND")
	)
	(segment
		(start 313.700414 -10.623042)
		(end 313.699906 -10.623042)
		(width 0.4064)
		(layer "B.Cu")
		(net "GND")
	)
	(segment
		(start 196.4436 -135.3312)
		(end 196.4436 -136.354058)
		(width 0.4064)
		(layer "B.Cu")
		(net "GND")
	)
	(segment
		(start 410.614368 -38.991032)
		(end 410.6926 -38.9128)
		(width 0.254)
		(layer "B.Cu")
		(net "GND")
	)
	(segment
		(start 289.899852 -140.706856)
		(end 289.810952 -140.617956)
		(width 0.4064)
		(layer "B.Cu")
		(net "GND")
	)
	(segment
		(start 166.4208 -86.868)
		(end 166.751 -87.1982)
		(width 0.4064)
		(layer "B.Cu")
		(net "GND")
	)
	(segment
		(start 213.399878 -128.276096)
		(end 213.399878 -129.568956)
		(width 0.4064)
		(layer "B.Cu")
		(net "GND")
	)
	(segment
		(start 125.749558 -9.156446)
		(end 125.749558 -10.623042)
		(width 0.4064)
		(layer "B.Cu")
		(net "GND")
	)
	(segment
		(start 226.137216 -2.314956)
		(end 226.111816 -2.314956)
		(width 0.4064)
		(layer "B.Cu")
		(net "GND")
	)
	(segment
		(start 291.354256 -131.084574)
		(end 291.422074 -131.016756)
		(width 0.4064)
		(layer "B.Cu")
		(net "GND")
	)
	(segment
		(start 124.049536 -1.021842)
		(end 124.049536 -2.314956)
		(width 0.4064)
		(layer "B.Cu")
		(net "GND")
	)
	(segment
		(start 212.550502 -15.222982)
		(end 212.549994 -15.222982)
		(width 0.4064)
		(layer "B.Cu")
		(net "GND")
	)
	(segment
		(start 309.411878 -11.916156)
		(end 309.437278 -11.916156)
		(width 0.4064)
		(layer "B.Cu")
		(net "GND")
	)
	(segment
		(start 305.199796 -132.875782)
		(end 305.199796 -131.016756)
		(width 0.4064)
		(layer "B.Cu")
		(net "GND")
	)
	(segment
		(start 313.699906 -10.623042)
		(end 313.699906 -9.156446)
		(width 0.4064)
		(layer "B.Cu")
		(net "GND")
	)
	(segment
		(start 242.299744 -142.055596)
		(end 242.299998 -142.05585)
		(width 0.4064)
		(layer "B.Cu")
		(net "GND")
	)
	(segment
		(start 204.899768 -142.476982)
		(end 204.899768 -140.617956)
		(width 0.4064)
		(layer "B.Cu")
		(net "GND")
	)
	(segment
		(start 205.750414 -20.224242)
		(end 205.749906 -20.224242)
		(width 0.4064)
		(layer "B.Cu")
		(net "GND")
	)
	(segment
		(start 390.13765 -112.65535)
		(end 390.5377 -112.2553)
		(width 0.254)
		(layer "B.Cu")
		(net "GND")
	)
	(segment
		(start 191.314832 -17.723612)
		(end 191.314832 -18.3642)
		(width 0.4064)
		(layer "B.Cu")
		(net "GND")
	)
	(segment
		(start 281.387296 -21.517356)
		(end 281.399996 -21.504656)
		(width 0.4064)
		(layer "B.Cu")
		(net "GND")
	)
	(segment
		(start 492.7219 -128.88468)
		(end 492.7219 -130.33756)
		(width 0.254)
		(layer "B.Cu")
		(net "GND")
	)
	(segment
		(start 209.150458 -1.021842)
		(end 209.14995 -1.021842)
		(width 0.4064)
		(layer "B.Cu")
		(net "GND")
	)
	(segment
		(start 114.699542 -147.478496)
		(end 114.699542 -148.771356)
		(width 0.4064)
		(layer "B.Cu")
		(net "GND")
	)
	(segment
		(start 237.20044 -137.877296)
		(end 237.199932 -137.877296)
		(width 0.4064)
		(layer "B.Cu")
		(net "GND")
	)
	(segment
		(start 124.89942 -15.222982)
		(end 124.89942 -13.452856)
		(width 0.4064)
		(layer "B.Cu")
		(net "GND")
	)
	(segment
		(start 75.599544 -142.477236)
		(end 75.599544 -142.10665)
		(width 0.4064)
		(layer "B.Cu")
		(net "GND")
	)
	(segment
		(start 422.389554 -137.044938)
		(end 423.488358 -135.946134)
		(width 0.254)
		(layer "B.Cu")
		(net "GND")
	)
	(segment
		(start 44.092114 -11.912092)
		(end 44.092114 -11.893296)
		(width 0.4064)
		(layer "B.Cu")
		(net "GND")
	)
	(segment
		(start 53.499512 -11.835892)
		(end 53.442108 -11.893296)
		(width 0.4064)
		(layer "B.Cu")
		(net "GND")
	)
	(segment
		(start 208.30032 -24.824182)
		(end 208.299812 -24.824182)
		(width 0.254)
		(layer "B.Cu")
		(net "GND")
	)
	(segment
		(start 163.576 -83.058)
		(end 163.576 -83.3628)
		(width 0.4064)
		(layer "B.Cu")
		(net "GND")
	)
	(segment
		(start 405.598376 -32.6644)
		(end 405.262588 -32.328612)
		(width 0.254)
		(layer "B.Cu")
		(net "GND")
	)
	(segment
		(start 298.399962 -128.276096)
		(end 298.399962 -129.568956)
		(width 0.4064)
		(layer "B.Cu")
		(net "GND")
	)
	(segment
		(start 311.150508 -10.623042)
		(end 311.15 -10.623042)
		(width 0.4064)
		(layer "B.Cu")
		(net "GND")
	)
	(segment
		(start 495.665506 -133.6675)
		(end 495.665506 -134.274306)
		(width 0.254)
		(layer "B.Cu")
		(net "GND")
	)
	(segment
		(start 119.337328 -13.948156)
		(end 119.799354 -14.410182)
		(width 0.4064)
		(layer "B.Cu")
		(net "GND")
	)
	(segment
		(start 71.171562 -3.762756)
		(end 71.095362 -3.838956)
		(width 0.4064)
		(layer "B.Cu")
		(net "GND")
	)
	(segment
		(start 475.165928 -123.375928)
		(end 475.015052 -123.375928)
		(width 0.254)
		(layer "B.Cu")
		(net "GND")
	)
	(segment
		(start 195.549774 -15.222982)
		(end 195.549774 -13.929106)
		(width 0.4064)
		(layer "B.Cu")
		(net "GND")
	)
	(segment
		(start 135.949436 -7.4676)
		(end 135.949436 -5.621782)
		(width 0.4064)
		(layer "B.Cu")
		(net "GND")
	)
	(segment
		(start 48.399446 -1.021842)
		(end 48.399446 0.444754)
		(width 0.4064)
		(layer "B.Cu")
		(net "GND")
	)
	(segment
		(start 119.799354 -16.23822)
		(end 119.34063 -16.696944)
		(width 0.4064)
		(layer "B.Cu")
		(net "GND")
	)
	(segment
		(start 44.092114 -2.292096)
		(end 44.149518 -2.234692)
		(width 0.4064)
		(layer "B.Cu")
		(net "GND")
	)
	(segment
		(start 292.392608 -2.310892)
		(end 292.392608 -2.292096)
		(width 0.4064)
		(layer "B.Cu")
		(net "GND")
	)
	(segment
		(start 403.1234 -22.5044)
		(end 403.1234 -23.114)
		(width 0.254)
		(layer "B.Cu")
		(net "GND")
	)
	(segment
		(start 209.092546 -11.912092)
		(end 209.092546 -11.893296)
		(width 0.4064)
		(layer "B.Cu")
		(net "GND")
	)
	(segment
		(start 213.400386 -147.478496)
		(end 213.399878 -147.478496)
		(width 0.4064)
		(layer "B.Cu")
		(net "GND")
	)
	(segment
		(start 384.085338 -71.296276)
		(end 384.1242 -71.335138)
		(width 0.254)
		(layer "B.Cu")
		(net "GND")
	)
	(segment
		(start 238.437928 -23.549356)
		(end 238.899954 -24.011382)
		(width 0.4064)
		(layer "B.Cu")
		(net "GND")
	)
	(segment
		(start 207.449928 -1.021842)
		(end 207.449928 -2.302256)
		(width 0.4064)
		(layer "B.Cu")
		(net "GND")
	)
	(segment
		(start 199.799956 -128.276096)
		(end 199.799956 -129.488692)
		(width 0.4064)
		(layer "B.Cu")
		(net "GND")
	)
	(segment
		(start 225.299778 -131.105656)
		(end 225.210878 -131.016756)
		(width 0.4064)
		(layer "B.Cu")
		(net "GND")
	)
	(segment
		(start 312.350404 -28.64104)
		(end 312.12409 -28.867354)
		(width 0.381)
		(layer "B.Cu")
		(net "GND")
	)
	(segment
		(start 51.79949 -128.276096)
		(end 51.79949 -129.556256)
		(width 0.4064)
		(layer "B.Cu")
		(net "GND")
	)
	(segment
		(start 255.3716 -139.9794)
		(end 255.018032 -139.9794)
		(width 0.4064)
		(layer "B.Cu")
		(net "GND")
	)
	(segment
		(start 232.950004 -5.621782)
		(end 232.950004 -5.32765)
		(width 0.4064)
		(layer "B.Cu")
		(net "GND")
	)
	(segment
		(start 390.76122 -152.70226)
		(end 390.737598 -152.678638)
		(width 0.254)
		(layer "B.Cu")
		(net "GND")
	)
	(segment
		(start 64.087502 -4.346956)
		(end 64.549528 -4.808982)
		(width 0.4064)
		(layer "B.Cu")
		(net "GND")
	)
	(segment
		(start 43.050968 -13.434568)
		(end 43.050968 -14.246352)
		(width 0.4064)
		(layer "B.Cu")
		(net "GND")
	)
	(segment
		(start 291.354256 -131.851146)
		(end 291.354256 -131.7752)
		(width 0.254)
		(layer "B.Cu")
		(net "GND")
	)
	(segment
		(start 234.65028 -132.876036)
		(end 234.649772 -132.875782)
		(width 0.4064)
		(layer "B.Cu")
		(net "GND")
	)
	(segment
		(start 317.09995 -20.224242)
		(end 317.09995 -18.757646)
		(width 0.4064)
		(layer "B.Cu")
		(net "GND")
	)
	(segment
		(start 39.049452 -9.156446)
		(end 39.049452 -10.623042)
		(width 0.4064)
		(layer "B.Cu")
		(net "GND")
	)
	(segment
		(start 310.30037 -152.078436)
		(end 310.299862 -152.078182)
		(width 0.254)
		(layer "B.Cu")
		(net "GND")
	)
	(segment
		(start 387.8707 -104.5464)
		(end 386.9817 -104.5464)
		(width 0.3048)
		(layer "B.Cu")
		(net "GND")
	)
	(segment
		(start 77.299312 -142.055596)
		(end 77.299566 -142.05585)
		(width 0.4064)
		(layer "B.Cu")
		(net "GND")
	)
	(segment
		(start 209.14995 -137.877296)
		(end 209.14995 -139.089892)
		(width 0.4064)
		(layer "B.Cu")
		(net "GND")
	)
	(segment
		(start 43.29938 -7.4676)
		(end 43.29938 -5.621782)
		(width 0.4064)
		(layer "B.Cu")
		(net "GND")
	)
	(segment
		(start 127.392176 -11.893296)
		(end 127.392176 -11.912092)
		(width 0.4064)
		(layer "B.Cu")
		(net "GND")
	)
	(segment
		(start 198.061834 -2.314956)
		(end 198.087234 -2.314956)
		(width 0.4064)
		(layer "B.Cu")
		(net "GND")
	)
	(segment
		(start 294.999918 -147.478496)
		(end 294.999918 -148.771356)
		(width 0.4064)
		(layer "B.Cu")
		(net "GND")
	)
	(segment
		(start 286.499808 -132.875782)
		(end 286.499808 -131.016756)
		(width 0.4064)
		(layer "B.Cu")
		(net "GND")
	)
	(segment
		(start 241.44986 -9.156446)
		(end 241.44986 -10.623042)
		(width 0.4064)
		(layer "B.Cu")
		(net "GND")
	)
	(segment
		(start 446.87998 -143.965422)
		(end 446.129918 -143.21536)
		(width 0.254)
		(layer "B.Cu")
		(net "GND")
	)
	(segment
		(start 57.74944 -9.156446)
		(end 57.74944 -10.623042)
		(width 0.4064)
		(layer "B.Cu")
		(net "GND")
	)
	(segment
		(start 133.39953 -137.877296)
		(end 133.39953 -139.170156)
		(width 0.4064)
		(layer "B.Cu")
		(net "GND")
	)
	(segment
		(start 122.349514 -1.021842)
		(end 122.349514 -2.314956)
		(width 0.4064)
		(layer "B.Cu")
		(net "GND")
	)
	(segment
		(start 55.199534 -15.222982)
		(end 55.199534 -16.23822)
		(width 0.4064)
		(layer "B.Cu")
		(net "GND")
	)
	(segment
		(start 300.70425 -141.452346)
		(end 300.949868 -141.697964)
		(width 0.254)
		(layer "B.Cu")
		(net "GND")
	)
	(segment
		(start 413.511492 -43.904916)
		(end 413.511492 -43.242992)
		(width 0.254)
		(layer "B.Cu")
		(net "GND")
	)
	(segment
		(start 484.989124 -19.50466)
		(end 484.847138 -19.50466)
		(width 0.254)
		(layer "B.Cu")
		(net "GND")
	)
	(segment
		(start 292.450012 -20.224242)
		(end 292.450012 -18.80235)
		(width 0.4064)
		(layer "B.Cu")
		(net "GND")
	)
	(segment
		(start 218.499944 -9.20115)
		(end 218.499944 -10.623042)
		(width 0.4064)
		(layer "B.Cu")
		(net "GND")
	)
	(segment
		(start 198.949818 -152.078182)
		(end 198.949818 -151.299164)
		(width 0.254)
		(layer "B.Cu")
		(net "GND")
	)
	(segment
		(start 115.549426 -23.054056)
		(end 115.460526 -22.965156)
		(width 0.4064)
		(layer "B.Cu")
		(net "GND")
	)
	(segment
		(start 280.550366 -142.477236)
		(end 280.550366 -140.681964)
		(width 0.508)
		(layer "B.Cu")
		(net "GND")
	)
	(segment
		(start 293.688008 -4.346956)
		(end 294.14978 -4.808728)
		(width 0.4064)
		(layer "B.Cu")
		(net "GND")
	)
	(segment
		(start 103.858568 5.11302)
		(end 104.018588 5.27304)
		(width 0.508)
		(layer "B.Cu")
		(net "GND")
	)
	(segment
		(start 288.200338 -152.078436)
		(end 288.200338 -150.219664)
		(width 0.4064)
		(layer "B.Cu")
		(net "GND")
	)
	(segment
		(start 226.822 -17.2466)
		(end 226.9998 -17.0688)
		(width 0.4064)
		(layer "B.Cu")
		(net "GND")
	)
	(segment
		(start 410.690314 -31.734506)
		(end 410.590492 -31.634684)
		(width 0.508)
		(layer "B.Cu")
		(net "GND")
	)
	(segment
		(start 38.199568 -15.222982)
		(end 38.199568 -17.207992)
		(width 0.4064)
		(layer "B.Cu")
		(net "GND")
	)
	(segment
		(start 385.3688 -2.448814)
		(end 386.456936 -2.448814)
		(width 0.254)
		(layer "B.Cu")
		(net "GND")
	)
	(segment
		(start 75.599544 -15.222982)
		(end 75.599544 -17.207992)
		(width 0.4064)
		(layer "B.Cu")
		(net "GND")
	)
	(segment
		(start 294.14978 -15.222982)
		(end 294.14978 -14.409928)
		(width 0.4064)
		(layer "B.Cu")
		(net "GND")
	)
	(segment
		(start 73.899522 -26.22423)
		(end 73.440798 -26.682954)
		(width 0.4064)
		(layer "B.Cu")
		(net "GND")
	)
	(segment
		(start 297.549824 -152.078182)
		(end 297.549824 -150.219156)
		(width 0.4064)
		(layer "B.Cu")
		(net "GND")
	)
	(segment
		(start 199.799956 -129.488692)
		(end 199.742552 -129.546096)
		(width 0.4064)
		(layer "B.Cu")
		(net "GND")
	)
	(segment
		(start 216.80043 -1.021842)
		(end 216.799922 -1.021842)
		(width 0.4064)
		(layer "B.Cu")
		(net "GND")
	)
	(segment
		(start 203.2 -7.606792)
		(end 203.199746 -7.607046)
		(width 0.4064)
		(layer "B.Cu")
		(net "GND")
	)
	(segment
		(start 50.949352 -140.706856)
		(end 50.860452 -140.617956)
		(width 0.4064)
		(layer "B.Cu")
		(net "GND")
	)
	(segment
		(start 231.249982 -5.621782)
		(end 231.249982 -5.25145)
		(width 0.4064)
		(layer "B.Cu")
		(net "GND")
	)
	(segment
		(start 261.777734 4.003548)
		(end 261.777734 2.324608)
		(width 0.508)
		(layer "B.Cu")
		(net "GND")
	)
	(segment
		(start 461.7466 -125.23597)
		(end 461.7466 -125.8824)
		(width 0.254)
		(layer "B.Cu")
		(net "GND")
	)
	(segment
		(start 237.142528 -21.494496)
		(end 237.142528 -21.513292)
		(width 0.4064)
		(layer "B.Cu")
		(net "GND")
	)
	(segment
		(start 124.89942 -24.824182)
		(end 124.89942 -25.709372)
		(width 0.4064)
		(layer "B.Cu")
		(net "GND")
	)
	(segment
		(start 291.600382 -5.621782)
		(end 291.599874 -5.621782)
		(width 0.254)
		(layer "B.Cu")
		(net "GND")
	)
	(segment
		(start 270.956532 -12.954)
		(end 272.027904 -12.954)
		(width 0.381)
		(layer "B.Cu")
		(net "GND")
	)
	(segment
		(start 242.299744 -150.231856)
		(end 242.287044 -150.219156)
		(width 0.4064)
		(layer "B.Cu")
		(net "GND")
	)
	(segment
		(start 225.201734 -17.208246)
		(end 225.299778 -17.110202)
		(width 0.4064)
		(layer "B.Cu")
		(net "GND")
	)
	(segment
		(start 370.0145 -96.9899)
		(end 370.566442 -96.437958)
		(width 0.254)
		(layer "B.Cu")
		(net "GND")
	)
	(segment
		(start 445.233806 -37.1475)
		(end 445.352678 -37.028628)
		(width 0.4064)
		(layer "B.Cu")
		(net "GND")
	)
	(segment
		(start 174.371 -88.1126)
		(end 174.371 -87.1728)
		(width 0.4064)
		(layer "B.Cu")
		(net "GND")
	)
	(segment
		(start 411.662118 -89.411302)
		(end 411.451806 -89.621614)
		(width 0.254)
		(layer "B.Cu")
		(net "GND")
	)
	(segment
		(start 295.85031 -132.876036)
		(end 295.849802 -132.875782)
		(width 0.4064)
		(layer "B.Cu")
		(net "GND")
	)
	(segment
		(start 148.699474 -128.276096)
		(end 148.699474 -129.568956)
		(width 0.4064)
		(layer "B.Cu")
		(net "GND")
	)
	(segment
		(start 380.67488 -57.0865)
		(end 380.66599 -57.07761)
		(width 0.254)
		(layer "B.Cu")
		(net "GND")
	)
	(segment
		(start 61.745368 -141.351)
		(end 61.745368 -140.694156)
		(width 0.4064)
		(layer "B.Cu")
		(net "GND")
	)
	(segment
		(start 463.32775 -126.33325)
		(end 463.4865 -126.492)
		(width 0.254)
		(layer "B.Cu")
		(net "GND")
	)
	(segment
		(start 221.04985 -1.021842)
		(end 221.04985 -2.314956)
		(width 0.4064)
		(layer "B.Cu")
		(net "GND")
	)
	(segment
		(start 229.81158 -86.97722)
		(end 231.2924 -85.4964)
		(width 0.254)
		(layer "B.Cu")
		(net "GND")
	)
	(segment
		(start 234.65028 -152.078436)
		(end 234.649772 -152.078182)
		(width 0.4064)
		(layer "B.Cu")
		(net "GND")
	)
	(segment
		(start 225.299778 -132.875782)
		(end 225.299778 -131.105656)
		(width 0.4064)
		(layer "B.Cu")
		(net "GND")
	)
	(segment
		(start 113.967768 -140.4874)
		(end 113.967768 -141.058392)
		(width 0.4064)
		(layer "B.Cu")
		(net "GND")
	)
	(segment
		(start 242.300506 -134.860284)
		(end 242.299744 -134.861046)
		(width 0.4064)
		(layer "B.Cu")
		(net "GND")
	)
	(segment
		(start 243.15039 -20.224242)
		(end 243.149882 -20.224242)
		(width 0.4064)
		(layer "B.Cu")
		(net "GND")
	)
	(segment
		(start 335.399634 -85.71484)
		(end 335.256124 -85.85835)
		(width 0.4064)
		(layer "B.Cu")
		(net "GND")
	)
	(segment
		(start 32.249364 -15.222982)
		(end 32.249364 -14.115542)
		(width 0.4064)
		(layer "B.Cu")
		(net "GND")
	)
	(segment
		(start 102.7938 -149.8092)
		(end 103.678736 -149.8092)
		(width 0.4064)
		(layer "B.Cu")
		(net "GND")
	)
	(segment
		(start 287.349946 -9.156446)
		(end 287.349946 -10.623042)
		(width 0.4064)
		(layer "B.Cu")
		(net "GND")
	)
	(segment
		(start 209.14995 -18.80235)
		(end 209.092546 -18.744946)
		(width 0.4064)
		(layer "B.Cu")
		(net "GND")
	)
	(segment
		(start 216.80043 -128.276096)
		(end 216.799922 -128.276096)
		(width 0.4064)
		(layer "B.Cu")
		(net "GND")
	)
	(segment
		(start 198.949818 -5.621782)
		(end 198.949818 -7.4676)
		(width 0.4064)
		(layer "B.Cu")
		(net "GND")
	)
	(segment
		(start 52.398168 -131.7752)
		(end 52.398168 -131.090162)
		(width 0.4064)
		(layer "B.Cu")
		(net "GND")
	)
	(segment
		(start 294.999918 -129.568956)
		(end 294.999918 -128.276096)
		(width 0.4064)
		(layer "B.Cu")
		(net "GND")
	)
	(segment
		(start 254.789432 -3.3528)
		(end 255.072388 -3.635756)
		(width 0.4064)
		(layer "B.Cu")
		(net "GND")
	)
	(segment
		(start 43.29938 -151.349964)
		(end 43.050968 -151.101552)
		(width 0.254)
		(layer "B.Cu")
		(net "GND")
	)
	(segment
		(start 300.099984 -137.877296)
		(end 300.099984 -139.157456)
		(width 0.4064)
		(layer "B.Cu")
		(net "GND")
	)
	(segment
		(start 198.772018 -3.762756)
		(end 198.7042 -3.830574)
		(width 0.254)
		(layer "B.Cu")
		(net "GND")
	)
	(segment
		(start 477.770444 -13.623036)
		(end 477.6978 -13.69568)
		(width 0.254)
		(layer "B.Cu")
		(net "GND")
	)
	(segment
		(start 223.599756 -24.580596)
		(end 223.599756 -22.965156)
		(width 0.4064)
		(layer "B.Cu")
		(net "GND")
	)
	(segment
		(start 289.899852 -3.851656)
		(end 289.810952 -3.762756)
		(width 0.4064)
		(layer "B.Cu")
		(net "GND")
	)
	(segment
		(start 223.60001 -7.606792)
		(end 223.60001 -5.621782)
		(width 0.4064)
		(layer "B.Cu")
		(net "GND")
	)
	(segment
		(start 66.24955 -24.45385)
		(end 66.24955 -24.824182)
		(width 0.4064)
		(layer "B.Cu")
		(net "GND")
	)
	(segment
		(start 231.2924 -85.4964)
		(end 231.2924 -85.2932)
		(width 0.254)
		(layer "B.Cu")
		(net "GND")
	)
	(segment
		(start 90.802968 -2.975356)
		(end 91.421712 -2.975356)
		(width 0.4064)
		(layer "B.Cu")
		(net "GND")
	)
	(segment
		(start 370.5352 -64.740028)
		(end 370.459 -64.663828)
		(width 0.254)
		(layer "B.Cu")
		(net "GND")
	)
	(segment
		(start 496.1382 -134.747)
		(end 496.6716 -134.747)
		(width 0.254)
		(layer "B.Cu")
		(net "GND")
	)
	(segment
		(start 67.949572 -17.207992)
		(end 67.949572 -15.222982)
		(width 0.4064)
		(layer "B.Cu")
		(net "GND")
	)
	(segment
		(start 370.344954 -71.800466)
		(end 370.344954 -71.894954)
		(width 0.254)
		(layer "B.Cu")
		(net "GND")
	)
	(segment
		(start 174.0916 -88.392)
		(end 174.371 -88.1126)
		(width 0.4064)
		(layer "B.Cu")
		(net "GND")
	)
	(segment
		(start 439.166254 -148.844)
		(end 438.97423 -148.651976)
		(width 0.254)
		(layer "B.Cu")
		(net "GND")
	)
	(segment
		(start 310.122062 -22.965156)
		(end 310.054244 -23.032974)
		(width 0.4064)
		(layer "B.Cu")
		(net "GND")
	)
	(segment
		(start 54.737508 -13.948156)
		(end 55.199534 -14.410182)
		(width 0.4064)
		(layer "B.Cu")
		(net "GND")
	)
	(segment
		(start 113.472722 -135.651494)
		(end 113.933478 -135.651494)
		(width 0.4064)
		(layer "B.Cu")
		(net "GND")
	)
	(segment
		(start 236.349794 -25.937972)
		(end 236.349794 -24.824182)
		(width 0.4064)
		(layer "B.Cu")
		(net "GND")
	)
	(segment
		(start 243.15039 -1.021842)
		(end 243.149882 -1.021842)
		(width 0.4064)
		(layer "B.Cu")
		(net "GND")
	)
	(segment
		(start 278.850344 -5.621782)
		(end 278.849836 -5.621782)
		(width 0.4064)
		(layer "B.Cu")
		(net "GND")
	)
	(segment
		(start 118.099332 -1.021842)
		(end 118.099332 -2.234692)
		(width 0.4064)
		(layer "B.Cu")
		(net "GND")
	)
	(segment
		(start 95.913448 2.7686)
		(end 96.578928 2.7686)
		(width 0.4064)
		(layer "B.Cu")
		(net "GND")
	)
	(segment
		(start 279.4254 -29.1592)
		(end 279.2476 -29.337)
		(width 0.254)
		(layer "B.Cu")
		(net "GND")
	)
	(segment
		(start 199.742552 -129.546096)
		(end 199.742552 -129.564892)
		(width 0.4064)
		(layer "B.Cu")
		(net "GND")
	)
	(segment
		(start 231.249728 -24.453596)
		(end 231.249728 -22.965156)
		(width 0.4064)
		(layer "B.Cu")
		(net "GND")
	)
	(segment
		(start 280.550366 -5.621782)
		(end 280.549858 -5.621782)
		(width 0.4064)
		(layer "B.Cu")
		(net "GND")
	)
	(segment
		(start 234.65028 -15.222982)
		(end 234.649772 -15.222982)
		(width 0.4064)
		(layer "B.Cu")
		(net "GND")
	)
	(segment
		(start 197.250304 -24.824182)
		(end 197.249796 -24.824182)
		(width 0.4064)
		(layer "B.Cu")
		(net "GND")
	)
	(segment
		(start 164.7952 -88.392)
		(end 164.4904 -88.392)
		(width 0.4064)
		(layer "B.Cu")
		(net "GND")
	)
	(segment
		(start 402.096478 -93.979238)
		(end 401.99564 -93.8784)
		(width 0.254)
		(layer "B.Cu")
		(net "GND")
	)
	(segment
		(start 206.501746 -17.208246)
		(end 206.59979 -17.110202)
		(width 0.4064)
		(layer "B.Cu")
		(net "GND")
	)
	(segment
		(start 215.949784 -152.078182)
		(end 215.949784 -150.308056)
		(width 0.4064)
		(layer "B.Cu")
		(net "GND")
	)
	(segment
		(start 383.3368 -115.4557)
		(end 383.3241 -115.443)
		(width 0.3556)
		(layer "B.Cu")
		(net "GND")
	)
	(segment
		(start 49.249584 -152.078436)
		(end 49.249584 -151.73325)
		(width 0.4064)
		(layer "B.Cu")
		(net "GND")
	)
	(segment
		(start 114.699542 -11.9126)
		(end 114.699542 -10.623042)
		(width 0.4064)
		(layer "B.Cu")
		(net "GND")
	)
	(segment
		(start 56.899302 -142.131796)
		(end 56.899302 -140.617956)
		(width 0.4064)
		(layer "B.Cu")
		(net "GND")
	)
	(segment
		(start 204.049884 -9.156446)
		(end 204.049884 -10.623042)
		(width 0.4064)
		(layer "B.Cu")
		(net "GND")
	)
	(segment
		(start 278.849836 -139.587986)
		(end 278.921972 -139.660122)
		(width 0.4064)
		(layer "B.Cu")
		(net "GND")
	)
	(segment
		(start 221.050358 -20.224242)
		(end 221.04985 -20.224242)
		(width 0.4064)
		(layer "B.Cu")
		(net "GND")
	)
	(segment
		(start 119.799354 -4.808982)
		(end 119.799354 -5.621782)
		(width 0.4064)
		(layer "B.Cu")
		(net "GND")
	)
	(segment
		(start 60.299346 -142.477236)
		(end 60.299346 -140.706856)
		(width 0.4064)
		(layer "B.Cu")
		(net "GND")
	)
	(segment
		(start 388.3279 -104.4702)
		(end 388.1374 -104.2797)
		(width 0.3556)
		(layer "B.Cu")
		(net "GND")
	)
	(segment
		(start 290.750498 -20.224242)
		(end 290.74999 -20.224242)
		(width 0.4064)
		(layer "B.Cu")
		(net "GND")
	)
	(segment
		(start 211.699856 -18.757646)
		(end 211.699856 -20.224242)
		(width 0.4064)
		(layer "B.Cu")
		(net "GND")
	)
	(segment
		(start 238.900462 -24.824182)
		(end 238.899954 -24.824182)
		(width 0.4064)
		(layer "B.Cu")
		(net "GND")
	)
	(segment
		(start 301.800006 -148.691092)
		(end 301.800006 -147.478496)
		(width 0.4064)
		(layer "B.Cu")
		(net "GND")
	)
	(segment
		(start 204.049884 -1.021842)
		(end 204.049884 0.444754)
		(width 0.4064)
		(layer "B.Cu")
		(net "GND")
	)
	(segment
		(start 407.67 0.2794)
		(end 407.67 -0.7366)
		(width 0.254)
		(layer "B.Cu")
		(net "GND")
	)
	(segment
		(start 211.700364 -20.224242)
		(end 211.699856 -20.224242)
		(width 0.4064)
		(layer "B.Cu")
		(net "GND")
	)
	(segment
		(start 491.21441 -55.043578)
		(end 491.21441 -55.047896)
		(width 0.4064)
		(layer "B.Cu")
		(net "GND")
	)
	(segment
		(start 311.150508 -137.877296)
		(end 311.15 -137.877296)
		(width 0.4064)
		(layer "B.Cu")
		(net "GND")
	)
	(segment
		(start 175.26 -77.9526)
		(end 175.26 -77.597)
		(width 0.381)
		(layer "B.Cu")
		(net "GND")
	)
	(segment
		(start 210.849972 -152.078182)
		(end 210.849972 -151.265382)
		(width 0.4064)
		(layer "B.Cu")
		(net "GND")
	)
	(segment
		(start 349.500952 -146.812)
		(end 349.494094 -146.805142)
		(width 0.254)
		(layer "B.Cu")
		(net "GND")
	)
	(segment
		(start 301.800514 -10.623042)
		(end 301.800006 -10.623042)
		(width 0.4064)
		(layer "B.Cu")
		(net "GND")
	)
	(segment
		(start 216.799922 -137.877296)
		(end 216.799922 -139.157456)
		(width 0.4064)
		(layer "B.Cu")
		(net "GND")
	)
	(segment
		(start 117.249448 -152.078436)
		(end 117.249448 -151.299164)
		(width 0.254)
		(layer "B.Cu")
		(net "GND")
	)
	(segment
		(start 129.999486 -1.021842)
		(end 129.999486 -2.314956)
		(width 0.4064)
		(layer "B.Cu")
		(net "GND")
	)
	(segment
		(start 136.74217 -2.292096)
		(end 136.74217 -2.310892)
		(width 0.4064)
		(layer "B.Cu")
		(net "GND")
	)
	(segment
		(start 481.0379 -146.072098)
		(end 481.0379 -146.7993)
		(width 0.254)
		(layer "B.Cu")
		(net "GND")
	)
	(segment
		(start 282.004262 -4.597146)
		(end 282.24988 -4.842764)
		(width 0.254)
		(layer "B.Cu")
		(net "GND")
	)
	(segment
		(start 309.411878 -129.568956)
		(end 309.437278 -129.568956)
		(width 0.4064)
		(layer "B.Cu")
		(net "GND")
	)
	(segment
		(start 481.0379 -146.7993)
		(end 480.4664 -147.3708)
		(width 0.254)
		(layer "B.Cu")
		(net "GND")
	)
	(segment
		(start 69.64934 -142.477236)
		(end 69.64934 -140.706856)
		(width 0.4064)
		(layer "B.Cu")
		(net "GND")
	)
	(segment
		(start 145.053812 -140.685774)
		(end 145.12163 -140.617956)
		(width 0.4064)
		(layer "B.Cu")
		(net "GND")
	)
	(segment
		(start 213.400386 -128.276096)
		(end 213.399878 -128.276096)
		(width 0.4064)
		(layer "B.Cu")
		(net "GND")
	)
	(segment
		(start 71.095362 -131.7498)
		(end 71.095362 -131.092956)
		(width 0.4064)
		(layer "B.Cu")
		(net "GND")
	)
	(segment
		(start 224.450402 -1.021842)
		(end 224.449894 -1.021842)
		(width 0.4064)
		(layer "B.Cu")
		(net "GND")
	)
	(segment
		(start 279.699974 -139.170156)
		(end 279.699974 -137.877296)
		(width 0.4064)
		(layer "B.Cu")
		(net "GND")
	)
	(segment
		(start 78.714854 -87.784686)
		(end 78.338172 -87.784686)
		(width 0.254)
		(layer "B.Cu")
		(net "GND")
	)
	(segment
		(start 500.6848 -38.735)
		(end 500.661686 -38.711886)
		(width 0.254)
		(layer "B.Cu")
		(net "GND")
	)
	(segment
		(start 209.150458 -128.276096)
		(end 209.14995 -128.276096)
		(width 0.4064)
		(layer "B.Cu")
		(net "GND")
	)
	(segment
		(start 307.749956 0.457454)
		(end 307.749956 -1.021842)
		(width 0.4064)
		(layer "B.Cu")
		(net "GND")
	)
	(segment
		(start 138.499342 -5.621782)
		(end 138.499342 -4.808728)
		(width 0.4064)
		(layer "B.Cu")
		(net "GND")
	)
	(segment
		(start 364.321852 -44.837858)
		(end 365.549942 -44.837858)
		(width 0.254)
		(layer "B.Cu")
		(net "GND")
	)
	(segment
		(start 268.679168 -8.1534)
		(end 267.794232 -8.1534)
		(width 0.381)
		(layer "B.Cu")
		(net "GND")
	)
	(segment
		(start 42.436796 -21.517356)
		(end 42.411396 -21.517356)
		(width 0.4064)
		(layer "B.Cu")
		(net "GND")
	)
	(segment
		(start 290.71189 -139.170156)
		(end 290.73729 -139.170156)
		(width 0.4064)
		(layer "B.Cu")
		(net "GND")
	)
	(segment
		(start 444.9572 -35.9918)
		(end 445.0715 -35.8775)
		(width 0.4064)
		(layer "B.Cu")
		(net "GND")
	)
	(segment
		(start 312.849768 -16.238474)
		(end 312.849768 -15.222982)
		(width 0.4064)
		(layer "B.Cu")
		(net "GND")
	)
	(segment
		(start 244.25402 -86.57336)
		(end 243.88953 -86.57336)
		(width 0.254)
		(layer "B.Cu")
		(net "GND")
	)
	(segment
		(start 233.799888 -21.517356)
		(end 233.799888 -20.224242)
		(width 0.4064)
		(layer "B.Cu")
		(net "GND")
	)
	(segment
		(start 117.249448 -132.876036)
		(end 117.249448 -132.148326)
		(width 0.3556)
		(layer "B.Cu")
		(net "GND")
	)
	(segment
		(start 311.15 -128.276096)
		(end 311.15 -129.488692)
		(width 0.4064)
		(layer "B.Cu")
		(net "GND")
	)
	(segment
		(start 220.200474 -24.824182)
		(end 220.199966 -24.824182)
		(width 0.4064)
		(layer "B.Cu")
		(net "GND")
	)
	(segment
		(start 231.249728 -5.251196)
		(end 231.249728 -3.762756)
		(width 0.4064)
		(layer "B.Cu")
		(net "GND")
	)
	(segment
		(start 375.9835 -45.72)
		(end 376.560842 -45.72)
		(width 0.254)
		(layer "B.Cu")
		(net "GND")
	)
	(segment
		(start 384.554984 -102.756716)
		(end 384.8227 -102.489)
		(width 0.3556)
		(layer "B.Cu")
		(net "GND")
	)
	(segment
		(start 135.703818 -141.3764)
		(end 135.703818 -140.685774)
		(width 0.4064)
		(layer "B.Cu")
		(net "GND")
	)
	(segment
		(start 242.299998 -151.65705)
		(end 242.299744 -151.656796)
		(width 0.4064)
		(layer "B.Cu")
		(net "GND")
	)
	(segment
		(start 205.750414 -147.478496)
		(end 205.749906 -147.478496)
		(width 0.4064)
		(layer "B.Cu")
		(net "GND")
	)
	(segment
		(start 215.0999 -128.276096)
		(end 215.0999 -129.568956)
		(width 0.4064)
		(layer "B.Cu")
		(net "GND")
	)
	(segment
		(start 66.24955 -142.477236)
		(end 66.24955 -142.10665)
		(width 0.4064)
		(layer "B.Cu")
		(net "GND")
	)
	(segment
		(start 144.411446 -11.916156)
		(end 144.436846 -11.916156)
		(width 0.4064)
		(layer "B.Cu")
		(net "GND")
	)
	(segment
		(start 279.699974 -137.877042)
		(end 279.699974 -136.397746)
		(width 0.508)
		(layer "B.Cu")
		(net "GND")
	)
	(segment
		(start 198.099934 -148.758656)
		(end 198.087234 -148.771356)
		(width 0.4064)
		(layer "B.Cu")
		(net "GND")
	)
	(segment
		(start 370.459 -64.663828)
		(end 370.459 -64.008)
		(width 0.254)
		(layer "B.Cu")
		(net "GND")
	)
	(segment
		(start 466.182202 -8.37692)
		(end 465.641944 -8.37692)
		(width 0.254)
		(layer "B.Cu")
		(net "GND")
	)
	(segment
		(start 196.342 0.515366)
		(end 196.342 1.524)
		(width 0.381)
		(layer "B.Cu")
		(net "GND")
	)
	(segment
		(start 198.949818 -17.0688)
		(end 198.772018 -17.2466)
		(width 0.4064)
		(layer "B.Cu")
		(net "GND")
	)
	(segment
		(start 487.1085 -153.0985)
		(end 487.1085 -152.5016)
		(width 0.254)
		(layer "B.Cu")
		(net "GND")
	)
	(segment
		(start 371.641624 -74.694288)
		(end 371.945154 -74.997818)
		(width 0.254)
		(layer "B.Cu")
		(net "GND")
	)
	(segment
		(start 195.550282 -5.621782)
		(end 195.549774 -5.621782)
		(width 0.4064)
		(layer "B.Cu")
		(net "GND")
	)
	(segment
		(start 140.199364 -25.645872)
		(end 139.34948 -26.495756)
		(width 0.4064)
		(layer "B.Cu")
		(net "GND")
	)
	(segment
		(start 283.04236 -148.748496)
		(end 283.04236 -148.767292)
		(width 0.4064)
		(layer "B.Cu")
		(net "GND")
	)
	(segment
		(start 221.899988 -17.207992)
		(end 221.899988 -15.222982)
		(width 0.4064)
		(layer "B.Cu")
		(net "GND")
	)
	(segment
		(start 67.949572 -152.078436)
		(end 67.949572 -151.78405)
		(width 0.4064)
		(layer "B.Cu")
		(net "GND")
	)
	(segment
		(start 242.299998 -142.476982)
		(end 242.299998 -142.477236)
		(width 0.508)
		(layer "B.Cu")
		(net "GND")
	)
	(segment
		(start 236.095794 -150.295356)
		(end 236.171994 -150.219156)
		(width 0.4064)
		(layer "B.Cu")
		(net "GND")
	)
	(segment
		(start 496.326414 -39.651686)
		(end 497.299996 -39.651686)
		(width 0.254)
		(layer "B.Cu")
		(net "GND")
	)
	(segment
		(start 311.092596 -148.767292)
		(end 311.092596 -148.748496)
		(width 0.4064)
		(layer "B.Cu")
		(net "GND")
	)
	(segment
		(start 409.116784 -9.411716)
		(end 409.116784 -9.052306)
		(width 0.254)
		(layer "B.Cu")
		(net "GND")
	)
	(segment
		(start 149.549358 -3.762756)
		(end 149.549358 -5.621782)
		(width 0.4064)
		(layer "B.Cu")
		(net "GND")
	)
	(segment
		(start 239.750346 -137.877296)
		(end 239.749838 -137.877296)
		(width 0.4064)
		(layer "B.Cu")
		(net "GND")
	)
	(segment
		(start 317.627 1.928368)
		(end 317.400432 1.7018)
		(width 0.4064)
		(layer "B.Cu")
		(net "GND")
	)
	(segment
		(start 303.500282 -142.477236)
		(end 303.499774 -142.476982)
		(width 0.4064)
		(layer "B.Cu")
		(net "GND")
	)
	(segment
		(start 196.399912 -1.021842)
		(end 196.399912 0.457454)
		(width 0.4064)
		(layer "B.Cu")
		(net "GND")
	)
	(segment
		(start 308.600348 -132.876036)
		(end 308.59984 -132.875782)
		(width 0.4064)
		(layer "B.Cu")
		(net "GND")
	)
	(segment
		(start 169.926 -86.868)
		(end 169.6212 -86.868)
		(width 0.4064)
		(layer "B.Cu")
		(net "GND")
	)
	(segment
		(start 283.04236 -139.166092)
		(end 283.04236 -139.147296)
		(width 0.4064)
		(layer "B.Cu")
		(net "GND")
	)
	(segment
		(start 444.7286 -129.377186)
		(end 445.2366 -129.377186)
		(width 0.254)
		(layer "B.Cu")
		(net "GND")
	)
	(segment
		(start 124.89942 -142.477236)
		(end 124.89942 -140.706856)
		(width 0.4064)
		(layer "B.Cu")
		(net "GND")
	)
	(segment
		(start 124.81052 -22.965156)
		(end 124.89942 -23.054056)
		(width 0.4064)
		(layer "B.Cu")
		(net "GND")
	)
	(segment
		(start 16.2052 -83.6168)
		(end 16.0782 -83.7438)
		(width 0.254)
		(layer "B.Cu")
		(net "GND")
	)
	(segment
		(start 279.699974 -20.224242)
		(end 279.699974 -21.517356)
		(width 0.4064)
		(layer "B.Cu")
		(net "GND")
	)
	(segment
		(start 152.099518 -128.276096)
		(end 152.099518 -129.579878)
		(width 0.4064)
		(layer "B.Cu")
		(net "GND")
	)
	(segment
		(start 294.14978 -16.238474)
		(end 294.14978 -15.222982)
		(width 0.4064)
		(layer "B.Cu")
		(net "GND")
	)
	(segment
		(start 307.749956 -9.143746)
		(end 307.749956 -10.623042)
		(width 0.4064)
		(layer "B.Cu")
		(net "GND")
	)
	(segment
		(start 390.737598 -152.625298)
		(end 390.67994 -152.56764)
		(width 0.254)
		(layer "B.Cu")
		(net "GND")
	)
	(segment
		(start 288.200338 -132.876036)
		(end 288.19983 -132.875782)
		(width 0.4064)
		(layer "B.Cu")
		(net "GND")
	)
	(segment
		(start 316.25032 -142.477236)
		(end 316.249812 -142.476982)
		(width 0.4064)
		(layer "B.Cu")
		(net "GND")
	)
	(segment
		(start 143.599408 -150.42896)
		(end 143.809212 -150.219156)
		(width 0.4064)
		(layer "B.Cu")
		(net "GND")
	)
	(segment
		(start 300.772068 -131.016756)
		(end 300.70425 -131.084574)
		(width 0.4064)
		(layer "B.Cu")
		(net "GND")
	)
	(segment
		(start 62.792102 -9.143746)
		(end 62.849506 -9.20115)
		(width 0.4064)
		(layer "B.Cu")
		(net "GND")
	)
	(segment
		(start 222.749872 -20.224242)
		(end 222.749872 -18.757646)
		(width 0.4064)
		(layer "B.Cu")
		(net "GND")
	)
	(segment
		(start 197.249796 -4.514342)
		(end 197.160896 -4.425442)
		(width 0.4064)
		(layer "B.Cu")
		(net "GND")
	)
	(segment
		(start 301.800514 -1.021842)
		(end 301.800006 -1.021842)
		(width 0.4064)
		(layer "B.Cu")
		(net "GND")
	)
	(segment
		(start 458.422756 -21.985478)
		(end 457.7842 -22.624034)
		(width 0.254)
		(layer "B.Cu")
		(net "GND")
	)
	(segment
		(start 278.849836 -144.5768)
		(end 278.849836 -142.477236)
		(width 0.508)
		(layer "B.Cu")
		(net "GND")
	)
	(segment
		(start 282.250388 -5.621782)
		(end 282.24988 -5.621782)
		(width 0.254)
		(layer "B.Cu")
		(net "GND")
	)
	(segment
		(start 306.900326 -142.477236)
		(end 306.899818 -142.476982)
		(width 0.4064)
		(layer "B.Cu")
		(net "GND")
	)
	(segment
		(start 270.956532 -140.208)
		(end 272.027904 -140.208)
		(width 0.4572)
		(layer "B.Cu")
		(net "GND")
	)
	(segment
		(start 47.549562 -142.18285)
		(end 47.549308 -142.182596)
		(width 0.4064)
		(layer "B.Cu")
		(net "GND")
	)
	(segment
		(start 65.399412 -128.276096)
		(end 65.399412 -129.568956)
		(width 0.4064)
		(layer "B.Cu")
		(net "GND")
	)
	(segment
		(start 174.0662 -86.868)
		(end 173.736 -86.868)
		(width 0.4064)
		(layer "B.Cu")
		(net "GND")
	)
	(segment
		(start 257.048 -18.0086)
		(end 257.5814 -18.542)
		(width 0.4064)
		(layer "B.Cu")
		(net "GND")
	)
	(segment
		(start 127.44958 -10.623042)
		(end 127.44958 -11.835892)
		(width 0.4064)
		(layer "B.Cu")
		(net "GND")
	)
	(segment
		(start 317.09995 -18.757646)
		(end 317.146432 -18.711164)
		(width 0.4064)
		(layer "B.Cu")
		(net "GND")
	)
	(segment
		(start 117.249448 -17.0688)
		(end 117.249448 -15.222982)
		(width 0.4064)
		(layer "B.Cu")
		(net "GND")
	)
	(segment
		(start 280.549858 -15.222982)
		(end 280.549858 -17.110202)
		(width 0.4064)
		(layer "B.Cu")
		(net "GND")
	)
	(segment
		(start 300.061884 -11.916156)
		(end 300.061884 -12.916916)
		(width 0.4064)
		(layer "B.Cu")
		(net "GND")
	)
	(segment
		(start 39.049452 -137.877296)
		(end 39.049452 -139.170156)
		(width 0.4064)
		(layer "B.Cu")
		(net "GND")
	)
	(segment
		(start 229.54996 -132.062982)
		(end 229.087934 -131.600956)
		(width 0.4064)
		(layer "B.Cu")
		(net "GND")
	)
	(segment
		(start 233.799888 -128.276096)
		(end 233.799888 -129.568956)
		(width 0.4064)
		(layer "B.Cu")
		(net "GND")
	)
	(segment
		(start 66.24955 -132.50545)
		(end 66.249296 -132.505196)
		(width 0.4064)
		(layer "B.Cu")
		(net "GND")
	)
	(segment
		(start 400.14398 -77.64272)
		(end 400.71675 -77.06995)
		(width 0.254)
		(layer "B.Cu")
		(net "GND")
	)
	(segment
		(start 235.500418 -128.276096)
		(end 235.49991 -128.276096)
		(width 0.4064)
		(layer "B.Cu")
		(net "GND")
	)
	(segment
		(start 45.84954 -151.265382)
		(end 45.387514 -150.803356)
		(width 0.4064)
		(layer "B.Cu")
		(net "GND")
	)
	(segment
		(start 229.091236 -26.682954)
		(end 229.54996 -26.22423)
		(width 0.4064)
		(layer "B.Cu")
		(net "GND")
	)
	(segment
		(start 290.74999 -26.495756)
		(end 291.599874 -25.645872)
		(width 0.4064)
		(layer "B.Cu")
		(net "GND")
	)
	(segment
		(start 26.769568 -145.3642)
		(end 26.769568 -145.9992)
		(width 0.4064)
		(layer "B.Cu")
		(net "GND")
	)
	(segment
		(start 143.599408 -152.078436)
		(end 143.599408 -150.42896)
		(width 0.4064)
		(layer "B.Cu")
		(net "GND")
	)
	(segment
		(start 281.361896 -129.568956)
		(end 281.387296 -129.568956)
		(width 0.4064)
		(layer "B.Cu")
		(net "GND")
	)
	(segment
		(start 72.1995 -9.20115)
		(end 72.1995 -10.623042)
		(width 0.4064)
		(layer "B.Cu")
		(net "GND")
	)
	(segment
		(start 205.749906 -18.744946)
		(end 205.749906 -20.224242)
		(width 0.4064)
		(layer "B.Cu")
		(net "GND")
	)
	(segment
		(start 424.0403 -5.9055)
		(end 422.91 -5.9055)
		(width 0.254)
		(layer "B.Cu")
		(net "GND")
	)
	(segment
		(start 369.488466 -77.494892)
		(end 369.545108 -77.494892)
		(width 0.254)
		(layer "B.Cu")
		(net "GND")
	)
	(segment
		(start 61.745368 -141.4526)
		(end 61.745368 -141.351)
		(width 0.254)
		(layer "B.Cu")
		(net "GND")
	)
	(segment
		(start 222.749872 -2.314956)
		(end 222.749872 -1.021842)
		(width 0.4064)
		(layer "B.Cu")
		(net "GND")
	)
	(segment
		(start 214.250016 -24.824182)
		(end 214.250016 -24.47925)
		(width 0.4064)
		(layer "B.Cu")
		(net "GND")
	)
	(segment
		(start 421.680132 -137.044938)
		(end 422.389554 -137.044938)
		(width 0.254)
		(layer "B.Cu")
		(net "GND")
	)
	(segment
		(start 62.792102 -129.546096)
		(end 62.792102 -129.564892)
		(width 0.4064)
		(layer "B.Cu")
		(net "GND")
	)
	(segment
		(start 231.25049 -132.876036)
		(end 231.249982 -132.875782)
		(width 0.4064)
		(layer "B.Cu")
		(net "GND")
	)
	(segment
		(start 56.899302 -14.877796)
		(end 56.899556 -14.87805)
		(width 0.4064)
		(layer "B.Cu")
		(net "GND")
	)
	(segment
		(start 31.341568 -144.977612)
		(end 31.341568 -145.941034)
		(width 0.4064)
		(layer "B.Cu")
		(net "GND")
	)
	(segment
		(start 221.04985 0.444754)
		(end 221.04985 -1.021842)
		(width 0.4064)
		(layer "B.Cu")
		(net "GND")
	)
	(segment
		(start 409.116784 -9.052306)
		(end 408.827478 -8.763)
		(width 0.254)
		(layer "B.Cu")
		(net "GND")
	)
	(segment
		(start 136.799574 -147.478496)
		(end 136.799574 -148.691092)
		(width 0.4064)
		(layer "B.Cu")
		(net "GND")
	)
	(segment
		(start 191.314832 -8.460232)
		(end 191.314832 -8.122412)
		(width 0.254)
		(layer "B.Cu")
		(net "GND")
	)
	(segment
		(start 493.653572 -132.631942)
		(end 493.653572 -133.223)
		(width 0.254)
		(layer "B.Cu")
		(net "GND")
	)
	(segment
		(start 132.549392 -22.965156)
		(end 132.549392 -24.824182)
		(width 0.4064)
		(layer "B.Cu")
		(net "GND")
	)
	(segment
		(start 229.81158 -87.27567)
		(end 229.81158 -86.97722)
		(width 0.254)
		(layer "B.Cu")
		(net "GND")
	)
	(segment
		(start 30.147768 -134.4168)
		(end 29.690568 -134.874)
		(width 0.4064)
		(layer "B.Cu")
		(net "GND")
	)
	(segment
		(start 437.690006 -41.203626)
		(end 437.690006 -40.5257)
		(width 0.3556)
		(layer "B.Cu")
		(net "GND")
	)
	(segment
		(start 295.85031 -152.078436)
		(end 295.85031 -150.219664)
		(width 0.4064)
		(layer "B.Cu")
		(net "GND")
	)
	(segment
		(start 196.4436 -136.354058)
		(end 196.399912 -136.397746)
		(width 0.4064)
		(layer "B.Cu")
		(net "GND")
	)
	(segment
		(start 289.899852 -142.476982)
		(end 289.899852 -140.706856)
		(width 0.4064)
		(layer "B.Cu")
		(net "GND")
	)
	(segment
		(start 291.354256 -150.286974)
		(end 291.422074 -150.219156)
		(width 0.4064)
		(layer "B.Cu")
		(net "GND")
	)
	(segment
		(start 72.142096 -129.546096)
		(end 72.142096 -129.564892)
		(width 0.4064)
		(layer "B.Cu")
		(net "GND")
	)
	(segment
		(start 49.249584 -151.73325)
		(end 49.24933 -151.732996)
		(width 0.4064)
		(layer "B.Cu")
		(net "GND")
	)
	(segment
		(start 362.8136 -58.6486)
		(end 362.8136 -57.404)
		(width 0.254)
		(layer "B.Cu")
		(net "GND")
	)
	(segment
		(start 34.799524 -139.089892)
		(end 34.74212 -139.147296)
		(width 0.4064)
		(layer "B.Cu")
		(net "GND")
	)
	(segment
		(start 237.199932 -2.234692)
		(end 237.199932 -1.021842)
		(width 0.4064)
		(layer "B.Cu")
		(net "GND")
	)
	(segment
		(start 289.049968 -20.224242)
		(end 289.049968 -18.744946)
		(width 0.4064)
		(layer "B.Cu")
		(net "GND")
	)
	(segment
		(start 204.049884 -128.276096)
		(end 204.049884 -129.568956)
		(width 0.4064)
		(layer "B.Cu")
		(net "GND")
	)
	(segment
		(start 310.299862 -7.4676)
		(end 310.299862 -5.621782)
		(width 0.4064)
		(layer "B.Cu")
		(net "GND")
	)
	(segment
		(start 229.54996 -24.824182)
		(end 229.54996 -24.011382)
		(width 0.4064)
		(layer "B.Cu")
		(net "GND")
	)
	(segment
		(start 261.7216 -6.6421)
		(end 261.7216 -5.8928)
		(width 0.508)
		(layer "B.Cu")
		(net "GND")
	)
	(segment
		(start 267.794232 -149.8092)
		(end 268.679168 -149.8092)
		(width 0.4572)
		(layer "B.Cu")
		(net "GND")
	)
	(segment
		(start 445.687196 -38.39591)
		(end 445.792606 -38.2905)
		(width 0.4064)
		(layer "B.Cu")
		(net "GND")
	)
	(segment
		(start 242.299998 -142.05585)
		(end 242.299998 -142.476982)
		(width 0.4064)
		(layer "B.Cu")
		(net "GND")
	)
	(segment
		(start 442.262006 -40.5257)
		(end 442.262006 -41.203626)
		(width 0.3556)
		(layer "B.Cu")
		(net "GND")
	)
	(segment
		(start 78.14945 -128.275842)
		(end 78.14945 -128.276096)
		(width 0.4064)
		(layer "B.Cu")
		(net "GND")
	)
	(segment
		(start 116.386864 -148.771356)
		(end 116.361464 -148.771356)
		(width 0.4064)
		(layer "B.Cu")
		(net "GND")
	)
	(segment
		(start 218.44254 -11.893296)
		(end 218.44254 -11.912092)
		(width 0.4064)
		(layer "B.Cu")
		(net "GND")
	)
	(segment
		(start 172.136816 -86.868)
		(end 171.852844 -87.151972)
		(width 0.4064)
		(layer "B.Cu")
		(net "GND")
	)
	(segment
		(start 453.24141 -3.852672)
		(end 453.24141 -3.029204)
		(width 0.254)
		(layer "B.Cu")
		(net "GND")
	)
	(segment
		(start 45.387514 -4.346956)
		(end 45.84954 -4.808982)
		(width 0.4064)
		(layer "B.Cu")
		(net "GND")
	)
	(segment
		(start 127.44958 -139.089892)
		(end 127.392176 -139.147296)
		(width 0.4064)
		(layer "B.Cu")
		(net "GND")
	)
	(segment
		(start 70.499478 -148.733256)
		(end 70.461378 -148.771356)
		(width 0.4064)
		(layer "B.Cu")
		(net "GND")
	)
	(segment
		(start 217.650314 -132.876036)
		(end 217.649806 -132.875782)
		(width 0.254)
		(layer "B.Cu")
		(net "GND")
	)
	(segment
		(start 452.6788 -5.5118)
		(end 453.24141 -4.94919)
		(width 0.254)
		(layer "B.Cu")
		(net "GND")
	)
	(segment
		(start 376.93981 -48.30699)
		(end 376.418348 -48.30699)
		(width 0.254)
		(layer "B.Cu")
		(net "GND")
	)
	(segment
		(start 119.799354 -142.477236)
		(end 119.799354 -141.664182)
		(width 0.4064)
		(layer "B.Cu")
		(net "GND")
	)
	(segment
		(start 232.099866 -10.623042)
		(end 232.099866 -11.916156)
		(width 0.4064)
		(layer "B.Cu")
		(net "GND")
	)
	(segment
		(start 194.53733 -144.37487)
		(end 194.437 -144.4752)
		(width 0.4064)
		(layer "B.Cu")
		(net "GND")
	)
	(segment
		(start 60.299346 -15.222982)
		(end 60.299346 -13.452856)
		(width 0.4064)
		(layer "B.Cu")
		(net "GND")
	)
	(segment
		(start 58.599578 -5.37845)
		(end 58.599578 -5.621782)
		(width 0.4064)
		(layer "B.Cu")
		(net "GND")
	)
	(segment
		(start 96.04248 -140.04544)
		(end 96.00692 -140.00988)
		(width 0.508)
		(layer "B.Cu")
		(net "GND")
	)
	(segment
		(start 282.07208 -17.2466)
		(end 282.24988 -17.0688)
		(width 0.4064)
		(layer "B.Cu")
		(net "GND")
	)
	(segment
		(start 116.386864 -139.170156)
		(end 116.361464 -139.170156)
		(width 0.4064)
		(layer "B.Cu")
		(net "GND")
	)
	(segment
		(start 145.12163 -3.762756)
		(end 145.053812 -3.830574)
		(width 0.4064)
		(layer "B.Cu")
		(net "GND")
	)
	(segment
		(start 90.18651 -17.35709)
		(end 90.874088 -17.35709)
		(width 0.4064)
		(layer "B.Cu")
		(net "GND")
	)
	(segment
		(start 247.4595 -3.3528)
		(end 246.5832 -3.3528)
		(width 0.4572)
		(layer "B.Cu")
		(net "GND")
	)
	(segment
		(start 475.2086 -45.6438)
		(end 475.234 -45.6692)
		(width 0.508)
		(layer "B.Cu")
		(net "GND")
	)
	(segment
		(start 289.050476 -147.478496)
		(end 289.049968 -147.478496)
		(width 0.4064)
		(layer "B.Cu")
		(net "GND")
	)
	(segment
		(start 218.499944 -2.234692)
		(end 218.44254 -2.292096)
		(width 0.4064)
		(layer "B.Cu")
		(net "GND")
	)
	(segment
		(start 135.099552 -9.156446)
		(end 135.099552 -10.623042)
		(width 0.4064)
		(layer "B.Cu")
		(net "GND")
	)
	(segment
		(start 483.6795 -141.4145)
		(end 484.7209 -141.4145)
		(width 0.254)
		(layer "B.Cu")
		(net "GND")
	)
	(segment
		(start 377.6218 -47.625)
		(end 376.93981 -48.30699)
		(width 0.254)
		(layer "B.Cu")
		(net "GND")
	)
	(segment
		(start 43.29938 -152.078436)
		(end 43.29938 -151.349964)
		(width 0.254)
		(layer "B.Cu")
		(net "GND")
	)
	(segment
		(start 220.200474 -5.621782)
		(end 220.199966 -5.621782)
		(width 0.4064)
		(layer "B.Cu")
		(net "GND")
	)
	(segment
		(start 406.7048 -54.356)
		(end 406.387046 -54.673754)
		(width 0.254)
		(layer "B.Cu")
		(net "GND")
	)
	(segment
		(start 242.299998 -5.621782)
		(end 242.299998 -3.76301)
		(width 0.4064)
		(layer "B.Cu")
		(net "GND")
	)
	(segment
		(start 226.137216 -148.771356)
		(end 226.111816 -148.771356)
		(width 0.4064)
		(layer "B.Cu")
		(net "GND")
	)
	(segment
		(start 291.354256 -151.053546)
		(end 291.354256 -150.9776)
		(width 0.254)
		(layer "B.Cu")
		(net "GND")
	)
	(segment
		(start 52.398168 -141.427454)
		(end 52.398168 -141.3764)
		(width 0.254)
		(layer "B.Cu")
		(net "GND")
	)
	(segment
		(start 204.900276 -132.876036)
		(end 204.899768 -132.875782)
		(width 0.4064)
		(layer "B.Cu")
		(net "GND")
	)
	(segment
		(start 377.94692 -109.928914)
		(end 377.589288 -109.928914)
		(width 0.254)
		(layer "B.Cu")
		(net "GND")
	)
	(segment
		(start 283.100272 -147.478496)
		(end 283.099764 -147.478496)
		(width 0.4064)
		(layer "B.Cu")
		(net "GND")
	)
	(segment
		(start 113.944146 -18.691606)
		(end 113.849404 -18.786348)
		(width 0.4064)
		(layer "B.Cu")
		(net "GND")
	)
	(segment
		(start 133.39953 -147.478496)
		(end 133.39953 -148.771356)
		(width 0.4064)
		(layer "B.Cu")
		(net "GND")
	)
	(segment
		(start 143.599408 -17.110202)
		(end 143.501364 -17.208246)
		(width 0.4064)
		(layer "B.Cu")
		(net "GND")
	)
	(segment
		(start 132.549392 -25.661112)
		(end 133.384036 -26.495756)
		(width 0.4064)
		(layer "B.Cu")
		(net "GND")
	)
	(segment
		(start 77.299566 -7.606792)
		(end 77.299312 -7.607046)
		(width 0.4064)
		(layer "B.Cu")
		(net "GND")
	)
	(segment
		(start 197.249796 -14.115542)
		(end 197.160896 -14.026642)
		(width 0.4064)
		(layer "B.Cu")
		(net "GND")
	)
	(segment
		(start 50.949352 -24.824182)
		(end 50.949352 -23.054056)
		(width 0.4064)
		(layer "B.Cu")
		(net "GND")
	)
	(segment
		(start 129.999486 -147.478496)
		(end 129.999486 -148.771356)
		(width 0.4064)
		(layer "B.Cu")
		(net "GND")
	)
	(segment
		(start 373.565166 -61.282834)
		(end 373.565166 -61.098938)
		(width 0.254)
		(layer "B.Cu")
		(net "GND")
	)
	(segment
		(start 36.499546 -14.410182)
		(end 36.499546 -15.222982)
		(width 0.4064)
		(layer "B.Cu")
		(net "GND")
	)
	(segment
		(start 207.437228 -129.568956)
		(end 207.411828 -129.568956)
		(width 0.4064)
		(layer "B.Cu")
		(net "GND")
	)
	(segment
		(start 259.8928 -155.1178)
		(end 260.0198 -155.2448)
		(width 0.4064)
		(layer "B.Cu")
		(net "GND")
	)
	(segment
		(start 114.83848 -125.78588)
		(end 114.5413 -126.08306)
		(width 0.508)
		(layer "B.Cu")
		(net "GND")
	)
	(segment
		(start 433.85232 -12.01928)
		(end 432.6255 -12.01928)
		(width 0.254)
		(layer "B.Cu")
		(net "GND")
	)
	(segment
		(start 464.521296 -141.646402)
		(end 464.486498 -141.6812)
		(width 0.254)
		(layer "B.Cu")
		(net "GND")
	)
	(segment
		(start 311.092596 -129.546096)
		(end 311.092596 -129.564892)
		(width 0.4064)
		(layer "B.Cu")
		(net "GND")
	)
	(segment
		(start 217.3986 -14.1224)
		(end 217.3986 -13.437362)
		(width 0.4064)
		(layer "B.Cu")
		(net "GND")
	)
	(segment
		(start 214.250016 -132.875782)
		(end 214.250016 -132.53085)
		(width 0.4064)
		(layer "B.Cu")
		(net "GND")
	)
	(segment
		(start 125.749558 -148.758656)
		(end 125.736858 -148.771356)
		(width 0.4064)
		(layer "B.Cu")
		(net "GND")
	)
	(segment
		(start 51.78679 -139.170156)
		(end 51.76139 -139.170156)
		(width 0.4064)
		(layer "B.Cu")
		(net "GND")
	)
	(segment
		(start 34.74212 -2.292096)
		(end 34.799524 -2.234692)
		(width 0.4064)
		(layer "B.Cu")
		(net "GND")
	)
	(segment
		(start 298.399962 -21.517356)
		(end 298.399962 -20.224242)
		(width 0.4064)
		(layer "B.Cu")
		(net "GND")
	)
	(segment
		(start 236.349794 -5.621782)
		(end 236.349794 -4.8514)
		(width 0.254)
		(layer "B.Cu")
		(net "GND")
	)
	(segment
		(start 295.000426 -147.478496)
		(end 294.999918 -147.478496)
		(width 0.4064)
		(layer "B.Cu")
		(net "GND")
	)
	(segment
		(start 231.25049 -152.078436)
		(end 231.249982 -152.078182)
		(width 0.4064)
		(layer "B.Cu")
		(net "GND")
	)
	(segment
		(start 424.2943 -2.965958)
		(end 424.2943 -5.6515)
		(width 0.254)
		(layer "B.Cu")
		(net "GND")
	)
	(segment
		(start 424.2943 -5.6515)
		(end 424.0403 -5.9055)
		(width 0.254)
		(layer "B.Cu")
		(net "GND")
	)
	(segment
		(start 47.549308 -132.581396)
		(end 47.549308 -131.016756)
		(width 0.4064)
		(layer "B.Cu")
		(net "GND")
	)
	(segment
		(start 68.799456 -147.478496)
		(end 68.799456 -148.771356)
		(width 0.4064)
		(layer "B.Cu")
		(net "GND")
	)
	(segment
		(start 235.49991 -129.530856)
		(end 235.46181 -129.568956)
		(width 0.4064)
		(layer "B.Cu")
		(net "GND")
	)
	(segment
		(start 214.250524 -142.477236)
		(end 214.250016 -142.476982)
		(width 0.4064)
		(layer "B.Cu")
		(net "GND")
	)
	(segment
		(start 404.204424 -31.912052)
		(end 404.846028 -31.912052)
		(width 0.254)
		(layer "B.Cu")
		(net "GND")
	)
	(segment
		(start 71.349362 -25.937972)
		(end 72.1487 -26.73731)
		(width 0.4064)
		(layer "B.Cu")
		(net "GND")
	)
	(segment
		(start 230.399844 -10.623042)
		(end 230.399844 -9.156446)
		(width 0.4064)
		(layer "B.Cu")
		(net "GND")
	)
	(segment
		(start 317.09995 -21.528278)
		(end 317.09995 -20.224242)
		(width 0.4064)
		(layer "B.Cu")
		(net "GND")
	)
	(segment
		(start 311.15 -2.234692)
		(end 311.092596 -2.292096)
		(width 0.4064)
		(layer "B.Cu")
		(net "GND")
	)
	(segment
		(start 272.415 4.318)
		(end 272.415 4.064)
		(width 0.381)
		(layer "B.Cu")
		(net "GND")
	)
	(segment
		(start 225.300286 -24.824182)
		(end 225.299778 -24.824182)
		(width 0.4064)
		(layer "B.Cu")
		(net "GND")
	)
	(segment
		(start 289.899852 -23.054056)
		(end 289.899852 -24.824182)
		(width 0.4064)
		(layer "B.Cu")
		(net "GND")
	)
	(segment
		(start 427.5836 -17.272)
		(end 426.5676 -18.288)
		(width 0.254)
		(layer "B.Cu")
		(net "GND")
	)
	(segment
		(start 140.199364 -5.621782)
		(end 140.199364 -7.607046)
		(width 0.4064)
		(layer "B.Cu")
		(net "GND")
	)
	(segment
		(start 77.299566 -5.621782)
		(end 77.299566 -7.606792)
		(width 0.4064)
		(layer "B.Cu")
		(net "GND")
	)
	(segment
		(start 393.65047 -105.78211)
		(end 393.726416 -105.78211)
		(width 0.254)
		(layer "B.Cu")
		(net "GND")
	)
	(segment
		(start 395.5542 -63.627)
		(end 395.8082 -63.373)
		(width 0.254)
		(layer "B.Cu")
		(net "GND")
	)
	(segment
		(start 67.949572 -25.638252)
		(end 68.799456 -26.488136)
		(width 0.4064)
		(layer "B.Cu")
		(net "GND")
	)
	(segment
		(start 31.39948 -11.916156)
		(end 31.39948 -10.623042)
		(width 0.4064)
		(layer "B.Cu")
		(net "GND")
	)
	(segment
		(start 309.437278 -2.314956)
		(end 309.411878 -2.314956)
		(width 0.4064)
		(layer "B.Cu")
		(net "GND")
	)
	(segment
		(start 207.449928 -20.224242)
		(end 207.449928 -21.504656)
		(width 0.4064)
		(layer "B.Cu")
		(net "GND")
	)
	(segment
		(start 163.6776 -76.356718)
		(end 163.6776 -76.708)
		(width 0.381)
		(layer "B.Cu")
		(net "GND")
	)
	(segment
		(start 460.464408 -150.266654)
		(end 460.63027 -150.100792)
		(width 0.3048)
		(layer "B.Cu")
		(net "GND")
	)
	(segment
		(start 58.599578 -142.477236)
		(end 58.599578 -142.23365)
		(width 0.4064)
		(layer "B.Cu")
		(net "GND")
	)
	(segment
		(start 225.210878 -150.219156)
		(end 225.210878 -150.193756)
		(width 0.4064)
		(layer "B.Cu")
		(net "GND")
	)
	(segment
		(start 31.39948 -1.021842)
		(end 31.39948 0.457454)
		(width 0.4064)
		(layer "B.Cu")
		(net "GND")
	)
	(segment
		(start 58.599578 -24.58085)
		(end 58.599578 -24.824182)
		(width 0.4064)
		(layer "B.Cu")
		(net "GND")
	)
	(segment
		(start 360.73588 -51.26228)
		(end 363.9185 -51.26228)
		(width 0.254)
		(layer "B.Cu")
		(net "GND")
	)
	(segment
		(start 378.10313 -110.085124)
		(end 377.94692 -109.928914)
		(width 0.254)
		(layer "B.Cu")
		(net "GND")
	)
	(segment
		(start 202.349862 -147.478496)
		(end 202.349862 -148.771356)
		(width 0.4064)
		(layer "B.Cu")
		(net "GND")
	)
	(segment
		(start 241.44986 -137.877296)
		(end 241.44986 -139.170156)
		(width 0.4064)
		(layer "B.Cu")
		(net "GND")
	)
	(segment
		(start 210.849972 -5.621782)
		(end 210.849972 -6.63702)
		(width 0.4064)
		(layer "B.Cu")
		(net "GND")
	)
	(segment
		(start 145.12163 -22.965156)
		(end 145.053812 -23.032974)
		(width 0.4064)
		(layer "B.Cu")
		(net "GND")
	)
	(segment
		(start 239.750346 -147.478496)
		(end 239.749838 -147.478496)
		(width 0.4064)
		(layer "B.Cu")
		(net "GND")
	)
	(segment
		(start 75.599544 -14.85265)
		(end 75.599544 -15.222982)
		(width 0.4064)
		(layer "B.Cu")
		(net "GND")
	)
	(segment
		(start 152.099518 -17.733518)
		(end 152.099518 -16.687546)
		(width 0.4064)
		(layer "B.Cu")
		(net "GND")
	)
	(segment
		(start 312.849768 -6.637274)
		(end 312.849768 -5.621782)
		(width 0.4064)
		(layer "B.Cu")
		(net "GND")
	)
	(segment
		(start 202.349862 -128.276096)
		(end 202.349862 -129.568956)
		(width 0.4064)
		(layer "B.Cu")
		(net "GND")
	)
	(segment
		(start 147.849336 -141.663928)
		(end 147.387564 -141.202156)
		(width 0.4064)
		(layer "B.Cu")
		(net "GND")
	)
	(segment
		(start 51.79949 -9.156446)
		(end 51.79949 -10.623042)
		(width 0.4064)
		(layer "B.Cu")
		(net "GND")
	)
	(segment
		(start 297.549824 -3.762756)
		(end 297.549824 -5.621782)
		(width 0.4064)
		(layer "B.Cu")
		(net "GND")
	)
	(segment
		(start 214.250524 -24.824182)
		(end 214.250016 -24.824182)
		(width 0.4064)
		(layer "B.Cu")
		(net "GND")
	)
	(segment
		(start 499.2116 -38.2016)
		(end 498.792754 -38.620446)
		(width 0.254)
		(layer "B.Cu")
		(net "GND")
	)
	(segment
		(start 33.703768 -3.830574)
		(end 33.771586 -3.762756)
		(width 0.4064)
		(layer "B.Cu")
		(net "GND")
	)
	(segment
		(start 196.40042 -20.224242)
		(end 196.399912 -20.224242)
		(width 0.4064)
		(layer "B.Cu")
		(net "GND")
	)
	(segment
		(start 56.899556 -132.876036)
		(end 56.899556 -132.53085)
		(width 0.4064)
		(layer "B.Cu")
		(net "GND")
	)
	(segment
		(start 236.350302 -5.621782)
		(end 236.349794 -5.621782)
		(width 0.254)
		(layer "B.Cu")
		(net "GND")
	)
	(segment
		(start 203.2 -152.078182)
		(end 203.2 -150.21941)
		(width 0.4064)
		(layer "B.Cu")
		(net "GND")
	)
	(segment
		(start 220.199966 -16.23822)
		(end 220.199966 -15.222982)
		(width 0.4064)
		(layer "B.Cu")
		(net "GND")
	)
	(segment
		(start 125.736858 -148.771356)
		(end 125.711458 -148.771356)
		(width 0.4064)
		(layer "B.Cu")
		(net "GND")
	)
	(segment
		(start 44.149518 -11.835892)
		(end 44.149518 -10.623042)
		(width 0.4064)
		(layer "B.Cu")
		(net "GND")
	)
	(segment
		(start 422.91 -5.9055)
		(end 422.91 -6.6675)
		(width 0.254)
		(layer "B.Cu")
		(net "GND")
	)
	(segment
		(start 281.399996 -1.021842)
		(end 281.399996 -2.302256)
		(width 0.4064)
		(layer "B.Cu")
		(net "GND")
	)
	(segment
		(start 291.354256 -3.830574)
		(end 291.354256 -4.5212)
		(width 0.4064)
		(layer "B.Cu")
		(net "GND")
	)
	(segment
		(start 208.0514 -141.500352)
		(end 208.0514 -140.675868)
		(width 0.4064)
		(layer "B.Cu")
		(net "GND")
	)
	(segment
		(start 232.099866 -20.224242)
		(end 232.099866 -21.517356)
		(width 0.4064)
		(layer "B.Cu")
		(net "GND")
	)
	(segment
		(start 284.800294 -15.222982)
		(end 284.799786 -15.222982)
		(width 0.4064)
		(layer "B.Cu")
		(net "GND")
	)
	(segment
		(start 317.949834 -132.875782)
		(end 317.949834 -131.571746)
		(width 0.4064)
		(layer "B.Cu")
		(net "GND")
	)
	(segment
		(start 417.6014 -21.336)
		(end 418.1094 -20.828)
		(width 0.254)
		(layer "B.Cu")
		(net "GND")
	)
	(segment
		(start 279.700482 -147.478496)
		(end 279.699974 -147.478496)
		(width 0.4064)
		(layer "B.Cu")
		(net "GND")
	)
	(segment
		(start 126.353824 -3.830574)
		(end 126.353824 -4.5212)
		(width 0.4064)
		(layer "B.Cu")
		(net "GND")
	)
	(segment
		(start 329.356466 -56.215534)
		(end 329.692 -55.88)
		(width 0.254)
		(layer "B.Cu")
		(net "GND")
	)
	(segment
		(start 56.899556 -142.13205)
		(end 56.899302 -142.131796)
		(width 0.4064)
		(layer "B.Cu")
		(net "GND")
	)
	(segment
		(start 284.341062 -16.696944)
		(end 284.799786 -16.23822)
		(width 0.4064)
		(layer "B.Cu")
		(net "GND")
	)
	(segment
		(start 126.599442 -132.096764)
		(end 126.353824 -131.851146)
		(width 0.254)
		(layer "B.Cu")
		(net "GND")
	)
	(segment
		(start 127.44958 -2.234692)
		(end 127.44958 -1.021842)
		(width 0.4064)
		(layer "B.Cu")
		(net "GND")
	)
	(segment
		(start 289.90036 -24.824182)
		(end 289.899852 -24.824182)
		(width 0.4064)
		(layer "B.Cu")
		(net "GND")
	)
	(segment
		(start 223.600518 -15.222982)
		(end 223.60001 -15.222982)
		(width 0.4064)
		(layer "B.Cu")
		(net "GND")
	)
	(segment
		(start 235.49991 -18.795746)
		(end 235.49991 -20.224242)
		(width 0.4064)
		(layer "B.Cu")
		(net "GND")
	)
	(segment
		(start 255.072388 -3.635756)
		(end 255.8034 -3.635756)
		(width 0.4064)
		(layer "B.Cu")
		(net "GND")
	)
	(segment
		(start 135.099552 -1.021842)
		(end 135.099552 -2.302256)
		(width 0.4064)
		(layer "B.Cu")
		(net "GND")
	)
	(segment
		(start 261.3406 -140.081)
		(end 261.3406 -139.3952)
		(width 0.4064)
		(layer "B.Cu")
		(net "GND")
	)
	(segment
		(start 175.26 -76.0476)
		(end 175.852074 -75.455526)
		(width 0.381)
		(layer "B.Cu")
		(net "GND")
	)
	(segment
		(start 214.250524 -152.078436)
		(end 214.250016 -152.078182)
		(width 0.4064)
		(layer "B.Cu")
		(net "GND")
	)
	(segment
		(start 51.79949 -21.504656)
		(end 51.78679 -21.517356)
		(width 0.4064)
		(layer "B.Cu")
		(net "GND")
	)
	(segment
		(start 300.099984 -147.478496)
		(end 300.099984 -148.733256)
		(width 0.4064)
		(layer "B.Cu")
		(net "GND")
	)
	(segment
		(start 224.450402 -147.478496)
		(end 224.449894 -147.478496)
		(width 0.4064)
		(layer "B.Cu")
		(net "GND")
	)
	(segment
		(start 66.24955 -142.10665)
		(end 66.249296 -142.106396)
		(width 0.4064)
		(layer "B.Cu")
		(net "GND")
	)
	(segment
		(start 300.70425 -23.032974)
		(end 300.70425 -23.7236)
		(width 0.4064)
		(layer "B.Cu")
		(net "GND")
	)
	(segment
		(start 301.742602 -18.744946)
		(end 301.800006 -18.80235)
		(width 0.4064)
		(layer "B.Cu")
		(net "GND")
	)
	(segment
		(start 238.44123 -7.095744)
		(end 238.899954 -6.63702)
		(width 0.4064)
		(layer "B.Cu")
		(net "GND")
	)
	(segment
		(start 77.526388 -126.10338)
		(end 77.932788 -126.10338)
		(width 0.254)
		(layer "B.Cu")
		(net "GND")
	)
	(segment
		(start 232.950004 -25.638252)
		(end 232.950004 -24.824182)
		(width 0.4064)
		(layer "B.Cu")
		(net "GND")
	)
	(segment
		(start 211.699856 -20.224242)
		(end 211.699856 -21.517356)
		(width 0.4064)
		(layer "B.Cu")
		(net "GND")
	)
	(segment
		(start 163.4236 -78.613)
		(end 162.3314 -78.613)
		(width 0.381)
		(layer "B.Cu")
		(net "GND")
	)
	(segment
		(start 202.35037 -128.276096)
		(end 202.349862 -128.276096)
		(width 0.4064)
		(layer "B.Cu")
		(net "GND")
	)
	(segment
		(start 113.849404 -17.193006)
		(end 113.951258 -17.29486)
		(width 0.4064)
		(layer "B.Cu")
		(net "GND")
	)
	(segment
		(start 176.6316 -83.312)
		(end 175.537622 -83.312)
		(width 0.4064)
		(layer "B.Cu")
		(net "GND")
	)
	(segment
		(start 225.299778 -150.308056)
		(end 225.210878 -150.219156)
		(width 0.4064)
		(layer "B.Cu")
		(net "GND")
	)
	(segment
		(start 294.150288 -142.477236)
		(end 294.14978 -142.476982)
		(width 0.4064)
		(layer "B.Cu")
		(net "GND")
	)
	(segment
		(start 389.991346 -48.49368)
		(end 388.657846 -48.49368)
		(width 0.254)
		(layer "B.Cu")
		(net "GND")
	)
	(segment
		(start 220.199966 -5.621782)
		(end 220.199966 -4.808982)
		(width 0.4064)
		(layer "B.Cu")
		(net "GND")
	)
	(segment
		(start 113.2078 -3.4798)
		(end 113.0808 -3.3528)
		(width 0.381)
		(layer "B.Cu")
		(net "GND")
	)
	(segment
		(start 296.69994 -129.568956)
		(end 296.69994 -128.276096)
		(width 0.4064)
		(layer "B.Cu")
		(net "GND")
	)
	(segment
		(start 124.049536 0.457454)
		(end 124.049536 -1.021842)
		(width 0.4064)
		(layer "B.Cu")
		(net "GND")
	)
	(segment
		(start 163.80206 -84.074)
		(end 163.80206 -84.328)
		(width 0.3556)
		(layer "B.Cu")
		(net "GND")
	)
	(segment
		(start 448.945 -147.8026)
		(end 449.326 -147.8026)
		(width 0.254)
		(layer "B.Cu")
		(net "GND")
	)
	(segment
		(start 166.0652 -73.66)
		(end 166.497 -73.66)
		(width 0.254)
		(layer "B.Cu")
		(net "GND")
	)
	(segment
		(start 410.436314 -87.526114)
		(end 409.884118 -87.526114)
		(width 0.254)
		(layer "B.Cu")
		(net "GND")
	)
	(segment
		(start 278.850344 -15.222982)
		(end 278.849836 -15.222982)
		(width 0.4064)
		(layer "B.Cu")
		(net "GND")
	)
	(segment
		(start 497.65204 -128.52654)
		(end 498.328188 -128.52654)
		(width 0.254)
		(layer "B.Cu")
		(net "GND")
	)
	(segment
		(start 51.79949 -148.758656)
		(end 51.78679 -148.771356)
		(width 0.4064)
		(layer "B.Cu")
		(net "GND")
	)
	(segment
		(start 386.861812 -42.310812)
		(end 387.153404 -42.602404)
		(width 0.254)
		(layer "B.Cu")
		(net "GND")
	)
	(segment
		(start 163.6776 -80.3402)
		(end 163.6776 -80.7212)
		(width 0.4064)
		(layer "B.Cu")
		(net "GND")
	)
	(segment
		(start 225.299778 -23.054056)
		(end 225.210878 -22.965156)
		(width 0.4064)
		(layer "B.Cu")
		(net "GND")
	)
	(segment
		(start 294.999918 -1.021842)
		(end 294.999918 -2.314956)
		(width 0.4064)
		(layer "B.Cu")
		(net "GND")
	)
	(segment
		(start 31.900114 -73.0504)
		(end 31.0134 -73.0504)
		(width 0.254)
		(layer "B.Cu")
		(net "GND")
	)
	(segment
		(start 410.633418 -93.114114)
		(end 410.633418 -93.904816)
		(width 0.254)
		(layer "B.Cu")
		(net "GND")
	)
	(segment
		(start 374.231916 -37.063426)
		(end 374.934226 -37.063426)
		(width 0.254)
		(layer "B.Cu")
		(net "GND")
	)
	(segment
		(start 307.749956 -1.021842)
		(end 307.749956 -2.314956)
		(width 0.4064)
		(layer "B.Cu")
		(net "GND")
	)
	(segment
		(start 53.499512 -128.276096)
		(end 53.499512 -129.488692)
		(width 0.4064)
		(layer "B.Cu")
		(net "GND")
	)
	(segment
		(start 444.951866 -38.39591)
		(end 445.687196 -38.39591)
		(width 0.4064)
		(layer "B.Cu")
		(net "GND")
	)
	(segment
		(start 57.74944 -137.877296)
		(end 57.74944 -139.170156)
		(width 0.4064)
		(layer "B.Cu")
		(net "GND")
	)
	(segment
		(start 471.14206 -129.1844)
		(end 471.14206 -128.83896)
		(width 0.254)
		(layer "B.Cu")
		(net "GND")
	)
	(segment
		(start 242.299998 -152.078182)
		(end 242.299998 -151.65705)
		(width 0.4064)
		(layer "B.Cu")
		(net "GND")
	)
	(segment
		(start 207.449928 -129.556256)
		(end 207.437228 -129.568956)
		(width 0.4064)
		(layer "B.Cu")
		(net "GND")
	)
	(segment
		(start 307.750464 -137.877296)
		(end 307.749956 -137.877296)
		(width 0.4064)
		(layer "B.Cu")
		(net "GND")
	)
	(segment
		(start 491.174532 -55.047896)
		(end 491.174532 -55.107078)
		(width 0.4064)
		(layer "B.Cu")
		(net "GND")
	)
	(segment
		(start 66.249296 -142.106396)
		(end 66.249296 -140.617956)
		(width 0.4064)
		(layer "B.Cu")
		(net "GND")
	)
	(segment
		(start 116.399564 -137.877296)
		(end 116.399564 -139.157456)
		(width 0.4064)
		(layer "B.Cu")
		(net "GND")
	)
	(segment
		(start 16.0782 -83.7438)
		(end 16.0782 -84.455)
		(width 0.254)
		(layer "B.Cu")
		(net "GND")
	)
	(segment
		(start 203.2 -132.875782)
		(end 203.2 -131.01701)
		(width 0.4064)
		(layer "B.Cu")
		(net "GND")
	)
	(segment
		(start 391.3505 -11.049)
		(end 392.030458 -11.728958)
		(width 0.254)
		(layer "B.Cu")
		(net "GND")
	)
	(segment
		(start 255.153668 -149.444964)
		(end 255.627124 -149.444964)
		(width 0.4572)
		(layer "B.Cu")
		(net "GND")
	)
	(segment
		(start 44.149518 -139.089892)
		(end 44.092114 -139.147296)
		(width 0.4064)
		(layer "B.Cu")
		(net "GND")
	)
	(segment
		(start 202.35037 -1.021842)
		(end 202.349862 -1.021842)
		(width 0.4064)
		(layer "B.Cu")
		(net "GND")
	)
	(segment
		(start 96.086168 -3.321812)
		(end 96.086168 -1.778)
		(width 0.508)
		(layer "B.Cu")
		(net "GND")
	)
	(segment
		(start 295.849802 -132.875782)
		(end 295.849802 -131.016756)
		(width 0.4064)
		(layer "B.Cu")
		(net "GND")
	)
	(segment
		(start 250.7615 -3.3528)
		(end 249.9106 -3.3528)
		(width 0.4572)
		(layer "B.Cu")
		(net "GND")
	)
	(segment
		(start 450.061838 -155.250134)
		(end 450.128132 -155.18384)
		(width 0.254)
		(layer "B.Cu")
		(net "GND")
	)
	(segment
		(start 247.1166 -26.6446)
		(end 247.1166 -27.2034)
		(width 0.4064)
		(layer "B.Cu")
		(net "GND")
	)
	(segment
		(start 395.780006 -27.403806)
		(end 396.30096 -27.92476)
		(width 0.254)
		(layer "B.Cu")
		(net "GND")
	)
	(segment
		(start 141.049502 -147.478496)
		(end 141.049502 -148.771356)
		(width 0.4064)
		(layer "B.Cu")
		(net "GND")
	)
	(segment
		(start 113.849404 -15.222982)
		(end 113.849404 -17.193006)
		(width 0.4064)
		(layer "B.Cu")
		(net "GND")
	)
	(segment
		(start 298.40047 -20.224242)
		(end 298.399962 -20.224242)
		(width 0.4064)
		(layer "B.Cu")
		(net "GND")
	)
	(segment
		(start 429.913542 -21.801582)
		(end 429.7172 -21.997924)
		(width 0.254)
		(layer "B.Cu")
		(net "GND")
	)
	(segment
		(start 380.2507 -46.0883)
		(end 379.9967 -46.3423)
		(width 0.254)
		(layer "B.Cu")
		(net "GND")
	)
	(segment
		(start 143.809212 -140.617956)
		(end 143.599408 -140.82776)
		(width 0.4064)
		(layer "B.Cu")
		(net "GND")
	)
	(segment
		(start 231.25049 -15.222982)
		(end 231.249982 -15.222982)
		(width 0.4064)
		(layer "B.Cu")
		(net "GND")
	)
	(segment
		(start 434.0098 -42.0116)
		(end 434.545994 -42.0116)
		(width 0.381)
		(layer "B.Cu")
		(net "GND")
	)
	(segment
		(start 218.499944 -129.488692)
		(end 218.44254 -129.546096)
		(width 0.4064)
		(layer "B.Cu")
		(net "GND")
	)
	(segment
		(start 95.005906 -156.703014)
		(end 94.68104 -157.02788)
		(width 0.508)
		(layer "B.Cu")
		(net "GND")
	)
	(segment
		(start 135.099552 -139.157456)
		(end 135.086852 -139.170156)
		(width 0.4064)
		(layer "B.Cu")
		(net "GND")
	)
	(segment
		(start 314.54979 -17.208246)
		(end 314.54979 -15.222982)
		(width 0.4064)
		(layer "B.Cu")
		(net "GND")
	)
	(segment
		(start 236.095794 -23.041356)
		(end 236.171994 -22.965156)
		(width 0.4064)
		(layer "B.Cu")
		(net "GND")
	)
	(segment
		(start 211.699856 0.444754)
		(end 211.699856 -1.021842)
		(width 0.4064)
		(layer "B.Cu")
		(net "GND")
	)
	(segment
		(start 127.392176 -2.310892)
		(end 127.392176 -2.292096)
		(width 0.4064)
		(layer "B.Cu")
		(net "GND")
	)
	(segment
		(start 208.299812 -4.893564)
		(end 208.0514 -4.645152)
		(width 0.254)
		(layer "B.Cu")
		(net "GND")
	)
	(segment
		(start 214.250016 -152.078182)
		(end 214.250016 -151.73325)
		(width 0.4064)
		(layer "B.Cu")
		(net "GND")
	)
	(segment
		(start 232.94975 -132.581396)
		(end 232.94975 -131.016756)
		(width 0.4064)
		(layer "B.Cu")
		(net "GND")
	)
	(segment
		(start 278.957786 -18.007584)
		(end 278.90597 -18.0594)
		(width 0.381)
		(layer "B.Cu")
		(net "GND")
	)
	(segment
		(start 198.7042 -140.685774)
		(end 198.772018 -140.617956)
		(width 0.4064)
		(layer "B.Cu")
		(net "GND")
	)
	(segment
		(start 438.5945 -12.01928)
		(end 437.35752 -12.01928)
		(width 0.254)
		(layer "B.Cu")
		(net "GND")
	)
	(segment
		(start 44.092114 -2.310892)
		(end 44.092114 -2.292096)
		(width 0.4064)
		(layer "B.Cu")
		(net "GND")
	)
	(segment
		(start 133.39953 0.457454)
		(end 133.39953 -1.021842)
		(width 0.4064)
		(layer "B.Cu")
		(net "GND")
	)
	(segment
		(start 146.149568 -128.276096)
		(end 146.149568 -129.488692)
		(width 0.4064)
		(layer "B.Cu")
		(net "GND")
	)
	(segment
		(start 206.59979 -3.826256)
		(end 206.51089 -3.737356)
		(width 0.4064)
		(layer "B.Cu")
		(net "GND")
	)
	(segment
		(start 144.449546 -18.757646)
		(end 144.449546 -20.224242)
		(width 0.4064)
		(layer "B.Cu")
		(net "GND")
	)
	(segment
		(start 441.119006 -41.203626)
		(end 441.119006 -40.5257)
		(width 0.3556)
		(layer "B.Cu")
		(net "GND")
	)
	(segment
		(start 198.100442 -1.021842)
		(end 198.099934 -1.021842)
		(width 0.4064)
		(layer "B.Cu")
		(net "GND")
	)
	(segment
		(start 402.9964 2.4384)
		(end 402.9964 1.956562)
		(width 0.254)
		(layer "B.Cu")
		(net "GND")
	)
	(segment
		(start 496.213638 -36.957762)
		(end 496.919504 -36.957762)
		(width 0.254)
		(layer "B.Cu")
		(net "GND")
	)
	(segment
		(start 226.149916 -1.021842)
		(end 226.149916 -2.302256)
		(width 0.4064)
		(layer "B.Cu")
		(net "GND")
	)
	(segment
		(start 216.80043 -10.623042)
		(end 216.799922 -10.623042)
		(width 0.4064)
		(layer "B.Cu")
		(net "GND")
	)
	(segment
		(start 126.353824 -23.7236)
		(end 126.353824 -23.799546)
		(width 0.254)
		(layer "B.Cu")
		(net "GND")
	)
	(segment
		(start 145.053812 -23.032974)
		(end 145.053812 -23.7236)
		(width 0.4064)
		(layer "B.Cu")
		(net "GND")
	)
	(segment
		(start 416.464242 -9.6774)
		(end 416.464242 -10.314178)
		(width 0.254)
		(layer "B.Cu")
		(net "GND")
	)
	(segment
		(start 42.449496 -18.795746)
		(end 42.449496 -20.224242)
		(width 0.4064)
		(layer "B.Cu")
		(net "GND")
	)
	(segment
		(start 379.6792 -45.1485)
		(end 380.2888 -45.1485)
		(width 0.254)
		(layer "B.Cu")
		(net "GND")
	)
	(segment
		(start 175.36668 -81.407)
		(end 175.36668 -81.12252)
		(width 0.381)
		(layer "B.Cu")
		(net "GND")
	)
	(segment
		(start 197.249796 -5.621782)
		(end 197.249796 -4.514342)
		(width 0.4064)
		(layer "B.Cu")
		(net "GND")
	)
	(segment
		(start 151.24938 -22.965156)
		(end 151.24938 -24.824182)
		(width 0.4064)
		(layer "B.Cu")
		(net "GND")
	)
	(segment
		(start 223.60001 -14.97965)
		(end 223.599756 -14.979396)
		(width 0.4064)
		(layer "B.Cu")
		(net "GND")
	)
	(segment
		(start 317.950342 -152.078436)
		(end 317.949834 -152.078182)
		(width 0.4064)
		(layer "B.Cu")
		(net "GND")
	)
	(segment
		(start 224.449894 -1.021842)
		(end 224.449894 -2.314956)
		(width 0.4064)
		(layer "B.Cu")
		(net "GND")
	)
	(segment
		(start 58.599324 -142.233396)
		(end 58.599324 -140.617956)
		(width 0.4064)
		(layer "B.Cu")
		(net "GND")
	)
	(segment
		(start 405.262588 -32.046672)
		(end 405.62276 -31.6865)
		(width 0.254)
		(layer "B.Cu")
		(net "GND")
	)
	(segment
		(start 314.550298 -132.876036)
		(end 314.54979 -132.875782)
		(width 0.4064)
		(layer "B.Cu")
		(net "GND")
	)
	(segment
		(start 461.869282 -33.852358)
		(end 461.869282 -34.478722)
		(width 0.254)
		(layer "B.Cu")
		(net "GND")
	)
	(segment
		(start 45.84954 -132.876036)
		(end 45.84954 -132.062982)
		(width 0.4064)
		(layer "B.Cu")
		(net "GND")
	)
	(segment
		(start 311.15 -1.021842)
		(end 311.15 -2.234692)
		(width 0.4064)
		(layer "B.Cu")
		(net "GND")
	)
	(segment
		(start 226.149916 -10.623042)
		(end 226.149916 -9.156446)
		(width 0.4064)
		(layer "B.Cu")
		(net "GND")
	)
	(segment
		(start 226.7458 -131.8514)
		(end 226.7458 -131.7498)
		(width 0.254)
		(layer "B.Cu")
		(net "GND")
	)
	(segment
		(start 42.449496 -148.758656)
		(end 42.436796 -148.771356)
		(width 0.4064)
		(layer "B.Cu")
		(net "GND")
	)
	(segment
		(start 235.49991 -9.156446)
		(end 235.49991 -10.623042)
		(width 0.4064)
		(layer "B.Cu")
		(net "GND")
	)
	(segment
		(start 152.626568 1.928368)
		(end 152.4 1.7018)
		(width 0.4064)
		(layer "B.Cu")
		(net "GND")
	)
	(segment
		(start 405.683974 -54.673754)
		(end 405.404828 -54.9529)
		(width 0.254)
		(layer "B.Cu")
		(net "GND")
	)
	(segment
		(start 464.690714 -3.6195)
		(end 464.907376 -3.402838)
		(width 0.254)
		(layer "B.Cu")
		(net "GND")
	)
	(segment
		(start 116.399564 -148.758656)
		(end 116.386864 -148.771356)
		(width 0.4064)
		(layer "B.Cu")
		(net "GND")
	)
	(segment
		(start 197.249796 -152.078182)
		(end 197.249796 -150.970742)
		(width 0.4064)
		(layer "B.Cu")
		(net "GND")
	)
	(segment
		(start 234.649772 -152.078182)
		(end 234.649772 -150.308056)
		(width 0.4064)
		(layer "B.Cu")
		(net "GND")
	)
	(segment
		(start 17.9324 -93.5736)
		(end 18.669 -94.3102)
		(width 0.4064)
		(layer "B.Cu")
		(net "GND")
	)
	(segment
		(start 491.67542 -153.924)
		(end 490.488986 -153.924)
		(width 0.254)
		(layer "B.Cu")
		(net "GND")
	)
	(segment
		(start 215.100408 -147.478496)
		(end 215.0999 -147.478496)
		(width 0.4064)
		(layer "B.Cu")
		(net "GND")
	)
	(segment
		(start 305.200304 -24.824182)
		(end 305.199796 -24.824182)
		(width 0.4064)
		(layer "B.Cu")
		(net "GND")
	)
	(segment
		(start 99.2886 3.8862)
		(end 99.2886 3.299968)
		(width 0.508)
		(layer "B.Cu")
		(net "GND")
	)
	(segment
		(start 309.411878 -139.170156)
		(end 309.437278 -139.170156)
		(width 0.4064)
		(layer "B.Cu")
		(net "GND")
	)
	(segment
		(start 113.967768 -131.457192)
		(end 113.967768 -130.8862)
		(width 0.4064)
		(layer "B.Cu")
		(net "GND")
	)
	(segment
		(start 311.15 -129.488692)
		(end 311.092596 -129.546096)
		(width 0.4064)
		(layer "B.Cu")
		(net "GND")
	)
	(segment
		(start 73.899522 -152.078436)
		(end 73.899522 -151.265382)
		(width 0.4064)
		(layer "B.Cu")
		(net "GND")
	)
	(segment
		(start 92.152978 -134.440422)
		(end 91.684348 -134.909052)
		(width 0.381)
		(layer "B.Cu")
		(net "GND")
	)
	(segment
		(start 365.114078 -42.887138)
		(end 365.791496 -42.20972)
		(width 0.254)
		(layer "B.Cu")
		(net "GND")
	)
	(segment
		(start 50.099468 -20.224242)
		(end 50.099468 -18.744946)
		(width 0.4064)
		(layer "B.Cu")
		(net "GND")
	)
	(segment
		(start 143.809212 -22.965156)
		(end 145.12163 -22.965156)
		(width 0.4064)
		(layer "B.Cu")
		(net "GND")
	)
	(segment
		(start 235.500418 -10.623042)
		(end 235.49991 -10.623042)
		(width 0.4064)
		(layer "B.Cu")
		(net "GND")
	)
	(segment
		(start 221.899988 -5.27685)
		(end 221.899734 -5.276596)
		(width 0.4064)
		(layer "B.Cu")
		(net "GND")
	)
	(segment
		(start 124.049536 -11.916156)
		(end 124.049536 -10.623042)
		(width 0.4064)
		(layer "B.Cu")
		(net "GND")
	)
	(segment
		(start 152.949402 -5.621782)
		(end 152.949402 -4.317746)
		(width 0.4064)
		(layer "B.Cu")
		(net "GND")
	)
	(segment
		(start 221.050358 -10.623042)
		(end 221.04985 -10.623042)
		(width 0.4064)
		(layer "B.Cu")
		(net "GND")
	)
	(segment
		(start 309.450486 -20.224242)
		(end 309.449978 -20.224242)
		(width 0.4064)
		(layer "B.Cu")
		(net "GND")
	)
	(segment
		(start 46.699424 0.444754)
		(end 46.699424 -1.021842)
		(width 0.4064)
		(layer "B.Cu")
		(net "GND")
	)
	(segment
		(start 201.500486 -24.824182)
		(end 201.499978 -24.824182)
		(width 0.4064)
		(layer "B.Cu")
		(net "GND")
	)
	(segment
		(start 221.899988 -152.078182)
		(end 221.899988 -151.73325)
		(width 0.4064)
		(layer "B.Cu")
		(net "GND")
	)
	(segment
		(start 64.549528 -5.621782)
		(end 64.549528 -6.63702)
		(width 0.4064)
		(layer "B.Cu")
		(net "GND")
	)
	(segment
		(start 198.950326 -5.621782)
		(end 198.949818 -5.621782)
		(width 0.4064)
		(layer "B.Cu")
		(net "GND")
	)
	(segment
		(start 195.549774 -150.642574)
		(end 194.945 -150.0378)
		(width 0.4064)
		(layer "B.Cu")
		(net "GND")
	)
	(segment
		(start 55.199534 -16.23822)
		(end 54.74081 -16.696944)
		(width 0.4064)
		(layer "B.Cu")
		(net "GND")
	)
	(segment
		(start 50.860452 -22.965156)
		(end 50.860452 -22.939756)
		(width 0.4064)
		(layer "B.Cu")
		(net "GND")
	)
	(segment
		(start 237.20044 -1.021842)
		(end 237.199932 -1.021842)
		(width 0.4064)
		(layer "B.Cu")
		(net "GND")
	)
	(segment
		(start 214.249762 -142.131796)
		(end 214.249762 -140.617956)
		(width 0.4064)
		(layer "B.Cu")
		(net "GND")
	)
	(segment
		(start 31.39948 -129.568956)
		(end 31.39948 -128.276096)
		(width 0.4064)
		(layer "B.Cu")
		(net "GND")
	)
	(segment
		(start 290.74999 0.444754)
		(end 290.74999 -1.021842)
		(width 0.4064)
		(layer "B.Cu")
		(net "GND")
	)
	(segment
		(start 135.703818 -4.5212)
		(end 135.703818 -3.830574)
		(width 0.4064)
		(layer "B.Cu")
		(net "GND")
	)
	(segment
		(start 230.399844 -20.224242)
		(end 230.399844 -21.517356)
		(width 0.4064)
		(layer "B.Cu")
		(net "GND")
	)
	(segment
		(start 217.649806 -132.07746)
		(end 217.3986 -131.826254)
		(width 0.254)
		(layer "B.Cu")
		(net "GND")
	)
	(segment
		(start 300.949868 -15.222982)
		(end 300.949868 -14.443964)
		(width 0.254)
		(layer "B.Cu")
		(net "GND")
	)
	(segment
		(start 290.74999 -1.021842)
		(end 290.74999 -2.302256)
		(width 0.4064)
		(layer "B.Cu")
		(net "GND")
	)
	(segment
		(start 194.945 -150.0378)
		(end 194.7164 -150.0378)
		(width 0.4064)
		(layer "B.Cu")
		(net "GND")
	)
	(segment
		(start 280.460958 -150.219156)
		(end 280.460958 -150.193756)
		(width 0.4064)
		(layer "B.Cu")
		(net "GND")
	)
	(segment
		(start 152.949402 -152.078436)
		(end 152.949402 -150.774146)
		(width 0.4064)
		(layer "B.Cu")
		(net "GND")
	)
	(segment
		(start 135.949436 -25.937972)
		(end 136.748774 -26.73731)
		(width 0.4064)
		(layer "B.Cu")
		(net "GND")
	)
	(segment
		(start 236.095794 -14.1986)
		(end 236.095794 -14.097)
		(width 0.254)
		(layer "B.Cu")
		(net "GND")
	)
	(segment
		(start 32.249364 -17.110202)
		(end 32.249364 -15.222982)
		(width 0.4064)
		(layer "B.Cu")
		(net "GND")
	)
	(segment
		(start 215.860884 -150.219156)
		(end 215.860884 -150.193756)
		(width 0.4064)
		(layer "B.Cu")
		(net "GND")
	)
	(segment
		(start 317.950342 -24.824182)
		(end 317.949834 -24.824182)
		(width 0.4064)
		(layer "B.Cu")
		(net "GND")
	)
	(segment
		(start 376.869198 -109.392212)
		(end 376.889772 -109.371638)
		(width 0.254)
		(layer "B.Cu")
		(net "GND")
	)
	(segment
		(start 113.849404 -137.877296)
		(end 113.849404 -139.587986)
		(width 0.4064)
		(layer "B.Cu")
		(net "GND")
	)
	(segment
		(start 365.468408 -48.242728)
		(end 365.270288 -48.242728)
		(width 0.254)
		(layer "B.Cu")
		(net "GND")
	)
	(segment
		(start 436.5244 -41.18102)
		(end 436.5244 -40.548306)
		(width 0.3556)
		(layer "B.Cu")
		(net "GND")
	)
	(segment
		(start 239.750346 -10.623042)
		(end 239.749838 -10.623042)
		(width 0.4064)
		(layer "B.Cu")
		(net "GND")
	)
	(segment
		(start 43.12158 -13.363956)
		(end 43.050968 -13.434568)
		(width 0.4064)
		(layer "B.Cu")
		(net "GND")
	)
	(segment
		(start 223.599756 -7.607046)
		(end 223.60001 -7.606792)
		(width 0.4064)
		(layer "B.Cu")
		(net "GND")
	)
	(segment
		(start 206.600298 -132.876036)
		(end 206.59979 -132.875782)
		(width 0.4064)
		(layer "B.Cu")
		(net "GND")
	)
	(segment
		(start 64.549528 -26.22423)
		(end 64.090804 -26.682954)
		(width 0.4064)
		(layer "B.Cu")
		(net "GND")
	)
	(segment
		(start 225.300286 -15.222982)
		(end 225.299778 -15.222982)
		(width 0.4064)
		(layer "B.Cu")
		(net "GND")
	)
	(segment
		(start 371.329712 -98.633026)
		(end 371.000274 -98.962464)
		(width 0.254)
		(layer "B.Cu")
		(net "GND")
	)
	(segment
		(start 484.336852 4.157472)
		(end 484.235252 4.055872)
		(width 0.508)
		(layer "B.Cu")
		(net "GND")
	)
	(segment
		(start 370.746274 -71.49338)
		(end 370.745512 -71.494142)
		(width 0.127)
		(layer "B.Cu")
		(net "GND")
	)
	(segment
		(start 242.299998 -26.635202)
		(end 242.2652 -26.67)
		(width 0.4064)
		(layer "B.Cu")
		(net "GND")
	)
	(segment
		(start 77.299566 -132.45465)
		(end 77.299312 -132.454396)
		(width 0.4064)
		(layer "B.Cu")
		(net "GND")
	)
	(segment
		(start 109.2581 -8.1534)
		(end 110.111032 -8.1534)
		(width 0.4064)
		(layer "B.Cu")
		(net "GND")
	)
	(segment
		(start 313.700414 -20.224242)
		(end 313.699906 -20.224242)
		(width 0.4064)
		(layer "B.Cu")
		(net "GND")
	)
	(segment
		(start 232.950512 -132.876036)
		(end 232.950004 -132.875782)
		(width 0.4064)
		(layer "B.Cu")
		(net "GND")
	)
	(segment
		(start 72.142096 -18.744946)
		(end 72.1995 -18.80235)
		(width 0.4064)
		(layer "B.Cu")
		(net "GND")
	)
	(segment
		(start 231.249982 -14.85265)
		(end 231.249728 -14.852396)
		(width 0.4064)
		(layer "B.Cu")
		(net "GND")
	)
	(segment
		(start 169.3926 -83.7438)
		(end 169.799 -84.1502)
		(width 0.254)
		(layer "B.Cu")
		(net "GND")
	)
	(segment
		(start 311.092596 -11.893296)
		(end 311.15 -11.835892)
		(width 0.4064)
		(layer "B.Cu")
		(net "GND")
	)
	(segment
		(start 498.729 -131.6228)
		(end 498.729 -132.334)
		(width 0.254)
		(layer "B.Cu")
		(net "GND")
	)
	(segment
		(start 240.599722 -7.607046)
		(end 240.599976 -7.606792)
		(width 0.4064)
		(layer "B.Cu")
		(net "GND")
	)
	(segment
		(start 125.711458 -12.640818)
		(end 125.711458 -11.916156)
		(width 0.4064)
		(layer "B.Cu")
		(net "GND")
	)
	(segment
		(start 226.149916 -129.556256)
		(end 226.137216 -129.568956)
		(width 0.4064)
		(layer "B.Cu")
		(net "GND")
	)
	(segment
		(start 214.249762 -132.530596)
		(end 214.249762 -131.016756)
		(width 0.4064)
		(layer "B.Cu")
		(net "GND")
	)
	(segment
		(start 373.544846 -73.495154)
		(end 373.944388 -73.095612)
		(width 0.254)
		(layer "B.Cu")
		(net "GND")
	)
	(segment
		(start 386.80898 -128.2192)
		(end 386.80898 -127.8128)
		(width 0.4064)
		(layer "B.Cu")
		(net "GND")
	)
	(segment
		(start 194.564 -154.559)
		(end 194.691 -154.178)
		(width 0.4064)
		(layer "B.Cu")
		(net "GND")
	)
	(segment
		(start 152.099518 -147.478496)
		(end 152.099518 -148.782278)
		(width 0.4064)
		(layer "B.Cu")
		(net "GND")
	)
	(segment
		(start 163.576 -83.53806)
		(end 163.42106 -83.693)
		(width 0.381)
		(layer "B.Cu")
		(net "GND")
	)
	(segment
		(start 278.2062 -3.4798)
		(end 278.8666 -3.4798)
		(width 0.381)
		(layer "B.Cu")
		(net "GND")
	)
	(segment
		(start 483.87254 -121.77014)
		(end 483.97414 -121.77014)
		(width 0.254)
		(layer "B.Cu")
		(net "GND")
	)
	(segment
		(start 402.742146 1.702308)
		(end 402.449538 1.702308)
		(width 0.254)
		(layer "B.Cu")
		(net "GND")
	)
	(segment
		(start 218.44254 0.457454)
		(end 218.499944 0.40005)
		(width 0.4064)
		(layer "B.Cu")
		(net "GND")
	)
	(segment
		(start 17.378172 -82.139028)
		(end 17.653 -81.8642)
		(width 0.254)
		(layer "B.Cu")
		(net "GND")
	)
	(segment
		(start 238.900462 -142.477236)
		(end 238.899954 -142.476982)
		(width 0.4064)
		(layer "B.Cu")
		(net "GND")
	)
	(segment
		(start 496.05438 -127.26162)
		(end 496.4557 -127.26162)
		(width 0.254)
		(layer "B.Cu")
		(net "GND")
	)
	(segment
		(start 287.349946 -1.021842)
		(end 287.349946 -2.314956)
		(width 0.4064)
		(layer "B.Cu")
		(net "GND")
	)
	(segment
		(start 235.46181 -26.488136)
		(end 234.649772 -25.676098)
		(width 0.4064)
		(layer "B.Cu")
		(net "GND")
	)
	(segment
		(start 66.24955 -151.70785)
		(end 66.249296 -151.707596)
		(width 0.4064)
		(layer "B.Cu")
		(net "GND")
	)
	(segment
		(start 118.099332 -129.488692)
		(end 118.041928 -129.546096)
		(width 0.4064)
		(layer "B.Cu")
		(net "GND")
	)
	(segment
		(start 410.6672 -87.757)
		(end 410.436314 -87.526114)
		(width 0.254)
		(layer "B.Cu")
		(net "GND")
	)
	(segment
		(start 217.3986 -131.7752)
		(end 217.3986 -131.090162)
		(width 0.4064)
		(layer "B.Cu")
		(net "GND")
	)
	(segment
		(start 420.4589 -70.0405)
		(end 419.6715 -70.0405)
		(width 0.254)
		(layer "B.Cu")
		(net "GND")
	)
	(segment
		(start 227.849938 -18.80235)
		(end 227.849938 -20.224242)
		(width 0.4064)
		(layer "B.Cu")
		(net "GND")
	)
	(segment
		(start 96.27997 -136.15289)
		(end 96.27997 -135.577834)
		(width 0.4064)
		(layer "B.Cu")
		(net "GND")
	)
	(segment
		(start 475.546928 -123.756928)
		(end 475.165928 -123.375928)
		(width 0.254)
		(layer "B.Cu")
		(net "GND")
	)
	(segment
		(start 73.899522 -24.824182)
		(end 73.899522 -26.22423)
		(width 0.4064)
		(layer "B.Cu")
		(net "GND")
	)
	(segment
		(start 32.249364 -23.716742)
		(end 32.160464 -23.627842)
		(width 0.4064)
		(layer "B.Cu")
		(net "GND")
	)
	(segment
		(start 373.207026 -86.301326)
		(end 373.538496 -86.632796)
		(width 0.254)
		(layer "B.Cu")
		(net "GND")
	)
	(segment
		(start 66.249296 -132.505196)
		(end 66.249296 -131.016756)
		(width 0.4064)
		(layer "B.Cu")
		(net "GND")
	)
	(segment
		(start 42.436796 -2.314956)
		(end 42.411396 -2.314956)
		(width 0.4064)
		(layer "B.Cu")
		(net "GND")
	)
	(segment
		(start 220.199966 -141.664182)
		(end 219.73794 -141.202156)
		(width 0.4064)
		(layer "B.Cu")
		(net "GND")
	)
	(segment
		(start 44.092114 -18.744946)
		(end 44.149518 -18.80235)
		(width 0.4064)
		(layer "B.Cu")
		(net "GND")
	)
	(segment
		(start 58.599578 -7.606792)
		(end 58.599324 -7.607046)
		(width 0.4064)
		(layer "B.Cu")
		(net "GND")
	)
	(segment
		(start 73.899522 -132.876036)
		(end 73.899522 -132.062982)
		(width 0.4064)
		(layer "B.Cu")
		(net "GND")
	)
	(segment
		(start 442.722 -13.8938)
		(end 442.722 -13.1064)
		(width 0.254)
		(layer "B.Cu")
		(net "GND")
	)
	(segment
		(start 342.0237 -81.8769)
		(end 342.0237 -82.2452)
		(width 0.254)
		(layer "B.Cu")
		(net "GND")
	)
	(segment
		(start 2.517648 -7.5692)
		(end 2.930906 -7.982458)
		(width 0.254)
		(layer "B.Cu")
		(net "GND")
	)
	(segment
		(start 143.599408 -131.22656)
		(end 143.809212 -131.016756)
		(width 0.4064)
		(layer "B.Cu")
		(net "GND")
	)
	(segment
		(start 215.950292 -15.222982)
		(end 215.949784 -15.222982)
		(width 0.4064)
		(layer "B.Cu")
		(net "GND")
	)
	(segment
		(start 401.20824 -53.35778)
		(end 401.20316 -53.36286)
		(width 0.254)
		(layer "B.Cu")
		(net "GND")
	)
	(segment
		(start 235.49991 -8.317484)
		(end 236.171994 -7.6454)
		(width 0.4064)
		(layer "B.Cu")
		(net "GND")
	)
	(segment
		(start 138.499342 -151.265128)
		(end 138.03757 -150.803356)
		(width 0.4064)
		(layer "B.Cu")
		(net "GND")
	)
	(segment
		(start 207.437228 -2.314956)
		(end 207.411828 -2.314956)
		(width 0.4064)
		(layer "B.Cu")
		(net "GND")
	)
	(segment
		(start 301.800006 -128.276096)
		(end 301.800006 -129.488692)
		(width 0.4064)
		(layer "B.Cu")
		(net "GND")
	)
	(segment
		(start 147.849336 -24.824182)
		(end 147.849336 -24.011128)
		(width 0.4064)
		(layer "B.Cu")
		(net "GND")
	)
	(segment
		(start 168.9862 -88.392)
		(end 169.291 -88.0872)
		(width 0.4064)
		(layer "B.Cu")
		(net "GND")
	)
	(segment
		(start 33.771586 -17.2466)
		(end 33.949386 -17.0688)
		(width 0.4064)
		(layer "B.Cu")
		(net "GND")
	)
	(segment
		(start 451.9422 -129.0574)
		(end 451.9422 -126.301246)
		(width 0.254)
		(layer "B.Cu")
		(net "GND")
	)
	(segment
		(start 144.436846 -148.771356)
		(end 144.411446 -148.771356)
		(width 0.4064)
		(layer "B.Cu")
		(net "GND")
	)
	(segment
		(start 449.6435 -25.273)
		(end 448.8815 -25.273)
		(width 0.254)
		(layer "B.Cu")
		(net "GND")
	)
	(segment
		(start 121.499376 -15.222982)
		(end 121.499376 -13.363956)
		(width 0.4064)
		(layer "B.Cu")
		(net "GND")
	)
	(segment
		(start 235.500418 -147.478496)
		(end 235.49991 -147.478496)
		(width 0.4064)
		(layer "B.Cu")
		(net "GND")
	)
	(segment
		(start 217.3986 -23.038562)
		(end 217.472006 -22.965156)
		(width 0.4064)
		(layer "B.Cu")
		(net "GND")
	)
	(segment
		(start 289.049968 -21.517356)
		(end 289.049968 -20.224242)
		(width 0.4064)
		(layer "B.Cu")
		(net "GND")
	)
	(segment
		(start 272.027904 -135.4074)
		(end 270.956532 -135.4074)
		(width 0.4572)
		(layer "B.Cu")
		(net "GND")
	)
	(segment
		(start 375.2088 -37.338)
		(end 375.2088 -38.2016)
		(width 0.254)
		(layer "B.Cu")
		(net "GND")
	)
	(segment
		(start 146.092164 -139.147296)
		(end 146.092164 -139.166092)
		(width 0.4064)
		(layer "B.Cu")
		(net "GND")
	)
	(segment
		(start 77.299312 -151.656796)
		(end 77.299312 -150.231856)
		(width 0.4064)
		(layer "B.Cu")
		(net "GND")
	)
	(segment
		(start 482.854 -33.401)
		(end 482.854 -34.804096)
		(width 0.254)
		(layer "B.Cu")
		(net "GND")
	)
	(segment
		(start 483.802944 -18.460466)
		(end 483.802944 -17.934178)
		(width 0.254)
		(layer "B.Cu")
		(net "GND")
	)
	(segment
		(start 238.899954 -132.875782)
		(end 238.899954 -132.062982)
		(width 0.4064)
		(layer "B.Cu")
		(net "GND")
	)
	(segment
		(start 199.799956 -148.691092)
		(end 199.742552 -148.748496)
		(width 0.4064)
		(layer "B.Cu")
		(net "GND")
	)
	(segment
		(start 310.299862 -24.045164)
		(end 310.299862 -24.823674)
		(width 0.254)
		(layer "B.Cu")
		(net "GND")
	)
	(segment
		(start 163.395406 -86.35492)
		(end 162.3949 -86.35492)
		(width 0.4064)
		(layer "B.Cu")
		(net "GND")
	)
	(segment
		(start 61.745368 -131.092956)
		(end 61.821568 -131.016756)
		(width 0.4064)
		(layer "B.Cu")
		(net "GND")
	)
	(segment
		(start 287.349946 -10.623042)
		(end 287.349946 -11.916156)
		(width 0.4064)
		(layer "B.Cu")
		(net "GND")
	)
	(segment
		(start 52.398168 -131.826254)
		(end 52.398168 -131.7752)
		(width 0.254)
		(layer "B.Cu")
		(net "GND")
	)
	(segment
		(start 78.288134 -12.954)
		(end 79.334868 -12.954)
		(width 0.4064)
		(layer "B.Cu")
		(net "GND")
	)
	(segment
		(start 140.199364 -15.222982)
		(end 140.199364 -17.208246)
		(width 0.4064)
		(layer "B.Cu")
		(net "GND")
	)
	(segment
		(start 43.29938 -141.748764)
		(end 43.050968 -141.500352)
		(width 0.254)
		(layer "B.Cu")
		(net "GND")
	)
	(segment
		(start 440.284362 -33.581848)
		(end 439.903362 -33.962848)
		(width 0.254)
		(layer "B.Cu")
		(net "GND")
	)
	(segment
		(start 33.703768 -131.7752)
		(end 33.703768 -131.084574)
		(width 0.4064)
		(layer "B.Cu")
		(net "GND")
	)
	(segment
		(start 390.473692 -41.326562)
		(end 391.573512 -42.426382)
		(width 0.254)
		(layer "B.Cu")
		(net "GND")
	)
	(segment
		(start 281.399996 -2.302256)
		(end 281.387296 -2.314956)
		(width 0.4064)
		(layer "B.Cu")
		(net "GND")
	)
	(segment
		(start 152.146 -8.128)
		(end 152.146 -7.132828)
		(width 0.4064)
		(layer "B.Cu")
		(net "GND")
	)
	(segment
		(start 56.899302 -132.530596)
		(end 56.899302 -131.016756)
		(width 0.4064)
		(layer "B.Cu")
		(net "GND")
	)
	(segment
		(start 89.789 -135.4074)
		(end 89.925144 -135.4074)
		(width 0.4064)
		(layer "B.Cu")
		(net "GND")
	)
	(segment
		(start 308.511956 -3.737356)
		(end 308.5084 -3.737356)
		(width 0.254)
		(layer "B.Cu")
		(net "GND")
	)
	(segment
		(start 284.799786 -132.875782)
		(end 284.799786 -132.062982)
		(width 0.3556)
		(layer "B.Cu")
		(net "GND")
	)
	(segment
		(start 202.349862 -137.877296)
		(end 202.349862 -139.170156)
		(width 0.4064)
		(layer "B.Cu")
		(net "GND")
	)
	(segment
		(start 216.787222 -139.170156)
		(end 216.761822 -139.170156)
		(width 0.4064)
		(layer "B.Cu")
		(net "GND")
	)
	(segment
		(start 500.9642 -140.3858)
		(end 500.5578 -139.9794)
		(width 0.254)
		(layer "B.Cu")
		(net "GND")
	)
	(segment
		(start 77.82052 -28.85186)
		(end 78.102968 -28.569412)
		(width 0.381)
		(layer "B.Cu")
		(net "GND")
	)
	(segment
		(start 129.149348 -24.824182)
		(end 129.149348 -26.224484)
		(width 0.4064)
		(layer "B.Cu")
		(net "GND")
	)
	(segment
		(start 236.349794 -7.4676)
		(end 236.349794 -5.621782)
		(width 0.4064)
		(layer "B.Cu")
		(net "GND")
	)
	(segment
		(start 150.399496 -20.224242)
		(end 150.399496 -21.517356)
		(width 0.4064)
		(layer "B.Cu")
		(net "GND")
	)
	(segment
		(start 61.745368 -131.7498)
		(end 61.745368 -131.092956)
		(width 0.4064)
		(layer "B.Cu")
		(net "GND")
	)
	(segment
		(start 41.599358 -17.110202)
		(end 41.501314 -17.208246)
		(width 0.4064)
		(layer "B.Cu")
		(net "GND")
	)
	(segment
		(start 292.450012 -147.478496)
		(end 292.45052 -147.478496)
		(width 0.4064)
		(layer "B.Cu")
		(net "GND")
	)
	(segment
		(start 436.638446 -148.9075)
		(end 437.0197 -148.9075)
		(width 0.254)
		(layer "B.Cu")
		(net "GND")
	)
	(segment
		(start 39.899336 -5.621782)
		(end 39.899336 -7.607046)
		(width 0.4064)
		(layer "B.Cu")
		(net "GND")
	)
	(segment
		(start 375.93016 -97.58934)
		(end 376.428 -98.08718)
		(width 0.254)
		(layer "B.Cu")
		(net "GND")
	)
	(segment
		(start 374.74271 -76.292964)
		(end 374.742964 -76.292964)
		(width 0.254)
		(layer "B.Cu")
		(net "GND")
	)
	(segment
		(start 125.749558 -1.021842)
		(end 125.749558 -2.302256)
		(width 0.4064)
		(layer "B.Cu")
		(net "GND")
	)
	(segment
		(start 204.049884 -18.757646)
		(end 204.049884 -20.224242)
		(width 0.4064)
		(layer "B.Cu")
		(net "GND")
	)
	(segment
		(start 17.378172 -82.677)
		(end 17.3482 -82.706972)
		(width 0.254)
		(layer "B.Cu")
		(net "GND")
	)
	(segment
		(start 91.143074 -150.098506)
		(end 90.626692 -150.098506)
		(width 0.381)
		(layer "B.Cu")
		(net "GND")
	)
	(segment
		(start 127.44958 -18.80235)
		(end 127.44958 -20.224242)
		(width 0.4064)
		(layer "B.Cu")
		(net "GND")
	)
	(segment
		(start 243.149882 -147.478242)
		(end 243.149882 -147.478496)
		(width 0.4064)
		(layer "B.Cu")
		(net "GND")
	)
	(segment
		(start 117.00383 -4.5212)
		(end 117.00383 -4.597146)
		(width 0.254)
		(layer "B.Cu")
		(net "GND")
	)
	(segment
		(start 145.053812 -23.799546)
		(end 145.29943 -24.045164)
		(width 0.254)
		(layer "B.Cu")
		(net "GND")
	)
	(segment
		(start 411.372812 -92.211906)
		(end 411.662118 -91.9226)
		(width 0.254)
		(layer "B.Cu")
		(net "GND")
	)
	(segment
		(start 237.20044 -10.623042)
		(end 237.199932 -10.623042)
		(width 0.4064)
		(layer "B.Cu")
		(net "GND")
	)
	(segment
		(start 198.087234 -129.568956)
		(end 198.061834 -129.568956)
		(width 0.4064)
		(layer "B.Cu")
		(net "GND")
	)
	(segment
		(start 44.149518 -128.276096)
		(end 44.149518 -129.488692)
		(width 0.4064)
		(layer "B.Cu")
		(net "GND")
	)
	(segment
		(start 218.500452 -147.478496)
		(end 218.499944 -147.478496)
		(width 0.4064)
		(layer "B.Cu")
		(net "GND")
	)
	(segment
		(start 369.145058 -77.8383)
		(end 369.488466 -77.494892)
		(width 0.254)
		(layer "B.Cu")
		(net "GND")
	)
	(segment
		(start 449.6943 -130.7719)
		(end 449.6943 -131.971796)
		(width 0.254)
		(layer "B.Cu")
		(net "GND")
	)
	(segment
		(start 236.095794 -23.6982)
		(end 236.095794 -23.041356)
		(width 0.4064)
		(layer "B.Cu")
		(net "GND")
	)
	(segment
		(start 208.0514 -13.434568)
		(end 208.122012 -13.363956)
		(width 0.4064)
		(layer "B.Cu")
		(net "GND")
	)
	(segment
		(start 263.7028 -25.6794)
		(end 263.1186 -25.0952)
		(width 0.381)
		(layer "B.Cu")
		(net "GND")
	)
	(segment
		(start 469.13927 -138.557)
		(end 469.6206 -138.557)
		(width 0.254)
		(layer "B.Cu")
		(net "GND")
	)
	(segment
		(start 289.899852 -25.709372)
		(end 289.113468 -26.495756)
		(width 0.4064)
		(layer "B.Cu")
		(net "GND")
	)
	(segment
		(start 116.386864 -2.314956)
		(end 116.361464 -2.314956)
		(width 0.4064)
		(layer "B.Cu")
		(net "GND")
	)
	(segment
		(start 43.050968 -131.074668)
		(end 43.12158 -131.004056)
		(width 0.254)
		(layer "B.Cu")
		(net "GND")
	)
	(segment
		(start 365.379 -41.4782)
		(end 366.268 -41.4782)
		(width 0.254)
		(layer "B.Cu")
		(net "GND")
	)
	(segment
		(start 317.09995 -135.335518)
		(end 317.09995 -134.340346)
		(width 0.4064)
		(layer "B.Cu")
		(net "GND")
	)
	(segment
		(start 26.8478 -30.988)
		(end 26.8478 -32.268414)
		(width 0.254)
		(layer "B.Cu")
		(net "GND")
	)
	(segment
		(start 195.550282 -24.824182)
		(end 195.549774 -24.824182)
		(width 0.4064)
		(layer "B.Cu")
		(net "GND")
	)
	(segment
		(start 242.300506 -15.222982)
		(end 242.299998 -15.222982)
		(width 0.4064)
		(layer "B.Cu")
		(net "GND")
	)
	(segment
		(start 290.74999 -9.156446)
		(end 290.74999 -10.623042)
		(width 0.4064)
		(layer "B.Cu")
		(net "GND")
	)
	(segment
		(start 395.780006 -27.195018)
		(end 395.780006 -27.403806)
		(width 0.254)
		(layer "B.Cu")
		(net "GND")
	)
	(segment
		(start 25.509474 -82.430366)
		(end 25.34158 -82.59826)
		(width 0.254)
		(layer "B.Cu")
		(net "GND")
	)
	(segment
		(start 48.399446 -9.156446)
		(end 48.399446 -10.623042)
		(width 0.4064)
		(layer "B.Cu")
		(net "GND")
	)
	(segment
		(start 38.199568 -131.01701)
		(end 38.199314 -131.016756)
		(width 0.4064)
		(layer "B.Cu")
		(net "GND")
	)
	(segment
		(start 208.0514 -4.645152)
		(end 208.0514 -3.833368)
		(width 0.4064)
		(layer "B.Cu")
		(net "GND")
	)
	(segment
		(start 197.160896 -141.280642)
		(end 197.160896 -140.592556)
		(width 0.4064)
		(layer "B.Cu")
		(net "GND")
	)
	(segment
		(start 70.499478 -20.224242)
		(end 70.499478 -21.479256)
		(width 0.4064)
		(layer "B.Cu")
		(net "GND")
	)
	(segment
		(start 61.821568 -22.965156)
		(end 61.745368 -23.041356)
		(width 0.4064)
		(layer "B.Cu")
		(net "GND")
	)
	(segment
		(start 402.717 -25.654)
		(end 402.573998 -25.654)
		(width 0.254)
		(layer "B.Cu")
		(net "GND")
	)
	(segment
		(start 48.399446 -20.224242)
		(end 48.399446 -21.517356)
		(width 0.4064)
		(layer "B.Cu")
		(net "GND")
	)
	(segment
		(start 382.524 -47.38878)
		(end 382.016 -47.38878)
		(width 0.254)
		(layer "B.Cu")
		(net "GND")
	)
	(segment
		(start 281.686 -81.6102)
		(end 282.0162 -81.6102)
		(width 0.254)
		(layer "B.Cu")
		(net "GND")
	)
	(segment
		(start 310.054244 -151.053546)
		(end 310.054244 -150.9776)
		(width 0.254)
		(layer "B.Cu")
		(net "GND")
	)
	(segment
		(start 67.949572 -5.621782)
		(end 67.949572 -7.606792)
		(width 0.4064)
		(layer "B.Cu")
		(net "GND")
	)
	(segment
		(start 312.849768 -15.222982)
		(end 312.849768 -14.409928)
		(width 0.4064)
		(layer "B.Cu")
		(net "GND")
	)
	(segment
		(start 136.799574 -18.80235)
		(end 136.799574 -20.224242)
		(width 0.4064)
		(layer "B.Cu")
		(net "GND")
	)
	(segment
		(start 314.760102 -29.10205)
		(end 315.0997 -28.762452)
		(width 0.254)
		(layer "B.Cu")
		(net "GND")
	)
	(segment
		(start 50.949352 -142.477236)
		(end 50.949352 -140.706856)
		(width 0.4064)
		(layer "B.Cu")
		(net "GND")
	)
	(segment
		(start 152.626568 -135.376412)
		(end 152.099518 -134.849362)
		(width 0.4064)
		(layer "B.Cu")
		(net "GND")
	)
	(segment
		(start 201.499978 -152.078182)
		(end 201.499978 -151.265382)
		(width 0.4064)
		(layer "B.Cu")
		(net "GND")
	)
	(segment
		(start 208.30032 -15.222982)
		(end 208.299812 -15.222982)
		(width 0.4064)
		(layer "B.Cu")
		(net "GND")
	)
	(segment
		(start 65.399412 -137.877296)
		(end 65.399412 -139.170156)
		(width 0.4064)
		(layer "B.Cu")
		(net "GND")
	)
	(segment
		(start 196.342 -154.6352)
		(end 196.342 -155.542234)
		(width 0.4064)
		(layer "B.Cu")
		(net "GND")
	)
	(segment
		(start 145.29943 -142.477236)
		(end 145.29943 -141.697964)
		(width 0.254)
		(layer "B.Cu")
		(net "GND")
	)
	(segment
		(start 447.6242 -13.1064)
		(end 447.90233 -13.38453)
		(width 0.254)
		(layer "B.Cu")
		(net "GND")
	)
	(segment
		(start 115.549426 -150.308056)
		(end 115.460526 -150.219156)
		(width 0.4064)
		(layer "B.Cu")
		(net "GND")
	)
	(segment
		(start 53.442108 -11.893296)
		(end 53.442108 -11.912092)
		(width 0.4064)
		(layer "B.Cu")
		(net "GND")
	)
	(segment
		(start 449.326 -150.1394)
		(end 449.326 -149.3901)
		(width 0.254)
		(layer "B.Cu")
		(net "GND")
	)
	(segment
		(start 225.299778 -17.110202)
		(end 225.299778 -15.222982)
		(width 0.4064)
		(layer "B.Cu")
		(net "GND")
	)
	(segment
		(start 210.849972 -4.808982)
		(end 210.849972 -5.621782)
		(width 0.4064)
		(layer "B.Cu")
		(net "GND")
	)
	(segment
		(start 374.742964 -76.292964)
		(end 375.145046 -76.695046)
		(width 0.254)
		(layer "B.Cu")
		(net "GND")
	)
	(segment
		(start 67.099434 -1.021842)
		(end 67.099434 -2.314956)
		(width 0.4064)
		(layer "B.Cu")
		(net "GND")
	)
	(segment
		(start 286.500316 -142.477236)
		(end 286.499808 -142.476982)
		(width 0.4064)
		(layer "B.Cu")
		(net "GND")
	)
	(segment
		(start 413.511492 -43.242992)
		(end 413.3215 -43.053)
		(width 0.254)
		(layer "B.Cu")
		(net "GND")
	)
	(segment
		(start 399.3642 -106.172)
		(end 399.345404 -106.190796)
		(width 0.254)
		(layer "B.Cu")
		(net "GND")
	)
	(segment
		(start 69.64934 -150.308056)
		(end 69.56044 -150.219156)
		(width 0.4064)
		(layer "B.Cu")
		(net "GND")
	)
	(segment
		(start 314.550298 -24.824182)
		(end 314.54979 -24.824182)
		(width 0.4064)
		(layer "B.Cu")
		(net "GND")
	)
	(segment
		(start 110.286546 -135.4074)
		(end 110.33633 -135.357616)
		(width 0.4572)
		(layer "B.Cu")
		(net "GND")
	)
	(segment
		(start 445.5922 -157.154372)
		(end 444.687706 -157.154372)
		(width 0.254)
		(layer "B.Cu")
		(net "GND")
	)
	(segment
		(start 301.800006 -21.455888)
		(end 301.742602 -21.513292)
		(width 0.4064)
		(layer "B.Cu")
		(net "GND")
	)
	(segment
		(start 316.25032 -152.078436)
		(end 316.249812 -152.078182)
		(width 0.4064)
		(layer "B.Cu")
		(net "GND")
	)
	(segment
		(start 232.950004 -151.78405)
		(end 232.94975 -151.783796)
		(width 0.4064)
		(layer "B.Cu")
		(net "GND")
	)
	(segment
		(start 295.849802 -25.654508)
		(end 296.69105 -26.495756)
		(width 0.4064)
		(layer "B.Cu")
		(net "GND")
	)
	(segment
		(start 85.761068 -3.3528)
		(end 84.910168 -3.3528)
		(width 0.4572)
		(layer "B.Cu")
		(net "GND")
	)
	(segment
		(start 73.437496 -4.346956)
		(end 73.899522 -4.808982)
		(width 0.4064)
		(layer "B.Cu")
		(net "GND")
	)
	(segment
		(start 192.024 -135.763)
		(end 192.024 -136.398)
		(width 0.4064)
		(layer "B.Cu")
		(net "GND")
	)
	(segment
		(start 148.699474 -18.757646)
		(end 148.699474 -20.224242)
		(width 0.4064)
		(layer "B.Cu")
		(net "GND")
	)
	(segment
		(start 292.450012 -11.835892)
		(end 292.392608 -11.893296)
		(width 0.4064)
		(layer "B.Cu")
		(net "GND")
	)
	(segment
		(start 123.199398 -7.607046)
		(end 123.199398 -5.621782)
		(width 0.4064)
		(layer "B.Cu")
		(net "GND")
	)
	(segment
		(start 289.049968 -128.276096)
		(end 289.049968 -129.568956)
		(width 0.4064)
		(layer "B.Cu")
		(net "GND")
	)
	(segment
		(start 130.84937 -24.824182)
		(end 130.84937 -25.654508)
		(width 0.4064)
		(layer "B.Cu")
		(net "GND")
	)
	(segment
		(start 43.29938 -15.222982)
		(end 43.29938 -17.0688)
		(width 0.4064)
		(layer "B.Cu")
		(net "GND")
	)
	(segment
		(start 126.599442 -7.4676)
		(end 126.421642 -7.6454)
		(width 0.4064)
		(layer "B.Cu")
		(net "GND")
	)
	(segment
		(start 458.355954 -135.9662)
		(end 459.169008 -136.779254)
		(width 0.508)
		(layer "B.Cu")
		(net "GND")
	)
	(segment
		(start 468.8205 -138.23823)
		(end 469.13927 -138.557)
		(width 0.254)
		(layer "B.Cu")
		(net "GND")
	)
	(segment
		(start 408.183588 -21.336)
		(end 408.691588 -20.828)
		(width 0.254)
		(layer "B.Cu")
		(net "GND")
	)
	(segment
		(start 136.799574 -129.488692)
		(end 136.74217 -129.546096)
		(width 0.4064)
		(layer "B.Cu")
		(net "GND")
	)
	(segment
		(start 241.44986 0.444754)
		(end 241.44986 -1.021842)
		(width 0.4064)
		(layer "B.Cu")
		(net "GND")
	)
	(segment
		(start 32.160464 -131.679442)
		(end 32.160464 -130.991356)
		(width 0.4064)
		(layer "B.Cu")
		(net "GND")
	)
	(segment
		(start 77.299566 -134.188454)
		(end 77.299566 -132.876036)
		(width 0.508)
		(layer "B.Cu")
		(net "GND")
	)
	(segment
		(start 284.799786 -132.062982)
		(end 284.33776 -131.600956)
		(width 0.4064)
		(layer "B.Cu")
		(net "GND")
	)
	(segment
		(start 61.149484 -137.877296)
		(end 61.149484 -139.157456)
		(width 0.4064)
		(layer "B.Cu")
		(net "GND")
	)
	(segment
		(start 281.399996 -148.758656)
		(end 281.387296 -148.771356)
		(width 0.4064)
		(layer "B.Cu")
		(net "GND")
	)
	(segment
		(start 222.749872 -21.517356)
		(end 222.749872 -20.224242)
		(width 0.4064)
		(layer "B.Cu")
		(net "GND")
	)
	(segment
		(start 114.699542 -1.021842)
		(end 114.699542 -2.314956)
		(width 0.4064)
		(layer "B.Cu")
		(net "GND")
	)
	(segment
		(start 198.7042 -141.452346)
		(end 198.7042 -141.3764)
		(width 0.254)
		(layer "B.Cu")
		(net "GND")
	)
	(segment
		(start 378.841 -61.3156)
		(end 378.841 -61.247528)
		(width 0.254)
		(layer "B.Cu")
		(net "GND")
	)
	(segment
		(start 305.199796 -5.621782)
		(end 305.199796 -3.762756)
		(width 0.4064)
		(layer "B.Cu")
		(net "GND")
	)
	(segment
		(start 278.850344 -20.224242)
		(end 278.849836 -20.224242)
		(width 0.4064)
		(layer "B.Cu")
		(net "GND")
	)
	(segment
		(start 312.849768 -5.621782)
		(end 312.849768 -4.808728)
		(width 0.4064)
		(layer "B.Cu")
		(net "GND")
	)
	(segment
		(start 223.600518 -142.477236)
		(end 223.60001 -142.476982)
		(width 0.4064)
		(layer "B.Cu")
		(net "GND")
	)
	(segment
		(start 434.94325 -13.60805)
		(end 434.06695 -13.60805)
		(width 0.254)
		(layer "B.Cu")
		(net "GND")
	)
	(segment
		(start 163.80206 -85.598)
		(end 163.80206 -85.948266)
		(width 0.4064)
		(layer "B.Cu")
		(net "GND")
	)
	(segment
		(start 197.160896 -130.991356)
		(end 197.249796 -131.080256)
		(width 0.4064)
		(layer "B.Cu")
		(net "GND")
	)
	(segment
		(start 58.599578 -17.207992)
		(end 58.599578 -15.222982)
		(width 0.4064)
		(layer "B.Cu")
		(net "GND")
	)
	(segment
		(start 312.850276 -15.222982)
		(end 312.849768 -15.222982)
		(width 0.4064)
		(layer "B.Cu")
		(net "GND")
	)
	(segment
		(start 306.900326 -24.824182)
		(end 306.899818 -24.824182)
		(width 0.4064)
		(layer "B.Cu")
		(net "GND")
	)
	(segment
		(start 128.836928 -64.934338)
		(end 128.227328 -64.324738)
		(width 0.254)
		(layer "B.Cu")
		(net "GND")
	)
	(segment
		(start 278.850344 -128.276096)
		(end 278.849836 -128.276096)
		(width 0.4064)
		(layer "B.Cu")
		(net "GND")
	)
	(segment
		(start 239.749838 -18.757646)
		(end 239.749838 -20.224242)
		(width 0.4064)
		(layer "B.Cu")
		(net "GND")
	)
	(segment
		(start 42.365168 -104.252776)
		(end 41.883838 -104.252776)
		(width 0.254)
		(layer "B.Cu")
		(net "GND")
	)
	(segment
		(start 198.949818 -141.697964)
		(end 198.7042 -141.452346)
		(width 0.254)
		(layer "B.Cu")
		(net "GND")
	)
	(segment
		(start 208.299812 -132.147564)
		(end 208.0514 -131.899152)
		(width 0.254)
		(layer "B.Cu")
		(net "GND")
	)
	(segment
		(start 282.24988 -7.4676)
		(end 282.07208 -7.6454)
		(width 0.4064)
		(layer "B.Cu")
		(net "GND")
	)
	(segment
		(start 282.004262 -141.452346)
		(end 282.004262 -140.660374)
		(width 0.254)
		(layer "B.Cu")
		(net "GND")
	)
	(segment
		(start 315.399928 -137.877296)
		(end 315.399928 -139.170156)
		(width 0.4064)
		(layer "B.Cu")
		(net "GND")
	)
	(segment
		(start 66.24955 -14.85265)
		(end 66.249296 -14.852396)
		(width 0.4064)
		(layer "B.Cu")
		(net "GND")
	)
	(segment
		(start 31.443168 -135.3312)
		(end 31.443168 -136.354058)
		(width 0.4064)
		(layer "B.Cu")
		(net "GND")
	)
	(segment
		(start 324.904862 -119.80164)
		(end 325.5264 -120.423178)
		(width 0.254)
		(layer "B.Cu")
		(net "GND")
	)
	(segment
		(start 301.800006 -10.623042)
		(end 301.800006 -9.20115)
		(width 0.4064)
		(layer "B.Cu")
		(net "GND")
	)
	(segment
		(start 78.102968 -28.569412)
		(end 78.102968 -27.813)
		(width 0.381)
		(layer "B.Cu")
		(net "GND")
	)
	(segment
		(start 406.347168 -14.7193)
		(end 405.6507 -15.415768)
		(width 0.254)
		(layer "B.Cu")
		(net "GND")
	)
	(segment
		(start 372.0211 -89.249504)
		(end 372.379494 -88.89111)
		(width 0.254)
		(layer "B.Cu")
		(net "GND")
	)
	(segment
		(start 410.379418 -92.860114)
		(end 410.633418 -93.114114)
		(width 0.254)
		(layer "B.Cu")
		(net "GND")
	)
	(segment
		(start 141.899386 -132.876036)
		(end 141.899386 -131.016756)
		(width 0.4064)
		(layer "B.Cu")
		(net "GND")
	)
	(segment
		(start 443.552326 -147.663154)
		(end 443.552326 -148.140674)
		(width 0.254)
		(layer "B.Cu")
		(net "GND")
	)
	(segment
		(start 459.792832 -130.9624)
		(end 459.1304 -130.9624)
		(width 0.254)
		(layer "B.Cu")
		(net "GND")
	)
	(segment
		(start 102.7938 -12.954)
		(end 103.678736 -12.954)
		(width 0.4064)
		(layer "B.Cu")
		(net "GND")
	)
	(segment
		(start 78.14945 -136.387078)
		(end 78.14945 -137.877042)
		(width 0.508)
		(layer "B.Cu")
		(net "GND")
	)
	(segment
		(start 77.299566 -24.40305)
		(end 77.299566 -24.824182)
		(width 0.4064)
		(layer "B.Cu")
		(net "GND")
	)
	(segment
		(start 25.34158 -82.59826)
		(end 25.34158 -82.613246)
		(width 0.254)
		(layer "B.Cu")
		(net "GND")
	)
	(segment
		(start 203.2 -150.21941)
		(end 203.199746 -150.219156)
		(width 0.4064)
		(layer "B.Cu")
		(net "GND")
	)
	(segment
		(start 67.099434 -9.156446)
		(end 67.099434 -10.623042)
		(width 0.4064)
		(layer "B.Cu")
		(net "GND")
	)
	(segment
		(start 47.549562 -151.78405)
		(end 47.549308 -151.783796)
		(width 0.4064)
		(layer "B.Cu")
		(net "GND")
	)
	(segment
		(start 240.600484 -152.078436)
		(end 240.599976 -152.078182)
		(width 0.4064)
		(layer "B.Cu")
		(net "GND")
	)
	(segment
		(start 233.799888 -1.021842)
		(end 233.799888 0.457454)
		(width 0.4064)
		(layer "B.Cu")
		(net "GND")
	)
	(segment
		(start 21.6662 -85.2805)
		(end 21.6662 -85.2424)
		(width 0.254)
		(layer "B.Cu")
		(net "GND")
	)
	(segment
		(start 202.349862 -20.224242)
		(end 202.349862 -18.757646)
		(width 0.4064)
		(layer "B.Cu")
		(net "GND")
	)
	(segment
		(start 420.624 -21.463)
		(end 421.132 -21.463)
		(width 0.254)
		(layer "B.Cu")
		(net "GND")
	)
	(segment
		(start 195.2244 -153.6446)
		(end 195.5038 -153.6446)
		(width 0.4064)
		(layer "B.Cu")
		(net "GND")
	)
	(segment
		(start 298.399962 -137.877296)
		(end 298.40047 -137.877296)
		(width 0.4064)
		(layer "B.Cu")
		(net "GND")
	)
	(segment
		(start 135.703818 -23.7236)
		(end 135.703818 -23.799546)
		(width 0.254)
		(layer "B.Cu")
		(net "GND")
	)
	(segment
		(start 313.203844 -28.64104)
		(end 312.350404 -28.64104)
		(width 0.381)
		(layer "B.Cu")
		(net "GND")
	)
	(segment
		(start 61.999368 -24.0538)
		(end 61.999368 -24.824182)
		(width 0.254)
		(layer "B.Cu")
		(net "GND")
	)
	(segment
		(start 49.249584 -15.222982)
		(end 49.249584 -17.207992)
		(width 0.4064)
		(layer "B.Cu")
		(net "GND")
	)
	(segment
		(start 74.749406 -18.757646)
		(end 74.749406 -20.224242)
		(width 0.4064)
		(layer "B.Cu")
		(net "GND")
	)
	(segment
		(start 237.199932 -18.80235)
		(end 237.199932 -20.224242)
		(width 0.4064)
		(layer "B.Cu")
		(net "GND")
	)
	(segment
		(start 14.445488 -78.438502)
		(end 14.445488 -78.8797)
		(width 0.508)
		(layer "B.Cu")
		(net "GND")
	)
	(segment
		(start 138.499342 -6.637274)
		(end 138.499342 -5.621782)
		(width 0.4064)
		(layer "B.Cu")
		(net "GND")
	)
	(segment
		(start 14.061186 -78.0542)
		(end 14.445488 -78.438502)
		(width 0.508)
		(layer "B.Cu")
		(net "GND")
	)
	(segment
		(start 414.528 -20.3962)
		(end 414.528 -21.082)
		(width 0.254)
		(layer "B.Cu")
		(net "GND")
	)
	(segment
		(start 256.167636 -150.105364)
		(end 256.4892 -149.7838)
		(width 0.381)
		(layer "B.Cu")
		(net "GND")
	)
	(segment
		(start 142.749524 -10.623042)
		(end 142.749524 -9.143746)
		(width 0.4064)
		(layer "B.Cu")
		(net "GND")
	)
	(segment
		(start 283.099764 -129.488692)
		(end 283.099764 -128.276096)
		(width 0.4064)
		(layer "B.Cu")
		(net "GND")
	)
	(segment
		(start 67.949572 -132.876036)
		(end 67.949572 -132.58165)
		(width 0.4064)
		(layer "B.Cu")
		(net "GND")
	)
	(segment
		(start 380.365 -19.304)
		(end 380.365 -20.193)
		(width 0.254)
		(layer "B.Cu")
		(net "GND")
	)
	(segment
		(start 310.054244 -141.452346)
		(end 310.299862 -141.697964)
		(width 0.254)
		(layer "B.Cu")
		(net "GND")
	)
	(segment
		(start 36.499546 -24.011382)
		(end 36.03752 -23.549356)
		(width 0.4064)
		(layer "B.Cu")
		(net "GND")
	)
	(segment
		(start 41.501314 -7.607046)
		(end 41.599358 -7.509002)
		(width 0.4064)
		(layer "B.Cu")
		(net "GND")
	)
	(segment
		(start 209.092546 -11.893296)
		(end 209.14995 -11.835892)
		(width 0.4064)
		(layer "B.Cu")
		(net "GND")
	)
	(segment
		(start 291.354256 -23.7236)
		(end 291.354256 -23.032974)
		(width 0.4064)
		(layer "B.Cu")
		(net "GND")
	)
	(segment
		(start 215.950292 -132.876036)
		(end 215.949784 -132.875782)
		(width 0.4064)
		(layer "B.Cu")
		(net "GND")
	)
	(segment
		(start 221.900496 -5.621782)
		(end 221.899988 -5.621782)
		(width 0.4064)
		(layer "B.Cu")
		(net "GND")
	)
	(segment
		(start 313.424062 -28.420822)
		(end 313.203844 -28.64104)
		(width 0.381)
		(layer "B.Cu")
		(net "GND")
	)
	(segment
		(start 476.936816 -146.359372)
		(end 476.936816 -146.533616)
		(width 0.254)
		(layer "B.Cu")
		(net "GND")
	)
	(segment
		(start 492.97844 -131.95681)
		(end 493.653572 -132.631942)
		(width 0.254)
		(layer "B.Cu")
		(net "GND")
	)
	(segment
		(start 451.436994 -28.552648)
		(end 451.781672 -28.897326)
		(width 0.4064)
		(layer "B.Cu")
		(net "GND")
	)
	(segment
		(start 56.049418 -18.757646)
		(end 56.049418 -20.224242)
		(width 0.4064)
		(layer "B.Cu")
		(net "GND")
	)
	(segment
		(start 215.860884 -22.965156)
		(end 215.860884 -22.939756)
		(width 0.4064)
		(layer "B.Cu")
		(net "GND")
	)
	(segment
		(start 66.249296 -3.762756)
		(end 66.249296 -5.251196)
		(width 0.4064)
		(layer "B.Cu")
		(net "GND")
	)
	(segment
		(start 152.626568 2.19202)
		(end 152.626568 1.928368)
		(width 0.4064)
		(layer "B.Cu")
		(net "GND")
	)
	(segment
		(start 300.949868 -17.0688)
		(end 300.949868 -15.222982)
		(width 0.4064)
		(layer "B.Cu")
		(net "GND")
	)
	(segment
		(start 249.9106 -8.1534)
		(end 250.7615 -8.1534)
		(width 0.4572)
		(layer "B.Cu")
		(net "GND")
	)
	(segment
		(start 231.8004 -84.7852)
		(end 233.008932 -84.7852)
		(width 0.1524)
		(layer "B.Cu")
		(net "GND")
	)
	(segment
		(start 231.249728 -142.106396)
		(end 231.249728 -140.617956)
		(width 0.4064)
		(layer "B.Cu")
		(net "GND")
	)
	(segment
		(start 301.800006 -129.488692)
		(end 301.742602 -129.546096)
		(width 0.4064)
		(layer "B.Cu")
		(net "GND")
	)
	(segment
		(start 195.549774 -132.875782)
		(end 195.549774 -131.5466)
		(width 0.4064)
		(layer "B.Cu")
		(net "GND")
	)
	(segment
		(start 285.649924 -10.623042)
		(end 285.649924 -11.916156)
		(width 0.4064)
		(layer "B.Cu")
		(net "GND")
	)
	(segment
		(start 237.199932 -1.021842)
		(end 237.199932 0.40005)
		(width 0.4064)
		(layer "B.Cu")
		(net "GND")
	)
	(segment
		(start 282.004262 -131.902708)
		(end 282.004262 -131.059174)
		(width 0.3556)
		(layer "B.Cu")
		(net "GND")
	)
	(segment
		(start 292.450012 -9.20115)
		(end 292.450012 -10.623042)
		(width 0.4064)
		(layer "B.Cu")
		(net "GND")
	)
	(segment
		(start 444.02248 -147.693634)
		(end 443.992 -147.663154)
		(width 0.254)
		(layer "B.Cu")
		(net "GND")
	)
	(segment
		(start 297.549824 -15.222982)
		(end 297.549824 -13.363956)
		(width 0.4064)
		(layer "B.Cu")
		(net "GND")
	)
	(segment
		(start 308.59984 -152.078182)
		(end 308.600348 -152.078436)
		(width 0.4064)
		(layer "B.Cu")
		(net "GND")
	)
	(segment
		(start 286.500316 -150.219664)
		(end 286.499808 -150.219156)
		(width 0.4064)
		(layer "B.Cu")
		(net "GND")
	)
	(segment
		(start 267.794232 -140.208)
		(end 268.679168 -140.208)
		(width 0.4572)
		(layer "B.Cu")
		(net "GND")
	)
	(segment
		(start 216.799922 -10.623042)
		(end 216.799922 -11.903456)
		(width 0.4064)
		(layer "B.Cu")
		(net "GND")
	)
	(segment
		(start 246.619268 -145.0086)
		(end 247.4595 -145.0086)
		(width 0.4572)
		(layer "B.Cu")
		(net "GND")
	)
	(segment
		(start 299.249846 -142.476982)
		(end 299.249846 -140.706856)
		(width 0.4064)
		(layer "B.Cu")
		(net "GND")
	)
	(segment
		(start 156.68498 -8.128)
		(end 156.690568 -8.122412)
		(width 0.254)
		(layer "B.Cu")
		(net "GND")
	)
	(segment
		(start 458.422756 -21.2471)
		(end 457.495656 -20.32)
		(width 0.254)
		(layer "B.Cu")
		(net "GND")
	)
	(segment
		(start 472.233498 -135.78459)
		(end 472.233498 -135.684514)
		(width 0.254)
		(layer "B.Cu")
		(net "GND")
	)
	(segment
		(start 75.599544 -152.078436)
		(end 75.599544 -151.70785)
		(width 0.4064)
		(layer "B.Cu")
		(net "GND")
	)
	(segment
		(start 369.527836 -98.68154)
		(end 369.527836 -97.476564)
		(width 0.254)
		(layer "B.Cu")
		(net "GND")
	)
	(segment
		(start 291.600382 -152.078436)
		(end 291.600382 -151.299672)
		(width 0.254)
		(layer "B.Cu")
		(net "GND")
	)
	(segment
		(start 135.703818 -151.053546)
		(end 135.703818 -150.9776)
		(width 0.254)
		(layer "B.Cu")
		(net "GND")
	)
	(segment
		(start 56.899302 -3.762756)
		(end 56.899302 -5.276596)
		(width 0.4064)
		(layer "B.Cu")
		(net "GND")
	)
	(segment
		(start 237.142528 -129.546096)
		(end 237.142528 -129.564892)
		(width 0.4064)
		(layer "B.Cu")
		(net "GND")
	)
	(segment
		(start 217.649806 -7.4676)
		(end 217.649806 -5.621782)
		(width 0.4064)
		(layer "B.Cu")
		(net "GND")
	)
	(segment
		(start 123.199398 -17.208246)
		(end 123.199398 -15.222982)
		(width 0.4064)
		(layer "B.Cu")
		(net "GND")
	)
	(segment
		(start 77.299566 -142.477236)
		(end 77.299566 -143.799306)
		(width 0.508)
		(layer "B.Cu")
		(net "GND")
	)
	(segment
		(start 289.050476 -1.021842)
		(end 289.049968 -1.021842)
		(width 0.4064)
		(layer "B.Cu")
		(net "GND")
	)
	(segment
		(start 165.862 -81.407)
		(end 166.5986 -81.407)
		(width 0.4064)
		(layer "B.Cu")
		(net "GND")
	)
	(segment
		(start 49.24933 -24.478996)
		(end 49.24933 -22.965156)
		(width 0.4064)
		(layer "B.Cu")
		(net "GND")
	)
	(segment
		(start 33.703768 -13.431774)
		(end 33.771586 -13.363956)
		(width 0.4064)
		(layer "B.Cu")
		(net "GND")
	)
	(segment
		(start 417.7538 -13.848334)
		(end 418.1094 -13.492734)
		(width 0.254)
		(layer "B.Cu")
		(net "GND")
	)
	(segment
		(start 405.404828 -54.9529)
		(end 405.404828 -55.626)
		(width 0.254)
		(layer "B.Cu")
		(net "GND")
	)
	(segment
		(start 208.0514 -150.277068)
		(end 208.122012 -150.206456)
		(width 0.254)
		(layer "B.Cu")
		(net "GND")
	)
	(segment
		(start 299.249846 -23.054056)
		(end 299.249846 -24.824182)
		(width 0.4064)
		(layer "B.Cu")
		(net "GND")
	)
	(segment
		(start 419.436804 -30.988)
		(end 419.490144 -30.93466)
		(width 0.254)
		(layer "B.Cu")
		(net "GND")
	)
	(segment
		(start 324.358 -120.86844)
		(end 325.5264 -120.86844)
		(width 0.254)
		(layer "B.Cu")
		(net "GND")
	)
	(segment
		(start 229.54996 -142.476982)
		(end 229.54996 -141.664182)
		(width 0.4064)
		(layer "B.Cu")
		(net "GND")
	)
	(segment
		(start 409.0543 -9.4742)
		(end 409.116784 -9.411716)
		(width 0.254)
		(layer "B.Cu")
		(net "GND")
	)
	(segment
		(start 134.160514 -22.939756)
		(end 134.160514 -22.965156)
		(width 0.4064)
		(layer "B.Cu")
		(net "GND")
	)
	(segment
		(start 163.576 -81.4832)
		(end 163.2458 -81.153)
		(width 0.4064)
		(layer "B.Cu")
		(net "GND")
	)
	(segment
		(start 147.849336 -132.876036)
		(end 147.849336 -132.062728)
		(width 0.4064)
		(layer "B.Cu")
		(net "GND")
	)
	(segment
		(start 199.799956 -139.089892)
		(end 199.742552 -139.147296)
		(width 0.4064)
		(layer "B.Cu")
		(net "GND")
	)
	(segment
		(start 59.449462 -20.224242)
		(end 59.449462 -18.744946)
		(width 0.4064)
		(layer "B.Cu")
		(net "GND")
	)
	(segment
		(start 227.000308 -5.621782)
		(end 226.9998 -5.621782)
		(width 0.254)
		(layer "B.Cu")
		(net "GND")
	)
	(segment
		(start 120.649492 -21.517356)
		(end 120.649492 -20.224242)
		(width 0.4064)
		(layer "B.Cu")
		(net "GND")
	)
	(segment
		(start 133.39953 -1.021842)
		(end 133.39953 -2.314956)
		(width 0.4064)
		(layer "B.Cu")
		(net "GND")
	)
	(segment
		(start 407.036016 4.141216)
		(end 406.8064 3.9116)
		(width 0.254)
		(layer "B.Cu")
		(net "GND")
	)
	(segment
		(start 449.1736 -130.2512)
		(end 449.6943 -130.7719)
		(width 0.254)
		(layer "B.Cu")
		(net "GND")
	)
	(segment
		(start 126.599442 -14.443964)
		(end 126.599442 -15.222982)
		(width 0.254)
		(layer "B.Cu")
		(net "GND")
	)
	(segment
		(start 315.399928 -20.224242)
		(end 315.399928 -18.757646)
		(width 0.4064)
		(layer "B.Cu")
		(net "GND")
	)
	(segment
		(start 131.699508 -9.156446)
		(end 131.699508 -10.623042)
		(width 0.4064)
		(layer "B.Cu")
		(net "GND")
	)
	(segment
		(start 370.29009 -65.411604)
		(end 370.29009 -64.985138)
		(width 0.254)
		(layer "B.Cu")
		(net "GND")
	)
	(segment
		(start 299.249846 -150.308056)
		(end 299.160946 -150.219156)
		(width 0.4064)
		(layer "B.Cu")
		(net "GND")
	)
	(segment
		(start 218.500452 -10.623042)
		(end 218.499944 -10.623042)
		(width 0.4064)
		(layer "B.Cu")
		(net "GND")
	)
	(segment
		(start 215.949784 -132.875782)
		(end 215.949784 -131.105656)
		(width 0.4064)
		(layer "B.Cu")
		(net "GND")
	)
	(segment
		(start 310.122062 -140.617956)
		(end 310.054244 -140.685774)
		(width 0.4064)
		(layer "B.Cu")
		(net "GND")
	)
	(segment
		(start 483.782624 -144.5514)
		(end 483.241096 -144.009872)
		(width 0.254)
		(layer "B.Cu")
		(net "GND")
	)
	(segment
		(start 229.50805 -87.5792)
		(end 229.81158 -87.27567)
		(width 0.254)
		(layer "B.Cu")
		(net "GND")
	)
	(segment
		(start 285.650432 -137.877296)
		(end 285.649924 -137.877296)
		(width 0.4064)
		(layer "B.Cu")
		(net "GND")
	)
	(segment
		(start 434.132482 -149.5298)
		(end 434.132482 -148.520658)
		(width 0.4064)
		(layer "B.Cu")
		(net "GND")
	)
	(segment
		(start 229.550468 -142.477236)
		(end 229.54996 -142.476982)
		(width 0.4064)
		(layer "B.Cu")
		(net "GND")
	)
	(segment
		(start 125.749558 -128.276096)
		(end 125.749558 -129.556256)
		(width 0.4064)
		(layer "B.Cu")
		(net "GND")
	)
	(segment
		(start 123.199398 -5.621782)
		(end 123.199398 -3.762756)
		(width 0.4064)
		(layer "B.Cu")
		(net "GND")
	)
	(segment
		(start 226.9998 -17.0688)
		(end 226.9998 -15.222982)
		(width 0.4064)
		(layer "B.Cu")
		(net "GND")
	)
	(segment
		(start 217.649806 -24.02586)
		(end 217.3986 -23.774654)
		(width 0.254)
		(layer "B.Cu")
		(net "GND")
	)
	(segment
		(start 199.799956 -137.877296)
		(end 199.799956 -139.089892)
		(width 0.4064)
		(layer "B.Cu")
		(net "GND")
	)
	(segment
		(start 91.689428 -144.89684)
		(end 91.305126 -145.281142)
		(width 0.4064)
		(layer "B.Cu")
		(net "GND")
	)
	(segment
		(start 123.199398 -142.477236)
		(end 123.199398 -140.617956)
		(width 0.4064)
		(layer "B.Cu")
		(net "GND")
	)
	(segment
		(start 74.749406 -137.877296)
		(end 74.749406 -139.170156)
		(width 0.4064)
		(layer "B.Cu")
		(net "GND")
	)
	(segment
		(start 278.265128 -156.960824)
		(end 277.288752 -157.9372)
		(width 0.381)
		(layer "B.Cu")
		(net "GND")
	)
	(segment
		(start 278.849836 -132.876036)
		(end 278.849836 -132.875782)
		(width 0.508)
		(layer "B.Cu")
		(net "GND")
	)
	(segment
		(start 317.086996 -154.801824)
		(end 317.09995 -154.814778)
		(width 0.4064)
		(layer "B.Cu")
		(net "GND")
	)
	(segment
		(start 31.341568 -9.085834)
		(end 31.341568 -8.122412)
		(width 0.381)
		(layer "B.Cu")
		(net "GND")
	)
	(segment
		(start 78.128368 -18.7452)
		(end 78.14945 -18.766282)
		(width 0.4064)
		(layer "B.Cu")
		(net "GND")
	)
	(segment
		(start 166.624 -83.7692)
		(end 165.862 -84.5312)
		(width 0.254)
		(layer "B.Cu")
		(net "GND")
	)
	(segment
		(start 113.866168 -8.1026)
		(end 113.815368 -8.1534)
		(width 0.381)
		(layer "B.Cu")
		(net "GND")
	)
	(segment
		(start 22.6314 -32.024574)
		(end 22.225254 -32.43072)
		(width 0.508)
		(layer "B.Cu")
		(net "GND")
	)
	(segment
		(start 185.6994 -70.9422)
		(end 185.039 -71.6026)
		(width 0.4064)
		(layer "B.Cu")
		(net "GND")
	)
	(segment
		(start 67.949572 -142.477236)
		(end 67.949572 -142.18285)
		(width 0.4064)
		(layer "B.Cu")
		(net "GND")
	)
	(segment
		(start 450.6595 -19.177)
		(end 449.6181 -19.177)
		(width 0.254)
		(layer "B.Cu")
		(net "GND")
	)
	(segment
		(start 279.699974 -10.623042)
		(end 279.699974 -11.9126)
		(width 0.4064)
		(layer "B.Cu")
		(net "GND")
	)
	(segment
		(start 113.849404 -24.824182)
		(end 113.849404 -23.523956)
		(width 0.4064)
		(layer "B.Cu")
		(net "GND")
	)
	(segment
		(start 299.250354 -142.477236)
		(end 299.249846 -142.476982)
		(width 0.4064)
		(layer "B.Cu")
		(net "GND")
	)
	(segment
		(start 220.199966 -6.63702)
		(end 220.199966 -5.621782)
		(width 0.4064)
		(layer "B.Cu")
		(net "GND")
	)
	(segment
		(start 289.810952 -22.965156)
		(end 289.899852 -23.054056)
		(width 0.4064)
		(layer "B.Cu")
		(net "GND")
	)
	(segment
		(start 388.1374 -104.2797)
		(end 387.8707 -104.5464)
		(width 0.3048)
		(layer "B.Cu")
		(net "GND")
	)
	(segment
		(start 73.899522 -132.062982)
		(end 73.437496 -131.600956)
		(width 0.4064)
		(layer "B.Cu")
		(net "GND")
	)
	(segment
		(start 125.736858 -21.517356)
		(end 125.711458 -21.517356)
		(width 0.4064)
		(layer "B.Cu")
		(net "GND")
	)
	(segment
		(start 71.095362 -141.4526)
		(end 71.095362 -141.351)
		(width 0.254)
		(layer "B.Cu")
		(net "GND")
	)
	(segment
		(start 395.47546 -19.812)
		(end 395.9733 -20.30984)
		(width 0.254)
		(layer "B.Cu")
		(net "GND")
	)
	(segment
		(start 298.399962 0.457454)
		(end 298.399962 -1.021842)
		(width 0.4064)
		(layer "B.Cu")
		(net "GND")
	)
	(segment
		(start 62.792102 -11.893296)
		(end 62.792102 -11.912092)
		(width 0.4064)
		(layer "B.Cu")
		(net "GND")
	)
	(segment
		(start 280.549858 -17.110202)
		(end 280.451814 -17.208246)
		(width 0.4064)
		(layer "B.Cu")
		(net "GND")
	)
	(segment
		(start 113.0808 -3.3528)
		(end 112.397032 -3.3528)
		(width 0.381)
		(layer "B.Cu")
		(net "GND")
	)
	(segment
		(start 249.9106 -145.0086)
		(end 250.7615 -145.0086)
		(width 0.4572)
		(layer "B.Cu")
		(net "GND")
	)
	(segment
		(start 244.3353 -3.3528)
		(end 243.2304 -3.3528)
		(width 0.4572)
		(layer "B.Cu")
		(net "GND")
	)
	(segment
		(start 148.699474 -137.877296)
		(end 148.699474 -139.170156)
		(width 0.4064)
		(layer "B.Cu")
		(net "GND")
	)
	(segment
		(start 391.713466 -10.08253)
		(end 391.3505 -10.445496)
		(width 0.254)
		(layer "B.Cu")
		(net "GND")
	)
	(segment
		(start 50.099468 -1.021842)
		(end 50.099468 0.457454)
		(width 0.4064)
		(layer "B.Cu")
		(net "GND")
	)
	(segment
		(start 42.449496 -139.157456)
		(end 42.436796 -139.170156)
		(width 0.4064)
		(layer "B.Cu")
		(net "GND")
	)
	(segment
		(start 226.149916 -148.758656)
		(end 226.137216 -148.771356)
		(width 0.4064)
		(layer "B.Cu")
		(net "GND")
	)
	(segment
		(start 95.908368 2.76352)
		(end 95.913448 2.7686)
		(width 0.4064)
		(layer "B.Cu")
		(net "GND")
	)
	(segment
		(start 61.745368 -140.694156)
		(end 61.821568 -140.617956)
		(width 0.4064)
		(layer "B.Cu")
		(net "GND")
	)
	(segment
		(start 56.049418 -1.021842)
		(end 56.049418 -2.314956)
		(width 0.4064)
		(layer "B.Cu")
		(net "GND")
	)
	(segment
		(start 215.949784 -7.509002)
		(end 215.949784 -5.621782)
		(width 0.4064)
		(layer "B.Cu")
		(net "GND")
	)
	(segment
		(start 329.692 -55.88)
		(end 329.692 -55.626)
		(width 0.254)
		(layer "B.Cu")
		(net "GND")
	)
	(segment
		(start 90.845894 -135.012684)
		(end 90.845894 -135.636)
		(width 0.4064)
		(layer "B.Cu")
		(net "GND")
	)
	(segment
		(start 421.005 -31.81985)
		(end 421.09009 -31.73476)
		(width 0.508)
		(layer "B.Cu")
		(net "GND")
	)
	(segment
		(start 236.095794 -14.097)
		(end 236.095794 -13.440156)
		(width 0.4064)
		(layer "B.Cu")
		(net "GND")
	)
	(segment
		(start 78.14945 -10.623042)
		(end 78.14945 -12.472162)
		(width 0.4064)
		(layer "B.Cu")
		(net "GND")
	)
	(segment
		(start 381.556768 -41.877234)
		(end 381.556768 -41.896284)
		(width 0.254)
		(layer "B.Cu")
		(net "GND")
	)
	(segment
		(start 242.299998 -142.477236)
		(end 242.299998 -143.683736)
		(width 0.508)
		(layer "B.Cu")
		(net "GND")
	)
	(segment
		(start 297.550332 -24.824182)
		(end 297.549824 -24.824182)
		(width 0.4064)
		(layer "B.Cu")
		(net "GND")
	)
	(segment
		(start 476.541846 -16.406876)
		(end 475.187518 -16.406876)
		(width 0.254)
		(layer "B.Cu")
		(net "GND")
	)
	(segment
		(start 283.100272 -20.224242)
		(end 283.099764 -20.224242)
		(width 0.4064)
		(layer "B.Cu")
		(net "GND")
	)
	(segment
		(start 305.200304 -142.477236)
		(end 305.199796 -142.476982)
		(width 0.4064)
		(layer "B.Cu")
		(net "GND")
	)
	(segment
		(start 115.549426 -132.876036)
		(end 115.549426 -132.875782)
		(width 0.508)
		(layer "B.Cu")
		(net "GND")
	)
	(segment
		(start 424.1165 -21.9075)
		(end 424.1165 -21.59)
		(width 0.254)
		(layer "B.Cu")
		(net "GND")
	)
	(segment
		(start 126.599442 -25.645872)
		(end 125.749558 -26.495756)
		(width 0.4064)
		(layer "B.Cu")
		(net "GND")
	)
	(segment
		(start 283.04236 -11.893296)
		(end 283.04236 -11.912092)
		(width 0.4064)
		(layer "B.Cu")
		(net "GND")
	)
	(segment
		(start 41.599358 -5.621782)
		(end 41.599358 -3.826256)
		(width 0.4064)
		(layer "B.Cu")
		(net "GND")
	)
	(segment
		(start 367.260124 -45.927772)
		(end 366.331754 -45.927772)
		(width 0.254)
		(layer "B.Cu")
		(net "GND")
	)
	(segment
		(start 298.399962 -20.224242)
		(end 298.399962 -18.744946)
		(width 0.4064)
		(layer "B.Cu")
		(net "GND")
	)
	(segment
		(start 235.500418 -1.021842)
		(end 235.49991 -1.021842)
		(width 0.4064)
		(layer "B.Cu")
		(net "GND")
	)
	(segment
		(start 206.59979 -150.282656)
		(end 206.51089 -150.193756)
		(width 0.4064)
		(layer "B.Cu")
		(net "GND")
	)
	(segment
		(start 42.449496 -20.224242)
		(end 42.449496 -21.504656)
		(width 0.4064)
		(layer "B.Cu")
		(net "GND")
	)
	(segment
		(start 314.550298 -5.621782)
		(end 314.54979 -5.621782)
		(width 0.4064)
		(layer "B.Cu")
		(net "GND")
	)
	(segment
		(start 117.00383 -140.660374)
		(end 117.071648 -140.592556)
		(width 0.254)
		(layer "B.Cu")
		(net "GND")
	)
	(segment
		(start 56.049418 -128.276096)
		(end 56.049418 -129.568956)
		(width 0.4064)
		(layer "B.Cu")
		(net "GND")
	)
	(segment
		(start 167.7416 0.6604)
		(end 167.811704 0.6604)
		(width 0.4064)
		(layer "B.Cu")
		(net "GND")
	)
	(segment
		(start 403.391624 -31.912052)
		(end 404.204424 -31.912052)
		(width 0.254)
		(layer "B.Cu")
		(net "GND")
	)
	(segment
		(start 61.999368 -141.7066)
		(end 61.745368 -141.4526)
		(width 0.254)
		(layer "B.Cu")
		(net "GND")
	)
	(segment
		(start 389.01751 -44.86783)
		(end 389.14451 -44.86783)
		(width 0.254)
		(layer "B.Cu")
		(net "GND")
	)
	(segment
		(start 223.60001 -132.875782)
		(end 223.60001 -132.63245)
		(width 0.4064)
		(layer "B.Cu")
		(net "GND")
	)
	(segment
		(start 210.85048 -15.222982)
		(end 210.849972 -15.222982)
		(width 0.4064)
		(layer "B.Cu")
		(net "GND")
	)
	(segment
		(start 390.4742 -63.072772)
		(end 389.84555 -63.072772)
		(width 0.254)
		(layer "B.Cu")
		(net "GND")
	)
	(segment
		(start 210.387946 -4.346956)
		(end 210.849972 -4.808982)
		(width 0.4064)
		(layer "B.Cu")
		(net "GND")
	)
	(segment
		(start 438.58688 -157.1498)
		(end 438.589928 -157.152848)
		(width 0.254)
		(layer "B.Cu")
		(net "GND")
	)
	(segment
		(start 393.726416 -105.78211)
		(end 394.17625 -105.332276)
		(width 0.254)
		(layer "B.Cu")
		(net "GND")
	)
	(segment
		(start 239.750346 -1.021842)
		(end 239.749838 -1.021842)
		(width 0.4064)
		(layer "B.Cu")
		(net "GND")
	)
	(segment
		(start 287.349946 -147.478496)
		(end 287.349946 -148.771356)
		(width 0.4064)
		(layer "B.Cu")
		(net "GND")
	)
	(segment
		(start 239.749838 -11.916156)
		(end 239.749838 -10.623042)
		(width 0.4064)
		(layer "B.Cu")
		(net "GND")
	)
	(segment
		(start 43.29938 -17.0688)
		(end 43.12158 -17.2466)
		(width 0.4064)
		(layer "B.Cu")
		(net "GND")
	)
	(segment
		(start 135.771636 -7.6454)
		(end 135.949436 -7.4676)
		(width 0.4064)
		(layer "B.Cu")
		(net "GND")
	)
	(segment
		(start 498.792754 -39.761922)
		(end 498.792754 -39.702486)
		(width 0.254)
		(layer "B.Cu")
		(net "GND")
	)
	(segment
		(start 209.092546 -21.513292)
		(end 209.092546 -21.494496)
		(width 0.4064)
		(layer "B.Cu")
		(net "GND")
	)
	(segment
		(start 476.82658 -16.122142)
		(end 476.541846 -16.406876)
		(width 0.254)
		(layer "B.Cu")
		(net "GND")
	)
	(segment
		(start 287.349946 -18.757646)
		(end 287.349946 -20.224242)
		(width 0.4064)
		(layer "B.Cu")
		(net "GND")
	)
	(segment
		(start 79.334868 -3.3528)
		(end 78.229968 -3.3528)
		(width 0.4064)
		(layer "B.Cu")
		(net "GND")
	)
	(segment
		(start 40.749474 -18.744946)
		(end 40.749474 -20.224242)
		(width 0.4064)
		(layer "B.Cu")
		(net "GND")
	)
	(segment
		(start 50.860452 -13.338556)
		(end 50.860452 -13.363956)
		(width 0.4064)
		(layer "B.Cu")
		(net "GND")
	)
	(segment
		(start 496.34648 -129.63652)
		(end 496.34648 -129.44348)
		(width 0.254)
		(layer "B.Cu")
		(net "GND")
	)
	(segment
		(start 368.261138 -51.389788)
		(end 368.388646 -51.26228)
		(width 0.254)
		(layer "B.Cu")
		(net "GND")
	)
	(segment
		(start 29.563568 -154.305)
		(end 30.223968 -153.6446)
		(width 0.4064)
		(layer "B.Cu")
		(net "GND")
	)
	(segment
		(start 61.999368 -4.8514)
		(end 61.999368 -5.621782)
		(width 0.254)
		(layer "B.Cu")
		(net "GND")
	)
	(segment
		(start 396.27937 -41.54932)
		(end 396.768066 -41.54932)
		(width 0.254)
		(layer "B.Cu")
		(net "GND")
	)
	(segment
		(start 282.004262 -23.799546)
		(end 282.004262 -23.7236)
		(width 0.254)
		(layer "B.Cu")
		(net "GND")
	)
	(segment
		(start 113.849404 -139.587986)
		(end 113.92154 -139.660122)
		(width 0.4064)
		(layer "B.Cu")
		(net "GND")
	)
	(segment
		(start 450.317362 -28.334462)
		(end 449.7959 -27.813)
		(width 0.4064)
		(layer "B.Cu")
		(net "GND")
	)
	(segment
		(start 236.095794 -23.7998)
		(end 236.095794 -23.6982)
		(width 0.254)
		(layer "B.Cu")
		(net "GND")
	)
	(segment
		(start 300.772068 -17.2466)
		(end 300.949868 -17.0688)
		(width 0.4064)
		(layer "B.Cu")
		(net "GND")
	)
	(segment
		(start 428.3075 -23.368)
		(end 428.3075 -24.13)
		(width 0.254)
		(layer "B.Cu")
		(net "GND")
	)
	(segment
		(start 43.050968 -4.645152)
		(end 43.050968 -3.833368)
		(width 0.4064)
		(layer "B.Cu")
		(net "GND")
	)
	(segment
		(start 163.576 -83.3628)
		(end 163.576 -83.53806)
		(width 0.381)
		(layer "B.Cu")
		(net "GND")
	)
	(segment
		(start 19.05 -44.831)
		(end 19.304 -44.831)
		(width 0.254)
		(layer "B.Cu")
		(net "GND")
	)
	(segment
		(start 208.30032 -5.621782)
		(end 208.299812 -5.621782)
		(width 0.4064)
		(layer "B.Cu")
		(net "GND")
	)
	(segment
		(start 324.50532 -123.51512)
		(end 324.104 -123.1138)
		(width 0.254)
		(layer "B.Cu")
		(net "GND")
	)
	(segment
		(start 61.149484 -10.623042)
		(end 61.149484 -11.903456)
		(width 0.4064)
		(layer "B.Cu")
		(net "GND")
	)
	(segment
		(start 115.451382 -7.607046)
		(end 115.549426 -7.509002)
		(width 0.4064)
		(layer "B.Cu")
		(net "GND")
	)
	(segment
		(start 300.087284 -2.314956)
		(end 300.061884 -2.314956)
		(width 0.4064)
		(layer "B.Cu")
		(net "GND")
	)
	(segment
		(start 198.949818 -24.045164)
		(end 198.7042 -23.799546)
		(width 0.254)
		(layer "B.Cu")
		(net "GND")
	)
	(segment
		(start 309.449978 -1.021842)
		(end 309.449978 -2.302256)
		(width 0.4064)
		(layer "B.Cu")
		(net "GND")
	)
	(segment
		(start 82.21218 -125.64745)
		(end 82.21218 -126.816104)
		(width 0.4064)
		(layer "B.Cu")
		(net "GND")
	)
	(segment
		(start 52.649374 -132.07746)
		(end 52.398168 -131.826254)
		(width 0.254)
		(layer "B.Cu")
		(net "GND")
	)
	(segment
		(start 415.5186 -21.082)
		(end 415.7726 -21.336)
		(width 0.254)
		(layer "B.Cu")
		(net "GND")
	)
	(segment
		(start 215.950292 -24.824182)
		(end 215.949784 -24.824182)
		(width 0.4064)
		(layer "B.Cu")
		(net "GND")
	)
	(segment
		(start 340.487 -11.938)
		(end 340.7156 -11.7094)
		(width 0.254)
		(layer "B.Cu")
		(net "GND")
	)
	(segment
		(start 289.049968 -1.021842)
		(end 289.049968 0.457454)
		(width 0.4064)
		(layer "B.Cu")
		(net "GND")
	)
	(segment
		(start 222.749872 -1.021842)
		(end 222.749872 0.444754)
		(width 0.4064)
		(layer "B.Cu")
		(net "GND")
	)
	(segment
		(start 65.399412 -9.156446)
		(end 65.399412 -10.623042)
		(width 0.4064)
		(layer "B.Cu")
		(net "GND")
	)
	(segment
		(start 408.761692 -90.193114)
		(end 409.884118 -90.193114)
		(width 0.254)
		(layer "B.Cu")
		(net "GND")
	)
	(segment
		(start 139.34948 -20.224242)
		(end 139.34948 -18.757646)
		(width 0.4064)
		(layer "B.Cu")
		(net "GND")
	)
	(segment
		(start 221.899734 -5.276596)
		(end 221.899734 -3.762756)
		(width 0.4064)
		(layer "B.Cu")
		(net "GND")
	)
	(segment
		(start 311.15 -10.623042)
		(end 311.15 -9.20115)
		(width 0.4064)
		(layer "B.Cu")
		(net "GND")
	)
	(segment
		(start 478.0915 -117.6655)
		(end 478.0915 -118.385336)
		(width 0.254)
		(layer "B.Cu")
		(net "GND")
	)
	(segment
		(start 301.800514 -20.224242)
		(end 301.800006 -20.224242)
		(width 0.4064)
		(layer "B.Cu")
		(net "GND")
	)
	(segment
		(start 71.349362 -132.876036)
		(end 71.349362 -132.1054)
		(width 0.254)
		(layer "B.Cu")
		(net "GND")
	)
	(segment
		(start 91.844368 -17.6276)
		(end 91.454478 -18.01749)
		(width 0.4064)
		(layer "B.Cu")
		(net "GND")
	)
	(segment
		(start 442.8871 -18.9738)
		(end 443.92596 -18.9738)
		(width 0.254)
		(layer "B.Cu")
		(net "GND")
	)
	(segment
		(start 300.70425 -150.286974)
		(end 300.70425 -150.9776)
		(width 0.4064)
		(layer "B.Cu")
		(net "GND")
	)
	(segment
		(start 45.84954 -4.808982)
		(end 45.84954 -5.621782)
		(width 0.4064)
		(layer "B.Cu")
		(net "GND")
	)
	(segment
		(start 66.24955 -5.621782)
		(end 66.24955 -7.606792)
		(width 0.4064)
		(layer "B.Cu")
		(net "GND")
	)
	(segment
		(start 449.3387 -148.59)
		(end 449.3387 -147.8153)
		(width 0.254)
		(layer "B.Cu")
		(net "GND")
	)
	(segment
		(start 316.25032 -132.876036)
		(end 316.249812 -132.875782)
		(width 0.4064)
		(layer "B.Cu")
		(net "GND")
	)
	(segment
		(start 210.85048 -24.824182)
		(end 210.849972 -24.824182)
		(width 0.4064)
		(layer "B.Cu")
		(net "GND")
	)
	(segment
		(start 135.061452 -11.916156)
		(end 135.086852 -11.916156)
		(width 0.4064)
		(layer "B.Cu")
		(net "GND")
	)
	(segment
		(start 120.649492 -10.623042)
		(end 120.649492 -9.156446)
		(width 0.4064)
		(layer "B.Cu")
		(net "GND")
	)
	(segment
		(start 232.94975 -24.529796)
		(end 232.94975 -22.965156)
		(width 0.4064)
		(layer "B.Cu")
		(net "GND")
	)
	(segment
		(start 117.249448 -142.477236)
		(end 117.249448 -141.697964)
		(width 0.254)
		(layer "B.Cu")
		(net "GND")
	)
	(segment
		(start 44.149518 -137.877296)
		(end 44.149518 -139.089892)
		(width 0.4064)
		(layer "B.Cu")
		(net "GND")
	)
	(segment
		(start 292.45052 -20.224242)
		(end 292.450012 -20.224242)
		(width 0.4064)
		(layer "B.Cu")
		(net "GND")
	)
	(segment
		(start 229.54996 -132.875782)
		(end 229.54996 -132.062982)
		(width 0.4064)
		(layer "B.Cu")
		(net "GND")
	)
	(segment
		(start 404.4315 -23.61184)
		(end 404.18258 -23.86076)
		(width 0.254)
		(layer "B.Cu")
		(net "GND")
	)
	(segment
		(start 147.849336 -14.409928)
		(end 147.387564 -13.948156)
		(width 0.4064)
		(layer "B.Cu")
		(net "GND")
	)
	(segment
		(start 376.428 -98.08718)
		(end 376.428 -98.354896)
		(width 0.254)
		(layer "B.Cu")
		(net "GND")
	)
	(segment
		(start 150.399496 -1.021842)
		(end 150.399496 -2.314956)
		(width 0.4064)
		(layer "B.Cu")
		(net "GND")
	)
	(segment
		(start 33.703768 -23.799546)
		(end 33.703768 -23.7236)
		(width 0.254)
		(layer "B.Cu")
		(net "GND")
	)
	(segment
		(start 173.736 -86.868)
		(end 172.466 -86.868)
		(width 0.4064)
		(layer "B.Cu")
		(net "GND")
	)
	(segment
		(start 227.792534 -148.748496)
		(end 227.792534 -148.767292)
		(width 0.4064)
		(layer "B.Cu")
		(net "GND")
	)
	(segment
		(start 350.3168 -154.7622)
		(end 350.284542 -154.729942)
		(width 0.254)
		(layer "B.Cu")
		(net "GND")
	)
	(segment
		(start 69.64934 -25.676098)
		(end 70.461378 -26.488136)
		(width 0.4064)
		(layer "B.Cu")
		(net "GND")
	)
	(segment
		(start 256.089658 -8.468868)
		(end 256.656332 -8.468868)
		(width 0.4064)
		(layer "B.Cu")
		(net "GND")
	)
	(segment
		(start 462.05775 -124.92482)
		(end 461.7466 -125.23597)
		(width 0.254)
		(layer "B.Cu")
		(net "GND")
	)
	(segment
		(start 216.787222 -21.517356)
		(end 216.761822 -21.517356)
		(width 0.4064)
		(layer "B.Cu")
		(net "GND")
	)
	(segment
		(start 59.449462 -21.517356)
		(end 59.449462 -20.224242)
		(width 0.4064)
		(layer "B.Cu")
		(net "GND")
	)
	(segment
		(start 300.099984 -10.623042)
		(end 300.099984 -9.156446)
		(width 0.4064)
		(layer "B.Cu")
		(net "GND")
	)
	(segment
		(start 129.999486 -137.877296)
		(end 129.999486 -139.170156)
		(width 0.4064)
		(layer "B.Cu")
		(net "GND")
	)
	(segment
		(start 306.049934 -11.916156)
		(end 306.049934 -10.623042)
		(width 0.4064)
		(layer "B.Cu")
		(net "GND")
	)
	(segment
		(start 442.96838 -148.72462)
		(end 442.564774 -148.72462)
		(width 0.254)
		(layer "B.Cu")
		(net "GND")
	)
	(segment
		(start 500.6594 -38.7604)
		(end 500.6848 -38.735)
		(width 0.254)
		(layer "B.Cu")
		(net "GND")
	)
	(segment
		(start 207.449928 -10.623042)
		(end 207.449928 -9.156446)
		(width 0.4064)
		(layer "B.Cu")
		(net "GND")
	)
	(segment
		(start 32.249364 -24.824182)
		(end 32.249364 -23.716742)
		(width 0.4064)
		(layer "B.Cu")
		(net "GND")
	)
	(segment
		(start 41.599358 -150.282656)
		(end 41.510458 -150.193756)
		(width 0.4064)
		(layer "B.Cu")
		(net "GND")
	)
	(segment
		(start 278.418036 -145.0086)
		(end 278.849836 -144.5768)
		(width 0.4572)
		(layer "B.Cu")
		(net "GND")
	)
	(segment
		(start 408.8003 -8.763)
		(end 409.224988 -8.338312)
		(width 0.254)
		(layer "B.Cu")
		(net "GND")
	)
	(segment
		(start 261.4422 -8.122412)
		(end 261.7216 -7.843012)
		(width 0.4064)
		(layer "B.Cu")
		(net "GND")
	)
	(segment
		(start 352.02368 -89.067132)
		(end 352.626676 -89.067132)
		(width 0.254)
		(layer "B.Cu")
		(net "GND")
	)
	(segment
		(start 303.500282 -15.222982)
		(end 303.499774 -15.222982)
		(width 0.4064)
		(layer "B.Cu")
		(net "GND")
	)
	(segment
		(start 201.041254 -16.696944)
		(end 201.499978 -16.23822)
		(width 0.4064)
		(layer "B.Cu")
		(net "GND")
	)
	(segment
		(start 308.809644 -131.016756)
		(end 310.122062 -131.016756)
		(width 0.4064)
		(layer "B.Cu")
		(net "GND")
	)
	(segment
		(start 377.80595 -83.3755)
		(end 377.7234 -83.29295)
		(width 0.254)
		(layer "B.Cu")
		(net "GND")
	)
	(segment
		(start 118.099332 -139.089892)
		(end 118.041928 -139.147296)
		(width 0.4064)
		(layer "B.Cu")
		(net "GND")
	)
	(segment
		(start 375.519696 -60.852304)
		(end 375.519696 -61.388752)
		(width 0.254)
		(layer "B.Cu")
		(net "GND")
	)
	(segment
		(start 411.662118 -91.9226)
		(end 411.662118 -91.493594)
		(width 0.254)
		(layer "B.Cu")
		(net "GND")
	)
	(segment
		(start 284.33776 -4.346956)
		(end 284.799786 -4.808982)
		(width 0.4064)
		(layer "B.Cu")
		(net "GND")
	)
	(segment
		(start 156.591 -17.78)
		(end 156.647388 -17.723612)
		(width 0.4064)
		(layer "B.Cu")
		(net "GND")
	)
	(segment
		(start 78.14945 -128.276096)
		(end 78.14945 -130.124962)
		(width 0.4064)
		(layer "B.Cu")
		(net "GND")
	)
	(segment
		(start 294.14978 -142.476982)
		(end 294.14978 -141.663928)
		(width 0.4064)
		(layer "B.Cu")
		(net "GND")
	)
	(segment
		(start 259.2832 -26.8478)
		(end 259.2832 -26.475182)
		(width 0.381)
		(layer "B.Cu")
		(net "GND")
	)
	(segment
		(start 386.64642 -84.1629)
		(end 387.16712 -84.1629)
		(width 0.254)
		(layer "B.Cu")
		(net "GND")
	)
	(segment
		(start 79.264002 -87.632286)
		(end 79.264002 -86.743286)
		(width 0.254)
		(layer "B.Cu")
		(net "GND")
	)
	(segment
		(start 91.379548 -135.636)
		(end 90.845894 -135.636)
		(width 0.381)
		(layer "B.Cu")
		(net "GND")
	)
	(segment
		(start 240.599976 -24.824182)
		(end 240.599976 -24.45385)
		(width 0.4064)
		(layer "B.Cu")
		(net "GND")
	)
	(segment
		(start 53.499512 -148.691092)
		(end 53.442108 -148.748496)
		(width 0.4064)
		(layer "B.Cu")
		(net "GND")
	)
	(segment
		(start 212.54974 -14.928596)
		(end 212.54974 -13.363956)
		(width 0.4064)
		(layer "B.Cu")
		(net "GND")
	)
	(segment
		(start 303.499774 -24.011128)
		(end 303.499774 -24.824182)
		(width 0.4064)
		(layer "B.Cu")
		(net "GND")
	)
	(segment
		(start 221.050358 -137.877296)
		(end 221.04985 -137.877296)
		(width 0.4064)
		(layer "B.Cu")
		(net "GND")
	)
	(segment
		(start 232.099866 -128.276096)
		(end 232.099866 -129.568956)
		(width 0.4064)
		(layer "B.Cu")
		(net "GND")
	)
	(segment
		(start 61.999368 -152.078436)
		(end 61.999368 -151.3078)
		(width 0.254)
		(layer "B.Cu")
		(net "GND")
	)
	(segment
		(start 314.54979 -132.875782)
		(end 314.54979 -131.016756)
		(width 0.4064)
		(layer "B.Cu")
		(net "GND")
	)
	(segment
		(start 304.35042 -10.623042)
		(end 304.349912 -10.623042)
		(width 0.4064)
		(layer "B.Cu")
		(net "GND")
	)
	(segment
		(start 368.975386 -47.643034)
		(end 367.260124 -45.927772)
		(width 0.254)
		(layer "B.Cu")
		(net "GND")
	)
	(segment
		(start 70.499478 -9.156446)
		(end 70.499478 -10.623042)
		(width 0.4064)
		(layer "B.Cu")
		(net "GND")
	)
	(segment
		(start 254.789432 -17.7546)
		(end 255.186942 -17.35709)
		(width 0.4572)
		(layer "B.Cu")
		(net "GND")
	)
	(segment
		(start 225.299778 -24.824182)
		(end 225.299778 -23.054056)
		(width 0.4064)
		(layer "B.Cu")
		(net "GND")
	)
	(segment
		(start 33.949386 -132.876036)
		(end 33.949386 -132.096764)
		(width 0.254)
		(layer "B.Cu")
		(net "GND")
	)
	(segment
		(start 236.095794 -131.092956)
		(end 236.171994 -131.016756)
		(width 0.4064)
		(layer "B.Cu")
		(net "GND")
	)
	(segment
		(start 310.299862 -24.823674)
		(end 310.30037 -24.824182)
		(width 0.254)
		(layer "B.Cu")
		(net "GND")
	)
	(segment
		(start 113.849404 -128.276096)
		(end 113.849404 -126.089156)
		(width 0.508)
		(layer "B.Cu")
		(net "GND")
	)
	(segment
		(start 216.80043 -20.224242)
		(end 216.799922 -20.224242)
		(width 0.4064)
		(layer "B.Cu")
		(net "GND")
	)
	(segment
		(start 241.44986 -18.757646)
		(end 241.44986 -20.224242)
		(width 0.4064)
		(layer "B.Cu")
		(net "GND")
	)
	(segment
		(start 157.361382 -154.782012)
		(end 157.488382 -154.655012)
		(width 0.4064)
		(layer "B.Cu")
		(net "GND")
	)
	(segment
		(start 50.099468 -139.170156)
		(end 50.099468 -137.877296)
		(width 0.4064)
		(layer "B.Cu")
		(net "GND")
	)
	(segment
		(start 468.884 -128.524)
		(end 468.376 -128.524)
		(width 0.254)
		(layer "B.Cu")
		(net "GND")
	)
	(segment
		(start 126.353824 -131.7752)
		(end 126.353824 -131.084574)
		(width 0.4064)
		(layer "B.Cu")
		(net "GND")
	)
	(segment
		(start 282.250388 -15.222982)
		(end 282.24988 -15.222982)
		(width 0.4064)
		(layer "B.Cu")
		(net "GND")
	)
	(segment
		(start 300.950376 -24.824182)
		(end 300.949868 -24.824182)
		(width 0.254)
		(layer "B.Cu")
		(net "GND")
	)
	(segment
		(start 321.65544 -8.128)
		(end 321.591432 -8.128)
		(width 0.381)
		(layer "B.Cu")
		(net "GND")
	)
	(segment
		(start 414.063942 -9.1821)
		(end 413.639 -8.757158)
		(width 0.254)
		(layer "B.Cu")
		(net "GND")
	)
	(segment
		(start 278.897588 -9.083294)
		(end 278.849836 -9.131046)
		(width 0.4064)
		(layer "B.Cu")
		(net "GND")
	)
	(segment
		(start 42.449496 -11.903456)
		(end 42.449496 -10.623042)
		(width 0.4064)
		(layer "B.Cu")
		(net "GND")
	)
	(segment
		(start 285.650432 -10.623042)
		(end 285.649924 -10.623042)
		(width 0.4064)
		(layer "B.Cu")
		(net "GND")
	)
	(segment
		(start 134.160514 -131.016756)
		(end 134.160514 -130.991356)
		(width 0.4064)
		(layer "B.Cu")
		(net "GND")
	)
	(segment
		(start 299.249846 -132.875782)
		(end 299.249846 -131.105656)
		(width 0.4064)
		(layer "B.Cu")
		(net "GND")
	)
	(segment
		(start 117.249448 -132.148326)
		(end 117.00383 -131.902708)
		(width 0.3556)
		(layer "B.Cu")
		(net "GND")
	)
	(segment
		(start 491.21441 -55.047896)
		(end 491.174532 -55.047896)
		(width 0.4064)
		(layer "B.Cu")
		(net "GND")
	)
	(segment
		(start 141.899386 -3.762756)
		(end 141.899386 -5.621782)
		(width 0.4064)
		(layer "B.Cu")
		(net "GND")
	)
	(segment
		(start 77.264768 -26.67)
		(end 77.299566 -26.635202)
		(width 0.4064)
		(layer "B.Cu")
		(net "GND")
	)
	(segment
		(start 114.699542 -18.744946)
		(end 114.699542 -20.224242)
		(width 0.4064)
		(layer "B.Cu")
		(net "GND")
	)
	(segment
		(start 51.79949 -18.757646)
		(end 51.79949 -20.224242)
		(width 0.4064)
		(layer "B.Cu")
		(net "GND")
	)
	(segment
		(start 458.557376 -25.273)
		(end 457.7842 -25.273)
		(width 0.508)
		(layer "B.Cu")
		(net "GND")
	)
	(segment
		(start 17.653 -81.8642)
		(end 17.653 -81.788)
		(width 0.254)
		(layer "B.Cu")
		(net "GND")
	)
	(segment
		(start 386.96138 -61.66358)
		(end 387.368034 -62.070234)
		(width 0.254)
		(layer "B.Cu")
		(net "GND")
	)
	(segment
		(start 196.40042 -147.478496)
		(end 196.399912 -147.478496)
		(width 0.4064)
		(layer "B.Cu")
		(net "GND")
	)
	(segment
		(start 71.095362 -14.1986)
		(end 71.349362 -14.4526)
		(width 0.254)
		(layer "B.Cu")
		(net "GND")
	)
	(segment
		(start 304.349912 -147.478496)
		(end 304.35042 -147.478496)
		(width 0.4064)
		(layer "B.Cu")
		(net "GND")
	)
	(segment
		(start 290.73729 -11.916156)
		(end 290.74999 -11.903456)
		(width 0.4064)
		(layer "B.Cu")
		(net "GND")
	)
	(segment
		(start 260.741668 -27.4828)
		(end 260.53415 -27.275282)
		(width 0.381)
		(layer "B.Cu")
		(net "GND")
	)
	(segment
		(start 309.449978 -10.623042)
		(end 309.449978 -9.156446)
		(width 0.4064)
		(layer "B.Cu")
		(net "GND")
	)
	(segment
		(start 67.099434 -21.517356)
		(end 67.099434 -20.224242)
		(width 0.4064)
		(layer "B.Cu")
		(net "GND")
	)
	(segment
		(start 122.349514 -11.916156)
		(end 122.349514 -10.623042)
		(width 0.4064)
		(layer "B.Cu")
		(net "GND")
	)
	(segment
		(start 134.249414 -23.054056)
		(end 134.249414 -24.824182)
		(width 0.4064)
		(layer "B.Cu")
		(net "GND")
	)
	(segment
		(start 410.889196 -94.160594)
		(end 411.662118 -94.160594)
		(width 0.254)
		(layer "B.Cu")
		(net "GND")
	)
	(segment
		(start 243.1034 -27.813)
		(end 241.466116 -28.491434)
		(width 0.4064)
		(layer "B.Cu")
		(net "GND")
	)
	(segment
		(start 294.150288 -24.824182)
		(end 294.14978 -24.824182)
		(width 0.4064)
		(layer "B.Cu")
		(net "GND")
	)
	(segment
		(start 494.712244 -50.043588)
		(end 495.237008 -50.043588)
		(width 0.254)
		(layer "B.Cu")
		(net "GND")
	)
	(segment
		(start 152.146 -18.711164)
		(end 152.099518 -18.757646)
		(width 0.4064)
		(layer "B.Cu")
		(net "GND")
	)
	(segment
		(start 281.387296 -2.314956)
		(end 281.361896 -2.314956)
		(width 0.4064)
		(layer "B.Cu")
		(net "GND")
	)
	(segment
		(start 128.897888 -64.934338)
		(end 128.836928 -64.934338)
		(width 0.254)
		(layer "B.Cu")
		(net "GND")
	)
	(segment
		(start 263.7028 -26.543)
		(end 263.7028 -27.1018)
		(width 0.381)
		(layer "B.Cu")
		(net "GND")
	)
	(segment
		(start 500.093234 -39.702486)
		(end 500.377714 -39.702486)
		(width 0.254)
		(layer "B.Cu")
		(net "GND")
	)
	(segment
		(start 408.127454 -29.819854)
		(end 408.127454 -29.972)
		(width 0.254)
		(layer "B.Cu")
		(net "GND")
	)
	(segment
		(start 464.4898 -144.646396)
		(end 464.47329 -144.629886)
		(width 0.4064)
		(layer "B.Cu")
		(net "GND")
	)
	(segment
		(start 279.699974 -9.143746)
		(end 279.699974 -10.623042)
		(width 0.4064)
		(layer "B.Cu")
		(net "GND")
	)
	(segment
		(start 250.7615 -140.208)
		(end 249.9106 -140.208)
		(width 0.4572)
		(layer "B.Cu")
		(net "GND")
	)
	(segment
		(start 471.0557 -128.7526)
		(end 471.0557 -128.39954)
		(width 0.254)
		(layer "B.Cu")
		(net "GND")
	)
	(segment
		(start 26.3144 2.1336)
		(end 25.39746 3.05054)
		(width 0.4064)
		(layer "B.Cu")
		(net "GND")
	)
	(segment
		(start 198.950326 -132.876036)
		(end 198.949818 -132.875782)
		(width 0.254)
		(layer "B.Cu")
		(net "GND")
	)
	(segment
		(start 144.449546 -137.877296)
		(end 144.449546 -139.157456)
		(width 0.4064)
		(layer "B.Cu")
		(net "GND")
	)
	(segment
		(start 201.499978 -4.808982)
		(end 201.499978 -5.621782)
		(width 0.4064)
		(layer "B.Cu")
		(net "GND")
	)
	(segment
		(start 388.366 -130.88874)
		(end 388.71906 -130.88874)
		(width 0.254)
		(layer "B.Cu")
		(net "GND")
	)
	(segment
		(start 385.19354 -81.51876)
		(end 385.4704 -81.51876)
		(width 0.254)
		(layer "B.Cu")
		(net "GND")
	)
	(segment
		(start 33.703768 -14.1224)
		(end 33.703768 -13.431774)
		(width 0.4064)
		(layer "B.Cu")
		(net "GND")
	)
	(segment
		(start 164.5412 -86.868)
		(end 164.846 -86.868)
		(width 0.4064)
		(layer "B.Cu")
		(net "GND")
	)
	(segment
		(start 261.3152 -135.376412)
		(end 261.3152 -136.1948)
		(width 0.4064)
		(layer "B.Cu")
		(net "GND")
	)
	(segment
		(start 292.450012 -128.276096)
		(end 292.450012 -129.488692)
		(width 0.4064)
		(layer "B.Cu")
		(net "GND")
	)
	(segment
		(start 305.199796 -15.222982)
		(end 305.199796 -13.363956)
		(width 0.4064)
		(layer "B.Cu")
		(net "GND")
	)
	(segment
		(start 415.47288 -49.390808)
		(end 415.512504 -49.351184)
		(width 0.254)
		(layer "B.Cu")
		(net "GND")
	)
	(segment
		(start 226.7458 -23.7998)
		(end 226.7458 -23.6982)
		(width 0.254)
		(layer "B.Cu")
		(net "GND")
	)
	(segment
		(start 297.550332 -142.477236)
		(end 297.549824 -142.476982)
		(width 0.4064)
		(layer "B.Cu")
		(net "GND")
	)
	(segment
		(start 292.392608 -21.513292)
		(end 292.392608 -21.494496)
		(width 0.4064)
		(layer "B.Cu")
		(net "GND")
	)
	(segment
		(start 17.3482 -83.439)
		(end 17.1704 -83.6168)
		(width 0.254)
		(layer "B.Cu")
		(net "GND")
	)
	(segment
		(start 315.0997 -28.762452)
		(end 315.595508 -28.762452)
		(width 0.254)
		(layer "B.Cu")
		(net "GND")
	)
	(segment
		(start 227.792534 -18.744946)
		(end 227.849938 -18.80235)
		(width 0.4064)
		(layer "B.Cu")
		(net "GND")
	)
	(segment
		(start 321.2338 -125.004322)
		(end 321.7291 -125.004322)
		(width 0.254)
		(layer "B.Cu")
		(net "GND")
	)
	(segment
		(start 76.449428 -10.623042)
		(end 76.449428 -11.916156)
		(width 0.4064)
		(layer "B.Cu")
		(net "GND")
	)
	(segment
		(start 89.789 -17.7546)
		(end 90.18651 -17.35709)
		(width 0.4064)
		(layer "B.Cu")
		(net "GND")
	)
	(segment
		(start 33.949386 -7.4676)
		(end 33.949386 -5.621782)
		(width 0.4064)
		(layer "B.Cu")
		(net "GND")
	)
	(segment
		(start 303.500282 -24.824182)
		(end 303.499774 -24.824182)
		(width 0.4064)
		(layer "B.Cu")
		(net "GND")
	)
	(segment
		(start 102.7938 -17.7546)
		(end 103.678736 -17.7546)
		(width 0.4064)
		(layer "B.Cu")
		(net "GND")
	)
	(segment
		(start 456.536806 -36.522406)
		(end 457.267056 -36.522406)
		(width 0.254)
		(layer "B.Cu")
		(net "GND")
	)
	(segment
		(start 305.199796 -142.476982)
		(end 305.199796 -140.617956)
		(width 0.4064)
		(layer "B.Cu")
		(net "GND")
	)
	(segment
		(start 142.749524 -11.916156)
		(end 142.749524 -10.623042)
		(width 0.4064)
		(layer "B.Cu")
		(net "GND")
	)
	(segment
		(start 299.250354 -15.222982)
		(end 299.249846 -15.222982)
		(width 0.4064)
		(layer "B.Cu")
		(net "GND")
	)
	(segment
		(start 142.749524 -20.224242)
		(end 142.749524 -18.744946)
		(width 0.4064)
		(layer "B.Cu")
		(net "GND")
	)
	(segment
		(start 38.199568 -24.824182)
		(end 38.199568 -22.96541)
		(width 0.4064)
		(layer "B.Cu")
		(net "GND")
	)
	(segment
		(start 217.3986 -3.836162)
		(end 217.472006 -3.762756)
		(width 0.4064)
		(layer "B.Cu")
		(net "GND")
	)
	(segment
		(start 62.792102 -139.147296)
		(end 62.792102 -139.166092)
		(width 0.4064)
		(layer "B.Cu")
		(net "GND")
	)
	(segment
		(start 284.800294 -152.078436)
		(end 284.800294 -151.26589)
		(width 0.4064)
		(layer "B.Cu")
		(net "GND")
	)
	(segment
		(start 46.699424 -20.224242)
		(end 46.699424 -21.517356)
		(width 0.4064)
		(layer "B.Cu")
		(net "GND")
	)
	(segment
		(start 66.24955 -5.25145)
		(end 66.24955 -5.621782)
		(width 0.4064)
		(layer "B.Cu")
		(net "GND")
	)
	(segment
		(start 47.549308 -14.928596)
		(end 47.549308 -13.363956)
		(width 0.4064)
		(layer "B.Cu")
		(net "GND")
	)
	(segment
		(start 70.499478 -139.132056)
		(end 70.461378 -139.170156)
		(width 0.4064)
		(layer "B.Cu")
		(net "GND")
	)
	(segment
		(start 230.400352 -20.224242)
		(end 230.399844 -20.224242)
		(width 0.4064)
		(layer "B.Cu")
		(net "GND")
	)
	(segment
		(start 311.092596 -148.748496)
		(end 311.15 -148.691092)
		(width 0.4064)
		(layer "B.Cu")
		(net "GND")
	)
	(segment
		(start 221.050358 -128.276096)
		(end 221.04985 -128.276096)
		(width 0.4064)
		(layer "B.Cu")
		(net "GND")
	)
	(segment
		(start 450.317362 -28.552648)
		(end 451.436994 -28.552648)
		(width 0.4064)
		(layer "B.Cu")
		(net "GND")
	)
	(segment
		(start 289.899852 -17.110202)
		(end 289.899852 -15.222982)
		(width 0.4064)
		(layer "B.Cu")
		(net "GND")
	)
	(segment
		(start 138.499342 -4.808728)
		(end 138.03757 -4.346956)
		(width 0.4064)
		(layer "B.Cu")
		(net "GND")
	)
	(segment
		(start 33.949386 -24.045164)
		(end 33.703768 -23.799546)
		(width 0.254)
		(layer "B.Cu")
		(net "GND")
	)
	(segment
		(start 260.4643 -150.7871)
		(end 260.87578 -150.37562)
		(width 0.381)
		(layer "B.Cu")
		(net "GND")
	)
	(segment
		(start 418.211 -7.239)
		(end 418.1475 -7.3025)
		(width 0.254)
		(layer "B.Cu")
		(net "GND")
	)
	(segment
		(start 220.199966 -132.062982)
		(end 219.73794 -131.600956)
		(width 0.4064)
		(layer "B.Cu")
		(net "GND")
	)
	(segment
		(start 232.950004 -14.92885)
		(end 232.94975 -14.928596)
		(width 0.4064)
		(layer "B.Cu")
		(net "GND")
	)
	(segment
		(start 299.249846 -3.851656)
		(end 299.249846 -5.621782)
		(width 0.4064)
		(layer "B.Cu")
		(net "GND")
	)
	(segment
		(start 232.099866 -9.156446)
		(end 232.099866 -10.623042)
		(width 0.4064)
		(layer "B.Cu")
		(net "GND")
	)
	(segment
		(start 130.84937 -7.607046)
		(end 130.84937 -5.621782)
		(width 0.4064)
		(layer "B.Cu")
		(net "GND")
	)
	(segment
		(start 152.099518 -144.450562)
		(end 152.626568 -144.977612)
		(width 0.4064)
		(layer "B.Cu")
		(net "GND")
	)
	(segment
		(start 203.199746 -3.762756)
		(end 203.2 -3.76301)
		(width 0.4064)
		(layer "B.Cu")
		(net "GND")
	)
	(segment
		(start 499.2116 -38.0238)
		(end 499.2116 -38.2016)
		(width 0.254)
		(layer "B.Cu")
		(net "GND")
	)
	(segment
		(start 226.150424 -20.224242)
		(end 226.149916 -20.224242)
		(width 0.4064)
		(layer "B.Cu")
		(net "GND")
	)
	(segment
		(start 283.099764 -139.089892)
		(end 283.099764 -137.877296)
		(width 0.4064)
		(layer "B.Cu")
		(net "GND")
	)
	(segment
		(start 150.399496 -10.623042)
		(end 150.399496 -9.156446)
		(width 0.4064)
		(layer "B.Cu")
		(net "GND")
	)
	(segment
		(start 234.649772 -5.621782)
		(end 234.649772 -3.851656)
		(width 0.4064)
		(layer "B.Cu")
		(net "GND")
	)
	(segment
		(start 77.299312 -140.630656)
		(end 77.299312 -142.055596)
		(width 0.4064)
		(layer "B.Cu")
		(net "GND")
	)
	(segment
		(start 241.450368 -20.224242)
		(end 241.44986 -20.224242)
		(width 0.4064)
		(layer "B.Cu")
		(net "GND")
	)
	(segment
		(start 226.9998 -142.476982)
		(end 226.9998 -141.7066)
		(width 0.254)
		(layer "B.Cu")
		(net "GND")
	)
	(segment
		(start 256.921 -134.9756)
		(end 257.429 -134.4676)
		(width 0.4064)
		(layer "B.Cu")
		(net "GND")
	)
	(segment
		(start 209.14995 -148.691092)
		(end 209.092546 -148.748496)
		(width 0.4064)
		(layer "B.Cu")
		(net "GND")
	)
	(segment
		(start 125.711458 -11.916156)
		(end 125.736858 -11.916156)
		(width 0.4064)
		(layer "B.Cu")
		(net "GND")
	)
	(segment
		(start 42.436796 -148.771356)
		(end 42.411396 -148.771356)
		(width 0.4064)
		(layer "B.Cu")
		(net "GND")
	)
	(segment
		(start 464.47329 -144.629886)
		(end 464.282028 -144.629886)
		(width 0.4064)
		(layer "B.Cu")
		(net "GND")
	)
	(segment
		(start 116.399564 -129.556256)
		(end 116.386864 -129.568956)
		(width 0.4064)
		(layer "B.Cu")
		(net "GND")
	)
	(segment
		(start 300.100492 -128.276096)
		(end 300.099984 -128.276096)
		(width 0.4064)
		(layer "B.Cu")
		(net "GND")
	)
	(segment
		(start 280.549858 -131.105656)
		(end 280.549858 -132.875782)
		(width 0.4064)
		(layer "B.Cu")
		(net "GND")
	)
	(segment
		(start 406.387046 -54.673754)
		(end 405.683974 -54.673754)
		(width 0.254)
		(layer "B.Cu")
		(net "GND")
	)
	(segment
		(start 53.442108 0.457454)
		(end 53.499512 0.40005)
		(width 0.4064)
		(layer "B.Cu")
		(net "GND")
	)
	(segment
		(start 373.8753 -96.4946)
		(end 374.06072 -96.68002)
		(width 0.254)
		(layer "B.Cu")
		(net "GND")
	)
	(segment
		(start 415.29 -31.9405)
		(end 416.1155 -31.9405)
		(width 0.254)
		(layer "B.Cu")
		(net "GND")
	)
	(segment
		(start 410.6545 -34.098992)
		(end 410.690314 -34.134806)
		(width 0.4572)
		(layer "B.Cu")
		(net "GND")
	)
	(segment
		(start 225.299778 -3.851656)
		(end 225.210878 -3.762756)
		(width 0.4064)
		(layer "B.Cu")
		(net "GND")
	)
	(segment
		(start 220.199966 -152.078182)
		(end 220.199966 -151.265382)
		(width 0.4064)
		(layer "B.Cu")
		(net "GND")
	)
	(segment
		(start 152.146 -9.109964)
		(end 152.146 -8.128)
		(width 0.4064)
		(layer "B.Cu")
		(net "GND")
	)
	(segment
		(start 40.749474 -2.314956)
		(end 40.749474 -1.021842)
		(width 0.4064)
		(layer "B.Cu")
		(net "GND")
	)
	(segment
		(start 41.599358 -140.681456)
		(end 41.510458 -140.592556)
		(width 0.4064)
		(layer "B.Cu")
		(net "GND")
	)
	(segment
		(start 34.74212 -148.748496)
		(end 34.74212 -148.767292)
		(width 0.4064)
		(layer "B.Cu")
		(net "GND")
	)
	(segment
		(start 374.1547 -96.58604)
		(end 375.44502 -96.58604)
		(width 0.254)
		(layer "B.Cu")
		(net "GND")
	)
	(segment
		(start 72.1995 -147.478496)
		(end 72.1995 -148.691092)
		(width 0.4064)
		(layer "B.Cu")
		(net "GND")
	)
	(segment
		(start 67.949318 -14.928596)
		(end 67.949318 -13.363956)
		(width 0.4064)
		(layer "B.Cu")
		(net "GND")
	)
	(segment
		(start 95.131636 -11.9126)
		(end 96.091248 -12.872212)
		(width 0.508)
		(layer "B.Cu")
		(net "GND")
	)
	(segment
		(start 195.550282 -142.477236)
		(end 195.549774 -142.477236)
		(width 0.4064)
		(layer "B.Cu")
		(net "GND")
	)
	(segment
		(start 308.59984 -7.509002)
		(end 308.59984 -5.621782)
		(width 0.4064)
		(layer "B.Cu")
		(net "GND")
	)
	(segment
		(start 116.386864 -21.517356)
		(end 116.361464 -21.517356)
		(width 0.4064)
		(layer "B.Cu")
		(net "GND")
	)
	(segment
		(start 195.549774 -4.277106)
		(end 195.549774 -5.621782)
		(width 0.4064)
		(layer "B.Cu")
		(net "GND")
	)
	(segment
		(start 58.599324 -5.378196)
		(end 58.599578 -5.37845)
		(width 0.4064)
		(layer "B.Cu")
		(net "GND")
	)
	(segment
		(start 237.142528 -11.893296)
		(end 237.199932 -11.835892)
		(width 0.4064)
		(layer "B.Cu")
		(net "GND")
	)
	(segment
		(start 64.087502 -23.549356)
		(end 64.549528 -24.011382)
		(width 0.4064)
		(layer "B.Cu")
		(net "GND")
	)
	(segment
		(start 242.299998 -24.824182)
		(end 242.299998 -26.635202)
		(width 0.4064)
		(layer "B.Cu")
		(net "GND")
	)
	(segment
		(start 226.9998 -151.3078)
		(end 226.7458 -151.0538)
		(width 0.254)
		(layer "B.Cu")
		(net "GND")
	)
	(segment
		(start 117.249448 -5.621782)
		(end 117.249448 -7.4676)
		(width 0.4064)
		(layer "B.Cu")
		(net "GND")
	)
	(segment
		(start 421.395652 -24.158194)
		(end 421.390826 -24.158194)
		(width 0.254)
		(layer "B.Cu")
		(net "GND")
	)
	(segment
		(start 386.79374 -83.805776)
		(end 386.541518 -84.057998)
		(width 0.254)
		(layer "B.Cu")
		(net "GND")
	)
	(segment
		(start 305.199796 -25.645872)
		(end 305.199796 -24.824182)
		(width 0.4064)
		(layer "B.Cu")
		(net "GND")
	)
	(segment
		(start 210.85048 -5.621782)
		(end 210.849972 -5.621782)
		(width 0.4064)
		(layer "B.Cu")
		(net "GND")
	)
	(segment
		(start 38.199568 -22.96541)
		(end 38.199314 -22.965156)
		(width 0.4064)
		(layer "B.Cu")
		(net "GND")
	)
	(segment
		(start 395.097 -62.738)
		(end 395.097 -63.627)
		(width 0.254)
		(layer "B.Cu")
		(net "GND")
	)
	(segment
		(start 217.649806 -141.67866)
		(end 217.3986 -141.427454)
		(width 0.254)
		(layer "B.Cu")
		(net "GND")
	)
	(segment
		(start 278.849836 -141.176756)
		(end 278.9682 -141.058392)
		(width 0.4064)
		(layer "B.Cu")
		(net "GND")
	)
	(segment
		(start 224.449894 -26.488136)
		(end 223.60001 -25.638252)
		(width 0.4064)
		(layer "B.Cu")
		(net "GND")
	)
	(segment
		(start 82.459068 -8.1534)
		(end 81.618836 -8.1534)
		(width 0.508)
		(layer "B.Cu")
		(net "GND")
	)
	(segment
		(start 44.092114 -11.893296)
		(end 44.149518 -11.835892)
		(width 0.4064)
		(layer "B.Cu")
		(net "GND")
	)
	(segment
		(start 306.049934 -1.021842)
		(end 306.049934 -2.314956)
		(width 0.4064)
		(layer "B.Cu")
		(net "GND")
	)
	(segment
		(start 493.429798 -26.257758)
		(end 493.429798 -25.622758)
		(width 0.254)
		(layer "B.Cu")
		(net "GND")
	)
	(segment
		(start 18.9992 -94.6404)
		(end 19.05 -94.6404)
		(width 0.254)
		(layer "B.Cu")
		(net "GND")
	)
	(segment
		(start 66.249296 -5.251196)
		(end 66.24955 -5.25145)
		(width 0.4064)
		(layer "B.Cu")
		(net "GND")
	)
	(segment
		(start 364.4265 -56.97728)
		(end 370.3955 -56.97728)
		(width 0.254)
		(layer "B.Cu")
		(net "GND")
	)
	(segment
		(start 76.449428 -20.224242)
		(end 76.449428 -21.517356)
		(width 0.4064)
		(layer "B.Cu")
		(net "GND")
	)
	(segment
		(start 235.49991 -11.878056)
		(end 235.46181 -11.916156)
		(width 0.4064)
		(layer "B.Cu")
		(net "GND")
	)
	(segment
		(start 32.249364 -150.970742)
		(end 32.160464 -150.881842)
		(width 0.4064)
		(layer "B.Cu")
		(net "GND")
	)
	(segment
		(start 171.196 -86.868)
		(end 171.568872 -86.868)
		(width 0.4064)
		(layer "B.Cu")
		(net "GND")
	)
	(segment
		(start 210.849972 -24.824182)
		(end 210.849972 -24.011382)
		(width 0.4064)
		(layer "B.Cu")
		(net "GND")
	)
	(segment
		(start 169.701972 -129.615184)
		(end 169.063416 -130.25374)
		(width 0.381)
		(layer "B.Cu")
		(net "GND")
	)
	(segment
		(start 242.299998 -17.207992)
		(end 242.299744 -17.208246)
		(width 0.4064)
		(layer "B.Cu")
		(net "GND")
	)
	(segment
		(start 492.7219 -130.33756)
		(end 492.97844 -130.5941)
		(width 0.254)
		(layer "B.Cu")
		(net "GND")
	)
	(segment
		(start 311.15 -11.835892)
		(end 311.15 -10.623042)
		(width 0.4064)
		(layer "B.Cu")
		(net "GND")
	)
	(segment
		(start 211.700364 -137.877296)
		(end 211.699856 -137.877296)
		(width 0.4064)
		(layer "B.Cu")
		(net "GND")
	)
	(segment
		(start 221.050358 -147.478496)
		(end 221.04985 -147.478496)
		(width 0.4064)
		(layer "B.Cu")
		(net "GND")
	)
	(segment
		(start 278.2062 -150.0886)
		(end 278.9682 -150.0886)
		(width 0.4064)
		(layer "B.Cu")
		(net "GND")
	)
	(segment
		(start 377.7234 -82.7786)
		(end 377.698 -82.7532)
		(width 0.254)
		(layer "B.Cu")
		(net "GND")
	)
	(segment
		(start 61.745368 -14.097)
		(end 61.745368 -13.440156)
		(width 0.4064)
		(layer "B.Cu")
		(net "GND")
	)
	(segment
		(start 233.799888 -20.224242)
		(end 233.799888 -18.744946)
		(width 0.4064)
		(layer "B.Cu")
		(net "GND")
	)
	(segment
		(start 388.71906 -130.88874)
		(end 389.02132 -130.58648)
		(width 0.254)
		(layer "B.Cu")
		(net "GND")
	)
	(segment
		(start 281.400504 -147.478496)
		(end 281.399996 -147.478496)
		(width 0.4064)
		(layer "B.Cu")
		(net "GND")
	)
	(segment
		(start 375.2088 -38.2016)
		(end 375.371106 -38.363906)
		(width 0.254)
		(layer "B.Cu")
		(net "GND")
	)
	(segment
		(start 278.849836 -137.877296)
		(end 278.849836 -139.587986)
		(width 0.4064)
		(layer "B.Cu")
		(net "GND")
	)
	(segment
		(start 135.703818 -140.685774)
		(end 135.771636 -140.617956)
		(width 0.4064)
		(layer "B.Cu")
		(net "GND")
	)
	(segment
		(start 156.647388 -17.723612)
		(end 157.528768 -17.723612)
		(width 0.4064)
		(layer "B.Cu")
		(net "GND")
	)
	(segment
		(start 163.407852 -76.08697)
		(end 163.6776 -76.356718)
		(width 0.381)
		(layer "B.Cu")
		(net "GND")
	)
	(segment
		(start 143.809212 -150.219156)
		(end 145.12163 -150.219156)
		(width 0.4064)
		(layer "B.Cu")
		(net "GND")
	)
	(segment
		(start 44.092114 -139.147296)
		(end 44.092114 -139.166092)
		(width 0.4064)
		(layer "B.Cu")
		(net "GND")
	)
	(segment
		(start 237.199932 -129.488692)
		(end 237.142528 -129.546096)
		(width 0.4064)
		(layer "B.Cu")
		(net "GND")
	)
	(segment
		(start 207.449928 -148.758656)
		(end 207.437228 -148.771356)
		(width 0.4064)
		(layer "B.Cu")
		(net "GND")
	)
	(segment
		(start 233.800396 -1.021842)
		(end 233.799888 -1.021842)
		(width 0.4064)
		(layer "B.Cu")
		(net "GND")
	)
	(segment
		(start 227.850446 -128.276096)
		(end 227.849938 -128.276096)
		(width 0.4064)
		(layer "B.Cu")
		(net "GND")
	)
	(segment
		(start 315.399928 -128.276096)
		(end 315.400436 -128.276096)
		(width 0.4064)
		(layer "B.Cu")
		(net "GND")
	)
	(segment
		(start 373.906288 -36.096448)
		(end 373.906288 -36.471606)
		(width 0.254)
		(layer "B.Cu")
		(net "GND")
	)
	(segment
		(start 50.949352 -23.054056)
		(end 50.860452 -22.965156)
		(width 0.4064)
		(layer "B.Cu")
		(net "GND")
	)
	(segment
		(start 78.229968 -135.4074)
		(end 79.360268 -135.4074)
		(width 0.4572)
		(layer "B.Cu")
		(net "GND")
	)
	(segment
		(start 66.249296 -24.453596)
		(end 66.24955 -24.45385)
		(width 0.4064)
		(layer "B.Cu")
		(net "GND")
	)
	(segment
		(start 238.899954 -6.63702)
		(end 238.899954 -5.621782)
		(width 0.4064)
		(layer "B.Cu")
		(net "GND")
	)
	(segment
		(start 382.6891 -158.26994)
		(end 383.1844 -158.26994)
		(width 0.254)
		(layer "B.Cu")
		(net "GND")
	)
	(segment
		(start 303.499774 -5.621782)
		(end 303.499774 -6.637274)
		(width 0.4064)
		(layer "B.Cu")
		(net "GND")
	)
	(segment
		(start 278.849836 -17.193006)
		(end 278.95169 -17.29486)
		(width 0.4064)
		(layer "B.Cu")
		(net "GND")
	)
	(segment
		(start 136.799574 -9.20115)
		(end 136.74217 -9.143746)
		(width 0.4064)
		(layer "B.Cu")
		(net "GND")
	)
	(segment
		(start 77.299566 -15.222982)
		(end 77.299566 -17.207992)
		(width 0.4064)
		(layer "B.Cu")
		(net "GND")
	)
	(segment
		(start 150.399496 -147.478496)
		(end 150.399496 -148.771356)
		(width 0.4064)
		(layer "B.Cu")
		(net "GND")
	)
	(segment
		(start 322.06184 -7.237476)
		(end 322.06184 -7.7216)
		(width 0.4064)
		(layer "B.Cu")
		(net "GND")
	)
	(segment
		(start 102.0953 -135.4074)
		(end 103.678736 -135.4074)
		(width 0.4572)
		(layer "B.Cu")
		(net "GND")
	)
	(segment
		(start 242.300506 -132.876036)
		(end 242.300506 -134.860284)
		(width 0.4064)
		(layer "B.Cu")
		(net "GND")
	)
	(segment
		(start 144.449546 -139.157456)
		(end 144.436846 -139.170156)
		(width 0.4064)
		(layer "B.Cu")
		(net "GND")
	)
	(segment
		(start 331.80528 -7.3406)
		(end 331.80528 -7.86638)
		(width 0.254)
		(layer "B.Cu")
		(net "GND")
	)
	(segment
		(start 226.111816 -21.517356)
		(end 226.137216 -21.517356)
		(width 0.4064)
		(layer "B.Cu")
		(net "GND")
	)
	(segment
		(start 236.349794 -141.7066)
		(end 236.095794 -141.4526)
		(width 0.254)
		(layer "B.Cu")
		(net "GND")
	)
	(segment
		(start 278.849836 -20.224242)
		(end 278.849836 -21.567648)
		(width 0.4064)
		(layer "B.Cu")
		(net "GND")
	)
	(segment
		(start 45.84954 -132.062982)
		(end 45.387514 -131.600956)
		(width 0.4064)
		(layer "B.Cu")
		(net "GND")
	)
	(segment
		(start 236.095794 -141.351)
		(end 236.095794 -140.694156)
		(width 0.4064)
		(layer "B.Cu")
		(net "GND")
	)
	(segment
		(start 370.745258 -76.294742)
		(end 370.344954 -76.695046)
		(width 0.254)
		(layer "B.Cu")
		(net "GND")
	)
	(segment
		(start 73.899522 -5.621782)
		(end 73.899522 -6.63702)
		(width 0.4064)
		(layer "B.Cu")
		(net "GND")
	)
	(segment
		(start 297.549824 -17.208246)
		(end 297.549824 -15.222982)
		(width 0.4064)
		(layer "B.Cu")
		(net "GND")
	)
	(segment
		(start 291.354256 -23.799546)
		(end 291.354256 -23.7236)
		(width 0.254)
		(layer "B.Cu")
		(net "GND")
	)
	(segment
		(start 117.071648 -3.762756)
		(end 117.00383 -3.830574)
		(width 0.254)
		(layer "B.Cu")
		(net "GND")
	)
	(segment
		(start 297.549824 -132.875782)
		(end 297.549824 -131.016756)
		(width 0.4064)
		(layer "B.Cu")
		(net "GND")
	)
	(segment
		(start 216.799922 -1.021842)
		(end 216.799922 -2.302256)
		(width 0.4064)
		(layer "B.Cu")
		(net "GND")
	)
	(segment
		(start 317.100458 -128.276096)
		(end 317.09995 -128.276096)
		(width 0.4064)
		(layer "B.Cu")
		(net "GND")
	)
	(segment
		(start 218.499944 -1.021842)
		(end 218.499944 -2.234692)
		(width 0.4064)
		(layer "B.Cu")
		(net "GND")
	)
	(segment
		(start 288.200338 -142.477236)
		(end 288.19983 -142.476982)
		(width 0.4064)
		(layer "B.Cu")
		(net "GND")
	)
	(segment
		(start 66.249296 -14.852396)
		(end 66.249296 -13.363956)
		(width 0.4064)
		(layer "B.Cu")
		(net "GND")
	)
	(segment
		(start 381.2032 -50.3555)
		(end 380.9492 -50.6095)
		(width 0.254)
		(layer "B.Cu")
		(net "GND")
	)
	(segment
		(start 61.999368 -17.0688)
		(end 61.999368 -15.222982)
		(width 0.4064)
		(layer "B.Cu")
		(net "GND")
	)
	(segment
		(start 295.849802 -17.208246)
		(end 295.849802 -15.222982)
		(width 0.4064)
		(layer "B.Cu")
		(net "GND")
	)
	(segment
		(start 199.799956 -11.835892)
		(end 199.799956 -10.623042)
		(width 0.4064)
		(layer "B.Cu")
		(net "GND")
	)
	(segment
		(start 134.249414 -15.222982)
		(end 134.249414 -17.110202)
		(width 0.4064)
		(layer "B.Cu")
		(net "GND")
	)
	(segment
		(start 78.14945 -147.478242)
		(end 78.14945 -145.988278)
		(width 0.508)
		(layer "B.Cu")
		(net "GND")
	)
	(segment
		(start 218.44254 -18.744946)
		(end 218.499944 -18.80235)
		(width 0.4064)
		(layer "B.Cu")
		(net "GND")
	)
	(segment
		(start 309.449978 -129.556256)
		(end 309.449978 -128.276096)
		(width 0.4064)
		(layer "B.Cu")
		(net "GND")
	)
	(segment
		(start 410.690314 -34.134806)
		(end 410.616146 -34.208974)
		(width 0.4572)
		(layer "B.Cu")
		(net "GND")
	)
	(segment
		(start 379.674882 -45.188378)
		(end 379.66015 -45.188378)
		(width 0.254)
		(layer "B.Cu")
		(net "GND")
	)
	(segment
		(start 477.242632 -137.136632)
		(end 477.012 -136.906)
		(width 0.254)
		(layer "B.Cu")
		(net "GND")
	)
	(segment
		(start 207.437228 -11.916156)
		(end 207.449928 -11.903456)
		(width 0.4064)
		(layer "B.Cu")
		(net "GND")
	)
	(segment
		(start 388.070598 -1.8034)
		(end 388.0358 -1.768602)
		(width 0.254)
		(layer "B.Cu")
		(net "GND")
	)
	(segment
		(start 34.799524 -11.835892)
		(end 34.74212 -11.893296)
		(width 0.4064)
		(layer "B.Cu")
		(net "GND")
	)
	(segment
		(start 124.049536 -10.623042)
		(end 124.049536 -9.143746)
		(width 0.4064)
		(layer "B.Cu")
		(net "GND")
	)
	(segment
		(start 196.342 -8.122412)
		(end 196.342 -9.085834)
		(width 0.381)
		(layer "B.Cu")
		(net "GND")
	)
	(segment
		(start 142.749524 -129.568956)
		(end 142.749524 -128.276096)
		(width 0.4064)
		(layer "B.Cu")
		(net "GND")
	)
	(segment
		(start 41.599358 -15.222982)
		(end 41.599358 -17.110202)
		(width 0.4064)
		(layer "B.Cu")
		(net "GND")
	)
	(segment
		(start 225.299778 -140.706856)
		(end 225.210878 -140.617956)
		(width 0.4064)
		(layer "B.Cu")
		(net "GND")
	)
	(segment
		(start 238.899954 -14.410182)
		(end 238.437928 -13.948156)
		(width 0.4064)
		(layer "B.Cu")
		(net "GND")
	)
	(segment
		(start 232.099866 -137.877296)
		(end 232.099866 -139.170156)
		(width 0.4064)
		(layer "B.Cu")
		(net "GND")
	)
	(segment
		(start 135.949436 -132.096764)
		(end 135.703818 -131.851146)
		(width 0.254)
		(layer "B.Cu")
		(net "GND")
	)
	(segment
		(start 53.499512 -137.877296)
		(end 53.499512 -139.089892)
		(width 0.4064)
		(layer "B.Cu")
		(net "GND")
	)
	(segment
		(start 310.299862 -14.443964)
		(end 310.054244 -14.198346)
		(width 0.254)
		(layer "B.Cu")
		(net "GND")
	)
	(segment
		(start 236.349794 -142.476982)
		(end 236.349794 -141.7066)
		(width 0.254)
		(layer "B.Cu")
		(net "GND")
	)
	(segment
		(start 198.087234 -21.517356)
		(end 198.099934 -21.504656)
		(width 0.4064)
		(layer "B.Cu")
		(net "GND")
	)
	(segment
		(start 32.249364 -131.768342)
		(end 32.160464 -131.679442)
		(width 0.4064)
		(layer "B.Cu")
		(net "GND")
	)
	(segment
		(start 439.662316 -148.845016)
		(end 439.6613 -148.844)
		(width 0.254)
		(layer "B.Cu")
		(net "GND")
	)
	(segment
		(start 207.437228 -148.771356)
		(end 207.411828 -148.771356)
		(width 0.4064)
		(layer "B.Cu")
		(net "GND")
	)
	(segment
		(start 311.092596 -2.292096)
		(end 311.092596 -2.310892)
		(width 0.4064)
		(layer "B.Cu")
		(net "GND")
	)
	(segment
		(start 225.210878 -22.965156)
		(end 225.210878 -22.939756)
		(width 0.4064)
		(layer "B.Cu")
		(net "GND")
	)
	(segment
		(start 282.004262 -23.7236)
		(end 282.004262 -23.007574)
		(width 0.4064)
		(layer "B.Cu")
		(net "GND")
	)
	(segment
		(start 78.14945 -137.877296)
		(end 78.14945 -139.2428)
		(width 0.4064)
		(layer "B.Cu")
		(net "GND")
	)
	(segment
		(start 57.74944 -1.021842)
		(end 57.74944 0.444754)
		(width 0.4064)
		(layer "B.Cu")
		(net "GND")
	)
	(segment
		(start 300.099984 -139.157456)
		(end 300.087284 -139.170156)
		(width 0.4064)
		(layer "B.Cu")
		(net "GND")
	)
	(segment
		(start 126.599442 -24.045164)
		(end 126.599442 -24.824182)
		(width 0.254)
		(layer "B.Cu")
		(net "GND")
	)
	(segment
		(start 310.054244 -4.597146)
		(end 310.054244 -4.5212)
		(width 0.254)
		(layer "B.Cu")
		(net "GND")
	)
	(segment
		(start 143.507968 -3.737356)
		(end 143.511524 -3.737356)
		(width 0.254)
		(layer "B.Cu")
		(net "GND")
	)
	(segment
		(start 369.682014 -25.7175)
		(end 369.038632 -26.360882)
		(width 0.508)
		(layer "B.Cu")
		(net "GND")
	)
	(segment
		(start 432.438302 -20.29079)
		(end 432.438302 -21.618194)
		(width 0.254)
		(layer "B.Cu")
		(net "GND")
	)
	(segment
		(start 118.099332 -18.80235)
		(end 118.099332 -20.224242)
		(width 0.4064)
		(layer "B.Cu")
		(net "GND")
	)
	(segment
		(start 124.89942 -23.054056)
		(end 124.89942 -24.824182)
		(width 0.4064)
		(layer "B.Cu")
		(net "GND")
	)
	(segment
		(start 448.900804 -19.939)
		(end 447.8655 -19.939)
		(width 0.254)
		(layer "B.Cu")
		(net "GND")
	)
	(segment
		(start 101.555296 -156.910024)
		(end 101.555296 -158.383986)
		(width 0.4064)
		(layer "B.Cu")
		(net "GND")
	)
	(segment
		(start 405.21509 -24.92629)
		(end 405.726646 -25.437846)
		(width 0.254)
		(layer "B.Cu")
		(net "GND")
	)
	(segment
		(start 280.549858 -132.875782)
		(end 280.549858 -132.876036)
		(width 0.508)
		(layer "B.Cu")
		(net "GND")
	)
	(segment
		(start 499.955566 -38.33622)
		(end 499.955566 -38.090094)
		(width 0.254)
		(layer "B.Cu")
		(net "GND")
	)
	(segment
		(start 151.24938 -13.363956)
		(end 151.24938 -15.222982)
		(width 0.4064)
		(layer "B.Cu")
		(net "GND")
	)
	(segment
		(start 281.399996 -129.556256)
		(end 281.399996 -128.276096)
		(width 0.4064)
		(layer "B.Cu")
		(net "GND")
	)
	(segment
		(start 206.59979 -140.681456)
		(end 206.51089 -140.592556)
		(width 0.4064)
		(layer "B.Cu")
		(net "GND")
	)
	(segment
		(start 52.649374 -151.27986)
		(end 52.398168 -151.028654)
		(width 0.254)
		(layer "B.Cu")
		(net "GND")
	)
	(segment
		(start 373.854472 -88.89111)
		(end 373.498618 -88.89111)
		(width 0.254)
		(layer "B.Cu")
		(net "GND")
	)
	(segment
		(start 144.449546 -148.758656)
		(end 144.436846 -148.771356)
		(width 0.4064)
		(layer "B.Cu")
		(net "GND")
	)
	(segment
		(start 480.633532 2.576068)
		(end 479.95205 3.25755)
		(width 0.254)
		(layer "B.Cu")
		(net "GND")
	)
	(segment
		(start 408.04338 -23.473918)
		(end 408.04338 -23.814786)
		(width 0.254)
		(layer "B.Cu")
		(net "GND")
	)
	(segment
		(start 71.349362 -5.621782)
		(end 71.349362 -7.4676)
		(width 0.4064)
		(layer "B.Cu")
		(net "GND")
	)
	(segment
		(start 205.750414 -137.877296)
		(end 205.749906 -137.877296)
		(width 0.4064)
		(layer "B.Cu")
		(net "GND")
	)
	(segment
		(start 32.249364 -7.509002)
		(end 32.249364 -5.621782)
		(width 0.4064)
		(layer "B.Cu")
		(net "GND")
	)
	(segment
		(start 79.502 -64.262)
		(end 78.589886 -64.262)
		(width 0.254)
		(layer "B.Cu")
		(net "GND")
	)
	(segment
		(start 140.199364 -152.078436)
		(end 140.199364 -150.219156)
		(width 0.4064)
		(layer "B.Cu")
		(net "GND")
	)
	(segment
		(start 66.249296 -151.707596)
		(end 66.249296 -150.219156)
		(width 0.4064)
		(layer "B.Cu")
		(net "GND")
	)
	(segment
		(start 73.899522 -151.265382)
		(end 73.437496 -150.803356)
		(width 0.4064)
		(layer "B.Cu")
		(net "GND")
	)
	(segment
		(start 428.529496 -23.368)
		(end 428.3075 -23.368)
		(width 0.254)
		(layer "B.Cu")
		(net "GND")
	)
	(segment
		(start 113.849404 -142.477236)
		(end 113.849404 -144.5768)
		(width 0.4064)
		(layer "B.Cu")
		(net "GND")
	)
	(segment
		(start 31.341568 -18.687034)
		(end 31.39948 -18.744946)
		(width 0.381)
		(layer "B.Cu")
		(net "GND")
	)
	(segment
		(start 60.299346 -131.105656)
		(end 60.210446 -131.016756)
		(width 0.4064)
		(layer "B.Cu")
		(net "GND")
	)
	(segment
		(start 34.799524 -148.691092)
		(end 34.74212 -148.748496)
		(width 0.4064)
		(layer "B.Cu")
		(net "GND")
	)
	(segment
		(start 61.745368 -150.9522)
		(end 61.745368 -150.295356)
		(width 0.4064)
		(layer "B.Cu")
		(net "GND")
	)
	(segment
		(start 223.60001 -25.638252)
		(end 223.60001 -24.824182)
		(width 0.4064)
		(layer "B.Cu")
		(net "GND")
	)
	(segment
		(start 82.116168 -26.6446)
		(end 82.116168 -27.2034)
		(width 0.4064)
		(layer "B.Cu")
		(net "GND")
	)
	(segment
		(start 51.79949 0.444754)
		(end 51.79949 -1.021842)
		(width 0.4064)
		(layer "B.Cu")
		(net "GND")
	)
	(segment
		(start 227.850446 -1.021842)
		(end 227.849938 -1.021842)
		(width 0.4064)
		(layer "B.Cu")
		(net "GND")
	)
	(segment
		(start 369.80876 -98.962464)
		(end 369.527836 -98.68154)
		(width 0.254)
		(layer "B.Cu")
		(net "GND")
	)
	(segment
		(start 300.949868 -142.476982)
		(end 300.950376 -142.477236)
		(width 0.254)
		(layer "B.Cu")
		(net "GND")
	)
	(segment
		(start 377.242832 -98.354896)
		(end 378.210572 -99.322636)
		(width 0.2032)
		(layer "B.Cu")
		(net "GND")
	)
	(segment
		(start 74.749406 -2.314956)
		(end 74.749406 -1.021842)
		(width 0.4064)
		(layer "B.Cu")
		(net "GND")
	)
	(segment
		(start 283.099764 -9.20115)
		(end 283.099764 -10.623042)
		(width 0.4064)
		(layer "B.Cu")
		(net "GND")
	)
	(segment
		(start 229.54996 -4.808982)
		(end 229.087934 -4.346956)
		(width 0.4064)
		(layer "B.Cu")
		(net "GND")
	)
	(segment
		(start 79.264002 -87.632286)
		(end 78.867254 -87.632286)
		(width 0.254)
		(layer "B.Cu")
		(net "GND")
	)
	(segment
		(start 33.099502 -11.903456)
		(end 33.086802 -11.916156)
		(width 0.4064)
		(layer "B.Cu")
		(net "GND")
	)
	(segment
		(start 375.793 -60.579)
		(end 375.519696 -60.852304)
		(width 0.254)
		(layer "B.Cu")
		(net "GND")
	)
	(segment
		(start -0.500126 -45.310044)
		(end 0.933958 -46.744128)
		(width 0.508)
		(layer "B.Cu")
		(net "GND")
	)
	(segment
		(start 43.050968 -151.101552)
		(end 43.050968 -150.277068)
		(width 0.4064)
		(layer "B.Cu")
		(net "GND")
	)
	(segment
		(start 152.099518 -21.528278)
		(end 152.099518 -20.224242)
		(width 0.4064)
		(layer "B.Cu")
		(net "GND")
	)
	(segment
		(start 301.742602 -148.767292)
		(end 301.742602 -148.748496)
		(width 0.4064)
		(layer "B.Cu")
		(net "GND")
	)
	(segment
		(start 241.44986 -20.224242)
		(end 241.44986 -21.517356)
		(width 0.4064)
		(layer "B.Cu")
		(net "GND")
	)
	(segment
		(start 299.250354 -132.876036)
		(end 299.249846 -132.875782)
		(width 0.4064)
		(layer "B.Cu")
		(net "GND")
	)
	(segment
		(start 71.095362 -13.440156)
		(end 71.095362 -14.097)
		(width 0.4064)
		(layer "B.Cu")
		(net "GND")
	)
	(segment
		(start 126.421642 -13.363956)
		(end 126.353824 -13.431774)
		(width 0.4064)
		(layer "B.Cu")
		(net "GND")
	)
	(segment
		(start 239.749838 -147.478496)
		(end 239.749838 -148.771356)
		(width 0.4064)
		(layer "B.Cu")
		(net "GND")
	)
	(segment
		(start 33.099502 -147.478496)
		(end 33.099502 -148.758656)
		(width 0.4064)
		(layer "B.Cu")
		(net "GND")
	)
	(segment
		(start 217.3986 -23.774654)
		(end 217.3986 -23.7236)
		(width 0.254)
		(layer "B.Cu")
		(net "GND")
	)
	(segment
		(start 242.299998 -13.36421)
		(end 242.299744 -13.363956)
		(width 0.4064)
		(layer "B.Cu")
		(net "GND")
	)
	(segment
		(start 447.929 -152.1714)
		(end 447.929 -152.5524)
		(width 0.254)
		(layer "B.Cu")
		(net "GND")
	)
	(segment
		(start 289.899852 -131.105656)
		(end 289.810952 -131.016756)
		(width 0.4064)
		(layer "B.Cu")
		(net "GND")
	)
	(segment
		(start 92.047568 -8.0772)
		(end 91.6559 -8.468868)
		(width 0.4064)
		(layer "B.Cu")
		(net "GND")
	)
	(segment
		(start 79.502 -65.151)
		(end 79.502 -64.262)
		(width 0.254)
		(layer "B.Cu")
		(net "GND")
	)
	(segment
		(start 116.386864 -11.916156)
		(end 116.399564 -11.903456)
		(width 0.4064)
		(layer "B.Cu")
		(net "GND")
	)
	(segment
		(start 331.80528 -7.86638)
		(end 331.45476 -8.2169)
		(width 0.254)
		(layer "B.Cu")
		(net "GND")
	)
	(segment
		(start 280.550366 -140.681964)
		(end 280.460958 -140.592556)
		(width 0.508)
		(layer "B.Cu")
		(net "GND")
	)
	(segment
		(start 141.049502 -21.517356)
		(end 141.049502 -20.224242)
		(width 0.4064)
		(layer "B.Cu")
		(net "GND")
	)
	(segment
		(start 201.499978 -132.062982)
		(end 201.037952 -131.600956)
		(width 0.4064)
		(layer "B.Cu")
		(net "GND")
	)
	(segment
		(start 383.9718 -81.61274)
		(end 384.31724 -81.2673)
		(width 0.254)
		(layer "B.Cu")
		(net "GND")
	)
	(segment
		(start 212.550502 -152.078436)
		(end 212.549994 -152.078182)
		(width 0.4064)
		(layer "B.Cu")
		(net "GND")
	)
	(segment
		(start 44.092114 -21.494496)
		(end 44.092114 -21.513292)
		(width 0.4064)
		(layer "B.Cu")
		(net "GND")
	)
	(segment
		(start 296.69994 -18.757646)
		(end 296.69994 -20.224242)
		(width 0.4064)
		(layer "B.Cu")
		(net "GND")
	)
	(segment
		(start 370.651278 -71.494142)
		(end 370.344954 -71.800466)
		(width 0.254)
		(layer "B.Cu")
		(net "GND")
	)
	(segment
		(start 32.160464 -4.425442)
		(end 32.160464 -3.737356)
		(width 0.4064)
		(layer "B.Cu")
		(net "GND")
	)
	(segment
		(start 402.1963 -52.705)
		(end 402.1963 -52.7304)
		(width 0.254)
		(layer "B.Cu")
		(net "GND")
	)
	(segment
		(start 377.80595 -83.845146)
		(end 377.80595 -83.3755)
		(width 0.254)
		(layer "B.Cu")
		(net "GND")
	)
	(segment
		(start 288.200338 -15.222982)
		(end 288.19983 -15.222982)
		(width 0.4064)
		(layer "B.Cu")
		(net "GND")
	)
	(segment
		(start 33.949386 -17.0688)
		(end 33.949386 -15.222982)
		(width 0.4064)
		(layer "B.Cu")
		(net "GND")
	)
	(segment
		(start 317.09995 -10.623042)
		(end 317.09995 -9.156446)
		(width 0.4064)
		(layer "B.Cu")
		(net "GND")
	)
	(segment
		(start 279.4254 -28.829)
		(end 279.4254 -29.1592)
		(width 0.254)
		(layer "B.Cu")
		(net "GND")
	)
	(segment
		(start 232.950004 -132.875782)
		(end 232.950004 -132.58165)
		(width 0.4064)
		(layer "B.Cu")
		(net "GND")
	)
	(segment
		(start 331.31506 -8.3566)
		(end 330.7588 -8.3566)
		(width 0.254)
		(layer "B.Cu")
		(net "GND")
	)
	(segment
		(start 146.149568 -147.478496)
		(end 146.149568 -148.691092)
		(width 0.4064)
		(layer "B.Cu")
		(net "GND")
	)
	(segment
		(start 204.049884 -137.877296)
		(end 204.049884 -139.170156)
		(width 0.4064)
		(layer "B.Cu")
		(net "GND")
	)
	(segment
		(start 51.79949 -2.302256)
		(end 51.78679 -2.314956)
		(width 0.4064)
		(layer "B.Cu")
		(net "GND")
	)
	(segment
		(start 201.499978 -24.824182)
		(end 201.499978 -24.011382)
		(width 0.4064)
		(layer "B.Cu")
		(net "GND")
	)
	(segment
		(start 499.995698 -54.405022)
		(end 499.12016 -54.405022)
		(width 0.508)
		(layer "B.Cu")
		(net "GND")
	)
	(segment
		(start 82.459068 -3.3528)
		(end 81.582768 -3.3528)
		(width 0.4064)
		(layer "B.Cu")
		(net "GND")
	)
	(segment
		(start 135.703818 -14.198346)
		(end 135.703818 -14.1224)
		(width 0.254)
		(layer "B.Cu")
		(net "GND")
	)
	(segment
		(start 369.187984 -38.386512)
		(end 370.929916 -38.386512)
		(width 0.254)
		(layer "B.Cu")
		(net "GND")
	)
	(segment
		(start 258.758436 -157.016958)
		(end 258.631436 -157.016958)
		(width 0.4064)
		(layer "B.Cu")
		(net "GND")
	)
	(segment
		(start 312.391298 -7.095744)
		(end 312.849768 -6.637274)
		(width 0.4064)
		(layer "B.Cu")
		(net "GND")
	)
	(segment
		(start 295.85031 -150.219664)
		(end 295.849802 -150.219156)
		(width 0.4064)
		(layer "B.Cu")
		(net "GND")
	)
	(segment
		(start 300.70425 -150.9776)
		(end 300.70425 -151.053546)
		(width 0.254)
		(layer "B.Cu")
		(net "GND")
	)
	(segment
		(start 56.899556 -5.621782)
		(end 56.899556 -7.606792)
		(width 0.4064)
		(layer "B.Cu")
		(net "GND")
	)
	(segment
		(start 280.550366 -144.363694)
		(end 280.451814 -144.462246)
		(width 0.508)
		(layer "B.Cu")
		(net "GND")
	)
	(segment
		(start 234.649772 -3.851656)
		(end 234.560872 -3.762756)
		(width 0.4064)
		(layer "B.Cu")
		(net "GND")
	)
	(segment
		(start 103.678736 -145.0086)
		(end 102.7938 -145.0086)
		(width 0.4572)
		(layer "B.Cu")
		(net "GND")
	)
	(segment
		(start 217.649806 -142.476982)
		(end 217.649806 -141.67866)
		(width 0.254)
		(layer "B.Cu")
		(net "GND")
	)
	(segment
		(start 216.787222 -129.568956)
		(end 216.761822 -129.568956)
		(width 0.4064)
		(layer "B.Cu")
		(net "GND")
	)
	(segment
		(start 141.049502 -128.276096)
		(end 141.049502 -129.568956)
		(width 0.4064)
		(layer "B.Cu")
		(net "GND")
	)
	(segment
		(start 115.549426 -24.824182)
		(end 115.549426 -23.054056)
		(width 0.4064)
		(layer "B.Cu")
		(net "GND")
	)
	(segment
		(start 290.71189 -11.916156)
		(end 290.73729 -11.916156)
		(width 0.4064)
		(layer "B.Cu")
		(net "GND")
	)
	(segment
		(start 36.499546 -4.808982)
		(end 36.499546 -5.621782)
		(width 0.4064)
		(layer "B.Cu")
		(net "GND")
	)
	(segment
		(start 312.850276 -152.078436)
		(end 312.849768 -152.078182)
		(width 0.4064)
		(layer "B.Cu")
		(net "GND")
	)
	(segment
		(start 311.150508 -1.021842)
		(end 311.15 -1.021842)
		(width 0.4064)
		(layer "B.Cu")
		(net "GND")
	)
	(segment
		(start 135.703818 -23.799546)
		(end 135.949436 -24.045164)
		(width 0.254)
		(layer "B.Cu")
		(net "GND")
	)
	(segment
		(start 199.800464 -128.276096)
		(end 199.799956 -128.276096)
		(width 0.4064)
		(layer "B.Cu")
		(net "GND")
	)
	(segment
		(start 386.6896 -54.61)
		(end 386.1435 -54.61)
		(width 0.254)
		(layer "B.Cu")
		(net "GND")
	)
	(segment
		(start 206.59979 -131.080256)
		(end 206.51089 -130.991356)
		(width 0.4064)
		(layer "B.Cu")
		(net "GND")
	)
	(segment
		(start 53.499512 -129.488692)
		(end 53.442108 -129.546096)
		(width 0.4064)
		(layer "B.Cu")
		(net "GND")
	)
	(segment
		(start 70.499478 -11.878056)
		(end 70.461378 -11.916156)
		(width 0.4064)
		(layer "B.Cu")
		(net "GND")
	)
	(segment
		(start 138.499342 -15.222982)
		(end 138.499342 -14.409928)
		(width 0.4064)
		(layer "B.Cu")
		(net "GND")
	)
	(segment
		(start 70.499478 -137.877296)
		(end 70.499478 -139.132056)
		(width 0.4064)
		(layer "B.Cu")
		(net "GND")
	)
	(segment
		(start 322.065904 -18.254472)
		(end 322.065904 -18.713704)
		(width 0.4064)
		(layer "B.Cu")
		(net "GND")
	)
	(segment
		(start 55.199534 -24.824182)
		(end 55.199534 -24.011382)
		(width 0.4064)
		(layer "B.Cu")
		(net "GND")
	)
	(segment
		(start 222.75038 -137.877296)
		(end 222.749872 -137.877296)
		(width 0.4064)
		(layer "B.Cu")
		(net "GND")
	)
	(segment
		(start 58.599324 -22.965156)
		(end 58.599324 -24.580596)
		(width 0.4064)
		(layer "B.Cu")
		(net "GND")
	)
	(segment
		(start 116.399564 -21.504656)
		(end 116.386864 -21.517356)
		(width 0.4064)
		(layer "B.Cu")
		(net "GND")
	)
	(segment
		(start 309.411878 -21.517356)
		(end 309.437278 -21.517356)
		(width 0.4064)
		(layer "B.Cu")
		(net "GND")
	)
	(segment
		(start 395.28877 -40.55872)
		(end 396.27937 -41.54932)
		(width 0.254)
		(layer "B.Cu")
		(net "GND")
	)
	(segment
		(start 238.899954 -152.078182)
		(end 238.899954 -151.265382)
		(width 0.4064)
		(layer "B.Cu")
		(net "GND")
	)
	(segment
		(start 172.466 -86.868)
		(end 172.136816 -86.868)
		(width 0.4064)
		(layer "B.Cu")
		(net "GND")
	)
	(segment
		(start 215.100408 -1.021842)
		(end 215.0999 -1.021842)
		(width 0.4064)
		(layer "B.Cu")
		(net "GND")
	)
	(segment
		(start 450.141594 -18.52549)
		(end 450.141594 -17.9451)
		(width 0.254)
		(layer "B.Cu")
		(net "GND")
	)
	(segment
		(start 411.662118 -94.160594)
		(end 411.662118 -94.881446)
		(width 0.254)
		(layer "B.Cu")
		(net "GND")
	)
	(segment
		(start 284.800294 -132.876036)
		(end 284.799786 -132.875782)
		(width 0.3556)
		(layer "B.Cu")
		(net "GND")
	)
	(segment
		(start 352.02368 -88.622632)
		(end 351.8662 -88.465152)
		(width 0.254)
		(layer "B.Cu")
		(net "GND")
	)
	(segment
		(start 242.299998 -15.222982)
		(end 242.299998 -17.207992)
		(width 0.4064)
		(layer "B.Cu")
		(net "GND")
	)
	(segment
		(start 474.58376 -43.67911)
		(end 474.56725 -43.6626)
		(width 0.508)
		(layer "B.Cu")
		(net "GND")
	)
	(segment
		(start 116.399564 -1.021842)
		(end 116.399564 -2.302256)
		(width 0.4064)
		(layer "B.Cu")
		(net "GND")
	)
	(segment
		(start 307.749956 -18.744946)
		(end 307.749956 -20.224242)
		(width 0.4064)
		(layer "B.Cu")
		(net "GND")
	)
	(segment
		(start 282.004262 -140.660374)
		(end 282.07208 -140.592556)
		(width 0.254)
		(layer "B.Cu")
		(net "GND")
	)
	(segment
		(start 375.630694 -77.094334)
		(end 375.944892 -77.408532)
		(width 0.254)
		(layer "B.Cu")
		(net "GND")
	)
	(segment
		(start 122.349514 -128.276096)
		(end 122.349514 -129.568956)
		(width 0.4064)
		(layer "B.Cu")
		(net "GND")
	)
	(segment
		(start 393.18565 -116.094764)
		(end 392.930888 -115.840002)
		(width 0.4064)
		(layer "B.Cu")
		(net "GND")
	)
	(segment
		(start 278.849836 -128.276096)
		(end 278.849836 -130.124962)
		(width 0.4064)
		(layer "B.Cu")
		(net "GND")
	)
	(segment
		(start 204.050392 -147.478496)
		(end 204.049884 -147.478496)
		(width 0.4064)
		(layer "B.Cu")
		(net "GND")
	)
	(segment
		(start 373.498618 -88.89111)
		(end 373.498618 -88.235282)
		(width 0.254)
		(layer "B.Cu")
		(net "GND")
	)
	(segment
		(start 117.249448 -4.842764)
		(end 117.249448 -5.621782)
		(width 0.254)
		(layer "B.Cu")
		(net "GND")
	)
	(segment
		(start 310.299862 -132.096764)
		(end 310.299862 -132.875782)
		(width 0.254)
		(layer "B.Cu")
		(net "GND")
	)
	(segment
		(start 226.9998 -5.621782)
		(end 226.9998 -4.8514)
		(width 0.254)
		(layer "B.Cu")
		(net "GND")
	)
	(segment
		(start 3.011932 -15.9512)
		(end 3.013456 -15.949676)
		(width 0.254)
		(layer "B.Cu")
		(net "GND")
	)
	(segment
		(start 216.799922 0.444754)
		(end 216.799922 -1.021842)
		(width 0.4064)
		(layer "B.Cu")
		(net "GND")
	)
	(segment
		(start 240.599976 -24.45385)
		(end 240.599722 -24.453596)
		(width 0.4064)
		(layer "B.Cu")
		(net "GND")
	)
	(segment
		(start 122.349514 -10.623042)
		(end 122.349514 -9.156446)
		(width 0.4064)
		(layer "B.Cu")
		(net "GND")
	)
	(segment
		(start 386.96138 -61.61532)
		(end 386.96138 -61.66358)
		(width 0.254)
		(layer "B.Cu")
		(net "GND")
	)
	(segment
		(start 71.095362 -23.041356)
		(end 71.095362 -23.6982)
		(width 0.4064)
		(layer "B.Cu")
		(net "GND")
	)
	(segment
		(start 292.450012 0.40005)
		(end 292.392608 0.457454)
		(width 0.4064)
		(layer "B.Cu")
		(net "GND")
	)
	(segment
		(start 490.081062 -129.845308)
		(end 491.41253 -128.51384)
		(width 0.254)
		(layer "B.Cu")
		(net "GND")
	)
	(segment
		(start 124.049536 -129.568956)
		(end 124.049536 -128.276096)
		(width 0.4064)
		(layer "B.Cu")
		(net "GND")
	)
	(segment
		(start 69.64934 -5.621782)
		(end 69.64934 -3.851656)
		(width 0.4064)
		(layer "B.Cu")
		(net "GND")
	)
	(segment
		(start 145.053812 -131.851146)
		(end 145.29943 -132.096764)
		(width 0.254)
		(layer "B.Cu")
		(net "GND")
	)
	(segment
		(start 301.800006 -2.234692)
		(end 301.742602 -2.292096)
		(width 0.4064)
		(layer "B.Cu")
		(net "GND")
	)
	(segment
		(start 67.949572 -132.58165)
		(end 67.949318 -132.581396)
		(width 0.4064)
		(layer "B.Cu")
		(net "GND")
	)
	(segment
		(start 282.004262 -3.830574)
		(end 282.004262 -4.5212)
		(width 0.4064)
		(layer "B.Cu")
		(net "GND")
	)
	(segment
		(start 141.899386 -142.477236)
		(end 141.899386 -140.617956)
		(width 0.4064)
		(layer "B.Cu")
		(net "GND")
	)
	(segment
		(start 208.299812 -15.222982)
		(end 208.299812 -14.494764)
		(width 0.254)
		(layer "B.Cu")
		(net "GND")
	)
	(segment
		(start 215.949784 -140.706856)
		(end 215.860884 -140.617956)
		(width 0.4064)
		(layer "B.Cu")
		(net "GND")
	)
	(segment
		(start 113.849404 -23.523956)
		(end 113.967768 -23.405592)
		(width 0.4064)
		(layer "B.Cu")
		(net "GND")
	)
	(segment
		(start 316.442598 -30.813502)
		(end 315.345826 -30.813502)
		(width 0.381)
		(layer "B.Cu")
		(net "GND")
	)
	(segment
		(start 304.349912 -128.276096)
		(end 304.349912 -129.568956)
		(width 0.4064)
		(layer "B.Cu")
		(net "GND")
	)
	(segment
		(start 58.599578 -142.23365)
		(end 58.599324 -142.233396)
		(width 0.4064)
		(layer "B.Cu")
		(net "GND")
	)
	(segment
		(start 135.703818 -14.1224)
		(end 135.703818 -13.431774)
		(width 0.4064)
		(layer "B.Cu")
		(net "GND")
	)
	(segment
		(start 143.809212 -131.016756)
		(end 145.12163 -131.016756)
		(width 0.4064)
		(layer "B.Cu")
		(net "GND")
	)
	(segment
		(start 217.649806 -5.621782)
		(end 217.649806 -4.82346)
		(width 0.254)
		(layer "B.Cu")
		(net "GND")
	)
	(segment
		(start 279.700482 -20.224242)
		(end 279.699974 -20.224242)
		(width 0.4064)
		(layer "B.Cu")
		(net "GND")
	)
	(segment
		(start 142.749524 -148.771356)
		(end 142.749524 -147.478496)
		(width 0.4064)
		(layer "B.Cu")
		(net "GND")
	)
	(segment
		(start 402.881846 -23.949152)
		(end 402.488146 -23.949152)
		(width 0.254)
		(layer "B.Cu")
		(net "GND")
	)
	(segment
		(start 308.501796 -7.607046)
		(end 308.59984 -7.509002)
		(width 0.4064)
		(layer "B.Cu")
		(net "GND")
	)
	(segment
		(start 402.9964 1.956562)
		(end 402.742146 1.702308)
		(width 0.254)
		(layer "B.Cu")
		(net "GND")
	)
	(segment
		(start 282.24988 -24.824182)
		(end 282.24988 -24.045164)
		(width 0.254)
		(layer "B.Cu")
		(net "GND")
	)
	(segment
		(start 346.07754 -91.622118)
		(end 346.07754 -90.880692)
		(width 0.2032)
		(layer "B.Cu")
		(net "GND")
	)
	(segment
		(start 239.749838 -10.623042)
		(end 239.749838 -9.156446)
		(width 0.4064)
		(layer "B.Cu")
		(net "GND")
	)
	(segment
		(start 127.44958 -128.276096)
		(end 127.44958 -129.488692)
		(width 0.4064)
		(layer "B.Cu")
		(net "GND")
	)
	(segment
		(start 287.350454 -137.877296)
		(end 287.349946 -137.877296)
		(width 0.4064)
		(layer "B.Cu")
		(net "GND")
	)
	(segment
		(start 372.0211 -89.7255)
		(end 372.0211 -89.249504)
		(width 0.254)
		(layer "B.Cu")
		(net "GND")
	)
	(segment
		(start 411.56636 -94.977204)
		(end 411.593538 -94.977204)
		(width 0.254)
		(layer "B.Cu")
		(net "GND")
	)
	(segment
		(start 270.956532 -3.3528)
		(end 272.027904 -3.3528)
		(width 0.381)
		(layer "B.Cu")
		(net "GND")
	)
	(segment
		(start 240.599976 -151.70785)
		(end 240.599722 -151.707596)
		(width 0.4064)
		(layer "B.Cu")
		(net "GND")
	)
	(segment
		(start 32.15132 -17.208246)
		(end 32.249364 -17.110202)
		(width 0.4064)
		(layer "B.Cu")
		(net "GND")
	)
	(segment
		(start 226.150424 -137.877296)
		(end 226.149916 -137.877296)
		(width 0.4064)
		(layer "B.Cu")
		(net "GND")
	)
	(segment
		(start 239.750346 -20.224242)
		(end 239.749838 -20.224242)
		(width 0.4064)
		(layer "B.Cu")
		(net "GND")
	)
	(segment
		(start 73.899522 -15.222982)
		(end 73.899522 -14.410182)
		(width 0.4064)
		(layer "B.Cu")
		(net "GND")
	)
	(segment
		(start 232.099866 -26.488136)
		(end 231.249982 -25.638252)
		(width 0.4064)
		(layer "B.Cu")
		(net "GND")
	)
	(segment
		(start 279.700482 -128.276096)
		(end 279.699974 -128.276096)
		(width 0.4064)
		(layer "B.Cu")
		(net "GND")
	)
	(segment
		(start 46.699424 -10.623042)
		(end 46.699424 -11.916156)
		(width 0.4064)
		(layer "B.Cu")
		(net "GND")
	)
	(segment
		(start 146.149568 -21.437092)
		(end 146.092164 -21.494496)
		(width 0.4064)
		(layer "B.Cu")
		(net "GND")
	)
	(segment
		(start 84.910168 -145.0086)
		(end 85.761068 -145.0086)
		(width 0.4572)
		(layer "B.Cu")
		(net "GND")
	)
	(segment
		(start 307.749956 -20.224242)
		(end 307.749956 -21.517356)
		(width 0.4064)
		(layer "B.Cu")
		(net "GND")
	)
	(segment
		(start 214.581232 -97.2312)
		(end 215.041226 -97.2312)
		(width 0.254)
		(layer "B.Cu")
		(net "GND")
	)
	(segment
		(start 96.578928 1.6383)
		(end 96.578928 2.7686)
		(width 0.508)
		(layer "B.Cu")
		(net "GND")
	)
	(segment
		(start 317.950342 -5.621782)
		(end 317.949834 -5.621782)
		(width 0.4064)
		(layer "B.Cu")
		(net "GND")
	)
	(segment
		(start 284.799786 -24.824182)
		(end 284.799786 -24.011382)
		(width 0.4064)
		(layer "B.Cu")
		(net "GND")
	)
	(segment
		(start 231.2924 -85.2932)
		(end 231.7242 -84.8614)
		(width 0.254)
		(layer "B.Cu")
		(net "GND")
	)
	(segment
		(start 52.398168 -151.028654)
		(end 52.398168 -150.9776)
		(width 0.254)
		(layer "B.Cu")
		(net "GND")
	)
	(segment
		(start 122.349514 -147.478496)
		(end 122.349514 -148.771356)
		(width 0.4064)
		(layer "B.Cu")
		(net "GND")
	)
	(segment
		(start 392.684 -102.763066)
		(end 392.684 -103.3272)
		(width 0.3556)
		(layer "B.Cu")
		(net "GND")
	)
	(segment
		(start 152.099518 -9.156446)
		(end 152.146 -9.109964)
		(width 0.4064)
		(layer "B.Cu")
		(net "GND")
	)
	(segment
		(start 231.249728 -132.505196)
		(end 231.249728 -131.016756)
		(width 0.4064)
		(layer "B.Cu")
		(net "GND")
	)
	(segment
		(start 61.745368 -14.1986)
		(end 61.745368 -14.097)
		(width 0.254)
		(layer "B.Cu")
		(net "GND")
	)
	(segment
		(start 138.499342 -132.062728)
		(end 138.03757 -131.600956)
		(width 0.4064)
		(layer "B.Cu")
		(net "GND")
	)
	(segment
		(start 310.054244 -150.9776)
		(end 310.054244 -150.286974)
		(width 0.4064)
		(layer "B.Cu")
		(net "GND")
	)
	(segment
		(start 74.749406 -10.623042)
		(end 74.749406 -11.916156)
		(width 0.4064)
		(layer "B.Cu")
		(net "GND")
	)
	(segment
		(start 143.599408 -140.82776)
		(end 143.599408 -142.477236)
		(width 0.4064)
		(layer "B.Cu")
		(net "GND")
	)
	(segment
		(start 91.421712 -2.975356)
		(end 91.704668 -3.258312)
		(width 0.4064)
		(layer "B.Cu")
		(net "GND")
	)
	(segment
		(start 369.9383 -6.2357)
		(end 369.5954 -6.2357)
		(width 0.381)
		(layer "B.Cu")
		(net "GND")
	)
	(segment
		(start 71.171562 -7.6454)
		(end 70.499478 -8.317484)
		(width 0.4064)
		(layer "B.Cu")
		(net "GND")
	)
	(segment
		(start 308.501796 -17.208246)
		(end 308.59984 -17.110202)
		(width 0.4064)
		(layer "B.Cu")
		(net "GND")
	)
	(segment
		(start 226.150424 -10.623042)
		(end 226.149916 -10.623042)
		(width 0.4064)
		(layer "B.Cu")
		(net "GND")
	)
	(segment
		(start 152.099518 -1.021842)
		(end 152.099518 -2.325878)
		(width 0.4064)
		(layer "B.Cu")
		(net "GND")
	)
	(segment
		(start 199.799956 -1.021842)
		(end 199.799956 -2.234692)
		(width 0.4064)
		(layer "B.Cu")
		(net "GND")
	)
	(segment
		(start 31.341568 -145.941034)
		(end 31.39948 -145.998946)
		(width 0.4064)
		(layer "B.Cu")
		(net "GND")
	)
	(segment
		(start 381.4953 -46.0883)
		(end 380.746 -46.0883)
		(width 0.254)
		(layer "B.Cu")
		(net "GND")
	)
	(segment
		(start 289.050476 -128.276096)
		(end 289.049968 -128.276096)
		(width 0.4064)
		(layer "B.Cu")
		(net "GND")
	)
	(segment
		(start 198.099934 -21.504656)
		(end 198.099934 -20.224242)
		(width 0.4064)
		(layer "B.Cu")
		(net "GND")
	)
	(segment
		(start 217.472006 -17.2466)
		(end 217.649806 -17.0688)
		(width 0.4064)
		(layer "B.Cu")
		(net "GND")
	)
	(segment
		(start 146.149568 -9.20115)
		(end 146.092164 -9.143746)
		(width 0.4064)
		(layer "B.Cu")
		(net "GND")
	)
	(segment
		(start 118.099332 -9.20115)
		(end 118.041928 -9.143746)
		(width 0.4064)
		(layer "B.Cu")
		(net "GND")
	)
	(segment
		(start 195.533772 -134.4168)
		(end 195.1482 -134.4168)
		(width 0.4064)
		(layer "B.Cu")
		(net "GND")
	)
	(segment
		(start 227.792534 -139.147296)
		(end 227.792534 -139.166092)
		(width 0.4064)
		(layer "B.Cu")
		(net "GND")
	)
	(segment
		(start 124.049536 -18.744946)
		(end 124.049536 -20.224242)
		(width 0.4064)
		(layer "B.Cu")
		(net "GND")
	)
	(segment
		(start 31.685738 -87.8332)
		(end 30.9372 -87.8332)
		(width 0.254)
		(layer "B.Cu")
		(net "GND")
	)
	(segment
		(start 403.391624 -31.912052)
		(end 402.972524 -31.912052)
		(width 0.254)
		(layer "B.Cu")
		(net "GND")
	)
	(segment
		(start 297.549824 -142.476982)
		(end 297.549824 -140.617956)
		(width 0.4064)
		(layer "B.Cu")
		(net "GND")
	)
	(segment
		(start 141.049502 -10.623042)
		(end 141.049502 -9.156446)
		(width 0.4064)
		(layer "B.Cu")
		(net "GND")
	)
	(segment
		(start 317.09995 -17.733518)
		(end 317.09995 -16.687546)
		(width 0.4064)
		(layer "B.Cu")
		(net "GND")
	)
	(segment
		(start 136.799574 -21.455888)
		(end 136.74217 -21.513292)
		(width 0.4064)
		(layer "B.Cu")
		(net "GND")
	)
	(segment
		(start 167.767 -125.603)
		(end 167.767 -124.968)
		(width 0.4064)
		(layer "B.Cu")
		(net "GND")
	)
	(segment
		(start 65.399412 0.444754)
		(end 65.399412 -1.021842)
		(width 0.4064)
		(layer "B.Cu")
		(net "GND")
	)
	(segment
		(start 215.949784 -17.110202)
		(end 215.949784 -15.222982)
		(width 0.4064)
		(layer "B.Cu")
		(net "GND")
	)
	(segment
		(start 301.742602 -2.292096)
		(end 301.742602 -2.310892)
		(width 0.4064)
		(layer "B.Cu")
		(net "GND")
	)
	(segment
		(start 495.025934 -40.329866)
		(end 495.025934 -39.651686)
		(width 0.254)
		(layer "B.Cu")
		(net "GND")
	)
	(segment
		(start 197.249796 -17.110202)
		(end 197.249796 -15.222982)
		(width 0.4064)
		(layer "B.Cu")
		(net "GND")
	)
	(segment
		(start 214.250016 -151.73325)
		(end 214.249762 -151.732996)
		(width 0.4064)
		(layer "B.Cu")
		(net "GND")
	)
	(segment
		(start 453.4154 -146.7612)
		(end 453.0598 -147.1168)
		(width 0.254)
		(layer "B.Cu")
		(net "GND")
	)
	(segment
		(start 316.249812 -15.222982)
		(end 316.249812 -17.208246)
		(width 0.4064)
		(layer "B.Cu")
		(net "GND")
	)
	(segment
		(start 34.74212 -139.147296)
		(end 34.74212 -139.166092)
		(width 0.4064)
		(layer "B.Cu")
		(net "GND")
	)
	(segment
		(start 309.449978 -139.157456)
		(end 309.449978 -137.877296)
		(width 0.4064)
		(layer "B.Cu")
		(net "GND")
	)
	(segment
		(start 71.095362 -150.295356)
		(end 71.171562 -150.219156)
		(width 0.4064)
		(layer "B.Cu")
		(net "GND")
	)
	(segment
		(start 67.099434 -20.224242)
		(end 67.099434 -18.757646)
		(width 0.4064)
		(layer "B.Cu")
		(net "GND")
	)
	(segment
		(start 41.599358 -132.876036)
		(end 41.599358 -131.080256)
		(width 0.4064)
		(layer "B.Cu")
		(net "GND")
	)
	(segment
		(start 416.9664 -24.511)
		(end 416.9664 -25.146)
		(width 0.254)
		(layer "B.Cu")
		(net "GND")
	)
	(segment
		(start 118.099332 -137.877296)
		(end 118.099332 -139.089892)
		(width 0.4064)
		(layer "B.Cu")
		(net "GND")
	)
	(segment
		(start 364.321852 -41.8338)
		(end 364.677452 -41.4782)
		(width 0.254)
		(layer "B.Cu")
		(net "GND")
	)
	(segment
		(start 205.749906 -1.021842)
		(end 205.749906 0.457454)
		(width 0.4064)
		(layer "B.Cu")
		(net "GND")
	)
	(segment
		(start 288.19983 -5.621782)
		(end 288.19983 -7.607046)
		(width 0.4064)
		(layer "B.Cu")
		(net "GND")
	)
	(segment
		(start 378.8664 -47.625)
		(end 377.6218 -47.625)
		(width 0.254)
		(layer "B.Cu")
		(net "GND")
	)
	(segment
		(start 282.07208 -3.762756)
		(end 282.004262 -3.830574)
		(width 0.254)
		(layer "B.Cu")
		(net "GND")
	)
	(segment
		(start 33.099502 -2.302256)
		(end 33.099502 -1.021842)
		(width 0.4064)
		(layer "B.Cu")
		(net "GND")
	)
	(segment
		(start 236.349794 -132.875782)
		(end 236.349794 -132.1054)
		(width 0.254)
		(layer "B.Cu")
		(net "GND")
	)
	(segment
		(start 96.27997 -135.577834)
		(end 96.078548 -135.376412)
		(width 0.4064)
		(layer "B.Cu")
		(net "GND")
	)
	(segment
		(start 212.549994 -132.58165)
		(end 212.54974 -132.581396)
		(width 0.4064)
		(layer "B.Cu")
		(net "GND")
	)
	(segment
		(start 292.392608 -9.143746)
		(end 292.450012 -9.20115)
		(width 0.4064)
		(layer "B.Cu")
		(net "GND")
	)
	(segment
		(start 34.799524 -10.623042)
		(end 34.799524 -11.835892)
		(width 0.4064)
		(layer "B.Cu")
		(net "GND")
	)
	(segment
		(start 132.549392 -142.477236)
		(end 132.549392 -140.617956)
		(width 0.4064)
		(layer "B.Cu")
		(net "GND")
	)
	(segment
		(start 213.399878 -147.478496)
		(end 213.399878 -148.771356)
		(width 0.4064)
		(layer "B.Cu")
		(net "GND")
	)
	(segment
		(start 468.376 -128.524)
		(end 468.122 -128.27)
		(width 0.254)
		(layer "B.Cu")
		(net "GND")
	)
	(segment
		(start 146.149568 -11.835892)
		(end 146.149568 -10.623042)
		(width 0.4064)
		(layer "B.Cu")
		(net "GND")
	)
	(segment
		(start 139.34948 -137.877296)
		(end 139.34948 -139.170156)
		(width 0.4064)
		(layer "B.Cu")
		(net "GND")
	)
	(segment
		(start 289.899852 -5.621782)
		(end 289.899852 -3.851656)
		(width 0.4064)
		(layer "B.Cu")
		(net "GND")
	)
	(segment
		(start 198.7042 -131.084574)
		(end 198.772018 -131.016756)
		(width 0.4064)
		(layer "B.Cu")
		(net "GND")
	)
	(segment
		(start 120.649492 -128.276096)
		(end 120.649492 -129.568956)
		(width 0.4064)
		(layer "B.Cu")
		(net "GND")
	)
	(segment
		(start 210.85048 -142.477236)
		(end 210.849972 -142.476982)
		(width 0.4064)
		(layer "B.Cu")
		(net "GND")
	)
	(segment
		(start 135.949436 -14.443964)
		(end 135.703818 -14.198346)
		(width 0.254)
		(layer "B.Cu")
		(net "GND")
	)
	(segment
		(start 209.14995 -2.234692)
		(end 209.14995 -1.021842)
		(width 0.4064)
		(layer "B.Cu")
		(net "GND")
	)
	(segment
		(start 58.599578 -25.638252)
		(end 59.449462 -26.488136)
		(width 0.4064)
		(layer "B.Cu")
		(net "GND")
	)
	(segment
		(start 41.599358 -152.078436)
		(end 41.599358 -150.282656)
		(width 0.4064)
		(layer "B.Cu")
		(net "GND")
	)
	(segment
		(start 372.379494 -88.89111)
		(end 372.609618 -88.89111)
		(width 0.254)
		(layer "B.Cu")
		(net "GND")
	)
	(segment
		(start 220.199966 -151.265382)
		(end 219.73794 -150.803356)
		(width 0.4064)
		(layer "B.Cu")
		(net "GND")
	)
	(segment
		(start 240.599722 -24.453596)
		(end 240.599722 -22.965156)
		(width 0.4064)
		(layer "B.Cu")
		(net "GND")
	)
	(segment
		(start 363.4486 -63.5889)
		(end 363.8042 -63.5889)
		(width 0.254)
		(layer "B.Cu")
		(net "GND")
	)
	(segment
		(start 131.699508 -21.517356)
		(end 131.699508 -20.224242)
		(width 0.4064)
		(layer "B.Cu")
		(net "GND")
	)
	(segment
		(start 231.249982 -24.824182)
		(end 231.249982 -24.45385)
		(width 0.4064)
		(layer "B.Cu")
		(net "GND")
	)
	(segment
		(start 323.29882 -119.80164)
		(end 324.904862 -119.80164)
		(width 0.254)
		(layer "B.Cu")
		(net "GND")
	)
	(segment
		(start 43.050968 -3.833368)
		(end 43.12158 -3.762756)
		(width 0.4064)
		(layer "B.Cu")
		(net "GND")
	)
	(segment
		(start 164.00018 3.6322)
		(end 163.74618 3.3782)
		(width 0.254)
		(layer "B.Cu")
		(net "GND")
	)
	(segment
		(start 291.599874 -142.476982)
		(end 291.599874 -141.697964)
		(width 0.254)
		(layer "B.Cu")
		(net "GND")
	)
	(segment
		(start 294.150288 -152.078436)
		(end 294.184578 -152.044146)
		(width 0.4064)
		(layer "B.Cu")
		(net "GND")
	)
	(segment
		(start 225.300286 -142.477236)
		(end 225.299778 -142.476982)
		(width 0.4064)
		(layer "B.Cu")
		(net "GND")
	)
	(segment
		(start 118.099332 -128.276096)
		(end 118.099332 -129.488692)
		(width 0.4064)
		(layer "B.Cu")
		(net "GND")
	)
	(segment
		(start 113.849404 -131.575556)
		(end 113.967768 -131.457192)
		(width 0.4064)
		(layer "B.Cu")
		(net "GND")
	)
	(segment
		(start 287.349946 -128.276096)
		(end 287.349946 -129.568956)
		(width 0.4064)
		(layer "B.Cu")
		(net "GND")
	)
	(segment
		(start 278.850344 -150.777448)
		(end 278.9682 -150.659592)
		(width 0.4064)
		(layer "B.Cu")
		(net "GND")
	)
	(segment
		(start 51.78679 -129.568956)
		(end 51.76139 -129.568956)
		(width 0.4064)
		(layer "B.Cu")
		(net "GND")
	)
	(segment
		(start 172.384212 -70.555104)
		(end 172.327316 -70.612)
		(width 0.254)
		(layer "B.Cu")
		(net "GND")
	)
	(segment
		(start 317.146432 -8.128)
		(end 317.146432 -7.132828)
		(width 0.4064)
		(layer "B.Cu")
		(net "GND")
	)
	(segment
		(start 199.742552 0.457454)
		(end 199.799956 0.40005)
		(width 0.4064)
		(layer "B.Cu")
		(net "GND")
	)
	(segment
		(start 117.249448 -15.222982)
		(end 117.249448 -14.443964)
		(width 0.254)
		(layer "B.Cu")
		(net "GND")
	)
	(segment
		(start 124.89942 -25.709372)
		(end 124.113036 -26.495756)
		(width 0.4064)
		(layer "B.Cu")
		(net "GND")
	)
	(segment
		(start 136.799574 -1.021842)
		(end 136.799574 -2.234692)
		(width 0.4064)
		(layer "B.Cu")
		(net "GND")
	)
	(segment
		(start 382.651 -0.889)
		(end 382.7526 -0.889)
		(width 0.254)
		(layer "B.Cu")
		(net "GND")
	)
	(segment
		(start 217.649806 -151.27986)
		(end 217.3986 -151.028654)
		(width 0.254)
		(layer "B.Cu")
		(net "GND")
	)
	(segment
		(start 238.900462 -132.876036)
		(end 238.899954 -132.875782)
		(width 0.4064)
		(layer "B.Cu")
		(net "GND")
	)
	(segment
		(start 268.859 3.8862)
		(end 269.748 4.7752)
		(width 0.381)
		(layer "B.Cu")
		(net "GND")
	)
	(segment
		(start 240.599976 -142.476982)
		(end 240.599976 -142.10665)
		(width 0.4064)
		(layer "B.Cu")
		(net "GND")
	)
	(segment
		(start 286.500316 -152.078436)
		(end 286.500316 -150.219664)
		(width 0.4064)
		(layer "B.Cu")
		(net "GND")
	)
	(segment
		(start 70.499478 -2.276856)
		(end 70.461378 -2.314956)
		(width 0.4064)
		(layer "B.Cu")
		(net "GND")
	)
	(segment
		(start 128.687576 -23.549356)
		(end 129.149348 -24.011128)
		(width 0.4064)
		(layer "B.Cu")
		(net "GND")
	)
	(segment
		(start 313.700414 -128.276096)
		(end 313.699906 -128.276096)
		(width 0.4064)
		(layer "B.Cu")
		(net "GND")
	)
	(segment
		(start 145.12163 -150.219156)
		(end 145.053812 -150.286974)
		(width 0.4064)
		(layer "B.Cu")
		(net "GND")
	)
	(segment
		(start 226.7458 -131.7498)
		(end 226.7458 -131.092956)
		(width 0.4064)
		(layer "B.Cu")
		(net "GND")
	)
	(segment
		(start 49.249584 -132.876036)
		(end 49.249584 -132.53085)
		(width 0.4064)
		(layer "B.Cu")
		(net "GND")
	)
	(segment
		(start 278.849836 -21.567648)
		(end 278.947372 -21.665184)
		(width 0.4064)
		(layer "B.Cu")
		(net "GND")
	)
	(segment
		(start 117.249448 -24.045164)
		(end 117.00383 -23.799546)
		(width 0.254)
		(layer "B.Cu")
		(net "GND")
	)
	(segment
		(start 72.142096 -139.147296)
		(end 72.142096 -139.166092)
		(width 0.4064)
		(layer "B.Cu")
		(net "GND")
	)
	(segment
		(start 96.416368 1.47574)
		(end 96.5708 1.321308)
		(width 0.508)
		(layer "B.Cu")
		(net "GND")
	)
	(segment
		(start 36.03752 -13.948156)
		(end 36.499546 -14.410182)
		(width 0.4064)
		(layer "B.Cu")
		(net "GND")
	)
	(segment
		(start 40.749474 -10.623042)
		(end 40.749474 -11.916156)
		(width 0.4064)
		(layer "B.Cu")
		(net "GND")
	)
	(segment
		(start 393.296902 -113.903252)
		(end 393.006326 -113.903252)
		(width 0.4064)
		(layer "B.Cu")
		(net "GND")
	)
	(segment
		(start 40.749474 -9.143746)
		(end 40.749474 -10.623042)
		(width 0.4064)
		(layer "B.Cu")
		(net "GND")
	)
	(segment
		(start -0.452882 -136.673082)
		(end -0.6604 -136.8806)
		(width 0.254)
		(layer "B.Cu")
		(net "GND")
	)
	(segment
		(start 307.750464 -10.623042)
		(end 307.749956 -10.623042)
		(width 0.4064)
		(layer "B.Cu")
		(net "GND")
	)
	(segment
		(start 301.800006 -139.089892)
		(end 301.742602 -139.147296)
		(width 0.4064)
		(layer "B.Cu")
		(net "GND")
	)
	(segment
		(start 273.1516 4.8006)
		(end 272.415 4.064)
		(width 0.381)
		(layer "B.Cu")
		(net "GND")
	)
	(segment
		(start 407.5176 -29.4132)
		(end 407.7208 -29.4132)
		(width 0.254)
		(layer "B.Cu")
		(net "GND")
	)
	(segment
		(start 237.199932 -147.478496)
		(end 237.199932 -148.691092)
		(width 0.4064)
		(layer "B.Cu")
		(net "GND")
	)
	(segment
		(start 134.15137 -7.607046)
		(end 134.249414 -7.509002)
		(width 0.4064)
		(layer "B.Cu")
		(net "GND")
	)
	(segment
		(start 167.0812 -86.868)
		(end 166.751 -87.1982)
		(width 0.4064)
		(layer "B.Cu")
		(net "GND")
	)
	(segment
		(start 496.34648 -129.44348)
		(end 495.935 -129.032)
		(width 0.254)
		(layer "B.Cu")
		(net "GND")
	)
	(segment
		(start 33.086802 -2.314956)
		(end 33.099502 -2.302256)
		(width 0.4064)
		(layer "B.Cu")
		(net "GND")
	)
	(segment
		(start 66.24955 -17.207992)
		(end 66.24955 -15.222982)
		(width 0.4064)
		(layer "B.Cu")
		(net "GND")
	)
	(segment
		(start 273.758152 -157.9118)
		(end 272.231104 -157.9118)
		(width 0.381)
		(layer "B.Cu")
		(net "GND")
	)
	(segment
		(start 450.317362 -28.552648)
		(end 450.317362 -28.334462)
		(width 0.4064)
		(layer "B.Cu")
		(net "GND")
	)
	(segment
		(start 242.299998 -3.76301)
		(end 242.299744 -3.762756)
		(width 0.4064)
		(layer "B.Cu")
		(net "GND")
	)
	(segment
		(start 390.5758 -155.800044)
		(end 390.578594 -155.802838)
		(width 0.381)
		(layer "B.Cu")
		(net "GND")
	)
	(segment
		(start 390.76122 -153.46172)
		(end 390.76122 -152.70226)
		(width 0.254)
		(layer "B.Cu")
		(net "GND")
	)
	(segment
		(start 61.149484 -128.276096)
		(end 61.149484 -129.556256)
		(width 0.4064)
		(layer "B.Cu")
		(net "GND")
	)
	(segment
		(start 212.549994 -5.32765)
		(end 212.549994 -5.621782)
		(width 0.4064)
		(layer "B.Cu")
		(net "GND")
	)
	(segment
		(start 493.451388 -126.5174)
		(end 493.451388 -125.720348)
		(width 0.254)
		(layer "B.Cu")
		(net "GND")
	)
	(segment
		(start 284.799786 -142.476982)
		(end 284.799786 -141.664182)
		(width 0.4064)
		(layer "B.Cu")
		(net "GND")
	)
	(segment
		(start 417.232846 -45.873162)
		(end 417.547298 -46.187614)
		(width 0.508)
		(layer "B.Cu")
		(net "GND")
	)
	(segment
		(start 197.249796 -15.222982)
		(end 197.249796 -14.115542)
		(width 0.4064)
		(layer "B.Cu")
		(net "GND")
	)
	(segment
		(start 214.249762 -24.478996)
		(end 214.249762 -22.965156)
		(width 0.4064)
		(layer "B.Cu")
		(net "GND")
	)
	(segment
		(start 76.449428 -128.276096)
		(end 76.449428 -129.568956)
		(width 0.4064)
		(layer "B.Cu")
		(net "GND")
	)
	(segment
		(start 235.46181 -2.314956)
		(end 235.49991 -2.276856)
		(width 0.4064)
		(layer "B.Cu")
		(net "GND")
	)
	(segment
		(start 42.436796 -129.568956)
		(end 42.411396 -129.568956)
		(width 0.4064)
		(layer "B.Cu")
		(net "GND")
	)
	(segment
		(start 88.748108 -126.275592)
		(end 88.748108 -125.99162)
		(width 0.254)
		(layer "B.Cu")
		(net "GND")
	)
	(segment
		(start 247.4214 -26.289)
		(end 247.4214 -26.3398)
		(width 0.4064)
		(layer "B.Cu")
		(net "GND")
	)
	(segment
		(start 415.318448 -49.575974)
		(end 415.47288 -49.421542)
		(width 0.254)
		(layer "B.Cu")
		(net "GND")
	)
	(segment
		(start 380.746 -45.6057)
		(end 380.746 -46.0883)
		(width 0.254)
		(layer "B.Cu")
		(net "GND")
	)
	(segment
		(start 197.249796 -7.509002)
		(end 197.249796 -5.621782)
		(width 0.4064)
		(layer "B.Cu")
		(net "GND")
	)
	(segment
		(start 300.70425 -23.799546)
		(end 300.949868 -24.045164)
		(width 0.254)
		(layer "B.Cu")
		(net "GND")
	)
	(segment
		(start 33.949386 -132.096764)
		(end 33.703768 -131.851146)
		(width 0.254)
		(layer "B.Cu")
		(net "GND")
	)
	(segment
		(start 409.208986 -12.13993)
		(end 409.672028 -12.602972)
		(width 0.254)
		(layer "B.Cu")
		(net "GND")
	)
	(segment
		(start 217.649806 -24.824182)
		(end 217.649806 -24.02586)
		(width 0.254)
		(layer "B.Cu")
		(net "GND")
	)
	(segment
		(start 117.00383 -131.059174)
		(end 117.071648 -130.991356)
		(width 0.3556)
		(layer "B.Cu")
		(net "GND")
	)
	(segment
		(start 50.860452 -3.762756)
		(end 50.860452 -3.737356)
		(width 0.4064)
		(layer "B.Cu")
		(net "GND")
	)
	(segment
		(start 283.04236 -129.564892)
		(end 283.04236 -129.546096)
		(width 0.4064)
		(layer "B.Cu")
		(net "GND")
	)
	(segment
		(start 284.800294 -142.477236)
		(end 284.799786 -142.476982)
		(width 0.4064)
		(layer "B.Cu")
		(net "GND")
	)
	(segment
		(start 126.353824 -14.1224)
		(end 126.353824 -14.198346)
		(width 0.254)
		(layer "B.Cu")
		(net "GND")
	)
	(segment
		(start 283.099764 -2.234692)
		(end 283.099764 -1.021842)
		(width 0.4064)
		(layer "B.Cu")
		(net "GND")
	)
	(segment
		(start 71.095362 -131.092956)
		(end 71.171562 -131.016756)
		(width 0.4064)
		(layer "B.Cu")
		(net "GND")
	)
	(segment
		(start 373.207788 -74.7014)
		(end 373.544846 -75.038458)
		(width 0.254)
		(layer "B.Cu")
		(net "GND")
	)
	(segment
		(start 61.745368 -3.838956)
		(end 61.745368 -4.4958)
		(width 0.4064)
		(layer "B.Cu")
		(net "GND")
	)
	(segment
		(start 375.93016 -97.07118)
		(end 375.93016 -97.58934)
		(width 0.254)
		(layer "B.Cu")
		(net "GND")
	)
	(segment
		(start 127.392176 -9.143746)
		(end 127.44958 -9.20115)
		(width 0.4064)
		(layer "B.Cu")
		(net "GND")
	)
	(segment
		(start 410.483812 -13.100812)
		(end 410.483812 -13.773912)
		(width 0.254)
		(layer "B.Cu")
		(net "GND")
	)
	(segment
		(start 121.499376 -22.965156)
		(end 121.499376 -24.824182)
		(width 0.4064)
		(layer "B.Cu")
		(net "GND")
	)
	(segment
		(start 50.860452 -13.363956)
		(end 50.949352 -13.452856)
		(width 0.4064)
		(layer "B.Cu")
		(net "GND")
	)
	(segment
		(start 236.349794 -152.078182)
		(end 236.349794 -151.3078)
		(width 0.254)
		(layer "B.Cu")
		(net "GND")
	)
	(segment
		(start 339.725 -11.938)
		(end 340.487 -11.938)
		(width 0.254)
		(layer "B.Cu")
		(net "GND")
	)
	(segment
		(start 207.411828 -11.916156)
		(end 207.437228 -11.916156)
		(width 0.4064)
		(layer "B.Cu")
		(net "GND")
	)
	(segment
		(start 42.411396 -11.916156)
		(end 42.436796 -11.916156)
		(width 0.4064)
		(layer "B.Cu")
		(net "GND")
	)
	(segment
		(start 204.050392 -128.276096)
		(end 204.049884 -128.276096)
		(width 0.4064)
		(layer "B.Cu")
		(net "GND")
	)
	(segment
		(start 278.849836 -9.131046)
		(end 278.849836 -10.623042)
		(width 0.4064)
		(layer "B.Cu")
		(net "GND")
	)
	(segment
		(start 295.85031 -15.222982)
		(end 295.849802 -15.222982)
		(width 0.4064)
		(layer "B.Cu")
		(net "GND")
	)
	(segment
		(start 232.950004 -15.222982)
		(end 232.950004 -14.92885)
		(width 0.4064)
		(layer "B.Cu")
		(net "GND")
	)
	(segment
		(start 203.2 -24.824182)
		(end 203.2 -22.96541)
		(width 0.4064)
		(layer "B.Cu")
		(net "GND")
	)
	(segment
		(start 215.949784 -23.054056)
		(end 215.860884 -22.965156)
		(width 0.4064)
		(layer "B.Cu")
		(net "GND")
	)
	(segment
		(start 314.54979 -24.824182)
		(end 314.54979 -22.965156)
		(width 0.4064)
		(layer "B.Cu")
		(net "GND")
	)
	(segment
		(start 115.460526 -3.737356)
		(end 115.460526 -3.762756)
		(width 0.4064)
		(layer "B.Cu")
		(net "GND")
	)
	(segment
		(start 389.255 -16.383)
		(end 389.255 -17.272)
		(width 0.254)
		(layer "B.Cu")
		(net "GND")
	)
	(segment
		(start 280.460958 -130.991356)
		(end 280.460958 -131.016756)
		(width 0.4064)
		(layer "B.Cu")
		(net "GND")
	)
	(segment
		(start 300.70425 -4.5212)
		(end 300.70425 -4.597146)
		(width 0.254)
		(layer "B.Cu")
		(net "GND")
	)
	(segment
		(start 217.649806 -14.42466)
		(end 217.3986 -14.173454)
		(width 0.254)
		(layer "B.Cu")
		(net "GND")
	)
	(segment
		(start 289.899852 -15.222982)
		(end 289.899852 -13.452856)
		(width 0.4064)
		(layer "B.Cu")
		(net "GND")
	)
	(segment
		(start 231.249982 -17.207992)
		(end 231.249982 -15.222982)
		(width 0.4064)
		(layer "B.Cu")
		(net "GND")
	)
	(segment
		(start 314.54979 -7.607046)
		(end 314.54979 -5.621782)
		(width 0.4064)
		(layer "B.Cu")
		(net "GND")
	)
	(segment
		(start 310.30037 -5.621782)
		(end 310.299862 -5.621782)
		(width 0.254)
		(layer "B.Cu")
		(net "GND")
	)
	(segment
		(start 78.9178 -149.8092)
		(end 78.613 -150.114)
		(width 0.508)
		(layer "B.Cu")
		(net "GND")
	)
	(segment
		(start 309.449978 -128.276096)
		(end 309.450486 -128.276096)
		(width 0.4064)
		(layer "B.Cu")
		(net "GND")
	)
	(segment
		(start 421.005 -32.512)
		(end 421.005 -31.81985)
		(width 0.508)
		(layer "B.Cu")
		(net "GND")
	)
	(segment
		(start 375.052082 -98.372168)
		(end 374.21312 -98.372168)
		(width 0.254)
		(layer "B.Cu")
		(net "GND")
	)
	(segment
		(start 314.54979 -152.078182)
		(end 314.54979 -150.219156)
		(width 0.4064)
		(layer "B.Cu")
		(net "GND")
	)
	(segment
		(start 55.199534 -151.265382)
		(end 54.737508 -150.803356)
		(width 0.4064)
		(layer "B.Cu")
		(net "GND")
	)
	(segment
		(start 42.449496 -129.556256)
		(end 42.436796 -129.568956)
		(width 0.4064)
		(layer "B.Cu")
		(net "GND")
	)
	(segment
		(start 123.199398 -132.876036)
		(end 123.199398 -131.016756)
		(width 0.4064)
		(layer "B.Cu")
		(net "GND")
	)
	(segment
		(start 96.00692 -139.053316)
		(end 95.714566 -138.760962)
		(width 0.508)
		(layer "B.Cu")
		(net "GND")
	)
	(segment
		(start 281.399996 -139.157456)
		(end 281.399996 -137.877296)
		(width 0.4064)
		(layer "B.Cu")
		(net "GND")
	)
	(segment
		(start 406.4762 -14.7193)
		(end 406.347168 -14.7193)
		(width 0.254)
		(layer "B.Cu")
		(net "GND")
	)
	(segment
		(start 70.499478 -8.317484)
		(end 70.499478 -9.156446)
		(width 0.4064)
		(layer "B.Cu")
		(net "GND")
	)
	(segment
		(start 408.691588 -20.828)
		(end 408.8765 -20.828)
		(width 0.254)
		(layer "B.Cu")
		(net "GND")
	)
	(segment
		(start 237.20044 -128.276096)
		(end 237.199932 -128.276096)
		(width 0.4064)
		(layer "B.Cu")
		(net "GND")
	)
	(segment
		(start 403.733 -0.3048)
		(end 403.733 0.1524)
		(width 0.254)
		(layer "B.Cu")
		(net "GND")
	)
	(segment
		(start 131.699508 -1.021842)
		(end 131.699508 -2.314956)
		(width 0.4064)
		(layer "B.Cu")
		(net "GND")
	)
	(segment
		(start 233.799888 -26.488136)
		(end 232.950004 -25.638252)
		(width 0.4064)
		(layer "B.Cu")
		(net "GND")
	)
	(segment
		(start 443.46368 -58.717688)
		(end 443.129162 -59.052206)
		(width 0.381)
		(layer "B.Cu")
		(net "GND")
	)
	(segment
		(start 132.549392 -7.607046)
		(end 132.549392 -5.621782)
		(width 0.4064)
		(layer "B.Cu")
		(net "GND")
	)
	(segment
		(start 479.288602 -53.450998)
		(end 479.2472 -53.4924)
		(width 0.254)
		(layer "B.Cu")
		(net "GND")
	)
	(segment
		(start 295.849802 -142.476982)
		(end 295.849802 -140.617956)
		(width 0.4064)
		(layer "B.Cu")
		(net "GND")
	)
	(segment
		(start 65.399412 -10.623042)
		(end 65.399412 -11.916156)
		(width 0.4064)
		(layer "B.Cu")
		(net "GND")
	)
	(segment
		(start 64.549528 -142.477236)
		(end 64.549528 -141.664182)
		(width 0.4064)
		(layer "B.Cu")
		(net "GND")
	)
	(segment
		(start 439.6613 -148.844)
		(end 439.166254 -148.844)
		(width 0.254)
		(layer "B.Cu")
		(net "GND")
	)
	(segment
		(start 231.249982 -142.10665)
		(end 231.249728 -142.106396)
		(width 0.4064)
		(layer "B.Cu")
		(net "GND")
	)
	(segment
		(start 71.349362 -14.4526)
		(end 71.349362 -15.222982)
		(width 0.254)
		(layer "B.Cu")
		(net "GND")
	)
	(segment
		(start 44.149518 -10.623042)
		(end 44.149518 -9.20115)
		(width 0.4064)
		(layer "B.Cu")
		(net "GND")
	)
	(segment
		(start 116.399564 -139.157456)
		(end 116.386864 -139.170156)
		(width 0.4064)
		(layer "B.Cu")
		(net "GND")
	)
	(segment
		(start 134.249414 -152.078436)
		(end 134.249414 -150.308056)
		(width 0.4064)
		(layer "B.Cu")
		(net "GND")
	)
	(segment
		(start 290.74999 -2.302256)
		(end 290.73729 -2.314956)
		(width 0.4064)
		(layer "B.Cu")
		(net "GND")
	)
	(segment
		(start 286.500316 -15.222982)
		(end 286.499808 -15.222982)
		(width 0.4064)
		(layer "B.Cu")
		(net "GND")
	)
	(segment
		(start 52.398168 -141.3764)
		(end 52.398168 -140.691362)
		(width 0.4064)
		(layer "B.Cu")
		(net "GND")
	)
	(segment
		(start 464.486498 -141.6812)
		(end 464.41868 -141.6812)
		(width 0.254)
		(layer "B.Cu")
		(net "GND")
	)
	(segment
		(start 26.896568 -155.856432)
		(end 26.896568 -155.448)
		(width 0.4064)
		(layer "B.Cu")
		(net "GND")
	)
	(segment
		(start 67.099434 -137.877296)
		(end 67.099434 -139.170156)
		(width 0.4064)
		(layer "B.Cu")
		(net "GND")
	)
	(segment
		(start 203.2 -142.476982)
		(end 203.2 -140.61821)
		(width 0.4064)
		(layer "B.Cu")
		(net "GND")
	)
	(segment
		(start 227.792534 -21.494496)
		(end 227.792534 -21.513292)
		(width 0.4064)
		(layer "B.Cu")
		(net "GND")
	)
	(segment
		(start 232.099866 -147.478496)
		(end 232.099866 -148.771356)
		(width 0.4064)
		(layer "B.Cu")
		(net "GND")
	)
	(segment
		(start 88.24976 -126.77394)
		(end 88.748108 -126.275592)
		(width 0.254)
		(layer "B.Cu")
		(net "GND")
	)
	(segment
		(start 227.849938 -139.089892)
		(end 227.792534 -139.147296)
		(width 0.4064)
		(layer "B.Cu")
		(net "GND")
	)
	(segment
		(start 256.089658 -7.813802)
		(end 256.089658 -8.468868)
		(width 0.4064)
		(layer "B.Cu")
		(net "GND")
	)
	(segment
		(start 281.399996 -11.903456)
		(end 281.387296 -11.916156)
		(width 0.4064)
		(layer "B.Cu")
		(net "GND")
	)
	(segment
		(start 198.087234 -11.916156)
		(end 198.099934 -11.903456)
		(width 0.4064)
		(layer "B.Cu")
		(net "GND")
	)
	(segment
		(start 231.249728 -14.852396)
		(end 231.249728 -13.363956)
		(width 0.4064)
		(layer "B.Cu")
		(net "GND")
	)
	(segment
		(start 163.6776 -78.867)
		(end 163.4236 -78.613)
		(width 0.381)
		(layer "B.Cu")
		(net "GND")
	)
	(segment
		(start 282.250388 -24.824182)
		(end 282.24988 -24.824182)
		(width 0.254)
		(layer "B.Cu")
		(net "GND")
	)
	(segment
		(start 172.1358 -88.392)
		(end 172.466 -88.392)
		(width 0.4064)
		(layer "B.Cu")
		(net "GND")
	)
	(segment
		(start -3.09626 -119.66956)
		(end -3.73126 -119.66956)
		(width 0.254)
		(layer "B.Cu")
		(net "GND")
	)
	(segment
		(start 283.04236 -129.546096)
		(end 283.099764 -129.488692)
		(width 0.4064)
		(layer "B.Cu")
		(net "GND")
	)
	(segment
		(start 279.699974 -147.478496)
		(end 279.699974 -148.771356)
		(width 0.4064)
		(layer "B.Cu")
		(net "GND")
	)
	(segment
		(start 232.950512 -5.621782)
		(end 232.950004 -5.621782)
		(width 0.4064)
		(layer "B.Cu")
		(net "GND")
	)
	(segment
		(start 331.80528 -7.3406)
		(end 331.80528 -6.015482)
		(width 0.254)
		(layer "B.Cu")
		(net "GND")
	)
	(segment
		(start 289.810952 -140.617956)
		(end 289.810952 -140.592556)
		(width 0.4064)
		(layer "B.Cu")
		(net "GND")
	)
	(segment
		(start 278.0792 -3.3528)
		(end 278.2062 -3.4798)
		(width 0.381)
		(layer "B.Cu")
		(net "GND")
	)
	(segment
		(start 315.345826 -30.813502)
		(end 314.760102 -30.227778)
		(width 0.381)
		(layer "B.Cu")
		(net "GND")
	)
	(segment
		(start 460.121 -153.289)
		(end 460.248 -153.416)
		(width 0.4064)
		(layer "B.Cu")
		(net "GND")
	)
	(segment
		(start 221.899988 -14.87805)
		(end 221.899734 -14.877796)
		(width 0.4064)
		(layer "B.Cu")
		(net "GND")
	)
	(segment
		(start 43.050968 -140.675868)
		(end 43.12158 -140.605256)
		(width 0.254)
		(layer "B.Cu")
		(net "GND")
	)
	(segment
		(start 57.74944 -21.517356)
		(end 57.74944 -20.224242)
		(width 0.4064)
		(layer "B.Cu")
		(net "GND")
	)
	(segment
		(start 300.70425 -23.7236)
		(end 300.70425 -23.799546)
		(width 0.254)
		(layer "B.Cu")
		(net "GND")
	)
	(segment
		(start 483.97414 -121.77014)
		(end 484.418894 -122.214894)
		(width 0.254)
		(layer "B.Cu")
		(net "GND")
	)
	(segment
		(start 229.54996 -152.078182)
		(end 229.54996 -151.265382)
		(width 0.4064)
		(layer "B.Cu")
		(net "GND")
	)
	(segment
		(start 280.451814 -7.607046)
		(end 280.549858 -7.509002)
		(width 0.4064)
		(layer "B.Cu")
		(net "GND")
	)
	(segment
		(start 136.799574 -10.623042)
		(end 136.799574 -9.20115)
		(width 0.4064)
		(layer "B.Cu")
		(net "GND")
	)
	(segment
		(start 171.069 -74.041)
		(end 172.65396 -74.041)
		(width 0.254)
		(layer "B.Cu")
		(net "GND")
	)
	(segment
		(start 61.821568 -3.762756)
		(end 61.745368 -3.838956)
		(width 0.4064)
		(layer "B.Cu")
		(net "GND")
	)
	(segment
		(start 291.600382 -132.876036)
		(end 291.599874 -132.875782)
		(width 0.254)
		(layer "B.Cu")
		(net "GND")
	)
	(segment
		(start 119.799354 -151.265382)
		(end 119.337328 -150.803356)
		(width 0.4064)
		(layer "B.Cu")
		(net "GND")
	)
	(segment
		(start 50.949352 -132.876036)
		(end 50.949352 -131.105656)
		(width 0.4064)
		(layer "B.Cu")
		(net "GND")
	)
	(segment
		(start 242.2652 -26.67)
		(end 242.5446 -26.67)
		(width 0.4064)
		(layer "B.Cu")
		(net "GND")
	)
	(segment
		(start 465.97316 -130.5052)
		(end 465.97316 -131.9784)
		(width 0.381)
		(layer "B.Cu")
		(net "GND")
	)
	(segment
		(start 82.459068 -17.7546)
		(end 81.618836 -17.7546)
		(width 0.4064)
		(layer "B.Cu")
		(net "GND")
	)
	(segment
		(start 445.296544 -21.74748)
		(end 445.694562 -21.349462)
		(width 0.254)
		(layer "B.Cu")
		(net "GND")
	)
	(segment
		(start 53.442108 -148.748496)
		(end 53.442108 -148.767292)
		(width 0.4064)
		(layer "B.Cu")
		(net "GND")
	)
	(segment
		(start 13.589 -78.0542)
		(end 14.061186 -78.0542)
		(width 0.508)
		(layer "B.Cu")
		(net "GND")
	)
	(segment
		(start 62.849506 -9.20115)
		(end 62.849506 -10.623042)
		(width 0.4064)
		(layer "B.Cu")
		(net "GND")
	)
	(segment
		(start 256.39776 -145.29054)
		(end 255.862328 -145.29054)
		(width 0.4064)
		(layer "B.Cu")
		(net "GND")
	)
	(segment
		(start 237.20044 -147.478496)
		(end 237.199932 -147.478496)
		(width 0.4064)
		(layer "B.Cu")
		(net "GND")
	)
	(segment
		(start 299.250354 -5.621782)
		(end 299.249846 -5.621782)
		(width 0.4064)
		(layer "B.Cu")
		(net "GND")
	)
	(segment
		(start 232.950004 -132.58165)
		(end 232.94975 -132.581396)
		(width 0.4064)
		(layer "B.Cu")
		(net "GND")
	)
	(segment
		(start 115.549426 -134.239254)
		(end 115.549426 -132.876036)
		(width 0.508)
		(layer "B.Cu")
		(net "GND")
	)
	(segment
		(start 91.684348 -134.909052)
		(end 91.684348 -135.3312)
		(width 0.381)
		(layer "B.Cu")
		(net "GND")
	)
	(segment
		(start 126.421642 -3.762756)
		(end 126.353824 -3.830574)
		(width 0.4064)
		(layer "B.Cu")
		(net "GND")
	)
	(segment
		(start 278.849836 -127.339852)
		(end 278.849836 -128.276096)
		(width 0.4064)
		(layer "B.Cu")
		(net "GND")
	)
	(segment
		(start 309.449978 0.444754)
		(end 309.449978 -1.021842)
		(width 0.4064)
		(layer "B.Cu")
		(net "GND")
	)
	(segment
		(start 52.398168 -13.437362)
		(end 52.398168 -14.1224)
		(width 0.4064)
		(layer "B.Cu")
		(net "GND")
	)
	(segment
		(start 124.89942 -152.078436)
		(end 124.89942 -150.308056)
		(width 0.4064)
		(layer "B.Cu")
		(net "GND")
	)
	(segment
		(start 208.122012 -17.2466)
		(end 208.299812 -17.0688)
		(width 0.4064)
		(layer "B.Cu")
		(net "GND")
	)
	(segment
		(start 277.397464 -145.0086)
		(end 278.418036 -145.0086)
		(width 0.4572)
		(layer "B.Cu")
		(net "GND")
	)
	(segment
		(start 198.949818 -132.096764)
		(end 198.7042 -131.851146)
		(width 0.254)
		(layer "B.Cu")
		(net "GND")
	)
	(segment
		(start 204.899768 -24.824182)
		(end 204.899768 -22.965156)
		(width 0.4064)
		(layer "B.Cu")
		(net "GND")
	)
	(segment
		(start 135.703818 -131.7752)
		(end 135.703818 -131.084574)
		(width 0.4064)
		(layer "B.Cu")
		(net "GND")
	)
	(segment
		(start 68.894706 -68.46824)
		(end 67.04584 -68.46824)
		(width 0.254)
		(layer "B.Cu")
		(net "GND")
	)
	(segment
		(start 135.086852 -11.916156)
		(end 135.099552 -11.903456)
		(width 0.4064)
		(layer "B.Cu")
		(net "GND")
	)
	(segment
		(start 48.399446 -10.623042)
		(end 48.399446 -11.916156)
		(width 0.4064)
		(layer "B.Cu")
		(net "GND")
	)
	(segment
		(start 382.0668 -82.423)
		(end 382.54686 -82.423)
		(width 0.254)
		(layer "B.Cu")
		(net "GND")
	)
	(segment
		(start 139.34948 -21.517356)
		(end 139.34948 -20.224242)
		(width 0.4064)
		(layer "B.Cu")
		(net "GND")
	)
	(segment
		(start 61.136784 -21.517356)
		(end 61.111384 -21.517356)
		(width 0.4064)
		(layer "B.Cu")
		(net "GND")
	)
	(segment
		(start 230.400352 -1.021842)
		(end 230.399844 -1.021842)
		(width 0.4064)
		(layer "B.Cu")
		(net "GND")
	)
	(segment
		(start 33.949386 -15.222982)
		(end 33.949386 -14.443964)
		(width 0.254)
		(layer "B.Cu")
		(net "GND")
	)
	(segment
		(start 211.700364 -128.276096)
		(end 211.699856 -128.276096)
		(width 0.4064)
		(layer "B.Cu")
		(net "GND")
	)
	(segment
		(start 472.250516 -145.477484)
		(end 472.830652 -145.477484)
		(width 0.254)
		(layer "B.Cu")
		(net "GND")
	)
	(segment
		(start 449.1863 -19.6088)
		(end 449.1863 -19.653504)
		(width 0.254)
		(layer "B.Cu")
		(net "GND")
	)
	(segment
		(start 312.849768 -152.078182)
		(end 312.849768 -151.265128)
		(width 0.4064)
		(layer "B.Cu")
		(net "GND")
	)
	(segment
		(start 75.599544 -17.207992)
		(end 75.59929 -17.208246)
		(width 0.4064)
		(layer "B.Cu")
		(net "GND")
	)
	(segment
		(start 57.74944 -20.224242)
		(end 57.74944 -18.757646)
		(width 0.4064)
		(layer "B.Cu")
		(net "GND")
	)
	(segment
		(start 165.6334 -73.2282)
		(end 166.0652 -73.66)
		(width 0.254)
		(layer "B.Cu")
		(net "GND")
	)
	(segment
		(start 132.549392 -5.621782)
		(end 132.549392 -3.762756)
		(width 0.4064)
		(layer "B.Cu")
		(net "GND")
	)
	(segment
		(start 218.499944 -128.276096)
		(end 218.499944 -129.488692)
		(width 0.4064)
		(layer "B.Cu")
		(net "GND")
	)
	(segment
		(start 418.1094 -13.492734)
		(end 418.8206 -13.492734)
		(width 0.254)
		(layer "B.Cu")
		(net "GND")
	)
	(segment
		(start 69.64934 -17.110202)
		(end 69.551296 -17.208246)
		(width 0.4064)
		(layer "B.Cu")
		(net "GND")
	)
	(segment
		(start 196.399912 -2.314956)
		(end 196.399912 -1.021842)
		(width 0.4064)
		(layer "B.Cu")
		(net "GND")
	)
	(segment
		(start 135.703818 -4.597146)
		(end 135.703818 -4.5212)
		(width 0.254)
		(layer "B.Cu")
		(net "GND")
	)
	(segment
		(start 146.149568 -139.089892)
		(end 146.092164 -139.147296)
		(width 0.4064)
		(layer "B.Cu")
		(net "GND")
	)
	(segment
		(start 138.499342 -26.224484)
		(end 138.253724 -26.470356)
		(width 0.4064)
		(layer "B.Cu")
		(net "GND")
	)
	(segment
		(start 61.999368 -14.4526)
		(end 61.745368 -14.1986)
		(width 0.254)
		(layer "B.Cu")
		(net "GND")
	)
	(segment
		(start 299.160946 -131.016756)
		(end 299.160946 -130.991356)
		(width 0.4064)
		(layer "B.Cu")
		(net "GND")
	)
	(segment
		(start 241.450368 -1.021842)
		(end 241.44986 -1.021842)
		(width 0.4064)
		(layer "B.Cu")
		(net "GND")
	)
	(segment
		(start 282.24988 -132.148326)
		(end 282.004262 -131.902708)
		(width 0.3556)
		(layer "B.Cu")
		(net "GND")
	)
	(segment
		(start 72.142096 -21.494496)
		(end 72.142096 -21.513292)
		(width 0.4064)
		(layer "B.Cu")
		(net "GND")
	)
	(segment
		(start 218.44254 -21.494496)
		(end 218.44254 -21.513292)
		(width 0.4064)
		(layer "B.Cu")
		(net "GND")
	)
	(segment
		(start 201.499978 -14.410182)
		(end 201.037952 -13.948156)
		(width 0.4064)
		(layer "B.Cu")
		(net "GND")
	)
	(segment
		(start 197.249796 -132.875782)
		(end 197.250304 -132.876036)
		(width 0.4064)
		(layer "B.Cu")
		(net "GND")
	)
	(segment
		(start 220.199966 -24.011382)
		(end 219.73794 -23.549356)
		(width 0.4064)
		(layer "B.Cu")
		(net "GND")
	)
	(segment
		(start 126.599442 -24.824182)
		(end 126.599442 -25.645872)
		(width 0.4064)
		(layer "B.Cu")
		(net "GND")
	)
	(segment
		(start 77.299312 -3.762756)
		(end 77.299566 -3.76301)
		(width 0.4064)
		(layer "B.Cu")
		(net "GND")
	)
	(segment
		(start 202.349862 -21.517356)
		(end 202.349862 -20.224242)
		(width 0.4064)
		(layer "B.Cu")
		(net "GND")
	)
	(segment
		(start 306.050442 -137.877296)
		(end 306.049934 -137.877296)
		(width 0.4064)
		(layer "B.Cu")
		(net "GND")
	)
	(segment
		(start 211.700364 -147.478496)
		(end 211.699856 -147.478496)
		(width 0.4064)
		(layer "B.Cu")
		(net "GND")
	)
	(segment
		(start 17.378172 -82.677)
		(end 17.378172 -82.139028)
		(width 0.254)
		(layer "B.Cu")
		(net "GND")
	)
	(segment
		(start 421.132 -21.463)
		(end 421.386 -21.717)
		(width 0.254)
		(layer "B.Cu")
		(net "GND")
	)
	(segment
		(start 434.722524 -42.91838)
		(end 434.722524 -42.546778)
		(width 0.254)
		(layer "B.Cu")
		(net "GND")
	)
	(segment
		(start 52.649374 -152.078436)
		(end 52.649374 -151.27986)
		(width 0.254)
		(layer "B.Cu")
		(net "GND")
	)
	(segment
		(start 58.599324 -132.632196)
		(end 58.599324 -131.016756)
		(width 0.4064)
		(layer "B.Cu")
		(net "GND")
	)
	(segment
		(start 292.392608 -148.748496)
		(end 292.450012 -148.691092)
		(width 0.4064)
		(layer "B.Cu")
		(net "GND")
	)
	(segment
		(start 449.3387 -147.8153)
		(end 449.326 -147.8026)
		(width 0.254)
		(layer "B.Cu")
		(net "GND")
	)
	(segment
		(start 197.160896 -14.026642)
		(end 197.160896 -13.338556)
		(width 0.4064)
		(layer "B.Cu")
		(net "GND")
	)
	(segment
		(start 225.299778 -25.676098)
		(end 225.299778 -24.824182)
		(width 0.4064)
		(layer "B.Cu")
		(net "GND")
	)
	(segment
		(start 308.59984 -150.42896)
		(end 308.59984 -152.078182)
		(width 0.4064)
		(layer "B.Cu")
		(net "GND")
	)
	(segment
		(start 226.150424 -1.021842)
		(end 226.149916 -1.021842)
		(width 0.4064)
		(layer "B.Cu")
		(net "GND")
	)
	(segment
		(start 209.092546 -21.494496)
		(end 209.14995 -21.437092)
		(width 0.4064)
		(layer "B.Cu")
		(net "GND")
	)
	(segment
		(start 494.387124 -43.644312)
		(end 494.706148 -43.644312)
		(width 0.254)
		(layer "B.Cu")
		(net "GND")
	)
	(segment
		(start 230.400352 -147.478496)
		(end 230.399844 -147.478496)
		(width 0.4064)
		(layer "B.Cu")
		(net "GND")
	)
	(segment
		(start 33.949386 -151.299164)
		(end 33.703768 -151.053546)
		(width 0.254)
		(layer "B.Cu")
		(net "GND")
	)
	(segment
		(start 215.860884 -3.762756)
		(end 215.860884 -3.737356)
		(width 0.4064)
		(layer "B.Cu")
		(net "GND")
	)
	(segment
		(start 49.249584 -132.53085)
		(end 49.24933 -132.530596)
		(width 0.4064)
		(layer "B.Cu")
		(net "GND")
	)
	(segment
		(start 256.0828 -7.806944)
		(end 256.089658 -7.813802)
		(width 0.4064)
		(layer "B.Cu")
		(net "GND")
	)
	(segment
		(start 113.849404 -11.857736)
		(end 113.923318 -11.93165)
		(width 0.4064)
		(layer "B.Cu")
		(net "GND")
	)
	(segment
		(start 56.899556 -17.207992)
		(end 56.899302 -17.208246)
		(width 0.4064)
		(layer "B.Cu")
		(net "GND")
	)
	(segment
		(start 215.949784 -142.476982)
		(end 215.949784 -140.706856)
		(width 0.4064)
		(layer "B.Cu")
		(net "GND")
	)
	(segment
		(start 127.44958 -9.20115)
		(end 127.44958 -10.623042)
		(width 0.4064)
		(layer "B.Cu")
		(net "GND")
	)
	(segment
		(start 47.549562 -24.824182)
		(end 47.549562 -24.53005)
		(width 0.4064)
		(layer "B.Cu")
		(net "GND")
	)
	(segment
		(start 495.665506 -134.274306)
		(end 496.1382 -134.747)
		(width 0.254)
		(layer "B.Cu")
		(net "GND")
	)
	(segment
		(start 218.500452 -20.224242)
		(end 218.499944 -20.224242)
		(width 0.4064)
		(layer "B.Cu")
		(net "GND")
	)
	(segment
		(start 294.999918 0.444754)
		(end 294.999918 -1.021842)
		(width 0.4064)
		(layer "B.Cu")
		(net "GND")
	)
	(segment
		(start 127.392176 -139.147296)
		(end 127.392176 -139.166092)
		(width 0.4064)
		(layer "B.Cu")
		(net "GND")
	)
	(segment
		(start 113.849404 -14.13002)
		(end 113.849404 -15.222982)
		(width 0.4064)
		(layer "B.Cu")
		(net "GND")
	)
	(segment
		(start 373.86514 -74.695304)
		(end 373.544846 -75.015598)
		(width 0.254)
		(layer "B.Cu")
		(net "GND")
	)
	(segment
		(start 183.515 -71.7042)
		(end 183.515 -71.9582)
		(width 0.4064)
		(layer "B.Cu")
		(net "GND")
	)
	(segment
		(start 226.150424 -128.276096)
		(end 226.149916 -128.276096)
		(width 0.4064)
		(layer "B.Cu")
		(net "GND")
	)
	(segment
		(start 374.089168 -89.125806)
		(end 373.854472 -88.89111)
		(width 0.254)
		(layer "B.Cu")
		(net "GND")
	)
	(segment
		(start 371.545358 -74.694288)
		(end 371.641624 -74.694288)
		(width 0.254)
		(layer "B.Cu")
		(net "GND")
	)
	(segment
		(start 226.9998 -24.0538)
		(end 226.7458 -23.7998)
		(width 0.254)
		(layer "B.Cu")
		(net "GND")
	)
	(segment
		(start 234.65028 -142.477236)
		(end 234.649772 -142.476982)
		(width 0.4064)
		(layer "B.Cu")
		(net "GND")
	)
	(segment
		(start 217.3986 -131.090162)
		(end 217.472006 -131.016756)
		(width 0.4064)
		(layer "B.Cu")
		(net "GND")
	)
	(segment
		(start 249.9106 -135.4074)
		(end 250.7615 -135.4074)
		(width 0.4572)
		(layer "B.Cu")
		(net "GND")
	)
	(segment
		(start 61.999368 -24.824182)
		(end 61.999368 -25.937972)
		(width 0.4064)
		(layer "B.Cu")
		(net "GND")
	)
	(segment
		(start 130.84937 -15.222982)
		(end 130.84937 -13.363956)
		(width 0.4064)
		(layer "B.Cu")
		(net "GND")
	)
	(segment
		(start 317.09995 -147.478496)
		(end 317.100458 -147.478496)
		(width 0.4064)
		(layer "B.Cu")
		(net "GND")
	)
	(segment
		(start 46.699424 -128.276096)
		(end 46.699424 -129.568956)
		(width 0.4064)
		(layer "B.Cu")
		(net "GND")
	)
	(segment
		(start 148.699474 -147.478496)
		(end 148.699474 -148.771356)
		(width 0.4064)
		(layer "B.Cu")
		(net "GND")
	)
	(segment
		(start 439.626756 -142.827756)
		(end 439.626756 -143.589756)
		(width 0.254)
		(layer "B.Cu")
		(net "GND")
	)
	(segment
		(start 135.703818 -150.286974)
		(end 135.771636 -150.219156)
		(width 0.4064)
		(layer "B.Cu")
		(net "GND")
	)
	(segment
		(start 26.67 -156.091382)
		(end 26.67 -156.083)
		(width 0.4064)
		(layer "B.Cu")
		(net "GND")
	)
	(segment
		(start 199.799956 -18.80235)
		(end 199.742552 -18.744946)
		(width 0.4064)
		(layer "B.Cu")
		(net "GND")
	)
	(segment
		(start 52.398168 -4.5212)
		(end 52.398168 -3.836162)
		(width 0.4064)
		(layer "B.Cu")
		(net "GND")
	)
	(segment
		(start 459.869032 -131.0386)
		(end 459.792832 -130.9624)
		(width 0.254)
		(layer "B.Cu")
		(net "GND")
	)
	(segment
		(start 162.25266 -83.693)
		(end 163.42106 -83.693)
		(width 0.381)
		(layer "B.Cu")
		(net "GND")
	)
	(segment
		(start 53.499512 -10.623042)
		(end 53.499512 -11.835892)
		(width 0.4064)
		(layer "B.Cu")
		(net "GND")
	)
	(segment
		(start 438.833006 -40.5257)
		(end 438.833006 -41.203626)
		(width 0.3556)
		(layer "B.Cu")
		(net "GND")
	)
	(segment
		(start 144.449546 -129.556256)
		(end 144.436846 -129.568956)
		(width 0.4064)
		(layer "B.Cu")
		(net "GND")
	)
	(segment
		(start 62.849506 -148.691092)
		(end 62.792102 -148.748496)
		(width 0.4064)
		(layer "B.Cu")
		(net "GND")
	)
	(segment
		(start 82.420968 -26.289)
		(end 82.116168 -26.5938)
		(width 0.381)
		(layer "B.Cu")
		(net "GND")
	)
	(segment
		(start 232.100374 -10.623042)
		(end 232.099866 -10.623042)
		(width 0.4064)
		(layer "B.Cu")
		(net "GND")
	)
	(segment
		(start 55.199534 -132.062982)
		(end 54.737508 -131.600956)
		(width 0.4064)
		(layer "B.Cu")
		(net "GND")
	)
	(segment
		(start 62.849506 -11.835892)
		(end 62.792102 -11.893296)
		(width 0.4064)
		(layer "B.Cu")
		(net "GND")
	)
	(segment
		(start 299.249846 -7.509002)
		(end 299.151802 -7.607046)
		(width 0.4064)
		(layer "B.Cu")
		(net "GND")
	)
	(segment
		(start 214.250016 -5.621782)
		(end 214.250016 -5.27685)
		(width 0.4064)
		(layer "B.Cu")
		(net "GND")
	)
	(segment
		(start 204.899768 -152.078182)
		(end 204.899768 -150.219156)
		(width 0.4064)
		(layer "B.Cu")
		(net "GND")
	)
	(segment
		(start 215.949784 -5.621782)
		(end 215.949784 -3.851656)
		(width 0.4064)
		(layer "B.Cu")
		(net "GND")
	)
	(segment
		(start 323.629274 -124.1298)
		(end 325.4629 -124.1298)
		(width 0.254)
		(layer "B.Cu")
		(net "GND")
	)
	(segment
		(start 315.022992 -39.352728)
		(end 315.195458 -39.352728)
		(width 0.381)
		(layer "B.Cu")
		(net "GND")
	)
	(segment
		(start 71.349362 -24.0538)
		(end 71.349362 -24.824182)
		(width 0.254)
		(layer "B.Cu")
		(net "GND")
	)
	(segment
		(start 275.286978 -135.4074)
		(end 275.336762 -135.357616)
		(width 0.4572)
		(layer "B.Cu")
		(net "GND")
	)
	(segment
		(start 259.710682 -27.275282)
		(end 259.2832 -26.8478)
		(width 0.381)
		(layer "B.Cu")
		(net "GND")
	)
	(segment
		(start 310.054244 -13.431774)
		(end 310.122062 -13.363956)
		(width 0.4064)
		(layer "B.Cu")
		(net "GND")
	)
	(segment
		(start 147.390866 -16.696944)
		(end 147.849336 -16.238474)
		(width 0.4064)
		(layer "B.Cu")
		(net "GND")
	)
	(segment
		(start 218.499944 -20.224242)
		(end 218.499944 -21.437092)
		(width 0.4064)
		(layer "B.Cu")
		(net "GND")
	)
	(segment
		(start 464.178396 -144.526254)
		(end 463.690208 -144.526254)
		(width 0.4064)
		(layer "B.Cu")
		(net "GND")
	)
	(segment
		(start 95.555816 -150.7871)
		(end 95.555816 -150.059644)
		(width 0.4572)
		(layer "B.Cu")
		(net "GND")
	)
	(segment
		(start 292.392608 -2.292096)
		(end 292.450012 -2.234692)
		(width 0.4064)
		(layer "B.Cu")
		(net "GND")
	)
	(segment
		(start 210.849972 -16.23822)
		(end 210.849972 -15.222982)
		(width 0.4064)
		(layer "B.Cu")
		(net "GND")
	)
	(segment
		(start 299.160946 -3.762756)
		(end 299.249846 -3.851656)
		(width 0.4064)
		(layer "B.Cu")
		(net "GND")
	)
	(segment
		(start 368.967004 -26.362152)
		(end 368.972592 -26.362152)
		(width 0.508)
		(layer "B.Cu")
		(net "GND")
	)
	(segment
		(start 402.626576 -32.258)
		(end 402.209 -32.258)
		(width 0.254)
		(layer "B.Cu")
		(net "GND")
	)
	(segment
		(start 240.599722 -151.707596)
		(end 240.599722 -150.219156)
		(width 0.4064)
		(layer "B.Cu")
		(net "GND")
	)
	(segment
		(start 56.899556 -14.87805)
		(end 56.899556 -15.222982)
		(width 0.4064)
		(layer "B.Cu")
		(net "GND")
	)
	(segment
		(start 205.749906 -11.916156)
		(end 205.749906 -10.623042)
		(width 0.4064)
		(layer "B.Cu")
		(net "GND")
	)
	(segment
		(start 370.323364 -3.420364)
		(end 370.967 -4.064)
		(width 0.381)
		(layer "B.Cu")
		(net "GND")
	)
	(segment
		(start 203.199746 -17.208246)
		(end 203.2 -17.207992)
		(width 0.4064)
		(layer "B.Cu")
		(net "GND")
	)
	(segment
		(start 289.93592 -152.042876)
		(end 289.93592 -150.344124)
		(width 0.4064)
		(layer "B.Cu")
		(net "GND")
	)
	(segment
		(start 282.250388 -152.078436)
		(end 282.250388 -151.299672)
		(width 0.254)
		(layer "B.Cu")
		(net "GND")
	)
	(segment
		(start 236.349794 -15.222982)
		(end 236.349794 -14.4526)
		(width 0.254)
		(layer "B.Cu")
		(net "GND")
	)
	(segment
		(start 214.250524 -5.621782)
		(end 214.250016 -5.621782)
		(width 0.4064)
		(layer "B.Cu")
		(net "GND")
	)
	(segment
		(start 263.7028 -27.1018)
		(end 263.3218 -27.4828)
		(width 0.381)
		(layer "B.Cu")
		(net "GND")
	)
	(segment
		(start 113.417604 -145.0086)
		(end 113.849404 -144.5768)
		(width 0.4572)
		(layer "B.Cu")
		(net "GND")
	)
	(segment
		(start 407.036016 4.405884)
		(end 407.036016 4.141216)
		(width 0.254)
		(layer "B.Cu")
		(net "GND")
	)
	(segment
		(start 78.102968 -27.813)
		(end 78.102968 -27.2288)
		(width 0.4064)
		(layer "B.Cu")
		(net "GND")
	)
	(segment
		(start 71.349362 -152.078436)
		(end 71.349362 -151.3078)
		(width 0.254)
		(layer "B.Cu")
		(net "GND")
	)
	(segment
		(start 66.24955 -25.638252)
		(end 67.099434 -26.488136)
		(width 0.4064)
		(layer "B.Cu")
		(net "GND")
	)
	(segment
		(start 77.299566 -13.36421)
		(end 77.299566 -15.222982)
		(width 0.4064)
		(layer "B.Cu")
		(net "GND")
	)
	(segment
		(start 213.399878 -20.224242)
		(end 213.399878 -18.757646)
		(width 0.4064)
		(layer "B.Cu")
		(net "GND")
	)
	(segment
		(start 211.699856 -128.276096)
		(end 211.699856 -129.568956)
		(width 0.4064)
		(layer "B.Cu")
		(net "GND")
	)
	(segment
		(start 56.049418 -137.877296)
		(end 56.049418 -139.170156)
		(width 0.4064)
		(layer "B.Cu")
		(net "GND")
	)
	(segment
		(start 146.149568 -20.224242)
		(end 146.149568 -21.437092)
		(width 0.4064)
		(layer "B.Cu")
		(net "GND")
	)
	(segment
		(start 136.799574 -2.234692)
		(end 136.74217 -2.292096)
		(width 0.4064)
		(layer "B.Cu")
		(net "GND")
	)
	(segment
		(start 421.235632 -24.003)
		(end 420.624 -24.003)
		(width 0.254)
		(layer "B.Cu")
		(net "GND")
	)
	(segment
		(start 240.600484 -142.477236)
		(end 240.599976 -142.476982)
		(width 0.4064)
		(layer "B.Cu")
		(net "GND")
	)
	(segment
		(start 316.249812 -152.078182)
		(end 316.249812 -150.219156)
		(width 0.4064)
		(layer "B.Cu")
		(net "GND")
	)
	(segment
		(start 409.884118 -92.860114)
		(end 410.379418 -92.860114)
		(width 0.254)
		(layer "B.Cu")
		(net "GND")
	)
	(segment
		(start 227.850446 -20.224242)
		(end 227.849938 -20.224242)
		(width 0.4064)
		(layer "B.Cu")
		(net "GND")
	)
	(segment
		(start 381.309626 -105.815384)
		(end 382.0668 -105.815384)
		(width 0.254)
		(layer "B.Cu")
		(net "GND")
	)
	(segment
		(start 254.789432 -12.954)
		(end 255.130046 -12.613386)
		(width 0.4572)
		(layer "B.Cu")
		(net "GND")
	)
	(segment
		(start 308.59984 -142.476982)
		(end 308.59984 -140.82776)
		(width 0.4064)
		(layer "B.Cu")
		(net "GND")
	)
	(segment
		(start 226.7458 -151.0538)
		(end 226.7458 -150.9522)
		(width 0.254)
		(layer "B.Cu")
		(net "GND")
	)
	(segment
		(start 39.049452 -128.276096)
		(end 39.049452 -129.568956)
		(width 0.4064)
		(layer "B.Cu")
		(net "GND")
	)
	(segment
		(start 44.149518 0.40005)
		(end 44.092114 0.457454)
		(width 0.4064)
		(layer "B.Cu")
		(net "GND")
	)
	(segment
		(start 294.999918 -137.877296)
		(end 294.999918 -139.170156)
		(width 0.4064)
		(layer "B.Cu")
		(net "GND")
	)
	(segment
		(start 301.742602 -11.912092)
		(end 301.742602 -11.893296)
		(width 0.4064)
		(layer "B.Cu")
		(net "GND")
	)
	(segment
		(start 296.700448 -1.021842)
		(end 296.69994 -1.021842)
		(width 0.4064)
		(layer "B.Cu")
		(net "GND")
	)
	(segment
		(start 231.25049 -24.824182)
		(end 231.249982 -24.824182)
		(width 0.4064)
		(layer "B.Cu")
		(net "GND")
	)
	(segment
		(start 224.449894 -128.276096)
		(end 224.449894 -129.568956)
		(width 0.4064)
		(layer "B.Cu")
		(net "GND")
	)
	(segment
		(start -0.500126 -45.310044)
		(end 0.933958 -43.87596)
		(width 0.508)
		(layer "B.Cu")
		(net "GND")
	)
	(segment
		(start 72.1995 -139.089892)
		(end 72.142096 -139.147296)
		(width 0.4064)
		(layer "B.Cu")
		(net "GND")
	)
	(segment
		(start 133.39953 -129.568956)
		(end 133.39953 -128.276096)
		(width 0.4064)
		(layer "B.Cu")
		(net "GND")
	)
	(segment
		(start 278.850344 -137.877296)
		(end 278.849836 -137.877296)
		(width 0.4064)
		(layer "B.Cu")
		(net "GND")
	)
	(segment
		(start 278.849836 -142.477236)
		(end 278.849836 -142.476982)
		(width 0.508)
		(layer "B.Cu")
		(net "GND")
	)
	(segment
		(start 378.8918 -61.381894)
		(end 378.8918 -61.3664)
		(width 0.254)
		(layer "B.Cu")
		(net "GND")
	)
	(segment
		(start 195.549774 -141.1478)
		(end 195.549774 -142.477236)
		(width 0.4064)
		(layer "B.Cu")
		(net "GND")
	)
	(segment
		(start 284.799786 -6.63702)
		(end 284.341062 -7.095744)
		(width 0.4064)
		(layer "B.Cu")
		(net "GND")
	)
	(segment
		(start 304.349912 -139.170156)
		(end 304.349912 -137.877296)
		(width 0.4064)
		(layer "B.Cu")
		(net "GND")
	)
	(segment
		(start 39.049452 -10.623042)
		(end 39.049452 -11.916156)
		(width 0.4064)
		(layer "B.Cu")
		(net "GND")
	)
	(segment
		(start 362.8136 -57.404)
		(end 363.24032 -56.97728)
		(width 0.254)
		(layer "B.Cu")
		(net "GND")
	)
	(segment
		(start 300.70425 -14.1224)
		(end 300.70425 -13.431774)
		(width 0.4064)
		(layer "B.Cu")
		(net "GND")
	)
	(segment
		(start 212.549994 -142.476982)
		(end 212.549994 -142.18285)
		(width 0.4064)
		(layer "B.Cu")
		(net "GND")
	)
	(segment
		(start 201.499978 -142.476982)
		(end 201.499978 -141.664182)
		(width 0.4064)
		(layer "B.Cu")
		(net "GND")
	)
	(segment
		(start 294.14978 -132.062728)
		(end 293.688008 -131.600956)
		(width 0.4064)
		(layer "B.Cu")
		(net "GND")
	)
	(segment
		(start 61.136784 -139.170156)
		(end 61.111384 -139.170156)
		(width 0.4064)
		(layer "B.Cu")
		(net "GND")
	)
	(segment
		(start 82.21218 -125.64745)
		(end 82.2198 -125.63983)
		(width 0.254)
		(layer "B.Cu")
		(net "GND")
	)
	(segment
		(start 448.2846 -130.2512)
		(end 449.1736 -130.2512)
		(width 0.254)
		(layer "B.Cu")
		(net "GND")
	)
	(segment
		(start 209.14995 -21.437092)
		(end 209.14995 -20.224242)
		(width 0.4064)
		(layer "B.Cu")
		(net "GND")
	)
	(segment
		(start 96.086168 -1.778)
		(end 96.213168 -1.651)
		(width 0.508)
		(layer "B.Cu")
		(net "GND")
	)
	(segment
		(start 255.018032 -139.9794)
		(end 254.789432 -140.208)
		(width 0.4064)
		(layer "B.Cu")
		(net "GND")
	)
	(segment
		(start 33.703768 -150.9776)
		(end 33.703768 -150.286974)
		(width 0.4064)
		(layer "B.Cu")
		(net "GND")
	)
	(segment
		(start 391.573512 -42.426382)
		(end 391.573512 -43.599608)
		(width 0.254)
		(layer "B.Cu")
		(net "GND")
	)
	(segment
		(start 378.817378 -65.621662)
		(end 378.169678 -65.621662)
		(width 0.254)
		(layer "B.Cu")
		(net "GND")
	)
	(segment
		(start 286.499808 -24.824182)
		(end 286.499808 -22.965156)
		(width 0.4064)
		(layer "B.Cu")
		(net "GND")
	)
	(segment
		(start 491.174532 -55.107078)
		(end 490.951266 -55.330344)
		(width 0.4064)
		(layer "B.Cu")
		(net "GND")
	)
	(segment
		(start 38.199568 -140.61821)
		(end 38.199314 -140.617956)
		(width 0.4064)
		(layer "B.Cu")
		(net "GND")
	)
	(segment
		(start 77.286612 -140.617956)
		(end 77.299312 -140.630656)
		(width 0.4064)
		(layer "B.Cu")
		(net "GND")
	)
	(segment
		(start 62.849506 -139.089892)
		(end 62.792102 -139.147296)
		(width 0.4064)
		(layer "B.Cu")
		(net "GND")
	)
	(segment
		(start 126.353824 -23.799546)
		(end 126.599442 -24.045164)
		(width 0.254)
		(layer "B.Cu")
		(net "GND")
	)
	(segment
		(start 267.095732 -135.4074)
		(end 268.679168 -135.4074)
		(width 0.4572)
		(layer "B.Cu")
		(net "GND")
	)
	(segment
		(start 303.499774 -152.078182)
		(end 303.499774 -151.265128)
		(width 0.4064)
		(layer "B.Cu")
		(net "GND")
	)
	(segment
		(start 242.299744 -140.630656)
		(end 242.299744 -142.055596)
		(width 0.4064)
		(layer "B.Cu")
		(net "GND")
	)
	(segment
		(start 277.910036 -135.538972)
		(end 277.778464 -135.4074)
		(width 0.4572)
		(layer "B.Cu")
		(net "GND")
	)
	(segment
		(start 33.086802 -129.568956)
		(end 33.061402 -129.568956)
		(width 0.4064)
		(layer "B.Cu")
		(net "GND")
	)
	(segment
		(start 77.299312 -150.231856)
		(end 77.286612 -150.219156)
		(width 0.4064)
		(layer "B.Cu")
		(net "GND")
	)
	(segment
		(start 216.80043 -147.478496)
		(end 216.799922 -147.478496)
		(width 0.4064)
		(layer "B.Cu")
		(net "GND")
	)
	(segment
		(start 33.703768 -23.032974)
		(end 33.771586 -22.965156)
		(width 0.4064)
		(layer "B.Cu")
		(net "GND")
	)
	(segment
		(start 278.0538 -140.208)
		(end 277.397464 -140.208)
		(width 0.4572)
		(layer "B.Cu")
		(net "GND")
	)
	(segment
		(start 109.2581 -149.8092)
		(end 110.109 -149.8092)
		(width 0.4064)
		(layer "B.Cu")
		(net "GND")
	)
	(segment
		(start 67.099434 -147.478496)
		(end 67.099434 -148.771356)
		(width 0.4064)
		(layer "B.Cu")
		(net "GND")
	)
	(segment
		(start 285.649924 -147.478496)
		(end 285.649924 -148.771356)
		(width 0.4064)
		(layer "B.Cu")
		(net "GND")
	)
	(segment
		(start 306.049934 -128.276096)
		(end 306.049934 -129.568956)
		(width 0.4064)
		(layer "B.Cu")
		(net "GND")
	)
	(segment
		(start 300.949868 -24.824182)
		(end 300.949868 -25.937972)
		(width 0.4064)
		(layer "B.Cu")
		(net "GND")
	)
	(segment
		(start 134.249414 -131.105656)
		(end 134.160514 -131.016756)
		(width 0.4064)
		(layer "B.Cu")
		(net "GND")
	)
	(segment
		(start 135.703818 -23.032974)
		(end 135.703818 -23.7236)
		(width 0.4064)
		(layer "B.Cu")
		(net "GND")
	)
	(segment
		(start 96.5708 1.321308)
		(end 96.5708 0.3048)
		(width 0.508)
		(layer "B.Cu")
		(net "GND")
	)
	(segment
		(start 124.81052 -140.617956)
		(end 124.81052 -140.592556)
		(width 0.4064)
		(layer "B.Cu")
		(net "GND")
	)
	(segment
		(start 289.050476 -10.623042)
		(end 289.049968 -10.623042)
		(width 0.4064)
		(layer "B.Cu")
		(net "GND")
	)
	(segment
		(start 227.849938 -11.835892)
		(end 227.849938 -10.623042)
		(width 0.4064)
		(layer "B.Cu")
		(net "GND")
	)
	(segment
		(start 218.499944 -10.623042)
		(end 218.499944 -11.835892)
		(width 0.4064)
		(layer "B.Cu")
		(net "GND")
	)
	(segment
		(start 119.799354 -141.664182)
		(end 119.337328 -141.202156)
		(width 0.4064)
		(layer "B.Cu")
		(net "GND")
	)
	(segment
		(start 135.949436 -24.824182)
		(end 135.949436 -25.937972)
		(width 0.4064)
		(layer "B.Cu")
		(net "GND")
	)
	(segment
		(start 64.549528 -15.222982)
		(end 64.549528 -16.23822)
		(width 0.4064)
		(layer "B.Cu")
		(net "GND")
	)
	(segment
		(start 85.761068 -17.7546)
		(end 84.910168 -17.7546)
		(width 0.4064)
		(layer "B.Cu")
		(net "GND")
	)
	(segment
		(start 34.799524 -128.276096)
		(end 34.799524 -129.488692)
		(width 0.4064)
		(layer "B.Cu")
		(net "GND")
	)
	(segment
		(start 140.199364 -13.363956)
		(end 140.199364 -15.222982)
		(width 0.4064)
		(layer "B.Cu")
		(net "GND")
	)
	(segment
		(start 235.49991 -21.479256)
		(end 235.46181 -21.517356)
		(width 0.4064)
		(layer "B.Cu")
		(net "GND")
	)
	(segment
		(start 61.999368 -132.1054)
		(end 61.745368 -131.8514)
		(width 0.254)
		(layer "B.Cu")
		(net "GND")
	)
	(segment
		(start 465.641944 -8.37692)
		(end 464.625944 -8.37692)
		(width 0.254)
		(layer "B.Cu")
		(net "GND")
	)
	(segment
		(start 291.354256 -150.9776)
		(end 291.354256 -150.286974)
		(width 0.4064)
		(layer "B.Cu")
		(net "GND")
	)
	(segment
		(start 64.549528 -16.23822)
		(end 64.090804 -16.696944)
		(width 0.4064)
		(layer "B.Cu")
		(net "GND")
	)
	(segment
		(start 299.249846 -131.105656)
		(end 299.160946 -131.016756)
		(width 0.4064)
		(layer "B.Cu")
		(net "GND")
	)
	(segment
		(start 299.249846 -17.110202)
		(end 299.151802 -17.208246)
		(width 0.4064)
		(layer "B.Cu")
		(net "GND")
	)
	(segment
		(start 488.5944 -140.7414)
		(end 488.7468 -140.589)
		(width 0.254)
		(layer "B.Cu")
		(net "GND")
	)
	(segment
		(start 376.560842 -45.72)
		(end 376.814842 -45.974)
		(width 0.254)
		(layer "B.Cu")
		(net "GND")
	)
	(segment
		(start 258.764278 -157.0228)
		(end 258.758436 -157.016958)
		(width 0.4064)
		(layer "B.Cu")
		(net "GND")
	)
	(segment
		(start 374.086374 -83.86953)
		(end 373.73814 -83.521296)
		(width 0.254)
		(layer "B.Cu")
		(net "GND")
	)
	(segment
		(start 447.079878 -151.953722)
		(end 447.711322 -151.953722)
		(width 0.254)
		(layer "B.Cu")
		(net "GND")
	)
	(segment
		(start 278.9682 -141.058392)
		(end 278.9682 -140.4874)
		(width 0.4064)
		(layer "B.Cu")
		(net "GND")
	)
	(segment
		(start 129.149348 -132.062728)
		(end 128.687576 -131.600956)
		(width 0.4064)
		(layer "B.Cu")
		(net "GND")
	)
	(segment
		(start 299.250354 -152.078436)
		(end 299.249846 -152.078182)
		(width 0.4064)
		(layer "B.Cu")
		(net "GND")
	)
	(segment
		(start 42.449496 -10.623042)
		(end 42.449496 -9.156446)
		(width 0.4064)
		(layer "B.Cu")
		(net "GND")
	)
	(segment
		(start 402.455888 -93.979238)
		(end 402.096478 -93.979238)
		(width 0.254)
		(layer "B.Cu")
		(net "GND")
	)
	(segment
		(start 216.799922 -147.478496)
		(end 216.799922 -148.758656)
		(width 0.4064)
		(layer "B.Cu")
		(net "GND")
	)
	(segment
		(start 126.599442 -132.876036)
		(end 126.599442 -132.096764)
		(width 0.254)
		(layer "B.Cu")
		(net "GND")
	)
	(segment
		(start 165.862 -80.391)
		(end 166.5986 -80.391)
		(width 0.4064)
		(layer "B.Cu")
		(net "GND")
	)
	(segment
		(start 233.800396 -128.276096)
		(end 233.799888 -128.276096)
		(width 0.4064)
		(layer "B.Cu")
		(net "GND")
	)
	(segment
		(start 449.326 -147.8026)
		(end 449.326 -147.0406)
		(width 0.254)
		(layer "B.Cu")
		(net "GND")
	)
	(segment
		(start 31.443168 -136.354058)
		(end 31.39948 -136.397746)
		(width 0.4064)
		(layer "B.Cu")
		(net "GND")
	)
	(segment
		(start 89.789 -145.0086)
		(end 90.151204 -144.646396)
		(width 0.4064)
		(layer "B.Cu")
		(net "GND")
	)
	(segment
		(start 471.932 -145.796)
		(end 472.250516 -145.477484)
		(width 0.254)
		(layer "B.Cu")
		(net "GND")
	)
	(segment
		(start 218.499944 0.40005)
		(end 218.499944 -1.021842)
		(width 0.4064)
		(layer "B.Cu")
		(net "GND")
	)
	(segment
		(start 75.599544 -24.824182)
		(end 75.599544 -24.45385)
		(width 0.4064)
		(layer "B.Cu")
		(net "GND")
	)
	(segment
		(start 220.199966 -24.824182)
		(end 220.199966 -24.011382)
		(width 0.4064)
		(layer "B.Cu")
		(net "GND")
	)
	(segment
		(start 260.0198 -157.0228)
		(end 258.764278 -157.0228)
		(width 0.4064)
		(layer "B.Cu")
		(net "GND")
	)
	(segment
		(start 229.550468 -15.222982)
		(end 229.54996 -15.222982)
		(width 0.4064)
		(layer "B.Cu")
		(net "GND")
	)
	(segment
		(start 143.599408 -15.222982)
		(end 143.599408 -17.110202)
		(width 0.4064)
		(layer "B.Cu")
		(net "GND")
	)
	(segment
		(start 386.9436 -55.3466)
		(end 386.9436 -54.864)
		(width 0.254)
		(layer "B.Cu")
		(net "GND")
	)
	(segment
		(start 105.9561 -149.8092)
		(end 106.841036 -149.8092)
		(width 0.4064)
		(layer "B.Cu")
		(net "GND")
	)
	(segment
		(start 229.550468 -152.078436)
		(end 229.54996 -152.078182)
		(width 0.4064)
		(layer "B.Cu")
		(net "GND")
	)
	(segment
		(start 64.549528 -152.078436)
		(end 64.549528 -151.265382)
		(width 0.4064)
		(layer "B.Cu")
		(net "GND")
	)
	(segment
		(start 215.0999 -10.623042)
		(end 215.0999 -11.916156)
		(width 0.4064)
		(layer "B.Cu")
		(net "GND")
	)
	(segment
		(start 212.549994 -14.92885)
		(end 212.54974 -14.928596)
		(width 0.4064)
		(layer "B.Cu")
		(net "GND")
	)
	(segment
		(start 351.8662 -88.465152)
		(end 351.8662 -88.269572)
		(width 0.254)
		(layer "B.Cu")
		(net "GND")
	)
	(segment
		(start 382.776984 -71.296276)
		(end 384.085338 -71.296276)
		(width 0.254)
		(layer "B.Cu")
		(net "GND")
	)
	(segment
		(start 284.799786 -15.222982)
		(end 284.799786 -14.410182)
		(width 0.4064)
		(layer "B.Cu")
		(net "GND")
	)
	(segment
		(start 198.7042 -23.7236)
		(end 198.7042 -23.032974)
		(width 0.4064)
		(layer "B.Cu")
		(net "GND")
	)
	(segment
		(start 368.346228 -69.895974)
		(end 368.345974 -69.895974)
		(width 0.254)
		(layer "B.Cu")
		(net "GND")
	)
	(segment
		(start 373.1641 -61.6839)
		(end 373.565166 -61.282834)
		(width 0.254)
		(layer "B.Cu")
		(net "GND")
	)
	(segment
		(start 114.699542 -139.170156)
		(end 114.699542 -137.877296)
		(width 0.4064)
		(layer "B.Cu")
		(net "GND")
	)
	(segment
		(start 114.699542 -128.276096)
		(end 114.699542 -127.006096)
		(width 0.508)
		(layer "B.Cu")
		(net "GND")
	)
	(segment
		(start 255.87452 -17.35709)
		(end 255.87452 -18.01749)
		(width 0.4064)
		(layer "B.Cu")
		(net "GND")
	)
	(segment
		(start 260.731 -136.779)
		(end 260.731 -137.414)
		(width 0.4064)
		(layer "B.Cu")
		(net "GND")
	)
	(segment
		(start 207.449928 -11.903456)
		(end 207.449928 -10.623042)
		(width 0.4064)
		(layer "B.Cu")
		(net "GND")
	)
	(segment
		(start 317.950342 -132.876036)
		(end 317.949834 -132.875782)
		(width 0.4064)
		(layer "B.Cu")
		(net "GND")
	)
	(segment
		(start 279.699974 -1.021842)
		(end 279.699974 0.457454)
		(width 0.4064)
		(layer "B.Cu")
		(net "GND")
	)
	(segment
		(start 114.699542 -127.006096)
		(end 114.822224 -126.883414)
		(width 0.508)
		(layer "B.Cu")
		(net "GND")
	)
	(segment
		(start 242.300506 -131.030218)
		(end 242.287044 -131.016756)
		(width 0.4064)
		(layer "B.Cu")
		(net "GND")
	)
	(segment
		(start 295.849802 -3.762756)
		(end 295.849802 -5.621782)
		(width 0.4064)
		(layer "B.Cu")
		(net "GND")
	)
	(segment
		(start 309.449978 -147.478496)
		(end 309.449978 -148.758656)
		(width 0.4064)
		(layer "B.Cu")
		(net "GND")
	)
	(segment
		(start 289.899852 -24.824182)
		(end 289.899852 -25.709372)
		(width 0.4064)
		(layer "B.Cu")
		(net "GND")
	)
	(segment
		(start 389.3312 -19.96186)
		(end 389.33374 -19.95932)
		(width 0.254)
		(layer "B.Cu")
		(net "GND")
	)
	(segment
		(start 289.90036 -142.477236)
		(end 289.899852 -142.476982)
		(width 0.4064)
		(layer "B.Cu")
		(net "GND")
	)
	(segment
		(start 90.496644 -8.1534)
		(end 90.8431 -7.806944)
		(width 0.4064)
		(layer "B.Cu")
		(net "GND")
	)
	(segment
		(start 52.398168 -14.1224)
		(end 52.398168 -14.173454)
		(width 0.254)
		(layer "B.Cu")
		(net "GND")
	)
	(segment
		(start 127.44958 -148.691092)
		(end 127.392176 -148.748496)
		(width 0.4064)
		(layer "B.Cu")
		(net "GND")
	)
	(segment
		(start 316.249812 -5.621782)
		(end 316.249812 -7.607046)
		(width 0.4064)
		(layer "B.Cu")
		(net "GND")
	)
	(segment
		(start 232.950004 -5.32765)
		(end 232.94975 -5.327396)
		(width 0.4064)
		(layer "B.Cu")
		(net "GND")
	)
	(segment
		(start 85.761068 -149.8092)
		(end 84.910168 -149.8092)
		(width 0.4064)
		(layer "B.Cu")
		(net "GND")
	)
	(segment
		(start 221.04985 -10.623042)
		(end 221.04985 -11.916156)
		(width 0.4064)
		(layer "B.Cu")
		(net "GND")
	)
	(segment
		(start 285.650432 -1.021842)
		(end 285.649924 -1.021842)
		(width 0.4064)
		(layer "B.Cu")
		(net "GND")
	)
	(segment
		(start 198.7042 -4.597146)
		(end 198.949818 -4.842764)
		(width 0.254)
		(layer "B.Cu")
		(net "GND")
	)
	(segment
		(start 209.092546 -2.292096)
		(end 209.14995 -2.234692)
		(width 0.4064)
		(layer "B.Cu")
		(net "GND")
	)
	(segment
		(start 34.74212 -9.143746)
		(end 34.799524 -9.20115)
		(width 0.4064)
		(layer "B.Cu")
		(net "GND")
	)
	(segment
		(start 233.799888 -2.314956)
		(end 233.799888 -1.021842)
		(width 0.4064)
		(layer "B.Cu")
		(net "GND")
	)
	(segment
		(start 405.6507 -15.415768)
		(end 405.6507 -17.17294)
		(width 0.254)
		(layer "B.Cu")
		(net "GND")
	)
	(segment
		(start 278.850344 -142.477236)
		(end 278.849836 -142.477236)
		(width 0.508)
		(layer "B.Cu")
		(net "GND")
	)
	(segment
		(start 217.649806 -132.875782)
		(end 217.649806 -132.07746)
		(width 0.254)
		(layer "B.Cu")
		(net "GND")
	)
	(segment
		(start 78.2193 -12.542012)
		(end 78.2193 -12.885166)
		(width 0.4064)
		(layer "B.Cu")
		(net "GND")
	)
	(segment
		(start 30.223968 -153.6446)
		(end 30.503368 -153.6446)
		(width 0.4064)
		(layer "B.Cu")
		(net "GND")
	)
	(segment
		(start 214.250016 -24.47925)
		(end 214.249762 -24.478996)
		(width 0.4064)
		(layer "B.Cu")
		(net "GND")
	)
	(segment
		(start 294.150288 -15.222982)
		(end 294.14978 -15.222982)
		(width 0.4064)
		(layer "B.Cu")
		(net "GND")
	)
	(segment
		(start 352.424492 -89.865962)
		(end 352.679 -89.611454)
		(width 0.254)
		(layer "B.Cu")
		(net "GND")
	)
	(segment
		(start 133.39953 -21.517356)
		(end 133.39953 -20.224242)
		(width 0.4064)
		(layer "B.Cu")
		(net "GND")
	)
	(segment
		(start 365.252 -53.213)
		(end 365.506 -52.959)
		(width 0.254)
		(layer "B.Cu")
		(net "GND")
	)
	(segment
		(start 130.84937 -152.078436)
		(end 130.84937 -150.219156)
		(width 0.4064)
		(layer "B.Cu")
		(net "GND")
	)
	(segment
		(start 309.449978 -11.903456)
		(end 309.449978 -10.623042)
		(width 0.4064)
		(layer "B.Cu")
		(net "GND")
	)
	(segment
		(start 73.899522 -24.011382)
		(end 73.899522 -24.824182)
		(width 0.4064)
		(layer "B.Cu")
		(net "GND")
	)
	(segment
		(start 300.772068 -140.617956)
		(end 300.70425 -140.685774)
		(width 0.4064)
		(layer "B.Cu")
		(net "GND")
	)
	(segment
		(start 218.44254 -148.748496)
		(end 218.44254 -148.767292)
		(width 0.4064)
		(layer "B.Cu")
		(net "GND")
	)
	(segment
		(start 192.0494 -9.1948)
		(end 191.314832 -8.460232)
		(width 0.254)
		(layer "B.Cu")
		(net "GND")
	)
	(segment
		(start 37.34943 -128.276096)
		(end 37.34943 -129.568956)
		(width 0.4064)
		(layer "B.Cu")
		(net "GND")
	)
	(segment
		(start 175.7172 -80.772)
		(end 176.6316 -80.772)
		(width 0.4064)
		(layer "B.Cu")
		(net "GND")
	)
	(segment
		(start 198.949818 -24.824182)
		(end 198.949818 -24.045164)
		(width 0.254)
		(layer "B.Cu")
		(net "GND")
	)
	(segment
		(start 261.7216 -5.8928)
		(end 261.7343 -5.8801)
		(width 0.508)
		(layer "B.Cu")
		(net "GND")
	)
	(segment
		(start 79.233268 -17.8816)
		(end 78.229968 -17.8816)
		(width 0.508)
		(layer "B.Cu")
		(net "GND")
	)
	(segment
		(start 126.599442 -5.621782)
		(end 126.599442 -7.4676)
		(width 0.4064)
		(layer "B.Cu")
		(net "GND")
	)
	(segment
		(start 255.521206 -139.829794)
		(end 255.3716 -139.9794)
		(width 0.4064)
		(layer "B.Cu")
		(net "GND")
	)
	(segment
		(start 58.599578 -132.63245)
		(end 58.599324 -132.632196)
		(width 0.4064)
		(layer "B.Cu")
		(net "GND")
	)
	(segment
		(start 60.299346 -140.706856)
		(end 60.210446 -140.617956)
		(width 0.4064)
		(layer "B.Cu")
		(net "GND")
	)
	(segment
		(start 93.420946 -157.02788)
		(end 93.397324 -157.004258)
		(width 0.508)
		(layer "B.Cu")
		(net "GND")
	)
	(segment
		(start 283.099764 -1.021842)
		(end 283.099764 0.40005)
		(width 0.4064)
		(layer "B.Cu")
		(net "GND")
	)
	(segment
		(start 303.499774 -132.875782)
		(end 303.499774 -132.062728)
		(width 0.4064)
		(layer "B.Cu")
		(net "GND")
	)
	(segment
		(start 404.063708 -0.635508)
		(end 403.733 -0.3048)
		(width 0.254)
		(layer "B.Cu")
		(net "GND")
	)
	(segment
		(start 401.99564 -93.8784)
		(end 401.955 -93.8784)
		(width 0.254)
		(layer "B.Cu")
		(net "GND")
	)
	(segment
		(start 218.499944 -21.437092)
		(end 218.44254 -21.494496)
		(width 0.4064)
		(layer "B.Cu")
		(net "GND")
	)
	(segment
		(start 143.599408 -13.427456)
		(end 143.599408 -15.222982)
		(width 0.254)
		(layer "B.Cu")
		(net "GND")
	)
	(segment
		(start 47.549308 -3.762756)
		(end 47.549308 -5.327396)
		(width 0.4064)
		(layer "B.Cu")
		(net "GND")
	)
	(segment
		(start 198.7042 -23.799546)
		(end 198.7042 -23.7236)
		(width 0.254)
		(layer "B.Cu")
		(net "GND")
	)
	(segment
		(start 310.299862 -17.0688)
		(end 310.299862 -15.222982)
		(width 0.4064)
		(layer "B.Cu")
		(net "GND")
	)
	(segment
		(start 300.949868 -132.096764)
		(end 300.949868 -132.875782)
		(width 0.254)
		(layer "B.Cu")
		(net "GND")
	)
	(segment
		(start 402.805646 -25.742646)
		(end 402.717 -25.654)
		(width 0.254)
		(layer "B.Cu")
		(net "GND")
	)
	(segment
		(start 237.142528 -2.292096)
		(end 237.199932 -2.234692)
		(width 0.4064)
		(layer "B.Cu")
		(net "GND")
	)
	(segment
		(start 33.949386 -152.078436)
		(end 33.949386 -151.299164)
		(width 0.254)
		(layer "B.Cu")
		(net "GND")
	)
	(segment
		(start 317.09995 -148.782278)
		(end 317.09995 -147.478496)
		(width 0.4064)
		(layer "B.Cu")
		(net "GND")
	)
	(segment
		(start 76.449428 -147.478496)
		(end 76.449428 -148.771356)
		(width 0.4064)
		(layer "B.Cu")
		(net "GND")
	)
	(segment
		(start 72.1995 -148.691092)
		(end 72.142096 -148.748496)
		(width 0.4064)
		(layer "B.Cu")
		(net "GND")
	)
	(segment
		(start 311.092596 -21.513292)
		(end 311.092596 -21.494496)
		(width 0.4064)
		(layer "B.Cu")
		(net "GND")
	)
	(segment
		(start 296.69994 -137.877296)
		(end 296.69994 -139.170156)
		(width 0.4064)
		(layer "B.Cu")
		(net "GND")
	)
	(segment
		(start 289.810952 -22.939756)
		(end 289.810952 -22.965156)
		(width 0.4064)
		(layer "B.Cu")
		(net "GND")
	)
	(segment
		(start 290.750498 -128.276096)
		(end 290.74999 -128.276096)
		(width 0.4064)
		(layer "B.Cu")
		(net "GND")
	)
	(segment
		(start 240.599722 -142.106396)
		(end 240.599722 -140.617956)
		(width 0.4064)
		(layer "B.Cu")
		(net "GND")
	)
	(segment
		(start 175.537622 -83.312)
		(end 175.323754 -83.525868)
		(width 0.4064)
		(layer "B.Cu")
		(net "GND")
	)
	(segment
		(start 213.400386 -10.623042)
		(end 213.399878 -10.623042)
		(width 0.4064)
		(layer "B.Cu")
		(net "GND")
	)
	(segment
		(start 241.450368 -10.623042)
		(end 241.44986 -10.623042)
		(width 0.4064)
		(layer "B.Cu")
		(net "GND")
	)
	(segment
		(start 77.315568 -126.3142)
		(end 77.526388 -126.10338)
		(width 0.254)
		(layer "B.Cu")
		(net "GND")
	)
	(segment
		(start 416.179 -21.336)
		(end 416.9664 -21.336)
		(width 0.254)
		(layer "B.Cu")
		(net "GND")
	)
	(segment
		(start 215.949784 -150.308056)
		(end 215.860884 -150.219156)
		(width 0.4064)
		(layer "B.Cu")
		(net "GND")
	)
	(segment
		(start 226.111816 -11.916156)
		(end 226.137216 -11.916156)
		(width 0.4064)
		(layer "B.Cu")
		(net "GND")
	)
	(segment
		(start 136.799574 -20.224242)
		(end 136.799574 -21.455888)
		(width 0.4064)
		(layer "B.Cu")
		(net "GND")
	)
	(segment
		(start 311.15 -148.691092)
		(end 311.15 -147.478496)
		(width 0.4064)
		(layer "B.Cu")
		(net "GND")
	)
	(segment
		(start 278.330152 -125.69444)
		(end 279.699974 -127.064262)
		(width 0.4064)
		(layer "B.Cu")
		(net "GND")
	)
	(segment
		(start 303.499774 -4.808728)
		(end 303.499774 -5.621782)
		(width 0.4064)
		(layer "B.Cu")
		(net "GND")
	)
	(segment
		(start 209.14995 -9.20115)
		(end 209.092546 -9.143746)
		(width 0.4064)
		(layer "B.Cu")
		(net "GND")
	)
	(segment
		(start 449.6435 -26.543)
		(end 448.8815 -26.543)
		(width 0.254)
		(layer "B.Cu")
		(net "GND")
	)
	(segment
		(start 33.099502 -1.021842)
		(end 33.099502 0.444754)
		(width 0.4064)
		(layer "B.Cu")
		(net "GND")
	)
	(segment
		(start 238.899954 -141.664182)
		(end 238.437928 -141.202156)
		(width 0.4064)
		(layer "B.Cu")
		(net "GND")
	)
	(segment
		(start 36.499546 -15.222982)
		(end 36.499546 -16.23822)
		(width 0.4064)
		(layer "B.Cu")
		(net "GND")
	)
	(segment
		(start 31.908496 -64.930782)
		(end 31.688278 -65.151)
		(width 0.254)
		(layer "B.Cu")
		(net "GND")
	)
	(segment
		(start 291.422074 -17.2466)
		(end 291.599874 -17.0688)
		(width 0.4064)
		(layer "B.Cu")
		(net "GND")
	)
	(segment
		(start 282.004262 -131.059174)
		(end 282.07208 -130.991356)
		(width 0.3556)
		(layer "B.Cu")
		(net "GND")
	)
	(segment
		(start 37.34943 -18.757646)
		(end 37.34943 -20.224242)
		(width 0.4064)
		(layer "B.Cu")
		(net "GND")
	)
	(segment
		(start 122.349514 -137.877296)
		(end 122.349514 -139.170156)
		(width 0.4064)
		(layer "B.Cu")
		(net "GND")
	)
	(segment
		(start 227.792534 -11.893296)
		(end 227.849938 -11.835892)
		(width 0.4064)
		(layer "B.Cu")
		(net "GND")
	)
	(segment
		(start 141.049502 -137.877296)
		(end 141.049502 -139.170156)
		(width 0.4064)
		(layer "B.Cu")
		(net "GND")
	)
	(segment
		(start 227.849938 -128.276096)
		(end 227.849938 -129.488692)
		(width 0.4064)
		(layer "B.Cu")
		(net "GND")
	)
	(segment
		(start 42.449496 -1.021842)
		(end 42.449496 -2.302256)
		(width 0.4064)
		(layer "B.Cu")
		(net "GND")
	)
	(segment
		(start 123.199398 -22.965156)
		(end 123.199398 -24.824182)
		(width 0.4064)
		(layer "B.Cu")
		(net "GND")
	)
	(segment
		(start 202.35037 -10.623042)
		(end 202.349862 -10.623042)
		(width 0.4064)
		(layer "B.Cu")
		(net "GND")
	)
	(segment
		(start 393.351512 -44.900088)
		(end 395.42974 -44.900088)
		(width 0.254)
		(layer "B.Cu")
		(net "GND")
	)
	(segment
		(start 119.799354 -24.011382)
		(end 119.337328 -23.549356)
		(width 0.4064)
		(layer "B.Cu")
		(net "GND")
	)
	(segment
		(start 373.565166 -61.098938)
		(end 373.565166 -60.222892)
		(width 0.254)
		(layer "B.Cu")
		(net "GND")
	)
	(segment
		(start 129.999486 -128.276096)
		(end 129.999486 -129.568956)
		(width 0.4064)
		(layer "B.Cu")
		(net "GND")
	)
	(segment
		(start 75.599544 -5.621782)
		(end 75.599544 -7.606792)
		(width 0.4064)
		(layer "B.Cu")
		(net "GND")
	)
	(segment
		(start 81.618836 -145.0086)
		(end 82.459068 -145.0086)
		(width 0.4572)
		(layer "B.Cu")
		(net "GND")
	)
	(segment
		(start 294.14978 -5.621782)
		(end 294.14978 -6.637274)
		(width 0.4064)
		(layer "B.Cu")
		(net "GND")
	)
	(segment
		(start 316.060074 -28.297886)
		(end 316.060074 -27.733752)
		(width 0.254)
		(layer "B.Cu")
		(net "GND")
	)
	(segment
		(start 204.049884 -10.623042)
		(end 204.049884 -11.916156)
		(width 0.4064)
		(layer "B.Cu")
		(net "GND")
	)
	(segment
		(start 150.399496 -18.757646)
		(end 150.399496 -20.224242)
		(width 0.4064)
		(layer "B.Cu")
		(net "GND")
	)
	(segment
		(start 217.650314 -15.222982)
		(end 217.649806 -15.222982)
		(width 0.254)
		(layer "B.Cu")
		(net "GND")
	)
	(segment
		(start 196.515736 -96.168464)
		(end 196.1134 -96.5708)
		(width 0.254)
		(layer "B.Cu")
		(net "GND")
	)
	(segment
		(start 364.321852 -42.887138)
		(end 364.321852 -41.8338)
		(width 0.254)
		(layer "B.Cu")
		(net "GND")
	)
	(segment
		(start 138.253724 -26.470356)
		(end 138.040872 -26.682954)
		(width 0.4064)
		(layer "B.Cu")
		(net "GND")
	)
	(segment
		(start 409.884118 -92.540328)
		(end 410.21254 -92.211906)
		(width 0.254)
		(layer "B.Cu")
		(net "GND")
	)
	(segment
		(start 304.349912 -20.224242)
		(end 304.349912 -21.517356)
		(width 0.4064)
		(layer "B.Cu")
		(net "GND")
	)
	(segment
		(start 272.231104 -157.9118)
		(end 271.280128 -156.960824)
		(width 0.381)
		(layer "B.Cu")
		(net "GND")
	)
	(segment
		(start 53.499512 -2.234692)
		(end 53.442108 -2.292096)
		(width 0.4064)
		(layer "B.Cu")
		(net "GND")
	)
	(segment
		(start 315.400436 -1.021842)
		(end 315.399928 -1.021842)
		(width 0.4064)
		(layer "B.Cu")
		(net "GND")
	)
	(segment
		(start 477.770444 -13.537946)
		(end 477.770444 -13.623036)
		(width 0.254)
		(layer "B.Cu")
		(net "GND")
	)
	(segment
		(start 196.893434 -55.528464)
		(end 196.464936 -55.528464)
		(width 0.254)
		(layer "B.Cu")
		(net "GND")
	)
	(segment
		(start 50.860452 -140.617956)
		(end 50.860452 -140.592556)
		(width 0.4064)
		(layer "B.Cu")
		(net "GND")
	)
	(segment
		(start 306.049934 0.444754)
		(end 306.049934 -1.021842)
		(width 0.4064)
		(layer "B.Cu")
		(net "GND")
	)
	(segment
		(start 61.149484 -147.478496)
		(end 61.149484 -148.758656)
		(width 0.4064)
		(layer "B.Cu")
		(net "GND")
	)
	(segment
		(start 212.54974 -3.762756)
		(end 212.54974 -5.327396)
		(width 0.4064)
		(layer "B.Cu")
		(net "GND")
	)
	(segment
		(start 215.0999 -147.478496)
		(end 215.0999 -148.771356)
		(width 0.4064)
		(layer "B.Cu")
		(net "GND")
	)
	(segment
		(start 60.299346 -23.054056)
		(end 60.299346 -24.824182)
		(width 0.4064)
		(layer "B.Cu")
		(net "GND")
	)
	(segment
		(start 199.742552 -11.912092)
		(end 199.742552 -11.893296)
		(width 0.4064)
		(layer "B.Cu")
		(net "GND")
	)
	(segment
		(start 289.049968 -147.478496)
		(end 289.049968 -148.771356)
		(width 0.4064)
		(layer "B.Cu")
		(net "GND")
	)
	(segment
		(start 449.5927 -142.9512)
		(end 448.9958 -142.9512)
		(width 0.254)
		(layer "B.Cu")
		(net "GND")
	)
	(segment
		(start 212.550502 -5.621782)
		(end 212.549994 -5.621782)
		(width 0.4064)
		(layer "B.Cu")
		(net "GND")
	)
	(segment
		(start 291.599874 -132.096764)
		(end 291.354256 -131.851146)
		(width 0.254)
		(layer "B.Cu")
		(net "GND")
	)
	(segment
		(start 284.800294 -24.824182)
		(end 284.799786 -24.824182)
		(width 0.4064)
		(layer "B.Cu")
		(net "GND")
	)
	(segment
		(start 289.801808 -7.607046)
		(end 289.899852 -7.509002)
		(width 0.4064)
		(layer "B.Cu")
		(net "GND")
	)
	(segment
		(start 478.0915 -118.385336)
		(end 477.84639 -118.630446)
		(width 0.254)
		(layer "B.Cu")
		(net "GND")
	)
	(segment
		(start 141.899386 -15.222982)
		(end 141.899386 -13.363956)
		(width 0.4064)
		(layer "B.Cu")
		(net "GND")
	)
	(segment
		(start 236.095794 -151.0538)
		(end 236.095794 -150.9522)
		(width 0.254)
		(layer "B.Cu")
		(net "GND")
	)
	(segment
		(start 146.092164 -11.912092)
		(end 146.092164 -11.893296)
		(width 0.4064)
		(layer "B.Cu")
		(net "GND")
	)
	(segment
		(start 278.849836 -18.786348)
		(end 278.944578 -18.691606)
		(width 0.4064)
		(layer "B.Cu")
		(net "GND")
	)
	(segment
		(start 53.499512 -21.437092)
		(end 53.442108 -21.494496)
		(width 0.4064)
		(layer "B.Cu")
		(net "GND")
	)
	(segment
		(start 270.956532 -149.8092)
		(end 271.841468 -149.8092)
		(width 0.4572)
		(layer "B.Cu")
		(net "GND")
	)
	(segment
		(start 458.422756 -21.494242)
		(end 458.422756 -21.2471)
		(width 0.254)
		(layer "B.Cu")
		(net "GND")
	)
	(segment
		(start 294.14978 -24.824182)
		(end 294.14978 -26.224484)
		(width 0.4064)
		(layer "B.Cu")
		(net "GND")
	)
	(segment
		(start 236.349794 -24.0538)
		(end 236.095794 -23.7998)
		(width 0.254)
		(layer "B.Cu")
		(net "GND")
	)
	(segment
		(start 216.80043 -137.877296)
		(end 216.799922 -137.877296)
		(width 0.4064)
		(layer "B.Cu")
		(net "GND")
	)
	(segment
		(start 134.249414 -140.706856)
		(end 134.160514 -140.617956)
		(width 0.4064)
		(layer "B.Cu")
		(net "GND")
	)
	(segment
		(start 41.599358 -3.826256)
		(end 41.510458 -3.737356)
		(width 0.4064)
		(layer "B.Cu")
		(net "GND")
	)
	(segment
		(start 198.099934 -11.903456)
		(end 198.099934 -10.623042)
		(width 0.4064)
		(layer "B.Cu")
		(net "GND")
	)
	(segment
		(start 141.049502 -20.224242)
		(end 141.049502 -18.757646)
		(width 0.4064)
		(layer "B.Cu")
		(net "GND")
	)
	(segment
		(start 113.849404 -10.623042)
		(end 113.849404 -11.857736)
		(width 0.4064)
		(layer "B.Cu")
		(net "GND")
	)
	(segment
		(start 205.749906 -2.314956)
		(end 205.749906 -1.021842)
		(width 0.4064)
		(layer "B.Cu")
		(net "GND")
	)
	(segment
		(start 145.053812 -131.7752)
		(end 145.053812 -131.851146)
		(width 0.254)
		(layer "B.Cu")
		(net "GND")
	)
	(segment
		(start 61.745368 -4.5974)
		(end 61.999368 -4.8514)
		(width 0.254)
		(layer "B.Cu")
		(net "GND")
	)
	(segment
		(start 304.349912 -26.495756)
		(end 305.199796 -25.645872)
		(width 0.4064)
		(layer "B.Cu")
		(net "GND")
	)
	(segment
		(start 238.899954 -132.062982)
		(end 238.437928 -131.600956)
		(width 0.4064)
		(layer "B.Cu")
		(net "GND")
	)
	(segment
		(start 39.899336 -22.965156)
		(end 39.899336 -24.824182)
		(width 0.4064)
		(layer "B.Cu")
		(net "GND")
	)
	(segment
		(start 314.54979 -15.222982)
		(end 314.54979 -13.363956)
		(width 0.4064)
		(layer "B.Cu")
		(net "GND")
	)
	(segment
		(start 145.053812 -131.084574)
		(end 145.053812 -131.7752)
		(width 0.4064)
		(layer "B.Cu")
		(net "GND")
	)
	(segment
		(start 124.89942 -17.110202)
		(end 124.801376 -17.208246)
		(width 0.4064)
		(layer "B.Cu")
		(net "GND")
	)
	(segment
		(start 140.199364 -22.965156)
		(end 140.199364 -24.824182)
		(width 0.4064)
		(layer "B.Cu")
		(net "GND")
	)
	(segment
		(start 134.249414 -24.824182)
		(end 134.249414 -25.683718)
		(width 0.4064)
		(layer "B.Cu")
		(net "GND")
	)
	(segment
		(start 296.700448 -20.224242)
		(end 296.69994 -20.224242)
		(width 0.4064)
		(layer "B.Cu")
		(net "GND")
	)
	(segment
		(start 30.549342 -132.876036)
		(end 30.549342 -131.5466)
		(width 0.4064)
		(layer "B.Cu")
		(net "GND")
	)
	(segment
		(start 205.750414 -128.276096)
		(end 205.749906 -128.276096)
		(width 0.4064)
		(layer "B.Cu")
		(net "GND")
	)
	(segment
		(start 230.399844 -18.757646)
		(end 230.399844 -20.224242)
		(width 0.4064)
		(layer "B.Cu")
		(net "GND")
	)
	(segment
		(start 368.895122 -42.625772)
		(end 369.156488 -42.887138)
		(width 0.254)
		(layer "B.Cu")
		(net "GND")
	)
	(segment
		(start 30.549342 -150.642574)
		(end 29.944568 -150.0378)
		(width 0.4064)
		(layer "B.Cu")
		(net "GND")
	)
	(segment
		(start 300.099984 -129.556256)
		(end 300.087284 -129.568956)
		(width 0.4064)
		(layer "B.Cu")
		(net "GND")
	)
	(segment
		(start 376.428 -98.354896)
		(end 377.242832 -98.354896)
		(width 0.2032)
		(layer "B.Cu")
		(net "GND")
	)
	(segment
		(start 0.365506 -136.673082)
		(end -0.452882 -136.673082)
		(width 0.254)
		(layer "B.Cu")
		(net "GND")
	)
	(segment
		(start 460.8576 -125.48997)
		(end 460.8576 -125.8824)
		(width 0.254)
		(layer "B.Cu")
		(net "GND")
	)
	(segment
		(start 385.454144 -47.244)
		(end 385.401312 -47.296832)
		(width 0.254)
		(layer "B.Cu")
		(net "GND")
	)
	(segment
		(start 277.397464 -149.8092)
		(end 277.9268 -149.8092)
		(width 0.4064)
		(layer "B.Cu")
		(net "GND")
	)
	(segment
		(start 42.411396 -18.757646)
		(end 42.449496 -18.795746)
		(width 0.4064)
		(layer "B.Cu")
		(net "GND")
	)
	(segment
		(start 229.550468 -132.876036)
		(end 229.54996 -132.875782)
		(width 0.4064)
		(layer "B.Cu")
		(net "GND")
	)
	(segment
		(start 116.399564 -2.302256)
		(end 116.386864 -2.314956)
		(width 0.4064)
		(layer "B.Cu")
		(net "GND")
	)
	(segment
		(start 75.599544 -142.10665)
		(end 75.59929 -142.106396)
		(width 0.4064)
		(layer "B.Cu")
		(net "GND")
	)
	(segment
		(start 226.9998 -141.7066)
		(end 226.7458 -141.4526)
		(width 0.254)
		(layer "B.Cu")
		(net "GND")
	)
	(segment
		(start 33.086802 -11.916156)
		(end 33.061402 -11.916156)
		(width 0.4064)
		(layer "B.Cu")
		(net "GND")
	)
	(segment
		(start 69.64934 -152.078436)
		(end 69.64934 -150.308056)
		(width 0.4064)
		(layer "B.Cu")
		(net "GND")
	)
	(segment
		(start 317.146432 -9.109964)
		(end 317.146432 -8.128)
		(width 0.4064)
		(layer "B.Cu")
		(net "GND")
	)
	(segment
		(start 285.650432 -20.224242)
		(end 285.649924 -20.224242)
		(width 0.4064)
		(layer "B.Cu")
		(net "GND")
	)
	(segment
		(start 71.171562 -13.363956)
		(end 71.095362 -13.440156)
		(width 0.4064)
		(layer "B.Cu")
		(net "GND")
	)
	(segment
		(start 287.349946 -20.224242)
		(end 287.349946 -21.517356)
		(width 0.4064)
		(layer "B.Cu")
		(net "GND")
	)
	(segment
		(start 495.065558 -43.644312)
		(end 494.706148 -43.644312)
		(width 0.254)
		(layer "B.Cu")
		(net "GND")
	)
	(segment
		(start 197.250304 -142.477236)
		(end 197.249796 -142.476982)
		(width 0.4064)
		(layer "B.Cu")
		(net "GND")
	)
	(segment
		(start 289.810952 -3.762756)
		(end 289.810952 -3.737356)
		(width 0.4064)
		(layer "B.Cu")
		(net "GND")
	)
	(segment
		(start 133.39953 -10.623042)
		(end 133.39953 -11.916156)
		(width 0.4064)
		(layer "B.Cu")
		(net "GND")
	)
	(segment
		(start 33.086802 -21.517356)
		(end 33.061402 -21.517356)
		(width 0.4064)
		(layer "B.Cu")
		(net "GND")
	)
	(segment
		(start 30.549342 -152.078436)
		(end 30.549342 -150.642574)
		(width 0.4064)
		(layer "B.Cu")
		(net "GND")
	)
	(segment
		(start 260.87578 -150.37562)
		(end 260.87578 -149.7711)
		(width 0.381)
		(layer "B.Cu")
		(net "GND")
	)
	(segment
		(start 307.749956 -129.568956)
		(end 307.749956 -128.276096)
		(width 0.4064)
		(layer "B.Cu")
		(net "GND")
	)
	(segment
		(start 210.849972 -141.664182)
		(end 210.387946 -141.202156)
		(width 0.4064)
		(layer "B.Cu")
		(net "GND")
	)
	(segment
		(start 125.736858 -139.170156)
		(end 125.711458 -139.170156)
		(width 0.4064)
		(layer "B.Cu")
		(net "GND")
	)
	(segment
		(start 280.549858 -7.509002)
		(end 280.549858 -5.621782)
		(width 0.4064)
		(layer "B.Cu")
		(net "GND")
	)
	(segment
		(start 352.679 -89.611454)
		(end 352.679 -89.119456)
		(width 0.254)
		(layer "B.Cu")
		(net "GND")
	)
	(segment
		(start 436.5244 -40.548306)
		(end 436.547006 -40.5257)
		(width 0.3556)
		(layer "B.Cu")
		(net "GND")
	)
	(segment
		(start 50.949352 -13.452856)
		(end 50.949352 -15.222982)
		(width 0.4064)
		(layer "B.Cu")
		(net "GND")
	)
	(segment
		(start 33.703768 -150.286974)
		(end 33.771586 -150.219156)
		(width 0.4064)
		(layer "B.Cu")
		(net "GND")
	)
	(segment
		(start 246.619268 -135.4074)
		(end 247.4595 -135.4074)
		(width 0.4572)
		(layer "B.Cu")
		(net "GND")
	)
	(segment
		(start 436.547006 -41.203626)
		(end 436.5244 -41.18102)
		(width 0.3556)
		(layer "B.Cu")
		(net "GND")
	)
	(segment
		(start 230.400352 -128.276096)
		(end 230.399844 -128.276096)
		(width 0.4064)
		(layer "B.Cu")
		(net "GND")
	)
	(segment
		(start 119.799354 -6.63702)
		(end 119.34063 -7.095744)
		(width 0.4064)
		(layer "B.Cu")
		(net "GND")
	)
	(segment
		(start 113.849404 -137.877296)
		(end 113.849404 -136.379966)
		(width 0.4064)
		(layer "B.Cu")
		(net "GND")
	)
	(segment
		(start 29.563568 -154.559)
		(end 29.563568 -154.305)
		(width 0.4064)
		(layer "B.Cu")
		(net "GND")
	)
	(segment
		(start 135.703818 -13.431774)
		(end 135.771636 -13.363956)
		(width 0.4064)
		(layer "B.Cu")
		(net "GND")
	)
	(segment
		(start 204.899768 -7.607046)
		(end 204.899768 -5.621782)
		(width 0.4064)
		(layer "B.Cu")
		(net "GND")
	)
	(segment
		(start 68.799456 -128.276096)
		(end 68.799456 -129.568956)
		(width 0.4064)
		(layer "B.Cu")
		(net "GND")
	)
	(segment
		(start 238.899954 -4.808982)
		(end 238.437928 -4.346956)
		(width 0.4064)
		(layer "B.Cu")
		(net "GND")
	)
	(segment
		(start 116.361464 -11.916156)
		(end 116.386864 -11.916156)
		(width 0.4064)
		(layer "B.Cu")
		(net "GND")
	)
	(segment
		(start 472.233498 -136.166606)
		(end 472.233498 -135.78459)
		(width 0.254)
		(layer "B.Cu")
		(net "GND")
	)
	(segment
		(start 164.211 -88.1126)
		(end 164.211 -87.1982)
		(width 0.4064)
		(layer "B.Cu")
		(net "GND")
	)
	(segment
		(start 44.149518 -2.234692)
		(end 44.149518 -1.021842)
		(width 0.4064)
		(layer "B.Cu")
		(net "GND")
	)
	(segment
		(start 203.2 -5.621782)
		(end 203.2 -7.606792)
		(width 0.4064)
		(layer "B.Cu")
		(net "GND")
	)
	(segment
		(start 495.9096 -129.032)
		(end 495.935 -129.032)
		(width 0.254)
		(layer "B.Cu")
		(net "GND")
	)
	(segment
		(start 308.59984 -15.222982)
		(end 308.59984 -13.427456)
		(width 0.254)
		(layer "B.Cu")
		(net "GND")
	)
	(segment
		(start 145.29943 -14.443964)
		(end 145.29943 -15.222982)
		(width 0.254)
		(layer "B.Cu")
		(net "GND")
	)
	(segment
		(start 313.699906 -20.224242)
		(end 313.699906 -18.757646)
		(width 0.4064)
		(layer "B.Cu")
		(net "GND")
	)
	(segment
		(start 52.398168 -140.691362)
		(end 52.471574 -140.617956)
		(width 0.4064)
		(layer "B.Cu")
		(net "GND")
	)
	(segment
		(start 227.849938 -129.488692)
		(end 227.792534 -129.546096)
		(width 0.4064)
		(layer "B.Cu")
		(net "GND")
	)
	(segment
		(start 285.649924 -137.877296)
		(end 285.649924 -139.170156)
		(width 0.4064)
		(layer "B.Cu")
		(net "GND")
	)
	(segment
		(start 131.699508 -147.478496)
		(end 131.699508 -148.771356)
		(width 0.4064)
		(layer "B.Cu")
		(net "GND")
	)
	(segment
		(start 82.2198 -125.63983)
		(end 83.56727 -125.63983)
		(width 0.254)
		(layer "B.Cu")
		(net "GND")
	)
	(segment
		(start 218.499944 -18.80235)
		(end 218.499944 -20.224242)
		(width 0.4064)
		(layer "B.Cu")
		(net "GND")
	)
	(segment
		(start 226.137216 -129.568956)
		(end 226.111816 -129.568956)
		(width 0.4064)
		(layer "B.Cu")
		(net "GND")
	)
	(segment
		(start 491.2868 -112.903)
		(end 492.4044 -114.0206)
		(width 0.254)
		(layer "B.Cu")
		(net "GND")
	)
	(segment
		(start 42.449496 -147.478496)
		(end 42.449496 -148.758656)
		(width 0.4064)
		(layer "B.Cu")
		(net "GND")
	)
	(segment
		(start 115.549426 -7.509002)
		(end 115.549426 -5.621782)
		(width 0.4064)
		(layer "B.Cu")
		(net "GND")
	)
	(segment
		(start 267.794232 -3.3528)
		(end 268.679168 -3.3528)
		(width 0.381)
		(layer "B.Cu")
		(net "GND")
	)
	(segment
		(start 220.200474 -142.477236)
		(end 220.199966 -142.476982)
		(width 0.4064)
		(layer "B.Cu")
		(net "GND")
	)
	(segment
		(start 383.3241 -115.443)
		(end 382.7272 -115.443)
		(width 0.3556)
		(layer "B.Cu")
		(net "GND")
	)
	(segment
		(start 136.799574 -11.835892)
		(end 136.799574 -10.623042)
		(width 0.4064)
		(layer "B.Cu")
		(net "GND")
	)
	(segment
		(start 308.600348 -5.621782)
		(end 308.59984 -5.621782)
		(width 0.254)
		(layer "B.Cu")
		(net "GND")
	)
	(segment
		(start 300.099984 -2.302256)
		(end 300.087284 -2.314956)
		(width 0.4064)
		(layer "B.Cu")
		(net "GND")
	)
	(segment
		(start 163.8808 2.130044)
		(end 163.8808 0.870458)
		(width 0.254)
		(layer "B.Cu")
		(net "GND")
	)
	(segment
		(start 255.8034 -2.975356)
		(end 256.422144 -2.975356)
		(width 0.4064)
		(layer "B.Cu")
		(net "GND")
	)
	(segment
		(start 120.649492 -137.877296)
		(end 120.649492 -139.170156)
		(width 0.4064)
		(layer "B.Cu")
		(net "GND")
	)
	(segment
		(start 215.100408 -20.224242)
		(end 215.0999 -20.224242)
		(width 0.4064)
		(layer "B.Cu")
		(net "GND")
	)
	(segment
		(start 33.949386 -24.824182)
		(end 33.949386 -24.045164)
		(width 0.254)
		(layer "B.Cu")
		(net "GND")
	)
	(segment
		(start 205.750414 -10.623042)
		(end 205.749906 -10.623042)
		(width 0.4064)
		(layer "B.Cu")
		(net "GND")
	)
	(segment
		(start 115.549426 -140.706856)
		(end 115.549426 -142.476982)
		(width 0.4064)
		(layer "B.Cu")
		(net "GND")
	)
	(segment
		(start 390.93775 -104.65435)
		(end 391.3378 -104.2543)
		(width 0.3556)
		(layer "B.Cu")
		(net "GND")
	)
	(segment
		(start 37.34943 -2.314956)
		(end 37.34943 -1.021842)
		(width 0.4064)
		(layer "B.Cu")
		(net "GND")
	)
	(segment
		(start 30.549342 -5.621782)
		(end 30.549342 -4.277106)
		(width 0.4064)
		(layer "B.Cu")
		(net "GND")
	)
	(segment
		(start 376.346466 -77.896466)
		(end 376.744738 -78.294738)
		(width 0.254)
		(layer "B.Cu")
		(net "GND")
	)
	(segment
		(start 50.099468 -9.143746)
		(end 50.099468 -10.623042)
		(width 0.4064)
		(layer "B.Cu")
		(net "GND")
	)
	(segment
		(start 370.566442 -96.437958)
		(end 372.240048 -96.437958)
		(width 0.254)
		(layer "B.Cu")
		(net "GND")
	)
	(segment
		(start 59.449462 -10.623042)
		(end 59.449462 -9.143746)
		(width 0.4064)
		(layer "B.Cu")
		(net "GND")
	)
	(segment
		(start 125.736858 -129.568956)
		(end 125.711458 -129.568956)
		(width 0.4064)
		(layer "B.Cu")
		(net "GND")
	)
	(segment
		(start 317.100458 -10.623042)
		(end 317.09995 -10.623042)
		(width 0.4064)
		(layer "B.Cu")
		(net "GND")
	)
	(segment
		(start 240.599976 -14.85265)
		(end 240.599722 -14.852396)
		(width 0.4064)
		(layer "B.Cu")
		(net "GND")
	)
	(segment
		(start 204.900276 -24.824182)
		(end 204.899768 -24.824182)
		(width 0.4064)
		(layer "B.Cu")
		(net "GND")
	)
	(segment
		(start 271.9578 4.7752)
		(end 272.415 4.318)
		(width 0.381)
		(layer "B.Cu")
		(net "GND")
	)
	(segment
		(start 231.249728 -17.208246)
		(end 231.249982 -17.207992)
		(width 0.4064)
		(layer "B.Cu")
		(net "GND")
	)
	(segment
		(start 60.210446 -131.016756)
		(end 60.210446 -130.991356)
		(width 0.4064)
		(layer "B.Cu")
		(net "GND")
	)
	(segment
		(start 19.304 -44.831)
		(end 19.7231 -45.2501)
		(width 0.254)
		(layer "B.Cu")
		(net "GND")
	)
	(segment
		(start 132.549392 -152.078436)
		(end 132.549392 -150.219156)
		(width 0.4064)
		(layer "B.Cu")
		(net "GND")
	)
	(segment
		(start 90.802968 -3.635756)
		(end 90.802968 -2.975356)
		(width 0.4064)
		(layer "B.Cu")
		(net "GND")
	)
	(segment
		(start 246.619268 -8.1534)
		(end 247.4595 -8.1534)
		(width 0.4572)
		(layer "B.Cu")
		(net "GND")
	)
	(segment
		(start 431.98034 -18.616168)
		(end 431.98034 -18.613628)
		(width 0.381)
		(layer "B.Cu")
		(net "GND")
	)
	(segment
		(start 151.24938 -132.876036)
		(end 151.24938 -131.016756)
		(width 0.4064)
		(layer "B.Cu")
		(net "GND")
	)
	(segment
		(start 142.749524 -1.021842)
		(end 142.749524 -2.314956)
		(width 0.4064)
		(layer "B.Cu")
		(net "GND")
	)
	(segment
		(start 495.552476 -44.13123)
		(end 495.065558 -43.644312)
		(width 0.254)
		(layer "B.Cu")
		(net "GND")
	)
	(segment
		(start 78.14945 -12.472162)
		(end 78.2193 -12.542012)
		(width 0.4064)
		(layer "B.Cu")
		(net "GND")
	)
	(segment
		(start 70.499478 -128.276096)
		(end 70.499478 -129.530856)
		(width 0.4064)
		(layer "B.Cu")
		(net "GND")
	)
	(segment
		(start 379.650752 -45.181774)
		(end 379.650752 -45.176948)
		(width 0.254)
		(layer "B.Cu")
		(net "GND")
	)
	(segment
		(start 311.092596 -139.147296)
		(end 311.092596 -139.166092)
		(width 0.4064)
		(layer "B.Cu")
		(net "GND")
	)
	(segment
		(start 203.200508 -15.222982)
		(end 203.2 -15.222982)
		(width 0.4064)
		(layer "B.Cu")
		(net "GND")
	)
	(segment
		(start 280.460958 -13.363956)
		(end 280.460958 -13.338556)
		(width 0.4064)
		(layer "B.Cu")
		(net "GND")
	)
	(segment
		(start 227.000308 -132.876036)
		(end 226.9998 -132.875782)
		(width 0.254)
		(layer "B.Cu")
		(net "GND")
	)
	(segment
		(start 440.4233 -148.845016)
		(end 439.662316 -148.845016)
		(width 0.254)
		(layer "B.Cu")
		(net "GND")
	)
	(segment
		(start 381.762 -157.816296)
		(end 382.187704 -158.242)
		(width 0.254)
		(layer "B.Cu")
		(net "GND")
	)
	(segment
		(start 352.626676 -89.067132)
		(end 352.679 -89.119456)
		(width 0.254)
		(layer "B.Cu")
		(net "GND")
	)
	(segment
		(start 31.395416 -9.139682)
		(end 31.341568 -9.085834)
		(width 0.381)
		(layer "B.Cu")
		(net "GND")
	)
	(segment
		(start 169.701972 -128.905)
		(end 169.701972 -129.615184)
		(width 0.381)
		(layer "B.Cu")
		(net "GND")
	)
	(segment
		(start 277.9268 -149.8092)
		(end 278.2062 -150.0886)
		(width 0.4064)
		(layer "B.Cu")
		(net "GND")
	)
	(segment
		(start 144.449546 -128.276096)
		(end 144.449546 -129.556256)
		(width 0.4064)
		(layer "B.Cu")
		(net "GND")
	)
	(segment
		(start 300.949868 -7.4676)
		(end 300.772068 -7.6454)
		(width 0.4064)
		(layer "B.Cu")
		(net "GND")
	)
	(segment
		(start 274.258532 -17.7546)
		(end 275.111464 -17.7546)
		(width 0.381)
		(layer "B.Cu")
		(net "GND")
	)
	(segment
		(start 300.70425 -131.7752)
		(end 300.70425 -131.851146)
		(width 0.254)
		(layer "B.Cu")
		(net "GND")
	)
	(segment
		(start 212.549994 -24.824182)
		(end 212.549994 -24.53005)
		(width 0.4064)
		(layer "B.Cu")
		(net "GND")
	)
	(segment
		(start 62.792102 -2.292096)
		(end 62.792102 -2.310892)
		(width 0.4064)
		(layer "B.Cu")
		(net "GND")
	)
	(segment
		(start 308.59984 -131.22656)
		(end 308.809644 -131.016756)
		(width 0.4064)
		(layer "B.Cu")
		(net "GND")
	)
	(segment
		(start 378.82195 -110.085124)
		(end 378.10313 -110.085124)
		(width 0.254)
		(layer "B.Cu")
		(net "GND")
	)
	(segment
		(start 282.004262 -150.261574)
		(end 282.07208 -150.193756)
		(width 0.254)
		(layer "B.Cu")
		(net "GND")
	)
	(segment
		(start 240.599976 -152.078182)
		(end 240.599976 -151.70785)
		(width 0.4064)
		(layer "B.Cu")
		(net "GND")
	)
	(segment
		(start 226.9998 -24.824182)
		(end 226.9998 -24.0538)
		(width 0.254)
		(layer "B.Cu")
		(net "GND")
	)
	(segment
		(start 283.099764 -21.437092)
		(end 283.04236 -21.494496)
		(width 0.4064)
		(layer "B.Cu")
		(net "GND")
	)
	(segment
		(start 292.450012 -18.80235)
		(end 292.392608 -18.744946)
		(width 0.4064)
		(layer "B.Cu")
		(net "GND")
	)
	(segment
		(start 395.1097 -19.812)
		(end 395.47546 -19.812)
		(width 0.254)
		(layer "B.Cu")
		(net "GND")
	)
	(segment
		(start 410.483812 -13.773912)
		(end 410.8069 -14.097)
		(width 0.254)
		(layer "B.Cu")
		(net "GND")
	)
	(segment
		(start -4.36626 -118.803928)
		(end -4.339336 -118.777004)
		(width 0.254)
		(layer "B.Cu")
		(net "GND")
	)
	(segment
		(start 78.14945 -147.478496)
		(end 78.14945 -147.478242)
		(width 0.4064)
		(layer "B.Cu")
		(net "GND")
	)
	(segment
		(start 115.549426 -15.222982)
		(end 115.549426 -17.110202)
		(width 0.4064)
		(layer "B.Cu")
		(net "GND")
	)
	(segment
		(start 367.9444 -6.2357)
		(end 368.7064 -6.2357)
		(width 0.4572)
		(layer "B.Cu")
		(net "GND")
	)
	(segment
		(start 33.703768 -151.053546)
		(end 33.703768 -150.9776)
		(width 0.254)
		(layer "B.Cu")
		(net "GND")
	)
	(segment
		(start 118.099332 -2.234692)
		(end 118.041928 -2.292096)
		(width 0.4064)
		(layer "B.Cu")
		(net "GND")
	)
	(segment
		(start 282.004262 -23.007574)
		(end 282.07208 -22.939756)
		(width 0.4064)
		(layer "B.Cu")
		(net "GND")
	)
	(segment
		(start 416.585908 -140.9065)
		(end 416.71494 -140.9065)
		(width 0.381)
		(layer "B.Cu")
		(net "GND")
	)
	(segment
		(start 215.950292 -152.078436)
		(end 215.949784 -152.078182)
		(width 0.4064)
		(layer "B.Cu")
		(net "GND")
	)
	(segment
		(start 127.44958 -137.877296)
		(end 127.44958 -139.089892)
		(width 0.4064)
		(layer "B.Cu")
		(net "GND")
	)
	(segment
		(start 175.323754 -85.217)
		(end 175.323754 -85.689948)
		(width 0.4064)
		(layer "B.Cu")
		(net "GND")
	)
	(segment
		(start 365.844328 -46.415198)
		(end 365.844328 -47.866808)
		(width 0.254)
		(layer "B.Cu")
		(net "GND")
	)
	(segment
		(start 115.549426 -3.851656)
		(end 115.549426 -5.621782)
		(width 0.4064)
		(layer "B.Cu")
		(net "GND")
	)
	(segment
		(start 196.342 -155.542234)
		(end 196.399912 -155.600146)
		(width 0.4064)
		(layer "B.Cu")
		(net "GND")
	)
	(segment
		(start 215.0999 -9.143746)
		(end 215.0999 -10.623042)
		(width 0.4064)
		(layer "B.Cu")
		(net "GND")
	)
	(segment
		(start 72.1995 -18.80235)
		(end 72.1995 -20.224242)
		(width 0.4064)
		(layer "B.Cu")
		(net "GND")
	)
	(segment
		(start 142.749524 -139.170156)
		(end 142.749524 -137.877296)
		(width 0.4064)
		(layer "B.Cu")
		(net "GND")
	)
	(segment
		(start 293.69131 -16.696944)
		(end 294.14978 -16.238474)
		(width 0.4064)
		(layer "B.Cu")
		(net "GND")
	)
	(segment
		(start 289.90036 -15.222982)
		(end 289.899852 -15.222982)
		(width 0.4064)
		(layer "B.Cu")
		(net "GND")
	)
	(segment
		(start 464.282028 -144.629886)
		(end 464.178396 -144.526254)
		(width 0.4064)
		(layer "B.Cu")
		(net "GND")
	)
	(segment
		(start 232.100374 -1.021842)
		(end 232.099866 -1.021842)
		(width 0.4064)
		(layer "B.Cu")
		(net "GND")
	)
	(segment
		(start 297.550332 -5.621782)
		(end 297.549824 -5.621782)
		(width 0.4064)
		(layer "B.Cu")
		(net "GND")
	)
	(segment
		(start 403.5298 -23.949152)
		(end 402.881846 -23.949152)
		(width 0.254)
		(layer "B.Cu")
		(net "GND")
	)
	(segment
		(start 447.711322 -151.953722)
		(end 447.929 -152.1714)
		(width 0.254)
		(layer "B.Cu")
		(net "GND")
	)
	(segment
		(start 112.9538 -149.8092)
		(end 113.2332 -150.0886)
		(width 0.4064)
		(layer "B.Cu")
		(net "GND")
	)
	(segment
		(start 78.2193 -12.885166)
		(end 78.288134 -12.954)
		(width 0.4064)
		(layer "B.Cu")
		(net "GND")
	)
	(segment
		(start 149.549358 -22.965156)
		(end 149.549358 -24.824182)
		(width 0.4064)
		(layer "B.Cu")
		(net "GND")
	)
	(segment
		(start 317.100458 -1.021842)
		(end 317.09995 -1.021842)
		(width 0.4064)
		(layer "B.Cu")
		(net "GND")
	)
	(segment
		(start 115.549426 -15.222982)
		(end 115.549426 -13.452856)
		(width 0.4064)
		(layer "B.Cu")
		(net "GND")
	)
	(segment
		(start 234.649772 -7.509002)
		(end 234.649772 -5.621782)
		(width 0.4064)
		(layer "B.Cu")
		(net "GND")
	)
	(segment
		(start 283.099764 -147.478496)
		(end 283.099764 -148.691092)
		(width 0.4064)
		(layer "B.Cu")
		(net "GND")
	)
	(segment
		(start 303.041304 -16.696944)
		(end 303.499774 -16.238474)
		(width 0.4064)
		(layer "B.Cu")
		(net "GND")
	)
	(segment
		(start 77.544168 -26.67)
		(end 77.264768 -26.67)
		(width 0.4064)
		(layer "B.Cu")
		(net "GND")
	)
	(segment
		(start 44.149518 -147.478496)
		(end 44.149518 -148.691092)
		(width 0.4064)
		(layer "B.Cu")
		(net "GND")
	)
	(segment
		(start 380.464568 -41.772332)
		(end 380.3904 -41.8465)
		(width 0.254)
		(layer "B.Cu")
		(net "GND")
	)
	(segment
		(start 90.151204 -144.646396)
		(end 90.861896 -144.646396)
		(width 0.4064)
		(layer "B.Cu")
		(net "GND")
	)
	(segment
		(start 411.662118 -88.826594)
		(end 411.228794 -88.826594)
		(width 0.254)
		(layer "B.Cu")
		(net "GND")
	)
	(segment
		(start 214.250524 -15.222982)
		(end 214.250016 -15.222982)
		(width 0.4064)
		(layer "B.Cu")
		(net "GND")
	)
	(segment
		(start 371.945154 -74.997818)
		(end 371.945154 -75.018646)
		(width 0.254)
		(layer "B.Cu")
		(net "GND")
	)
	(segment
		(start 283.04236 -139.147296)
		(end 283.099764 -139.089892)
		(width 0.4064)
		(layer "B.Cu")
		(net "GND")
	)
	(segment
		(start 213.399878 -1.021842)
		(end 213.399878 -2.314956)
		(width 0.4064)
		(layer "B.Cu")
		(net "GND")
	)
	(segment
		(start 70.499478 -10.623042)
		(end 70.499478 -11.878056)
		(width 0.4064)
		(layer "B.Cu")
		(net "GND")
	)
	(segment
		(start 284.800294 -5.621782)
		(end 284.799786 -5.621782)
		(width 0.4064)
		(layer "B.Cu")
		(net "GND")
	)
	(segment
		(start 204.050392 -137.877296)
		(end 204.049884 -137.877296)
		(width 0.4064)
		(layer "B.Cu")
		(net "GND")
	)
	(segment
		(start 126.353824 -141.3764)
		(end 126.353824 -140.685774)
		(width 0.4064)
		(layer "B.Cu")
		(net "GND")
	)
	(segment
		(start 279.700482 -10.623042)
		(end 279.699974 -10.623042)
		(width 0.4064)
		(layer "B.Cu")
		(net "GND")
	)
	(segment
		(start 224.450402 -10.623042)
		(end 224.449894 -10.623042)
		(width 0.4064)
		(layer "B.Cu")
		(net "GND")
	)
	(segment
		(start 39.049452 -2.314956)
		(end 39.049452 -1.021842)
		(width 0.4064)
		(layer "B.Cu")
		(net "GND")
	)
	(segment
		(start 219.741242 -7.095744)
		(end 220.199966 -6.63702)
		(width 0.4064)
		(layer "B.Cu")
		(net "GND")
	)
	(segment
		(start 215.0999 0.457454)
		(end 215.0999 -1.021842)
		(width 0.4064)
		(layer "B.Cu")
		(net "GND")
	)
	(segment
		(start 36.499546 -132.062982)
		(end 36.03752 -131.600956)
		(width 0.4064)
		(layer "B.Cu")
		(net "GND")
	)
	(segment
		(start 291.354256 -4.5212)
		(end 291.354256 -4.597146)
		(width 0.254)
		(layer "B.Cu")
		(net "GND")
	)
	(segment
		(start 291.354256 -141.3764)
		(end 291.354256 -140.685774)
		(width 0.4064)
		(layer "B.Cu")
		(net "GND")
	)
	(segment
		(start 61.745368 -13.440156)
		(end 61.821568 -13.363956)
		(width 0.4064)
		(layer "B.Cu")
		(net "GND")
	)
	(segment
		(start 416.3695 -29.337)
		(end 416.3695 -28.613862)
		(width 0.254)
		(layer "B.Cu")
		(net "GND")
	)
	(segment
		(start 199.799956 -9.20115)
		(end 199.742552 -9.143746)
		(width 0.4064)
		(layer "B.Cu")
		(net "GND")
	)
	(segment
		(start 156.461968 -154.782012)
		(end 157.361382 -154.782012)
		(width 0.4064)
		(layer "B.Cu")
		(net "GND")
	)
	(segment
		(start 126.599442 -17.0688)
		(end 126.421642 -17.2466)
		(width 0.4064)
		(layer "B.Cu")
		(net "GND")
	)
	(segment
		(start 235.500418 -137.877296)
		(end 235.49991 -137.877296)
		(width 0.4064)
		(layer "B.Cu")
		(net "GND")
	)
	(segment
		(start 238.899954 -142.476982)
		(end 238.899954 -141.664182)
		(width 0.4064)
		(layer "B.Cu")
		(net "GND")
	)
	(segment
		(start 61.999368 -7.4676)
		(end 61.821568 -7.6454)
		(width 0.4064)
		(layer "B.Cu")
		(net "GND")
	)
	(segment
		(start 47.549562 -132.876036)
		(end 47.549562 -132.58165)
		(width 0.4064)
		(layer "B.Cu")
		(net "GND")
	)
	(segment
		(start 382.016 -47.371)
		(end 381.635 -46.99)
		(width 0.254)
		(layer "B.Cu")
		(net "GND")
	)
	(segment
		(start 69.56044 -150.219156)
		(end 69.56044 -150.193756)
		(width 0.4064)
		(layer "B.Cu")
		(net "GND")
	)
	(segment
		(start 172.65396 -74.041)
		(end 172.70476 -73.9902)
		(width 0.254)
		(layer "B.Cu")
		(net "GND")
	)
	(segment
		(start 107.414568 3.81)
		(end 107.414568 5.280406)
		(width 0.508)
		(layer "B.Cu")
		(net "GND")
	)
	(segment
		(start 130.84937 -132.876036)
		(end 130.84937 -131.016756)
		(width 0.4064)
		(layer "B.Cu")
		(net "GND")
	)
	(segment
		(start 409.428188 -8.338312)
		(end 409.955746 -7.810754)
		(width 0.254)
		(layer "B.Cu")
		(net "GND")
	)
	(segment
		(start 374.777 -101.1936)
		(end 374.777 -101.62159)
		(width 0.254)
		(layer "B.Cu")
		(net "GND")
	)
	(segment
		(start 313.700414 -147.478496)
		(end 313.699906 -147.478496)
		(width 0.4064)
		(layer "B.Cu")
		(net "GND")
	)
	(segment
		(start 310.054244 -150.286974)
		(end 310.122062 -150.219156)
		(width 0.4064)
		(layer "B.Cu")
		(net "GND")
	)
	(segment
		(start 72.1995 -128.276096)
		(end 72.1995 -129.488692)
		(width 0.4064)
		(layer "B.Cu")
		(net "GND")
	)
	(segment
		(start 225.299778 -7.509002)
		(end 225.299778 -5.621782)
		(width 0.4064)
		(layer "B.Cu")
		(net "GND")
	)
	(segment
		(start 379.579632 -47.0916)
		(end 379.3998 -47.0916)
		(width 0.254)
		(layer "B.Cu")
		(net "GND")
	)
	(segment
		(start 218.44254 -139.147296)
		(end 218.44254 -139.166092)
		(width 0.4064)
		(layer "B.Cu")
		(net "GND")
	)
	(segment
		(start 374.231916 -37.063426)
		(end 373.84228 -37.063426)
		(width 0.254)
		(layer "B.Cu")
		(net "GND")
	)
	(segment
		(start 44.149518 -1.021842)
		(end 44.149518 0.40005)
		(width 0.4064)
		(layer "B.Cu")
		(net "GND")
	)
	(segment
		(start 58.599324 -17.208246)
		(end 58.599578 -17.207992)
		(width 0.4064)
		(layer "B.Cu")
		(net "GND")
	)
	(segment
		(start 291.600382 -24.824182)
		(end 291.599874 -24.824182)
		(width 0.254)
		(layer "B.Cu")
		(net "GND")
	)
	(segment
		(start 47.549308 -5.327396)
		(end 47.549562 -5.32765)
		(width 0.4064)
		(layer "B.Cu")
		(net "GND")
	)
	(segment
		(start 463.677 -3.6195)
		(end 464.690714 -3.6195)
		(width 0.254)
		(layer "B.Cu")
		(net "GND")
	)
	(segment
		(start 146.092164 -2.292096)
		(end 146.092164 -2.310892)
		(width 0.4064)
		(layer "B.Cu")
		(net "GND")
	)
	(segment
		(start 291.354256 -14.1224)
		(end 291.354256 -13.431774)
		(width 0.4064)
		(layer "B.Cu")
		(net "GND")
	)
	(segment
		(start 317.09995 -144.987518)
		(end 317.146432 -145.034)
		(width 0.508)
		(layer "B.Cu")
		(net "GND")
	)
	(segment
		(start 198.7042 -3.830574)
		(end 198.7042 -4.597146)
		(width 0.254)
		(layer "B.Cu")
		(net "GND")
	)
	(segment
		(start 310.054244 -131.851146)
		(end 310.299862 -132.096764)
		(width 0.254)
		(layer "B.Cu")
		(net "GND")
	)
	(segment
		(start 199.799956 -2.234692)
		(end 199.742552 -2.292096)
		(width 0.4064)
		(layer "B.Cu")
		(net "GND")
	)
	(segment
		(start 69.64934 -3.851656)
		(end 69.56044 -3.762756)
		(width 0.4064)
		(layer "B.Cu")
		(net "GND")
	)
	(segment
		(start 61.745368 -23.6982)
		(end 61.745368 -23.7998)
		(width 0.254)
		(layer "B.Cu")
		(net "GND")
	)
	(segment
		(start 113.849404 -4.487164)
		(end 113.849404 -5.621782)
		(width 0.4064)
		(layer "B.Cu")
		(net "GND")
	)
	(segment
		(start 50.949352 -131.105656)
		(end 50.860452 -131.016756)
		(width 0.4064)
		(layer "B.Cu")
		(net "GND")
	)
	(segment
		(start 376.1105 -60.8965)
		(end 375.793 -60.579)
		(width 0.254)
		(layer "B.Cu")
		(net "GND")
	)
	(segment
		(start 296.69994 -1.021842)
		(end 296.69994 -2.314956)
		(width 0.4064)
		(layer "B.Cu")
		(net "GND")
	)
	(segment
		(start 499.080028 -143.002)
		(end 498.5512 -143.002)
		(width 0.254)
		(layer "B.Cu")
		(net "GND")
	)
	(segment
		(start 395.9733 -20.30984)
		(end 395.9733 -20.6248)
		(width 0.254)
		(layer "B.Cu")
		(net "GND")
	)
	(segment
		(start 300.70425 -3.830574)
		(end 300.70425 -4.5212)
		(width 0.4064)
		(layer "B.Cu")
		(net "GND")
	)
	(segment
		(start 278.850344 -152.078436)
		(end 278.850344 -150.777448)
		(width 0.4064)
		(layer "B.Cu")
		(net "GND")
	)
	(segment
		(start 221.899988 -132.875782)
		(end 221.899988 -132.53085)
		(width 0.4064)
		(layer "B.Cu")
		(net "GND")
	)
	(segment
		(start 243.615718 -64.2874)
		(end 243.338604 -64.010286)
		(width 0.254)
		(layer "B.Cu")
		(net "GND")
	)
	(segment
		(start 256.422144 -2.975356)
		(end 256.7686 -3.321812)
		(width 0.4064)
		(layer "B.Cu")
		(net "GND")
	)
	(segment
		(start 76.779628 -28.85186)
		(end 77.82052 -28.85186)
		(width 0.381)
		(layer "B.Cu")
		(net "GND")
	)
	(segment
		(start 124.81052 -3.737356)
		(end 124.81052 -3.762756)
		(width 0.4064)
		(layer "B.Cu")
		(net "GND")
	)
	(segment
		(start 232.950004 -24.53005)
		(end 232.94975 -24.529796)
		(width 0.4064)
		(layer "B.Cu")
		(net "GND")
	)
	(segment
		(start 43.050968 -131.899152)
		(end 43.050968 -131.074668)
		(width 0.4064)
		(layer "B.Cu")
		(net "GND")
	)
	(segment
		(start 229.091236 -16.696944)
		(end 229.54996 -16.23822)
		(width 0.4064)
		(layer "B.Cu")
		(net "GND")
	)
	(segment
		(start 226.149916 -11.903456)
		(end 226.149916 -10.623042)
		(width 0.4064)
		(layer "B.Cu")
		(net "GND")
	)
	(segment
		(start 129.149348 -26.224484)
		(end 128.690878 -26.682954)
		(width 0.4064)
		(layer "B.Cu")
		(net "GND")
	)
	(segment
		(start 294.14978 -141.663928)
		(end 293.688008 -141.202156)
		(width 0.4064)
		(layer "B.Cu")
		(net "GND")
	)
	(segment
		(start 444.208916 -14.867382)
		(end 444.208916 -14.855698)
		(width 0.254)
		(layer "B.Cu")
		(net "GND")
	)
	(segment
		(start 198.949818 -7.4676)
		(end 198.772018 -7.6454)
		(width 0.4064)
		(layer "B.Cu")
		(net "GND")
	)
	(segment
		(start 40.749474 -137.877296)
		(end 40.749474 -139.170156)
		(width 0.4064)
		(layer "B.Cu")
		(net "GND")
	)
	(segment
		(start 196.399912 -20.224242)
		(end 196.399912 -21.517356)
		(width 0.4064)
		(layer "B.Cu")
		(net "GND")
	)
	(segment
		(start 449.6181 -19.177)
		(end 449.1863 -19.6088)
		(width 0.254)
		(layer "B.Cu")
		(net "GND")
	)
	(segment
		(start 308.59984 -17.110202)
		(end 308.59984 -15.222982)
		(width 0.4064)
		(layer "B.Cu")
		(net "GND")
	)
	(segment
		(start 371.545358 -73.095358)
		(end 371.945154 -73.495154)
		(width 0.254)
		(layer "B.Cu")
		(net "GND")
	)
	(segment
		(start 236.171994 -7.6454)
		(end 236.349794 -7.4676)
		(width 0.4064)
		(layer "B.Cu")
		(net "GND")
	)
	(segment
		(start 41.599358 -23.028656)
		(end 41.510458 -22.939756)
		(width 0.4064)
		(layer "B.Cu")
		(net "GND")
	)
	(segment
		(start 217.472006 -7.6454)
		(end 217.649806 -7.4676)
		(width 0.4064)
		(layer "B.Cu")
		(net "GND")
	)
	(segment
		(start 115.460526 -150.219156)
		(end 115.460526 -150.193756)
		(width 0.4064)
		(layer "B.Cu")
		(net "GND")
	)
	(segment
		(start 227.849938 -1.021842)
		(end 227.849938 0.40005)
		(width 0.4064)
		(layer "B.Cu")
		(net "GND")
	)
	(segment
		(start 479.95205 3.25755)
		(end 479.95205 3.825748)
		(width 0.254)
		(layer "B.Cu")
		(net "GND")
	)
	(segment
		(start 102.7938 -3.3528)
		(end 103.678736 -3.3528)
		(width 0.508)
		(layer "B.Cu")
		(net "GND")
	)
	(segment
		(start 346.07754 -90.880692)
		(end 345.532202 -90.335354)
		(width 0.2032)
		(layer "B.Cu")
		(net "GND")
	)
	(segment
		(start 117.00383 -151.053546)
		(end 117.00383 -150.261574)
		(width 0.254)
		(layer "B.Cu")
		(net "GND")
	)
	(segment
		(start 33.703768 -140.685774)
		(end 33.771586 -140.617956)
		(width 0.4064)
		(layer "B.Cu")
		(net "GND")
	)
	(segment
		(start 96.721168 -7.843012)
		(end 96.441768 -8.122412)
		(width 0.4064)
		(layer "B.Cu")
		(net "GND")
	)
	(segment
		(start 369.145058 -77.896212)
		(end 369.145058 -77.8383)
		(width 0.254)
		(layer "B.Cu")
		(net "GND")
	)
	(segment
		(start 205.749906 -147.478496)
		(end 205.749906 -148.771356)
		(width 0.4064)
		(layer "B.Cu")
		(net "GND")
	)
	(segment
		(start 315.399928 -10.623042)
		(end 315.399928 -11.916156)
		(width 0.4064)
		(layer "B.Cu")
		(net "GND")
	)
	(segment
		(start 382.93675 -105.45445)
		(end 383.3368 -105.0544)
		(width 0.3048)
		(layer "B.Cu")
		(net "GND")
	)
	(segment
		(start 102.7938 -8.1534)
		(end 103.678736 -8.1534)
		(width 0.4064)
		(layer "B.Cu")
		(net "GND")
	)
	(segment
		(start 69.64934 -23.054056)
		(end 69.64934 -24.824182)
		(width 0.4064)
		(layer "B.Cu")
		(net "GND")
	)
	(segment
		(start 410.6545 -33.401)
		(end 410.6545 -34.098992)
		(width 0.4572)
		(layer "B.Cu")
		(net "GND")
	)
	(segment
		(start 82.21218 -126.816104)
		(end 82.343498 -126.947422)
		(width 0.4064)
		(layer "B.Cu")
		(net "GND")
	)
	(segment
		(start 382.187704 -158.242)
		(end 382.66116 -158.242)
		(width 0.254)
		(layer "B.Cu")
		(net "GND")
	)
	(segment
		(start 198.099934 -137.877296)
		(end 198.099934 -139.157456)
		(width 0.4064)
		(layer "B.Cu")
		(net "GND")
	)
	(segment
		(start 42.436796 -11.916156)
		(end 42.449496 -11.903456)
		(width 0.4064)
		(layer "B.Cu")
		(net "GND")
	)
	(segment
		(start 43.050968 -150.277068)
		(end 43.12158 -150.206456)
		(width 0.254)
		(layer "B.Cu")
		(net "GND")
	)
	(segment
		(start 194.691 -154.178)
		(end 195.2244 -153.6446)
		(width 0.4064)
		(layer "B.Cu")
		(net "GND")
	)
	(segment
		(start 370.745512 -71.494142)
		(end 370.651278 -71.494142)
		(width 0.254)
		(layer "B.Cu")
		(net "GND")
	)
	(segment
		(start 477.3803 -14.0589)
		(end 476.984568 -14.0589)
		(width 0.254)
		(layer "B.Cu")
		(net "GND")
	)
	(segment
		(start 243.149882 -20.224242)
		(end 243.149882 -18.766282)
		(width 0.4064)
		(layer "B.Cu")
		(net "GND")
	)
	(segment
		(start 308.59984 -24.824182)
		(end 308.59984 -23.17496)
		(width 0.4064)
		(layer "B.Cu")
		(net "GND")
	)
	(segment
		(start 214.249762 -5.276596)
		(end 214.249762 -3.762756)
		(width 0.4064)
		(layer "B.Cu")
		(net "GND")
	)
	(segment
		(start 208.299812 -7.4676)
		(end 208.299812 -5.621782)
		(width 0.4064)
		(layer "B.Cu")
		(net "GND")
	)
	(segment
		(start 301.800006 -11.835892)
		(end 301.800006 -10.623042)
		(width 0.4064)
		(layer "B.Cu")
		(net "GND")
	)
	(segment
		(start 311.092596 -11.912092)
		(end 311.092596 -11.893296)
		(width 0.4064)
		(layer "B.Cu")
		(net "GND")
	)
	(segment
		(start 291.599874 -5.621782)
		(end 291.599874 -7.4676)
		(width 0.4064)
		(layer "B.Cu")
		(net "GND")
	)
	(segment
		(start 141.049502 0.444754)
		(end 141.049502 -1.021842)
		(width 0.4064)
		(layer "B.Cu")
		(net "GND")
	)
	(segment
		(start 42.449496 0.444754)
		(end 42.449496 -1.021842)
		(width 0.4064)
		(layer "B.Cu")
		(net "GND")
	)
	(segment
		(start 413.639 -8.757158)
		(end 413.639 -8.1026)
		(width 0.254)
		(layer "B.Cu")
		(net "GND")
	)
	(segment
		(start 75.59929 -142.106396)
		(end 75.59929 -140.617956)
		(width 0.4064)
		(layer "B.Cu")
		(net "GND")
	)
	(segment
		(start 218.499944 -139.089892)
		(end 218.44254 -139.147296)
		(width 0.4064)
		(layer "B.Cu")
		(net "GND")
	)
	(segment
		(start 261.7216 -7.843012)
		(end 261.7216 -6.6421)
		(width 0.4064)
		(layer "B.Cu")
		(net "GND")
	)
	(segment
		(start 395.8082 -63.373)
		(end 396.74419 -63.373)
		(width 0.254)
		(layer "B.Cu")
		(net "GND")
	)
	(segment
		(start 201.500486 -152.078436)
		(end 201.499978 -152.078182)
		(width 0.4064)
		(layer "B.Cu")
		(net "GND")
	)
	(segment
		(start 312.849768 -151.265128)
		(end 312.387996 -150.803356)
		(width 0.4064)
		(layer "B.Cu")
		(net "GND")
	)
	(segment
		(start 268.679168 -145.0086)
		(end 267.794232 -145.0086)
		(width 0.4572)
		(layer "B.Cu")
		(net "GND")
	)
	(segment
		(start 382.016 -47.38878)
		(end 382.016 -47.371)
		(width 0.254)
		(layer "B.Cu")
		(net "GND")
	)
	(segment
		(start 207.450436 -10.623042)
		(end 207.449928 -10.623042)
		(width 0.4064)
		(layer "B.Cu")
		(net "GND")
	)
	(segment
		(start 167.7416 0.6858)
		(end 167.7416 0.6604)
		(width 0.4064)
		(layer "B.Cu")
		(net "GND")
	)
	(segment
		(start 207.449928 -137.877296)
		(end 207.449928 -139.157456)
		(width 0.4064)
		(layer "B.Cu")
		(net "GND")
	)
	(segment
		(start 310.299862 -152.078182)
		(end 310.299862 -151.299164)
		(width 0.254)
		(layer "B.Cu")
		(net "GND")
	)
	(segment
		(start 69.64934 -131.105656)
		(end 69.56044 -131.016756)
		(width 0.4064)
		(layer "B.Cu")
		(net "GND")
	)
	(segment
		(start 310.299862 -5.621782)
		(end 310.299862 -4.842764)
		(width 0.254)
		(layer "B.Cu")
		(net "GND")
	)
	(segment
		(start 206.600298 -152.078436)
		(end 206.59979 -152.078182)
		(width 0.4064)
		(layer "B.Cu")
		(net "GND")
	)
	(segment
		(start 164.211 -87.1982)
		(end 164.5412 -86.868)
		(width 0.4064)
		(layer "B.Cu")
		(net "GND")
	)
	(segment
		(start 369.690904 -77.494892)
		(end 369.945158 -77.240638)
		(width 0.254)
		(layer "B.Cu")
		(net "GND")
	)
	(segment
		(start 407.090118 -25.96896)
		(end 407.156158 -26.035)
		(width 0.254)
		(layer "B.Cu")
		(net "GND")
	)
	(segment
		(start 260.4643 -150.7871)
		(end 259.8293 -150.7871)
		(width 0.381)
		(layer "B.Cu")
		(net "GND")
	)
	(segment
		(start 395.839442 -11.408918)
		(end 395.548358 -11.700002)
		(width 0.254)
		(layer "B.Cu")
		(net "GND")
	)
	(segment
		(start 288.200338 -5.621782)
		(end 288.19983 -5.621782)
		(width 0.4064)
		(layer "B.Cu")
		(net "GND")
	)
	(segment
		(start 294.184578 -151.299926)
		(end 293.688008 -150.803356)
		(width 0.4064)
		(layer "B.Cu")
		(net "GND")
	)
	(segment
		(start 113.688368 -140.208)
		(end 113.967768 -140.4874)
		(width 0.4064)
		(layer "B.Cu")
		(net "GND")
	)
	(segment
		(start 176.7332 -78.232)
		(end 175.5394 -78.232)
		(width 0.4064)
		(layer "B.Cu")
		(net "GND")
	)
	(segment
		(start 494.48212 -122.5423)
		(end 494.63452 -122.5423)
		(width 0.254)
		(layer "B.Cu")
		(net "GND")
	)
	(segment
		(start 236.349794 -24.824182)
		(end 236.349794 -24.0538)
		(width 0.254)
		(layer "B.Cu")
		(net "GND")
	)
	(segment
		(start 317.100458 -20.224242)
		(end 317.09995 -20.224242)
		(width 0.4064)
		(layer "B.Cu")
		(net "GND")
	)
	(segment
		(start 204.899768 -5.621782)
		(end 204.899768 -3.762756)
		(width 0.4064)
		(layer "B.Cu")
		(net "GND")
	)
	(segment
		(start 206.600298 -142.477236)
		(end 206.59979 -142.476982)
		(width 0.4064)
		(layer "B.Cu")
		(net "GND")
	)
	(segment
		(start 297.549824 -5.621782)
		(end 297.549824 -7.607046)
		(width 0.4064)
		(layer "B.Cu")
		(net "GND")
	)
	(segment
		(start 300.099984 -21.479256)
		(end 300.061884 -21.517356)
		(width 0.4064)
		(layer "B.Cu")
		(net "GND")
	)
	(segment
		(start 195.549774 -143.946626)
		(end 195.5038 -143.9926)
		(width 0.4064)
		(layer "B.Cu")
		(net "GND")
	)
	(segment
		(start 242.5446 -26.67)
		(end 243.1034 -27.2288)
		(width 0.4064)
		(layer "B.Cu")
		(net "GND")
	)
	(segment
		(start 236.349794 -17.0688)
		(end 236.349794 -15.222982)
		(width 0.4064)
		(layer "B.Cu")
		(net "GND")
	)
	(segment
		(start 382.397 -1.143)
		(end 382.651 -0.889)
		(width 0.254)
		(layer "B.Cu")
		(net "GND")
	)
	(segment
		(start 243.193824 -149.371304)
		(end 243.193824 -149.436836)
		(width 0.4064)
		(layer "B.Cu")
		(net "GND")
	)
	(segment
		(start 47.549562 -24.53005)
		(end 47.549308 -24.529796)
		(width 0.4064)
		(layer "B.Cu")
		(net "GND")
	)
	(segment
		(start 281.400504 -1.021842)
		(end 281.399996 -1.021842)
		(width 0.4064)
		(layer "B.Cu")
		(net "GND")
	)
	(segment
		(start 145.053812 -151.053546)
		(end 145.29943 -151.299164)
		(width 0.254)
		(layer "B.Cu")
		(net "GND")
	)
	(segment
		(start 127.44958 -21.437092)
		(end 127.392176 -21.494496)
		(width 0.4064)
		(layer "B.Cu")
		(net "GND")
	)
	(segment
		(start 237.199932 -139.089892)
		(end 237.142528 -139.147296)
		(width 0.4064)
		(layer "B.Cu")
		(net "GND")
	)
	(segment
		(start 33.099502 -129.556256)
		(end 33.086802 -129.568956)
		(width 0.4064)
		(layer "B.Cu")
		(net "GND")
	)
	(segment
		(start 292.392608 -129.546096)
		(end 292.392608 -129.564892)
		(width 0.4064)
		(layer "B.Cu")
		(net "GND")
	)
	(segment
		(start 148.699474 -10.623042)
		(end 148.699474 -9.156446)
		(width 0.4064)
		(layer "B.Cu")
		(net "GND")
	)
	(segment
		(start 124.89942 -13.452856)
		(end 125.711458 -12.640818)
		(width 0.4064)
		(layer "B.Cu")
		(net "GND")
	)
	(segment
		(start 437.0324 -17.8308)
		(end 437.0324 -18.212054)
		(width 0.254)
		(layer "B.Cu")
		(net "GND")
	)
	(segment
		(start 218.500452 -128.276096)
		(end 218.499944 -128.276096)
		(width 0.4064)
		(layer "B.Cu")
		(net "GND")
	)
	(segment
		(start 61.136784 -11.916156)
		(end 61.111384 -11.916156)
		(width 0.4064)
		(layer "B.Cu")
		(net "GND")
	)
	(segment
		(start 79.360268 -17.7546)
		(end 79.233268 -17.8816)
		(width 0.508)
		(layer "B.Cu")
		(net "GND")
	)
	(segment
		(start 201.499978 -132.875782)
		(end 201.499978 -132.062982)
		(width 0.4064)
		(layer "B.Cu")
		(net "GND")
	)
	(segment
		(start 364.1725 -63.2206)
		(end 364.4392 -63.2206)
		(width 0.254)
		(layer "B.Cu")
		(net "GND")
	)
	(segment
		(start 9.81583 -43.87596)
		(end 11.249914 -45.310044)
		(width 0.508)
		(layer "B.Cu")
		(net "GND")
	)
	(segment
		(start 239.749838 -2.314956)
		(end 239.749838 -1.021842)
		(width 0.4064)
		(layer "B.Cu")
		(net "GND")
	)
	(segment
		(start 67.04584 -68.46824)
		(end 64.262 -65.6844)
		(width 0.254)
		(layer "B.Cu")
		(net "GND")
	)
	(segment
		(start 390.5758 -155.167838)
		(end 390.5758 -155.800044)
		(width 0.381)
		(layer "B.Cu")
		(net "GND")
	)
	(segment
		(start 36.499546 -152.078436)
		(end 36.499546 -151.265382)
		(width 0.4064)
		(layer "B.Cu")
		(net "GND")
	)
	(segment
		(start 295.000426 -137.877296)
		(end 294.999918 -137.877296)
		(width 0.4064)
		(layer "B.Cu")
		(net "GND")
	)
	(segment
		(start 231.249982 -152.078182)
		(end 231.249982 -151.70785)
		(width 0.4064)
		(layer "B.Cu")
		(net "GND")
	)
	(segment
		(start 373.538496 -86.632796)
		(end 374.015 -86.632796)
		(width 0.254)
		(layer "B.Cu")
		(net "GND")
	)
	(segment
		(start 197.160896 -150.881842)
		(end 197.160896 -150.193756)
		(width 0.4064)
		(layer "B.Cu")
		(net "GND")
	)
	(segment
		(start 50.949352 -152.078436)
		(end 50.949352 -150.308056)
		(width 0.4064)
		(layer "B.Cu")
		(net "GND")
	)
	(segment
		(start 226.9998 -25.937972)
		(end 226.9998 -24.824182)
		(width 0.4064)
		(layer "B.Cu")
		(net "GND")
	)
	(segment
		(start 413.1056 1.2446)
		(end 413.1056 -1.1684)
		(width 0.254)
		(layer "B.Cu")
		(net "GND")
	)
	(segment
		(start 300.949868 -152.078182)
		(end 300.950376 -152.078436)
		(width 0.254)
		(layer "B.Cu")
		(net "GND")
	)
	(segment
		(start 372.240048 -96.437958)
		(end 372.29669 -96.4946)
		(width 0.254)
		(layer "B.Cu")
		(net "GND")
	)
	(segment
		(start 31.688278 -65.151)
		(end 30.988 -65.151)
		(width 0.254)
		(layer "B.Cu")
		(net "GND")
	)
	(segment
		(start 217.3986 -150.292562)
		(end 217.472006 -150.219156)
		(width 0.4064)
		(layer "B.Cu")
		(net "GND")
	)
	(segment
		(start 208.299812 -141.748764)
		(end 208.0514 -141.500352)
		(width 0.254)
		(layer "B.Cu")
		(net "GND")
	)
	(segment
		(start 55.199534 -5.621782)
		(end 55.199534 -6.63702)
		(width 0.4064)
		(layer "B.Cu")
		(net "GND")
	)
	(segment
		(start 495.237008 -50.043588)
		(end 495.615976 -49.66462)
		(width 0.254)
		(layer "B.Cu")
		(net "GND")
	)
	(segment
		(start 225.210878 -13.363956)
		(end 225.210878 -13.338556)
		(width 0.4064)
		(layer "B.Cu")
		(net "GND")
	)
	(segment
		(start 18.669 -94.3102)
		(end 18.9992 -94.6404)
		(width 0.254)
		(layer "B.Cu")
		(net "GND")
	)
	(segment
		(start 201.499978 -141.664182)
		(end 201.037952 -141.202156)
		(width 0.4064)
		(layer "B.Cu")
		(net "GND")
	)
	(segment
		(start 288.19983 -24.824182)
		(end 288.19983 -22.965156)
		(width 0.4064)
		(layer "B.Cu")
		(net "GND")
	)
	(segment
		(start 169.291 -87.1982)
		(end 168.9608 -86.868)
		(width 0.4064)
		(layer "B.Cu")
		(net "GND")
	)
	(segment
		(start 449.3387 -149.3774)
		(end 449.3387 -148.59)
		(width 0.254)
		(layer "B.Cu")
		(net "GND")
	)
	(segment
		(start 281.399996 -137.877296)
		(end 281.400504 -137.877296)
		(width 0.4064)
		(layer "B.Cu")
		(net "GND")
	)
	(segment
		(start 198.949818 -151.299164)
		(end 198.7042 -151.053546)
		(width 0.254)
		(layer "B.Cu")
		(net "GND")
	)
	(segment
		(start 55.199534 -4.808982)
		(end 55.199534 -5.621782)
		(width 0.4064)
		(layer "B.Cu")
		(net "GND")
	)
	(segment
		(start 421.390826 -24.252174)
		(end 420.878 -24.765)
		(width 0.254)
		(layer "B.Cu")
		(net "GND")
	)
	(segment
		(start 300.099984 -1.021842)
		(end 300.099984 -2.302256)
		(width 0.4064)
		(layer "B.Cu")
		(net "GND")
	)
	(segment
		(start 415.47288 -49.421542)
		(end 415.47288 -49.390808)
		(width 0.254)
		(layer "B.Cu")
		(net "GND")
	)
	(segment
		(start 294.14978 -4.808728)
		(end 294.14978 -5.621782)
		(width 0.4064)
		(layer "B.Cu")
		(net "GND")
	)
	(segment
		(start 221.899988 -7.606792)
		(end 221.899988 -5.621782)
		(width 0.4064)
		(layer "B.Cu")
		(net "GND")
	)
	(segment
		(start 31.39948 -2.314956)
		(end 31.39948 -1.021842)
		(width 0.4064)
		(layer "B.Cu")
		(net "GND")
	)
	(segment
		(start 289.899852 -13.452856)
		(end 290.71189 -12.640818)
		(width 0.4064)
		(layer "B.Cu")
		(net "GND")
	)
	(segment
		(start 484.7209 -141.4145)
		(end 484.7336 -141.4272)
		(width 0.254)
		(layer "B.Cu")
		(net "GND")
	)
	(segment
		(start 244.3099 -12.954)
		(end 243.288566 -12.954)
		(width 0.381)
		(layer "B.Cu")
		(net "GND")
	)
	(segment
		(start 173.9646 -88.392)
		(end 174.0916 -88.392)
		(width 0.4064)
		(layer "B.Cu")
		(net "GND")
	)
	(segment
		(start 407.416 -29.5148)
		(end 407.5176 -29.4132)
		(width 0.254)
		(layer "B.Cu")
		(net "GND")
	)
	(segment
		(start 317.949834 -5.621782)
		(end 317.949834 -4.317746)
		(width 0.4064)
		(layer "B.Cu")
		(net "GND")
	)
	(segment
		(start 290.73729 -139.170156)
		(end 290.74999 -139.157456)
		(width 0.4064)
		(layer "B.Cu")
		(net "GND")
	)
	(segment
		(start 416.77844 -140.843)
		(end 417.006024 -140.843)
		(width 0.381)
		(layer "B.Cu")
		(net "GND")
	)
	(segment
		(start 437.35752 -12.01928)
		(end 437.1086 -12.2682)
		(width 0.254)
		(layer "B.Cu")
		(net "GND")
	)
	(segment
		(start 278.93264 -135.587486)
		(end 278.884126 -135.538972)
		(width 0.4572)
		(layer "B.Cu")
		(net "GND")
	)
	(segment
		(start 56.899556 -7.606792)
		(end 56.899302 -7.607046)
		(width 0.4064)
		(layer "B.Cu")
		(net "GND")
	)
	(segment
		(start 449.6816 -142.8623)
		(end 449.5927 -142.9512)
		(width 0.254)
		(layer "B.Cu")
		(net "GND")
	)
	(segment
		(start 280.549858 -5.621782)
		(end 280.549858 -3.851656)
		(width 0.4064)
		(layer "B.Cu")
		(net "GND")
	)
	(segment
		(start 371.54485 -71.49338)
		(end 370.746274 -71.49338)
		(width 0.127)
		(layer "B.Cu")
		(net "GND")
	)
	(segment
		(start 213.400386 -1.021842)
		(end 213.399878 -1.021842)
		(width 0.4064)
		(layer "B.Cu")
		(net "GND")
	)
	(segment
		(start 300.061884 -12.916916)
		(end 299.249846 -13.728954)
		(width 0.4064)
		(layer "B.Cu")
		(net "GND")
	)
	(segment
		(start 234.560872 -3.762756)
		(end 234.560872 -3.737356)
		(width 0.4064)
		(layer "B.Cu")
		(net "GND")
	)
	(segment
		(start 223.599756 -151.834596)
		(end 223.599756 -150.219156)
		(width 0.4064)
		(layer "B.Cu")
		(net "GND")
	)
	(segment
		(start 376.744738 -70.38467)
		(end 376.744738 -70.295262)
		(width 0.254)
		(layer "B.Cu")
		(net "GND")
	)
	(segment
		(start 212.54974 -142.182596)
		(end 212.54974 -140.617956)
		(width 0.4064)
		(layer "B.Cu")
		(net "GND")
	)
	(segment
		(start 243.149882 -149.327362)
		(end 243.193824 -149.371304)
		(width 0.4064)
		(layer "B.Cu")
		(net "GND")
	)
	(segment
		(start 33.703768 -141.3764)
		(end 33.703768 -140.685774)
		(width 0.4064)
		(layer "B.Cu")
		(net "GND")
	)
	(segment
		(start 376.344688 -70.695566)
		(end 376.433842 -70.695566)
		(width 0.254)
		(layer "B.Cu")
		(net "GND")
	)
	(segment
		(start 299.249846 -152.078182)
		(end 299.249846 -150.308056)
		(width 0.4064)
		(layer "B.Cu")
		(net "GND")
	)
	(segment
		(start 456.040744 -35.174174)
		(end 456.040744 -36.026344)
		(width 0.254)
		(layer "B.Cu")
		(net "GND")
	)
	(segment
		(start 375.944892 -77.408532)
		(end 375.944892 -77.494892)
		(width 0.254)
		(layer "B.Cu")
		(net "GND")
	)
	(segment
		(start 232.94975 -7.607046)
		(end 232.950004 -7.606792)
		(width 0.4064)
		(layer "B.Cu")
		(net "GND")
	)
	(segment
		(start 255.862328 -145.29054)
		(end 255.862328 -144.63014)
		(width 0.4064)
		(layer "B.Cu")
		(net "GND")
	)
	(segment
		(start 470.63152 -129.1844)
		(end 470.49436 -129.32156)
		(width 0.254)
		(layer "B.Cu")
		(net "GND")
	)
	(segment
		(start 42.449496 -2.302256)
		(end 42.436796 -2.314956)
		(width 0.4064)
		(layer "B.Cu")
		(net "GND")
	)
	(segment
		(start 66.249296 -22.965156)
		(end 66.249296 -24.453596)
		(width 0.4064)
		(layer "B.Cu")
		(net "GND")
	)
	(segment
		(start 126.353824 -150.9776)
		(end 126.353824 -150.286974)
		(width 0.4064)
		(layer "B.Cu")
		(net "GND")
	)
	(segment
		(start 40.749474 -20.224242)
		(end 40.749474 -21.517356)
		(width 0.4064)
		(layer "B.Cu")
		(net "GND")
	)
	(segment
		(start 402.312632 -22.225)
		(end 402.844 -22.225)
		(width 0.254)
		(layer "B.Cu")
		(net "GND")
	)
	(segment
		(start 145.29943 -7.4676)
		(end 145.12163 -7.6454)
		(width 0.4064)
		(layer "B.Cu")
		(net "GND")
	)
	(segment
		(start 310.054244 -3.830574)
		(end 310.122062 -3.762756)
		(width 0.4064)
		(layer "B.Cu")
		(net "GND")
	)
	(segment
		(start 198.949818 -4.842764)
		(end 198.949818 -5.621782)
		(width 0.254)
		(layer "B.Cu")
		(net "GND")
	)
	(segment
		(start 445.937132 -32.4485)
		(end 445.937132 -31.932626)
		(width 0.4064)
		(layer "B.Cu")
		(net "GND")
	)
	(segment
		(start 373.544846 -75.038458)
		(end 373.544846 -75.094846)
		(width 0.254)
		(layer "B.Cu")
		(net "GND")
	)
	(segment
		(start 68.799456 -18.744946)
		(end 68.799456 -20.224242)
		(width 0.4064)
		(layer "B.Cu")
		(net "GND")
	)
	(segment
		(start 206.59979 -5.621782)
		(end 206.59979 -3.826256)
		(width 0.4064)
		(layer "B.Cu")
		(net "GND")
	)
	(segment
		(start 145.053812 -14.1224)
		(end 145.053812 -14.198346)
		(width 0.254)
		(layer "B.Cu")
		(net "GND")
	)
	(segment
		(start 368.967004 -26.360882)
		(end 368.967004 -26.362152)
		(width 0.508)
		(layer "B.Cu")
		(net "GND")
	)
	(segment
		(start 311.15 -137.877296)
		(end 311.15 -139.089892)
		(width 0.4064)
		(layer "B.Cu")
		(net "GND")
	)
	(segment
		(start 134.249414 -5.621782)
		(end 134.249414 -3.851656)
		(width 0.4064)
		(layer "B.Cu")
		(net "GND")
	)
	(segment
		(start 123.199398 -150.427182)
		(end 123.5075 -150.11908)
		(width 0.4064)
		(layer "B.Cu")
		(net "GND")
	)
	(segment
		(start 145.053812 -4.5212)
		(end 145.053812 -4.597146)
		(width 0.254)
		(layer "B.Cu")
		(net "GND")
	)
	(segment
		(start 364.677452 -41.4782)
		(end 365.379 -41.4782)
		(width 0.254)
		(layer "B.Cu")
		(net "GND")
	)
	(segment
		(start 300.061884 -11.916156)
		(end 300.087284 -11.916156)
		(width 0.4064)
		(layer "B.Cu")
		(net "GND")
	)
	(segment
		(start 64.549528 -151.265382)
		(end 64.087502 -150.803356)
		(width 0.4064)
		(layer "B.Cu")
		(net "GND")
	)
	(segment
		(start 443.405006 -41.203626)
		(end 443.405006 -40.5257)
		(width 0.3556)
		(layer "B.Cu")
		(net "GND")
	)
	(segment
		(start 45.84954 -15.222982)
		(end 45.84954 -16.23822)
		(width 0.4064)
		(layer "B.Cu")
		(net "GND")
	)
	(segment
		(start 282.24988 -15.222982)
		(end 282.24988 -14.443964)
		(width 0.254)
		(layer "B.Cu")
		(net "GND")
	)
	(segment
		(start 46.699424 -147.478496)
		(end 46.699424 -148.771356)
		(width 0.4064)
		(layer "B.Cu")
		(net "GND")
	)
	(segment
		(start 475.206568 -148.14423)
		(end 475.51721 -148.454872)
		(width 0.254)
		(layer "B.Cu")
		(net "GND")
	)
	(segment
		(start 221.04985 -9.156446)
		(end 221.04985 -10.623042)
		(width 0.4064)
		(layer "B.Cu")
		(net "GND")
	)
	(segment
		(start 217.3986 -4.5212)
		(end 217.3986 -3.836162)
		(width 0.4064)
		(layer "B.Cu")
		(net "GND")
	)
	(segment
		(start 231.249982 -15.222982)
		(end 231.249982 -14.85265)
		(width 0.4064)
		(layer "B.Cu")
		(net "GND")
	)
	(segment
		(start 381.556768 -41.896284)
		(end 381.432816 -41.772332)
		(width 0.254)
		(layer "B.Cu")
		(net "GND")
	)
	(segment
		(start 118.099332 -148.691092)
		(end 118.041928 -148.748496)
		(width 0.4064)
		(layer "B.Cu")
		(net "GND")
	)
	(segment
		(start 321.0052 -154.1272)
		(end 321.691 -154.813)
		(width 0.4064)
		(layer "B.Cu")
		(net "GND")
	)
	(segment
		(start 256.7432 -12.827)
		(end 256.529586 -12.613386)
		(width 0.508)
		(layer "B.Cu")
		(net "GND")
	)
	(segment
		(start 78.229968 -145.0086)
		(end 79.360268 -145.0086)
		(width 0.4572)
		(layer "B.Cu")
		(net "GND")
	)
	(segment
		(start 294.999918 -9.156446)
		(end 294.999918 -10.623042)
		(width 0.4064)
		(layer "B.Cu")
		(net "GND")
	)
	(segment
		(start 305.199796 -152.078182)
		(end 305.199796 -150.219156)
		(width 0.4064)
		(layer "B.Cu")
		(net "GND")
	)
	(segment
		(start 226.7458 -150.295356)
		(end 226.822 -150.219156)
		(width 0.4064)
		(layer "B.Cu")
		(net "GND")
	)
	(segment
		(start 73.437496 -23.549356)
		(end 73.899522 -24.011382)
		(width 0.4064)
		(layer "B.Cu")
		(net "GND")
	)
	(segment
		(start 289.90036 -152.078436)
		(end 289.93592 -152.042876)
		(width 0.4064)
		(layer "B.Cu")
		(net "GND")
	)
	(segment
		(start 443.908688 -141.062202)
		(end 444.246 -140.72489)
		(width 0.254)
		(layer "B.Cu")
		(net "GND")
	)
	(segment
		(start 316.249812 -13.363956)
		(end 316.249812 -15.222982)
		(width 0.4064)
		(layer "B.Cu")
		(net "GND")
	)
	(segment
		(start 204.900276 -15.222982)
		(end 204.899768 -15.222982)
		(width 0.4064)
		(layer "B.Cu")
		(net "GND")
	)
	(segment
		(start 207.437228 -21.517356)
		(end 207.411828 -21.517356)
		(width 0.4064)
		(layer "B.Cu")
		(net "GND")
	)
	(segment
		(start 282.250388 -132.876036)
		(end 282.24988 -132.875782)
		(width 0.3556)
		(layer "B.Cu")
		(net "GND")
	)
	(segment
		(start 31.174182 -56.802782)
		(end 30.988 -56.6166)
		(width 0.254)
		(layer "B.Cu")
		(net "GND")
	)
	(segment
		(start 383.77495 -102.756716)
		(end 384.554984 -102.756716)
		(width 0.3556)
		(layer "B.Cu")
		(net "GND")
	)
	(segment
		(start 433.705 -13.97)
		(end 432.6255 -13.97)
		(width 0.254)
		(layer "B.Cu")
		(net "GND")
	)
	(segment
		(start 198.949818 -142.476982)
		(end 198.949818 -141.697964)
		(width 0.254)
		(layer "B.Cu")
		(net "GND")
	)
	(segment
		(start 456.040744 -36.026344)
		(end 456.536806 -36.522406)
		(width 0.254)
		(layer "B.Cu")
		(net "GND")
	)
	(segment
		(start 214.249762 -17.208246)
		(end 214.250016 -17.207992)
		(width 0.4064)
		(layer "B.Cu")
		(net "GND")
	)
	(segment
		(start 291.354256 -140.685774)
		(end 291.422074 -140.617956)
		(width 0.4064)
		(layer "B.Cu")
		(net "GND")
	)
	(segment
		(start 11.249914 -45.310044)
		(end 12.683998 -46.744128)
		(width 0.508)
		(layer "B.Cu")
		(net "GND")
	)
	(segment
		(start 202.35037 -20.224242)
		(end 202.349862 -20.224242)
		(width 0.4064)
		(layer "B.Cu")
		(net "GND")
	)
	(segment
		(start 123.199398 -152.078436)
		(end 123.199398 -150.427182)
		(width 0.4064)
		(layer "B.Cu")
		(net "GND")
	)
	(segment
		(start 113.967768 -150.659592)
		(end 113.849404 -150.777956)
		(width 0.4064)
		(layer "B.Cu")
		(net "GND")
	)
	(segment
		(start 206.59979 -7.509002)
		(end 206.59979 -5.621782)
		(width 0.4064)
		(layer "B.Cu")
		(net "GND")
	)
	(segment
		(start 300.100492 -1.021842)
		(end 300.099984 -1.021842)
		(width 0.4064)
		(layer "B.Cu")
		(net "GND")
	)
	(segment
		(start 373.126 -74.7014)
		(end 373.207788 -74.7014)
		(width 0.254)
		(layer "B.Cu")
		(net "GND")
	)
	(segment
		(start 305.199796 -24.824182)
		(end 305.199796 -22.965156)
		(width 0.4064)
		(layer "B.Cu")
		(net "GND")
	)
	(segment
		(start 67.949318 -5.327396)
		(end 67.949572 -5.32765)
		(width 0.4064)
		(layer "B.Cu")
		(net "GND")
	)
	(segment
		(start 315.400436 -10.623042)
		(end 315.399928 -10.623042)
		(width 0.4064)
		(layer "B.Cu")
		(net "GND")
	)
	(segment
		(start 82.459068 -140.208)
		(end 81.565242 -140.208)
		(width 0.4064)
		(layer "B.Cu")
		(net "GND")
	)
	(segment
		(start 196.399912 -128.276096)
		(end 196.399912 -129.568956)
		(width 0.4064)
		(layer "B.Cu")
		(net "GND")
	)
	(segment
		(start 402.463 -148.9964)
		(end 401.931632 -148.9964)
		(width 0.4064)
		(layer "B.Cu")
		(net "GND")
	)
	(segment
		(start 303.500282 -152.078436)
		(end 303.499774 -152.078182)
		(width 0.4064)
		(layer "B.Cu")
		(net "GND")
	)
	(segment
		(start 118.099332 -11.835892)
		(end 118.099332 -10.623042)
		(width 0.4064)
		(layer "B.Cu")
		(net "GND")
	)
	(segment
		(start 203.2 -22.96541)
		(end 203.199746 -22.965156)
		(width 0.4064)
		(layer "B.Cu")
		(net "GND")
	)
	(segment
		(start 163.80206 -85.948266)
		(end 163.395406 -86.35492)
		(width 0.4064)
		(layer "B.Cu")
		(net "GND")
	)
	(segment
		(start 198.061834 -11.916156)
		(end 198.087234 -11.916156)
		(width 0.4064)
		(layer "B.Cu")
		(net "GND")
	)
	(segment
		(start 171.069 -74.041)
		(end 171.069 -73.5838)
		(width 0.254)
		(layer "B.Cu")
		(net "GND")
	)
	(segment
		(start 211.699856 -10.623042)
		(end 211.699856 -9.156446)
		(width 0.4064)
		(layer "B.Cu")
		(net "GND")
	)
	(segment
		(start 331.851 -157.226)
		(end 332.1304 -157.5054)
		(width 0.508)
		(layer "B.Cu")
		(net "GND")
	)
	(segment
		(start 382.0668 -105.815384)
		(end 382.07696 -105.805224)
		(width 0.254)
		(layer "B.Cu")
		(net "GND")
	)
	(segment
		(start 36.03752 -4.346956)
		(end 36.499546 -4.808982)
		(width 0.4064)
		(layer "B.Cu")
		(net "GND")
	)
	(segment
		(start 300.087284 -139.170156)
		(end 300.061884 -139.170156)
		(width 0.4064)
		(layer "B.Cu")
		(net "GND")
	)
	(segment
		(start 294.14978 -132.875782)
		(end 294.14978 -132.062728)
		(width 0.4064)
		(layer "B.Cu")
		(net "GND")
	)
	(segment
		(start 115.460526 -140.617956)
		(end 115.549426 -140.706856)
		(width 0.4064)
		(layer "B.Cu")
		(net "GND")
	)
	(segment
		(start 37.34943 -1.021842)
		(end 37.34943 0.444754)
		(width 0.4064)
		(layer "B.Cu")
		(net "GND")
	)
	(segment
		(start 201.499978 -5.621782)
		(end 201.499978 -6.63702)
		(width 0.4064)
		(layer "B.Cu")
		(net "GND")
	)
	(segment
		(start 373.1641 -61.704474)
		(end 373.1641 -61.6839)
		(width 0.254)
		(layer "B.Cu")
		(net "GND")
	)
	(segment
		(start 409.884118 -92.860114)
		(end 409.884118 -92.540328)
		(width 0.254)
		(layer "B.Cu")
		(net "GND")
	)
	(segment
		(start 261.2136 -1.651)
		(end 261.4676 -1.905)
		(width 0.508)
		(layer "B.Cu")
		(net "GND")
	)
	(segment
		(start 50.099468 -10.623042)
		(end 50.099468 -11.916156)
		(width 0.4064)
		(layer "B.Cu")
		(net "GND")
	)
	(segment
		(start 400.97075 -74.53122)
		(end 400.97202 -74.53122)
		(width 0.254)
		(layer "B.Cu")
		(net "GND")
	)
	(segment
		(start 292.450012 -1.021842)
		(end 292.450012 0.40005)
		(width 0.4064)
		(layer "B.Cu")
		(net "GND")
	)
	(segment
		(start 306.900326 -15.222982)
		(end 306.899818 -15.222982)
		(width 0.4064)
		(layer "B.Cu")
		(net "GND")
	)
	(segment
		(start 114.699542 -10.623042)
		(end 114.699542 -9.143746)
		(width 0.4064)
		(layer "B.Cu")
		(net "GND")
	)
	(segment
		(start 249.9106 -17.7546)
		(end 250.7615 -17.7546)
		(width 0.4064)
		(layer "B.Cu")
		(net "GND")
	)
	(segment
		(start 372.2751 -74.6887)
		(end 372.351046 -74.6887)
		(width 0.254)
		(layer "B.Cu")
		(net "GND")
	)
	(segment
		(start 59.449462 -2.314956)
		(end 59.449462 -1.021842)
		(width 0.4064)
		(layer "B.Cu")
		(net "GND")
	)
	(segment
		(start 281.387296 -11.916156)
		(end 281.361896 -11.916156)
		(width 0.4064)
		(layer "B.Cu")
		(net "GND")
	)
	(segment
		(start 227.849938 -10.623042)
		(end 227.849938 -9.20115)
		(width 0.4064)
		(layer "B.Cu")
		(net "GND")
	)
	(segment
		(start 125.749558 -139.157456)
		(end 125.736858 -139.170156)
		(width 0.4064)
		(layer "B.Cu")
		(net "GND")
	)
	(segment
		(start 227.849938 -148.691092)
		(end 227.792534 -148.748496)
		(width 0.4064)
		(layer "B.Cu")
		(net "GND")
	)
	(segment
		(start 377.75642 -66.03492)
		(end 377.75642 -66.3321)
		(width 0.254)
		(layer "B.Cu")
		(net "GND")
	)
	(segment
		(start 300.70425 -141.3764)
		(end 300.70425 -141.452346)
		(width 0.254)
		(layer "B.Cu")
		(net "GND")
	)
	(segment
		(start 69.56044 -22.965156)
		(end 69.64934 -23.054056)
		(width 0.4064)
		(layer "B.Cu")
		(net "GND")
	)
	(segment
		(start 290.73729 -21.517356)
		(end 290.74999 -21.504656)
		(width 0.4064)
		(layer "B.Cu")
		(net "GND")
	)
	(segment
		(start 146.092164 -11.893296)
		(end 146.149568 -11.835892)
		(width 0.4064)
		(layer "B.Cu")
		(net "GND")
	)
	(segment
		(start 203.2 -13.36421)
		(end 203.199746 -13.363956)
		(width 0.4064)
		(layer "B.Cu")
		(net "GND")
	)
	(segment
		(start 395.839442 -9.941052)
		(end 395.839442 -11.408918)
		(width 0.254)
		(layer "B.Cu")
		(net "GND")
	)
	(segment
		(start 321.7291 -125.004322)
		(end 322.168774 -124.564648)
		(width 0.254)
		(layer "B.Cu")
		(net "GND")
	)
	(segment
		(start 255.186434 -135.010398)
		(end 255.830578 -135.010398)
		(width 0.4572)
		(layer "B.Cu")
		(net "GND")
	)
	(segment
		(start 290.71189 -12.640818)
		(end 290.71189 -11.916156)
		(width 0.4064)
		(layer "B.Cu")
		(net "GND")
	)
	(segment
		(start 216.799922 -139.157456)
		(end 216.787222 -139.170156)
		(width 0.4064)
		(layer "B.Cu")
		(net "GND")
	)
	(segment
		(start 113.849404 -21.567648)
		(end 113.94694 -21.665184)
		(width 0.4064)
		(layer "B.Cu")
		(net "GND")
	)
	(segment
		(start 239.749838 -137.877296)
		(end 239.749838 -139.170156)
		(width 0.4064)
		(layer "B.Cu")
		(net "GND")
	)
	(segment
		(start 325.10222 -123.51512)
		(end 324.50532 -123.51512)
		(width 0.254)
		(layer "B.Cu")
		(net "GND")
	)
	(segment
		(start 394.17625 -105.332276)
		(end 394.032232 -105.188258)
		(width 0.3556)
		(layer "B.Cu")
		(net "GND")
	)
	(segment
		(start 317.949834 -152.078182)
		(end 317.949834 -150.774146)
		(width 0.4064)
		(layer "B.Cu")
		(net "GND")
	)
	(segment
		(start 135.949436 -151.299164)
		(end 135.703818 -151.053546)
		(width 0.254)
		(layer "B.Cu")
		(net "GND")
	)
	(segment
		(start 294.14978 -14.409928)
		(end 293.688008 -13.948156)
		(width 0.4064)
		(layer "B.Cu")
		(net "GND")
	)
	(segment
		(start 450.061838 -155.848812)
		(end 450.061838 -155.250134)
		(width 0.254)
		(layer "B.Cu")
		(net "GND")
	)
	(segment
		(start 141.899386 -22.965156)
		(end 141.899386 -24.824182)
		(width 0.4064)
		(layer "B.Cu")
		(net "GND")
	)
	(segment
		(start 119.799354 -132.876036)
		(end 119.799354 -132.062982)
		(width 0.3556)
		(layer "B.Cu")
		(net "GND")
	)
	(segment
		(start 421.390826 -24.158194)
		(end 421.235632 -24.003)
		(width 0.254)
		(layer "B.Cu")
		(net "GND")
	)
	(segment
		(start 215.0999 -20.224242)
		(end 215.0999 -18.744946)
		(width 0.4064)
		(layer "B.Cu")
		(net "GND")
	)
	(segment
		(start 306.899818 -152.078182)
		(end 306.899818 -150.219156)
		(width 0.4064)
		(layer "B.Cu")
		(net "GND")
	)
	(segment
		(start 49.24933 -142.131796)
		(end 49.24933 -140.617956)
		(width 0.4064)
		(layer "B.Cu")
		(net "GND")
	)
	(segment
		(start 379.9967 -46.674532)
		(end 379.579632 -47.0916)
		(width 0.254)
		(layer "B.Cu")
		(net "GND")
	)
	(segment
		(start 404.4315 -22.987)
		(end 404.4315 -23.61184)
		(width 0.254)
		(layer "B.Cu")
		(net "GND")
	)
	(segment
		(start 67.949318 -22.965156)
		(end 67.949318 -24.529796)
		(width 0.4064)
		(layer "B.Cu")
		(net "GND")
	)
	(segment
		(start 416.9664 -23.876)
		(end 416.9664 -24.511)
		(width 0.254)
		(layer "B.Cu")
		(net "GND")
	)
	(segment
		(start 201.499978 -6.63702)
		(end 201.041254 -7.095744)
		(width 0.4064)
		(layer "B.Cu")
		(net "GND")
	)
	(segment
		(start 118.041928 -11.893296)
		(end 118.099332 -11.835892)
		(width 0.4064)
		(layer "B.Cu")
		(net "GND")
	)
	(segment
		(start 294.150288 -132.876036)
		(end 294.14978 -132.875782)
		(width 0.4064)
		(layer "B.Cu")
		(net "GND")
	)
	(segment
		(start 288.19983 -15.222982)
		(end 288.19983 -17.208246)
		(width 0.4064)
		(layer "B.Cu")
		(net "GND")
	)
	(segment
		(start 300.949868 -5.621782)
		(end 300.949868 -7.4676)
		(width 0.4064)
		(layer "B.Cu")
		(net "GND")
	)
	(segment
		(start 166.16934 -147.74926)
		(end 165.5445 -148.3741)
		(width 0.254)
		(layer "B.Cu")
		(net "GND")
	)
	(segment
		(start 311.15 -18.80235)
		(end 311.092596 -18.744946)
		(width 0.4064)
		(layer "B.Cu")
		(net "GND")
	)
	(segment
		(start 218.500452 -137.877296)
		(end 218.499944 -137.877296)
		(width 0.4064)
		(layer "B.Cu")
		(net "GND")
	)
	(segment
		(start 204.900276 -142.477236)
		(end 204.899768 -142.476982)
		(width 0.4064)
		(layer "B.Cu")
		(net "GND")
	)
	(segment
		(start 222.75038 -1.021842)
		(end 222.749872 -1.021842)
		(width 0.4064)
		(layer "B.Cu")
		(net "GND")
	)
	(segment
		(start 126.353824 -4.597146)
		(end 126.599442 -4.842764)
		(width 0.254)
		(layer "B.Cu")
		(net "GND")
	)
	(segment
		(start 78.14945 -20.224242)
		(end 78.14945 -22.073362)
		(width 0.4064)
		(layer "B.Cu")
		(net "GND")
	)
	(segment
		(start 499.955566 -38.090094)
		(end 499.935246 -38.069774)
		(width 0.254)
		(layer "B.Cu")
		(net "GND")
	)
	(segment
		(start 82.459068 -12.954)
		(end 81.582768 -12.954)
		(width 0.4064)
		(layer "B.Cu")
		(net "GND")
	)
	(segment
		(start 43.29938 -14.494764)
		(end 43.29938 -15.222982)
		(width 0.254)
		(layer "B.Cu")
		(net "GND")
	)
	(segment
		(start 41.599358 -131.080256)
		(end 41.510458 -130.991356)
		(width 0.4064)
		(layer "B.Cu")
		(net "GND")
	)
	(segment
		(start 369.545108 -77.494892)
		(end 369.690904 -77.494892)
		(width 0.254)
		(layer "B.Cu")
		(net "GND")
	)
	(segment
		(start 58.599578 -132.876036)
		(end 58.599578 -132.63245)
		(width 0.4064)
		(layer "B.Cu")
		(net "GND")
	)
	(segment
		(start 279.700482 -1.021842)
		(end 279.699974 -1.021842)
		(width 0.4064)
		(layer "B.Cu")
		(net "GND")
	)
	(segment
		(start 67.949318 -3.762756)
		(end 67.949318 -5.327396)
		(width 0.4064)
		(layer "B.Cu")
		(net "GND")
	)
	(segment
		(start 146.149568 -2.234692)
		(end 146.092164 -2.292096)
		(width 0.4064)
		(layer "B.Cu")
		(net "GND")
	)
	(segment
		(start 60.299346 -25.676098)
		(end 61.111384 -26.488136)
		(width 0.4064)
		(layer "B.Cu")
		(net "GND")
	)
	(segment
		(start 234.649772 -15.222982)
		(end 234.649772 -17.110202)
		(width 0.4064)
		(layer "B.Cu")
		(net "GND")
	)
	(segment
		(start 41.599358 -7.509002)
		(end 41.599358 -5.621782)
		(width 0.4064)
		(layer "B.Cu")
		(net "GND")
	)
	(segment
		(start 72.1995 -11.835892)
		(end 72.142096 -11.893296)
		(width 0.4064)
		(layer "B.Cu")
		(net "GND")
	)
	(segment
		(start 287.350454 -10.623042)
		(end 287.349946 -10.623042)
		(width 0.4064)
		(layer "B.Cu")
		(net "GND")
	)
	(segment
		(start 406.003506 -32.6644)
		(end 405.598376 -32.6644)
		(width 0.254)
		(layer "B.Cu")
		(net "GND")
	)
	(segment
		(start 242.300506 -5.621782)
		(end 242.299998 -5.621782)
		(width 0.4064)
		(layer "B.Cu")
		(net "GND")
	)
	(segment
		(start 196.893434 -79.912464)
		(end 196.388736 -79.912464)
		(width 0.254)
		(layer "B.Cu")
		(net "GND")
	)
	(segment
		(start 394.95984 -38.9382)
		(end 394.95984 -39.497)
		(width 0.254)
		(layer "B.Cu")
		(net "GND")
	)
	(segment
		(start 230.400352 -10.623042)
		(end 230.399844 -10.623042)
		(width 0.4064)
		(layer "B.Cu")
		(net "GND")
	)
	(segment
		(start 282.004262 -151.053546)
		(end 282.004262 -150.261574)
		(width 0.254)
		(layer "B.Cu")
		(net "GND")
	)
	(segment
		(start 417.7665 -30.988)
		(end 419.436804 -30.988)
		(width 0.254)
		(layer "B.Cu")
		(net "GND")
	)
	(segment
		(start 196.880734 -96.168464)
		(end 196.515736 -96.168464)
		(width 0.254)
		(layer "B.Cu")
		(net "GND")
	)
	(segment
		(start 117.00383 -23.007574)
		(end 117.071648 -22.939756)
		(width 0.4064)
		(layer "B.Cu")
		(net "GND")
	)
	(segment
		(start 124.89942 -15.222982)
		(end 124.89942 -17.110202)
		(width 0.4064)
		(layer "B.Cu")
		(net "GND")
	)
	(segment
		(start 198.7042 -151.053546)
		(end 198.7042 -150.9776)
		(width 0.254)
		(layer "B.Cu")
		(net "GND")
	)
	(segment
		(start 31.39948 0.457454)
		(end 31.341568 0.515366)
		(width 0.381)
		(layer "B.Cu")
		(net "GND")
	)
	(segment
		(start 433.8955 -41.8973)
		(end 434.0098 -42.0116)
		(width 0.381)
		(layer "B.Cu")
		(net "GND")
	)
	(segment
		(start 300.772068 -150.219156)
		(end 300.70425 -150.286974)
		(width 0.4064)
		(layer "B.Cu")
		(net "GND")
	)
	(segment
		(start 309.449978 -137.877296)
		(end 309.450486 -137.877296)
		(width 0.4064)
		(layer "B.Cu")
		(net "GND")
	)
	(segment
		(start 31.341568 -155.542234)
		(end 31.39948 -155.600146)
		(width 0.4064)
		(layer "B.Cu")
		(net "GND")
	)
	(segment
		(start 117.00383 -3.830574)
		(end 117.00383 -4.5212)
		(width 0.4064)
		(layer "B.Cu")
		(net "GND")
	)
	(segment
		(start 239.749838 -1.021842)
		(end 239.749838 0.444754)
		(width 0.4064)
		(layer "B.Cu")
		(net "GND")
	)
	(segment
		(start 205.749906 -137.877296)
		(end 205.749906 -139.170156)
		(width 0.4064)
		(layer "B.Cu")
		(net "GND")
	)
	(segment
		(start 113.849404 -128.276096)
		(end 113.849404 -130.124962)
		(width 0.4064)
		(layer "B.Cu")
		(net "GND")
	)
	(segment
		(start 291.600382 -151.299672)
		(end 291.354256 -151.053546)
		(width 0.254)
		(layer "B.Cu")
		(net "GND")
	)
	(segment
		(start 304.349912 -10.623042)
		(end 304.349912 -9.156446)
		(width 0.4064)
		(layer "B.Cu")
		(net "GND")
	)
	(segment
		(start 218.499944 -11.835892)
		(end 218.44254 -11.893296)
		(width 0.4064)
		(layer "B.Cu")
		(net "GND")
	)
	(segment
		(start 212.54974 -132.581396)
		(end 212.54974 -131.016756)
		(width 0.4064)
		(layer "B.Cu")
		(net "GND")
	)
	(segment
		(start 67.949572 -24.53005)
		(end 67.949572 -24.824182)
		(width 0.4064)
		(layer "B.Cu")
		(net "GND")
	)
	(segment
		(start 61.745368 -151.0538)
		(end 61.745368 -150.9522)
		(width 0.254)
		(layer "B.Cu")
		(net "GND")
	)
	(segment
		(start 278.9682 -140.4874)
		(end 278.3332 -140.4874)
		(width 0.4572)
		(layer "B.Cu")
		(net "GND")
	)
	(segment
		(start 313.699906 -128.276096)
		(end 313.699906 -129.568956)
		(width 0.4064)
		(layer "B.Cu")
		(net "GND")
	)
	(segment
		(start 317.146432 -135.382)
		(end 317.09995 -135.335518)
		(width 0.4064)
		(layer "B.Cu")
		(net "GND")
	)
	(segment
		(start 233.008932 -84.7852)
		(end 233.036618 -84.812886)
		(width 0.1524)
		(layer "B.Cu")
		(net "GND")
	)
	(segment
		(start 234.551728 -7.607046)
		(end 234.649772 -7.509002)
		(width 0.4064)
		(layer "B.Cu")
		(net "GND")
	)
	(segment
		(start 208.30032 -132.876036)
		(end 208.299812 -132.875782)
		(width 0.254)
		(layer "B.Cu")
		(net "GND")
	)
	(segment
		(start 315.399928 -21.517356)
		(end 315.399928 -20.224242)
		(width 0.4064)
		(layer "B.Cu")
		(net "GND")
	)
	(segment
		(start 60.210446 -3.762756)
		(end 60.299346 -3.851656)
		(width 0.4064)
		(layer "B.Cu")
		(net "GND")
	)
	(segment
		(start 459.16723 -26.543)
		(end 459.16723 -25.882854)
		(width 0.508)
		(layer "B.Cu")
		(net "GND")
	)
	(segment
		(start 411.662118 -88.826594)
		(end 411.662118 -89.411302)
		(width 0.254)
		(layer "B.Cu")
		(net "GND")
	)
	(segment
		(start 211.699856 -11.916156)
		(end 211.699856 -10.623042)
		(width 0.4064)
		(layer "B.Cu")
		(net "GND")
	)
	(segment
		(start 145.053812 -3.830574)
		(end 145.053812 -4.5212)
		(width 0.4064)
		(layer "B.Cu")
		(net "GND")
	)
	(segment
		(start 132.549392 -13.363956)
		(end 132.549392 -15.222982)
		(width 0.4064)
		(layer "B.Cu")
		(net "GND")
	)
	(segment
		(start 129.999486 -20.224242)
		(end 129.999486 -21.517356)
		(width 0.4064)
		(layer "B.Cu")
		(net "GND")
	)
	(segment
		(start 117.071648 -17.2466)
		(end 117.249448 -17.0688)
		(width 0.4064)
		(layer "B.Cu")
		(net "GND")
	)
	(segment
		(start 92.39504 -134.440422)
		(end 92.152978 -134.440422)
		(width 0.381)
		(layer "B.Cu")
		(net "GND")
	)
	(segment
		(start 291.354256 -141.452346)
		(end 291.354256 -141.3764)
		(width 0.254)
		(layer "B.Cu")
		(net "GND")
	)
	(segment
		(start 45.84954 -16.23822)
		(end 45.390816 -16.696944)
		(width 0.4064)
		(layer "B.Cu")
		(net "GND")
	)
	(segment
		(start 121.499376 -152.078436)
		(end 121.499376 -150.219156)
		(width 0.4064)
		(layer "B.Cu")
		(net "GND")
	)
	(segment
		(start 221.899734 -24.478996)
		(end 221.899734 -22.965156)
		(width 0.4064)
		(layer "B.Cu")
		(net "GND")
	)
	(segment
		(start 226.7458 -13.440156)
		(end 226.822 -13.363956)
		(width 0.4064)
		(layer "B.Cu")
		(net "GND")
	)
	(segment
		(start 127.392176 -18.744946)
		(end 127.44958 -18.80235)
		(width 0.4064)
		(layer "B.Cu")
		(net "GND")
	)
	(segment
		(start 223.600518 -152.078436)
		(end 223.60001 -152.078182)
		(width 0.4064)
		(layer "B.Cu")
		(net "GND")
	)
	(segment
		(start 51.79949 -20.224242)
		(end 51.79949 -21.504656)
		(width 0.4064)
		(layer "B.Cu")
		(net "GND")
	)
	(segment
		(start 151.24938 -5.621782)
		(end 151.24938 -3.762756)
		(width 0.4064)
		(layer "B.Cu")
		(net "GND")
	)
	(segment
		(start 382.7653 -57.0865)
		(end 380.67488 -57.0865)
		(width 0.254)
		(layer "B.Cu")
		(net "GND")
	)
	(segment
		(start 78.589886 -64.262)
		(end 78.338172 -64.010286)
		(width 0.254)
		(layer "B.Cu")
		(net "GND")
	)
	(segment
		(start 384.31724 -81.06918)
		(end 384.74396 -81.06918)
		(width 0.254)
		(layer "B.Cu")
		(net "GND")
	)
	(segment
		(start 402.679408 -93.755718)
		(end 402.455888 -93.979238)
		(width 0.254)
		(layer "B.Cu")
		(net "GND")
	)
	(segment
		(start 232.950004 -7.606792)
		(end 232.950004 -5.621782)
		(width 0.4064)
		(layer "B.Cu")
		(net "GND")
	)
	(segment
		(start 232.100374 -137.877296)
		(end 232.099866 -137.877296)
		(width 0.4064)
		(layer "B.Cu")
		(net "GND")
	)
	(segment
		(start 347.132148 -91.380818)
		(end 347.132148 -89.9033)
		(width 0.2032)
		(layer "B.Cu")
		(net "GND")
	)
	(segment
		(start 52.398168 -4.572254)
		(end 52.398168 -4.5212)
		(width 0.254)
		(layer "B.Cu")
		(net "GND")
	)
	(segment
		(start 300.949868 -151.299164)
		(end 300.949868 -152.078182)
		(width 0.254)
		(layer "B.Cu")
		(net "GND")
	)
	(segment
		(start 226.822 -7.6454)
		(end 226.9998 -7.4676)
		(width 0.4064)
		(layer "B.Cu")
		(net "GND")
	)
	(segment
		(start 212.549994 -17.207992)
		(end 212.549994 -15.222982)
		(width 0.4064)
		(layer "B.Cu")
		(net "GND")
	)
	(segment
		(start 388.972806 -7.859014)
		(end 388.235952 -7.12216)
		(width 0.254)
		(layer "B.Cu")
		(net "GND")
	)
	(segment
		(start 278.849836 -131.575556)
		(end 278.9682 -131.457192)
		(width 0.4064)
		(layer "B.Cu")
		(net "GND")
	)
	(segment
		(start 135.703818 -131.851146)
		(end 135.703818 -131.7752)
		(width 0.254)
		(layer "B.Cu")
		(net "GND")
	)
	(segment
		(start 31.713678 -81.3816)
		(end 31.0134 -81.3816)
		(width 0.254)
		(layer "B.Cu")
		(net "GND")
	)
	(segment
		(start 157.046168 -145.8722)
		(end 157.046168 -145.333212)
		(width 0.4064)
		(layer "B.Cu")
		(net "GND")
	)
	(segment
		(start 371.22227 -56.97728)
		(end 370.3955 -56.97728)
		(width 0.254)
		(layer "B.Cu")
		(net "GND")
	)
	(segment
		(start 202.349862 -2.314956)
		(end 202.349862 -1.021842)
		(width 0.4064)
		(layer "B.Cu")
		(net "GND")
	)
	(segment
		(start 371.54358 -73.095358)
		(end 371.545358 -73.095358)
		(width 0.254)
		(layer "B.Cu")
		(net "GND")
	)
	(segment
		(start 26.3144 -17.723612)
		(end 26.3144 -18.3642)
		(width 0.254)
		(layer "B.Cu")
		(net "GND")
	)
	(segment
		(start 71.349362 -24.824182)
		(end 71.349362 -25.937972)
		(width 0.4064)
		(layer "B.Cu")
		(net "GND")
	)
	(segment
		(start 17.3482 -82.706972)
		(end 17.3482 -83.439)
		(width 0.254)
		(layer "B.Cu")
		(net "GND")
	)
	(segment
		(start 294.14978 -26.224484)
		(end 293.69131 -26.682954)
		(width 0.4064)
		(layer "B.Cu")
		(net "GND")
	)
	(segment
		(start 441.347606 -16.164306)
		(end 441.347606 -15.681706)
		(width 0.254)
		(layer "B.Cu")
		(net "GND")
	)
	(segment
		(start 146.149568 -10.623042)
		(end 146.149568 -9.20115)
		(width 0.4064)
		(layer "B.Cu")
		(net "GND")
	)
	(segment
		(start 56.049418 -9.156446)
		(end 56.049418 -10.623042)
		(width 0.4064)
		(layer "B.Cu")
		(net "GND")
	)
	(segment
		(start 290.750498 -1.021842)
		(end 290.74999 -1.021842)
		(width 0.4064)
		(layer "B.Cu")
		(net "GND")
	)
	(segment
		(start 55.199534 -142.477236)
		(end 55.199534 -141.664182)
		(width 0.4064)
		(layer "B.Cu")
		(net "GND")
	)
	(segment
		(start 105.9561 -140.208)
		(end 107.027472 -140.208)
		(width 0.4064)
		(layer "B.Cu")
		(net "GND")
	)
	(segment
		(start 306.900326 -5.621782)
		(end 306.899818 -5.621782)
		(width 0.4064)
		(layer "B.Cu")
		(net "GND")
	)
	(segment
		(start 303.499774 -142.476982)
		(end 303.499774 -141.663928)
		(width 0.4064)
		(layer "B.Cu")
		(net "GND")
	)
	(segment
		(start 416.290252 -39.186358)
		(end 416.839146 -39.735252)
		(width 0.4572)
		(layer "B.Cu")
		(net "GND")
	)
	(segment
		(start 417.032694 -39.9288)
		(end 416.839146 -39.735252)
		(width 0.4572)
		(layer "B.Cu")
		(net "GND")
	)
	(segment
		(start 235.49991 -20.224242)
		(end 235.49991 -21.479256)
		(width 0.4064)
		(layer "B.Cu")
		(net "GND")
	)
	(segment
		(start 447.679826 -143.965422)
		(end 446.87998 -143.965422)
		(width 0.254)
		(layer "B.Cu")
		(net "GND")
	)
	(segment
		(start 484.847138 -19.50466)
		(end 483.802944 -18.460466)
		(width 0.254)
		(layer "B.Cu")
		(net "GND")
	)
	(segment
		(start 97.851976 -128.022858)
		(end 97.42932 -127.600202)
		(width 0.381)
		(layer "B.Cu")
		(net "GND")
	)
	(segment
		(start 300.949868 -4.842764)
		(end 300.949868 -5.621782)
		(width 0.254)
		(layer "B.Cu")
		(net "GND")
	)
	(segment
		(start 301.800006 -137.877296)
		(end 301.800006 -139.089892)
		(width 0.4064)
		(layer "B.Cu")
		(net "GND")
	)
	(segment
		(start 208.30032 -142.477236)
		(end 208.299812 -142.476982)
		(width 0.254)
		(layer "B.Cu")
		(net "GND")
	)
	(segment
		(start 308.809644 -150.219156)
		(end 308.59984 -150.42896)
		(width 0.4064)
		(layer "B.Cu")
		(net "GND")
	)
	(segment
		(start 68.799456 -10.623042)
		(end 68.799456 -11.916156)
		(width 0.4064)
		(layer "B.Cu")
		(net "GND")
	)
	(segment
		(start 144.436846 -2.314956)
		(end 144.411446 -2.314956)
		(width 0.4064)
		(layer "B.Cu")
		(net "GND")
	)
	(segment
		(start 217.650314 -24.824182)
		(end 217.649806 -24.824182)
		(width 0.254)
		(layer "B.Cu")
		(net "GND")
	)
	(segment
		(start 386.08 -47.244)
		(end 385.454144 -47.244)
		(width 0.254)
		(layer "B.Cu")
		(net "GND")
	)
	(segment
		(start 495.45748 -129.48412)
		(end 495.9096 -129.032)
		(width 0.254)
		(layer "B.Cu")
		(net "GND")
	)
	(segment
		(start 303.499774 -151.265128)
		(end 303.038002 -150.803356)
		(width 0.4064)
		(layer "B.Cu")
		(net "GND")
	)
	(segment
		(start 272.415 4.064)
		(end 272.415 3.81)
		(width 0.508)
		(layer "B.Cu")
		(net "GND")
	)
	(segment
		(start 61.999368 -5.621782)
		(end 61.999368 -7.4676)
		(width 0.4064)
		(layer "B.Cu")
		(net "GND")
	)
	(segment
		(start 371.5258 -56.3118)
		(end 371.5258 -56.67375)
		(width 0.254)
		(layer "B.Cu")
		(net "GND")
	)
	(segment
		(start 214.250524 -132.876036)
		(end 214.250016 -132.875782)
		(width 0.4064)
		(layer "B.Cu")
		(net "GND")
	)
	(segment
		(start 221.04985 -20.224242)
		(end 221.04985 -18.757646)
		(width 0.4064)
		(layer "B.Cu")
		(net "GND")
	)
	(segment
		(start 208.0514 -14.246352)
		(end 208.0514 -13.434568)
		(width 0.4064)
		(layer "B.Cu")
		(net "GND")
	)
	(segment
		(start 299.160946 -3.737356)
		(end 299.160946 -3.762756)
		(width 0.4064)
		(layer "B.Cu")
		(net "GND")
	)
	(segment
		(start 70.499478 0.444754)
		(end 70.499478 -1.021842)
		(width 0.4064)
		(layer "B.Cu")
		(net "GND")
	)
	(segment
		(start 278.849836 -11.857736)
		(end 278.92375 -11.93165)
		(width 0.4064)
		(layer "B.Cu")
		(net "GND")
	)
	(segment
		(start 62.792102 -148.748496)
		(end 62.792102 -148.767292)
		(width 0.4064)
		(layer "B.Cu")
		(net "GND")
	)
	(segment
		(start 317.100458 -137.877296)
		(end 317.09995 -137.877296)
		(width 0.4064)
		(layer "B.Cu")
		(net "GND")
	)
	(segment
		(start 498.792754 -38.620446)
		(end 498.792754 -39.702486)
		(width 0.254)
		(layer "B.Cu")
		(net "GND")
	)
	(segment
		(start 227.792534 -11.912092)
		(end 227.792534 -11.893296)
		(width 0.4064)
		(layer "B.Cu")
		(net "GND")
	)
	(segment
		(start 402.239734 -22.152102)
		(end 402.312632 -22.225)
		(width 0.254)
		(layer "B.Cu")
		(net "GND")
	)
	(segment
		(start 279.699974 -145.998946)
		(end 279.699974 -147.478496)
		(width 0.4064)
		(layer "B.Cu")
		(net "GND")
	)
	(segment
		(start 240.600484 -5.621782)
		(end 240.599976 -5.621782)
		(width 0.4064)
		(layer "B.Cu")
		(net "GND")
	)
	(segment
		(start 348.234 -82.6516)
		(end 348.234 -81.8896)
		(width 0.254)
		(layer "B.Cu")
		(net "GND")
	)
	(segment
		(start 61.999368 -142.477236)
		(end 61.999368 -141.7066)
		(width 0.254)
		(layer "B.Cu")
		(net "GND")
	)
	(segment
		(start 299.249846 -25.683718)
		(end 300.061884 -26.495756)
		(width 0.4064)
		(layer "B.Cu")
		(net "GND")
	)
	(segment
		(start 382.54686 -82.423)
		(end 383.35712 -81.61274)
		(width 0.254)
		(layer "B.Cu")
		(net "GND")
	)
	(segment
		(start 151.24938 -152.078436)
		(end 151.24938 -150.219156)
		(width 0.4064)
		(layer "B.Cu")
		(net "GND")
	)
	(segment
		(start 59.449462 -128.276096)
		(end 59.449462 -129.568956)
		(width 0.4064)
		(layer "B.Cu")
		(net "GND")
	)
	(segment
		(start 416.179 -23.876)
		(end 416.179 -24.511)
		(width 0.254)
		(layer "B.Cu")
		(net "GND")
	)
	(segment
		(start 238.899954 -26.22423)
		(end 238.44123 -26.682954)
		(width 0.4064)
		(layer "B.Cu")
		(net "GND")
	)
	(segment
		(start 279.699974 -137.877296)
		(end 279.699974 -137.877042)
		(width 0.4064)
		(layer "B.Cu")
		(net "GND")
	)
	(segment
		(start 69.64934 -15.222982)
		(end 69.64934 -17.110202)
		(width 0.4064)
		(layer "B.Cu")
		(net "GND")
	)
	(segment
		(start 196.40042 -10.623042)
		(end 196.399912 -10.623042)
		(width 0.4064)
		(layer "B.Cu")
		(net "GND")
	)
	(segment
		(start 416.71494 -140.9065)
		(end 416.77844 -140.843)
		(width 0.381)
		(layer "B.Cu")
		(net "GND")
	)
	(segment
		(start 206.59979 -17.110202)
		(end 206.59979 -15.222982)
		(width 0.4064)
		(layer "B.Cu")
		(net "GND")
	)
	(segment
		(start 52.398168 -150.9776)
		(end 52.398168 -150.292562)
		(width 0.4064)
		(layer "B.Cu")
		(net "GND")
	)
	(segment
		(start 56.899302 -5.276596)
		(end 56.899556 -5.27685)
		(width 0.4064)
		(layer "B.Cu")
		(net "GND")
	)
	(segment
		(start 471.14206 -129.1844)
		(end 470.63152 -129.1844)
		(width 0.254)
		(layer "B.Cu")
		(net "GND")
	)
	(segment
		(start 25.39746 3.05054)
		(end 25.171908 3.05054)
		(width 0.4064)
		(layer "B.Cu")
		(net "GND")
	)
	(segment
		(start 47.549562 -5.621782)
		(end 47.549562 -7.606792)
		(width 0.4064)
		(layer "B.Cu")
		(net "GND")
	)
	(segment
		(start 33.949386 -142.477236)
		(end 33.949386 -141.697964)
		(width 0.254)
		(layer "B.Cu")
		(net "GND")
	)
	(segment
		(start 125.736858 -11.916156)
		(end 125.749558 -11.903456)
		(width 0.4064)
		(layer "B.Cu")
		(net "GND")
	)
	(segment
		(start 73.899522 -142.477236)
		(end 73.899522 -141.664182)
		(width 0.4064)
		(layer "B.Cu")
		(net "GND")
	)
	(segment
		(start 201.499978 -16.23822)
		(end 201.499978 -15.222982)
		(width 0.4064)
		(layer "B.Cu")
		(net "GND")
	)
	(segment
		(start 215.860884 -140.617956)
		(end 215.860884 -140.592556)
		(width 0.4064)
		(layer "B.Cu")
		(net "GND")
	)
	(segment
		(start 447.079878 -151.953722)
		(end 446.803018 -151.676862)
		(width 0.254)
		(layer "B.Cu")
		(net "GND")
	)
	(segment
		(start 32.249364 -4.514342)
		(end 32.160464 -4.425442)
		(width 0.4064)
		(layer "B.Cu")
		(net "GND")
	)
	(segment
		(start 94.8436 -150.8252)
		(end 94.8817 -150.7871)
		(width 0.4572)
		(layer "B.Cu")
		(net "GND")
	)
	(segment
		(start 79.360268 -8.1534)
		(end 78.255368 -8.1534)
		(width 0.4572)
		(layer "B.Cu")
		(net "GND")
	)
	(segment
		(start 300.70425 -131.851146)
		(end 300.949868 -132.096764)
		(width 0.254)
		(layer "B.Cu")
		(net "GND")
	)
	(segment
		(start 198.7042 -13.431774)
		(end 198.7042 -14.198346)
		(width 0.254)
		(layer "B.Cu")
		(net "GND")
	)
	(segment
		(start 368.975386 -47.827184)
		(end 368.975386 -47.643034)
		(width 0.254)
		(layer "B.Cu")
		(net "GND")
	)
	(segment
		(start 208.0514 -23.023068)
		(end 208.122012 -22.952456)
		(width 0.254)
		(layer "B.Cu")
		(net "GND")
	)
	(segment
		(start 272.027904 -8.1534)
		(end 270.956532 -8.1534)
		(width 0.381)
		(layer "B.Cu")
		(net "GND")
	)
	(segment
		(start 150.399496 -128.276096)
		(end 150.399496 -129.568956)
		(width 0.4064)
		(layer "B.Cu")
		(net "GND")
	)
	(segment
		(start 113.849404 -9.131046)
		(end 113.849404 -10.623042)
		(width 0.4064)
		(layer "B.Cu")
		(net "GND")
	)
	(segment
		(start 114.699542 -129.568956)
		(end 114.699542 -128.276096)
		(width 0.4064)
		(layer "B.Cu")
		(net "GND")
	)
	(segment
		(start 405.9174 -33.1216)
		(end 406.003506 -33.035494)
		(width 0.254)
		(layer "B.Cu")
		(net "GND")
	)
	(segment
		(start 61.149484 -9.156446)
		(end 61.149484 -10.623042)
		(width 0.4064)
		(layer "B.Cu")
		(net "GND")
	)
	(segment
		(start 222.75038 -10.623042)
		(end 222.749872 -10.623042)
		(width 0.4064)
		(layer "B.Cu")
		(net "GND")
	)
	(segment
		(start 309.437278 -21.517356)
		(end 309.449978 -21.504656)
		(width 0.4064)
		(layer "B.Cu")
		(net "GND")
	)
	(segment
		(start 131.699508 0.444754)
		(end 131.699508 -1.021842)
		(width 0.4064)
		(layer "B.Cu")
		(net "GND")
	)
	(segment
		(start 416.290252 -38.934644)
		(end 416.290252 -39.186358)
		(width 0.4572)
		(layer "B.Cu")
		(net "GND")
	)
	(segment
		(start 406.8572 -29.5148)
		(end 407.416 -29.5148)
		(width 0.254)
		(layer "B.Cu")
		(net "GND")
	)
	(segment
		(start 291.599874 -132.875782)
		(end 291.599874 -132.096764)
		(width 0.254)
		(layer "B.Cu")
		(net "GND")
	)
	(segment
		(start 371.000274 -98.962464)
		(end 369.80876 -98.962464)
		(width 0.254)
		(layer "B.Cu")
		(net "GND")
	)
	(segment
		(start 33.099502 -18.757646)
		(end 33.099502 -20.224242)
		(width 0.4064)
		(layer "B.Cu")
		(net "GND")
	)
	(segment
		(start 373.73814 -83.521296)
		(end 373.244872 -83.521296)
		(width 0.254)
		(layer "B.Cu")
		(net "GND")
	)
	(segment
		(start 395.351254 -9.452864)
		(end 395.839442 -9.941052)
		(width 0.254)
		(layer "B.Cu")
		(net "GND")
	)
	(segment
		(start 317.146432 -18.711164)
		(end 317.146432 -17.78)
		(width 0.4064)
		(layer "B.Cu")
		(net "GND")
	)
	(segment
		(start 198.099934 -147.478496)
		(end 198.099934 -148.758656)
		(width 0.4064)
		(layer "B.Cu")
		(net "GND")
	)
	(segment
		(start 410.633418 -93.904816)
		(end 410.889196 -94.160594)
		(width 0.254)
		(layer "B.Cu")
		(net "GND")
	)
	(segment
		(start 164.4904 -88.392)
		(end 164.211 -88.1126)
		(width 0.4064)
		(layer "B.Cu")
		(net "GND")
	)
	(segment
		(start 311.15 -147.478496)
		(end 311.150508 -147.478496)
		(width 0.4064)
		(layer "B.Cu")
		(net "GND")
	)
	(segment
		(start 457.495656 -20.32)
		(end 457.2 -20.32)
		(width 0.254)
		(layer "B.Cu")
		(net "GND")
	)
	(segment
		(start 374.4722 -155.9052)
		(end 374.856248 -155.521152)
		(width 0.4064)
		(layer "B.Cu")
		(net "GND")
	)
	(segment
		(start 232.94975 -151.783796)
		(end 232.94975 -150.219156)
		(width 0.4064)
		(layer "B.Cu")
		(net "GND")
	)
	(segment
		(start 203.200508 -24.824182)
		(end 203.2 -24.824182)
		(width 0.4064)
		(layer "B.Cu")
		(net "GND")
	)
	(segment
		(start 33.099502 -10.623042)
		(end 33.099502 -11.903456)
		(width 0.4064)
		(layer "B.Cu")
		(net "GND")
	)
	(segment
		(start 292.392608 -21.494496)
		(end 292.450012 -21.437092)
		(width 0.4064)
		(layer "B.Cu")
		(net "GND")
	)
	(segment
		(start 300.100492 -147.478496)
		(end 300.099984 -147.478496)
		(width 0.4064)
		(layer "B.Cu")
		(net "GND")
	)
	(segment
		(start 377.3043 -60.8965)
		(end 376.1105 -60.8965)
		(width 0.254)
		(layer "B.Cu")
		(net "GND")
	)
	(segment
		(start 145.29943 -17.0688)
		(end 145.12163 -17.2466)
		(width 0.4064)
		(layer "B.Cu")
		(net "GND")
	)
	(segment
		(start 244.25402 -87.46236)
		(end 244.25402 -86.57336)
		(width 0.254)
		(layer "B.Cu")
		(net "GND")
	)
	(segment
		(start 279.700482 -137.877296)
		(end 279.699974 -137.877296)
		(width 0.4064)
		(layer "B.Cu")
		(net "GND")
	)
	(segment
		(start 214.250016 -142.476982)
		(end 214.250016 -142.13205)
		(width 0.4064)
		(layer "B.Cu")
		(net "GND")
	)
	(segment
		(start 46.699424 -137.877296)
		(end 46.699424 -139.170156)
		(width 0.4064)
		(layer "B.Cu")
		(net "GND")
	)
	(segment
		(start 129.999486 -11.916156)
		(end 129.999486 -10.623042)
		(width 0.4064)
		(layer "B.Cu")
		(net "GND")
	)
	(segment
		(start 243.9162 -149.8092)
		(end 243.6114 -150.114)
		(width 0.4572)
		(layer "B.Cu")
		(net "GND")
	)
	(segment
		(start 448.9958 -142.9512)
		(end 448.818 -143.129)
		(width 0.254)
		(layer "B.Cu")
		(net "GND")
	)
	(segment
		(start 126.599442 -151.299164)
		(end 126.353824 -151.053546)
		(width 0.254)
		(layer "B.Cu")
		(net "GND")
	)
	(segment
		(start 394.93825 -110.25505)
		(end 395.16685 -110.48365)
		(width 0.254)
		(layer "B.Cu")
		(net "GND")
	)
	(segment
		(start 195.12153 -144.37487)
		(end 194.53733 -144.37487)
		(width 0.4064)
		(layer "B.Cu")
		(net "GND")
	)
	(segment
		(start 109.2581 -12.954)
		(end 110.111032 -12.954)
		(width 0.4064)
		(layer "B.Cu")
		(net "GND")
	)
	(segment
		(start 23.803356 -31.679896)
		(end 22.637496 -31.679896)
		(width 0.508)
		(layer "B.Cu")
		(net "GND")
	)
	(segment
		(start 234.560872 -131.016756)
		(end 234.560872 -130.991356)
		(width 0.4064)
		(layer "B.Cu")
		(net "GND")
	)
	(segment
		(start 52.398168 -14.173454)
		(end 52.649374 -14.42466)
		(width 0.254)
		(layer "B.Cu")
		(net "GND")
	)
	(segment
		(start 298.399962 -147.478496)
		(end 298.399962 -148.771356)
		(width 0.4064)
		(layer "B.Cu")
		(net "GND")
	)
	(segment
		(start 121.499376 -5.621782)
		(end 121.499376 -3.762756)
		(width 0.4064)
		(layer "B.Cu")
		(net "GND")
	)
	(segment
		(start 500.377714 -39.702486)
		(end 500.6594 -39.4208)
		(width 0.254)
		(layer "B.Cu")
		(net "GND")
	)
	(segment
		(start 289.899852 -7.509002)
		(end 289.899852 -5.621782)
		(width 0.4064)
		(layer "B.Cu")
		(net "GND")
	)
	(segment
		(start 234.649772 -142.476982)
		(end 234.649772 -140.706856)
		(width 0.4064)
		(layer "B.Cu")
		(net "GND")
	)
	(segment
		(start 114.822224 -126.363984)
		(end 114.5413 -126.08306)
		(width 0.508)
		(layer "B.Cu")
		(net "GND")
	)
	(segment
		(start 410.690822 -35.758628)
		(end 410.616146 -35.683952)
		(width 0.4572)
		(layer "B.Cu")
		(net "GND")
	)
	(segment
		(start 283.099764 -10.623042)
		(end 283.099764 -11.835892)
		(width 0.4064)
		(layer "B.Cu")
		(net "GND")
	)
	(segment
		(start 76.449428 -1.021842)
		(end 76.449428 0.444754)
		(width 0.4064)
		(layer "B.Cu")
		(net "GND")
	)
	(segment
		(start 395.42974 -44.900088)
		(end 395.639036 -44.690792)
		(width 0.254)
		(layer "B.Cu")
		(net "GND")
	)
	(segment
		(start 278.850344 -10.623042)
		(end 278.849836 -10.623042)
		(width 0.4064)
		(layer "B.Cu")
		(net "GND")
	)
	(segment
		(start 313.699906 -1.021842)
		(end 313.699906 -2.314956)
		(width 0.4064)
		(layer "B.Cu")
		(net "GND")
	)
	(segment
		(start 405.262588 -32.328612)
		(end 405.262588 -32.046672)
		(width 0.254)
		(layer "B.Cu")
		(net "GND")
	)
	(segment
		(start 215.949784 -13.452856)
		(end 215.860884 -13.363956)
		(width 0.4064)
		(layer "B.Cu")
		(net "GND")
	)
	(segment
		(start 135.061452 -12.916916)
		(end 135.061452 -11.916156)
		(width 0.4064)
		(layer "B.Cu")
		(net "GND")
	)
	(segment
		(start 393.722352 -26.032714)
		(end 393.43457 -25.744932)
		(width 0.254)
		(layer "B.Cu")
		(net "GND")
	)
	(segment
		(start 67.949318 -142.182596)
		(end 67.949318 -140.617956)
		(width 0.4064)
		(layer "B.Cu")
		(net "GND")
	)
	(segment
		(start 402.239734 -22.152102)
		(end 402.166836 -22.225)
		(width 0.254)
		(layer "B.Cu")
		(net "GND")
	)
	(segment
		(start 198.949818 -15.222982)
		(end 198.949818 -17.0688)
		(width 0.4064)
		(layer "B.Cu")
		(net "GND")
	)
	(segment
		(start 207.437228 -139.170156)
		(end 207.411828 -139.170156)
		(width 0.4064)
		(layer "B.Cu")
		(net "GND")
	)
	(segment
		(start 274.258532 -149.8092)
		(end 275.109432 -149.8092)
		(width 0.4572)
		(layer "B.Cu")
		(net "GND")
	)
	(segment
		(start 84.70138 -126.77394)
		(end 88.24976 -126.77394)
		(width 0.254)
		(layer "B.Cu")
		(net "GND")
	)
	(segment
		(start 51.78679 -148.771356)
		(end 51.76139 -148.771356)
		(width 0.4064)
		(layer "B.Cu")
		(net "GND")
	)
	(segment
		(start 90.071956 -3.635756)
		(end 90.802968 -3.635756)
		(width 0.4064)
		(layer "B.Cu")
		(net "GND")
	)
	(segment
		(start 129.149348 -14.409928)
		(end 128.687576 -13.948156)
		(width 0.4064)
		(layer "B.Cu")
		(net "GND")
	)
	(segment
		(start 72.1995 -129.488692)
		(end 72.142096 -129.546096)
		(width 0.4064)
		(layer "B.Cu")
		(net "GND")
	)
	(segment
		(start 71.095362 -14.097)
		(end 71.095362 -14.1986)
		(width 0.254)
		(layer "B.Cu")
		(net "GND")
	)
	(segment
		(start 418.1475 -7.3025)
		(end 417.576 -7.3025)
		(width 0.254)
		(layer "B.Cu")
		(net "GND")
	)
	(segment
		(start 202.35037 -137.877296)
		(end 202.349862 -137.877296)
		(width 0.4064)
		(layer "B.Cu")
		(net "GND")
	)
	(segment
		(start 138.499342 -132.876036)
		(end 138.499342 -132.062728)
		(width 0.4064)
		(layer "B.Cu")
		(net "GND")
	)
	(segment
		(start 291.599874 -7.4676)
		(end 291.422074 -7.6454)
		(width 0.4064)
		(layer "B.Cu")
		(net "GND")
	)
	(segment
		(start 91.704668 -3.258312)
		(end 91.704668 -3.321812)
		(width 0.4064)
		(layer "B.Cu")
		(net "GND")
	)
	(segment
		(start 52.649374 -14.42466)
		(end 52.649374 -15.222982)
		(width 0.254)
		(layer "B.Cu")
		(net "GND")
	)
	(segment
		(start 377.698 -82.677)
		(end 377.698 -81.8896)
		(width 0.254)
		(layer "B.Cu")
		(net "GND")
	)
	(segment
		(start 476.10014 -134.00024)
		(end 476.889572 -134.00024)
		(width 0.254)
		(layer "B.Cu")
		(net "GND")
	)
	(segment
		(start 405.62276 -31.6865)
		(end 406.019 -31.6865)
		(width 0.254)
		(layer "B.Cu")
		(net "GND")
	)
	(segment
		(start 368.662458 -42.625772)
		(end 368.895122 -42.625772)
		(width 0.254)
		(layer "B.Cu")
		(net "GND")
	)
	(segment
		(start 57.74944 -147.478496)
		(end 57.74944 -148.771356)
		(width 0.4064)
		(layer "B.Cu")
		(net "GND")
	)
	(segment
		(start 115.460526 -131.016756)
		(end 115.460526 -130.991356)
		(width 0.4064)
		(layer "B.Cu")
		(net "GND")
	)
	(segment
		(start 286.500316 -24.824182)
		(end 286.499808 -24.824182)
		(width 0.4064)
		(layer "B.Cu")
		(net "GND")
	)
	(segment
		(start 113.815368 -8.1534)
		(end 112.397032 -8.1534)
		(width 0.381)
		(layer "B.Cu")
		(net "GND")
	)
	(segment
		(start 299.250354 -24.824182)
		(end 299.249846 -24.824182)
		(width 0.4064)
		(layer "B.Cu")
		(net "GND")
	)
	(segment
		(start 146.092164 -129.546096)
		(end 146.092164 -129.564892)
		(width 0.4064)
		(layer "B.Cu")
		(net "GND")
	)
	(segment
		(start 68.799456 -20.224242)
		(end 68.799456 -21.517356)
		(width 0.4064)
		(layer "B.Cu")
		(net "GND")
	)
	(segment
		(start 424.796458 -2.4638)
		(end 424.2943 -2.965958)
		(width 0.254)
		(layer "B.Cu")
		(net "GND")
	)
	(segment
		(start 307.750464 -20.224242)
		(end 307.749956 -20.224242)
		(width 0.4064)
		(layer "B.Cu")
		(net "GND")
	)
	(segment
		(start 77.299566 -152.078436)
		(end 77.299566 -151.65705)
		(width 0.4064)
		(layer "B.Cu")
		(net "GND")
	)
	(segment
		(start 388.9248 -1.8034)
		(end 388.070598 -1.8034)
		(width 0.254)
		(layer "B.Cu")
		(net "GND")
	)
	(segment
		(start 325.4629 -123.8758)
		(end 325.10222 -123.51512)
		(width 0.254)
		(layer "B.Cu")
		(net "GND")
	)
	(segment
		(start 105.9561 -3.3528)
		(end 107.027472 -3.3528)
		(width 0.508)
		(layer "B.Cu")
		(net "GND")
	)
	(segment
		(start 234.65028 -24.824182)
		(end 234.649772 -24.824182)
		(width 0.4064)
		(layer "B.Cu")
		(net "GND")
	)
	(segment
		(start 146.092164 -18.744946)
		(end 146.149568 -18.80235)
		(width 0.4064)
		(layer "B.Cu")
		(net "GND")
	)
	(segment
		(start 243.15039 -147.478496)
		(end 243.149882 -147.478496)
		(width 0.4064)
		(layer "B.Cu")
		(net "GND")
	)
	(segment
		(start 135.949436 -24.045164)
		(end 135.949436 -24.824182)
		(width 0.254)
		(layer "B.Cu")
		(net "GND")
	)
	(segment
		(start 387.16712 -84.1629)
		(end 387.75894 -84.75472)
		(width 0.254)
		(layer "B.Cu")
		(net "GND")
	)
	(segment
		(start 404.846028 -31.912052)
		(end 405.262588 -32.328612)
		(width 0.254)
		(layer "B.Cu")
		(net "GND")
	)
	(segment
		(start 49.249584 -7.606792)
		(end 49.249584 -5.621782)
		(width 0.4064)
		(layer "B.Cu")
		(net "GND")
	)
	(segment
		(start 500.5578 -139.9794)
		(end 500.1514 -139.9794)
		(width 0.254)
		(layer "B.Cu")
		(net "GND")
	)
	(segment
		(start 156.814012 1.478788)
		(end 156.591 1.7018)
		(width 0.4064)
		(layer "B.Cu")
		(net "GND")
	)
	(segment
		(start 52.398168 -3.836162)
		(end 52.471574 -3.762756)
		(width 0.4064)
		(layer "B.Cu")
		(net "GND")
	)
	(segment
		(start 51.78679 -2.314956)
		(end 51.76139 -2.314956)
		(width 0.4064)
		(layer "B.Cu")
		(net "GND")
	)
	(segment
		(start 129.149348 -142.477236)
		(end 129.149348 -141.663928)
		(width 0.4064)
		(layer "B.Cu")
		(net "GND")
	)
	(segment
		(start 115.549426 -142.477236)
		(end 115.549426 -143.947388)
		(width 0.508)
		(layer "B.Cu")
		(net "GND")
	)
	(segment
		(start 37.34943 -20.224242)
		(end 37.34943 -21.517356)
		(width 0.4064)
		(layer "B.Cu")
		(net "GND")
	)
	(segment
		(start 207.450436 -147.478496)
		(end 207.449928 -147.478496)
		(width 0.4064)
		(layer "B.Cu")
		(net "GND")
	)
	(segment
		(start 212.549994 -7.606792)
		(end 212.54974 -7.607046)
		(width 0.4064)
		(layer "B.Cu")
		(net "GND")
	)
	(segment
		(start 52.471574 -13.363956)
		(end 52.398168 -13.437362)
		(width 0.4064)
		(layer "B.Cu")
		(net "GND")
	)
	(segment
		(start 243.15039 -10.623042)
		(end 243.149882 -10.623042)
		(width 0.4064)
		(layer "B.Cu")
		(net "GND")
	)
	(segment
		(start 226.137216 -21.517356)
		(end 226.149916 -21.504656)
		(width 0.4064)
		(layer "B.Cu")
		(net "GND")
	)
	(segment
		(start 199.799956 -21.437092)
		(end 199.799956 -20.224242)
		(width 0.4064)
		(layer "B.Cu")
		(net "GND")
	)
	(segment
		(start 226.9998 -132.1054)
		(end 226.7458 -131.8514)
		(width 0.254)
		(layer "B.Cu")
		(net "GND")
	)
	(segment
		(start 135.099552 -148.733256)
		(end 135.061452 -148.771356)
		(width 0.4064)
		(layer "B.Cu")
		(net "GND")
	)
	(segment
		(start 60.299346 -132.876036)
		(end 60.299346 -131.105656)
		(width 0.4064)
		(layer "B.Cu")
		(net "GND")
	)
	(segment
		(start 306.899818 -22.965156)
		(end 306.899818 -24.824182)
		(width 0.4064)
		(layer "B.Cu")
		(net "GND")
	)
	(segment
		(start 406.003506 -33.035494)
		(end 406.003506 -32.6644)
		(width 0.254)
		(layer "B.Cu")
		(net "GND")
	)
	(segment
		(start 196.893434 -63.656464)
		(end 196.515736 -63.656464)
		(width 0.254)
		(layer "B.Cu")
		(net "GND")
	)
	(segment
		(start 114.699542 0.457454)
		(end 114.699542 -1.021842)
		(width 0.4064)
		(layer "B.Cu")
		(net "GND")
	)
	(segment
		(start 280.550366 -15.222982)
		(end 280.549858 -15.222982)
		(width 0.4064)
		(layer "B.Cu")
		(net "GND")
	)
	(segment
		(start 381.762 -157.484572)
		(end 381.762 -157.816296)
		(width 0.254)
		(layer "B.Cu")
		(net "GND")
	)
	(segment
		(start 143.599408 -23.17496)
		(end 143.809212 -22.965156)
		(width 0.4064)
		(layer "B.Cu")
		(net "GND")
	)
	(segment
		(start 118.041928 -139.147296)
		(end 118.041928 -139.166092)
		(width 0.4064)
		(layer "B.Cu")
		(net "GND")
	)
	(segment
		(start 277.397464 -3.3528)
		(end 278.0792 -3.3528)
		(width 0.381)
		(layer "B.Cu")
		(net "GND")
	)
	(segment
		(start 208.0514 -131.074668)
		(end 208.122012 -131.004056)
		(width 0.254)
		(layer "B.Cu")
		(net "GND")
	)
	(segment
		(start 146.092164 -148.748496)
		(end 146.092164 -148.767292)
		(width 0.4064)
		(layer "B.Cu")
		(net "GND")
	)
	(segment
		(start 69.56044 -140.617956)
		(end 69.56044 -140.592556)
		(width 0.4064)
		(layer "B.Cu")
		(net "GND")
	)
	(segment
		(start 214.250016 -5.27685)
		(end 214.249762 -5.276596)
		(width 0.4064)
		(layer "B.Cu")
		(net "GND")
	)
	(segment
		(start 449.326 -147.0406)
		(end 449.326 -146.400012)
		(width 0.254)
		(layer "B.Cu")
		(net "GND")
	)
	(segment
		(start 221.900496 -15.222982)
		(end 221.899988 -15.222982)
		(width 0.4064)
		(layer "B.Cu")
		(net "GND")
	)
	(segment
		(start 301.800006 -9.20115)
		(end 301.742602 -9.143746)
		(width 0.4064)
		(layer "B.Cu")
		(net "GND")
	)
	(segment
		(start 460.63027 -150.100792)
		(end 460.63027 -149.326346)
		(width 0.3048)
		(layer "B.Cu")
		(net "GND")
	)
	(segment
		(start 300.70425 -13.431774)
		(end 300.772068 -13.363956)
		(width 0.4064)
		(layer "B.Cu")
		(net "GND")
	)
	(segment
		(start 61.745368 -4.4958)
		(end 61.745368 -4.5974)
		(width 0.254)
		(layer "B.Cu")
		(net "GND")
	)
	(segment
		(start 141.899386 -152.078436)
		(end 141.899386 -150.219156)
		(width 0.4064)
		(layer "B.Cu")
		(net "GND")
	)
	(segment
		(start 284.799786 -4.808982)
		(end 284.799786 -5.621782)
		(width 0.4064)
		(layer "B.Cu")
		(net "GND")
	)
	(segment
		(start 201.500486 -132.876036)
		(end 201.499978 -132.875782)
		(width 0.4064)
		(layer "B.Cu")
		(net "GND")
	)
	(segment
		(start 304.35042 -128.276096)
		(end 304.349912 -128.276096)
		(width 0.4064)
		(layer "B.Cu")
		(net "GND")
	)
	(segment
		(start 124.89942 -140.706856)
		(end 124.81052 -140.617956)
		(width 0.4064)
		(layer "B.Cu")
		(net "GND")
	)
	(segment
		(start 243.2304 -135.4074)
		(end 244.3607 -135.4074)
		(width 0.4572)
		(layer "B.Cu")
		(net "GND")
	)
	(segment
		(start 217.3986 -150.9776)
		(end 217.3986 -150.292562)
		(width 0.4064)
		(layer "B.Cu")
		(net "GND")
	)
	(segment
		(start 25.509474 -80.645)
		(end 25.509474 -82.430366)
		(width 0.254)
		(layer "B.Cu")
		(net "GND")
	)
	(segment
		(start 238.900462 -15.222982)
		(end 238.899954 -15.222982)
		(width 0.4064)
		(layer "B.Cu")
		(net "GND")
	)
	(segment
		(start 256.8194 -140.1826)
		(end 256.511806 -140.490194)
		(width 0.4064)
		(layer "B.Cu")
		(net "GND")
	)
	(segment
		(start 408.711146 -21.853652)
		(end 408.711146 -21.648674)
		(width 0.254)
		(layer "B.Cu")
		(net "GND")
	)
	(segment
		(start 330.869798 -5.08)
		(end 330.581 -5.08)
		(width 0.254)
		(layer "B.Cu")
		(net "GND")
	)
	(segment
		(start 501.0658 -140.3858)
		(end 500.9642 -140.3858)
		(width 0.254)
		(layer "B.Cu")
		(net "GND")
	)
	(segment
		(start 283.099764 -128.276096)
		(end 283.100272 -128.276096)
		(width 0.4064)
		(layer "B.Cu")
		(net "GND")
	)
	(segment
		(start 68.799456 -9.143746)
		(end 68.799456 -10.623042)
		(width 0.4064)
		(layer "B.Cu")
		(net "GND")
	)
	(segment
		(start 310.054244 -131.084574)
		(end 310.054244 -131.7752)
		(width 0.4064)
		(layer "B.Cu")
		(net "GND")
	)
	(segment
		(start 90.31986 -135.012684)
		(end 90.845894 -135.012684)
		(width 0.4064)
		(layer "B.Cu")
		(net "GND")
	)
	(segment
		(start 236.349794 -14.4526)
		(end 236.095794 -14.1986)
		(width 0.254)
		(layer "B.Cu")
		(net "GND")
	)
	(segment
		(start 283.04236 -9.143746)
		(end 283.099764 -9.20115)
		(width 0.4064)
		(layer "B.Cu")
		(net "GND")
	)
	(segment
		(start 223.600518 -132.876036)
		(end 223.60001 -132.875782)
		(width 0.4064)
		(layer "B.Cu")
		(net "GND")
	)
	(segment
		(start 444.26886 -129.836926)
		(end 444.7286 -129.377186)
		(width 0.254)
		(layer "B.Cu")
		(net "GND")
	)
	(segment
		(start 486.4354 -121.9327)
		(end 486.148888 -122.219212)
		(width 0.254)
		(layer "B.Cu")
		(net "GND")
	)
	(segment
		(start 220.199966 -15.222982)
		(end 220.199966 -14.410182)
		(width 0.4064)
		(layer "B.Cu")
		(net "GND")
	)
	(segment
		(start 117.249448 -24.824182)
		(end 117.249448 -24.045164)
		(width 0.254)
		(layer "B.Cu")
		(net "GND")
	)
	(segment
		(start 113.849404 -130.124962)
		(end 113.72469 -130.249676)
		(width 0.4064)
		(layer "B.Cu")
		(net "GND")
	)
	(segment
		(start 288.19983 -132.875782)
		(end 288.19983 -131.016756)
		(width 0.4064)
		(layer "B.Cu")
		(net "GND")
	)
	(segment
		(start 185.039 -71.6026)
		(end 185.039 -72.009)
		(width 0.4064)
		(layer "B.Cu")
		(net "GND")
	)
	(segment
		(start 227.799138 -26.73731)
		(end 226.9998 -25.937972)
		(width 0.4064)
		(layer "B.Cu")
		(net "GND")
	)
	(segment
		(start 380.365 -20.810982)
		(end 380.901702 -21.347684)
		(width 0.254)
		(layer "B.Cu")
		(net "GND")
	)
	(segment
		(start 30.503368 -143.9926)
		(end 30.549342 -143.946626)
		(width 0.4064)
		(layer "B.Cu")
		(net "GND")
	)
	(segment
		(start 128.687576 -4.346956)
		(end 129.149348 -4.808728)
		(width 0.4064)
		(layer "B.Cu")
		(net "GND")
	)
	(segment
		(start 491.93958 -154.18816)
		(end 491.67542 -153.924)
		(width 0.254)
		(layer "B.Cu")
		(net "GND")
	)
	(segment
		(start 373.244872 -83.521296)
		(end 372.954804 -83.811364)
		(width 0.254)
		(layer "B.Cu")
		(net "GND")
	)
	(segment
		(start 389.33374 -17.35074)
		(end 389.255 -17.272)
		(width 0.254)
		(layer "B.Cu")
		(net "GND")
	)
	(segment
		(start 27.1018 -32.522414)
		(end 27.242516 -32.522414)
		(width 0.254)
		(layer "B.Cu")
		(net "GND")
	)
	(segment
		(start 130.84937 -142.477236)
		(end 130.84937 -140.617956)
		(width 0.4064)
		(layer "B.Cu")
		(net "GND")
	)
	(segment
		(start 298.399962 -139.170156)
		(end 298.399962 -137.877296)
		(width 0.4064)
		(layer "B.Cu")
		(net "GND")
	)
	(segment
		(start 198.100442 -20.224242)
		(end 198.099934 -20.224242)
		(width 0.4064)
		(layer "B.Cu")
		(net "GND")
	)
	(segment
		(start 61.999368 -25.937972)
		(end 62.798706 -26.73731)
		(width 0.4064)
		(layer "B.Cu")
		(net "GND")
	)
	(segment
		(start 310.299862 -151.299164)
		(end 310.054244 -151.053546)
		(width 0.254)
		(layer "B.Cu")
		(net "GND")
	)
	(segment
		(start 217.3986 -151.028654)
		(end 217.3986 -150.9776)
		(width 0.254)
		(layer "B.Cu")
		(net "GND")
	)
	(segment
		(start 198.099934 -2.302256)
		(end 198.099934 -1.021842)
		(width 0.4064)
		(layer "B.Cu")
		(net "GND")
	)
	(segment
		(start 261.3406 -139.3952)
		(end 260.731 -138.7856)
		(width 0.4064)
		(layer "B.Cu")
		(net "GND")
	)
	(segment
		(start 126.599442 -4.842764)
		(end 126.599442 -5.621782)
		(width 0.254)
		(layer "B.Cu")
		(net "GND")
	)
	(segment
		(start 446.291716 -17.7292)
		(end 446.291716 -16.778986)
		(width 0.254)
		(layer "B.Cu")
		(net "GND")
	)
	(segment
		(start 307.750464 -1.021842)
		(end 307.749956 -1.021842)
		(width 0.4064)
		(layer "B.Cu")
		(net "GND")
	)
	(segment
		(start 215.860884 -13.363956)
		(end 215.860884 -13.338556)
		(width 0.4064)
		(layer "B.Cu")
		(net "GND")
	)
	(segment
		(start 382.66116 -158.242)
		(end 382.6891 -158.26994)
		(width 0.254)
		(layer "B.Cu")
		(net "GND")
	)
	(segment
		(start 143.599408 -3.82524)
		(end 143.599408 -5.621782)
		(width 0.254)
		(layer "B.Cu")
		(net "GND")
	)
	(segment
		(start 381.99695 -108.111036)
		(end 381.99695 -108.4834)
		(width 0.254)
		(layer "B.Cu")
		(net "GND")
	)
	(segment
		(start 141.899386 -24.824182)
		(end 141.899386 -25.645872)
		(width 0.4064)
		(layer "B.Cu")
		(net "GND")
	)
	(segment
		(start 61.149484 0.444754)
		(end 61.149484 -1.021842)
		(width 0.4064)
		(layer "B.Cu")
		(net "GND")
	)
	(segment
		(start 261.2644 -11.6586)
		(end 262.0264 -10.8966)
		(width 0.508)
		(layer "B.Cu")
		(net "GND")
	)
	(segment
		(start 236.350302 -24.824182)
		(end 236.349794 -24.824182)
		(width 0.254)
		(layer "B.Cu")
		(net "GND")
	)
	(segment
		(start 234.649772 -17.110202)
		(end 234.551728 -17.208246)
		(width 0.4064)
		(layer "B.Cu")
		(net "GND")
	)
	(segment
		(start 429.367696 -22.5298)
		(end 428.529496 -23.368)
		(width 0.254)
		(layer "B.Cu")
		(net "GND")
	)
	(segment
		(start 229.550468 -24.824182)
		(end 229.54996 -24.824182)
		(width 0.4064)
		(layer "B.Cu")
		(net "GND")
	)
	(segment
		(start 53.499512 -20.224242)
		(end 53.499512 -21.437092)
		(width 0.4064)
		(layer "B.Cu")
		(net "GND")
	)
	(segment
		(start 145.29943 -132.096764)
		(end 145.29943 -132.876036)
		(width 0.254)
		(layer "B.Cu")
		(net "GND")
	)
	(segment
		(start 207.450436 -1.021842)
		(end 207.449928 -1.021842)
		(width 0.4064)
		(layer "B.Cu")
		(net "GND")
	)
	(segment
		(start 217.649806 -4.82346)
		(end 217.3986 -4.572254)
		(width 0.254)
		(layer "B.Cu")
		(net "GND")
	)
	(segment
		(start 377.806204 -83.8454)
		(end 377.80595 -83.845146)
		(width 0.254)
		(layer "B.Cu")
		(net "GND")
	)
	(segment
		(start 242.300506 -24.824182)
		(end 242.299998 -24.824182)
		(width 0.4064)
		(layer "B.Cu")
		(net "GND")
	)
	(segment
		(start 468.8205 -137.795)
		(end 468.8205 -138.23823)
		(width 0.254)
		(layer "B.Cu")
		(net "GND")
	)
	(segment
		(start 227.792534 -2.292096)
		(end 227.849938 -2.234692)
		(width 0.4064)
		(layer "B.Cu")
		(net "GND")
	)
	(segment
		(start 306.049934 -10.623042)
		(end 306.049934 -9.156446)
		(width 0.4064)
		(layer "B.Cu")
		(net "GND")
	)
	(segment
		(start 311.150508 -20.224242)
		(end 311.15 -20.224242)
		(width 0.4064)
		(layer "B.Cu")
		(net "GND")
	)
	(segment
		(start 236.095794 -4.4958)
		(end 236.095794 -3.838956)
		(width 0.4064)
		(layer "B.Cu")
		(net "GND")
	)
	(segment
		(start 135.086852 -2.314956)
		(end 135.061452 -2.314956)
		(width 0.4064)
		(layer "B.Cu")
		(net "GND")
	)
	(segment
		(start 400.409156 -29.104844)
		(end 400.409156 -29.917898)
		(width 0.381)
		(layer "B.Cu")
		(net "GND")
	)
	(segment
		(start 490.823758 -38.885622)
		(end 490.146594 -39.562786)
		(width 0.254)
		(layer "B.Cu")
		(net "GND")
	)
	(segment
		(start 291.599874 -25.645872)
		(end 291.599874 -24.824182)
		(width 0.4064)
		(layer "B.Cu")
		(net "GND")
	)
	(segment
		(start 38.199568 -142.477236)
		(end 38.199568 -140.61821)
		(width 0.4064)
		(layer "B.Cu")
		(net "GND")
	)
	(segment
		(start 215.100408 -137.877296)
		(end 215.0999 -137.877296)
		(width 0.4064)
		(layer "B.Cu")
		(net "GND")
	)
	(segment
		(start 107.027472 -17.7546)
		(end 105.9561 -17.7546)
		(width 0.4064)
		(layer "B.Cu")
		(net "GND")
	)
	(segment
		(start 278.849836 -7.1374)
		(end 278.849836 -5.621782)
		(width 0.4064)
		(layer "B.Cu")
		(net "GND")
	)
	(segment
		(start 126.599442 -15.222982)
		(end 126.599442 -17.0688)
		(width 0.4064)
		(layer "B.Cu")
		(net "GND")
	)
	(segment
		(start 109.2581 -135.4074)
		(end 110.286546 -135.4074)
		(width 0.4572)
		(layer "B.Cu")
		(net "GND")
	)
	(segment
		(start 292.450012 -10.623042)
		(end 292.450012 -11.835892)
		(width 0.4064)
		(layer "B.Cu")
		(net "GND")
	)
	(segment
		(start 70.499478 -1.021842)
		(end 70.499478 -2.276856)
		(width 0.4064)
		(layer "B.Cu")
		(net "GND")
	)
	(segment
		(start 231.249982 -151.70785)
		(end 231.249728 -151.707596)
		(width 0.4064)
		(layer "B.Cu")
		(net "GND")
	)
	(segment
		(start 387.917182 -9.135364)
		(end 388.356094 -8.696452)
		(width 0.254)
		(layer "B.Cu")
		(net "GND")
	)
	(segment
		(start 313.699906 -137.877296)
		(end 313.700414 -137.877296)
		(width 0.4064)
		(layer "B.Cu")
		(net "GND")
	)
	(segment
		(start 77.286612 -22.965156)
		(end 77.299312 -22.977856)
		(width 0.4064)
		(layer "B.Cu")
		(net "GND")
	)
	(segment
		(start 52.649374 -4.82346)
		(end 52.398168 -4.572254)
		(width 0.254)
		(layer "B.Cu")
		(net "GND")
	)
	(segment
		(start 247.4595 -149.8092)
		(end 246.565674 -149.8092)
		(width 0.4064)
		(layer "B.Cu")
		(net "GND")
	)
	(segment
		(start 167.386 -86.868)
		(end 167.0812 -86.868)
		(width 0.4064)
		(layer "B.Cu")
		(net "GND")
	)
	(segment
		(start 34.799524 -20.224242)
		(end 34.799524 -21.437092)
		(width 0.4064)
		(layer "B.Cu")
		(net "GND")
	)
	(segment
		(start 43.29938 -142.477236)
		(end 43.29938 -141.748764)
		(width 0.254)
		(layer "B.Cu")
		(net "GND")
	)
	(segment
		(start 475.234 -45.6692)
		(end 475.234 -48.5394)
		(width 0.508)
		(layer "B.Cu")
		(net "GND")
	)
	(segment
		(start 281.399996 0.444754)
		(end 281.399996 -1.021842)
		(width 0.4064)
		(layer "B.Cu")
		(net "GND")
	)
	(segment
		(start 416.179 -8.270748)
		(end 416.179 -9.392158)
		(width 0.254)
		(layer "B.Cu")
		(net "GND")
	)
	(segment
		(start 306.899818 -25.645872)
		(end 306.049934 -26.495756)
		(width 0.4064)
		(layer "B.Cu")
		(net "GND")
	)
	(segment
		(start 96.213168 -1.651)
		(end 95.451168 -1.651)
		(width 0.508)
		(layer "B.Cu")
		(net "GND")
	)
	(segment
		(start 191.77 -145.3642)
		(end 191.77 -145.9992)
		(width 0.4064)
		(layer "B.Cu")
		(net "GND")
	)
	(segment
		(start 30.549342 -15.222982)
		(end 30.549342 -16.764)
		(width 0.4064)
		(layer "B.Cu")
		(net "GND")
	)
	(segment
		(start 241.466116 -28.491434)
		(end 241.4524 -28.5242)
		(width 0.4064)
		(layer "B.Cu")
		(net "GND")
	)
	(segment
		(start 243.149882 -137.877042)
		(end 243.149882 -136.387078)
		(width 0.508)
		(layer "B.Cu")
		(net "GND")
	)
	(segment
		(start 61.149484 -129.556256)
		(end 61.136784 -129.568956)
		(width 0.4064)
		(layer "B.Cu")
		(net "GND")
	)
	(segment
		(start 216.799922 -21.504656)
		(end 216.787222 -21.517356)
		(width 0.4064)
		(layer "B.Cu")
		(net "GND")
	)
	(segment
		(start 114.039142 -13.940282)
		(end 113.849404 -14.13002)
		(width 0.4064)
		(layer "B.Cu")
		(net "GND")
	)
	(segment
		(start 429.7172 -22.5298)
		(end 429.367696 -22.5298)
		(width 0.254)
		(layer "B.Cu")
		(net "GND")
	)
	(segment
		(start 306.899818 -132.875782)
		(end 306.899818 -131.016756)
		(width 0.4064)
		(layer "B.Cu")
		(net "GND")
	)
	(segment
		(start 96.091248 -12.872212)
		(end 96.091248 -12.999212)
		(width 0.508)
		(layer "B.Cu")
		(net "GND")
	)
	(segment
		(start 289.899852 -132.875782)
		(end 289.899852 -131.105656)
		(width 0.4064)
		(layer "B.Cu")
		(net "GND")
	)
	(segment
		(start 313.699906 -11.916156)
		(end 313.699906 -10.623042)
		(width 0.4064)
		(layer "B.Cu")
		(net "GND")
	)
	(segment
		(start 130.84937 -5.621782)
		(end 130.84937 -3.762756)
		(width 0.4064)
		(layer "B.Cu")
		(net "GND")
	)
	(segment
		(start 30.549342 -7.086346)
		(end 30.549342 -5.621782)
		(width 0.4064)
		(layer "B.Cu")
		(net "GND")
	)
	(segment
		(start 66.249296 -17.208246)
		(end 66.24955 -17.207992)
		(width 0.4064)
		(layer "B.Cu")
		(net "GND")
	)
	(segment
		(start 300.70425 -151.053546)
		(end 300.949868 -151.299164)
		(width 0.254)
		(layer "B.Cu")
		(net "GND")
	)
	(segment
		(start 480.037902 -53.450998)
		(end 479.288602 -53.450998)
		(width 0.254)
		(layer "B.Cu")
		(net "GND")
	)
	(segment
		(start 243.15039 -137.877296)
		(end 243.149882 -137.877296)
		(width 0.4064)
		(layer "B.Cu")
		(net "GND")
	)
	(segment
		(start 218.499944 -148.691092)
		(end 218.44254 -148.748496)
		(width 0.4064)
		(layer "B.Cu")
		(net "GND")
	)
	(segment
		(start 198.087234 -148.771356)
		(end 198.061834 -148.771356)
		(width 0.4064)
		(layer "B.Cu")
		(net "GND")
	)
	(segment
		(start 211.699856 -147.478496)
		(end 211.699856 -148.771356)
		(width 0.4064)
		(layer "B.Cu")
		(net "GND")
	)
	(segment
		(start 163.6776 -78.359)
		(end 163.4236 -78.613)
		(width 0.381)
		(layer "B.Cu")
		(net "GND")
	)
	(segment
		(start 418.1094 -19.8374)
		(end 418.6936 -19.2532)
		(width 0.254)
		(layer "B.Cu")
		(net "GND")
	)
	(segment
		(start 61.821568 -17.2466)
		(end 61.999368 -17.0688)
		(width 0.4064)
		(layer "B.Cu")
		(net "GND")
	)
	(segment
		(start 315.400436 -20.224242)
		(end 315.399928 -20.224242)
		(width 0.4064)
		(layer "B.Cu")
		(net "GND")
	)
	(segment
		(start 274.258532 -12.954)
		(end 275.111464 -12.954)
		(width 0.381)
		(layer "B.Cu")
		(net "GND")
	)
	(segment
		(start 72.1995 -137.877296)
		(end 72.1995 -139.089892)
		(width 0.4064)
		(layer "B.Cu")
		(net "GND")
	)
	(segment
		(start 405.369522 -17.454118)
		(end 405.369522 -18.166588)
		(width 0.254)
		(layer "B.Cu")
		(net "GND")
	)
	(segment
		(start 300.950376 -15.222982)
		(end 300.949868 -15.222982)
		(width 0.4064)
		(layer "B.Cu")
		(net "GND")
	)
	(segment
		(start 127.44958 0.40005)
		(end 127.392176 0.457454)
		(width 0.4064)
		(layer "B.Cu")
		(net "GND")
	)
	(segment
		(start 492.97844 -130.5941)
		(end 492.97844 -131.95681)
		(width 0.254)
		(layer "B.Cu")
		(net "GND")
	)
	(segment
		(start 287.350454 -20.224242)
		(end 287.349946 -20.224242)
		(width 0.4064)
		(layer "B.Cu")
		(net "GND")
	)
	(segment
		(start 75.59929 -5.251196)
		(end 75.599544 -5.25145)
		(width 0.4064)
		(layer "B.Cu")
		(net "GND")
	)
	(segment
		(start 61.745368 -23.041356)
		(end 61.745368 -23.6982)
		(width 0.4064)
		(layer "B.Cu")
		(net "GND")
	)
	(segment
		(start 221.899988 -151.73325)
		(end 221.899734 -151.732996)
		(width 0.4064)
		(layer "B.Cu")
		(net "GND")
	)
	(segment
		(start 450.6595 -19.043396)
		(end 450.141594 -18.52549)
		(width 0.254)
		(layer "B.Cu")
		(net "GND")
	)
	(segment
		(start 135.771636 -22.965156)
		(end 135.703818 -23.032974)
		(width 0.4064)
		(layer "B.Cu")
		(net "GND")
	)
	(segment
		(start 214.250016 -15.222982)
		(end 214.250016 -14.87805)
		(width 0.4064)
		(layer "B.Cu")
		(net "GND")
	)
	(segment
		(start 232.950512 -15.222982)
		(end 232.950004 -15.222982)
		(width 0.4064)
		(layer "B.Cu")
		(net "GND")
	)
	(segment
		(start 209.14995 0.40005)
		(end 209.092546 0.457454)
		(width 0.4064)
		(layer "B.Cu")
		(net "GND")
	)
	(segment
		(start 39.899336 -132.876036)
		(end 39.899336 -131.016756)
		(width 0.4064)
		(layer "B.Cu")
		(net "GND")
	)
	(segment
		(start 109.2581 -140.208)
		(end 110.111032 -140.208)
		(width 0.4064)
		(layer "B.Cu")
		(net "GND")
	)
	(segment
		(start 43.29938 -24.824182)
		(end 43.29938 -24.095964)
		(width 0.254)
		(layer "B.Cu")
		(net "GND")
	)
	(segment
		(start 58.599578 -5.621782)
		(end 58.599578 -7.606792)
		(width 0.4064)
		(layer "B.Cu")
		(net "GND")
	)
	(segment
		(start 211.700364 -10.623042)
		(end 211.699856 -10.623042)
		(width 0.4064)
		(layer "B.Cu")
		(net "GND")
	)
	(segment
		(start 296.69994 0.444754)
		(end 296.69994 -1.021842)
		(width 0.4064)
		(layer "B.Cu")
		(net "GND")
	)
	(segment
		(start 322.5292 1.478788)
		(end 322.306188 1.7018)
		(width 0.4064)
		(layer "B.Cu")
		(net "GND")
	)
	(segment
		(start 96.721168 -7.064248)
		(end 96.721168 -7.843012)
		(width 0.4064)
		(layer "B.Cu")
		(net "GND")
	)
	(segment
		(start 373.945404 -74.695304)
		(end 373.86514 -74.695304)
		(width 0.254)
		(layer "B.Cu")
		(net "GND")
	)
	(segment
		(start 240.599722 -14.852396)
		(end 240.599722 -13.363956)
		(width 0.4064)
		(layer "B.Cu")
		(net "GND")
	)
	(segment
		(start 73.899522 -6.63702)
		(end 73.440798 -7.095744)
		(width 0.4064)
		(layer "B.Cu")
		(net "GND")
	)
	(segment
		(start 129.149348 -152.078436)
		(end 129.149348 -151.265128)
		(width 0.4064)
		(layer "B.Cu")
		(net "GND")
	)
	(segment
		(start 375.44502 -96.58604)
		(end 375.93016 -97.07118)
		(width 0.254)
		(layer "B.Cu")
		(net "GND")
	)
	(segment
		(start 144.436846 -21.517356)
		(end 144.411446 -21.517356)
		(width 0.4064)
		(layer "B.Cu")
		(net "GND")
	)
	(segment
		(start 386.9436 -54.864)
		(end 386.6896 -54.61)
		(width 0.254)
		(layer "B.Cu")
		(net "GND")
	)
	(segment
		(start 199.799956 -10.623042)
		(end 199.799956 -9.20115)
		(width 0.4064)
		(layer "B.Cu")
		(net "GND")
	)
	(segment
		(start 206.600298 -5.621782)
		(end 206.59979 -5.621782)
		(width 0.4064)
		(layer "B.Cu")
		(net "GND")
	)
	(segment
		(start 147.849336 -151.265128)
		(end 147.387564 -150.803356)
		(width 0.4064)
		(layer "B.Cu")
		(net "GND")
	)
	(segment
		(start 144.449546 -2.302256)
		(end 144.436846 -2.314956)
		(width 0.4064)
		(layer "B.Cu")
		(net "GND")
	)
	(segment
		(start 297.550332 -132.876036)
		(end 297.549824 -132.875782)
		(width 0.4064)
		(layer "B.Cu")
		(net "GND")
	)
	(segment
		(start 196.395848 -9.139682)
		(end 196.399912 -9.139682)
		(width 0.381)
		(layer "B.Cu")
		(net "GND")
	)
	(segment
		(start 295.849802 -22.965156)
		(end 295.849802 -24.824182)
		(width 0.4064)
		(layer "B.Cu")
		(net "GND")
	)
	(segment
		(start 292.450012 -148.691092)
		(end 292.450012 -147.478496)
		(width 0.4064)
		(layer "B.Cu")
		(net "GND")
	)
	(segment
		(start 217.3986 -14.173454)
		(end 217.3986 -14.1224)
		(width 0.254)
		(layer "B.Cu")
		(net "GND")
	)
	(segment
		(start 58.599578 -15.222982)
		(end 58.599578 -14.97965)
		(width 0.4064)
		(layer "B.Cu")
		(net "GND")
	)
	(segment
		(start 75.59929 -132.505196)
		(end 75.59929 -131.016756)
		(width 0.4064)
		(layer "B.Cu")
		(net "GND")
	)
	(segment
		(start 306.900326 -152.078436)
		(end 306.899818 -152.078182)
		(width 0.4064)
		(layer "B.Cu")
		(net "GND")
	)
	(segment
		(start 300.949868 -14.443964)
		(end 300.70425 -14.198346)
		(width 0.254)
		(layer "B.Cu")
		(net "GND")
	)
	(segment
		(start 420.8526 -70.4342)
		(end 420.4589 -70.0405)
		(width 0.254)
		(layer "B.Cu")
		(net "GND")
	)
	(segment
		(start 203.200508 -152.078436)
		(end 203.2 -152.078182)
		(width 0.4064)
		(layer "B.Cu")
		(net "GND")
	)
	(segment
		(start 440.436 -23.3934)
		(end 440.4106 -23.4188)
		(width 0.254)
		(layer "B.Cu")
		(net "GND")
	)
	(segment
		(start 284.799786 -14.410182)
		(end 284.33776 -13.948156)
		(width 0.4064)
		(layer "B.Cu")
		(net "GND")
	)
	(segment
		(start 52.649374 -132.876036)
		(end 52.649374 -132.07746)
		(width 0.254)
		(layer "B.Cu")
		(net "GND")
	)
	(segment
		(start 310.054244 -141.3764)
		(end 310.054244 -141.452346)
		(width 0.254)
		(layer "B.Cu")
		(net "GND")
	)
	(segment
		(start 291.422074 -3.762756)
		(end 291.354256 -3.830574)
		(width 0.4064)
		(layer "B.Cu")
		(net "GND")
	)
	(segment
		(start 290.750498 -147.478496)
		(end 290.74999 -147.478496)
		(width 0.4064)
		(layer "B.Cu")
		(net "GND")
	)
	(segment
		(start 373.315738 -37.589968)
		(end 373.315738 -37.662104)
		(width 0.254)
		(layer "B.Cu")
		(net "GND")
	)
	(segment
		(start 399.345404 -106.190796)
		(end 398.63395 -106.190796)
		(width 0.254)
		(layer "B.Cu")
		(net "GND")
	)
	(segment
		(start 56.049418 -20.224242)
		(end 56.049418 -21.517356)
		(width 0.4064)
		(layer "B.Cu")
		(net "GND")
	)
	(segment
		(start 280.549858 -15.222982)
		(end 280.549858 -13.452856)
		(width 0.4064)
		(layer "B.Cu")
		(net "GND")
	)
	(segment
		(start 300.099984 -20.224242)
		(end 300.099984 -21.479256)
		(width 0.4064)
		(layer "B.Cu")
		(net "GND")
	)
	(segment
		(start 38.199568 -17.207992)
		(end 38.199314 -17.208246)
		(width 0.4064)
		(layer "B.Cu")
		(net "GND")
	)
	(segment
		(start 53.442108 -129.546096)
		(end 53.442108 -129.564892)
		(width 0.4064)
		(layer "B.Cu")
		(net "GND")
	)
	(segment
		(start 38.199314 -7.607046)
		(end 38.199568 -7.606792)
		(width 0.4064)
		(layer "B.Cu")
		(net "GND")
	)
	(segment
		(start 221.04985 -21.517356)
		(end 221.04985 -20.224242)
		(width 0.4064)
		(layer "B.Cu")
		(net "GND")
	)
	(segment
		(start 182.071518 3.664966)
		(end 182.071518 3.669792)
		(width 0.254)
		(layer "B.Cu")
		(net "GND")
	)
	(segment
		(start 214.249762 -14.877796)
		(end 214.249762 -13.363956)
		(width 0.4064)
		(layer "B.Cu")
		(net "GND")
	)
	(segment
		(start 284.799786 -5.621782)
		(end 284.799786 -6.63702)
		(width 0.4064)
		(layer "B.Cu")
		(net "GND")
	)
	(segment
		(start 282.24988 -142.476982)
		(end 282.24988 -141.697964)
		(width 0.254)
		(layer "B.Cu")
		(net "GND")
	)
	(segment
		(start 42.449496 -128.276096)
		(end 42.449496 -129.556256)
		(width 0.4064)
		(layer "B.Cu")
		(net "GND")
	)
	(segment
		(start 410.21254 -92.211906)
		(end 411.372812 -92.211906)
		(width 0.254)
		(layer "B.Cu")
		(net "GND")
	)
	(segment
		(start 94.244668 -11.9126)
		(end 95.131636 -11.9126)
		(width 0.508)
		(layer "B.Cu")
		(net "GND")
	)
	(segment
		(start 30.361128 -143.9926)
		(end 29.878528 -144.4752)
		(width 0.4064)
		(layer "B.Cu")
		(net "GND")
	)
	(segment
		(start 34.799524 -137.877296)
		(end 34.799524 -139.089892)
		(width 0.4064)
		(layer "B.Cu")
		(net "GND")
	)
	(segment
		(start 171.069 -73.5838)
		(end 170.7261 -73.2409)
		(width 0.254)
		(layer "B.Cu")
		(net "GND")
	)
	(segment
		(start 289.049968 -2.314956)
		(end 289.049968 -1.021842)
		(width 0.4064)
		(layer "B.Cu")
		(net "GND")
	)
	(segment
		(start 209.150458 -137.877296)
		(end 209.14995 -137.877296)
		(width 0.4064)
		(layer "B.Cu")
		(net "GND")
	)
	(segment
		(start 210.849972 -15.222982)
		(end 210.849972 -14.410182)
		(width 0.4064)
		(layer "B.Cu")
		(net "GND")
	)
	(segment
		(start 34.74212 -129.546096)
		(end 34.74212 -129.564892)
		(width 0.4064)
		(layer "B.Cu")
		(net "GND")
	)
	(segment
		(start 56.899556 -132.53085)
		(end 56.899302 -132.530596)
		(width 0.4064)
		(layer "B.Cu")
		(net "GND")
	)
	(segment
		(start 300.099984 -11.903456)
		(end 300.099984 -10.623042)
		(width 0.4064)
		(layer "B.Cu")
		(net "GND")
	)
	(segment
		(start 372.29669 -96.4946)
		(end 373.8753 -96.4946)
		(width 0.254)
		(layer "B.Cu")
		(net "GND")
	)
	(segment
		(start 373.906288 -36.471606)
		(end 374.231916 -36.797234)
		(width 0.254)
		(layer "B.Cu")
		(net "GND")
	)
	(segment
		(start 147.849336 -132.062728)
		(end 147.387564 -131.600956)
		(width 0.4064)
		(layer "B.Cu")
		(net "GND")
	)
	(segment
		(start 278.9682 -131.457192)
		(end 278.9682 -130.8862)
		(width 0.4064)
		(layer "B.Cu")
		(net "GND")
	)
	(segment
		(start 133.39953 -9.143746)
		(end 133.39953 -10.623042)
		(width 0.4064)
		(layer "B.Cu")
		(net "GND")
	)
	(segment
		(start 386.79374 -83.22056)
		(end 386.79374 -83.805776)
		(width 0.254)
		(layer "B.Cu")
		(net "GND")
	)
	(segment
		(start 113.849404 -132.875782)
		(end 113.849404 -131.575556)
		(width 0.4064)
		(layer "B.Cu")
		(net "GND")
	)
	(segment
		(start 402.679408 -92.993718)
		(end 402.679408 -93.755718)
		(width 0.254)
		(layer "B.Cu")
		(net "GND")
	)
	(segment
		(start 306.049934 -148.771356)
		(end 306.049934 -147.478496)
		(width 0.4064)
		(layer "B.Cu")
		(net "GND")
	)
	(segment
		(start 409.672028 -12.602972)
		(end 409.985972 -12.602972)
		(width 0.254)
		(layer "B.Cu")
		(net "GND")
	)
	(segment
		(start 157.528768 -135.376412)
		(end 156.690568 -135.376412)
		(width 0.4064)
		(layer "B.Cu")
		(net "GND")
	)
	(segment
		(start 381.432816 -41.772332)
		(end 380.464568 -41.772332)
		(width 0.254)
		(layer "B.Cu")
		(net "GND")
	)
	(segment
		(start 283.100272 -10.623042)
		(end 283.099764 -10.623042)
		(width 0.4064)
		(layer "B.Cu")
		(net "GND")
	)
	(segment
		(start 317.949834 2.514854)
		(end 317.627 2.19202)
		(width 0.4064)
		(layer "B.Cu")
		(net "GND")
	)
	(segment
		(start 50.949352 -3.851656)
		(end 50.860452 -3.762756)
		(width 0.4064)
		(layer "B.Cu")
		(net "GND")
	)
	(segment
		(start 234.649772 -24.824182)
		(end 234.649772 -23.054056)
		(width 0.4064)
		(layer "B.Cu")
		(net "GND")
	)
	(segment
		(start 198.100442 -128.276096)
		(end 198.099934 -128.276096)
		(width 0.4064)
		(layer "B.Cu")
		(net "GND")
	)
	(segment
		(start 127.392176 -129.546096)
		(end 127.392176 -129.564892)
		(width 0.4064)
		(layer "B.Cu")
		(net "GND")
	)
	(segment
		(start 166.19474 -3.68046)
		(end 165.4302 -4.445)
		(width 0.254)
		(layer "B.Cu")
		(net "GND")
	)
	(segment
		(start 296.69994 -9.156446)
		(end 296.69994 -10.623042)
		(width 0.4064)
		(layer "B.Cu")
		(net "GND")
	)
	(segment
		(start 141.899386 -25.645872)
		(end 141.62024 -25.925272)
		(width 0.4064)
		(layer "B.Cu")
		(net "GND")
	)
	(segment
		(start 312.391298 -16.696944)
		(end 312.849768 -16.238474)
		(width 0.4064)
		(layer "B.Cu")
		(net "GND")
	)
	(segment
		(start 136.74217 -148.748496)
		(end 136.74217 -148.767292)
		(width 0.4064)
		(layer "B.Cu")
		(net "GND")
	)
	(segment
		(start 446.672716 -18.1102)
		(end 446.291716 -17.7292)
		(width 0.254)
		(layer "B.Cu")
		(net "GND")
	)
	(segment
		(start 126.599442 -152.078436)
		(end 126.599442 -151.299164)
		(width 0.254)
		(layer "B.Cu")
		(net "GND")
	)
	(segment
		(start 172.70476 -73.9902)
		(end 173.482 -73.9902)
		(width 0.254)
		(layer "B.Cu")
		(net "GND")
	)
	(segment
		(start 378.930662 -55.33898)
		(end 378.930662 -54.97957)
		(width 0.254)
		(layer "B.Cu")
		(net "GND")
	)
	(segment
		(start 203.200508 -142.477236)
		(end 203.2 -142.476982)
		(width 0.4064)
		(layer "B.Cu")
		(net "GND")
	)
	(segment
		(start 371.5258 -56.67375)
		(end 371.22227 -56.97728)
		(width 0.254)
		(layer "B.Cu")
		(net "GND")
	)
	(segment
		(start 32.249364 -132.876036)
		(end 32.249364 -131.768342)
		(width 0.4064)
		(layer "B.Cu")
		(net "GND")
	)
	(segment
		(start 381.635 -46.228)
		(end 381.4953 -46.0883)
		(width 0.254)
		(layer "B.Cu")
		(net "GND")
	)
	(segment
		(start 55.199534 -132.876036)
		(end 55.199534 -132.062982)
		(width 0.4064)
		(layer "B.Cu")
		(net "GND")
	)
	(segment
		(start 300.70425 -131.084574)
		(end 300.70425 -131.7752)
		(width 0.4064)
		(layer "B.Cu")
		(net "GND")
	)
	(segment
		(start 33.703768 -131.851146)
		(end 33.703768 -131.7752)
		(width 0.254)
		(layer "B.Cu")
		(net "GND")
	)
	(segment
		(start 76.449428 -18.757646)
		(end 76.449428 -20.224242)
		(width 0.4064)
		(layer "B.Cu")
		(net "GND")
	)
	(segment
		(start 143.599408 -24.824182)
		(end 143.599408 -23.17496)
		(width 0.4064)
		(layer "B.Cu")
		(net "GND")
	)
	(segment
		(start 31.341568 0.515366)
		(end 31.341568 1.524)
		(width 0.381)
		(layer "B.Cu")
		(net "GND")
	)
	(segment
		(start 388.0358 -2.131568)
		(end 388.0358 -1.768602)
		(width 0.254)
		(layer "B.Cu")
		(net "GND")
	)
	(segment
		(start 472.71432 -136.42086)
		(end 472.487752 -136.42086)
		(width 0.254)
		(layer "B.Cu")
		(net "GND")
	)
	(segment
		(start 308.59984 -3.82524)
		(end 308.511956 -3.737356)
		(width 0.254)
		(layer "B.Cu")
		(net "GND")
	)
	(segment
		(start 434.721 -12.2682)
		(end 434.2384 -11.7856)
		(width 0.254)
		(layer "B.Cu")
		(net "GND")
	)
	(segment
		(start 295.85031 -142.477236)
		(end 295.849802 -142.476982)
		(width 0.4064)
		(layer "B.Cu")
		(net "GND")
	)
	(segment
		(start 53.499512 -18.80235)
		(end 53.499512 -20.224242)
		(width 0.4064)
		(layer "B.Cu")
		(net "GND")
	)
	(segment
		(start 237.199932 -10.623042)
		(end 237.199932 -9.20115)
		(width 0.4064)
		(layer "B.Cu")
		(net "GND")
	)
	(segment
		(start 201.500486 -15.222982)
		(end 201.499978 -15.222982)
		(width 0.4064)
		(layer "B.Cu")
		(net "GND")
	)
	(segment
		(start 222.75038 -20.224242)
		(end 222.749872 -20.224242)
		(width 0.4064)
		(layer "B.Cu")
		(net "GND")
	)
	(segment
		(start 212.54974 -24.529796)
		(end 212.54974 -22.965156)
		(width 0.4064)
		(layer "B.Cu")
		(net "GND")
	)
	(segment
		(start 226.9998 -15.222982)
		(end 226.9998 -14.4526)
		(width 0.254)
		(layer "B.Cu")
		(net "GND")
	)
	(segment
		(start 143.511524 -3.737356)
		(end 143.599408 -3.82524)
		(width 0.254)
		(layer "B.Cu")
		(net "GND")
	)
	(segment
		(start 126.353824 -13.431774)
		(end 126.353824 -14.1224)
		(width 0.4064)
		(layer "B.Cu")
		(net "GND")
	)
	(segment
		(start 461.869282 -34.478722)
		(end 461.397604 -34.9504)
		(width 0.254)
		(layer "B.Cu")
		(net "GND")
	)
	(segment
		(start 408.827478 -8.763)
		(end 408.8003 -8.763)
		(width 0.254)
		(layer "B.Cu")
		(net "GND")
	)
	(segment
		(start 42.436796 -139.170156)
		(end 42.411396 -139.170156)
		(width 0.4064)
		(layer "B.Cu")
		(net "GND")
	)
	(segment
		(start 65.399412 -1.021842)
		(end 65.399412 -2.314956)
		(width 0.4064)
		(layer "B.Cu")
		(net "GND")
	)
	(segment
		(start 410.5275 -4.318)
		(end 410.5275 -3.48742)
		(width 0.254)
		(layer "B.Cu")
		(net "GND")
	)
	(segment
		(start 116.386864 -129.568956)
		(end 116.361464 -129.568956)
		(width 0.4064)
		(layer "B.Cu")
		(net "GND")
	)
	(segment
		(start 152.099518 -18.757646)
		(end 152.099518 -20.224242)
		(width 0.4064)
		(layer "B.Cu")
		(net "GND")
	)
	(segment
		(start 231.249982 -142.476982)
		(end 231.249982 -142.10665)
		(width 0.4064)
		(layer "B.Cu")
		(net "GND")
	)
	(segment
		(start 226.7458 -23.041356)
		(end 226.822 -22.965156)
		(width 0.4064)
		(layer "B.Cu")
		(net "GND")
	)
	(segment
		(start 208.0514 -131.899152)
		(end 208.0514 -131.074668)
		(width 0.4064)
		(layer "B.Cu")
		(net "GND")
	)
	(segment
		(start 107.027472 -145.0086)
		(end 105.9561 -145.0086)
		(width 0.4572)
		(layer "B.Cu")
		(net "GND")
	)
	(segment
		(start 290.73729 -2.314956)
		(end 290.71189 -2.314956)
		(width 0.4064)
		(layer "B.Cu")
		(net "GND")
	)
	(segment
		(start 453.6948 -146.7612)
		(end 453.4154 -146.7612)
		(width 0.254)
		(layer "B.Cu")
		(net "GND")
	)
	(segment
		(start 38.199568 -7.606792)
		(end 38.199568 -5.621782)
		(width 0.4064)
		(layer "B.Cu")
		(net "GND")
	)
	(segment
		(start 151.24938 -15.222982)
		(end 151.24938 -17.208246)
		(width 0.4064)
		(layer "B.Cu")
		(net "GND")
	)
	(segment
		(start 116.399564 -147.478496)
		(end 116.399564 -148.758656)
		(width 0.4064)
		(layer "B.Cu")
		(net "GND")
	)
	(segment
		(start 118.041928 0.457454)
		(end 118.099332 0.40005)
		(width 0.4064)
		(layer "B.Cu")
		(net "GND")
	)
	(segment
		(start 135.099552 -2.302256)
		(end 135.086852 -2.314956)
		(width 0.4064)
		(layer "B.Cu")
		(net "GND")
	)
	(segment
		(start 135.099552 -128.276096)
		(end 135.099552 -129.556256)
		(width 0.4064)
		(layer "B.Cu")
		(net "GND")
	)
	(segment
		(start 203.200508 -132.876036)
		(end 203.2 -132.875782)
		(width 0.4064)
		(layer "B.Cu")
		(net "GND")
	)
	(segment
		(start 281.399996 -147.478496)
		(end 281.399996 -148.758656)
		(width 0.4064)
		(layer "B.Cu")
		(net "GND")
	)
	(segment
		(start 317.09995 -9.156446)
		(end 317.146432 -9.109964)
		(width 0.4064)
		(layer "B.Cu")
		(net "GND")
	)
	(segment
		(start 33.703768 -14.198346)
		(end 33.703768 -14.1224)
		(width 0.254)
		(layer "B.Cu")
		(net "GND")
	)
	(segment
		(start 278.849836 -20.224242)
		(end 278.849836 -18.786348)
		(width 0.4064)
		(layer "B.Cu")
		(net "GND")
	)
	(segment
		(start 306.899818 -7.607046)
		(end 306.899818 -5.621782)
		(width 0.4064)
		(layer "B.Cu")
		(net "GND")
	)
	(segment
		(start 374.015 -87.7189)
		(end 374.015 -86.632796)
		(width 0.254)
		(layer "B.Cu")
		(net "GND")
	)
	(segment
		(start 196.399912 -137.877296)
		(end 196.399912 -139.170156)
		(width 0.4064)
		(layer "B.Cu")
		(net "GND")
	)
	(segment
		(start 377.698 -82.7532)
		(end 377.698 -82.677)
		(width 0.254)
		(layer "B.Cu")
		(net "GND")
	)
	(segment
		(start 365.844328 -47.866808)
		(end 365.468408 -48.242728)
		(width 0.254)
		(layer "B.Cu")
		(net "GND")
	)
	(segment
		(start 416.179 -24.511)
		(end 416.179 -25.146)
		(width 0.254)
		(layer "B.Cu")
		(net "GND")
	)
	(segment
		(start 241.450368 -147.478496)
		(end 241.44986 -147.478496)
		(width 0.4064)
		(layer "B.Cu")
		(net "GND")
	)
	(segment
		(start 215.949784 -3.851656)
		(end 215.860884 -3.762756)
		(width 0.4064)
		(layer "B.Cu")
		(net "GND")
	)
	(segment
		(start 443.46368 -58.01614)
		(end 443.46368 -58.717688)
		(width 0.381)
		(layer "B.Cu")
		(net "GND")
	)
	(segment
		(start 418.6936 -19.2532)
		(end 418.6936 -17.201134)
		(width 0.254)
		(layer "B.Cu")
		(net "GND")
	)
	(segment
		(start 289.90036 -5.621782)
		(end 289.899852 -5.621782)
		(width 0.4064)
		(layer "B.Cu")
		(net "GND")
	)
	(segment
		(start 231.25049 -142.477236)
		(end 231.249982 -142.476982)
		(width 0.4064)
		(layer "B.Cu")
		(net "GND")
	)
	(segment
		(start 280.549858 -3.851656)
		(end 280.460958 -3.762756)
		(width 0.4064)
		(layer "B.Cu")
		(net "GND")
	)
	(segment
		(start 224.449894 0.457454)
		(end 224.449894 -1.021842)
		(width 0.4064)
		(layer "B.Cu")
		(net "GND")
	)
	(segment
		(start 256.8067 -144.8816)
		(end 256.39776 -145.29054)
		(width 0.4064)
		(layer "B.Cu")
		(net "GND")
	)
	(segment
		(start 378.116592 -54.1655)
		(end 377.1265 -54.1655)
		(width 0.254)
		(layer "B.Cu")
		(net "GND")
	)
	(segment
		(start 38.199568 -150.21941)
		(end 38.199314 -150.219156)
		(width 0.4064)
		(layer "B.Cu")
		(net "GND")
	)
	(segment
		(start 77.299312 -24.402796)
		(end 77.299566 -24.40305)
		(width 0.4064)
		(layer "B.Cu")
		(net "GND")
	)
	(segment
		(start 374.777 -101.62159)
		(end 374.8278 -101.67239)
		(width 0.254)
		(layer "B.Cu")
		(net "GND")
	)
	(segment
		(start 66.24955 -132.876036)
		(end 66.24955 -132.50545)
		(width 0.4064)
		(layer "B.Cu")
		(net "GND")
	)
	(segment
		(start 206.59979 -132.875782)
		(end 206.59979 -131.080256)
		(width 0.4064)
		(layer "B.Cu")
		(net "GND")
	)
	(segment
		(start 241.44986 -10.623042)
		(end 241.44986 -11.916156)
		(width 0.4064)
		(layer "B.Cu")
		(net "GND")
	)
	(segment
		(start 374.408446 -89.125806)
		(end 374.089168 -89.125806)
		(width 0.254)
		(layer "B.Cu")
		(net "GND")
	)
	(segment
		(start 61.149484 -18.757646)
		(end 61.149484 -20.224242)
		(width 0.4064)
		(layer "B.Cu")
		(net "GND")
	)
	(segment
		(start 121.499376 -17.208246)
		(end 121.499376 -15.222982)
		(width 0.4064)
		(layer "B.Cu")
		(net "GND")
	)
	(segment
		(start 417.576 -7.3025)
		(end 417.147248 -7.3025)
		(width 0.254)
		(layer "B.Cu")
		(net "GND")
	)
	(segment
		(start 182.071518 3.669792)
		(end 182.081932 3.669792)
		(width 0.254)
		(layer "B.Cu")
		(net "GND")
	)
	(segment
		(start 402.2344 -52.6669)
		(end 402.1963 -52.705)
		(width 0.254)
		(layer "B.Cu")
		(net "GND")
	)
	(segment
		(start 135.703818 -150.9776)
		(end 135.703818 -150.286974)
		(width 0.4064)
		(layer "B.Cu")
		(net "GND")
	)
	(segment
		(start 310.054244 -14.198346)
		(end 310.054244 -14.1224)
		(width 0.254)
		(layer "B.Cu")
		(net "GND")
	)
	(segment
		(start 309.450486 -147.478496)
		(end 309.449978 -147.478496)
		(width 0.4064)
		(layer "B.Cu")
		(net "GND")
	)
	(segment
		(start 138.499342 -14.409928)
		(end 138.03757 -13.948156)
		(width 0.4064)
		(layer "B.Cu")
		(net "GND")
	)
	(segment
		(start 440.112404 -151.602186)
		(end 440.040522 -151.674068)
		(width 0.254)
		(layer "B.Cu")
		(net "GND")
	)
	(segment
		(start 220.199966 -132.875782)
		(end 220.199966 -132.062982)
		(width 0.4064)
		(layer "B.Cu")
		(net "GND")
	)
	(segment
		(start 91.6559 -8.468868)
		(end 91.089226 -8.468868)
		(width 0.4064)
		(layer "B.Cu")
		(net "GND")
	)
	(segment
		(start 255.627124 -150.105364)
		(end 256.167636 -150.105364)
		(width 0.381)
		(layer "B.Cu")
		(net "GND")
	)
	(segment
		(start 68.799456 -1.021842)
		(end 68.799456 -2.314956)
		(width 0.4064)
		(layer "B.Cu")
		(net "GND")
	)
	(segment
		(start 311.658 -29.971238)
		(end 311.658 -35.987736)
		(width 0.381)
		(layer "B.Cu")
		(net "GND")
	)
	(segment
		(start 287.350454 -1.021842)
		(end 287.349946 -1.021842)
		(width 0.4064)
		(layer "B.Cu")
		(net "GND")
	)
	(segment
		(start 284.799786 -16.23822)
		(end 284.799786 -15.222982)
		(width 0.4064)
		(layer "B.Cu")
		(net "GND")
	)
	(segment
		(start 227.850446 -10.623042)
		(end 227.849938 -10.623042)
		(width 0.4064)
		(layer "B.Cu")
		(net "GND")
	)
	(segment
		(start 78.193392 -149.371304)
		(end 78.14945 -149.327362)
		(width 0.4064)
		(layer "B.Cu")
		(net "GND")
	)
	(segment
		(start 135.099552 -137.877296)
		(end 135.099552 -139.157456)
		(width 0.4064)
		(layer "B.Cu")
		(net "GND")
	)
	(segment
		(start 208.299812 -142.476982)
		(end 208.299812 -141.748764)
		(width 0.254)
		(layer "B.Cu")
		(net "GND")
	)
	(segment
		(start 127.392176 -21.494496)
		(end 127.392176 -21.513292)
		(width 0.4064)
		(layer "B.Cu")
		(net "GND")
	)
	(segment
		(start 277.288752 -157.9372)
		(end 275.685504 -157.9372)
		(width 0.381)
		(layer "B.Cu")
		(net "GND")
	)
	(segment
		(start 60.201302 -17.208246)
		(end 60.299346 -17.110202)
		(width 0.4064)
		(layer "B.Cu")
		(net "GND")
	)
	(segment
		(start 89.789 -12.954)
		(end 90.127582 -13.292582)
		(width 0.4064)
		(layer "B.Cu")
		(net "GND")
	)
	(segment
		(start 223.60001 -24.824182)
		(end 223.60001 -24.58085)
		(width 0.4064)
		(layer "B.Cu")
		(net "GND")
	)
	(segment
		(start 124.81052 -150.219156)
		(end 124.81052 -150.193756)
		(width 0.4064)
		(layer "B.Cu")
		(net "GND")
	)
	(segment
		(start 286.499808 -5.621782)
		(end 286.499808 -7.607046)
		(width 0.4064)
		(layer "B.Cu")
		(net "GND")
	)
	(segment
		(start 236.350302 -132.876036)
		(end 236.349794 -132.875782)
		(width 0.254)
		(layer "B.Cu")
		(net "GND")
	)
	(segment
		(start 45.84954 -152.078436)
		(end 45.84954 -151.265382)
		(width 0.4064)
		(layer "B.Cu")
		(net "GND")
	)
	(segment
		(start 290.73729 -148.771356)
		(end 290.71189 -148.771356)
		(width 0.4064)
		(layer "B.Cu")
		(net "GND")
	)
	(segment
		(start 114.699542 -147.478242)
		(end 114.699542 -147.478496)
		(width 0.4064)
		(layer "B.Cu")
		(net "GND")
	)
	(segment
		(start 371.887496 -89.859104)
		(end 372.0211 -89.7255)
		(width 0.254)
		(layer "B.Cu")
		(net "GND")
	)
	(segment
		(start 217.3986 -141.3764)
		(end 217.3986 -140.691362)
		(width 0.4064)
		(layer "B.Cu")
		(net "GND")
	)
	(segment
		(start 257.5814 -18.542)
		(end 257.6449 -18.542)
		(width 0.4064)
		(layer "B.Cu")
		(net "GND")
	)
	(segment
		(start 125.749558 -11.903456)
		(end 125.749558 -10.623042)
		(width 0.4064)
		(layer "B.Cu")
		(net "GND")
	)
	(segment
		(start 310.054244 -140.685774)
		(end 310.054244 -141.3764)
		(width 0.4064)
		(layer "B.Cu")
		(net "GND")
	)
	(segment
		(start 196.399912 -147.478496)
		(end 196.399912 -148.771356)
		(width 0.4064)
		(layer "B.Cu")
		(net "GND")
	)
	(segment
		(start 490.951266 -56.147462)
		(end 490.925866 -56.172862)
		(width 0.4064)
		(layer "B.Cu")
		(net "GND")
	)
	(segment
		(start 163.576 -81.788)
		(end 163.576 -81.4832)
		(width 0.4064)
		(layer "B.Cu")
		(net "GND")
	)
	(segment
		(start 469.043766 -8.010398)
		(end 466.548724 -8.010398)
		(width 0.254)
		(layer "B.Cu")
		(net "GND")
	)
	(segment
		(start 384.31724 -81.2673)
		(end 384.31724 -81.06918)
		(width 0.254)
		(layer "B.Cu")
		(net "GND")
	)
	(segment
		(start 230.399844 -11.916156)
		(end 230.399844 -10.623042)
		(width 0.4064)
		(layer "B.Cu")
		(net "GND")
	)
	(segment
		(start 61.149484 -20.224242)
		(end 61.149484 -21.504656)
		(width 0.4064)
		(layer "B.Cu")
		(net "GND")
	)
	(segment
		(start 45.387514 -13.948156)
		(end 45.84954 -14.410182)
		(width 0.4064)
		(layer "B.Cu")
		(net "GND")
	)
	(segment
		(start 241.450368 -137.877296)
		(end 241.44986 -137.877296)
		(width 0.4064)
		(layer "B.Cu")
		(net "GND")
	)
	(segment
		(start 206.59979 -24.824182)
		(end 206.59979 -23.028656)
		(width 0.4064)
		(layer "B.Cu")
		(net "GND")
	)
	(segment
		(start 456.7555 -135.9662)
		(end 458.355954 -135.9662)
		(width 0.508)
		(layer "B.Cu")
		(net "GND")
	)
	(segment
		(start 72.1995 -21.437092)
		(end 72.142096 -21.494496)
		(width 0.4064)
		(layer "B.Cu")
		(net "GND")
	)
	(segment
		(start 315.595508 -28.762452)
		(end 316.060074 -28.297886)
		(width 0.254)
		(layer "B.Cu")
		(net "GND")
	)
	(segment
		(start 148.699474 -20.224242)
		(end 148.699474 -21.517356)
		(width 0.4064)
		(layer "B.Cu")
		(net "GND")
	)
	(segment
		(start 389.14451 -44.86783)
		(end 389.151368 -44.874688)
		(width 0.254)
		(layer "B.Cu")
		(net "GND")
	)
	(segment
		(start 309.437278 -129.568956)
		(end 309.449978 -129.556256)
		(width 0.4064)
		(layer "B.Cu")
		(net "GND")
	)
	(segment
		(start 431.98034 -18.613628)
		(end 432.498246 -18.095722)
		(width 0.381)
		(layer "B.Cu")
		(net "GND")
	)
	(segment
		(start 141.049502 -1.021842)
		(end 141.049502 -2.314956)
		(width 0.4064)
		(layer "B.Cu")
		(net "GND")
	)
	(segment
		(start 78.613 -150.114)
		(end 78.204568 -150.114)
		(width 0.508)
		(layer "B.Cu")
		(net "GND")
	)
	(segment
		(start 410.8069 -14.097)
		(end 411.3022 -14.097)
		(width 0.254)
		(layer "B.Cu")
		(net "GND")
	)
	(segment
		(start 494.082578 -43.948858)
		(end 494.387124 -43.644312)
		(width 0.254)
		(layer "B.Cu")
		(net "GND")
	)
	(segment
		(start 235.49991 -139.132056)
		(end 235.46181 -139.170156)
		(width 0.4064)
		(layer "B.Cu")
		(net "GND")
	)
	(segment
		(start 56.899556 -5.27685)
		(end 56.899556 -5.621782)
		(width 0.4064)
		(layer "B.Cu")
		(net "GND")
	)
	(segment
		(start 59.449462 -11.916156)
		(end 59.449462 -10.623042)
		(width 0.4064)
		(layer "B.Cu")
		(net "GND")
	)
	(segment
		(start 36.499546 -6.63702)
		(end 36.040822 -7.095744)
		(width 0.4064)
		(layer "B.Cu")
		(net "GND")
	)
	(segment
		(start 206.59979 -142.476982)
		(end 206.59979 -140.681456)
		(width 0.4064)
		(layer "B.Cu")
		(net "GND")
	)
	(segment
		(start 43.29938 -24.095964)
		(end 43.050968 -23.847552)
		(width 0.254)
		(layer "B.Cu")
		(net "GND")
	)
	(segment
		(start 230.399844 -1.021842)
		(end 230.399844 0.444754)
		(width 0.4064)
		(layer "B.Cu")
		(net "GND")
	)
	(segment
		(start 120.649492 -11.916156)
		(end 120.649492 -10.623042)
		(width 0.4064)
		(layer "B.Cu")
		(net "GND")
	)
	(segment
		(start 231.249982 -25.638252)
		(end 231.249982 -24.824182)
		(width 0.4064)
		(layer "B.Cu")
		(net "GND")
	)
	(segment
		(start 135.099552 -129.556256)
		(end 135.086852 -129.568956)
		(width 0.4064)
		(layer "B.Cu")
		(net "GND")
	)
	(segment
		(start 39.899336 -152.078436)
		(end 39.899336 -150.219156)
		(width 0.4064)
		(layer "B.Cu")
		(net "GND")
	)
	(segment
		(start 163.74618 3.3782)
		(end 163.74618 2.264664)
		(width 0.254)
		(layer "B.Cu")
		(net "GND")
	)
	(segment
		(start 312.849768 -24.824182)
		(end 312.850276 -24.824182)
		(width 0.4064)
		(layer "B.Cu")
		(net "GND")
	)
	(segment
		(start 223.600518 -5.621782)
		(end 223.60001 -5.621782)
		(width 0.4064)
		(layer "B.Cu")
		(net "GND")
	)
	(segment
		(start 48.399446 -147.478496)
		(end 48.399446 -148.771356)
		(width 0.4064)
		(layer "B.Cu")
		(net "GND")
	)
	(segment
		(start 453.24141 -3.029204)
		(end 453.545448 -2.725166)
		(width 0.254)
		(layer "B.Cu")
		(net "GND")
	)
	(segment
		(start 44.149518 -21.437092)
		(end 44.092114 -21.494496)
		(width 0.4064)
		(layer "B.Cu")
		(net "GND")
	)
	(segment
		(start 132.549392 -24.824182)
		(end 132.549392 -25.661112)
		(width 0.4064)
		(layer "B.Cu")
		(net "GND")
	)
	(segment
		(start 215.950292 -5.621782)
		(end 215.949784 -5.621782)
		(width 0.4064)
		(layer "B.Cu")
		(net "GND")
	)
	(segment
		(start 284.800294 -151.26589)
		(end 284.33776 -150.803356)
		(width 0.4064)
		(layer "B.Cu")
		(net "GND")
	)
	(segment
		(start 281.387296 -129.568956)
		(end 281.399996 -129.556256)
		(width 0.4064)
		(layer "B.Cu")
		(net "GND")
	)
	(segment
		(start 299.160946 -150.219156)
		(end 299.160946 -150.193756)
		(width 0.4064)
		(layer "B.Cu")
		(net "GND")
	)
	(segment
		(start 75.59929 -3.762756)
		(end 75.59929 -5.251196)
		(width 0.4064)
		(layer "B.Cu")
		(net "GND")
	)
	(segment
		(start 223.60001 -17.207992)
		(end 223.60001 -15.222982)
		(width 0.4064)
		(layer "B.Cu")
		(net "GND")
	)
	(segment
		(start 223.599756 -5.378196)
		(end 223.599756 -3.762756)
		(width 0.4064)
		(layer "B.Cu")
		(net "GND")
	)
	(segment
		(start 292.392608 -148.767292)
		(end 292.392608 -148.748496)
		(width 0.4064)
		(layer "B.Cu")
		(net "GND")
	)
	(segment
		(start 47.549562 -17.207992)
		(end 47.549562 -15.222982)
		(width 0.4064)
		(layer "B.Cu")
		(net "GND")
	)
	(segment
		(start 317.09995 -143.941546)
		(end 317.09995 -144.987518)
		(width 0.508)
		(layer "B.Cu")
		(net "GND")
	)
	(segment
		(start 151.24938 -142.477236)
		(end 151.24938 -140.617956)
		(width 0.4064)
		(layer "B.Cu")
		(net "GND")
	)
	(segment
		(start 315.400436 -137.877296)
		(end 315.399928 -137.877296)
		(width 0.4064)
		(layer "B.Cu")
		(net "GND")
	)
	(segment
		(start 134.249414 -25.683718)
		(end 135.061452 -26.495756)
		(width 0.4064)
		(layer "B.Cu")
		(net "GND")
	)
	(segment
		(start 378.763784 -55.505858)
		(end 378.930662 -55.33898)
		(width 0.254)
		(layer "B.Cu")
		(net "GND")
	)
	(segment
		(start 225.210878 -140.617956)
		(end 225.210878 -140.592556)
		(width 0.4064)
		(layer "B.Cu")
		(net "GND")
	)
	(segment
		(start 145.29943 -5.621782)
		(end 145.29943 -7.4676)
		(width 0.4064)
		(layer "B.Cu")
		(net "GND")
	)
	(segment
		(start 225.210878 -131.016756)
		(end 225.210878 -130.991356)
		(width 0.4064)
		(layer "B.Cu")
		(net "GND")
	)
	(segment
		(start 33.703768 -23.7236)
		(end 33.703768 -23.032974)
		(width 0.4064)
		(layer "B.Cu")
		(net "GND")
	)
	(segment
		(start 404.913846 -25.600152)
		(end 404.913846 -25.227534)
		(width 0.254)
		(layer "B.Cu")
		(net "GND")
	)
	(segment
		(start 410.387292 -3.225292)
		(end 410.21 -3.048)
		(width 0.254)
		(layer "B.Cu")
		(net "GND")
	)
	(segment
		(start 34.799524 0.40005)
		(end 34.74212 0.457454)
		(width 0.4064)
		(layer "B.Cu")
		(net "GND")
	)
	(segment
		(start 311.092596 -21.494496)
		(end 311.15 -21.437092)
		(width 0.4064)
		(layer "B.Cu")
		(net "GND")
	)
	(segment
		(start 209.150458 -147.478496)
		(end 209.14995 -147.478496)
		(width 0.4064)
		(layer "B.Cu")
		(net "GND")
	)
	(segment
		(start 226.137216 -11.916156)
		(end 226.149916 -11.903456)
		(width 0.4064)
		(layer "B.Cu")
		(net "GND")
	)
	(segment
		(start 60.299346 -7.509002)
		(end 60.201302 -7.607046)
		(width 0.4064)
		(layer "B.Cu")
		(net "GND")
	)
	(segment
		(start 378.930662 -54.97957)
		(end 378.116592 -54.1655)
		(width 0.254)
		(layer "B.Cu")
		(net "GND")
	)
	(segment
		(start 54.737508 -4.346956)
		(end 55.199534 -4.808982)
		(width 0.4064)
		(layer "B.Cu")
		(net "GND")
	)
	(segment
		(start 210.85048 -152.078436)
		(end 210.849972 -152.078182)
		(width 0.4064)
		(layer "B.Cu")
		(net "GND")
	)
	(segment
		(start 134.249414 -142.477236)
		(end 134.249414 -140.706856)
		(width 0.4064)
		(layer "B.Cu")
		(net "GND")
	)
	(segment
		(start 321.59702 -135.376412)
		(end 321.591432 -135.382)
		(width 0.4064)
		(layer "B.Cu")
		(net "GND")
	)
	(segment
		(start 439.626756 -143.589756)
		(end 439.626756 -144.478756)
		(width 0.254)
		(layer "B.Cu")
		(net "GND")
	)
	(segment
		(start 409.224988 -8.338312)
		(end 409.428188 -8.338312)
		(width 0.254)
		(layer "B.Cu")
		(net "GND")
	)
	(segment
		(start 305.200304 -5.621782)
		(end 305.199796 -5.621782)
		(width 0.4064)
		(layer "B.Cu")
		(net "GND")
	)
	(segment
		(start 398.379696 -77.64272)
		(end 399.49628 -77.64272)
		(width 0.254)
		(layer "B.Cu")
		(net "GND")
	)
	(segment
		(start 76.451968 -28.5242)
		(end 76.779628 -28.85186)
		(width 0.381)
		(layer "B.Cu")
		(net "GND")
	)
	(segment
		(start 300.70425 -4.597146)
		(end 300.949868 -4.842764)
		(width 0.254)
		(layer "B.Cu")
		(net "GND")
	)
	(segment
		(start 305.200304 -15.222982)
		(end 305.199796 -15.222982)
		(width 0.4064)
		(layer "B.Cu")
		(net "GND")
	)
	(segment
		(start 113.849404 -150.777956)
		(end 113.849404 -152.078436)
		(width 0.4064)
		(layer "B.Cu")
		(net "GND")
	)
	(segment
		(start 280.550366 -152.078436)
		(end 280.550366 -150.308564)
		(width 0.4064)
		(layer "B.Cu")
		(net "GND")
	)
	(segment
		(start 244.3353 -149.8092)
		(end 243.9162 -149.8092)
		(width 0.4572)
		(layer "B.Cu")
		(net "GND")
	)
	(segment
		(start 232.950004 -152.078182)
		(end 232.950004 -151.78405)
		(width 0.4064)
		(layer "B.Cu")
		(net "GND")
	)
	(segment
		(start 352.02368 -89.067132)
		(end 352.02368 -88.622632)
		(width 0.254)
		(layer "B.Cu")
		(net "GND")
	)
	(segment
		(start 122.349514 -18.757646)
		(end 122.349514 -20.224242)
		(width 0.4064)
		(layer "B.Cu")
		(net "GND")
	)
	(segment
		(start 282.004262 -14.198346)
		(end 282.004262 -14.1224)
		(width 0.254)
		(layer "B.Cu")
		(net "GND")
	)
	(segment
		(start 117.00383 -131.902708)
		(end 117.00383 -131.059174)
		(width 0.3556)
		(layer "B.Cu")
		(net "GND")
	)
	(segment
		(start 62.849506 -1.021842)
		(end 62.849506 -2.234692)
		(width 0.4064)
		(layer "B.Cu")
		(net "GND")
	)
	(segment
		(start 255.4224 -8.1534)
		(end 255.768856 -7.806944)
		(width 0.4572)
		(layer "B.Cu")
		(net "GND")
	)
	(segment
		(start 55.199534 -152.078436)
		(end 55.199534 -151.265382)
		(width 0.4064)
		(layer "B.Cu")
		(net "GND")
	)
	(segment
		(start 227.849938 -147.478496)
		(end 227.849938 -148.691092)
		(width 0.4064)
		(layer "B.Cu")
		(net "GND")
	)
	(segment
		(start 58.599324 -24.580596)
		(end 58.599578 -24.58085)
		(width 0.4064)
		(layer "B.Cu")
		(net "GND")
	)
	(segment
		(start 32.249364 -152.078436)
		(end 32.249364 -150.970742)
		(width 0.4064)
		(layer "B.Cu")
		(net "GND")
	)
	(segment
		(start 134.160514 -140.617956)
		(end 134.160514 -140.592556)
		(width 0.4064)
		(layer "B.Cu")
		(net "GND")
	)
	(segment
		(start 297.549824 -25.661112)
		(end 298.384468 -26.495756)
		(width 0.4064)
		(layer "B.Cu")
		(net "GND")
	)
	(segment
		(start 458.761592 -144.145)
		(end 459.221332 -143.68526)
		(width 0.381)
		(layer "B.Cu")
		(net "GND")
	)
	(segment
		(start 79.334868 -140.208)
		(end 78.2574 -140.208)
		(width 0.4064)
		(layer "B.Cu")
		(net "GND")
	)
	(segment
		(start 195.549774 -152.078182)
		(end 195.549774 -150.642574)
		(width 0.4064)
		(layer "B.Cu")
		(net "GND")
	)
	(segment
		(start 480.4664 -147.3708)
		(end 480.0092 -147.3708)
		(width 0.254)
		(layer "B.Cu")
		(net "GND")
	)
	(segment
		(start 226.9998 -152.078182)
		(end 226.9998 -151.3078)
		(width 0.254)
		(layer "B.Cu")
		(net "GND")
	)
	(segment
		(start 62.792102 0.457454)
		(end 62.849506 0.40005)
		(width 0.4064)
		(layer "B.Cu")
		(net "GND")
	)
	(segment
		(start 287.350454 -128.276096)
		(end 287.349946 -128.276096)
		(width 0.4064)
		(layer "B.Cu")
		(net "GND")
	)
	(segment
		(start 36.499546 -24.824182)
		(end 36.499546 -24.011382)
		(width 0.4064)
		(layer "B.Cu")
		(net "GND")
	)
	(segment
		(start 132.549392 -132.876036)
		(end 132.549392 -131.016756)
		(width 0.4064)
		(layer "B.Cu")
		(net "GND")
	)
	(segment
		(start 243.149882 -18.766282)
		(end 243.1288 -18.7452)
		(width 0.4064)
		(layer "B.Cu")
		(net "GND")
	)
	(segment
		(start 388.235952 -7.12216)
		(end 388.209536 -7.12216)
		(width 0.254)
		(layer "B.Cu")
		(net "GND")
	)
	(segment
		(start 241.44986 -147.478496)
		(end 241.44986 -148.771356)
		(width 0.4064)
		(layer "B.Cu")
		(net "GND")
	)
	(segment
		(start 410.590492 -31.634684)
		(end 410.590492 -31.107888)
		(width 0.508)
		(layer "B.Cu")
		(net "GND")
	)
	(segment
		(start 9.542272 -121.94413)
		(end 9.542272 -122.640344)
		(width 0.254)
		(layer "B.Cu")
		(net "GND")
	)
	(segment
		(start 490.823758 -38.068758)
		(end 490.823758 -38.885622)
		(width 0.254)
		(layer "B.Cu")
		(net "GND")
	)
	(segment
		(start 56.049418 -10.623042)
		(end 56.049418 -11.916156)
		(width 0.4064)
		(layer "B.Cu")
		(net "GND")
	)
	(segment
		(start 231.25049 -5.621782)
		(end 231.249982 -5.621782)
		(width 0.4064)
		(layer "B.Cu")
		(net "GND")
	)
	(segment
		(start 212.549994 -152.078182)
		(end 212.549994 -151.78405)
		(width 0.4064)
		(layer "B.Cu")
		(net "GND")
	)
	(segment
		(start 116.399564 -10.623042)
		(end 116.399564 -9.156446)
		(width 0.4064)
		(layer "B.Cu")
		(net "GND")
	)
	(segment
		(start 41.599358 -142.477236)
		(end 41.599358 -140.681456)
		(width 0.4064)
		(layer "B.Cu")
		(net "GND")
	)
	(segment
		(start 50.099468 -2.314956)
		(end 50.099468 -1.021842)
		(width 0.4064)
		(layer "B.Cu")
		(net "GND")
	)
	(segment
		(start 301.742602 -139.147296)
		(end 301.742602 -139.166092)
		(width 0.4064)
		(layer "B.Cu")
		(net "GND")
	)
	(segment
		(start 291.600382 -142.477236)
		(end 291.599874 -142.476982)
		(width 0.254)
		(layer "B.Cu")
		(net "GND")
	)
	(segment
		(start 413.86252 -44.98848)
		(end 413.511492 -44.637452)
		(width 0.254)
		(layer "B.Cu")
		(net "GND")
	)
	(segment
		(start 124.89942 -131.105656)
		(end 124.81052 -131.016756)
		(width 0.4064)
		(layer "B.Cu")
		(net "GND")
	)
	(segment
		(start 67.949572 -142.18285)
		(end 67.949318 -142.182596)
		(width 0.4064)
		(layer "B.Cu")
		(net "GND")
	)
	(segment
		(start 401.412456 -29.302456)
		(end 400.812 -28.702)
		(width 0.381)
		(layer "B.Cu")
		(net "GND")
	)
	(segment
		(start 40.749474 -147.478496)
		(end 40.749474 -148.771356)
		(width 0.4064)
		(layer "B.Cu")
		(net "GND")
	)
	(segment
		(start 282.24988 -24.045164)
		(end 282.004262 -23.799546)
		(width 0.254)
		(layer "B.Cu")
		(net "GND")
	)
	(segment
		(start 198.099934 -139.157456)
		(end 198.087234 -139.170156)
		(width 0.4064)
		(layer "B.Cu")
		(net "GND")
	)
	(segment
		(start 407.156158 -26.035)
		(end 407.9875 -26.035)
		(width 0.254)
		(layer "B.Cu")
		(net "GND")
	)
	(segment
		(start 126.353824 -131.084574)
		(end 126.421642 -131.016756)
		(width 0.4064)
		(layer "B.Cu")
		(net "GND")
	)
	(segment
		(start 412.770828 1.579372)
		(end 413.1056 1.2446)
		(width 0.254)
		(layer "B.Cu")
		(net "GND")
	)
	(segment
		(start 244.129306 -64.2874)
		(end 243.615718 -64.2874)
		(width 0.254)
		(layer "B.Cu")
		(net "GND")
	)
	(segment
		(start 237.149132 -26.73731)
		(end 236.349794 -25.937972)
		(width 0.4064)
		(layer "B.Cu")
		(net "GND")
	)
	(segment
		(start 116.399564 -20.224242)
		(end 116.399564 -21.504656)
		(width 0.4064)
		(layer "B.Cu")
		(net "GND")
	)
	(segment
		(start 191.314832 1.191768)
		(end 191.314832 2.1336)
		(width 0.508)
		(layer "B.Cu")
		(net "GND")
	)
	(segment
		(start 424.2435 -22.0345)
		(end 424.1165 -21.9075)
		(width 0.254)
		(layer "B.Cu")
		(net "GND")
	)
	(segment
		(start 124.81052 -131.016756)
		(end 124.81052 -130.991356)
		(width 0.4064)
		(layer "B.Cu")
		(net "GND")
	)
	(segment
		(start 400.97202 -74.53122)
		(end 400.939 -74.4982)
		(width 0.254)
		(layer "B.Cu")
		(net "GND")
	)
	(segment
		(start 75.599544 -132.876036)
		(end 75.599544 -132.50545)
		(width 0.4064)
		(layer "B.Cu")
		(net "GND")
	)
	(segment
		(start 182.089298 3.664966)
		(end 182.071518 3.664966)
		(width 0.254)
		(layer "B.Cu")
		(net "GND")
	)
	(segment
		(start 281.387296 -148.771356)
		(end 281.361896 -148.771356)
		(width 0.4064)
		(layer "B.Cu")
		(net "GND")
	)
	(segment
		(start 97.42932 -127.600202)
		(end 97.42932 -126.43358)
		(width 0.381)
		(layer "B.Cu")
		(net "GND")
	)
	(segment
		(start 43.050968 -23.847552)
		(end 43.050968 -23.023068)
		(width 0.4064)
		(layer "B.Cu")
		(net "GND")
	)
	(segment
		(start 32.249364 -14.115542)
		(end 32.160464 -14.026642)
		(width 0.4064)
		(layer "B.Cu")
		(net "GND")
	)
	(segment
		(start 242.287044 -140.617956)
		(end 242.299744 -140.630656)
		(width 0.4064)
		(layer "B.Cu")
		(net "GND")
	)
	(segment
		(start 57.74944 -10.623042)
		(end 57.74944 -11.916156)
		(width 0.4064)
		(layer "B.Cu")
		(net "GND")
	)
	(segment
		(start 113.897156 -9.083294)
		(end 113.849404 -9.131046)
		(width 0.4064)
		(layer "B.Cu")
		(net "GND")
	)
	(segment
		(start 122.349514 0.444754)
		(end 122.349514 -1.021842)
		(width 0.4064)
		(layer "B.Cu")
		(net "GND")
	)
	(segment
		(start 71.349362 -132.1054)
		(end 71.095362 -131.8514)
		(width 0.254)
		(layer "B.Cu")
		(net "GND")
	)
	(segment
		(start 135.061452 -21.517356)
		(end 135.099552 -21.479256)
		(width 0.4064)
		(layer "B.Cu")
		(net "GND")
	)
	(segment
		(start 149.549358 -5.621782)
		(end 149.549358 -7.607046)
		(width 0.4064)
		(layer "B.Cu")
		(net "GND")
	)
	(segment
		(start 53.499512 -9.20115)
		(end 53.499512 -10.623042)
		(width 0.4064)
		(layer "B.Cu")
		(net "GND")
	)
	(segment
		(start 383.35712 -81.61274)
		(end 383.9718 -81.61274)
		(width 0.254)
		(layer "B.Cu")
		(net "GND")
	)
	(segment
		(start 227.850446 -137.877296)
		(end 227.849938 -137.877296)
		(width 0.4064)
		(layer "B.Cu")
		(net "GND")
	)
	(segment
		(start 450.141594 -17.1831)
		(end 450.141594 -17.9451)
		(width 0.254)
		(layer "B.Cu")
		(net "GND")
	)
	(segment
		(start 198.099934 -20.224242)
		(end 198.099934 -18.757646)
		(width 0.4064)
		(layer "B.Cu")
		(net "GND")
	)
	(segment
		(start 310.299862 -132.875782)
		(end 310.30037 -132.876036)
		(width 0.254)
		(layer "B.Cu")
		(net "GND")
	)
	(segment
		(start 126.353824 -140.685774)
		(end 126.421642 -140.617956)
		(width 0.4064)
		(layer "B.Cu")
		(net "GND")
	)
	(segment
		(start 198.7042 -150.9776)
		(end 198.7042 -150.286974)
		(width 0.4064)
		(layer "B.Cu")
		(net "GND")
	)
	(segment
		(start 175.36668 -82.677)
		(end 175.36668 -81.407)
		(width 0.381)
		(layer "B.Cu")
		(net "GND")
	)
	(segment
		(start 421.390826 -24.158194)
		(end 421.390826 -24.252174)
		(width 0.254)
		(layer "B.Cu")
		(net "GND")
	)
	(segment
		(start 292.45052 -1.021842)
		(end 292.450012 -1.021842)
		(width 0.4064)
		(layer "B.Cu")
		(net "GND")
	)
	(segment
		(start 53.499512 -1.021842)
		(end 53.499512 -2.234692)
		(width 0.4064)
		(layer "B.Cu")
		(net "GND")
	)
	(segment
		(start 412.68142 -14.097)
		(end 411.3022 -14.097)
		(width 0.254)
		(layer "B.Cu")
		(net "GND")
	)
	(segment
		(start 379.9967 -46.3423)
		(end 379.9967 -46.674532)
		(width 0.254)
		(layer "B.Cu")
		(net "GND")
	)
	(segment
		(start 221.899734 -132.530596)
		(end 221.899734 -131.016756)
		(width 0.4064)
		(layer "B.Cu")
		(net "GND")
	)
	(segment
		(start 379.66015 -45.188378)
		(end 379.66015 -45.181774)
		(width 0.254)
		(layer "B.Cu")
		(net "GND")
	)
	(segment
		(start 21.534374 -85.110574)
		(end 21.534374 -84.455)
		(width 0.254)
		(layer "B.Cu")
		(net "GND")
	)
	(segment
		(start 209.092546 -2.310892)
		(end 209.092546 -2.292096)
		(width 0.4064)
		(layer "B.Cu")
		(net "GND")
	)
	(segment
		(start 482.621844 -56.090058)
		(end 482.835458 -56.090058)
		(width 0.254)
		(layer "B.Cu")
		(net "GND")
	)
	(segment
		(start 209.092546 -129.546096)
		(end 209.092546 -129.564892)
		(width 0.4064)
		(layer "B.Cu")
		(net "GND")
	)
	(segment
		(start 247.4214 -26.3398)
		(end 247.1166 -26.6446)
		(width 0.4064)
		(layer "B.Cu")
		(net "GND")
	)
	(segment
		(start 281.400504 -20.224242)
		(end 281.399996 -20.224242)
		(width 0.4064)
		(layer "B.Cu")
		(net "GND")
	)
	(segment
		(start 129.149348 -5.621782)
		(end 129.149348 -6.637274)
		(width 0.4064)
		(layer "B.Cu")
		(net "GND")
	)
	(segment
		(start 127.44958 -20.224242)
		(end 127.44958 -21.437092)
		(width 0.4064)
		(layer "B.Cu")
		(net "GND")
	)
	(segment
		(start 369.944904 -70.695312)
		(end 369.944904 -70.694296)
		(width 0.254)
		(layer "B.Cu")
		(net "GND")
	)
	(segment
		(start 376.428 -99.748086)
		(end 375.052082 -98.372168)
		(width 0.254)
		(layer "B.Cu")
		(net "GND")
	)
	(segment
		(start 206.59979 -13.427456)
		(end 206.51089 -13.338556)
		(width 0.4064)
		(layer "B.Cu")
		(net "GND")
	)
	(segment
		(start 198.7042 -23.032974)
		(end 198.772018 -22.965156)
		(width 0.4064)
		(layer "B.Cu")
		(net "GND")
	)
	(segment
		(start 310.054244 -23.7236)
		(end 310.054244 -23.799546)
		(width 0.254)
		(layer "B.Cu")
		(net "GND")
	)
	(segment
		(start 142.749524 0.457454)
		(end 142.749524 -1.021842)
		(width 0.4064)
		(layer "B.Cu")
		(net "GND")
	)
	(segment
		(start 292.392608 -139.147296)
		(end 292.392608 -139.166092)
		(width 0.4064)
		(layer "B.Cu")
		(net "GND")
	)
	(segment
		(start 29.878528 -144.4752)
		(end 29.436568 -144.4752)
		(width 0.4064)
		(layer "B.Cu")
		(net "GND")
	)
	(segment
		(start 317.627 2.19202)
		(end 317.627 1.928368)
		(width 0.4064)
		(layer "B.Cu")
		(net "GND")
	)
	(segment
		(start 225.300286 -5.621782)
		(end 225.299778 -5.621782)
		(width 0.4064)
		(layer "B.Cu")
		(net "GND")
	)
	(segment
		(start 246.61876 -12.954)
		(end 246.5832 -12.91844)
		(width 0.4064)
		(layer "B.Cu")
		(net "GND")
	)
	(segment
		(start 130.84937 -25.654508)
		(end 131.690618 -26.495756)
		(width 0.4064)
		(layer "B.Cu")
		(net "GND")
	)
	(segment
		(start 169.063416 -130.25374)
		(end 168.81094 -130.25374)
		(width 0.381)
		(layer "B.Cu")
		(net "GND")
	)
	(segment
		(start 223.60001 -15.222982)
		(end 223.60001 -14.97965)
		(width 0.4064)
		(layer "B.Cu")
		(net "GND")
	)
	(segment
		(start 281.399996 -10.623042)
		(end 281.399996 -11.903456)
		(width 0.4064)
		(layer "B.Cu")
		(net "GND")
	)
	(segment
		(start 58.599578 -152.078436)
		(end 58.599578 -151.83485)
		(width 0.4064)
		(layer "B.Cu")
		(net "GND")
	)
	(segment
		(start 116.399564 0.444754)
		(end 116.399564 -1.021842)
		(width 0.4064)
		(layer "B.Cu")
		(net "GND")
	)
	(segment
		(start 322.168774 -124.564648)
		(end 323.194426 -124.564648)
		(width 0.254)
		(layer "B.Cu")
		(net "GND")
	)
	(segment
		(start 498.3734 -148.1582)
		(end 498.221 -148.0058)
		(width 0.254)
		(layer "B.Cu")
		(net "GND")
	)
	(segment
		(start 396.875 -77.461872)
		(end 397.137128 -77.724)
		(width 0.254)
		(layer "B.Cu")
		(net "GND")
	)
	(segment
		(start 418.6936 -17.201134)
		(end 418.0078 -17.201134)
		(width 0.254)
		(layer "B.Cu")
		(net "GND")
	)
	(segment
		(start 31.908496 -81.186782)
		(end 31.713678 -81.3816)
		(width 0.254)
		(layer "B.Cu")
		(net "GND")
	)
	(segment
		(start 282.24988 -132.875782)
		(end 282.24988 -132.148326)
		(width 0.3556)
		(layer "B.Cu")
		(net "GND")
	)
	(segment
		(start 33.086802 -148.771356)
		(end 33.061402 -148.771356)
		(width 0.4064)
		(layer "B.Cu")
		(net "GND")
	)
	(segment
		(start 19.05 -44.831)
		(end 18.161 -44.831)
		(width 0.254)
		(layer "B.Cu")
		(net "GND")
	)
	(segment
		(start 292.450012 -21.437092)
		(end 292.450012 -20.224242)
		(width 0.4064)
		(layer "B.Cu")
		(net "GND")
	)
	(segment
		(start 76.449428 -9.156446)
		(end 76.449428 -10.623042)
		(width 0.4064)
		(layer "B.Cu")
		(net "GND")
	)
	(segment
		(start 209.14995 -129.488692)
		(end 209.092546 -129.546096)
		(width 0.4064)
		(layer "B.Cu")
		(net "GND")
	)
	(segment
		(start 199.800464 -20.224242)
		(end 199.799956 -20.224242)
		(width 0.4064)
		(layer "B.Cu")
		(net "GND")
	)
	(segment
		(start 307.750464 -147.478496)
		(end 307.749956 -147.478496)
		(width 0.4064)
		(layer "B.Cu")
		(net "GND")
	)
	(segment
		(start 482.854 -34.804096)
		(end 483.650544 -35.60064)
		(width 0.254)
		(layer "B.Cu")
		(net "GND")
	)
	(segment
		(start 114.822224 -126.883414)
		(end 114.822224 -126.363984)
		(width 0.508)
		(layer "B.Cu")
		(net "GND")
	)
	(segment
		(start 250.7615 -149.8092)
		(end 249.9106 -149.8092)
		(width 0.4064)
		(layer "B.Cu")
		(net "GND")
	)
	(segment
		(start 380.2888 -45.1485)
		(end 380.746 -45.6057)
		(width 0.254)
		(layer "B.Cu")
		(net "GND")
	)
	(segment
		(start 72.142096 -11.893296)
		(end 72.142096 -11.912092)
		(width 0.4064)
		(layer "B.Cu")
		(net "GND")
	)
	(segment
		(start 196.40042 -128.276096)
		(end 196.399912 -128.276096)
		(width 0.4064)
		(layer "B.Cu")
		(net "GND")
	)
	(segment
		(start 300.100492 -20.224242)
		(end 300.099984 -20.224242)
		(width 0.4064)
		(layer "B.Cu")
		(net "GND")
	)
	(segment
		(start 226.149916 -139.157456)
		(end 226.137216 -139.170156)
		(width 0.4064)
		(layer "B.Cu")
		(net "GND")
	)
	(segment
		(start 11.249914 -45.310044)
		(end 12.683998 -43.87596)
		(width 0.508)
		(layer "B.Cu")
		(net "GND")
	)
	(segment
		(start 59.449462 -137.877296)
		(end 59.449462 -139.170156)
		(width 0.4064)
		(layer "B.Cu")
		(net "GND")
	)
	(segment
		(start 283.099764 -20.224242)
		(end 283.099764 -21.437092)
		(width 0.4064)
		(layer "B.Cu")
		(net "GND")
	)
	(segment
		(start 405.6507 -17.17294)
		(end 405.369522 -17.454118)
		(width 0.254)
		(layer "B.Cu")
		(net "GND")
	)
	(segment
		(start 55.199534 -141.664182)
		(end 54.737508 -141.202156)
		(width 0.4064)
		(layer "B.Cu")
		(net "GND")
	)
	(segment
		(start 216.799922 -20.224242)
		(end 216.799922 -21.504656)
		(width 0.4064)
		(layer "B.Cu")
		(net "GND")
	)
	(segment
		(start 113.849404 -134.130542)
		(end 113.849404 -132.876036)
		(width 0.508)
		(layer "B.Cu")
		(net "GND")
	)
	(segment
		(start 240.599976 -7.606792)
		(end 240.599976 -5.621782)
		(width 0.4064)
		(layer "B.Cu")
		(net "GND")
	)
	(segment
		(start 388.12851 -42.745914)
		(end 387.985 -42.602404)
		(width 0.254)
		(layer "B.Cu")
		(net "GND")
	)
	(segment
		(start 127.392176 -148.748496)
		(end 127.392176 -148.767292)
		(width 0.4064)
		(layer "B.Cu")
		(net "GND")
	)
	(segment
		(start 299.160946 -22.939756)
		(end 299.160946 -22.965156)
		(width 0.4064)
		(layer "B.Cu")
		(net "GND")
	)
	(segment
		(start 135.771636 -17.2466)
		(end 135.949436 -17.0688)
		(width 0.4064)
		(layer "B.Cu")
		(net "GND")
	)
	(segment
		(start 225.300286 -152.078436)
		(end 225.299778 -152.078182)
		(width 0.4064)
		(layer "B.Cu")
		(net "GND")
	)
	(segment
		(start 199.742552 -139.147296)
		(end 199.742552 -139.166092)
		(width 0.4064)
		(layer "B.Cu")
		(net "GND")
	)
	(segment
		(start 498.5512 -143.002)
		(end 498.221 -142.6718)
		(width 0.254)
		(layer "B.Cu")
		(net "GND")
	)
	(segment
		(start 417.232846 -45.539152)
		(end 417.232846 -45.873162)
		(width 0.508)
		(layer "B.Cu")
		(net "GND")
	)
	(segment
		(start 44.092114 -129.546096)
		(end 44.092114 -129.564892)
		(width 0.4064)
		(layer "B.Cu")
		(net "GND")
	)
	(segment
		(start 144.449546 0.444754)
		(end 144.449546 -1.021842)
		(width 0.4064)
		(layer "B.Cu")
		(net "GND")
	)
	(segment
		(start 163.74618 2.264664)
		(end 163.8808 2.130044)
		(width 0.254)
		(layer "B.Cu")
		(net "GND")
	)
	(segment
		(start 41.599358 -13.427456)
		(end 41.599358 -15.222982)
		(width 0.4064)
		(layer "B.Cu")
		(net "GND")
	)
	(segment
		(start 445.106806 -33.5915)
		(end 445.937132 -33.5915)
		(width 0.4064)
		(layer "B.Cu")
		(net "GND")
	)
	(segment
		(start 171.852844 -88.109044)
		(end 172.1358 -88.392)
		(width 0.4064)
		(layer "B.Cu")
		(net "GND")
	)
	(segment
		(start 135.099552 0.444754)
		(end 135.099552 -1.021842)
		(width 0.4064)
		(layer "B.Cu")
		(net "GND")
	)
	(segment
		(start 217.650314 -5.621782)
		(end 217.649806 -5.621782)
		(width 0.4064)
		(layer "B.Cu")
		(net "GND")
	)
	(segment
		(start 239.749838 -20.224242)
		(end 239.749838 -21.517356)
		(width 0.4064)
		(layer "B.Cu")
		(net "GND")
	)
	(segment
		(start 348.234 -82.6516)
		(end 349.123 -82.6516)
		(width 0.254)
		(layer "B.Cu")
		(net "GND")
	)
	(segment
		(start 242.299744 -151.656796)
		(end 242.299744 -150.231856)
		(width 0.4064)
		(layer "B.Cu")
		(net "GND")
	)
	(segment
		(start 47.549562 -5.32765)
		(end 47.549562 -5.621782)
		(width 0.4064)
		(layer "B.Cu")
		(net "GND")
	)
	(segment
		(start 291.354256 -13.431774)
		(end 291.422074 -13.363956)
		(width 0.4064)
		(layer "B.Cu")
		(net "GND")
	)
	(segment
		(start 146.149568 -129.488692)
		(end 146.092164 -129.546096)
		(width 0.4064)
		(layer "B.Cu")
		(net "GND")
	)
	(segment
		(start 396.30096 -27.92476)
		(end 396.7226 -27.92476)
		(width 0.254)
		(layer "B.Cu")
		(net "GND")
	)
	(segment
		(start 152.099518 -11.927078)
		(end 152.099518 -10.623042)
		(width 0.4064)
		(layer "B.Cu")
		(net "GND")
	)
	(segment
		(start 32.249364 -141.369542)
		(end 32.160464 -141.280642)
		(width 0.4064)
		(layer "B.Cu")
		(net "GND")
	)
	(segment
		(start 312.12409 -28.867354)
		(end 312.12409 -29.505148)
		(width 0.381)
		(layer "B.Cu")
		(net "GND")
	)
	(segment
		(start 195.549774 -142.477236)
		(end 195.549774 -143.946626)
		(width 0.4064)
		(layer "B.Cu")
		(net "GND")
	)
	(segment
		(start 216.799922 -129.556256)
		(end 216.787222 -129.568956)
		(width 0.4064)
		(layer "B.Cu")
		(net "GND")
	)
	(segment
		(start 52.649374 -7.4676)
		(end 52.649374 -5.621782)
		(width 0.4064)
		(layer "B.Cu")
		(net "GND")
	)
	(segment
		(start 129.149348 -151.265128)
		(end 128.687576 -150.803356)
		(width 0.4064)
		(layer "B.Cu")
		(net "GND")
	)
	(segment
		(start 203.2 -131.01701)
		(end 203.199746 -131.016756)
		(width 0.4064)
		(layer "B.Cu")
		(net "GND")
	)
	(segment
		(start 196.464936 -55.528464)
		(end 196.1134 -55.88)
		(width 0.254)
		(layer "B.Cu")
		(net "GND")
	)
	(segment
		(start 378.489972 -60.8965)
		(end 377.3043 -60.8965)
		(width 0.254)
		(layer "B.Cu")
		(net "GND")
	)
	(segment
		(start 303.499774 -15.222982)
		(end 303.499774 -14.409928)
		(width 0.4064)
		(layer "B.Cu")
		(net "GND")
	)
	(segment
		(start 408.43708 -90.551)
		(end 408.43708 -90.517726)
		(width 0.254)
		(layer "B.Cu")
		(net "GND")
	)
	(segment
		(start 218.500452 -1.021842)
		(end 218.499944 -1.021842)
		(width 0.4064)
		(layer "B.Cu")
		(net "GND")
	)
	(segment
		(start 208.299812 -132.875782)
		(end 208.299812 -132.147564)
		(width 0.254)
		(layer "B.Cu")
		(net "GND")
	)
	(segment
		(start 210.849972 -132.875782)
		(end 210.849972 -132.062982)
		(width 0.4064)
		(layer "B.Cu")
		(net "GND")
	)
	(segment
		(start 387.731 -128.6256)
		(end 387.21538 -128.6256)
		(width 0.4064)
		(layer "B.Cu")
		(net "GND")
	)
	(segment
		(start 288.19983 -13.363956)
		(end 288.19983 -15.222982)
		(width 0.4064)
		(layer "B.Cu")
		(net "GND")
	)
	(segment
		(start 119.337328 -4.346956)
		(end 119.799354 -4.808982)
		(width 0.4064)
		(layer "B.Cu")
		(net "GND")
	)
	(segment
		(start 381.79375 -107.907836)
		(end 381.99695 -108.111036)
		(width 0.254)
		(layer "B.Cu")
		(net "GND")
	)
	(segment
		(start 306.050442 -128.276096)
		(end 306.049934 -128.276096)
		(width 0.4064)
		(layer "B.Cu")
		(net "GND")
	)
	(segment
		(start 77.299566 -132.876036)
		(end 77.299566 -132.875782)
		(width 0.508)
		(layer "B.Cu")
		(net "GND")
	)
	(segment
		(start 89.925144 -135.4074)
		(end 90.31986 -135.012684)
		(width 0.4064)
		(layer "B.Cu")
		(net "GND")
	)
	(segment
		(start 274.258532 -3.3528)
		(end 275.111464 -3.3528)
		(width 0.381)
		(layer "B.Cu")
		(net "GND")
	)
	(segment
		(start 376.344688 -77.896466)
		(end 376.346466 -77.896466)
		(width 0.254)
		(layer "B.Cu")
		(net "GND")
	)
	(segment
		(start 216.787222 -11.916156)
		(end 216.761822 -11.916156)
		(width 0.4064)
		(layer "B.Cu")
		(net "GND")
	)
	(segment
		(start 278.850344 -132.876036)
		(end 278.849836 -132.876036)
		(width 0.508)
		(layer "B.Cu")
		(net "GND")
	)
	(segment
		(start 115.460526 -22.965156)
		(end 115.460526 -22.939756)
		(width 0.4064)
		(layer "B.Cu")
		(net "GND")
	)
	(segment
		(start 492.76 -135.2804)
		(end 492.8108 -135.2804)
		(width 0.254)
		(layer "B.Cu")
		(net "GND")
	)
	(segment
		(start 72.142096 -9.143746)
		(end 72.1995 -9.20115)
		(width 0.4064)
		(layer "B.Cu")
		(net "GND")
	)
	(segment
		(start 18.4785 -90.1065)
		(end 18.4785 -90.5383)
		(width 0.254)
		(layer "B.Cu")
		(net "GND")
	)
	(segment
		(start 213.400386 -20.224242)
		(end 213.399878 -20.224242)
		(width 0.4064)
		(layer "B.Cu")
		(net "GND")
	)
	(segment
		(start 136.74217 -129.546096)
		(end 136.74217 -129.564892)
		(width 0.4064)
		(layer "B.Cu")
		(net "GND")
	)
	(segment
		(start 61.149484 -21.504656)
		(end 61.136784 -21.517356)
		(width 0.4064)
		(layer "B.Cu")
		(net "GND")
	)
	(segment
		(start 280.460958 -131.016756)
		(end 280.549858 -131.105656)
		(width 0.4064)
		(layer "B.Cu")
		(net "GND")
	)
	(segment
		(start 437.1086 -12.2682)
		(end 434.721 -12.2682)
		(width 0.254)
		(layer "B.Cu")
		(net "GND")
	)
	(segment
		(start 196.342 -9.085834)
		(end 196.395848 -9.139682)
		(width 0.381)
		(layer "B.Cu")
		(net "GND")
	)
	(segment
		(start 122.349514 -20.224242)
		(end 122.349514 -21.517356)
		(width 0.4064)
		(layer "B.Cu")
		(net "GND")
	)
	(segment
		(start 113.2332 -150.0886)
		(end 113.967768 -150.0886)
		(width 0.4064)
		(layer "B.Cu")
		(net "GND")
	)
	(segment
		(start 301.800514 -128.276096)
		(end 301.800006 -128.276096)
		(width 0.4064)
		(layer "B.Cu")
		(net "GND")
	)
	(segment
		(start 126.353824 -23.032974)
		(end 126.353824 -23.7236)
		(width 0.4064)
		(layer "B.Cu")
		(net "GND")
	)
	(segment
		(start 242.299998 -24.40305)
		(end 242.299998 -24.824182)
		(width 0.4064)
		(layer "B.Cu")
		(net "GND")
	)
	(segment
		(start 39.049452 -147.478496)
		(end 39.049452 -148.771356)
		(width 0.4064)
		(layer "B.Cu")
		(net "GND")
	)
	(segment
		(start 31.39948 -21.517356)
		(end 31.39948 -20.224242)
		(width 0.4064)
		(layer "B.Cu")
		(net "GND")
	)
	(segment
		(start 229.54996 -151.265382)
		(end 229.087934 -150.803356)
		(width 0.4064)
		(layer "B.Cu")
		(net "GND")
	)
	(segment
		(start 127.44958 -147.478496)
		(end 127.44958 -148.691092)
		(width 0.4064)
		(layer "B.Cu")
		(net "GND")
	)
	(segment
		(start 61.999368 -151.3078)
		(end 61.745368 -151.0538)
		(width 0.254)
		(layer "B.Cu")
		(net "GND")
	)
	(segment
		(start 52.649374 -24.824182)
		(end 52.649374 -24.02586)
		(width 0.254)
		(layer "B.Cu")
		(net "GND")
	)
	(segment
		(start 169.6212 -86.868)
		(end 169.291 -87.1982)
		(width 0.4064)
		(layer "B.Cu")
		(net "GND")
	)
	(segment
		(start 91.66098 -140.16228)
		(end 91.333066 -140.490194)
		(width 0.381)
		(layer "B.Cu")
		(net "GND")
	)
	(segment
		(start 91.333066 -140.490194)
		(end 90.814906 -140.490194)
		(width 0.381)
		(layer "B.Cu")
		(net "GND")
	)
	(segment
		(start 278.3332 -140.4874)
		(end 278.0538 -140.208)
		(width 0.4572)
		(layer "B.Cu")
		(net "GND")
	)
	(segment
		(start 135.949436 -132.876036)
		(end 135.949436 -132.096764)
		(width 0.254)
		(layer "B.Cu")
		(net "GND")
	)
	(segment
		(start 124.89942 -132.876036)
		(end 124.89942 -131.105656)
		(width 0.4064)
		(layer "B.Cu")
		(net "GND")
	)
	(segment
		(start 234.649772 -132.875782)
		(end 234.649772 -131.105656)
		(width 0.4064)
		(layer "B.Cu")
		(net "GND")
	)
	(segment
		(start 139.34948 -11.916156)
		(end 139.34948 -10.623042)
		(width 0.4064)
		(layer "B.Cu")
		(net "GND")
	)
	(segment
		(start 308.600348 -24.824182)
		(end 308.59984 -24.824182)
		(width 0.4064)
		(layer "B.Cu")
		(net "GND")
	)
	(segment
		(start 78.867254 -87.632286)
		(end 78.714854 -87.784686)
		(width 0.254)
		(layer "B.Cu")
		(net "GND")
	)
	(segment
		(start 394.032232 -105.188258)
		(end 393.224258 -105.188258)
		(width 0.3556)
		(layer "B.Cu")
		(net "GND")
	)
	(segment
		(start 291.599874 -15.222982)
		(end 291.599874 -14.443964)
		(width 0.254)
		(layer "B.Cu")
		(net "GND")
	)
	(segment
		(start 280.550366 -132.876036)
		(end 280.549858 -132.876036)
		(width 0.508)
		(layer "B.Cu")
		(net "GND")
	)
	(segment
		(start 311.15 -20.224242)
		(end 311.15 -18.80235)
		(width 0.4064)
		(layer "B.Cu")
		(net "GND")
	)
	(segment
		(start 406.7556 -29.6164)
		(end 406.8572 -29.5148)
		(width 0.254)
		(layer "B.Cu")
		(net "GND")
	)
	(segment
		(start 444.246 -140.72489)
		(end 444.246 -140.427202)
		(width 0.254)
		(layer "B.Cu")
		(net "GND")
	)
	(segment
		(start 280.550366 -142.477236)
		(end 280.550366 -144.363694)
		(width 0.508)
		(layer "B.Cu")
		(net "GND")
	)
	(segment
		(start 71.095362 -151.0538)
		(end 71.095362 -150.9522)
		(width 0.254)
		(layer "B.Cu")
		(net "GND")
	)
	(segment
		(start 149.549358 -15.222982)
		(end 149.549358 -17.208246)
		(width 0.4064)
		(layer "B.Cu")
		(net "GND")
	)
	(segment
		(start 196.342 -18.687034)
		(end 196.399912 -18.744946)
		(width 0.381)
		(layer "B.Cu")
		(net "GND")
	)
	(segment
		(start 198.087234 -139.170156)
		(end 198.061834 -139.170156)
		(width 0.4064)
		(layer "B.Cu")
		(net "GND")
	)
	(segment
		(start 486.6767 -153.5303)
		(end 487.1085 -153.0985)
		(width 0.254)
		(layer "B.Cu")
		(net "GND")
	)
	(segment
		(start 39.049452 -1.021842)
		(end 39.049452 0.444754)
		(width 0.4064)
		(layer "B.Cu")
		(net "GND")
	)
	(segment
		(start 469.515444 -7.53872)
		(end 469.043766 -8.010398)
		(width 0.254)
		(layer "B.Cu")
		(net "GND")
	)
	(segment
		(start 377.145042 -69.894958)
		(end 377.544838 -69.495162)
		(width 0.254)
		(layer "B.Cu")
		(net "GND")
	)
	(segment
		(start 306.050442 -10.623042)
		(end 306.049934 -10.623042)
		(width 0.4064)
		(layer "B.Cu")
		(net "GND")
	)
	(segment
		(start 117.249448 -151.299164)
		(end 117.00383 -151.053546)
		(width 0.254)
		(layer "B.Cu")
		(net "GND")
	)
	(segment
		(start 117.249448 -141.697964)
		(end 117.00383 -141.452346)
		(width 0.254)
		(layer "B.Cu")
		(net "GND")
	)
	(segment
		(start 1.9304 -7.5692)
		(end 2.517648 -7.5692)
		(width 0.254)
		(layer "B.Cu")
		(net "GND")
	)
	(segment
		(start 32.160464 -150.881842)
		(end 32.160464 -150.193756)
		(width 0.4064)
		(layer "B.Cu")
		(net "GND")
	)
	(segment
		(start 317.09995 -137.877296)
		(end 317.09995 -139.181078)
		(width 0.4064)
		(layer "B.Cu")
		(net "GND")
	)
	(segment
		(start 299.249846 -140.706856)
		(end 299.160946 -140.617956)
		(width 0.4064)
		(layer "B.Cu")
		(net "GND")
	)
	(segment
		(start 226.111816 -26.488136)
		(end 225.299778 -25.676098)
		(width 0.4064)
		(layer "B.Cu")
		(net "GND")
	)
	(segment
		(start 385.774692 -42.310812)
		(end 386.861812 -42.310812)
		(width 0.254)
		(layer "B.Cu")
		(net "GND")
	)
	(segment
		(start 278.330152 -126.820168)
		(end 278.849836 -127.339852)
		(width 0.4064)
		(layer "B.Cu")
		(net "GND")
	)
	(segment
		(start 420.878 -24.765)
		(end 420.624 -24.765)
		(width 0.254)
		(layer "B.Cu")
		(net "GND")
	)
	(segment
		(start 114.699542 -20.224242)
		(end 114.699542 -21.517356)
		(width 0.4064)
		(layer "B.Cu")
		(net "GND")
	)
	(segment
		(start 236.095794 -140.694156)
		(end 236.171994 -140.617956)
		(width 0.4064)
		(layer "B.Cu")
		(net "GND")
	)
	(segment
		(start 229.54996 -141.664182)
		(end 229.087934 -141.202156)
		(width 0.4064)
		(layer "B.Cu")
		(net "GND")
	)
	(segment
		(start 290.74999 -148.758656)
		(end 290.73729 -148.771356)
		(width 0.4064)
		(layer "B.Cu")
		(net "GND")
	)
	(segment
		(start 182.43042 2.63652)
		(end 182.43042 3.323844)
		(width 0.254)
		(layer "B.Cu")
		(net "GND")
	)
	(segment
		(start 304.349912 -2.314956)
		(end 304.349912 -1.021842)
		(width 0.4064)
		(layer "B.Cu")
		(net "GND")
	)
	(segment
		(start 182.7784 -70.9676)
		(end 183.515 -71.7042)
		(width 0.4064)
		(layer "B.Cu")
		(net "GND")
	)
	(segment
		(start 39.899336 -142.477236)
		(end 39.899336 -140.617956)
		(width 0.4064)
		(layer "B.Cu")
		(net "GND")
	)
	(segment
		(start 43.29938 -132.147564)
		(end 43.050968 -131.899152)
		(width 0.254)
		(layer "B.Cu")
		(net "GND")
	)
	(segment
		(start 288.200338 -150.219664)
		(end 288.19983 -150.219156)
		(width 0.4064)
		(layer "B.Cu")
		(net "GND")
	)
	(segment
		(start 140.199364 -142.477236)
		(end 140.199364 -140.617956)
		(width 0.4064)
		(layer "B.Cu")
		(net "GND")
	)
	(segment
		(start 306.899818 -142.476982)
		(end 306.899818 -140.617956)
		(width 0.4064)
		(layer "B.Cu")
		(net "GND")
	)
	(segment
		(start 11.249914 -45.310044)
		(end 12.683998 -46.744128)
		(width 0.508)
		(layer "In1.Cu")
		(net "GND")
	)
	(segment
		(start 495.3 -56.079898)
		(end 496.22202 -56.886348)
		(width 0.508)
		(layer "In1.Cu")
		(net "GND")
	)
	(segment
		(start -0.500126 -45.310044)
		(end 0.933958 -43.87596)
		(width 0.508)
		(layer "In1.Cu")
		(net "GND")
	)
	(segment
		(start 418.421058 0.08001)
		(end 419.082982 0.741934)
		(width 0.508)
		(layer "In1.Cu")
		(net "GND")
	)
	(segment
		(start 353.635056 -6.089904)
		(end 354.278946 -6.733794)
		(width 0.508)
		(layer "In1.Cu")
		(net "GND")
	)
	(segment
		(start 479.620072 -153.650442)
		(end 480.335844 -152.93467)
		(width 0.254)
		(layer "In1.Cu")
		(net "GND")
	)
	(segment
		(start 478.33915 -129.845308)
		(end 479.381058 -129.845308)
		(width 0.635)
		(layer "In1.Cu")
		(net "GND")
	)
	(segment
		(start 499.736872 -51.302158)
		(end 500.55018 -52.579778)
		(width 0.508)
		(layer "In1.Cu")
		(net "GND")
	)
	(segment
		(start 410.5148 -28.9306)
		(end 410.8704 -28.9306)
		(width 0.089408)
		(layer "In1.Cu")
		(net "GND")
	)
	(segment
		(start 487.66984 -132.236464)
		(end 488.250992 -131.655312)
		(width 0.254)
		(layer "In1.Cu")
		(net "GND")
	)
	(segment
		(start 480.385628 -125.937772)
		(end 481.1014 -125.222)
		(width 0.254)
		(layer "In1.Cu")
		(net "GND")
	)
	(segment
		(start -1.93421 -46.744128)
		(end -0.500126 -45.310044)
		(width 0.508)
		(layer "In1.Cu")
		(net "GND")
	)
	(segment
		(start 410.5148 -29.7434)
		(end 410.845 -29.7434)
		(width 0.089408)
		(layer "In1.Cu")
		(net "GND")
	)
	(segment
		(start 9.81583 -43.87596)
		(end 11.249914 -45.310044)
		(width 0.508)
		(layer "In1.Cu")
		(net "GND")
	)
	(segment
		(start 417.759134 0.741934)
		(end 418.421058 0.08001)
		(width 0.508)
		(layer "In1.Cu")
		(net "GND")
	)
	(segment
		(start 494.37798 -58.886344)
		(end 495.3 -58.079894)
		(width 0.508)
		(layer "In1.Cu")
		(net "GND")
	)
	(segment
		(start 26.714196 -26.14295)
		(end 27.241246 -26.67)
		(width 0.254)
		(layer "In1.Cu")
		(net "GND")
	)
	(segment
		(start 0 0)
		(end 2.430526 2.430526)
		(width 0.762)
		(layer "In1.Cu")
		(net "GND")
	)
	(segment
		(start 114.451384 -18.007584)
		(end 113.957354 -18.007584)
		(width 0.4064)
		(layer "In1.Cu")
		(net "GND")
	)
	(segment
		(start 29.615638 -37.824156)
		(end 30.47492 -36.964874)
		(width 0.508)
		(layer "In1.Cu")
		(net "GND")
	)
	(segment
		(start 30.47492 -36.964874)
		(end 31.334202 -36.105592)
		(width 0.508)
		(layer "In1.Cu")
		(net "GND")
	)
	(segment
		(start 479.381058 -134.528306)
		(end 479.381058 -135.265414)
		(width 0.635)
		(layer "In1.Cu")
		(net "GND")
	)
	(segment
		(start 495.3 -58.079894)
		(end 496.22202 -57.273444)
		(width 0.508)
		(layer "In1.Cu")
		(net "GND")
	)
	(segment
		(start 499.736872 -53.857398)
		(end 500.55018 -52.579778)
		(width 0.508)
		(layer "In1.Cu")
		(net "GND")
	)
	(segment
		(start 461.497172 -157.83814)
		(end 462.19491 -157.140402)
		(width 0.254)
		(layer "In1.Cu")
		(net "GND")
	)
	(segment
		(start 494.651538 -59.652154)
		(end 495.3 -61.35497)
		(width 0.508)
		(layer "In1.Cu")
		(net "GND")
	)
	(segment
		(start 494.651538 -54.507638)
		(end 495.3 -52.804822)
		(width 0.508)
		(layer "In1.Cu")
		(net "GND")
	)
	(segment
		(start 494.37798 -56.886348)
		(end 495.3 -56.079898)
		(width 0.508)
		(layer "In1.Cu")
		(net "GND")
	)
	(segment
		(start 461.497172 -156.442664)
		(end 462.19491 -157.140402)
		(width 0.254)
		(layer "In1.Cu")
		(net "GND")
	)
	(segment
		(start 397.51 3.81)
		(end 398.261586 3.058414)
		(width 0.254)
		(layer "In1.Cu")
		(net "GND")
	)
	(segment
		(start 469.618568 -147.092924)
		(end 470.2175 -146.493992)
		(width 0.254)
		(layer "In1.Cu")
		(net "GND")
	)
	(segment
		(start 490.081062 -135.265414)
		(end 491.12297 -135.265414)
		(width 0.508)
		(layer "In1.Cu")
		(net "GND")
	)
	(segment
		(start 500.253 -24.13)
		(end 500.253 -25.4)
		(width 0.2032)
		(layer "In1.Cu")
		(net "GND")
	)
	(segment
		(start 497.819934 -61.054996)
		(end 498.32006 -60.55487)
		(width 0.508)
		(layer "In1.Cu")
		(net "GND")
	)
	(segment
		(start 498.32006 -53.604922)
		(end 498.820186 -53.104796)
		(width 0.508)
		(layer "In1.Cu")
		(net "GND")
	)
	(segment
		(start 114.427 -17.2974)
		(end 114.42446 -17.29486)
		(width 0.4064)
		(layer "In1.Cu")
		(net "GND")
	)
	(segment
		(start -1.93421 -43.87596)
		(end -0.500126 -45.310044)
		(width 0.508)
		(layer "In1.Cu")
		(net "GND")
	)
	(segment
		(start 479.381058 -129.845308)
		(end 479.381058 -130.582416)
		(width 0.635)
		(layer "In1.Cu")
		(net "GND")
	)
	(segment
		(start 0 0)
		(end 2.430526 -2.430526)
		(width 0.762)
		(layer "In1.Cu")
		(net "GND")
	)
	(segment
		(start 499.736872 -60.302394)
		(end 500.55018 -61.580014)
		(width 0.508)
		(layer "In1.Cu")
		(net "GND")
	)
	(segment
		(start 114.699542 -18.744946)
		(end 114.646202 -18.691606)
		(width 0.4064)
		(layer "In1.Cu")
		(net "GND")
	)
	(segment
		(start 479.381058 -135.265414)
		(end 480.778566 -135.265414)
		(width 0.635)
		(layer "In1.Cu")
		(net "GND")
	)
	(segment
		(start 410.3116 -28.702)
		(end 410.3116 -28.321)
		(width 0.089408)
		(layer "In1.Cu")
		(net "GND")
	)
	(segment
		(start 3.195828 -46.744128)
		(end 4.629912 -45.310044)
		(width 0.508)
		(layer "In1.Cu")
		(net "GND")
	)
	(segment
		(start 481.1014 -125.222)
		(end 481.817172 -125.937772)
		(width 0.254)
		(layer "In1.Cu")
		(net "GND")
	)
	(segment
		(start 397.51 3.81)
		(end 398.261586 4.561586)
		(width 0.254)
		(layer "In1.Cu")
		(net "GND")
	)
	(segment
		(start 500.55018 -60.302394)
		(end 500.55018 -61.580014)
		(width 0.508)
		(layer "In1.Cu")
		(net "GND")
	)
	(segment
		(start 3.195828 -43.87596)
		(end 4.629912 -45.310044)
		(width 0.508)
		(layer "In1.Cu")
		(net "GND")
	)
	(segment
		(start 396.758414 3.058414)
		(end 397.51 3.81)
		(width 0.254)
		(layer "In1.Cu")
		(net "GND")
	)
	(segment
		(start 488.250992 -131.655312)
		(end 488.832144 -131.07416)
		(width 0.254)
		(layer "In1.Cu")
		(net "GND")
	)
	(segment
		(start 494.37798 -55.273448)
		(end 495.3 -56.079898)
		(width 0.508)
		(layer "In1.Cu")
		(net "GND")
	)
	(segment
		(start 480.385628 -124.506228)
		(end 481.1014 -125.222)
		(width 0.254)
		(layer "In1.Cu")
		(net "GND")
	)
	(segment
		(start 487.66984 -131.07416)
		(end 488.250992 -131.655312)
		(width 0.254)
		(layer "In1.Cu")
		(net "GND")
	)
	(segment
		(start 495.32921 -154.520646)
		(end 496.000024 -153.849832)
		(width 0.254)
		(layer "In1.Cu")
		(net "GND")
	)
	(segment
		(start 498.32006 -53.604922)
		(end 498.820186 -54.105048)
		(width 0.508)
		(layer "In1.Cu")
		(net "GND")
	)
	(segment
		(start 384.535172 -6.089904)
		(end 385.179062 -5.446014)
		(width 0.508)
		(layer "In1.Cu")
		(net "GND")
	)
	(segment
		(start 488.250992 -131.655312)
		(end 488.832144 -132.236464)
		(width 0.254)
		(layer "In1.Cu")
		(net "GND")
	)
	(segment
		(start 407.08199 -74.246232)
		(end 409.719526 -76.883768)
		(width 0.762)
		(layer "In1.Cu")
		(net "GND")
	)
	(segment
		(start 497.819934 -53.104796)
		(end 498.32006 -53.604922)
		(width 0.508)
		(layer "In1.Cu")
		(net "GND")
	)
	(segment
		(start 3.940048 -110.259876)
		(end 4.79933 -111.119158)
		(width 0.508)
		(layer "In1.Cu")
		(net "GND")
	)
	(segment
		(start 410.3116 -29.9466)
		(end 410.3116 -30.353)
		(width 0.089408)
		(layer "In1.Cu")
		(net "GND")
	)
	(segment
		(start 407.08199 -79.521304)
		(end 409.719526 -76.883768)
		(width 0.762)
		(layer "In1.Cu")
		(net "GND")
	)
	(segment
		(start 490.081062 -129.1082)
		(end 490.081062 -129.845308)
		(width 0.635)
		(layer "In1.Cu")
		(net "GND")
	)
	(segment
		(start 479.381058 -129.1082)
		(end 479.381058 -129.845308)
		(width 0.635)
		(layer "In1.Cu")
		(net "GND")
	)
	(segment
		(start 462.19491 -157.140402)
		(end 462.892648 -156.442664)
		(width 0.254)
		(layer "In1.Cu")
		(net "GND")
	)
	(segment
		(start 490.081062 -134.528306)
		(end 490.081062 -135.265414)
		(width 0.508)
		(layer "In1.Cu")
		(net "GND")
	)
	(segment
		(start 479.381058 -129.845308)
		(end 480.422966 -129.845308)
		(width 0.635)
		(layer "In1.Cu")
		(net "GND")
	)
	(segment
		(start 3.940048 -110.259876)
		(end 4.79933 -109.400594)
		(width 0.508)
		(layer "In1.Cu")
		(net "GND")
	)
	(segment
		(start 470.2175 -142.494)
		(end 470.816432 -143.092932)
		(width 0.254)
		(layer "In1.Cu")
		(net "GND")
	)
	(segment
		(start 114.42446 -17.29486)
		(end 113.951258 -17.29486)
		(width 0.4064)
		(layer "In1.Cu")
		(net "GND")
	)
	(segment
		(start 3.080766 -109.400594)
		(end 3.940048 -110.259876)
		(width 0.508)
		(layer "In1.Cu")
		(net "GND")
	)
	(segment
		(start 496.000024 -153.849832)
		(end 496.670838 -154.520646)
		(width 0.254)
		(layer "In1.Cu")
		(net "GND")
	)
	(segment
		(start 27.241246 -26.67)
		(end 27.768296 -26.14295)
		(width 0.254)
		(layer "In1.Cu")
		(net "GND")
	)
	(segment
		(start 383.891282 -5.446014)
		(end 384.535172 -6.089904)
		(width 0.508)
		(layer "In1.Cu")
		(net "GND")
	)
	(segment
		(start 4.629912 -45.310044)
		(end 6.063996 -46.744128)
		(width 0.508)
		(layer "In1.Cu")
		(net "GND")
	)
	(segment
		(start 477.98355 -135.265414)
		(end 479.381058 -135.265414)
		(width 0.635)
		(layer "In1.Cu")
		(net "GND")
	)
	(segment
		(start 114.4524 -18.0086)
		(end 114.451384 -18.007584)
		(width 0.4064)
		(layer "In1.Cu")
		(net "GND")
	)
	(segment
		(start 495.32921 -153.179018)
		(end 496.000024 -153.849832)
		(width 0.254)
		(layer "In1.Cu")
		(net "GND")
	)
	(segment
		(start -0.500126 -45.310044)
		(end 0.933958 -46.744128)
		(width 0.508)
		(layer "In1.Cu")
		(net "GND")
	)
	(segment
		(start 490.081062 -129.845308)
		(end 491.47857 -129.845308)
		(width 0.635)
		(layer "In1.Cu")
		(net "GND")
	)
	(segment
		(start 479.381058 -135.265414)
		(end 479.381058 -136.002522)
		(width 0.635)
		(layer "In1.Cu")
		(net "GND")
	)
	(segment
		(start 470.2175 -142.494)
		(end 470.816432 -141.895068)
		(width 0.254)
		(layer "In1.Cu")
		(net "GND")
	)
	(segment
		(start -2.430526 2.430526)
		(end 0 0)
		(width 0.762)
		(layer "In1.Cu")
		(net "GND")
	)
	(segment
		(start 417.759134 -0.581914)
		(end 418.421058 0.08001)
		(width 0.508)
		(layer "In1.Cu")
		(net "GND")
	)
	(segment
		(start 479.620072 -152.218898)
		(end 480.335844 -152.93467)
		(width 0.254)
		(layer "In1.Cu")
		(net "GND")
	)
	(segment
		(start 495.3 -56.079898)
		(end 496.22202 -55.273448)
		(width 0.508)
		(layer "In1.Cu")
		(net "GND")
	)
	(segment
		(start 480.335844 -152.93467)
		(end 481.051616 -152.218898)
		(width 0.254)
		(layer "In1.Cu")
		(net "GND")
	)
	(segment
		(start 480.92614 -6.144006)
		(end 481.57003 -5.500116)
		(width 0.254)
		(layer "In1.Cu")
		(net "GND")
	)
	(segment
		(start 488.683554 -129.845308)
		(end 490.081062 -129.845308)
		(width 0.635)
		(layer "In1.Cu")
		(net "GND")
	)
	(segment
		(start 27.241246 -26.67)
		(end 27.768296 -27.19705)
		(width 0.254)
		(layer "In1.Cu")
		(net "GND")
	)
	(segment
		(start 418.421058 0.08001)
		(end 419.082982 -0.581914)
		(width 0.508)
		(layer "In1.Cu")
		(net "GND")
	)
	(segment
		(start 462.19491 -157.140402)
		(end 462.892648 -157.83814)
		(width 0.254)
		(layer "In1.Cu")
		(net "GND")
	)
	(segment
		(start 29.615638 -36.105592)
		(end 30.47492 -36.964874)
		(width 0.508)
		(layer "In1.Cu")
		(net "GND")
	)
	(segment
		(start 498.32006 -60.55487)
		(end 498.820186 -61.054996)
		(width 0.508)
		(layer "In1.Cu")
		(net "GND")
	)
	(segment
		(start 352.991166 -5.446014)
		(end 353.635056 -6.089904)
		(width 0.508)
		(layer "In1.Cu")
		(net "GND")
	)
	(segment
		(start 481.1014 -125.222)
		(end 481.817172 -124.506228)
		(width 0.254)
		(layer "In1.Cu")
		(net "GND")
	)
	(segment
		(start 470.2175 -146.493992)
		(end 470.816432 -147.092924)
		(width 0.254)
		(layer "In1.Cu")
		(net "GND")
	)
	(segment
		(start 495.3 -58.079894)
		(end 496.22202 -58.886344)
		(width 0.508)
		(layer "In1.Cu")
		(net "GND")
	)
	(segment
		(start 480.335844 -152.93467)
		(end 481.051616 -153.650442)
		(width 0.254)
		(layer "In1.Cu")
		(net "GND")
	)
	(segment
		(start 490.081062 -135.265414)
		(end 490.081062 -136.002522)
		(width 0.508)
		(layer "In1.Cu")
		(net "GND")
	)
	(segment
		(start 469.618568 -143.092932)
		(end 470.2175 -142.494)
		(width 0.254)
		(layer "In1.Cu")
		(net "GND")
	)
	(segment
		(start -2.430526 -2.430526)
		(end 0 0)
		(width 0.762)
		(layer "In1.Cu")
		(net "GND")
	)
	(segment
		(start 114.646202 -18.691606)
		(end 113.944146 -18.691606)
		(width 0.4064)
		(layer "In1.Cu")
		(net "GND")
	)
	(segment
		(start 9.81583 -46.744128)
		(end 11.249914 -45.310044)
		(width 0.508)
		(layer "In1.Cu")
		(net "GND")
	)
	(segment
		(start 480.92614 -4.856226)
		(end 481.57003 -5.500116)
		(width 0.254)
		(layer "In1.Cu")
		(net "GND")
	)
	(segment
		(start 495.3 -59.652154)
		(end 495.3 -61.35497)
		(width 0.508)
		(layer "In1.Cu")
		(net "GND")
	)
	(segment
		(start 494.651538 -51.623214)
		(end 495.3 -52.804822)
		(width 0.508)
		(layer "In1.Cu")
		(net "GND")
	)
	(segment
		(start 498.32006 -60.55487)
		(end 498.820186 -60.054744)
		(width 0.508)
		(layer "In1.Cu")
		(net "GND")
	)
	(segment
		(start 26.714196 -27.19705)
		(end 27.241246 -26.67)
		(width 0.254)
		(layer "In1.Cu")
		(net "GND")
	)
	(segment
		(start 409.719526 -76.883768)
		(end 412.357062 -79.521304)
		(width 0.762)
		(layer "In1.Cu")
		(net "GND")
	)
	(segment
		(start 11.249914 -45.310044)
		(end 12.683998 -43.87596)
		(width 0.508)
		(layer "In1.Cu")
		(net "GND")
	)
	(segment
		(start 409.719526 -76.883768)
		(end 412.357062 -74.246232)
		(width 0.762)
		(layer "In1.Cu")
		(net "GND")
	)
	(segment
		(start 30.47492 -36.964874)
		(end 31.334202 -37.824156)
		(width 0.508)
		(layer "In1.Cu")
		(net "GND")
	)
	(segment
		(start 490.081062 -129.845308)
		(end 490.081062 -130.582416)
		(width 0.635)
		(layer "In1.Cu")
		(net "GND")
	)
	(segment
		(start 4.629912 -45.310044)
		(end 6.063996 -43.87596)
		(width 0.508)
		(layer "In1.Cu")
		(net "GND")
	)
	(segment
		(start 496.000024 -153.849832)
		(end 496.670838 -153.179018)
		(width 0.254)
		(layer "In1.Cu")
		(net "GND")
	)
	(segment
		(start 352.991166 -6.733794)
		(end 353.635056 -6.089904)
		(width 0.508)
		(layer "In1.Cu")
		(net "GND")
	)
	(segment
		(start 383.891282 -6.733794)
		(end 384.535172 -6.089904)
		(width 0.508)
		(layer "In1.Cu")
		(net "GND")
	)
	(segment
		(start 489.039154 -135.265414)
		(end 490.081062 -135.265414)
		(width 0.508)
		(layer "In1.Cu")
		(net "GND")
	)
	(segment
		(start 384.535172 -6.089904)
		(end 385.179062 -6.733794)
		(width 0.508)
		(layer "In1.Cu")
		(net "GND")
	)
	(segment
		(start 3.080766 -111.119158)
		(end 3.940048 -110.259876)
		(width 0.508)
		(layer "In1.Cu")
		(net "GND")
	)
	(segment
		(start 396.758414 4.561586)
		(end 397.51 3.81)
		(width 0.254)
		(layer "In1.Cu")
		(net "GND")
	)
	(segment
		(start 469.618568 -145.89506)
		(end 470.2175 -146.493992)
		(width 0.254)
		(layer "In1.Cu")
		(net "GND")
	)
	(segment
		(start 409.4734 -28.3464)
		(end 409.4734 -28.7528)
		(width 0.089408)
		(layer "In1.Cu")
		(net "GND")
	)
	(segment
		(start 353.635056 -6.089904)
		(end 354.278946 -5.446014)
		(width 0.508)
		(layer "In1.Cu")
		(net "GND")
	)
	(segment
		(start 409.2448 -29.7434)
		(end 408.8638 -29.7434)
		(width 0.089408)
		(layer "In1.Cu")
		(net "GND")
	)
	(segment
		(start 470.2175 -146.493992)
		(end 470.816432 -145.89506)
		(width 0.254)
		(layer "In1.Cu")
		(net "GND")
	)
	(segment
		(start 469.618568 -141.895068)
		(end 470.2175 -142.494)
		(width 0.254)
		(layer "In1.Cu")
		(net "GND")
	)
	(segment
		(start 9.81583 -46.744128)
		(end 11.249914 -45.310044)
		(width 0.508)
		(layer "In2.Cu")
		(net "GND")
	)
	(segment
		(start 11.249914 -45.310044)
		(end 12.683998 -43.87596)
		(width 0.508)
		(layer "In2.Cu")
		(net "GND")
	)
	(segment
		(start 9.81583 -43.87596)
		(end 11.249914 -45.310044)
		(width 0.508)
		(layer "In2.Cu")
		(net "GND")
	)
	(segment
		(start -0.500126 -45.310044)
		(end 0.933958 -43.87596)
		(width 0.508)
		(layer "In2.Cu")
		(net "GND")
	)
	(segment
		(start -0.500126 -45.310044)
		(end 0.933958 -46.744128)
		(width 0.508)
		(layer "In2.Cu")
		(net "GND")
	)
	(segment
		(start 11.249914 -45.310044)
		(end 12.683998 -46.744128)
		(width 0.508)
		(layer "In2.Cu")
		(net "GND")
	)
	(segment
		(start -1.93421 -46.744128)
		(end -0.500126 -45.310044)
		(width 0.508)
		(layer "In2.Cu")
		(net "GND")
	)
	(segment
		(start 3.195828 -43.87596)
		(end 4.629912 -45.310044)
		(width 0.508)
		(layer "In2.Cu")
		(net "GND")
	)
	(segment
		(start 4.629912 -45.310044)
		(end 6.063996 -46.744128)
		(width 0.508)
		(layer "In2.Cu")
		(net "GND")
	)
	(segment
		(start 3.195828 -46.744128)
		(end 4.629912 -45.310044)
		(width 0.508)
		(layer "In2.Cu")
		(net "GND")
	)
	(segment
		(start 4.629912 -45.310044)
		(end 6.063996 -43.87596)
		(width 0.508)
		(layer "In2.Cu")
		(net "GND")
	)
	(segment
		(start -2.999994 -85.630004)
		(end -2.44602 -85.07603)
		(width 0.508)
		(layer "In3.Cu")
		(net "GND")
	)
	(segment
		(start 0.999998 -85.630004)
		(end 1.553972 -85.07603)
		(width 0.508)
		(layer "In3.Cu")
		(net "GND")
	)
	(segment
		(start -0.999998 -57.909968)
		(end -0.446024 -58.463942)
		(width 0.508)
		(layer "In3.Cu")
		(net "GND")
	)
	(segment
		(start 432.36007 -136.344914)
		(end 432.932078 -136.916922)
		(width 0.254)
		(layer "In3.Cu")
		(net "GND")
	)
	(segment
		(start -2.999994 -51.90998)
		(end -2.44602 -51.356006)
		(width 0.508)
		(layer "In3.Cu")
		(net "GND")
	)
	(segment
		(start -2.999994 -57.909968)
		(end -2.44602 -58.463942)
		(width 0.508)
		(layer "In3.Cu")
		(net "GND")
	)
	(segment
		(start 445.38011 -136.344914)
		(end 445.916304 -136.881108)
		(width 0.254)
		(layer "In3.Cu")
		(net "GND")
	)
	(segment
		(start 444.843916 -135.80872)
		(end 445.38011 -136.344914)
		(width 0.254)
		(layer "In3.Cu")
		(net "GND")
	)
	(segment
		(start -1.553972 -79.076042)
		(end -0.999998 -79.630016)
		(width 0.508)
		(layer "In3.Cu")
		(net "GND")
	)
	(segment
		(start 435.598062 -135.772906)
		(end 436.17007 -136.344914)
		(width 0.254)
		(layer "In3.Cu")
		(net "GND")
	)
	(segment
		(start -3.553968 -58.463942)
		(end -2.999994 -57.909968)
		(width 0.508)
		(layer "In3.Cu")
		(net "GND")
	)
	(segment
		(start 0.446024 -57.355994)
		(end 0.999998 -57.909968)
		(width 0.508)
		(layer "In3.Cu")
		(net "GND")
	)
	(segment
		(start 444.843916 -136.881108)
		(end 445.38011 -136.344914)
		(width 0.254)
		(layer "In3.Cu")
		(net "GND")
	)
	(segment
		(start -0.999998 -51.90998)
		(end -0.446024 -52.463954)
		(width 0.508)
		(layer "In3.Cu")
		(net "GND")
	)
	(segment
		(start -1.553972 -80.18399)
		(end -0.999998 -79.630016)
		(width 0.508)
		(layer "In3.Cu")
		(net "GND")
	)
	(segment
		(start -1.553972 -51.356006)
		(end -0.999998 -51.90998)
		(width 0.508)
		(layer "In3.Cu")
		(net "GND")
	)
	(segment
		(start 432.36007 -136.344914)
		(end 432.932078 -135.772906)
		(width 0.254)
		(layer "In3.Cu")
		(net "GND")
	)
	(segment
		(start -0.999998 -85.630004)
		(end -0.446024 -85.07603)
		(width 0.508)
		(layer "In3.Cu")
		(net "GND")
	)
	(segment
		(start -1.553972 -58.463942)
		(end -0.999998 -57.909968)
		(width 0.508)
		(layer "In3.Cu")
		(net "GND")
	)
	(segment
		(start 0.446024 -85.07603)
		(end 0.999998 -85.630004)
		(width 0.508)
		(layer "In3.Cu")
		(net "GND")
	)
	(segment
		(start -2.999994 -79.630016)
		(end -2.44602 -79.076042)
		(width 0.508)
		(layer "In3.Cu")
		(net "GND")
	)
	(segment
		(start 444.380112 -136.344914)
		(end 444.843916 -136.808718)
		(width 0.254)
		(layer "In3.Cu")
		(net "GND")
	)
	(segment
		(start -0.999998 -79.630016)
		(end -0.446024 -79.076042)
		(width 0.508)
		(layer "In3.Cu")
		(net "GND")
	)
	(segment
		(start 0.446024 -80.18399)
		(end 0.999998 -79.630016)
		(width 0.508)
		(layer "In3.Cu")
		(net "GND")
	)
	(segment
		(start -2.999994 -85.630004)
		(end -2.44602 -86.183978)
		(width 0.508)
		(layer "In3.Cu")
		(net "GND")
	)
	(segment
		(start 436.17007 -136.344914)
		(end 436.742078 -135.772906)
		(width 0.508)
		(layer "In3.Cu")
		(net "GND")
	)
	(segment
		(start 428.55007 -136.344914)
		(end 429.122078 -135.772906)
		(width 0.254)
		(layer "In3.Cu")
		(net "GND")
	)
	(segment
		(start 427.978062 -135.772906)
		(end 428.55007 -136.344914)
		(width 0.508)
		(layer "In3.Cu")
		(net "GND")
	)
	(segment
		(start -0.999998 -57.909968)
		(end -0.446024 -57.355994)
		(width 0.508)
		(layer "In3.Cu")
		(net "GND")
	)
	(segment
		(start 444.843916 -136.808718)
		(end 444.843916 -136.881108)
		(width 0.254)
		(layer "In3.Cu")
		(net "GND")
	)
	(segment
		(start 443.843918 -136.881108)
		(end 444.380112 -136.344914)
		(width 0.254)
		(layer "In3.Cu")
		(net "GND")
	)
	(segment
		(start 444.380112 -136.344914)
		(end 444.916306 -135.80872)
		(width 0.254)
		(layer "In3.Cu")
		(net "GND")
	)
	(segment
		(start -0.999998 -79.630016)
		(end -0.446024 -80.18399)
		(width 0.508)
		(layer "In3.Cu")
		(net "GND")
	)
	(segment
		(start -3.553968 -51.356006)
		(end -2.999994 -51.90998)
		(width 0.508)
		(layer "In3.Cu")
		(net "GND")
	)
	(segment
		(start -2.999994 -51.90998)
		(end -2.44602 -52.463954)
		(width 0.508)
		(layer "In3.Cu")
		(net "GND")
	)
	(segment
		(start 0.446024 -51.356006)
		(end 0.999998 -51.90998)
		(width 0.508)
		(layer "In3.Cu")
		(net "GND")
	)
	(segment
		(start -3.553968 -80.18399)
		(end -2.999994 -79.630016)
		(width 0.508)
		(layer "In3.Cu")
		(net "GND")
	)
	(segment
		(start 500.253 -25.4)
		(end 500.253 -24.13)
		(width 0.1524)
		(layer "In3.Cu")
		(net "GND")
	)
	(segment
		(start 445.38011 -136.344914)
		(end 445.916304 -135.80872)
		(width 0.254)
		(layer "In3.Cu")
		(net "GND")
	)
	(segment
		(start 0.446024 -52.463954)
		(end 0.999998 -51.90998)
		(width 0.508)
		(layer "In3.Cu")
		(net "GND")
	)
	(segment
		(start 0.999998 -85.630004)
		(end 1.553972 -86.183978)
		(width 0.508)
		(layer "In3.Cu")
		(net "GND")
	)
	(segment
		(start -1.553972 -86.183978)
		(end -0.999998 -85.630004)
		(width 0.508)
		(layer "In3.Cu")
		(net "GND")
	)
	(segment
		(start 428.55007 -136.344914)
		(end 429.122078 -136.916922)
		(width 0.254)
		(layer "In3.Cu")
		(net "GND")
	)
	(segment
		(start 0.446024 -86.183978)
		(end 0.999998 -85.630004)
		(width 0.508)
		(layer "In3.Cu")
		(net "GND")
	)
	(segment
		(start -3.553968 -86.183978)
		(end -2.999994 -85.630004)
		(width 0.508)
		(layer "In3.Cu")
		(net "GND")
	)
	(segment
		(start 436.17007 -136.344914)
		(end 436.742078 -136.916922)
		(width 0.508)
		(layer "In3.Cu")
		(net "GND")
	)
	(segment
		(start -2.999994 -57.909968)
		(end -2.44602 -57.355994)
		(width 0.508)
		(layer "In3.Cu")
		(net "GND")
	)
	(segment
		(start -1.553972 -52.463954)
		(end -0.999998 -51.90998)
		(width 0.508)
		(layer "In3.Cu")
		(net "GND")
	)
	(segment
		(start -3.553968 -79.076042)
		(end -2.999994 -79.630016)
		(width 0.508)
		(layer "In3.Cu")
		(net "GND")
	)
	(segment
		(start 496.000024 3.79984)
		(end 496.813332 5.21716)
		(width 0.508)
		(layer "In3.Cu")
		(net "GND")
	)
	(segment
		(start 0.999998 -79.630016)
		(end 1.553972 -80.18399)
		(width 0.508)
		(layer "In3.Cu")
		(net "GND")
	)
	(segment
		(start 0.446024 -79.076042)
		(end 0.999998 -79.630016)
		(width 0.508)
		(layer "In3.Cu")
		(net "GND")
	)
	(segment
		(start 427.978062 -136.916922)
		(end 428.55007 -136.344914)
		(width 0.508)
		(layer "In3.Cu")
		(net "GND")
	)
	(segment
		(start 432.36007 -136.344914)
		(end 431.788062 -136.916922)
		(width 0.254)
		(layer "In3.Cu")
		(net "GND")
	)
	(segment
		(start 60.523628 -165.06698)
		(end 60.523628 -165.01618)
		(width 0.254)
		(layer "In3.Cu")
		(net "GND")
	)
	(segment
		(start 496.000024 -14.800072)
		(end 496.813332 -16.217392)
		(width 0.508)
		(layer "In3.Cu")
		(net "GND")
	)
	(segment
		(start -0.999998 -51.90998)
		(end -0.446024 -51.356006)
		(width 0.508)
		(layer "In3.Cu")
		(net "GND")
	)
	(segment
		(start 431.788062 -135.772906)
		(end 432.36007 -136.344914)
		(width 0.254)
		(layer "In3.Cu")
		(net "GND")
	)
	(segment
		(start 443.843918 -135.80872)
		(end 444.380112 -136.344914)
		(width 0.254)
		(layer "In3.Cu")
		(net "GND")
	)
	(segment
		(start 495.186716 -16.217392)
		(end 496.000024 -14.800072)
		(width 0.508)
		(layer "In3.Cu")
		(net "GND")
	)
	(segment
		(start -1.553972 -85.07603)
		(end -0.999998 -85.630004)
		(width 0.508)
		(layer "In3.Cu")
		(net "GND")
	)
	(segment
		(start 444.843916 -136.808718)
		(end 444.916306 -136.881108)
		(width 0.254)
		(layer "In3.Cu")
		(net "GND")
	)
	(segment
		(start 243.274596 -22.198076)
		(end 242.924076 -22.198076)
		(width 0.4572)
		(layer "In3.Cu")
		(net "GND")
	)
	(segment
		(start -0.999998 -85.630004)
		(end -0.446024 -86.183978)
		(width 0.508)
		(layer "In3.Cu")
		(net "GND")
	)
	(segment
		(start -3.553968 -52.463954)
		(end -2.999994 -51.90998)
		(width 0.508)
		(layer "In3.Cu")
		(net "GND")
	)
	(segment
		(start 495.186716 5.21716)
		(end 496.000024 3.79984)
		(width 0.508)
		(layer "In3.Cu")
		(net "GND")
	)
	(segment
		(start -1.553972 -57.355994)
		(end -0.999998 -57.909968)
		(width 0.508)
		(layer "In3.Cu")
		(net "GND")
	)
	(segment
		(start -3.553968 -57.355994)
		(end -2.999994 -57.909968)
		(width 0.508)
		(layer "In3.Cu")
		(net "GND")
	)
	(segment
		(start -3.553968 -85.07603)
		(end -2.999994 -85.630004)
		(width 0.508)
		(layer "In3.Cu")
		(net "GND")
	)
	(segment
		(start 0.999998 -79.630016)
		(end 1.553972 -79.076042)
		(width 0.508)
		(layer "In3.Cu")
		(net "GND")
	)
	(segment
		(start -2.999994 -79.630016)
		(end -2.44602 -80.18399)
		(width 0.508)
		(layer "In3.Cu")
		(net "GND")
	)
	(segment
		(start 0.446024 -58.463942)
		(end 0.999998 -57.909968)
		(width 0.508)
		(layer "In3.Cu")
		(net "GND")
	)
	(segment
		(start 435.598062 -136.916922)
		(end 436.17007 -136.344914)
		(width 0.254)
		(layer "In3.Cu")
		(net "GND")
	)
	(segment
		(start 11.249914 -45.310044)
		(end 12.683998 -46.744128)
		(width 0.508)
		(layer "In4.Cu")
		(net "GND")
	)
	(segment
		(start 4.629912 -45.310044)
		(end 6.063996 -43.87596)
		(width 0.508)
		(layer "In4.Cu")
		(net "GND")
	)
	(segment
		(start 3.195828 -46.744128)
		(end 4.629912 -45.310044)
		(width 0.508)
		(layer "In4.Cu")
		(net "GND")
	)
	(segment
		(start -1.93421 -46.744128)
		(end -0.500126 -45.310044)
		(width 0.508)
		(layer "In4.Cu")
		(net "GND")
	)
	(segment
		(start -0.500126 -45.310044)
		(end 0.933958 -46.744128)
		(width 0.508)
		(layer "In4.Cu")
		(net "GND")
	)
	(segment
		(start -0.500126 -45.310044)
		(end 0.933958 -43.87596)
		(width 0.508)
		(layer "In4.Cu")
		(net "GND")
	)
	(segment
		(start 9.81583 -46.744128)
		(end 11.249914 -45.310044)
		(width 0.508)
		(layer "In4.Cu")
		(net "GND")
	)
	(segment
		(start 3.195828 -43.87596)
		(end 4.629912 -45.310044)
		(width 0.508)
		(layer "In4.Cu")
		(net "GND")
	)
	(segment
		(start -1.93421 -43.87596)
		(end -0.500126 -45.310044)
		(width 0.508)
		(layer "In4.Cu")
		(net "GND")
	)
	(segment
		(start 4.629912 -45.310044)
		(end 6.063996 -46.744128)
		(width 0.508)
		(layer "In4.Cu")
		(net "GND")
	)
	(segment
		(start 9.81583 -43.87596)
		(end 11.249914 -45.310044)
		(width 0.508)
		(layer "In4.Cu")
		(net "GND")
	)
	(segment
		(start 420.677086 -33.179766)
		(end 420.677086 -33.495234)
		(width 0.1143)
		(layer "In5.Cu")
		(net "GND")
	)
	(segment
		(start 481.1014 -125.222)
		(end 481.817172 -125.937772)
		(width 0.254)
		(layer "In5.Cu")
		(net "GND")
	)
	(segment
		(start 3.940048 -110.259876)
		(end 4.79933 -111.119158)
		(width 0.508)
		(layer "In5.Cu")
		(net "GND")
	)
	(segment
		(start 409.719526 -76.883768)
		(end 412.357062 -74.246232)
		(width 0.762)
		(layer "In5.Cu")
		(net "GND")
	)
	(segment
		(start 383.891282 -5.446014)
		(end 384.535172 -6.089904)
		(width 0.508)
		(layer "In5.Cu")
		(net "GND")
	)
	(segment
		(start 371.550184 -78.892908)
		(end 371.550184 -79.289656)
		(width 0.1143)
		(layer "In5.Cu")
		(net "GND")
	)
	(segment
		(start -2.430526 -2.430526)
		(end 0 0)
		(width 0.762)
		(layer "In5.Cu")
		(net "GND")
	)
	(segment
		(start 462.19491 -157.140402)
		(end 462.892648 -157.83814)
		(width 0.254)
		(layer "In5.Cu")
		(net "GND")
	)
	(segment
		(start 479.381058 -135.265414)
		(end 480.778566 -135.265414)
		(width 0.635)
		(layer "In5.Cu")
		(net "GND")
	)
	(segment
		(start 27.241246 -26.67)
		(end 27.768296 -27.19705)
		(width 0.254)
		(layer "In5.Cu")
		(net "GND")
	)
	(segment
		(start 407.08199 -74.246232)
		(end 409.719526 -76.883768)
		(width 0.762)
		(layer "In5.Cu")
		(net "GND")
	)
	(segment
		(start 498.32006 -53.604922)
		(end 498.820186 -54.105048)
		(width 0.508)
		(layer "In5.Cu")
		(net "GND")
	)
	(segment
		(start 370.741448 -78.91526)
		(end 370.741448 -80.103218)
		(width 0.1143)
		(layer "In5.Cu")
		(net "GND")
	)
	(segment
		(start 495.32921 -153.179018)
		(end 496.000024 -153.849832)
		(width 0.254)
		(layer "In5.Cu")
		(net "GND")
	)
	(segment
		(start 477.98355 -135.265414)
		(end 479.381058 -135.265414)
		(width 0.635)
		(layer "In5.Cu")
		(net "GND")
	)
	(segment
		(start 30.47492 -36.964874)
		(end 31.334202 -36.105592)
		(width 0.508)
		(layer "In5.Cu")
		(net "GND")
	)
	(segment
		(start 396.758414 3.058414)
		(end 397.51 3.81)
		(width 0.254)
		(layer "In5.Cu")
		(net "GND")
	)
	(segment
		(start 494.651538 -59.652154)
		(end 495.3 -61.35497)
		(width 0.508)
		(layer "In5.Cu")
		(net "GND")
	)
	(segment
		(start 495.3 -56.079898)
		(end 496.22202 -55.273448)
		(width 0.508)
		(layer "In5.Cu")
		(net "GND")
	)
	(segment
		(start 494.651538 -51.623214)
		(end 495.3 -52.804822)
		(width 0.508)
		(layer "In5.Cu")
		(net "GND")
	)
	(segment
		(start 479.381058 -135.265414)
		(end 479.381058 -136.002522)
		(width 0.635)
		(layer "In5.Cu")
		(net "GND")
	)
	(segment
		(start 9.81583 -46.744128)
		(end 11.249914 -45.310044)
		(width 0.508)
		(layer "In5.Cu")
		(net "GND")
	)
	(segment
		(start 418.421058 0.08001)
		(end 419.082982 0.741934)
		(width 0.508)
		(layer "In5.Cu")
		(net "GND")
	)
	(segment
		(start 409.719526 -76.883768)
		(end 412.357062 -79.521304)
		(width 0.762)
		(layer "In5.Cu")
		(net "GND")
	)
	(segment
		(start 417.759134 -0.581914)
		(end 418.421058 0.08001)
		(width 0.508)
		(layer "In5.Cu")
		(net "GND")
	)
	(segment
		(start 27.241246 -26.67)
		(end 27.768296 -26.14295)
		(width 0.254)
		(layer "In5.Cu")
		(net "GND")
	)
	(segment
		(start 498.32006 -53.604922)
		(end 498.820186 -53.104796)
		(width 0.508)
		(layer "In5.Cu")
		(net "GND")
	)
	(segment
		(start 3.195828 -43.87596)
		(end 4.629912 -45.310044)
		(width 0.508)
		(layer "In5.Cu")
		(net "GND")
	)
	(segment
		(start 0 0)
		(end 2.430526 2.430526)
		(width 0.762)
		(layer "In5.Cu")
		(net "GND")
	)
	(segment
		(start 3.195828 -46.744128)
		(end 4.629912 -45.310044)
		(width 0.508)
		(layer "In5.Cu")
		(net "GND")
	)
	(segment
		(start 490.081062 -134.528306)
		(end 490.081062 -135.265414)
		(width 0.508)
		(layer "In5.Cu")
		(net "GND")
	)
	(segment
		(start 419.664642 -32.9311)
		(end 419.248844 -32.9311)
		(width 0.1143)
		(layer "In5.Cu")
		(net "GND")
	)
	(segment
		(start 353.635056 -6.089904)
		(end 354.278946 -6.733794)
		(width 0.508)
		(layer "In5.Cu")
		(net "GND")
	)
	(segment
		(start 420.460932 -31.347156)
		(end 420.119048 -31.347156)
		(width 0.1143)
		(layer "In5.Cu")
		(net "GND")
	)
	(segment
		(start 479.381058 -129.845308)
		(end 479.381058 -130.582416)
		(width 0.635)
		(layer "In5.Cu")
		(net "GND")
	)
	(segment
		(start 480.385628 -125.937772)
		(end 481.1014 -125.222)
		(width 0.254)
		(layer "In5.Cu")
		(net "GND")
	)
	(segment
		(start 495.3 -58.079894)
		(end 496.22202 -58.886344)
		(width 0.508)
		(layer "In5.Cu")
		(net "GND")
	)
	(segment
		(start 4.629912 -45.310044)
		(end 6.063996 -46.744128)
		(width 0.508)
		(layer "In5.Cu")
		(net "GND")
	)
	(segment
		(start -0.500126 -45.310044)
		(end 0.933958 -46.744128)
		(width 0.508)
		(layer "In5.Cu")
		(net "GND")
	)
	(segment
		(start 480.92614 -4.856226)
		(end 481.57003 -5.500116)
		(width 0.254)
		(layer "In5.Cu")
		(net "GND")
	)
	(segment
		(start 78.2193 -12.885166)
		(end 77.919834 -12.885166)
		(width 0.4572)
		(layer "In5.Cu")
		(net "GND")
	)
	(segment
		(start 494.37798 -58.886344)
		(end 495.3 -58.079894)
		(width 0.508)
		(layer "In5.Cu")
		(net "GND")
	)
	(segment
		(start 3.940048 -110.259876)
		(end 4.79933 -109.400594)
		(width 0.508)
		(layer "In5.Cu")
		(net "GND")
	)
	(segment
		(start 3.080766 -109.400594)
		(end 3.940048 -110.259876)
		(width 0.508)
		(layer "In5.Cu")
		(net "GND")
	)
	(segment
		(start 480.335844 -152.93467)
		(end 481.051616 -153.650442)
		(width 0.254)
		(layer "In5.Cu")
		(net "GND")
	)
	(segment
		(start 278.9682 -130.8862)
		(end 279.4 -130.8862)
		(width 0.4572)
		(layer "In5.Cu")
		(net "GND")
	)
	(segment
		(start 384.535172 -6.089904)
		(end 385.179062 -5.446014)
		(width 0.508)
		(layer "In5.Cu")
		(net "GND")
	)
	(segment
		(start 78.274164 -22.198076)
		(end 77.925676 -22.198076)
		(width 0.4572)
		(layer "In5.Cu")
		(net "GND")
	)
	(segment
		(start 487.66984 -131.07416)
		(end 488.250992 -131.655312)
		(width 0.254)
		(layer "In5.Cu")
		(net "GND")
	)
	(segment
		(start 11.249914 -45.310044)
		(end 12.683998 -46.744128)
		(width 0.508)
		(layer "In5.Cu")
		(net "GND")
	)
	(segment
		(start 470.2175 -146.493992)
		(end 470.816432 -145.89506)
		(width 0.254)
		(layer "In5.Cu")
		(net "GND")
	)
	(segment
		(start 29.615638 -37.824156)
		(end 30.47492 -36.964874)
		(width 0.508)
		(layer "In5.Cu")
		(net "GND")
	)
	(segment
		(start 419.307772 -32.129222)
		(end 419.681406 -32.129222)
		(width 0.1143)
		(layer "In5.Cu")
		(net "GND")
	)
	(segment
		(start 494.37798 -55.273448)
		(end 495.3 -56.079898)
		(width 0.508)
		(layer "In5.Cu")
		(net "GND")
	)
	(segment
		(start 479.620072 -152.218898)
		(end 480.335844 -152.93467)
		(width 0.254)
		(layer "In5.Cu")
		(net "GND")
	)
	(segment
		(start -2.430526 2.430526)
		(end 0 0)
		(width 0.762)
		(layer "In5.Cu")
		(net "GND")
	)
	(segment
		(start -1.93421 -43.87596)
		(end -0.500126 -45.310044)
		(width 0.508)
		(layer "In5.Cu")
		(net "GND")
	)
	(segment
		(start 496.000024 -153.849832)
		(end 496.670838 -154.520646)
		(width 0.254)
		(layer "In5.Cu")
		(net "GND")
	)
	(segment
		(start 494.651538 -54.507638)
		(end 495.3 -52.804822)
		(width 0.508)
		(layer "In5.Cu")
		(net "GND")
	)
	(segment
		(start 26.714196 -27.19705)
		(end 27.241246 -26.67)
		(width 0.254)
		(layer "In5.Cu")
		(net "GND")
	)
	(segment
		(start 499.736872 -51.302158)
		(end 500.55018 -52.579778)
		(width 0.508)
		(layer "In5.Cu")
		(net "GND")
	)
	(segment
		(start 489.039154 -135.265414)
		(end 490.081062 -135.265414)
		(width 0.508)
		(layer "In5.Cu")
		(net "GND")
	)
	(segment
		(start 487.66984 -132.236464)
		(end 488.250992 -131.655312)
		(width 0.254)
		(layer "In5.Cu")
		(net "GND")
	)
	(segment
		(start 488.683554 -129.845308)
		(end 490.081062 -129.845308)
		(width 0.635)
		(layer "In5.Cu")
		(net "GND")
	)
	(segment
		(start 499.736872 -60.302394)
		(end 500.55018 -61.580014)
		(width 0.508)
		(layer "In5.Cu")
		(net "GND")
	)
	(segment
		(start 352.991166 -6.733794)
		(end 353.635056 -6.089904)
		(width 0.508)
		(layer "In5.Cu")
		(net "GND")
	)
	(segment
		(start 371.771672 -78.697074)
		(end 372.144036 -78.697074)
		(width 0.1143)
		(layer "In5.Cu")
		(net "GND")
	)
	(segment
		(start 500.55018 -60.302394)
		(end 500.55018 -61.580014)
		(width 0.508)
		(layer "In5.Cu")
		(net "GND")
	)
	(segment
		(start 469.618568 -145.89506)
		(end 470.2175 -146.493992)
		(width 0.254)
		(layer "In5.Cu")
		(net "GND")
	)
	(segment
		(start 421.694356 -37.741098)
		(end 422.118282 -37.741098)
		(width 0.1143)
		(layer "In5.Cu")
		(net "GND")
	)
	(segment
		(start 78.128368 -18.7452)
		(end 77.9272 -18.7452)
		(width 0.4572)
		(layer "In5.Cu")
		(net "GND")
	)
	(segment
		(start 407.08199 -79.521304)
		(end 409.719526 -76.883768)
		(width 0.762)
		(layer "In5.Cu")
		(net "GND")
	)
	(segment
		(start 370.151914 -77.901546)
		(end 370.559076 -77.901546)
		(width 0.1143)
		(layer "In5.Cu")
		(net "GND")
	)
	(segment
		(start 481.1014 -125.222)
		(end 481.817172 -124.506228)
		(width 0.254)
		(layer "In5.Cu")
		(net "GND")
	)
	(segment
		(start 469.618568 -147.092924)
		(end 470.2175 -146.493992)
		(width 0.254)
		(layer "In5.Cu")
		(net "GND")
	)
	(segment
		(start -1.93421 -46.744128)
		(end -0.500126 -45.310044)
		(width 0.508)
		(layer "In5.Cu")
		(net "GND")
	)
	(segment
		(start 396.758414 4.561586)
		(end 397.51 3.81)
		(width 0.254)
		(layer "In5.Cu")
		(net "GND")
	)
	(segment
		(start 11.249914 -45.310044)
		(end 12.683998 -43.87596)
		(width 0.508)
		(layer "In5.Cu")
		(net "GND")
	)
	(segment
		(start 495.3 -59.652154)
		(end 495.3 -61.35497)
		(width 0.508)
		(layer "In5.Cu")
		(net "GND")
	)
	(segment
		(start 497.819934 -53.104796)
		(end 498.32006 -53.604922)
		(width 0.508)
		(layer "In5.Cu")
		(net "GND")
	)
	(segment
		(start 488.250992 -131.655312)
		(end 488.832144 -132.236464)
		(width 0.254)
		(layer "In5.Cu")
		(net "GND")
	)
	(segment
		(start 495.3 -56.079898)
		(end 496.22202 -56.886348)
		(width 0.508)
		(layer "In5.Cu")
		(net "GND")
	)
	(segment
		(start 479.381058 -129.845308)
		(end 480.422966 -129.845308)
		(width 0.635)
		(layer "In5.Cu")
		(net "GND")
	)
	(segment
		(start 480.385628 -124.506228)
		(end 481.1014 -125.222)
		(width 0.254)
		(layer "In5.Cu")
		(net "GND")
	)
	(segment
		(start 490.081062 -129.845308)
		(end 491.47857 -129.845308)
		(width 0.635)
		(layer "In5.Cu")
		(net "GND")
	)
	(segment
		(start 498.32006 -60.55487)
		(end 498.820186 -60.054744)
		(width 0.508)
		(layer "In5.Cu")
		(net "GND")
	)
	(segment
		(start 419.896544 -31.930594)
		(end 419.896544 -31.506668)
		(width 0.1143)
		(layer "In5.Cu")
		(net "GND")
	)
	(segment
		(start 29.615638 -36.105592)
		(end 30.47492 -36.964874)
		(width 0.508)
		(layer "In5.Cu")
		(net "GND")
	)
	(segment
		(start 461.497172 -157.83814)
		(end 462.19491 -157.140402)
		(width 0.254)
		(layer "In5.Cu")
		(net "GND")
	)
	(segment
		(start 500.253 -25.4)
		(end 500.253 -24.13)
		(width 0.1524)
		(layer "In5.Cu")
		(net "GND")
	)
	(segment
		(start -0.500126 -45.310044)
		(end 0.933958 -43.87596)
		(width 0.508)
		(layer "In5.Cu")
		(net "GND")
	)
	(segment
		(start 495.3 -58.079894)
		(end 496.22202 -57.273444)
		(width 0.508)
		(layer "In5.Cu")
		(net "GND")
	)
	(segment
		(start 371.714522 -77.884528)
		(end 372.164102 -77.884528)
		(width 0.1143)
		(layer "In5.Cu")
		(net "GND")
	)
	(segment
		(start 30.47492 -36.964874)
		(end 31.334202 -37.824156)
		(width 0.508)
		(layer "In5.Cu")
		(net "GND")
	)
	(segment
		(start 480.335844 -152.93467)
		(end 481.051616 -152.218898)
		(width 0.254)
		(layer "In5.Cu")
		(net "GND")
	)
	(segment
		(start 0 0)
		(end 2.430526 -2.430526)
		(width 0.762)
		(layer "In5.Cu")
		(net "GND")
	)
	(segment
		(start 490.081062 -129.845308)
		(end 490.081062 -130.582416)
		(width 0.635)
		(layer "In5.Cu")
		(net "GND")
	)
	(segment
		(start 469.618568 -143.092932)
		(end 470.2175 -142.494)
		(width 0.254)
		(layer "In5.Cu")
		(net "GND")
	)
	(segment
		(start 370.737384 -77.310742)
		(end 370.737384 -77.680058)
		(width 0.1143)
		(layer "In5.Cu")
		(net "GND")
	)
	(segment
		(start 478.33915 -129.845308)
		(end 479.381058 -129.845308)
		(width 0.635)
		(layer "In5.Cu")
		(net "GND")
	)
	(segment
		(start 490.081062 -129.1082)
		(end 490.081062 -129.845308)
		(width 0.635)
		(layer "In5.Cu")
		(net "GND")
	)
	(segment
		(start 497.819934 -61.054996)
		(end 498.32006 -60.55487)
		(width 0.508)
		(layer "In5.Cu")
		(net "GND")
	)
	(segment
		(start 470.2175 -142.494)
		(end 470.816432 -141.895068)
		(width 0.254)
		(layer "In5.Cu")
		(net "GND")
	)
	(segment
		(start 495.32921 -154.520646)
		(end 496.000024 -153.849832)
		(width 0.254)
		(layer "In5.Cu")
		(net "GND")
	)
	(segment
		(start 499.736872 -53.857398)
		(end 500.55018 -52.579778)
		(width 0.508)
		(layer "In5.Cu")
		(net "GND")
	)
	(segment
		(start 479.381058 -134.528306)
		(end 479.381058 -135.265414)
		(width 0.635)
		(layer "In5.Cu")
		(net "GND")
	)
	(segment
		(start 490.081062 -135.265414)
		(end 491.12297 -135.265414)
		(width 0.508)
		(layer "In5.Cu")
		(net "GND")
	)
	(segment
		(start 352.991166 -5.446014)
		(end 353.635056 -6.089904)
		(width 0.508)
		(layer "In5.Cu")
		(net "GND")
	)
	(segment
		(start 353.635056 -6.089904)
		(end 354.278946 -5.446014)
		(width 0.508)
		(layer "In5.Cu")
		(net "GND")
	)
	(segment
		(start 498.32006 -60.55487)
		(end 498.820186 -61.054996)
		(width 0.508)
		(layer "In5.Cu")
		(net "GND")
	)
	(segment
		(start 26.714196 -26.14295)
		(end 27.241246 -26.67)
		(width 0.254)
		(layer "In5.Cu")
		(net "GND")
	)
	(segment
		(start 417.759134 0.741934)
		(end 418.421058 0.08001)
		(width 0.508)
		(layer "In5.Cu")
		(net "GND")
	)
	(segment
		(start 480.92614 -6.144006)
		(end 481.57003 -5.500116)
		(width 0.254)
		(layer "In5.Cu")
		(net "GND")
	)
	(segment
		(start 488.250992 -131.655312)
		(end 488.832144 -131.07416)
		(width 0.254)
		(layer "In5.Cu")
		(net "GND")
	)
	(segment
		(start 470.2175 -146.493992)
		(end 470.816432 -147.092924)
		(width 0.254)
		(layer "In5.Cu")
		(net "GND")
	)
	(segment
		(start 397.51 3.81)
		(end 398.261586 3.058414)
		(width 0.254)
		(layer "In5.Cu")
		(net "GND")
	)
	(segment
		(start 397.51 3.81)
		(end 398.261586 4.561586)
		(width 0.254)
		(layer "In5.Cu")
		(net "GND")
	)
	(segment
		(start 479.381058 -129.1082)
		(end 479.381058 -129.845308)
		(width 0.635)
		(layer "In5.Cu")
		(net "GND")
	)
	(segment
		(start 4.629912 -45.310044)
		(end 6.063996 -43.87596)
		(width 0.508)
		(layer "In5.Cu")
		(net "GND")
	)
	(segment
		(start 494.37798 -56.886348)
		(end 495.3 -56.079898)
		(width 0.508)
		(layer "In5.Cu")
		(net "GND")
	)
	(segment
		(start 490.081062 -135.265414)
		(end 490.081062 -136.002522)
		(width 0.508)
		(layer "In5.Cu")
		(net "GND")
	)
	(segment
		(start 3.080766 -111.119158)
		(end 3.940048 -110.259876)
		(width 0.508)
		(layer "In5.Cu")
		(net "GND")
	)
	(segment
		(start 462.19491 -157.140402)
		(end 462.892648 -156.442664)
		(width 0.254)
		(layer "In5.Cu")
		(net "GND")
	)
	(segment
		(start 418.421058 0.08001)
		(end 419.082982 -0.581914)
		(width 0.508)
		(layer "In5.Cu")
		(net "GND")
	)
	(segment
		(start 461.497172 -156.442664)
		(end 462.19491 -157.140402)
		(width 0.254)
		(layer "In5.Cu")
		(net "GND")
	)
	(segment
		(start 496.000024 -153.849832)
		(end 496.670838 -153.179018)
		(width 0.254)
		(layer "In5.Cu")
		(net "GND")
	)
	(segment
		(start 383.891282 -6.733794)
		(end 384.535172 -6.089904)
		(width 0.508)
		(layer "In5.Cu")
		(net "GND")
	)
	(segment
		(start 421.694356 -31.340806)
		(end 422.118282 -31.340806)
		(width 0.1143)
		(layer "In5.Cu")
		(net "GND")
	)
	(segment
		(start 384.535172 -6.089904)
		(end 385.179062 -6.733794)
		(width 0.508)
		(layer "In5.Cu")
		(net "GND")
	)
	(segment
		(start 470.2175 -142.494)
		(end 470.816432 -143.092932)
		(width 0.254)
		(layer "In5.Cu")
		(net "GND")
	)
	(segment
		(start 479.620072 -153.650442)
		(end 480.335844 -152.93467)
		(width 0.254)
		(layer "In5.Cu")
		(net "GND")
	)
	(segment
		(start 421.694356 -32.140906)
		(end 422.118282 -32.140906)
		(width 0.1143)
		(layer "In5.Cu")
		(net "GND")
	)
	(segment
		(start 9.81583 -43.87596)
		(end 11.249914 -45.310044)
		(width 0.508)
		(layer "In5.Cu")
		(net "GND")
	)
	(segment
		(start 469.618568 -141.895068)
		(end 470.2175 -142.494)
		(width 0.254)
		(layer "In5.Cu")
		(net "GND")
	)
	(segment
		(start 4.629912 -45.310044)
		(end 6.063996 -43.87596)
		(width 0.508)
		(layer "In8.Cu")
		(net "GND")
	)
	(segment
		(start 353.635056 -6.089904)
		(end 354.278946 -5.446014)
		(width 0.508)
		(layer "In8.Cu")
		(net "GND")
	)
	(segment
		(start 494.651538 -59.652154)
		(end 495.3 -61.35497)
		(width 0.508)
		(layer "In8.Cu")
		(net "GND")
	)
	(segment
		(start 499.736872 -60.302394)
		(end 500.55018 -61.580014)
		(width 0.508)
		(layer "In8.Cu")
		(net "GND")
	)
	(segment
		(start -1.93421 -46.744128)
		(end -0.500126 -45.310044)
		(width 0.508)
		(layer "In8.Cu")
		(net "GND")
	)
	(segment
		(start 384.535172 -6.089904)
		(end 385.179062 -5.446014)
		(width 0.508)
		(layer "In8.Cu")
		(net "GND")
	)
	(segment
		(start 499.736872 -51.302158)
		(end 500.55018 -52.579778)
		(width 0.508)
		(layer "In8.Cu")
		(net "GND")
	)
	(segment
		(start 435.598062 -136.916922)
		(end 436.17007 -136.344914)
		(width 0.254)
		(layer "In8.Cu")
		(net "GND")
	)
	(segment
		(start 445.38011 -136.344914)
		(end 445.916304 -136.881108)
		(width 0.254)
		(layer "In8.Cu")
		(net "GND")
	)
	(segment
		(start 383.891282 -6.733794)
		(end 384.535172 -6.089904)
		(width 0.508)
		(layer "In8.Cu")
		(net "GND")
	)
	(segment
		(start 494.651538 -54.507638)
		(end 495.3 -52.804822)
		(width 0.508)
		(layer "In8.Cu")
		(net "GND")
	)
	(segment
		(start 444.380112 -136.344914)
		(end 444.916306 -135.80872)
		(width 0.254)
		(layer "In8.Cu")
		(net "GND")
	)
	(segment
		(start 9.81583 -43.87596)
		(end 11.249914 -45.310044)
		(width 0.508)
		(layer "In8.Cu")
		(net "GND")
	)
	(segment
		(start 443.843918 -135.80872)
		(end 444.380112 -136.344914)
		(width 0.254)
		(layer "In8.Cu")
		(net "GND")
	)
	(segment
		(start 11.249914 -45.310044)
		(end 12.683998 -46.744128)
		(width 0.508)
		(layer "In8.Cu")
		(net "GND")
	)
	(segment
		(start 3.940048 -110.259876)
		(end 4.79933 -109.400594)
		(width 0.508)
		(layer "In8.Cu")
		(net "GND")
	)
	(segment
		(start 498.32006 -60.55487)
		(end 498.820186 -61.054996)
		(width 0.508)
		(layer "In8.Cu")
		(net "GND")
	)
	(segment
		(start 428.55007 -136.344914)
		(end 429.122078 -136.916922)
		(width 0.254)
		(layer "In8.Cu")
		(net "GND")
	)
	(segment
		(start 432.36007 -136.344914)
		(end 432.932078 -135.772906)
		(width 0.254)
		(layer "In8.Cu")
		(net "GND")
	)
	(segment
		(start 445.38011 -136.344914)
		(end 445.916304 -135.80872)
		(width 0.254)
		(layer "In8.Cu")
		(net "GND")
	)
	(segment
		(start 494.37798 -55.273448)
		(end 495.3 -56.079898)
		(width 0.508)
		(layer "In8.Cu")
		(net "GND")
	)
	(segment
		(start 494.37798 -56.886348)
		(end 495.3 -56.079898)
		(width 0.508)
		(layer "In8.Cu")
		(net "GND")
	)
	(segment
		(start 407.08199 -79.521304)
		(end 409.719526 -76.883768)
		(width 0.762)
		(layer "In8.Cu")
		(net "GND")
	)
	(segment
		(start 0 0)
		(end 2.430526 -2.430526)
		(width 0.762)
		(layer "In8.Cu")
		(net "GND")
	)
	(segment
		(start 0 0)
		(end 2.430526 2.430526)
		(width 0.762)
		(layer "In8.Cu")
		(net "GND")
	)
	(segment
		(start 417.759134 -0.581914)
		(end 418.421058 0.08001)
		(width 0.508)
		(layer "In8.Cu")
		(net "GND")
	)
	(segment
		(start 436.17007 -136.344914)
		(end 436.742078 -136.916922)
		(width 0.254)
		(layer "In8.Cu")
		(net "GND")
	)
	(segment
		(start 352.991166 -6.733794)
		(end 353.635056 -6.089904)
		(width 0.508)
		(layer "In8.Cu")
		(net "GND")
	)
	(segment
		(start 497.819934 -53.104796)
		(end 498.32006 -53.604922)
		(width 0.508)
		(layer "In8.Cu")
		(net "GND")
	)
	(segment
		(start 480.92614 -6.144006)
		(end 481.57003 -5.500116)
		(width 0.254)
		(layer "In8.Cu")
		(net "GND")
	)
	(segment
		(start 494.37798 -58.886344)
		(end 495.3 -58.079894)
		(width 0.508)
		(layer "In8.Cu")
		(net "GND")
	)
	(segment
		(start -1.93421 -43.87596)
		(end -0.500126 -45.310044)
		(width 0.508)
		(layer "In8.Cu")
		(net "GND")
	)
	(segment
		(start 443.843918 -136.881108)
		(end 444.380112 -136.344914)
		(width 0.254)
		(layer "In8.Cu")
		(net "GND")
	)
	(segment
		(start 4.629912 -45.310044)
		(end 6.063996 -46.744128)
		(width 0.508)
		(layer "In8.Cu")
		(net "GND")
	)
	(segment
		(start 495.3 -56.079898)
		(end 496.22202 -55.273448)
		(width 0.508)
		(layer "In8.Cu")
		(net "GND")
	)
	(segment
		(start 498.32006 -60.55487)
		(end 498.820186 -60.054744)
		(width 0.508)
		(layer "In8.Cu")
		(net "GND")
	)
	(segment
		(start 498.32006 -53.604922)
		(end 498.820186 -54.105048)
		(width 0.508)
		(layer "In8.Cu")
		(net "GND")
	)
	(segment
		(start 499.736872 -53.857398)
		(end 500.55018 -52.579778)
		(width 0.508)
		(layer "In8.Cu")
		(net "GND")
	)
	(segment
		(start 498.32006 -53.604922)
		(end 498.820186 -53.104796)
		(width 0.508)
		(layer "In8.Cu")
		(net "GND")
	)
	(segment
		(start 428.55007 -136.344914)
		(end 429.122078 -135.772906)
		(width 0.254)
		(layer "In8.Cu")
		(net "GND")
	)
	(segment
		(start 481.965 -147.193)
		(end 482.626924 -146.531076)
		(width 0.254)
		(layer "In8.Cu")
		(net "GND")
	)
	(segment
		(start -2.430526 2.430526)
		(end 0 0)
		(width 0.762)
		(layer "In8.Cu")
		(net "GND")
	)
	(segment
		(start 3.080766 -111.119158)
		(end 3.940048 -110.259876)
		(width 0.508)
		(layer "In8.Cu")
		(net "GND")
	)
	(segment
		(start 427.978062 -136.916922)
		(end 428.55007 -136.344914)
		(width 0.254)
		(layer "In8.Cu")
		(net "GND")
	)
	(segment
		(start 494.651538 -51.623214)
		(end 495.3 -52.804822)
		(width 0.508)
		(layer "In8.Cu")
		(net "GND")
	)
	(segment
		(start 497.819934 -61.054996)
		(end 498.32006 -60.55487)
		(width 0.508)
		(layer "In8.Cu")
		(net "GND")
	)
	(segment
		(start 11.249914 -45.310044)
		(end 12.683998 -43.87596)
		(width 0.508)
		(layer "In8.Cu")
		(net "GND")
	)
	(segment
		(start 431.788062 -135.772906)
		(end 432.36007 -136.344914)
		(width 0.254)
		(layer "In8.Cu")
		(net "GND")
	)
	(segment
		(start 409.719526 -76.883768)
		(end 412.357062 -79.521304)
		(width 0.762)
		(layer "In8.Cu")
		(net "GND")
	)
	(segment
		(start 3.195828 -43.87596)
		(end 4.629912 -45.310044)
		(width 0.508)
		(layer "In8.Cu")
		(net "GND")
	)
	(segment
		(start 407.08199 -74.246232)
		(end 409.719526 -76.883768)
		(width 0.762)
		(layer "In8.Cu")
		(net "GND")
	)
	(segment
		(start 482.092 -149.709886)
		(end 482.753924 -149.047962)
		(width 0.254)
		(layer "In8.Cu")
		(net "GND")
	)
	(segment
		(start 3.940048 -110.259876)
		(end 4.79933 -111.119158)
		(width 0.508)
		(layer "In8.Cu")
		(net "GND")
	)
	(segment
		(start -0.500126 -45.310044)
		(end 0.933958 -46.744128)
		(width 0.508)
		(layer "In8.Cu")
		(net "GND")
	)
	(segment
		(start -0.500126 -45.310044)
		(end 0.933958 -43.87596)
		(width 0.508)
		(layer "In8.Cu")
		(net "GND")
	)
	(segment
		(start 495.3 -58.079894)
		(end 496.22202 -57.273444)
		(width 0.508)
		(layer "In8.Cu")
		(net "GND")
	)
	(segment
		(start 409.719526 -76.883768)
		(end 412.357062 -74.246232)
		(width 0.762)
		(layer "In8.Cu")
		(net "GND")
	)
	(segment
		(start 444.843916 -136.881108)
		(end 445.38011 -136.344914)
		(width 0.254)
		(layer "In8.Cu")
		(net "GND")
	)
	(segment
		(start 383.891282 -5.446014)
		(end 384.535172 -6.089904)
		(width 0.508)
		(layer "In8.Cu")
		(net "GND")
	)
	(segment
		(start 418.421058 0.08001)
		(end 419.082982 -0.581914)
		(width 0.508)
		(layer "In8.Cu")
		(net "GND")
	)
	(segment
		(start 431.788062 -136.916922)
		(end 432.36007 -136.344914)
		(width 0.254)
		(layer "In8.Cu")
		(net "GND")
	)
	(segment
		(start 444.843916 -135.80872)
		(end 445.38011 -136.344914)
		(width 0.254)
		(layer "In8.Cu")
		(net "GND")
	)
	(segment
		(start 495.3 -56.079898)
		(end 496.22202 -56.886348)
		(width 0.508)
		(layer "In8.Cu")
		(net "GND")
	)
	(segment
		(start 480.92614 -4.856226)
		(end 481.57003 -5.500116)
		(width 0.254)
		(layer "In8.Cu")
		(net "GND")
	)
	(segment
		(start 352.991166 -5.446014)
		(end 353.635056 -6.089904)
		(width 0.508)
		(layer "In8.Cu")
		(net "GND")
	)
	(segment
		(start 436.17007 -136.344914)
		(end 436.742078 -135.772906)
		(width 0.254)
		(layer "In8.Cu")
		(net "GND")
	)
	(segment
		(start 3.080766 -109.400594)
		(end 3.940048 -110.259876)
		(width 0.508)
		(layer "In8.Cu")
		(net "GND")
	)
	(segment
		(start 495.3 -59.652154)
		(end 495.3 -61.35497)
		(width 0.508)
		(layer "In8.Cu")
		(net "GND")
	)
	(segment
		(start 418.421058 0.08001)
		(end 419.082982 0.741934)
		(width 0.508)
		(layer "In8.Cu")
		(net "GND")
	)
	(segment
		(start 495.3 -58.079894)
		(end 496.22202 -58.886344)
		(width 0.508)
		(layer "In8.Cu")
		(net "GND")
	)
	(segment
		(start 435.598062 -135.772906)
		(end 436.17007 -136.344914)
		(width 0.254)
		(layer "In8.Cu")
		(net "GND")
	)
	(segment
		(start -2.430526 -2.430526)
		(end 0 0)
		(width 0.762)
		(layer "In8.Cu")
		(net "GND")
	)
	(segment
		(start 353.635056 -6.089904)
		(end 354.278946 -6.733794)
		(width 0.508)
		(layer "In8.Cu")
		(net "GND")
	)
	(segment
		(start 3.195828 -46.744128)
		(end 4.629912 -45.310044)
		(width 0.508)
		(layer "In8.Cu")
		(net "GND")
	)
	(segment
		(start 432.36007 -136.344914)
		(end 432.932078 -136.916922)
		(width 0.254)
		(layer "In8.Cu")
		(net "GND")
	)
	(segment
		(start 417.759134 0.741934)
		(end 418.421058 0.08001)
		(width 0.508)
		(layer "In8.Cu")
		(net "GND")
	)
	(segment
		(start 384.535172 -6.089904)
		(end 385.179062 -6.733794)
		(width 0.508)
		(layer "In8.Cu")
		(net "GND")
	)
	(segment
		(start 427.978062 -135.772906)
		(end 428.55007 -136.344914)
		(width 0.254)
		(layer "In8.Cu")
		(net "GND")
	)
	(segment
		(start 444.380112 -136.344914)
		(end 444.916306 -136.881108)
		(width 0.254)
		(layer "In8.Cu")
		(net "GND")
	)
	(segment
		(start 500.55018 -60.302394)
		(end 500.55018 -61.580014)
		(width 0.508)
		(layer "In8.Cu")
		(net "GND")
	)
	(segment
		(start 9.81583 -46.744128)
		(end 11.249914 -45.310044)
		(width 0.508)
		(layer "In8.Cu")
		(net "GND")
	)
	(segment
		(start -1.93421 -46.744128)
		(end -0.500126 -45.310044)
		(width 0.508)
		(layer "In9.Cu")
		(net "GND")
	)
	(segment
		(start 3.195828 -46.744128)
		(end 4.629912 -45.310044)
		(width 0.508)
		(layer "In9.Cu")
		(net "GND")
	)
	(segment
		(start 4.629912 -45.310044)
		(end 6.063996 -43.87596)
		(width 0.508)
		(layer "In9.Cu")
		(net "GND")
	)
	(segment
		(start -0.500126 -45.310044)
		(end 0.933958 -43.87596)
		(width 0.508)
		(layer "In9.Cu")
		(net "GND")
	)
	(segment
		(start -0.500126 -45.310044)
		(end 0.933958 -46.744128)
		(width 0.508)
		(layer "In9.Cu")
		(net "GND")
	)
	(segment
		(start -1.93421 -43.87596)
		(end -0.500126 -45.310044)
		(width 0.508)
		(layer "In9.Cu")
		(net "GND")
	)
	(segment
		(start 9.293606 -45.310044)
		(end 11.249914 -45.310044)
		(width 0.508)
		(layer "In9.Cu")
		(net "GND")
	)
	(segment
		(start 4.629912 -45.310044)
		(end 6.063996 -46.744128)
		(width 0.508)
		(layer "In9.Cu")
		(net "GND")
	)
	(segment
		(start 9.81583 -46.744128)
		(end 11.249914 -45.310044)
		(width 0.508)
		(layer "In9.Cu")
		(net "GND")
	)
	(segment
		(start 3.195828 -43.87596)
		(end 4.629912 -45.310044)
		(width 0.508)
		(layer "In9.Cu")
		(net "GND")
	)
	(segment
		(start 435.598062 -135.772906)
		(end 436.17007 -136.344914)
		(width 0.254)
		(layer "In10.Cu")
		(net "GND")
	)
	(segment
		(start 490.081062 -134.528306)
		(end 490.081062 -135.265414)
		(width 0.508)
		(layer "In10.Cu")
		(net "GND")
	)
	(segment
		(start 480.335844 -152.93467)
		(end 481.051616 -153.650442)
		(width 0.254)
		(layer "In10.Cu")
		(net "GND")
	)
	(segment
		(start 444.380112 -136.344914)
		(end 444.916306 -136.881108)
		(width 0.254)
		(layer "In10.Cu")
		(net "GND")
	)
	(segment
		(start 462.19491 -157.140402)
		(end 462.892648 -156.442664)
		(width 0.254)
		(layer "In10.Cu")
		(net "GND")
	)
	(segment
		(start 470.2175 -142.494)
		(end 470.816432 -141.895068)
		(width 0.254)
		(layer "In10.Cu")
		(net "GND")
	)
	(segment
		(start 443.843918 -136.881108)
		(end 444.380112 -136.344914)
		(width 0.254)
		(layer "In10.Cu")
		(net "GND")
	)
	(segment
		(start 480.92614 -4.856226)
		(end 481.57003 -5.500116)
		(width 0.254)
		(layer "In10.Cu")
		(net "GND")
	)
	(segment
		(start 469.618568 -143.092932)
		(end 470.2175 -142.494)
		(width 0.254)
		(layer "In10.Cu")
		(net "GND")
	)
	(segment
		(start 478.33915 -129.845308)
		(end 479.381058 -129.845308)
		(width 0.635)
		(layer "In10.Cu")
		(net "GND")
	)
	(segment
		(start 488.250992 -131.655312)
		(end 488.832144 -131.07416)
		(width 0.254)
		(layer "In10.Cu")
		(net "GND")
	)
	(segment
		(start 469.618568 -141.895068)
		(end 470.2175 -142.494)
		(width 0.254)
		(layer "In10.Cu")
		(net "GND")
	)
	(segment
		(start 27.241246 -26.67)
		(end 27.768296 -26.14295)
		(width 0.254)
		(layer "In10.Cu")
		(net "GND")
	)
	(segment
		(start 397.51 3.81)
		(end 398.261586 3.058414)
		(width 0.254)
		(layer "In10.Cu")
		(net "GND")
	)
	(segment
		(start 479.381058 -135.265414)
		(end 479.381058 -136.002522)
		(width 0.635)
		(layer "In10.Cu")
		(net "GND")
	)
	(segment
		(start 443.843918 -135.80872)
		(end 444.380112 -136.344914)
		(width 0.254)
		(layer "In10.Cu")
		(net "GND")
	)
	(segment
		(start 396.758414 3.058414)
		(end 397.51 3.81)
		(width 0.254)
		(layer "In10.Cu")
		(net "GND")
	)
	(segment
		(start 435.598062 -136.916922)
		(end 436.17007 -136.344914)
		(width 0.254)
		(layer "In10.Cu")
		(net "GND")
	)
	(segment
		(start 479.381058 -129.845308)
		(end 479.381058 -130.582416)
		(width 0.635)
		(layer "In10.Cu")
		(net "GND")
	)
	(segment
		(start 479.381058 -129.845308)
		(end 480.422966 -129.845308)
		(width 0.635)
		(layer "In10.Cu")
		(net "GND")
	)
	(segment
		(start 489.039154 -135.265414)
		(end 490.081062 -135.265414)
		(width 0.508)
		(layer "In10.Cu")
		(net "GND")
	)
	(segment
		(start 481.1014 -125.222)
		(end 481.817172 -125.937772)
		(width 0.254)
		(layer "In10.Cu")
		(net "GND")
	)
	(segment
		(start 461.497172 -157.83814)
		(end 462.19491 -157.140402)
		(width 0.254)
		(layer "In10.Cu")
		(net "GND")
	)
	(segment
		(start 469.618568 -147.092924)
		(end 470.2175 -146.493992)
		(width 0.254)
		(layer "In10.Cu")
		(net "GND")
	)
	(segment
		(start 436.17007 -136.344914)
		(end 436.742078 -136.916922)
		(width 0.254)
		(layer "In10.Cu")
		(net "GND")
	)
	(segment
		(start 479.620072 -153.650442)
		(end 480.335844 -152.93467)
		(width 0.254)
		(layer "In10.Cu")
		(net "GND")
	)
	(segment
		(start 490.081062 -135.265414)
		(end 490.081062 -136.002522)
		(width 0.508)
		(layer "In10.Cu")
		(net "GND")
	)
	(segment
		(start 479.620072 -152.218898)
		(end 480.335844 -152.93467)
		(width 0.254)
		(layer "In10.Cu")
		(net "GND")
	)
	(segment
		(start 431.788062 -135.772906)
		(end 432.36007 -136.344914)
		(width 0.254)
		(layer "In10.Cu")
		(net "GND")
	)
	(segment
		(start 396.758414 4.561586)
		(end 397.51 3.81)
		(width 0.254)
		(layer "In10.Cu")
		(net "GND")
	)
	(segment
		(start 495.32921 -154.520646)
		(end 496.000024 -153.849832)
		(width 0.254)
		(layer "In10.Cu")
		(net "GND")
	)
	(segment
		(start 278.849836 -144.5768)
		(end 279.4762 -144.5768)
		(width 0.4572)
		(layer "In10.Cu")
		(net "GND")
	)
	(segment
		(start 279.62987 -136.327642)
		(end 279.699974 -136.397746)
		(width 0.4572)
		(layer "In10.Cu")
		(net "GND")
	)
	(segment
		(start 436.17007 -136.344914)
		(end 436.742078 -135.772906)
		(width 0.254)
		(layer "In10.Cu")
		(net "GND")
	)
	(segment
		(start 487.66984 -132.236464)
		(end 488.250992 -131.655312)
		(width 0.254)
		(layer "In10.Cu")
		(net "GND")
	)
	(segment
		(start 480.385628 -124.506228)
		(end 481.1014 -125.222)
		(width 0.254)
		(layer "In10.Cu")
		(net "GND")
	)
	(segment
		(start 432.36007 -136.344914)
		(end 432.932078 -135.772906)
		(width 0.254)
		(layer "In10.Cu")
		(net "GND")
	)
	(segment
		(start 445.38011 -136.344914)
		(end 445.916304 -135.80872)
		(width 0.254)
		(layer "In10.Cu")
		(net "GND")
	)
	(segment
		(start 444.843916 -135.80872)
		(end 445.38011 -136.344914)
		(width 0.254)
		(layer "In10.Cu")
		(net "GND")
	)
	(segment
		(start 487.66984 -131.07416)
		(end 488.250992 -131.655312)
		(width 0.254)
		(layer "In10.Cu")
		(net "GND")
	)
	(segment
		(start 278.866346 -145.992342)
		(end 279.69337 -145.992342)
		(width 0.4572)
		(layer "In10.Cu")
		(net "GND")
	)
	(segment
		(start 27.241246 -26.67)
		(end 27.768296 -27.19705)
		(width 0.254)
		(layer "In10.Cu")
		(net "GND")
	)
	(segment
		(start 480.92614 -6.144006)
		(end 481.57003 -5.500116)
		(width 0.254)
		(layer "In10.Cu")
		(net "GND")
	)
	(segment
		(start 490.081062 -135.265414)
		(end 491.12297 -135.265414)
		(width 0.508)
		(layer "In10.Cu")
		(net "GND")
	)
	(segment
		(start 490.081062 -129.1082)
		(end 490.081062 -129.845308)
		(width 0.635)
		(layer "In10.Cu")
		(net "GND")
	)
	(segment
		(start 490.081062 -129.845308)
		(end 491.47857 -129.845308)
		(width 0.635)
		(layer "In10.Cu")
		(net "GND")
	)
	(segment
		(start 496.000024 -153.849832)
		(end 496.670838 -153.179018)
		(width 0.254)
		(layer "In10.Cu")
		(net "GND")
	)
	(segment
		(start 279.69337 -145.992342)
		(end 279.699974 -145.998946)
		(width 0.4572)
		(layer "In10.Cu")
		(net "GND")
	)
	(segment
		(start 488.683554 -129.845308)
		(end 490.081062 -129.845308)
		(width 0.635)
		(layer "In10.Cu")
		(net "GND")
	)
	(segment
		(start 479.381058 -134.528306)
		(end 479.381058 -135.265414)
		(width 0.635)
		(layer "In10.Cu")
		(net "GND")
	)
	(segment
		(start 278.896572 -134.913624)
		(end 279.414224 -134.913624)
		(width 0.4572)
		(layer "In10.Cu")
		(net "GND")
	)
	(segment
		(start 461.497172 -156.442664)
		(end 462.19491 -157.140402)
		(width 0.254)
		(layer "In10.Cu")
		(net "GND")
	)
	(segment
		(start 490.081062 -129.845308)
		(end 490.081062 -130.582416)
		(width 0.635)
		(layer "In10.Cu")
		(net "GND")
	)
	(segment
		(start 397.51 3.81)
		(end 398.261586 4.561586)
		(width 0.254)
		(layer "In10.Cu")
		(net "GND")
	)
	(segment
		(start 479.381058 -135.265414)
		(end 480.778566 -135.265414)
		(width 0.635)
		(layer "In10.Cu")
		(net "GND")
	)
	(segment
		(start 480.385628 -125.937772)
		(end 481.1014 -125.222)
		(width 0.254)
		(layer "In10.Cu")
		(net "GND")
	)
	(segment
		(start 444.843916 -136.881108)
		(end 445.38011 -136.344914)
		(width 0.254)
		(layer "In10.Cu")
		(net "GND")
	)
	(segment
		(start 469.618568 -145.89506)
		(end 470.2175 -146.493992)
		(width 0.254)
		(layer "In10.Cu")
		(net "GND")
	)
	(segment
		(start 444.380112 -136.344914)
		(end 444.916306 -135.80872)
		(width 0.254)
		(layer "In10.Cu")
		(net "GND")
	)
	(segment
		(start 488.250992 -131.655312)
		(end 488.832144 -132.236464)
		(width 0.254)
		(layer "In10.Cu")
		(net "GND")
	)
	(segment
		(start 496.000024 -153.849832)
		(end 496.670838 -154.520646)
		(width 0.254)
		(layer "In10.Cu")
		(net "GND")
	)
	(segment
		(start 428.55007 -136.344914)
		(end 429.122078 -136.916922)
		(width 0.254)
		(layer "In10.Cu")
		(net "GND")
	)
	(segment
		(start 445.38011 -136.344914)
		(end 445.916304 -136.881108)
		(width 0.254)
		(layer "In10.Cu")
		(net "GND")
	)
	(segment
		(start 428.55007 -136.344914)
		(end 429.122078 -135.772906)
		(width 0.254)
		(layer "In10.Cu")
		(net "GND")
	)
	(segment
		(start 477.98355 -135.265414)
		(end 479.381058 -135.265414)
		(width 0.635)
		(layer "In10.Cu")
		(net "GND")
	)
	(segment
		(start 495.32921 -153.179018)
		(end 496.000024 -153.849832)
		(width 0.254)
		(layer "In10.Cu")
		(net "GND")
	)
	(segment
		(start 470.2175 -146.493992)
		(end 470.816432 -145.89506)
		(width 0.254)
		(layer "In10.Cu")
		(net "GND")
	)
	(segment
		(start 427.978062 -136.916922)
		(end 428.55007 -136.344914)
		(width 0.254)
		(layer "In10.Cu")
		(net "GND")
	)
	(segment
		(start 470.2175 -146.493992)
		(end 470.816432 -147.092924)
		(width 0.254)
		(layer "In10.Cu")
		(net "GND")
	)
	(segment
		(start 432.36007 -136.344914)
		(end 432.932078 -136.916922)
		(width 0.254)
		(layer "In10.Cu")
		(net "GND")
	)
	(segment
		(start 278.93264 -135.587486)
		(end 279.402286 -135.587486)
		(width 0.4572)
		(layer "In10.Cu")
		(net "GND")
	)
	(segment
		(start 26.714196 -27.19705)
		(end 27.241246 -26.67)
		(width 0.254)
		(layer "In10.Cu")
		(net "GND")
	)
	(segment
		(start 431.788062 -136.916922)
		(end 432.36007 -136.344914)
		(width 0.254)
		(layer "In10.Cu")
		(net "GND")
	)
	(segment
		(start 480.335844 -152.93467)
		(end 481.051616 -152.218898)
		(width 0.254)
		(layer "In10.Cu")
		(net "GND")
	)
	(segment
		(start 278.90216 -136.327642)
		(end 279.62987 -136.327642)
		(width 0.4572)
		(layer "In10.Cu")
		(net "GND")
	)
	(segment
		(start 479.381058 -129.1082)
		(end 479.381058 -129.845308)
		(width 0.635)
		(layer "In10.Cu")
		(net "GND")
	)
	(segment
		(start 462.19491 -157.140402)
		(end 462.892648 -157.83814)
		(width 0.254)
		(layer "In10.Cu")
		(net "GND")
	)
	(segment
		(start 481.1014 -125.222)
		(end 481.817172 -124.506228)
		(width 0.254)
		(layer "In10.Cu")
		(net "GND")
	)
	(segment
		(start 427.978062 -135.772906)
		(end 428.55007 -136.344914)
		(width 0.254)
		(layer "In10.Cu")
		(net "GND")
	)
	(segment
		(start 470.2175 -142.494)
		(end 470.816432 -143.092932)
		(width 0.254)
		(layer "In10.Cu")
		(net "GND")
	)
	(segment
		(start 26.714196 -26.14295)
		(end 27.241246 -26.67)
		(width 0.254)
		(layer "In10.Cu")
		(net "GND")
	)
	(segment
		(start -1.93421 -43.87596)
		(end -0.500126 -45.310044)
		(width 0.508)
		(layer "In11.Cu")
		(net "GND")
	)
	(segment
		(start 4.629912 -45.310044)
		(end 6.063996 -43.87596)
		(width 0.508)
		(layer "In11.Cu")
		(net "GND")
	)
	(segment
		(start -0.500126 -45.310044)
		(end 0.933958 -46.744128)
		(width 0.508)
		(layer "In11.Cu")
		(net "GND")
	)
	(segment
		(start 3.195828 -43.87596)
		(end 4.629912 -45.310044)
		(width 0.508)
		(layer "In11.Cu")
		(net "GND")
	)
	(segment
		(start 9.81583 -46.744128)
		(end 11.249914 -45.310044)
		(width 0.508)
		(layer "In11.Cu")
		(net "GND")
	)
	(segment
		(start 367.9952 -108.6612)
		(end 367.411 -108.6612)
		(width 0.508)
		(layer "In11.Cu")
		(net "GND")
	)
	(segment
		(start 9.81583 -43.87596)
		(end 11.249914 -45.310044)
		(width 0.508)
		(layer "In11.Cu")
		(net "GND")
	)
	(segment
		(start -0.500126 -45.310044)
		(end 0.933958 -43.87596)
		(width 0.508)
		(layer "In11.Cu")
		(net "GND")
	)
	(segment
		(start -1.93421 -46.744128)
		(end -0.500126 -45.310044)
		(width 0.508)
		(layer "In11.Cu")
		(net "GND")
	)
	(segment
		(start 3.195828 -46.744128)
		(end 4.629912 -45.310044)
		(width 0.508)
		(layer "In11.Cu")
		(net "GND")
	)
	(segment
		(start 4.629912 -45.310044)
		(end 6.063996 -46.744128)
		(width 0.508)
		(layer "In11.Cu")
		(net "GND")
	)
	(segment
		(start 488.683554 -129.845308)
		(end 490.081062 -129.845308)
		(width 0.635)
		(layer "In12.Cu")
		(net "GND")
	)
	(segment
		(start 428.55007 -136.344914)
		(end 429.122078 -136.916922)
		(width 0.254)
		(layer "In12.Cu")
		(net "GND")
	)
	(segment
		(start 490.081062 -135.265414)
		(end 490.081062 -136.002522)
		(width 0.508)
		(layer "In12.Cu")
		(net "GND")
	)
	(segment
		(start 444.380112 -136.344914)
		(end 444.916306 -136.881108)
		(width 0.254)
		(layer "In12.Cu")
		(net "GND")
	)
	(segment
		(start 495.3 -56.079898)
		(end 496.22202 -56.886348)
		(width 0.508)
		(layer "In12.Cu")
		(net "GND")
	)
	(segment
		(start 496.000024 -153.849832)
		(end 496.670838 -154.520646)
		(width 0.254)
		(layer "In12.Cu")
		(net "GND")
	)
	(segment
		(start 479.381058 -129.1082)
		(end 479.381058 -129.845308)
		(width 0.635)
		(layer "In12.Cu")
		(net "GND")
	)
	(segment
		(start 470.2175 -146.493992)
		(end 470.816432 -147.092924)
		(width 0.254)
		(layer "In12.Cu")
		(net "GND")
	)
	(segment
		(start 372.184168 -78.699868)
		(end 371.703346 -78.699868)
		(width 0.1143)
		(layer "In12.Cu")
		(net "GND")
	)
	(segment
		(start 499.736872 -51.302158)
		(end 500.55018 -52.579778)
		(width 0.508)
		(layer "In12.Cu")
		(net "GND")
	)
	(segment
		(start 494.37798 -58.886344)
		(end 495.3 -58.079894)
		(width 0.508)
		(layer "In12.Cu")
		(net "GND")
	)
	(segment
		(start 479.381058 -129.845308)
		(end 479.381058 -130.582416)
		(width 0.635)
		(layer "In12.Cu")
		(net "GND")
	)
	(segment
		(start 27.241246 -26.67)
		(end 27.768296 -26.14295)
		(width 0.254)
		(layer "In12.Cu")
		(net "GND")
	)
	(segment
		(start -0.500126 -45.310044)
		(end 0.933958 -43.87596)
		(width 0.508)
		(layer "In12.Cu")
		(net "GND")
	)
	(segment
		(start 488.250992 -131.655312)
		(end 488.832144 -132.236464)
		(width 0.254)
		(layer "In12.Cu")
		(net "GND")
	)
	(segment
		(start 480.92614 -4.856226)
		(end 481.57003 -5.500116)
		(width 0.254)
		(layer "In12.Cu")
		(net "GND")
	)
	(segment
		(start 494.651538 -51.623214)
		(end 495.3 -52.804822)
		(width 0.508)
		(layer "In12.Cu")
		(net "GND")
	)
	(segment
		(start 9.81583 -46.744128)
		(end 11.249914 -45.310044)
		(width 0.508)
		(layer "In12.Cu")
		(net "GND")
	)
	(segment
		(start 490.081062 -129.1082)
		(end 490.081062 -129.845308)
		(width 0.635)
		(layer "In12.Cu")
		(net "GND")
	)
	(segment
		(start 27.241246 -26.67)
		(end 27.768296 -27.19705)
		(width 0.254)
		(layer "In12.Cu")
		(net "GND")
	)
	(segment
		(start 470.2175 -142.494)
		(end 470.816432 -141.895068)
		(width 0.254)
		(layer "In12.Cu")
		(net "GND")
	)
	(segment
		(start 479.620072 -153.650442)
		(end 480.335844 -152.93467)
		(width 0.254)
		(layer "In12.Cu")
		(net "GND")
	)
	(segment
		(start 418.421058 0.08001)
		(end 419.082982 0.741934)
		(width 0.508)
		(layer "In12.Cu")
		(net "GND")
	)
	(segment
		(start 480.335844 -152.93467)
		(end 481.051616 -153.650442)
		(width 0.254)
		(layer "In12.Cu")
		(net "GND")
	)
	(segment
		(start 384.535172 -6.089904)
		(end 385.179062 -6.733794)
		(width 0.508)
		(layer "In12.Cu")
		(net "GND")
	)
	(segment
		(start 462.19491 -157.140402)
		(end 462.892648 -156.442664)
		(width 0.254)
		(layer "In12.Cu")
		(net "GND")
	)
	(segment
		(start 397.51 3.81)
		(end 398.261586 3.058414)
		(width 0.254)
		(layer "In12.Cu")
		(net "GND")
	)
	(segment
		(start 499.736872 -60.302394)
		(end 500.55018 -61.580014)
		(width 0.508)
		(layer "In12.Cu")
		(net "GND")
	)
	(segment
		(start 494.37798 -55.273448)
		(end 495.3 -56.079898)
		(width 0.508)
		(layer "In12.Cu")
		(net "GND")
	)
	(segment
		(start 11.249914 -45.310044)
		(end 12.683998 -43.87596)
		(width 0.508)
		(layer "In12.Cu")
		(net "GND")
	)
	(segment
		(start 444.380112 -136.344914)
		(end 444.916306 -135.80872)
		(width 0.254)
		(layer "In12.Cu")
		(net "GND")
	)
	(segment
		(start 371.533166 -78.876398)
		(end 371.535198 -78.87843)
		(width 0.1143)
		(layer "In12.Cu")
		(net "GND")
	)
	(segment
		(start 480.335844 -152.93467)
		(end 481.051616 -152.218898)
		(width 0.254)
		(layer "In12.Cu")
		(net "GND")
	)
	(segment
		(start 4.629912 -45.310044)
		(end 6.063996 -43.87596)
		(width 0.508)
		(layer "In12.Cu")
		(net "GND")
	)
	(segment
		(start 495.32921 -154.520646)
		(end 496.000024 -153.849832)
		(width 0.254)
		(layer "In12.Cu")
		(net "GND")
	)
	(segment
		(start 478.33915 -129.845308)
		(end 479.381058 -129.845308)
		(width 0.635)
		(layer "In12.Cu")
		(net "GND")
	)
	(segment
		(start 479.381058 -135.265414)
		(end 479.381058 -136.002522)
		(width 0.635)
		(layer "In12.Cu")
		(net "GND")
	)
	(segment
		(start 499.736872 -53.857398)
		(end 500.55018 -52.579778)
		(width 0.508)
		(layer "In12.Cu")
		(net "GND")
	)
	(segment
		(start 443.843918 -136.881108)
		(end 444.380112 -136.344914)
		(width 0.254)
		(layer "In12.Cu")
		(net "GND")
	)
	(segment
		(start 0 0)
		(end 2.430526 -2.430526)
		(width 0.762)
		(layer "In12.Cu")
		(net "GND")
	)
	(segment
		(start 498.32006 -53.604922)
		(end 498.820186 -54.105048)
		(width 0.508)
		(layer "In12.Cu")
		(net "GND")
	)
	(segment
		(start 481.965 -147.193)
		(end 482.626924 -146.531076)
		(width 0.254)
		(layer "In12.Cu")
		(net "GND")
	)
	(segment
		(start 469.618568 -147.092924)
		(end 470.2175 -146.493992)
		(width 0.254)
		(layer "In12.Cu")
		(net "GND")
	)
	(segment
		(start 3.195828 -46.744128)
		(end 4.629912 -45.310044)
		(width 0.508)
		(layer "In12.Cu")
		(net "GND")
	)
	(segment
		(start 469.618568 -145.89506)
		(end 470.2175 -146.493992)
		(width 0.254)
		(layer "In12.Cu")
		(net "GND")
	)
	(segment
		(start 495.3 -56.079898)
		(end 496.22202 -55.273448)
		(width 0.508)
		(layer "In12.Cu")
		(net "GND")
	)
	(segment
		(start 371.535198 -78.87843)
		(end 371.535198 -79.284068)
		(width 0.1143)
		(layer "In12.Cu")
		(net "GND")
	)
	(segment
		(start 435.598062 -136.916922)
		(end 436.17007 -136.344914)
		(width 0.254)
		(layer "In12.Cu")
		(net "GND")
	)
	(segment
		(start 9.81583 -43.87596)
		(end 11.249914 -45.310044)
		(width 0.508)
		(layer "In12.Cu")
		(net "GND")
	)
	(segment
		(start 490.081062 -129.845308)
		(end 490.081062 -130.582416)
		(width 0.635)
		(layer "In12.Cu")
		(net "GND")
	)
	(segment
		(start 479.381058 -134.528306)
		(end 479.381058 -135.265414)
		(width 0.635)
		(layer "In12.Cu")
		(net "GND")
	)
	(segment
		(start 29.615638 -36.105592)
		(end 30.47492 -36.964874)
		(width 0.508)
		(layer "In12.Cu")
		(net "GND")
	)
	(segment
		(start 479.381058 -129.845308)
		(end 480.422966 -129.845308)
		(width 0.635)
		(layer "In12.Cu")
		(net "GND")
	)
	(segment
		(start 396.758414 3.058414)
		(end 397.51 3.81)
		(width 0.254)
		(layer "In12.Cu")
		(net "GND")
	)
	(segment
		(start 487.66984 -131.07416)
		(end 488.250992 -131.655312)
		(width 0.254)
		(layer "In12.Cu")
		(net "GND")
	)
	(segment
		(start 488.250992 -131.655312)
		(end 488.832144 -131.07416)
		(width 0.254)
		(layer "In12.Cu")
		(net "GND")
	)
	(segment
		(start 418.421058 0.08001)
		(end 419.082982 -0.581914)
		(width 0.508)
		(layer "In12.Cu")
		(net "GND")
	)
	(segment
		(start 417.759134 -0.581914)
		(end 418.421058 0.08001)
		(width 0.508)
		(layer "In12.Cu")
		(net "GND")
	)
	(segment
		(start 498.32006 -60.55487)
		(end 498.820186 -61.054996)
		(width 0.508)
		(layer "In12.Cu")
		(net "GND")
	)
	(segment
		(start 436.17007 -136.344914)
		(end 436.742078 -136.916922)
		(width 0.254)
		(layer "In12.Cu")
		(net "GND")
	)
	(segment
		(start 417.759134 0.741934)
		(end 418.421058 0.08001)
		(width 0.508)
		(layer "In12.Cu")
		(net "GND")
	)
	(segment
		(start 431.788062 -136.916922)
		(end 432.36007 -136.344914)
		(width 0.254)
		(layer "In12.Cu")
		(net "GND")
	)
	(segment
		(start 495.3 -59.652154)
		(end 495.3 -61.35497)
		(width 0.508)
		(layer "In12.Cu")
		(net "GND")
	)
	(segment
		(start 494.651538 -54.507638)
		(end 495.3 -52.804822)
		(width 0.508)
		(layer "In12.Cu")
		(net "GND")
	)
	(segment
		(start 435.598062 -135.772906)
		(end 436.17007 -136.344914)
		(width 0.254)
		(layer "In12.Cu")
		(net "GND")
	)
	(segment
		(start 409.719526 -76.883768)
		(end 412.357062 -74.246232)
		(width 0.762)
		(layer "In12.Cu")
		(net "GND")
	)
	(segment
		(start 445.38011 -136.344914)
		(end 445.916304 -136.881108)
		(width 0.254)
		(layer "In12.Cu")
		(net "GND")
	)
	(segment
		(start 384.535172 -6.089904)
		(end 385.179062 -5.446014)
		(width 0.508)
		(layer "In12.Cu")
		(net "GND")
	)
	(segment
		(start 482.092 -149.709886)
		(end 482.753924 -149.047962)
		(width 0.254)
		(layer "In12.Cu")
		(net "GND")
	)
	(segment
		(start 470.2175 -146.493992)
		(end 470.816432 -145.89506)
		(width 0.254)
		(layer "In12.Cu")
		(net "GND")
	)
	(segment
		(start 432.36007 -136.344914)
		(end 432.932078 -135.772906)
		(width 0.254)
		(layer "In12.Cu")
		(net "GND")
	)
	(segment
		(start 352.991166 -6.733794)
		(end 353.635056 -6.089904)
		(width 0.508)
		(layer "In12.Cu")
		(net "GND")
	)
	(segment
		(start 500.55018 -60.302394)
		(end 500.55018 -61.580014)
		(width 0.508)
		(layer "In12.Cu")
		(net "GND")
	)
	(segment
		(start 461.497172 -156.442664)
		(end 462.19491 -157.140402)
		(width 0.254)
		(layer "In12.Cu")
		(net "GND")
	)
	(segment
		(start 436.17007 -136.344914)
		(end 436.742078 -135.772906)
		(width 0.254)
		(layer "In12.Cu")
		(net "GND")
	)
	(segment
		(start 409.719526 -76.883768)
		(end 412.357062 -79.521304)
		(width 0.762)
		(layer "In12.Cu")
		(net "GND")
	)
	(segment
		(start -2.430526 2.430526)
		(end 0 0)
		(width 0.762)
		(layer "In12.Cu")
		(net "GND")
	)
	(segment
		(start 481.1014 -125.222)
		(end 481.817172 -124.506228)
		(width 0.254)
		(layer "In12.Cu")
		(net "GND")
	)
	(segment
		(start 383.891282 -5.446014)
		(end 384.535172 -6.089904)
		(width 0.508)
		(layer "In12.Cu")
		(net "GND")
	)
	(segment
		(start 372.171976 -77.89418)
		(end 371.724936 -77.89418)
		(width 0.1143)
		(layer "In12.Cu")
		(net "GND")
	)
	(segment
		(start 353.635056 -6.089904)
		(end 354.278946 -6.733794)
		(width 0.508)
		(layer "In12.Cu")
		(net "GND")
	)
	(segment
		(start 490.081062 -134.528306)
		(end 490.081062 -135.265414)
		(width 0.508)
		(layer "In12.Cu")
		(net "GND")
	)
	(segment
		(start -1.93421 -43.87596)
		(end -0.500126 -45.310044)
		(width 0.508)
		(layer "In12.Cu")
		(net "GND")
	)
	(segment
		(start 3.080766 -111.119158)
		(end 3.940048 -110.259876)
		(width 0.508)
		(layer "In12.Cu")
		(net "GND")
	)
	(segment
		(start 470.2175 -142.494)
		(end 470.816432 -143.092932)
		(width 0.254)
		(layer "In12.Cu")
		(net "GND")
	)
	(segment
		(start 479.381058 -135.265414)
		(end 480.778566 -135.265414)
		(width 0.635)
		(layer "In12.Cu")
		(net "GND")
	)
	(segment
		(start 497.819934 -53.104796)
		(end 498.32006 -53.604922)
		(width 0.508)
		(layer "In12.Cu")
		(net "GND")
	)
	(segment
		(start 480.92614 -6.144006)
		(end 481.57003 -5.500116)
		(width 0.254)
		(layer "In12.Cu")
		(net "GND")
	)
	(segment
		(start -2.430526 -2.430526)
		(end 0 0)
		(width 0.762)
		(layer "In12.Cu")
		(net "GND")
	)
	(segment
		(start 490.081062 -135.265414)
		(end 491.12297 -135.265414)
		(width 0.508)
		(layer "In12.Cu")
		(net "GND")
	)
	(segment
		(start 427.978062 -136.916922)
		(end 428.55007 -136.344914)
		(width 0.254)
		(layer "In12.Cu")
		(net "GND")
	)
	(segment
		(start 396.758414 4.561586)
		(end 397.51 3.81)
		(width 0.254)
		(layer "In12.Cu")
		(net "GND")
	)
	(segment
		(start 26.714196 -27.19705)
		(end 27.241246 -26.67)
		(width 0.254)
		(layer "In12.Cu")
		(net "GND")
	)
	(segment
		(start 3.940048 -110.259876)
		(end 4.79933 -109.400594)
		(width 0.508)
		(layer "In12.Cu")
		(net "GND")
	)
	(segment
		(start 383.891282 -6.733794)
		(end 384.535172 -6.089904)
		(width 0.508)
		(layer "In12.Cu")
		(net "GND")
	)
	(segment
		(start 495.32921 -153.179018)
		(end 496.000024 -153.849832)
		(width 0.254)
		(layer "In12.Cu")
		(net "GND")
	)
	(segment
		(start 444.843916 -135.80872)
		(end 445.38011 -136.344914)
		(width 0.254)
		(layer "In12.Cu")
		(net "GND")
	)
	(segment
		(start 490.081062 -129.845308)
		(end 491.47857 -129.845308)
		(width 0.635)
		(layer "In12.Cu")
		(net "GND")
	)
	(segment
		(start 497.819934 -61.054996)
		(end 498.32006 -60.55487)
		(width 0.508)
		(layer "In12.Cu")
		(net "GND")
	)
	(segment
		(start 498.32006 -53.604922)
		(end 498.820186 -53.104796)
		(width 0.508)
		(layer "In12.Cu")
		(net "GND")
	)
	(segment
		(start 4.629912 -45.310044)
		(end 6.063996 -46.744128)
		(width 0.508)
		(layer "In12.Cu")
		(net "GND")
	)
	(segment
		(start 3.195828 -43.87596)
		(end 4.629912 -45.310044)
		(width 0.508)
		(layer "In12.Cu")
		(net "GND")
	)
	(segment
		(start 443.843918 -135.80872)
		(end 444.380112 -136.344914)
		(width 0.254)
		(layer "In12.Cu")
		(net "GND")
	)
	(segment
		(start 3.940048 -110.259876)
		(end 4.79933 -111.119158)
		(width 0.508)
		(layer "In12.Cu")
		(net "GND")
	)
	(segment
		(start 498.32006 -60.55487)
		(end 498.820186 -60.054744)
		(width 0.508)
		(layer "In12.Cu")
		(net "GND")
	)
	(segment
		(start 353.635056 -6.089904)
		(end 354.278946 -5.446014)
		(width 0.508)
		(layer "In12.Cu")
		(net "GND")
	)
	(segment
		(start 352.991166 -5.446014)
		(end 353.635056 -6.089904)
		(width 0.508)
		(layer "In12.Cu")
		(net "GND")
	)
	(segment
		(start 3.080766 -109.400594)
		(end 3.940048 -110.259876)
		(width 0.508)
		(layer "In12.Cu")
		(net "GND")
	)
	(segment
		(start 495.3 -58.079894)
		(end 496.22202 -58.886344)
		(width 0.508)
		(layer "In12.Cu")
		(net "GND")
	)
	(segment
		(start 370.749322 -77.219556)
		(end 370.749322 -77.718412)
		(width 0.1143)
		(layer "In12.Cu")
		(net "GND")
	)
	(segment
		(start 487.66984 -132.236464)
		(end 488.250992 -131.655312)
		(width 0.254)
		(layer "In12.Cu")
		(net "GND")
	)
	(segment
		(start 469.618568 -143.092932)
		(end 470.2175 -142.494)
		(width 0.254)
		(layer "In12.Cu")
		(net "GND")
	)
	(segment
		(start 30.47492 -36.964874)
		(end 31.334202 -36.105592)
		(width 0.508)
		(layer "In12.Cu")
		(net "GND")
	)
	(segment
		(start 370.1161 -77.908404)
		(end 370.56314 -77.908404)
		(width 0.1143)
		(layer "In12.Cu")
		(net "GND")
	)
	(segment
		(start 494.651538 -59.652154)
		(end 495.3 -61.35497)
		(width 0.508)
		(layer "In12.Cu")
		(net "GND")
	)
	(segment
		(start 407.08199 -79.521304)
		(end 409.719526 -76.883768)
		(width 0.762)
		(layer "In12.Cu")
		(net "GND")
	)
	(segment
		(start 11.249914 -45.310044)
		(end 12.683998 -46.744128)
		(width 0.508)
		(layer "In12.Cu")
		(net "GND")
	)
	(segment
		(start 431.788062 -135.772906)
		(end 432.36007 -136.344914)
		(width 0.254)
		(layer "In12.Cu")
		(net "GND")
	)
	(segment
		(start 397.51 3.81)
		(end 398.261586 4.561586)
		(width 0.254)
		(layer "In12.Cu")
		(net "GND")
	)
	(segment
		(start 407.08199 -74.246232)
		(end 409.719526 -76.883768)
		(width 0.762)
		(layer "In12.Cu")
		(net "GND")
	)
	(segment
		(start 29.615638 -37.824156)
		(end 30.47492 -36.964874)
		(width 0.508)
		(layer "In12.Cu")
		(net "GND")
	)
	(segment
		(start 489.039154 -135.265414)
		(end 490.081062 -135.265414)
		(width 0.508)
		(layer "In12.Cu")
		(net "GND")
	)
	(segment
		(start 462.19491 -157.140402)
		(end 462.892648 -157.83814)
		(width 0.254)
		(layer "In12.Cu")
		(net "GND")
	)
	(segment
		(start 495.3 -58.079894)
		(end 496.22202 -57.273444)
		(width 0.508)
		(layer "In12.Cu")
		(net "GND")
	)
	(segment
		(start 479.620072 -152.218898)
		(end 480.335844 -152.93467)
		(width 0.254)
		(layer "In12.Cu")
		(net "GND")
	)
	(segment
		(start 30.47492 -36.964874)
		(end 31.334202 -37.824156)
		(width 0.508)
		(layer "In12.Cu")
		(net "GND")
	)
	(segment
		(start 469.618568 -141.895068)
		(end 470.2175 -142.494)
		(width 0.254)
		(layer "In12.Cu")
		(net "GND")
	)
	(segment
		(start 444.843916 -136.881108)
		(end 445.38011 -136.344914)
		(width 0.254)
		(layer "In12.Cu")
		(net "GND")
	)
	(segment
		(start 480.385628 -124.506228)
		(end 481.1014 -125.222)
		(width 0.254)
		(layer "In12.Cu")
		(net "GND")
	)
	(segment
		(start 480.385628 -125.937772)
		(end 481.1014 -125.222)
		(width 0.254)
		(layer "In12.Cu")
		(net "GND")
	)
	(segment
		(start 432.36007 -136.344914)
		(end 432.932078 -136.916922)
		(width 0.254)
		(layer "In12.Cu")
		(net "GND")
	)
	(segment
		(start 461.497172 -157.83814)
		(end 462.19491 -157.140402)
		(width 0.254)
		(layer "In12.Cu")
		(net "GND")
	)
	(segment
		(start 428.55007 -136.344914)
		(end 429.122078 -135.772906)
		(width 0.254)
		(layer "In12.Cu")
		(net "GND")
	)
	(segment
		(start 481.1014 -125.222)
		(end 481.817172 -125.937772)
		(width 0.254)
		(layer "In12.Cu")
		(net "GND")
	)
	(segment
		(start 477.98355 -135.265414)
		(end 479.381058 -135.265414)
		(width 0.635)
		(layer "In12.Cu")
		(net "GND")
	)
	(segment
		(start -0.500126 -45.310044)
		(end 0.933958 -46.744128)
		(width 0.508)
		(layer "In12.Cu")
		(net "GND")
	)
	(segment
		(start 445.38011 -136.344914)
		(end 445.916304 -135.80872)
		(width 0.254)
		(layer "In12.Cu")
		(net "GND")
	)
	(segment
		(start -1.93421 -46.744128)
		(end -0.500126 -45.310044)
		(width 0.508)
		(layer "In12.Cu")
		(net "GND")
	)
	(segment
		(start 496.000024 -153.849832)
		(end 496.670838 -153.179018)
		(width 0.254)
		(layer "In12.Cu")
		(net "GND")
	)
	(segment
		(start 0 0)
		(end 2.430526 2.430526)
		(width 0.762)
		(layer "In12.Cu")
		(net "GND")
	)
	(segment
		(start 26.714196 -26.14295)
		(end 27.241246 -26.67)
		(width 0.254)
		(layer "In12.Cu")
		(net "GND")
	)
	(segment
		(start 427.978062 -135.772906)
		(end 428.55007 -136.344914)
		(width 0.254)
		(layer "In12.Cu")
		(net "GND")
	)
	(segment
		(start 494.37798 -56.886348)
		(end 495.3 -56.079898)
		(width 0.508)
		(layer "In12.Cu")
		(net "GND")
	)
	(zone
		(layer "F.Cu")
		(hatch none 0.5)
		(connect_pads
			(clearance 0)
		)
		(min_thickness 0.25)
		(keepout
			(tracks not_allowed)
			(vias allowed)
			(pads allowed)
			(copperpour not_allowed)
			(footprints allowed)
		)
		(placement
			(enabled no)
			(sheetname "")
		)
		(fill
			(thermal_gap 0.5)
			(thermal_bridge_width 0.5)
			(island_removal_mode 0)
		)
		(polygon
			(pts
				(xy 436.104538 -3.22326) (xy 436.104538 -2.937764) (xy 436.272432 -2.76987)
				(arc
					(start 436.444136 -2.76987)
					(mid 436.968053 -2.83972)
					(end 436.444136 -2.90957)
				)
				(xy 436.330344 -2.90957) (xy 436.244238 -2.995676) (xy 436.244238 -3.22326)
				(arc
					(start 436.701184 -3.22326)
					(mid 437.084724 -2.839847)
					(end 436.701438 -2.45618)
				)
				(arc
					(start 435.431438 -2.45618)
					(mid 435.047898 -2.83972)
					(end 435.431438 -3.22326)
				)
				(xy 435.863238 -3.22326) (xy 435.863238 -2.982976) (xy 435.789832 -2.90957)
				(arc
					(start 435.68874 -2.90957)
					(mid 435.164823 -2.83972)
					(end 435.68874 -2.76987)
				)
				(xy 435.847744 -2.76987) (xy 436.002938 -2.925064) (xy 436.002938 -3.22326)
			)
		)
	)
	(zone
		(layer "F.Cu")
		(hatch none 0.5)
		(connect_pads
			(clearance 0)
		)
		(min_thickness 0.25)
		(keepout
			(tracks allowed)
			(vias allowed)
			(pads allowed)
			(copperpour allowed)
			(footprints allowed)
		)
		(placement
			(enabled no)
			(sheetname "")
		)
		(fill
			(thermal_gap 0.5)
			(thermal_bridge_width 0.5)
			(island_removal_mode 0)
		)
		(polygon
			(pts
				(xy 8.183626 -3.406394) (xy 8.183626 -2.009394) (xy 11.612626 -2.009394) (xy 11.612626 -3.406394)
			)
		)
	)
	(zone
		(layer "F.Cu")
		(hatch none 0.5)
		(connect_pads
			(clearance 0)
		)
		(min_thickness 0.25)
		(keepout
			(tracks allowed)
			(vias allowed)
			(pads allowed)
			(copperpour allowed)
			(footprints allowed)
		)
		(placement
			(enabled no)
			(sheetname "")
		)
		(fill
			(thermal_gap 0.5)
			(thermal_bridge_width 0.5)
			(island_removal_mode 0)
		)
		(polygon
			(pts
				(xy 106.017568 -42.037) (xy 105.357168 -41.273476) (xy 105.357168 -40.1574) (xy 105.382568 -40.132)
				(xy 105.81894 -40.132) (xy 109.370368 -40.132) (xy 109.548168 -40.3098) (xy 109.662468 -40.3098)
				(xy 111.986568 -40.3098) (xy 112.164368 -40.4876) (xy 112.164368 -40.9448) (xy 111.351568 -41.7576)
				(xy 111.351568 -49.657) (xy 106.017568 -49.657)
			)
		)
	)
	(zone
		(layer "F.Cu")
		(hatch none 0.5)
		(connect_pads
			(clearance 0)
		)
		(min_thickness 0.25)
		(keepout
			(tracks not_allowed)
			(vias allowed)
			(pads allowed)
			(copperpour not_allowed)
			(footprints allowed)
		)
		(placement
			(enabled no)
			(sheetname "")
		)
		(fill
			(thermal_gap 0.5)
			(thermal_bridge_width 0.5)
			(island_removal_mode 0)
		)
		(polygon
			(pts
				(arc
					(start 56.999886 -78.449932)
					(mid 55.099966 -76.550012)
					(end 56.999886 -74.650092)
				)
				(arc
					(start 56.999886 -74.650092)
					(mid 58.899806 -76.550012)
					(end 56.999886 -78.449932)
				)
			)
		)
	)
	(zone
		(layer "F.Cu")
		(hatch none 0.5)
		(connect_pads
			(clearance 0)
		)
		(min_thickness 0.25)
		(keepout
			(tracks not_allowed)
			(vias allowed)
			(pads allowed)
			(copperpour not_allowed)
			(footprints allowed)
		)
		(placement
			(enabled no)
			(sheetname "")
		)
		(fill
			(thermal_gap 0.5)
			(thermal_bridge_width 0.5)
			(island_removal_mode 0)
		)
		(polygon
			(pts
				(xy 403.465792 -10.295636) (xy 403.973792 -10.295636) (xy 403.973792 -10.651236) (xy 403.465792 -10.651236)
			)
		)
	)
	(zone
		(net "P12V_STBY")
		(layer "F.Cu")
		(hatch none 0.5)
		(connect_pads
			(clearance 0.5)
		)
		(min_thickness 0.25)
		(fill yes
			(thermal_gap 0.5)
			(thermal_bridge_width 0.5)
			(island_removal_mode 0)
		)
		(polygon
			(pts
				(xy 177.419 -97.917) (xy 177.419 -98.1964) (xy 177.419 -100.6094) (xy 177.419 -102.489) (xy 177.419 -103.378)
				(xy 177.673 -103.632) (xy 183.896 -103.632) (xy 184.277 -103.632) (xy 184.531 -103.378) (xy 184.531 -98.552)
				(xy 184.531 -98.171) (xy 183.769 -97.409) (xy 183.60009 -97.24009) (xy 177.523902 -97.24009) (xy 177.419 -97.344992)
				(xy 177.419 -97.536)
			)
		)
	)
	(zone
		(net "GND")
		(layer "F.Cu")
		(hatch none 0.5)
		(connect_pads
			(clearance 0.5)
		)
		(min_thickness 0.25)
		(fill yes
			(thermal_gap 0.5)
			(thermal_bridge_width 0.5)
			(island_removal_mode 0)
		)
		(polygon
			(pts
				(xy 471.2335 -26.9367) (xy 472.0971 -26.9367) (xy 472.567 -27.4066) (xy 473.6465 -27.4066) (xy 473.6719 -27.432)
				(xy 473.6719 -28.702) (xy 473.6592 -28.7147) (xy 472.1987 -28.7147) (xy 471.9955 -28.5115) (xy 471.9701 -28.4861)
				(xy 471.3224 -28.4861) (xy 471.17 -28.3337) (xy 471.17 -27.0002)
			)
		)
	)
	(zone
		(layer "F.Cu")
		(hatch none 0.5)
		(connect_pads
			(clearance 0)
		)
		(min_thickness 0.25)
		(keepout
			(tracks allowed)
			(vias allowed)
			(pads allowed)
			(copperpour allowed)
			(footprints allowed)
		)
		(placement
			(enabled no)
			(sheetname "")
		)
		(fill
			(thermal_gap 0.5)
			(thermal_bridge_width 0.5)
			(island_removal_mode 0)
		)
		(polygon
			(pts
				(xy 192.151 -4.318) (xy 192.151 -3.302) (xy 193.421 -3.302) (xy 193.421 -4.318)
			)
		)
	)
	(zone
		(layer "F.Cu")
		(hatch none 0.5)
		(connect_pads
			(clearance 0)
		)
		(min_thickness 0.25)
		(keepout
			(tracks allowed)
			(vias allowed)
			(pads allowed)
			(copperpour allowed)
			(footprints not_allowed)
		)
		(placement
			(enabled no)
			(sheetname "")
		)
		(fill
			(thermal_gap 0.5)
			(thermal_bridge_width 0.5)
			(island_removal_mode 0)
		)
		(polygon
			(pts
				(xy 342.52535 -130.16611) (xy 337.725512 -130.16611) (xy 337.725512 -159.100012) (xy 342.52535 -159.100012)
			)
		)
	)
	(zone
		(layer "F.Cu")
		(hatch none 0.5)
		(connect_pads
			(clearance 0)
		)
		(min_thickness 0.25)
		(keepout
			(tracks allowed)
			(vias allowed)
			(pads allowed)
			(copperpour allowed)
			(footprints allowed)
		)
		(placement
			(enabled no)
			(sheetname "")
		)
		(fill
			(thermal_gap 0.5)
			(thermal_bridge_width 0.5)
			(island_removal_mode 0)
		)
		(polygon
			(pts
				(xy 29.083 -66.548) (xy 29.083 -62.992) (xy 31.242 -62.992) (xy 31.242 -66.548)
			)
		)
	)
	(zone
		(net "VR_FET_SW_P12V_STBY_PVCCIN_CPU0")
		(layer "F.Cu")
		(hatch none 0.5)
		(connect_pads
			(clearance 0.5)
		)
		(min_thickness 0.25)
		(fill yes
			(thermal_gap 0.5)
			(thermal_bridge_width 0.5)
			(island_removal_mode 0)
		)
		(polygon
			(pts
				(xy 196.487034 -75.188064) (xy 196.614034 -75.061064) (xy 196.648832 -75.026266) (xy 196.648832 -75.014582)
				(xy 196.648832 -73.67905) (xy 196.650102 -73.67778) (xy 198.627238 -73.67778) (xy 198.631048 -73.68159)
				(xy 198.631048 -76.03998) (xy 198.561452 -76.109576) (xy 198.561452 -76.112878) (xy 198.297038 -76.377292)
				(xy 198.297038 -76.9493) (xy 198.284846 -76.961492) (xy 197.717156 -76.961492) (xy 197.582028 -76.826364)
				(xy 197.541896 -76.826364) (xy 195.920868 -76.826364) (xy 195.78574 -76.961492) (xy 195.0847 -76.961492)
				(xy 195.07708 -76.961492) (xy 194.498214 -76.382626) (xy 194.498214 -75.576684) (xy 194.555364 -75.519534)
				(xy 195.162678 -75.519534) (xy 195.277232 -75.40498) (xy 195.353432 -75.32878) (xy 195.355718 -75.32878)
				(xy 195.496434 -75.188064)
			)
		)
	)
	(zone
		(layer "F.Cu")
		(hatch none 0.5)
		(connect_pads
			(clearance 0)
		)
		(min_thickness 0.25)
		(keepout
			(tracks not_allowed)
			(vias allowed)
			(pads allowed)
			(copperpour not_allowed)
			(footprints allowed)
		)
		(placement
			(enabled no)
			(sheetname "")
		)
		(fill
			(thermal_gap 0.5)
			(thermal_bridge_width 0.5)
			(island_removal_mode 0)
		)
		(polygon
			(pts
				(arc
					(start 455.719688 -44.7675)
					(mid 456.243605 -44.83735)
					(end 455.719688 -44.9072)
				)
				(xy 455.596752 -44.9072) (xy 455.50455 -44.999402) (xy 455.50455 -45.22089)
				(arc
					(start 455.97699 -45.22089)
					(mid 456.36053 -44.83735)
					(end 455.97699 -44.45381)
				)
				(arc
					(start 454.707244 -44.45381)
					(mid 454.32345 -44.837223)
					(end 454.70699 -45.22089)
				)
				(xy 455.12355 -45.22089) (xy 455.12355 -45.019722) (xy 455.011028 -44.9072)
				(arc
					(start 454.964292 -44.9072)
					(mid 454.440375 -44.83735)
					(end 454.964292 -44.7675)
				)
				(xy 455.06894 -44.7675) (xy 455.26325 -44.96181) (xy 455.26325 -45.22089) (xy 455.36485 -45.22089)
				(xy 455.36485 -44.94149) (xy 455.53884 -44.7675)
			)
		)
	)
	(zone
		(net "GND")
		(layer "F.Cu")
		(hatch none 0.5)
		(connect_pads
			(clearance 0.5)
		)
		(min_thickness 0.25)
		(fill yes
			(thermal_gap 0.5)
			(thermal_bridge_width 0.5)
			(island_removal_mode 0)
		)
		(polygon
			(pts
				(xy 159.886142 -59.408822) (xy 159.784796 -59.510168) (xy 159.784796 -63.271908) (xy 159.872172 -63.359284)
				(xy 160.95345 -63.359284) (xy 161.100008 -63.212726) (xy 161.100008 -62.567566) (xy 161.250376 -62.417198)
				(xy 162.178492 -62.417198) (xy 162.193224 -62.402466) (xy 162.193224 -60.27674) (xy 162.183064 -60.26658)
				(xy 161.348928 -60.26658) (xy 160.928812 -59.846464) (xy 160.928812 -59.496198) (xy 160.841436 -59.408822)
			)
		)
		(polygon
			(pts
				(xy 161.5186 -61.4299) (xy 161.3154 -61.4299) (xy 161.3154 -61.6331) (xy 161.5186 -61.6331)
			)
		)
		(polygon
			(pts
				(xy 161.5186 -61.0489) (xy 161.3154 -61.0489) (xy 161.3154 -61.2521) (xy 161.5186 -61.2521)
			)
		)
	)
	(zone
		(layer "F.Cu")
		(hatch none 0.5)
		(connect_pads
			(clearance 0)
		)
		(min_thickness 0.25)
		(keepout
			(tracks allowed)
			(vias allowed)
			(pads allowed)
			(copperpour allowed)
			(footprints not_allowed)
		)
		(placement
			(enabled no)
			(sheetname "")
		)
		(fill
			(thermal_gap 0.5)
			(thermal_bridge_width 0.5)
			(island_removal_mode 0)
		)
		(polygon
			(pts
				(xy 9.624568 -159.100012) (xy 14.524736 -159.100012) (xy 14.524736 -130.16992) (xy 9.624568 -130.16611)
				(xy 9.624568 -134.965948) (xy 7.224522 -134.965948) (xy 7.224522 -150.599902) (xy 9.624568 -150.599902)
			)
		)
	)
	(zone
		(layer "F.Cu")
		(hatch none 0.5)
		(connect_pads
			(clearance 0)
		)
		(min_thickness 0.25)
		(keepout
			(tracks allowed)
			(vias allowed)
			(pads allowed)
			(copperpour allowed)
			(footprints allowed)
		)
		(placement
			(enabled no)
			(sheetname "")
		)
		(fill
			(thermal_gap 0.5)
			(thermal_bridge_width 0.5)
			(island_removal_mode 0)
		)
		(polygon
			(pts
				(xy 197.5358 -99.8728) (xy 197.5358 -95.504) (xy 199.9488 -95.504) (xy 199.9488 -99.8728)
			)
		)
	)
	(zone
		(layer "F.Cu")
		(hatch none 0.5)
		(connect_pads
			(clearance 0)
		)
		(min_thickness 0.25)
		(keepout
			(tracks allowed)
			(vias allowed)
			(pads allowed)
			(copperpour allowed)
			(footprints allowed)
		)
		(placement
			(enabled no)
			(sheetname "")
		)
		(fill
			(thermal_gap 0.5)
			(thermal_bridge_width 0.5)
			(island_removal_mode 0)
		)
		(polygon
			(pts
				(xy 466.531706 -23.607776) (xy 467.236302 -23.607776) (xy 467.309708 -23.53437) (xy 467.309708 -22.59711)
				(xy 467.199726 -22.487128) (xy 466.49894 -22.487128) (xy 466.494876 -22.483064) (xy 466.419438 -22.483064)
				(xy 466.348318 -22.554184) (xy 466.348318 -23.566374) (xy 466.38972 -23.607776)
			)
		)
	)
	(zone
		(layer "F.Cu")
		(hatch none 0.5)
		(connect_pads
			(clearance 0)
		)
		(min_thickness 0.25)
		(keepout
			(tracks allowed)
			(vias allowed)
			(pads allowed)
			(copperpour allowed)
			(footprints not_allowed)
		)
		(placement
			(enabled no)
			(sheetname "")
		)
		(fill
			(thermal_gap 0.5)
			(thermal_bridge_width 0.5)
			(island_removal_mode 0)
		)
		(polygon
			(pts
				(xy 163.524692 -130.16611) (xy 167.124634 -130.16611) (xy 167.124634 -159.100012) (xy 163.524692 -159.100012)
			)
		)
	)
	(zone
		(layer "F.Cu")
		(hatch none 0.5)
		(connect_pads
			(clearance 0)
		)
		(min_thickness 0.25)
		(keepout
			(tracks allowed)
			(vias allowed)
			(pads allowed)
			(copperpour allowed)
			(footprints allowed)
		)
		(placement
			(enabled no)
			(sheetname "")
		)
		(fill
			(thermal_gap 0.5)
			(thermal_bridge_width 0.5)
			(island_removal_mode 0)
		)
		(polygon
			(pts
				(xy 195.1736 -76.708) (xy 195.1736 -75.3999) (xy 197.231 -75.3999) (xy 197.231 -76.708)
			)
		)
	)
	(zone
		(net "GND")
		(layer "F.Cu")
		(hatch none 0.5)
		(connect_pads
			(clearance 0.5)
		)
		(min_thickness 0.25)
		(fill yes
			(thermal_gap 0.5)
			(thermal_bridge_width 0.5)
			(island_removal_mode 0)
		)
		(polygon
			(pts
				(xy 475.91726 -32.97174) (xy 479.88728 -32.97174) (xy 480.0092 -32.84982) (xy 480.0092 -32.4104)
				(xy 480.1616 -32.258) (xy 481.584 -32.258) (xy 481.6094 -32.2326) (xy 481.6094 -31.9786) (xy 481.584 -31.9532)
				(xy 480.0854 -31.9532) (xy 480.0092 -31.877) (xy 480.0092 -30.3784) (xy 480.1108 -30.2768) (xy 481.584 -30.2768)
				(xy 481.6348 -30.226) (xy 481.6348 -29.9974) (xy 481.584 -29.9466) (xy 480.2632 -29.9466) (xy 480.0092 -29.6926)
				(xy 480.0092 -28.8798) (xy 479.9076 -28.7782) (xy 475.8944 -28.7782) (xy 475.80042 -28.87218) (xy 475.80042 -30.77718)
				(xy 475.6658 -30.9118) (xy 474.2434 -30.9118) (xy 474.1672 -30.988) (xy 474.1672 -31.242) (xy 474.1926 -31.2674)
				(xy 475.62262 -31.2674) (xy 475.80042 -31.4452) (xy 475.80042 -32.8549)
			)
		)
	)
	(zone
		(layer "F.Cu")
		(hatch none 0.5)
		(connect_pads
			(clearance 0)
		)
		(min_thickness 0.25)
		(keepout
			(tracks allowed)
			(vias allowed)
			(pads allowed)
			(copperpour allowed)
			(footprints not_allowed)
		)
		(placement
			(enabled no)
			(sheetname "")
		)
		(fill
			(thermal_gap 0.5)
			(thermal_bridge_width 0.5)
			(island_removal_mode 0)
		)
		(polygon
			(pts
				(arc
					(start 83.000088 -114.089942)
					(mid 80.460088 -111.549942)
					(end 83.000088 -109.009942)
				)
				(arc
					(start 83.000088 -109.009942)
					(mid 85.540088 -111.549942)
					(end 83.000088 -114.089942)
				)
			)
		)
	)
	(zone
		(layer "F.Cu")
		(hatch none 0.5)
		(connect_pads
			(clearance 0)
		)
		(min_thickness 0.25)
		(keepout
			(tracks not_allowed)
			(vias allowed)
			(pads allowed)
			(copperpour not_allowed)
			(footprints allowed)
		)
		(placement
			(enabled no)
			(sheetname "")
		)
		(fill
			(thermal_gap 0.5)
			(thermal_bridge_width 0.5)
			(island_removal_mode 0)
		)
		(polygon
			(pts
				(arc
					(start 360.499914 5.999988)
					(mid 364.499906 1.999996)
					(end 360.499914 -2.00025)
				)
				(arc
					(start 357.000048 -2.00025)
					(mid 352.999802 1.999996)
					(end 357.000048 5.999988)
				)
			)
		)
	)
	(zone
		(layer "F.Cu")
		(hatch none 0.5)
		(connect_pads
			(clearance 0)
		)
		(min_thickness 0.25)
		(keepout
			(tracks allowed)
			(vias allowed)
			(pads allowed)
			(copperpour allowed)
			(footprints not_allowed)
		)
		(placement
			(enabled no)
			(sheetname "")
		)
		(fill
			(thermal_gap 0.5)
			(thermal_bridge_width 0.5)
			(island_removal_mode 0)
		)
		(polygon
			(pts
				(arc
					(start 365.899954 -85.849968)
					(mid 366.968883 -83.34377)
					(end 369.489736 -82.30997)
				)
				(arc
					(start 369.489736 -82.30997)
					(mid 373.079772 -85.900006)
					(end 369.489736 -89.490042)
				)
				(arc
					(start 369.489736 -89.490042)
					(mid 366.96895 -88.456174)
					(end 365.899954 -85.950044)
				)
				(xy 360.579924 -85.950044) (xy 360.579924 -118.000018) (xy 353.579938 -118.000018) (xy 353.579938 -137.80008)
				(xy 400.979894 -137.80008) (xy 400.979894 -140.800074) (xy 406.439878 -140.800074)
				(arc
					(start 406.439878 -137.489692)
					(mid 402.899872 -133.87489)
					(end 406.489916 -130.309874)
				)
				(arc
					(start 406.489916 -130.309874)
					(mid 410.079865 -133.874891)
					(end 406.539954 -137.489692)
				)
				(xy 406.539954 -140.800074) (xy 414.98012 -140.800074) (xy 414.98012 -81.419954) (xy 404.3299 -81.419954)
				(xy 404.3299 -73.000108) (xy 383.37998 -73.000108) (xy 383.37998 -60.999878) (xy 360.579924 -60.999878)
				(xy 360.579924 -85.849968)
			)
		)
	)
	(zone
		(layer "F.Cu")
		(hatch none 0.5)
		(connect_pads
			(clearance 0)
		)
		(min_thickness 0.25)
		(keepout
			(tracks allowed)
			(vias allowed)
			(pads allowed)
			(copperpour allowed)
			(footprints not_allowed)
		)
		(placement
			(enabled no)
			(sheetname "")
		)
		(fill
			(thermal_gap 0.5)
			(thermal_bridge_width 0.5)
			(island_removal_mode 0)
		)
		(polygon
			(pts
				(arc
					(start 222.000064 -74.650092)
					(mid 223.899984 -76.550012)
					(end 222.000064 -78.449932)
				)
				(arc
					(start 222.000064 -78.449932)
					(mid 220.100144 -76.550012)
					(end 222.000064 -74.650092)
				)
			)
		)
	)
	(zone
		(net "GND")
		(layer "F.Cu")
		(hatch none 0.5)
		(connect_pads
			(clearance 0.5)
		)
		(min_thickness 0.25)
		(fill yes
			(thermal_gap 0.5)
			(thermal_bridge_width 0.5)
			(island_removal_mode 0)
		)
		(polygon
			(pts
				(xy 3.8354 -126.1872) (xy 3.8354 -129.7432) (xy 0.2794 -129.7432) (xy 0.2794 -126.1872)
			)
		)
	)
	(zone
		(net "GND")
		(layer "F.Cu")
		(hatch none 0.5)
		(connect_pads
			(clearance 0.5)
		)
		(min_thickness 0.25)
		(fill yes
			(thermal_gap 0.5)
			(thermal_bridge_width 0.5)
			(island_removal_mode 0)
		)
		(polygon
			(pts
				(xy 331.597 -152.146) (xy 331.597 -149.8346) (xy 331.5208 -149.7584) (xy 330.4032 -149.7584) (xy 330.327 -149.7584)
				(xy 330.0476 -149.479) (xy 329.714606 -149.479) (xy 329.606656 -149.58695) (xy 329.606656 -152.214834)
				(xy 329.663298 -152.271476) (xy 331.589634 -152.271476) (xy 331.597 -152.26411)
			)
		)
	)
	(zone
		(layer "F.Cu")
		(hatch none 0.5)
		(connect_pads
			(clearance 0)
		)
		(min_thickness 0.25)
		(keepout
			(tracks allowed)
			(vias allowed)
			(pads allowed)
			(copperpour allowed)
			(footprints not_allowed)
		)
		(placement
			(enabled no)
			(sheetname "")
		)
		(fill
			(thermal_gap 0.5)
			(thermal_bridge_width 0.5)
			(island_removal_mode 0)
		)
		(polygon
			(pts
				(xy 348.832678 -11.59002) (xy 480.119944 -11.59002) (xy 480.119944 -0.990092)
				(arc
					(start 477.157034 -0.990092)
					(mid 475.921217 -1.739004)
					(end 474.49994 -1.999996)
				)
				(arc
					(start 471.000074 -1.999996)
					(mid 469.578774 -1.739063)
					(end 468.34298 -0.990092)
				)
				(arc
					(start 363.157262 -0.990092)
					(mid 361.921353 -1.739207)
					(end 360.499914 -2.00025)
				)
				(arc
					(start 357.000048 -2.00025)
					(mid 355.578616 -1.739188)
					(end 354.3427 -0.990092)
				)
				(xy 348.832678 -0.990092)
			)
		)
	)
	(zone
		(layer "F.Cu")
		(hatch none 0.5)
		(connect_pads
			(clearance 0)
		)
		(min_thickness 0.25)
		(keepout
			(tracks allowed)
			(vias allowed)
			(pads allowed)
			(copperpour allowed)
			(footprints allowed)
		)
		(placement
			(enabled no)
			(sheetname "")
		)
		(fill
			(thermal_gap 0.5)
			(thermal_bridge_width 0.5)
			(island_removal_mode 0)
		)
		(polygon
			(pts
				(xy 175.8696 -56.9722) (xy 175.8696 -52.6034) (xy 178.2826 -52.6034) (xy 178.2826 -56.9722)
			)
		)
	)
	(zone
		(layer "F.Cu")
		(hatch none 0.5)
		(connect_pads
			(clearance 0)
		)
		(min_thickness 0.25)
		(keepout
			(tracks allowed)
			(vias allowed)
			(pads allowed)
			(copperpour allowed)
			(footprints allowed)
		)
		(placement
			(enabled no)
			(sheetname "")
		)
		(fill
			(thermal_gap 0.5)
			(thermal_bridge_width 0.5)
			(island_removal_mode 0)
		)
		(polygon
			(pts
				(xy 67.945 -82.423) (xy 68.707 -82.423) (xy 68.961 -82.677) (xy 68.961 -83.058) (xy 67.818 -83.058)
				(xy 67.818 -82.55)
			)
		)
	)
	(zone
		(net "PVDDQ_ABC")
		(layer "F.Cu")
		(hatch none 0.5)
		(connect_pads
			(clearance 0.5)
		)
		(min_thickness 0.25)
		(fill yes
			(thermal_gap 0.5)
			(thermal_bridge_width 0.5)
			(island_removal_mode 0)
		)
		(polygon
			(pts
				(xy 265.811 0.3048) (xy 277.241 0.3048) (xy 277.495 0.5588) (xy 277.495 2.3876) (xy 277.1648 2.7178)
				(xy 266.6238 2.7178) (xy 265.6332 1.7272) (xy 265.6332 0.4826)
			)
		)
	)
	(zone
		(net "AGND_PVPP_KLM")
		(layer "F.Cu")
		(hatch none 0.5)
		(connect_pads
			(clearance 0.5)
		)
		(min_thickness 0.25)
		(fill yes
			(thermal_gap 0.5)
			(thermal_bridge_width 0.5)
			(island_removal_mode 0)
		)
		(polygon
			(pts
				(xy 174.46498 -130.86842) (xy 174.5996 -130.7338) (xy 174.5996 -129.7686) (xy 174.4345 -129.6035)
				(xy 172.8089 -129.6035) (xy 172.1612 -130.2512) (xy 172.1612 -130.81) (xy 172.21962 -130.86842)
			)
		)
	)
	(zone
		(layer "F.Cu")
		(hatch none 0.5)
		(connect_pads
			(clearance 0)
		)
		(min_thickness 0.25)
		(keepout
			(tracks allowed)
			(vias allowed)
			(pads allowed)
			(copperpour allowed)
			(footprints allowed)
		)
		(placement
			(enabled no)
			(sheetname "")
		)
		(fill
			(thermal_gap 0.5)
			(thermal_bridge_width 0.5)
			(island_removal_mode 0)
		)
		(polygon
			(pts
				(xy 475.45498 -32.140144) (xy 475.45498 -31.64713) (xy 475.218506 -31.410656) (xy 473.645738 -31.410656)
				(xy 473.584524 -31.47187) (xy 473.584524 -32.091122) (xy 473.584524 -33.229804) (xy 473.7989 -33.44418)
				(xy 475.2975 -33.44418) (xy 475.45498 -33.2867)
			)
		)
	)
	(zone
		(net "GND")
		(layer "F.Cu")
		(hatch none 0.5)
		(connect_pads
			(clearance 0.5)
		)
		(min_thickness 0.25)
		(fill yes
			(thermal_gap 0.5)
			(thermal_bridge_width 0.5)
			(island_removal_mode 0)
		)
		(polygon
			(pts
				(xy 35.56 -51.7144) (xy 35.545268 -51.729132) (xy 34.562034 -51.729132) (xy 33.806384 -52.484782)
				(xy 33.806384 -52.967128) (xy 33.814004 -52.967128) (xy 33.814004 -53.475636) (xy 33.806384 -53.475636)
				(xy 33.806384 -53.723286) (xy 33.336484 -54.193186) (xy 33.336484 -55.23103) (xy 33.294066 -55.273448)
				(xy 32.253682 -55.273448) (xy 32.25292 -55.27294) (xy 32.252412 -55.273448) (xy 31.736792 -55.273448)
				(xy 31.68904 -55.3212) (xy 31.684468 -55.3212) (xy 31.633668 -55.372) (xy 31.633668 -56.896) (xy 31.786068 -57.0484)
				(xy 33.716468 -57.0484) (xy 33.782508 -57.11444) (xy 33.950148 -57.11444) (xy 33.950148 -57.28208)
				(xy 34.021268 -57.3532) (xy 34.021268 -59.99226) (xy 33.87852 -60.135008) (xy 33.87852 -60.630816)
				(xy 33.866582 -60.630816) (xy 33.866582 -61.632592) (xy 33.864296 -61.634878) (xy 33.864296 -61.760862)
				(arc
					(start 33.372044 -62.25413)
					(mid 33.357773 -62.267584)
					(end 33.342834 -62.280292)
				)
				(xy 33.342834 -63.375286) (xy 33.30448 -63.41364) (xy 31.70809 -63.41364) (xy 31.68142 -63.44031)
				(xy 31.68142 -65.099946) (xy 31.753556 -65.172082) (xy 33.63595 -65.172082) (xy 33.706308 -65.24244)
				(xy 33.950148 -65.24244) (xy 33.950148 -65.48628) (xy 34.021268 -65.5574) (xy 34.021268 -68.036948)
				(xy 33.950148 -68.108068) (xy 33.950148 -68.189856) (xy 33.86836 -68.189856) (xy 33.731962 -68.326254)
				(xy 33.731962 -69.998082) (xy 34.149284 -70.415404) (xy 34.149284 -71.380604) (xy 34.47796 -71.380604)
				(xy 34.47796 -72.143112) (xy 33.867852 -72.143112) (xy 33.867852 -71.383652) (xy 33.640776 -71.383652)
				(xy 33.640776 -70.600316) (xy 33.58134 -70.54088) (xy 33.32226 -70.54088) (xy 33.31718 -70.54596)
				(xy 33.31718 -71.46544) (xy 33.31591 -71.46671) (xy 33.31591 -71.50989) (xy 33.28162 -71.54418)
				(xy 31.707074 -71.54418) (xy 31.660592 -71.590662) (xy 31.660592 -73.265284) (xy 31.70428 -73.308972)
				(xy 33.888172 -73.308972) (xy 33.94964 -73.37044) (xy 33.9598 -73.37044) (xy 33.9598 -76.341732)
				(xy 33.824672 -76.47686) (xy 33.824672 -78.020926) (xy 33.547304 -78.298548) (xy 33.547304 -78.316836)
				(xy 33.373568 -78.490318)
				(arc
					(start 33.372806 -78.49108)
					(mid 33.353786 -78.510084)
					(end 33.333436 -78.527656)
				)
				(xy 33.333436 -79.609188) (xy 33.330642 -79.611982) (xy 33.330642 -79.686658) (xy 33.2867 -79.7306)
				(xy 31.735268 -79.7306) (xy 31.684468 -79.7814) (xy 31.684468 -81.2038) (xy 31.887668 -81.407) (xy 33.640268 -81.407)
				(xy 33.731708 -81.49844) (xy 33.950148 -81.49844) (xy 33.950148 -81.71688) (xy 34.046668 -81.8134)
				(xy 34.046668 -84.475828) (xy 33.818576 -84.704174) (xy 33.818576 -85.119972) (xy 33.810956 -85.119972)
				(xy 33.475168 -85.45576) (xy 33.097724 -85.45576) (xy 33.012126 -85.541358) (xy 33.012126 -86.012782)
				(xy 33.097978 -86.098634) (xy 33.192212 -86.098634) (xy 33.373314 -86.279736) (xy 33.373314 -86.618572)
				(arc
					(start 33.372552 -86.619334)
					(mid 33.355216 -86.63683)
					(end 33.336738 -86.653116)
				)
				(xy 33.336738 -87.714582) (xy 33.33242 -87.7189) (xy 33.33242 -87.84844) (xy 33.29432 -87.88654)
				(xy 31.783528 -87.88654) (xy 31.760668 -87.9094) (xy 31.760668 -89.408) (xy 31.887668 -89.535) (xy 33.513268 -89.535)
				(xy 33.604708 -89.62644) (xy 33.950148 -89.62644) (xy 33.950148 -89.97188) (xy 34.046668 -90.0684)
				(xy 34.046668 -92.45727) (xy 33.950148 -92.55379) (xy 33.950148 -92.573856) (xy 33.930336 -92.573856)
				(xy 33.806638 -92.6973) (xy 33.806638 -93.14688) (xy 33.853374 -93.193616) (xy 34.412174 -93.193616)
				(xy 34.604198 -93.001592) (xy 43.053 -93.001592) (xy 43.266868 -92.787724) (xy 43.266868 -53.5178)
				(xy 43.274234 -53.510434) (xy 43.166792 -53.402992) (xy 43.166792 -52.4002) (xy 41.895268 -52.4002)
				(xy 41.869868 -52.4256) (xy 39.939468 -52.4256) (xy 39.355776 -51.841908) (xy 39.355014 -51.841908)
				(xy 39.355014 -51.841146) (xy 39.293292 -51.779424) (xy 39.228268 -51.7144)
			)
		)
		(polygon
			(pts
				(xy 37.10432 -61.577474) (xy 37.03828 -61.577474) (xy 36.842954 -61.7728) (xy 36.942522 -61.7728)
				(xy 37.121084 -61.594238)
			)
		)
		(polygon
			(pts
				(xy 37.278564 -60.654946) (xy 36.832032 -60.654946) (xy 36.832032 -60.659518) (xy 37.03701 -60.864496)
				(xy 37.233098 -60.864496) (xy 37.360606 -60.736988)
			)
		)
		(polygon
			(pts
				(xy 37.897562 -68.757546) (xy 37.794438 -68.757546) (xy 37.794438 -68.805298) (xy 37.937694 -68.948554)
				(xy 38.08857 -68.948554)
			)
		)
		(polygon
			(pts
				(xy 38.080188 -69.677788) (xy 37.960554 -69.677788) (xy 37.804852 -69.83349) (xy 37.804852 -69.875908)
				(xy 37.890196 -69.875908) (xy 38.080188 -69.685916)
			)
		)
		(polygon
			(pts
				(xy 37.113464 -77.188822) (xy 37.03955 -77.188822) (xy 37.03955 -77.257148) (xy 37.200586 -77.418184)
				(xy 37.296598 -77.418184) (xy 37.296598 -77.371956)
			)
		)
		(polygon
			(pts
				(xy 37.286692 -78.10373) (xy 37.188648 -78.10373) (xy 37.037264 -78.255114) (xy 37.037264 -78.307184)
				(xy 37.112702 -78.307184) (xy 37.301424 -78.118462)
			)
		)
		(polygon
			(pts
				(xy 37.57168 -85.139784) (xy 37.468302 -85.139784) (xy 37.468302 -85.209634) (xy 37.586158 -85.32749)
				(xy 37.759386 -85.32749)
			)
		)
		(polygon
			(pts
				(xy 37.748972 -86.05901) (xy 37.658294 -86.05901) (xy 37.609272 -86.108032) (xy 37.609272 -86.208362)
				(xy 37.612828 -86.208362) (xy 37.748972 -86.072218)
			)
		)
		(polygon
			(pts
				(xy 39.458138 -69.556122) (xy 39.276274 -69.556122) (xy 39.276274 -69.558916) (xy 39.265098 -69.558916)
				(xy 39.264336 -69.559678) (xy 39.264336 -69.69252) (xy 39.37 -69.798184) (xy 39.37 -70.586092) (xy 39.341298 -70.614794)
				(xy 39.341298 -70.688962) (xy 39.360094 -70.707758) (xy 39.41699 -70.707758) (xy 39.462202 -70.662546)
				(xy 39.462202 -69.558916) (xy 39.458138 -69.558916)
			)
		)
		(polygon
			(pts
				(xy 39.29888 -60.70854) (xy 39.295832 -60.70854) (xy 39.246048 -60.758324) (xy 39.246048 -60.88126)
				(xy 39.802308 -61.43752) (xy 39.802308 -61.211968)
			)
		)
		(polygon
			(pts
				(xy 39.879778 -62.457838) (xy 39.794942 -62.373002) (xy 39.771574 -62.39637) (xy 39.771574 -62.493398)
				(xy 39.783258 -62.505082) (xy 39.879778 -62.505082)
			)
		)
		(polygon
			(pts
				(xy 39.08679 -62.424818) (xy 39.058342 -62.39637) (xy 38.95471 -62.500002) (xy 38.95471 -62.521592)
				(xy 39.070788 -62.521592) (xy 39.08679 -62.50559)
			)
		)
		(polygon
			(pts
				(xy 39.510716 -54.275736) (xy 39.505382 -54.275736) (xy 39.448994 -54.332124) (xy 39.448994 -54.376828)
				(xy 39.493444 -54.376828) (xy 39.552626 -54.317646)
			)
		)
		(polygon
			(pts
				(xy 40.31107 -54.326282) (xy 40.25646 -54.271672) (xy 40.230552 -54.29758) (xy 40.230552 -54.348126)
				(xy 40.25265 -54.370224) (xy 40.302688 -54.370224) (xy 40.31107 -54.361842)
			)
		)
		(polygon
			(pts
				(xy 39.472108 -52.526692) (xy 39.435024 -52.526692) (xy 39.401496 -52.56022) (xy 39.401496 -52.679854)
				(xy 40.263064 -53.541422) (xy 40.263064 -53.317648)
			)
		)
		(polygon
			(pts
				(xy 37.826442 -52.526692) (xy 37.019992 -52.526692) (xy 37.019992 -52.583588) (xy 37.826442 -52.583588)
			)
		)
		(polygon
			(pts
				(xy 37.822124 -53.265324) (xy 37.037264 -53.265324) (xy 37.037264 -53.289708) (xy 37.822124 -53.289708)
			)
		)
		(polygon
			(pts
				(xy 38.712394 -52.526692) (xy 38.553136 -52.526692) (xy 38.553136 -52.689252) (xy 38.712394 -52.689252)
			)
		)
		(polygon
			(pts
				(xy 38.721538 -53.159406) (xy 38.570916 -53.159406) (xy 38.570916 -53.289708) (xy 38.721538 -53.289708)
			)
		)
		(polygon
			(pts
				(xy 38.54196 -60.70854) (xy 38.38321 -60.70854) (xy 38.38321 -60.851796) (xy 38.54196 -60.851796)
			)
		)
		(polygon
			(pts
				(xy 38.539928 -61.337698) (xy 38.39718 -61.337698) (xy 38.39718 -61.471556) (xy 38.539928 -61.471556)
			)
		)
		(polygon
			(pts
				(xy 39.421562 -68.935092) (xy 39.27475 -68.935092) (xy 39.27475 -69.08165) (xy 39.421562 -69.08165)
			)
		)
		(polygon
			(pts
				(xy 38.760654 -77.367892) (xy 38.621716 -77.367892) (xy 38.621716 -77.51191) (xy 38.760654 -77.51191)
			)
		)
		(polygon
			(pts
				(xy 38.762686 -78.000098) (xy 38.621716 -78.000098) (xy 38.621716 -78.130908) (xy 38.762686 -78.130908)
			)
		)
		(polygon
			(pts
				(xy 38.534848 -85.318092) (xy 38.366446 -85.318092) (xy 38.366446 -85.484208) (xy 38.534848 -85.484208)
			)
		)
		(polygon
			(pts
				(xy 38.535864 -85.937344) (xy 38.369748 -85.937344) (xy 38.369748 -86.081108) (xy 38.535864 -86.081108)
			)
		)
		(polygon
			(pts
				(xy 36.248086 -86.0298) (xy 36.044886 -86.0298) (xy 36.044886 -86.233) (xy 36.248086 -86.233)
			)
		)
		(polygon
			(pts
				(xy 35.384486 -86.0298) (xy 35.181286 -86.0298) (xy 35.181286 -86.233) (xy 35.384486 -86.233)
			)
		)
		(polygon
			(pts
				(xy 36.248086 -85.1662) (xy 36.044886 -85.1662) (xy 36.044886 -85.3694) (xy 36.248086 -85.3694)
			)
		)
		(polygon
			(pts
				(xy 35.384486 -85.1662) (xy 35.181286 -85.1662) (xy 35.181286 -85.3694) (xy 35.384486 -85.3694)
			)
		)
		(polygon
			(pts
				(xy 35.7886 -78.0796) (xy 35.5854 -78.0796) (xy 35.5854 -78.2828) (xy 35.7886 -78.2828)
			)
		)
		(polygon
			(pts
				(xy 34.925 -78.0796) (xy 34.7218 -78.0796) (xy 34.7218 -78.2828) (xy 34.925 -78.2828)
			)
		)
		(polygon
			(pts
				(xy 35.7886 -77.216) (xy 35.5854 -77.216) (xy 35.5854 -77.4192) (xy 35.7886 -77.4192)
			)
		)
		(polygon
			(pts
				(xy 34.925 -77.216) (xy 34.7218 -77.216) (xy 34.7218 -77.4192) (xy 34.925 -77.4192)
			)
		)
		(polygon
			(pts
				(xy 36.576 -69.6468) (xy 36.3728 -69.6468) (xy 36.3728 -69.85) (xy 36.576 -69.85)
			)
		)
		(polygon
			(pts
				(xy 35.7124 -69.6468) (xy 35.5092 -69.6468) (xy 35.5092 -69.85) (xy 35.7124 -69.85)
			)
		)
		(polygon
			(pts
				(xy 36.576 -68.7832) (xy 36.3728 -68.7832) (xy 36.3728 -68.9864) (xy 36.576 -68.9864)
			)
		)
		(polygon
			(pts
				(xy 35.7124 -68.7832) (xy 35.5092 -68.7832) (xy 35.5092 -68.9864) (xy 35.7124 -68.9864)
			)
		)
		(polygon
			(pts
				(xy 35.6108 -61.5442) (xy 35.4076 -61.5442) (xy 35.4076 -61.7474) (xy 35.6108 -61.7474)
			)
		)
		(polygon
			(pts
				(xy 35.6108 -60.6806) (xy 35.4076 -60.6806) (xy 35.4076 -60.8838) (xy 35.6108 -60.8838)
			)
		)
		(polygon
			(pts
				(xy 35.6108 -53.2384) (xy 35.4076 -53.2384) (xy 35.4076 -53.4416) (xy 35.6108 -53.4416)
			)
		)
		(polygon
			(pts
				(xy 34.7472 -53.2384) (xy 34.544 -53.2384) (xy 34.544 -53.4416) (xy 34.7472 -53.4416)
			)
		)
		(polygon
			(pts
				(xy 42.3799 -53.07838) (xy 42.1767 -53.07838) (xy 42.1767 -53.28158) (xy 42.3799 -53.28158)
			)
		)
		(polygon
			(pts
				(xy 35.6108 -52.3748) (xy 35.4076 -52.3748) (xy 35.4076 -52.578) (xy 35.6108 -52.578)
			)
		)
		(polygon
			(pts
				(xy 34.7472 -52.3748) (xy 34.544 -52.3748) (xy 34.544 -52.578) (xy 34.7472 -52.578)
			)
		)
	)
	(zone
		(layer "F.Cu")
		(hatch none 0.5)
		(connect_pads
			(clearance 0)
		)
		(min_thickness 0.25)
		(keepout
			(tracks not_allowed)
			(vias allowed)
			(pads allowed)
			(copperpour not_allowed)
			(footprints allowed)
		)
		(placement
			(enabled no)
			(sheetname "")
		)
		(fill
			(thermal_gap 0.5)
			(thermal_bridge_width 0.5)
			(island_removal_mode 0)
		)
		(polygon
			(pts
				(xy 456.355958 -63.588138) (xy 456.318874 -63.551054) (xy 456.318874 -63.498222) (xy 456.318874 -63.22314)
				(xy 456.318874 -63.217552) (xy 455.987404 -63.217552) (xy 455.987404 -63.246254) (xy 455.987404 -63.498476)
				(xy 455.987404 -63.551308) (xy 455.95032 -63.588392) (xy 455.885804 -63.652908) (xy 455.84872 -63.689992)
				(xy 455.795888 -63.689992)
				(arc
					(start 455.778616 -63.689992)
					(mid 455.252788 -63.626492)
					(end 455.778616 -63.562992)
				)
				(xy 455.795888 -63.562992) (xy 455.860404 -63.498476) (xy 455.860404 -63.246254) (xy 455.831702 -63.217552)
				(arc
					(start 455.519536 -63.217552)
					(mid 455.110596 -63.626492)
					(end 455.519536 -64.035432)
				)
				(arc
					(start 456.789282 -64.035432)
					(mid 457.198476 -63.626619)
					(end 456.789536 -63.217552)
				)
				(xy 456.451462 -63.217552) (xy 456.445874 -63.22314) (xy 456.445874 -63.498222) (xy 456.510644 -63.562992)
				(arc
					(start 456.530456 -63.562992)
					(mid 457.056284 -63.626492)
					(end 456.530456 -63.689992)
				)
				(xy 456.510644 -63.689992) (xy 456.457812 -63.689992) (xy 456.420728 -63.652908)
			)
		)
	)
	(zone
		(layer "F.Cu")
		(hatch none 0.5)
		(connect_pads
			(clearance 0)
		)
		(min_thickness 0.25)
		(keepout
			(tracks not_allowed)
			(vias allowed)
			(pads allowed)
			(copperpour not_allowed)
			(footprints allowed)
		)
		(placement
			(enabled no)
			(sheetname "")
		)
		(fill
			(thermal_gap 0.5)
			(thermal_bridge_width 0.5)
			(island_removal_mode 0)
		)
		(polygon
			(pts
				(xy 448.056 -120.43283) (xy 448.056 -120.731026) (xy 447.900806 -120.88622)
				(arc
					(start 447.729102 -120.88622)
					(mid 447.205185 -120.81637)
					(end 447.729102 -120.74652)
				)
				(xy 447.842894 -120.74652) (xy 447.9163 -120.673114) (xy 447.9163 -120.43283)
				(arc
					(start 447.472054 -120.43283)
					(mid 447.08826 -120.816243)
					(end 447.4718 -121.19991)
				)
				(arc
					(start 448.7418 -121.19991)
					(mid 449.12534 -120.81637)
					(end 448.7418 -120.43283)
				)
				(xy 448.2973 -120.43283) (xy 448.2973 -120.673114) (xy 448.370706 -120.74652)
				(arc
					(start 448.484498 -120.74652)
					(mid 449.008415 -120.81637)
					(end 448.484498 -120.88622)
				)
				(xy 448.312794 -120.88622) (xy 448.1576 -120.731026) (xy 448.1576 -120.43283)
			)
		)
	)
	(zone
		(layer "F.Cu")
		(hatch none 0.5)
		(connect_pads
			(clearance 0)
		)
		(min_thickness 0.25)
		(keepout
			(tracks allowed)
			(vias allowed)
			(pads allowed)
			(copperpour allowed)
			(footprints not_allowed)
		)
		(placement
			(enabled no)
			(sheetname "")
		)
		(fill
			(thermal_gap 0.5)
			(thermal_bridge_width 0.5)
			(island_removal_mode 0)
		)
		(polygon
			(pts
				(arc
					(start 360.499914 5.999988)
					(mid 364.499906 1.999996)
					(end 360.499914 -2.00025)
				)
				(arc
					(start 357.000048 -2.00025)
					(mid 352.999802 1.999996)
					(end 357.000048 5.999988)
				)
			)
		)
	)
	(zone
		(layer "F.Cu")
		(hatch none 0.5)
		(connect_pads
			(clearance 0)
		)
		(min_thickness 0.25)
		(keepout
			(tracks allowed)
			(vias allowed)
			(pads allowed)
			(copperpour allowed)
			(footprints allowed)
		)
		(placement
			(enabled no)
			(sheetname "")
		)
		(fill
			(thermal_gap 0.5)
			(thermal_bridge_width 0.5)
			(island_removal_mode 0)
		)
		(polygon
			(pts
				(xy 81.252568 -99.9236) (xy 86.307168 -99.9236) (xy 86.561168 -100.1776) (xy 86.561168 -102.235)
				(xy 82.395568 -102.235) (xy 82.395568 -102.743) (xy 81.252568 -102.743) (xy 81.252568 -102.235)
			)
		)
	)
	(zone
		(layer "F.Cu")
		(hatch none 0.5)
		(connect_pads
			(clearance 0)
		)
		(min_thickness 0.25)
		(keepout
			(tracks allowed)
			(vias allowed)
			(pads allowed)
			(copperpour allowed)
			(footprints not_allowed)
		)
		(placement
			(enabled no)
			(sheetname "")
		)
		(fill
			(thermal_gap 0.5)
			(thermal_bridge_width 0.5)
			(island_removal_mode 0)
		)
		(polygon
			(pts
				(arc
					(start 63.5 -43.09999)
					(mid 62.297903 -43.597915)
					(end 61.799978 -44.800012)
				)
				(arc
					(start 61.799978 -52.178712)
					(mid 61.853264 -52.4466)
					(end 62.004956 -52.673758)
				)
				(arc
					(start 63.126366 -53.794914)
					(mid 63.624948 -54.541095)
					(end 63.799974 -55.421276)
				)
				(arc
					(start 63.799974 -58.799984)
					(mid 63.363567 -59.878099)
					(end 62.300104 -60.34913)
				)
				(arc
					(start 62.300104 -92.750894)
					(mid 63.3636 -93.221893)
					(end 63.799974 -94.30004)
				)
				(arc
					(start 63.799974 -97.678748)
					(mid 63.624899 -98.558908)
					(end 63.126366 -99.30511)
				)
				(arc
					(start 62.004956 -100.426266)
					(mid 61.853193 -100.653395)
					(end 61.799978 -100.921312)
				)
				(arc
					(start 61.799978 -108.300012)
					(mid 62.297903 -109.502109)
					(end 63.5 -110.000034)
				)
				(arc
					(start 69.15404 -110.000034)
					(mid 69.393378 -109.957739)
					(end 69.603874 -109.836204)
				)
				(arc
					(start 72.93864 -107.03814)
					(mid 73.63046 -106.638708)
					(end 74.417174 -106.499914)
				)
				(arc
					(start 135.582914 -106.499914)
					(mid 136.369507 -106.638696)
					(end 137.061194 -107.03814)
				)
				(arc
					(start 140.39596 -109.836204)
					(mid 140.606563 -109.957785)
					(end 140.846048 -110.000034)
				)
				(arc
					(start 146.500088 -110.000034)
					(mid 147.702185 -109.502109)
					(end 148.20011 -108.300012)
				)
				(arc
					(start 148.20011 -100.921312)
					(mid 148.146722 -100.653381)
					(end 147.994878 -100.426266)
				)
				(arc
					(start 146.873722 -99.30511)
					(mid 146.37514 -98.558929)
					(end 146.200114 -97.678748)
				)
				(arc
					(start 146.200114 -96.0501)
					(mid 147.898831 -91.948907)
					(end 151.99995 -90.25001)
				)
				(arc
					(start 157.750002 -90.25001)
					(mid 159.376326 -90.923656)
					(end 160.049972 -92.54998)
				)
				(arc
					(start 160.049972 -112.799876)
					(mid 158.93695 -115.486948)
					(end 156.249878 -116.59997)
				)
				(arc
					(start 53.749956 -116.59997)
					(mid 51.063138 -115.486843)
					(end 49.950116 -112.799876)
				)
				(arc
					(start 49.950116 -40.299894)
					(mid 51.063063 -37.613001)
					(end 53.749956 -36.500054)
				)
				(xy 155.58135 -36.500054) (xy 160.049972 -40.968676)
				(arc
					(start 160.049972 -60.550044)
					(mid 159.376326 -62.176368)
					(end 157.750002 -62.850014)
				)
				(arc
					(start 151.99995 -62.850014)
					(mid 147.898921 -61.151102)
					(end 146.200114 -57.049924)
				)
				(arc
					(start 146.200114 -55.421276)
					(mid 146.375189 -54.541116)
					(end 146.873722 -53.794914)
				)
				(arc
					(start 147.994878 -52.673758)
					(mid 148.146724 -52.446644)
					(end 148.20011 -52.178712)
				)
				(arc
					(start 148.20011 -44.800012)
					(mid 147.702185 -43.597915)
					(end 146.500088 -43.09999)
				)
				(arc
					(start 140.846048 -43.09999)
					(mid 140.606555 -43.142216)
					(end 140.39596 -43.26382)
				)
				(arc
					(start 137.061194 -46.061884)
					(mid 136.369503 -46.461316)
					(end 135.582914 -46.60011)
				)
				(arc
					(start 74.417174 -46.60011)
					(mid 73.630436 -46.461384)
					(end 72.93864 -46.061884)
				)
				(arc
					(start 69.603874 -43.26382)
					(mid 69.39341 -43.142196)
					(end 69.15404 -43.09999)
				)
			)
		)
	)
	(zone
		(layer "F.Cu")
		(hatch none 0.5)
		(connect_pads
			(clearance 0)
		)
		(min_thickness 0.25)
		(keepout
			(tracks allowed)
			(vias allowed)
			(pads allowed)
			(copperpour allowed)
			(footprints not_allowed)
		)
		(placement
			(enabled no)
			(sheetname "")
		)
		(fill
			(thermal_gap 0.5)
			(thermal_bridge_width 0.5)
			(island_removal_mode 0)
		)
		(polygon
			(pts
				(arc
					(start 33.919922 -44.99991)
					(mid 35.470084 -46.550072)
					(end 33.919922 -48.09998)
				)
				(arc
					(start 33.919922 -48.09998)
					(mid 32.370014 -46.550072)
					(end 33.919922 -44.99991)
				)
			)
		)
	)
	(zone
		(layer "F.Cu")
		(hatch none 0.5)
		(connect_pads
			(clearance 0)
		)
		(min_thickness 0.25)
		(keepout
			(tracks not_allowed)
			(vias allowed)
			(pads allowed)
			(copperpour not_allowed)
			(footprints allowed)
		)
		(placement
			(enabled no)
			(sheetname "")
		)
		(fill
			(thermal_gap 0.5)
			(thermal_bridge_width 0.5)
			(island_removal_mode 0)
		)
		(polygon
			(pts
				(arc
					(start 15.520924 -36.509198)
					(mid 15.451074 -37.033115)
					(end 15.381224 -36.509198)
				)
				(xy 15.381224 -36.395406) (xy 15.307818 -36.322) (xy 15.135606 -36.322) (xy 15.067534 -36.390072)
				(arc
					(start 15.067534 -36.7665)
					(mid 15.451074 -37.15004)
					(end 15.834614 -36.7665)
				)
				(arc
					(start 15.834614 -35.496754)
					(mid 15.451201 -35.11296)
					(end 15.067534 -35.4965)
				)
				(xy 15.067534 -35.872928) (xy 15.135606 -35.941) (xy 15.307818 -35.941) (xy 15.381224 -35.867594)
				(arc
					(start 15.381224 -35.753802)
					(mid 15.451074 -35.229885)
					(end 15.520924 -35.753802)
				)
				(xy 15.520924 -35.925506) (xy 15.36573 -36.0807) (xy 15.077694 -36.0807) (xy 15.067534 -36.07054)
				(xy 15.067534 -36.19246) (xy 15.077694 -36.1823) (xy 15.36573 -36.1823) (xy 15.520924 -36.337494)
			)
		)
	)
	(zone
		(net "GND")
		(layer "F.Cu")
		(hatch none 0.5)
		(connect_pads
			(clearance 0.5)
		)
		(min_thickness 0.25)
		(fill yes
			(thermal_gap 0.5)
			(thermal_bridge_width 0.5)
			(island_removal_mode 0)
		)
		(polygon
			(pts
				(xy 396.364714 -59.709304) (xy 396.992348 -59.709304) (xy 397.30553 -59.709304) (xy 397.574008 -59.977782)
				(xy 397.574008 -60.290964) (xy 397.574008 -63.287402) (xy 397.574008 -63.941706) (xy 397.306546 -64.209168)
				(xy 396.652242 -64.209168) (xy 395.990572 -64.209168) (xy 395.502638 -63.721234) (xy 395.502638 -63.721488)
				(xy 394.974572 -63.193422) (xy 394.974572 -60.189872) (xy 394.974572 -59.862974) (xy 395.128242 -59.709304)
				(xy 395.45514 -59.709304)
			)
		)
	)
	(zone
		(net "VR_PVCCIO_CPU1_PH1_SW")
		(layer "F.Cu")
		(hatch none 0.5)
		(connect_pads
			(clearance 0.5)
		)
		(min_thickness 0.25)
		(fill yes
			(thermal_gap 0.5)
			(thermal_bridge_width 0.5)
			(island_removal_mode 0)
		)
		(polygon
			(pts
				(xy 169.8752 -55.8038) (xy 173.4566 -55.8038) (xy 174.244 -56.5912) (xy 174.8028 -56.5912) (xy 174.879 -56.515)
				(xy 174.879 -52.2986) (xy 174.879 -52.07) (xy 173.9646 -51.1556) (xy 170.18 -51.1556) (xy 169.692574 -51.1556)
				(xy 169.319448 -51.528726) (xy 169.319448 -55.657496) (xy 169.465752 -55.8038)
			)
		)
	)
	(zone
		(layer "F.Cu")
		(hatch none 0.5)
		(connect_pads
			(clearance 0)
		)
		(min_thickness 0.25)
		(keepout
			(tracks not_allowed)
			(vias allowed)
			(pads allowed)
			(copperpour not_allowed)
			(footprints allowed)
		)
		(placement
			(enabled no)
			(sheetname "")
		)
		(fill
			(thermal_gap 0.5)
			(thermal_bridge_width 0.5)
			(island_removal_mode 0)
		)
		(polygon
			(pts
				(arc
					(start 198.930006 -110.10011)
					(mid 195.380102 -106.550206)
					(end 198.930006 -103.000048)
				)
				(arc
					(start 198.930006 -103.000048)
					(mid 202.480164 -106.550206)
					(end 198.930006 -110.10011)
				)
			)
		)
	)
	(zone
		(layer "F.Cu")
		(hatch none 0.5)
		(connect_pads
			(clearance 0)
		)
		(min_thickness 0.25)
		(keepout
			(tracks not_allowed)
			(vias allowed)
			(pads allowed)
			(copperpour not_allowed)
			(footprints allowed)
		)
		(placement
			(enabled no)
			(sheetname "")
		)
		(fill
			(thermal_gap 0.5)
			(thermal_bridge_width 0.5)
			(island_removal_mode 0)
		)
		(polygon
			(pts
				(xy 395.212824 -106.470958) (xy 395.164056 -106.488992)
				(arc
					(start 394.880084 -106.356912)
					(mid 394.430201 -106.077903)
					(end 394.93317 -106.24312)
				)
				(xy 395.216888 -106.374946) (xy 395.234922 -106.423714)
				(arc
					(start 395.532356 -106.423714)
					(mid 395.550389 -105.948708)
					(end 395.92377 -106.24312)
				)
				(arc
					(start 396.008352 -106.282236)
					(mid 395.945839 -105.972307)
					(end 395.66215 -105.832656)
				)
				(arc
					(start 394.671804 -105.832656)
					(mid 394.31341 -106.190669)
					(end 394.67155 -106.548936)
				)
				(arc
					(start 395.66215 -106.548936)
					(mid 395.827497 -106.508483)
					(end 395.95552 -106.396282)
				)
				(arc
					(start 395.870684 -106.356912)
					(mid 395.716339 -106.451841)
					(end 395.536928 -106.426254)
				)
				(xy 395.234668 -106.426254) (xy 395.234668 -106.424222)
			)
		)
	)
	(zone
		(net "VR_FET_SW_P12V_STBY_PVDDQ_KLM")
		(layer "F.Cu")
		(hatch none 0.5)
		(connect_pads
			(clearance 0.5)
		)
		(min_thickness 0.25)
		(fill yes
			(thermal_gap 0.5)
			(thermal_bridge_width 0.5)
			(island_removal_mode 0)
		)
		(polygon
			(pts
				(xy 11.4046 -132.615686) (xy 11.4046 -131.2164) (xy 12.5222 -130.0988) (xy 12.5222 -129.8448) (xy 12.5222 -129.5654)
				(xy 12.5222 -128.6002) (xy 12.5222 -127.7493) (xy 12.96416 -127.30734) (xy 12.96416 -126.29134)
				(xy 13.00988 -126.24562) (xy 16.43888 -126.24562) (xy 16.57096 -126.3777) (xy 16.57096 -127.862838)
				(xy 16.57096 -128.28905) (xy 15.148306 -129.711704) (xy 15.148306 -133.19252) (xy 15.002764 -133.338062)
				(xy 14.940026 -133.4008) (xy 13.228574 -133.4008) (xy 13.091922 -133.264148) (xy 13.091922 -133.07187)
				(xy 12.712446 -132.692394) (xy 11.481308 -132.692394)
			)
		)
	)
	(zone
		(net "P3V3_STBY")
		(layer "F.Cu")
		(hatch none 0.5)
		(connect_pads
			(clearance 0.5)
		)
		(min_thickness 0.25)
		(fill yes
			(thermal_gap 0.5)
			(thermal_bridge_width 0.5)
			(island_removal_mode 0)
		)
		(polygon
			(pts
				(xy 176.461928 -115.786662) (xy 176.461928 -112.721136) (xy 176.67605 -112.507014) (xy 177.7619 -112.507014)
				(xy 177.899314 -112.644428) (xy 177.899314 -124.640086) (xy 177.899314 -125.656086) (xy 177.3936 -126.1618)
				(xy 175.26 -126.1618) (xy 175.0568 -126.1618) (xy 174.9044 -126.0094) (xy 174.9044 -124.6378) (xy 175.062896 -124.479304)
				(xy 175.062896 -123.4694) (xy 176.439068 -122.093228) (xy 176.61636 -121.915936) (xy 176.61636 -117.973348)
				(xy 176.439068 -117.796056) (xy 176.439068 -115.809522)
			)
		)
	)
	(zone
		(net "SATA6G_S1_RX_C_DP")
		(layer "F.Cu")
		(hatch none 0.5)
		(connect_pads
			(clearance 0.5)
		)
		(min_thickness 0.25)
		(fill yes
			(thermal_gap 0.5)
			(thermal_bridge_width 0.5)
			(island_removal_mode 0)
		)
		(polygon
			(pts
				(arc
					(start 435.333394 -136.344914)
					(mid 434.466746 -136.344914)
					(end 435.333394 -136.344914)
				)
			)
		)
	)
	(zone
		(net "P3V3_STBY")
		(layer "F.Cu")
		(hatch none 0.5)
		(connect_pads
			(clearance 0.5)
		)
		(min_thickness 0.25)
		(fill yes
			(thermal_gap 0.5)
			(thermal_bridge_width 0.5)
			(island_removal_mode 0)
		)
		(polygon
			(pts
				(xy 341.9602 -115.727988) (xy 341.9602 -112.903) (xy 342.056212 -112.806988) (xy 342.1634 -112.6998)
				(xy 342.519762 -112.6998) (xy 342.960452 -113.14049) (xy 342.960452 -113.330736) (xy 343.179654 -113.549938)
				(xy 343.179654 -113.774474) (xy 342.982804 -113.971324) (xy 342.982804 -114.626644) (xy 343.18321 -114.82705)
				(xy 343.18321 -115.034822) (xy 342.982804 -115.235228) (xy 342.982804 -115.884198) (xy 343.1794 -116.080794)
				(xy 343.1794 -116.40693) (xy 343.089992 -116.496592) (xy 342.728804 -116.496592)
			)
		)
	)
	(zone
		(layer "F.Cu")
		(hatch none 0.5)
		(connect_pads
			(clearance 0)
		)
		(min_thickness 0.25)
		(keepout
			(tracks allowed)
			(vias allowed)
			(pads allowed)
			(copperpour allowed)
			(footprints not_allowed)
		)
		(placement
			(enabled no)
			(sheetname "")
		)
		(fill
			(thermal_gap 0.5)
			(thermal_bridge_width 0.5)
			(island_removal_mode 0)
		)
		(polygon
			(pts
				(xy 337.425284 -22.930104) (xy 337.425284 5.999988) (xy 342.325452 5.999988) (xy 342.325452 -22.930104)
			)
		)
	)
	(zone
		(net "P12V_MB0_SW")
		(layer "F.Cu")
		(hatch none 0.5)
		(connect_pads
			(clearance 0.5)
		)
		(min_thickness 0.25)
		(fill yes
			(thermal_gap 0.5)
			(thermal_bridge_width 0.5)
			(island_removal_mode 0)
		)
		(polygon
			(pts
				(xy 11.4554 -67.691) (xy 15.0622 -67.691) (xy 15.24 -67.8688) (xy 18.8722 -67.8688) (xy 19.2278 -67.5132)
				(xy 19.2278 -60.8203) (xy 19.348958 -60.699142) (xy 19.348958 -57.017158) (xy 19.05 -56.7182) (xy 12.057888 -56.7182)
				(xy 10.6934 -58.082688) (xy 10.6934 -64.135) (xy 10.7188 -64.1604) (xy 14.097 -64.1604) (xy 14.3256 -64.389)
				(xy 14.3256 -65.6082) (xy 14.1478 -65.786) (xy 10.795 -65.786) (xy 10.6934 -65.8876) (xy 10.6934 -66.929)
			)
		)
	)
	(zone
		(net "VR_FET_SW_P12V_STBY_PVDDQ_GHJ")
		(layer "F.Cu")
		(hatch none 0.5)
		(connect_pads
			(clearance 0.5)
		)
		(min_thickness 0.25)
		(fill yes
			(thermal_gap 0.5)
			(thermal_bridge_width 0.5)
			(island_removal_mode 0)
		)
		(polygon
			(pts
				(xy -3.03276 -12.37488) (xy -4.25196 -13.59408) (xy -4.25196 -15.597632) (xy -4.25196 -16.559022)
				(xy -3.379216 -17.431766) (xy -1.986026 -17.431766) (xy -1.22174 -16.66748) (xy -1.22174 -13.53566)
				(xy -0.09398 -12.4079) (xy -0.09398 -9.37514) (xy -0.09398 -8.98906) (xy -0.89154 -8.1915) (xy -0.897636 -8.185404)
				(xy -0.903732 -8.179308) (xy -0.903732 -5.779008) (xy -1.1176 -5.56514) (xy -2.66954 -5.56514) (xy -2.85242 -5.56514)
				(xy -3.03276 -5.74548)
			)
		)
	)
	(zone
		(layer "F.Cu")
		(hatch none 0.5)
		(connect_pads
			(clearance 0)
		)
		(min_thickness 0.25)
		(keepout
			(tracks not_allowed)
			(vias allowed)
			(pads allowed)
			(copperpour not_allowed)
			(footprints allowed)
		)
		(placement
			(enabled no)
			(sheetname "")
		)
		(fill
			(thermal_gap 0.5)
			(thermal_bridge_width 0.5)
			(island_removal_mode 0)
		)
		(polygon
			(pts
				(arc
					(start 406.25395 -95.819722)
					(mid 405.926314 -95.403186)
					(end 406.34285 -95.730822)
				)
				(xy 406.434544 -95.822516) (xy 406.523952 -95.822516)
				(arc
					(start 406.523952 -95.592138)
					(mid 406.115139 -95.182944)
					(end 405.706072 -95.591884)
				)
				(arc
					(start 405.706072 -96.607376)
					(mid 406.115012 -97.016316)
					(end 406.523952 -96.607376)
				)
				(xy 406.523952 -96.366584) (xy 406.444958 -96.366584)
				(arc
					(start 406.34285 -96.468438)
					(mid 405.926314 -96.796074)
					(end 406.25395 -96.379538)
				)
				(xy 406.392634 -96.240854) (xy 406.392634 -96.2406) (xy 406.523952 -96.2406) (xy 406.523952 -95.947992)
				(xy 406.38222 -95.947992)
			)
		)
	)
	(zone
		(layer "F.Cu")
		(hatch none 0.5)
		(connect_pads
			(clearance 0)
		)
		(min_thickness 0.25)
		(keepout
			(tracks not_allowed)
			(vias allowed)
			(pads allowed)
			(copperpour not_allowed)
			(footprints allowed)
		)
		(placement
			(enabled no)
			(sheetname "")
		)
		(fill
			(thermal_gap 0.5)
			(thermal_bridge_width 0.5)
			(island_removal_mode 0)
		)
		(polygon
			(pts
				(xy 440.756802 -5.314442) (xy 440.756802 -5.612384) (xy 440.632088 -5.737098)
				(arc
					(start 440.481974 -5.737098)
					(mid 439.958057 -5.667248)
					(end 440.481974 -5.597398)
				)
				(xy 440.574176 -5.597398) (xy 440.617102 -5.554472) (xy 440.617102 -5.372354) (xy 440.528456 -5.283708)
				(arc
					(start 440.224672 -5.283708)
					(mid 439.841132 -5.667248)
					(end 440.224672 -6.050788)
				)
				(arc
					(start 441.494418 -6.050788)
					(mid 441.878212 -5.667375)
					(end 441.494672 -5.283708)
				)
				(xy 441.241688 -5.283708) (xy 441.13196 -5.393436) (xy 441.13196 -5.553202) (xy 441.176156 -5.597398)
				(arc
					(start 441.23737 -5.597398)
					(mid 441.761287 -5.667248)
					(end 441.23737 -5.737098)
				)
				(xy 441.118244 -5.737098) (xy 440.99226 -5.611114) (xy 440.99226 -5.335524) (xy 441.044076 -5.283708)
				(xy 440.726068 -5.283708)
			)
		)
	)
	(zone
		(layer "F.Cu")
		(hatch none 0.5)
		(connect_pads
			(clearance 0)
		)
		(min_thickness 0.25)
		(keepout
			(tracks not_allowed)
			(vias allowed)
			(pads allowed)
			(copperpour not_allowed)
			(footprints allowed)
		)
		(placement
			(enabled no)
			(sheetname "")
		)
		(fill
			(thermal_gap 0.5)
			(thermal_bridge_width 0.5)
			(island_removal_mode 0)
		)
		(polygon
			(pts
				(arc
					(start 495.720116 -32.120078)
					(mid 494.12017 -30.520132)
					(end 495.720116 -28.919932)
				)
				(arc
					(start 497.320062 -28.919932)
					(mid 498.920262 -30.520132)
					(end 497.320062 -32.120078)
				)
			)
		)
	)
	(zone
		(layer "F.Cu")
		(hatch none 0.5)
		(connect_pads
			(clearance 0)
		)
		(min_thickness 0.25)
		(keepout
			(tracks allowed)
			(vias allowed)
			(pads allowed)
			(copperpour allowed)
			(footprints allowed)
		)
		(placement
			(enabled no)
			(sheetname "")
		)
		(fill
			(thermal_gap 0.5)
			(thermal_bridge_width 0.5)
			(island_removal_mode 0)
		)
		(polygon
			(pts
				(xy 363.4994 -140.4366) (xy 361.4166 -140.4366) (xy 361.4166 -139.3444) (xy 363.4994 -139.3444)
			)
		)
	)
	(zone
		(net "P1V05_PCH_STBY")
		(layer "F.Cu")
		(hatch none 0.5)
		(connect_pads
			(clearance 0.5)
		)
		(min_thickness 0.25)
		(fill yes
			(thermal_gap 0.5)
			(thermal_bridge_width 0.5)
			(island_removal_mode 0)
		)
		(polygon
			(pts
				(xy 370.47678 -129.82702) (xy 370.3574 -129.9464) (xy 367.9952 -129.9464) (xy 367.937288 -130.004312)
				(xy 367.937288 -130.777488) (xy 368.0206 -130.8608) (xy 370.1034 -130.8608) (xy 371.436646 -132.194046)
				(xy 374.797828 -132.194046) (xy 375.12371 -132.519928) (xy 376.267472 -132.519928) (xy 377.3424 -131.445)
				(xy 377.3424 -130.7592) (xy 376.41022 -129.82702)
			)
		)
		(polygon
			(pts
				(xy 376.0216 -131.5339) (xy 375.8184 -131.5339) (xy 375.8184 -131.7371) (xy 376.0216 -131.7371)
			)
		)
		(polygon
			(pts
				(xy 375.2596 -131.5339) (xy 375.0564 -131.5339) (xy 375.0564 -131.7371) (xy 375.2596 -131.7371)
			)
		)
		(polygon
			(pts
				(xy 373.761 -131.2037) (xy 373.5578 -131.2037) (xy 373.5578 -131.4069) (xy 373.761 -131.4069)
			)
		)
		(polygon
			(pts
				(xy 372.999 -131.2037) (xy 372.7958 -131.2037) (xy 372.7958 -131.4069) (xy 372.999 -131.4069)
			)
		)
		(polygon
			(pts
				(xy 372.491 -131.2037) (xy 372.2878 -131.2037) (xy 372.2878 -131.4069) (xy 372.491 -131.4069)
			)
		)
		(polygon
			(pts
				(xy 371.729 -131.2037) (xy 371.5258 -131.2037) (xy 371.5258 -131.4069) (xy 371.729 -131.4069)
			)
		)
	)
	(zone
		(layer "F.Cu")
		(hatch none 0.5)
		(connect_pads
			(clearance 0)
		)
		(min_thickness 0.25)
		(keepout
			(tracks allowed)
			(vias allowed)
			(pads allowed)
			(copperpour allowed)
			(footprints allowed)
		)
		(placement
			(enabled no)
			(sheetname "")
		)
		(fill
			(thermal_gap 0.5)
			(thermal_bridge_width 0.5)
			(island_removal_mode 0)
		)
		(polygon
			(pts
				(xy 31.369 -69.469) (xy 33.528 -69.469) (xy 33.528 -71.12) (xy 31.369 -71.12)
			)
		)
	)
	(zone
		(layer "F.Cu")
		(hatch none 0.5)
		(connect_pads
			(clearance 0)
		)
		(min_thickness 0.25)
		(keepout
			(tracks not_allowed)
			(vias allowed)
			(pads allowed)
			(copperpour not_allowed)
			(footprints allowed)
		)
		(placement
			(enabled no)
			(sheetname "")
		)
		(fill
			(thermal_gap 0.5)
			(thermal_bridge_width 0.5)
			(island_removal_mode 0)
		)
		(polygon
			(pts
				(xy 16.531336 -30.84703) (xy 16.68272 -30.998414)
				(arc
					(start 16.68272 -31.170118)
					(mid 16.61287 -31.694035)
					(end 16.54302 -31.170118)
				)
				(xy 16.54302 -31.056326) (xy 16.473424 -30.98673) (xy 16.22933 -30.98673)
				(arc
					(start 16.22933 -31.427166)
					(mid 16.612743 -31.81096)
					(end 16.99641 -31.42742)
				)
				(arc
					(start 16.99641 -30.15742)
					(mid 16.61287 -29.77388)
					(end 16.22933 -30.15742)
				)
				(xy 16.22933 -30.60573) (xy 16.465804 -30.60573) (xy 16.54302 -30.528514)
				(arc
					(start 16.54302 -30.414722)
					(mid 16.61287 -29.890805)
					(end 16.68272 -30.414722)
				)
				(xy 16.68272 -30.586426) (xy 16.523716 -30.74543) (xy 16.22933 -30.74543) (xy 16.22933 -30.84703)
			)
		)
	)
	(zone
		(layer "F.Cu")
		(hatch none 0.5)
		(connect_pads
			(clearance 0)
		)
		(min_thickness 0.25)
		(keepout
			(tracks allowed)
			(vias allowed)
			(pads allowed)
			(copperpour allowed)
			(footprints allowed)
		)
		(placement
			(enabled no)
			(sheetname "")
		)
		(fill
			(thermal_gap 0.5)
			(thermal_bridge_width 0.5)
			(island_removal_mode 0)
		)
		(polygon
			(pts
				(xy 227.203 -29.591) (xy 227.203 -27.559) (xy 229.362 -27.559) (xy 229.362 -29.591)
			)
		)
	)
	(zone
		(net "PVDDQ_DEF")
		(layer "F.Cu")
		(hatch none 0.5)
		(connect_pads
			(clearance 0.5)
		)
		(min_thickness 0.25)
		(fill yes
			(thermal_gap 0.5)
			(thermal_bridge_width 0.5)
			(island_removal_mode 0)
		)
		(polygon
			(pts
				(xy 329.6158 -155.065984) (xy 329.6158 -153.3652) (xy 329.9206 -153.0604) (xy 331.597 -153.0604)
				(xy 331.9272 -152.7302) (xy 331.9272 -149.2504) (xy 331.6478 -148.971) (xy 330.327 -148.971) (xy 330.237338 -148.881338)
				(xy 330.237338 -147.915884) (xy 328.676 -146.354546) (xy 328.676 -142.494) (xy 328.676 -140.3604)
				(xy 328.676 -139.8778) (xy 329.5142 -139.0396) (xy 335.3562 -139.0396) (xy 335.8134 -139.0396) (xy 336.6135 -139.8397)
				(xy 336.6135 -140.2969) (xy 336.6135 -143.0655) (xy 337.54695 -143.99895) (xy 337.54695 -155.44165)
				(xy 337.54695 -155.74645) (xy 337.025234 -156.268166) (xy 332.274672 -156.268166) (xy 331.848206 -155.8417)
				(xy 331.8256 -155.8417) (xy 330.391516 -155.8417)
			)
		)
	)
	(zone
		(net "P12V_HDD_SATA")
		(layer "F.Cu")
		(hatch none 0.5)
		(connect_pads
			(clearance 0.5)
		)
		(min_thickness 0.25)
		(fill yes
			(thermal_gap 0.5)
			(thermal_bridge_width 0.5)
			(island_removal_mode 0)
		)
		(polygon
			(pts
				(xy 453.9488 -131.891786) (xy 453.9488 -131.8768) (xy 453.9488 -130.6703) (xy 452.5264 -129.2479)
				(xy 452.5264 -127.9144) (xy 452.5264 -126.2126) (xy 452.0819 -125.7681) (xy 447.3575 -125.7681)
				(xy 447.1543 -125.9713) (xy 447.1543 -127.1524) (xy 447.294 -127.2921) (xy 448.5132 -127.2921) (xy 448.8434 -127.6223)
				(xy 448.8434 -129.893822) (xy 448.935348 -129.98577) (xy 450.378068 -129.98577) (xy 450.534278 -129.82956)
				(xy 451.437756 -129.82956) (xy 451.663562 -130.055366) (xy 451.663562 -130.37312) (xy 451.455282 -130.5814)
				(xy 451.2564 -130.5814) (xy 451.231 -130.6068) (xy 451.231 -132.7404) (xy 451.358 -132.8674) (xy 451.5866 -133.096)
				(xy 452.979282 -133.096) (xy 453.244458 -132.830824) (xy 453.244458 -132.596128)
			)
		)
	)
	(zone
		(layer "F.Cu")
		(hatch none 0.5)
		(connect_pads
			(clearance 0)
		)
		(min_thickness 0.25)
		(keepout
			(tracks not_allowed)
			(vias allowed)
			(pads allowed)
			(copperpour not_allowed)
			(footprints allowed)
		)
		(placement
			(enabled no)
			(sheetname "")
		)
		(fill
			(thermal_gap 0.5)
			(thermal_bridge_width 0.5)
			(island_removal_mode 0)
		)
		(polygon
			(pts
				(arc
					(start 152.999948 -100.449888)
					(mid 151.100028 -98.549968)
					(end 152.999948 -96.650048)
				)
				(arc
					(start 152.999948 -96.650048)
					(mid 154.899868 -98.549968)
					(end 152.999948 -100.449888)
				)
			)
		)
	)
	(zone
		(net "VR_PVCCIN_CPU0_VD12")
		(layer "F.Cu")
		(hatch none 0.5)
		(connect_pads
			(clearance 0.5)
		)
		(min_thickness 0.25)
		(fill yes
			(thermal_gap 0.5)
			(thermal_bridge_width 0.5)
			(island_removal_mode 0)
		)
		(polygon
			(pts
				(xy 181.8132 -73.1774) (xy 181.8894 -73.1012) (xy 182.118 -73.1012) (xy 182.1688 -73.0504) (xy 182.1688 -72.517)
				(xy 182.0672 -72.4154) (xy 181.3306 -72.4154) (xy 181.0512 -72.6948) (xy 180.152802 -72.6948) (xy 180.128926 -72.718676)
				(xy 180.128926 -74.044048) (xy 180.128926 -74.312526) (xy 180.128926 -74.490326) (xy 180.213 -74.5744)
				(xy 181.356 -74.5744) (xy 181.8132 -74.1172)
			)
		)
	)
	(zone
		(layer "F.Cu")
		(hatch none 0.5)
		(connect_pads
			(clearance 0)
		)
		(min_thickness 0.25)
		(keepout
			(tracks allowed)
			(vias allowed)
			(pads allowed)
			(copperpour allowed)
			(footprints allowed)
		)
		(placement
			(enabled no)
			(sheetname "")
		)
		(fill
			(thermal_gap 0.5)
			(thermal_bridge_width 0.5)
			(island_removal_mode 0)
		)
		(polygon
			(pts
				(xy 343.24798 -136.86028) (xy 343.24798 -137.55624) (xy 341.1855 -137.55624) (xy 341.1855 -136.86028)
			)
		)
	)
	(zone
		(layer "F.Cu")
		(hatch none 0.5)
		(connect_pads
			(clearance 0)
		)
		(min_thickness 0.25)
		(keepout
			(tracks allowed)
			(vias allowed)
			(pads allowed)
			(copperpour allowed)
			(footprints allowed)
		)
		(placement
			(enabled no)
			(sheetname "")
		)
		(fill
			(thermal_gap 0.5)
			(thermal_bridge_width 0.5)
			(island_removal_mode 0)
		)
		(polygon
			(pts
				(xy 27.432 -4.191) (xy 27.432 -3.429) (xy 28.321 -3.429) (xy 28.321 -4.191)
			)
		)
	)
	(zone
		(layer "F.Cu")
		(hatch none 0.5)
		(connect_pads
			(clearance 0)
		)
		(min_thickness 0.25)
		(keepout
			(tracks allowed)
			(vias allowed)
			(pads allowed)
			(copperpour allowed)
			(footprints allowed)
		)
		(placement
			(enabled no)
			(sheetname "")
		)
		(fill
			(thermal_gap 0.5)
			(thermal_bridge_width 0.5)
			(island_removal_mode 0)
		)
		(polygon
			(pts
				(xy 350.362266 -79.322676) (xy 350.362266 -77.036676) (xy 352.368866 -77.036676) (xy 352.368866 -79.322676)
			)
		)
	)
	(zone
		(net "AGND_PVPP_GHJ")
		(layer "F.Cu")
		(hatch none 0.5)
		(connect_pads
			(clearance 0.5)
		)
		(min_thickness 0.25)
		(fill yes
			(thermal_gap 0.5)
			(thermal_bridge_width 0.5)
			(island_removal_mode 0)
		)
		(polygon
			(pts
				(xy 172.36694 -8.064754) (xy 174.42815 -8.064754) (xy 174.709582 -7.783322) (xy 174.709582 -6.868668)
				(xy 174.688754 -6.84784) (xy 174.094648 -6.84784) (xy 174.047404 -6.800596) (xy 172.972476 -6.800596)
				(xy 172.303186 -7.469886) (xy 172.303186 -8.001)
			)
		)
	)
	(zone
		(layer "F.Cu")
		(hatch none 0.5)
		(connect_pads
			(clearance 0)
		)
		(min_thickness 0.25)
		(keepout
			(tracks allowed)
			(vias allowed)
			(pads allowed)
			(copperpour allowed)
			(footprints allowed)
		)
		(placement
			(enabled no)
			(sheetname "")
		)
		(fill
			(thermal_gap 0.5)
			(thermal_bridge_width 0.5)
			(island_removal_mode 0)
		)
		(polygon
			(pts
				(xy 178.2318 -8.1026) (xy 181.229 -8.1026) (xy 181.229 -8.5852) (xy 179.4002 -8.5852) (xy 179.4002 -10.6172)
				(xy 178.2318 -10.6172)
			)
		)
	)
	(zone
		(net "P12V")
		(layer "F.Cu")
		(hatch none 0.5)
		(connect_pads
			(clearance 0.5)
		)
		(min_thickness 0.25)
		(fill yes
			(thermal_gap 0.5)
			(thermal_bridge_width 0.5)
			(island_removal_mode 0)
		)
		(polygon
			(pts
				(xy 474.582744 -6.16712) (xy 474.887544 -5.86232) (xy 474.887544 -3.34772) (xy 474.684344 -3.14452)
				(xy 470.645744 -3.14452) (xy 470.64041 -3.14833) (xy 470.224612 -3.14833) (xy 469.825832 -3.54711)
				(xy 469.825832 -3.762248) (xy 469.825832 -8.368538) (xy 469.834214 -8.37692) (xy 470.163144 -8.37692)
				(xy 474.354144 -8.37692) (xy 474.506544 -8.37692) (xy 474.582744 -8.30072)
			)
		)
	)
	(zone
		(layer "F.Cu")
		(hatch none 0.5)
		(connect_pads
			(clearance 0)
		)
		(min_thickness 0.25)
		(keepout
			(tracks not_allowed)
			(vias allowed)
			(pads allowed)
			(copperpour not_allowed)
			(footprints allowed)
		)
		(placement
			(enabled no)
			(sheetname "")
		)
		(fill
			(thermal_gap 0.5)
			(thermal_bridge_width 0.5)
			(island_removal_mode 0)
		)
		(polygon
			(pts
				(arc
					(start 222.000064 -79.090012)
					(mid 219.460064 -76.550012)
					(end 222.000064 -74.010012)
				)
				(arc
					(start 222.000064 -74.010012)
					(mid 224.540064 -76.550012)
					(end 222.000064 -79.090012)
				)
			)
		)
	)
	(zone
		(net "VR_PVNN_PCH_PH1_PHASE_SW")
		(layer "F.Cu")
		(hatch none 0.5)
		(connect_pads
			(clearance 0.5)
		)
		(min_thickness 0.25)
		(fill yes
			(thermal_gap 0.5)
			(thermal_bridge_width 0.5)
			(island_removal_mode 0)
		)
		(polygon
			(pts
				(xy 378.8664 -150.41626) (xy 378.8664 -146.7358) (xy 378.8664 -146.515074) (xy 378.375164 -146.023838)
				(xy 374.968008 -146.023838) (xy 374.868694 -146.023838) (xy 374.809258 -146.023838) (xy 374.593358 -146.239738)
				(xy 374.571514 -146.261582) (xy 374.571514 -149.722586) (xy 374.137682 -150.156418) (xy 374.137682 -150.703534)
				(xy 374.216422 -150.782274) (xy 378.500386 -150.782274)
			)
		)
	)
	(zone
		(net "P3V3_STBY")
		(layer "F.Cu")
		(hatch none 0.5)
		(connect_pads
			(clearance 0.5)
		)
		(min_thickness 0.25)
		(fill yes
			(thermal_gap 0.5)
			(thermal_bridge_width 0.5)
			(island_removal_mode 0)
		)
		(polygon
			(pts
				(xy 405.873204 -92.869004) (xy 405.549862 -93.192346) (xy 405.549862 -94.839028) (xy 405.681688 -94.970854)
				(xy 407.008076 -94.970854) (xy 407.0858 -94.89313) (xy 407.0858 -92.890594) (xy 407.06421 -92.869004)
			)
		)
		(polygon
			(pts
				(xy 406.3111 -93.560392) (xy 406.1079 -93.560392) (xy 406.1079 -93.763592) (xy 406.3111 -93.763592)
			)
		)
		(polygon
			(pts
				(xy 406.3111 -93.992192) (xy 406.1079 -93.992192) (xy 406.1079 -94.195392) (xy 406.3111 -94.195392)
			)
		)
	)
	(zone
		(layer "F.Cu")
		(hatch none 0.5)
		(connect_pads
			(clearance 0)
		)
		(min_thickness 0.25)
		(keepout
			(tracks allowed)
			(vias allowed)
			(pads allowed)
			(copperpour allowed)
			(footprints not_allowed)
		)
		(placement
			(enabled no)
			(sheetname "")
		)
		(fill
			(thermal_gap 0.5)
			(thermal_bridge_width 0.5)
			(island_removal_mode 0)
		)
		(polygon
			(pts
				(xy 193.707512 -33.1978) (xy 161.247328 -33.1978) (xy 161.247328 -119.823992) (xy 193.707512 -119.823992)
				(xy 193.707512 -111.05007) (xy 194.429888 -111.05007) (xy 194.429888 -42.049954) (xy 193.707512 -42.049954)
			)
		)
	)
	(zone
		(net "VR_P3V3_STBY_PHASE")
		(layer "F.Cu")
		(hatch none 0.5)
		(connect_pads
			(clearance 0.5)
		)
		(min_thickness 0.25)
		(fill yes
			(thermal_gap 0.5)
			(thermal_bridge_width 0.5)
			(island_removal_mode 0)
		)
		(polygon
			(pts
				(xy 474.525848 -12.449048) (xy 473.7608 -11.684) (xy 471.070686 -11.684) (xy 471.070686 -18.819114)
				(xy 470.998804 -18.890996) (xy 470.74201 -19.14779) (xy 470.74201 -20.72767) (xy 470.853516 -20.839176)
				(xy 474.357192 -20.839176) (xy 474.525848 -20.67052)
			)
		)
	)
	(zone
		(net "P3V3_STBY")
		(layer "F.Cu")
		(hatch none 0.5)
		(connect_pads
			(clearance 0.5)
		)
		(min_thickness 0.25)
		(fill yes
			(thermal_gap 0.5)
			(thermal_bridge_width 0.5)
			(island_removal_mode 0)
		)
		(polygon
			(pts
				(xy 386.366258 -86.392258) (xy 386.269484 -86.295484) (xy 386.269484 -85.925914) (xy 386.06857 -85.725)
				(xy 385.8768 -85.725) (xy 384.8608 -86.741) (xy 383.286 -86.741) (xy 382.778 -86.233) (xy 382.143 -86.233)
				(xy 381.996442 -86.379558) (xy 381.996442 -87.54618) (xy 381.996696 -87.546434) (xy 382.016508 -87.566246)
				(xy 386.333238 -87.566246) (xy 386.366258 -87.533226)
			)
		)
	)
	(zone
		(layer "F.Cu")
		(hatch none 0.5)
		(connect_pads
			(clearance 0)
		)
		(min_thickness 0.25)
		(keepout
			(tracks allowed)
			(vias allowed)
			(pads allowed)
			(copperpour allowed)
			(footprints not_allowed)
		)
		(placement
			(enabled no)
			(sheetname "")
		)
		(fill
			(thermal_gap 0.5)
			(thermal_bridge_width 0.5)
			(island_removal_mode 0)
		)
		(polygon
			(pts
				(xy 19.524726 -159.100012) (xy 19.524726 -130.16992) (xy 14.524736 -130.16992) (xy 14.524736 -159.100012)
			)
		)
	)
	(zone
		(layer "F.Cu")
		(hatch none 0.5)
		(connect_pads
			(clearance 0)
		)
		(min_thickness 0.25)
		(keepout
			(tracks allowed)
			(vias allowed)
			(pads allowed)
			(copperpour allowed)
			(footprints not_allowed)
		)
		(placement
			(enabled no)
			(sheetname "")
		)
		(fill
			(thermal_gap 0.5)
			(thermal_bridge_width 0.5)
			(island_removal_mode 0)
		)
		(polygon
			(pts
				(xy 426.20057 -51.676808) (xy 426.20057 -44.676822) (xy 430.950624 -44.676822) (xy 430.950624 -51.676808)
			)
		)
	)
	(zone
		(layer "F.Cu")
		(hatch none 0.5)
		(connect_pads
			(clearance 0)
		)
		(min_thickness 0.25)
		(keepout
			(tracks allowed)
			(vias allowed)
			(pads allowed)
			(copperpour allowed)
			(footprints not_allowed)
		)
		(placement
			(enabled no)
			(sheetname "")
		)
		(fill
			(thermal_gap 0.5)
			(thermal_bridge_width 0.5)
			(island_removal_mode 0)
		)
		(polygon
			(pts
				(xy 28.699968 -23.50008) (xy 16.949928 -23.50008) (xy 16.949928 -29.420058) (xy 28.699968 -29.420058)
			)
		)
	)
	(zone
		(layer "F.Cu")
		(hatch none 0.5)
		(connect_pads
			(clearance 0)
		)
		(min_thickness 0.25)
		(keepout
			(tracks allowed)
			(vias allowed)
			(pads allowed)
			(copperpour allowed)
			(footprints allowed)
		)
		(placement
			(enabled no)
			(sheetname "")
		)
		(fill
			(thermal_gap 0.5)
			(thermal_bridge_width 0.5)
			(island_removal_mode 0)
		)
		(polygon
			(pts
				(xy 340.995 -28.067) (xy 340.995 -26.035) (xy 343.154 -26.035) (xy 343.154 -28.067)
			)
		)
	)
	(zone
		(net "GND")
		(layer "F.Cu")
		(hatch none 0.5)
		(connect_pads
			(clearance 0.5)
		)
		(min_thickness 0.25)
		(fill yes
			(thermal_gap 0.5)
			(thermal_bridge_width 0.5)
			(island_removal_mode 0)
		)
		(polygon
			(pts
				(xy 442.038994 -40.259508) (xy 443.529466 -40.259508) (xy 443.702694 -40.432736) (xy 443.702694 -42.996358)
				(xy 443.58941 -43.109642) (xy 442.10986 -43.109642) (xy 442.02731 -43.109642) (xy 441.836048 -42.91838)
				(xy 441.836048 -42.835576) (xy 441.836048 -40.462454)
			)
		)
	)
	(zone
		(layer "F.Cu")
		(hatch none 0.5)
		(connect_pads
			(clearance 0)
		)
		(min_thickness 0.25)
		(keepout
			(tracks allowed)
			(vias allowed)
			(pads allowed)
			(copperpour allowed)
			(footprints not_allowed)
		)
		(placement
			(enabled no)
			(sheetname "")
		)
		(fill
			(thermal_gap 0.5)
			(thermal_bridge_width 0.5)
			(island_removal_mode 0)
		)
		(polygon
			(pts
				(arc
					(start 198.930006 -44.99991)
					(mid 200.480168 -46.550072)
					(end 198.930006 -48.09998)
				)
				(arc
					(start 198.930006 -48.09998)
					(mid 197.380098 -46.550072)
					(end 198.930006 -44.99991)
				)
			)
		)
	)
	(zone
		(layer "F.Cu")
		(hatch none 0.5)
		(connect_pads
			(clearance 0)
		)
		(min_thickness 0.25)
		(keepout
			(tracks allowed)
			(vias allowed)
			(pads allowed)
			(copperpour allowed)
			(footprints not_allowed)
		)
		(placement
			(enabled no)
			(sheetname "")
		)
		(fill
			(thermal_gap 0.5)
			(thermal_bridge_width 0.5)
			(island_removal_mode 0)
		)
		(polygon
			(pts
				(arc
					(start 248.000012 -114.089942)
					(mid 245.460012 -111.549942)
					(end 248.000012 -109.009942)
				)
				(arc
					(start 248.000012 -109.009942)
					(mid 250.540012 -111.549942)
					(end 248.000012 -114.089942)
				)
			)
		)
	)
	(zone
		(layer "F.Cu")
		(hatch none 0.5)
		(connect_pads
			(clearance 0)
		)
		(min_thickness 0.25)
		(keepout
			(tracks allowed)
			(vias allowed)
			(pads allowed)
			(copperpour allowed)
			(footprints allowed)
		)
		(placement
			(enabled no)
			(sheetname "")
		)
		(fill
			(thermal_gap 0.5)
			(thermal_bridge_width 0.5)
			(island_removal_mode 0)
		)
		(polygon
			(pts
				(xy -0.7366 -145.7706) (xy 1.5494 -145.7706) (xy 1.5494 -147.7772) (xy -0.7366 -147.7772)
			)
		)
	)
	(zone
		(layer "F.Cu")
		(hatch none 0.5)
		(connect_pads
			(clearance 0)
		)
		(min_thickness 0.25)
		(keepout
			(tracks not_allowed)
			(vias allowed)
			(pads allowed)
			(copperpour not_allowed)
			(footprints allowed)
		)
		(placement
			(enabled no)
			(sheetname "")
		)
		(fill
			(thermal_gap 0.5)
			(thermal_bridge_width 0.5)
			(island_removal_mode 0)
		)
		(polygon
			(pts
				(arc
					(start 431.888646 -138.461242)
					(mid 431.504852 -138.844655)
					(end 431.888392 -139.228322)
				)
				(xy 432.332892 -139.228322)
				(arc
					(start 432.332892 -139.1666)
					(mid 432.279962 -139.012095)
					(end 432.143408 -138.922506)
				)
				(arc
					(start 432.143408 -138.922506)
					(mid 431.621819 -138.837287)
					(end 432.147218 -138.78052)
				)
				(arc
					(start 432.147218 -138.78052)
					(mid 432.370552 -138.902842)
					(end 432.471322 -139.136628)
				)
				(xy 432.472592 -139.137644) (xy 432.472592 -139.228322) (xy 432.574192 -139.228322) (xy 432.574192 -139.137644)
				(arc
					(start 432.575462 -139.136628)
					(mid 432.676368 -138.902966)
					(end 432.899566 -138.78052)
				)
				(arc
					(start 432.899566 -138.78052)
					(mid 433.424917 -138.837289)
					(end 432.903376 -138.922506)
				)
				(arc
					(start 432.903376 -138.922506)
					(mid 432.766825 -139.012097)
					(end 432.713892 -139.1666)
				)
				(xy 432.713892 -139.228322)
				(arc
					(start 433.158392 -139.228322)
					(mid 433.541932 -138.844782)
					(end 433.158392 -138.461242)
				)
			)
		)
	)
	(zone
		(net "GND")
		(layer "F.Cu")
		(hatch none 0.5)
		(connect_pads
			(clearance 0.5)
		)
		(min_thickness 0.25)
		(fill yes
			(thermal_gap 0.5)
			(thermal_bridge_width 0.5)
			(island_removal_mode 0)
		)
		(polygon
			(pts
				(xy 278.944832 -14.387322) (xy 278.327612 -13.770102) (xy 278.327612 -12.036044) (xy 278.868378 -11.495278)
				(xy 279.695656 -11.495278) (xy 280.152348 -11.95197) (xy 280.152348 -12.827) (xy 280.3398 -13.014452)
				(xy 280.3398 -13.0302) (xy 280.3652 -13.0556) (xy 280.6954 -13.0556) (xy 280.7208 -13.081) (xy 280.7208 -13.589)
				(xy 280.539444 -13.770356) (xy 280.152348 -13.770356) (xy 280.13152 -13.770356) (xy 280.129996 -13.768832)
				(xy 279.917398 -13.556234) (xy 279.51938 -13.556234) (xy 279.320244 -13.75537) (xy 279.30856 -13.767054)
				(xy 279.30856 -14.333728) (xy 279.254966 -14.387322)
			)
		)
	)
	(zone
		(layer "F.Cu")
		(hatch none 0.5)
		(connect_pads
			(clearance 0)
		)
		(min_thickness 0.25)
		(keepout
			(tracks allowed)
			(vias allowed)
			(pads allowed)
			(copperpour allowed)
			(footprints not_allowed)
		)
		(placement
			(enabled no)
			(sheetname "")
		)
		(fill
			(thermal_gap 0.5)
			(thermal_bridge_width 0.5)
			(island_removal_mode 0)
		)
		(polygon
			(pts
				(xy 22.52472 -14.519148) (xy 22.52472 -11.317986) (xy 163.524692 -11.317986) (xy 163.524692 -14.519148)
			)
		)
	)
	(zone
		(net "PVDDQ_KLM")
		(layer "F.Cu")
		(hatch none 0.5)
		(connect_pads
			(clearance 0.5)
		)
		(min_thickness 0.25)
		(fill yes
			(thermal_gap 0.5)
			(thermal_bridge_width 0.5)
			(island_removal_mode 0)
		)
		(polygon
			(pts
				(xy 92.76842 -148.47824) (xy 92.46108 -148.78558) (xy 92.46108 -150.30196) (xy 93.19768 -151.03856)
				(xy 93.58122 -151.03856) (xy 93.63964 -150.98014) (xy 93.63964 -150.50262) (xy 93.8403 -150.30196)
				(xy 94.69628 -150.30196) (xy 94.82582 -150.17242) (xy 94.82582 -148.98624) (xy 94.31782 -148.47824)
			)
		)
		(polygon
			(pts
				(xy 93.457268 -150.2029) (xy 93.254068 -150.2029) (xy 93.254068 -150.4061) (xy 93.457268 -150.4061)
			)
		)
		(polygon
			(pts
				(xy 93.457268 -149.2123) (xy 93.254068 -149.2123) (xy 93.254068 -149.4155) (xy 93.457268 -149.4155)
			)
		)
	)
	(zone
		(net "VR_PVDDQ_GHJ_PH2_BOOT")
		(layer "F.Cu")
		(hatch none 0.5)
		(connect_pads
			(clearance 0.5)
		)
		(min_thickness 0.25)
		(fill yes
			(thermal_gap 0.5)
			(thermal_bridge_width 0.5)
			(island_removal_mode 0)
		)
		(polygon
			(pts
				(xy -0.0762 -19.4818) (xy -0.0762 -18.8214) (xy -0.0762 -18.7198) (xy 0.0254 -18.6182) (xy 0.127 -18.6182)
				(xy 0.16256 -18.58264) (xy 0.16256 -17.81556) (xy 0.1016 -17.7546) (xy -0.6858 -17.7546) (xy -0.7874 -17.8562)
				(xy -0.7874 -19.3802) (xy -0.6604 -19.5072) (xy -0.624586 -19.543014) (xy -0.112268 -19.543014)
				(xy -0.0762 -19.506946)
			)
		)
	)
	(zone
		(net "GND")
		(layer "F.Cu")
		(hatch none 0.5)
		(connect_pads
			(clearance 0.5)
		)
		(min_thickness 0.25)
		(fill yes
			(thermal_gap 0.5)
			(thermal_bridge_width 0.5)
			(island_removal_mode 0)
		)
		(polygon
			(pts
				(xy 76.921868 -150.967948) (xy 78.338426 -150.967948) (xy 78.48092 -150.825454) (xy 78.48092 -148.709126)
				(xy 78.260956 -148.489162) (xy 77.024992 -148.489162) (xy 76.076556 -148.489162) (xy 76.009754 -148.555964)
				(xy 76.009754 -149.68982) (xy 76.766166 -150.446232) (xy 76.846684 -150.52675) (xy 76.853034 -150.5331)
				(xy 76.853034 -150.899114)
			)
		)
	)
	(zone
		(net "GND")
		(layer "F.Cu")
		(hatch none 0.5)
		(connect_pads
			(clearance 0.5)
		)
		(min_thickness 0.25)
		(fill yes
			(thermal_gap 0.5)
			(thermal_bridge_width 0.5)
			(island_removal_mode 0)
		)
		(polygon
			(pts
				(xy 413.6517 -88.21674) (xy 415.65322 -88.21674) (xy 415.69894 -88.17102) (xy 415.69894 -86.14156)
				(xy 415.66846 -86.11108) (xy 413.64662 -86.11108) (xy 413.60598 -86.15172) (xy 413.60598 -88.17102)
			)
		)
	)
	(zone
		(net "VR_PVCCIN_CPU1_PHASE5")
		(layer "F.Cu")
		(hatch none 0.5)
		(connect_pads
			(clearance 0.5)
		)
		(min_thickness 0.25)
		(fill yes
			(thermal_gap 0.5)
			(thermal_bridge_width 0.5)
			(island_removal_mode 0)
		)
		(polygon
			(pts
				(xy 41.745154 -91.985846) (xy 41.9608 -91.7702) (xy 41.9608 -87.6046) (xy 41.458388 -87.102188)
				(xy 36.490148 -87.102188) (xy 36.449 -87.143336) (xy 36.449 -91.835224) (xy 36.599622 -91.985846)
			)
		)
	)
	(zone
		(net "VR_PVCCIO_CPU1_VDD")
		(layer "F.Cu")
		(hatch none 0.5)
		(connect_pads
			(clearance 0.5)
		)
		(min_thickness 0.25)
		(fill yes
			(thermal_gap 0.5)
			(thermal_bridge_width 0.5)
			(island_removal_mode 0)
		)
		(polygon
			(pts
				(xy 173.0502 -68.1228) (xy 173.4566 -68.5292) (xy 173.9392 -68.5292) (xy 173.99 -68.58) (xy 173.99 -70.8406)
				(xy 173.8884 -70.9422) (xy 173.0502 -70.9422) (xy 172.7708 -70.6628) (xy 172.7708 -69.1134) (xy 172.4914 -68.834)
				(xy 172.4914 -68.5038) (xy 172.28185 -68.29425) (xy 171.39285 -68.29425) (xy 171.3738 -68.2752)
				(xy 171.323 -68.2244) (xy 171.323 -68.1736) (xy 171.3738 -68.1228) (xy 171.3992 -68.0974) (xy 173.0248 -68.0974)
			)
		)
	)
	(zone
		(net "GND")
		(layer "F.Cu")
		(hatch none 0.5)
		(connect_pads
			(clearance 0.5)
		)
		(min_thickness 0.25)
		(fill yes
			(thermal_gap 0.5)
			(thermal_bridge_width 0.5)
			(island_removal_mode 0)
		)
		(polygon
			(pts
				(xy 277.622 -18.923) (xy 280.035 -18.923) (xy 280.035 -17.78) (xy 279.146 -16.891) (xy 278.511 -16.891)
				(xy 278.257 -17.145) (xy 277.749 -17.145) (xy 265.790934 -17.145) (xy 265.733022 -17.145) (xy 265.6967 -17.181322)
				(xy 265.6967 -17.24406) (xy 265.6967 -17.772126) (xy 265.748262 -17.823688) (xy 271.722088 -17.823688)
				(xy 271.9324 -18.034) (xy 272.1864 -18.288) (xy 277.368 -18.288) (xy 277.622 -18.542)
			)
		)
	)
	(zone
		(layer "F.Cu")
		(hatch none 0.5)
		(connect_pads
			(clearance 0)
		)
		(min_thickness 0.25)
		(keepout
			(tracks allowed)
			(vias allowed)
			(pads allowed)
			(copperpour allowed)
			(footprints not_allowed)
		)
		(placement
			(enabled no)
			(sheetname "")
		)
		(fill
			(thermal_gap 0.5)
			(thermal_bridge_width 0.5)
			(island_removal_mode 0)
		)
		(polygon
			(pts
				(arc
					(start 474.49994 5.999988)
					(mid 478.499932 1.999996)
					(end 474.49994 -1.999996)
				)
				(arc
					(start 471.000074 -1.999996)
					(mid 467.000082 1.999996)
					(end 471.000074 5.999988)
				)
			)
		)
	)
	(zone
		(layer "F.Cu")
		(hatch none 0.5)
		(connect_pads
			(clearance 0)
		)
		(min_thickness 0.25)
		(keepout
			(tracks allowed)
			(vias allowed)
			(pads allowed)
			(copperpour allowed)
			(footprints allowed)
		)
		(placement
			(enabled no)
			(sheetname "")
		)
		(fill
			(thermal_gap 0.5)
			(thermal_bridge_width 0.5)
			(island_removal_mode 0)
		)
		(polygon
			(pts
				(xy 324.8914 -122.0343) (xy 322.6054 -122.0343) (xy 322.6054 -120.0277) (xy 324.8914 -120.0277)
			)
		)
	)
	(zone
		(layer "F.Cu")
		(hatch none 0.5)
		(connect_pads
			(clearance 0)
		)
		(min_thickness 0.25)
		(keepout
			(tracks not_allowed)
			(vias allowed)
			(pads allowed)
			(copperpour not_allowed)
			(footprints allowed)
		)
		(placement
			(enabled no)
			(sheetname "")
		)
		(fill
			(thermal_gap 0.5)
			(thermal_bridge_width 0.5)
			(island_removal_mode 0)
		)
		(polygon
			(pts
				(xy 421.540686 -3.789172) (xy 421.807386 -3.789172) (xy 421.807386 -4.982972) (xy 421.540686 -4.982972)
			)
		)
	)
	(zone
		(layer "F.Cu")
		(hatch none 0.5)
		(connect_pads
			(clearance 0)
		)
		(min_thickness 0.25)
		(keepout
			(tracks not_allowed)
			(vias allowed)
			(pads allowed)
			(copperpour not_allowed)
			(footprints allowed)
		)
		(placement
			(enabled no)
			(sheetname "")
		)
		(fill
			(thermal_gap 0.5)
			(thermal_bridge_width 0.5)
			(island_removal_mode 0)
		)
		(polygon
			(pts
				(xy 376.334274 -3.320542) (xy 376.334274 -3.046476) (xy 376.513598 -2.867152)
				(arc
					(start 376.712988 -2.867152)
					(mid 377.236905 -2.937002)
					(end 376.712988 -3.006852)
				)
				(xy 376.57151 -3.006852) (xy 376.473974 -3.104388) (xy 376.473974 -3.320542)
				(arc
					(start 376.970036 -3.320542)
					(mid 377.35383 -2.937129)
					(end 376.97029 -2.553462)
				)
				(arc
					(start 375.70029 -2.553462)
					(mid 375.31675 -2.937002)
					(end 375.70029 -3.320542)
				)
				(xy 376.092974 -3.320542) (xy 376.092974 -3.080512) (xy 376.019314 -3.006852)
				(arc
					(start 375.957592 -3.006852)
					(mid 375.433675 -2.937002)
					(end 375.957592 -2.867152)
				)
				(xy 376.077226 -2.867152) (xy 376.232674 -3.0226) (xy 376.232674 -3.320542)
			)
		)
	)
	(zone
		(net "PVDDQ_GHJ")
		(layer "F.Cu")
		(hatch none 0.5)
		(connect_pads
			(clearance 0.5)
		)
		(min_thickness 0.25)
		(fill yes
			(thermal_gap 0.5)
			(thermal_bridge_width 0.5)
			(island_removal_mode 0)
		)
		(polygon
			(pts
				(xy 100.838 0.0762) (xy 100.7872 0.0254) (xy 100.7872 -2.516632) (xy 100.988368 -2.7178) (xy 100.988368 -3.864864)
				(xy 101.082094 -3.95859) (xy 101.264212 -3.95859) (xy 101.48824 -4.182618) (xy 101.48824 -4.690872)
				(xy 101.5746 -4.777232) (xy 101.5746 -5.9436) (xy 101.727 -6.096) (xy 102.1588 -6.096) (xy 102.3112 -5.9436)
				(xy 102.3112 -4.9022) (xy 102.3112 -4.89458) (xy 102.413816 -4.791964) (xy 102.421436 -4.791964)
				(xy 104.042718 -4.791964) (xy 104.1654 -4.914646) (xy 104.1654 -4.9784) (xy 104.1654 -5.9436) (xy 104.3178 -6.096)
				(xy 104.7496 -6.096) (xy 104.902 -5.9436) (xy 104.902 -4.9022) (xy 104.902 -4.85775) (xy 104.966262 -4.793488)
				(xy 105.734358 -4.793488) (xy 105.8672 -4.92633) (xy 105.8672 -4.953) (xy 105.8672 -5.969) (xy 105.9942 -6.096)
				(xy 106.426 -6.096) (xy 106.553 -5.969) (xy 106.553 -4.9276) (xy 106.553 -4.890262) (xy 106.627422 -4.81584)
				(xy 106.64952 -4.793742) (xy 108.28909 -4.793742) (xy 108.311188 -4.81584) (xy 108.3818 -4.886452)
				(xy 108.3818 -4.9276) (xy 108.3818 -5.9436) (xy 108.5596 -6.1214) (xy 108.9406 -6.1214) (xy 109.093 -5.969)
				(xy 109.093 -4.9022) (xy 109.1692 -4.826) (xy 109.205776 -4.789424) (xy 109.996224 -4.789424) (xy 110.0328 -4.826)
				(xy 110.109 -4.9022) (xy 110.109 -5.9182) (xy 110.2868 -6.096) (xy 110.617 -6.096) (xy 110.7694 -5.9436)
				(xy 110.7694 -4.953) (xy 110.7694 -4.914646) (xy 110.86719 -4.816856) (xy 110.890812 -4.793234)
				(xy 111.753142 -4.793234) (xy 111.782606 -4.822698) (xy 111.8362 -4.876292) (xy 111.8362 -4.9784)
				(xy 111.8362 -5.969) (xy 111.9886 -6.1214) (xy 112.3442 -6.1214) (xy 112.546384 -5.919216) (xy 112.546384 -4.647184)
				(xy 112.748568 -4.445) (xy 112.748568 -2.286) (xy 112.432084 -1.969516) (xy 111.697516 -1.969516)
				(xy 111.5568 -1.8288) (xy 110.1598 -1.8288) (xy 109.9566 -1.6256) (xy 109.9566 -0.762) (xy 109.7534 -0.5588)
				(xy 109.4232 -0.5588) (xy 109.22 -0.762) (xy 109.22 -1.7272) (xy 109.1184 -1.8288) (xy 108.331 -1.8288)
				(xy 108.331 -0.762) (xy 108.1278 -0.5588) (xy 107.6706 -0.5588) (xy 107.4928 -0.7366) (xy 107.4928 -1.778)
				(xy 107.442 -1.8288) (xy 106.6546 -1.8288) (xy 106.5784 -1.7526) (xy 106.5784 -0.6604) (xy 106.4006 -0.4826)
				(xy 106.045 -0.4826) (xy 105.8418 -0.6858) (xy 105.8418 -1.778) (xy 105.791 -1.8288) (xy 104.1146 -1.8288)
				(xy 104.013 -1.7272) (xy 104.013 -0.4064) (xy 103.9114 -0.3048) (xy 103.4796 -0.3048) (xy 103.3272 -0.4572)
				(xy 103.3272 -1.6764) (xy 103.1748 -1.8288) (xy 101.5746 -1.8288) (xy 101.4222 -1.6764) (xy 101.4222 0)
				(xy 101.346 0.0762)
			)
		)
		(polygon
			(pts
				(xy 110.657132 -3.7465) (xy 110.453932 -3.7465) (xy 110.453932 -3.9497) (xy 110.657132 -3.9497)
			)
		)
		(polygon
			(pts
				(xy 107.5182 -3.7465) (xy 107.315 -3.7465) (xy 107.315 -3.9497) (xy 107.5182 -3.9497)
			)
		)
		(polygon
			(pts
				(xy 104.2162 -3.7465) (xy 104.013 -3.7465) (xy 104.013 -3.9497) (xy 104.2162 -3.9497)
			)
		)
		(polygon
			(pts
				(xy 107.5182 -2.7559) (xy 107.315 -2.7559) (xy 107.315 -2.9591) (xy 107.5182 -2.9591)
			)
		)
		(polygon
			(pts
				(xy 104.2162 -2.7559) (xy 104.013 -2.7559) (xy 104.013 -2.9591) (xy 104.2162 -2.9591)
			)
		)
	)
	(zone
		(layer "F.Cu")
		(hatch none 0.5)
		(connect_pads
			(clearance 0)
		)
		(min_thickness 0.25)
		(keepout
			(tracks allowed)
			(vias allowed)
			(pads allowed)
			(copperpour allowed)
			(footprints allowed)
		)
		(placement
			(enabled no)
			(sheetname "")
		)
		(fill
			(thermal_gap 0.5)
			(thermal_bridge_width 0.5)
			(island_removal_mode 0)
		)
		(polygon
			(pts
				(xy 461.809338 -146.452336) (xy 464.692238 -146.452336) (xy 465.055458 -146.089116) (xy 465.055458 -145.259806)
				(xy 464.763104 -144.967452) (xy 461.927956 -144.967452) (xy 461.659224 -145.236184) (xy 461.659224 -146.302222)
			)
		)
	)
	(zone
		(layer "F.Cu")
		(hatch none 0.5)
		(connect_pads
			(clearance 0)
		)
		(min_thickness 0.25)
		(keepout
			(tracks allowed)
			(vias allowed)
			(pads allowed)
			(copperpour allowed)
			(footprints allowed)
		)
		(placement
			(enabled no)
			(sheetname "")
		)
		(fill
			(thermal_gap 0.5)
			(thermal_bridge_width 0.5)
			(island_removal_mode 0)
		)
		(polygon
			(pts
				(xy 66.901568 -60.132722) (xy 65.493392 -60.132722) (xy 65.127124 -59.766454) (xy 65.127124 -54.102)
				(xy 65.123568 -54.098444) (xy 65.123568 -53.34) (xy 68.679568 -49.784) (xy 75.283568 -49.784) (xy 75.410568 -49.911)
				(xy 76.172568 -49.911) (xy 81.379568 -49.911) (xy 86.205568 -49.911) (xy 86.205568 -49.657) (xy 116.558568 -49.657)
				(xy 116.558568 -49.53) (xy 116.939568 -49.149) (xy 116.939568 -48.514) (xy 117.955568 -47.498) (xy 119.479568 -47.498)
				(xy 122.565668 -50.5841) (xy 122.819668 -50.5841) (xy 124.295154 -49.108614) (xy 127.531368 -49.108614)
				(xy 127.787146 -49.364392) (xy 128.179068 -49.364392) (xy 135.395716 -49.364392) (xy 136.17067 -50.1396)
				(xy 139.672568 -50.1396) (xy 139.672568 -50.038) (xy 141.196568 -48.514) (xy 144.752568 -48.514)
				(xy 147.165568 -50.927) (xy 147.165568 -55.4228) (xy 145.692368 -56.896) (xy 145.692368 -64.7446)
				(xy 146.606768 -65.659) (xy 146.606768 -66.7258) (xy 146.603974 -66.7258) (xy 145.333974 -67.9958)
				(xy 145.333974 -100.129594) (xy 138.275568 -107.188) (xy 134.719568 -103.632) (xy 134.465568 -103.886)
				(xy 117.828568 -103.886) (xy 117.828568 -105.029) (xy 117.828568 -106.045) (xy 113.129568 -106.045)
				(xy 113.002568 -106.045) (xy 113.002568 -106.807) (xy 105.763568 -106.807) (xy 105.763568 -106.172)
				(xy 105.763568 -102.235) (xy 82.395568 -102.235) (xy 82.395568 -102.743) (xy 81.125568 -102.743)
				(xy 80.236568 -103.632) (xy 80.109568 -103.632) (xy 79.474568 -102.997) (xy 78.839568 -102.997)
				(xy 78.331568 -102.489) (xy 75.664568 -102.489) (xy 75.664568 -101.981) (xy 67.409568 -101.981)
				(xy 67.409568 -101.346) (xy 66.901568 -101.346) (xy 66.901568 -89.051638)
			)
		)
	)
	(zone
		(net "GND")
		(layer "F.Cu")
		(hatch none 0.5)
		(connect_pads
			(clearance 0.5)
		)
		(min_thickness 0.25)
		(fill yes
			(thermal_gap 0.5)
			(thermal_bridge_width 0.5)
			(island_removal_mode 0)
		)
		(polygon
			(pts
				(xy 243.225828 -14.385544) (xy 242.003326 -14.385544) (xy 241.84102 -14.223492) (xy 241.84102 -13.65758)
				(xy 241.828574 -13.645134) (xy 241.075464 -12.892024) (xy 241.075464 -11.734038) (xy 241.331242 -11.47826)
				(xy 242.0112 -11.47826) (xy 242.01628 -11.472926) (xy 243.219732 -11.472926) (xy 243.407438 -11.660632)
				(xy 243.407438 -14.203934)
			)
		)
	)
	(zone
		(layer "F.Cu")
		(hatch none 0.5)
		(connect_pads
			(clearance 0)
		)
		(min_thickness 0.25)
		(keepout
			(tracks allowed)
			(vias allowed)
			(pads allowed)
			(copperpour allowed)
			(footprints allowed)
		)
		(placement
			(enabled no)
			(sheetname "")
		)
		(fill
			(thermal_gap 0.5)
			(thermal_bridge_width 0.5)
			(island_removal_mode 0)
		)
		(polygon
			(pts
				(xy 243.332 -45.72) (xy 246.507 -48.895) (xy 246.507 -49.784) (xy 246.507 -49.911) (xy 250.444 -49.911)
				(xy 250.444 -49.784) (xy 250.444 -47.371) (xy 250.444 -47.117) (xy 250.444 -46.99) (xy 245.11 -41.656)
				(xy 241.046 -45.72) (xy 241.3 -45.72)
			)
		)
	)
	(zone
		(layer "F.Cu")
		(hatch none 0.5)
		(connect_pads
			(clearance 0)
		)
		(min_thickness 0.25)
		(keepout
			(tracks allowed)
			(vias allowed)
			(pads allowed)
			(copperpour allowed)
			(footprints not_allowed)
		)
		(placement
			(enabled no)
			(sheetname "")
		)
		(fill
			(thermal_gap 0.5)
			(thermal_bridge_width 0.5)
			(island_removal_mode 0)
		)
		(polygon
			(pts
				(arc
					(start 357.000048 -159.100012)
					(mid 353.000056 -155.10002)
					(end 357.000048 -151.100028)
				)
				(arc
					(start 360.499914 -151.100028)
					(mid 364.499906 -155.10002)
					(end 360.499914 -159.100012)
				)
			)
		)
	)
	(zone
		(layer "F.Cu")
		(hatch none 0.5)
		(connect_pads
			(clearance 0)
		)
		(min_thickness 0.25)
		(keepout
			(tracks not_allowed)
			(vias allowed)
			(pads allowed)
			(copperpour not_allowed)
			(footprints allowed)
		)
		(placement
			(enabled no)
			(sheetname "")
		)
		(fill
			(thermal_gap 0.5)
			(thermal_bridge_width 0.5)
			(island_removal_mode 0)
		)
		(polygon
			(pts
				(xy 458.19187 -120.00103) (xy 458.19187 -120.278906) (xy 458.016356 -120.45442)
				(arc
					(start 457.844652 -120.45442)
					(mid 457.320735 -120.38457)
					(end 457.844652 -120.31472)
				)
				(xy 457.958444 -120.31472) (xy 458.05217 -120.220994) (xy 458.05217 -120.00103)
				(arc
					(start 457.587604 -120.00103)
					(mid 457.20381 -120.384443)
					(end 457.58735 -120.76811)
				)
				(arc
					(start 458.85735 -120.76811)
					(mid 459.24089 -120.38457)
					(end 458.85735 -120.00103)
				)
				(xy 458.43317 -120.00103) (xy 458.43317 -120.261634) (xy 458.486256 -120.31472)
				(arc
					(start 458.600048 -120.31472)
					(mid 459.123965 -120.38457)
					(end 458.600048 -120.45442)
				)
				(xy 458.428344 -120.45442) (xy 458.29347 -120.319546) (xy 458.29347 -120.00103)
			)
		)
	)
	(zone
		(layer "F.Cu")
		(hatch none 0.5)
		(connect_pads
			(clearance 0)
		)
		(min_thickness 0.25)
		(keepout
			(tracks allowed)
			(vias allowed)
			(pads allowed)
			(copperpour allowed)
			(footprints allowed)
		)
		(placement
			(enabled no)
			(sheetname "")
		)
		(fill
			(thermal_gap 0.5)
			(thermal_bridge_width 0.5)
			(island_removal_mode 0)
		)
		(polygon
			(pts
				(xy 282.829 -103.886) (xy 282.829 -100.965) (xy 283.972 -99.822) (xy 286.639 -99.822) (xy 287.909 -101.092)
				(xy 287.909 -102.362) (xy 287.909 -102.616) (xy 287.655 -102.87) (xy 287.655 -103.124) (xy 288.29 -103.759)
				(xy 288.29 -103.886) (xy 287.274 -103.886)
			)
		)
	)
	(zone
		(layer "F.Cu")
		(hatch none 0.5)
		(connect_pads
			(clearance 0)
		)
		(min_thickness 0.25)
		(keepout
			(tracks allowed)
			(vias allowed)
			(pads allowed)
			(copperpour allowed)
			(footprints allowed)
		)
		(placement
			(enabled no)
			(sheetname "")
		)
		(fill
			(thermal_gap 0.5)
			(thermal_bridge_width 0.5)
			(island_removal_mode 0)
		)
		(polygon
			(pts
				(xy 490.3216 -35.7886) (xy 490.3216 -33.3248) (xy 491.744 -33.3248) (xy 491.744 -33.3502) (xy 491.8964 -33.5026)
				(xy 492.0234 -33.6296) (xy 492.0234 -35.0774) (xy 491.8964 -35.2044) (xy 491.744 -35.3568) (xy 491.744 -35.7886)
			)
		)
	)
	(zone
		(layer "F.Cu")
		(hatch none 0.5)
		(connect_pads
			(clearance 0)
		)
		(min_thickness 0.25)
		(keepout
			(tracks not_allowed)
			(vias allowed)
			(pads allowed)
			(copperpour not_allowed)
			(footprints allowed)
		)
		(placement
			(enabled no)
			(sheetname "")
		)
		(fill
			(thermal_gap 0.5)
			(thermal_bridge_width 0.5)
			(island_removal_mode 0)
		)
		(polygon
			(pts
				(arc
					(start 152.999948 -52.010056)
					(mid 155.539948 -54.550056)
					(end 152.999948 -57.090056)
				)
				(arc
					(start 152.999948 -57.090056)
					(mid 150.459948 -54.550056)
					(end 152.999948 -52.010056)
				)
			)
		)
	)
	(zone
		(layer "F.Cu")
		(hatch none 0.5)
		(connect_pads
			(clearance 0.5)
		)
		(min_thickness 0.25)
		(fill
			(thermal_gap 0.5)
			(thermal_bridge_width 0.5)
			(island_removal_mode 0)
		)
		(polygon
			(pts
				(xy 31.486602 -83.316064) (xy 31.613602 -83.189064) (xy 31.613602 -83.17738) (xy 31.6484 -83.142582)
				(xy 31.6484 -81.80578) (xy 33.630616 -81.80578) (xy 33.630616 -84.16798) (xy 33.44672 -84.351876)
				(xy 33.44672 -85.105494) (xy 33.4137 -85.13826) (xy 32.53232 -85.13826) (xy 32.117792 -84.723732)
				(xy 32.09544 -84.719922) (xy 31.38551 -84.719922) (xy 31.004256 -85.101176) (xy 30.04439 -85.101176)
				(xy 30.031944 -85.113622) (xy 30.007306 -85.13826) (xy 29.61767 -85.13826) (xy 29.3878 -84.90839)
				(xy 29.3878 -83.68538) (xy 29.5402 -83.53298) (xy 30.2768 -83.53298) (xy 30.353 -83.45678) (xy 30.355286 -83.45678)
				(xy 30.496002 -83.316064)
			)
		)
	)
	(zone
		(layer "F.Cu")
		(hatch none 0.5)
		(connect_pads
			(clearance 0)
		)
		(min_thickness 0.25)
		(keepout
			(tracks allowed)
			(vias allowed)
			(pads allowed)
			(copperpour allowed)
			(footprints allowed)
		)
		(placement
			(enabled no)
			(sheetname "")
		)
		(fill
			(thermal_gap 0.5)
			(thermal_bridge_width 0.5)
			(island_removal_mode 0)
		)
		(polygon
			(pts
				(xy 324.8914 -124.2187) (xy 322.6054 -124.2187) (xy 322.6054 -122.2121) (xy 324.8914 -122.2121)
			)
		)
	)
	(zone
		(layer "F.Cu")
		(hatch none 0.5)
		(connect_pads
			(clearance 0)
		)
		(min_thickness 0.25)
		(keepout
			(tracks allowed)
			(vias allowed)
			(pads allowed)
			(copperpour allowed)
			(footprints allowed)
		)
		(placement
			(enabled no)
			(sheetname "")
		)
		(fill
			(thermal_gap 0.5)
			(thermal_bridge_width 0.5)
			(island_removal_mode 0)
		)
		(polygon
			(pts
				(xy 476.522796 -35.92957) (xy 478.511108 -35.92957) (xy 478.79635 -35.644328) (xy 478.79635 -33.460182)
				(xy 478.674176 -33.338008) (xy 476.571818 -33.338008) (xy 476.066358 -33.843468) (xy 476.066358 -35.473132)
			)
		)
	)
	(zone
		(net "GND")
		(layer "F.Cu")
		(hatch none 0.5)
		(connect_pads
			(clearance 0.5)
		)
		(min_thickness 0.25)
		(fill yes
			(thermal_gap 0.5)
			(thermal_bridge_width 0.5)
			(island_removal_mode 0)
		)
		(polygon
			(pts
				(xy 213.995 -91.821) (xy 213.7664 -92.0496) (xy 213.7664 -93.218) (xy 213.9696 -93.4212) (xy 215.1888 -93.4212)
				(xy 215.5444 -93.0656) (xy 215.5444 -92.0496) (xy 215.3158 -91.821)
			)
		)
		(polygon
			(pts
				(xy 215.3412 -92.4941) (xy 215.138 -92.4941) (xy 215.138 -92.6973) (xy 215.3412 -92.6973)
			)
		)
		(polygon
			(pts
				(xy 214.5792 -92.4941) (xy 214.376 -92.4941) (xy 214.376 -92.6973) (xy 214.5792 -92.6973)
			)
		)
	)
	(zone
		(net "GND")
		(layer "F.Cu")
		(hatch none 0.5)
		(connect_pads
			(clearance 0.5)
		)
		(min_thickness 0.25)
		(fill yes
			(thermal_gap 0.5)
			(thermal_bridge_width 0.5)
			(island_removal_mode 0)
		)
		(polygon
			(pts
				(xy 464.8708 -39.2176) (xy 464.8708 -40.2844) (xy 464.9216 -40.3352) (xy 465.7598 -40.3352) (xy 465.8868 -40.4622)
				(xy 466.6742 -40.4622) (xy 466.8774 -40.259) (xy 466.8774 -38.7858) (xy 466.725 -38.6334) (xy 465.455 -38.6334)
			)
		)
		(polygon
			(pts
				(xy 465.8106 -39.3319) (xy 465.6074 -39.3319) (xy 465.6074 -39.5351) (xy 465.8106 -39.5351)
			)
		)
	)
	(zone
		(layer "F.Cu")
		(hatch none 0.5)
		(connect_pads
			(clearance 0)
		)
		(min_thickness 0.25)
		(keepout
			(tracks allowed)
			(vias allowed)
			(pads allowed)
			(copperpour allowed)
			(footprints allowed)
		)
		(placement
			(enabled no)
			(sheetname "")
		)
		(fill
			(thermal_gap 0.5)
			(thermal_bridge_width 0.5)
			(island_removal_mode 0)
		)
		(polygon
			(pts
				(xy 80.109568 -103.886) (xy 78.077568 -105.918) (xy 75.791568 -105.918) (xy 75.283568 -106.426)
				(xy 74.775568 -106.426) (xy 72.362568 -108.839) (xy 71.854568 -108.839) (xy 71.854568 -104.521)
				(xy 70.584568 -104.521) (xy 70.584568 -102.108) (xy 70.584568 -101.981) (xy 75.664568 -101.981)
				(xy 75.664568 -102.489) (xy 78.331568 -102.489) (xy 78.839568 -102.997) (xy 79.474568 -102.997)
				(xy 80.109568 -103.632)
			)
		)
	)
	(zone
		(layer "F.Cu")
		(hatch none 0.5)
		(connect_pads
			(clearance 0)
		)
		(min_thickness 0.25)
		(keepout
			(tracks allowed)
			(vias allowed)
			(pads allowed)
			(copperpour allowed)
			(footprints allowed)
		)
		(placement
			(enabled no)
			(sheetname "")
		)
		(fill
			(thermal_gap 0.5)
			(thermal_bridge_width 0.5)
			(island_removal_mode 0)
		)
		(polygon
			(pts
				(xy -0.158496 -143.501618) (xy 2.000504 -143.501618) (xy 2.000504 -145.152618) (xy -0.158496 -145.152618)
			)
		)
	)
	(zone
		(layer "F.Cu")
		(hatch none 0.5)
		(connect_pads
			(clearance 0)
		)
		(min_thickness 0.25)
		(keepout
			(tracks not_allowed)
			(vias allowed)
			(pads allowed)
			(copperpour not_allowed)
			(footprints allowed)
		)
		(placement
			(enabled no)
			(sheetname "")
		)
		(fill
			(thermal_gap 0.5)
			(thermal_bridge_width 0.5)
			(island_removal_mode 0)
		)
		(polygon
			(pts
				(arc
					(start 409.719526 -80.88376)
					(mid 405.719534 -76.883768)
					(end 409.719526 -72.883776)
				)
				(arc
					(start 409.719526 -72.883776)
					(mid 413.719518 -76.883768)
					(end 409.719526 -80.88376)
				)
			)
		)
	)
	(zone
		(net "P1V2_AUX_BMC")
		(layer "F.Cu")
		(hatch none 0.5)
		(connect_pads
			(clearance 0.5)
		)
		(min_thickness 0.25)
		(fill yes
			(thermal_gap 0.5)
			(thermal_bridge_width 0.5)
			(island_removal_mode 0)
		)
		(polygon
			(pts
				(xy 468.603838 -38.52545) (xy 470.2048 -38.52545) (xy 470.281 -38.44925) (xy 470.281 -37.840412)
				(xy 470.281 -37.592) (xy 470.281 -36.99256) (xy 470.8525 -36.42106) (xy 471.55862 -36.42106) (xy 471.63609 -36.34359)
				(xy 471.63609 -35.64763) (xy 471.78468 -35.49904) (xy 471.88374 -35.49904) (xy 472.1098 -35.27298)
				(xy 472.1098 -34.95294) (xy 472.04122 -34.88436) (xy 471.4875 -34.88436) (xy 468.723726 -34.88436)
				(xy 468.64524 -34.88436) (xy 468.41918 -34.6583) (xy 467.49208 -34.6583) (xy 467.4362 -34.71418)
				(xy 467.4362 -35.521646) (xy 467.934294 -36.01974) (xy 467.934294 -36.506912) (xy 467.934294 -37.855906)
			)
		)
	)
	(zone
		(net "GND")
		(layer "F.Cu")
		(hatch none 0.5)
		(connect_pads
			(clearance 0.5)
		)
		(min_thickness 0.25)
		(fill yes
			(thermal_gap 0.5)
			(thermal_bridge_width 0.5)
			(island_removal_mode 0)
		)
		(polygon
			(pts
				(xy 78.225396 -14.385544) (xy 77.002894 -14.385544) (xy 76.840334 -14.222984) (xy 76.840334 -13.341096)
				(xy 76.297282 -12.798044) (xy 76.297282 -12.29233) (xy 76.297282 -11.79576) (xy 76.620116 -11.472926)
				(xy 77.015848 -11.472926) (xy 78.2193 -11.472926) (xy 78.407006 -11.660632) (xy 78.407006 -14.203934)
			)
		)
	)
	(zone
		(net "GND")
		(layer "F.Cu")
		(hatch none 0.5)
		(connect_pads
			(clearance 0.5)
		)
		(min_thickness 0.25)
		(fill yes
			(thermal_gap 0.5)
			(thermal_bridge_width 0.5)
			(island_removal_mode 0)
		)
		(polygon
			(pts
				(xy 379.300232 -40.421814) (xy 379.300232 -39.081202) (xy 379.73762 -38.643814) (xy 381.840232 -38.643814)
				(xy 383.999232 -38.643814) (xy 384.022346 -38.643814) (xy 384.051048 -38.672516) (xy 384.051048 -39.63543)
				(xy 383.96291 -39.723568) (xy 383.96291 -40.060626) (xy 384.173476 -40.271192) (xy 384.319272 -40.271192)
				(xy 384.407664 -40.359584) (xy 384.407664 -41.157144) (xy 384.289808 -41.275) (xy 384.172206 -41.392602)
				(xy 382.10236 -41.392602) (xy 382.101852 -41.393364) (xy 382.012952 -41.393364) (xy 381.820674 -41.585642)
				(xy 381.820674 -42.28973) (xy 381.780034 -42.33037) (xy 379.553978 -42.33037) (xy 379.300232 -42.076624)
			)
		)
	)
	(zone
		(layer "F.Cu")
		(hatch none 0.5)
		(connect_pads
			(clearance 0)
		)
		(min_thickness 0.25)
		(keepout
			(tracks allowed)
			(vias allowed)
			(pads allowed)
			(copperpour allowed)
			(footprints not_allowed)
		)
		(placement
			(enabled no)
			(sheetname "")
		)
		(fill
			(thermal_gap 0.5)
			(thermal_bridge_width 0.5)
			(island_removal_mode 0)
		)
		(polygon
			(pts
				(xy 187.525406 -159.100012) (xy 328.525378 -159.100012) (xy 328.525378 -157.768544) (xy 187.525406 -157.768544)
			)
		)
	)
	(zone
		(layer "F.Cu")
		(hatch none 0.5)
		(connect_pads
			(clearance 0)
		)
		(min_thickness 0.25)
		(keepout
			(tracks allowed)
			(vias allowed)
			(pads allowed)
			(copperpour allowed)
			(footprints allowed)
		)
		(placement
			(enabled no)
			(sheetname "")
		)
		(fill
			(thermal_gap 0.5)
			(thermal_bridge_width 0.5)
			(island_removal_mode 0)
		)
		(polygon
			(pts
				(xy 197.612 -75.5396) (xy 197.612 -71.1708) (xy 200.025 -71.1708) (xy 200.025 -75.5396)
			)
		)
	)
	(zone
		(net "PVCCMCP_CPU1")
		(layer "F.Cu")
		(hatch none 0.5)
		(connect_pads
			(clearance 0.5)
		)
		(min_thickness 0.25)
		(fill yes
			(thermal_gap 0.5)
			(thermal_bridge_width 0.5)
			(island_removal_mode 0)
		)
		(polygon
			(pts
				(xy 107.998768 -76.962) (xy 107.981242 -76.979526) (xy 107.500674 -76.979526) (xy 107.2896 -77.1906)
				(xy 103.97744 -77.1906) (xy 103.85044 -77.3176) (xy 103.85044 -78.174088) (xy 104.1146 -78.438248)
				(xy 104.1146 -79.9338) (xy 104.267 -80.0862) (xy 112.418368 -80.0862) (xy 112.596168 -79.9084) (xy 112.596168 -79.1464)
				(xy 112.799368 -78.9432) (xy 112.799368 -77.1144) (xy 112.646968 -76.962)
			)
		)
		(polygon
			(pts
				(xy 111.783368 -79.0575) (xy 111.580168 -79.0575) (xy 111.580168 -79.2607) (xy 111.783368 -79.2607)
			)
		)
		(polygon
			(pts
				(xy 111.275368 -79.0575) (xy 111.072168 -79.0575) (xy 111.072168 -79.2607) (xy 111.275368 -79.2607)
			)
		)
		(polygon
			(pts
				(xy 110.513368 -79.0575) (xy 110.310168 -79.0575) (xy 110.310168 -79.2607) (xy 110.513368 -79.2607)
			)
		)
		(polygon
			(pts
				(xy 110.005368 -79.0575) (xy 109.802168 -79.0575) (xy 109.802168 -79.2607) (xy 110.005368 -79.2607)
			)
		)
		(polygon
			(pts
				(xy 109.243368 -79.0575) (xy 109.040168 -79.0575) (xy 109.040168 -79.2607) (xy 109.243368 -79.2607)
			)
		)
		(polygon
			(pts
				(xy 108.735368 -79.0575) (xy 108.532168 -79.0575) (xy 108.532168 -79.2607) (xy 108.735368 -79.2607)
			)
		)
		(polygon
			(pts
				(xy 107.973368 -79.0575) (xy 107.770168 -79.0575) (xy 107.770168 -79.2607) (xy 107.973368 -79.2607)
			)
		)
		(polygon
			(pts
				(xy 107.465368 -79.0575) (xy 107.262168 -79.0575) (xy 107.262168 -79.2607) (xy 107.465368 -79.2607)
			)
		)
		(polygon
			(pts
				(xy 106.703368 -79.0575) (xy 106.500168 -79.0575) (xy 106.500168 -79.2607) (xy 106.703368 -79.2607)
			)
		)
		(polygon
			(pts
				(xy 106.195368 -79.0575) (xy 105.992168 -79.0575) (xy 105.992168 -79.2607) (xy 106.195368 -79.2607)
			)
		)
		(polygon
			(pts
				(xy 105.433368 -79.0575) (xy 105.230168 -79.0575) (xy 105.230168 -79.2607) (xy 105.433368 -79.2607)
			)
		)
		(polygon
			(pts
				(xy 104.925368 -79.0575) (xy 104.722168 -79.0575) (xy 104.722168 -79.2607) (xy 104.925368 -79.2607)
			)
		)
		(polygon
			(pts
				(xy 107.38104 -77.979016) (xy 107.17784 -77.979016) (xy 107.17784 -78.182216) (xy 107.38104 -78.182216)
			)
		)
		(polygon
			(pts
				(xy 106.61904 -77.979016) (xy 106.41584 -77.979016) (xy 106.41584 -78.182216) (xy 106.61904 -78.182216)
			)
		)
		(polygon
			(pts
				(xy 106.13644 -77.979016) (xy 105.93324 -77.979016) (xy 105.93324 -78.182216) (xy 106.13644 -78.182216)
			)
		)
		(polygon
			(pts
				(xy 105.37444 -77.979016) (xy 105.17124 -77.979016) (xy 105.17124 -78.182216) (xy 105.37444 -78.182216)
			)
		)
		(polygon
			(pts
				(xy 104.89184 -77.979016) (xy 104.68864 -77.979016) (xy 104.68864 -78.182216) (xy 104.89184 -78.182216)
			)
		)
		(polygon
			(pts
				(xy 111.391192 -77.772514) (xy 111.187992 -77.772514) (xy 111.187992 -77.975714) (xy 111.391192 -77.975714)
			)
		)
		(polygon
			(pts
				(xy 110.629192 -77.772514) (xy 110.425992 -77.772514) (xy 110.425992 -77.975714) (xy 110.629192 -77.975714)
			)
		)
		(polygon
			(pts
				(xy 110.121192 -77.772514) (xy 109.917992 -77.772514) (xy 109.917992 -77.975714) (xy 110.121192 -77.975714)
			)
		)
		(polygon
			(pts
				(xy 109.359192 -77.772514) (xy 109.155992 -77.772514) (xy 109.155992 -77.975714) (xy 109.359192 -77.975714)
			)
		)
		(polygon
			(pts
				(xy 108.851192 -77.772514) (xy 108.647992 -77.772514) (xy 108.647992 -77.975714) (xy 108.851192 -77.975714)
			)
		)
		(polygon
			(pts
				(xy 108.089192 -77.772514) (xy 107.885992 -77.772514) (xy 107.885992 -77.975714) (xy 108.089192 -77.975714)
			)
		)
		(polygon
			(pts
				(xy 111.903002 -77.725016) (xy 111.699802 -77.725016) (xy 111.699802 -77.928216) (xy 111.903002 -77.928216)
			)
		)
	)
	(zone
		(layer "F.Cu")
		(hatch none 0.5)
		(connect_pads
			(clearance 0)
		)
		(min_thickness 0.25)
		(keepout
			(tracks allowed)
			(vias allowed)
			(pads allowed)
			(copperpour allowed)
			(footprints allowed)
		)
		(placement
			(enabled no)
			(sheetname "")
		)
		(fill
			(thermal_gap 0.5)
			(thermal_bridge_width 0.5)
			(island_removal_mode 0)
		)
		(polygon
			(pts
				(xy 173.4058 -10.5029) (xy 175.6918 -10.5029) (xy 175.6918 -13.0302) (xy 173.4058 -13.0302)
			)
		)
	)
	(zone
		(net "SATA6G_S1_RX_C_DN")
		(layer "F.Cu")
		(hatch none 0.5)
		(connect_pads
			(clearance 0.5)
		)
		(min_thickness 0.25)
		(fill yes
			(thermal_gap 0.5)
			(thermal_bridge_width 0.5)
			(island_removal_mode 0)
		)
		(polygon
			(pts
				(arc
					(start 434.03901 -136.344914)
					(mid 433.22113 -136.344914)
					(end 434.03901 -136.344914)
				)
			)
		)
	)
	(zone
		(layer "F.Cu")
		(hatch none 0.5)
		(connect_pads
			(clearance 0)
		)
		(min_thickness 0.25)
		(keepout
			(tracks not_allowed)
			(vias allowed)
			(pads allowed)
			(copperpour not_allowed)
			(footprints allowed)
		)
		(placement
			(enabled no)
			(sheetname "")
		)
		(fill
			(thermal_gap 0.5)
			(thermal_bridge_width 0.5)
			(island_removal_mode 0)
		)
		(polygon
			(pts
				(xy 369.223544 -10.293858) (xy 369.731544 -10.293858) (xy 369.731544 -10.649458) (xy 369.223544 -10.649458)
			)
		)
	)
	(zone
		(net "GND")
		(layer "F.Cu")
		(hatch none 0.5)
		(connect_pads
			(clearance 0.5)
		)
		(min_thickness 0.25)
		(fill yes
			(thermal_gap 0.5)
			(thermal_bridge_width 0.5)
			(island_removal_mode 0)
		)
		(polygon
			(pts
				(xy 241.9223 -150.967948) (xy 243.338858 -150.967948) (xy 243.481352 -150.825454) (xy 243.481352 -148.709126)
				(xy 243.261388 -148.489162) (xy 242.025424 -148.489162) (xy 242.024662 -148.4884) (xy 241.2492 -148.4884)
				(xy 241.0968 -148.6408) (xy 241.0968 -148.9456) (xy 241.106198 -148.9456) (xy 241.766598 -149.606)
				(xy 241.766598 -150.584154) (xy 241.853466 -150.671022) (xy 241.853466 -150.899114)
			)
		)
	)
	(zone
		(net "GND")
		(layer "F.Cu")
		(hatch none 0.5)
		(connect_pads
			(clearance 0.5)
		)
		(min_thickness 0.25)
		(fill yes
			(thermal_gap 0.5)
			(thermal_bridge_width 0.5)
			(island_removal_mode 0)
		)
		(polygon
			(pts
				(xy 175.1584 -51.743864) (xy 175.1584 -56.8452) (xy 175.0314 -56.9722) (xy 173.5328 -56.9722) (xy 173.1772 -56.6166)
				(xy 171.3738 -56.6166) (xy 171.196 -56.7944) (xy 171.196 -57.2897) (xy 171.2595 -57.3532) (xy 172.8597 -57.3532)
				(xy 172.9994 -57.4929) (xy 172.9994 -58.3819) (xy 172.8724 -58.5089) (xy 171.9453 -58.5089) (xy 171.7548 -58.3184)
				(xy 171.2722 -58.3184) (xy 171.0944 -58.3184) (xy 169.9514 -58.3184) (xy 169.6593 -58.3184) (xy 169.3418 -58.6359)
				(xy 169.3418 -58.928) (xy 169.3418 -63.02756) (xy 169.477944 -63.163704) (xy 169.737532 -63.163704)
				(xy 170.073828 -63.5) (xy 174.1551 -63.5) (xy 174.6631 -62.992) (xy 182.0926 -62.992) (xy 182.499 -62.5856)
				(xy 182.499 -61.849) (xy 183.5404 -60.8076) (xy 184.002934 -60.8076) (xy 184.655968 -61.460634)
				(xy 186.573922 -61.460634) (xy 187.132722 -62.019434) (xy 189.0776 -62.019434) (xy 189.731396 -62.019434)
				(xy 189.879732 -61.871098) (xy 189.879732 -60.850272) (xy 189.753494 -60.724034) (xy 189.171834 -60.724034)
				(xy 187.523882 -60.724034) (xy 186.7662 -59.966352) (xy 186.7662 -59.69) (xy 186.563 -59.4868) (xy 183.0324 -59.4868)
				(xy 182.8038 -59.7154) (xy 182.8038 -60.198) (xy 181.7878 -61.214) (xy 175.38192 -61.214) (xy 175.04791 -60.87999)
				(xy 175.04791 -59.221624) (xy 175.214534 -59.055) (xy 176.9364 -59.055) (xy 177.546 -58.4454) (xy 177.546 -57.70245)
				(xy 178.0032 -57.24525) (xy 178.0032 -57.0484) (xy 178.0286 -57.023) (xy 178.0286 -56.2102) (xy 178.1302 -56.1086)
				(xy 179.1208 -56.1086) (xy 179.1462 -56.134) (xy 179.1462 -57.0484) (xy 179.1716 -57.0738) (xy 179.3494 -57.0738)
				(xy 179.3748 -57.0484) (xy 179.3748 -56.2102) (xy 179.4764 -56.1086) (xy 179.6034 -56.1086) (xy 179.6796 -56.0324)
				(xy 179.6796 -54.4576) (xy 179.5526 -54.3306) (xy 177.6984 -54.3306) (xy 177.3682 -54.0004) (xy 177.3682 -51.943)
				(xy 177.35804 -51.93284) (xy 177.35804 -50.823622) (xy 177.279046 -50.744628) (xy 176.836578 -50.744628)
				(xy 176.80051 -50.780696) (xy 176.80051 -51.384708) (xy 176.608994 -51.576224) (xy 175.32604 -51.576224)
			)
		)
	)
	(zone
		(net "PVDDQ_KLM")
		(layer "F.Cu")
		(hatch none 0.5)
		(connect_pads
			(clearance 0.5)
		)
		(min_thickness 0.25)
		(fill yes
			(thermal_gap 0.5)
			(thermal_bridge_width 0.5)
			(island_removal_mode 0)
		)
		(polygon
			(pts
				(xy 112.358424 -155.830524) (xy 112.528604 -155.660344) (xy 112.528604 -153.43251) (xy 112.405668 -153.309574)
				(xy 100.863654 -153.309574) (xy 100.677726 -153.495502) (xy 100.677726 -155.561792) (xy 100.946458 -155.830524)
			)
		)
	)
	(zone
		(layer "F.Cu")
		(hatch none 0.5)
		(connect_pads
			(clearance 0)
		)
		(min_thickness 0.25)
		(keepout
			(tracks allowed)
			(vias allowed)
			(pads allowed)
			(copperpour allowed)
			(footprints not_allowed)
		)
		(placement
			(enabled no)
			(sheetname "")
		)
		(fill
			(thermal_gap 0.5)
			(thermal_bridge_width 0.5)
			(island_removal_mode 0)
		)
		(polygon
			(pts
				(xy 465.74202 -136.53008) (xy 465.74202 -123.880118) (xy 477.09201 -123.880118) (xy 477.09201 -126.492)
				(xy 477.33204 -126.492) (xy 477.33204 -136.53008)
			)
		)
	)
	(zone
		(net "GND")
		(layer "F.Cu")
		(hatch none 0.5)
		(connect_pads
			(clearance 0.5)
		)
		(min_thickness 0.25)
		(fill yes
			(thermal_gap 0.5)
			(thermal_bridge_width 0.5)
			(island_removal_mode 0)
		)
		(polygon
			(pts
				(xy 17.8816 -125.9205) (xy 18.288 -125.5141) (xy 20.5232 -125.5141) (xy 20.7772 -125.5141) (xy 21.08708 -125.5141)
				(xy 21.77034 -126.19736) (xy 21.77034 -126.50724) (xy 21.77034 -127.75946) (xy 21.336 -128.1938)
				(xy 20.9296 -128.6002) (xy 18.2372 -128.6002) (xy 17.8816 -128.2446) (xy 17.8816 -127.4445)
			)
		)
	)
	(zone
		(layer "F.Cu")
		(hatch none 0.5)
		(connect_pads
			(clearance 0)
		)
		(min_thickness 0.25)
		(keepout
			(tracks allowed)
			(vias allowed)
			(pads allowed)
			(copperpour allowed)
			(footprints allowed)
		)
		(placement
			(enabled no)
			(sheetname "")
		)
		(fill
			(thermal_gap 0.5)
			(thermal_bridge_width 0.5)
			(island_removal_mode 0)
		)
		(polygon
			(pts
				(xy 355.996748 -79.45755) (xy 355.996748 -77.17155) (xy 358.003348 -77.17155) (xy 358.003348 -79.45755)
			)
		)
	)
	(zone
		(net "GND")
		(layer "F.Cu")
		(hatch none 0.5)
		(connect_pads
			(clearance 0.5)
		)
		(min_thickness 0.25)
		(fill yes
			(thermal_gap 0.5)
			(thermal_bridge_width 0.5)
			(island_removal_mode 0)
		)
		(polygon
			(pts
				(xy 394.7414 -105.80624) (xy 394.84808 -105.69956) (xy 394.84808 -105.522522) (xy 394.797788 -105.47223)
				(xy 394.797788 -105.424224) (xy 394.433044 -105.05948) (xy 393.75334 -105.05948) (xy 393.665964 -105.146856)
				(xy 393.665964 -105.771188) (xy 393.667488 -105.772712) (xy 393.652502 -105.787698) (xy 393.652502 -105.957624)
				(xy 393.728448 -106.03357) (xy 394.301472 -106.03357) (xy 394.363702 -105.97134) (xy 394.51534 -105.819702)
				(xy 394.669264 -105.819702) (xy 394.669518 -105.819956) (xy 394.727684 -105.819956)
			)
		)
	)
	(zone
		(net "GND")
		(layer "F.Cu")
		(hatch none 0.5)
		(connect_pads
			(clearance 0.5)
		)
		(min_thickness 0.25)
		(fill yes
			(thermal_gap 0.5)
			(thermal_bridge_width 0.5)
			(island_removal_mode 0)
		)
		(polygon
			(pts
				(xy 112.621568 -18.923) (xy 115.034568 -18.923) (xy 115.034568 -17.78) (xy 114.145568 -16.891) (xy 113.510568 -16.891)
				(xy 113.256568 -17.145) (xy 112.748568 -17.145) (xy 100.734114 -17.145) (xy 100.681028 -17.198086)
				(xy 100.681028 -17.208754) (xy 100.682552 -17.210278) (xy 100.682552 -17.529048) (xy 100.62718 -17.58442)
				(xy 100.62718 -17.830292) (xy 100.830888 -18.034) (xy 106.931968 -18.034) (xy 107.185968 -18.288)
				(xy 112.367568 -18.288) (xy 112.621568 -18.542)
			)
		)
	)
	(zone
		(layer "F.Cu")
		(hatch none 0.5)
		(connect_pads
			(clearance 0)
		)
		(min_thickness 0.25)
		(keepout
			(tracks not_allowed)
			(vias allowed)
			(pads allowed)
			(copperpour not_allowed)
			(footprints allowed)
		)
		(placement
			(enabled no)
			(sheetname "")
		)
		(fill
			(thermal_gap 0.5)
			(thermal_bridge_width 0.5)
			(island_removal_mode 0)
		)
		(polygon
			(pts
				(arc
					(start 13.028676 -30.419802)
					(mid 13.098526 -29.895885)
					(end 13.168376 -30.419802)
				)
				(xy 13.168376 -30.533594) (xy 13.241782 -30.607) (xy 13.482066 -30.607)
				(arc
					(start 13.482066 -30.1625)
					(mid 13.098526 -29.77896)
					(end 12.714986 -30.1625)
				)
				(arc
					(start 12.714986 -31.432246)
					(mid 13.098399 -31.81604)
					(end 13.482066 -31.4325)
				)
				(xy 13.482066 -30.988) (xy 13.241782 -30.988) (xy 13.168376 -31.061406)
				(arc
					(start 13.168376 -31.175198)
					(mid 13.098526 -31.699115)
					(end 13.028676 -31.175198)
				)
				(xy 13.028676 -31.003494) (xy 13.18387 -30.8483) (xy 13.482066 -30.8483) (xy 13.482066 -30.7467)
				(xy 13.18387 -30.7467) (xy 13.028676 -30.591506)
			)
		)
	)
	(zone
		(layer "F.Cu")
		(hatch none 0.5)
		(connect_pads
			(clearance 0)
		)
		(min_thickness 0.25)
		(keepout
			(tracks allowed)
			(vias allowed)
			(pads allowed)
			(copperpour allowed)
			(footprints allowed)
		)
		(placement
			(enabled no)
			(sheetname "")
		)
		(fill
			(thermal_gap 0.5)
			(thermal_bridge_width 0.5)
			(island_removal_mode 0)
		)
		(polygon
			(pts
				(xy 283.718 -103.505) (xy 284.099 -103.505) (xy 284.353 -103.251) (xy 284.353 -102.743) (xy 284.099 -102.489)
				(xy 283.972 -102.489) (xy 283.718 -102.743)
			)
		)
	)
	(zone
		(layer "F.Cu")
		(hatch none 0.5)
		(connect_pads
			(clearance 0)
		)
		(min_thickness 0.25)
		(keepout
			(tracks not_allowed)
			(vias allowed)
			(pads allowed)
			(copperpour not_allowed)
			(footprints allowed)
		)
		(placement
			(enabled no)
			(sheetname "")
		)
		(fill
			(thermal_gap 0.5)
			(thermal_bridge_width 0.5)
			(island_removal_mode 0)
		)
		(polygon
			(pts
				(arc
					(start 395.093952 -25.775158)
					(mid 395.030058 -25.839834)
					(end 394.948156 -25.879298)
				)
				(xy 395.16685 -25.879298) (xy 395.16685 -25.848056)
			)
		)
	)
	(zone
		(net "P12V_STBY")
		(layer "F.Cu")
		(hatch none 0.5)
		(connect_pads
			(clearance 0.5)
		)
		(min_thickness 0.25)
		(fill yes
			(thermal_gap 0.5)
			(thermal_bridge_width 0.5)
			(island_removal_mode 0)
		)
		(polygon
			(pts
				(xy 355.82479 -102.6668) (xy 354.0252 -102.6668) (xy 353.62642 -103.06558) (xy 353.62642 -104.57942)
				(xy 353.62642 -107.057698) (xy 353.70897 -107.140248) (xy 353.893882 -107.140248) (xy 353.895406 -107.138724)
				(xy 355.813614 -107.138724) (xy 355.919786 -107.032552) (xy 355.919786 -105.067608) (xy 355.882448 -105.03027)
				(xy 355.882448 -102.724458)
			)
		)
	)
	(zone
		(layer "F.Cu")
		(hatch none 0.5)
		(connect_pads
			(clearance 0)
		)
		(min_thickness 0.25)
		(keepout
			(tracks allowed)
			(vias allowed)
			(pads allowed)
			(copperpour allowed)
			(footprints allowed)
		)
		(placement
			(enabled no)
			(sheetname "")
		)
		(fill
			(thermal_gap 0.5)
			(thermal_bridge_width 0.5)
			(island_removal_mode 0)
		)
		(polygon
			(pts
				(xy 147.193 -56.261) (xy 147.193 -55.626) (xy 148.082 -55.626) (xy 148.082 -56.261)
			)
		)
	)
	(zone
		(net "GND")
		(layer "F.Cu")
		(hatch none 0.5)
		(connect_pads
			(clearance 0.5)
		)
		(min_thickness 0.25)
		(fill yes
			(thermal_gap 0.5)
			(thermal_bridge_width 0.5)
			(island_removal_mode 0)
		)
		(polygon
			(pts
				(xy 466.937598 -37.677598) (xy 467.135972 -37.479224) (xy 467.135972 -35.673792) (xy 467.13394 -35.67176)
				(xy 467.13394 -34.77768) (xy 466.9536 -34.59734) (xy 465.19084 -34.59734) (xy 464.815174 -34.973006)
				(xy 464.815174 -35.673792) (xy 464.815174 -37.414454) (xy 465.078318 -37.677598)
			)
		)
	)
	(zone
		(net "VR_FET_SW_P12V_STBY_PVDDQ_DEF")
		(layer "F.Cu")
		(hatch none 0.5)
		(connect_pads
			(clearance 0.5)
		)
		(min_thickness 0.25)
		(fill yes
			(thermal_gap 0.5)
			(thermal_bridge_width 0.5)
			(island_removal_mode 0)
		)
		(polygon
			(pts
				(xy 389.970772 -153.21534) (xy 389.394954 -153.791158) (xy 389.387842 -153.791158) (xy 389.2042 -153.9748)
				(xy 385.8514 -153.9748) (xy 385.7752 -154.051) (xy 385.7752 -155.8798) (xy 385.8514 -155.956) (xy 387.223 -155.956)
				(xy 387.3246 -156.0576) (xy 387.3246 -156.920692) (xy 387.33095 -156.927042) (xy 389.139938 -156.927042)
				(xy 389.249412 -156.817568) (xy 389.249412 -155.862528) (xy 389.971788 -155.140152) (xy 389.971788 -153.9494)
				(xy 390.187942 -153.733246) (xy 390.82853 -153.733246) (xy 390.833356 -153.72842) (xy 390.833356 -153.2255)
				(xy 390.823196 -153.21534)
			)
		)
	)
	(zone
		(layer "F.Cu")
		(hatch none 0.5)
		(connect_pads
			(clearance 0)
		)
		(min_thickness 0.25)
		(keepout
			(tracks not_allowed)
			(vias allowed)
			(pads allowed)
			(copperpour not_allowed)
			(footprints allowed)
		)
		(placement
			(enabled no)
			(sheetname "")
		)
		(fill
			(thermal_gap 0.5)
			(thermal_bridge_width 0.5)
			(island_removal_mode 0)
		)
		(polygon
			(pts
				(xy 384.193796 -30.071822)
				(arc
					(start 384.406902 -30.284928)
					(mid 384.728067 -30.704899)
					(end 384.308096 -30.383734)
				)
				(xy 384.15595 -30.231588)
				(arc
					(start 384.15595 -30.516322)
					(mid 384.53949 -30.899862)
					(end 384.92303 -30.516322)
				)
				(arc
					(start 384.92303 -29.551376)
					(mid 384.539617 -29.167836)
					(end 384.15595 -29.551122)
				)
				(xy 384.15595 -29.830522) (xy 384.161284 -29.830522)
				(arc
					(start 384.308096 -29.68371)
					(mid 384.728067 -29.362545)
					(end 384.406902 -29.782516)
				)
				(xy 384.219196 -29.970222) (xy 384.15595 -29.970222) (xy 384.15595 -30.071822)
			)
		)
	)
	(zone
		(net "GND")
		(layer "F.Cu")
		(hatch none 0.5)
		(connect_pads
			(clearance 0.5)
		)
		(min_thickness 0.25)
		(fill yes
			(thermal_gap 0.5)
			(thermal_bridge_width 0.5)
			(island_removal_mode 0)
		)
		(polygon
			(pts
				(xy 198.811388 -52.369212) (xy 198.811388 -52.967128) (xy 198.814436 -52.967128) (xy 198.814436 -53.475636)
				(xy 198.811388 -53.475636) (xy 198.811388 -53.801264) (xy 198.925688 -53.915564) (xy 199.375014 -53.915564)
				(xy 199.5932 -54.13375) (xy 199.5932 -55.88) (xy 199.5424 -55.9308) (xy 198.755 -55.9308) (xy 198.6788 -55.8546)
				(xy 198.6788 -55.2958) (xy 198.5772 -55.1942) (xy 198.5772 -54.3052) (xy 198.5518 -54.2798) (xy 198.324216 -54.2798)
				(xy 198.324216 -55.23103) (xy 198.281798 -55.273448) (xy 197.241414 -55.273448) (xy 197.23354 -55.26532)
				(xy 197.225412 -55.273448) (xy 196.724524 -55.273448) (xy 196.676772 -55.3212) (xy 196.6722 -55.3212)
				(xy 196.6214 -55.372) (xy 196.6214 -56.896) (xy 196.7738 -57.0484) (xy 198.7042 -57.0484) (xy 198.896732 -57.0484)
				(xy 199.009 -57.160668) (xy 199.009 -57.3532) (xy 199.009 -59.929522) (xy 199.001888 -59.936634)
				(xy 199.001888 -60.586112) (xy 199.001888 -60.613798) (xy 198.899018 -60.716668) (xy 198.750428 -60.865258)
				(xy 198.750428 -60.96) (xy 198.750428 -61.422788) (xy 198.750428 -61.540898) (xy 198.47433 -61.816996)
				(xy 198.47433 -62.144402) (xy 198.374 -62.244732) (xy 198.374 -62.357) (xy 198.348092 -62.382908)
				(xy 198.348092 -62.435994) (xy 198.330566 -62.45352) (xy 198.330566 -63.3476) (xy 196.7484 -63.3476)
				(xy 196.6468 -63.4492) (xy 196.6468 -65.024) (xy 196.6468 -65.077594) (xy 196.669152 -65.099946)
				(xy 196.741288 -65.172082) (xy 198.623682 -65.172082) (xy 198.880222 -65.172082) (xy 198.95058 -65.24244)
				(xy 199.009 -65.30086) (xy 199.009 -65.5574) (xy 199.009 -68.185538) (xy 198.957692 -68.236592)
				(xy 198.6788 -68.236592) (xy 198.628 -68.287392) (xy 198.628 -69.7484) (xy 198.318628 -70.057772)
				(xy 198.35114 -70.090538) (xy 198.35114 -70.56247) (xy 198.32574 -70.58787) (xy 198.32574 -71.486776)
				(xy 198.283576 -71.52894) (xy 197.243192 -71.52894) (xy 197.235826 -71.521574) (xy 196.93001 -71.521574)
				(xy 196.915786 -71.535798) (xy 196.703188 -71.535798) (xy 196.648324 -71.590662) (xy 196.648324 -73.265284)
				(xy 196.692012 -73.308972) (xy 198.657972 -73.308972) (xy 198.889112 -73.308972) (xy 198.890636 -73.310496)
				(xy 198.95058 -73.37044) (xy 199.0344 -73.45426) (xy 199.0344 -73.6854) (xy 199.0344 -76.291186)
				(xy 198.940166 -76.38542) (xy 198.7042 -76.38542) (xy 198.7042 -77.7494) (xy 198.350124 -78.103476)
				(xy 198.350124 -78.25613) (xy 198.350632 -78.256638) (xy 198.350632 -78.6638) (xy 198.321168 -78.693264)
				(xy 198.321168 -79.609188) (xy 198.254874 -79.675482) (xy 197.2564 -79.675482) (xy 197.252082 -79.6798)
				(xy 196.943472 -79.6798) (xy 196.918072 -79.7052) (xy 196.7484 -79.7052) (xy 196.6722 -79.7814)
				(xy 196.6722 -81.2038) (xy 196.8754 -81.407) (xy 198.628 -81.407) (xy 198.85914 -81.407) (xy 198.861172 -81.409032)
				(xy 198.95058 -81.49844) (xy 199.0344 -81.58226) (xy 199.0344 -81.8134) (xy 199.0344 -84.478114)
				(xy 199.07377 -84.517484) (xy 199.07377 -85.15223) (xy 199.0344 -85.1916) (xy 198.820024 -85.405976)
				(xy 198.820024 -86.168484) (xy 198.547736 -86.440772) (xy 198.547736 -86.444836) (xy 198.373746 -86.618572)
				(arc
					(start 198.373238 -86.619334)
					(mid 198.351723 -86.640575)
					(end 198.328534 -86.659974)
				)
				(xy 198.32447 -86.664038) (xy 198.32447 -87.714582) (xy 198.23684 -87.802212) (xy 196.938138 -87.802212)
				(xy 196.90715 -87.8332) (xy 196.8246 -87.8332) (xy 196.7484 -87.9094) (xy 196.7484 -89.408) (xy 196.8754 -89.535)
				(xy 198.501 -89.535) (xy 198.85914 -89.535) (xy 198.95058 -89.62644) (xy 199.0344 -89.71026) (xy 199.0344 -90.0684)
				(xy 199.0344 -92.2274) (xy 198.763128 -92.498672) (xy 198.755 -92.498672) (xy 198.681086 -92.572586)
				(xy 198.681086 -93.207586) (xy 198.6915 -93.218) (xy 199.1868 -93.218) (xy 199.4916 -92.9132) (xy 201.4474 -92.9132)
				(xy 201.550524 -93.016324) (xy 202.413108 -93.016324) (xy 202.452732 -92.9767) (xy 205.222348 -92.9767)
				(xy 205.2955 -93.049852) (xy 208.065878 -93.049852) (xy 208.174844 -92.940886) (xy 208.174844 -53.597556)
				(xy 208.242916 -53.529484) (xy 208.342992 -53.429408) (xy 208.342992 -52.419758) (xy 208.33588 -52.412646)
				(arc
					(start 208.09839 -52.412646)
					(mid 208.074637 -52.413289)
					(end 208.050892 -52.412392)
				)
				(xy 207.443324 -52.412392) (xy 207.430116 -52.425854) (xy 206.6544 -52.425854) (xy 206.425546 -52.197)
				(xy 205.994 -52.197) (xy 205.8162 -52.197) (xy 205.1304 -52.197) (xy 205.0542 -52.197) (xy 204.6732 -51.816)
				(xy 204.597 -51.816) (xy 204.5462 -51.816) (xy 204.4954 -51.816) (xy 204.2414 -52.07) (xy 203.8096 -52.07)
				(xy 203.4286 -51.689) (xy 203.327 -51.689) (xy 202.946 -51.689) (xy 202.9206 -51.689) (xy 202.819 -51.7906)
				(xy 202.7936 -51.7906) (xy 202.3872 -51.7906) (xy 202.3364 -51.7398) (xy 202.2348 -51.6382) (xy 202.2094 -51.6382)
				(xy 201.1172 -51.6382) (xy 201.041 -51.562) (xy 200.787 -51.562) (xy 199.6313 -51.562) (xy 199.39 -51.562)
				(xy 198.882 -52.07) (xy 198.8312 -52.1208) (xy 198.811388 -52.140612)
			)
		)
		(polygon
			(pts
				(xy 202.781154 -53.08473) (xy 202.647042 -53.08473) (xy 202.647042 -53.090064) (xy 202.591162 -53.090064)
				(xy 202.442318 -53.238908) (xy 202.442318 -53.289708) (xy 202.533758 -53.289708) (xy 202.711558 -53.111908)
				(xy 202.781154 -53.111908)
			)
		)
		(polygon
			(pts
				(xy 203.567792 -61.575696) (xy 203.477114 -61.575696) (xy 203.312268 -61.740542) (xy 203.312268 -61.764672)
				(xy 203.414884 -61.764672) (xy 203.585826 -61.59373)
			)
		)
		(polygon
			(pts
				(xy 203.3905 -69.7103) (xy 203.2635 -69.7103) (xy 203.1238 -69.85) (xy 203.1238 -69.8754) (xy 203.2254 -69.8754)
			)
		)
		(polygon
			(pts
				(xy 203.2254 -77.8256) (xy 203.0857 -77.8256) (xy 202.9079 -78.0034) (xy 202.9079 -78.0161) (xy 202.9206 -78.0288)
				(xy 203.0222 -78.0288)
			)
		)
		(polygon
			(pts
				(xy 202.6285 -84.8868) (xy 202.4634 -84.8868) (xy 202.6539 -85.0773) (xy 202.819 -85.0773)
			)
		)
		(polygon
			(pts
				(xy 202.7809 -85.8012) (xy 202.6793 -85.8012) (xy 202.4761 -86.0044) (xy 202.5904 -86.0044) (xy 202.7809 -85.8139)
			)
		)
		(polygon
			(pts
				(xy 205.287118 -62.452504) (xy 205.254098 -62.419484) (xy 205.235556 -62.438026) (xy 205.235556 -62.464696)
				(xy 205.2447 -62.47384) (xy 205.276958 -62.47384) (xy 205.287118 -62.46368)
			)
		)
		(polygon
			(pts
				(xy 204.499464 -61.456316) (xy 204.349604 -61.456316) (xy 204.349604 -61.45911) (xy 204.349096 -61.45911)
				(xy 204.349096 -61.595254) (xy 204.349604 -61.595254) (xy 204.349604 -61.595508) (xy 204.474572 -61.595508)
				(xy 204.515212 -61.636148) (xy 204.545946 -61.636148) (xy 204.561948 -61.620146) (xy 204.52969 -61.587888)
				(xy 204.517498 -61.587888) (xy 204.517498 -61.45911) (xy 204.499464 -61.45911)
			)
		)
		(polygon
			(pts
				(xy 204.512926 -62.446408) (xy 204.512926 -62.4205) (xy 204.473556 -62.45987) (xy 204.473556 -62.465204)
				(xy 204.478128 -62.469776) (xy 204.489558 -62.469776)
			)
		)
		(polygon
			(pts
				(xy 202.784202 -52.348892) (xy 202.642978 -52.348892) (xy 202.642978 -52.406804) (xy 202.784202 -52.406804)
			)
		)
		(polygon
			(pts
				(xy 203.669646 -52.348892) (xy 203.494386 -52.348892) (xy 203.494386 -52.553362) (xy 203.669646 -52.553362)
			)
		)
		(polygon
			(pts
				(xy 203.675234 -52.97932) (xy 203.526644 -52.97932) (xy 203.526644 -53.112162) (xy 203.675234 -53.112162)
			)
		)
		(polygon
			(pts
				(xy 204.508608 -60.832492) (xy 204.340968 -60.832492) (xy 204.340968 -60.998608) (xy 204.508608 -60.998608)
			)
		)
		(polygon
			(pts
				(xy 204.245464 -68.960492) (xy 204.105002 -68.960492) (xy 204.105002 -69.111622) (xy 204.245464 -69.111622)
			)
		)
		(polygon
			(pts
				(xy 204.249274 -69.577458) (xy 204.073506 -69.577458) (xy 204.073506 -69.723508) (xy 204.249274 -69.723508)
			)
		)
		(polygon
			(pts
				(xy 204.045566 -77.088492) (xy 203.866242 -77.088492) (xy 203.866242 -77.270356) (xy 204.045566 -77.270356)
			)
		)
		(polygon
			(pts
				(xy 204.043788 -77.694282) (xy 203.87818 -77.694282) (xy 203.87818 -77.851508) (xy 204.043788 -77.851508)
			)
		)
		(polygon
			(pts
				(xy 204.168248 -85.064092) (xy 203.99883 -85.064092) (xy 203.99883 -85.258148) (xy 204.168248 -85.258148)
			)
		)
		(polygon
			(pts
				(xy 204.203046 -85.655658) (xy 204.038962 -85.655658) (xy 204.038962 -85.827108) (xy 204.203046 -85.827108)
			)
		)
		(polygon
			(pts
				(xy 201.2442 -85.7758) (xy 201.041 -85.7758) (xy 201.041 -85.979) (xy 201.2442 -85.979)
			)
		)
		(polygon
			(pts
				(xy 200.3806 -85.7758) (xy 200.1774 -85.7758) (xy 200.1774 -85.979) (xy 200.3806 -85.979)
			)
		)
		(polygon
			(pts
				(xy 201.2442 -84.9122) (xy 201.041 -84.9122) (xy 201.041 -85.1154) (xy 201.2442 -85.1154)
			)
		)
		(polygon
			(pts
				(xy 200.3806 -84.9122) (xy 200.1774 -84.9122) (xy 200.1774 -85.1154) (xy 200.3806 -85.1154)
			)
		)
		(polygon
			(pts
				(xy 201.69378 -77.8002) (xy 201.49058 -77.8002) (xy 201.49058 -78.0034) (xy 201.69378 -78.0034)
			)
		)
		(polygon
			(pts
				(xy 200.83018 -77.8002) (xy 200.62698 -77.8002) (xy 200.62698 -78.0034) (xy 200.83018 -78.0034)
			)
		)
		(polygon
			(pts
				(xy 201.69378 -76.9366) (xy 201.49058 -76.9366) (xy 201.49058 -77.1398) (xy 201.69378 -77.1398)
			)
		)
		(polygon
			(pts
				(xy 200.83018 -76.9366) (xy 200.62698 -76.9366) (xy 200.62698 -77.1398) (xy 200.83018 -77.1398)
			)
		)
		(polygon
			(pts
				(xy 201.901298 -69.646292) (xy 201.698098 -69.646292) (xy 201.698098 -69.849492) (xy 201.901298 -69.849492)
			)
		)
		(polygon
			(pts
				(xy 201.037698 -69.646292) (xy 200.834498 -69.646292) (xy 200.834498 -69.849492) (xy 201.037698 -69.849492)
			)
		)
		(polygon
			(pts
				(xy 201.901298 -68.782692) (xy 201.698098 -68.782692) (xy 201.698098 -68.985892) (xy 201.901298 -68.985892)
			)
		)
		(polygon
			(pts
				(xy 201.037698 -68.782692) (xy 200.834498 -68.782692) (xy 200.834498 -68.985892) (xy 201.037698 -68.985892)
			)
		)
		(polygon
			(pts
				(xy 202.095354 -61.535564) (xy 201.892154 -61.535564) (xy 201.892154 -61.738764) (xy 202.095354 -61.738764)
			)
		)
		(polygon
			(pts
				(xy 201.231754 -61.535564) (xy 201.028554 -61.535564) (xy 201.028554 -61.738764) (xy 201.231754 -61.738764)
			)
		)
		(polygon
			(pts
				(xy 202.095354 -60.671964) (xy 201.892154 -60.671964) (xy 201.892154 -60.875164) (xy 202.095354 -60.875164)
			)
		)
		(polygon
			(pts
				(xy 201.231754 -60.671964) (xy 201.028554 -60.671964) (xy 201.028554 -60.875164) (xy 201.231754 -60.875164)
			)
		)
		(polygon
			(pts
				(xy 207.5561 -53.07838) (xy 207.3529 -53.07838) (xy 207.3529 -53.28158) (xy 207.5561 -53.28158)
			)
		)
		(polygon
			(pts
				(xy 201.218546 -53.0606) (xy 201.015346 -53.0606) (xy 201.015346 -53.2638) (xy 201.218546 -53.2638)
			)
		)
		(polygon
			(pts
				(xy 200.354946 -53.0606) (xy 200.151746 -53.0606) (xy 200.151746 -53.2638) (xy 200.354946 -53.2638)
			)
		)
		(polygon
			(pts
				(xy 201.218546 -52.197) (xy 201.015346 -52.197) (xy 201.015346 -52.4002) (xy 201.218546 -52.4002)
			)
		)
		(polygon
			(pts
				(xy 200.354946 -52.197) (xy 200.151746 -52.197) (xy 200.151746 -52.4002) (xy 200.354946 -52.4002)
			)
		)
	)
	(zone
		(net "GND")
		(layer "F.Cu")
		(hatch none 0.5)
		(connect_pads
			(clearance 0.5)
		)
		(min_thickness 0.25)
		(fill yes
			(thermal_gap 0.5)
			(thermal_bridge_width 0.5)
			(island_removal_mode 0)
		)
		(polygon
			(pts
				(xy 500.867934 -20.461478) (xy 500.867934 -19.811492) (xy 500.868188 -19.811746) (xy 500.868188 -19.089878)
				(xy 500.013732 -18.235422) (xy 499.32336 -18.235422) (xy 498.933216 -18.625566) (xy 497.91493 -18.625566)
				(xy 497.825776 -18.71472) (xy 497.825776 -20.143724) (xy 497.7511 -20.2184) (xy 497.7511 -21.002752)
				(xy 497.9543 -21.205698) (xy 497.9543 -22.991318) (xy 498.148864 -23.186136) (xy 498.216936 -23.186136)
				(xy 498.4115 -23.3807) (xy 498.4115 -23.448518) (xy 498.414802 -23.45182) (xy 498.414802 -23.917402)
				(xy 498.4369 -23.9395) (xy 498.895878 -23.9395) (xy 498.975634 -23.859744) (xy 498.975634 -21.764244)
				(xy 499.553484 -21.186394) (xy 499.553484 -20.98167) (xy 499.849648 -20.685506) (xy 500.643906 -20.685506)
			)
		)
	)
	(zone
		(layer "F.Cu")
		(hatch none 0.5)
		(connect_pads
			(clearance 0)
		)
		(min_thickness 0.25)
		(keepout
			(tracks not_allowed)
			(vias allowed)
			(pads allowed)
			(copperpour not_allowed)
			(footprints allowed)
		)
		(placement
			(enabled no)
			(sheetname "")
		)
		(fill
			(thermal_gap 0.5)
			(thermal_bridge_width 0.5)
			(island_removal_mode 0)
		)
		(polygon
			(pts
				(xy 407.057098 -2.81432) (xy 407.212292 -2.969514) (xy 407.212292 -3.26771) (xy 407.313892 -3.26771)
				(xy 407.313892 -2.969514) (xy 407.469086 -2.81432)
				(arc
					(start 407.64079 -2.81432)
					(mid 408.164707 -2.88417)
					(end 407.64079 -2.95402)
				)
				(xy 407.526998 -2.95402) (xy 407.453592 -3.027426) (xy 407.453592 -3.26771)
				(arc
					(start 407.897838 -3.26771)
					(mid 408.281632 -2.884297)
					(end 407.898092 -2.50063)
				)
				(arc
					(start 406.628092 -2.50063)
					(mid 406.244552 -2.88417)
					(end 406.628092 -3.26771)
				)
				(xy 407.072592 -3.26771) (xy 407.072592 -3.027426) (xy 406.999186 -2.95402)
				(arc
					(start 406.885394 -2.95402)
					(mid 406.361477 -2.88417)
					(end 406.885394 -2.81432)
				)
			)
		)
	)
	(zone
		(layer "F.Cu")
		(hatch none 0.5)
		(connect_pads
			(clearance 0)
		)
		(min_thickness 0.25)
		(keepout
			(tracks not_allowed)
			(vias allowed)
			(pads allowed)
			(copperpour not_allowed)
			(footprints allowed)
		)
		(placement
			(enabled no)
			(sheetname "")
		)
		(fill
			(thermal_gap 0.5)
			(thermal_bridge_width 0.5)
			(island_removal_mode 0)
		)
		(polygon
			(pts
				(xy 378.581666 -131.699)
				(arc
					(start 378.568712 -131.826762)
					(mid 378.457842 -132.345268)
					(end 378.45492 -131.815078)
				)
				(arc
					(start 378.466858 -131.699508)
					(mid 378.104569 -132.089274)
					(end 378.4854 -132.461)
				)
				(arc
					(start 379.1458 -132.461)
					(mid 379.480278 -132.262443)
					(end 379.466094 -131.873752)
				)
				(xy 379.466094 -131.944364)
				(arc
					(start 379.46457 -131.945888)
					(mid 379.447288 -132.008837)
					(end 379.411992 -132.063744)
				)
				(arc
					(start 379.411992 -132.063744)
					(mid 378.897609 -132.17759)
					(end 379.351794 -131.910582)
				)
				(arc
					(start 379.351794 -131.807712)
					(mid 379.348449 -131.778755)
					(end 379.338586 -131.751324)
				)
				(arc
					(start 379.338586 -131.751324)
					(mid 379.245681 -131.712307)
					(end 379.1458 -131.699)
				)
			)
		)
	)
	(zone
		(net "P3V3_STBY")
		(layer "F.Cu")
		(hatch none 0.5)
		(connect_pads
			(clearance 0.5)
		)
		(min_thickness 0.25)
		(fill yes
			(thermal_gap 0.5)
			(thermal_bridge_width 0.5)
			(island_removal_mode 0)
		)
		(polygon
			(pts
				(xy 393.80922 -104.05364) (xy 394.73378 -104.05364) (xy 394.96238 -104.28224) (xy 394.96238 -104.68356)
				(xy 394.691108 -104.954832) (xy 394.682726 -104.94645) (xy 392.76909 -104.94645) (xy 392.47826 -104.65562)
				(xy 392.47826 -103.70058) (xy 392.66114 -103.5177) (xy 392.81862 -103.5177) (xy 393.10818 -103.5177)
				(xy 393.27328 -103.5177)
			)
		)
	)
	(zone
		(layer "F.Cu")
		(hatch none 0.5)
		(connect_pads
			(clearance 0)
		)
		(min_thickness 0.25)
		(keepout
			(tracks allowed)
			(vias allowed)
			(pads allowed)
			(copperpour allowed)
			(footprints allowed)
		)
		(placement
			(enabled no)
			(sheetname "")
		)
		(fill
			(thermal_gap 0.5)
			(thermal_bridge_width 0.5)
			(island_removal_mode 0)
		)
		(polygon
			(pts
				(xy 4.38404 -129.55524) (xy 4.38404 -126.88824) (xy 6.59892 -126.88824) (xy 6.59892 -129.55524)
			)
		)
	)
	(zone
		(layer "F.Cu")
		(hatch none 0.5)
		(connect_pads
			(clearance 0)
		)
		(min_thickness 0.25)
		(keepout
			(tracks allowed)
			(vias allowed)
			(pads allowed)
			(copperpour allowed)
			(footprints not_allowed)
		)
		(placement
			(enabled no)
			(sheetname "")
		)
		(fill
			(thermal_gap 0.5)
			(thermal_bridge_width 0.5)
			(island_removal_mode 0)
		)
		(polygon
			(pts
				(xy 21.836888 -49.299876) (xy 15.216886 -49.299876) (xy 15.216886 -54.099968) (xy 21.836888 -54.099968)
			)
		)
	)
	(zone
		(layer "F.Cu")
		(hatch none 0.5)
		(connect_pads
			(clearance 0)
		)
		(min_thickness 0.25)
		(keepout
			(tracks allowed)
			(vias allowed)
			(pads allowed)
			(copperpour allowed)
			(footprints allowed)
		)
		(placement
			(enabled no)
			(sheetname "")
		)
		(fill
			(thermal_gap 0.5)
			(thermal_bridge_width 0.5)
			(island_removal_mode 0)
		)
		(polygon
			(pts
				(xy 393.81684 -151.73452) (xy 393.81684 -150.89886) (xy 393.04722 -150.89886) (xy 393.04722 -149.964902)
				(xy 393.81684 -149.964902) (xy 395.70914 -149.964902) (xy 395.70914 -151.73452)
			)
		)
	)
	(zone
		(net "VR_PVCCIN_CPU0_PHASE3")
		(layer "F.Cu")
		(hatch none 0.5)
		(connect_pads
			(clearance 0.5)
		)
		(min_thickness 0.25)
		(fill yes
			(thermal_gap 0.5)
			(thermal_bridge_width 0.5)
			(island_removal_mode 0)
		)
		(polygon
			(pts
				(xy 201.7522 -75.911202) (xy 205.657196 -75.911202) (xy 206.558896 -75.911202) (xy 206.884778 -75.58532)
				(xy 206.884778 -71.13905) (xy 206.57693 -70.831202) (xy 205.657196 -70.831202) (xy 201.7776 -70.831202)
				(xy 201.4728 -71.136002) (xy 201.4728 -75.631802)
			)
		)
	)
	(zone
		(layer "F.Cu")
		(hatch none 0.5)
		(connect_pads
			(clearance 0)
		)
		(min_thickness 0.25)
		(keepout
			(tracks not_allowed)
			(vias allowed)
			(pads allowed)
			(copperpour not_allowed)
			(footprints allowed)
		)
		(placement
			(enabled no)
			(sheetname "")
		)
		(fill
			(thermal_gap 0.5)
			(thermal_bridge_width 0.5)
			(island_removal_mode 0)
		)
		(polygon
			(pts
				(xy 439.187082 -9.64057) (xy 439.187082 -9.925304) (xy 439.018426 -10.09396)
				(arc
					(start 439.012584 -10.09396)
					(mid 438.489358 -10.043941)
					(end 438.999122 -9.915906)
				)
				(xy 439.047382 -9.867392) (xy 439.047382 -9.64057)
				(arc
					(start 438.755536 -9.64057)
					(mid 438.371996 -10.023983)
					(end 438.755282 -10.40765)
				)
				(arc
					(start 439.720482 -10.40765)
					(mid 440.104022 -10.02411)
					(end 439.720482 -9.64057)
				)
				(xy 439.428382 -9.64057) (xy 439.428382 -9.795256)
				(arc
					(start 439.503058 -9.869932)
					(mid 439.973613 -10.108311)
					(end 439.453782 -10.018268)
				)
				(xy 439.288682 -9.853168) (xy 439.288682 -9.64057)
			)
		)
	)
	(zone
		(layer "F.Cu")
		(hatch none 0.5)
		(connect_pads
			(clearance 0)
		)
		(min_thickness 0.25)
		(keepout
			(tracks not_allowed)
			(vias allowed)
			(pads allowed)
			(copperpour not_allowed)
			(footprints allowed)
		)
		(placement
			(enabled no)
			(sheetname "")
		)
		(fill
			(thermal_gap 0.5)
			(thermal_bridge_width 0.5)
			(island_removal_mode 0)
		)
		(polygon
			(pts
				(xy 445.491108 -10.030714) (xy 445.500506 -10.058146) (xy 445.516762 -10.105644) (xy 445.613282 -10.07237)
				(xy 445.597026 -10.024872) (xy 445.587628 -9.997694) (xy 445.587628 -9.99744) (xy 445.600328 -9.971532)
				(arc
					(start 445.695832 -9.77646)
					(mid 445.988197 -9.336185)
					(end 445.821308 -9.837674)
				)
				(xy 445.738504 -10.007092) (xy 445.745362 -10.027158) (xy 445.996822 -9.941052)
				(arc
					(start 445.99606 -9.938512)
					(mid 446.234312 -9.45134)
					(end 445.74714 -9.213088)
				)
				(xy 445.746378 -9.210548) (xy 444.883032 -9.506458) (xy 444.883032 -9.506712)
				(arc
					(start 444.883794 -9.508744)
					(mid 444.645262 -9.996095)
					(end 445.13246 -10.234422)
				)
				(xy 445.133222 -10.236962) (xy 445.384682 -10.150856) (xy 445.377824 -10.13079)
				(arc
					(start 445.208406 -10.047732)
					(mid 444.768486 -9.754325)
					(end 445.269874 -9.922256)
				)
				(xy 445.4652 -10.018014)
			)
		)
	)
	(zone
		(net "PVSA_CPU1")
		(layer "F.Cu")
		(hatch none 0.5)
		(connect_pads
			(clearance 0.5)
		)
		(min_thickness 0.25)
		(fill yes
			(thermal_gap 0.5)
			(thermal_bridge_width 0.5)
			(island_removal_mode 0)
		)
		(polygon
			(pts
				(xy 43.747182 -92.9132) (xy 43.17746 -93.482922) (xy 43.17746 -99.036124) (xy 43.391328 -99.249992)
				(xy 44.686982 -100.5459) (xy 50.0761 -100.5459) (xy 52.705 -97.917) (xy 52.705 -94.0816) (xy 51.5366 -92.9132)
			)
		)
		(polygon
			(pts
				(xy 49.911 -94.0943) (xy 49.7078 -94.0943) (xy 49.7078 -94.2975) (xy 49.911 -94.2975)
			)
		)
		(polygon
			(pts
				(xy 49.149 -94.0943) (xy 48.9458 -94.0943) (xy 48.9458 -94.2975) (xy 49.149 -94.2975)
			)
		)
	)
	(zone
		(layer "F.Cu")
		(hatch none 0.5)
		(connect_pads
			(clearance 0)
		)
		(min_thickness 0.25)
		(keepout
			(tracks allowed)
			(vias allowed)
			(pads allowed)
			(copperpour allowed)
			(footprints not_allowed)
		)
		(placement
			(enabled no)
			(sheetname "")
		)
		(fill
			(thermal_gap 0.5)
			(thermal_bridge_width 0.5)
			(island_removal_mode 0)
		)
		(polygon
			(pts
				(xy 194.429888 -42.049954) (xy 194.429888 -111.05007) (xy 203.030074 -111.05007) (xy 203.030074 -42.049954)
			)
		)
	)
	(zone
		(net "PVCCIN_CPU1")
		(layer "F.Cu")
		(hatch none 0.5)
		(connect_pads
			(clearance 0.5)
		)
		(min_thickness 0.25)
		(fill yes
			(thermal_gap 0.5)
			(thermal_bridge_width 0.5)
			(island_removal_mode 0)
		)
		(polygon
			(pts
				(arc
					(start 104.417876 -88.889586)
					(mid 104.569085 -88.920831)
					(end 104.695498 -89.009474)
				)
				(xy 104.829102 -89.009474) (xy 105.31856 -89.498678) (xy 105.322624 -89.494614) (xy 113.857786 -89.494614)
				(xy 115.254532 -88.097868) (xy 115.254532 -86.294468) (xy 115.064032 -86.103968) (xy 113.3856 -86.103968)
				(xy 112.899952 -85.61832) (xy 110.81258 -85.61832) (xy 109.65434 -84.46008) (xy 107.98048 -84.46008)
				(xy 107.95 -84.490814) (xy 107.95 -85.662008) (xy 107.150408 -86.4616) (xy 98.35261 -86.4616) (xy 97.004124 -85.113114)
				(xy 96.111314 -85.113114) (xy 94.650814 -83.652614) (xy 93.076014 -83.652614) (xy 92.368624 -82.945224)
				(xy 92.368624 -79.567278) (xy 92.368116 -79.567024) (xy 92.368116 -78.975204) (xy 92.368624 -78.97495)
				(xy 92.368624 -78.953614) (xy 92.495624 -78.826614) (xy 92.51696 -78.826614) (xy 92.644214 -78.699106)
				(xy 93.109034 -78.699106) (xy 93.23451 -78.824582) (xy 96.433132 -78.824582) (xy 96.433132 -78.954122)
				(xy 96.656652 -79.177642) (xy 96.656652 -79.859632) (xy 96.83242 -80.0354) (xy 103.776526 -80.0354)
				(xy 103.935022 -79.876904) (xy 103.935022 -78.575662) (xy 103.6066 -78.24724) (xy 103.6066 -77.201268)
				(xy 98.38944 -77.201268) (xy 98.38944 -77.19187) (xy 97.806764 -77.19187) (xy 97.806764 -77.177138)
				(xy 97.32518 -77.177138) (xy 97.32518 -77.19187) (xy 96.562164 -77.19187) (xy 96.562164 -77.177138)
				(xy 96.08058 -77.177138) (xy 96.08058 -77.19187) (xy 95.317564 -77.19187) (xy 95.317564 -77.177138)
				(xy 94.83598 -77.177138) (xy 94.83598 -77.19187) (xy 94.072964 -77.19187) (xy 94.072964 -77.177138)
				(xy 93.59138 -77.177138) (xy 93.59138 -77.19187) (xy 92.828364 -77.19187) (xy 92.828364 -76.947522)
				(xy 92.495116 -76.947522) (xy 92.495116 -74.63663) (xy 98.539554 -74.63663) (xy 98.542856 -74.639678)
				(xy 103.6066 -74.639678) (xy 103.6066 -72.95769) (xy 103.5304 -72.88149) (xy 98.397568 -72.88149)
				(xy 98.38563 -72.893428) (xy 93.073728 -72.893428) (xy 93.054424 -72.87387) (xy 92.828364 -72.87387)
				(xy 92.828364 -72.673718) (xy 92.495116 -72.673718) (xy 92.495116 -70.876668) (xy 93.121226 -70.250558)
				(xy 96.10598 -70.250558) (xy 96.10598 -67.677538) (xy 98.672904 -67.677538) (xy 98.672904 -66.70929)
				(xy 106.28249 -66.70929) (xy 106.287824 -66.714624) (xy 108.494576 -66.714624) (xy 108.712 -66.4972)
				(xy 109.8296 -66.4972) (xy 110.0836 -66.7512) (xy 110.0836 -67.5386) (xy 110.236 -67.691) (xy 110.6424 -67.691)
				(xy 110.9472 -67.3862) (xy 110.998 -67.3862) (xy 111.0234 -67.3608) (xy 111.0234 -67.1322) (xy 111.4806 -66.675)
				(xy 112.7252 -66.675) (xy 113.1316 -67.0814) (xy 113.7412 -67.0814) (xy 114.4524 -67.7926) (xy 114.4524 -68.28409)
				(xy 115.943634 -68.28409) (xy 116.10467 -68.123054) (xy 116.10467 -66.853054) (xy 115.866164 -66.614548)
				(arc
					(start 115.832382 -66.634614)
					(mid 115.4006 -66.603819)
					(end 115.275614 -66.189352)
				)
				(arc
					(start 115.275614 -66.189352)
					(mid 115.260995 -66.098564)
					(end 115.179094 -66.056764)
				)
				(arc
					(start 115.071398 -66.056764)
					(mid 114.790926 -66.191593)
					(end 114.503454 -66.072512)
				)
				(xy 114.488468 -66.056764) (xy 114.475006 -66.056764) (xy 114.35842 -65.940178) (xy 114.35842 -65.91427)
				(xy 114.098832 -65.654682)
				(arc
					(start 114.06759 -65.667636)
					(mid 113.74111 -65.651081)
					(end 113.547398 -65.387728)
				)
				(xy 113.54435 -65.372488)
				(arc
					(start 113.294668 -65.122806)
					(mid 113.185407 -65.180961)
					(end 113.063274 -65.201038)
				)
				(arc
					(start 112.662462 -65.201038)
					(mid 112.589639 -65.23179)
					(end 112.560862 -65.305432)
				)
				(arc
					(start 112.560862 -65.305432)
					(mid 112.546813 -65.414871)
					(end 112.499902 -65.514728)
				)
				(arc
					(start 112.499902 -65.514728)
					(mid 112.305129 -65.657156)
					(end 112.064292 -65.64249)
				)
				(arc
					(start 112.064292 -65.64249)
					(mid 111.848995 -65.301428)
					(end 112.0902 -64.978026)
				)
				(arc
					(start 112.0902 -64.978026)
					(mid 112.118593 -64.954006)
					(end 112.122966 -64.917066)
				)
				(arc
					(start 112.122966 -64.917066)
					(mid 112.112963 -64.86404)
					(end 112.11052 -64.810132)
				)
				(arc
					(start 112.11052 -64.810132)
					(mid 112.081673 -64.736889)
					(end 112.009174 -64.706246)
				)
				(arc
					(start 111.803688 -64.706246)
					(mid 111.730954 -64.736907)
					(end 111.702088 -64.810386)
				)
				(arc
					(start 111.702088 -64.810386)
					(mid 111.697466 -64.877717)
					(end 111.680244 -64.942974)
				)
				(arc
					(start 111.680244 -64.942974)
					(mid 111.424924 -65.167287)
					(end 111.097822 -65.0748)
				)
				(arc
					(start 111.097822 -65.0748)
					(mid 110.998989 -64.741283)
					(end 111.23168 -64.482726)
				)
				(arc
					(start 111.23168 -64.482726)
					(mid 111.260073 -64.458706)
					(end 111.264446 -64.421766)
				)
				(arc
					(start 111.264446 -64.421766)
					(mid 111.254443 -64.36874)
					(end 111.252 -64.314832)
				)
				(arc
					(start 111.252 -64.314832)
					(mid 111.22325 -64.241164)
					(end 111.1504 -64.210438)
				)
				(arc
					(start 110.944914 -64.210438)
					(mid 110.872003 -64.241281)
					(end 110.843314 -64.315086)
				)
				(arc
					(start 110.843314 -64.315086)
					(mid 110.388404 -64.66651)
					(end 110.193836 -64.125602)
				)
				(arc
					(start 110.193836 -64.125602)
					(mid 110.199607 -64.020888)
					(end 110.109762 -63.966852)
				)
				(xy 109.986572 -63.966852)
				(arc
					(start 109.972602 -63.995554)
					(mid 109.831879 -64.152256)
					(end 109.629448 -64.210438)
				)
				(arc
					(start 109.227874 -64.210438)
					(mid 109.154963 -64.241281)
					(end 109.126274 -64.315086)
				)
				(arc
					(start 109.126274 -64.315086)
					(mid 108.671364 -64.66651)
					(end 108.476796 -64.125602)
				)
				(arc
					(start 108.476796 -64.125602)
					(mid 108.482567 -64.020888)
					(end 108.392722 -63.966852)
				)
				(xy 108.273342 -63.966852)
				(arc
					(start 108.242354 -64.020446)
					(mid 107.721146 -64.15913)
					(end 107.582462 -63.637922)
				)
				(arc
					(start 107.597448 -63.612268)
					(mid 107.597652 -63.510513)
					(end 107.509564 -63.459614)
				)
				(xy 107.415584 -63.459614)
				(arc
					(start 107.402122 -63.489586)
					(mid 107.261474 -63.654173)
					(end 107.053888 -63.715646)
				)
				(arc
					(start 106.652568 -63.715646)
					(mid 106.580087 -63.746307)
					(end 106.551222 -63.819532)
				)
				(arc
					(start 106.551222 -63.819532)
					(mid 106.549621 -63.863615)
					(end 106.542586 -63.907162)
				)
				(arc
					(start 106.542586 -63.907162)
					(mid 106.204794 -64.18572)
					(end 105.852722 -63.92545)
				)
				(arc
					(start 105.852722 -63.92545)
					(mid 105.844502 -63.766822)
					(end 105.906062 -63.620396)
				)
				(arc
					(start 105.906062 -63.620396)
					(mid 105.913926 -63.514928)
					(end 105.823766 -63.459614)
				)
				(xy 97.360232 -63.459614)
				(arc
					(start 97.3582 -63.461646)
					(mid 97.331632 -63.480138)
					(end 97.321624 -63.510922)
				)
				(arc
					(start 97.321624 -63.510922)
					(mid 97.211497 -63.783314)
					(end 96.94037 -63.896494)
				)
				(arc
					(start 96.36887 -63.896494)
					(mid 96.09776 -63.783296)
					(end 95.987616 -63.510922)
				)
				(arc
					(start 95.987616 -63.510922)
					(mid 95.972918 -63.474671)
					(end 95.936816 -63.459614)
				)
				(arc
					(start 95.655384 -63.459614)
					(mid 95.619284 -63.474673)
					(end 95.604584 -63.510922)
				)
				(arc
					(start 95.604584 -63.510922)
					(mid 95.494457 -63.783314)
					(end 95.22333 -63.896494)
				)
				(arc
					(start 94.847664 -63.896494)
					(mid 94.77493 -63.927155)
					(end 94.746064 -64.000634)
				)
				(arc
					(start 94.746064 -64.000634)
					(mid 94.637968 -64.276693)
					(end 94.36481 -64.391794)
				)
				(arc
					(start 93.98889 -64.391794)
					(mid 93.916321 -64.422546)
					(end 93.887544 -64.495934)
				)
				(arc
					(start 93.887544 -64.495934)
					(mid 93.779448 -64.771993)
					(end 93.50629 -64.887094)
				)
				(arc
					(start 93.130624 -64.887094)
					(mid 93.05789 -64.917755)
					(end 93.029024 -64.991234)
				)
				(arc
					(start 93.029024 -64.991234)
					(mid 92.920928 -65.267293)
					(end 92.64777 -65.382394)
				)
				(arc
					(start 92.27185 -65.382394)
					(mid 92.199281 -65.413146)
					(end 92.170504 -65.486534)
				)
				(arc
					(start 92.170504 -65.486534)
					(mid 92.062408 -65.762593)
					(end 91.78925 -65.877694)
				)
				(arc
					(start 91.413584 -65.877694)
					(mid 91.34085 -65.908355)
					(end 91.311984 -65.981834)
				)
				(arc
					(start 91.311984 -65.981834)
					(mid 91.203888 -66.257893)
					(end 90.93073 -66.372994)
				)
				(xy 90.7542 -66.372994) (xy 87.8332 -69.293994)
				(arc
					(start 87.8332 -72.114918)
					(mid 87.692954 -72.262302)
					(end 87.496904 -72.316594)
				)
				(arc
					(start 86.925404 -72.316594)
					(mid 86.692982 -72.237623)
					(end 86.55685 -72.033384)
				)
				(xy 86.546944 -71.995538) (xy 86.158324 -71.995538)
				(arc
					(start 86.148418 -72.033384)
					(mid 86.012243 -72.237567)
					(end 85.779864 -72.316594)
				)
				(arc
					(start 85.208364 -72.316594)
					(mid 84.975942 -72.237623)
					(end 84.83981 -72.033384)
				)
				(xy 84.829904 -71.995538) (xy 84.441284 -71.995538)
				(arc
					(start 84.431378 -72.033384)
					(mid 84.295203 -72.237567)
					(end 84.062824 -72.316594)
				)
				(arc
					(start 83.491324 -72.316594)
					(mid 83.258902 -72.237623)
					(end 83.12277 -72.033384)
				)
				(xy 83.112864 -71.995538) (xy 82.724244 -71.995538)
				(arc
					(start 82.714338 -72.033384)
					(mid 82.578163 -72.237567)
					(end 82.345784 -72.316594)
				)
				(arc
					(start 81.774284 -72.316594)
					(mid 81.541862 -72.237623)
					(end 81.40573 -72.033384)
				)
				(xy 81.395824 -71.995538) (xy 81.007204 -71.995538)
				(arc
					(start 80.997298 -72.033384)
					(mid 80.861123 -72.237567)
					(end 80.628744 -72.316594)
				)
				(arc
					(start 80.252824 -72.316594)
					(mid 80.180255 -72.347346)
					(end 80.151478 -72.420734)
				)
				(arc
					(start 80.151478 -72.420734)
					(mid 80.043382 -72.696793)
					(end 79.770224 -72.811894)
				)
				(arc
					(start 79.198724 -72.811894)
					(mid 78.81747 -72.43064)
					(end 79.198724 -72.049386)
				)
				(arc
					(start 79.57439 -72.049386)
					(mid 79.647213 -72.018634)
					(end 79.67599 -71.944992)
				)
				(arc
					(start 79.67599 -71.944992)
					(mid 79.784086 -71.668933)
					(end 80.057244 -71.553578)
				)
				(arc
					(start 80.124554 -71.553578)
					(mid 80.218386 -71.490942)
					(end 80.196436 -71.38035)
				)
				(xy 80.14208 -71.325994)
				(arc
					(start 80.057244 -71.325994)
					(mid 79.769589 -71.194959)
					(end 79.679546 -70.891908)
				)
				(xy 79.683102 -70.867016) (xy 79.64678 -70.830694)
				(arc
					(start 79.198216 -70.830694)
					(mid 79.039683 -70.796054)
					(end 78.909926 -70.698614)
				)
				(arc
					(start 78.342236 -70.698614)
					(mid 78.212473 -70.796043)
					(end 78.053946 -70.830694)
				)
				(arc
					(start 77.48143 -70.830694)
					(mid 77.322897 -70.796054)
					(end 77.19314 -70.698614)
				)
				(arc
					(start 76.625196 -70.698614)
					(mid 76.495433 -70.796043)
					(end 76.336906 -70.830694)
				)
				(arc
					(start 75.76439 -70.830694)
					(mid 75.605857 -70.796054)
					(end 75.4761 -70.698614)
				)
				(arc
					(start 74.908156 -70.698614)
					(mid 74.778393 -70.796043)
					(end 74.619866 -70.830694)
				)
				(arc
					(start 74.04735 -70.830694)
					(mid 73.888817 -70.796054)
					(end 73.75906 -70.698614)
				)
				(arc
					(start 73.191116 -70.698614)
					(mid 73.061353 -70.796043)
					(end 72.902826 -70.830694)
				)
				(arc
					(start 72.33031 -70.830694)
					(mid 72.171777 -70.796054)
					(end 72.04202 -70.698614)
				)
				(xy 71.915782 -70.698614)
				(arc
					(start 71.722742 -70.505574)
					(mid 71.625067 -70.479379)
					(end 71.55307 -70.550532)
				)
				(arc
					(start 71.55307 -70.550532)
					(mid 71.416447 -70.75267)
					(end 71.185278 -70.830694)
				)
				(arc
					(start 70.613778 -70.830694)
					(mid 70.340712 -70.715503)
					(end 70.232524 -70.439534)
				)
				(arc
					(start 70.232524 -70.439534)
					(mid 70.20377 -70.366124)
					(end 70.131178 -70.335394)
				)
				(arc
					(start 69.755258 -70.335394)
					(mid 69.482192 -70.220203)
					(end 69.374004 -69.944234)
				)
				(arc
					(start 69.374004 -69.944234)
					(mid 69.345068 -69.870901)
					(end 69.272404 -69.840348)
				)
				(arc
					(start 68.896738 -69.840094)
					(mid 68.723351 -69.798516)
					(end 68.587874 -69.682614)
				)
				(arc
					(start 68.060062 -69.682614)
					(mid 67.924674 -69.798412)
					(end 67.751452 -69.840094)
				)
				(arc
					(start 67.10299 -69.840094)
					(mid 67.031484 -69.83328)
					(end 66.962528 -69.81317)
				)
				(xy 66.953384 -69.809614) (xy 66.638424 -69.809614) (xy 48.795178 -51.966368) (xy 44.172632 -51.966368)
				(xy 43.6372 -52.5018) (xy 43.6372 -92.332048) (xy 43.891708 -92.586556) (xy 48.133762 -92.586556)
				(xy 48.23714 -92.482924) (xy 48.23714 -91.198446) (xy 48.23714 -90.991944) (xy 48.437292 -90.791792)
				(xy 50.49139 -90.791792) (xy 50.784252 -91.084654) (xy 50.784252 -92.213938) (xy 51.000406 -92.430092)
				(xy 60.446412 -92.430092)
				(arc
					(start 72.902318 -79.974186)
					(mid 73.107268 -80.033911)
					(end 73.248012 -80.194404)
				)
				(xy 73.261728 -80.223614) (xy 73.688448 -80.223614)
				(arc
					(start 73.702164 -80.194404)
					(mid 73.842929 -80.033944)
					(end 74.047858 -79.974186)
				)
				(arc
					(start 74.619358 -79.974186)
					(mid 74.824308 -80.033911)
					(end 74.965052 -80.194404)
				)
				(xy 74.978768 -80.223614) (xy 75.405488 -80.223614)
				(arc
					(start 75.419204 -80.194404)
					(mid 75.559969 -80.033944)
					(end 75.764898 -79.974186)
				)
				(arc
					(start 76.336398 -79.974186)
					(mid 76.541348 -80.033911)
					(end 76.682092 -80.194404)
				)
				(xy 76.695808 -80.223614) (xy 77.122528 -80.223614)
				(arc
					(start 77.136244 -80.194404)
					(mid 77.277009 -80.033944)
					(end 77.481938 -79.974186)
				)
				(arc
					(start 78.053438 -79.974186)
					(mid 78.258388 -80.033911)
					(end 78.399132 -80.194404)
				)
				(xy 78.412848 -80.223614) (xy 78.839314 -80.223614)
				(arc
					(start 78.85303 -80.194404)
					(mid 78.993795 -80.033944)
					(end 79.198724 -79.974186)
				)
				(arc
					(start 79.57439 -79.974186)
					(mid 79.647213 -79.943434)
					(end 79.67599 -79.869792)
				)
				(arc
					(start 79.67599 -79.869792)
					(mid 79.784086 -79.593733)
					(end 80.057244 -79.478378)
				)
				(arc
					(start 80.433164 -79.478378)
					(mid 80.505645 -79.447717)
					(end 80.53451 -79.374492)
				)
				(arc
					(start 80.53451 -79.354934)
					(mid 80.505756 -79.281524)
					(end 80.433164 -79.250794)
				)
				(arc
					(start 80.057244 -79.250794)
					(mid 79.784178 -79.135603)
					(end 79.67599 -78.859634)
				)
				(arc
					(start 79.67599 -78.859634)
					(mid 79.647147 -78.786133)
					(end 79.57439 -78.755494)
				)
				(arc
					(start 79.198724 -78.755494)
					(mid 78.81747 -78.37424)
					(end 79.198724 -77.992986)
				)
				(arc
					(start 79.770224 -77.992986)
					(mid 80.043201 -78.108086)
					(end 80.151478 -78.383892)
				)
				(arc
					(start 80.151478 -78.383892)
					(mid 80.180321 -78.457393)
					(end 80.253078 -78.488032)
				)
				(arc
					(start 80.628744 -78.487778)
					(mid 80.901992 -78.603046)
					(end 81.009998 -78.879192)
				)
				(arc
					(start 81.009998 -78.879192)
					(mid 81.038748 -78.95286)
					(end 81.111598 -78.983586)
				)
				(arc
					(start 81.29143 -78.983586)
					(mid 81.364253 -78.952834)
					(end 81.39303 -78.879192)
				)
				(arc
					(start 81.39303 -78.879192)
					(mid 81.501126 -78.603133)
					(end 81.774284 -78.487778)
				)
				(arc
					(start 82.345784 -78.487778)
					(mid 82.619032 -78.603046)
					(end 82.727038 -78.879192)
				)
				(arc
					(start 82.727038 -78.879192)
					(mid 82.755788 -78.95286)
					(end 82.828638 -78.983586)
				)
				(arc
					(start 83.00847 -78.983586)
					(mid 83.081293 -78.952834)
					(end 83.11007 -78.879192)
				)
				(arc
					(start 83.11007 -78.879192)
					(mid 83.218166 -78.603133)
					(end 83.491324 -78.487778)
				)
				(arc
					(start 84.062824 -78.487778)
					(mid 84.336072 -78.603046)
					(end 84.444078 -78.879192)
				)
				(arc
					(start 84.444078 -78.879192)
					(mid 84.472828 -78.95286)
					(end 84.545678 -78.983586)
				)
				(arc
					(start 84.72551 -78.983586)
					(mid 84.798333 -78.952834)
					(end 84.82711 -78.879192)
				)
				(arc
					(start 84.82711 -78.879192)
					(mid 84.935206 -78.603133)
					(end 85.208364 -78.487778)
				)
				(arc
					(start 85.779864 -78.487778)
					(mid 86.053112 -78.603046)
					(end 86.161118 -78.879192)
				)
				(arc
					(start 86.161118 -78.879192)
					(mid 86.189868 -78.95286)
					(end 86.262718 -78.983586)
				)
				(arc
					(start 86.44255 -78.983586)
					(mid 86.515373 -78.952834)
					(end 86.54415 -78.879192)
				)
				(arc
					(start 86.54415 -78.879192)
					(mid 86.652246 -78.603133)
					(end 86.925404 -78.487778)
				)
				(arc
					(start 87.496904 -78.487778)
					(mid 87.878412 -78.869286)
					(end 87.496904 -79.250794)
				)
				(arc
					(start 87.120984 -79.250794)
					(mid 87.048415 -79.281546)
					(end 87.019638 -79.354934)
				)
				(arc
					(start 87.019638 -79.374492)
					(mid 87.048481 -79.447993)
					(end 87.121238 -79.478632)
				)
				(arc
					(start 87.496904 -79.478378)
					(mid 87.878412 -79.859886)
					(end 87.496904 -80.241394)
				)
				(arc
					(start 87.45474 -80.241394)
					(mid 87.360908 -80.30403)
					(end 87.382858 -80.414622)
				)
				(xy 87.437468 -80.468978)
				(arc
					(start 87.496904 -80.468978)
					(mid 87.69458 -80.524228)
					(end 87.834978 -80.673956)
				)
				(xy 88.096852 -80.673956) (xy 88.236044 -80.813148) (xy 88.236044 -80.964786)
				(arc
					(start 88.355424 -80.964786)
					(mid 88.736678 -81.34604)
					(end 88.355424 -81.727294)
				)
				(xy 88.236044 -81.727294) (xy 88.236044 -81.955386)
				(arc
					(start 88.355424 -81.955386)
					(mid 88.736678 -82.33664)
					(end 88.355424 -82.717894)
				)
				(xy 88.236044 -82.717894) (xy 88.236044 -82.945986)
				(arc
					(start 88.355424 -82.945986)
					(mid 88.736678 -83.32724)
					(end 88.355424 -83.708494)
				)
				(xy 88.236044 -83.708494) (xy 88.236044 -83.936586)
				(arc
					(start 88.355424 -83.936586)
					(mid 88.628401 -84.051686)
					(end 88.736678 -84.327492)
				)
				(arc
					(start 88.736678 -84.327492)
					(mid 88.765521 -84.400993)
					(end 88.838278 -84.431632)
				)
				(arc
					(start 89.213944 -84.431378)
					(mid 89.487192 -84.546646)
					(end 89.595198 -84.822792)
				)
				(arc
					(start 89.595198 -84.822792)
					(mid 89.623948 -84.89646)
					(end 89.696798 -84.927186)
				)
				(arc
					(start 90.07221 -84.927186)
					(mid 90.345187 -85.042286)
					(end 90.453464 -85.318092)
				)
				(arc
					(start 90.453464 -85.318092)
					(mid 90.482307 -85.391593)
					(end 90.555064 -85.422232)
				)
				(arc
					(start 90.93073 -85.421978)
					(mid 91.203978 -85.537246)
					(end 91.311984 -85.813392)
				)
				(arc
					(start 91.311984 -85.813392)
					(mid 91.340734 -85.88706)
					(end 91.413584 -85.917786)
				)
				(arc
					(start 91.78925 -85.917786)
					(mid 92.062227 -86.032886)
					(end 92.170504 -86.308692)
				)
				(arc
					(start 92.170504 -86.308692)
					(mid 92.199347 -86.382193)
					(end 92.272104 -86.412832)
				)
				(arc
					(start 92.64777 -86.412578)
					(mid 92.921018 -86.527846)
					(end 93.029024 -86.803992)
				)
				(arc
					(start 93.029024 -86.803992)
					(mid 93.057774 -86.87766)
					(end 93.130624 -86.908386)
				)
				(arc
					(start 93.50629 -86.908386)
					(mid 93.779267 -87.023486)
					(end 93.887544 -87.299292)
				)
				(arc
					(start 93.887544 -87.299292)
					(mid 93.916387 -87.372793)
					(end 93.989144 -87.403432)
				)
				(arc
					(start 94.36481 -87.403178)
					(mid 94.638058 -87.518446)
					(end 94.746064 -87.794592)
				)
				(arc
					(start 94.746064 -87.794592)
					(mid 94.774814 -87.86826)
					(end 94.847664 -87.898986)
				)
				(arc
					(start 95.027496 -87.898986)
					(mid 95.100319 -87.868234)
					(end 95.129096 -87.794592)
				)
				(arc
					(start 95.129096 -87.794592)
					(mid 95.237192 -87.518533)
					(end 95.51035 -87.403178)
				)
				(arc
					(start 96.08185 -87.403178)
					(mid 96.355098 -87.518446)
					(end 96.463104 -87.794592)
				)
				(arc
					(start 96.463104 -87.794592)
					(mid 96.491854 -87.86826)
					(end 96.564704 -87.898986)
				)
				(arc
					(start 96.94037 -87.898986)
					(mid 97.213347 -88.014086)
					(end 97.321624 -88.289892)
				)
				(arc
					(start 97.321624 -88.289892)
					(mid 97.350467 -88.363393)
					(end 97.423224 -88.394032)
				)
				(arc
					(start 97.79889 -88.393778)
					(mid 98.04988 -88.48805)
					(end 98.176842 -88.724232)
				)
				(xy 98.179128 -88.74125) (xy 98.228912 -88.791288) (xy 98.279712 -88.842088) (xy 98.327464 -88.889586)
				(arc
					(start 98.65741 -88.889586)
					(mid 98.903429 -88.979585)
					(end 99.03333 -89.207086)
				)
				(xy 99.040696 -89.24925) (xy 99.41941 -89.24925) (xy 99.426776 -89.207086)
				(arc
					(start 99.433888 -89.173558)
					(mid 99.429649 -89.136431)
					(end 99.401122 -89.112344)
				)
				(arc
					(start 99.401122 -89.112344)
					(mid 99.312555 -88.484023)
					(end 99.871276 -88.785192)
				)
				(arc
					(start 99.871276 -88.785192)
					(mid 99.899937 -88.858769)
					(end 99.972622 -88.889586)
				)
				(arc
					(start 100.374196 -88.889586)
					(mid 100.620215 -88.979585)
					(end 100.750116 -89.207086)
				)
				(xy 100.757482 -89.24925) (xy 101.13645 -89.24925) (xy 101.143816 -89.207086)
				(arc
					(start 101.150928 -89.173558)
					(mid 101.146689 -89.136431)
					(end 101.118162 -89.112344)
				)
				(arc
					(start 101.118162 -89.112344)
					(mid 101.029595 -88.484023)
					(end 101.588316 -88.785192)
				)
				(arc
					(start 101.588316 -88.785192)
					(mid 101.616977 -88.858769)
					(end 101.689662 -88.889586)
				)
				(arc
					(start 102.091236 -88.889586)
					(mid 102.337255 -88.979585)
					(end 102.467156 -89.207086)
				)
				(xy 102.474522 -89.24925)
				(arc
					(start 102.642162 -89.24925)
					(mid 102.737749 -89.182084)
					(end 102.706932 -89.069418)
				)
				(arc
					(start 102.706932 -89.069418)
					(mid 102.604658 -88.93788)
					(end 102.568248 -88.775286)
				)
				(arc
					(start 102.568248 -88.165686)
					(mid 102.949756 -87.784178)
					(end 103.331264 -88.165686)
				)
				(arc
					(start 103.331264 -88.775286)
					(mid 103.294855 -88.93788)
					(end 103.19258 -89.069418)
				)
				(arc
					(start 103.19258 -89.069418)
					(mid 103.161796 -89.182072)
					(end 103.25735 -89.24925)
				)
				(xy 103.42499 -89.24925)
				(arc
					(start 103.432356 -89.207086)
					(mid 103.562236 -88.979559)
					(end 103.808276 -88.889586)
				)
			)
		)
		(polygon
			(pts
				(arc
					(start 102.091236 -87.924386)
					(mid 102.091236 -88.636094)
					(end 102.091236 -87.924386)
				)
			)
		)
		(polygon
			(pts
				(arc
					(start 100.374196 -87.924386)
					(mid 100.374196 -88.636094)
					(end 100.374196 -87.924386)
				)
			)
		)
		(polygon
			(pts
				(arc
					(start 97.79889 -87.428832)
					(mid 97.79889 -88.14054)
					(end 97.79889 -87.428832)
				)
			)
		)
		(polygon
			(pts
				(xy 49.911 -87.01532) (xy 49.7078 -87.01532) (xy 49.7078 -87.21852) (xy 49.911 -87.21852)
			)
		)
		(polygon
			(pts
				(xy 49.149 -87.01532) (xy 48.9458 -87.01532) (xy 48.9458 -87.21852) (xy 49.149 -87.21852)
			)
		)
		(polygon
			(pts
				(arc
					(start 96.94037 -86.933786)
					(mid 96.94037 -87.645494)
					(end 96.94037 -86.933786)
				)
			)
		)
		(polygon
			(pts
				(arc
					(start 96.08185 -86.438232)
					(mid 96.08185 -87.14994)
					(end 96.08185 -86.438232)
				)
			)
		)
		(polygon
			(pts
				(arc
					(start 95.22333 -85.943186)
					(mid 95.22333 -86.654894)
					(end 95.22333 -85.943186)
				)
			)
		)
		(polygon
			(pts
				(arc
					(start 94.36481 -85.447632)
					(mid 94.36481 -86.15934)
					(end 94.36481 -85.447632)
				)
			)
		)
		(polygon
			(pts
				(xy 108.96981 -85.233002) (xy 108.76661 -85.233002) (xy 108.76661 -85.436202) (xy 108.96981 -85.436202)
			)
		)
		(polygon
			(pts
				(arc
					(start 93.50629 -84.952586)
					(mid 93.50629 -85.664294)
					(end 93.50629 -84.952586)
				)
			)
		)
		(polygon
			(pts
				(arc
					(start 92.64777 -84.457032)
					(mid 92.64777 -85.16874)
					(end 92.64777 -84.457032)
				)
			)
		)
		(polygon
			(pts
				(arc
					(start 91.78925 -83.961986)
					(mid 91.78925 -84.673694)
					(end 91.78925 -83.961986)
				)
			)
		)
		(polygon
			(pts
				(arc
					(start 90.93073 -83.466432)
					(mid 90.93073 -84.17814)
					(end 90.93073 -83.466432)
				)
			)
		)
		(polygon
			(pts
				(arc
					(start 90.07221 -82.971386)
					(mid 90.07221 -83.683094)
					(end 90.07221 -82.971386)
				)
			)
		)
		(polygon
			(pts
				(arc
					(start 90.07221 -81.980786)
					(mid 90.07221 -82.692494)
					(end 90.07221 -81.980786)
				)
			)
		)
		(polygon
			(pts
				(arc
					(start 90.07221 -80.990186)
					(mid 90.07221 -81.701894)
					(end 90.07221 -80.990186)
				)
			)
		)
		(polygon
			(pts
				(arc
					(start 90.07221 -79.999586)
					(mid 90.07221 -80.711294)
					(end 90.07221 -79.999586)
				)
			)
		)
		(polygon
			(pts
				(xy 103.655368 -79.0575) (xy 103.452168 -79.0575) (xy 103.452168 -79.2607) (xy 103.655368 -79.2607)
			)
		)
		(polygon
			(pts
				(xy 102.893368 -79.0575) (xy 102.690168 -79.0575) (xy 102.690168 -79.2607) (xy 102.893368 -79.2607)
			)
		)
		(polygon
			(pts
				(xy 102.410768 -79.0575) (xy 102.207568 -79.0575) (xy 102.207568 -79.2607) (xy 102.410768 -79.2607)
			)
		)
		(polygon
			(pts
				(xy 101.648768 -79.0575) (xy 101.445568 -79.0575) (xy 101.445568 -79.2607) (xy 101.648768 -79.2607)
			)
		)
		(polygon
			(pts
				(xy 101.166168 -79.0575) (xy 100.962968 -79.0575) (xy 100.962968 -79.2607) (xy 101.166168 -79.2607)
			)
		)
		(polygon
			(pts
				(xy 100.404168 -79.0575) (xy 100.200968 -79.0575) (xy 100.200968 -79.2607) (xy 100.404168 -79.2607)
			)
		)
		(polygon
			(pts
				(xy 99.921568 -79.0575) (xy 99.718368 -79.0575) (xy 99.718368 -79.2607) (xy 99.921568 -79.2607)
			)
		)
		(polygon
			(pts
				(xy 99.159568 -79.0575) (xy 98.956368 -79.0575) (xy 98.956368 -79.2607) (xy 99.159568 -79.2607)
			)
		)
		(polygon
			(pts
				(xy 98.676968 -79.0575) (xy 98.473768 -79.0575) (xy 98.473768 -79.2607) (xy 98.676968 -79.2607)
			)
		)
		(polygon
			(pts
				(xy 97.914968 -79.0575) (xy 97.711768 -79.0575) (xy 97.711768 -79.2607) (xy 97.914968 -79.2607)
			)
		)
		(polygon
			(pts
				(xy 97.432368 -79.0575) (xy 97.229168 -79.0575) (xy 97.229168 -79.2607) (xy 97.432368 -79.2607)
			)
		)
		(polygon
			(pts
				(arc
					(start 90.07221 -79.008986)
					(mid 90.07221 -79.720694)
					(end 90.07221 -79.008986)
				)
			)
		)
		(polygon
			(pts
				(xy 49.911 -78.7019) (xy 49.7078 -78.7019) (xy 49.7078 -78.9051) (xy 49.911 -78.9051)
			)
		)
		(polygon
			(pts
				(xy 49.149 -78.7019) (xy 48.9458 -78.7019) (xy 48.9458 -78.9051) (xy 49.149 -78.9051)
			)
		)
		(polygon
			(pts
				(xy 102.88524 -77.979016) (xy 102.68204 -77.979016) (xy 102.68204 -78.182216) (xy 102.88524 -78.182216)
			)
		)
		(polygon
			(pts
				(xy 102.40264 -77.979016) (xy 102.19944 -77.979016) (xy 102.19944 -78.182216) (xy 102.40264 -78.182216)
			)
		)
		(polygon
			(pts
				(xy 101.64064 -77.979016) (xy 101.43744 -77.979016) (xy 101.43744 -78.182216) (xy 101.64064 -78.182216)
			)
		)
		(polygon
			(pts
				(xy 101.15804 -77.979016) (xy 100.95484 -77.979016) (xy 100.95484 -78.182216) (xy 101.15804 -78.182216)
			)
		)
		(polygon
			(pts
				(xy 100.39604 -77.979016) (xy 100.19284 -77.979016) (xy 100.19284 -78.182216) (xy 100.39604 -78.182216)
			)
		)
		(polygon
			(pts
				(xy 99.91344 -77.979016) (xy 99.71024 -77.979016) (xy 99.71024 -78.182216) (xy 99.91344 -78.182216)
			)
		)
		(polygon
			(pts
				(xy 99.15144 -77.979016) (xy 98.94824 -77.979016) (xy 98.94824 -78.182216) (xy 99.15144 -78.182216)
			)
		)
		(polygon
			(pts
				(xy 98.66884 -77.979016) (xy 98.46564 -77.979016) (xy 98.46564 -78.182216) (xy 98.66884 -78.182216)
			)
		)
		(polygon
			(pts
				(xy 97.90684 -77.979016) (xy 97.70364 -77.979016) (xy 97.70364 -78.182216) (xy 97.90684 -78.182216)
			)
		)
		(polygon
			(pts
				(xy 97.42424 -77.979016) (xy 97.22104 -77.979016) (xy 97.22104 -78.182216) (xy 97.42424 -78.182216)
			)
		)
		(polygon
			(pts
				(xy 96.66224 -77.979016) (xy 96.45904 -77.979016) (xy 96.45904 -78.182216) (xy 96.66224 -78.182216)
			)
		)
		(polygon
			(pts
				(xy 96.17964 -77.979016) (xy 95.97644 -77.979016) (xy 95.97644 -78.182216) (xy 96.17964 -78.182216)
			)
		)
		(polygon
			(pts
				(xy 95.41764 -77.979016) (xy 95.21444 -77.979016) (xy 95.21444 -78.182216) (xy 95.41764 -78.182216)
			)
		)
		(polygon
			(pts
				(xy 94.93504 -77.979016) (xy 94.73184 -77.979016) (xy 94.73184 -78.182216) (xy 94.93504 -78.182216)
			)
		)
		(polygon
			(pts
				(xy 94.17304 -77.979016) (xy 93.96984 -77.979016) (xy 93.96984 -78.182216) (xy 94.17304 -78.182216)
			)
		)
		(polygon
			(pts
				(xy 93.69044 -77.979016) (xy 93.48724 -77.979016) (xy 93.48724 -78.182216) (xy 93.69044 -78.182216)
			)
		)
		(polygon
			(pts
				(xy 92.92844 -77.979016) (xy 92.72524 -77.979016) (xy 92.72524 -78.182216) (xy 92.92844 -78.182216)
			)
		)
		(polygon
			(pts
				(arc
					(start 90.070178 -74.042778)
					(mid 90.070178 -74.780394)
					(end 90.070178 -74.042778)
				)
			)
		)
		(polygon
			(pts
				(xy 102.88524 -73.661016) (xy 102.68204 -73.661016) (xy 102.68204 -73.864216) (xy 102.88524 -73.864216)
			)
		)
		(polygon
			(pts
				(xy 102.40264 -73.661016) (xy 102.19944 -73.661016) (xy 102.19944 -73.864216) (xy 102.40264 -73.864216)
			)
		)
		(polygon
			(pts
				(xy 101.64064 -73.661016) (xy 101.43744 -73.661016) (xy 101.43744 -73.864216) (xy 101.64064 -73.864216)
			)
		)
		(polygon
			(pts
				(xy 101.15804 -73.661016) (xy 100.95484 -73.661016) (xy 100.95484 -73.864216) (xy 101.15804 -73.864216)
			)
		)
		(polygon
			(pts
				(xy 100.39604 -73.661016) (xy 100.19284 -73.661016) (xy 100.19284 -73.864216) (xy 100.39604 -73.864216)
			)
		)
		(polygon
			(pts
				(xy 99.91344 -73.661016) (xy 99.71024 -73.661016) (xy 99.71024 -73.864216) (xy 99.91344 -73.864216)
			)
		)
		(polygon
			(pts
				(xy 99.15144 -73.661016) (xy 98.94824 -73.661016) (xy 98.94824 -73.864216) (xy 99.15144 -73.864216)
			)
		)
		(polygon
			(pts
				(xy 98.66884 -73.661016) (xy 98.46564 -73.661016) (xy 98.46564 -73.864216) (xy 98.66884 -73.864216)
			)
		)
		(polygon
			(pts
				(xy 97.90684 -73.661016) (xy 97.70364 -73.661016) (xy 97.70364 -73.864216) (xy 97.90684 -73.864216)
			)
		)
		(polygon
			(pts
				(xy 97.42424 -73.661016) (xy 97.22104 -73.661016) (xy 97.22104 -73.864216) (xy 97.42424 -73.864216)
			)
		)
		(polygon
			(pts
				(xy 96.66224 -73.661016) (xy 96.45904 -73.661016) (xy 96.45904 -73.864216) (xy 96.66224 -73.864216)
			)
		)
		(polygon
			(pts
				(xy 96.17964 -73.661016) (xy 95.97644 -73.661016) (xy 95.97644 -73.864216) (xy 96.17964 -73.864216)
			)
		)
		(polygon
			(pts
				(xy 95.41764 -73.661016) (xy 95.21444 -73.661016) (xy 95.21444 -73.864216) (xy 95.41764 -73.864216)
			)
		)
		(polygon
			(pts
				(xy 94.93504 -73.661016) (xy 94.73184 -73.661016) (xy 94.73184 -73.864216) (xy 94.93504 -73.864216)
			)
		)
		(polygon
			(pts
				(xy 94.17304 -73.661016) (xy 93.96984 -73.661016) (xy 93.96984 -73.864216) (xy 94.17304 -73.864216)
			)
		)
		(polygon
			(pts
				(xy 93.69044 -73.661016) (xy 93.48724 -73.661016) (xy 93.48724 -73.864216) (xy 93.69044 -73.864216)
			)
		)
		(polygon
			(pts
				(xy 92.92844 -73.661016) (xy 92.72524 -73.661016) (xy 92.72524 -73.864216) (xy 92.92844 -73.864216)
			)
		)
		(polygon
			(pts
				(xy 49.911 -71.3359) (xy 49.7078 -71.3359) (xy 49.7078 -71.5391) (xy 49.911 -71.5391)
			)
		)
		(polygon
			(pts
				(xy 49.149 -71.3359) (xy 48.9458 -71.3359) (xy 48.9458 -71.5391) (xy 49.149 -71.5391)
			)
		)
		(polygon
			(pts
				(arc
					(start 91.78925 -67.121786)
					(mid 91.78925 -67.833494)
					(end 91.78925 -67.121786)
				)
			)
		)
		(polygon
			(pts
				(arc
					(start 92.64777 -66.626232)
					(mid 92.64777 -67.33794)
					(end 92.64777 -66.626232)
				)
			)
		)
		(polygon
			(pts
				(arc
					(start 93.50629 -66.131186)
					(mid 93.50629 -66.842894)
					(end 93.50629 -66.131186)
				)
			)
		)
		(polygon
			(pts
				(arc
					(start 94.36481 -65.635632)
					(mid 94.36481 -66.34734)
					(end 94.36481 -65.635632)
				)
			)
		)
		(polygon
			(pts
				(arc
					(start 95.22333 -65.140586)
					(mid 95.22333 -65.852294)
					(end 95.22333 -65.140586)
				)
			)
		)
		(polygon
			(pts
				(arc
					(start 96.08185 -64.645032)
					(mid 96.08185 -65.35674)
					(end 96.08185 -64.645032)
				)
			)
		)
		(polygon
			(pts
				(arc
					(start 96.94037 -64.149986)
					(mid 96.94037 -64.861694)
					(end 96.94037 -64.149986)
				)
			)
		)
		(polygon
			(pts
				(xy 49.911 -63.423292) (xy 49.7078 -63.423292) (xy 49.7078 -63.626492) (xy 49.911 -63.626492)
			)
		)
		(polygon
			(pts
				(xy 49.149 -63.423292) (xy 48.9458 -63.423292) (xy 48.9458 -63.626492) (xy 49.149 -63.626492)
			)
		)
		(polygon
			(pts
				(xy 49.911 -58.597292) (xy 49.7078 -58.597292) (xy 49.7078 -58.800492) (xy 49.911 -58.800492)
			)
		)
		(polygon
			(pts
				(xy 49.149 -58.597292) (xy 48.9458 -58.597292) (xy 48.9458 -58.800492) (xy 49.149 -58.800492)
			)
		)
		(polygon
			(pts
				(xy 44.6659 -53.07838) (xy 44.4627 -53.07838) (xy 44.4627 -53.28158) (xy 44.6659 -53.28158)
			)
		)
		(polygon
			(pts
				(xy 44.6659 -52.31638) (xy 44.4627 -52.31638) (xy 44.4627 -52.51958) (xy 44.6659 -52.51958)
			)
		)
	)
	(zone
		(layer "F.Cu")
		(hatch none 0.5)
		(connect_pads
			(clearance 0)
		)
		(min_thickness 0.25)
		(keepout
			(tracks not_allowed)
			(vias allowed)
			(pads allowed)
			(copperpour not_allowed)
			(footprints allowed)
		)
		(placement
			(enabled no)
			(sheetname "")
		)
		(fill
			(thermal_gap 0.5)
			(thermal_bridge_width 0.5)
			(island_removal_mode 0)
		)
		(polygon
			(pts
				(arc
					(start 474.49994 -151.100028)
					(mid 478.499932 -155.10002)
					(end 474.49994 -159.100012)
				)
				(arc
					(start 471.000074 -159.100012)
					(mid 467.000082 -155.10002)
					(end 471.000074 -151.100028)
				)
			)
		)
	)
	(zone
		(net "PVNN_PCH_STBY")
		(layer "F.Cu")
		(hatch none 0.5)
		(connect_pads
			(clearance 0.5)
		)
		(min_thickness 0.25)
		(fill yes
			(thermal_gap 0.5)
			(thermal_bridge_width 0.5)
			(island_removal_mode 0)
		)
		(polygon
			(pts
				(xy 389.866632 -111.506) (xy 387.35 -111.506) (xy 387.223 -111.379) (xy 387.223 -107.442) (xy 387.35 -107.315)
				(xy 391.287 -107.315) (xy 391.414 -107.442) (xy 391.414 -109.60862) (xy 391.31748 -109.70514) (xy 389.91794 -109.70514)
				(xy 389.795258 -109.827822) (xy 389.795258 -110.112048) (xy 389.795258 -110.40745) (xy 389.910066 -110.522258)
				(xy 389.910066 -110.769908) (xy 389.818118 -110.861856) (xy 389.818118 -111.225076) (xy 389.866632 -111.27359)
			)
		)
	)
	(zone
		(net "PVDDQ_KLM")
		(layer "F.Cu")
		(hatch none 0.5)
		(connect_pads
			(clearance 0.5)
		)
		(min_thickness 0.25)
		(fill yes
			(thermal_gap 0.5)
			(thermal_bridge_width 0.5)
			(island_removal_mode 0)
		)
		(polygon
			(pts
				(arc
					(start 80.371188 -139.03198)
					(mid 80.362129 -138.936342)
					(end 80.277462 -138.89101)
				)
				(arc
					(start 79.421228 -138.89101)
					(mid 79.336611 -138.936374)
					(end 79.327502 -139.03198)
				)
				(arc
					(start 79.327502 -139.03198)
					(mid 79.271877 -139.399301)
					(end 78.919578 -139.51712)
				)
				(arc
					(start 78.919578 -139.51712)
					(mid 78.83362 -139.536742)
					(end 78.795372 -139.61618)
				)
				(xy 78.795372 -139.699492) (xy 79.932276 -139.699492) (xy 79.932276 -139.826492) (xy 80.313276 -139.826492)
				(xy 80.313276 -140.589508) (xy 79.932276 -140.589508) (xy 79.932276 -140.716508) (xy 78.795372 -140.716508)
				(xy 78.795372 -141.293596) (xy 78.865984 -141.364462)
				(arc
					(start 79.398114 -141.364462)
					(mid 79.475664 -141.328502)
					(end 79.49819 -141.246098)
				)
				(arc
					(start 79.49819 -141.246098)
					(mid 79.849472 -140.831571)
					(end 80.200754 -141.246098)
				)
				(arc
					(start 80.200754 -141.246098)
					(mid 80.223379 -141.328418)
					(end 80.30083 -141.364462)
				)
				(arc
					(start 81.098136 -141.364462)
					(mid 81.175686 -141.328502)
					(end 81.198212 -141.246098)
				)
				(arc
					(start 81.198212 -141.246098)
					(mid 81.549494 -140.831571)
					(end 81.900776 -141.246098)
				)
				(arc
					(start 81.900776 -141.246098)
					(mid 81.923401 -141.328418)
					(end 82.000852 -141.364462)
				)
				(xy 82.063336 -141.364462) (xy 82.063336 -141.305534)
				(arc
					(start 82.060796 -141.297914)
					(mid 82.372704 -140.832603)
					(end 82.75066 -141.246098)
				)
				(arc
					(start 82.75066 -141.246098)
					(mid 82.773285 -141.328418)
					(end 82.850736 -141.364462)
				)
				(arc
					(start 83.648042 -141.364462)
					(mid 83.725592 -141.328502)
					(end 83.748118 -141.246098)
				)
				(arc
					(start 83.748118 -141.246098)
					(mid 84.0994 -140.831571)
					(end 84.450682 -141.246098)
				)
				(arc
					(start 84.450682 -141.246098)
					(mid 84.473307 -141.328418)
					(end 84.550758 -141.364462)
				)
				(xy 84.613496 -141.364462) (xy 84.613496 -141.305534)
				(arc
					(start 84.610956 -141.297914)
					(mid 84.922864 -140.832603)
					(end 85.30082 -141.246098)
				)
				(arc
					(start 85.30082 -141.246098)
					(mid 85.323445 -141.328418)
					(end 85.400896 -141.364462)
				)
				(arc
					(start 86.198202 -141.364462)
					(mid 86.275752 -141.328502)
					(end 86.298278 -141.246098)
				)
				(arc
					(start 86.298278 -141.246098)
					(mid 86.64956 -140.831571)
					(end 87.000842 -141.246098)
				)
				(arc
					(start 87.000842 -141.246098)
					(mid 87.023467 -141.328418)
					(end 87.100918 -141.364462)
				)
				(xy 87.163402 -141.364462) (xy 87.163402 -141.305534)
				(arc
					(start 87.160862 -141.297914)
					(mid 87.47277 -140.832603)
					(end 87.850726 -141.246098)
				)
				(arc
					(start 87.850726 -141.246098)
					(mid 87.873351 -141.328418)
					(end 87.950802 -141.364462)
				)
				(arc
					(start 88.748108 -141.364462)
					(mid 88.825658 -141.328502)
					(end 88.848184 -141.246098)
				)
				(arc
					(start 88.848184 -141.246098)
					(mid 89.199466 -140.831571)
					(end 89.550748 -141.246098)
				)
				(arc
					(start 89.550748 -141.246098)
					(mid 89.573373 -141.328418)
					(end 89.650824 -141.364462)
				)
				(xy 90.5002 -141.364462) (xy 90.6018 -141.466062) (xy 90.6018 -142.8242) (xy 90.7034 -142.9258)
				(xy 91.0844 -142.9258) (xy 91.186 -142.8242) (xy 91.186 -141.466062) (xy 91.2876 -141.364462) (xy 92.074238 -141.364462)
				(xy 92.254324 -141.184376) (xy 92.254324 -139.072112) (xy 92.073222 -138.89101)
				(arc
					(start 88.77046 -138.89101)
					(mid 88.68587 -138.936716)
					(end 88.677242 -139.032488)
				)
				(arc
					(start 88.677242 -139.032488)
					(mid 88.349582 -139.528386)
					(end 88.021922 -139.032488)
				)
				(arc
					(start 88.021922 -139.032488)
					(mid 88.013313 -138.936704)
					(end 87.928704 -138.89101)
				)
				(arc
					(start 87.920322 -138.89101)
					(mid 87.835732 -138.936716)
					(end 87.827104 -139.032488)
				)
				(arc
					(start 87.827104 -139.032488)
					(mid 87.499444 -139.528386)
					(end 87.171784 -139.032488)
				)
				(arc
					(start 87.171784 -139.032488)
					(mid 87.163175 -138.936704)
					(end 87.078566 -138.89101)
				)
				(arc
					(start 86.221316 -138.89101)
					(mid 86.136699 -138.936374)
					(end 86.12759 -139.03198)
				)
				(arc
					(start 86.12759 -139.03198)
					(mid 85.799422 -139.526227)
					(end 85.471254 -139.03198)
				)
				(arc
					(start 85.471254 -139.03198)
					(mid 85.462195 -138.936342)
					(end 85.377528 -138.89101)
				)
				(arc
					(start 85.371178 -138.89101)
					(mid 85.286561 -138.936374)
					(end 85.277452 -139.03198)
				)
				(arc
					(start 85.277452 -139.03198)
					(mid 84.949284 -139.526227)
					(end 84.621116 -139.03198)
				)
				(arc
					(start 84.621116 -139.03198)
					(mid 84.612057 -138.936342)
					(end 84.52739 -138.89101)
				)
				(arc
					(start 83.67141 -138.89101)
					(mid 83.586793 -138.936374)
					(end 83.577684 -139.03198)
				)
				(arc
					(start 83.577684 -139.03198)
					(mid 83.249516 -139.526227)
					(end 82.921348 -139.03198)
				)
				(arc
					(start 82.921348 -139.03198)
					(mid 82.912289 -138.936342)
					(end 82.827622 -138.89101)
				)
				(arc
					(start 82.821272 -138.89101)
					(mid 82.736655 -138.936374)
					(end 82.727546 -139.03198)
				)
				(arc
					(start 82.727546 -139.03198)
					(mid 82.399378 -139.526227)
					(end 82.07121 -139.03198)
				)
				(arc
					(start 82.07121 -139.03198)
					(mid 82.062151 -138.936342)
					(end 81.977484 -138.89101)
				)
				(arc
					(start 81.12125 -138.89101)
					(mid 81.036633 -138.936374)
					(end 81.027524 -139.03198)
				)
				(arc
					(start 81.027524 -139.03198)
					(mid 80.699356 -139.526227)
					(end 80.371188 -139.03198)
				)
			)
		)
		(polygon
			(pts
				(xy 88.0491 -140.6017) (xy 87.8459 -140.6017) (xy 87.8459 -140.8049) (xy 88.0491 -140.8049)
			)
		)
		(polygon
			(pts
				(xy 81.285588 -140.6017) (xy 81.082388 -140.6017) (xy 81.082388 -140.8049) (xy 81.285588 -140.8049)
			)
		)
		(polygon
			(pts
				(xy 88.0491 -139.6111) (xy 87.8459 -139.6111) (xy 87.8459 -139.8143) (xy 88.0491 -139.8143)
			)
		)
		(polygon
			(pts
				(xy 84.402168 -139.6111) (xy 84.198968 -139.6111) (xy 84.198968 -139.8143) (xy 84.402168 -139.8143)
			)
		)
		(polygon
			(pts
				(xy 81.285588 -139.6111) (xy 81.082388 -139.6111) (xy 81.082388 -139.8143) (xy 81.285588 -139.8143)
			)
		)
	)
	(zone
		(net "GND")
		(layer "F.Cu")
		(hatch none 0.5)
		(connect_pads
			(clearance 0.5)
		)
		(min_thickness 0.25)
		(fill yes
			(thermal_gap 0.5)
			(thermal_bridge_width 0.5)
			(island_removal_mode 0)
		)
		(polygon
			(pts
				(xy 326.39 -36.195) (xy 330.835 -36.195) (xy 331.724 -35.306) (xy 331.724 -32.385) (xy 331.343 -32.004)
				(xy 326.771 -32.004) (xy 325.755 -33.02) (xy 325.755 -35.56)
			)
		)
	)
	(zone
		(layer "F.Cu")
		(hatch none 0.5)
		(connect_pads
			(clearance 0)
		)
		(min_thickness 0.25)
		(keepout
			(tracks allowed)
			(vias allowed)
			(pads allowed)
			(copperpour allowed)
			(footprints not_allowed)
		)
		(placement
			(enabled no)
			(sheetname "")
		)
		(fill
			(thermal_gap 0.5)
			(thermal_bridge_width 0.5)
			(island_removal_mode 0)
		)
		(polygon
			(pts
				(arc
					(start -5.999988 4.99999)
					(mid -5.707095 5.707095)
					(end -4.99999 5.999988)
				)
				(xy 6.999986 5.999988) (xy 6.999986 -6.999986) (xy -5.999988 -6.999986) (xy -5.999988 -2.500122)
				(arc
					(start -4.898898 -2.500122)
					(mid 5.500463 0)
					(end -4.898898 2.500122)
				)
				(xy -5.999988 2.500122)
			)
		)
	)
	(zone
		(layer "F.Cu")
		(hatch none 0.5)
		(connect_pads
			(clearance 0)
		)
		(min_thickness 0.25)
		(keepout
			(tracks allowed)
			(vias allowed)
			(pads allowed)
			(copperpour allowed)
			(footprints not_allowed)
		)
		(placement
			(enabled no)
			(sheetname "")
		)
		(fill
			(thermal_gap 0.5)
			(thermal_bridge_width 0.5)
			(island_removal_mode 0)
		)
		(polygon
			(pts
				(arc
					(start 420.120064 -78.98003)
					(mid 419.680672 -80.040688)
					(end 418.61994 -80.4799)
				)
				(arc
					(start 411.470856 -80.4799)
					(mid 413.617188 -75.98513)
					(end 409.719526 -72.883776)
				)
				(arc
					(start 409.719526 -72.883776)
					(mid 405.821789 -75.985113)
					(end 407.968196 -80.4799)
				)
				(arc
					(start 406.619964 -80.4799)
					(mid 405.559396 -80.040598)
					(end 405.120094 -78.98003)
				)
				(arc
					(start 405.120094 -47.680118)
					(mid 405.55938 -46.61946)
					(end 406.619964 -46.179994)
				)
				(arc
					(start 418.61994 -46.179994)
					(mid 419.680688 -46.61937)
					(end 420.120064 -47.680118)
				)
			)
		)
	)
	(zone
		(layer "F.Cu")
		(hatch none 0.5)
		(connect_pads
			(clearance 0)
		)
		(min_thickness 0.25)
		(keepout
			(tracks allowed)
			(vias allowed)
			(pads allowed)
			(copperpour allowed)
			(footprints allowed)
		)
		(placement
			(enabled no)
			(sheetname "")
		)
		(fill
			(thermal_gap 0.5)
			(thermal_bridge_width 0.5)
			(island_removal_mode 0)
		)
		(polygon
			(pts
				(xy 160.6042 -67.31) (xy 160.6042 -63.754) (xy 163.576 -63.754) (xy 163.576 -67.31)
			)
		)
	)
	(zone
		(layer "F.Cu")
		(hatch none 0.5)
		(connect_pads
			(clearance 0)
		)
		(min_thickness 0.25)
		(keepout
			(tracks not_allowed)
			(vias allowed)
			(pads allowed)
			(copperpour not_allowed)
			(footprints allowed)
		)
		(placement
			(enabled no)
			(sheetname "")
		)
		(fill
			(thermal_gap 0.5)
			(thermal_bridge_width 0.5)
			(island_removal_mode 0)
		)
		(polygon
			(pts
				(xy 449.749164 -114.020092) (xy 449.749164 -114.295682) (xy 449.571364 -114.473482)
				(arc
					(start 449.422266 -114.473482)
					(mid 448.898349 -114.403632)
					(end 449.422266 -114.333782)
				)
				(xy 449.513452 -114.333782) (xy 449.609464 -114.23777) (xy 449.609464 -114.020092)
				(arc
					(start 449.165218 -114.020092)
					(mid 448.781678 -114.403505)
					(end 449.164964 -114.787172)
				)
				(arc
					(start 450.434964 -114.787172)
					(mid 450.818504 -114.403632)
					(end 450.434964 -114.020092)
				)
				(xy 449.990464 -114.020092) (xy 449.990464 -114.23777) (xy 450.086476 -114.333782)
				(arc
					(start 450.177662 -114.333782)
					(mid 450.701579 -114.403632)
					(end 450.177662 -114.473482)
				)
				(xy 450.028564 -114.473482) (xy 449.850764 -114.295682) (xy 449.850764 -114.020092)
			)
		)
	)
	(zone
		(layer "F.Cu")
		(hatch none 0.5)
		(connect_pads
			(clearance 0)
		)
		(min_thickness 0.25)
		(keepout
			(tracks allowed)
			(vias allowed)
			(pads allowed)
			(copperpour allowed)
			(footprints not_allowed)
		)
		(placement
			(enabled no)
			(sheetname "")
		)
		(fill
			(thermal_gap 0.5)
			(thermal_bridge_width 0.5)
			(island_removal_mode 0)
		)
		(polygon
			(pts
				(xy 187.525406 -151.368506) (xy 328.525378 -151.368506) (xy 328.525378 -148.167344) (xy 187.525406 -148.167344)
			)
		)
	)
	(zone
		(net "PVNN_PCH_STBY")
		(layer "F.Cu")
		(hatch none 0.5)
		(connect_pads
			(clearance 0.5)
		)
		(min_thickness 0.25)
		(fill yes
			(thermal_gap 0.5)
			(thermal_bridge_width 0.5)
			(island_removal_mode 0)
		)
		(polygon
			(pts
				(xy 366.542066 -135.562594) (xy 366.325404 -135.779256) (xy 366.325404 -139.769596) (xy 366.24006 -139.85494)
				(xy 366.24006 -142.61846) (xy 367.2078 -143.5862) (xy 371.014244 -143.5862) (xy 371.393212 -143.207232)
				(xy 381.046228 -143.207232) (xy 381.896366 -142.357094) (xy 381.896366 -141.353032) (xy 381.858012 -141.314678)
				(xy 381.858012 -140.038074) (xy 381.930656 -139.96543) (xy 381.930656 -137.201656) (xy 381.6858 -136.9568)
				(xy 378.664216 -136.9568) (xy 378.373386 -136.66597) (xy 377.426982 -136.66597) (xy 377.249436 -136.488424)
				(xy 373.30888 -136.488424) (xy 373.258588 -136.538716) (xy 371.968776 -136.538716) (xy 371.96649 -136.541002)
				(xy 371.762274 -136.541002) (xy 371.614446 -136.68883) (xy 371.614446 -137.343896) (xy 371.369844 -137.588498)
				(xy 370.869464 -137.588498) (xy 370.7511 -137.706862) (xy 370.7511 -137.70864) (xy 370.32692 -138.13282)
				(xy 368.778536 -138.13282) (xy 368.702844 -138.208512) (xy 368.702844 -139.051284) (xy 368.470942 -139.283186)
				(xy 367.370106 -139.283186) (xy 367.12271 -139.03579) (xy 367.12271 -137.342118) (xy 366.845342 -137.06475)
				(xy 366.845342 -136.733534) (xy 367.55324 -136.025636) (xy 368.4143 -136.025636) (xy 368.52733 -136.138666)
				(xy 368.52733 -136.646666) (xy 368.555016 -136.674352) (xy 369.042188 -136.674352) (xy 369.0747 -136.64184)
				(xy 369.0747 -135.91286) (xy 369.080288 -135.907272) (xy 369.080288 -135.7757) (xy 368.867182 -135.562594)
			)
		)
		(polygon
			(pts
				(xy 381.1143 -142.0241) (xy 380.9111 -142.0241) (xy 380.9111 -142.2273) (xy 381.1143 -142.2273)
			)
		)
		(polygon
			(pts
				(xy 381.1143 -141.2621) (xy 380.9111 -141.2621) (xy 380.9111 -141.4653) (xy 381.1143 -141.4653)
			)
		)
		(polygon
			(pts
				(xy 381.1143 -140.716) (xy 380.9111 -140.716) (xy 380.9111 -140.9192) (xy 381.1143 -140.9192)
			)
		)
		(polygon
			(pts
				(xy 381.1143 -139.954) (xy 380.9111 -139.954) (xy 380.9111 -140.1572) (xy 381.1143 -140.1572)
			)
		)
		(polygon
			(pts
				(xy 378.2949 -137.4521) (xy 378.0917 -137.4521) (xy 378.0917 -137.6553) (xy 378.2949 -137.6553)
			)
		)
		(polygon
			(pts
				(xy 377.5329 -137.4521) (xy 377.3297 -137.4521) (xy 377.3297 -137.6553) (xy 377.5329 -137.6553)
			)
		)
	)
	(zone
		(layer "F.Cu")
		(hatch none 0.5)
		(connect_pads
			(clearance 0)
		)
		(min_thickness 0.25)
		(keepout
			(tracks allowed)
			(vias allowed)
			(pads allowed)
			(copperpour allowed)
			(footprints allowed)
		)
		(placement
			(enabled no)
			(sheetname "")
		)
		(fill
			(thermal_gap 0.5)
			(thermal_bridge_width 0.5)
			(island_removal_mode 0)
		)
		(polygon
			(pts
				(xy 111.707168 -45.9486) (xy 114.399568 -43.2562) (xy 114.399568 -41.3004) (xy 114.907568 -40.7924)
				(xy 121.155968 -40.7924) (xy 121.359168 -40.9956) (xy 121.790968 -40.9956) (xy 122.095768 -41.3004)
				(xy 122.552968 -41.3004) (xy 123.213368 -41.9608) (xy 123.213368 -42.1894) (xy 121.448068 -43.9547)
				(xy 117.015768 -48.387) (xy 116.939568 -48.514) (xy 116.939568 -49.149) (xy 116.558568 -49.53) (xy 116.558568 -49.657)
				(xy 111.605568 -49.657) (xy 111.605568 -45.974) (xy 111.630968 -45.9486)
			)
		)
	)
	(zone
		(layer "F.Cu")
		(hatch none 0.5)
		(connect_pads
			(clearance 0)
		)
		(min_thickness 0.25)
		(keepout
			(tracks allowed)
			(vias allowed)
			(pads allowed)
			(copperpour allowed)
			(footprints allowed)
		)
		(placement
			(enabled no)
			(sheetname "")
		)
		(fill
			(thermal_gap 0.5)
			(thermal_bridge_width 0.5)
			(island_removal_mode 0)
		)
		(polygon
			(pts
				(xy 180.0225 -131.318) (xy 180.0225 -129.286) (xy 183.769 -129.286) (xy 183.769 -131.318)
			)
		)
	)
	(zone
		(layer "F.Cu")
		(hatch none 0.5)
		(connect_pads
			(clearance 0)
		)
		(min_thickness 0.25)
		(keepout
			(tracks allowed)
			(vias allowed)
			(pads allowed)
			(copperpour allowed)
			(footprints allowed)
		)
		(placement
			(enabled no)
			(sheetname "")
		)
		(fill
			(thermal_gap 0.5)
			(thermal_bridge_width 0.5)
			(island_removal_mode 0)
		)
		(polygon
			(pts
				(xy 102.489 -62.738) (xy 103.251 -62.738) (xy 103.505 -62.992) (xy 103.505 -63.373) (xy 102.362 -63.373)
				(xy 102.362 -62.865)
			)
		)
	)
	(zone
		(layer "F.Cu")
		(hatch none 0.5)
		(connect_pads
			(clearance 0)
		)
		(min_thickness 0.25)
		(keepout
			(tracks allowed)
			(vias allowed)
			(pads allowed)
			(copperpour allowed)
			(footprints allowed)
		)
		(placement
			(enabled no)
			(sheetname "")
		)
		(fill
			(thermal_gap 0.5)
			(thermal_bridge_width 0.5)
			(island_removal_mode 0)
		)
		(polygon
			(pts
				(xy 296.4434 -49.108614) (xy 295.238424 -49.108614) (xy 293.62908 -49.108614) (xy 292.5318 -49.108614)
				(xy 292.52418 -49.11598) (xy 289.28822 -49.11598) (xy 287.8582 -50.546) (xy 287.528 -50.546) (xy 284.48 -47.498)
				(xy 282.956 -47.498) (xy 282.9306 -47.4726) (xy 286.3469 -44.0563) (xy 287.0454 -44.0563) (xy 288.3789 -44.0563)
				(xy 288.5186 -44.196) (xy 293.37 -44.196) (xy 294.64 -42.926) (xy 294.64 -42.9006) (xy 295.0591 -42.4815)
				(xy 295.0591 -42.4688) (xy 302.3108 -42.4688) (xy 302.2727 -42.5069) (xy 302.2727 -43.279314)
			)
		)
	)
	(zone
		(net "VR_P1V05_PCH_STBY_PH1_PHASE_SW")
		(layer "F.Cu")
		(hatch none 0.5)
		(connect_pads
			(clearance 0.5)
		)
		(min_thickness 0.25)
		(fill yes
			(thermal_gap 0.5)
			(thermal_bridge_width 0.5)
			(island_removal_mode 0)
		)
		(polygon
			(pts
				(xy 382.6256 -150.5966) (xy 383.1336 -151.1046) (xy 387.64845 -151.1046) (xy 387.881114 -150.871936)
				(xy 387.881114 -149.67458) (xy 386.45338 -148.246846) (xy 386.45338 -145.54708) (xy 386.45338 -145.38198)
				(xy 386.3086 -145.2372) (xy 382.6764 -145.2372) (xy 382.4986 -145.415) (xy 382.4986 -150.4696)
			)
		)
	)
	(zone
		(net "P12V")
		(layer "F.Cu")
		(hatch none 0.5)
		(connect_pads
			(clearance 0.5)
		)
		(min_thickness 0.25)
		(fill yes
			(thermal_gap 0.5)
			(thermal_bridge_width 0.5)
			(island_removal_mode 0)
		)
		(polygon
			(pts
				(xy 452.9074 -126.5682) (xy 452.9074 -126.7206) (xy 452.9074 -129.27838) (xy 453.71766 -130.08864)
				(xy 454.97496 -130.08864) (xy 455.3458 -129.7178) (xy 455.3458 -126.492) (xy 455.493374 -126.344426)
				(xy 455.493374 -125.918976) (xy 455.41438 -125.839982) (xy 453.360536 -125.839982) (xy 453.24268 -125.839982)
				(xy 452.9074 -126.175262) (xy 452.9074 -126.293118)
			)
		)
	)
	(zone
		(net "PVTT_ABC")
		(layer "F.Cu")
		(hatch none 0.5)
		(connect_pads
			(clearance 0.5)
		)
		(min_thickness 0.25)
		(fill yes
			(thermal_gap 0.5)
			(thermal_bridge_width 0.5)
			(island_removal_mode 0)
		)
		(polygon
			(pts
				(xy 259.08 4.699) (xy 260.985 4.699) (xy 262.643366 3.040634) (xy 262.643366 0.503936) (xy 262.690356 0.456946)
				(xy 263.226296 -0.078994) (xy 263.553194 -0.078994) (xy 264.2616 -0.7874) (xy 264.668 -1.1938) (xy 264.668 -1.6002)
				(xy 264.668 -7.3152) (xy 264.668 -9.8044) (xy 264.668 -11.557) (xy 264.864088 -11.753088) (xy 264.864088 -12.768326)
				(xy 265.048746 -12.952984) (xy 265.158982 -13.06322) (xy 265.176 -13.080238) (xy 265.176 -13.369798)
				(xy 265.035538 -13.51026) (xy 264.814304 -13.731494) (xy 264.814304 -14.318488) (xy 264.881868 -14.386052)
				(xy 264.881868 -17.185132) (xy 263.906 -18.161) (xy 261.6327 -18.161) (xy 260.6675 -17.1958) (xy 259.7658 -17.1958)
				(xy 258.953 -16.383) (xy 258.953 -14.605) (xy 259.08 -14.478) (xy 259.842 -14.478) (xy 259.969 -14.605)
				(xy 260.985 -14.605) (xy 261.39394 -14.605) (xy 261.529068 -14.740128) (xy 261.953502 -14.740128)
				(xy 262.099806 -14.593824) (xy 262.099806 -14.158468) (xy 261.9883 -14.046962) (xy 261.9883 -11.467338)
				(xy 262.038592 -11.417046) (xy 262.400542 -11.055096) (xy 262.400542 -10.742676) (xy 262.18134 -10.523474)
				(xy 261.867396 -10.523474) (xy 261.72922 -10.661904) (xy 261.72922 -10.664444) (xy 261.128764 -11.2649)
				(xy 260.74751 -11.2649) (xy 259.0546 -11.2649) (xy 259.047488 -11.257788) (xy 259.047488 -4.223512)
				(xy 259.08 -4.191) (xy 261.79272 -4.191) (xy 261.927848 -4.055872) (xy 261.927848 -1.510792) (xy 261.642606 -1.22555)
				(xy 260.84276 -1.22555) (xy 260.76656 -1.30175) (xy 260.76656 -2.09042) (xy 260.41858 -2.4384) (xy 259.6896 -2.4384)
				(xy 259.1054 -2.4384) (xy 259.05079 -2.38379) (xy 259.05079 -1.72593) (xy 259.032248 -1.707388)
				(xy 259.032248 4.651248) (xy 259.05079 4.66979)
			)
		)
	)
	(zone
		(layer "F.Cu")
		(hatch none 0.5)
		(connect_pads
			(clearance 0)
		)
		(min_thickness 0.25)
		(keepout
			(tracks not_allowed)
			(vias allowed)
			(pads allowed)
			(copperpour not_allowed)
			(footprints allowed)
		)
		(placement
			(enabled no)
			(sheetname "")
		)
		(fill
			(thermal_gap 0.5)
			(thermal_bridge_width 0.5)
			(island_removal_mode 0)
		)
		(polygon
			(pts
				(arc
					(start 83.000088 -114.089942)
					(mid 80.460088 -111.549942)
					(end 83.000088 -109.009942)
				)
				(arc
					(start 83.000088 -109.009942)
					(mid 85.540088 -111.549942)
					(end 83.000088 -114.089942)
				)
			)
		)
	)
	(zone
		(layer "F.Cu")
		(hatch none 0.5)
		(connect_pads
			(clearance 0)
		)
		(min_thickness 0.25)
		(keepout
			(tracks not_allowed)
			(vias allowed)
			(pads allowed)
			(copperpour not_allowed)
			(footprints allowed)
		)
		(placement
			(enabled no)
			(sheetname "")
		)
		(fill
			(thermal_gap 0.5)
			(thermal_bridge_width 0.5)
			(island_removal_mode 0)
		)
		(polygon
			(pts
				(xy 325.1835 -120.142) (xy 325.1835 -120.65) (xy 324.8025 -120.65) (xy 324.8025 -120.142)
			)
		)
	)
	(zone
		(layer "F.Cu")
		(hatch none 0.5)
		(connect_pads
			(clearance 0)
		)
		(min_thickness 0.25)
		(keepout
			(tracks allowed)
			(vias allowed)
			(pads allowed)
			(copperpour allowed)
			(footprints not_allowed)
		)
		(placement
			(enabled no)
			(sheetname "")
		)
		(fill
			(thermal_gap 0.5)
			(thermal_bridge_width 0.5)
			(island_removal_mode 0)
		)
		(polygon
			(pts
				(arc
					(start 175.50003 -151.100028)
					(mid 179.500022 -155.10002)
					(end 175.50003 -159.100012)
				)
				(arc
					(start 171.99991 -159.100012)
					(mid 167.999918 -155.10002)
					(end 171.99991 -151.100028)
				)
			)
		)
	)
	(zone
		(layer "F.Cu")
		(hatch none 0.5)
		(connect_pads
			(clearance 0)
		)
		(min_thickness 0.25)
		(keepout
			(tracks not_allowed)
			(vias allowed)
			(pads allowed)
			(copperpour not_allowed)
			(footprints allowed)
		)
		(placement
			(enabled no)
			(sheetname "")
		)
		(fill
			(thermal_gap 0.5)
			(thermal_bridge_width 0.5)
			(island_removal_mode 0)
		)
		(polygon
			(pts
				(arc
					(start 198.930006 -108.100114)
					(mid 197.380098 -106.550206)
					(end 198.930006 -105.000044)
				)
				(arc
					(start 198.930006 -105.000044)
					(mid 200.480168 -106.550206)
					(end 198.930006 -108.100114)
				)
			)
		)
	)
	(zone
		(net "GND")
		(layer "F.Cu")
		(hatch none 0.5)
		(connect_pads
			(clearance 0.5)
		)
		(min_thickness 0.25)
		(fill yes
			(thermal_gap 0.5)
			(thermal_bridge_width 0.5)
			(island_removal_mode 0)
		)
		(polygon
			(pts
				(xy 76.953618 -141.366748) (xy 78.338426 -141.366748) (xy 78.48092 -141.224254) (xy 78.48092 -139.107926)
				(xy 78.260956 -138.887962) (xy 77.024992 -138.887962) (xy 76.288138 -138.887962) (xy 76.1365 -139.0396)
				(xy 76.1365 -139.591034) (xy 76.766166 -140.2207) (xy 76.766166 -140.979398) (xy 76.83373 -141.046962)
				(xy 76.83373 -141.144244) (xy 76.83373 -141.24686)
			)
		)
	)
	(zone
		(net "GND")
		(layer "F.Cu")
		(hatch none 0.5)
		(connect_pads
			(clearance 0.5)
		)
		(min_thickness 0.25)
		(fill yes
			(thermal_gap 0.5)
			(thermal_bridge_width 0.5)
			(island_removal_mode 0)
		)
		(polygon
			(pts
				(xy 31.737046 -116.503704) (xy 36.53155 -116.503704) (xy 37.221922 -115.813332) (xy 37.221922 -109.90707)
				(xy 35.668458 -108.353606) (xy 33.118044 -108.353606) (xy 32.427672 -107.663234) (xy 31.33471 -107.663234)
				(xy 31.113984 -107.88396) (xy 31.113984 -115.880642)
			)
		)
	)
	(zone
		(layer "F.Cu")
		(hatch none 0.5)
		(connect_pads
			(clearance 0)
		)
		(min_thickness 0.25)
		(keepout
			(tracks allowed)
			(vias allowed)
			(pads allowed)
			(copperpour allowed)
			(footprints not_allowed)
		)
		(placement
			(enabled no)
			(sheetname "")
		)
		(fill
			(thermal_gap 0.5)
			(thermal_bridge_width 0.5)
			(island_removal_mode 0)
		)
		(polygon
			(pts
				(arc
					(start 152.999948 -101.089968)
					(mid 150.459948 -98.549968)
					(end 152.999948 -96.009968)
				)
				(arc
					(start 152.999948 -96.009968)
					(mid 155.539948 -98.549968)
					(end 152.999948 -101.089968)
				)
			)
		)
	)
	(zone
		(layer "F.Cu")
		(hatch none 0.5)
		(connect_pads
			(clearance 0)
		)
		(min_thickness 0.25)
		(keepout
			(tracks not_allowed)
			(vias allowed)
			(pads allowed)
			(copperpour not_allowed)
			(footprints allowed)
		)
		(placement
			(enabled no)
			(sheetname "")
		)
		(fill
			(thermal_gap 0.5)
			(thermal_bridge_width 0.5)
			(island_removal_mode 0)
		)
		(polygon
			(pts
				(xy 465.749132 -114.06886) (xy 465.749132 -114.353086) (xy 465.579968 -114.52225)
				(arc
					(start 465.457032 -114.52225)
					(mid 464.933115 -114.4524)
					(end 465.457032 -114.38255)
				)
				(xy 465.522056 -114.38255) (xy 465.609432 -114.295174) (xy 465.609432 -114.06886)
				(arc
					(start 465.199984 -114.06886)
					(mid 464.81619 -114.452273)
					(end 465.19973 -114.83594)
				)
				(arc
					(start 466.46973 -114.83594)
					(mid 466.85327 -114.4524)
					(end 466.46973 -114.06886)
				)
				(xy 465.990432 -114.06886) (xy 465.990432 -114.295174) (xy 466.077808 -114.38255)
				(arc
					(start 466.212428 -114.38255)
					(mid 466.736345 -114.4524)
					(end 466.212428 -114.52225)
				)
				(xy 466.019896 -114.52225) (xy 465.850732 -114.353086) (xy 465.850732 -114.06886)
			)
		)
	)
	(zone
		(layer "F.Cu")
		(hatch none 0.5)
		(connect_pads
			(clearance 0)
		)
		(min_thickness 0.25)
		(keepout
			(tracks allowed)
			(vias allowed)
			(pads allowed)
			(copperpour allowed)
			(footprints allowed)
		)
		(placement
			(enabled no)
			(sheetname "")
		)
		(fill
			(thermal_gap 0.5)
			(thermal_bridge_width 0.5)
			(island_removal_mode 0)
		)
		(polygon
			(pts
				(xy 348.234 -6.223) (xy 350.52 -6.223) (xy 350.52 -8.2296) (xy 348.234 -8.2296)
			)
		)
	)
	(zone
		(layer "F.Cu")
		(hatch none 0.5)
		(connect_pads
			(clearance 0)
		)
		(min_thickness 0.25)
		(keepout
			(tracks allowed)
			(vias allowed)
			(pads allowed)
			(copperpour allowed)
			(footprints allowed)
		)
		(placement
			(enabled no)
			(sheetname "")
		)
		(fill
			(thermal_gap 0.5)
			(thermal_bridge_width 0.5)
			(island_removal_mode 0)
		)
		(polygon
			(pts
				(xy 342.392 -13.335) (xy 342.392 -11.303) (xy 344.551 -11.303) (xy 344.551 -13.335)
			)
		)
	)
	(zone
		(layer "F.Cu")
		(hatch none 0.5)
		(connect_pads
			(clearance 0)
		)
		(min_thickness 0.25)
		(keepout
			(tracks allowed)
			(vias allowed)
			(pads allowed)
			(copperpour allowed)
			(footprints allowed)
		)
		(placement
			(enabled no)
			(sheetname "")
		)
		(fill
			(thermal_gap 0.5)
			(thermal_bridge_width 0.5)
			(island_removal_mode 0)
		)
		(polygon
			(pts
				(xy 192.278 -13.843) (xy 192.278 -12.954) (xy 193.167 -12.954) (xy 193.167 -13.843)
			)
		)
	)
	(zone
		(layer "F.Cu")
		(hatch none 0.5)
		(connect_pads
			(clearance 0)
		)
		(min_thickness 0.25)
		(keepout
			(tracks not_allowed)
			(vias allowed)
			(pads allowed)
			(copperpour not_allowed)
			(footprints allowed)
		)
		(placement
			(enabled no)
			(sheetname "")
		)
		(fill
			(thermal_gap 0.5)
			(thermal_bridge_width 0.5)
			(island_removal_mode 0)
		)
		(polygon
			(pts
				(xy 409.674822 -10.814558) (xy 410.182822 -10.814558) (xy 410.182822 -11.170158) (xy 409.674822 -11.170158)
			)
		)
	)
	(zone
		(layer "F.Cu")
		(hatch none 0.5)
		(connect_pads
			(clearance 0)
		)
		(min_thickness 0.25)
		(keepout
			(tracks not_allowed)
			(vias allowed)
			(pads allowed)
			(copperpour not_allowed)
			(footprints allowed)
		)
		(placement
			(enabled no)
			(sheetname "")
		)
		(fill
			(thermal_gap 0.5)
			(thermal_bridge_width 0.5)
			(island_removal_mode 0)
		)
		(polygon
			(pts
				(arc
					(start 4.629912 -42.7101)
					(mid 7.229856 -45.310044)
					(end 4.629912 -47.909988)
				)
				(arc
					(start 4.629912 -47.909988)
					(mid 2.029968 -45.310044)
					(end 4.629912 -42.7101)
				)
			)
		)
	)
	(zone
		(net "GND")
		(layer "F.Cu")
		(hatch none 0.5)
		(connect_pads
			(clearance 0.5)
		)
		(min_thickness 0.25)
		(fill yes
			(thermal_gap 0.5)
			(thermal_bridge_width 0.5)
			(island_removal_mode 0)
		)
		(polygon
			(pts
				(xy 279.817068 -141.390878) (xy 278.43734 -141.390878) (xy 278.359108 -141.3129) (xy 278.359616 -141.312392)
				(xy 278.359616 -141.031468) (xy 278.23033 -140.902182) (xy 278.23033 -138.976862) (xy 278.43734 -138.769852)
				(xy 279.861264 -138.769852) (xy 280.06167 -138.970258) (xy 280.06167 -141.146276)
			)
		)
	)
	(zone
		(net "GND")
		(layer "F.Cu")
		(hatch none 0.5)
		(connect_pads
			(clearance 0.5)
		)
		(min_thickness 0.25)
		(fill yes
			(thermal_gap 0.5)
			(thermal_bridge_width 0.5)
			(island_removal_mode 0)
		)
		(polygon
			(pts
				(xy 391.795 -104.775) (xy 390.144 -104.775) (xy 389.763 -105.156) (xy 389.509 -105.156) (xy 389.128 -104.775)
				(xy 387.015228 -104.775) (xy 386.842 -104.601772) (xy 386.842 -104.181656) (xy 386.883656 -104.14)
				(xy 386.969 -104.14) (xy 387.096 -104.013) (xy 387.223 -104.013) (xy 387.35 -104.14) (xy 387.353048 -104.14)
				(xy 387.383782 -104.170734) (xy 387.861556 -104.170734) (xy 387.89229 -104.14) (xy 388.576312 -104.14)
				(xy 388.607046 -104.170734) (xy 388.846568 -104.170734) (xy 388.877302 -104.14) (xy 389.577326 -104.14)
				(xy 389.607806 -104.17048) (xy 389.826754 -104.17048) (xy 389.857234 -104.14) (xy 390.563862 -104.14)
				(xy 390.598152 -104.17429) (xy 390.81837 -104.17429) (xy 390.85266 -104.14) (xy 390.852914 -104.14)
				(xy 390.869424 -104.12349) (xy 391.52957 -104.12349) (xy 391.569956 -104.163876) (xy 391.598912 -104.163876)
				(xy 391.795 -104.359964)
			)
		)
	)
	(zone
		(layer "F.Cu")
		(hatch none 0.5)
		(connect_pads
			(clearance 0)
		)
		(min_thickness 0.25)
		(keepout
			(tracks allowed)
			(vias allowed)
			(pads allowed)
			(copperpour allowed)
			(footprints allowed)
		)
		(placement
			(enabled no)
			(sheetname "")
		)
		(fill
			(thermal_gap 0.5)
			(thermal_bridge_width 0.5)
			(island_removal_mode 0)
		)
		(polygon
			(pts
				(xy 345.531186 -126.559056) (xy 345.531186 -124.854208) (xy 348.8436 -124.854208) (xy 348.8436 -126.559056)
			)
		)
	)
	(zone
		(layer "F.Cu")
		(hatch none 0.5)
		(connect_pads
			(clearance 0)
		)
		(min_thickness 0.25)
		(keepout
			(tracks allowed)
			(vias allowed)
			(pads allowed)
			(copperpour allowed)
			(footprints not_allowed)
		)
		(placement
			(enabled no)
			(sheetname "")
		)
		(fill
			(thermal_gap 0.5)
			(thermal_bridge_width 0.5)
			(island_removal_mode 0)
		)
		(polygon
			(pts
				(arc
					(start 495.020092 -34.120074)
					(mid 491.42015 -30.520132)
					(end 495.020092 -26.919936)
				)
				(arc
					(start 498.020086 -26.919936)
					(mid 501.75979 -30.520137)
					(end 498.020086 -34.120074)
				)
			)
		)
	)
	(zone
		(net "P3V3")
		(layer "F.Cu")
		(hatch none 0.5)
		(connect_pads
			(clearance 0.5)
		)
		(min_thickness 0.25)
		(fill yes
			(thermal_gap 0.5)
			(thermal_bridge_width 0.5)
			(island_removal_mode 0)
		)
		(polygon
			(pts
				(xy 477.9264 -117.983) (xy 477.9264 -114.6302) (xy 478.663 -113.8936) (xy 478.663 -111.0869) (xy 478.7519 -110.998)
				(xy 481.6094 -110.998) (xy 481.711 -111.0996) (xy 481.711 -113.8428) (xy 480.8728 -114.681) (xy 480.8728 -115.0112)
				(xy 480.8728 -117.983) (xy 480.695 -118.1608) (xy 478.1042 -118.1608)
			)
		)
	)
	(zone
		(net "GND")
		(layer "F.Cu")
		(hatch none 0.5)
		(connect_pads
			(clearance 0.5)
		)
		(min_thickness 0.25)
		(fill yes
			(thermal_gap 0.5)
			(thermal_bridge_width 0.5)
			(island_removal_mode 0)
		)
		(polygon
			(pts
				(xy 173.3804 -129.2352) (xy 174.1932 -129.2352) (xy 174.371 -129.0574) (xy 174.371 -127.9144) (xy 174.1932 -127.7366)
				(xy 173.7614 -127.7366) (xy 173.640496 -127.857504) (xy 173.640496 -128.187704) (xy 173.609 -128.2192)
				(xy 173.2788 -128.5494) (xy 173.2788 -129.1336)
			)
		)
	)
	(zone
		(net "PVDDQ_GHJ")
		(layer "F.Cu")
		(hatch none 0.5)
		(connect_pads
			(clearance 0.5)
		)
		(min_thickness 0.25)
		(fill yes
			(thermal_gap 0.5)
			(thermal_bridge_width 0.5)
			(island_removal_mode 0)
		)
		(polygon
			(pts
				(xy 79.347568 -11.4808) (xy 78.585568 -12.2428) (xy 78.585568 -14.2621) (xy 78.712568 -14.3891)
				(xy 93.000068 -14.3891) (xy 93.190568 -14.5796) (xy 93.190568 -16.3576) (xy 92.961968 -16.5862)
				(xy 92.961968 -16.891) (xy 93.088968 -17.018) (xy 93.520768 -17.018) (xy 93.7006 -16.838168) (xy 93.7006 -14.4907)
				(xy 93.9673 -14.224) (xy 94.63278 -14.224) (xy 94.85122 -14.00556) (xy 94.85122 -12.45108) (xy 94.73184 -12.3317)
				(xy 92.6973 -12.3317) (xy 92.64396 -12.38504) (xy 92.64396 -13.36294) (xy 92.55252 -13.45438) (xy 91.32316 -13.45438)
				(xy 91.32316 -12.20216) (xy 91.33586 -12.18946) (xy 91.33586 -11.6332) (xy 91.18346 -11.4808)
			)
		)
		(polygon
			(pts
				(xy 88.0491 -13.3477) (xy 87.8459 -13.3477) (xy 87.8459 -13.5509) (xy 88.0491 -13.5509)
			)
		)
		(polygon
			(pts
				(xy 93.682312 -13.218668) (xy 93.479112 -13.218668) (xy 93.479112 -13.421868) (xy 93.682312 -13.421868)
			)
		)
		(polygon
			(pts
				(xy 88.0491 -12.3571) (xy 87.8459 -12.3571) (xy 87.8459 -12.5603) (xy 88.0491 -12.5603)
			)
		)
		(polygon
			(pts
				(xy 84.402168 -12.3571) (xy 84.198968 -12.3571) (xy 84.198968 -12.5603) (xy 84.402168 -12.5603)
			)
		)
		(polygon
			(pts
				(xy 81.303368 -12.3571) (xy 81.100168 -12.3571) (xy 81.100168 -12.5603) (xy 81.303368 -12.5603)
			)
		)
	)
	(zone
		(net "VR_PVCCIN_CPU0_PHASE5")
		(layer "F.Cu")
		(hatch none 0.5)
		(connect_pads
			(clearance 0.5)
		)
		(min_thickness 0.25)
		(fill yes
			(thermal_gap 0.5)
			(thermal_bridge_width 0.5)
			(island_removal_mode 0)
		)
		(polygon
			(pts
				(xy 201.7776 -92.167202) (xy 205.657196 -92.167202) (xy 206.645764 -92.167202) (xy 206.8703 -91.942666)
				(xy 206.8703 -87.617554) (xy 206.339948 -87.087202) (xy 205.657196 -87.087202) (xy 201.803 -87.087202)
				(xy 201.4728 -87.417402) (xy 201.4728 -91.862402)
			)
		)
	)
	(zone
		(layer "F.Cu")
		(hatch none 0.5)
		(connect_pads
			(clearance 0)
		)
		(min_thickness 0.25)
		(keepout
			(tracks not_allowed)
			(vias allowed)
			(pads allowed)
			(copperpour not_allowed)
			(footprints allowed)
		)
		(placement
			(enabled no)
			(sheetname "")
		)
		(fill
			(thermal_gap 0.5)
			(thermal_bridge_width 0.5)
			(island_removal_mode 0)
		)
		(polygon
			(pts
				(arc
					(start 83.000088 -113.450116)
					(mid 81.100168 -111.550196)
					(end 83.000088 -109.650022)
				)
				(arc
					(start 83.000088 -109.650022)
					(mid 84.900262 -111.550196)
					(end 83.000088 -113.450116)
				)
			)
		)
	)
	(zone
		(net "PVTT_KLM")
		(layer "F.Cu")
		(hatch none 0.5)
		(connect_pads
			(clearance 0.5)
		)
		(min_thickness 0.25)
		(fill yes
			(thermal_gap 0.5)
			(thermal_bridge_width 0.5)
			(island_removal_mode 0)
		)
		(polygon
			(pts
				(xy 94.003368 -157.5054) (xy 94.003368 -157.133544) (xy 94.047564 -157.089348) (xy 94.047564 -153.755598)
				(xy 94.048072 -153.75509) (xy 94.048072 -151.116538) (xy 94.048072 -150.6474) (xy 94.050104 -150.645368)
				(xy 94.124272 -150.5712) (xy 94.257368 -150.5712) (xy 94.301818 -150.5712) (xy 94.41053 -150.679912)
				(xy 94.41053 -150.724362) (xy 94.41053 -150.975568) (xy 94.75978 -151.324818) (xy 96.378014 -151.324818)
				(xy 96.74606 -150.956772) (xy 96.74606 -149.097492) (xy 96.74606 -149.036786) (xy 96.718882 -149.009608)
				(xy 93.952314 -149.009608) (xy 93.85935 -148.916644) (xy 93.85935 -148.679408) (xy 93.86316 -148.679408)
				(xy 94.047564 -148.495004) (xy 94.047564 -147.184364) (xy 94.042738 -147.179538) (xy 94.042738 -141.92123)
				(xy 94.104968 -141.859) (xy 94.155768 -141.8082) (xy 96.29394 -141.8082) (xy 96.81464 -141.2875)
				(xy 96.87306 -141.22908) (xy 96.87306 -138.603736) (xy 96.81464 -138.545316) (xy 96.624648 -138.355324)
				(xy 95.819976 -138.355324) (xy 95.491554 -138.355324) (xy 95.162878 -138.684) (xy 94.234 -138.684)
				(xy 93.98 -138.43) (xy 93.98 -136.689592) (xy 94.65564 -136.013952) (xy 97.57283 -136.013952) (xy 97.728532 -136.169654)
				(xy 99.478084 -136.169654) (xy 99.826572 -136.518142) (xy 99.826572 -157.221428) (xy 99.3648 -157.6832)
				(xy 96.594168 -157.6832) (xy 94.181168 -157.6832)
			)
		)
	)
	(zone
		(layer "F.Cu")
		(hatch none 0.5)
		(connect_pads
			(clearance 0)
		)
		(min_thickness 0.25)
		(keepout
			(tracks not_allowed)
			(vias allowed)
			(pads allowed)
			(copperpour not_allowed)
			(footprints allowed)
		)
		(placement
			(enabled no)
			(sheetname "")
		)
		(fill
			(thermal_gap 0.5)
			(thermal_bridge_width 0.5)
			(island_removal_mode 0)
		)
		(polygon
			(pts
				(arc
					(start 173.928532 -153.15565)
					(mid 173.338124 -153.485632)
					(end 172.671486 -153.599896)
				)
				(arc
					(start 171.99991 -153.599896)
					(mid 170.499786 -155.10002)
					(end 171.99991 -156.59989)
				)
				(arc
					(start 172.671486 -156.59989)
					(mid 173.338157 -156.714274)
					(end 173.928532 -157.04439)
				)
				(arc
					(start 173.928532 -157.04439)
					(mid 177.999652 -155.10002)
					(end 173.928532 -153.15565)
				)
			)
		)
	)
	(zone
		(layer "F.Cu")
		(hatch none 0.5)
		(connect_pads
			(clearance 0)
		)
		(min_thickness 0.25)
		(keepout
			(tracks allowed)
			(vias allowed)
			(pads allowed)
			(copperpour allowed)
			(footprints not_allowed)
		)
		(placement
			(enabled no)
			(sheetname "")
		)
		(fill
			(thermal_gap 0.5)
			(thermal_bridge_width 0.5)
			(island_removal_mode 0)
		)
		(polygon
			(pts
				(xy 332.725268 -130.16611) (xy 337.725512 -130.16611) (xy 337.725512 -159.100012) (xy 332.725268 -159.100012)
			)
		)
	)
	(zone
		(layer "F.Cu")
		(hatch none 0.5)
		(connect_pads
			(clearance 0)
		)
		(min_thickness 0.25)
		(keepout
			(tracks not_allowed)
			(vias allowed)
			(pads allowed)
			(copperpour not_allowed)
			(footprints allowed)
		)
		(placement
			(enabled no)
			(sheetname "")
		)
		(fill
			(thermal_gap 0.5)
			(thermal_bridge_width 0.5)
			(island_removal_mode 0)
		)
		(polygon
			(pts
				(xy 443.296294 -5.508498) (xy 443.296294 -5.689854) (xy 443.02426 -5.961888)
				(arc
					(start 443.01791 -5.961888)
					(mid 442.49476 -5.91224)
					(end 443.004448 -5.784088)
				)
				(xy 443.156594 -5.631942) (xy 443.156594 -5.508498)
				(arc
					(start 442.760608 -5.508498)
					(mid 442.377068 -5.892038)
					(end 442.760608 -6.275578)
				)
				(arc
					(start 444.030354 -6.275578)
					(mid 444.414148 -5.892165)
					(end 444.030608 -5.508498)
				)
				(xy 443.537594 -5.508498) (xy 443.537594 -5.61213) (xy 443.747652 -5.822188)
				(arc
					(start 443.773306 -5.822188)
					(mid 444.297223 -5.892038)
					(end 443.773306 -5.961888)
				)
				(xy 443.68974 -5.961888) (xy 443.397894 -5.670042) (xy 443.397894 -5.508498)
			)
		)
	)
	(zone
		(layer "F.Cu")
		(hatch none 0.5)
		(connect_pads
			(clearance 0)
		)
		(min_thickness 0.25)
		(keepout
			(tracks allowed)
			(vias allowed)
			(pads allowed)
			(copperpour allowed)
			(footprints not_allowed)
		)
		(placement
			(enabled no)
			(sheetname "")
		)
		(fill
			(thermal_gap 0.5)
			(thermal_bridge_width 0.5)
			(island_removal_mode 0)
		)
		(polygon
			(pts
				(arc
					(start 127 -44.090082)
					(mid 124.46 -41.550082)
					(end 127 -39.010082)
				)
				(arc
					(start 127 -39.010082)
					(mid 129.54 -41.550082)
					(end 127 -44.090082)
				)
			)
		)
	)
	(zone
		(net "P12V_STBY")
		(layer "F.Cu")
		(hatch none 0.5)
		(connect_pads
			(clearance 0.5)
		)
		(min_thickness 0.25)
		(fill yes
			(thermal_gap 0.5)
			(thermal_bridge_width 0.5)
			(island_removal_mode 0)
		)
		(polygon
			(pts
				(xy 442.4172 -64.5414) (xy 442.4172 -60.8838) (xy 442.3156 -60.7822) (xy 440.3344 -60.7822) (xy 440.2582 -60.8584)
				(xy 440.2582 -64.5414) (xy 440.3344 -64.6176) (xy 440.3344 -64.643) (xy 442.3156 -64.643)
			)
		)
	)
	(zone
		(net "PVDDQ_ABC")
		(layer "F.Cu")
		(hatch none 0.5)
		(connect_pads
			(clearance 0.5)
		)
		(min_thickness 0.25)
		(fill yes
			(thermal_gap 0.5)
			(thermal_bridge_width 0.5)
			(island_removal_mode 0)
		)
		(polygon
			(pts
				(xy 266.29487 -1.85293) (xy 265.9888 -2.159) (xy 265.9888 -4.191) (xy 266.56792 -4.77012) (xy 277.42388 -4.77012)
				(xy 277.749 -4.445) (xy 277.749 -2.286) (xy 277.31593 -1.85293)
			)
		)
		(polygon
			(pts
				(xy 275.657564 -3.7465) (xy 275.454364 -3.7465) (xy 275.454364 -3.9497) (xy 275.657564 -3.9497)
			)
		)
		(polygon
			(pts
				(xy 272.518632 -3.7465) (xy 272.315432 -3.7465) (xy 272.315432 -3.9497) (xy 272.518632 -3.9497)
			)
		)
		(polygon
			(pts
				(xy 269.216632 -3.7465) (xy 269.013432 -3.7465) (xy 269.013432 -3.9497) (xy 269.216632 -3.9497)
			)
		)
		(polygon
			(pts
				(xy 272.518632 -2.7559) (xy 272.315432 -2.7559) (xy 272.315432 -2.9591) (xy 272.518632 -2.9591)
			)
		)
		(polygon
			(pts
				(xy 269.216632 -2.7559) (xy 269.013432 -2.7559) (xy 269.013432 -2.9591) (xy 269.216632 -2.9591)
			)
		)
	)
	(zone
		(net "P12V_STBY")
		(layer "F.Cu")
		(hatch none 0.5)
		(connect_pads
			(clearance 0.5)
		)
		(min_thickness 0.25)
		(fill yes
			(thermal_gap 0.5)
			(thermal_bridge_width 0.5)
			(island_removal_mode 0)
		)
		(polygon
			(pts
				(xy 352.6028 -137.668254) (xy 352.460052 -137.811002) (xy 351.462848 -137.811002) (xy 351.2566 -137.604754)
				(xy 351.2566 -135.7122) (xy 351.028 -135.4836) (xy 351.028 -134.535926) (xy 351.063306 -134.50062)
				(xy 352.53422 -134.50062) (xy 352.6028 -134.5692)
			)
		)
	)
	(zone
		(net "GND")
		(layer "F.Cu")
		(hatch none 0.5)
		(connect_pads
			(clearance 0.5)
		)
		(min_thickness 0.25)
		(fill yes
			(thermal_gap 0.5)
			(thermal_bridge_width 0.5)
			(island_removal_mode 0)
		)
		(polygon
			(pts
				(xy 24.5364 -46.3804) (xy 24.5364 -44.1452) (xy 25.273 -43.4086) (xy 26.1112 -43.4086) (xy 26.8732 -44.1706)
				(xy 26.8732 -46.3804) (xy 26.8732 -47.0662) (xy 26.8732 -47.3456) (xy 26.8605 -47.3583) (xy 26.8605 -48.0695)
				(xy 26.67 -48.26) (xy 24.638 -48.26) (xy 24.5364 -48.1584) (xy 24.5364 -47.3456) (xy 24.5364 -47.1932)
			)
		)
	)
	(zone
		(layer "F.Cu")
		(hatch none 0.5)
		(connect_pads
			(clearance 0)
		)
		(min_thickness 0.25)
		(keepout
			(tracks allowed)
			(vias allowed)
			(pads allowed)
			(copperpour allowed)
			(footprints not_allowed)
		)
		(placement
			(enabled no)
			(sheetname "")
		)
		(fill
			(thermal_gap 0.5)
			(thermal_bridge_width 0.5)
			(island_removal_mode 0)
		)
		(polygon
			(pts
				(arc
					(start 318.000126 -101.089968)
					(mid 315.460126 -98.549968)
					(end 318.000126 -96.009968)
				)
				(arc
					(start 318.000126 -96.009968)
					(mid 320.540126 -98.549968)
					(end 318.000126 -101.089968)
				)
			)
		)
	)
	(zone
		(layer "F.Cu")
		(hatch none 0.5)
		(connect_pads
			(clearance 0)
		)
		(min_thickness 0.25)
		(keepout
			(tracks allowed)
			(vias allowed)
			(pads allowed)
			(copperpour allowed)
			(footprints not_allowed)
		)
		(placement
			(enabled no)
			(sheetname "")
		)
		(fill
			(thermal_gap 0.5)
			(thermal_bridge_width 0.5)
			(island_removal_mode 0)
		)
		(polygon
			(pts
				(arc
					(start 406.489916 -137.489946)
					(mid 402.89988 -133.89991)
					(end 406.489916 -130.309874)
				)
				(arc
					(start 406.489916 -130.309874)
					(mid 410.079952 -133.89991)
					(end 406.489916 -137.489946)
				)
			)
		)
	)
	(zone
		(layer "F.Cu")
		(hatch none 0.5)
		(connect_pads
			(clearance 0)
		)
		(min_thickness 0.25)
		(keepout
			(tracks allowed)
			(vias allowed)
			(pads allowed)
			(copperpour allowed)
			(footprints allowed)
		)
		(placement
			(enabled no)
			(sheetname "")
		)
		(fill
			(thermal_gap 0.5)
			(thermal_bridge_width 0.5)
			(island_removal_mode 0)
		)
		(polygon
			(pts
				(xy 232.827576 -98.44024) (xy 233.731054 -98.44024) (xy 234.20705 -98.916236) (xy 235.201714 -98.916236)
				(xy 236.711236 -100.425758) (xy 237.580424 -100.425758) (xy 237.61446 -100.45954) (xy 237.617 -100.457)
				(xy 238.76 -100.457) (xy 238.76 -101.854) (xy 238.260128 -101.854) (xy 232.664 -101.854) (xy 232.537 -101.727)
				(xy 232.537 -98.806) (xy 232.618788 -98.724212) (xy 232.618788 -98.649028)
			)
		)
	)
	(zone
		(layer "F.Cu")
		(hatch none 0.5)
		(connect_pads
			(clearance 0)
		)
		(min_thickness 0.25)
		(keepout
			(tracks allowed)
			(vias allowed)
			(pads allowed)
			(copperpour allowed)
			(footprints allowed)
		)
		(placement
			(enabled no)
			(sheetname "")
		)
		(fill
			(thermal_gap 0.5)
			(thermal_bridge_width 0.5)
			(island_removal_mode 0)
		)
		(polygon
			(pts
				(xy 343.916 -19.431) (xy 343.916 -17.399) (xy 346.075 -17.399) (xy 346.075 -19.431)
			)
		)
	)
	(zone
		(layer "F.Cu")
		(hatch none 0.5)
		(connect_pads
			(clearance 0)
		)
		(min_thickness 0.25)
		(keepout
			(tracks allowed)
			(vias allowed)
			(pads allowed)
			(copperpour allowed)
			(footprints allowed)
		)
		(placement
			(enabled no)
			(sheetname "")
		)
		(fill
			(thermal_gap 0.5)
			(thermal_bridge_width 0.5)
			(island_removal_mode 0)
		)
		(polygon
			(pts
				(xy 374.1166 -151.765) (xy 378.4854 -151.765) (xy 378.4854 -154.178) (xy 378.4854 -154.3558) (xy 378.4092 -154.432)
				(xy 375.0056 -154.432) (xy 372.5164 -154.432) (xy 372.1862 -154.1018) (xy 372.1862 -153.0858) (xy 372.1862 -152.6794)
				(xy 373.1006 -151.765)
			)
		)
	)
	(zone
		(layer "F.Cu")
		(hatch none 0.5)
		(connect_pads
			(clearance 0)
		)
		(min_thickness 0.25)
		(keepout
			(tracks allowed)
			(vias allowed)
			(pads allowed)
			(copperpour allowed)
			(footprints allowed)
		)
		(placement
			(enabled no)
			(sheetname "")
		)
		(fill
			(thermal_gap 0.5)
			(thermal_bridge_width 0.5)
			(island_removal_mode 0)
		)
		(polygon
			(pts
				(xy 164.5412 -86.7918) (xy 164.5412 -84.7598) (xy 173.0756 -84.7598) (xy 173.0756 -86.7918)
			)
		)
	)
	(zone
		(layer "F.Cu")
		(hatch none 0.5)
		(connect_pads
			(clearance 0)
		)
		(min_thickness 0.25)
		(keepout
			(tracks not_allowed)
			(vias allowed)
			(pads allowed)
			(copperpour not_allowed)
			(footprints allowed)
		)
		(placement
			(enabled no)
			(sheetname "")
		)
		(fill
			(thermal_gap 0.5)
			(thermal_bridge_width 0.5)
			(island_removal_mode 0)
		)
		(polygon
			(pts
				(arc
					(start 127 -39.649908)
					(mid 128.900174 -41.550082)
					(end 127 -43.450002)
				)
				(arc
					(start 127 -43.450002)
					(mid 125.10008 -41.550082)
					(end 127 -39.649908)
				)
			)
		)
	)
	(zone
		(net "GND")
		(layer "F.Cu")
		(hatch none 0.5)
		(connect_pads
			(clearance 0.5)
		)
		(min_thickness 0.25)
		(fill yes
			(thermal_gap 0.5)
			(thermal_bridge_width 0.5)
			(island_removal_mode 0)
		)
		(polygon
			(pts
				(xy 367.954306 -131.384294) (xy 367.8936 -131.445) (xy 367.8936 -132.65404) (xy 369.695476 -134.455916)
				(xy 371.603016 -134.455916) (xy 371.8433 -134.6962) (xy 371.8433 -135.7249) (xy 371.8814 -135.763)
				(xy 373.700294 -135.763) (xy 373.738394 -135.7249) (xy 375.1199 -135.7249) (xy 375.140728 -135.745728)
				(xy 375.140728 -136.071356) (xy 375.16943 -136.100058) (xy 375.226072 -136.1567) (xy 375.658126 -136.1567)
				(xy 377.430792 -136.1567) (xy 377.430792 -136.156192) (xy 378.193808 -136.156192) (xy 378.193808 -136.1567)
				(xy 380.4031 -136.1567) (xy 380.40945 -136.15035) (xy 381.84455 -136.15035) (xy 382.570482 -136.876282)
				(xy 382.570482 -138.163046) (xy 382.719072 -138.311636) (xy 382.719072 -138.368024) (xy 382.718818 -138.368278)
				(xy 382.718818 -139.745974) (xy 382.4097 -140.055092) (xy 382.410208 -140.055092) (xy 382.410208 -140.818108)
				(xy 382.4097 -140.818108) (xy 382.4097 -141.363192) (xy 382.410208 -141.363192) (xy 382.410208 -142.531592)
				(xy 381.069596 -143.872204) (xy 366.02416 -143.872204) (xy 365.369094 -144.52727) (xy 365.369094 -147.766786)
				(xy 365.447834 -147.845526) (xy 367.051082 -147.845526) (xy 367.411 -148.205444) (xy 367.411 -149.357588)
				(xy 367.968784 -149.915372) (xy 369.668298 -149.915372) (xy 371.133878 -151.380952) (xy 371.133878 -152.59812)
				(xy 371.133878 -152.917398) (xy 372.07698 -153.8605) (xy 373.063262 -153.8605) (xy 373.190008 -153.986992)
				(xy 374.484392 -153.986992) (xy 374.5484 -154.051) (xy 374.5484 -154.9146) (xy 374.4468 -155.0162)
				(xy 373.6594 -155.0162) (xy 373.6086 -155.067) (xy 373.6086 -155.2956) (xy 373.634 -155.321) (xy 374.523 -155.321)
				(xy 374.5738 -155.3718) (xy 374.5738 -155.6258) (xy 374.594374 -155.646374) (xy 376.33402 -155.646374)
				(xy 376.3772 -155.603194) (xy 376.3772 -153.698448) (xy 376.59818 -153.477468) (xy 376.598942 -153.477468)
				(xy 376.764296 -153.312114) (xy 379.202442 -153.312114) (xy 379.43155 -153.541222) (xy 381.076962 -153.541222)
				(xy 381.317754 -153.782014) (xy 381.321564 -153.782014) (xy 381.321564 -153.781252) (xy 382.010412 -153.781252)
				(xy 382.48336 -154.2542) (xy 383.6162 -154.2542) (xy 383.6416 -154.2796) (xy 383.6416 -155.3718)
				(xy 383.6162 -155.3972) (xy 382.6764 -155.3972) (xy 382.651 -155.4226) (xy 382.651 -155.575) (xy 382.6764 -155.6004)
				(xy 383.5654 -155.6004) (xy 383.6416 -155.6766) (xy 383.6416 -155.8798) (xy 383.6924 -155.9306)
				(xy 385.3688 -155.9306) (xy 385.3942 -155.9052) (xy 385.3942 -153.8986) (xy 385.7244 -153.5684)
				(xy 389.0645 -153.5684) (xy 389.509 -153.1239)
				(arc
					(start 389.509 -151.992584)
					(mid 389.489304 -151.96494)
					(end 389.471662 -151.935942)
				)
				(arc
					(start 389.471662 -151.935942)
					(mid 389.432378 -151.844565)
					(end 389.413242 -151.746966)
				)
				(arc
					(start 389.413242 -151.746966)
					(mid 389.425502 -151.591999)
					(end 389.487664 -151.449532)
				)
				(arc
					(start 389.487664 -147.864068)
					(mid 389.514355 -147.721575)
					(end 389.590788 -147.598384)
				)
				(xy 389.590788 -143.718026) (xy 389.431784 -143.559022) (xy 386.75564 -143.559022) (xy 385.462018 -142.2654)
				(xy 385.462018 -141.058392) (xy 385.47548 -141.04493) (xy 385.47548 -139.11072) (xy 386.334762 -138.251438)
				(xy 388.602982 -138.251438) (xy 388.60984 -138.24458) (xy 388.60984 -135.412226) (xy 388.34568 -135.148066)
				(xy 386.908548 -135.148066) (xy 384.475482 -132.715) (xy 380.8222 -132.715) (xy 380.37262 -133.16458)
				(xy 378.1171 -133.16458) (xy 377.83897 -132.88645) (xy 376.19559 -132.88645) (xy 376.03684 -133.0452)
				(xy 375.1326 -133.0452) (xy 374.8278 -132.7404) (xy 371.5004 -132.7404) (xy 370.144294 -131.384294)
			)
		)
		(polygon
			(pts
				(xy 381.864108 -147.546568) (xy 381.134112 -147.546568) (xy 381.083566 -147.597114) (xy 381.083566 -149.6949)
				(xy 380.948692 -149.829774) (xy 380.948692 -150.708106) (xy 381.064262 -150.823676) (xy 381.934466 -150.823676)
				(xy 382.078738 -150.679404) (xy 382.078738 -149.827996) (xy 381.901192 -149.65045) (xy 381.901192 -148.327364)
				(xy 381.942848 -148.285708) (xy 381.942848 -147.625308)
			)
		)
		(polygon
			(pts
				(xy 373.006112 -146.17954) (xy 372.124986 -146.17954) (xy 372.084854 -146.219672) (xy 372.084854 -148.303996)
				(xy 371.985286 -148.403564) (xy 371.985286 -149.30247) (xy 372.080536 -149.39772) (xy 372.976648 -149.39772)
				(xy 373.112538 -149.26183) (xy 373.112538 -148.404326) (xy 372.937786 -148.229574) (xy 372.937786 -147.011136)
				(xy 373.054626 -146.894296) (xy 373.054626 -146.228054)
			)
		)
		(polygon
			(pts
				(xy 372.8466 -153.2509) (xy 372.6434 -153.2509) (xy 372.6434 -153.4541) (xy 372.8466 -153.4541)
			)
		)
		(polygon
			(pts
				(xy 372.3386 -153.2509) (xy 372.1354 -153.2509) (xy 372.1354 -153.4541) (xy 372.3386 -153.4541)
			)
		)
		(polygon
			(pts
				(xy 373.083582 -150.584662) (xy 372.880382 -150.584662) (xy 372.880382 -150.787862) (xy 373.083582 -150.787862)
			)
		)
		(polygon
			(pts
				(xy 372.219982 -150.584662) (xy 372.016782 -150.584662) (xy 372.016782 -150.787862) (xy 372.219982 -150.787862)
			)
		)
		(polygon
			(pts
				(xy 373.083582 -149.721062) (xy 372.880382 -149.721062) (xy 372.880382 -149.924262) (xy 373.083582 -149.924262)
			)
		)
		(polygon
			(pts
				(xy 372.219982 -149.721062) (xy 372.016782 -149.721062) (xy 372.016782 -149.924262) (xy 372.219982 -149.924262)
			)
		)
		(polygon
			(pts
				(xy 383.4003 -142.0241) (xy 383.1971 -142.0241) (xy 383.1971 -142.2273) (xy 383.4003 -142.2273)
			)
		)
		(polygon
			(pts
				(xy 384.677666 -141.750796) (xy 384.474466 -141.750796) (xy 384.474466 -141.953996) (xy 384.677666 -141.953996)
			)
		)
		(polygon
			(pts
				(xy 383.4003 -141.2621) (xy 383.1971 -141.2621) (xy 383.1971 -141.4653) (xy 383.4003 -141.4653)
			)
		)
		(polygon
			(pts
				(xy 384.677666 -140.988796) (xy 384.474466 -140.988796) (xy 384.474466 -141.191996) (xy 384.677666 -141.191996)
			)
		)
		(polygon
			(pts
				(xy 383.4003 -140.716) (xy 383.1971 -140.716) (xy 383.1971 -140.9192) (xy 383.4003 -140.9192)
			)
		)
		(polygon
			(pts
				(xy 384.71348 -140.42644) (xy 384.51028 -140.42644) (xy 384.51028 -140.62964) (xy 384.71348 -140.62964)
			)
		)
		(polygon
			(pts
				(xy 383.4003 -139.954) (xy 383.1971 -139.954) (xy 383.1971 -140.1572) (xy 383.4003 -140.1572)
			)
		)
		(polygon
			(pts
				(xy 384.71348 -139.66444) (xy 384.51028 -139.66444) (xy 384.51028 -139.86764) (xy 384.71348 -139.86764)
			)
		)
		(polygon
			(pts
				(xy 378.2949 -135.1661) (xy 378.0917 -135.1661) (xy 378.0917 -135.3693) (xy 378.2949 -135.3693)
			)
		)
		(polygon
			(pts
				(xy 377.5329 -135.1661) (xy 377.3297 -135.1661) (xy 377.3297 -135.3693) (xy 377.5329 -135.3693)
			)
		)
		(polygon
			(pts
				(xy 376.0216 -133.8199) (xy 375.8184 -133.8199) (xy 375.8184 -134.0231) (xy 376.0216 -134.0231)
			)
		)
		(polygon
			(pts
				(xy 375.2596 -133.8199) (xy 375.0564 -133.8199) (xy 375.0564 -134.0231) (xy 375.2596 -134.0231)
			)
		)
		(polygon
			(pts
				(xy 373.761 -133.4897) (xy 373.5578 -133.4897) (xy 373.5578 -133.6929) (xy 373.761 -133.6929)
			)
		)
		(polygon
			(pts
				(xy 372.999 -133.4897) (xy 372.7958 -133.4897) (xy 372.7958 -133.6929) (xy 372.999 -133.6929)
			)
		)
		(polygon
			(pts
				(xy 372.491 -133.4897) (xy 372.2878 -133.4897) (xy 372.2878 -133.6929) (xy 372.491 -133.6929)
			)
		)
		(polygon
			(pts
				(xy 371.729 -133.4897) (xy 371.5258 -133.4897) (xy 371.5258 -133.6929) (xy 371.729 -133.6929)
			)
		)
		(polygon
			(pts
				(xy 370.205 -132.1689) (xy 370.0018 -132.1689) (xy 370.0018 -132.3721) (xy 370.205 -132.3721)
			)
		)
		(polygon
			(pts
				(xy 369.443 -132.1689) (xy 369.2398 -132.1689) (xy 369.2398 -132.3721) (xy 369.443 -132.3721)
			)
		)
		(polygon
			(pts
				(xy 368.8842 -132.1689) (xy 368.681 -132.1689) (xy 368.681 -132.3721) (xy 368.8842 -132.3721)
			)
		)
	)
	(zone
		(layer "F.Cu")
		(hatch none 0.5)
		(connect_pads
			(clearance 0)
		)
		(min_thickness 0.25)
		(keepout
			(tracks not_allowed)
			(vias allowed)
			(pads allowed)
			(copperpour not_allowed)
			(footprints allowed)
		)
		(placement
			(enabled no)
			(sheetname "")
		)
		(fill
			(thermal_gap 0.5)
			(thermal_bridge_width 0.5)
			(island_removal_mode 0)
		)
		(polygon
			(pts
				(arc
					(start 382.92659 -129.485136)
					(mid 382.6711 -129.949693)
					(end 382.82118 -129.441194)
				)
				(xy 382.870202 -129.32283)
				(arc
					(start 382.774444 -129.32283)
					(mid 382.39319 -129.703703)
					(end 382.77419 -130.08483)
				)
				(arc
					(start 383.43459 -130.08483)
					(mid 383.713097 -129.963821)
					(end 383.814574 -129.677668)
				)
				(arc
					(start 383.814574 -129.677668)
					(mid 383.761866 -129.7258)
					(end 383.696464 -129.754376)
				)
				(arc
					(start 383.696464 -129.754376)
					(mid 383.168004 -129.713096)
					(end 383.692146 -129.634234)
				)
				(arc
					(start 383.692146 -129.634234)
					(mid 383.732471 -129.595903)
					(end 383.747264 -129.542286)
				)
				(arc
					(start 383.747264 -129.542286)
					(mid 383.73808 -129.496115)
					(end 383.711958 -129.456942)
				)
				(arc
					(start 383.643632 -129.388616)
					(mid 383.635132 -129.380898)
					(end 383.625852 -129.374138)
				)
				(arc
					(start 383.61366 -129.367534)
					(mid 383.591126 -129.359748)
					(end 383.567432 -129.35712)
				)
				(xy 383.310892 -129.35712)
				(arc
					(start 383.309622 -129.35585)
					(mid 383.255544 -129.344896)
					(end 383.204974 -129.32283)
				)
				(xy 382.99644 -129.32283) (xy 382.99644 -129.328926) (xy 382.987804 -129.337562)
			)
		)
	)
	(zone
		(layer "F.Cu")
		(hatch none 0.5)
		(connect_pads
			(clearance 0)
		)
		(min_thickness 0.25)
		(keepout
			(tracks not_allowed)
			(vias allowed)
			(pads allowed)
			(copperpour not_allowed)
			(footprints allowed)
		)
		(placement
			(enabled no)
			(sheetname "")
		)
		(fill
			(thermal_gap 0.5)
			(thermal_bridge_width 0.5)
			(island_removal_mode 0)
		)
		(polygon
			(pts
				(arc
					(start 15.51813 -25.842468)
					(mid 15.438963 -26.365087)
					(end 15.37843 -25.839928)
				)
				(xy 15.380716 -25.726898) (xy 15.325852 -25.672034) (xy 15.117572 -25.672034) (xy 15.059914 -25.729692)
				(arc
					(start 15.059914 -26.098246)
					(mid 15.443327 -26.48204)
					(end 15.826994 -26.0985)
				)
				(arc
					(start 15.826994 -24.8285)
					(mid 15.443454 -24.44496)
					(end 15.059914 -24.8285)
				)
				(xy 15.059914 -25.197308) (xy 15.117572 -25.254966) (xy 15.325852 -25.254966) (xy 15.380716 -25.200102)
				(arc
					(start 15.37843 -25.087072)
					(mid 15.438962 -24.561858)
					(end 15.51813 -25.084532)
				)
				(xy 15.520416 -25.199086) (xy 15.520924 -25.199594) (xy 15.520924 -25.227788) (xy 15.521432 -25.256236)
				(xy 15.520924 -25.256744) (xy 15.520924 -25.257506) (xy 15.500858 -25.277572) (xy 15.4813 -25.297892)
				(xy 15.480538 -25.297892) (xy 15.383764 -25.394666) (xy 15.059914 -25.394666) (xy 15.059914 -25.532334)
				(xy 15.383764 -25.532334) (xy 15.480538 -25.629108) (xy 15.4813 -25.629108) (xy 15.500858 -25.649428)
				(xy 15.520924 -25.669494) (xy 15.520924 -25.670256) (xy 15.521432 -25.670764) (xy 15.520924 -25.699212)
				(xy 15.520924 -25.727406) (xy 15.520416 -25.727914)
			)
		)
	)
	(zone
		(layer "F.Cu")
		(hatch none 0.5)
		(connect_pads
			(clearance 0)
		)
		(min_thickness 0.25)
		(keepout
			(tracks not_allowed)
			(vias allowed)
			(pads allowed)
			(copperpour not_allowed)
			(footprints allowed)
		)
		(placement
			(enabled no)
			(sheetname "")
		)
		(fill
			(thermal_gap 0.5)
			(thermal_bridge_width 0.5)
			(island_removal_mode 0)
		)
		(polygon
			(pts
				(xy 452.949056 -114.020092) (xy 452.949056 -114.279172) (xy 452.754746 -114.473482)
				(arc
					(start 452.622158 -114.473482)
					(mid 452.098241 -114.403632)
					(end 452.622158 -114.333782)
				)
				(xy 452.696834 -114.333782) (xy 452.809356 -114.22126) (xy 452.809356 -114.020092)
				(arc
					(start 452.36511 -114.020092)
					(mid 451.981316 -114.403505)
					(end 452.364856 -114.787172)
				)
				(arc
					(start 453.634856 -114.787172)
					(mid 454.018396 -114.403632)
					(end 453.634856 -114.020092)
				)
				(xy 453.190356 -114.020092) (xy 453.190356 -114.22126) (xy 453.302878 -114.333782)
				(arc
					(start 453.377554 -114.333782)
					(mid 453.901471 -114.403632)
					(end 453.377554 -114.473482)
				)
				(xy 453.244966 -114.473482) (xy 453.050656 -114.279172) (xy 453.050656 -114.020092)
			)
		)
	)
	(zone
		(net "P2V5_AUX_BMC")
		(layer "F.Cu")
		(hatch none 0.5)
		(connect_pads
			(clearance 0.5)
		)
		(min_thickness 0.25)
		(fill yes
			(thermal_gap 0.5)
			(thermal_bridge_width 0.5)
			(island_removal_mode 0)
		)
		(polygon
			(pts
				(xy 448.636644 -25.911556) (xy 449.012056 -25.911556) (xy 450.330062 -27.229562) (xy 452.264526 -27.229562)
				(xy 452.3105 -27.183588) (xy 452.3105 -27.0637) (xy 452.3105 -26.290524) (xy 452.11492 -26.094944)
				(xy 452.11492 -25.907238) (xy 452.11492 -24.61768) (xy 452.3232 -24.4094) (xy 452.4756 -24.4094)
				(xy 453.1106 -23.7744) (xy 453.1106 -22.500336) (xy 453.081898 -22.471634) (xy 452.233284 -22.471634)
				(xy 452.140828 -22.56409) (xy 451.063614 -22.56409) (xy 450.98081 -22.56409) (xy 450.6849 -22.86)
				(xy 450.6849 -23.2156) (xy 450.4309 -23.4696) (xy 449.6435 -23.4696) (xy 449.4403 -23.2664) (xy 449.4403 -21.914612)
				(xy 449.3768 -21.851112) (xy 447.375788 -21.851112) (xy 447.1797 -22.0472) (xy 447.1797 -24.0919)
				(xy 447.04 -24.2316) (xy 445.633856 -24.2316) (xy 445.625728 -24.239728) (xy 445.533272 -24.239728)
				(xy 444.373 -25.4) (xy 443.484 -25.4) (xy 442.722 -26.162) (xy 442.722 -26.273252) (xy 443.245748 -26.797)
				(xy 447.615818 -26.797) (xy 448.501262 -25.911556)
			)
		)
	)
	(zone
		(net "PVTT_ABC")
		(layer "F.Cu")
		(hatch none 0.5)
		(connect_pads
			(clearance 0.5)
		)
		(min_thickness 0.25)
		(fill yes
			(thermal_gap 0.5)
			(thermal_bridge_width 0.5)
			(island_removal_mode 0)
		)
		(polygon
			(pts
				(xy 183.498998 1.612392) (xy 183.498998 -0.089408) (xy 183.549798 -0.140208) (xy 183.727598 -0.140208)
				(xy 183.752998 -0.114808) (xy 183.752998 0.494792) (xy 183.752998 0.538988) (xy 185.357262 2.143252)
				(xy 185.404506 2.190496) (xy 185.404506 3.438144) (xy 185.357262 3.485388) (xy 185.357262 4.392168)
				(xy 185.241438 4.507992) (xy 183.930798 4.507992) (xy 183.771032 4.507992) (xy 183.582056 4.319016)
				(xy 183.582056 3.480308) (xy 183.752998 3.309366) (xy 183.752998 1.866392) (xy 183.651398 1.764792)
			)
		)
	)
	(zone
		(layer "F.Cu")
		(hatch none 0.5)
		(connect_pads
			(clearance 0)
		)
		(min_thickness 0.25)
		(keepout
			(tracks not_allowed)
			(vias allowed)
			(pads allowed)
			(copperpour not_allowed)
			(footprints allowed)
		)
		(placement
			(enabled no)
			(sheetname "")
		)
		(fill
			(thermal_gap 0.5)
			(thermal_bridge_width 0.5)
			(island_removal_mode 0)
		)
		(polygon
			(pts
				(arc
					(start 394.948156 -25.366218)
					(mid 395.088898 -25.463118)
					(end 395.141958 -25.625552)
				)
				(xy 395.30655 -25.790144) (xy 395.30655 -25.879298) (xy 395.4272 -25.879298) (xy 395.4272 -25.74544)
				(arc
					(start 395.503908 -25.668732)
					(mid 395.540686 -25.481055)
					(end 395.693646 -25.366218)
				)
			)
		)
	)
	(zone
		(layer "F.Cu")
		(hatch none 0.5)
		(connect_pads
			(clearance 0)
		)
		(min_thickness 0.25)
		(keepout
			(tracks allowed)
			(vias allowed)
			(pads allowed)
			(copperpour allowed)
			(footprints not_allowed)
		)
		(placement
			(enabled no)
			(sheetname "")
		)
		(fill
			(thermal_gap 0.5)
			(thermal_bridge_width 0.5)
			(island_removal_mode 0)
		)
		(polygon
			(pts
				(arc
					(start 291.999924 -109.650022)
					(mid 293.900098 -111.550196)
					(end 291.999924 -113.450116)
				)
				(arc
					(start 291.999924 -113.450116)
					(mid 290.100004 -111.550196)
					(end 291.999924 -109.650022)
				)
			)
		)
	)
	(zone
		(net "GND")
		(layer "F.Cu")
		(hatch none 0.5)
		(connect_pads
			(clearance 0.5)
		)
		(min_thickness 0.25)
		(fill yes
			(thermal_gap 0.5)
			(thermal_bridge_width 0.5)
			(island_removal_mode 0)
		)
		(polygon
			(pts
				(xy 182.499 -68.072) (xy 182.499 -71.628) (xy 186.055 -71.628) (xy 186.055 -68.072)
			)
		)
	)
	(zone
		(layer "F.Cu")
		(hatch none 0.5)
		(connect_pads
			(clearance 0)
		)
		(min_thickness 0.25)
		(keepout
			(tracks allowed)
			(vias allowed)
			(pads allowed)
			(copperpour allowed)
			(footprints allowed)
		)
		(placement
			(enabled no)
			(sheetname "")
		)
		(fill
			(thermal_gap 0.5)
			(thermal_bridge_width 0.5)
			(island_removal_mode 0)
		)
		(polygon
			(pts
				(xy 345.694 -156.464) (xy 345.694 -152.0952) (xy 348.107 -152.0952) (xy 348.107 -156.464)
			)
		)
	)
	(zone
		(net "GND")
		(layer "F.Cu")
		(hatch none 0.5)
		(connect_pads
			(clearance 0.5)
		)
		(min_thickness 0.25)
		(fill yes
			(thermal_gap 0.5)
			(thermal_bridge_width 0.5)
			(island_removal_mode 0)
		)
		(polygon
			(pts
				(xy 161.840164 -28.949396) (xy 161.354008 -29.435806) (xy 161.354008 -30.065472) (xy 161.387028 -30.098492)
				(xy 161.387028 -30.391608) (xy 161.151824 -30.626812) (xy 160.244536 -30.626812) (xy 158.2674 -32.603694)
				(xy 158.2674 -33.513268) (xy 158.471108 -33.716976) (xy 164.979858 -33.716976) (xy 165.095174 -33.60166)
				(xy 165.119812 -33.60166) (xy 165.12032 -33.601152) (xy 167.382952 -33.601152) (xy 167.654478 -33.872678)
				(xy 167.654478 -36.274248) (xy 167.877236 -36.497006) (xy 167.877236 -40.430704) (xy 168.010078 -40.5638)
				(xy 186.3344 -40.5638) (xy 186.7154 -40.9448) (xy 186.7154 -41.5544) (xy 186.691524 -41.578276)
				(xy 186.691524 -42.216324) (xy 186.8932 -42.418) (xy 186.8932 -44.184824) (xy 187.234576 -44.5262)
				(xy 192.914778 -44.5262) (xy 194.339972 -43.101006) (xy 206.049626 -43.101006) (xy 207.152748 -41.997884)
				(xy 207.152748 -35.450018) (xy 206.212186 -34.509456) (xy 192.065656 -34.509456) (xy 191.77 -34.2138)
				(xy 191.77 -32.5628) (xy 190.7032 -31.496) (xy 187.7568 -31.496) (xy 186.69 -32.5628) (xy 186.69 -34.2138)
				(xy 186.689746 -34.214054) (xy 186.689746 -34.356802) (xy 186.509914 -34.536634) (xy 176.302924 -34.536634)
				(xy 174.91456 -33.14827) (xy 174.91456 -29.527754) (xy 174.336202 -28.949396)
			)
		)
		(polygon
			(pts
				(xy 170.491912 -37.683948) (xy 170.491912 -37.232336) (xy 170.019726 -37.704522) (xy 170.019726 -38.273228)
				(xy 170.147234 -38.400736) (xy 170.606466 -38.400736) (xy 170.08983 -38.917372) (xy 170.08983 -38.917626)
				(xy 170.09364 -38.917626) (xy 170.739562 -38.271704) (xy 170.739562 -37.931598)
			)
		)
		(polygon
			(pts
				(xy 165.077394 -32.7279) (xy 164.874194 -32.7279) (xy 164.874194 -32.9311) (xy 165.077394 -32.9311)
			)
		)
		(polygon
			(pts
				(xy 164.086794 -32.7279) (xy 163.670742 -32.7279) (xy 163.670742 -32.9311) (xy 164.086794 -32.9311)
			)
		)
		(polygon
			(pts
				(xy 162.883342 -32.7279) (xy 162.680142 -32.7279) (xy 162.680142 -32.9311) (xy 162.883342 -32.9311)
			)
		)
	)
	(zone
		(layer "F.Cu")
		(hatch none 0.5)
		(connect_pads
			(clearance 0)
		)
		(min_thickness 0.25)
		(keepout
			(tracks allowed)
			(vias allowed)
			(pads allowed)
			(copperpour allowed)
			(footprints allowed)
		)
		(placement
			(enabled no)
			(sheetname "")
		)
		(fill
			(thermal_gap 0.5)
			(thermal_bridge_width 0.5)
			(island_removal_mode 0)
		)
		(polygon
			(pts
				(xy 380.44501 -31.91383) (xy 380.44501 -29.942536) (xy 382.422146 -29.942536) (xy 382.572514 -29.942536)
				(xy 382.914398 -30.28442) (xy 382.914398 -31.614618) (xy 382.615186 -31.91383) (xy 382.422146 -31.91383)
			)
		)
	)
	(zone
		(net "GND")
		(layer "F.Cu")
		(hatch none 0.5)
		(connect_pads
			(clearance 0.5)
		)
		(min_thickness 0.25)
		(fill yes
			(thermal_gap 0.5)
			(thermal_bridge_width 0.5)
			(island_removal_mode 0)
		)
		(polygon
			(pts
				(xy 450.46773 -131.886452) (xy 450.46773 -130.606292) (xy 450.446902 -130.585464) (xy 449.337684 -130.585464)
				(xy 449.323968 -130.59918) (xy 449.265548 -130.6576) (xy 449.134484 -130.788664) (xy 446.85966 -130.788664)
				(xy 446.7606 -130.887724) (xy 446.7606 -131.8514) (xy 446.7606 -132.74675) (xy 446.950338 -132.936488)
				(xy 450.092318 -132.936488) (xy 450.46773 -132.561076)
			)
		)
	)
	(zone
		(layer "F.Cu")
		(hatch none 0.5)
		(connect_pads
			(clearance 0)
		)
		(min_thickness 0.25)
		(keepout
			(tracks allowed)
			(vias allowed)
			(pads allowed)
			(copperpour allowed)
			(footprints allowed)
		)
		(placement
			(enabled no)
			(sheetname "")
		)
		(fill
			(thermal_gap 0.5)
			(thermal_bridge_width 0.5)
			(island_removal_mode 0)
		)
		(polygon
			(pts
				(xy 1.397 -150.622) (xy 1.397 -149.352) (xy 2.667 -149.352) (xy 2.667 -150.622)
			)
		)
	)
	(zone
		(layer "F.Cu")
		(hatch none 0.5)
		(connect_pads
			(clearance 0)
		)
		(min_thickness 0.25)
		(keepout
			(tracks allowed)
			(vias allowed)
			(pads allowed)
			(copperpour allowed)
			(footprints allowed)
		)
		(placement
			(enabled no)
			(sheetname "")
		)
		(fill
			(thermal_gap 0.5)
			(thermal_bridge_width 0.5)
			(island_removal_mode 0)
		)
		(polygon
			(pts
				(xy 339.8647 -25.8826) (xy 339.8647 -23.4696) (xy 341.3506 -23.4696) (xy 341.3506 -25.8826)
			)
		)
	)
	(zone
		(layer "F.Cu")
		(hatch none 0.5)
		(connect_pads
			(clearance 0)
		)
		(min_thickness 0.25)
		(keepout
			(tracks allowed)
			(vias allowed)
			(pads allowed)
			(copperpour allowed)
			(footprints allowed)
		)
		(placement
			(enabled no)
			(sheetname "")
		)
		(fill
			(thermal_gap 0.5)
			(thermal_bridge_width 0.5)
			(island_removal_mode 0)
		)
		(polygon
			(pts
				(xy 1.6256 -7.5438) (xy 3.9116 -7.5438) (xy 3.9116 -9.5504) (xy 1.6256 -9.5504)
			)
		)
	)
	(zone
		(net "PVDDQ_GHJ")
		(layer "F.Cu")
		(hatch none 0.5)
		(connect_pads
			(clearance 0.5)
		)
		(min_thickness 0.25)
		(fill yes
			(thermal_gap 0.5)
			(thermal_bridge_width 0.5)
			(island_removal_mode 0)
		)
		(polygon
			(pts
				(xy 168.783 -3.3274) (xy 169.291 -3.3274) (xy 169.3418 -3.2766) (xy 169.3418 -0.8128) (xy 169.2148 -0.6858)
				(xy 168.3004 -0.6858) (xy 168.148 -0.8382) (xy 168.148 -2.6924)
			)
		)
	)
	(zone
		(net "P12V")
		(layer "F.Cu")
		(hatch none 0.5)
		(connect_pads
			(clearance 0.5)
		)
		(min_thickness 0.25)
		(fill yes
			(thermal_gap 0.5)
			(thermal_bridge_width 0.5)
			(island_removal_mode 0)
		)
		(polygon
			(pts
				(xy 495.426238 -20.700492) (xy 496.594892 -20.700492) (xy 496.925092 -21.030692) (xy 497.307108 -21.030692)
				(xy 497.369084 -20.968716) (xy 497.369084 -20.325842) (xy 497.1034 -20.060158) (xy 497.1034 -18.696686)
				(xy 496.085114 -17.6784) (xy 493.705642 -17.6784) (xy 493.101884 -17.074642) (xy 490.051598 -17.074642)
				(xy 489.7882 -17.33804) (xy 489.7882 -17.9705) (xy 489.7882 -20.5613) (xy 490.1565 -20.9296) (xy 490.317282 -21.090382)
				(xy 490.347508 -21.090382) (xy 493.239552 -21.090382) (xy 493.365028 -20.964906) (xy 493.254538 -20.854416)
				(xy 493.254538 -19.963638) (xy 493.285526 -19.93265) (xy 493.316006 -19.90217) (xy 495.016282 -19.90217)
				(xy 495.046762 -19.93265) (xy 495.110516 -19.996404) (xy 495.110516 -20.451572) (xy 495.240056 -20.581112)
				(xy 495.35969 -20.700492)
			)
		)
	)
	(zone
		(net "PVDDQ_KLM")
		(layer "F.Cu")
		(hatch none 0.5)
		(connect_pads
			(clearance 0.5)
		)
		(min_thickness 0.25)
		(fill yes
			(thermal_gap 0.5)
			(thermal_bridge_width 0.5)
			(island_removal_mode 0)
		)
		(polygon
			(pts
				(xy 78.745334 -153.36647) (xy 78.735174 -153.37663)
				(arc
					(start 78.735174 -154.450542)
					(mid 78.778282 -154.533616)
					(end 78.871064 -154.5463)
				)
				(arc
					(start 78.871064 -154.5463)
					(mid 79.284054 -154.651722)
					(end 79.341472 -155.074112)
				)
				(xy 79.336392 -155.08478) (xy 79.336392 -155.839922) (xy 80.317848 -155.839922)
				(arc
					(start 80.317848 -154.905456)
					(mid 80.699356 -154.523948)
					(end 81.080864 -154.905456)
				)
				(xy 81.080864 -155.839922) (xy 82.06232 -155.839922) (xy 82.06232 -155.08478)
				(arc
					(start 82.05724 -155.074112)
					(mid 82.399378 -154.524007)
					(end 82.741516 -155.074112)
				)
				(xy 82.736436 -155.08478) (xy 82.736436 -155.839922) (xy 82.912712 -155.839922) (xy 82.912712 -155.743402)
				(arc
					(start 82.907378 -155.732734)
					(mid 83.249516 -155.182629)
					(end 83.591654 -155.732734)
				)
				(xy 83.58632 -155.743402) (xy 83.58632 -155.839922) (xy 84.61248 -155.839922) (xy 84.61248 -155.743402)
				(arc
					(start 84.6074 -155.732734)
					(mid 84.949538 -155.182629)
					(end 85.291676 -155.732734)
				)
				(xy 85.286596 -155.743402) (xy 85.286596 -155.839922) (xy 85.462364 -155.839922) (xy 85.462364 -155.08478)
				(arc
					(start 85.457284 -155.074112)
					(mid 85.799422 -154.524007)
					(end 86.14156 -155.074112)
				)
				(xy 86.13648 -155.08478) (xy 86.13648 -155.839922) (xy 87.16264 -155.839922) (xy 87.16264 -155.08478)
				(arc
					(start 87.157306 -155.074112)
					(mid 87.499444 -154.524007)
					(end 87.841582 -155.074112)
				)
				(xy 87.836248 -155.08478) (xy 87.836248 -155.839922) (xy 88.012524 -155.839922) (xy 88.012524 -155.718002)
				(arc
					(start 88.007444 -155.707334)
					(mid 88.349582 -155.157229)
					(end 88.69172 -155.707334)
				)
				(xy 88.68664 -155.718002) (xy 88.68664 -155.839922) (xy 89.712292 -155.839922) (xy 89.712292 -155.718256)
				(arc
					(start 89.707212 -155.707588)
					(mid 90.04935 -155.157483)
					(end 90.391488 -155.707588)
				)
				(xy 90.386408 -155.718256) (xy 90.386408 -155.839922) (xy 90.964512 -155.839922) (xy 93.49105 -155.839922)
				(xy 93.758512 -155.57246) (xy 93.758512 -153.466038) (xy 93.635322 -153.342848) (xy 90.961718 -153.342848)
				(xy 90.938096 -153.36647) (xy 90.386408 -153.36647) (xy 90.386408 -154.072844)
				(arc
					(start 90.391742 -154.083512)
					(mid 90.049604 -154.633617)
					(end 89.707466 -154.083512)
				)
				(xy 89.7128 -154.072844) (xy 89.7128 -153.36647) (xy 89.562432 -153.36647) (xy 89.562432 -153.42489)
				(arc
					(start 89.564464 -153.432002)
					(mid 89.22605 -153.923247)
					(end 88.82253 -153.483818)
				)
				(arc
					(start 88.82253 -153.483818)
					(mid 88.79938 -153.40206)
					(end 88.7222 -153.36647)
				)
				(arc
					(start 87.971122 -153.36647)
					(mid 87.892113 -153.404509)
					(end 87.872062 -153.489914)
				)
				(arc
					(start 87.872062 -153.489914)
					(mid 87.471078 -153.952443)
					(end 87.143082 -153.435558)
				)
				(xy 87.146638 -153.426668) (xy 87.146638 -153.36647) (xy 86.986364 -153.36647) (xy 86.986364 -154.072844)
				(arc
					(start 86.991698 -154.083512)
					(mid 86.64956 -154.633617)
					(end 86.307422 -154.083512)
				)
				(xy 86.312756 -154.072844) (xy 86.312756 -153.36647) (xy 85.286596 -153.36647) (xy 85.286596 -154.072844)
				(arc
					(start 85.291676 -154.083512)
					(mid 84.949538 -154.633617)
					(end 84.6074 -154.083512)
				)
				(xy 84.61248 -154.072844) (xy 84.61248 -153.36647) (xy 84.452206 -153.36647) (xy 84.452206 -153.426668)
				(arc
					(start 84.455762 -153.435558)
					(mid 84.127769 -153.952473)
					(end 83.726782 -153.489914)
				)
				(arc
					(start 83.726782 -153.489914)
					(mid 83.706799 -153.404454)
					(end 83.627722 -153.36647)
				)
				(arc
					(start 82.876644 -153.36647)
					(mid 82.799433 -153.402032)
					(end 82.776314 -153.483818)
				)
				(arc
					(start 82.776314 -153.483818)
					(mid 82.372788 -153.923333)
					(end 82.03438 -153.432002)
				)
				(xy 82.036412 -153.42489) (xy 82.036412 -153.36647) (xy 81.886552 -153.36647) (xy 81.886552 -154.072844)
				(arc
					(start 81.891632 -154.083512)
					(mid 81.549494 -154.633617)
					(end 81.207356 -154.083512)
				)
				(xy 81.212436 -154.072844) (xy 81.212436 -153.36647) (xy 80.186276 -153.36647) (xy 80.186276 -154.072844)
				(arc
					(start 80.19161 -154.083512)
					(mid 79.849472 -154.633617)
					(end 79.507334 -154.083512)
				)
				(xy 79.512668 -154.072844) (xy 79.512668 -153.36647)
			)
		)
	)
	(zone
		(net "P3V3_STBY")
		(layer "F.Cu")
		(hatch none 0.5)
		(connect_pads
			(clearance 0.5)
		)
		(min_thickness 0.25)
		(fill yes
			(thermal_gap 0.5)
			(thermal_bridge_width 0.5)
			(island_removal_mode 0)
		)
		(polygon
			(pts
				(xy 397.129 -49.123346) (xy 397.129 -47.931324) (xy 397.249142 -47.811182) (xy 399.681954 -47.811182)
				(xy 399.801842 -47.691294) (xy 402.087334 -47.691294) (xy 402.143976 -47.747936) (xy 402.143976 -48.2727)
				(xy 402.144738 -48.273462) (xy 402.144738 -49.10963) (xy 402.144738 -49.662842) (xy 402.114258 -49.693322)
				(xy 401.68322 -49.693322) (xy 401.327874 -49.337976) (xy 400.741642 -49.337976) (xy 400.715734 -49.312068)
				(xy 397.317722 -49.312068)
			)
		)
	)
	(zone
		(net "P5V_STBY")
		(layer "F.Cu")
		(hatch none 0.5)
		(connect_pads
			(clearance 0.5)
		)
		(min_thickness 0.25)
		(fill yes
			(thermal_gap 0.5)
			(thermal_bridge_width 0.5)
			(island_removal_mode 0)
		)
		(polygon
			(pts
				(xy 404.876 -63.246) (xy 404.876 -59.819794) (xy 405.101806 -59.593988) (xy 407.936446 -59.593988)
				(xy 408.12593 -59.404504) (xy 408.12593 -58.222896) (xy 408.065478 -58.162444) (xy 404.712932 -58.162444)
				(xy 404.426674 -58.448702) (xy 401.414488 -58.448702) (xy 400.7612 -59.10199) (xy 400.7612 -62.934088)
				(xy 400.4818 -63.213488) (xy 400.4818 -65.573402) (xy 402.181822 -67.273424) (xy 402.181822 -69.627242)
				(xy 402.181822 -70.215506) (xy 402.349716 -70.3834) (xy 405.426926 -70.3834) (xy 405.442928 -70.367144)
				(xy 405.442928 -63.812928)
			)
		)
	)
	(zone
		(net "GND")
		(layer "F.Cu")
		(hatch none 0.5)
		(connect_pads
			(clearance 0.5)
		)
		(min_thickness 0.25)
		(fill yes
			(thermal_gap 0.5)
			(thermal_bridge_width 0.5)
			(island_removal_mode 0)
		)
		(polygon
			(pts
				(xy 474.441774 -42.151808) (xy 475.505272 -42.151808) (xy 475.71279 -42.359326) (xy 475.71279 -43.866562)
				(xy 475.592902 -43.98645) (xy 474.561662 -43.98645) (xy 474.41739 -43.842178) (xy 474.41739 -42.176192)
			)
		)
	)
	(zone
		(net "GND")
		(layer "F.Cu")
		(hatch none 0.5)
		(connect_pads
			(clearance 0.5)
		)
		(min_thickness 0.25)
		(fill yes
			(thermal_gap 0.5)
			(thermal_bridge_width 0.5)
			(island_removal_mode 0)
		)
		(polygon
			(pts
				(xy 242.697 -4.853178) (xy 242.6208 -4.929378) (xy 242.6208 -6.6548) (xy 242.5192 -6.7564) (xy 242.062 -6.7564)
				(xy 241.986308 -6.680708) (xy 241.986308 -4.825492) (xy 241.839242 -4.678426) (xy 241.839242 -4.15163)
				(xy 241.198654 -3.511042) (xy 241.198654 -2.035302) (xy 241.293396 -1.94056) (xy 242.026948 -1.94056)
				(xy 243.2304 -1.94056) (xy 243.418106 -2.128266) (xy 243.418106 -4.671568) (xy 243.300504 -4.78917)
				(xy 242.761008 -4.78917)
			)
		)
	)
	(zone
		(layer "F.Cu")
		(hatch none 0.5)
		(connect_pads
			(clearance 0)
		)
		(min_thickness 0.25)
		(keepout
			(tracks not_allowed)
			(vias allowed)
			(pads allowed)
			(copperpour not_allowed)
			(footprints allowed)
		)
		(placement
			(enabled no)
			(sheetname "")
		)
		(fill
			(thermal_gap 0.5)
			(thermal_bridge_width 0.5)
			(island_removal_mode 0)
		)
		(polygon
			(pts
				(xy 431.265838 -3.258058) (xy 431.265838 -3.015488) (xy 431.476658 -2.804668)
				(arc
					(start 431.593498 -2.804668)
					(mid 432.117415 -2.874518)
					(end 431.593498 -2.944368)
				)
				(xy 431.53457 -2.944368) (xy 431.405538 -3.0734) (xy 431.405538 -3.258058)
				(arc
					(start 431.850546 -3.258058)
					(mid 432.23434 -2.874645)
					(end 431.8508 -2.490978)
				)
				(arc
					(start 430.5808 -2.490978)
					(mid 430.19726 -2.874518)
					(end 430.5808 -3.258058)
				)
				(xy 431.024538 -3.258058) (xy 431.024538 -3.0607) (xy 430.908206 -2.944368)
				(arc
					(start 430.838102 -2.944368)
					(mid 430.314185 -2.874518)
					(end 430.838102 -2.804668)
				)
				(xy 430.966118 -2.804668) (xy 431.164238 -3.002788) (xy 431.164238 -3.258058)
			)
		)
	)
	(zone
		(net "PVDDQ_GHJ")
		(layer "F.Cu")
		(hatch none 0.5)
		(connect_pads
			(clearance 0.5)
		)
		(min_thickness 0.25)
		(fill yes
			(thermal_gap 0.5)
			(thermal_bridge_width 0.5)
			(island_removal_mode 0)
		)
		(polygon
			(pts
				(xy 93.923104 -2.6162) (xy 93.808804 -2.5019) (xy 93.69806 -2.39141) (xy 93.69806 -2.159) (xy 93.57106 -2.032)
				(xy 93.355668 -2.032)
				(arc
					(start 92.966032 -2.421636)
					(mid 92.906675 -2.541603)
					(end 92.809568 -2.633726)
				)
				(arc
					(start 92.809568 -4.009898)
					(mid 92.965384 -4.219823)
					(end 92.949522 -4.480814)
				)
				(arc
					(start 92.949522 -4.480814)
					(mid 92.957748 -4.576851)
					(end 93.042486 -4.6228)
				)
				(xy 93.546168 -4.6228) (xy 93.69806 -4.470654) (xy 93.69806 -4.21259) (xy 93.698568 -4.212336) (xy 93.698568 -4.064)
				(xy 93.800168 -3.9624) (xy 94.8055 -3.9624) (xy 94.8182 -3.9497) (xy 94.8182 -2.6797) (xy 94.7547 -2.6162)
			)
		)
		(polygon
			(pts
				(xy 93.584268 -3.715512) (xy 93.381068 -3.715512) (xy 93.381068 -3.918712) (xy 93.584268 -3.918712)
			)
		)
		(polygon
			(pts
				(xy 93.584268 -2.724912) (xy 93.381068 -2.724912) (xy 93.381068 -2.928112) (xy 93.584268 -2.928112)
			)
		)
	)
	(zone
		(layer "F.Cu")
		(hatch none 0.5)
		(connect_pads
			(clearance 0)
		)
		(min_thickness 0.25)
		(keepout
			(tracks not_allowed)
			(vias allowed)
			(pads allowed)
			(copperpour not_allowed)
			(footprints allowed)
		)
		(placement
			(enabled no)
			(sheetname "")
		)
		(fill
			(thermal_gap 0.5)
			(thermal_bridge_width 0.5)
			(island_removal_mode 0)
		)
		(polygon
			(pts
				(arc
					(start 381.100838 -22.248368)
					(mid 380.779673 -21.828397)
					(end 381.199644 -22.149562)
				)
				(xy 381.35179 -22.301708)
				(arc
					(start 381.35179 -22.017228)
					(mid 380.968377 -21.633434)
					(end 380.58471 -22.016974)
				)
				(arc
					(start 380.58471 -22.982174)
					(mid 380.96825 -23.365714)
					(end 381.35179 -22.982174)
				)
				(xy 381.35179 -22.71903) (xy 381.3302 -22.71903)
				(arc
					(start 381.199644 -22.849586)
					(mid 380.779673 -23.170751)
					(end 381.100838 -22.75078)
				)
				(xy 381.272288 -22.57933) (xy 381.35179 -22.57933) (xy 381.35179 -22.47773) (xy 381.3302 -22.47773)
			)
		)
	)
	(zone
		(net "GND")
		(layer "F.Cu")
		(hatch none 0.5)
		(connect_pads
			(clearance 0.5)
		)
		(min_thickness 0.25)
		(fill yes
			(thermal_gap 0.5)
			(thermal_bridge_width 0.5)
			(island_removal_mode 0)
		)
		(polygon
			(pts
				(xy 346.456 -13.589) (xy 346.456 -17.145) (xy 342.9 -17.145) (xy 342.9 -13.589)
			)
		)
	)
	(zone
		(net "P1V2_AUX_BMC")
		(layer "F.Cu")
		(hatch none 0.5)
		(connect_pads
			(clearance 0.5)
		)
		(min_thickness 0.25)
		(fill yes
			(thermal_gap 0.5)
			(thermal_bridge_width 0.5)
			(island_removal_mode 0)
		)
		(polygon
			(pts
				(xy 442.738256 -27.249628) (xy 442.738256 -27.92984) (xy 444.579248 -29.770832) (xy 447.488818 -29.770832)
				(xy 447.549524 -29.710126) (xy 447.549524 -28.090368) (xy 447.507868 -28.048712) (xy 446.989708 -28.048712)
				(xy 446.83299 -28.20543) (xy 445.39154 -28.20543) (xy 444.455042 -28.20543) (xy 443.30112 -27.051508)
				(xy 443.147196 -27.051508) (xy 442.959236 -26.863548) (xy 442.811154 -26.863548) (xy 442.738256 -26.936446)
			)
		)
	)
	(zone
		(net "VR_PVCCIN_CPU1_PHASE1")
		(layer "F.Cu")
		(hatch none 0.5)
		(connect_pads
			(clearance 0.5)
		)
		(min_thickness 0.25)
		(fill yes
			(thermal_gap 0.5)
			(thermal_bridge_width 0.5)
			(island_removal_mode 0)
		)
		(polygon
			(pts
				(xy 36.4998 -59.655202) (xy 40.303196 -59.655202) (xy 41.563798 -59.655202) (xy 42.037 -59.182)
				(xy 42.037 -55.0672) (xy 41.545002 -54.575202) (xy 40.303196 -54.575202) (xy 36.5252 -54.575202)
				(xy 36.4744 -54.626002) (xy 36.4744 -59.629802)
			)
		)
	)
	(zone
		(net "P5V")
		(layer "F.Cu")
		(hatch none 0.5)
		(connect_pads
			(clearance 0.5)
		)
		(min_thickness 0.25)
		(fill yes
			(thermal_gap 0.5)
			(thermal_bridge_width 0.5)
			(island_removal_mode 0)
		)
		(polygon
			(pts
				(xy 437.5658 -128.9304) (xy 438.3024 -128.9304) (xy 438.658 -129.286) (xy 443.65164 -129.286) (xy 443.7126 -129.22504)
				(xy 443.822836 -129.114804) (xy 443.822836 -127.478536) (xy 443.822836 -127.28321) (xy 443.552326 -127.0127)
				(xy 443.357 -127.0127) (xy 442.7347 -127.0127) (xy 442.2013 -127.0127) (xy 441.579 -126.3904) (xy 440.4614 -125.2728)
				(xy 439.67781 -124.48921) (xy 438.48274 -124.48921) (xy 436.45582 -124.48921) (xy 436.2831 -124.66193)
				(xy 436.2831 -126.3777) (xy 436.32882 -126.42342) (xy 437.31434 -126.42342) (xy 437.43626 -126.54534)
				(xy 437.43626 -126.546356) (xy 437.487314 -126.59741) (xy 437.508904 -126.619) (xy 437.508904 -127.746252)
				(xy 437.508904 -128.873504)
			)
		)
	)
	(zone
		(layer "F.Cu")
		(hatch none 0.5)
		(connect_pads
			(clearance 0)
		)
		(min_thickness 0.25)
		(keepout
			(tracks allowed)
			(vias allowed)
			(pads allowed)
			(copperpour allowed)
			(footprints allowed)
		)
		(placement
			(enabled no)
			(sheetname "")
		)
		(fill
			(thermal_gap 0.5)
			(thermal_bridge_width 0.5)
			(island_removal_mode 0)
		)
		(polygon
			(pts
				(xy 345.7702 -0.9652) (xy 345.7702 3.4036) (xy 348.1832 3.4036) (xy 348.1832 -0.9652)
			)
		)
	)
	(zone
		(net "GND")
		(layer "F.Cu")
		(hatch none 0.5)
		(connect_pads
			(clearance 0.5)
		)
		(min_thickness 0.25)
		(fill yes
			(thermal_gap 0.5)
			(thermal_bridge_width 0.5)
			(island_removal_mode 0)
		)
		(polygon
			(pts
				(xy 92.76842 -78.994) (xy 92.67825 -79.08417) (xy 92.67825 -80.43545) (xy 92.8878 -80.645) (xy 96.111568 -80.645)
				(xy 96.213168 -80.5434) (xy 96.213168 -79.1718) (xy 96.177862 -79.136494) (xy 93.155262 -79.136494)
				(xy 93.139768 -79.121) (xy 93.012768 -78.994)
			)
		)
		(polygon
			(pts
				(xy 95.41764 -79.630016) (xy 95.21444 -79.630016) (xy 95.21444 -79.833216) (xy 95.41764 -79.833216)
			)
		)
		(polygon
			(pts
				(xy 94.98584 -79.630016) (xy 94.78264 -79.630016) (xy 94.78264 -79.833216) (xy 94.98584 -79.833216)
			)
		)
		(polygon
			(pts
				(xy 94.22384 -79.630016) (xy 94.02064 -79.630016) (xy 94.02064 -79.833216) (xy 94.22384 -79.833216)
			)
		)
		(polygon
			(pts
				(xy 93.79204 -79.630016) (xy 93.58884 -79.630016) (xy 93.58884 -79.833216) (xy 93.79204 -79.833216)
			)
		)
		(polygon
			(pts
				(xy 93.03004 -79.630016) (xy 92.82684 -79.630016) (xy 92.82684 -79.833216) (xy 93.03004 -79.833216)
			)
		)
	)
	(zone
		(net "VR_PVPP_KLM_PHASE")
		(layer "F.Cu")
		(hatch none 0.5)
		(connect_pads
			(clearance 0.5)
		)
		(min_thickness 0.25)
		(fill yes
			(thermal_gap 0.5)
			(thermal_bridge_width 0.5)
			(island_removal_mode 0)
		)
		(polygon
			(pts
				(xy 171.8564 -136.271) (xy 173.4185 -136.271) (xy 174.117 -136.9695) (xy 175.133 -136.9695) (xy 175.514 -136.5885)
				(xy 179.705 -136.5885) (xy 179.832 -136.7155) (xy 179.832 -138.8745) (xy 179.705 -139.0015) (xy 176.149 -139.0015)
				(xy 176.022 -139.1285) (xy 176.022 -140.1445) (xy 176.022 -140.5382) (xy 175.966628 -140.593572)
				(xy 174.57928 -140.593572) (xy 174.498 -140.674852) (xy 174.498 -140.9192) (xy 174.498 -141.3256)
				(xy 174.4091 -141.4145) (xy 171.445428 -141.4145) (xy 169.7482 -139.717272) (xy 169.18178 -139.150852)
				(xy 169.18178 -134.67207) (xy 169.076116 -134.566406) (xy 169.076116 -133.297168) (xy 169.176446 -133.196838)
				(xy 169.876978 -133.196838) (xy 169.955718 -133.275578) (xy 169.955718 -134.106666) (xy 170.12158 -134.272528)
				(xy 170.12158 -134.80288) (xy 170.12158 -135.32358) (xy 171.06265 -136.26465) (xy 171.85005 -136.26465)
			)
		)
	)
	(zone
		(layer "F.Cu")
		(hatch none 0.5)
		(connect_pads
			(clearance 0)
		)
		(min_thickness 0.25)
		(keepout
			(tracks allowed)
			(vias allowed)
			(pads allowed)
			(copperpour allowed)
			(footprints not_allowed)
		)
		(placement
			(enabled no)
			(sheetname "")
		)
		(fill
			(thermal_gap 0.5)
			(thermal_bridge_width 0.5)
			(island_removal_mode 0)
		)
		(polygon
			(pts
				(xy 465.29879 -0.990092) (xy 404.770082 -0.990092) (xy 404.770082 5.999988) (xy 465.29879 5.999988)
			)
		)
	)
	(zone
		(layer "F.Cu")
		(hatch none 0.5)
		(connect_pads
			(clearance 0)
		)
		(min_thickness 0.25)
		(keepout
			(tracks allowed)
			(vias allowed)
			(pads allowed)
			(copperpour allowed)
			(footprints allowed)
		)
		(placement
			(enabled no)
			(sheetname "")
		)
		(fill
			(thermal_gap 0.5)
			(thermal_bridge_width 0.5)
			(island_removal_mode 0)
		)
		(polygon
			(pts
				(xy 277.495 -103.378) (xy 277.495 -100.838) (xy 278.511 -99.822) (xy 281.686 -99.822) (xy 282.829 -100.965)
				(xy 282.829 -103.378) (xy 282.829 -103.505) (xy 282.829 -103.632) (xy 277.495 -103.632) (xy 277.495 -103.505)
			)
		)
	)
	(zone
		(net "GND")
		(layer "F.Cu")
		(hatch none 0.5)
		(connect_pads
			(clearance 0.5)
		)
		(min_thickness 0.25)
		(fill yes
			(thermal_gap 0.5)
			(thermal_bridge_width 0.5)
			(island_removal_mode 0)
		)
		(polygon
			(pts
				(xy 187.408058 -8.360156) (xy 187.408058 -11.309604) (xy 187.146184 -11.571478) (xy 185.713878 -11.571478)
				(xy 184.490106 -11.571478) (xy 184.437528 -11.5189) (xy 184.437528 -8.424418) (xy 184.667144 -8.194802)
				(xy 187.242704 -8.194802)
			)
		)
	)
	(zone
		(layer "F.Cu")
		(hatch none 0.5)
		(connect_pads
			(clearance 0)
		)
		(min_thickness 0.25)
		(keepout
			(tracks allowed)
			(vias allowed)
			(pads allowed)
			(copperpour allowed)
			(footprints not_allowed)
		)
		(placement
			(enabled no)
			(sheetname "")
		)
		(fill
			(thermal_gap 0.5)
			(thermal_bridge_width 0.5)
			(island_removal_mode 0)
		)
		(polygon
			(pts
				(arc
					(start 465.019898 -34.120074)
					(mid 461.419956 -30.520132)
					(end 465.019898 -26.919936)
				)
				(arc
					(start 468.019892 -26.919936)
					(mid 471.620088 -30.520132)
					(end 468.019892 -34.120074)
				)
			)
		)
	)
	(zone
		(net "PVCCIO_CPU1")
		(layer "F.Cu")
		(hatch none 0.5)
		(connect_pads
			(clearance 0.5)
		)
		(min_thickness 0.25)
		(fill yes
			(thermal_gap 0.5)
			(thermal_bridge_width 0.5)
			(island_removal_mode 0)
		)
		(polygon
			(pts
				(xy 162.42538 -51.05654) (xy 161.188146 -52.293774) (xy 161.188146 -58.785252) (xy 161.186368 -58.786776)
				(xy 161.186368 -59.543696) (xy 161.394648 -59.751976) (xy 162.263582 -59.751976) (xy 162.6235 -60.111894)
				(xy 162.6235 -62.478412) (xy 162.170618 -62.931294) (xy 161.405824 -62.931294) (xy 161.38144 -62.955678)
				(xy 161.38144 -63.819786) (xy 161.444432 -63.882778) (xy 162.217608 -63.882778) (xy 162.329622 -63.770764)
				(xy 162.329622 -63.610236) (xy 162.330892 -63.608966) (xy 162.330892 -63.476886) (xy 162.616642 -63.191136)
				(xy 163.115752 -63.191136) (xy 163.141152 -63.165736) (xy 163.141152 -62.874398) (xy 163.37915 -62.6364)
				(xy 166.3446 -62.6364) (xy 166.5478 -62.4332) (xy 166.5478 -51.60264) (xy 166.0017 -51.05654)
			)
		)
		(polygon
			(pts
				(xy 162.2806 -58.7629) (xy 162.0774 -58.7629) (xy 162.0774 -58.9661) (xy 162.2806 -58.9661)
			)
		)
		(polygon
			(pts
				(xy 161.5186 -58.7629) (xy 161.3154 -58.7629) (xy 161.3154 -58.9661) (xy 161.5186 -58.9661)
			)
		)
	)
	(zone
		(layer "F.Cu")
		(hatch none 0.5)
		(connect_pads
			(clearance 0)
		)
		(min_thickness 0.25)
		(keepout
			(tracks not_allowed)
			(vias allowed)
			(pads allowed)
			(copperpour not_allowed)
			(footprints allowed)
		)
		(placement
			(enabled no)
			(sheetname "")
		)
		(fill
			(thermal_gap 0.5)
			(thermal_bridge_width 0.5)
			(island_removal_mode 0)
		)
		(polygon
			(pts
				(arc
					(start 447.083434 -4.860036)
					(mid 447.404599 -5.280007)
					(end 446.984628 -4.958842)
				)
				(xy 446.728596 -4.70281) (xy 446.605406 -4.70154) (xy 446.605406 -4.851146)
				(arc
					(start 446.507362 -4.94919)
					(mid 446.087391 -5.270355)
					(end 446.408556 -4.850384)
				)
				(xy 446.465706 -4.793234) (xy 446.465706 -4.700016)
				(arc
					(start 446.280286 -4.698238)
					(mid 445.892683 -5.077587)
					(end 446.271904 -5.465318)
				)
				(arc
					(start 447.211958 -5.47497)
					(mid 447.599562 -5.095494)
					(end 447.220086 -4.70789)
				)
				(xy 446.92824 -4.704842)
			)
		)
	)
	(zone
		(net "VR_PVCCIN_CPU1_PHASE3")
		(layer "F.Cu")
		(hatch none 0.5)
		(connect_pads
			(clearance 0.5)
		)
		(min_thickness 0.25)
		(fill yes
			(thermal_gap 0.5)
			(thermal_bridge_width 0.5)
			(island_removal_mode 0)
		)
		(polygon
			(pts
				(xy 36.4998 -75.944222) (xy 40.303196 -75.944222) (xy 41.563798 -75.944222) (xy 42.037 -75.47102)
				(xy 42.037 -71.35622) (xy 41.545002 -70.864222) (xy 40.303196 -70.864222) (xy 36.5252 -70.864222)
				(xy 36.4744 -70.915022) (xy 36.4744 -75.918822)
			)
		)
	)
	(zone
		(net "GND")
		(layer "F.Cu")
		(hatch none 0.5)
		(connect_pads
			(clearance 0.5)
		)
		(min_thickness 0.25)
		(fill yes
			(thermal_gap 0.5)
			(thermal_bridge_width 0.5)
			(island_removal_mode 0)
		)
		(polygon
			(pts
				(xy 381.7874 -21.7932) (xy 381.7874 -19.953986) (xy 382.1684 -19.572986) (xy 384.318002 -19.572986)
				(xy 384.329178 -19.584162) (xy 384.668522 -19.584162) (xy 384.97002 -19.88566) (xy 384.97002 -21.904452)
				(xy 384.903472 -21.971) (xy 384.431286 -21.971) (xy 383.967736 -21.971) (xy 381.9652 -21.971)
			)
		)
	)
	(zone
		(net "GND")
		(layer "F.Cu")
		(hatch none 0.5)
		(connect_pads
			(clearance 0.5)
		)
		(min_thickness 0.25)
		(fill yes
			(thermal_gap 0.5)
			(thermal_bridge_width 0.5)
			(island_removal_mode 0)
		)
		(polygon
			(pts
				(xy 243.481352 -140.750036) (xy 243.481352 -139.107926) (xy 243.261388 -138.887962) (xy 242.025424 -138.887962)
				(xy 242.01882 -138.89482) (xy 241.21618 -138.89482) (xy 241.046 -139.065) (xy 241.046 -139.614402)
				(xy 241.766598 -140.335) (xy 241.766598 -140.97254) (xy 241.848894 -141.054836) (xy 241.848894 -141.293342)
				(xy 241.9223 -141.366748) (xy 242.0112 -141.455648) (xy 242.0112 -142.7988) (xy 242.1382 -142.9258)
				(xy 242.443 -142.9258) (xy 242.57 -142.7988) (xy 242.57 -141.544548) (xy 242.74272 -141.371828)
				(xy 242.74272 -141.046962) (xy 242.964462 -140.82522) (xy 243.406168 -140.82522)
			)
		)
	)
	(zone
		(layer "F.Cu")
		(hatch none 0.5)
		(connect_pads
			(clearance 0)
		)
		(min_thickness 0.25)
		(keepout
			(tracks allowed)
			(vias allowed)
			(pads allowed)
			(copperpour allowed)
			(footprints allowed)
		)
		(placement
			(enabled no)
			(sheetname "")
		)
		(fill
			(thermal_gap 0.5)
			(thermal_bridge_width 0.5)
			(island_removal_mode 0)
		)
		(polygon
			(pts
				(xy 245.11 -103.886) (xy 243.078 -105.918) (xy 240.792 -105.918) (xy 240.284 -106.426) (xy 239.776 -106.426)
				(xy 237.363 -108.839) (xy 236.855 -108.839) (xy 236.855 -104.521) (xy 235.585 -104.521) (xy 235.585 -102.108)
				(xy 235.585 -101.981) (xy 240.665 -101.981) (xy 240.665 -102.489) (xy 243.332 -102.489) (xy 243.84 -102.997)
				(xy 244.475 -102.997) (xy 245.11 -103.632)
			)
		)
	)
	(zone
		(net "P3V3")
		(layer "F.Cu")
		(hatch none 0.5)
		(connect_pads
			(clearance 0.5)
		)
		(min_thickness 0.25)
		(fill yes
			(thermal_gap 0.5)
			(thermal_bridge_width 0.5)
			(island_removal_mode 0)
		)
		(polygon
			(pts
				(xy 465.0486 -3.8354) (xy 464.9724 -3.9116) (xy 464.9724 -8.382) (xy 465.0486 -8.4582) (xy 466.2932 -8.4582)
				(xy 466.5472 -8.2042) (xy 466.5472 -7.112) (xy 467.106 -7.112) (xy 467.36 -6.858) (xy 467.36 -5.461)
				(xy 467.106 -5.207) (xy 466.598 -5.207) (xy 466.5472 -5.1562) (xy 466.5472 -4.064) (xy 466.3186 -3.8354)
			)
		)
	)
	(zone
		(layer "F.Cu")
		(hatch none 0.5)
		(connect_pads
			(clearance 0)
		)
		(min_thickness 0.25)
		(keepout
			(tracks not_allowed)
			(vias allowed)
			(pads allowed)
			(copperpour not_allowed)
			(footprints allowed)
		)
		(placement
			(enabled no)
			(sheetname "")
		)
		(fill
			(thermal_gap 0.5)
			(thermal_bridge_width 0.5)
			(island_removal_mode 0)
		)
		(polygon
			(pts
				(xy 460.934308 -121.10974) (xy 460.934308 -121.397776) (xy 460.768954 -121.56313)
				(arc
					(start 460.600552 -121.56313)
					(mid 460.076635 -121.49328)
					(end 460.600552 -121.42343)
				)
				(xy 460.711042 -121.42343) (xy 460.794608 -121.339864) (xy 460.794608 -121.10974)
				(arc
					(start 460.343504 -121.10974)
					(mid 459.95971 -121.493153)
					(end 460.34325 -121.87682)
				)
				(arc
					(start 461.61325 -121.87682)
					(mid 461.99679 -121.49328)
					(end 461.61325 -121.10974)
				)
				(xy 461.175608 -121.10974) (xy 461.175608 -121.341642) (xy 461.257396 -121.42343)
				(arc
					(start 461.355948 -121.42343)
					(mid 461.879865 -121.49328)
					(end 461.355948 -121.56313)
				)
				(xy 461.199484 -121.56313) (xy 461.035908 -121.399554) (xy 461.035908 -121.10974)
			)
		)
	)
	(zone
		(net "GND")
		(layer "F.Cu")
		(hatch none 0.5)
		(connect_pads
			(clearance 0.5)
		)
		(min_thickness 0.25)
		(fill yes
			(thermal_gap 0.5)
			(thermal_bridge_width 0.5)
			(island_removal_mode 0)
		)
		(polygon
			(pts
				(xy 175.4886 -134.6454) (xy 177.4952 -134.6454) (xy 177.546 -134.6962) (xy 177.546 -136.1186) (xy 177.419 -136.2456)
				(xy 174.4472 -136.2456) (xy 174.4218 -136.2202) (xy 174.4218 -135.9662) (xy 174.4472 -135.9408)
				(xy 175.26 -135.9408) (xy 175.4378 -135.763) (xy 175.4378 -134.6962)
			)
		)
	)
	(zone
		(layer "F.Cu")
		(hatch none 0.5)
		(connect_pads
			(clearance 0)
		)
		(min_thickness 0.25)
		(keepout
			(tracks not_allowed)
			(vias allowed)
			(pads allowed)
			(copperpour not_allowed)
			(footprints allowed)
		)
		(placement
			(enabled no)
			(sheetname "")
		)
		(fill
			(thermal_gap 0.5)
			(thermal_bridge_width 0.5)
			(island_removal_mode 0)
		)
		(polygon
			(pts
				(xy 380.652528 -128.726438) (xy 380.65329 -128.711706)
				(arc
					(start 380.562612 -128.711706)
					(mid 380.181358 -129.092579)
					(end 380.562358 -129.473706)
				)
				(arc
					(start 381.222758 -129.473706)
					(mid 381.553734 -129.281428)
					(end 381.550672 -128.89865)
				)
				(xy 381.550672 -129.078228)
				(arc
					(start 381.548386 -129.080514)
					(mid 381.522735 -129.140563)
					(end 381.473456 -129.183384)
				)
				(arc
					(start 381.473456 -129.183384)
					(mid 380.958944 -129.13144)
					(end 381.436372 -128.93294)
				)
				(arc
					(start 381.436372 -128.83261)
					(mid 381.412194 -128.774238)
					(end 381.353822 -128.75006)
				)
				(xy 380.964948 -128.75006)
				(arc
					(start 380.962662 -128.747774)
					(mid 380.923796 -128.734868)
					(end 380.890018 -128.711706)
				)
				(xy 380.767844 -128.711706) (xy 380.766828 -128.729232) (xy 380.771146 -128.739138) (xy 380.765812 -128.751838)
				(xy 380.76505 -128.765554) (xy 380.756922 -128.77292)
				(arc
					(start 380.715012 -128.874012)
					(mid 380.460552 -129.338951)
					(end 380.609602 -128.830324)
				)
			)
		)
	)
	(zone
		(layer "F.Cu")
		(hatch none 0.5)
		(connect_pads
			(clearance 0)
		)
		(min_thickness 0.25)
		(keepout
			(tracks allowed)
			(vias allowed)
			(pads allowed)
			(copperpour allowed)
			(footprints not_allowed)
		)
		(placement
			(enabled no)
			(sheetname "")
		)
		(fill
			(thermal_gap 0.5)
			(thermal_bridge_width 0.5)
			(island_removal_mode 0)
		)
		(polygon
			(pts
				(arc
					(start 226.79279 -52.885848)
					(mid 226.576008 -52.561411)
					(end 226.499928 -52.178712)
				)
				(arc
					(start 226.499928 -44.800012)
					(mid 227.085713 -43.385801)
					(end 228.499924 -42.800016)
				)
				(arc
					(start 234.153964 -42.800016)
					(mid 234.496009 -42.860332)
					(end 234.796838 -43.03395)
				)
				(arc
					(start 238.131604 -45.832014)
					(mid 238.733096 -46.179309)
					(end 239.417098 -46.299882)
				)
				(xy 269.699994 -46.299882) (xy 269.699994 -67.300094) (xy 263.700006 -67.300094) (xy 257.450082 -71.049896)
				(xy 257.450082 -82.049874) (xy 263.700006 -85.79993) (xy 276.29993 -85.79993) (xy 282.550108 -82.049874)
				(xy 282.550108 -71.049896) (xy 276.29993 -67.300094) (xy 269.899892 -67.300094) (xy 269.899892 -46.299882)
				(arc
					(start 300.582838 -46.299882)
					(mid 301.266981 -46.179338)
					(end 301.868586 -45.832014)
				)
				(arc
					(start 305.203098 -43.03395)
					(mid 305.503903 -42.860264)
					(end 305.845972 -42.800016)
				)
				(arc
					(start 311.500012 -42.800016)
					(mid 312.914223 -43.385801)
					(end 313.500008 -44.800012)
				)
				(arc
					(start 313.500008 -52.178712)
					(mid 313.423888 -52.561395)
					(end 313.207146 -52.885848)
				)
				(arc
					(start 312.085736 -54.007004)
					(mid 311.652173 -54.655878)
					(end 311.500012 -55.421276)
				)
				(arc
					(start 311.500012 -57.049924)
					(mid 313.110779 -60.939168)
					(end 316.999874 -62.55004)
				)
				(arc
					(start 322.749926 -62.55004)
					(mid 324.164137 -61.964255)
					(end 324.749922 -60.550044)
				)
				(xy 324.749922 -41.092882) (xy 320.457068 -36.800028) (xy 269.899892 -36.800028) (xy 269.899892 -35.299904)
				(xy 326.247506 -35.299904) (xy 326.247506 -117.80012) (xy 213.74735 -117.80012) (xy 213.74735 -35.299904)
				(xy 269.699994 -35.299904) (xy 269.699994 -36.800028)
				(arc
					(start 218.74988 -36.800028)
					(mid 216.275101 -37.825115)
					(end 215.250014 -40.299894)
				)
				(arc
					(start 215.250014 -112.799876)
					(mid 216.274996 -115.274909)
					(end 218.74988 -116.299996)
				)
				(arc
					(start 321.250056 -116.299996)
					(mid 323.724925 -115.274819)
					(end 324.749922 -112.799876)
				)
				(arc
					(start 324.749922 -92.54998)
					(mid 324.164137 -91.135769)
					(end 322.749926 -90.549984)
				)
				(arc
					(start 316.999874 -90.549984)
					(mid 313.110869 -92.16102)
					(end 311.500012 -96.0501)
				)
				(arc
					(start 311.500012 -97.678748)
					(mid 311.652233 -98.444016)
					(end 312.085736 -99.092766)
				)
				(arc
					(start 313.207146 -100.214176)
					(mid 313.423928 -100.538613)
					(end 313.500008 -100.921312)
				)
				(arc
					(start 313.500008 -108.300012)
					(mid 312.914223 -109.714223)
					(end 311.500012 -110.300008)
				)
				(arc
					(start 305.845972 -110.300008)
					(mid 305.503927 -110.239692)
					(end 305.203098 -110.066074)
				)
				(arc
					(start 301.868586 -107.26801)
					(mid 301.26699 -106.920562)
					(end 300.582838 -106.799888)
				)
				(arc
					(start 239.417098 -106.799888)
					(mid 238.733067 -106.920592)
					(end 238.131604 -107.26801)
				)
				(arc
					(start 234.796838 -110.066074)
					(mid 234.496033 -110.23976)
					(end 234.153964 -110.300008)
				)
				(arc
					(start 228.499924 -110.300008)
					(mid 227.085713 -109.714223)
					(end 226.499928 -108.300012)
				)
				(arc
					(start 226.499928 -100.921312)
					(mid 226.576048 -100.538629)
					(end 226.79279 -100.214176)
				)
				(arc
					(start 227.9142 -99.092766)
					(mid 228.347686 -98.444009)
					(end 228.499924 -97.678748)
				)
				(arc
					(start 228.499924 -94.30004)
					(mid 228.133827 -93.416203)
					(end 227.24999 -93.050106)
				)
				(arc
					(start 227.24999 -93.050106)
					(mid 227.073333 -92.976722)
					(end 227.000054 -92.799916)
				)
				(arc
					(start 227.000054 -60.300108)
					(mid 227.073243 -60.123287)
					(end 227.24999 -60.049918)
				)
				(arc
					(start 227.24999 -60.049918)
					(mid 228.133827 -59.683821)
					(end 228.499924 -58.799984)
				)
				(arc
					(start 228.499924 -55.421276)
					(mid 228.347683 -54.655911)
					(end 227.9142 -54.007004)
				)
			)
		)
	)
	(zone
		(net "GND")
		(layer "F.Cu")
		(hatch none 0.5)
		(connect_pads
			(clearance 0.5)
		)
		(min_thickness 0.25)
		(fill yes
			(thermal_gap 0.5)
			(thermal_bridge_width 0.5)
			(island_removal_mode 0)
		)
		(polygon
			(pts
				(xy 497.219986 -26.886154) (xy 497.219986 -25.412954) (xy 497.219986 -25.309068) (xy 497.219986 -25.30348)
				(xy 497.142262 -25.225756) (xy 497.1415 -25.225756) (xy 497.115592 -25.199848) (xy 496.358926 -25.199848)
				(xy 496.336828 -25.199848) (xy 496.31346 -25.17648) (xy 496.31346 -24.90089) (xy 496.33124 -24.88311)
				(xy 496.370102 -24.88311) (xy 497.295932 -24.88311) (xy 498.188742 -24.88311) (xy 498.261386 -24.955754)
				(xy 498.261386 -26.759154) (xy 498.318536 -26.816304) (xy 498.321076 -26.813764) (xy 499.152164 -26.813764)
				(xy 499.69674 -27.35834) (xy 499.69674 -27.63266) (xy 499.491 -27.8384) (xy 498.9576 -27.8384) (xy 498.36324 -27.24404)
				(xy 498.32387 -27.24404) (xy 497.577872 -27.24404) (xy 497.300504 -27.24404) (xy 497.219986 -27.163522)
			)
		)
	)
	(zone
		(layer "F.Cu")
		(hatch none 0.5)
		(connect_pads
			(clearance 0)
		)
		(min_thickness 0.25)
		(keepout
			(tracks allowed)
			(vias allowed)
			(pads allowed)
			(copperpour allowed)
			(footprints allowed)
		)
		(placement
			(enabled no)
			(sheetname "")
		)
		(fill
			(thermal_gap 0.5)
			(thermal_bridge_width 0.5)
			(island_removal_mode 0)
		)
		(polygon
			(pts
				(xy 163.4236 -84.201) (xy 163.4236 -77.2414) (xy 165.9636 -77.2414) (xy 165.9636 -84.201) (xy 165.9636 -85.42274)
				(xy 165.641274 -85.745066) (xy 163.77539 -85.745066) (xy 163.4236 -85.393276)
			)
		)
	)
	(zone
		(layer "F.Cu")
		(hatch none 0.5)
		(connect_pads
			(clearance 0)
		)
		(min_thickness 0.25)
		(keepout
			(tracks allowed)
			(vias allowed)
			(pads allowed)
			(copperpour allowed)
			(footprints allowed)
		)
		(placement
			(enabled no)
			(sheetname "")
		)
		(fill
			(thermal_gap 0.5)
			(thermal_bridge_width 0.5)
			(island_removal_mode 0)
		)
		(polygon
			(pts
				(xy 195.3006 -98.5774) (xy 195.3006 -96.1644) (xy 197.4596 -96.1644) (xy 197.4596 -98.5774)
			)
		)
	)
	(zone
		(layer "F.Cu")
		(hatch none 0.5)
		(connect_pads
			(clearance 0)
		)
		(min_thickness 0.25)
		(keepout
			(tracks not_allowed)
			(vias allowed)
			(pads allowed)
			(copperpour not_allowed)
			(footprints allowed)
		)
		(placement
			(enabled no)
			(sheetname "")
		)
		(fill
			(thermal_gap 0.5)
			(thermal_bridge_width 0.5)
			(island_removal_mode 0)
		)
		(polygon
			(pts
				(arc
					(start 494.867692 -34.120328)
					(mid 491.26775 -30.520386)
					(end 494.867692 -26.92019)
				)
				(arc
					(start 497.867686 -26.92019)
					(mid 501.60739 -30.520391)
					(end 497.867686 -34.120328)
				)
			)
		)
	)
	(zone
		(layer "F.Cu")
		(hatch none 0.5)
		(connect_pads
			(clearance 0)
		)
		(min_thickness 0.25)
		(keepout
			(tracks allowed)
			(vias allowed)
			(pads allowed)
			(copperpour allowed)
			(footprints not_allowed)
		)
		(placement
			(enabled no)
			(sheetname "")
		)
		(fill
			(thermal_gap 0.5)
			(thermal_bridge_width 0.5)
			(island_removal_mode 0)
		)
		(polygon
			(pts
				(arc
					(start 291.999924 -39.649908)
					(mid 293.900098 -41.550082)
					(end 291.999924 -43.450002)
				)
				(arc
					(start 291.999924 -43.450002)
					(mid 290.100004 -41.550082)
					(end 291.999924 -39.649908)
				)
			)
		)
	)
	(zone
		(layer "F.Cu")
		(hatch none 0.5)
		(connect_pads
			(clearance 0)
		)
		(min_thickness 0.25)
		(keepout
			(tracks not_allowed)
			(vias allowed)
			(pads allowed)
			(copperpour not_allowed)
			(footprints allowed)
		)
		(placement
			(enabled no)
			(sheetname "")
		)
		(fill
			(thermal_gap 0.5)
			(thermal_bridge_width 0.5)
			(island_removal_mode 0)
		)
		(polygon
			(pts
				(arc
					(start 452.519796 -44.7675)
					(mid 453.043713 -44.83735)
					(end 452.519796 -44.9072)
				)
				(xy 452.47306 -44.9072) (xy 452.31685 -45.06341) (xy 452.31685 -45.22089)
				(arc
					(start 452.776844 -45.22089)
					(mid 453.160638 -44.837477)
					(end 452.777098 -44.45381)
				)
				(arc
					(start 451.507098 -44.45381)
					(mid 451.123558 -44.83735)
					(end 451.507098 -45.22089)
				)
				(xy 451.93585 -45.22089) (xy 451.93585 -45.031914) (xy 451.811136 -44.9072)
				(arc
					(start 451.7644 -44.9072)
					(mid 451.240483 -44.83735)
					(end 451.7644 -44.7675)
				)
				(xy 451.869048 -44.7675) (xy 452.07555 -44.974002) (xy 452.07555 -45.22089) (xy 452.17715 -45.22089)
				(xy 452.17715 -45.005498) (xy 452.415148 -44.7675)
			)
		)
	)
	(zone
		(layer "F.Cu")
		(hatch none 0.5)
		(connect_pads
			(clearance 0)
		)
		(min_thickness 0.25)
		(keepout
			(tracks allowed)
			(vias allowed)
			(pads allowed)
			(copperpour allowed)
			(footprints allowed)
		)
		(placement
			(enabled no)
			(sheetname "")
		)
		(fill
			(thermal_gap 0.5)
			(thermal_bridge_width 0.5)
			(island_removal_mode 0)
		)
		(polygon
			(pts
				(xy 126.769368 -29.464) (xy 126.769368 -27.432) (xy 128.928368 -27.432) (xy 128.928368 -29.464)
			)
		)
	)
	(zone
		(net "GND")
		(layer "F.Cu")
		(hatch none 0.5)
		(connect_pads
			(clearance 0.5)
		)
		(min_thickness 0.25)
		(fill yes
			(thermal_gap 0.5)
			(thermal_bridge_width 0.5)
			(island_removal_mode 0)
		)
		(polygon
			(pts
				(xy 18.9484 -100.6602) (xy 19.2024 -100.4062) (xy 21.205952 -100.4062) (xy 21.939504 -101.139752)
				(xy 21.939504 -104.49814) (xy 21.541232 -104.896412) (xy 19.567652 -104.896412) (xy 18.480786 -104.896412)
				(xy 18.092928 -104.508554) (xy 18.092928 -101.515672) (xy 18.115788 -101.492812) (xy 18.115788 -101.219762)
				(xy 18.67535 -100.6602)
			)
		)
	)
	(zone
		(layer "F.Cu")
		(hatch none 0.5)
		(connect_pads
			(clearance 0)
		)
		(min_thickness 0.25)
		(keepout
			(tracks allowed)
			(vias allowed)
			(pads allowed)
			(copperpour allowed)
			(footprints allowed)
		)
		(placement
			(enabled no)
			(sheetname "")
		)
		(fill
			(thermal_gap 0.5)
			(thermal_bridge_width 0.5)
			(island_removal_mode 0)
		)
		(polygon
			(pts
				(xy 288.29 -103.886) (xy 282.829 -103.886) (xy 282.829 -106.045) (xy 283.337 -106.045) (xy 284.734 -107.442)
			)
		)
	)
	(zone
		(net "VR_FET_SW_P12V_STBY_PVCCIN_CPU1")
		(layer "F.Cu")
		(hatch none 0.5)
		(connect_pads
			(clearance 0.5)
		)
		(min_thickness 0.25)
		(fill yes
			(thermal_gap 0.5)
			(thermal_bridge_width 0.5)
			(island_removal_mode 0)
		)
		(polygon
			(pts
				(xy 31.6484 -98.06178) (xy 31.6484 -99.398582) (xy 31.613602 -99.43338) (xy 31.613602 -99.445064)
				(xy 31.486602 -99.572064) (xy 30.709362 -99.572064) (xy 30.051756 -100.22967) (xy 29.928566 -100.35286)
				(xy 23.27402 -100.35286) (xy 23.265892 -100.360988) (xy 22.62759 -100.360988) (xy 22.224238 -100.76434)
				(xy 22.224238 -109.887004) (xy 22.737826 -110.400592) (xy 22.737826 -110.507526) (xy 22.737826 -116.014754)
				(xy 23.581614 -116.858542) (xy 24.373332 -116.858542) (xy 25.439116 -116.858542) (xy 28.945078 -116.858542)
				(xy 29.800804 -116.858542) (xy 30.58541 -116.073936) (xy 30.58541 -108.551472) (xy 27.6606 -105.626662)
				(xy 27.6606 -105.158286) (xy 27.6606 -104.14) (xy 26.924 -103.4034) (xy 26.924 -103.40213) (xy 26.912316 -103.390446)
				(xy 26.912316 -103.020114) (xy 26.924 -103.00843) (xy 27.126946 -102.805484) (xy 27.219402 -102.805484)
				(xy 27.284934 -102.739952) (xy 27.284934 -102.337108) (xy 27.747468 -101.874574) (xy 28.33624 -101.874574)
				(xy 28.812744 -101.39807) (xy 31.312104 -101.39807) (xy 31.364936 -101.39807) (xy 32.425894 -102.459028)
				(xy 32.436308 -102.469442) (xy 32.887158 -102.469442) (xy 32.925512 -102.431088) (xy 32.925512 -101.129084)
				(xy 32.936688 -101.117908) (xy 33.630616 -100.42398) (xy 33.630616 -98.06178)
			)
		)
	)
	(zone
		(net "PVTT_DEF")
		(layer "F.Cu")
		(hatch none 0.5)
		(connect_pads
			(clearance 0.5)
		)
		(min_thickness 0.25)
		(fill yes
			(thermal_gap 0.5)
			(thermal_bridge_width 0.5)
			(island_removal_mode 0)
		)
		(polygon
			(pts
				(xy 182.144924 -151.7777) (xy 180.493924 -153.4287) (xy 180.493924 -154.4447) (xy 180.493924 -155.119324)
				(xy 180.493924 -155.784296) (xy 180.52542 -155.815792) (xy 181.206648 -156.49702) (xy 182.18404 -156.49702)
				(xy 182.210964 -156.470096) (xy 182.210964 -154.88666) (xy 182.226712 -154.870912) (xy 182.26278 -154.834844)
				(xy 182.26278 -153.056844) (xy 182.398924 -152.9207) (xy 182.525924 -152.7937) (xy 182.525924 -150.8887)
				(xy 182.245 -150.8887) (xy 182.245 -151.677624)
			)
		)
	)
	(zone
		(net "GND")
		(layer "F.Cu")
		(hatch none 0.5)
		(connect_pads
			(clearance 0.5)
		)
		(min_thickness 0.25)
		(fill yes
			(thermal_gap 0.5)
			(thermal_bridge_width 0.5)
			(island_removal_mode 0)
		)
		(polygon
			(pts
				(xy 393.96543 -155.628594) (xy 397.587216 -155.628594) (xy 397.615918 -155.599892) (xy 397.615918 -152.038304)
				(xy 397.561054 -151.98344) (xy 393.975844 -151.98344) (xy 393.944602 -152.014682) (xy 393.944602 -155.607766)
			)
		)
	)
	(zone
		(net "GND")
		(layer "F.Cu")
		(hatch none 0.5)
		(connect_pads
			(clearance 0.5)
		)
		(min_thickness 0.25)
		(fill yes
			(thermal_gap 0.5)
			(thermal_bridge_width 0.5)
			(island_removal_mode 0)
		)
		(polygon
			(pts
				(xy 198.374 -94.9198) (xy 198.312278 -94.981522) (xy 198.312278 -95.845122) (xy 198.1708 -95.9866)
				(xy 197.291452 -95.9866) (xy 197.286626 -95.981774) (xy 197.2818 -95.9866) (xy 196.7738 -95.9866)
				(xy 196.6722 -96.0882) (xy 196.6722 -97.4344) (xy 196.8754 -97.6376) (xy 198.5518 -97.6376) (xy 198.832216 -97.6376)
				(xy 199.009 -97.814384) (xy 199.009 -98.0948) (xy 199.009 -101.3968) (xy 199.026272 -101.414072)
				(xy 199.026272 -102.19182) (xy 199.140572 -102.30612) (xy 203.81468 -102.30612) (xy 204.9526 -101.1682)
				(xy 207.01 -101.1682) (xy 207.80121 -100.37699) (xy 207.80121 -93.628718) (xy 207.73898 -93.566488)
				(xy 205.246478 -93.566488) (xy 205.119224 -93.693742) (xy 205.119224 -94.805246) (xy 205.208378 -94.8944)
				(xy 206.3496 -94.8944) (xy 206.350616 -94.895416) (xy 206.658718 -94.895416) (xy 207.00365 -95.240348)
				(xy 207.00365 -98.912934) (xy 206.66329 -99.253294) (xy 206.66329 -100.130356) (xy 206.19339 -100.600256)
				(xy 206.104744 -100.600256) (xy 205.994 -100.600256) (xy 201.600308 -100.600256) (xy 201.167492 -100.167694)
				(xy 201.167492 -95.301308) (xy 201.170286 -95.298514) (xy 201.558906 -94.910148) (xy 201.7776 -94.910148)
				(xy 201.93 -94.757748) (xy 201.93 -94.3356) (xy 201.825352 -94.230952) (xy 200.734676 -94.230952)
				(xy 200.453752 -94.230952) (xy 200.3552 -94.1324) (xy 200.3552 -93.2942) (xy 200.2282 -93.1672)
				(xy 199.967088 -93.1672) (xy 199.644 -93.1672) (xy 199.1868 -93.6244) (xy 199.136 -93.6244) (xy 199.0598 -93.6244)
				(xy 198.6534 -93.6244) (xy 198.6534 -94.403926) (xy 198.442326 -94.615) (xy 198.442326 -94.851474)
			)
		)
	)
	(zone
		(layer "F.Cu")
		(hatch none 0.5)
		(connect_pads
			(clearance 0)
		)
		(min_thickness 0.25)
		(keepout
			(tracks not_allowed)
			(vias allowed)
			(pads allowed)
			(copperpour not_allowed)
			(footprints allowed)
		)
		(placement
			(enabled no)
			(sheetname "")
		)
		(fill
			(thermal_gap 0.5)
			(thermal_bridge_width 0.5)
			(island_removal_mode 0)
		)
		(polygon
			(pts
				(xy 444.026036 -8.74141) (xy 444.026036 -9.03097)
				(arc
					(start 443.88659 -9.170416)
					(mid 443.360236 -9.16696)
					(end 443.859412 -8.999982)
				)
				(xy 443.886336 -8.973058) (xy 443.886336 -8.781796) (xy 443.84595 -8.74141)
				(arc
					(start 443.6237 -8.74141)
					(mid 443.24016 -9.12495)
					(end 443.6237 -9.50849)
				)
				(arc
					(start 444.563246 -9.50849)
					(mid 444.94704 -9.125077)
					(end 444.5635 -8.74141)
				)
				(xy 444.267336 -8.74141) (xy 444.267336 -8.99033)
				(arc
					(start 444.312294 -9.035288)
					(mid 444.82995 -9.134817)
					(end 444.306198 -9.1948)
				)
				(xy 444.274194 -9.1948) (xy 444.127636 -9.048242) (xy 444.127636 -8.74141)
			)
		)
	)
	(zone
		(layer "F.Cu")
		(hatch none 0.5)
		(connect_pads
			(clearance 0)
		)
		(min_thickness 0.25)
		(keepout
			(tracks not_allowed)
			(vias allowed)
			(pads allowed)
			(copperpour not_allowed)
			(footprints allowed)
		)
		(placement
			(enabled no)
			(sheetname "")
		)
		(fill
			(thermal_gap 0.5)
			(thermal_bridge_width 0.5)
			(island_removal_mode 0)
		)
		(polygon
			(pts
				(arc
					(start 13.434314 -26.606754)
					(mid 13.050901 -26.22296)
					(end 12.667234 -26.6065)
				)
				(arc
					(start 12.667234 -27.8765)
					(mid 13.050774 -28.26004)
					(end 13.434314 -27.8765)
				)
				(xy 13.434314 -27.450034) (xy 13.175996 -27.450034) (xy 13.120624 -27.505406)
				(arc
					(start 13.120624 -27.619198)
					(mid 13.050774 -28.143115)
					(end 12.980924 -27.619198)
				)
				(xy 12.980924 -27.447494) (xy 13.118084 -27.310334) (xy 13.434314 -27.310334) (xy 13.434314 -27.172666)
				(xy 13.118084 -27.172666) (xy 12.980924 -27.035506)
				(arc
					(start 12.980924 -26.863802)
					(mid 13.050774 -26.339885)
					(end 13.120624 -26.863802)
				)
				(xy 13.120624 -26.977594) (xy 13.175996 -27.032966) (xy 13.434314 -27.032966)
			)
		)
	)
	(zone
		(net "VR_PVCCIO_CPU0_PH1_SW")
		(layer "F.Cu")
		(hatch none 0.5)
		(connect_pads
			(clearance 0.5)
		)
		(min_thickness 0.25)
		(fill yes
			(thermal_gap 0.5)
			(thermal_bridge_width 0.5)
			(island_removal_mode 0)
		)
		(polygon
			(pts
				(xy 340.3727 -99.949) (xy 344.297 -99.949) (xy 344.4494 -99.7966) (xy 344.4494 -95.4532) (xy 344.1446 -95.1484)
				(xy 340.7664 -95.1484) (xy 339.88502 -96.02978) (xy 339.88502 -96.031812) (xy 339.385402 -96.53143)
				(xy 339.385402 -99.812602) (xy 339.5218 -99.949)
			)
		)
	)
	(zone
		(layer "F.Cu")
		(hatch none 0.5)
		(connect_pads
			(clearance 0)
		)
		(min_thickness 0.25)
		(keepout
			(tracks allowed)
			(vias allowed)
			(pads allowed)
			(copperpour allowed)
			(footprints allowed)
		)
		(placement
			(enabled no)
			(sheetname "")
		)
		(fill
			(thermal_gap 0.5)
			(thermal_bridge_width 0.5)
			(island_removal_mode 0)
		)
		(polygon
			(pts
				(xy 383.794 -154.432) (xy 386.08 -154.432) (xy 386.08 -156.4386) (xy 383.794 -156.4386)
			)
		)
	)
	(zone
		(layer "F.Cu")
		(hatch none 0.5)
		(connect_pads
			(clearance 0)
		)
		(min_thickness 0.25)
		(keepout
			(tracks allowed)
			(vias allowed)
			(pads allowed)
			(copperpour allowed)
			(footprints allowed)
		)
		(placement
			(enabled no)
			(sheetname "")
		)
		(fill
			(thermal_gap 0.5)
			(thermal_bridge_width 0.5)
			(island_removal_mode 0)
		)
		(polygon
			(pts
				(xy 117.828568 -103.886) (xy 117.828568 -100.965) (xy 118.971568 -99.822) (xy 121.638568 -99.822)
				(xy 122.908568 -101.092) (xy 122.908568 -102.362) (xy 122.908568 -102.616) (xy 122.654568 -102.87)
				(xy 122.654568 -103.124) (xy 123.289568 -103.759) (xy 123.289568 -103.886) (xy 122.273568 -103.886)
			)
		)
	)
	(zone
		(net "AGND_PVPP_GHJ")
		(layer "F.Cu")
		(hatch none 0.5)
		(connect_pads
			(clearance 0.5)
		)
		(min_thickness 0.25)
		(fill yes
			(thermal_gap 0.5)
			(thermal_bridge_width 0.5)
			(island_removal_mode 0)
		)
		(polygon
			(pts
				(xy 177.419 -10.922) (xy 177.927 -10.922) (xy 178.054 -10.795) (xy 178.054 -10.0584) (xy 178.457098 -9.655302)
				(xy 178.457098 -8.810498) (xy 178.3588 -8.7122) (xy 178.2572 -8.7122) (xy 178.1556 -8.7122) (xy 178.0032 -8.7122)
				(xy 177.8508 -8.8646) (xy 177.8508 -9.4742) (xy 177.8508 -9.508998) (xy 177.292 -10.067798) (xy 177.292 -10.795)
			)
		)
	)
	(zone
		(layer "F.Cu")
		(hatch none 0.5)
		(connect_pads
			(clearance 0)
		)
		(min_thickness 0.25)
		(keepout
			(tracks not_allowed)
			(vias allowed)
			(pads allowed)
			(copperpour not_allowed)
			(footprints allowed)
		)
		(placement
			(enabled no)
			(sheetname "")
		)
		(fill
			(thermal_gap 0.5)
			(thermal_bridge_width 0.5)
			(island_removal_mode 0)
		)
		(polygon
			(pts
				(arc
					(start 3.50012 -151.100028)
					(mid 7.500112 -155.10002)
					(end 3.50012 -159.100012)
				)
				(arc
					(start 0 -159.100012)
					(mid -3.999992 -155.10002)
					(end 0 -151.100028)
				)
			)
		)
	)
	(zone
		(net "GND")
		(layer "F.Cu")
		(hatch none 0.5)
		(connect_pads
			(clearance 0.5)
		)
		(min_thickness 0.25)
		(fill yes
			(thermal_gap 0.5)
			(thermal_bridge_width 0.5)
			(island_removal_mode 0)
		)
		(polygon
			(pts
				(xy 8.4836 -107.2388) (xy 8.334756 -107.387644) (xy 8.334756 -108.436156) (xy 8.334756 -108.789216)
				(xy 8.523986 -108.978446) (xy 8.523986 -110.366302) (xy 8.334756 -110.555532) (xy 8.326882 -110.563406)
				(xy 8.326882 -111.164624) (xy 8.607806 -111.445548) (xy 8.607806 -112.663224) (xy 8.661908 -112.717072)
				(xy 11.056112 -112.717072) (xy 11.17346 -112.599724) (xy 11.17346 -109.061758) (xy 10.554716 -108.443014)
				(xy 10.554716 -107.924854) (xy 9.868662 -107.2388) (xy 9.493504 -107.2388) (xy 9.3726 -107.2388)
			)
		)
	)
	(zone
		(net "VR_FET_SW_P12V_STBY_PVPP_KLM")
		(layer "F.Cu")
		(hatch none 0.5)
		(connect_pads
			(clearance 0.5)
		)
		(min_thickness 0.25)
		(fill yes
			(thermal_gap 0.5)
			(thermal_bridge_width 0.5)
			(island_removal_mode 0)
		)
		(polygon
			(pts
				(xy 177.8 -136.2075) (xy 180.848 -136.2075) (xy 180.8734 -136.2075) (xy 180.8861 -136.2202) (xy 182.5752 -136.2202)
				(xy 182.7276 -136.3726) (xy 182.7276 -136.906) (xy 182.753 -136.9314) (xy 186.944 -136.9314) (xy 187.2361 -136.6393)
				(xy 187.2361 -135.8265) (xy 187.0964 -135.6868) (xy 185.4708 -135.6868) (xy 185.041032 -135.257032)
				(xy 184.638442 -135.257032) (xy 184.637934 -135.256524) (xy 184.547256 -135.256524) (xy 183.769 -134.478268)
				(xy 183.769 -134.38759) (xy 183.769 -133.985) (xy 183.769 -133.037072) (xy 183.639206 -132.907278)
				(xy 183.639206 -131.535678) (xy 183.559958 -131.45643) (xy 181.950868 -131.45643) (xy 180.946298 -132.461)
				(xy 180.848 -132.461) (xy 180.213 -132.461) (xy 179.832 -132.842) (xy 179.07 -133.604) (xy 178.8287 -133.604)
				(xy 178.816 -133.6167) (xy 178.816 -134.5565) (xy 178.689 -134.6835) (xy 177.8 -134.6835)
			)
		)
	)
	(zone
		(net "GND")
		(layer "F.Cu")
		(hatch none 0.5)
		(connect_pads
			(clearance 0.5)
		)
		(min_thickness 0.25)
		(fill yes
			(thermal_gap 0.5)
			(thermal_bridge_width 0.5)
			(island_removal_mode 0)
		)
		(polygon
			(pts
				(xy 186.436 -84.7344) (xy 184.6326 -84.7344) (xy 183.5912 -85.7758) (xy 183.5912 -95.758) (xy 187.2488 -95.758)
				(xy 187.4266 -95.5802) (xy 187.6806 -95.3262) (xy 187.6806 -85.09) (xy 187.325 -84.7344)
			)
		)
	)
	(zone
		(layer "F.Cu")
		(hatch none 0.5)
		(connect_pads
			(clearance 0)
		)
		(min_thickness 0.25)
		(keepout
			(tracks not_allowed)
			(vias allowed)
			(pads allowed)
			(copperpour not_allowed)
			(footprints allowed)
		)
		(placement
			(enabled no)
			(sheetname "")
		)
		(fill
			(thermal_gap 0.5)
			(thermal_bridge_width 0.5)
			(island_removal_mode 0)
		)
		(polygon
			(pts
				(arc
					(start 222.000064 -78.449932)
					(mid 220.100144 -76.550012)
					(end 222.000064 -74.650092)
				)
				(arc
					(start 222.000064 -74.650092)
					(mid 223.899984 -76.550012)
					(end 222.000064 -78.449932)
				)
			)
		)
	)
	(zone
		(layer "F.Cu")
		(hatch none 0.5)
		(connect_pads
			(clearance 0)
		)
		(min_thickness 0.25)
		(keepout
			(tracks allowed)
			(vias allowed)
			(pads allowed)
			(copperpour allowed)
			(footprints not_allowed)
		)
		(placement
			(enabled no)
			(sheetname "")
		)
		(fill
			(thermal_gap 0.5)
			(thermal_bridge_width 0.5)
			(island_removal_mode 0)
		)
		(polygon
			(pts
				(arc
					(start 318.000126 -96.650048)
					(mid 319.900046 -98.549968)
					(end 318.000126 -100.449888)
				)
				(arc
					(start 318.000126 -100.449888)
					(mid 316.100206 -98.549968)
					(end 318.000126 -96.650048)
				)
			)
		)
	)
	(zone
		(layer "F.Cu")
		(hatch none 0.5)
		(connect_pads
			(clearance 0)
		)
		(min_thickness 0.25)
		(keepout
			(tracks allowed)
			(vias allowed)
			(pads allowed)
			(copperpour allowed)
			(footprints not_allowed)
		)
		(placement
			(enabled no)
			(sheetname "")
		)
		(fill
			(thermal_gap 0.5)
			(thermal_bridge_width 0.5)
			(island_removal_mode 0)
		)
		(polygon
			(pts
				(arc
					(start 495.720116 -32.120078)
					(mid 494.12017 -30.520132)
					(end 495.720116 -28.919932)
				)
				(arc
					(start 497.320062 -28.919932)
					(mid 498.920262 -30.520132)
					(end 497.320062 -32.120078)
				)
			)
		)
	)
	(zone
		(net "P12V_NVDIMM_DEF")
		(layer "F.Cu")
		(hatch none 0.5)
		(connect_pads
			(clearance 0.5)
		)
		(min_thickness 0.25)
		(fill yes
			(thermal_gap 0.5)
			(thermal_bridge_width 0.5)
			(island_removal_mode 0)
		)
		(polygon
			(pts
				(xy 194.945 -157.799024) (xy 194.837558 -157.906466) (xy 192.004442 -157.906466) (xy 190.329566 -157.906466)
				(xy 190.32855 -157.90545) (xy 189.63005 -157.90545) (xy 189.5856 -157.861) (xy 189.5856 -139.2174)
				(xy 190.119 -138.684) (xy 191.897 -136.906) (xy 191.897 -131.344416) (xy 192.543938 -130.697478)
				(xy 192.543938 -129.40157) (xy 192.488312 -129.345944) (xy 192.152016 -129.345944) (xy 191.897 -129.090928)
				(xy 191.897 -128.168654) (xy 192.035684 -128.02997) (xy 194.769994 -128.02997) (xy 194.945 -128.204976)
			)
		)
	)
	(zone
		(layer "F.Cu")
		(hatch none 0.5)
		(connect_pads
			(clearance 0)
		)
		(min_thickness 0.25)
		(keepout
			(tracks not_allowed)
			(vias allowed)
			(pads allowed)
			(copperpour not_allowed)
			(footprints allowed)
		)
		(placement
			(enabled no)
			(sheetname "")
		)
		(fill
			(thermal_gap 0.5)
			(thermal_bridge_width 0.5)
			(island_removal_mode 0)
		)
		(polygon
			(pts
				(arc
					(start 369.48999 -89.490042)
					(mid 365.899954 -85.900006)
					(end 369.48999 -82.30997)
				)
				(arc
					(start 369.48999 -82.30997)
					(mid 373.080026 -85.900006)
					(end 369.48999 -89.490042)
				)
			)
		)
	)
	(zone
		(layer "F.Cu")
		(hatch none 0.5)
		(connect_pads
			(clearance 0)
		)
		(min_thickness 0.25)
		(keepout
			(tracks not_allowed)
			(vias allowed)
			(pads allowed)
			(copperpour not_allowed)
			(footprints allowed)
		)
		(placement
			(enabled no)
			(sheetname "")
		)
		(fill
			(thermal_gap 0.5)
			(thermal_bridge_width 0.5)
			(island_removal_mode 0)
		)
		(polygon
			(pts
				(xy 364.14075 -2.353564) (xy 364.14075 -2.180844) (xy 364.42142 -1.900174)
				(arc
					(start 364.493048 -1.900174)
					(mid 365.016965 -1.970024)
					(end 364.493048 -2.039874)
				)
				(xy 364.479332 -2.039874) (xy 364.28045 -2.238756) (xy 364.28045 -2.353564)
				(arc
					(start 364.750096 -2.353564)
					(mid 365.13389 -1.970151)
					(end 364.75035 -1.586484)
				)
				(arc
					(start 363.48035 -1.586484)
					(mid 363.09681 -1.970024)
					(end 363.48035 -2.353564)
				)
				(xy 363.89945 -2.353564) (xy 363.89945 -2.221484)
				(arc
					(start 363.73308 -2.055114)
					(mid 363.213799 -1.962068)
					(end 363.737652 -1.900174)
				)
				(xy 363.775752 -1.900174) (xy 364.03915 -2.163572) (xy 364.03915 -2.353564)
			)
		)
	)
	(zone
		(layer "F.Cu")
		(hatch none 0.5)
		(connect_pads
			(clearance 0)
		)
		(min_thickness 0.25)
		(keepout
			(tracks allowed)
			(vias allowed)
			(pads allowed)
			(copperpour allowed)
			(footprints not_allowed)
		)
		(placement
			(enabled no)
			(sheetname "")
		)
		(fill
			(thermal_gap 0.5)
			(thermal_bridge_width 0.5)
			(island_removal_mode 0)
		)
		(polygon
			(pts
				(arc
					(start 198.930006 -50.099976)
					(mid 195.380102 -46.550072)
					(end 198.930006 -42.999914)
				)
				(arc
					(start 198.930006 -42.999914)
					(mid 202.480164 -46.550072)
					(end 198.930006 -50.099976)
				)
			)
		)
	)
	(zone
		(layer "F.Cu")
		(hatch none 0.5)
		(connect_pads
			(clearance 0)
		)
		(min_thickness 0.25)
		(keepout
			(tracks allowed)
			(vias allowed)
			(pads allowed)
			(copperpour allowed)
			(footprints allowed)
		)
		(placement
			(enabled no)
			(sheetname "")
		)
		(fill
			(thermal_gap 0.5)
			(thermal_bridge_width 0.5)
			(island_removal_mode 0)
		)
		(polygon
			(pts
				(xy 4.1656 -19.3802) (xy 4.1656 -15.0114) (xy 6.5786 -15.0114) (xy 6.5786 -19.3802)
			)
		)
	)
	(zone
		(layer "F.Cu")
		(hatch none 0.5)
		(connect_pads
			(clearance 0)
		)
		(min_thickness 0.25)
		(keepout
			(tracks not_allowed)
			(vias allowed)
			(pads allowed)
			(copperpour not_allowed)
			(footprints allowed)
		)
		(placement
			(enabled no)
			(sheetname "")
		)
		(fill
			(thermal_gap 0.5)
			(thermal_bridge_width 0.5)
			(island_removal_mode 0)
		)
		(polygon
			(pts
				(arc
					(start 175.50003 -151.100028)
					(mid 179.500022 -155.10002)
					(end 175.50003 -159.100012)
				)
				(arc
					(start 171.99991 -159.100012)
					(mid 167.999918 -155.10002)
					(end 171.99991 -151.100028)
				)
			)
		)
	)
	(zone
		(net "GND")
		(layer "F.Cu")
		(hatch none 0.5)
		(connect_pads
			(clearance 0.5)
		)
		(min_thickness 0.25)
		(fill yes
			(thermal_gap 0.5)
			(thermal_bridge_width 0.5)
			(island_removal_mode 0)
		)
		(polygon
			(pts
				(xy 331.343 -14.097) (xy 330.327 -14.097) (xy 330.2 -14.224) (xy 330.2 -15.875) (xy 330.327 -16.002)
				(xy 331.343 -16.002) (xy 331.47 -15.875) (xy 331.47 -14.224)
			)
		)
	)
	(zone
		(layer "F.Cu")
		(hatch none 0.5)
		(connect_pads
			(clearance 0)
		)
		(min_thickness 0.25)
		(keepout
			(tracks not_allowed)
			(vias allowed)
			(pads allowed)
			(copperpour not_allowed)
			(footprints allowed)
		)
		(placement
			(enabled no)
			(sheetname "")
		)
		(fill
			(thermal_gap 0.5)
			(thermal_bridge_width 0.5)
			(island_removal_mode 0)
		)
		(polygon
			(pts
				(arc
					(start 56.999886 -79.090012)
					(mid 54.459886 -76.550012)
					(end 56.999886 -74.010012)
				)
				(arc
					(start 56.999886 -74.010012)
					(mid 59.539886 -76.550012)
					(end 56.999886 -79.090012)
				)
			)
		)
	)
	(zone
		(layer "F.Cu")
		(hatch none 0.5)
		(connect_pads
			(clearance 0)
		)
		(min_thickness 0.25)
		(keepout
			(tracks allowed)
			(vias allowed)
			(pads allowed)
			(copperpour allowed)
			(footprints allowed)
		)
		(placement
			(enabled no)
			(sheetname "")
		)
		(fill
			(thermal_gap 0.5)
			(thermal_bridge_width 0.5)
			(island_removal_mode 0)
		)
		(polygon
			(pts
				(xy 456.692 -145.923) (xy 456.692 -145.415) (xy 457.835 -145.415) (xy 457.835 -145.923)
			)
		)
	)
	(zone
		(net "VR_PVSA_CPU0_PHASE_SW")
		(layer "F.Cu")
		(hatch none 0.5)
		(connect_pads
			(clearance 0.5)
		)
		(min_thickness 0.25)
		(fill yes
			(thermal_gap 0.5)
			(thermal_bridge_width 0.5)
			(island_removal_mode 0)
		)
		(polygon
			(pts
				(xy 201.7268 -100.295202) (xy 205.995778 -100.295202) (xy 206.130398 -100.295202) (xy 206.4004 -100.0252)
				(xy 206.4004 -99.23653) (xy 206.862172 -98.774758) (xy 206.862172 -95.384112) (xy 206.67726 -95.1992)
				(xy 206.375 -95.1992) (xy 201.7014 -95.1992) (xy 201.685398 -95.215202) (xy 201.4728 -95.4278) (xy 201.4728 -100.041202)
			)
		)
	)
	(zone
		(layer "F.Cu")
		(hatch none 0.5)
		(connect_pads
			(clearance 0)
		)
		(min_thickness 0.25)
		(keepout
			(tracks allowed)
			(vias allowed)
			(pads allowed)
			(copperpour allowed)
			(footprints allowed)
		)
		(placement
			(enabled no)
			(sheetname "")
		)
		(fill
			(thermal_gap 0.5)
			(thermal_bridge_width 0.5)
			(island_removal_mode 0)
		)
		(polygon
			(pts
				(xy 480.539806 -33.33369) (xy 481.692966 -33.33369) (xy 481.695252 -33.331404) (xy 481.931726 -33.331404)
				(xy 482.092 -33.17113) (xy 482.092 -32.385) (xy 481.9396 -32.2326) (xy 480.675442 -32.2326) (xy 480.393248 -32.514794)
				(xy 480.393248 -33.187132)
			)
		)
	)
	(zone
		(net "PVSA_CPU0")
		(layer "F.Cu")
		(hatch none 0.5)
		(connect_pads
			(clearance 0.5)
		)
		(min_thickness 0.25)
		(fill yes
			(thermal_gap 0.5)
			(thermal_bridge_width 0.5)
			(island_removal_mode 0)
		)
		(polygon
			(pts
				(xy 216.55786 -98.3234) (xy 216.55786 -93.54566) (xy 216.55786 -93.282516) (xy 216.452704 -93.17736)
				(xy 215.849962 -93.17736) (xy 214.971122 -94.0562) (xy 214.0458 -94.0562) (xy 213.995 -94.0054)
				(xy 212.9282 -92.9386) (xy 209.042 -92.9386) (xy 208.6102 -92.9386) (xy 208.4578 -93.091) (xy 208.026 -93.5228)
				(xy 208.026 -99.95662) (xy 208.47558 -100.4062) (xy 209.169 -100.4062) (xy 210.3628 -100.4062) (xy 211.8106 -98.9584)
				(xy 211.847684 -98.921316) (xy 215.959944 -98.921316)
			)
		)
	)
	(zone
		(layer "F.Cu")
		(hatch none 0.5)
		(connect_pads
			(clearance 0)
		)
		(min_thickness 0.25)
		(keepout
			(tracks not_allowed)
			(vias allowed)
			(pads allowed)
			(copperpour not_allowed)
			(footprints allowed)
		)
		(placement
			(enabled no)
			(sheetname "")
		)
		(fill
			(thermal_gap 0.5)
			(thermal_bridge_width 0.5)
			(island_removal_mode 0)
		)
		(polygon
			(pts
				(arc
					(start 15.520924 -32.953198)
					(mid 15.451074 -33.477115)
					(end 15.381224 -32.953198)
				)
				(xy 15.381224 -32.839406) (xy 15.325852 -32.784034) (xy 15.117572 -32.784034) (xy 15.067534 -32.834072)
				(arc
					(start 15.067534 -33.2105)
					(mid 15.451074 -33.59404)
					(end 15.834614 -33.2105)
				)
				(arc
					(start 15.834614 -31.940754)
					(mid 15.451201 -31.55696)
					(end 15.067534 -31.9405)
				)
				(xy 15.067534 -32.316928) (xy 15.117572 -32.366966) (xy 15.325852 -32.366966) (xy 15.381224 -32.311594)
				(arc
					(start 15.381224 -32.197802)
					(mid 15.451074 -31.673885)
					(end 15.520924 -32.197802)
				)
				(xy 15.520924 -32.369506) (xy 15.383764 -32.506666) (xy 15.067534 -32.506666) (xy 15.067534 -32.644334)
				(xy 15.383764 -32.644334) (xy 15.520924 -32.781494)
			)
		)
	)
	(zone
		(net "GND")
		(layer "F.Cu")
		(hatch none 0.5)
		(connect_pads
			(clearance 0.5)
		)
		(min_thickness 0.25)
		(fill yes
			(thermal_gap 0.5)
			(thermal_bridge_width 0.5)
			(island_removal_mode 0)
		)
		(polygon
			(pts
				(xy 389.321294 -63.999872) (xy 388.992872 -63.999872) (xy 388.747 -64.245998) (xy 388.747 -64.897)
				(xy 388.686548 -64.957452) (xy 388.532624 -64.957452) (xy 388.528052 -64.957452) (xy 388.461504 -65.024)
				(xy 385.445 -65.024) (xy 385.2672 -64.8462) (xy 385.2672 -62.0776) (xy 385.6228 -61.722) (xy 389.1026 -61.722)
				(xy 389.255 -61.8744) (xy 389.92556 -62.54496) (xy 389.92556 -63.929514) (xy 389.911336 -63.943738)
				(xy 389.911082 -63.943738) (xy 389.377428 -63.943738)
			)
		)
	)
	(zone
		(layer "F.Cu")
		(hatch none 0.5)
		(connect_pads
			(clearance 0)
		)
		(min_thickness 0.25)
		(keepout
			(tracks not_allowed)
			(vias allowed)
			(pads allowed)
			(copperpour not_allowed)
			(footprints allowed)
		)
		(placement
			(enabled no)
			(sheetname "")
		)
		(fill
			(thermal_gap 0.5)
			(thermal_bridge_width 0.5)
			(island_removal_mode 0)
		)
		(polygon
			(pts
				(xy 323.9135 -121.92) (xy 323.9135 -121.412) (xy 324.2945 -121.412) (xy 324.2945 -121.92)
			)
		)
	)
	(zone
		(layer "F.Cu")
		(hatch none 0.5)
		(connect_pads
			(clearance 0)
		)
		(min_thickness 0.25)
		(keepout
			(tracks allowed)
			(vias allowed)
			(pads allowed)
			(copperpour allowed)
			(footprints allowed)
		)
		(placement
			(enabled no)
			(sheetname "")
		)
		(fill
			(thermal_gap 0.5)
			(thermal_bridge_width 0.5)
			(island_removal_mode 0)
		)
		(polygon
			(pts
				(xy 340.36 -16.002) (xy 340.36 -12.954) (xy 342.519 -12.954) (xy 342.519 -16.002)
			)
		)
	)
	(zone
		(layer "F.Cu")
		(hatch none 0.5)
		(connect_pads
			(clearance 0)
		)
		(min_thickness 0.25)
		(keepout
			(tracks allowed)
			(vias allowed)
			(pads allowed)
			(copperpour allowed)
			(footprints allowed)
		)
		(placement
			(enabled no)
			(sheetname "")
		)
		(fill
			(thermal_gap 0.5)
			(thermal_bridge_width 0.5)
			(island_removal_mode 0)
		)
		(polygon
			(pts
				(xy 301.3456 -29.3116) (xy 301.3456 -27.2288) (xy 302.9966 -27.2288) (xy 302.9966 -29.3116)
			)
		)
	)
	(zone
		(layer "F.Cu")
		(hatch none 0.5)
		(connect_pads
			(clearance 0)
		)
		(min_thickness 0.25)
		(keepout
			(tracks not_allowed)
			(vias allowed)
			(pads allowed)
			(copperpour not_allowed)
			(footprints allowed)
		)
		(placement
			(enabled no)
			(sheetname "")
		)
		(fill
			(thermal_gap 0.5)
			(thermal_bridge_width 0.5)
			(island_removal_mode 0)
		)
		(polygon
			(pts
				(arc
					(start 406.489916 -137.489946)
					(mid 402.89988 -133.89991)
					(end 406.489916 -130.309874)
				)
				(arc
					(start 406.489916 -130.309874)
					(mid 410.079952 -133.89991)
					(end 406.489916 -137.489946)
				)
			)
		)
	)
	(zone
		(layer "F.Cu")
		(hatch none 0.5)
		(connect_pads
			(clearance 0)
		)
		(min_thickness 0.25)
		(keepout
			(tracks allowed)
			(vias allowed)
			(pads allowed)
			(copperpour allowed)
			(footprints not_allowed)
		)
		(placement
			(enabled no)
			(sheetname "")
		)
		(fill
			(thermal_gap 0.5)
			(thermal_bridge_width 0.5)
			(island_removal_mode 0)
		)
		(polygon
			(pts
				(arc
					(start 83.000088 -109.650022)
					(mid 84.900262 -111.550196)
					(end 83.000088 -113.450116)
				)
				(arc
					(start 83.000088 -113.450116)
					(mid 81.100168 -111.550196)
					(end 83.000088 -109.650022)
				)
			)
		)
	)
	(zone
		(net "PVDDQ_KLM")
		(layer "F.Cu")
		(hatch none 0.5)
		(connect_pads
			(clearance 0.5)
		)
		(min_thickness 0.25)
		(fill yes
			(thermal_gap 0.5)
			(thermal_bridge_width 0.5)
			(island_removal_mode 0)
		)
		(polygon
			(pts
				(xy 98.041206 -84.328) (xy 97.954592 -84.414614) (xy 97.954592 -85.430614) (xy 98.716592 -86.192614)
				(xy 102.9716 -86.192614) (xy 103.113586 -86.3346) (xy 106.9086 -86.3346) (xy 107.6452 -85.598) (xy 107.6452 -84.5058)
				(xy 107.5944 -84.455) (xy 102.961186 -84.455) (xy 102.834186 -84.328)
			)
		)
		(polygon
			(pts
				(xy 106.961178 -85.233002) (xy 106.757978 -85.233002) (xy 106.757978 -85.436202) (xy 106.961178 -85.436202)
			)
		)
		(polygon
			(pts
				(xy 106.478578 -85.233002) (xy 106.275378 -85.233002) (xy 106.275378 -85.436202) (xy 106.478578 -85.436202)
			)
		)
		(polygon
			(pts
				(xy 105.716578 -85.233002) (xy 105.513378 -85.233002) (xy 105.513378 -85.436202) (xy 105.716578 -85.436202)
			)
		)
		(polygon
			(pts
				(xy 105.233978 -85.233002) (xy 105.030778 -85.233002) (xy 105.030778 -85.436202) (xy 105.233978 -85.436202)
			)
		)
		(polygon
			(pts
				(xy 104.471978 -85.233002) (xy 104.268778 -85.233002) (xy 104.268778 -85.436202) (xy 104.471978 -85.436202)
			)
		)
		(polygon
			(pts
				(xy 103.989378 -85.233002) (xy 103.786178 -85.233002) (xy 103.786178 -85.436202) (xy 103.989378 -85.436202)
			)
		)
		(polygon
			(pts
				(xy 103.227378 -85.233002) (xy 103.024178 -85.233002) (xy 103.024178 -85.436202) (xy 103.227378 -85.436202)
			)
		)
		(polygon
			(pts
				(xy 102.740968 -85.1027) (xy 102.537768 -85.1027) (xy 102.537768 -85.3059) (xy 102.740968 -85.3059)
			)
		)
		(polygon
			(pts
				(xy 101.978968 -85.1027) (xy 101.775768 -85.1027) (xy 101.775768 -85.3059) (xy 101.978968 -85.3059)
			)
		)
		(polygon
			(pts
				(xy 101.496368 -85.1027) (xy 101.293168 -85.1027) (xy 101.293168 -85.3059) (xy 101.496368 -85.3059)
			)
		)
		(polygon
			(pts
				(xy 100.734368 -85.1027) (xy 100.531168 -85.1027) (xy 100.531168 -85.3059) (xy 100.734368 -85.3059)
			)
		)
		(polygon
			(pts
				(xy 100.251768 -85.1027) (xy 100.048568 -85.1027) (xy 100.048568 -85.3059) (xy 100.251768 -85.3059)
			)
		)
		(polygon
			(pts
				(xy 99.489768 -85.1027) (xy 99.286568 -85.1027) (xy 99.286568 -85.3059) (xy 99.489768 -85.3059)
			)
		)
		(polygon
			(pts
				(xy 99.007168 -85.0519) (xy 98.803968 -85.0519) (xy 98.803968 -85.2551) (xy 99.007168 -85.2551)
			)
		)
	)
	(zone
		(net "GND")
		(layer "F.Cu")
		(hatch none 0.5)
		(connect_pads
			(clearance 0.5)
		)
		(min_thickness 0.25)
		(fill yes
			(thermal_gap 0.5)
			(thermal_bridge_width 0.5)
			(island_removal_mode 0)
		)
		(polygon
			(pts
				(xy 197.26021 -117.0432) (xy 200.5584 -117.0432) (xy 201.1426 -117.0432) (xy 201.5744 -116.6114)
				(xy 201.5744 -116.0272) (xy 201.5744 -111.6076) (xy 201.5744 -110.6424) (xy 201.370692 -110.438692)
				(xy 197.027292 -110.438692) (xy 196.839078 -110.626652) (xy 196.839078 -116.622068)
			)
		)
	)
	(zone
		(layer "F.Cu")
		(hatch none 0.5)
		(connect_pads
			(clearance 0)
		)
		(min_thickness 0.25)
		(keepout
			(tracks not_allowed)
			(vias allowed)
			(pads allowed)
			(copperpour not_allowed)
			(footprints allowed)
		)
		(placement
			(enabled no)
			(sheetname "")
		)
		(fill
			(thermal_gap 0.5)
			(thermal_bridge_width 0.5)
			(island_removal_mode 0)
		)
		(polygon
			(pts
				(xy 441.74918 -123.50623) (xy 441.74918 -123.812046) (xy 441.601606 -123.95962)
				(arc
					(start 441.429902 -123.95962)
					(mid 440.905985 -123.88977)
					(end 441.429902 -123.81992)
				)
				(xy 441.543694 -123.81992) (xy 441.60948 -123.754134) (xy 441.60948 -123.50623)
				(arc
					(start 441.172854 -123.50623)
					(mid 440.78906 -123.889643)
					(end 441.1726 -124.27331)
				)
				(arc
					(start 442.4426 -124.27331)
					(mid 442.82614 -123.88977)
					(end 442.4426 -123.50623)
				)
				(xy 441.99048 -123.50623) (xy 441.99048 -123.738894) (xy 442.071506 -123.81992)
				(arc
					(start 442.185298 -123.81992)
					(mid 442.709215 -123.88977)
					(end 442.185298 -123.95962)
				)
				(xy 442.013594 -123.95962) (xy 441.85078 -123.796806) (xy 441.85078 -123.50623)
			)
		)
	)
	(zone
		(layer "F.Cu")
		(hatch none 0.5)
		(connect_pads
			(clearance 0)
		)
		(min_thickness 0.25)
		(keepout
			(tracks allowed)
			(vias allowed)
			(pads allowed)
			(copperpour allowed)
			(footprints not_allowed)
		)
		(placement
			(enabled no)
			(sheetname "")
		)
		(fill
			(thermal_gap 0.5)
			(thermal_bridge_width 0.5)
			(island_removal_mode 0)
		)
		(polygon
			(pts
				(xy 487.309922 -120.400064) (xy 492.009938 -120.400064) (xy 492.009938 -122.340116) (xy 487.309922 -122.340116)
				(xy 487.309922 -123.686824) (xy 484.400098 -123.686824) (xy 484.400098 -121.37009) (xy 487.309922 -121.37009)
			)
		)
	)
	(zone
		(layer "F.Cu")
		(hatch none 0.5)
		(connect_pads
			(clearance 0)
		)
		(min_thickness 0.25)
		(keepout
			(tracks not_allowed)
			(vias allowed)
			(pads allowed)
			(copperpour not_allowed)
			(footprints allowed)
		)
		(placement
			(enabled no)
			(sheetname "")
		)
		(fill
			(thermal_gap 0.5)
			(thermal_bridge_width 0.5)
			(island_removal_mode 0)
		)
		(polygon
			(pts
				(arc
					(start -0.94996 -54.909974)
					(mid -1.999996 -55.96001)
					(end -3.050032 -54.909974)
				)
				(arc
					(start -3.050032 -54.909974)
					(mid -1.999996 -53.859938)
					(end -0.94996 -54.909974)
				)
			)
		)
	)
	(zone
		(net "PVDDQ_KLM")
		(layer "F.Cu")
		(hatch none 0.5)
		(connect_pads
			(clearance 0.5)
		)
		(min_thickness 0.25)
		(fill yes
			(thermal_gap 0.5)
			(thermal_bridge_width 0.5)
			(island_removal_mode 0)
		)
		(polygon
			(pts
				(xy 14.11224 -135.763) (xy 13.55598 -136.31926) (xy 13.55598 -141.89202) (xy 13.36548 -142.08252)
				(xy 13.36548 -151.49322) (xy 13.25372 -151.60498) (xy 13.25372 -153.07818) (xy 12.9159 -153.416)
				(xy 12.9159 -156.666692) (xy 13.680694 -157.431486) (xy 20.97659 -157.431486) (xy 21.28774 -157.120336)
				(xy 21.28774 -136.60374) (xy 20.447 -135.763)
			)
		)
		(polygon
			(pts
				(xy 13.89888 -154.4574) (xy 13.69568 -154.4574) (xy 13.69568 -154.6606) (xy 13.89888 -154.6606)
			)
		)
		(polygon
			(pts
				(xy 13.89888 -153.6954) (xy 13.69568 -153.6954) (xy 13.69568 -153.8986) (xy 13.89888 -153.8986)
			)
		)
	)
	(zone
		(net "VR_FET_SW_P12V_STBY_PVPP_ABC")
		(layer "F.Cu")
		(hatch none 0.5)
		(connect_pads
			(clearance 0.5)
		)
		(min_thickness 0.25)
		(fill yes
			(thermal_gap 0.5)
			(thermal_bridge_width 0.5)
			(island_removal_mode 0)
		)
		(polygon
			(pts
				(xy 345.4908 -27.9273) (xy 348.667324 -27.9273) (xy 348.968568 -28.228544) (xy 350.133412 -28.228544)
				(xy 350.133412 -28.229814) (xy 350.382332 -28.478734) (xy 350.382332 -29.04617) (xy 350.417384 -29.081222)
				(xy 353.9236 -29.081222) (xy 354.392484 -28.612084) (xy 354.392484 -27.469084) (xy 354.219002 -27.295602)
				(xy 352.466402 -27.295602) (xy 352.3488 -27.178) (xy 352.044 -26.8732) (xy 352.044 -24.3205) (xy 351.923096 -24.199596)
				(xy 348.545404 -24.199596) (xy 347.599 -25.146) (xy 346.6338 -25.146) (xy 346.5068 -25.273) (xy 346.5068 -26.2763)
				(xy 346.3798 -26.4033) (xy 345.4908 -26.4033)
			)
		)
	)
	(zone
		(layer "F.Cu")
		(hatch none 0.5)
		(connect_pads
			(clearance 0)
		)
		(min_thickness 0.25)
		(keepout
			(tracks not_allowed)
			(vias allowed)
			(pads allowed)
			(copperpour not_allowed)
			(footprints allowed)
		)
		(placement
			(enabled no)
			(sheetname "")
		)
		(fill
			(thermal_gap 0.5)
			(thermal_bridge_width 0.5)
			(island_removal_mode 0)
		)
		(polygon
			(pts
				(arc
					(start 152.999948 -101.089968)
					(mid 150.459948 -98.549968)
					(end 152.999948 -96.009968)
				)
				(arc
					(start 152.999948 -96.009968)
					(mid 155.539948 -98.549968)
					(end 152.999948 -101.089968)
				)
			)
		)
	)
	(zone
		(layer "F.Cu")
		(hatch none 0.5)
		(connect_pads
			(clearance 0)
		)
		(min_thickness 0.25)
		(keepout
			(tracks allowed)
			(vias allowed)
			(pads allowed)
			(copperpour allowed)
			(footprints allowed)
		)
		(placement
			(enabled no)
			(sheetname "")
		)
		(fill
			(thermal_gap 0.5)
			(thermal_bridge_width 0.5)
			(island_removal_mode 0)
		)
		(polygon
			(pts
				(xy 197.5104 -91.8464) (xy 197.5104 -87.4776) (xy 199.9234 -87.4776) (xy 199.9234 -91.8464)
			)
		)
	)
	(zone
		(layer "F.Cu")
		(hatch none 0.5)
		(connect_pads
			(clearance 0)
		)
		(min_thickness 0.25)
		(keepout
			(tracks allowed)
			(vias allowed)
			(pads allowed)
			(copperpour allowed)
			(footprints not_allowed)
		)
		(placement
			(enabled no)
			(sheetname "")
		)
		(fill
			(thermal_gap 0.5)
			(thermal_bridge_width 0.5)
			(island_removal_mode 0)
		)
		(polygon
			(pts
				(xy 328.525378 5.999988) (xy 328.525378 4.683252) (xy 187.525406 4.683252) (xy 187.525406 5.999988)
			)
		)
	)
	(zone
		(layer "F.Cu")
		(hatch none 0.5)
		(connect_pads
			(clearance 0)
		)
		(min_thickness 0.25)
		(keepout
			(tracks allowed)
			(vias allowed)
			(pads allowed)
			(copperpour allowed)
			(footprints allowed)
		)
		(placement
			(enabled no)
			(sheetname "")
		)
		(fill
			(thermal_gap 0.5)
			(thermal_bridge_width 0.5)
			(island_removal_mode 0)
		)
		(polygon
			(pts
				(xy 400.558 -156.6672) (xy 400.558 -154.8892) (xy 402.2344 -154.8892) (xy 402.2344 -156.6672)
			)
		)
	)
	(zone
		(layer "F.Cu")
		(hatch none 0.5)
		(connect_pads
			(clearance 0)
		)
		(min_thickness 0.25)
		(keepout
			(tracks allowed)
			(vias allowed)
			(pads allowed)
			(copperpour allowed)
			(footprints allowed)
		)
		(placement
			(enabled no)
			(sheetname "")
		)
		(fill
			(thermal_gap 0.5)
			(thermal_bridge_width 0.5)
			(island_removal_mode 0)
		)
		(polygon
			(pts
				(xy 236.601 -29.591) (xy 236.601 -27.559) (xy 238.76 -27.559) (xy 238.76 -29.591)
			)
		)
	)
	(zone
		(layer "F.Cu")
		(hatch none 0.5)
		(connect_pads
			(clearance 0)
		)
		(min_thickness 0.25)
		(keepout
			(tracks allowed)
			(vias allowed)
			(pads allowed)
			(copperpour allowed)
			(footprints not_allowed)
		)
		(placement
			(enabled no)
			(sheetname "")
		)
		(fill
			(thermal_gap 0.5)
			(thermal_bridge_width 0.5)
			(island_removal_mode 0)
		)
		(polygon
			(pts
				(xy 183.925464 -22.919182) (xy 177.42535 -22.919182)
				(arc
					(start 177.42535 -1.50622)
					(mid 179.374656 2.993818)
					(end 175.50003 5.999988)
				)
				(xy 183.925464 5.999988)
			)
		)
	)
	(zone
		(layer "F.Cu")
		(hatch none 0.5)
		(connect_pads
			(clearance 0)
		)
		(min_thickness 0.25)
		(keepout
			(tracks allowed)
			(vias allowed)
			(pads allowed)
			(copperpour allowed)
			(footprints not_allowed)
		)
		(placement
			(enabled no)
			(sheetname "")
		)
		(fill
			(thermal_gap 0.5)
			(thermal_bridge_width 0.5)
			(island_removal_mode 0)
		)
		(polygon
			(pts
				(xy 163.524692 -157.768544) (xy 163.524692 -159.100012) (xy 22.52472 -159.100012) (xy 22.52472 -157.768544)
			)
		)
	)
	(zone
		(layer "F.Cu")
		(hatch none 0.5)
		(connect_pads
			(clearance 0)
		)
		(min_thickness 0.25)
		(keepout
			(tracks allowed)
			(vias allowed)
			(pads allowed)
			(copperpour allowed)
			(footprints allowed)
		)
		(placement
			(enabled no)
			(sheetname "")
		)
		(fill
			(thermal_gap 0.5)
			(thermal_bridge_width 0.5)
			(island_removal_mode 0)
		)
		(polygon
			(pts
				(xy 488.7214 -39.8272) (xy 490.7534 -39.8272) (xy 490.7534 -41.529) (xy 488.7214 -41.529) (xy 488.393994 -41.529)
				(xy 488.314492 -41.449498) (xy 488.314492 -40.234108)
			)
		)
	)
	(zone
		(layer "F.Cu")
		(hatch none 0.5)
		(connect_pads
			(clearance 0)
		)
		(min_thickness 0.25)
		(keepout
			(tracks not_allowed)
			(vias allowed)
			(pads allowed)
			(copperpour not_allowed)
			(footprints allowed)
		)
		(placement
			(enabled no)
			(sheetname "")
		)
		(fill
			(thermal_gap 0.5)
			(thermal_bridge_width 0.5)
			(island_removal_mode 0)
		)
		(polygon
			(pts
				(xy 433.702968 -3.243834) (xy 433.702968 -3.011424) (xy 433.923948 -2.790444)
				(arc
					(start 434.024532 -2.790444)
					(mid 434.548449 -2.860294)
					(end 434.024532 -2.930144)
				)
				(xy 433.98186 -2.930144) (xy 433.842668 -3.069336) (xy 433.842668 -3.243834)
				(arc
					(start 434.28158 -3.243834)
					(mid 434.665374 -2.860421)
					(end 434.281834 -2.476754)
				)
				(arc
					(start 433.011834 -2.476754)
					(mid 432.628294 -2.860294)
					(end 433.011834 -3.243834)
				)
				(xy 433.461668 -3.243834) (xy 433.461668 -3.040888) (xy 433.350924 -2.930144)
				(arc
					(start 433.269136 -2.930144)
					(mid 432.745219 -2.860294)
					(end 433.269136 -2.790444)
				)
				(xy 433.408836 -2.790444) (xy 433.601368 -2.982976) (xy 433.601368 -3.243834)
			)
		)
	)
	(zone
		(layer "F.Cu")
		(hatch none 0.5)
		(connect_pads
			(clearance 0)
		)
		(min_thickness 0.25)
		(keepout
			(tracks allowed)
			(vias allowed)
			(pads allowed)
			(copperpour allowed)
			(footprints allowed)
		)
		(placement
			(enabled no)
			(sheetname "")
		)
		(fill
			(thermal_gap 0.5)
			(thermal_bridge_width 0.5)
			(island_removal_mode 0)
		)
		(polygon
			(pts
				(xy -2.444496 -139.564618) (xy -2.444496 -137.278618) (xy -0.285496 -137.278618) (xy -0.285496 -139.564618)
			)
		)
	)
	(zone
		(layer "F.Cu")
		(hatch none 0.5)
		(connect_pads
			(clearance 0)
		)
		(min_thickness 0.25)
		(keepout
			(tracks allowed)
			(vias allowed)
			(pads allowed)
			(copperpour allowed)
			(footprints not_allowed)
		)
		(placement
			(enabled no)
			(sheetname "")
		)
		(fill
			(thermal_gap 0.5)
			(thermal_bridge_width 0.5)
			(island_removal_mode 0)
		)
		(polygon
			(pts
				(xy 342.325452 5.999988)
				(arc
					(start 501.000014 5.999988)
					(mid 501.707119 5.707095)
					(end 502.000012 4.99999)
				)
				(arc
					(start 502.000012 3.999992)
					(mid 501.707119 3.292887)
					(end 501.000014 2.999994)
				)
				(arc
					(start 484.35006 2.999994)
					(mid 483.996597 2.853585)
					(end 483.849934 2.500122)
				)
				(arc
					(start 483.849934 -13.5001)
					(mid 483.996418 -13.853742)
					(end 484.35006 -13.999972)
				)
				(arc
					(start 501.000014 -13.999972)
					(mid 501.707119 -14.292865)
					(end 502.000012 -14.99997)
				)
				(arc
					(start 502.000012 -61.68009)
					(mid 501.707119 -62.387195)
					(end 501.000014 -62.680088)
				)
				(arc
					(start 480.480116 -62.680088)
					(mid 479.773011 -62.972981)
					(end 479.480118 -63.680086)
				)
				(arc
					(start 479.480118 -66.879978)
					(mid 479.187225 -67.587083)
					(end 478.48012 -67.879976)
				)
				(arc
					(start 428.209964 -67.879976)
					(mid 427.502859 -68.172869)
					(end 427.209966 -68.879974)
				)
				(arc
					(start 427.209966 -108.879894)
					(mid 427.502859 -109.586999)
					(end 428.209964 -109.879892)
				)
				(arc
					(start 501.000014 -109.879892)
					(mid 501.707119 -110.172785)
					(end 502.000012 -110.87989)
				)
				(arc
					(start 502.000012 -158.100014)
					(mid 501.707119 -158.807119)
					(end 501.000014 -159.100012)
				)
				(xy 342.52535 -159.100012) (xy 342.52535 -130.16611) (xy 326.247506 -130.16611) (xy 326.247506 -119.823992)
				(xy 353.579938 -119.823992) (xy 353.579938 -118.000018) (xy 358.68737 -118.000018) (xy 358.68737 -33.1978)
				(xy 326.247506 -33.1978) (xy 326.247506 -22.930104) (xy 342.325452 -22.930104)
			)
		)
	)
	(zone
		(layer "F.Cu")
		(hatch none 0.5)
		(connect_pads
			(clearance 0)
		)
		(min_thickness 0.25)
		(keepout
			(tracks allowed)
			(vias allowed)
			(pads allowed)
			(copperpour allowed)
			(footprints allowed)
		)
		(placement
			(enabled no)
			(sheetname "")
		)
		(fill
			(thermal_gap 0.5)
			(thermal_bridge_width 0.5)
			(island_removal_mode 0)
		)
		(polygon
			(pts
				(xy 71.600568 -29.591) (xy 71.600568 -27.559) (xy 73.759568 -27.559) (xy 73.759568 -29.591)
			)
		)
	)
	(zone
		(layer "F.Cu")
		(hatch none 0.5)
		(connect_pads
			(clearance 0)
		)
		(min_thickness 0.25)
		(keepout
			(tracks allowed)
			(vias allowed)
			(pads allowed)
			(copperpour allowed)
			(footprints allowed)
		)
		(placement
			(enabled no)
			(sheetname "")
		)
		(fill
			(thermal_gap 0.5)
			(thermal_bridge_width 0.5)
			(island_removal_mode 0)
		)
		(polygon
			(pts
				(xy 341.853266 -79.322676) (xy 341.853266 -77.036676) (xy 343.859866 -77.036676) (xy 343.859866 -79.322676)
			)
		)
	)
	(zone
		(layer "F.Cu")
		(hatch none 0.5)
		(connect_pads
			(clearance 0)
		)
		(min_thickness 0.25)
		(keepout
			(tracks not_allowed)
			(vias allowed)
			(pads allowed)
			(copperpour not_allowed)
			(footprints allowed)
		)
		(placement
			(enabled no)
			(sheetname "")
		)
		(fill
			(thermal_gap 0.5)
			(thermal_bridge_width 0.5)
			(island_removal_mode 0)
		)
		(polygon
			(pts
				(arc
					(start 83.000088 -43.450002)
					(mid 81.100168 -41.550082)
					(end 83.000088 -39.649908)
				)
				(arc
					(start 83.000088 -39.649908)
					(mid 84.900262 -41.550082)
					(end 83.000088 -43.450002)
				)
			)
		)
	)
	(zone
		(layer "F.Cu")
		(hatch none 0.5)
		(connect_pads
			(clearance 0)
		)
		(min_thickness 0.25)
		(keepout
			(tracks allowed)
			(vias allowed)
			(pads allowed)
			(copperpour allowed)
			(footprints not_allowed)
		)
		(placement
			(enabled no)
			(sheetname "")
		)
		(fill
			(thermal_gap 0.5)
			(thermal_bridge_width 0.5)
			(island_removal_mode 0)
		)
		(polygon
			(pts
				(xy 177.42535 -22.919182)
				(arc
					(start 177.42535 -1.50622)
					(mid 176.493849 -1.874594)
					(end 175.50003 -1.999996)
				)
				(xy 173.624494 -1.999996) (xy 173.624494 -22.919182)
			)
		)
	)
	(zone
		(layer "F.Cu")
		(hatch none 0.5)
		(connect_pads
			(clearance 0)
		)
		(min_thickness 0.25)
		(keepout
			(tracks allowed)
			(vias allowed)
			(pads allowed)
			(copperpour allowed)
			(footprints allowed)
		)
		(placement
			(enabled no)
			(sheetname "")
		)
		(fill
			(thermal_gap 0.5)
			(thermal_bridge_width 0.5)
			(island_removal_mode 0)
		)
		(polygon
			(pts
				(xy 347.314266 -79.322676) (xy 347.314266 -77.036676) (xy 349.320866 -77.036676) (xy 349.320866 -79.322676)
			)
		)
	)
	(zone
		(layer "F.Cu")
		(hatch none 0.5)
		(connect_pads
			(clearance 0)
		)
		(min_thickness 0.25)
		(keepout
			(tracks not_allowed)
			(vias allowed)
			(pads allowed)
			(copperpour not_allowed)
			(footprints allowed)
		)
		(placement
			(enabled no)
			(sheetname "")
		)
		(fill
			(thermal_gap 0.5)
			(thermal_bridge_width 0.5)
			(island_removal_mode 0)
		)
		(polygon
			(pts
				(arc
					(start 13.434314 -23.050754)
					(mid 13.050901 -22.66696)
					(end 12.667234 -23.0505)
				)
				(arc
					(start 12.667234 -24.3205)
					(mid 13.050774 -24.70404)
					(end 13.434314 -24.3205)
				)
				(xy 13.434314 -23.894034) (xy 13.175996 -23.894034) (xy 13.120624 -23.949406)
				(arc
					(start 13.120624 -24.063198)
					(mid 13.050774 -24.587115)
					(end 12.980924 -24.063198)
				)
				(xy 12.980924 -23.891494) (xy 13.118084 -23.754334) (xy 13.434314 -23.754334) (xy 13.434314 -23.616666)
				(xy 13.118084 -23.616666) (xy 12.980924 -23.479506)
				(arc
					(start 12.980924 -23.307802)
					(mid 13.050774 -22.783885)
					(end 13.120624 -23.307802)
				)
				(xy 13.120624 -23.421594) (xy 13.175996 -23.476966) (xy 13.434314 -23.476966)
			)
		)
	)
	(zone
		(layer "F.Cu")
		(hatch none 0.5)
		(connect_pads
			(clearance 0)
		)
		(min_thickness 0.25)
		(keepout
			(tracks allowed)
			(vias allowed)
			(pads allowed)
			(copperpour allowed)
			(footprints allowed)
		)
		(placement
			(enabled no)
			(sheetname "")
		)
		(fill
			(thermal_gap 0.5)
			(thermal_bridge_width 0.5)
			(island_removal_mode 0)
		)
		(polygon
			(pts
				(xy 246.253 -101.981) (xy 246.253 -99.9236) (xy 246.253 -98.552) (xy 240.665 -98.552) (xy 240.665 -98.7044)
				(xy 240.665 -101.981) (xy 240.665 -102.489) (xy 243.332 -102.489) (xy 243.84 -102.997) (xy 244.475 -102.997)
				(xy 245.11 -103.632) (xy 245.237 -103.632) (xy 246.126 -102.743) (xy 246.253 -102.743) (xy 246.253 -102.235)
			)
		)
	)
	(zone
		(layer "F.Cu")
		(hatch none 0.5)
		(connect_pads
			(clearance 0)
		)
		(min_thickness 0.25)
		(keepout
			(tracks allowed)
			(vias allowed)
			(pads allowed)
			(copperpour allowed)
			(footprints not_allowed)
		)
		(placement
			(enabled no)
			(sheetname "")
		)
		(fill
			(thermal_gap 0.5)
			(thermal_bridge_width 0.5)
			(island_removal_mode 0)
		)
		(polygon
			(pts
				(xy 6.999986 5.999988) (xy 14.524736 5.999988) (xy 14.524736 -5.500116) (xy 9.624568 -5.500116)
				(xy 9.624568 -13.999972) (xy -5.999988 -13.999972) (xy -5.999988 -6.999986) (xy 6.999986 -6.999986)
			)
		)
	)
	(zone
		(net "VR_PVSA_CPU1_PHASE_SW")
		(layer "F.Cu")
		(hatch none 0.5)
		(connect_pads
			(clearance 0.5)
		)
		(min_thickness 0.25)
		(fill yes
			(thermal_gap 0.5)
			(thermal_bridge_width 0.5)
			(island_removal_mode 0)
		)
		(polygon
			(pts
				(xy 36.449 -100.295202) (xy 40.303196 -100.295202) (xy 41.563798 -100.295202) (xy 41.9608 -99.8982)
				(xy 41.9608 -95.7326) (xy 41.443402 -95.215202) (xy 40.303196 -95.215202) (xy 36.449 -95.215202)
			)
		)
	)
	(zone
		(net "PVDDQ_DEF")
		(layer "F.Cu")
		(hatch none 0.5)
		(connect_pads
			(clearance 0.5)
		)
		(min_thickness 0.25)
		(fill yes
			(thermal_gap 0.5)
			(thermal_bridge_width 0.5)
			(island_removal_mode 0)
		)
		(polygon
			(pts
				(xy 277.35403 -155.83535) (xy 277.529036 -155.660344) (xy 277.529036 -153.43251) (xy 277.408386 -153.31186)
				(xy 265.8618 -153.31186) (xy 265.678158 -153.495502) (xy 265.678158 -155.561792) (xy 265.951716 -155.83535)
			)
		)
	)
	(zone
		(net "PVSA_CPU0")
		(layer "F.Cu")
		(hatch none 0.5)
		(connect_pads
			(clearance 0.5)
		)
		(min_thickness 0.25)
		(fill yes
			(thermal_gap 0.5)
			(thermal_bridge_width 0.5)
			(island_removal_mode 0)
		)
		(polygon
			(pts
				(xy 257.748024 -81.112614) (xy 257.748024 -82.763614) (xy 258.192524 -83.208114) (xy 259.705094 -83.208114)
				(xy 260.756146 -84.259166) (xy 262.49122 -84.259166) (xy 262.49122 -83.41106) (xy 261.746492 -83.41106)
				(xy 261.721346 -83.385914) (xy 261.721346 -83.180936) (xy 261.487412 -82.947002) (xy 261.487412 -81.770474)
				(xy 260.829552 -81.112614)
			)
		)
		(polygon
			(pts
				(xy 261.180072 -81.916016) (xy 260.976872 -81.916016) (xy 260.976872 -82.119216) (xy 261.180072 -82.119216)
			)
		)
		(polygon
			(pts
				(xy 260.418072 -81.916016) (xy 260.214872 -81.916016) (xy 260.214872 -82.119216) (xy 260.418072 -82.119216)
			)
		)
		(polygon
			(pts
				(xy 259.935472 -81.916016) (xy 259.732272 -81.916016) (xy 259.732272 -82.119216) (xy 259.935472 -82.119216)
			)
		)
		(polygon
			(pts
				(xy 259.173472 -81.916016) (xy 258.970272 -81.916016) (xy 258.970272 -82.119216) (xy 259.173472 -82.119216)
			)
		)
		(polygon
			(pts
				(xy 258.690872 -81.903316) (xy 258.487672 -81.903316) (xy 258.487672 -82.106516) (xy 258.690872 -82.106516)
			)
		)
	)
	(zone
		(layer "F.Cu")
		(hatch none 0.5)
		(connect_pads
			(clearance 0)
		)
		(min_thickness 0.25)
		(keepout
			(tracks not_allowed)
			(vias allowed)
			(pads allowed)
			(copperpour not_allowed)
			(footprints allowed)
		)
		(placement
			(enabled no)
			(sheetname "")
		)
		(fill
			(thermal_gap 0.5)
			(thermal_bridge_width 0.5)
			(island_removal_mode 0)
		)
		(polygon
			(pts
				(arc
					(start 433.300378 -114.596926)
					(mid 431.700432 -112.99698)
					(end 430.100486 -114.596926)
				)
				(arc
					(start 430.100486 -116.196872)
					(mid 431.700432 -117.796818)
					(end 433.300378 -116.196872)
				)
			)
		)
	)
	(zone
		(layer "F.Cu")
		(hatch none 0.5)
		(connect_pads
			(clearance 0)
		)
		(min_thickness 0.25)
		(keepout
			(tracks allowed)
			(vias allowed)
			(pads allowed)
			(copperpour allowed)
			(footprints not_allowed)
		)
		(placement
			(enabled no)
			(sheetname "")
		)
		(fill
			(thermal_gap 0.5)
			(thermal_bridge_width 0.5)
			(island_removal_mode 0)
		)
		(polygon
			(pts
				(arc
					(start 369.48999 -89.490042)
					(mid 365.899954 -85.900006)
					(end 369.48999 -82.30997)
				)
				(arc
					(start 369.48999 -82.30997)
					(mid 373.080026 -85.900006)
					(end 369.48999 -89.490042)
				)
			)
		)
	)
	(zone
		(layer "F.Cu")
		(hatch none 0.5)
		(connect_pads
			(clearance 0)
		)
		(min_thickness 0.25)
		(keepout
			(tracks not_allowed)
			(vias allowed)
			(pads allowed)
			(copperpour not_allowed)
			(footprints allowed)
		)
		(placement
			(enabled no)
			(sheetname "")
		)
		(fill
			(thermal_gap 0.5)
			(thermal_bridge_width 0.5)
			(island_removal_mode 0)
		)
		(polygon
			(pts
				(arc
					(start 0 2.830068)
					(mid 2.830068 0)
					(end 0 -2.830068)
				)
				(arc
					(start 0 -2.830068)
					(mid -2.830068 0)
					(end 0 2.830068)
				)
			)
		)
	)
	(zone
		(net "PVNN_PCH_STBY")
		(layer "F.Cu")
		(hatch none 0.5)
		(connect_pads
			(clearance 0.5)
		)
		(min_thickness 0.25)
		(fill yes
			(thermal_gap 0.5)
			(thermal_bridge_width 0.5)
			(island_removal_mode 0)
		)
		(polygon
			(pts
				(xy 381.635 -111.692944) (xy 381.635 -110.630208) (xy 381.648716 -110.616492) (xy 381.72009 -110.545118)
				(xy 382.030478 -110.545118) (xy 382.219962 -110.734602) (xy 382.608582 -110.734602) (xy 382.753616 -110.589568)
				(xy 382.753616 -109.835442) (xy 382.40081 -109.482636) (xy 381.70231 -109.482636) (xy 381.635 -109.415326)
				(xy 381.635 -106.299) (xy 381.51562 -106.17962) (xy 381.51562 -105.47858) (xy 381.69088 -105.30332)
				(xy 382.04902 -105.30332) (xy 382.4859 -105.7402) (xy 384.2512 -105.7402) (xy 386.207 -107.696)
				(xy 386.207 -111.185706) (xy 385.445 -111.947706) (xy 385.445 -112.005364) (xy 385.097782 -112.352582)
				(xy 382.294638 -112.352582)
			)
		)
	)
	(zone
		(net "VR_PVDDQ_DEF_PH2_SW")
		(layer "F.Cu")
		(hatch none 0.5)
		(connect_pads
			(clearance 0.5)
		)
		(min_thickness 0.25)
		(fill yes
			(thermal_gap 0.5)
			(thermal_bridge_width 0.5)
			(island_removal_mode 0)
		)
		(polygon
			(pts
				(xy 339.471 -144.918176) (xy 339.471 -148.844) (xy 339.852 -149.225) (xy 343.808812 -149.225) (xy 344.805 -148.228812)
				(xy 344.89898 -148.134832) (xy 344.89898 -143.134842) (xy 344.79103 -143.026892) (xy 342.850978 -143.026892)
				(xy 342.72347 -143.1544) (xy 342.632792 -143.245078) (xy 342.632792 -143.95831) (xy 342.025478 -144.565624)
				(xy 339.823552 -144.565624)
			)
		)
	)
	(zone
		(net "GND")
		(layer "F.Cu")
		(hatch none 0.5)
		(connect_pads
			(clearance 0.5)
		)
		(min_thickness 0.25)
		(fill yes
			(thermal_gap 0.5)
			(thermal_bridge_width 0.5)
			(island_removal_mode 0)
		)
		(polygon
			(pts
				(xy -4.8006 -43.2308) (xy -5.4102 -43.8404) (xy -5.4102 -44.3738) (xy -5.4864 -44.45) (xy -5.4864 -66.4972)
				(xy -5.4864 -86.7156) (xy -4.8768 -87.3252) (xy 1.2954 -87.3252) (xy 2.2352 -86.3854) (xy 2.2352 -79.502)
				(xy -0.889 -76.3778) (xy -0.889 -69.85) (xy 0.508 -68.453) (xy 0.508 -67.3354) (xy 0.508 -66.8782)
				(xy 0.508 -60.325) (xy 1.778 -59.055) (xy 1.778 -58.293) (xy 1.778 -56.7182) (xy 1.778 -49.7332)
				(xy 2.3876 -49.1236) (xy 2.8448 -48.6664) (xy 12.3444 -48.6664) (xy 13.4112 -47.5996) (xy 13.4112 -43.6118)
				(xy 13.1064 -43.307) (xy 13.0302 -43.2308) (xy 11.9634 -43.2308)
			)
		)
	)
	(zone
		(net "PVDDQ_GHJ")
		(layer "F.Cu")
		(hatch none 0.5)
		(connect_pads
			(clearance 0.5)
		)
		(min_thickness 0.25)
		(fill yes
			(thermal_gap 0.5)
			(thermal_bridge_width 0.5)
			(island_removal_mode 0)
		)
		(polygon
			(pts
				(xy 100.810568 0.3048) (xy 112.240568 0.3048) (xy 112.494568 0.5588) (xy 112.494568 2.3876) (xy 112.164368 2.7178)
				(xy 101.623368 2.7178) (xy 100.632768 1.7272) (xy 100.632768 0.4826)
			)
		)
	)
	(zone
		(layer "F.Cu")
		(hatch none 0.5)
		(connect_pads
			(clearance 0)
		)
		(min_thickness 0.25)
		(keepout
			(tracks allowed)
			(vias allowed)
			(pads allowed)
			(copperpour allowed)
			(footprints allowed)
		)
		(placement
			(enabled no)
			(sheetname "")
		)
		(fill
			(thermal_gap 0.5)
			(thermal_bridge_width 0.5)
			(island_removal_mode 0)
		)
		(polygon
			(pts
				(xy -0.635 -124.079) (xy 2.032 -124.079) (xy 2.032 -125.476) (xy -0.635 -125.476)
			)
		)
	)
	(zone
		(net "AGND_PVPP_ABC")
		(layer "F.Cu")
		(hatch none 0.5)
		(connect_pads
			(clearance 0.5)
		)
		(min_thickness 0.25)
		(fill yes
			(thermal_gap 0.5)
			(thermal_bridge_width 0.5)
			(island_removal_mode 0)
		)
		(polygon
			(pts
				(xy 345.1098 -26.1493) (xy 345.6178 -26.1493) (xy 345.7448 -26.0223) (xy 345.7448 -25.2857) (xy 346.202 -24.8285)
				(xy 346.202 -24.0919) (xy 346.0496 -23.9395) (xy 345.948 -23.9395) (xy 345.8464 -23.9395) (xy 345.694 -23.9395)
				(xy 345.5416 -24.0919) (xy 345.5416 -24.7015) (xy 345.3765 -24.8666) (xy 344.9828 -25.2603) (xy 344.9828 -26.0223)
			)
		)
	)
	(zone
		(layer "F.Cu")
		(hatch none 0.5)
		(connect_pads
			(clearance 0)
		)
		(min_thickness 0.25)
		(keepout
			(tracks allowed)
			(vias allowed)
			(pads allowed)
			(copperpour allowed)
			(footprints allowed)
		)
		(placement
			(enabled no)
			(sheetname "")
		)
		(fill
			(thermal_gap 0.5)
			(thermal_bridge_width 0.5)
			(island_removal_mode 0)
		)
		(polygon
			(pts
				(xy 29.083 -74.3966) (xy 29.083 -71.12) (xy 31.242 -71.12) (xy 31.242 -74.676) (xy 31.242 -75.311)
				(xy 27.686 -75.311) (xy 27.686 -74.3966)
			)
		)
	)
	(zone
		(layer "F.Cu")
		(hatch none 0.5)
		(connect_pads
			(clearance 0)
		)
		(min_thickness 0.25)
		(keepout
			(tracks allowed)
			(vias allowed)
			(pads allowed)
			(copperpour allowed)
			(footprints allowed)
		)
		(placement
			(enabled no)
			(sheetname "")
		)
		(fill
			(thermal_gap 0.5)
			(thermal_bridge_width 0.5)
			(island_removal_mode 0)
		)
		(polygon
			(pts
				(xy 178.6636 -80.5434) (xy 179.07 -80.5434) (xy 179.197 -80.4164) (xy 179.197 -78.7654) (xy 179.0954 -78.6638)
				(xy 178.689 -78.6638) (xy 178.4858 -78.867) (xy 178.4858 -80.3656)
			)
		)
	)
	(zone
		(layer "F.Cu")
		(hatch none 0.5)
		(connect_pads
			(clearance 0)
		)
		(min_thickness 0.25)
		(keepout
			(tracks not_allowed)
			(vias allowed)
			(pads allowed)
			(copperpour not_allowed)
			(footprints allowed)
		)
		(placement
			(enabled no)
			(sheetname "")
		)
		(fill
			(thermal_gap 0.5)
			(thermal_bridge_width 0.5)
			(island_removal_mode 0)
		)
		(polygon
			(pts
				(xy 444.92037 -123.53163) (xy 444.92037 -123.710192) (xy 444.645542 -123.98502)
				(arc
					(start 444.579502 -123.98502)
					(mid 444.055585 -123.91517)
					(end 444.579502 -123.84532)
				)
				(xy 444.58763 -123.84532) (xy 444.78067 -123.65228) (xy 444.78067 -123.53163)
				(arc
					(start 444.322454 -123.53163)
					(mid 443.93866 -123.915043)
					(end 444.3222 -124.29871)
				)
				(arc
					(start 445.5922 -124.29871)
					(mid 445.97574 -123.91517)
					(end 445.5922 -123.53163)
				)
				(xy 445.16167 -123.53163) (xy 445.16167 -123.657868)
				(arc
					(start 445.337946 -123.834398)
					(mid 445.858844 -123.920342)
					(end 445.334898 -123.98502)
				)
				(xy 445.29121 -123.98502) (xy 445.02197 -123.71578) (xy 445.02197 -123.53163)
			)
		)
	)
	(zone
		(layer "F.Cu")
		(hatch none 0.5)
		(connect_pads
			(clearance 0)
		)
		(min_thickness 0.25)
		(keepout
			(tracks allowed)
			(vias allowed)
			(pads allowed)
			(copperpour allowed)
			(footprints allowed)
		)
		(placement
			(enabled no)
			(sheetname "")
		)
		(fill
			(thermal_gap 0.5)
			(thermal_bridge_width 0.5)
			(island_removal_mode 0)
		)
		(polygon
			(pts
				(xy 323.902324 -116.7511) (xy 321.2592 -116.7511) (xy 321.2592 -114.334798) (xy 323.902324 -114.334798)
			)
		)
	)
	(zone
		(net "VR_FET_SW_P12V_STBY_PVCCIN_CPU0")
		(layer "F.Cu")
		(hatch none 0.5)
		(connect_pads
			(clearance 0.5)
		)
		(min_thickness 0.25)
		(fill yes
			(thermal_gap 0.5)
			(thermal_bridge_width 0.5)
			(island_removal_mode 0)
		)
		(polygon
			(pts
				(xy 177.930556 -50.504852) (xy 177.7238 -50.711354) (xy 177.7238 -53.7972) (xy 177.8762 -53.9496)
				(xy 179.6288 -53.9496) (xy 179.705 -53.8734) (xy 179.705 -52.6288) (xy 179.9082 -52.4256) (xy 180.6956 -52.4256)
				(xy 181.1274 -51.9938) (xy 181.5846 -51.9938) (xy 181.737 -51.8414) (xy 181.737 -51.3334) (xy 181.864 -51.2064)
				(xy 183.0197 -51.2064) (xy 184.4929 -52.6796) (xy 184.4929 -54.1909) (xy 184.4929 -55.5879) (xy 184.49036 -55.59044)
				(xy 184.49036 -55.630064) (xy 183.1086 -57.011824) (xy 183.1086 -57.6707) (xy 182.5625 -58.2168)
				(xy 181.0893 -58.2168) (xy 180.7083 -58.5978) (xy 177.8 -58.5978) (xy 177.0634 -59.3344) (xy 175.351186 -59.3344)
				(xy 175.311816 -59.37377) (xy 175.311816 -60.533788) (xy 175.321976 -60.543948) (xy 175.321976 -60.74537)
				(xy 175.435006 -60.8584) (xy 175.636428 -60.8584) (xy 181.7116 -60.8584) (xy 182.372 -60.198) (xy 182.372 -59.4614)
				(xy 182.5498 -59.2836) (xy 186.861958 -59.2836) (xy 187.036964 -59.458606) (xy 187.036964 -59.655456)
				(xy 187.380372 -59.998864) (xy 187.461144 -60.079636) (xy 188.6204 -60.079636) (xy 189.535054 -60.079636)
				(xy 189.9412 -59.67349) (xy 189.9412 -58.758836) (xy 189.9412 -57.7088) (xy 190.8302 -56.8198) (xy 190.8302 -54.6608)
				(xy 190.1952 -54.0258) (xy 188.3029 -54.0258) (xy 187.833 -53.5559) (xy 187.833 -51.2191) (xy 186.9821 -50.3682)
				(xy 179.560728 -50.3682) (xy 179.447698 -50.48123) (xy 177.954178 -50.48123)
			)
		)
	)
	(zone
		(layer "F.Cu")
		(hatch none 0.5)
		(connect_pads
			(clearance 0)
		)
		(min_thickness 0.25)
		(keepout
			(tracks allowed)
			(vias allowed)
			(pads allowed)
			(copperpour allowed)
			(footprints allowed)
		)
		(placement
			(enabled no)
			(sheetname "")
		)
		(fill
			(thermal_gap 0.5)
			(thermal_bridge_width 0.5)
			(island_removal_mode 0)
		)
		(polygon
			(pts
				(xy 67.827144 -98.44024) (xy 68.730622 -98.44024) (xy 69.206618 -98.916236) (xy 70.201282 -98.916236)
				(xy 71.710804 -100.425758) (xy 72.579992 -100.425758) (xy 72.614028 -100.45954) (xy 72.616568 -100.457)
				(xy 73.759568 -100.457) (xy 73.759568 -101.854) (xy 73.259696 -101.854) (xy 67.663568 -101.854)
				(xy 67.536568 -101.727) (xy 67.536568 -98.806) (xy 67.618356 -98.724212) (xy 67.618356 -98.649028)
			)
		)
	)
	(zone
		(layer "F.Cu")
		(hatch none 0.5)
		(connect_pads
			(clearance 0)
		)
		(min_thickness 0.25)
		(keepout
			(tracks not_allowed)
			(vias allowed)
			(pads allowed)
			(copperpour not_allowed)
			(footprints allowed)
		)
		(placement
			(enabled no)
			(sheetname "")
		)
		(fill
			(thermal_gap 0.5)
			(thermal_bridge_width 0.5)
			(island_removal_mode 0)
		)
		(polygon
			(pts
				(xy 375.8184 -128.64465)
				(arc
					(start 375.8184 -128.765046)
					(mid 375.76125 -129.292447)
					(end 375.7041 -128.765046)
				)
				(arc
					(start 375.7041 -128.648968)
					(mid 375.381121 -129.054305)
					(end 375.76125 -129.40665)
				)
				(arc
					(start 376.42165 -129.40665)
					(mid 376.782897 -129.146735)
					(end 376.651266 -128.721612)
				)
				(xy 376.651266 -128.876806) (xy 376.649996 -128.87833)
				(arc
					(start 376.64898 -128.88595)
					(mid 376.243038 -129.223874)
					(end 376.536966 -128.785112)
				)
				(arc
					(start 376.536966 -128.716278)
					(mid 376.532852 -128.686006)
					(end 376.520964 -128.657858)
				)
				(arc
					(start 376.520964 -128.657858)
					(mid 376.471744 -128.64796)
					(end 376.42165 -128.64465)
				)
			)
		)
	)
	(zone
		(net "GND")
		(layer "F.Cu")
		(hatch none 0.5)
		(connect_pads
			(clearance 0.5)
		)
		(min_thickness 0.25)
		(fill yes
			(thermal_gap 0.5)
			(thermal_bridge_width 0.5)
			(island_removal_mode 0)
		)
		(polygon
			(pts
				(xy 423.796714 -136.361678) (xy 423.796714 -134.329424) (xy 422.881552 -133.414262) (xy 417.808918 -133.414262)
				(xy 416.811714 -132.417058) (xy 416.40252 -132.417058) (xy 414.404302 -132.417058) (xy 414.359852 -132.461508)
				(xy 414.359852 -133.02742) (xy 414.399222 -133.06679) (xy 415.787586 -133.06679) (xy 415.863024 -132.991352)
				(xy 416.343592 -132.991352) (xy 416.696144 -133.343904) (xy 416.696144 -134.229602) (xy 416.67684 -134.248906)
				(xy 414.900618 -136.025128) (xy 413.14243 -136.025128) (xy 412.921196 -135.803894) (xy 412.921196 -135.40994)
				(xy 412.895542 -135.384286) (xy 412.321248 -135.384286) (xy 412.27248 -135.335518) (xy 411.549596 -135.335518)
				(xy 411.531054 -135.35406) (xy 411.531054 -136.217914) (xy 411.624526 -136.311386) (xy 418.848032 -136.311386)
				(xy 420.13632 -137.599674) (xy 422.952418 -137.599674) (xy 423.069512 -137.48258) (xy 423.069512 -137.08888)
			)
		)
	)
	(zone
		(layer "F.Cu")
		(hatch none 0.5)
		(connect_pads
			(clearance 0)
		)
		(min_thickness 0.25)
		(keepout
			(tracks allowed)
			(vias allowed)
			(pads allowed)
			(copperpour allowed)
			(footprints allowed)
		)
		(placement
			(enabled no)
			(sheetname "")
		)
		(fill
			(thermal_gap 0.5)
			(thermal_bridge_width 0.5)
			(island_removal_mode 0)
		)
		(polygon
			(pts
				(xy 271.0942 -49.657) (xy 271.0942 -53.0098) (xy 272.6944 -54.61) (xy 274.701 -54.61) (xy 276.1488 -53.1622)
				(xy 276.606 -53.1622) (xy 277.876 -54.4322) (xy 279.9588 -54.4322) (xy 281.559 -52.832) (xy 281.559 -50.038)
				(xy 281.557476 -49.657)
			)
		)
	)
	(zone
		(layer "F.Cu")
		(hatch none 0.5)
		(connect_pads
			(clearance 0)
		)
		(min_thickness 0.25)
		(keepout
			(tracks allowed)
			(vias allowed)
			(pads allowed)
			(copperpour allowed)
			(footprints allowed)
		)
		(placement
			(enabled no)
			(sheetname "")
		)
		(fill
			(thermal_gap 0.5)
			(thermal_bridge_width 0.5)
			(island_removal_mode 0)
		)
		(polygon
			(pts
				(xy 82.395568 -102.235) (xy 85.824568 -102.235) (xy 85.824568 -102.362) (xy 85.824568 -104.775)
				(xy 85.824568 -105.029) (xy 85.824568 -105.537) (xy 80.998568 -110.363) (xy 80.998568 -110.998)
				(xy 80.363568 -111.633) (xy 80.236568 -111.633) (xy 75.918568 -107.315) (xy 75.918568 -106.045)
				(xy 78.077568 -106.045) (xy 81.252568 -102.87) (xy 81.379568 -102.743) (xy 82.395568 -102.743)
			)
		)
	)
	(zone
		(layer "F.Cu")
		(hatch none 0.5)
		(connect_pads
			(clearance 0)
		)
		(min_thickness 0.25)
		(keepout
			(tracks not_allowed)
			(vias allowed)
			(pads allowed)
			(copperpour not_allowed)
			(footprints allowed)
		)
		(placement
			(enabled no)
			(sheetname "")
		)
		(fill
			(thermal_gap 0.5)
			(thermal_bridge_width 0.5)
			(island_removal_mode 0)
		)
		(polygon
			(pts
				(xy 395.664944 -107.347512) (xy 395.616176 -107.329478) (xy 395.594078 -107.282234) (xy 395.612112 -107.233466)
				(arc
					(start 395.89583 -107.10164)
					(mid 396.220255 -106.790012)
					(end 396.365984 -107.215432)
				)
				(arc
					(start 396.474696 -107.215432)
					(mid 396.463821 -106.863908)
					(end 396.15745 -106.691176)
				)
				(arc
					(start 395.16685 -106.691176)
					(mid 394.883108 -106.830787)
					(end 394.820648 -107.140756)
				)
				(arc
					(start 394.90523 -107.10164)
					(mid 395.408228 -106.936409)
					(end 394.958316 -107.215432)
				)
				(arc
					(start 394.87348 -107.254802)
					(mid 395.001486 -107.367035)
					(end 395.16685 -107.407456)
				)
				(arc
					(start 396.157196 -107.407456)
					(mid 396.341551 -107.356515)
					(end 396.473426 -107.217972)
				)
				(arc
					(start 396.363952 -107.217972)
					(mid 396.15745 -107.315939)
					(end 395.950948 -107.217972)
				)
				(xy 395.948662 -107.217972) (xy 395.948662 -107.215686)
			)
		)
	)
	(zone
		(net "PVDDQ_KLM")
		(layer "F.Cu")
		(hatch none 0.5)
		(connect_pads
			(clearance 0.5)
		)
		(min_thickness 0.25)
		(fill yes
			(thermal_gap 0.5)
			(thermal_bridge_width 0.5)
			(island_removal_mode 0)
		)
		(polygon
			(pts
				(xy 93.038168 -138.7348) (xy 92.83446 -138.938508) (xy 92.83446 -141.4399) (xy 92.89542 -141.50086)
				(xy 94.4245 -141.50086) (xy 94.96552 -140.95984) (xy 94.96552 -139.0015) (xy 94.69882 -138.7348)
			)
		)
		(polygon
			(pts
				(xy 93.685868 -140.6017) (xy 93.482668 -140.6017) (xy 93.482668 -140.8049) (xy 93.685868 -140.8049)
			)
		)
		(polygon
			(pts
				(xy 93.685868 -139.6111) (xy 93.482668 -139.6111) (xy 93.482668 -139.8143) (xy 93.685868 -139.8143)
			)
		)
	)
	(zone
		(layer "F.Cu")
		(hatch none 0.5)
		(connect_pads
			(clearance 0)
		)
		(min_thickness 0.25)
		(keepout
			(tracks allowed)
			(vias allowed)
			(pads allowed)
			(copperpour allowed)
			(footprints not_allowed)
		)
		(placement
			(enabled no)
			(sheetname "")
		)
		(fill
			(thermal_gap 0.5)
			(thermal_bridge_width 0.5)
			(island_removal_mode 0)
		)
		(polygon
			(pts
				(arc
					(start 4.629912 -43.710098)
					(mid 6.229858 -45.310044)
					(end 4.629912 -46.90999)
				)
				(arc
					(start 4.629912 -46.90999)
					(mid 3.029966 -45.310044)
					(end 4.629912 -43.710098)
				)
			)
		)
	)
	(zone
		(net "P1V8_MCP_CPU1")
		(layer "F.Cu")
		(hatch none 0.5)
		(connect_pads
			(clearance 0.5)
		)
		(min_thickness 0.25)
		(fill yes
			(thermal_gap 0.5)
			(thermal_bridge_width 0.5)
			(island_removal_mode 0)
		)
		(polygon
			(pts
				(xy 118.274592 -81.874106) (xy 115.988592 -81.874106) (xy 115.861592 -81.747106) (xy 115.861592 -80.985106)
				(xy 115.988592 -80.858106) (xy 117.45849 -80.858106) (xy 118.274338 -80.042258) (xy 118.274338 -78.699868)
				(xy 118.782592 -78.191614) (xy 120.687592 -78.191614) (xy 120.814592 -78.318614) (xy 121.043192 -78.547214)
				(xy 121.043192 -79.868014) (xy 120.814592 -80.096614) (xy 120.687592 -80.223614) (xy 120.687592 -81.366614)
				(xy 120.1801 -81.874106)
			)
		)
		(polygon
			(pts
				(arc
					(start 120.246902 -78.688438)
					(mid 119.611902 -78.688438)
					(end 120.246902 -78.688438)
				)
			)
		)
		(polygon
			(pts
				(arc
					(start 120.246902 -79.678784)
					(mid 119.611902 -79.678784)
					(end 120.246902 -79.678784)
				)
			)
		)
		(polygon
			(pts
				(arc
					(start 120.246902 -80.669384)
					(mid 119.611902 -80.669384)
					(end 120.246902 -80.669384)
				)
			)
		)
	)
	(zone
		(layer "F.Cu")
		(hatch none 0.5)
		(connect_pads
			(clearance 0)
		)
		(min_thickness 0.25)
		(keepout
			(tracks allowed)
			(vias allowed)
			(pads allowed)
			(copperpour allowed)
			(footprints allowed)
		)
		(placement
			(enabled no)
			(sheetname "")
		)
		(fill
			(thermal_gap 0.5)
			(thermal_bridge_width 0.5)
			(island_removal_mode 0)
		)
		(polygon
			(pts
				(xy 355.3968 -140.081) (xy 355.3968 -138.6078) (xy 357.1748 -138.6078) (xy 357.1748 -140.081)
			)
		)
	)
	(zone
		(layer "F.Cu")
		(hatch none 0.5)
		(connect_pads
			(clearance 0)
		)
		(min_thickness 0.25)
		(keepout
			(tracks allowed)
			(vias allowed)
			(pads allowed)
			(copperpour allowed)
			(footprints allowed)
		)
		(placement
			(enabled no)
			(sheetname "")
		)
		(fill
			(thermal_gap 0.5)
			(thermal_bridge_width 0.5)
			(island_removal_mode 0)
		)
		(polygon
			(pts
				(xy 188.3664 -73.8124) (xy 187.325 -73.8124) (xy 187.0456 -74.0918) (xy 185.227976 -74.0918) (xy 184.824624 -74.495152)
				(xy 184.06872 -74.495152) (xy 184.06872 -74.486516) (xy 183.674004 -74.0918) (xy 181.9402 -74.0918)
				(xy 181.5846 -73.7362) (xy 181.5846 -73.6346) (xy 180.4797 -72.5297) (xy 179.9463 -72.5297) (xy 179.4256 -72.009)
				(xy 179.4256 -69.342) (xy 180.2638 -68.5038) (xy 180.2638 -67.9704) (xy 180.6448 -67.5894) (xy 181.5338 -67.5894)
				(xy 181.5338 -66.421) (xy 182.3085 -65.6463) (xy 182.2958 -65.6336) (xy 182.2958 -65.2526) (xy 182.5371 -65.0113)
				(xy 185.5851 -65.0113) (xy 186.2582 -64.3382) (xy 187.198 -64.3382) (xy 187.6298 -64.77) (xy 187.6298 -67.818)
				(xy 189.992 -67.818) (xy 190.119 -67.945) (xy 190.119 -68.961) (xy 189.0268 -68.961) (xy 188.6458 -69.342)
				(xy 188.6458 -73.533)
			)
		)
	)
	(zone
		(layer "F.Cu")
		(hatch none 0.5)
		(connect_pads
			(clearance 0)
		)
		(min_thickness 0.25)
		(keepout
			(tracks allowed)
			(vias allowed)
			(pads allowed)
			(copperpour allowed)
			(footprints allowed)
		)
		(placement
			(enabled no)
			(sheetname "")
		)
		(fill
			(thermal_gap 0.5)
			(thermal_bridge_width 0.5)
			(island_removal_mode 0)
		)
		(polygon
			(pts
				(xy 195.326 -77.47) (xy 198.882 -77.47) (xy 199.136 -77.724) (xy 199.136 -79.248) (xy 198.755 -79.629)
				(xy 196.977 -79.629) (xy 196.85 -79.756) (xy 196.85 -82.296) (xy 196.723 -82.423) (xy 195.072 -82.423)
				(xy 194.818 -82.169) (xy 194.31 -81.661) (xy 194.31 -77.978) (xy 194.818 -77.47)
			)
		)
	)
	(zone
		(net "VR_PVCCIN_CPU1_VD12")
		(layer "F.Cu")
		(hatch none 0.5)
		(connect_pads
			(clearance 0.5)
		)
		(min_thickness 0.25)
		(fill yes
			(thermal_gap 0.5)
			(thermal_bridge_width 0.5)
			(island_removal_mode 0)
		)
		(polygon
			(pts
				(xy 13.74775 -97.282) (xy 14.859 -97.282) (xy 14.8971 -97.2439) (xy 14.8971 -97.0788) (xy 14.9352 -97.0407)
				(xy 15.1765 -96.7994) (xy 15.240762 -96.735138) (xy 16.015462 -96.735138) (xy 17.0434 -95.7072)
				(xy 17.272 -95.7072) (xy 17.3228 -95.6564) (xy 17.3228 -95.123) (xy 17.2212 -95.0214) (xy 16.745458 -95.0214)
				(xy 15.831058 -95.9358) (xy 15.5702 -95.9358) (xy 13.5128 -95.9358) (xy 12.5984 -95.9358) (xy 12.337796 -96.196404)
				(xy 12.337796 -97.02165) (xy 12.598146 -97.282) (xy 13.39469 -97.282) (xy 13.462 -97.282) (xy 13.7414 -97.282)
				(xy 13.744448 -97.285048)
			)
		)
	)
	(zone
		(layer "F.Cu")
		(hatch none 0.5)
		(connect_pads
			(clearance 0)
		)
		(min_thickness 0.25)
		(keepout
			(tracks allowed)
			(vias allowed)
			(pads allowed)
			(copperpour allowed)
			(footprints allowed)
		)
		(placement
			(enabled no)
			(sheetname "")
		)
		(fill
			(thermal_gap 0.5)
			(thermal_bridge_width 0.5)
			(island_removal_mode 0)
		)
		(polygon
			(pts
				(xy 387.1849 -67.46494) (xy 387.1849 -63.55334) (xy 392.89736 -63.55334) (xy 392.89736 -67.46494)
			)
		)
	)
	(zone
		(layer "F.Cu")
		(hatch none 0.5)
		(connect_pads
			(clearance 0)
		)
		(min_thickness 0.25)
		(keepout
			(tracks not_allowed)
			(vias allowed)
			(pads allowed)
			(copperpour not_allowed)
			(footprints allowed)
		)
		(placement
			(enabled no)
			(sheetname "")
		)
		(fill
			(thermal_gap 0.5)
			(thermal_bridge_width 0.5)
			(island_removal_mode 0)
		)
		(polygon
			(pts
				(arc
					(start 11.84275 -32.197802)
					(mid 11.9126 -31.673885)
					(end 11.98245 -32.197802)
				)
				(xy 11.98245 -32.311594) (xy 12.055856 -32.385) (xy 12.29614 -32.385)
				(arc
					(start 12.29614 -31.940754)
					(mid 11.912727 -31.55696)
					(end 11.52906 -31.9405)
				)
				(arc
					(start 11.52906 -33.2105)
					(mid 11.9126 -33.59404)
					(end 12.29614 -33.2105)
				)
				(xy 12.29614 -32.766) (xy 12.055856 -32.766) (xy 11.98245 -32.839406)
				(arc
					(start 11.98245 -32.953198)
					(mid 11.9126 -33.477115)
					(end 11.84275 -32.953198)
				)
				(xy 11.84275 -32.781494) (xy 11.997944 -32.6263) (xy 12.29614 -32.6263) (xy 12.29614 -32.5247) (xy 11.997944 -32.5247)
				(xy 11.84275 -32.369506)
			)
		)
	)
	(zone
		(layer "F.Cu")
		(hatch none 0.5)
		(connect_pads
			(clearance 0)
		)
		(min_thickness 0.25)
		(keepout
			(tracks allowed)
			(vias allowed)
			(pads allowed)
			(copperpour allowed)
			(footprints not_allowed)
		)
		(placement
			(enabled no)
			(sheetname "")
		)
		(fill
			(thermal_gap 0.5)
			(thermal_bridge_width 0.5)
			(island_removal_mode 0)
		)
		(polygon
			(pts
				(xy 407.696924 -140.800074) (xy 407.696924 -159.100012) (xy 452.390002 -159.100012) (xy 452.390002 -142.328392)
				(xy 434.85689 -142.328392) (xy 434.85689 -141.590268) (xy 418.999924 -141.590268) (xy 418.999924 -137.329926)
				(xy 414.98012 -137.329926) (xy 414.98012 -140.800074)
			)
		)
	)
	(zone
		(layer "F.Cu")
		(hatch none 0.5)
		(connect_pads
			(clearance 0)
		)
		(min_thickness 0.25)
		(keepout
			(tracks allowed)
			(vias allowed)
			(pads allowed)
			(copperpour allowed)
			(footprints allowed)
		)
		(placement
			(enabled no)
			(sheetname "")
		)
		(fill
			(thermal_gap 0.5)
			(thermal_bridge_width 0.5)
			(island_removal_mode 0)
		)
		(polygon
			(pts
				(xy 125.575568 -100.711) (xy 126.845568 -100.711) (xy 126.845568 -101.346) (xy 124.813568 -103.378)
				(xy 122.781568 -103.378) (xy 122.527568 -103.124) (xy 122.400568 -103.124) (xy 122.400568 -102.616)
				(xy 123.797568 -101.219) (xy 125.067568 -101.219)
			)
		)
	)
	(zone
		(layer "F.Cu")
		(hatch none 0.5)
		(connect_pads
			(clearance 0)
		)
		(min_thickness 0.25)
		(keepout
			(tracks allowed)
			(vias allowed)
			(pads allowed)
			(copperpour allowed)
			(footprints not_allowed)
		)
		(placement
			(enabled no)
			(sheetname "")
		)
		(fill
			(thermal_gap 0.5)
			(thermal_bridge_width 0.5)
			(island_removal_mode 0)
		)
		(polygon
			(pts
				(arc
					(start 357.000048 0.499872)
					(mid 355.499924 1.999996)
					(end 357.000048 3.499866)
				)
				(arc
					(start 357.671624 3.499866)
					(mid 358.338295 3.61425)
					(end 358.92867 3.944366)
				)
				(arc
					(start 358.92867 3.944366)
					(mid 363.000204 2.000076)
					(end 358.92867 0.055372)
				)
				(arc
					(start 358.92867 0.055372)
					(mid 358.338274 0.385429)
					(end 357.671624 0.499872)
				)
			)
		)
	)
	(zone
		(layer "F.Cu")
		(hatch none 0.5)
		(connect_pads
			(clearance 0)
		)
		(min_thickness 0.25)
		(keepout
			(tracks allowed)
			(vias allowed)
			(pads allowed)
			(copperpour allowed)
			(footprints allowed)
		)
		(placement
			(enabled no)
			(sheetname "")
		)
		(fill
			(thermal_gap 0.5)
			(thermal_bridge_width 0.5)
			(island_removal_mode 0)
		)
		(polygon
			(pts
				(xy 270.764 -102.743) (xy 270.764 -106.172) (xy 251.587 -106.172) (xy 251.587 -102.743)
			)
		)
	)
	(zone
		(net "P1V05_PCH_STBY")
		(layer "F.Cu")
		(hatch none 0.5)
		(connect_pads
			(clearance 0.5)
		)
		(min_thickness 0.25)
		(fill yes
			(thermal_gap 0.5)
			(thermal_bridge_width 0.5)
			(island_removal_mode 0)
		)
		(polygon
			(pts
				(xy 386.223256 -139.030964) (xy 386.00888 -139.24534) (xy 386.00888 -142.14856) (xy 387.16712 -143.3068)
				(xy 389.509 -143.3068) (xy 389.8646 -143.6624) (xy 389.8646 -147.9804) (xy 389.9154 -148.0312) (xy 393.5476 -148.0312)
				(xy 394.028676 -147.550124) (xy 394.887958 -147.550124) (xy 395.021054 -147.417028) (xy 395.021054 -145.001996)
				(xy 394.96492 -144.945862) (xy 394.96492 -139.843256) (xy 394.152628 -139.030964)
			)
		)
		(polygon
			(pts
				(xy 394.2334 -146.5326) (xy 394.0302 -146.5326) (xy 394.0302 -146.7358) (xy 394.2334 -146.7358)
			)
		)
		(polygon
			(pts
				(xy 386.963666 -141.750796) (xy 386.760466 -141.750796) (xy 386.760466 -141.953996) (xy 386.963666 -141.953996)
			)
		)
		(polygon
			(pts
				(xy 386.963666 -140.988796) (xy 386.760466 -140.988796) (xy 386.760466 -141.191996) (xy 386.963666 -141.191996)
			)
		)
		(polygon
			(pts
				(xy 386.99948 -140.42644) (xy 386.79628 -140.42644) (xy 386.79628 -140.62964) (xy 386.99948 -140.62964)
			)
		)
		(polygon
			(pts
				(xy 386.99948 -139.66444) (xy 386.79628 -139.66444) (xy 386.79628 -139.86764) (xy 386.99948 -139.86764)
			)
		)
	)
	(zone
		(layer "F.Cu")
		(hatch none 0.5)
		(connect_pads
			(clearance 0)
		)
		(min_thickness 0.25)
		(keepout
			(tracks not_allowed)
			(vias allowed)
			(pads allowed)
			(copperpour not_allowed)
			(footprints allowed)
		)
		(placement
			(enabled no)
			(sheetname "")
		)
		(fill
			(thermal_gap 0.5)
			(thermal_bridge_width 0.5)
			(island_removal_mode 0)
		)
		(polygon
			(pts
				(arc
					(start 428.10049 -114.596926)
					(mid 431.700432 -110.996984)
					(end 435.300374 -114.596926)
				)
				(arc
					(start 435.300374 -116.196872)
					(mid 431.700432 -119.796814)
					(end 428.10049 -116.196872)
				)
			)
		)
	)
	(zone
		(layer "F.Cu")
		(hatch none 0.5)
		(connect_pads
			(clearance 0)
		)
		(min_thickness 0.25)
		(keepout
			(tracks allowed)
			(vias allowed)
			(pads allowed)
			(copperpour allowed)
			(footprints not_allowed)
		)
		(placement
			(enabled no)
			(sheetname "")
		)
		(fill
			(thermal_gap 0.5)
			(thermal_bridge_width 0.5)
			(island_removal_mode 0)
		)
		(polygon
			(pts
				(xy 19.524726 -22.919182) (xy 19.524726 5.999988) (xy 14.524736 5.999988) (xy 14.524736 -5.500116)
				(xy 9.624568 -5.500116) (xy 9.624568 -19.119088) (xy 14.524736 -19.119088) (xy 14.524736 -22.919182)
			)
		)
	)
	(zone
		(net "PVDDQ_GHJ")
		(layer "F.Cu")
		(hatch none 0.5)
		(connect_pads
			(clearance 0.5)
		)
		(min_thickness 0.25)
		(fill yes
			(thermal_gap 0.5)
			(thermal_bridge_width 0.5)
			(island_removal_mode 0)
		)
		(polygon
			(pts
				(xy 100.840794 -11.455146) (xy 100.7872 -11.50874) (xy 100.7872 -12.0396) (xy 101.013768 -12.266168)
				(xy 101.013768 -12.8524) (xy 101.318568 -13.1572) (xy 101.318568 -14.0208) (xy 101.677724 -14.379956)
				(xy 112.440212 -14.379956) (xy 113.078768 -13.7414) (xy 113.078768 -12.0142) (xy 112.519714 -11.455146)
			)
		)
		(polygon
			(pts
				(xy 110.657132 -13.3477) (xy 110.453932 -13.3477) (xy 110.453932 -13.5509) (xy 110.657132 -13.5509)
			)
		)
		(polygon
			(pts
				(xy 107.5182 -13.3477) (xy 107.315 -13.3477) (xy 107.315 -13.5509) (xy 107.5182 -13.5509)
			)
		)
		(polygon
			(pts
				(xy 104.2162 -13.3477) (xy 104.013 -13.3477) (xy 104.013 -13.5509) (xy 104.2162 -13.5509)
			)
		)
		(polygon
			(pts
				(xy 107.5182 -12.3571) (xy 107.315 -12.3571) (xy 107.315 -12.5603) (xy 107.5182 -12.5603)
			)
		)
		(polygon
			(pts
				(xy 104.2162 -12.3571) (xy 104.013 -12.3571) (xy 104.013 -12.5603) (xy 104.2162 -12.5603)
			)
		)
	)
	(zone
		(layer "F.Cu")
		(hatch none 0.5)
		(connect_pads
			(clearance 0)
		)
		(min_thickness 0.25)
		(keepout
			(tracks allowed)
			(vias allowed)
			(pads allowed)
			(copperpour allowed)
			(footprints allowed)
		)
		(placement
			(enabled no)
			(sheetname "")
		)
		(fill
			(thermal_gap 0.5)
			(thermal_bridge_width 0.5)
			(island_removal_mode 0)
		)
		(polygon
			(pts
				(xy 245.872 -52.2224) (xy 250.9266 -52.2224) (xy 251.1806 -51.9684) (xy 251.1806 -49.911) (xy 245.872 -49.911)
			)
		)
	)
	(zone
		(layer "F.Cu")
		(hatch none 0.5)
		(connect_pads
			(clearance 0)
		)
		(min_thickness 0.25)
		(keepout
			(tracks allowed)
			(vias allowed)
			(pads allowed)
			(copperpour allowed)
			(footprints allowed)
		)
		(placement
			(enabled no)
			(sheetname "")
		)
		(fill
			(thermal_gap 0.5)
			(thermal_bridge_width 0.5)
			(island_removal_mode 0)
		)
		(polygon
			(pts
				(xy 388.112 -154.178) (xy 388.112 -153.543) (xy 389.128 -153.543) (xy 389.128 -154.178)
			)
		)
	)
	(zone
		(net "GND")
		(layer "F.Cu")
		(hatch none 0.5)
		(connect_pads
			(clearance 0.5)
		)
		(min_thickness 0.25)
		(fill yes
			(thermal_gap 0.5)
			(thermal_bridge_width 0.5)
			(island_removal_mode 0)
		)
		(polygon
			(pts
				(xy 454.621392 -40.192198) (xy 454.240392 -40.573198) (xy 454.240392 -43.087798) (xy 454.452482 -43.299888)
				(xy 456.746102 -43.299888) (xy 456.907392 -43.138598) (xy 456.907392 -40.242998) (xy 456.856592 -40.192198)
			)
		)
		(polygon
			(pts
				(xy 456.183492 -42.681398) (xy 455.980292 -42.681398) (xy 455.980292 -42.884598) (xy 456.183492 -42.884598)
			)
		)
		(polygon
			(pts
				(xy 456.183492 -41.919398) (xy 455.980292 -41.919398) (xy 455.980292 -42.122598) (xy 456.183492 -42.122598)
			)
		)
	)
	(zone
		(net "PVDDQ_GHJ")
		(layer "F.Cu")
		(hatch none 0.5)
		(connect_pads
			(clearance 0.5)
		)
		(min_thickness 0.25)
		(fill yes
			(thermal_gap 0.5)
			(thermal_bridge_width 0.5)
			(island_removal_mode 0)
		)
		(polygon
			(pts
				(xy 78.712568 2.667) (xy 93.444568 2.667) (xy 93.673168 2.4384) (xy 93.673168 0.5334) (xy 93.469968 0.3302)
				(xy 79.550768 0.3302) (xy 78.712568 1.1684)
			)
		)
	)
	(zone
		(layer "F.Cu")
		(hatch none 0.5)
		(connect_pads
			(clearance 0)
		)
		(min_thickness 0.25)
		(keepout
			(tracks allowed)
			(vias allowed)
			(pads allowed)
			(copperpour allowed)
			(footprints allowed)
		)
		(placement
			(enabled no)
			(sheetname "")
		)
		(fill
			(thermal_gap 0.5)
			(thermal_bridge_width 0.5)
			(island_removal_mode 0)
		)
		(polygon
			(pts
				(xy 72.159368 -44.977558) (xy 69.674232 -44.977558) (xy 69.585332 -44.888658) (xy 69.585332 -43.744134)
				(xy 69.453252 -43.612054) (xy 69.35978 -43.612054) (xy 67.994276 -44.977558) (xy 67.2465 -45.725334)
				(xy 64.688212 -48.283622) (xy 64.688212 -48.534574) (xy 64.764412 -48.610774) (xy 66.6369 -48.610774)
				(xy 67.2465 -49.220374) (xy 67.748912 -49.722786) (xy 69.42074 -49.722786) (xy 72.159368 -49.722786)
			)
		)
	)
	(zone
		(layer "F.Cu")
		(hatch none 0.5)
		(connect_pads
			(clearance 0)
		)
		(min_thickness 0.25)
		(keepout
			(tracks allowed)
			(vias allowed)
			(pads allowed)
			(copperpour allowed)
			(footprints allowed)
		)
		(placement
			(enabled no)
			(sheetname "")
		)
		(fill
			(thermal_gap 0.5)
			(thermal_bridge_width 0.5)
			(island_removal_mode 0)
		)
		(polygon
			(pts
				(xy 1.778 -148.7932) (xy 1.778 -144.4244) (xy 4.191 -144.4244) (xy 4.191 -148.7932)
			)
		)
	)
	(zone
		(net "P5V_SWITCH_G")
		(layer "F.Cu")
		(hatch none 0.5)
		(connect_pads
			(clearance 0.5)
		)
		(min_thickness 0.25)
		(fill yes
			(thermal_gap 0.5)
			(thermal_bridge_width 0.5)
			(island_removal_mode 0)
		)
		(polygon
			(pts
				(xy 436.35676 -126.73076) (xy 437.21909 -126.73076) (xy 437.252618 -126.764288) (xy 437.252618 -127.601726)
				(xy 437.214772 -127.639572) (xy 436.3212 -127.639572) (xy 436.244746 -127.563118) (xy 436.244746 -126.746254)
				(xy 436.26024 -126.73076)
			)
		)
	)
	(zone
		(layer "F.Cu")
		(hatch none 0.5)
		(connect_pads
			(clearance 0)
		)
		(min_thickness 0.25)
		(keepout
			(tracks allowed)
			(vias allowed)
			(pads allowed)
			(copperpour allowed)
			(footprints not_allowed)
		)
		(placement
			(enabled no)
			(sheetname "")
		)
		(fill
			(thermal_gap 0.5)
			(thermal_bridge_width 0.5)
			(island_removal_mode 0)
		)
		(polygon
			(pts
				(xy 213.547452 -22.919182) (xy 213.547452 -130.16611) (xy 326.247506 -130.16611) (xy 326.247506 -117.80012)
				(xy 213.74735 -117.80012) (xy 213.74735 -35.299904) (xy 326.247506 -35.299904) (xy 326.247506 -22.919182)
			)
		)
	)
	(zone
		(net "GND")
		(layer "F.Cu")
		(hatch none 0.5)
		(connect_pads
			(clearance 0.5)
		)
		(min_thickness 0.25)
		(fill yes
			(thermal_gap 0.5)
			(thermal_bridge_width 0.5)
			(island_removal_mode 0)
		)
		(polygon
			(pts
				(xy 193.1416 -52.5018) (xy 193.1416 -49.7586) (xy 192.7352 -49.3522) (xy 189.0776 -49.3522) (xy 188.6712 -49.3522)
				(xy 188.2394 -49.784) (xy 188.2394 -53.1114) (xy 188.722 -53.594) (xy 192.7098 -53.594) (xy 193.1416 -53.1622)
			)
		)
	)
	(zone
		(layer "F.Cu")
		(hatch none 0.5)
		(connect_pads
			(clearance 0)
		)
		(min_thickness 0.25)
		(keepout
			(tracks not_allowed)
			(vias allowed)
			(pads allowed)
			(copperpour not_allowed)
			(footprints allowed)
		)
		(placement
			(enabled no)
			(sheetname "")
		)
		(fill
			(thermal_gap 0.5)
			(thermal_bridge_width 0.5)
			(island_removal_mode 0)
		)
		(polygon
			(pts
				(xy 402.576792 -10.295636) (xy 403.084792 -10.295636) (xy 403.084792 -10.651236) (xy 402.576792 -10.651236)
			)
		)
	)
	(zone
		(net "PVDDQ_GHJ")
		(layer "F.Cu")
		(hatch none 0.5)
		(connect_pads
			(clearance 0.5)
		)
		(min_thickness 0.25)
		(fill yes
			(thermal_gap 0.5)
			(thermal_bridge_width 0.5)
			(island_removal_mode 0)
		)
		(polygon
			(pts
				(xy 78.839568 -9.271) (xy 93.571568 -9.271) (xy 93.698568 -9.144) (xy 93.698568 -7.112) (xy 93.571568 -6.985)
				(xy 78.712568 -6.985) (xy 78.585568 -7.112) (xy 78.585568 -9.017)
			)
		)
	)
	(zone
		(net "GND")
		(layer "F.Cu")
		(hatch none 0.5)
		(connect_pads
			(clearance 0.5)
		)
		(min_thickness 0.25)
		(fill yes
			(thermal_gap 0.5)
			(thermal_bridge_width 0.5)
			(island_removal_mode 0)
		)
		(polygon
			(pts
				(xy 175.9458 -121.8946) (xy 174.9298 -122.9106) (xy 173.9392 -123.9012) (xy 171.1198 -123.9012)
				(xy 170.561 -124.46) (xy 169.418 -124.46) (xy 168.276524 -124.46) (xy 167.087296 -123.270772) (xy 166.577772 -123.270772)
				(xy 166.37 -123.063) (xy 166.37 -122.7074) (xy 166.624 -122.4534) (xy 166.6748 -122.4026) (xy 168.4782 -122.4026)
				(xy 169.2148 -121.666) (xy 171.9072 -118.9736) (xy 172.212 -118.6688) (xy 175.9712 -118.6688) (xy 176.149 -118.8466)
				(xy 176.149 -121.6914)
			)
		)
	)
	(zone
		(net "GND")
		(layer "F.Cu")
		(hatch none 0.5)
		(connect_pads
			(clearance 0.5)
		)
		(min_thickness 0.25)
		(fill yes
			(thermal_gap 0.5)
			(thermal_bridge_width 0.5)
			(island_removal_mode 0)
		)
		(polygon
			(pts
				(xy 7.001764 -127.393192) (xy 7.501128 -127.393192) (xy 7.944612 -126.949708) (xy 7.944612 -124.3965)
				(xy 7.458456 -123.910344) (xy 6.68655 -123.910344) (xy 6.547104 -124.04979) (xy 6.547104 -124.275596)
				(xy 6.987032 -124.715524) (xy 6.987032 -127.37846)
			)
		)
	)
	(zone
		(net "GND")
		(layer "F.Cu")
		(hatch none 0.5)
		(connect_pads
			(clearance 0.5)
		)
		(min_thickness 0.25)
		(fill yes
			(thermal_gap 0.5)
			(thermal_bridge_width 0.5)
			(island_removal_mode 0)
		)
		(polygon
			(pts
				(xy 406.1968 -116.5352) (xy 406.146 -116.586) (xy 406.146 -118.618) (xy 406.1968 -118.6688) (xy 407.038302 -118.6688)
				(xy 407.740612 -117.96649) (xy 407.740612 -117.334284) (xy 406.941528 -116.5352)
			)
		)
		(polygon
			(pts
				(xy 407.1366 -117.2464) (xy 406.9334 -117.2464) (xy 406.9334 -117.4496) (xy 407.1366 -117.4496)
			)
		)
		(polygon
			(pts
				(xy 407.1366 -117.7544) (xy 406.9334 -117.7544) (xy 406.9334 -117.9576) (xy 407.1366 -117.9576)
			)
		)
	)
	(zone
		(net "GND")
		(layer "F.Cu")
		(hatch none 0.5)
		(connect_pads
			(clearance 0.5)
		)
		(min_thickness 0.25)
		(fill yes
			(thermal_gap 0.5)
			(thermal_bridge_width 0.5)
			(island_removal_mode 0)
		)
		(polygon
			(pts
				(xy 113.923826 -14.366748) (xy 113.32718 -13.770102) (xy 113.32718 -12.036044) (xy 113.89868 -11.464544)
				(xy 115.172236 -11.464544) (xy 115.573302 -11.464544) (xy 115.75034 -11.641582) (xy 115.75034 -12.042394)
				(xy 115.75034 -13.95349) (xy 115.336828 -14.366748)
			)
		)
	)
	(zone
		(layer "F.Cu")
		(hatch none 0.5)
		(connect_pads
			(clearance 0)
		)
		(min_thickness 0.25)
		(keepout
			(tracks not_allowed)
			(vias allowed)
			(pads allowed)
			(copperpour not_allowed)
			(footprints allowed)
		)
		(placement
			(enabled no)
			(sheetname "")
		)
		(fill
			(thermal_gap 0.5)
			(thermal_bridge_width 0.5)
			(island_removal_mode 0)
		)
		(polygon
			(pts
				(arc
					(start 457.308712 -49.927764)
					(mid 457.832629 -49.997614)
					(end 457.308712 -50.067464)
				)
				(xy 457.19492 -50.067464) (xy 457.121514 -50.14087) (xy 457.121514 -50.381154)
				(arc
					(start 457.56576 -50.381154)
					(mid 457.949554 -49.997741)
					(end 457.566014 -49.614074)
				)
				(arc
					(start 456.296014 -49.614074)
					(mid 455.912474 -49.997614)
					(end 456.296014 -50.381154)
				)
				(xy 456.740514 -50.381154) (xy 456.740514 -50.14087) (xy 456.667108 -50.067464)
				(arc
					(start 456.553316 -50.067464)
					(mid 456.029399 -49.997614)
					(end 456.553316 -49.927764)
				)
				(xy 456.72502 -49.927764) (xy 456.880214 -50.082958) (xy 456.880214 -50.381154) (xy 456.981814 -50.381154)
				(xy 456.981814 -50.082958) (xy 457.137008 -49.927764)
			)
		)
	)
	(zone
		(layer "F.Cu")
		(hatch none 0.5)
		(connect_pads
			(clearance 0)
		)
		(min_thickness 0.25)
		(keepout
			(tracks allowed)
			(vias allowed)
			(pads allowed)
			(copperpour allowed)
			(footprints allowed)
		)
		(placement
			(enabled no)
			(sheetname "")
		)
		(fill
			(thermal_gap 0.5)
			(thermal_bridge_width 0.5)
			(island_removal_mode 0)
		)
		(polygon
			(pts
				(xy 277.9268 -158.6484) (xy 277.9268 -158.242) (xy 279.6794 -158.242) (xy 279.6794 -158.6484)
			)
		)
	)
	(zone
		(net "GND")
		(layer "F.Cu")
		(hatch none 0.5)
		(connect_pads
			(clearance 0.5)
		)
		(min_thickness 0.25)
		(fill yes
			(thermal_gap 0.5)
			(thermal_bridge_width 0.5)
			(island_removal_mode 0)
		)
		(polygon
			(pts
				(xy 37.540438 -48.689006) (xy 37.536374 -48.689006) (xy 37.3126 -48.465232) (xy 37.3126 -47.91583)
				(xy 37.3126 -43.42511) (xy 37.78631 -42.9514) (xy 42.923714 -42.9514) (xy 44.095416 -42.9514) (xy 44.51096 -43.366944)
				(xy 44.51096 -48.387508) (xy 44.51096 -48.876458) (xy 44.156122 -49.231296) (xy 38.483286 -49.231296)
				(xy 38.321488 -49.069498) (xy 38.20795 -49.069498) (xy 38.206172 -49.071276) (xy 37.922708 -49.071276)
			)
		)
	)
	(zone
		(layer "F.Cu")
		(hatch none 0.5)
		(connect_pads
			(clearance 0)
		)
		(min_thickness 0.25)
		(keepout
			(tracks allowed)
			(vias allowed)
			(pads allowed)
			(copperpour allowed)
			(footprints allowed)
		)
		(placement
			(enabled no)
			(sheetname "")
		)
		(fill
			(thermal_gap 0.5)
			(thermal_bridge_width 0.5)
			(island_removal_mode 0)
		)
		(polygon
			(pts
				(xy 341.63 -130.683) (xy 341.63 -132.461) (xy 341.609172 -132.461) (xy 341.609172 -132.73151) (xy 341.470996 -132.869686)
				(xy 339.942678 -132.869686) (xy 339.511386 -132.438394) (xy 339.511386 -130.687064) (xy 339.511386 -130.191256)
				(xy 339.296248 -129.976118) (xy 338.87791 -129.976118) (xy 338.796884 -129.895092) (xy 338.796884 -128.883156)
				(xy 338.858098 -128.821942) (xy 340.039198 -128.821942) (xy 340.708742 -129.491486) (xy 342.777826 -129.491486)
				(xy 342.915748 -129.629408) (xy 342.93175 -129.629408) (xy 342.947498 -129.645156) (xy 342.947498 -130.323844)
				(xy 342.87333 -130.398012) (xy 341.645748 -130.398012) (xy 341.63 -130.41376)
			)
		)
	)
	(zone
		(layer "F.Cu")
		(hatch none 0.5)
		(connect_pads
			(clearance 0)
		)
		(min_thickness 0.25)
		(keepout
			(tracks allowed)
			(vias allowed)
			(pads allowed)
			(copperpour allowed)
			(footprints allowed)
		)
		(placement
			(enabled no)
			(sheetname "")
		)
		(fill
			(thermal_gap 0.5)
			(thermal_bridge_width 0.5)
			(island_removal_mode 0)
		)
		(polygon
			(pts
				(xy 80.871568 -49.911) (xy 80.871568 -52.2224) (xy 79.626968 -53.467) (xy 77.493368 -53.467) (xy 76.223368 -52.197)
				(xy 76.223368 -50.9778) (xy 75.791568 -50.546) (xy 75.791568 -49.911) (xy 76.172568 -49.911) (xy 76.223368 -49.911)
			)
		)
	)
	(zone
		(net "GND")
		(layer "F.Cu")
		(hatch none 0.5)
		(connect_pads
			(clearance 0.5)
		)
		(min_thickness 0.25)
		(fill yes
			(thermal_gap 0.5)
			(thermal_bridge_width 0.5)
			(island_removal_mode 0)
		)
		(polygon
			(pts
				(xy 256.396236 -18.923) (xy 257.937 -18.923) (xy 258.024376 -18.835624) (xy 258.024376 -18.270982)
				(xy 257.927856 -18.174462) (xy 257.927856 -18.170652) (xy 257.537204 -17.78) (xy 256.667 -17.78)
				(xy 256.413 -17.526) (xy 256.413 -17.196308) (xy 256.338832 -17.12214) (xy 256.337816 -17.12214)
				(xy 256.319782 -17.104106) (xy 243.669566 -17.104106) (xy 243.651532 -17.12214) (xy 243.614194 -17.159732)
				(xy 243.614194 -17.388078) (xy 243.419376 -17.582896) (xy 243.377974 -17.624298) (xy 242.913916 -17.624298)
				(xy 242.824 -17.714214) (xy 242.824 -19.05) (xy 242.824 -20.8534) (xy 242.9002 -20.9296) (xy 243.4336 -20.9296)
				(xy 243.4844 -20.8788) (xy 243.4844 -18.8976) (xy 244.094 -18.288) (xy 244.3226 -18.288) (xy 255.651 -18.288)
				(xy 255.761236 -18.288) (xy 256.136648 -18.288) (xy 256.258568 -18.40992) (xy 256.258568 -18.785332)
			)
		)
	)
	(zone
		(layer "F.Cu")
		(hatch none 0.5)
		(connect_pads
			(clearance 0)
		)
		(min_thickness 0.25)
		(keepout
			(tracks not_allowed)
			(vias allowed)
			(pads allowed)
			(copperpour not_allowed)
			(footprints allowed)
		)
		(placement
			(enabled no)
			(sheetname "")
		)
		(fill
			(thermal_gap 0.5)
			(thermal_bridge_width 0.5)
			(island_removal_mode 0)
		)
		(polygon
			(pts
				(xy 459.349094 -114.020092) (xy 459.349094 -114.344958) (xy 459.22057 -114.473482)
				(arc
					(start 459.022196 -114.473482)
					(mid 458.498279 -114.403632)
					(end 459.022196 -114.333782)
				)
				(xy 459.162658 -114.333782) (xy 459.209394 -114.287046) (xy 459.209394 -114.020092)
				(arc
					(start 458.765148 -114.020092)
					(mid 458.381354 -114.403505)
					(end 458.764894 -114.787172)
				)
				(arc
					(start 460.034894 -114.787172)
					(mid 460.418434 -114.403632)
					(end 460.034894 -114.020092)
				)
				(xy 459.590394 -114.020092) (xy 459.590394 -114.287046) (xy 459.63713 -114.333782)
				(arc
					(start 459.777592 -114.333782)
					(mid 460.301509 -114.403632)
					(end 459.777592 -114.473482)
				)
				(xy 459.579218 -114.473482) (xy 459.450694 -114.344958) (xy 459.450694 -114.020092)
			)
		)
	)
	(zone
		(net "PVDDQ_DEF")
		(layer "F.Cu")
		(hatch none 0.5)
		(connect_pads
			(clearance 0.5)
		)
		(min_thickness 0.25)
		(fill yes
			(thermal_gap 0.5)
			(thermal_bridge_width 0.5)
			(island_removal_mode 0)
		)
		(polygon
			(pts
				(xy 257.8608 -149.1488) (xy 257.6068 -149.1488) (xy 257.4544 -149.3012) (xy 257.4544 -150.241) (xy 257.5814 -150.368)
				(xy 257.8608 -150.368) (xy 257.932936 -150.368) (xy 258.17703 -150.612094) (xy 258.17703 -150.93823)
				(xy 258.318 -151.0792) (xy 258.4958 -151.0792) (xy 259.1308 -150.4442) (xy 259.186934 -150.388066)
				(xy 259.50926 -150.388066) (xy 259.516372 -150.380954) (xy 259.62229 -150.275036) (xy 259.62229 -149.100286)
				(xy 259.086604 -148.5646) (xy 258.684776 -148.5646) (xy 258.59359 -148.655786) (xy 258.59359 -148.889212)
				(xy 258.334002 -149.1488)
			)
		)
		(polygon
			(pts
				(xy 258.4069 -150.1267) (xy 258.2037 -150.1267) (xy 258.2037 -150.3299) (xy 258.4069 -150.3299)
			)
		)
	)
	(zone
		(layer "F.Cu")
		(hatch none 0.5)
		(connect_pads
			(clearance 0)
		)
		(min_thickness 0.25)
		(keepout
			(tracks not_allowed)
			(vias allowed)
			(pads allowed)
			(copperpour not_allowed)
			(footprints allowed)
		)
		(placement
			(enabled no)
			(sheetname "")
		)
		(fill
			(thermal_gap 0.5)
			(thermal_bridge_width 0.5)
			(island_removal_mode 0)
		)
		(polygon
			(pts
				(xy 395.321536 -3.50774) (xy 395.321536 -3.232658) (xy 395.49832 -3.055874)
				(arc
					(start 395.51229 -3.055874)
					(mid 396.035644 -3.108416)
					(end 395.523466 -3.22834)
				)
				(xy 395.461236 -3.29057) (xy 395.461236 -3.449828) (xy 395.520672 -3.509264)
				(arc
					(start 395.769592 -3.509264)
					(mid 396.153132 -3.125724)
					(end 395.769592 -2.742184)
				)
				(arc
					(start 394.753846 -2.742184)
					(mid 394.370052 -3.125597)
					(end 394.753592 -3.509264)
				)
				(xy 395.0208 -3.509264) (xy 395.080236 -3.449828) (xy 395.080236 -3.282442)
				(arc
					(start 395.00683 -3.209036)
					(mid 394.487094 -3.118693)
					(end 395.010894 -3.055874)
				)
				(xy 395.05128 -3.055874) (xy 395.219936 -3.22453) (xy 395.219936 -3.50774) (xy 395.218412 -3.509264)
				(xy 395.32306 -3.509264)
			)
		)
	)
	(zone
		(net "GND")
		(layer "F.Cu")
		(hatch none 0.5)
		(connect_pads
			(clearance 0.5)
		)
		(min_thickness 0.25)
		(fill yes
			(thermal_gap 0.5)
			(thermal_bridge_width 0.5)
			(island_removal_mode 0)
		)
		(polygon
			(pts
				(xy 452.776082 -136.396222) (xy 452.776082 -133.857746) (xy 452.865236 -133.768592) (xy 455.312018 -133.768592)
				(xy 455.441558 -133.768592) (xy 455.477118 -133.804152) (xy 455.477118 -136.818624) (xy 455.646028 -136.987534)
				(xy 458.518006 -136.987534) (xy 458.648562 -136.987534) (xy 458.74559 -137.084562) (xy 458.74559 -138.756644)
				(xy 458.549756 -138.952478) (xy 458.42936 -138.952478) (xy 455.95032 -138.952478) (xy 455.869294 -139.033504)
				(xy 452.475092 -139.033504) (xy 452.368412 -138.926824) (xy 452.368412 -137.230612) (xy 452.776082 -136.822942)
				(xy 452.82231 -136.776714) (xy 452.82231 -136.44245)
			)
		)
	)
	(zone
		(layer "F.Cu")
		(hatch none 0.5)
		(connect_pads
			(clearance 0)
		)
		(min_thickness 0.25)
		(keepout
			(tracks not_allowed)
			(vias allowed)
			(pads allowed)
			(copperpour not_allowed)
			(footprints allowed)
		)
		(placement
			(enabled no)
			(sheetname "")
		)
		(fill
			(thermal_gap 0.5)
			(thermal_bridge_width 0.5)
			(island_removal_mode 0)
		)
		(polygon
			(pts
				(xy 451.2564 -120.28043) (xy 451.2564 -120.578626) (xy 451.101206 -120.73382)
				(arc
					(start 450.929502 -120.73382)
					(mid 450.405585 -120.66397)
					(end 450.929502 -120.59412)
				)
				(xy 451.043294 -120.59412) (xy 451.1167 -120.520714) (xy 451.1167 -120.28043)
				(arc
					(start 450.672454 -120.28043)
					(mid 450.28866 -120.663843)
					(end 450.6722 -121.04751)
				)
				(arc
					(start 451.9422 -121.04751)
					(mid 452.32574 -120.66397)
					(end 451.9422 -120.28043)
				)
				(xy 451.4977 -120.28043) (xy 451.4977 -120.520714) (xy 451.571106 -120.59412)
				(arc
					(start 451.684898 -120.59412)
					(mid 452.208815 -120.66397)
					(end 451.684898 -120.73382)
				)
				(xy 451.513194 -120.73382) (xy 451.358 -120.578626) (xy 451.358 -120.28043)
			)
		)
	)
	(zone
		(layer "F.Cu")
		(hatch none 0.5)
		(connect_pads
			(clearance 0)
		)
		(min_thickness 0.25)
		(keepout
			(tracks allowed)
			(vias allowed)
			(pads allowed)
			(copperpour allowed)
			(footprints allowed)
		)
		(placement
			(enabled no)
			(sheetname "")
		)
		(fill
			(thermal_gap 0.5)
			(thermal_bridge_width 0.5)
			(island_removal_mode 0)
		)
		(polygon
			(pts
				(xy 169.0878 -77.0636) (xy 169.0878 -75.1586) (xy 173.5582 -75.1586) (xy 173.5582 -77.0636)
			)
		)
	)
	(zone
		(net "VR_FET_SW_P12V_STBY_PVPP_DEF")
		(layer "F.Cu")
		(hatch none 0.5)
		(connect_pads
			(clearance 0.5)
		)
		(min_thickness 0.25)
		(fill yes
			(thermal_gap 0.5)
			(thermal_bridge_width 0.5)
			(island_removal_mode 0)
		)
		(polygon
			(pts
				(xy 347.361256 -129.472944) (xy 347.1926 -129.6416) (xy 345.2114 -129.6416) (xy 345.186 -129.667)
				(xy 345.186 -130.5687) (xy 345.059 -130.6957) (xy 344.17 -130.6957) (xy 344.17 -132.2197) (xy 347.3323 -132.2197)
				(xy 347.98 -132.8674) (xy 347.98 -133.731) (xy 348.107 -133.858) (xy 348.678246 -133.858) (xy 348.809564 -133.726682)
				(xy 352.363532 -133.726682) (xy 352.3996 -133.690614) (xy 352.3996 -131.905756) (xy 352.301302 -131.807712)
				(xy 350.96069 -131.807712) (xy 350.959166 -131.806188) (xy 350.899476 -131.806188) (xy 350.648016 -131.554728)
				(xy 350.648016 -129.884678) (xy 350.588072 -129.824734) (xy 349.63735 -129.824734) (xy 349.28556 -129.472944)
			)
		)
		(polygon
			(pts
				(xy 348.7166 -133.2484) (xy 348.5134 -133.2484) (xy 348.5134 -133.4516) (xy 348.7166 -133.4516)
			)
		)
	)
	(zone
		(layer "F.Cu")
		(hatch none 0.5)
		(connect_pads
			(clearance 0)
		)
		(min_thickness 0.25)
		(keepout
			(tracks allowed)
			(vias allowed)
			(pads allowed)
			(copperpour allowed)
			(footprints not_allowed)
		)
		(placement
			(enabled no)
			(sheetname "")
		)
		(fill
			(thermal_gap 0.5)
			(thermal_bridge_width 0.5)
			(island_removal_mode 0)
		)
		(polygon
			(pts
				(xy 22.52472 -22.919182) (xy 22.52472 5.999988) (xy 19.524726 5.999988) (xy 19.524726 -22.919182)
			)
		)
	)
	(zone
		(layer "F.Cu")
		(hatch none 0.5)
		(connect_pads
			(clearance 0)
		)
		(min_thickness 0.25)
		(keepout
			(tracks not_allowed)
			(vias allowed)
			(pads allowed)
			(copperpour not_allowed)
			(footprints allowed)
		)
		(placement
			(enabled no)
			(sheetname "")
		)
		(fill
			(thermal_gap 0.5)
			(thermal_bridge_width 0.5)
			(island_removal_mode 0)
		)
		(polygon
			(pts
				(xy 366.734344 -3.320542) (xy 366.734344 -3.046476) (xy 366.913668 -2.867152)
				(arc
					(start 367.113058 -2.867152)
					(mid 367.636975 -2.937002)
					(end 367.113058 -3.006852)
				)
				(xy 366.97158 -3.006852) (xy 366.874044 -3.104388) (xy 366.874044 -3.320542)
				(arc
					(start 367.37036 -3.320542)
					(mid 367.7539 -2.937002)
					(end 367.37036 -2.553462)
				)
				(arc
					(start 366.100614 -2.553462)
					(mid 365.717074 -2.936875)
					(end 366.10036 -3.320542)
				)
				(xy 366.493044 -3.320542) (xy 366.493044 -3.080512) (xy 366.419384 -3.006852)
				(arc
					(start 366.357662 -3.006852)
					(mid 365.833745 -2.937002)
					(end 366.357662 -2.867152)
				)
				(xy 366.477296 -2.867152) (xy 366.632744 -3.0226) (xy 366.632744 -3.320542)
			)
		)
	)
	(zone
		(layer "F.Cu")
		(hatch none 0.5)
		(connect_pads
			(clearance 0)
		)
		(min_thickness 0.25)
		(keepout
			(tracks not_allowed)
			(vias allowed)
			(pads allowed)
			(copperpour not_allowed)
			(footprints allowed)
		)
		(placement
			(enabled no)
			(sheetname "")
		)
		(fill
			(thermal_gap 0.5)
			(thermal_bridge_width 0.5)
			(island_removal_mode 0)
		)
		(polygon
			(pts
				(xy 429.624236 -9.639808) (xy 429.624236 -9.86917) (xy 429.400208 -10.093198)
				(arc
					(start 429.288194 -10.093198)
					(mid 428.764277 -10.023348)
					(end 429.288194 -9.953498)
				)
				(xy 429.342296 -9.953498) (xy 429.484536 -9.811258) (xy 429.484536 -9.639808)
				(arc
					(start 429.031146 -9.639808)
					(mid 428.647352 -10.023221)
					(end 429.030892 -10.406888)
				)
				(arc
					(start 430.300892 -10.406888)
					(mid 430.684432 -10.023348)
					(end 430.300892 -9.639808)
				)
				(xy 429.865536 -9.639808) (xy 429.865536 -9.85393) (xy 429.965104 -9.953498)
				(arc
					(start 430.04359 -9.953498)
					(mid 430.567507 -10.023348)
					(end 430.04359 -10.093198)
				)
				(xy 429.907192 -10.093198) (xy 429.725836 -9.911842) (xy 429.725836 -9.639808)
			)
		)
	)
	(zone
		(layer "F.Cu")
		(hatch none 0.5)
		(connect_pads
			(clearance 0)
		)
		(min_thickness 0.25)
		(keepout
			(tracks allowed)
			(vias allowed)
			(pads allowed)
			(copperpour allowed)
			(footprints not_allowed)
		)
		(placement
			(enabled no)
			(sheetname "")
		)
		(fill
			(thermal_gap 0.5)
			(thermal_bridge_width 0.5)
			(island_removal_mode 0)
		)
		(polygon
			(pts
				(xy 326.247506 -33.1978) (xy 326.247506 -22.930104) (xy 342.325452 -22.930104) (xy 342.325452 5.999988)
				(arc
					(start -4.99999 5.999988)
					(mid -5.707095 5.707095)
					(end -5.999988 4.99999)
				)
				(arc
					(start -5.999988 -158.100014)
					(mid -5.707095 -158.807119)
					(end -4.99999 -159.100012)
				)
				(xy 342.52535 -159.100012) (xy 342.52535 -130.16611) (xy 326.247506 -130.16611) (xy 326.247506 -119.823992)
				(xy 353.579938 -119.823992) (xy 353.579938 -118.000018) (xy 358.68737 -118.000018) (xy 358.68737 -33.1978)
			)
		)
	)
	(zone
		(layer "F.Cu")
		(hatch none 0.5)
		(connect_pads
			(clearance 0)
		)
		(min_thickness 0.25)
		(keepout
			(tracks not_allowed)
			(vias allowed)
			(pads allowed)
			(copperpour not_allowed)
			(footprints allowed)
		)
		(placement
			(enabled no)
			(sheetname "")
		)
		(fill
			(thermal_gap 0.5)
			(thermal_bridge_width 0.5)
			(island_removal_mode 0)
		)
		(polygon
			(pts
				(xy 464.162648 -120.755918) (xy 464.162648 -120.947434) (xy 463.900774 -121.209308)
				(arc
					(start 463.88274 -121.209308)
					(mid 463.35921 -121.154746)
					(end 463.872834 -121.039636)
				)
				(xy 464.022948 -120.889522) (xy 464.022948 -120.755918)
				(arc
					(start 463.625692 -120.755918)
					(mid 463.241898 -121.139331)
					(end 463.625438 -121.522998)
				)
				(arc
					(start 464.811618 -121.522998)
					(mid 465.195158 -121.139458)
					(end 464.811618 -120.755918)
				)
				(xy 464.403948 -120.755918) (xy 464.403948 -120.884442)
				(arc
					(start 464.562952 -121.043446)
					(mid 465.07782 -121.153232)
					(end 464.554316 -121.209308)
				)
				(xy 464.531202 -121.209308) (xy 464.264248 -120.942354) (xy 464.264248 -120.755918)
			)
		)
	)
	(zone
		(net "PVDDQ_GHJ")
		(layer "F.Cu")
		(hatch none 0.5)
		(connect_pads
			(clearance 0.5)
		)
		(min_thickness 0.25)
		(fill yes
			(thermal_gap 0.5)
			(thermal_bridge_width 0.5)
			(island_removal_mode 0)
		)
		(polygon
			(pts
				(xy 18.657824 -0.838708) (xy 18.644616 -0.851916) (xy 18.644616 -1.783588) (xy 18.714466 -1.853438)
				(xy 18.714466 -3.882898) (xy 18.688558 -3.908806) (xy 18.688558 -5.219446) (xy 18.320004 -5.588)
				(xy 14.732 -5.588) (xy 14.478 -5.842) (xy 14.478 -20.701) (xy 14.986 -21.209) (xy 20.574 -21.209)
				(xy 21.609812 -20.173188) (xy 21.609812 -1.063244) (xy 21.385276 -0.838708)
			)
		)
	)
	(zone
		(net "AGND_PVPP_DEF")
		(layer "F.Cu")
		(hatch none 0.5)
		(connect_pads
			(clearance 0.5)
		)
		(min_thickness 0.25)
		(fill yes
			(thermal_gap 0.5)
			(thermal_bridge_width 0.5)
			(island_removal_mode 0)
		)
		(polygon
			(pts
				(xy 340.868 -126.9492) (xy 341.10295 -127.18415) (xy 341.10295 -127.638556) (xy 341.051642 -127.689864)
				(xy 338.709254 -127.689864) (xy 338.478114 -127.458724) (xy 338.478114 -126.722886) (xy 338.6328 -126.5682)
				(xy 340.0806 -126.5682) (xy 340.100158 -126.5682) (xy 340.11108 -126.5682) (xy 340.473538 -126.930658)
				(xy 340.849458 -126.930658)
			)
		)
	)
	(zone
		(layer "F.Cu")
		(hatch none 0.5)
		(connect_pads
			(clearance 0)
		)
		(min_thickness 0.25)
		(keepout
			(tracks allowed)
			(vias allowed)
			(pads allowed)
			(copperpour allowed)
			(footprints not_allowed)
		)
		(placement
			(enabled no)
			(sheetname "")
		)
		(fill
			(thermal_gap 0.5)
			(thermal_bridge_width 0.5)
			(island_removal_mode 0)
		)
		(polygon
			(pts
				(xy 453.990456 -154.610054) (xy 466.620098 -154.610054) (xy 466.620098 -159.100012) (xy 453.990456 -159.100012)
			)
		)
	)
	(zone
		(layer "F.Cu")
		(hatch none 0.5)
		(connect_pads
			(clearance 0)
		)
		(min_thickness 0.25)
		(keepout
			(tracks allowed)
			(vias allowed)
			(pads allowed)
			(copperpour allowed)
			(footprints allowed)
		)
		(placement
			(enabled no)
			(sheetname "")
		)
		(fill
			(thermal_gap 0.5)
			(thermal_bridge_width 0.5)
			(island_removal_mode 0)
		)
		(polygon
			(pts
				(xy 359.5116 -142.0622) (xy 359.5116 -140.3096) (xy 361.2388 -140.3096) (xy 361.2388 -142.0622)
			)
		)
	)
	(zone
		(layer "F.Cu")
		(hatch none 0.5)
		(connect_pads
			(clearance 0)
		)
		(min_thickness 0.25)
		(keepout
			(tracks allowed)
			(vias allowed)
			(pads allowed)
			(copperpour allowed)
			(footprints not_allowed)
		)
		(placement
			(enabled no)
			(sheetname "")
		)
		(fill
			(thermal_gap 0.5)
			(thermal_bridge_width 0.5)
			(island_removal_mode 0)
		)
		(polygon
			(pts
				(xy 111.300006 -67.300094) (xy 117.54993 -71.049896) (xy 117.54993 -82.049874) (xy 111.300006 -85.79993)
				(xy 98.700082 -85.79993) (xy 92.449904 -82.049874) (xy 92.449904 -71.049896) (xy 98.700082 -67.300094)
			)
		)
	)
	(zone
		(net "P12V_STBY")
		(layer "F.Cu")
		(hatch none 0.5)
		(connect_pads
			(clearance 0.5)
		)
		(min_thickness 0.25)
		(fill yes
			(thermal_gap 0.5)
			(thermal_bridge_width 0.5)
			(island_removal_mode 0)
		)
		(polygon
			(pts
				(xy 185.293 -17.018) (xy 185.293 -16.764) (xy 185.293 -16.42999) (xy 184.517538 -15.654528) (xy 184.517538 -14.633702)
				(xy 184.545224 -14.606016) (xy 186.674506 -14.606016) (xy 186.681618 -14.613128) (xy 186.926728 -14.858238)
				(xy 186.926728 -17.035272) (xy 186.926728 -17.473676) (xy 186.715654 -17.68475) (xy 185.518044 -17.68475)
				(xy 185.293 -17.459706)
			)
		)
	)
	(zone
		(layer "F.Cu")
		(hatch none 0.5)
		(connect_pads
			(clearance 0)
		)
		(min_thickness 0.25)
		(keepout
			(tracks not_allowed)
			(vias allowed)
			(pads allowed)
			(copperpour not_allowed)
			(footprints allowed)
		)
		(placement
			(enabled no)
			(sheetname "")
		)
		(fill
			(thermal_gap 0.5)
			(thermal_bridge_width 0.5)
			(island_removal_mode 0)
		)
		(polygon
			(pts
				(arc
					(start 477.800416 -60.59678)
					(mid 474.200474 -64.196722)
					(end 470.600532 -60.59678)
				)
				(arc
					(start 470.600532 -58.996834)
					(mid 474.200474 -55.396892)
					(end 477.800416 -58.996834)
				)
			)
		)
	)
	(zone
		(net "VR_FET_SW_P12V_STBY_PVDDQ_ABC")
		(layer "F.Cu")
		(hatch none 0.5)
		(connect_pads
			(clearance 0.5)
		)
		(min_thickness 0.25)
		(fill yes
			(thermal_gap 0.5)
			(thermal_bridge_width 0.5)
			(island_removal_mode 0)
		)
		(polygon
			(pts
				(xy 350.423988 5.513324) (xy 346.842334 5.513324) (xy 346.6846 5.35559) (xy 346.6846 4.4196) (xy 346.6846 2.0828)
				(xy 348.582996 2.0828) (xy 348.617032 2.116836) (xy 348.617032 3.429) (xy 348.820232 3.6322) (xy 349.7199 3.6322)
				(xy 349.95358 3.86588) (xy 350.44888 3.86588) (xy 350.556576 3.973576) (xy 350.628458 4.045458)
				(xy 350.628458 5.308854)
			)
		)
	)
	(zone
		(layer "F.Cu")
		(hatch none 0.5)
		(connect_pads
			(clearance 0)
		)
		(min_thickness 0.25)
		(keepout
			(tracks not_allowed)
			(vias allowed)
			(pads allowed)
			(copperpour not_allowed)
			(footprints allowed)
		)
		(placement
			(enabled no)
			(sheetname "")
		)
		(fill
			(thermal_gap 0.5)
			(thermal_bridge_width 0.5)
			(island_removal_mode 0)
		)
		(polygon
			(pts
				(xy 400.738086 -7.192772) (xy 401.004786 -7.192772) (xy 401.004786 -8.386572) (xy 400.738086 -8.386572)
			)
		)
	)
	(zone
		(layer "F.Cu")
		(hatch none 0.5)
		(connect_pads
			(clearance 0)
		)
		(min_thickness 0.25)
		(keepout
			(tracks not_allowed)
			(vias allowed)
			(pads allowed)
			(copperpour not_allowed)
			(footprints allowed)
		)
		(placement
			(enabled no)
			(sheetname "")
		)
		(fill
			(thermal_gap 0.5)
			(thermal_bridge_width 0.5)
			(island_removal_mode 0)
		)
		(polygon
			(pts
				(arc
					(start 467.867492 -26.919936)
					(mid 471.467688 -30.520132)
					(end 467.867492 -34.120074)
				)
				(arc
					(start 464.867498 -34.120074)
					(mid 461.267556 -30.520132)
					(end 464.867498 -26.919936)
				)
			)
		)
	)
	(zone
		(layer "F.Cu")
		(hatch none 0.5)
		(connect_pads
			(clearance 0)
		)
		(min_thickness 0.25)
		(keepout
			(tracks allowed)
			(vias allowed)
			(pads allowed)
			(copperpour allowed)
			(footprints allowed)
		)
		(placement
			(enabled no)
			(sheetname "")
		)
		(fill
			(thermal_gap 0.5)
			(thermal_bridge_width 0.5)
			(island_removal_mode 0)
		)
		(polygon
			(pts
				(xy -1.524 -130.81) (xy -1.524 -126.619) (xy 0.127 -124.968) (xy 2.032 -124.968) (xy 2.286 -124.714)
				(xy 2.286 -123.825) (xy 2.54 -123.571) (xy 4.318 -123.571) (xy 4.699 -123.952) (xy 4.699 -130.429)
				(xy 3.175 -131.953) (xy -0.381 -131.953)
			)
		)
	)
	(zone
		(layer "F.Cu")
		(hatch none 0.5)
		(connect_pads
			(clearance 0)
		)
		(min_thickness 0.25)
		(keepout
			(tracks allowed)
			(vias allowed)
			(pads allowed)
			(copperpour allowed)
			(footprints not_allowed)
		)
		(placement
			(enabled no)
			(sheetname "")
		)
		(fill
			(thermal_gap 0.5)
			(thermal_bridge_width 0.5)
			(island_removal_mode 0)
		)
		(polygon
			(pts
				(arc
					(start 474.49994 -151.100028)
					(mid 478.499932 -155.10002)
					(end 474.49994 -159.100012)
				)
				(arc
					(start 471.000074 -159.100012)
					(mid 467.000082 -155.10002)
					(end 471.000074 -151.100028)
				)
			)
		)
	)
	(zone
		(net "PVDDQ_ABC")
		(layer "F.Cu")
		(hatch none 0.5)
		(connect_pads
			(clearance 0.5)
		)
		(min_thickness 0.25)
		(fill yes
			(thermal_gap 0.5)
			(thermal_bridge_width 0.5)
			(island_removal_mode 0)
		)
		(polygon
			(pts
				(xy 243.713 2.667) (xy 258.445 2.667) (xy 258.6736 2.4384) (xy 258.6736 0.5334) (xy 258.4704 0.3302)
				(xy 244.5512 0.3302) (xy 243.713 1.1684)
			)
		)
	)
	(zone
		(net "P3V3_STBY")
		(layer "F.Cu")
		(hatch none 0.5)
		(connect_pads
			(clearance 0.5)
		)
		(min_thickness 0.25)
		(fill yes
			(thermal_gap 0.5)
			(thermal_bridge_width 0.5)
			(island_removal_mode 0)
		)
		(polygon
			(pts
				(xy 402.108416 -150.443184) (xy 402.083016 -150.468584) (xy 401.600416 -150.468584) (xy 401.574 -150.495)
				(xy 401.574 -152.781) (xy 401.7518 -152.9588) (xy 403.098 -152.9588) (xy 403.1742 -153.035) (xy 403.1742 -153.059384)
				(xy 404.369016 -153.059384) (xy 404.369016 -151.332184) (xy 403.581616 -151.332184) (xy 403.403816 -151.154384)
				(xy 403.403816 -150.493984) (xy 403.353016 -150.443184)
			)
		)
		(polygon
			(pts
				(xy 402.0566 -151.9809) (xy 401.8534 -151.9809) (xy 401.8534 -152.1841) (xy 402.0566 -152.1841)
			)
		)
		(polygon
			(pts
				(xy 402.8186 -151.9809) (xy 402.6154 -151.9809) (xy 402.6154 -152.1841) (xy 402.8186 -152.1841)
			)
		)
		(polygon
			(pts
				(xy 403.645116 -152.221184) (xy 403.441916 -152.221184) (xy 403.441916 -152.424384) (xy 403.645116 -152.424384)
			)
		)
	)
	(zone
		(layer "F.Cu")
		(hatch none 0.5)
		(connect_pads
			(clearance 0)
		)
		(min_thickness 0.25)
		(keepout
			(tracks not_allowed)
			(vias allowed)
			(pads allowed)
			(copperpour not_allowed)
			(footprints allowed)
		)
		(placement
			(enabled no)
			(sheetname "")
		)
		(fill
			(thermal_gap 0.5)
			(thermal_bridge_width 0.5)
			(island_removal_mode 0)
		)
		(polygon
			(pts
				(arc
					(start 127 -114.089942)
					(mid 124.46 -111.549942)
					(end 127 -109.009942)
				)
				(arc
					(start 127 -109.009942)
					(mid 129.54 -111.549942)
					(end 127 -114.089942)
				)
			)
		)
	)
	(zone
		(layer "F.Cu")
		(hatch none 0.5)
		(connect_pads
			(clearance 0)
		)
		(min_thickness 0.25)
		(keepout
			(tracks allowed)
			(vias allowed)
			(pads allowed)
			(copperpour allowed)
			(footprints allowed)
		)
		(placement
			(enabled no)
			(sheetname "")
		)
		(fill
			(thermal_gap 0.5)
			(thermal_bridge_width 0.5)
			(island_removal_mode 0)
		)
		(polygon
			(pts
				(xy 353.253548 -79.38135) (xy 353.253548 -77.09535) (xy 355.260148 -77.09535) (xy 355.260148 -79.38135)
			)
		)
	)
	(zone
		(layer "F.Cu")
		(hatch none 0.5)
		(connect_pads
			(clearance 0)
		)
		(min_thickness 0.25)
		(keepout
			(tracks allowed)
			(vias allowed)
			(pads allowed)
			(copperpour allowed)
			(footprints not_allowed)
		)
		(placement
			(enabled no)
			(sheetname "")
		)
		(fill
			(thermal_gap 0.5)
			(thermal_bridge_width 0.5)
			(island_removal_mode 0)
		)
		(polygon
			(pts
				(arc
					(start 0 2.830068)
					(mid 2.830068 0)
					(end 0 -2.830068)
				)
				(arc
					(start 0 -2.830068)
					(mid -2.830068 0)
					(end 0 2.830068)
				)
			)
		)
	)
	(zone
		(net "VR_FET_SW_P12V_STBY_PVCCIN_CPU1")
		(layer "F.Cu")
		(hatch none 0.5)
		(connect_pads
			(clearance 0.5)
		)
		(min_thickness 0.25)
		(fill yes
			(thermal_gap 0.5)
			(thermal_bridge_width 0.5)
			(island_removal_mode 0)
		)
		(polygon
			(pts
				(xy 31.486602 -67.060064) (xy 31.613602 -66.933064) (xy 31.613602 -66.92138) (xy 31.6484 -66.886582)
				(xy 31.6484 -65.54978) (xy 33.630616 -65.54978) (xy 33.630616 -67.805808) (xy 33.380426 -68.055998)
				(xy 33.380426 -68.16217) (xy 33.380426 -68.768722) (xy 33.306258 -68.84289) (xy 32.699706 -68.84289)
				(xy 31.183072 -68.84289) (xy 30.748478 -68.408296) (xy 29.627576 -68.408296) (xy 29.3878 -68.16852)
				(xy 29.3878 -67.42938) (xy 29.5402 -67.27698) (xy 30.2768 -67.27698) (xy 30.353 -67.20078) (xy 30.355286 -67.20078)
				(xy 30.496002 -67.060064)
			)
		)
	)
	(zone
		(net "VR_PVCCIN_CPU0_PHASE2")
		(layer "F.Cu")
		(hatch none 0.5)
		(connect_pads
			(clearance 0.5)
		)
		(min_thickness 0.25)
		(fill yes
			(thermal_gap 0.5)
			(thermal_bridge_width 0.5)
			(island_removal_mode 0)
		)
		(polygon
			(pts
				(xy 201.8538 -67.783202) (xy 205.657196 -67.783202) (xy 206.529432 -67.783202) (xy 206.884778 -67.427856)
				(xy 206.884778 -63.174372) (xy 206.413608 -62.703202) (xy 205.657196 -62.703202) (xy 201.736198 -62.703202)
				(xy 201.4728 -62.9666) (xy 201.4728 -67.402202)
			)
		)
	)
	(zone
		(net "GND")
		(layer "F.Cu")
		(hatch none 0.5)
		(connect_pads
			(clearance 0.5)
		)
		(min_thickness 0.25)
		(fill yes
			(thermal_gap 0.5)
			(thermal_bridge_width 0.5)
			(island_removal_mode 0)
		)
		(polygon
			(pts
				(xy 437.81472 -132.4102) (xy 439.5978 -132.4102) (xy 440.0296 -131.9784) (xy 440.0296 -130.0988)
				(xy 439.9534 -130.0226) (xy 438.6834 -130.0226) (xy 438.2516 -129.5908) (xy 438.2516 -129.3622)
				(xy 438.2008 -129.3114) (xy 437.42356 -129.3114) (xy 437.2102 -129.52476) (xy 437.0832 -129.65176)
				(xy 437.0832 -132.08) (xy 437.4134 -132.4102)
			)
		)
	)
	(zone
		(net "AGND_P3V3_STBY")
		(layer "F.Cu")
		(hatch none 0.5)
		(connect_pads
			(clearance 0.5)
		)
		(min_thickness 0.25)
		(fill yes
			(thermal_gap 0.5)
			(thermal_bridge_width 0.5)
			(island_removal_mode 0)
		)
		(polygon
			(pts
				(xy 467.5378 -23.5458) (xy 468.3506 -23.5458) (xy 468.4268 -23.4696) (xy 468.4268 -22.6314) (xy 468.4522 -22.606)
				(xy 468.4522 -20.44446) (xy 468.40267 -20.39493) (xy 467.27237 -20.39493) (xy 467.17204 -20.49526)
				(xy 467.17204 -21.15566) (xy 467.25332 -21.23694) (xy 467.54796 -21.23694) (xy 467.78672 -21.4757)
				(xy 467.84514 -21.53412) (xy 467.84514 -22.27326) (xy 467.8426 -22.2758) (xy 467.8426 -22.3266)
				(xy 467.5632 -22.606) (xy 467.5124 -22.606) (xy 467.4616 -22.6568) (xy 467.4616 -23.4696)
			)
		)
	)
	(zone
		(net "SATA6G_S1_TX_C_DN")
		(layer "F.Cu")
		(hatch none 0.5)
		(connect_pads
			(clearance 0.5)
		)
		(min_thickness 0.25)
		(fill yes
			(thermal_gap 0.5)
			(thermal_bridge_width 0.5)
			(island_removal_mode 0)
		)
		(polygon
			(pts
				(arc
					(start 431.496724 -136.344914)
					(mid 430.683416 -136.344914)
					(end 431.496724 -136.344914)
				)
			)
		)
	)
	(zone
		(net "VR_FET_SW_P12V_STBY_PVCCIN_CPU0")
		(layer "F.Cu")
		(hatch none 0.5)
		(connect_pads
			(clearance 0.5)
		)
		(min_thickness 0.25)
		(fill yes
			(thermal_gap 0.5)
			(thermal_bridge_width 0.5)
			(island_removal_mode 0)
		)
		(polygon
			(pts
				(xy 196.487034 -67.060064) (xy 196.614034 -66.933064) (xy 196.614034 -66.92138) (xy 196.648832 -66.886582)
				(xy 196.648832 -65.551558) (xy 196.65061 -65.54978) (xy 198.62927 -65.54978) (xy 198.631048 -65.551558)
				(xy 198.631048 -67.882262) (xy 198.274178 -68.239132) (xy 198.274178 -68.25361) (xy 198.274178 -68.902072)
				(xy 198.244714 -68.931536) (xy 196.459348 -68.931536) (xy 196.209158 -68.681346) (xy 194.76466 -68.681346)
				(xy 194.48272 -68.399406) (xy 194.48272 -67.564) (xy 194.53352 -67.5132) (xy 195.199 -67.5132) (xy 195.298568 -67.413632)
				(xy 195.302632 -67.413632) (xy 195.6562 -67.060064)
			)
		)
	)
	(zone
		(net "VR_FET_SW_P12V_STBY_PVDDQ_ABC")
		(layer "F.Cu")
		(hatch none 0.5)
		(connect_pads
			(clearance 0.5)
		)
		(min_thickness 0.25)
		(fill yes
			(thermal_gap 0.5)
			(thermal_bridge_width 0.5)
			(island_removal_mode 0)
		)
		(polygon
			(pts
				(xy 349.380302 -2.785872) (xy 347.523562 -2.785872) (xy 347.432122 -2.694432) (xy 346.873068 -2.694432)
				(xy 346.837508 -2.729992) (xy 346.837508 -3.23596) (xy 346.6846 -3.388868) (xy 346.6846 -5.6642)
				(xy 346.6846 -5.931662) (xy 346.770706 -6.017768) (xy 348.566232 -6.017768) (xy 348.5896 -5.9944)
				(xy 348.7166 -5.8674) (xy 348.7166 -4.473194) (xy 348.829122 -4.360672) (xy 349.732092 -4.360672)
				(xy 349.976948 -4.115816) (xy 349.976948 -3.832098) (xy 350.067626 -3.74142) (xy 350.088454 -3.720592)
				(xy 351.988374 -3.720592) (xy 352.009202 -3.74142) (xy 352.57613 -4.308348) (xy 352.57613 -7.471156)
				(xy 353.20732 -8.102346) (xy 353.20732 -8.844026) (xy 353.20732 -9.04748) (xy 352.9584 -9.2964)
				(xy 352.425 -9.2964) (xy 352.298 -9.4234) (xy 352.298 -9.753346) (xy 352.298 -10.033) (xy 352.679 -10.414)
				(xy 352.679 -12.0142) (xy 352.425 -12.2682) (xy 352.298 -12.2682) (xy 351.858072 -12.2682) (xy 351.763076 -12.363196)
				(xy 351.763076 -16.002) (xy 352.679 -16.917924) (xy 352.679 -18.120614) (xy 353.220274 -18.661888)
				(xy 353.220274 -20.776692) (xy 352.679 -21.317966) (xy 352.679 -21.557234) (xy 352.679 -22.922484)
				(xy 353.124516 -23.368) (xy 355.092 -23.368) (xy 355.346 -23.114) (xy 355.346 -20.574) (xy 356.743 -19.177)
				(xy 356.743 -12.416536) (xy 356.75189 -12.407646) (xy 355.829108 -11.484864) (xy 355.829108 -7.422388)
				(xy 354.969826 -6.563106) (xy 354.969826 -4.052062) (xy 354.875084 -3.95732) (xy 354.095304 -3.17754)
				(xy 354.095304 -1.7272) (xy 354.031042 -1.662938) (xy 350.901508 -1.662938) (xy 350.5073 -2.057146)
				(xy 350.5073 -2.616708) (xy 350.5073 -2.699004) (xy 350.310958 -2.895346) (xy 349.7961 -2.895346)
				(xy 349.686626 -2.785872)
			)
		)
	)
	(zone
		(net "PVDDQ_GHJ")
		(layer "F.Cu")
		(hatch none 0.5)
		(connect_pads
			(clearance 0.5)
		)
		(min_thickness 0.25)
		(fill yes
			(thermal_gap 0.5)
			(thermal_bridge_width 0.5)
			(island_removal_mode 0)
		)
		(polygon
			(pts
				(xy 101.473 -9.271) (xy 103.2256 -9.271) (xy 103.3272 -9.3726) (xy 103.3272 -10.541) (xy 103.505 -10.7188)
				(xy 103.8352 -10.7188) (xy 104.013 -10.541) (xy 104.013 -9.271) (xy 105.7402 -9.271) (xy 105.8926 -9.4234)
				(xy 105.8926 -10.5918) (xy 105.9942 -10.6934) (xy 106.4006 -10.6934) (xy 106.553 -10.541) (xy 106.553 -9.3726)
				(xy 106.6546 -9.271) (xy 107.4166 -9.271) (xy 107.5436 -9.398) (xy 107.5436 -10.4902) (xy 107.7468 -10.6934)
				(xy 108.077 -10.6934) (xy 108.2294 -10.541) (xy 108.2294 -9.398) (xy 108.3564 -9.271) (xy 109.1438 -9.271)
				(xy 109.2708 -9.398) (xy 109.2708 -10.5156) (xy 109.4486 -10.6934) (xy 109.7534 -10.6934) (xy 109.9312 -10.5156)
				(xy 109.9312 -9.398) (xy 110.0582 -9.271) (xy 111.6838 -9.271) (xy 111.8108 -9.398) (xy 111.8108 -10.5918)
				(xy 111.9124 -10.6934) (xy 112.3696 -10.6934) (xy 112.4712 -10.5918) (xy 112.4712 -9.271) (xy 112.570768 -9.171432)
				(xy 112.570768 -7.173468) (xy 112.3315 -6.9342) (xy 101.572568 -6.9342) (xy 100.708968 -7.7978)
				(xy 100.708968 -8.8392) (xy 100.7618 -8.892032) (xy 100.7618 -10.5156) (xy 100.965 -10.7188) (xy 101.2698 -10.7188)
				(xy 101.4222 -10.5664) (xy 101.4222 -9.3218)
			)
		)
	)
	(zone
		(net "P1V05_PCH_STBY")
		(layer "F.Cu")
		(hatch none 0.5)
		(connect_pads
			(clearance 0.5)
		)
		(min_thickness 0.25)
		(fill yes
			(thermal_gap 0.5)
			(thermal_bridge_width 0.5)
			(island_removal_mode 0)
		)
		(polygon
			(pts
				(xy 383.413 -114.808) (xy 383.159 -114.808) (xy 383.03327 -114.68227) (xy 381.018034 -114.68227)
				(xy 380.674372 -114.338608) (xy 380.674372 -112.329976) (xy 380.736856 -112.267492) (xy 381.087376 -112.267492)
				(xy 381.9779 -113.158016) (xy 382.888236 -113.158016) (xy 383.178304 -113.448084) (xy 383.51079 -113.448084)
				(xy 383.570734 -113.448084) (xy 383.794 -113.67135) (xy 383.794 -114.427)
			)
		)
	)
	(zone
		(layer "F.Cu")
		(hatch none 0.5)
		(connect_pads
			(clearance 0)
		)
		(min_thickness 0.25)
		(keepout
			(tracks allowed)
			(vias allowed)
			(pads allowed)
			(copperpour allowed)
			(footprints allowed)
		)
		(placement
			(enabled no)
			(sheetname "")
		)
		(fill
			(thermal_gap 0.5)
			(thermal_bridge_width 0.5)
			(island_removal_mode 0)
		)
		(polygon
			(pts
				(xy 348.3356 -147.4978) (xy 348.3356 -145.2118) (xy 350.3422 -145.2118) (xy 350.3422 -147.4978)
			)
		)
	)
	(zone
		(net "GND")
		(layer "F.Cu")
		(hatch none 0.5)
		(connect_pads
			(clearance 0.5)
		)
		(min_thickness 0.25)
		(fill yes
			(thermal_gap 0.5)
			(thermal_bridge_width 0.5)
			(island_removal_mode 0)
		)
		(polygon
			(pts
				(xy 346.583 -132.9817) (xy 346.456 -133.1087) (xy 346.456 -135.1407) (xy 346.329 -135.2677) (xy 342.773 -135.2677)
				(xy 342.646 -135.3947) (xy 342.646 -136.2837) (xy 343.281 -136.9187) (xy 343.281 -137.5537) (xy 343.508584 -137.781284)
				(xy 350.673416 -137.781284) (xy 351.0026 -137.4521) (xy 351.0026 -135.89) (xy 350.6978 -135.5852)
				(xy 350.6978 -134.7216) (xy 350.4692 -134.493) (xy 348.996 -134.493) (xy 348.742 -134.239) (xy 347.98 -134.239)
				(xy 347.599 -133.858) (xy 347.599 -133.1722) (xy 347.4085 -132.9817)
			)
		)
		(polygon
			(pts
				(xy 343.8906 -137.3251) (xy 343.6874 -137.3251) (xy 343.6874 -137.5283) (xy 343.8906 -137.5283)
			)
		)
		(polygon
			(pts
				(xy 343.8906 -136.8171) (xy 343.6874 -136.8171) (xy 343.6874 -137.0203) (xy 343.8906 -137.0203)
			)
		)
		(polygon
			(pts
				(xy 348.7166 -134.6454) (xy 348.5134 -134.6454) (xy 348.5134 -134.8486) (xy 348.7166 -134.8486)
			)
		)
		(polygon
			(pts
				(xy 348.2086 -134.6454) (xy 348.0054 -134.6454) (xy 348.0054 -134.8486) (xy 348.2086 -134.8486)
			)
		)
	)
	(zone
		(layer "F.Cu")
		(hatch none 0.5)
		(connect_pads
			(clearance 0)
		)
		(min_thickness 0.25)
		(keepout
			(tracks not_allowed)
			(vias allowed)
			(pads allowed)
			(copperpour not_allowed)
			(footprints allowed)
		)
		(placement
			(enabled no)
			(sheetname "")
		)
		(fill
			(thermal_gap 0.5)
			(thermal_bridge_width 0.5)
			(island_removal_mode 0)
		)
		(polygon
			(pts
				(xy 381.341376 -28.501594)
				(arc
					(start 381.248158 -28.408376)
					(mid 380.926993 -27.988405)
					(end 381.346964 -28.30957)
				)
				(xy 381.399288 -28.361894) (xy 381.49911 -28.361894)
				(arc
					(start 381.49911 -28.177236)
					(mid 381.115697 -27.793442)
					(end 380.73203 -28.176982)
				)
				(arc
					(start 380.73203 -29.054552)
					(mid 381.11557 -29.438092)
					(end 381.49911 -29.054552)
				)
				(xy 381.49911 -28.763468)
				(arc
					(start 381.344678 -28.9179)
					(mid 380.930264 -29.246453)
					(end 381.244094 -28.820872)
				)
				(xy 381.461772 -28.603194) (xy 381.49911 -28.603194) (xy 381.49911 -28.501594)
			)
		)
	)
	(zone
		(net "P1V05_PCH_STBY")
		(layer "F.Cu")
		(hatch none 0.5)
		(connect_pads
			(clearance 0.5)
		)
		(min_thickness 0.25)
		(fill yes
			(thermal_gap 0.5)
			(thermal_bridge_width 0.5)
			(island_removal_mode 0)
		)
		(polygon
			(pts
				(xy 410.033216 -125.60427) (xy 409.837382 -125.800104) (xy 407.828496 -125.800104) (xy 407.801064 -125.827536)
				(xy 407.801064 -127.101092) (xy 407.869136 -127.169164) (xy 409.871164 -127.169164) (xy 410.6926 -127.9906)
				(xy 411.48 -127.9906) (xy 411.541722 -127.928878) (xy 411.541722 -126.92761) (xy 411.004512 -126.3904)
				(xy 410.845 -126.3904) (xy 410.6926 -126.238) (xy 410.6926 -125.623066) (xy 410.673804 -125.60427)
			)
		)
		(polygon
			(pts
				(xy 408.6606 -126.5809) (xy 408.4574 -126.5809) (xy 408.4574 -126.7841) (xy 408.6606 -126.7841)
			)
		)
		(polygon
			(pts
				(xy 409.1686 -126.5809) (xy 408.9654 -126.5809) (xy 408.9654 -126.7841) (xy 409.1686 -126.7841)
			)
		)
		(polygon
			(pts
				(xy 409.9306 -126.5809) (xy 409.7274 -126.5809) (xy 409.7274 -126.7841) (xy 409.9306 -126.7841)
			)
		)
		(polygon
			(pts
				(xy 410.7561 -127.0762) (xy 410.5529 -127.0762) (xy 410.5529 -127.2794) (xy 410.7561 -127.2794)
			)
		)
	)
	(zone
		(layer "F.Cu")
		(hatch none 0.5)
		(connect_pads
			(clearance 0)
		)
		(min_thickness 0.25)
		(keepout
			(tracks not_allowed)
			(vias allowed)
			(pads allowed)
			(copperpour not_allowed)
			(footprints allowed)
		)
		(placement
			(enabled no)
			(sheetname "")
		)
		(fill
			(thermal_gap 0.5)
			(thermal_bridge_width 0.5)
			(island_removal_mode 0)
		)
		(polygon
			(pts
				(arc
					(start 83.000088 -39.010082)
					(mid 85.540088 -41.550082)
					(end 83.000088 -44.090082)
				)
				(arc
					(start 83.000088 -44.090082)
					(mid 80.460088 -41.550082)
					(end 83.000088 -39.010082)
				)
			)
		)
	)
	(zone
		(net "GND")
		(layer "F.Cu")
		(hatch none 0.5)
		(connect_pads
			(clearance 0.5)
		)
		(min_thickness 0.25)
		(fill yes
			(thermal_gap 0.5)
			(thermal_bridge_width 0.5)
			(island_removal_mode 0)
		)
		(polygon
			(pts
				(xy 409.1432 -101.473) (xy 410.1084 -100.5078) (xy 410.1084 -99.2124) (xy 408.7114 -97.8154) (xy 408.70886 -97.8154)
				(xy 408.34056 -97.4471) (xy 407.22042 -97.4471) (xy 406.31364 -97.4471) (xy 405.48814 -96.6216)
				(xy 404.89124 -96.6216) (xy 404.50008 -96.6216) (xy 401.93722 -99.18446) (xy 401.93722 -99.491292)
				(xy 402.330412 -99.491292) (xy 403.562312 -98.259392) (xy 404.210266 -98.259392) (xy 404.665942 -97.803716)
				(xy 405.24303 -97.803716) (xy 405.364188 -97.682558) (xy 407.080974 -97.682558) (xy 407.314146 -97.91573)
				(xy 407.314146 -98.551238) (xy 406.95118 -98.914204) (xy 406.95118 -99.202494) (xy 406.908254 -99.24542)
				(xy 405.511762 -99.24542) (xy 405.486362 -99.22002) (xy 405.486362 -98.883724) (xy 405.437086 -98.834448)
				(xy 404.550118 -98.834448) (xy 404.532338 -98.816668) (xy 404.532338 -98.661474) (xy 404.496778 -98.625914)
				(xy 403.714204 -98.625914) (xy 402.47697 -99.863148) (xy 401.99818 -99.863148) (xy 401.93722 -99.924108)
				(xy 401.93722 -100.041202) (xy 404.519384 -100.041202) (xy 404.61692 -99.943666) (xy 405.365204 -99.943666)
				(xy 405.385016 -99.963478) (xy 405.385016 -100.173536) (xy 405.607012 -100.395532) (xy 405.607012 -100.675186)
				(xy 405.65959 -100.727764) (xy 407.466038 -100.727764) (xy 407.588212 -100.60559) (xy 407.588212 -99.546664)
				(xy 407.611834 -99.523042) (xy 409.001976 -99.523042) (xy 409.030678 -99.551744) (xy 409.030678 -100.820982)
				(xy 409.014676 -100.836984) (xy 407.894282 -100.836984) (xy 407.621486 -101.10978) (xy 405.487886 -101.10978)
				(xy 405.35606 -100.977954) (xy 404.742142 -100.977954) (xy 404.721568 -100.95738) (xy 404.721568 -100.957126)
				(xy 404.60041 -100.835968) (xy 404.60041 -100.728526) (xy 404.60041 -100.451666) (xy 404.562564 -100.41382)
				(xy 402.197062 -100.41382) (xy 402.181314 -100.429568) (xy 402.181314 -100.520246) (xy 402.206714 -100.545646)
				(xy 403.796246 -100.545646) (xy 404.749 -101.4984) (xy 405.13508 -101.4984) (xy 406.5778 -101.4984)
				(xy 406.6032 -101.473) (xy 406.7556 -101.473) (xy 407.9494 -101.473) (xy 408.0002 -101.5238) (xy 409.0924 -101.5238)
			)
		)
	)
	(zone
		(layer "F.Cu")
		(hatch none 0.5)
		(connect_pads
			(clearance 0)
		)
		(min_thickness 0.25)
		(keepout
			(tracks allowed)
			(vias allowed)
			(pads allowed)
			(copperpour allowed)
			(footprints allowed)
		)
		(placement
			(enabled no)
			(sheetname "")
		)
		(fill
			(thermal_gap 0.5)
			(thermal_bridge_width 0.5)
			(island_removal_mode 0)
		)
		(polygon
			(pts
				(xy 346.837 -101.473) (xy 353.06 -101.473) (xy 353.441 -101.092) (xy 353.441 -96.139) (xy 352.933 -95.631)
				(xy 350.139 -95.631) (xy 349.631 -96.139) (xy 349.631 -99.314) (xy 349.377 -99.568) (xy 346.837 -99.568)
				(xy 346.583 -99.822) (xy 346.583 -101.219)
			)
		)
	)
	(zone
		(layer "F.Cu")
		(hatch none 0.5)
		(connect_pads
			(clearance 0)
		)
		(min_thickness 0.25)
		(keepout
			(tracks allowed)
			(vias allowed)
			(pads allowed)
			(copperpour allowed)
			(footprints not_allowed)
		)
		(placement
			(enabled no)
			(sheetname "")
		)
		(fill
			(thermal_gap 0.5)
			(thermal_bridge_width 0.5)
			(island_removal_mode 0)
		)
		(polygon
			(pts
				(arc
					(start 83.000088 -44.090082)
					(mid 80.460088 -41.550082)
					(end 83.000088 -39.010082)
				)
				(arc
					(start 83.000088 -39.010082)
					(mid 85.540088 -41.550082)
					(end 83.000088 -44.090082)
				)
			)
		)
	)
	(zone
		(layer "F.Cu")
		(hatch none 0.5)
		(connect_pads
			(clearance 0)
		)
		(min_thickness 0.25)
		(keepout
			(tracks allowed)
			(vias allowed)
			(pads allowed)
			(copperpour allowed)
			(footprints allowed)
		)
		(placement
			(enabled no)
			(sheetname "")
		)
		(fill
			(thermal_gap 0.5)
			(thermal_bridge_width 0.5)
			(island_removal_mode 0)
		)
		(polygon
			(pts
				(xy 105.763568 -102.235) (xy 105.763568 -106.172) (xy 86.586568 -106.172) (xy 86.586568 -102.235)
			)
		)
	)
	(zone
		(layer "F.Cu")
		(hatch none 0.5)
		(connect_pads
			(clearance 0)
		)
		(min_thickness 0.25)
		(keepout
			(tracks not_allowed)
			(vias allowed)
			(pads allowed)
			(copperpour not_allowed)
			(footprints allowed)
		)
		(placement
			(enabled no)
			(sheetname "")
		)
		(fill
			(thermal_gap 0.5)
			(thermal_bridge_width 0.5)
			(island_removal_mode 0)
		)
		(polygon
			(pts
				(arc
					(start 320.642742 -98.549968)
					(mid 315.35751 -98.549968)
					(end 320.642742 -98.549968)
				)
			)
		)
	)
	(zone
		(net "GND")
		(layer "F.Cu")
		(hatch none 0.5)
		(connect_pads
			(clearance 0.5)
		)
		(min_thickness 0.25)
		(fill yes
			(thermal_gap 0.5)
			(thermal_bridge_width 0.5)
			(island_removal_mode 0)
		)
		(polygon
			(pts
				(xy 367.7666 -108.480606) (xy 367.7666 -108.987336) (xy 367.872772 -109.093508) (xy 368.911124 -109.093508)
				(xy 369.028472 -108.97616) (xy 369.028472 -108.50753) (xy 368.884708 -108.363766) (xy 367.88344 -108.363766)
			)
		)
	)
	(zone
		(layer "F.Cu")
		(hatch none 0.5)
		(connect_pads
			(clearance 0)
		)
		(min_thickness 0.25)
		(keepout
			(tracks allowed)
			(vias allowed)
			(pads allowed)
			(copperpour allowed)
			(footprints allowed)
		)
		(placement
			(enabled no)
			(sheetname "")
		)
		(fill
			(thermal_gap 0.5)
			(thermal_bridge_width 0.5)
			(island_removal_mode 0)
		)
		(polygon
			(pts
				(xy 267.335 -62.738) (xy 268.097 -62.738) (xy 268.351 -62.992) (xy 268.351 -63.373) (xy 267.208 -63.373)
				(xy 267.208 -62.865)
			)
		)
	)
	(zone
		(layer "F.Cu")
		(hatch none 0.5)
		(connect_pads
			(clearance 0)
		)
		(min_thickness 0.25)
		(keepout
			(tracks allowed)
			(vias allowed)
			(pads allowed)
			(copperpour allowed)
			(footprints allowed)
		)
		(placement
			(enabled no)
			(sheetname "")
		)
		(fill
			(thermal_gap 0.5)
			(thermal_bridge_width 0.5)
			(island_removal_mode 0)
		)
		(polygon
			(pts
				(xy 345.8464 -23.3045) (xy 348.8436 -23.3045) (xy 348.8436 -23.7871) (xy 347.0148 -23.7871) (xy 347.0148 -25.8191)
				(xy 345.8464 -25.8191)
			)
		)
	)
	(zone
		(layer "F.Cu")
		(hatch none 0.5)
		(connect_pads
			(clearance 0)
		)
		(min_thickness 0.25)
		(keepout
			(tracks allowed)
			(vias allowed)
			(pads allowed)
			(copperpour allowed)
			(footprints allowed)
		)
		(placement
			(enabled no)
			(sheetname "")
		)
		(fill
			(thermal_gap 0.5)
			(thermal_bridge_width 0.5)
			(island_removal_mode 0)
		)
		(polygon
			(pts
				(xy 237.1598 -44.977558) (xy 234.674664 -44.977558) (xy 234.585764 -44.888658) (xy 234.585764 -43.744134)
				(xy 234.453684 -43.612054) (xy 234.360212 -43.612054) (xy 232.994708 -44.977558) (xy 232.246932 -45.725334)
				(xy 229.688644 -48.283622) (xy 229.688644 -48.534574) (xy 229.764844 -48.610774) (xy 231.637332 -48.610774)
				(xy 232.246932 -49.220374) (xy 232.749344 -49.722786) (xy 234.421172 -49.722786) (xy 237.1598 -49.722786)
			)
		)
	)
	(zone
		(net "GND")
		(layer "F.Cu")
		(hatch none 0.5)
		(connect_pads
			(clearance 0.5)
		)
		(min_thickness 0.25)
		(fill yes
			(thermal_gap 0.5)
			(thermal_bridge_width 0.5)
			(island_removal_mode 0)
		)
		(polygon
			(pts
				(xy 17.0942 0.9398) (xy 16.764 0.6096) (xy 16.764 -0.4826) (xy 16.59001 -0.65659) (xy 16.59001 -2.025142)
				(xy 16.71447 -2.149602) (xy 16.71447 -3.0353) (xy 16.51 -3.23977) (xy 16.51 -4.094226) (xy 16.67891 -4.263136)
				(xy 16.67891 -4.577334) (xy 16.51 -4.746244) (xy 16.51 -5.08) (xy 16.7132 -5.2832) (xy 17.860264 -5.2832)
				(xy 17.922494 -5.22097) (xy 17.922494 -3.184652) (xy 17.947132 -3.160014) (xy 17.947132 -1.802638)
				(xy 18.137124 -1.612646) (xy 18.137124 -0.830834) (xy 18.137124 -0.658876) (xy 18.226278 -0.569722)
				(xy 18.4023 -0.569722) (xy 19.718782 -0.569722) (xy 19.812254 -0.47625) (xy 19.812254 0.721614)
				(xy 19.652996 0.880872) (xy 19.594068 0.9398) (xy 18.6944 0.9398)
			)
		)
	)
	(zone
		(layer "F.Cu")
		(hatch none 0.5)
		(connect_pads
			(clearance 0)
		)
		(min_thickness 0.25)
		(keepout
			(tracks allowed)
			(vias allowed)
			(pads allowed)
			(copperpour allowed)
			(footprints not_allowed)
		)
		(placement
			(enabled no)
			(sheetname "")
		)
		(fill
			(thermal_gap 0.5)
			(thermal_bridge_width 0.5)
			(island_removal_mode 0)
		)
		(polygon
			(pts
				(xy -0.500126 -74.749914) (xy -0.500126 -70.25005) (xy 3.999992 -70.25005) (xy 3.999992 -74.749914)
			)
		)
	)
	(zone
		(net "PVPP_ABC")
		(layer "F.Cu")
		(hatch none 0.5)
		(connect_pads
			(clearance 0.5)
		)
		(min_thickness 0.25)
		(fill yes
			(thermal_gap 0.5)
			(thermal_bridge_width 0.5)
			(island_removal_mode 0)
		)
		(polygon
			(pts
				(xy 297.585638 -51.751992) (xy 297.585638 -51.283108) (xy 297.815762 -51.052984) (xy 301.882556 -51.052984)
				(xy 301.927006 -51.052984) (xy 302.086772 -51.21275) (xy 302.086772 -51.459638) (xy 301.872142 -51.674268)
				(xy 301.123858 -51.674268) (xy 301.042578 -51.592988) (xy 300.331886 -51.592988) (xy 300.194218 -51.730656)
				(xy 300.029372 -51.730656) (xy 299.66666 -52.093368) (xy 299.519086 -52.093368) (xy 299.381672 -52.230782)
				(xy 298.621704 -52.230782) (xy 298.48429 -52.093368) (xy 297.927014 -52.093368)
			)
		)
	)
	(zone
		(net "P5V_USB")
		(layer "F.Cu")
		(hatch none 0.5)
		(connect_pads
			(clearance 0.5)
		)
		(min_thickness 0.25)
		(fill yes
			(thermal_gap 0.5)
			(thermal_bridge_width 0.5)
			(island_removal_mode 0)
		)
		(polygon
			(pts
				(xy 462.3054 -129.9972) (xy 462.3054 -127.36576) (xy 462.49463 -127.17653) (xy 465.724494 -127.17653)
				(xy 465.836 -127.288036) (xy 465.836 -130.429) (xy 464.9724 -131.2926) (xy 462.6102 -131.2926) (xy 462.3054 -130.9878)
			)
		)
	)
	(zone
		(net "AGND_PVPP_KLM")
		(layer "F.Cu")
		(hatch none 0.5)
		(connect_pads
			(clearance 0.5)
		)
		(min_thickness 0.25)
		(fill yes
			(thermal_gap 0.5)
			(thermal_bridge_width 0.5)
			(island_removal_mode 0)
		)
		(polygon
			(pts
				(xy 177.419 -134.4295) (xy 177.927 -134.4295) (xy 178.054 -134.3025) (xy 178.054 -133.5659) (xy 178.5112 -133.1087)
				(xy 178.5112 -132.3721) (xy 178.3588 -132.2197) (xy 178.2572 -132.2197) (xy 178.1556 -132.2197)
				(xy 178.0032 -132.2197) (xy 177.8508 -132.3721) (xy 177.8508 -132.9817) (xy 177.6857 -133.1468)
				(xy 177.292 -133.5405) (xy 177.292 -134.3025)
			)
		)
	)
	(zone
		(layer "F.Cu")
		(hatch none 0.5)
		(connect_pads
			(clearance 0)
		)
		(min_thickness 0.25)
		(keepout
			(tracks allowed)
			(vias allowed)
			(pads allowed)
			(copperpour allowed)
			(footprints not_allowed)
		)
		(placement
			(enabled no)
			(sheetname "")
		)
		(fill
			(thermal_gap 0.5)
			(thermal_bridge_width 0.5)
			(island_removal_mode 0)
		)
		(polygon
			(pts
				(xy 22.52472 -4.917948) (xy 22.52472 -1.716786) (xy 163.524692 -1.716786) (xy 163.524692 -4.917948)
			)
		)
	)
	(zone
		(layer "F.Cu")
		(hatch none 0.5)
		(connect_pads
			(clearance 0)
		)
		(min_thickness 0.25)
		(keepout
			(tracks not_allowed)
			(vias allowed)
			(pads allowed)
			(copperpour not_allowed)
			(footprints allowed)
		)
		(placement
			(enabled no)
			(sheetname "")
		)
		(fill
			(thermal_gap 0.5)
			(thermal_bridge_width 0.5)
			(island_removal_mode 0)
		)
		(polygon
			(pts
				(arc
					(start -5.999988 -152.599898)
					(mid -4.658223 -155.09995)
					(end -5.999988 -157.599888)
				)
			)
		)
	)
	(zone
		(layer "F.Cu")
		(hatch none 0.5)
		(connect_pads
			(clearance 0)
		)
		(min_thickness 0.25)
		(keepout
			(tracks not_allowed)
			(vias allowed)
			(pads allowed)
			(copperpour not_allowed)
			(footprints allowed)
		)
		(placement
			(enabled no)
			(sheetname "")
		)
		(fill
			(thermal_gap 0.5)
			(thermal_bridge_width 0.5)
			(island_removal_mode 0)
		)
		(polygon
			(pts
				(arc
					(start 462.119726 -44.7675)
					(mid 462.643643 -44.83735)
					(end 462.119726 -44.9072)
				)
				(xy 462.07299 -44.9072) (xy 461.91805 -45.06214) (xy 461.91805 -45.22089)
				(arc
					(start 462.376774 -45.22089)
					(mid 462.760314 -44.837477)
					(end 462.377028 -44.45381)
				)
				(arc
					(start 461.107028 -44.45381)
					(mid 460.723488 -44.83735)
					(end 461.107028 -45.22089)
				)
				(xy 461.53705 -45.22089) (xy 461.53705 -45.033184) (xy 461.411066 -44.9072)
				(arc
					(start 461.36433 -44.9072)
					(mid 460.840413 -44.83735)
					(end 461.36433 -44.7675)
				)
				(xy 461.468978 -44.7675) (xy 461.67675 -44.975272) (xy 461.67675 -45.22089) (xy 461.77835 -45.22089)
				(xy 461.77835 -45.004228) (xy 462.015078 -44.7675)
			)
		)
	)
	(zone
		(net "P12V_PSU")
		(layer "F.Cu")
		(hatch none 0.5)
		(connect_pads
			(clearance 0.5)
		)
		(min_thickness 0.25)
		(fill yes
			(thermal_gap 0.5)
			(thermal_bridge_width 0.5)
			(island_removal_mode 0)
		)
		(polygon
			(pts
				(xy 14.1986 -55.574692) (xy 14.1986 -53.0606) (xy 13.716 -52.578) (xy 13.716 -52.324) (xy 13.716 -50.419)
				(xy 13.3477 -50.0507) (xy 3.3909 -50.0507) (xy 3.0734 -50.3682) (xy 3.0734 -58.928) (xy 3.0734 -59.1058)
				(xy 2.3114 -59.8678) (xy 2.3114 -67.1322) (xy 3.5306 -68.3514) (xy 3.5306 -85.5726) (xy 4.139946 -86.181946)
				(xy 9.844786 -86.181946) (xy 10.541 -85.485732) (xy 10.541 -72.5932) (xy 8.0772 -70.1294) (xy 8.0772 -68.1482)
				(xy 8.077962 -68.147438) (xy 8.077962 -67.932046) (xy 9.0424 -66.967608) (xy 9.0424 -65.7352) (xy 8.89 -65.5828)
				(xy 5.6388 -65.5828) (xy 5.295138 -65.926462) (xy 4.860036 -65.926462) (xy 4.511294 -65.57772) (xy 4.511294 -64.337184)
				(xy 4.83362 -64.014858) (xy 5.277104 -64.014858) (xy 5.524246 -64.262) (xy 5.6134 -64.262) (xy 8.9408 -64.262)
				(xy 9.0424 -64.1604) (xy 9.0424 -62.9412) (xy 9.676638 -62.306962) (xy 9.676638 -57.663842) (xy 11.64336 -55.69712)
				(xy 14.076172 -55.69712)
			)
		)
	)
	(zone
		(layer "F.Cu")
		(hatch none 0.5)
		(connect_pads
			(clearance 0)
		)
		(min_thickness 0.25)
		(keepout
			(tracks not_allowed)
			(vias allowed)
			(pads allowed)
			(copperpour not_allowed)
			(footprints allowed)
		)
		(placement
			(enabled no)
			(sheetname "")
		)
		(fill
			(thermal_gap 0.5)
			(thermal_bridge_width 0.5)
			(island_removal_mode 0)
		)
		(polygon
			(pts
				(arc
					(start 4.629912 -43.710098)
					(mid 6.229858 -45.310044)
					(end 4.629912 -46.90999)
				)
				(arc
					(start 4.629912 -46.90999)
					(mid 3.029966 -45.310044)
					(end 4.629912 -43.710098)
				)
			)
		)
	)
	(zone
		(layer "F.Cu")
		(hatch none 0.5)
		(connect_pads
			(clearance 0)
		)
		(min_thickness 0.25)
		(keepout
			(tracks not_allowed)
			(vias allowed)
			(pads allowed)
			(copperpour not_allowed)
			(footprints allowed)
		)
		(placement
			(enabled no)
			(sheetname "")
		)
		(fill
			(thermal_gap 0.5)
			(thermal_bridge_width 0.5)
			(island_removal_mode 0)
		)
		(polygon
			(pts
				(xy 428.925736 -3.10769) (xy 428.925736 -2.826004) (xy 429.09744 -2.6543)
				(arc
					(start 429.24349 -2.6543)
					(mid 429.767407 -2.72415)
					(end 429.24349 -2.794)
				)
				(xy 429.155352 -2.794) (xy 429.065436 -2.883916) (xy 429.065436 -3.10769)
				(arc
					(start 429.500538 -3.10769)
					(mid 429.884332 -2.724277)
					(end 429.500792 -2.34061)
				)
				(arc
					(start 428.230792 -2.34061)
					(mid 427.847252 -2.72415)
					(end 428.230792 -3.10769)
				)
				(xy 428.684436 -3.10769) (xy 428.684436 -2.875788) (xy 428.602648 -2.794)
				(arc
					(start 428.488094 -2.794)
					(mid 427.964177 -2.72415)
					(end 428.488094 -2.6543)
				)
				(xy 428.66056 -2.6543) (xy 428.824136 -2.817876) (xy 428.824136 -3.10769)
			)
		)
	)
	(zone
		(layer "F.Cu")
		(hatch none 0.5)
		(connect_pads
			(clearance 0)
		)
		(min_thickness 0.25)
		(keepout
			(tracks not_allowed)
			(vias allowed)
			(pads allowed)
			(copperpour not_allowed)
			(footprints allowed)
		)
		(placement
			(enabled no)
			(sheetname "")
		)
		(fill
			(thermal_gap 0.5)
			(thermal_bridge_width 0.5)
			(island_removal_mode 0)
		)
		(polygon
			(pts
				(arc
					(start 450.907912 -49.927764)
					(mid 451.431829 -49.997614)
					(end 450.907912 -50.067464)
				)
				(xy 450.79412 -50.067464) (xy 450.720714 -50.14087) (xy 450.720714 -50.381154)
				(arc
					(start 451.16496 -50.381154)
					(mid 451.548754 -49.997741)
					(end 451.165214 -49.614074)
				)
				(arc
					(start 449.895214 -49.614074)
					(mid 449.511674 -49.997614)
					(end 449.895214 -50.381154)
				)
				(xy 450.339714 -50.381154) (xy 450.339714 -50.14087) (xy 450.266308 -50.067464)
				(arc
					(start 450.152516 -50.067464)
					(mid 449.628599 -49.997614)
					(end 450.152516 -49.927764)
				)
				(xy 450.32422 -49.927764) (xy 450.479414 -50.082958) (xy 450.479414 -50.381154) (xy 450.581014 -50.381154)
				(xy 450.581014 -50.082958) (xy 450.736208 -49.927764)
			)
		)
	)
	(zone
		(layer "F.Cu")
		(hatch none 0.5)
		(connect_pads
			(clearance 0)
		)
		(min_thickness 0.25)
		(keepout
			(tracks allowed)
			(vias allowed)
			(pads allowed)
			(copperpour allowed)
			(footprints allowed)
		)
		(placement
			(enabled no)
			(sheetname "")
		)
		(fill
			(thermal_gap 0.5)
			(thermal_bridge_width 0.5)
			(island_removal_mode 0)
		)
		(polygon
			(pts
				(xy 348.2848 1.4478) (xy 350.5708 1.4478) (xy 350.5708 -0.5588) (xy 348.2848 -0.5588)
			)
		)
	)
	(zone
		(layer "F.Cu")
		(hatch none 0.5)
		(connect_pads
			(clearance 0)
		)
		(min_thickness 0.25)
		(keepout
			(tracks not_allowed)
			(vias allowed)
			(pads allowed)
			(copperpour not_allowed)
			(footprints allowed)
		)
		(placement
			(enabled no)
			(sheetname "")
		)
		(fill
			(thermal_gap 0.5)
			(thermal_bridge_width 0.5)
			(island_removal_mode 0)
		)
		(polygon
			(pts
				(xy 417.622736 -9.639808) (xy 417.622736 -9.85647) (xy 417.386008 -10.093198)
				(arc
					(start 417.286694 -10.093198)
					(mid 416.762777 -10.023348)
					(end 417.286694 -9.953498)
				)
				(xy 417.328096 -9.953498) (xy 417.483036 -9.798558) (xy 417.483036 -9.639808)
				(arc
					(start 417.029392 -9.639808)
					(mid 416.645852 -10.023348)
					(end 417.029392 -10.406888)
				)
				(arc
					(start 418.299138 -10.406888)
					(mid 418.682932 -10.023475)
					(end 418.299392 -9.639808)
				)
				(xy 417.864036 -9.639808) (xy 417.864036 -9.79043) (xy 418.027104 -9.953498)
				(arc
					(start 418.04209 -9.953498)
					(mid 418.566007 -10.023348)
					(end 418.04209 -10.093198)
				)
				(xy 417.969192 -10.093198) (xy 417.724336 -9.848342) (xy 417.724336 -9.639808)
			)
		)
	)
	(zone
		(layer "F.Cu")
		(hatch none 0.5)
		(connect_pads
			(clearance 0)
		)
		(min_thickness 0.25)
		(keepout
			(tracks allowed)
			(vias allowed)
			(pads allowed)
			(copperpour allowed)
			(footprints allowed)
		)
		(placement
			(enabled no)
			(sheetname "")
		)
		(fill
			(thermal_gap 0.5)
			(thermal_bridge_width 0.5)
			(island_removal_mode 0)
		)
		(polygon
			(pts
				(xy 483.411022 -37.9222) (xy 486.8672 -37.9222) (xy 486.8672 -40.3606) (xy 481.4316 -40.3606) (xy 481.384356 -40.3606)
				(xy 479.8568 -38.833044) (xy 479.5266 -38.502844) (xy 479.5266 -37.123116) (xy 479.652584 -36.997132)
				(xy 479.943668 -36.997132) (xy 481.0252 -35.9156) (xy 482.371654 -35.9156) (xy 482.742748 -35.9156)
				(xy 483.255066 -36.427918) (xy 483.255066 -36.799012) (xy 483.255066 -37.766244)
			)
		)
	)
	(zone
		(layer "F.Cu")
		(hatch none 0.5)
		(connect_pads
			(clearance 0)
		)
		(min_thickness 0.25)
		(keepout
			(tracks allowed)
			(vias allowed)
			(pads allowed)
			(copperpour allowed)
			(footprints not_allowed)
		)
		(placement
			(enabled no)
			(sheetname "")
		)
		(fill
			(thermal_gap 0.5)
			(thermal_bridge_width 0.5)
			(island_removal_mode 0)
		)
		(polygon
			(pts
				(xy 328.525378 -11.317986) (xy 328.525378 -14.519148) (xy 187.525406 -14.519148) (xy 187.525406 -11.317986)
			)
		)
	)
	(zone
		(net "GND")
		(layer "F.Cu")
		(hatch none 0.5)
		(connect_pads
			(clearance 0.5)
		)
		(min_thickness 0.25)
		(fill yes
			(thermal_gap 0.5)
			(thermal_bridge_width 0.5)
			(island_removal_mode 0)
		)
		(polygon
			(pts
				(xy 16.110966 -74.547476) (xy 16.118586 -74.539856) (xy 16.118586 -74.455782) (xy 16.07566 -74.412856)
				(xy 15.612364 -74.412856) (xy 15.507208 -74.3077) (xy 15.405862 -74.3077) (xy 15.405862 -74.306938)
				(xy 15.3162 -74.217276) (xy 15.188946 -74.090022) (xy 15.186152 -74.087228) (xy 15.186152 -72.590152)
				(xy 15.01902 -72.42302) (xy 14.683994 -72.42302) (xy 14.36751 -72.106536) (xy 14.36751 -71.899018)
				(xy 14.368526 -71.898002) (xy 14.368526 -71.772526) (xy 14.0462 -71.4502) (xy 12.8016 -71.4502)
				(xy 12.069318 -71.4502) (xy 11.878056 -71.641462) (xy 11.878056 -72.529446) (xy 12.107672 -72.759062)
				(xy 12.5095 -72.759062) (xy 12.753594 -72.514968) (xy 14.075156 -72.514968) (xy 14.384782 -72.824594)
				(xy 14.384782 -73.030842) (xy 14.384782 -73.719182) (xy 15.213076 -74.547476)
			)
		)
	)
	(zone
		(layer "F.Cu")
		(hatch none 0.5)
		(connect_pads
			(clearance 0)
		)
		(min_thickness 0.25)
		(keepout
			(tracks allowed)
			(vias allowed)
			(pads allowed)
			(copperpour allowed)
			(footprints allowed)
		)
		(placement
			(enabled no)
			(sheetname "")
		)
		(fill
			(thermal_gap 0.5)
			(thermal_bridge_width 0.5)
			(island_removal_mode 0)
		)
		(polygon
			(pts
				(xy 382.143 -158.75) (xy 388.874 -158.75) (xy 389.255 -158.369) (xy 389.255 -154.305) (xy 388.366 -153.416)
				(xy 381.889 -153.416) (xy 381.409956 -153.895044) (xy 381.409956 -158.016956)
			)
		)
	)
	(zone
		(net "VR_P5V_STBY_BOOT")
		(layer "F.Cu")
		(hatch none 0.5)
		(connect_pads
			(clearance 0.5)
		)
		(min_thickness 0.25)
		(fill yes
			(thermal_gap 0.5)
			(thermal_bridge_width 0.5)
			(island_removal_mode 0)
		)
		(polygon
			(pts
				(xy 393.474702 -68.55587) (xy 393.465558 -68.565014) (xy 393.465558 -69.982334) (xy 393.511024 -70.0278)
				(xy 395.1605 -70.0278) (xy 395.1732 -70.0151) (xy 395.1732 -68.961) (xy 394.76807 -68.55587)
			)
		)
		(polygon
			(pts
				(xy 394.38453 -69.17055) (xy 394.18133 -69.17055) (xy 394.18133 -69.37375) (xy 394.38453 -69.37375)
			)
		)
	)
	(zone
		(layer "F.Cu")
		(hatch none 0.5)
		(connect_pads
			(clearance 0)
		)
		(min_thickness 0.25)
		(keepout
			(tracks not_allowed)
			(vias allowed)
			(pads allowed)
			(copperpour not_allowed)
			(footprints allowed)
		)
		(placement
			(enabled no)
			(sheetname "")
		)
		(fill
			(thermal_gap 0.5)
			(thermal_bridge_width 0.5)
			(island_removal_mode 0)
		)
		(polygon
			(pts
				(xy 371.623844 -10.293858) (xy 372.131844 -10.293858) (xy 372.131844 -10.649458) (xy 371.623844 -10.649458)
			)
		)
	)
	(zone
		(net "P5V_STBY")
		(layer "F.Cu")
		(hatch none 0.5)
		(connect_pads
			(clearance 0.5)
		)
		(min_thickness 0.25)
		(fill yes
			(thermal_gap 0.5)
			(thermal_bridge_width 0.5)
			(island_removal_mode 0)
		)
		(polygon
			(pts
				(xy 179.436776 -112.861344) (xy 179.681378 -112.616742) (xy 180.015388 -112.616742) (xy 180.325522 -112.92713)
				(xy 180.325522 -115.714018) (xy 180.598826 -115.987322) (xy 180.598826 -123.028456) (xy 180.4416 -123.185682)
				(xy 179.721002 -123.185682) (xy 179.436776 -122.901456)
			)
		)
	)
	(zone
		(layer "F.Cu")
		(hatch none 0.5)
		(connect_pads
			(clearance 0)
		)
		(min_thickness 0.25)
		(keepout
			(tracks allowed)
			(vias allowed)
			(pads allowed)
			(copperpour allowed)
			(footprints allowed)
		)
		(placement
			(enabled no)
			(sheetname "")
		)
		(fill
			(thermal_gap 0.5)
			(thermal_bridge_width 0.5)
			(island_removal_mode 0)
		)
		(polygon
			(pts
				(xy 374.523 -154.305) (xy 376.809 -154.305) (xy 376.809 -156.3116) (xy 374.523 -156.3116)
			)
		)
	)
	(zone
		(layer "F.Cu")
		(hatch none 0.5)
		(connect_pads
			(clearance 0)
		)
		(min_thickness 0.25)
		(keepout
			(tracks allowed)
			(vias allowed)
			(pads allowed)
			(copperpour allowed)
			(footprints allowed)
		)
		(placement
			(enabled no)
			(sheetname "")
		)
		(fill
			(thermal_gap 0.5)
			(thermal_bridge_width 0.5)
			(island_removal_mode 0)
		)
		(polygon
			(pts
				(xy 2.4638 -8.382) (xy 2.4638 -10.3886) (xy 2.4638 -11.173714) (xy 2.195576 -11.441938) (xy 0.536448 -11.441938)
				(xy 0.1778 -11.08329) (xy 0.1778 -10.3886) (xy 0.1778 -8.382) (xy 1.524 -7.0358) (xy 1.524 -6.4008)
				(xy 2.159 -5.7658) (xy 4.953 -5.7658) (xy 4.953 -7.2898) (xy 4.699 -7.5438) (xy 2.667 -7.5438) (xy 2.54 -7.6708)
				(xy 2.54 -8.3058)
			)
		)
	)
	(zone
		(net "P1V05_PCH_STBY")
		(layer "F.Cu")
		(hatch none 0.5)
		(connect_pads
			(clearance 0.5)
		)
		(min_thickness 0.25)
		(fill yes
			(thermal_gap 0.5)
			(thermal_bridge_width 0.5)
			(island_removal_mode 0)
		)
		(polygon
			(pts
				(xy 393.065 -110.744) (xy 392.684 -110.744) (xy 392.6713 -110.7313) (xy 392.4427 -110.7313) (xy 392.3284 -110.617)
				(xy 392.08964 -110.37824) (xy 391.90676 -110.19536) (xy 391.90676 -107.43184) (xy 392.08964 -107.24896)
				(xy 392.3284 -107.0102) (xy 392.33094 -107.00766) (xy 392.43 -106.908346) (xy 392.658346 -106.68)
				(xy 393.065 -106.68) (xy 393.192 -106.68) (xy 393.446 -106.934) (xy 393.446 -109.093) (xy 393.954 -109.601)
				(xy 393.954 -109.855)
			)
		)
	)
	(zone
		(net "GND")
		(layer "F.Cu")
		(hatch none 0.5)
		(connect_pads
			(clearance 0.5)
		)
		(min_thickness 0.25)
		(fill yes
			(thermal_gap 0.5)
			(thermal_bridge_width 0.5)
			(island_removal_mode 0)
		)
		(polygon
			(pts
				(xy 346.648532 -126.283212) (xy 346.648532 -126.681484) (xy 346.846652 -126.879604) (xy 346.846652 -127.377952)
				(xy 346.869258 -127.400558) (xy 347.355414 -127.400558) (xy 347.37548 -127.380492) (xy 347.37548 -126.288546)
				(xy 347.199712 -126.112778) (xy 346.818966 -126.112778)
			)
		)
	)
	(zone
		(layer "F.Cu")
		(hatch none 0.5)
		(connect_pads
			(clearance 0)
		)
		(min_thickness 0.25)
		(keepout
			(tracks allowed)
			(vias allowed)
			(pads allowed)
			(copperpour allowed)
			(footprints not_allowed)
		)
		(placement
			(enabled no)
			(sheetname "")
		)
		(fill
			(thermal_gap 0.5)
			(thermal_bridge_width 0.5)
			(island_removal_mode 0)
		)
		(polygon
			(pts
				(arc
					(start 56.999886 -74.650092)
					(mid 58.899806 -76.550012)
					(end 56.999886 -78.449932)
				)
				(arc
					(start 56.999886 -78.449932)
					(mid 55.099966 -76.550012)
					(end 56.999886 -74.650092)
				)
			)
		)
	)
	(zone
		(net "P12V_STBY")
		(layer "F.Cu")
		(hatch none 0.5)
		(connect_pads
			(clearance 0.5)
		)
		(min_thickness 0.25)
		(fill yes
			(thermal_gap 0.5)
			(thermal_bridge_width 0.5)
			(island_removal_mode 0)
		)
		(polygon
			(pts
				(xy 360.2482 -146.7358) (xy 364.363 -146.7358) (xy 364.5408 -146.558) (xy 364.5408 -144.4752) (xy 364.3376 -144.272)
				(xy 360.299 -144.272) (xy 359.39476 -144.272) (xy 359.049828 -144.616932) (xy 359.049828 -146.43989)
				(xy 359.345738 -146.7358)
			)
		)
	)
	(zone
		(layer "F.Cu")
		(hatch none 0.5)
		(connect_pads
			(clearance 0)
		)
		(min_thickness 0.25)
		(keepout
			(tracks not_allowed)
			(vias allowed)
			(pads allowed)
			(copperpour not_allowed)
			(footprints allowed)
		)
		(placement
			(enabled no)
			(sheetname "")
		)
		(fill
			(thermal_gap 0.5)
			(thermal_bridge_width 0.5)
			(island_removal_mode 0)
		)
		(polygon
			(pts
				(arc
					(start 428.10049 -58.996834)
					(mid 431.700432 -55.396892)
					(end 435.300374 -58.996834)
				)
				(arc
					(start 435.300374 -60.59678)
					(mid 431.700432 -64.196722)
					(end 428.10049 -60.59678)
				)
			)
		)
	)
	(zone
		(layer "F.Cu")
		(hatch none 0.5)
		(connect_pads
			(clearance 0)
		)
		(min_thickness 0.25)
		(keepout
			(tracks allowed)
			(vias allowed)
			(pads allowed)
			(copperpour allowed)
			(footprints allowed)
		)
		(placement
			(enabled no)
			(sheetname "")
		)
		(fill
			(thermal_gap 0.5)
			(thermal_bridge_width 0.5)
			(island_removal_mode 0)
		)
		(polygon
			(pts
				(xy 146.177 -59.69) (xy 146.177 -58.547) (xy 147.066 -58.547) (xy 147.066 -59.69)
			)
		)
	)
	(zone
		(layer "F.Cu")
		(hatch none 0.5)
		(connect_pads
			(clearance 0)
		)
		(min_thickness 0.25)
		(keepout
			(tracks allowed)
			(vias allowed)
			(pads allowed)
			(copperpour allowed)
			(footprints not_allowed)
		)
		(placement
			(enabled no)
			(sheetname "")
		)
		(fill
			(thermal_gap 0.5)
			(thermal_bridge_width 0.5)
			(island_removal_mode 0)
		)
		(polygon
			(pts
				(arc
					(start 409.719526 -80.88376)
					(mid 405.719534 -76.883768)
					(end 409.719526 -72.883776)
				)
				(arc
					(start 409.719526 -72.883776)
					(mid 413.719518 -76.883768)
					(end 409.719526 -80.88376)
				)
			)
		)
	)
	(zone
		(net "GND")
		(layer "F.Cu")
		(hatch none 0.5)
		(connect_pads
			(clearance 0.5)
		)
		(min_thickness 0.25)
		(fill yes
			(thermal_gap 0.5)
			(thermal_bridge_width 0.5)
			(island_removal_mode 0)
		)
		(polygon
			(pts
				(xy 96.040702 -3.971544) (xy 96.393 -3.971544) (xy 96.647 -3.717544) (xy 96.647 -1.651) (xy 96.380046 -1.384046)
				(xy 95.31858 -1.384046) (xy 95.198184 -1.504442) (xy 95.198184 -2.0955) (xy 95.377 -2.274316) (xy 95.377 -3.81)
				(xy 95.504 -3.937) (xy 96.040702 -3.937)
			)
		)
	)
	(zone
		(net "P1V8_MCP_CPU0")
		(layer "F.Cu")
		(hatch none 0.5)
		(connect_pads
			(clearance 0.5)
		)
		(min_thickness 0.25)
		(fill yes
			(thermal_gap 0.5)
			(thermal_bridge_width 0.5)
			(island_removal_mode 0)
		)
		(polygon
			(pts
				(xy 283.275024 -81.874106) (xy 282.864306 -81.874106) (xy 282.5242 -81.534) (xy 281.4066 -81.534)
				(xy 281.304492 -81.431892) (xy 281.304492 -80.542892) (xy 281.369516 -80.477614) (xy 282.839414 -80.477614)
				(xy 283.27477 -80.042258) (xy 283.27477 -78.699868) (xy 283.783024 -78.191614) (xy 285.688024 -78.191614)
				(xy 285.692088 -78.195932) (xy 286.183578 -78.195932) (xy 286.634174 -78.646528) (xy 286.634174 -79.620618)
				(xy 285.688024 -80.566768) (xy 285.688024 -81.090516) (xy 284.904434 -81.874106)
			)
		)
		(polygon
			(pts
				(arc
					(start 285.247334 -80.669384)
					(mid 284.612334 -80.669384)
					(end 285.247334 -80.669384)
				)
			)
		)
		(polygon
			(pts
				(arc
					(start 285.247334 -79.678784)
					(mid 284.612334 -79.678784)
					(end 285.247334 -79.678784)
				)
			)
		)
		(polygon
			(pts
				(arc
					(start 285.247334 -78.688438)
					(mid 284.612334 -78.688438)
					(end 285.247334 -78.688438)
				)
			)
		)
	)
	(zone
		(net "VR_PVDDQ_GHJ_PH1_SW")
		(layer "F.Cu")
		(hatch none 0.5)
		(connect_pads
			(clearance 0.5)
		)
		(min_thickness 0.25)
		(fill yes
			(thermal_gap 0.5)
			(thermal_bridge_width 0.5)
			(island_removal_mode 0)
		)
		(polygon
			(pts
				(xy 7.5184 -7.4168) (xy 7.5184 -11.5062) (xy 7.5184 -11.684) (xy 7.7978 -11.9634) (xy 7.9756 -11.9634)
				(xy 11.966702 -11.9634) (xy 12.573 -11.9634) (xy 12.954 -11.5824) (xy 12.954 -7.5184) (xy 12.5095 -7.0739)
				(xy 9.31418 -7.0739) (xy 9.1186 -6.87832) (xy 7.64032 -6.87832) (xy 7.5184 -7.00024) (xy 7.5184 -7.29361)
			)
		)
	)
	(zone
		(net "VR_PVCCIN_CPU1_PHASE4")
		(layer "F.Cu")
		(hatch none 0.5)
		(connect_pads
			(clearance 0.5)
		)
		(min_thickness 0.25)
		(fill yes
			(thermal_gap 0.5)
			(thermal_bridge_width 0.5)
			(island_removal_mode 0)
		)
		(polygon
			(pts
				(xy 36.4744 -84.039202) (xy 40.303196 -84.039202) (xy 41.385998 -84.039202) (xy 41.8592 -83.566)
				(xy 41.8592 -79.4258) (xy 41.392602 -78.959202) (xy 40.303196 -78.959202) (xy 36.4744 -78.959202)
			)
		)
	)
	(zone
		(net "VR_PVPP_KLM_BOOT_R")
		(layer "F.Cu")
		(hatch none 0.5)
		(connect_pads
			(clearance 0.5)
		)
		(min_thickness 0.25)
		(fill yes
			(thermal_gap 0.5)
			(thermal_bridge_width 0.5)
			(island_removal_mode 0)
		)
		(polygon
			(pts
				(xy 171.167044 -133.233414) (xy 171.173648 -133.22681) (xy 172.516292 -133.22681) (xy 172.543216 -133.253734)
				(xy 172.543216 -134.342124) (xy 172.451268 -134.434072) (xy 172.23994 -134.6454) (xy 170.6753 -134.6454)
				(xy 170.59148 -134.56158) (xy 170.59148 -133.50748) (xy 170.865546 -133.233414)
			)
		)
	)
	(zone
		(net "P12V_STBY")
		(layer "F.Cu")
		(hatch none 0.5)
		(connect_pads
			(clearance 0.5)
		)
		(min_thickness 0.25)
		(fill yes
			(thermal_gap 0.5)
			(thermal_bridge_width 0.5)
			(island_removal_mode 0)
		)
		(polygon
			(pts
				(xy 20.4724 -59.9948) (xy 21.971 -59.9948) (xy 22.3139 -60.3377) (xy 25.3873 -60.3377) (xy 25.527 -60.198)
				(xy 26.035 -59.69) (xy 26.035 -54.5084) (xy 24.4602 -52.9336) (xy 21.4122 -52.9336) (xy 20.3708 -53.975)
				(xy 20.3708 -59.8932)
			)
		)
	)
	(zone
		(net "PVDDQ_ABC")
		(layer "F.Cu")
		(hatch none 0.5)
		(connect_pads
			(clearance 0.5)
		)
		(min_thickness 0.25)
		(fill yes
			(thermal_gap 0.5)
			(thermal_bridge_width 0.5)
			(island_removal_mode 0)
		)
		(polygon
			(pts
				(xy 266.32154 -11.47826) (xy 266.0142 -11.7856) (xy 266.0142 -12.8524) (xy 266.319 -13.1572) (xy 266.319 -14.0208)
				(xy 266.6873 -14.3891) (xy 269.1384 -14.3891) (xy 269.24 -14.4907) (xy 269.24 -15.5321) (xy 269.3924 -15.6845)
				(xy 269.6083 -15.6845) (xy 269.7607 -15.5321) (xy 269.7607 -14.4907) (xy 269.8623 -14.3891) (xy 277.4315 -14.3891)
				(xy 278.0792 -13.7414) (xy 278.0792 -12.0142) (xy 277.54326 -11.47826)
			)
		)
		(polygon
			(pts
				(xy 275.657564 -13.3477) (xy 275.454364 -13.3477) (xy 275.454364 -13.5509) (xy 275.657564 -13.5509)
			)
		)
		(polygon
			(pts
				(xy 272.518632 -13.3477) (xy 272.315432 -13.3477) (xy 272.315432 -13.5509) (xy 272.518632 -13.5509)
			)
		)
		(polygon
			(pts
				(xy 269.216632 -13.3477) (xy 269.013432 -13.3477) (xy 269.013432 -13.5509) (xy 269.216632 -13.5509)
			)
		)
		(polygon
			(pts
				(xy 272.518632 -12.3571) (xy 272.315432 -12.3571) (xy 272.315432 -12.5603) (xy 272.518632 -12.5603)
			)
		)
		(polygon
			(pts
				(xy 269.216632 -12.3571) (xy 269.013432 -12.3571) (xy 269.013432 -12.5603) (xy 269.216632 -12.5603)
			)
		)
	)
	(zone
		(layer "F.Cu")
		(hatch none 0.5)
		(connect_pads
			(clearance 0)
		)
		(min_thickness 0.25)
		(keepout
			(tracks allowed)
			(vias allowed)
			(pads allowed)
			(copperpour allowed)
			(footprints not_allowed)
		)
		(placement
			(enabled no)
			(sheetname "")
		)
		(fill
			(thermal_gap 0.5)
			(thermal_bridge_width 0.5)
			(island_removal_mode 0)
		)
		(polygon
			(pts
				(arc
					(start -0.94996 -54.909974)
					(mid -1.999996 -55.96001)
					(end -3.050032 -54.909974)
				)
				(arc
					(start -3.050032 -54.909974)
					(mid -1.999996 -53.859938)
					(end -0.94996 -54.909974)
				)
			)
		)
	)
	(zone
		(layer "F.Cu")
		(hatch none 0.5)
		(connect_pads
			(clearance 0)
		)
		(min_thickness 0.25)
		(keepout
			(tracks allowed)
			(vias allowed)
			(pads allowed)
			(copperpour allowed)
			(footprints allowed)
		)
		(placement
			(enabled no)
			(sheetname "")
		)
		(fill
			(thermal_gap 0.5)
			(thermal_bridge_width 0.5)
			(island_removal_mode 0)
		)
		(polygon
			(pts
				(xy 208.534 -24.511) (xy 208.534 -22.479) (xy 210.693 -22.479) (xy 210.693 -24.511)
			)
		)
	)
	(zone
		(net "GND")
		(layer "F.Cu")
		(hatch none 0.5)
		(connect_pads
			(clearance 0.5)
		)
		(min_thickness 0.25)
		(fill yes
			(thermal_gap 0.5)
			(thermal_bridge_width 0.5)
			(island_removal_mode 0)
		)
		(polygon
			(pts
				(xy 256.337054 -134.177024) (xy 257.608832 -134.177024) (xy 257.717036 -134.177024) (xy 257.790696 -134.250684)
				(xy 257.790696 -134.752334) (xy 257.716528 -134.826502) (xy 257.55473 -134.826502) (xy 257.266186 -134.826502)
				(xy 256.177288 -135.9154) (xy 243.918232 -135.9154) (xy 243.556028 -136.277604) (xy 243.428012 -136.40562)
				(xy 243.428012 -136.468612) (xy 243.428012 -137.724388) (xy 243.2558 -137.8966) (xy 242.9764 -137.8966)
				(xy 242.8494 -137.7696) (xy 242.8494 -134.977632) (xy 242.876832 -134.9502) (xy 243.015008 -134.812024)
				(xy 244.094 -134.812024) (xy 244.3226 -134.812024) (xy 255.651 -134.812024) (xy 255.7145 -134.748524)
				(xy 256.059686 -134.748524) (xy 256.296668 -134.511542) (xy 256.296668 -134.21741)
			)
		)
	)
	(zone
		(net "VR_FET_SW_P12V_STBY_PVCCIO_CPU0")
		(layer "F.Cu")
		(hatch none 0.5)
		(connect_pads
			(clearance 0.5)
		)
		(min_thickness 0.25)
		(fill yes
			(thermal_gap 0.5)
			(thermal_bridge_width 0.5)
			(island_removal_mode 0)
		)
		(polygon
			(pts
				(xy 347.55455 -93.472) (xy 347.3704 -93.65615) (xy 347.3704 -97.0534) (xy 347.472 -97.155) (xy 349.2246 -97.155)
				(xy 349.3008 -97.0788) (xy 349.3008 -95.7072) (xy 349.4024 -95.6056) (xy 350.4057 -95.6056) (xy 350.9899 -95.0214)
				(xy 351.3582 -95.0214) (xy 351.4344 -94.9452) (xy 351.4344 -94.3483) (xy 351.60458 -94.17812) (xy 353.81692 -94.17812)
				(xy 354.142294 -94.17812) (xy 354.456746 -94.492572) (xy 354.456746 -94.817946) (xy 354.7618 -95.123)
				(xy 354.7618 -97.098866) (xy 355.565456 -97.902522) (xy 355.565456 -97.941384) (xy 355.565456 -99.538282)
				(xy 354.341938 -100.7618) (xy 353.9236 -100.7618) (xy 351.3582 -100.7618) (xy 351.1042 -101.0158)
				(xy 350.4692 -101.0158) (xy 350.139 -101.346) (xy 350.139 -101.727) (xy 350.012 -101.854) (xy 348.9706 -101.854)
				(xy 348.662752 -102.161848) (xy 348.662752 -102.301802) (xy 348.380304 -102.58425) (xy 348.24035 -102.58425)
				(xy 345.83751 -102.58425) (xy 345.712796 -102.708964) (xy 345.712796 -103.818182) (xy 345.780614 -103.886)
				(xy 350.089724 -103.886) (xy 351.781872 -103.886) (xy 351.891854 -103.776018) (xy 352.194622 -103.776018)
				(xy 353.247198 -103.776018) (xy 353.4029 -103.620316) (xy 353.4029 -102.56774) (xy 353.4029 -102.151688)
				(xy 353.439984 -102.114604) (xy 353.564952 -101.989636) (xy 357.072184 -101.989636) (xy 357.32212 -101.7397)
				(xy 357.32212 -94.35338) (xy 356.20833 -93.23959) (xy 356.202742 -93.23959) (xy 355.864922 -92.90177)
				(xy 355.79431 -92.831158) (xy 348.195392 -92.831158) (xy 348.12478 -92.90177) (xy 347.83395 -93.1926)
			)
		)
	)
	(zone
		(layer "F.Cu")
		(hatch none 0.5)
		(connect_pads
			(clearance 0)
		)
		(min_thickness 0.25)
		(keepout
			(tracks not_allowed)
			(vias allowed)
			(pads allowed)
			(copperpour not_allowed)
			(footprints allowed)
		)
		(placement
			(enabled no)
			(sheetname "")
		)
		(fill
			(thermal_gap 0.5)
			(thermal_bridge_width 0.5)
			(island_removal_mode 0)
		)
		(polygon
			(pts
				(arc
					(start 291.999924 -109.009942)
					(mid 294.539924 -111.549942)
					(end 291.999924 -114.089942)
				)
				(arc
					(start 291.999924 -114.089942)
					(mid 289.459924 -111.549942)
					(end 291.999924 -109.009942)
				)
			)
		)
	)
	(zone
		(layer "F.Cu")
		(hatch none 0.5)
		(connect_pads
			(clearance 0)
		)
		(min_thickness 0.25)
		(keepout
			(tracks not_allowed)
			(vias allowed)
			(pads allowed)
			(copperpour not_allowed)
			(footprints allowed)
		)
		(placement
			(enabled no)
			(sheetname "")
		)
		(fill
			(thermal_gap 0.5)
			(thermal_bridge_width 0.5)
			(island_removal_mode 0)
		)
		(polygon
			(pts
				(arc
					(start 13.028676 -33.975802)
					(mid 13.098526 -33.451885)
					(end 13.168376 -33.975802)
				)
				(xy 13.168376 -34.089594) (xy 13.241782 -34.163) (xy 13.482066 -34.163)
				(arc
					(start 13.482066 -33.7185)
					(mid 13.098526 -33.33496)
					(end 12.714986 -33.7185)
				)
				(arc
					(start 12.714986 -34.988246)
					(mid 13.098399 -35.37204)
					(end 13.482066 -34.9885)
				)
				(xy 13.482066 -34.544) (xy 13.241782 -34.544) (xy 13.168376 -34.617406)
				(arc
					(start 13.168376 -34.731198)
					(mid 13.098526 -35.255115)
					(end 13.028676 -34.731198)
				)
				(xy 13.028676 -34.559494) (xy 13.18387 -34.4043) (xy 13.482066 -34.4043) (xy 13.482066 -34.3027)
				(xy 13.18387 -34.3027) (xy 13.028676 -34.147506)
			)
		)
	)
	(zone
		(net "GND")
		(layer "F.Cu")
		(hatch none 0.5)
		(connect_pads
			(clearance 0.5)
		)
		(min_thickness 0.25)
		(fill yes
			(thermal_gap 0.5)
			(thermal_bridge_width 0.5)
			(island_removal_mode 0)
		)
		(polygon
			(pts
				(xy 169.1132 -46.5074) (xy 168.9862 -46.6344) (xy 168.9862 -49.7332) (xy 170.18 -50.927) (xy 173.99 -50.927)
				(xy 174.244 -51.181) (xy 176.022 -51.181) (xy 176.276 -50.927) (xy 176.276 -50.165) (xy 176.6062 -49.8348)
				(xy 176.6062 -46.5836) (xy 176.53 -46.5074)
			)
		)
	)
	(zone
		(layer "F.Cu")
		(hatch none 0.5)
		(connect_pads
			(clearance 0)
		)
		(min_thickness 0.25)
		(keepout
			(tracks allowed)
			(vias allowed)
			(pads allowed)
			(copperpour allowed)
			(footprints allowed)
		)
		(placement
			(enabled no)
			(sheetname "")
		)
		(fill
			(thermal_gap 0.5)
			(thermal_bridge_width 0.5)
			(island_removal_mode 0)
		)
		(polygon
			(pts
				(xy 112.494568 -104.521) (xy 112.494568 -106.172) (xy 112.494568 -106.807) (xy 106.271568 -106.807)
				(xy 106.271568 -106.172) (xy 106.271568 -104.521) (xy 106.271568 -104.14) (xy 112.494568 -104.14)
			)
		)
	)
	(zone
		(layer "F.Cu")
		(hatch none 0.5)
		(connect_pads
			(clearance 0)
		)
		(min_thickness 0.25)
		(keepout
			(tracks allowed)
			(vias allowed)
			(pads allowed)
			(copperpour allowed)
			(footprints allowed)
		)
		(placement
			(enabled no)
			(sheetname "")
		)
		(fill
			(thermal_gap 0.5)
			(thermal_bridge_width 0.5)
			(island_removal_mode 0)
		)
		(polygon
			(pts
				(xy 456.113642 -137.831576) (xy 458.436218 -137.831576) (xy 458.475588 -137.792206) (xy 458.475588 -136.678416)
				(xy 458.372972 -136.5758) (xy 456.105768 -136.5758) (xy 455.884788 -136.79678) (xy 455.884788 -137.602722)
			)
		)
	)
	(zone
		(layer "F.Cu")
		(hatch none 0.5)
		(connect_pads
			(clearance 0)
		)
		(min_thickness 0.25)
		(keepout
			(tracks not_allowed)
			(vias allowed)
			(pads allowed)
			(copperpour not_allowed)
			(footprints allowed)
		)
		(placement
			(enabled no)
			(sheetname "")
		)
		(fill
			(thermal_gap 0.5)
			(thermal_bridge_width 0.5)
			(island_removal_mode 0)
		)
		(polygon
			(pts
				(xy 408.197304 -96.241108)
				(arc
					(start 408.330146 -96.37395)
					(mid 408.657782 -96.790486)
					(end 408.241246 -96.46285)
				)
				(xy 408.14498 -96.366584) (xy 408.060144 -96.366584)
				(arc
					(start 408.060144 -96.601788)
					(mid 408.469084 -97.010728)
					(end 408.878024 -96.601788)
				)
				(arc
					(start 408.878024 -95.547688)
					(mid 408.469211 -95.138494)
					(end 408.060144 -95.547434)
				)
				(xy 408.060144 -95.783908) (xy 408.14371 -95.783908)
				(arc
					(start 408.241246 -95.686372)
					(mid 408.657782 -95.358736)
					(end 408.330146 -95.775272)
				)
				(xy 408.196034 -95.909384) (xy 408.060144 -95.909384) (xy 408.060144 -96.241108)
			)
		)
	)
	(zone
		(net "GND")
		(layer "F.Cu")
		(hatch none 0.5)
		(connect_pads
			(clearance 0.5)
		)
		(min_thickness 0.25)
		(fill yes
			(thermal_gap 0.5)
			(thermal_bridge_width 0.5)
			(island_removal_mode 0)
		)
		(polygon
			(pts
				(xy 411.4546 -60.6552) (xy 409.6766 -60.6552) (xy 409.4988 -60.4774) (xy 409.4988 -59.1566) (xy 409.7274 -58.928)
				(xy 412.3436 -58.928) (xy 413.2707 -58.0009) (xy 414.7947 -58.0009) (xy 415.0614 -57.7342) (xy 415.0614 -56.4134)
				(xy 415.0868 -56.388) (xy 415.417 -56.388) (xy 415.4678 -56.4388) (xy 415.4678 -57.6834) (xy 415.798 -58.0136)
				(xy 416.6362 -58.0136) (xy 417.0426 -58.42) (xy 417.0426 -60.2742) (xy 415.4678 -61.849) (xy 415.4678 -62.3062)
				(xy 415.3662 -62.4078) (xy 413.766 -62.4078) (xy 413.7406 -62.3824) (xy 413.7406 -61.8236) (xy 414.2486 -61.3156)
				(xy 414.2486 -60.6806) (xy 413.8676 -60.2996) (xy 413.258 -60.2996) (xy 412.9024 -60.6552)
			)
		)
	)
	(zone
		(layer "F.Cu")
		(hatch none 0.5)
		(connect_pads
			(clearance 0)
		)
		(min_thickness 0.25)
		(keepout
			(tracks not_allowed)
			(vias allowed)
			(pads allowed)
			(copperpour not_allowed)
			(footprints allowed)
		)
		(placement
			(enabled no)
			(sheetname "")
		)
		(fill
			(thermal_gap 0.5)
			(thermal_bridge_width 0.5)
			(island_removal_mode 0)
		)
		(polygon
			(pts
				(xy 412.59633 -10.01141) (xy 412.59633 -9.754108)
				(arc
					(start 412.15183 -9.75106)
					(mid 411.76575 -10.13206)
					(end 412.14675 -10.51814)
				)
				(arc
					(start 413.436816 -10.526776)
					(mid 413.822895 -10.145903)
					(end 413.44215 -9.759696)
				)
				(xy 412.97733 -9.756648) (xy 412.97733 -10.01903) (xy 413.031686 -10.073386)
				(arc
					(start 413.182308 -10.073386)
					(mid 413.706225 -10.143236)
					(end 413.182308 -10.213086)
				)
				(xy 412.973774 -10.213086) (xy 412.83763 -10.076942) (xy 412.83763 -9.755632) (xy 412.73603 -9.75487)
				(xy 412.73603 -10.069322) (xy 412.600902 -10.20445)
				(arc
					(start 412.406592 -10.20445)
					(mid 411.882675 -10.1346)
					(end 412.406592 -10.06475)
				)
				(xy 412.54299 -10.06475)
			)
		)
	)
	(zone
		(layer "F.Cu")
		(hatch none 0.5)
		(connect_pads
			(clearance 0)
		)
		(min_thickness 0.25)
		(keepout
			(tracks allowed)
			(vias allowed)
			(pads allowed)
			(copperpour allowed)
			(footprints allowed)
		)
		(placement
			(enabled no)
			(sheetname "")
		)
		(fill
			(thermal_gap 0.5)
			(thermal_bridge_width 0.5)
			(island_removal_mode 0)
		)
		(polygon
			(pts
				(xy 4.1656 -11.3284) (xy 4.1656 -6.9596) (xy 6.5786 -6.9596) (xy 6.5786 -11.3284)
			)
		)
	)
	(zone
		(net "GND")
		(layer "F.Cu")
		(hatch none 0.5)
		(connect_pads
			(clearance 0.5)
		)
		(min_thickness 0.25)
		(fill yes
			(thermal_gap 0.5)
			(thermal_bridge_width 0.5)
			(island_removal_mode 0)
		)
		(polygon
			(pts
				(xy 19.05 -55.518304) (xy 19.05 -53.1114) (xy 18.5928 -52.6542) (xy 15.5448 -52.6542) (xy 15.511526 -52.6542)
				(xy 14.9606 -52.103274) (xy 14.9606 -52.07) (xy 14.9606 -50.1396) (xy 14.732 -49.911) (xy 14.224508 -49.911)
				(xy 14.096492 -50.039016) (xy 14.096492 -52.348892) (xy 14.8336 -53.086) (xy 14.98854 -53.24094)
				(xy 14.98854 -55.546752) (xy 15.113508 -55.67172) (xy 18.896584 -55.67172)
			)
		)
	)
	(zone
		(net "PVDDQ_KLM")
		(layer "F.Cu")
		(hatch none 0.5)
		(connect_pads
			(clearance 0.5)
		)
		(min_thickness 0.25)
		(fill yes
			(thermal_gap 0.5)
			(thermal_bridge_width 0.5)
			(island_removal_mode 0)
		)
		(polygon
			(pts
				(arc
					(start 102.29342 -138.768836)
					(mid 102.201076 -138.828623)
					(end 102.21722 -138.937492)
				)
				(arc
					(start 102.21722 -138.937492)
					(mid 101.949504 -139.528213)
					(end 101.681788 -138.937492)
				)
				(arc
					(start 101.681788 -138.937492)
					(mid 101.698017 -138.828585)
					(end 101.605588 -138.768836)
				)
				(xy 100.928932 -138.768836) (xy 100.677726 -139.020042)
				(arc
					(start 100.677726 -140.856716)
					(mid 100.739948 -140.950375)
					(end 100.850446 -140.92936)
				)
				(arc
					(start 100.850446 -140.92936)
					(mid 101.273295 -140.873249)
					(end 101.446584 -141.263116)
				)
				(arc
					(start 101.446584 -141.263116)
					(mid 101.466206 -141.349074)
					(end 101.545644 -141.387322)
				)
				(arc
					(start 102.352602 -141.387322)
					(mid 102.431785 -141.349382)
					(end 102.451916 -141.263878)
				)
				(arc
					(start 102.451916 -141.263878)
					(mid 102.799642 -140.831701)
					(end 103.147368 -141.263878)
				)
				(arc
					(start 103.147368 -141.263878)
					(mid 103.16743 -141.349437)
					(end 103.246682 -141.387322)
				)
				(xy 103.323136 -141.387322) (xy 103.323136 -141.326616)
				(arc
					(start 103.319326 -141.317472)
					(mid 103.621045 -140.828803)
					(end 103.996744 -141.263116)
				)
				(arc
					(start 103.996744 -141.263116)
					(mid 104.016366 -141.349074)
					(end 104.095804 -141.387322)
				)
				(arc
					(start 104.902762 -141.387322)
					(mid 104.981945 -141.349382)
					(end 105.002076 -141.263878)
				)
				(arc
					(start 105.002076 -141.263878)
					(mid 105.349802 -140.831701)
					(end 105.697528 -141.263878)
				)
				(arc
					(start 105.697528 -141.263878)
					(mid 105.71759 -141.349437)
					(end 105.796842 -141.387322)
				)
				(arc
					(start 106.602784 -141.387322)
					(mid 106.681967 -141.349382)
					(end 106.702098 -141.263878)
				)
				(arc
					(start 106.702098 -141.263878)
					(mid 107.049824 -140.831701)
					(end 107.39755 -141.263878)
				)
				(arc
					(start 107.39755 -141.263878)
					(mid 107.417612 -141.349437)
					(end 107.496864 -141.387322)
				)
				(xy 107.573064 -141.387322) (xy 107.573064 -141.326616)
				(arc
					(start 107.569254 -141.317472)
					(mid 107.870973 -140.828803)
					(end 108.246672 -141.263116)
				)
				(arc
					(start 108.246672 -141.263116)
					(mid 108.266294 -141.349074)
					(end 108.345732 -141.387322)
				)
				(arc
					(start 109.153198 -141.387322)
					(mid 109.232631 -141.34907)
					(end 109.252258 -141.263116)
				)
				(arc
					(start 109.252258 -141.263116)
					(mid 109.599476 -140.827721)
					(end 109.946694 -141.263116)
				)
				(arc
					(start 109.946694 -141.263116)
					(mid 109.966316 -141.349074)
					(end 110.045754 -141.387322)
				)
				(arc
					(start 110.852458 -141.387322)
					(mid 110.931389 -141.34938)
					(end 110.951518 -141.264132)
				)
				(arc
					(start 110.951518 -141.264132)
					(mid 111.299498 -140.832015)
					(end 111.647478 -141.264132)
				)
				(arc
					(start 111.647478 -141.264132)
					(mid 111.667581 -141.3494)
					(end 111.746538 -141.387322)
				)
				(xy 112.326166 -141.387322) (xy 112.528604 -141.184884) (xy 112.528604 -140.716508) (xy 111.825024 -140.716508)
				(xy 111.825024 -140.589508) (xy 111.444024 -140.589508) (xy 111.444024 -139.826492) (xy 111.825024 -139.826492)
				(xy 111.825024 -139.699492) (xy 112.528604 -139.699492) (xy 112.528604 -138.95705) (xy 112.34039 -138.768836)
				(arc
					(start 111.643922 -138.768836)
					(mid 111.551578 -138.828623)
					(end 111.567722 -138.937492)
				)
				(arc
					(start 111.567722 -138.937492)
					(mid 111.300006 -139.528213)
					(end 111.03229 -138.937492)
				)
				(arc
					(start 111.03229 -138.937492)
					(mid 111.048519 -138.828585)
					(end 110.95609 -138.768836)
				)
				(arc
					(start 110.793784 -138.768836)
					(mid 110.70144 -138.828623)
					(end 110.717584 -138.937492)
				)
				(arc
					(start 110.717584 -138.937492)
					(mid 110.449868 -139.528213)
					(end 110.182152 -138.937492)
				)
				(arc
					(start 110.182152 -138.937492)
					(mid 110.198381 -138.828585)
					(end 110.105952 -138.768836)
				)
				(arc
					(start 109.093762 -138.768836)
					(mid 109.001418 -138.828623)
					(end 109.017562 -138.937492)
				)
				(arc
					(start 109.017562 -138.937492)
					(mid 108.749846 -139.528213)
					(end 108.48213 -138.937492)
				)
				(arc
					(start 108.48213 -138.937492)
					(mid 108.498359 -138.828585)
					(end 108.40593 -138.768836)
				)
				(arc
					(start 107.39374 -138.768836)
					(mid 107.301396 -138.828623)
					(end 107.31754 -138.937492)
				)
				(arc
					(start 107.31754 -138.937492)
					(mid 107.049824 -139.528213)
					(end 106.782108 -138.937492)
				)
				(arc
					(start 106.782108 -138.937492)
					(mid 106.798337 -138.828585)
					(end 106.705908 -138.768836)
				)
				(arc
					(start 105.693718 -138.768836)
					(mid 105.601374 -138.828623)
					(end 105.617518 -138.937492)
				)
				(arc
					(start 105.617518 -138.937492)
					(mid 105.349802 -139.528213)
					(end 105.082086 -138.937492)
				)
				(arc
					(start 105.082086 -138.937492)
					(mid 105.098315 -138.828585)
					(end 105.005886 -138.768836)
				)
				(arc
					(start 104.84358 -138.768836)
					(mid 104.751236 -138.828623)
					(end 104.76738 -138.937492)
				)
				(arc
					(start 104.76738 -138.937492)
					(mid 104.499664 -139.528213)
					(end 104.231948 -138.937492)
				)
				(arc
					(start 104.231948 -138.937492)
					(mid 104.248177 -138.828585)
					(end 104.155748 -138.768836)
				)
				(arc
					(start 103.143558 -138.768836)
					(mid 103.051214 -138.828623)
					(end 103.067358 -138.937492)
				)
				(arc
					(start 103.067358 -138.937492)
					(mid 102.799642 -139.528213)
					(end 102.531926 -138.937492)
				)
				(arc
					(start 102.531926 -138.937492)
					(mid 102.548155 -138.828585)
					(end 102.455726 -138.768836)
				)
			)
		)
		(polygon
			(pts
				(xy 110.657132 -140.6017) (xy 110.453932 -140.6017) (xy 110.453932 -140.8049) (xy 110.657132 -140.8049)
			)
		)
		(polygon
			(pts
				(xy 107.5182 -140.6017) (xy 107.315 -140.6017) (xy 107.315 -140.8049) (xy 107.5182 -140.8049)
			)
		)
		(polygon
			(pts
				(xy 104.2162 -140.6017) (xy 104.013 -140.6017) (xy 104.013 -140.8049) (xy 104.2162 -140.8049)
			)
		)
		(polygon
			(pts
				(xy 107.5182 -139.6111) (xy 107.315 -139.6111) (xy 107.315 -139.8143) (xy 107.5182 -139.8143)
			)
		)
		(polygon
			(pts
				(xy 104.2162 -139.6111) (xy 104.013 -139.6111) (xy 104.013 -139.8143) (xy 104.2162 -139.8143)
			)
		)
		(polygon
			(pts
				(xy 101.0539 -139.6111) (xy 100.8507 -139.6111) (xy 100.8507 -139.8143) (xy 101.0539 -139.8143)
			)
		)
	)
	(zone
		(layer "F.Cu")
		(hatch none 0.5)
		(connect_pads
			(clearance 0)
		)
		(min_thickness 0.25)
		(keepout
			(tracks allowed)
			(vias allowed)
			(pads allowed)
			(copperpour allowed)
			(footprints not_allowed)
		)
		(placement
			(enabled no)
			(sheetname "")
		)
		(fill
			(thermal_gap 0.5)
			(thermal_bridge_width 0.5)
			(island_removal_mode 0)
		)
		(polygon
			(pts
				(arc
					(start 222.000064 -79.090012)
					(mid 219.460064 -76.550012)
					(end 222.000064 -74.010012)
				)
				(arc
					(start 222.000064 -74.010012)
					(mid 224.540064 -76.550012)
					(end 222.000064 -79.090012)
				)
			)
		)
	)
	(zone
		(layer "F.Cu")
		(hatch none 0.5)
		(connect_pads
			(clearance 0)
		)
		(min_thickness 0.25)
		(keepout
			(tracks not_allowed)
			(vias allowed)
			(pads allowed)
			(copperpour not_allowed)
			(footprints allowed)
		)
		(placement
			(enabled no)
			(sheetname "")
		)
		(fill
			(thermal_gap 0.5)
			(thermal_bridge_width 0.5)
			(island_removal_mode 0)
		)
		(polygon
			(pts
				(arc
					(start 198.930006 -48.09998)
					(mid 197.380098 -46.550072)
					(end 198.930006 -44.99991)
				)
				(arc
					(start 198.930006 -44.99991)
					(mid 200.480168 -46.550072)
					(end 198.930006 -48.09998)
				)
			)
		)
	)
	(zone
		(net "VR_PVCCIN_CPU0_PHASE4")
		(layer "F.Cu")
		(hatch none 0.5)
		(connect_pads
			(clearance 0.5)
		)
		(min_thickness 0.25)
		(fill yes
			(thermal_gap 0.5)
			(thermal_bridge_width 0.5)
			(island_removal_mode 0)
		)
		(polygon
			(pts
				(xy 201.676 -84.039202) (xy 206.502 -84.039202) (xy 206.780638 -84.039202) (xy 206.913226 -83.906614)
				(xy 206.913226 -79.196184) (xy 206.676244 -78.959202) (xy 206.502 -78.959202) (xy 201.583798 -78.959202)
				(xy 201.4982 -79.0448) (xy 201.4982 -83.861402)
			)
		)
	)
	(zone
		(net "GND")
		(layer "F.Cu")
		(hatch none 0.5)
		(connect_pads
			(clearance 0.5)
		)
		(min_thickness 0.25)
		(fill yes
			(thermal_gap 0.5)
			(thermal_bridge_width 0.5)
			(island_removal_mode 0)
		)
		(polygon
			(pts
				(xy 332.994 -19.685) (xy 336.296 -19.685) (xy 336.55 -19.431) (xy 336.55 -14.478) (xy 336.169 -14.097)
				(xy 333.248 -14.097) (xy 332.74 -14.605) (xy 332.74 -19.431)
			)
		)
	)
	(zone
		(layer "F.Cu")
		(hatch none 0.5)
		(connect_pads
			(clearance 0)
		)
		(min_thickness 0.25)
		(keepout
			(tracks not_allowed)
			(vias allowed)
			(pads allowed)
			(copperpour not_allowed)
			(footprints allowed)
		)
		(placement
			(enabled no)
			(sheetname "")
		)
		(fill
			(thermal_gap 0.5)
			(thermal_bridge_width 0.5)
			(island_removal_mode 0)
		)
		(polygon
			(pts
				(arc
					(start 406.489916 -132.310124)
					(mid 408.079956 -133.900164)
					(end 406.489916 -135.48995)
				)
				(arc
					(start 406.489916 -135.48995)
					(mid 404.90013 -133.900164)
					(end 406.489916 -132.310124)
				)
			)
		)
	)
	(zone
		(net "PVDDQ_DEF")
		(layer "F.Cu")
		(hatch none 0.5)
		(connect_pads
			(clearance 0.5)
		)
		(min_thickness 0.25)
		(fill yes
			(thermal_gap 0.5)
			(thermal_bridge_width 0.5)
			(island_removal_mode 0)
		)
		(polygon
			(pts
				(xy 272.943828 -84.0994) (xy 272.628614 -84.414614) (xy 262.955024 -84.414614) (xy 262.955024 -85.430614)
				(xy 263.740138 -86.215728) (xy 267.75791 -86.215728) (xy 267.902182 -86.36) (xy 272.4404 -86.36)
				(xy 272.7452 -86.0552) (xy 272.7452 -85.06968) (xy 273.05254 -84.76234) (xy 273.558 -84.76234) (xy 273.6596 -84.66074)
				(xy 273.6596 -84.18322) (xy 273.57578 -84.0994)
			)
		)
		(polygon
			(pts
				(xy 271.96161 -85.233002) (xy 271.75841 -85.233002) (xy 271.75841 -85.436202) (xy 271.96161 -85.436202)
			)
		)
		(polygon
			(pts
				(xy 271.47901 -85.233002) (xy 271.27581 -85.233002) (xy 271.27581 -85.436202) (xy 271.47901 -85.436202)
			)
		)
		(polygon
			(pts
				(xy 270.71701 -85.233002) (xy 270.51381 -85.233002) (xy 270.51381 -85.436202) (xy 270.71701 -85.436202)
			)
		)
		(polygon
			(pts
				(xy 270.23441 -85.233002) (xy 270.03121 -85.233002) (xy 270.03121 -85.436202) (xy 270.23441 -85.436202)
			)
		)
		(polygon
			(pts
				(xy 269.47241 -85.233002) (xy 269.26921 -85.233002) (xy 269.26921 -85.436202) (xy 269.47241 -85.436202)
			)
		)
		(polygon
			(pts
				(xy 268.98981 -85.233002) (xy 268.78661 -85.233002) (xy 268.78661 -85.436202) (xy 268.98981 -85.436202)
			)
		)
		(polygon
			(pts
				(xy 268.22781 -85.233002) (xy 268.02461 -85.233002) (xy 268.02461 -85.436202) (xy 268.22781 -85.436202)
			)
		)
		(polygon
			(pts
				(xy 267.7414 -85.1027) (xy 267.5382 -85.1027) (xy 267.5382 -85.3059) (xy 267.7414 -85.3059)
			)
		)
		(polygon
			(pts
				(xy 266.9794 -85.1027) (xy 266.7762 -85.1027) (xy 266.7762 -85.3059) (xy 266.9794 -85.3059)
			)
		)
		(polygon
			(pts
				(xy 266.4968 -85.1027) (xy 266.2936 -85.1027) (xy 266.2936 -85.3059) (xy 266.4968 -85.3059)
			)
		)
		(polygon
			(pts
				(xy 265.7348 -85.1027) (xy 265.5316 -85.1027) (xy 265.5316 -85.3059) (xy 265.7348 -85.3059)
			)
		)
		(polygon
			(pts
				(xy 265.2522 -85.1027) (xy 265.049 -85.1027) (xy 265.049 -85.3059) (xy 265.2522 -85.3059)
			)
		)
		(polygon
			(pts
				(xy 264.4902 -85.1027) (xy 264.287 -85.1027) (xy 264.287 -85.3059) (xy 264.4902 -85.3059)
			)
		)
		(polygon
			(pts
				(xy 264.0076 -85.0519) (xy 263.8044 -85.0519) (xy 263.8044 -85.2551) (xy 264.0076 -85.2551)
			)
		)
	)
	(zone
		(layer "F.Cu")
		(hatch none 0.5)
		(connect_pads
			(clearance 0)
		)
		(min_thickness 0.25)
		(keepout
			(tracks allowed)
			(vias allowed)
			(pads allowed)
			(copperpour allowed)
			(footprints allowed)
		)
		(placement
			(enabled no)
			(sheetname "")
		)
		(fill
			(thermal_gap 0.5)
			(thermal_bridge_width 0.5)
			(island_removal_mode 0)
		)
		(polygon
			(pts
				(xy 290.576 -100.711) (xy 291.846 -100.711) (xy 291.846 -101.346) (xy 289.814 -103.378) (xy 287.782 -103.378)
				(xy 287.528 -103.124) (xy 287.401 -103.124) (xy 287.401 -102.616) (xy 288.798 -101.219) (xy 290.068 -101.219)
			)
		)
	)
	(zone
		(net "PVDDQ_DEF")
		(layer "F.Cu")
		(hatch none 0.5)
		(connect_pads
			(clearance 0.5)
		)
		(min_thickness 0.25)
		(fill yes
			(thermal_gap 0.5)
			(thermal_bridge_width 0.5)
			(island_removal_mode 0)
		)
		(polygon
			(pts
				(xy 243.866416 -155.839922) (xy 255.964944 -155.839922) (xy 255.9685 -155.836112) (xy 258.504944 -155.836112)
				(xy 258.798822 -155.542234) (xy 258.798822 -153.652474) (xy 258.512818 -153.36647) (xy 255.938528 -153.36647)
				(xy 243.745766 -153.36647) (xy 243.735606 -153.37663) (xy 243.735606 -155.709112)
			)
		)
	)
	(zone
		(layer "F.Cu")
		(hatch none 0.5)
		(connect_pads
			(clearance 0)
		)
		(min_thickness 0.25)
		(keepout
			(tracks allowed)
			(vias allowed)
			(pads allowed)
			(copperpour allowed)
			(footprints not_allowed)
		)
		(placement
			(enabled no)
			(sheetname "")
		)
		(fill
			(thermal_gap 0.5)
			(thermal_bridge_width 0.5)
			(island_removal_mode 0)
		)
		(polygon
			(pts
				(xy 360.650028 -19.43989) (xy 352.609912 -19.43989) (xy 351.54997 -18.379948) (xy 351.54997 -13.10005)
				(xy 352.609912 -12.040108) (xy 360.650028 -12.040108)
			)
		)
	)
	(zone
		(net "GND")
		(layer "F.Cu")
		(hatch none 0.5)
		(connect_pads
			(clearance 0.5)
		)
		(min_thickness 0.25)
		(fill yes
			(thermal_gap 0.5)
			(thermal_bridge_width 0.5)
			(island_removal_mode 0)
		)
		(polygon
			(pts
				(xy 33.373314 -94.746572)
				(arc
					(start 33.372806 -94.747334)
					(mid 33.35295 -94.767038)
					(end 33.331658 -94.78518)
				)
				(xy 33.324546 -94.792292) (xy 33.324546 -95.845122) (xy 33.183068 -95.9866) (xy 32.30372 -95.9866)
				(xy 32.29483 -95.97771) (xy 31.794958 -95.97771) (xy 31.684468 -96.0882) (xy 31.684468 -97.4344)
				(xy 31.887668 -97.6376) (xy 33.564068 -97.6376) (xy 33.680908 -97.75444) (xy 33.950148 -97.75444)
				(xy 33.950148 -98.02368) (xy 34.021268 -98.0948) (xy 34.021268 -100.429822) (xy 34.017458 -100.429822)
				(xy 34.017458 -100.48367) (xy 33.30956 -101.191568) (xy 33.30956 -102.535228) (xy 33.30067 -102.544118)
				(xy 33.30067 -102.644448) (xy 33.370774 -102.714552) (xy 33.753552 -102.714552) (xy 35.33902 -102.714552)
				(xy 35.342068 -102.7176) (xy 38.081966 -102.7176) (xy 38.788086 -102.01148) (xy 41.178988 -102.01148)
				(xy 42.022268 -101.1682) (xy 42.919904 -100.270564) (xy 42.919904 -93.844364) (xy 42.642282 -93.566742)
				(xy 40.748458 -93.566742) (xy 40.63746 -93.67774) (xy 40.63746 -94.706948) (xy 40.84066 -94.910148)
				(xy 41.569894 -94.910148) (xy 42.266108 -95.606108) (xy 42.266108 -100.024692) (xy 41.69029 -100.600256)
				(xy 36.143692 -100.600256) (xy 36.143692 -94.99092) (xy 35.9156 -94.762828) (xy 35.9156 -94.495366)
				(xy 35.9156 -93.72092) (xy 35.59556 -93.40088) (xy 34.598102 -93.40088) (xy 34.533078 -93.465904)
				(xy 33.05937 -93.465904) (xy 32.955484 -93.56979) (xy 32.955484 -94.06636) (xy 33.008316 -94.119192)
				(xy 33.36163 -94.119192) (xy 33.45942 -94.216982) (xy 33.45942 -94.660466)
			)
		)
	)
	(zone
		(layer "F.Cu")
		(hatch none 0.5)
		(connect_pads
			(clearance 0)
		)
		(min_thickness 0.25)
		(keepout
			(tracks not_allowed)
			(vias allowed)
			(pads allowed)
			(copperpour not_allowed)
			(footprints allowed)
		)
		(placement
			(enabled no)
			(sheetname "")
		)
		(fill
			(thermal_gap 0.5)
			(thermal_bridge_width 0.5)
			(island_removal_mode 0)
		)
		(polygon
			(pts
				(xy 420.013892 -9.639808) (xy 420.013892 -9.938004) (xy 419.858698 -10.093198)
				(arc
					(start 419.686994 -10.093198)
					(mid 419.163077 -10.023348)
					(end 419.686994 -9.953498)
				)
				(xy 419.800786 -9.953498) (xy 419.874192 -9.880092) (xy 419.874192 -9.639808)
				(arc
					(start 419.429692 -9.639808)
					(mid 419.046152 -10.023348)
					(end 419.429692 -10.406888)
				)
				(arc
					(start 420.699438 -10.406888)
					(mid 421.083232 -10.023475)
					(end 420.699692 -9.639808)
				)
				(xy 420.255192 -9.639808) (xy 420.255192 -9.880092) (xy 420.328598 -9.953498)
				(arc
					(start 420.44239 -9.953498)
					(mid 420.966307 -10.023348)
					(end 420.44239 -10.093198)
				)
				(xy 420.270686 -10.093198) (xy 420.115492 -9.938004) (xy 420.115492 -9.639808)
			)
		)
	)
	(zone
		(layer "F.Cu")
		(hatch none 0.5)
		(connect_pads
			(clearance 0)
		)
		(min_thickness 0.25)
		(keepout
			(tracks allowed)
			(vias allowed)
			(pads allowed)
			(copperpour allowed)
			(footprints allowed)
		)
		(placement
			(enabled no)
			(sheetname "")
		)
		(fill
			(thermal_gap 0.5)
			(thermal_bridge_width 0.5)
			(island_removal_mode 0)
		)
		(polygon
			(pts
				(xy 282.829 -103.759) (xy 282.829 -105.41) (xy 282.829 -106.045) (xy 277.495 -106.045) (xy 277.495 -103.632)
				(xy 282.829 -103.632)
			)
		)
	)
	(zone
		(layer "F.Cu")
		(hatch none 0.5)
		(connect_pads
			(clearance 0)
		)
		(min_thickness 0.25)
		(keepout
			(tracks allowed)
			(vias allowed)
			(pads allowed)
			(copperpour allowed)
			(footprints allowed)
		)
		(placement
			(enabled no)
			(sheetname "")
		)
		(fill
			(thermal_gap 0.5)
			(thermal_bridge_width 0.5)
			(island_removal_mode 0)
		)
		(polygon
			(pts
				(xy 412.877 -97.0534) (xy 412.877 -95.9358) (xy 414.6804 -95.9358) (xy 414.6804 -97.0534)
			)
		)
	)
	(zone
		(layer "F.Cu")
		(hatch none 0.5)
		(connect_pads
			(clearance 0)
		)
		(min_thickness 0.25)
		(keepout
			(tracks allowed)
			(vias allowed)
			(pads allowed)
			(copperpour allowed)
			(footprints allowed)
		)
		(placement
			(enabled no)
			(sheetname "")
		)
		(fill
			(thermal_gap 0.5)
			(thermal_bridge_width 0.5)
			(island_removal_mode 0)
		)
		(polygon
			(pts
				(xy 27.305 -23.749) (xy 27.305 -23.114) (xy 28.321 -23.114) (xy 28.321 -23.749)
			)
		)
	)
	(zone
		(layer "F.Cu")
		(hatch none 0.5)
		(connect_pads
			(clearance 0)
		)
		(min_thickness 0.25)
		(keepout
			(tracks allowed)
			(vias allowed)
			(pads allowed)
			(copperpour allowed)
			(footprints not_allowed)
		)
		(placement
			(enabled no)
			(sheetname "")
		)
		(fill
			(thermal_gap 0.5)
			(thermal_bridge_width 0.5)
			(island_removal_mode 0)
		)
		(polygon
			(pts
				(xy -5.999988 -23.759922) (xy 13.299948 -23.759922) (xy 13.299948 -41.660064) (xy -5.999988 -41.660064)
			)
		)
	)
	(zone
		(layer "F.Cu")
		(hatch none 0.5)
		(connect_pads
			(clearance 0)
		)
		(min_thickness 0.25)
		(keepout
			(tracks allowed)
			(vias allowed)
			(pads allowed)
			(copperpour allowed)
			(footprints not_allowed)
		)
		(placement
			(enabled no)
			(sheetname "")
		)
		(fill
			(thermal_gap 0.5)
			(thermal_bridge_width 0.5)
			(island_removal_mode 0)
		)
		(polygon
			(pts
				(arc
					(start 152.999948 -96.650048)
					(mid 154.899868 -98.549968)
					(end 152.999948 -100.449888)
				)
				(arc
					(start 152.999948 -100.449888)
					(mid 151.100028 -98.549968)
					(end 152.999948 -96.650048)
				)
			)
		)
	)
	(zone
		(net "PVDDQ_GHJ")
		(layer "F.Cu")
		(hatch none 0.5)
		(connect_pads
			(clearance 0.5)
		)
		(min_thickness 0.25)
		(fill yes
			(thermal_gap 0.5)
			(thermal_bridge_width 0.5)
			(island_removal_mode 0)
		)
		(polygon
			(pts
				(xy 90.026744 -2.768092) (xy 90.026744 -2.674874)
				(arc
					(start 89.985088 -2.667254)
					(mid 89.720421 -2.453449)
					(end 89.75598 -2.115058)
				)
				(arc
					(start 89.75598 -2.115058)
					(mid 89.762307 -2.01021)
					(end 89.672414 -1.9558)
				)
				(xy 89.535 -1.818386) (xy 89.535 -0.7112) (xy 89.408 -0.5842) (xy 89.0016 -0.5842) (xy 88.8746 -0.7112)
				(xy 88.8746 -1.8542) (xy 88.773 -1.9558)
				(arc
					(start 88.726518 -1.9558)
					(mid 88.63656 -2.010176)
					(end 88.642952 -2.115058)
				)
				(arc
					(start 88.642952 -2.115058)
					(mid 88.349582 -2.673136)
					(end 88.056212 -2.115058)
				)
				(arc
					(start 88.056212 -2.115058)
					(mid 88.062539 -2.01021)
					(end 87.972646 -1.9558)
				)
				(arc
					(start 87.87638 -1.9558)
					(mid 87.786422 -2.010176)
					(end 87.792814 -2.115058)
				)
				(arc
					(start 87.792814 -2.115058)
					(mid 87.499444 -2.673136)
					(end 87.206074 -2.115058)
				)
				(arc
					(start 87.206074 -2.115058)
					(mid 87.212401 -2.01021)
					(end 87.122508 -1.9558)
				)
				(arc
					(start 86.177628 -1.9558)
					(mid 86.088029 -2.009975)
					(end 86.093808 -2.11455)
				)
				(arc
					(start 86.093808 -2.11455)
					(mid 85.799422 -2.671082)
					(end 85.505036 -2.11455)
				)
				(arc
					(start 85.505036 -2.11455)
					(mid 85.510867 -2.009948)
					(end 85.421216 -1.9558)
				)
				(arc
					(start 85.32749 -1.9558)
					(mid 85.237891 -2.009975)
					(end 85.24367 -2.11455)
				)
				(arc
					(start 85.24367 -2.11455)
					(mid 84.949284 -2.671082)
					(end 84.654898 -2.11455)
				)
				(arc
					(start 84.654898 -2.11455)
					(mid 84.660729 -2.009948)
					(end 84.571078 -1.9558)
				)
				(arc
					(start 83.627722 -1.9558)
					(mid 83.538123 -2.009975)
					(end 83.543902 -2.11455)
				)
				(arc
					(start 83.543902 -2.11455)
					(mid 83.249516 -2.671082)
					(end 82.95513 -2.11455)
				)
				(arc
					(start 82.95513 -2.11455)
					(mid 82.960961 -2.009948)
					(end 82.87131 -1.9558)
				)
				(arc
					(start 82.777584 -1.9558)
					(mid 82.687985 -2.009975)
					(end 82.693764 -2.11455)
				)
				(arc
					(start 82.693764 -2.11455)
					(mid 82.399378 -2.671082)
					(end 82.104992 -2.11455)
				)
				(arc
					(start 82.104992 -2.11455)
					(mid 82.110823 -2.009948)
					(end 82.021172 -1.9558)
				)
				(arc
					(start 81.077562 -1.9558)
					(mid 80.987963 -2.009975)
					(end 80.993742 -2.11455)
				)
				(arc
					(start 80.993742 -2.11455)
					(mid 80.699356 -2.671082)
					(end 80.40497 -2.11455)
				)
				(arc
					(start 80.40497 -2.11455)
					(mid 80.410801 -2.009948)
					(end 80.32115 -1.9558)
				)
				(arc
					(start 79.37754 -1.9558)
					(mid 79.287941 -2.009975)
					(end 79.29372 -2.11455)
				)
				(arc
					(start 79.29372 -2.11455)
					(mid 79.307503 -2.136552)
					(end 79.319628 -2.159508)
				)
				(arc
					(start 79.319628 -2.159508)
					(mid 79.209292 -2.60248)
					(end 78.753716 -2.572766)
				)
				(arc
					(start 78.753716 -2.572766)
					(mid 78.64497 -2.557148)
					(end 78.585568 -2.649474)
				)
				(xy 78.585568 -2.996692) (xy 78.78826 -2.996692) (xy 78.78826 -2.844292) (xy 79.932276 -2.844292)
				(xy 79.932276 -2.971292) (xy 80.313276 -2.971292) (xy 80.313276 -3.734308) (xy 79.932276 -3.734308)
				(xy 79.932276 -3.861308) (xy 78.78826 -3.861308) (xy 78.78826 -3.708908) (xy 78.585568 -3.708908)
				(xy 78.585568 -4.2672) (xy 78.941168 -4.6228)
				(arc
					(start 79.432658 -4.6228)
					(mid 79.516935 -4.577566)
					(end 79.526384 -4.482338)
				)
				(arc
					(start 79.526384 -4.482338)
					(mid 79.849472 -3.976327)
					(end 80.17256 -4.482338)
				)
				(arc
					(start 80.17256 -4.482338)
					(mid 80.181927 -4.57762)
					(end 80.266286 -4.6228)
				)
				(arc
					(start 81.13268 -4.6228)
					(mid 81.216957 -4.577566)
					(end 81.226406 -4.482338)
				)
				(arc
					(start 81.226406 -4.482338)
					(mid 81.549494 -3.976327)
					(end 81.872582 -4.482338)
				)
				(arc
					(start 81.872582 -4.482338)
					(mid 81.881949 -4.57762)
					(end 81.966308 -4.6228)
				)
				(arc
					(start 81.982564 -4.6228)
					(mid 82.066841 -4.577566)
					(end 82.07629 -4.482338)
				)
				(arc
					(start 82.07629 -4.482338)
					(mid 82.399378 -3.976327)
					(end 82.722466 -4.482338)
				)
				(arc
					(start 82.722466 -4.482338)
					(mid 82.731833 -4.57762)
					(end 82.816192 -4.6228)
				)
				(xy 82.931 -4.737608) (xy 82.931 -5.969) (xy 83.058 -6.096) (xy 83.4136 -6.096) (xy 83.566 -5.9436)
				(xy 83.566 -4.699) (xy 83.6422 -4.6228)
				(arc
					(start 83.682586 -4.6228)
					(mid 83.766863 -4.577566)
					(end 83.776312 -4.482338)
				)
				(arc
					(start 83.776312 -4.482338)
					(mid 84.0994 -3.976327)
					(end 84.422488 -4.482338)
				)
				(arc
					(start 84.422488 -4.482338)
					(mid 84.431855 -4.57762)
					(end 84.516214 -4.6228)
				)
				(arc
					(start 84.532724 -4.6228)
					(mid 84.617001 -4.577566)
					(end 84.62645 -4.482338)
				)
				(arc
					(start 84.62645 -4.482338)
					(mid 84.949538 -3.976327)
					(end 85.272626 -4.482338)
				)
				(arc
					(start 85.272626 -4.482338)
					(mid 85.281993 -4.57762)
					(end 85.366352 -4.6228)
				)
				(arc
					(start 86.232746 -4.6228)
					(mid 86.317023 -4.577566)
					(end 86.326472 -4.482338)
				)
				(arc
					(start 86.326472 -4.482338)
					(mid 86.64956 -3.976327)
					(end 86.972648 -4.482338)
				)
				(arc
					(start 86.972648 -4.482338)
					(mid 86.982015 -4.57762)
					(end 87.066374 -4.6228)
				)
				(arc
					(start 87.08263 -4.6228)
					(mid 87.166907 -4.577566)
					(end 87.176356 -4.482338)
				)
				(arc
					(start 87.176356 -4.482338)
					(mid 87.499444 -3.976327)
					(end 87.822532 -4.482338)
				)
				(arc
					(start 87.822532 -4.482338)
					(mid 87.831899 -4.57762)
					(end 87.916258 -4.6228)
				)
				(xy 88.011 -4.717542) (xy 88.011 -5.969) (xy 88.138 -6.096) (xy 88.5444 -6.096) (xy 88.6968 -5.9436)
				(xy 88.6968 -4.6482) (xy 88.7222 -4.6228)
				(arc
					(start 88.782652 -4.6228)
					(mid 88.866929 -4.577566)
					(end 88.876378 -4.482338)
				)
				(arc
					(start 88.876378 -4.482338)
					(mid 89.199466 -3.976327)
					(end 89.522554 -4.482338)
				)
				(arc
					(start 89.522554 -4.482338)
					(mid 89.531921 -4.57762)
					(end 89.61628 -4.6228)
				)
				(arc
					(start 89.63279 -4.6228)
					(mid 89.717067 -4.577566)
					(end 89.726516 -4.482338)
				)
				(arc
					(start 89.726516 -4.482338)
					(mid 89.705369 -4.241122)
					(end 89.843356 -4.042156)
				)
				(arc
					(start 89.843356 -4.042156)
					(mid 89.885706 -3.967823)
					(end 89.85631 -3.88747)
				)
				(xy 89.829894 -3.861308) (xy 89.216992 -3.861308) (xy 89.216992 -3.734308) (xy 88.835992 -3.734308)
				(xy 88.835992 -2.971292) (xy 89.216992 -2.971292) (xy 89.216992 -2.844292) (xy 89.793826 -2.844292)
				(xy 89.870026 -2.768092)
			)
		)
		(polygon
			(pts
				(xy 88.0491 -3.7465) (xy 87.8459 -3.7465) (xy 87.8459 -3.9497) (xy 88.0491 -3.9497)
			)
		)
		(polygon
			(pts
				(xy 88.0491 -2.7559) (xy 87.8459 -2.7559) (xy 87.8459 -2.9591) (xy 88.0491 -2.9591)
			)
		)
		(polygon
			(pts
				(xy 84.402168 -2.7559) (xy 84.198968 -2.7559) (xy 84.198968 -2.9591) (xy 84.402168 -2.9591)
			)
		)
	)
	(zone
		(net "GND")
		(layer "F.Cu")
		(hatch none 0.5)
		(connect_pads
			(clearance 0.5)
		)
		(min_thickness 0.25)
		(fill yes
			(thermal_gap 0.5)
			(thermal_bridge_width 0.5)
			(island_removal_mode 0)
		)
		(polygon
			(pts
				(xy 95.505016 -138.600688) (xy 95.566738 -138.538966) (xy 96.034098 -138.538966) (xy 96.06915 -138.503914)
				(xy 96.571562 -138.503914) (xy 96.7359 -138.668252) (xy 96.7359 -140.73378) (xy 96.672908 -140.796772)
				(xy 95.757746 -140.796772) (xy 95.725488 -140.764514) (xy 95.725488 -139.359386) (xy 95.58274 -139.216638)
				(xy 95.458026 -139.091924) (xy 95.458026 -138.647678)
			)
		)
	)
	(zone
		(layer "F.Cu")
		(hatch none 0.5)
		(connect_pads
			(clearance 0)
		)
		(min_thickness 0.25)
		(keepout
			(tracks allowed)
			(vias allowed)
			(pads allowed)
			(copperpour allowed)
			(footprints allowed)
		)
		(placement
			(enabled no)
			(sheetname "")
		)
		(fill
			(thermal_gap 0.5)
			(thermal_bridge_width 0.5)
			(island_removal_mode 0)
		)
		(polygon
			(pts
				(xy 393.4206 -68.8848) (xy 393.4206 -67.0052) (xy 393.42568 -67.0052) (xy 393.42568 -66.5607) (xy 393.52728 -66.4591)
				(xy 394.24102 -66.4591) (xy 394.45438 -66.24574) (xy 394.45438 -65.96126) (xy 394.57122 -65.84442)
				(xy 395.51356 -65.84442) (xy 395.71422 -66.04508) (xy 395.71422 -66.42354) (xy 394.7922 -67.34556)
				(xy 394.7922 -68.8848)
			)
		)
	)
	(zone
		(layer "F.Cu")
		(hatch none 0.5)
		(connect_pads
			(clearance 0)
		)
		(min_thickness 0.25)
		(keepout
			(tracks allowed)
			(vias allowed)
			(pads allowed)
			(copperpour allowed)
			(footprints not_allowed)
		)
		(placement
			(enabled no)
			(sheetname "")
		)
		(fill
			(thermal_gap 0.5)
			(thermal_bridge_width 0.5)
			(island_removal_mode 0)
		)
		(polygon
			(pts
				(xy 430.950624 -51.676808) (xy 430.950624 -41.676828) (xy 474.950536 -41.676828) (xy 474.950536 -44.676822)
				(xy 432.95062 -44.676822) (xy 432.95062 -51.676808)
			)
		)
	)
	(zone
		(layer "F.Cu")
		(hatch none 0.5)
		(connect_pads
			(clearance 0)
		)
		(min_thickness 0.25)
		(keepout
			(tracks not_allowed)
			(vias allowed)
			(pads allowed)
			(copperpour not_allowed)
			(footprints allowed)
		)
		(placement
			(enabled no)
			(sheetname "")
		)
		(fill
			(thermal_gap 0.5)
			(thermal_bridge_width 0.5)
			(island_removal_mode 0)
		)
		(polygon
			(pts
				(xy 372.512844 -10.293858) (xy 373.020844 -10.293858) (xy 373.020844 -10.649458) (xy 372.512844 -10.649458)
			)
		)
	)
	(zone
		(layer "F.Cu")
		(hatch none 0.5)
		(connect_pads
			(clearance 0)
		)
		(min_thickness 0.25)
		(keepout
			(tracks not_allowed)
			(vias allowed)
			(pads allowed)
			(copperpour not_allowed)
			(footprints allowed)
		)
		(placement
			(enabled no)
			(sheetname "")
		)
		(fill
			(thermal_gap 0.5)
			(thermal_bridge_width 0.5)
			(island_removal_mode 0)
		)
		(polygon
			(pts
				(arc
					(start 395.741144 -31.87065)
					(mid 395.590235 -31.812252)
					(end 395.50086 -31.677356)
				)
				(arc
					(start 395.50086 -32.674306)
					(mid 395.569931 -32.557514)
					(end 395.68755 -32.489902)
				)
				(xy 395.68755 -32.484568) (xy 395.920468 -32.25165) (xy 396.01394 -32.25165) (xy 396.01394 -32.143446)
			)
		)
	)
	(zone
		(layer "F.Cu")
		(hatch none 0.5)
		(connect_pads
			(clearance 0)
		)
		(min_thickness 0.25)
		(keepout
			(tracks allowed)
			(vias allowed)
			(pads allowed)
			(copperpour allowed)
			(footprints allowed)
		)
		(placement
			(enabled no)
			(sheetname "")
		)
		(fill
			(thermal_gap 0.5)
			(thermal_bridge_width 0.5)
			(island_removal_mode 0)
		)
		(polygon
			(pts
				(xy 106.093768 -49.657) (xy 106.093768 -53.0098) (xy 107.693968 -54.61) (xy 109.700568 -54.61) (xy 111.148368 -53.1622)
				(xy 111.605568 -53.1622) (xy 112.875568 -54.4322) (xy 114.958368 -54.4322) (xy 116.558568 -52.832)
				(xy 116.558568 -50.038) (xy 116.557044 -49.657)
			)
		)
	)
	(zone
		(net "GND")
		(layer "F.Cu")
		(hatch none 0.5)
		(connect_pads
			(clearance 0.5)
		)
		(min_thickness 0.25)
		(fill yes
			(thermal_gap 0.5)
			(thermal_bridge_width 0.5)
			(island_removal_mode 0)
		)
		(polygon
			(pts
				(xy 96.330516 -128.902714) (xy 97.286826 -128.902714) (xy 97.475548 -129.091436) (xy 97.922334 -129.091436)
				(xy 98.334322 -128.679448) (xy 98.334322 -127.694944) (xy 98.138742 -127.499364) (xy 96.609662 -127.499364)
				(xy 96.309434 -127.799592) (xy 96.309434 -128.881632)
			)
		)
	)
	(zone
		(layer "F.Cu")
		(hatch none 0.5)
		(connect_pads
			(clearance 0)
		)
		(min_thickness 0.25)
		(keepout
			(tracks not_allowed)
			(vias allowed)
			(pads allowed)
			(copperpour not_allowed)
			(footprints allowed)
		)
		(placement
			(enabled no)
			(sheetname "")
		)
		(fill
			(thermal_gap 0.5)
			(thermal_bridge_width 0.5)
			(island_removal_mode 0)
		)
		(polygon
			(pts
				(xy 419.210998 -1.5367) (xy 419.368478 -1.69418) (xy 419.368478 -1.99009) (xy 419.470078 -1.99009)
				(xy 419.470078 -1.691894) (xy 419.625272 -1.5367)
				(arc
					(start 419.79469 -1.5367)
					(mid 420.318607 -1.60655)
					(end 419.79469 -1.6764)
				)
				(xy 419.683184 -1.6764) (xy 419.609778 -1.749806) (xy 419.609778 -1.99009)
				(arc
					(start 420.051738 -1.99009)
					(mid 420.435532 -1.606677)
					(end 420.051992 -1.22301)
				)
				(arc
					(start 418.781992 -1.22301)
					(mid 418.398452 -1.60655)
					(end 418.781992 -1.99009)
				)
				(xy 419.228778 -1.99009) (xy 419.228778 -1.752092) (xy 419.153086 -1.6764)
				(arc
					(start 419.039294 -1.6764)
					(mid 418.515377 -1.60655)
					(end 419.039294 -1.5367)
				)
			)
		)
	)
	(zone
		(layer "F.Cu")
		(hatch none 0.5)
		(connect_pads
			(clearance 0)
		)
		(min_thickness 0.25)
		(keepout
			(tracks allowed)
			(vias allowed)
			(pads allowed)
			(copperpour allowed)
			(footprints not_allowed)
		)
		(placement
			(enabled no)
			(sheetname "")
		)
		(fill
			(thermal_gap 0.5)
			(thermal_bridge_width 0.5)
			(island_removal_mode 0)
		)
		(polygon
			(pts
				(xy 22.52472 -132.166106) (xy 22.52472 -130.16611) (xy 163.524692 -130.16611) (xy 163.524692 -132.166106)
			)
		)
	)
	(zone
		(layer "F.Cu")
		(hatch none 0.5)
		(connect_pads
			(clearance 0)
		)
		(min_thickness 0.25)
		(keepout
			(tracks allowed)
			(vias allowed)
			(pads allowed)
			(copperpour allowed)
			(footprints not_allowed)
		)
		(placement
			(enabled no)
			(sheetname "")
		)
		(fill
			(thermal_gap 0.5)
			(thermal_bridge_width 0.5)
			(island_removal_mode 0)
		)
		(polygon
			(pts
				(xy 474.950536 -51.676808) (xy 479.70059 -51.676808) (xy 479.70059 -44.676822) (xy 474.950536 -44.676822)
			)
		)
	)
	(zone
		(layer "F.Cu")
		(hatch none 0.5)
		(connect_pads
			(clearance 0)
		)
		(min_thickness 0.25)
		(keepout
			(tracks allowed)
			(vias allowed)
			(pads allowed)
			(copperpour allowed)
			(footprints not_allowed)
		)
		(placement
			(enabled no)
			(sheetname "")
		)
		(fill
			(thermal_gap 0.5)
			(thermal_bridge_width 0.5)
			(island_removal_mode 0)
		)
		(polygon
			(pts
				(xy 163.524692 -148.167344) (xy 22.52472 -148.167344) (xy 22.52472 -151.368506) (xy 163.524692 -151.368506)
			)
		)
	)
	(zone
		(net "GND")
		(layer "F.Cu")
		(hatch none 0.5)
		(connect_pads
			(clearance 0.5)
		)
		(min_thickness 0.25)
		(fill yes
			(thermal_gap 0.5)
			(thermal_bridge_width 0.5)
			(island_removal_mode 0)
		)
		(polygon
			(pts
				(xy 383.4892 -70.809104) (xy 383.4892 -69.2658) (xy 383.92862 -68.82638) (xy 388.99338 -68.82638)
				(xy 389.767572 -68.051934) (xy 391.103612 -68.051934) (xy 391.122662 -68.032884) (xy 391.122916 -68.032884)
				(xy 391.16 -67.9958) (xy 391.16 -66.8528) (xy 391.16 -66.71564) (xy 391.202672 -66.672968) (xy 391.641584 -66.672968)
				(xy 391.791444 -66.672968) (xy 391.80262 -66.661792) (xy 391.80262 -65.57264) (xy 391.84072 -65.53454)
				(xy 392.5062 -65.53454) (xy 392.550904 -65.579244) (xy 392.550904 -66.66103) (xy 392.557 -66.667126)
				(xy 393.184126 -66.667126) (xy 393.192 -66.675) (xy 393.192 -68.4784) (xy 393.192 -68.67271) (xy 393.147296 -68.717414)
				(xy 392.724386 -68.717414) (xy 392.557254 -68.717414) (xy 392.554968 -68.7197) (xy 392.554968 -68.886832)
				(xy 392.554968 -69.823838) (xy 392.549888 -69.828918) (xy 391.80516 -69.828918) (xy 391.79881 -69.822568)
				(xy 391.79881 -68.76161) (xy 391.79881 -68.722494) (xy 391.796016 -68.7197) (xy 391.1473 -68.7197)
				(xy 391.143236 -68.723764) (xy 389.9154 -69.9516) (xy 389.9154 -70.109334) (xy 389.9154 -71.27621)
				(xy 389.89 -71.30161) (xy 385.77139 -71.30161) (xy 385.4704 -71.6026) (xy 383.8194 -71.6026) (xy 383.4892 -71.2724)
			)
		)
	)
	(zone
		(layer "F.Cu")
		(hatch none 0.5)
		(connect_pads
			(clearance 0)
		)
		(min_thickness 0.25)
		(keepout
			(tracks allowed)
			(vias allowed)
			(pads allowed)
			(copperpour allowed)
			(footprints allowed)
		)
		(placement
			(enabled no)
			(sheetname "")
		)
		(fill
			(thermal_gap 0.5)
			(thermal_bridge_width 0.5)
			(island_removal_mode 0)
		)
		(polygon
			(pts
				(xy 31.369 -85.725) (xy 33.528 -85.725) (xy 33.528 -87.376) (xy 31.369 -87.376)
			)
		)
	)
	(zone
		(layer "F.Cu")
		(hatch none 0.5)
		(connect_pads
			(clearance 0)
		)
		(min_thickness 0.25)
		(keepout
			(tracks allowed)
			(vias allowed)
			(pads allowed)
			(copperpour allowed)
			(footprints allowed)
		)
		(placement
			(enabled no)
			(sheetname "")
		)
		(fill
			(thermal_gap 0.5)
			(thermal_bridge_width 0.5)
			(island_removal_mode 0)
		)
		(polygon
			(pts
				(xy 195.5292 -73.7362) (xy 195.5292 -71.8566) (xy 197.3072 -71.8566) (xy 197.3072 -73.7362)
			)
		)
	)
	(zone
		(layer "F.Cu")
		(hatch none 0.5)
		(connect_pads
			(clearance 0)
		)
		(min_thickness 0.25)
		(keepout
			(tracks allowed)
			(vias allowed)
			(pads allowed)
			(copperpour allowed)
			(footprints not_allowed)
		)
		(placement
			(enabled no)
			(sheetname "")
		)
		(fill
			(thermal_gap 0.5)
			(thermal_bridge_width 0.5)
			(island_removal_mode 0)
		)
		(polygon
			(pts
				(xy 433.200048 -123.686824) (xy 426.200062 -123.686824) (xy 426.200062 -130.68681) (xy 433.200048 -130.68681)
			)
		)
	)
	(zone
		(layer "F.Cu")
		(hatch none 0.5)
		(connect_pads
			(clearance 0)
		)
		(min_thickness 0.25)
		(keepout
			(tracks allowed)
			(vias allowed)
			(pads allowed)
			(copperpour allowed)
			(footprints allowed)
		)
		(placement
			(enabled no)
			(sheetname "")
		)
		(fill
			(thermal_gap 0.5)
			(thermal_bridge_width 0.5)
			(island_removal_mode 0)
		)
		(polygon
			(pts
				(xy 195.0974 -60.579) (xy 195.0974 -59.436) (xy 197.104 -59.436) (xy 197.104 -60.579)
			)
		)
	)
	(zone
		(layer "F.Cu")
		(hatch none 0.5)
		(connect_pads
			(clearance 0)
		)
		(min_thickness 0.25)
		(keepout
			(tracks allowed)
			(vias allowed)
			(pads allowed)
			(copperpour allowed)
			(footprints allowed)
		)
		(placement
			(enabled no)
			(sheetname "")
		)
		(fill
			(thermal_gap 0.5)
			(thermal_bridge_width 0.5)
			(island_removal_mode 0)
		)
		(polygon
			(pts
				(xy 349.758 -99.9744) (xy 349.758 -97.6884) (xy 351.7646 -97.6884) (xy 351.7646 -99.9744)
			)
		)
	)
	(zone
		(layer "F.Cu")
		(hatch none 0.5)
		(connect_pads
			(clearance 0)
		)
		(min_thickness 0.25)
		(keepout
			(tracks allowed)
			(vias allowed)
			(pads allowed)
			(copperpour allowed)
			(footprints allowed)
		)
		(placement
			(enabled no)
			(sheetname "")
		)
		(fill
			(thermal_gap 0.5)
			(thermal_bridge_width 0.5)
			(island_removal_mode 0)
		)
		(polygon
			(pts
				(xy 348.3356 -156.0576) (xy 348.3356 -153.7716) (xy 350.3422 -153.7716) (xy 350.3422 -156.0576)
			)
		)
	)
	(zone
		(net "VR_PVCCIN_CPU1_PHASE2")
		(layer "F.Cu")
		(hatch none 0.5)
		(connect_pads
			(clearance 0.5)
		)
		(min_thickness 0.25)
		(fill yes
			(thermal_gap 0.5)
			(thermal_bridge_width 0.5)
			(island_removal_mode 0)
		)
		(polygon
			(pts
				(xy 36.4998 -67.816222) (xy 40.303196 -67.816222) (xy 41.563798 -67.816222) (xy 42.037 -67.34302)
				(xy 42.037 -63.22822) (xy 41.545002 -62.736222) (xy 40.303196 -62.736222) (xy 36.5252 -62.736222)
				(xy 36.4744 -62.787022) (xy 36.4744 -67.790822)
			)
		)
	)
	(zone
		(layer "F.Cu")
		(hatch none 0.5)
		(connect_pads
			(clearance 0)
		)
		(min_thickness 0.25)
		(keepout
			(tracks allowed)
			(vias allowed)
			(pads allowed)
			(copperpour allowed)
			(footprints allowed)
		)
		(placement
			(enabled no)
			(sheetname "")
		)
		(fill
			(thermal_gap 0.5)
			(thermal_bridge_width 0.5)
			(island_removal_mode 0)
		)
		(polygon
			(pts
				(xy 449.980558 -63.267336) (xy 452.79183 -63.267336) (xy 453.007222 -63.051944) (xy 453.007222 -60.282074)
				(xy 452.742046 -60.016898) (xy 450.130164 -60.016898) (xy 449.856352 -60.29071) (xy 449.856352 -63.14313)
			)
		)
	)
	(zone
		(layer "F.Cu")
		(hatch none 0.5)
		(connect_pads
			(clearance 0)
		)
		(min_thickness 0.25)
		(keepout
			(tracks allowed)
			(vias allowed)
			(pads allowed)
			(copperpour allowed)
			(footprints allowed)
		)
		(placement
			(enabled no)
			(sheetname "")
		)
		(fill
			(thermal_gap 0.5)
			(thermal_bridge_width 0.5)
			(island_removal_mode 0)
		)
		(polygon
			(pts
				(xy 372.6942 -155.829) (xy 372.6942 -153.3398) (xy 374.6246 -153.3398) (xy 374.6246 -155.829)
			)
		)
	)
	(zone
		(net "PVCCMCP_CPU0")
		(layer "F.Cu")
		(hatch none 0.5)
		(connect_pads
			(clearance 0.5)
		)
		(min_thickness 0.25)
		(fill yes
			(thermal_gap 0.5)
			(thermal_bridge_width 0.5)
			(island_removal_mode 0)
		)
		(polygon
			(pts
				(xy 272.9992 -76.962) (xy 272.735548 -77.225652) (xy 269.113 -77.225652) (xy 268.986 -77.352652)
				(xy 268.986 -80.01) (xy 269.022068 -80.046068) (xy 277.458932 -80.046068) (xy 277.5966 -79.9084)
				(xy 277.5966 -79.1464) (xy 277.7998 -78.9432) (xy 277.7998 -77.1144) (xy 277.6474 -76.962)
			)
		)
		(polygon
			(pts
				(xy 276.7838 -79.0575) (xy 276.5806 -79.0575) (xy 276.5806 -79.2607) (xy 276.7838 -79.2607)
			)
		)
		(polygon
			(pts
				(xy 276.2758 -79.0575) (xy 276.0726 -79.0575) (xy 276.0726 -79.2607) (xy 276.2758 -79.2607)
			)
		)
		(polygon
			(pts
				(xy 275.5138 -79.0575) (xy 275.3106 -79.0575) (xy 275.3106 -79.2607) (xy 275.5138 -79.2607)
			)
		)
		(polygon
			(pts
				(xy 275.0058 -79.0575) (xy 274.8026 -79.0575) (xy 274.8026 -79.2607) (xy 275.0058 -79.2607)
			)
		)
		(polygon
			(pts
				(xy 274.2438 -79.0575) (xy 274.0406 -79.0575) (xy 274.0406 -79.2607) (xy 274.2438 -79.2607)
			)
		)
		(polygon
			(pts
				(xy 273.7358 -79.0575) (xy 273.5326 -79.0575) (xy 273.5326 -79.2607) (xy 273.7358 -79.2607)
			)
		)
		(polygon
			(pts
				(xy 272.9738 -79.0575) (xy 272.7706 -79.0575) (xy 272.7706 -79.2607) (xy 272.9738 -79.2607)
			)
		)
		(polygon
			(pts
				(xy 272.4658 -79.0575) (xy 272.2626 -79.0575) (xy 272.2626 -79.2607) (xy 272.4658 -79.2607)
			)
		)
		(polygon
			(pts
				(xy 271.7038 -79.0575) (xy 271.5006 -79.0575) (xy 271.5006 -79.2607) (xy 271.7038 -79.2607)
			)
		)
		(polygon
			(pts
				(xy 271.1958 -79.0575) (xy 270.9926 -79.0575) (xy 270.9926 -79.2607) (xy 271.1958 -79.2607)
			)
		)
		(polygon
			(pts
				(xy 270.4338 -79.0575) (xy 270.2306 -79.0575) (xy 270.2306 -79.2607) (xy 270.4338 -79.2607)
			)
		)
		(polygon
			(pts
				(xy 269.9258 -79.0575) (xy 269.7226 -79.0575) (xy 269.7226 -79.2607) (xy 269.9258 -79.2607)
			)
		)
		(polygon
			(pts
				(xy 272.381472 -77.979016) (xy 272.178272 -77.979016) (xy 272.178272 -78.182216) (xy 272.381472 -78.182216)
			)
		)
		(polygon
			(pts
				(xy 271.619472 -77.979016) (xy 271.416272 -77.979016) (xy 271.416272 -78.182216) (xy 271.619472 -78.182216)
			)
		)
		(polygon
			(pts
				(xy 271.136872 -77.979016) (xy 270.933672 -77.979016) (xy 270.933672 -78.182216) (xy 271.136872 -78.182216)
			)
		)
		(polygon
			(pts
				(xy 270.374872 -77.979016) (xy 270.171672 -77.979016) (xy 270.171672 -78.182216) (xy 270.374872 -78.182216)
			)
		)
		(polygon
			(pts
				(xy 269.892272 -77.979016) (xy 269.689072 -77.979016) (xy 269.689072 -78.182216) (xy 269.892272 -78.182216)
			)
		)
		(polygon
			(pts
				(xy 276.391624 -77.772514) (xy 276.188424 -77.772514) (xy 276.188424 -77.975714) (xy 276.391624 -77.975714)
			)
		)
		(polygon
			(pts
				(xy 275.629624 -77.772514) (xy 275.426424 -77.772514) (xy 275.426424 -77.975714) (xy 275.629624 -77.975714)
			)
		)
		(polygon
			(pts
				(xy 275.121624 -77.772514) (xy 274.918424 -77.772514) (xy 274.918424 -77.975714) (xy 275.121624 -77.975714)
			)
		)
		(polygon
			(pts
				(xy 274.359624 -77.772514) (xy 274.156424 -77.772514) (xy 274.156424 -77.975714) (xy 274.359624 -77.975714)
			)
		)
		(polygon
			(pts
				(xy 273.851624 -77.772514) (xy 273.648424 -77.772514) (xy 273.648424 -77.975714) (xy 273.851624 -77.975714)
			)
		)
		(polygon
			(pts
				(xy 273.089624 -77.772514) (xy 272.886424 -77.772514) (xy 272.886424 -77.975714) (xy 273.089624 -77.975714)
			)
		)
		(polygon
			(pts
				(xy 276.903434 -77.725016) (xy 276.700234 -77.725016) (xy 276.700234 -77.928216) (xy 276.903434 -77.928216)
			)
		)
	)
	(zone
		(net "P3V3_DB1200")
		(layer "F.Cu")
		(hatch none 0.5)
		(connect_pads
			(clearance 0.5)
		)
		(min_thickness 0.25)
		(fill yes
			(thermal_gap 0.5)
			(thermal_bridge_width 0.5)
			(island_removal_mode 0)
		)
		(polygon
			(pts
				(xy 167.547544 -72.78497) (xy 167.523922 -72.761348) (xy 166.506398 -72.761348) (xy 166.1922 -73.075546)
				(xy 166.1922 -73.2028) (xy 166.1922 -73.879202) (xy 166.223442 -73.910444) (xy 166.751762 -73.910444)
				(xy 166.904416 -73.75779) (xy 166.904416 -73.436988) (xy 167.038782 -73.302622) (xy 167.499284 -73.302622)
				(xy 167.547544 -73.254362)
			)
		)
	)
	(zone
		(layer "F.Cu")
		(hatch none 0.5)
		(connect_pads
			(clearance 0)
		)
		(min_thickness 0.25)
		(keepout
			(tracks not_allowed)
			(vias allowed)
			(pads allowed)
			(copperpour not_allowed)
			(footprints allowed)
		)
		(placement
			(enabled no)
			(sheetname "")
		)
		(fill
			(thermal_gap 0.5)
			(thermal_bridge_width 0.5)
			(island_removal_mode 0)
		)
		(polygon
			(pts
				(arc
					(start 171.99991 -1.999996)
					(mid 167.999918 1.999996)
					(end 171.99991 5.999988)
				)
				(arc
					(start 175.50003 5.999988)
					(mid 179.500022 1.999996)
					(end 175.50003 -1.999996)
				)
			)
		)
	)
	(zone
		(net "PVDDQ_DEF")
		(layer "F.Cu")
		(hatch none 0.5)
		(connect_pads
			(clearance 0.5)
		)
		(min_thickness 0.25)
		(fill yes
			(thermal_gap 0.5)
			(thermal_bridge_width 0.5)
			(island_removal_mode 0)
		)
		(polygon
			(pts
				(xy 265.929364 -148.370036) (xy 265.678158 -148.621242) (xy 265.678158 -150.687532) (xy 265.979148 -150.988522)
				(xy 277.326598 -150.988522) (xy 277.529036 -150.786084) (xy 277.529036 -148.55825) (xy 277.340822 -148.370036)
			)
		)
		(polygon
			(pts
				(xy 275.657564 -150.2029) (xy 275.454364 -150.2029) (xy 275.454364 -150.4061) (xy 275.657564 -150.4061)
			)
		)
		(polygon
			(pts
				(xy 272.518632 -150.2029) (xy 272.315432 -150.2029) (xy 272.315432 -150.4061) (xy 272.518632 -150.4061)
			)
		)
		(polygon
			(pts
				(xy 269.216632 -150.2029) (xy 269.013432 -150.2029) (xy 269.013432 -150.4061) (xy 269.216632 -150.4061)
			)
		)
		(polygon
			(pts
				(xy 272.518632 -149.2123) (xy 272.315432 -149.2123) (xy 272.315432 -149.4155) (xy 272.518632 -149.4155)
			)
		)
		(polygon
			(pts
				(xy 269.216632 -149.2123) (xy 269.013432 -149.2123) (xy 269.013432 -149.4155) (xy 269.216632 -149.4155)
			)
		)
		(polygon
			(pts
				(xy 266.054332 -149.2123) (xy 265.851132 -149.2123) (xy 265.851132 -149.4155) (xy 266.054332 -149.4155)
			)
		)
	)
	(zone
		(layer "F.Cu")
		(hatch none 0.5)
		(connect_pads
			(clearance 0)
		)
		(min_thickness 0.25)
		(keepout
			(tracks allowed)
			(vias allowed)
			(pads allowed)
			(copperpour allowed)
			(footprints not_allowed)
		)
		(placement
			(enabled no)
			(sheetname "")
		)
		(fill
			(thermal_gap 0.5)
			(thermal_bridge_width 0.5)
			(island_removal_mode 0)
		)
		(polygon
			(pts
				(arc
					(start 493.100614 -114.596926)
					(mid 496.700556 -110.996984)
					(end 500.300498 -114.596926)
				)
				(arc
					(start 500.300498 -116.196872)
					(mid 496.700556 -119.796814)
					(end 493.100614 -116.196872)
				)
			)
		)
	)
	(zone
		(net "GND")
		(layer "F.Cu")
		(hatch none 0.5)
		(connect_pads
			(clearance 0.5)
		)
		(min_thickness 0.25)
		(fill yes
			(thermal_gap 0.5)
			(thermal_bridge_width 0.5)
			(island_removal_mode 0)
		)
		(polygon
			(pts
				(xy -5.5118 -14.3764) (xy -5.5118 -5.4356) (xy -5.461 -5.3848) (xy -3.556 -5.3848) (xy -3.429 -5.5118)
				(xy -3.429 -11.84275) (xy -3.434588 -11.848592) (xy -3.434588 -12.398248) (xy -4.501896 -13.465556)
				(xy -4.501896 -14.077696) (xy -4.501896 -15.337028) (xy -4.709668 -15.5448) (xy -4.953 -15.5448)
				(xy -5.3594 -15.5448) (xy -5.5118 -15.3924) (xy -5.5118 -14.6304)
			)
		)
	)
	(zone
		(layer "F.Cu")
		(hatch none 0.5)
		(connect_pads
			(clearance 0)
		)
		(min_thickness 0.25)
		(keepout
			(tracks not_allowed)
			(vias allowed)
			(pads allowed)
			(copperpour not_allowed)
			(footprints allowed)
		)
		(placement
			(enabled no)
			(sheetname "")
		)
		(fill
			(thermal_gap 0.5)
			(thermal_bridge_width 0.5)
			(island_removal_mode 0)
		)
		(polygon
			(pts
				(xy 16.36776 -27.2923) (xy 16.677386 -27.601926)
				(arc
					(start 16.677386 -27.619198)
					(mid 16.623107 -28.142711)
					(end 16.507206 -27.629358)
				)
				(xy 16.309848 -27.432) (xy 16.223996 -27.432)
				(arc
					(start 16.223996 -27.876246)
					(mid 16.607409 -28.26004)
					(end 16.991076 -27.8765)
				)
				(arc
					(start 16.991076 -26.6065)
					(mid 16.607536 -26.22296)
					(end 16.223996 -26.6065)
				)
				(xy 16.223996 -27.051) (xy 16.46428 -27.051) (xy 16.537686 -26.977594)
				(arc
					(start 16.537686 -26.863802)
					(mid 16.607536 -26.339885)
					(end 16.677386 -26.863802)
				)
				(xy 16.677386 -27.035506) (xy 16.522192 -27.1907) (xy 16.223996 -27.1907) (xy 16.223996 -27.2923)
			)
		)
	)
	(zone
		(net "GND")
		(layer "F.Cu")
		(hatch none 0.5)
		(connect_pads
			(clearance 0.5)
		)
		(min_thickness 0.25)
		(fill yes
			(thermal_gap 0.5)
			(thermal_bridge_width 0.5)
			(island_removal_mode 0)
		)
		(polygon
			(pts
				(xy 481.1268 -118.0719) (xy 481.1268 -114.7572) (xy 481.9396 -113.9444) (xy 481.9396 -111.0615)
				(xy 482.0158 -110.9853) (xy 483.2223 -110.9853) (xy 483.2604 -111.0234) (xy 483.2604 -114.046) (xy 482.4476 -114.8588)
				(xy 482.4476 -118.0846) (xy 482.3206 -118.2116) (xy 481.2665 -118.2116)
			)
		)
	)
	(zone
		(layer "F.Cu")
		(hatch none 0.5)
		(connect_pads
			(clearance 0)
		)
		(min_thickness 0.25)
		(keepout
			(tracks not_allowed)
			(vias allowed)
			(pads allowed)
			(copperpour not_allowed)
			(footprints allowed)
		)
		(placement
			(enabled no)
			(sheetname "")
		)
		(fill
			(thermal_gap 0.5)
			(thermal_bridge_width 0.5)
			(island_removal_mode 0)
		)
		(polygon
			(pts
				(xy 371.534182 -3.320542) (xy 371.534182 -3.046476) (xy 371.713506 -2.867152)
				(arc
					(start 371.912896 -2.867152)
					(mid 372.436813 -2.937002)
					(end 371.912896 -3.006852)
				)
				(xy 371.771418 -3.006852) (xy 371.673882 -3.104388) (xy 371.673882 -3.320542)
				(arc
					(start 372.169944 -3.320542)
					(mid 372.553738 -2.937129)
					(end 372.170198 -2.553462)
				)
				(arc
					(start 370.900198 -2.553462)
					(mid 370.516658 -2.937002)
					(end 370.900198 -3.320542)
				)
				(xy 371.292882 -3.320542) (xy 371.292882 -3.080512) (xy 371.219222 -3.006852)
				(arc
					(start 371.1575 -3.006852)
					(mid 370.633583 -2.937002)
					(end 371.1575 -2.867152)
				)
				(xy 371.277134 -2.867152) (xy 371.432582 -3.0226) (xy 371.432582 -3.320542)
			)
		)
	)
	(zone
		(net "PVTT_DEF")
		(layer "F.Cu")
		(hatch none 0.5)
		(connect_pads
			(clearance 0.5)
		)
		(min_thickness 0.25)
		(fill yes
			(thermal_gap 0.5)
			(thermal_bridge_width 0.5)
			(island_removal_mode 0)
		)
		(polygon
			(pts
				(xy 259.052822 -153.764488) (xy 259.052822 -150.683976) (xy 259.094732 -150.642066) (xy 259.383276 -150.642066)
				(xy 259.420106 -150.678896) (xy 259.420106 -150.727664) (xy 259.420106 -150.739094) (xy 259.420106 -151.03729)
				(xy 259.733288 -151.350472) (xy 261.1628 -151.350472) (xy 261.5946 -150.918672) (xy 261.5946 -149.313392)
				(xy 261.5946 -149.076918) (xy 261.475474 -148.957792) (xy 261.239 -148.957792) (xy 259.984748 -148.957792)
				(xy 259.920232 -148.893276) (xy 259.04825 -148.021294) (xy 259.04825 -141.457934) (xy 258.871466 -141.28115)
				(xy 258.871466 -140.924534) (xy 258.9022 -140.8938) (xy 260.524498 -140.8938) (xy 261.63778 -140.8938)
				(xy 261.690612 -140.8938) (xy 261.813802 -140.77061) (xy 261.813802 -138.971782) (xy 261.7216 -138.87958)
				(xy 261.34822 -138.5062) (xy 259.207 -138.5062) (xy 258.996688 -138.295888) (xy 259.000752 -138.291824)
				(xy 259.000752 -136.477248) (xy 259.715 -135.763) (xy 261.6708 -135.763) (xy 263.0424 -137.1346)
				(xy 263.0424 -143.411702) (xy 263.0424 -147.828) (xy 263.0678 -147.8534) (xy 263.0678 -153.2128)
				(xy 262.1026 -154.178) (xy 262.1026 -157.1752) (xy 261.5946 -157.6832) (xy 259.1816 -157.6832) (xy 259.044186 -157.545786)
				(xy 259.052822 -157.53715)
			)
		)
	)
	(zone
		(layer "F.Cu")
		(hatch none 0.5)
		(connect_pads
			(clearance 0)
		)
		(min_thickness 0.25)
		(keepout
			(tracks allowed)
			(vias allowed)
			(pads allowed)
			(copperpour allowed)
			(footprints allowed)
		)
		(placement
			(enabled no)
			(sheetname "")
		)
		(fill
			(thermal_gap 0.5)
			(thermal_bridge_width 0.5)
			(island_removal_mode 0)
		)
		(polygon
			(pts
				(xy 29.083 -82.804) (xy 29.083 -79.502) (xy 31.242 -79.502) (xy 31.242 -82.804)
			)
		)
	)
	(zone
		(layer "F.Cu")
		(hatch none 0.5)
		(connect_pads
			(clearance 0)
		)
		(min_thickness 0.25)
		(keepout
			(tracks not_allowed)
			(vias allowed)
			(pads allowed)
			(copperpour not_allowed)
			(footprints allowed)
		)
		(placement
			(enabled no)
			(sheetname "")
		)
		(fill
			(thermal_gap 0.5)
			(thermal_bridge_width 0.5)
			(island_removal_mode 0)
		)
		(polygon
			(pts
				(arc
					(start 318.000126 -57.090056)
					(mid 315.460126 -54.550056)
					(end 318.000126 -52.010056)
				)
				(arc
					(start 318.000126 -52.010056)
					(mid 320.540126 -54.550056)
					(end 318.000126 -57.090056)
				)
			)
		)
	)
	(zone
		(layer "F.Cu")
		(hatch none 0.5)
		(connect_pads
			(clearance 0)
		)
		(min_thickness 0.25)
		(keepout
			(tracks allowed)
			(vias allowed)
			(pads allowed)
			(copperpour allowed)
			(footprints allowed)
		)
		(placement
			(enabled no)
			(sheetname "")
		)
		(fill
			(thermal_gap 0.5)
			(thermal_bridge_width 0.5)
			(island_removal_mode 0)
		)
		(polygon
			(pts
				(xy 339.1027 -79.121) (xy 339.1027 -76.835) (xy 341.1093 -76.835) (xy 341.1093 -79.121)
			)
		)
	)
	(zone
		(layer "F.Cu")
		(hatch none 0.5)
		(connect_pads
			(clearance 0)
		)
		(min_thickness 0.25)
		(keepout
			(tracks allowed)
			(vias allowed)
			(pads allowed)
			(copperpour allowed)
			(footprints not_allowed)
		)
		(placement
			(enabled no)
			(sheetname "")
		)
		(fill
			(thermal_gap 0.5)
			(thermal_bridge_width 0.5)
			(island_removal_mode 0)
		)
		(polygon
			(pts
				(xy 332.425294 5.999988) (xy 337.425284 5.999988) (xy 337.425284 -22.919182) (xy 332.425294 -22.919182)
			)
		)
	)
	(zone
		(net "VR_FET_SW_P12V_STBY_PVCCIN_CPU0")
		(layer "F.Cu")
		(hatch none 0.5)
		(connect_pads
			(clearance 0.5)
		)
		(min_thickness 0.25)
		(fill yes
			(thermal_gap 0.5)
			(thermal_bridge_width 0.5)
			(island_removal_mode 0)
		)
		(polygon
			(pts
				(xy 196.487034 -58.932064) (xy 196.614034 -58.805064) (xy 196.614034 -58.79338) (xy 196.648832 -58.758582)
				(xy 196.648832 -57.430162) (xy 196.657214 -57.42178) (xy 198.62165 -57.42178) (xy 198.631048 -57.431178)
				(xy 198.631048 -59.7408) (xy 198.628 -59.743848) (xy 198.628 -59.996324) (xy 198.589392 -60.034932)
				(xy 198.589392 -60.617608) (xy 198.50608 -60.70092) (xy 197.31736 -60.70092) (xy 194.83578 -60.70092)
				(xy 194.65798 -60.52312) (xy 194.50558 -60.37072) (xy 194.50558 -59.48934) (xy 194.55892 -59.436)
				(xy 195.076064 -59.436) (xy 195.58 -58.932064)
			)
		)
	)
	(zone
		(net "P12V_STBY")
		(layer "F.Cu")
		(hatch none 0.5)
		(connect_pads
			(clearance 0.5)
		)
		(min_thickness 0.25)
		(fill yes
			(thermal_gap 0.5)
			(thermal_bridge_width 0.5)
			(island_removal_mode 0)
		)
		(polygon
			(pts
				(xy 161.337752 -114.130328) (xy 173.844966 -114.130328) (xy 174.059342 -114.344704) (xy 174.059342 -116.205)
				(xy 174.059342 -117.468142) (xy 173.132242 -118.395242) (xy 172.053758 -118.395242) (xy 171.958 -118.491)
				(xy 168.9735 -121.4755) (xy 168.336976 -122.112024) (xy 165.481 -122.112024) (xy 163.172394 -122.112024)
				(xy 161.368232 -120.307862) (xy 158.99257 -117.9322) (xy 158.472632 -117.9322) (xy 154.3558 -117.9322)
				(xy 154.1526 -118.1354) (xy 154.1526 -119.7102) (xy 154.1399 -119.7229) (xy 154.1399 -123.19889)
				(xy 153.961084 -123.377706) (xy 151.292306 -123.377706) (xy 149.22119 -121.30659) (xy 149.22119 -115.803172)
				(xy 150.186644 -114.837972) (xy 155.140152 -114.837972) (xy 155.847796 -114.130328) (xy 156.1211 -114.130328)
			)
		)
	)
	(zone
		(net "VR_PVPP_GHJ_PHASE")
		(layer "F.Cu")
		(hatch none 0.5)
		(connect_pads
			(clearance 0.5)
		)
		(min_thickness 0.25)
		(fill yes
			(thermal_gap 0.5)
			(thermal_bridge_width 0.5)
			(island_removal_mode 0)
		)
		(polygon
			(pts
				(xy 173.5328 -12.7889) (xy 172.501306 -12.7889) (xy 171.080176 -11.368024) (xy 170.991276 -11.279124)
				(xy 170.98899 -11.279124) (xy 170.48734 -10.77722) (xy 169.670222 -10.77722) (xy 169.54754 -10.654538)
				(xy 169.54754 -9.881362) (xy 169.49547 -9.829292) (xy 168.720008 -9.829292) (xy 168.638474 -9.910826)
				(xy 168.638474 -10.55751) (xy 169.926 -11.845036) (xy 169.926 -16.51) (xy 171.323 -17.907) (xy 174.17415 -17.907)
				(xy 174.222156 -17.858994) (xy 174.222156 -17.080738) (xy 174.538386 -16.764508) (xy 174.878492 -16.764508)
				(xy 174.879 -16.764) (xy 175.895 -16.764) (xy 176.0601 -16.5989) (xy 176.0601 -15.5829) (xy 176.1109 -15.5321)
				(xy 179.832 -15.5321) (xy 179.8701 -15.494) (xy 179.8701 -13.2969) (xy 179.9336 -13.2334) (xy 180.8734 -13.2334)
				(xy 180.8988 -13.208) (xy 180.8988 -12.954) (xy 180.8861 -12.9413) (xy 175.685196 -12.9413) (xy 175.167544 -13.458952)
				(xy 175.136048 -13.458952) (xy 175.133 -13.462) (xy 174.2059 -13.462)
			)
		)
	)
	(zone
		(layer "F.Cu")
		(hatch none 0.5)
		(connect_pads
			(clearance 0)
		)
		(min_thickness 0.25)
		(keepout
			(tracks allowed)
			(vias allowed)
			(pads allowed)
			(copperpour allowed)
			(footprints not_allowed)
		)
		(placement
			(enabled no)
			(sheetname "")
		)
		(fill
			(thermal_gap 0.5)
			(thermal_bridge_width 0.5)
			(island_removal_mode 0)
		)
		(polygon
			(pts
				(arc
					(start 369.48999 -84.309966)
					(mid 371.08003 -85.900006)
					(end 369.48999 -87.490046)
				)
				(arc
					(start 369.48999 -87.490046)
					(mid 367.89995 -85.900006)
					(end 369.48999 -84.309966)
				)
			)
		)
	)
	(zone
		(layer "F.Cu")
		(hatch none 0.5)
		(connect_pads
			(clearance 0)
		)
		(min_thickness 0.25)
		(keepout
			(tracks not_allowed)
			(vias allowed)
			(pads allowed)
			(copperpour not_allowed)
			(footprints allowed)
		)
		(placement
			(enabled no)
			(sheetname "")
		)
		(fill
			(thermal_gap 0.5)
			(thermal_bridge_width 0.5)
			(island_removal_mode 0)
		)
		(polygon
			(pts
				(arc
					(start 152.999948 -52.649882)
					(mid 154.900122 -54.550056)
					(end 152.999948 -56.449976)
				)
				(arc
					(start 152.999948 -56.449976)
					(mid 151.100028 -54.550056)
					(end 152.999948 -52.649882)
				)
			)
		)
	)
	(zone
		(layer "F.Cu")
		(hatch none 0.5)
		(connect_pads
			(clearance 0)
		)
		(min_thickness 0.25)
		(keepout
			(tracks allowed)
			(vias allowed)
			(pads allowed)
			(copperpour allowed)
			(footprints not_allowed)
		)
		(placement
			(enabled no)
			(sheetname "")
		)
		(fill
			(thermal_gap 0.5)
			(thermal_bridge_width 0.5)
			(island_removal_mode 0)
		)
		(polygon
			(pts
				(arc
					(start 318.000126 -52.649882)
					(mid 319.9003 -54.550056)
					(end 318.000126 -56.449976)
				)
				(arc
					(start 318.000126 -56.449976)
					(mid 316.100206 -54.550056)
					(end 318.000126 -52.649882)
				)
			)
		)
	)
	(zone
		(layer "F.Cu")
		(hatch none 0.5)
		(connect_pads
			(clearance 0)
		)
		(min_thickness 0.25)
		(keepout
			(tracks allowed)
			(vias allowed)
			(pads allowed)
			(copperpour allowed)
			(footprints not_allowed)
		)
		(placement
			(enabled no)
			(sheetname "")
		)
		(fill
			(thermal_gap 0.5)
			(thermal_bridge_width 0.5)
			(island_removal_mode 0)
		)
		(polygon
			(pts
				(xy -5.999988 2.500122)
				(arc
					(start -4.898898 2.500122)
					(mid -5.499955 0)
					(end -4.898898 -2.500122)
				)
				(xy -5.999988 -2.500122)
			)
		)
	)
	(zone
		(layer "F.Cu")
		(hatch none 0.5)
		(connect_pads
			(clearance 0)
		)
		(min_thickness 0.25)
		(keepout
			(tracks not_allowed)
			(vias allowed)
			(pads allowed)
			(copperpour not_allowed)
			(footprints allowed)
		)
		(placement
			(enabled no)
			(sheetname "")
		)
		(fill
			(thermal_gap 0.5)
			(thermal_bridge_width 0.5)
			(island_removal_mode 0)
		)
		(polygon
			(pts
				(xy 400.176492 -10.295636) (xy 400.684492 -10.295636) (xy 400.684492 -10.651236) (xy 400.176492 -10.651236)
			)
		)
	)
	(zone
		(layer "F.Cu")
		(hatch none 0.5)
		(connect_pads
			(clearance 0)
		)
		(min_thickness 0.25)
		(keepout
			(tracks allowed)
			(vias allowed)
			(pads allowed)
			(copperpour allowed)
			(footprints allowed)
		)
		(placement
			(enabled no)
			(sheetname "")
		)
		(fill
			(thermal_gap 0.5)
			(thermal_bridge_width 0.5)
			(island_removal_mode 0)
		)
		(polygon
			(pts
				(xy 232.41 -52.705) (xy 232.41 -52.324) (xy 234.823 -49.911) (xy 238.506 -49.911) (xy 238.633 -49.911)
				(xy 238.633 -50.546) (xy 235.599224 -53.579776) (xy 233.413554 -53.579776) (xy 232.664 -53.582316)
				(xy 232.664 -52.959)
			)
		)
	)
	(zone
		(net "GND")
		(layer "F.Cu")
		(hatch none 0.5)
		(connect_pads
			(clearance 0.5)
		)
		(min_thickness 0.25)
		(fill yes
			(thermal_gap 0.5)
			(thermal_bridge_width 0.5)
			(island_removal_mode 0)
		)
		(polygon
			(pts
				(xy 31.814262 -24.358854) (xy 36.204652 -28.749244) (xy 37.029644 -28.749244) (xy 40.001444 -28.749244)
				(xy 40.115744 -28.634944) (xy 40.17264 -28.578048) (xy 40.17264 -22.81555) (xy 40.024558 -22.667468)
				(xy 39.945056 -22.667468) (xy 31.930594 -22.667468) (xy 31.814262 -22.7838)
			)
		)
	)
	(zone
		(layer "F.Cu")
		(hatch none 0.5)
		(connect_pads
			(clearance 0)
		)
		(min_thickness 0.25)
		(keepout
			(tracks allowed)
			(vias allowed)
			(pads allowed)
			(copperpour allowed)
			(footprints allowed)
		)
		(placement
			(enabled no)
			(sheetname "")
		)
		(fill
			(thermal_gap 0.5)
			(thermal_bridge_width 0.5)
			(island_removal_mode 0)
		)
		(polygon
			(pts
				(xy 322.4784 -118.7323) (xy 320.1924 -118.7323) (xy 320.1924 -116.7257) (xy 322.4784 -116.7257)
			)
		)
	)
	(zone
		(layer "F.Cu")
		(hatch none 0.5)
		(connect_pads
			(clearance 0)
		)
		(min_thickness 0.25)
		(keepout
			(tracks allowed)
			(vias allowed)
			(pads allowed)
			(copperpour allowed)
			(footprints not_allowed)
		)
		(placement
			(enabled no)
			(sheetname "")
		)
		(fill
			(thermal_gap 0.5)
			(thermal_bridge_width 0.5)
			(island_removal_mode 0)
		)
		(polygon
			(pts
				(arc
					(start 0 -156.59989)
					(mid -1.49987 -155.10002)
					(end 0 -153.599896)
				)
				(arc
					(start 0.671576 -153.599896)
					(mid 1.338203 -153.485602)
					(end 1.928622 -153.15565)
				)
				(arc
					(start 1.928622 -153.15565)
					(mid 5.999742 -155.10002)
					(end 1.928622 -157.04439)
				)
				(arc
					(start 1.928622 -157.04439)
					(mid 1.338226 -156.714333)
					(end 0.671576 -156.59989)
				)
			)
		)
	)
	(zone
		(net "GND")
		(layer "F.Cu")
		(hatch none 0.5)
		(connect_pads
			(clearance 0.5)
		)
		(min_thickness 0.25)
		(fill yes
			(thermal_gap 0.5)
			(thermal_bridge_width 0.5)
			(island_removal_mode 0)
		)
		(polygon
			(pts
				(xy 171.4754 -148.71319) (xy 171.475146 -148.842222) (xy 171.475146 -149.731476) (xy 171.475146 -150.406354)
				(xy 171.34332 -150.53818) (xy 169.85234 -150.53818) (xy 169.697146 -150.382986) (xy 169.697146 -149.732746)
				(xy 169.697146 -149.477222) (xy 169.697146 -145.3134) (xy 169.697146 -145.2118) (xy 169.926 -144.982946)
				(xy 169.926 -144.2974) (xy 169.926 -144.270222) (xy 171.221146 -144.270222) (xy 171.4754 -144.524476)
			)
		)
	)
	(zone
		(layer "F.Cu")
		(hatch none 0.5)
		(connect_pads
			(clearance 0)
		)
		(min_thickness 0.25)
		(keepout
			(tracks not_allowed)
			(vias allowed)
			(pads allowed)
			(copperpour not_allowed)
			(footprints allowed)
		)
		(placement
			(enabled no)
			(sheetname "")
		)
		(fill
			(thermal_gap 0.5)
			(thermal_bridge_width 0.5)
			(island_removal_mode 0)
		)
		(polygon
			(pts
				(arc
					(start 448.124834 -5.965952)
					(mid 447.704863 -6.287117)
					(end 448.026028 -5.867146)
				)
				(xy 448.17538 -5.717794) (xy 448.17538 -5.715)
				(arc
					(start 447.893694 -5.715)
					(mid 447.5099 -6.098413)
					(end 447.89344 -6.48208)
				)
				(arc
					(start 448.835526 -6.48208)
					(mid 449.219066 -6.09854)
					(end 448.835526 -5.715)
				)
				(xy 448.55638 -5.715) (xy 448.55638 -5.720588)
				(arc
					(start 448.702938 -5.867146)
					(mid 449.024103 -6.287117)
					(end 448.604132 -5.965952)
				)
				(xy 448.41668 -5.7785) (xy 448.41668 -5.715) (xy 448.31508 -5.715) (xy 448.31508 -5.775706)
			)
		)
	)
	(zone
		(layer "F.Cu")
		(hatch none 0.5)
		(connect_pads
			(clearance 0)
		)
		(min_thickness 0.25)
		(keepout
			(tracks allowed)
			(vias allowed)
			(pads allowed)
			(copperpour allowed)
			(footprints allowed)
		)
		(placement
			(enabled no)
			(sheetname "")
		)
		(fill
			(thermal_gap 0.5)
			(thermal_bridge_width 0.5)
			(island_removal_mode 0)
		)
		(polygon
			(pts
				(xy 478.409 -46.355) (xy 478.409 -43.307) (xy 478.1296 -43.307) (xy 477.6216 -42.799) (xy 477.6216 -40.6654)
				(xy 478.409 -39.878) (xy 479.9838 -39.878) (xy 479.9838 -46.355)
			)
		)
	)
	(zone
		(net "GND")
		(layer "F.Cu")
		(hatch none 0.5)
		(connect_pads
			(clearance 0.5)
		)
		(min_thickness 0.25)
		(fill yes
			(thermal_gap 0.5)
			(thermal_bridge_width 0.5)
			(island_removal_mode 0)
		)
		(polygon
			(pts
				(xy 8.255 2.02565) (xy 11.811 2.02565) (xy 11.811 -1.53035) (xy 8.255 -1.53035)
			)
		)
	)
	(zone
		(layer "F.Cu")
		(hatch none 0.5)
		(connect_pads
			(clearance 0)
		)
		(min_thickness 0.25)
		(keepout
			(tracks allowed)
			(vias allowed)
			(pads allowed)
			(copperpour allowed)
			(footprints allowed)
		)
		(placement
			(enabled no)
			(sheetname "")
		)
		(fill
			(thermal_gap 0.5)
			(thermal_bridge_width 0.5)
			(island_removal_mode 0)
		)
		(polygon
			(pts
				(xy 347.599 -2.667) (xy 352.044 -2.667) (xy 352.679 -2.032) (xy 352.679 2.159) (xy 352.171 2.667)
				(xy 351.293684 2.667) (xy 351.293684 2.739644) (xy 350.985836 3.047492) (xy 350.985836 3.513328)
				(xy 350.717104 3.78206) (xy 349.216472 3.78206) (xy 348.932246 3.497834) (xy 348.932246 1.341628)
				(xy 348.97187 1.302004) (xy 348.97187 -0.683514) (xy 348.766384 -0.889) (xy 347.472 -0.889) (xy 347.345 -1.016)
				(xy 347.345 -2.413)
			)
		)
	)
	(zone
		(layer "F.Cu")
		(hatch none 0.5)
		(connect_pads
			(clearance 0)
		)
		(min_thickness 0.25)
		(keepout
			(tracks not_allowed)
			(vias allowed)
			(pads allowed)
			(copperpour not_allowed)
			(footprints allowed)
		)
		(placement
			(enabled no)
			(sheetname "")
		)
		(fill
			(thermal_gap 0.5)
			(thermal_bridge_width 0.5)
			(island_removal_mode 0)
		)
		(polygon
			(pts
				(arc
					(start 360.499914 -151.100028)
					(mid 364.499906 -155.10002)
					(end 360.499914 -159.100012)
				)
				(arc
					(start 357.000048 -159.100012)
					(mid 353.000056 -155.10002)
					(end 357.000048 -151.100028)
				)
			)
		)
	)
	(zone
		(layer "F.Cu")
		(hatch none 0.5)
		(connect_pads
			(clearance 0)
		)
		(min_thickness 0.25)
		(keepout
			(tracks not_allowed)
			(vias allowed)
			(pads allowed)
			(copperpour not_allowed)
			(footprints allowed)
		)
		(placement
			(enabled no)
			(sheetname "")
		)
		(fill
			(thermal_gap 0.5)
			(thermal_bridge_width 0.5)
			(island_removal_mode 0)
		)
		(polygon
			(pts
				(xy 402.522436 -3.26771) (xy 402.522436 -3.0353) (xy 402.743416 -2.81432)
				(arc
					(start 402.84019 -2.81432)
					(mid 403.364107 -2.88417)
					(end 402.84019 -2.95402)
				)
				(xy 402.801328 -2.95402) (xy 402.662136 -3.093212) (xy 402.662136 -3.26771)
				(arc
					(start 403.097238 -3.26771)
					(mid 403.481032 -2.884297)
					(end 403.097492 -2.50063)
				)
				(arc
					(start 401.827492 -2.50063)
					(mid 401.443952 -2.88417)
					(end 401.827492 -3.26771)
				)
				(xy 402.281136 -3.26771) (xy 402.281136 -3.071368) (xy 402.163788 -2.95402)
				(arc
					(start 402.084794 -2.95402)
					(mid 401.560877 -2.88417)
					(end 402.084794 -2.81432)
				)
				(xy 402.2217 -2.81432) (xy 402.420836 -3.013456) (xy 402.420836 -3.26771)
			)
		)
	)
	(zone
		(net "P3V3_STBY")
		(layer "F.Cu")
		(hatch none 0.5)
		(connect_pads
			(clearance 0.5)
		)
		(min_thickness 0.25)
		(fill yes
			(thermal_gap 0.5)
			(thermal_bridge_width 0.5)
			(island_removal_mode 0)
		)
		(polygon
			(pts
				(xy 392.811 -115.564666) (xy 392.049 -115.564666) (xy 392.049 -112.776) (xy 392.35507 -112.46993)
				(xy 392.819382 -112.46993) (xy 392.819382 -113.275618) (xy 392.811 -113.284)
			)
		)
	)
	(zone
		(layer "F.Cu")
		(hatch none 0.5)
		(connect_pads
			(clearance 0)
		)
		(min_thickness 0.25)
		(keepout
			(tracks allowed)
			(vias allowed)
			(pads allowed)
			(copperpour allowed)
			(footprints not_allowed)
		)
		(placement
			(enabled no)
			(sheetname "")
		)
		(fill
			(thermal_gap 0.5)
			(thermal_bridge_width 0.5)
			(island_removal_mode 0)
		)
		(polygon
			(pts
				(arc
					(start 198.930006 -103.000048)
					(mid 202.480164 -106.550206)
					(end 198.930006 -110.10011)
				)
				(arc
					(start 198.930006 -110.10011)
					(mid 195.380102 -106.550206)
					(end 198.930006 -103.000048)
				)
			)
		)
	)
	(zone
		(layer "F.Cu")
		(hatch none 0.5)
		(connect_pads
			(clearance 0)
		)
		(min_thickness 0.25)
		(keepout
			(tracks allowed)
			(vias allowed)
			(pads allowed)
			(copperpour allowed)
			(footprints allowed)
		)
		(placement
			(enabled no)
			(sheetname "")
		)
		(fill
			(thermal_gap 0.5)
			(thermal_bridge_width 0.5)
			(island_removal_mode 0)
		)
		(polygon
			(pts
				(xy 181.326282 -0.245872) (xy 182.7276 -0.245872) (xy 182.822596 -0.150876) (xy 182.822596 0.836422)
				(xy 182.384446 1.274572) (xy 181.105048 1.274572) (xy 180.868066 1.03759) (xy 180.868066 0.212344)
			)
		)
	)
	(zone
		(layer "F.Cu")
		(hatch none 0.5)
		(connect_pads
			(clearance 0)
		)
		(min_thickness 0.25)
		(keepout
			(tracks not_allowed)
			(vias allowed)
			(pads allowed)
			(copperpour not_allowed)
			(footprints allowed)
		)
		(placement
			(enabled no)
			(sheetname "")
		)
		(fill
			(thermal_gap 0.5)
			(thermal_bridge_width 0.5)
			(island_removal_mode 0)
		)
		(polygon
			(pts
				(xy 378.576586 -1.685036) (xy 378.749052 -1.857502) (xy 378.749052 -2.138426) (xy 378.850652 -2.138426)
				(xy 378.850652 -1.84023) (xy 379.005846 -1.685036)
				(arc
					(start 379.160278 -1.685036)
					(mid 379.684195 -1.754886)
					(end 379.160278 -1.824736)
				)
				(xy 379.063758 -1.824736) (xy 378.990352 -1.898142) (xy 378.990352 -2.138426)
				(arc
					(start 379.417326 -2.138426)
					(mid 379.800866 -1.755013)
					(end 379.41758 -1.371346)
				)
				(arc
					(start 378.14758 -1.371346)
					(mid 377.76404 -1.754886)
					(end 378.14758 -2.138426)
				)
				(xy 378.609352 -2.138426) (xy 378.609352 -1.915414) (xy 378.518674 -1.824736)
				(arc
					(start 378.404882 -1.824736)
					(mid 377.880965 -1.754886)
					(end 378.404882 -1.685036)
				)
			)
		)
	)
	(zone
		(layer "F.Cu")
		(hatch none 0.5)
		(connect_pads
			(clearance 0)
		)
		(min_thickness 0.25)
		(keepout
			(tracks allowed)
			(vias allowed)
			(pads allowed)
			(copperpour allowed)
			(footprints not_allowed)
		)
		(placement
			(enabled no)
			(sheetname "")
		)
		(fill
			(thermal_gap 0.5)
			(thermal_bridge_width 0.5)
			(island_removal_mode 0)
		)
		(polygon
			(pts
				(xy 104.70007 -35.299904) (xy 48.747426 -35.299904) (xy 48.747426 -117.80012) (xy 161.247328 -117.80012)
				(xy 161.247328 -35.299904) (xy 104.899968 -35.299904) (xy 104.899968 -36.500054) (xy 155.58135 -36.500054)
				(xy 160.049972 -40.968676)
				(arc
					(start 160.049972 -60.550044)
					(mid 159.376326 -62.176368)
					(end 157.750002 -62.850014)
				)
				(arc
					(start 151.99995 -62.850014)
					(mid 147.898921 -61.151102)
					(end 146.200114 -57.049924)
				)
				(arc
					(start 146.200114 -55.421276)
					(mid 146.375189 -54.541116)
					(end 146.873722 -53.794914)
				)
				(arc
					(start 147.994878 -52.673758)
					(mid 148.146724 -52.446644)
					(end 148.20011 -52.178712)
				)
				(arc
					(start 148.20011 -44.800012)
					(mid 147.702185 -43.597915)
					(end 146.500088 -43.09999)
				)
				(arc
					(start 140.846048 -43.09999)
					(mid 140.606555 -43.142216)
					(end 140.39596 -43.26382)
				)
				(arc
					(start 137.061194 -46.061884)
					(mid 136.369503 -46.461316)
					(end 135.582914 -46.60011)
				)
				(xy 104.899968 -46.60011) (xy 104.899968 -67.300094) (xy 111.300006 -67.300094) (xy 117.54993 -71.049896)
				(xy 117.54993 -82.049874) (xy 111.300006 -85.79993) (xy 98.700082 -85.79993) (xy 92.449904 -82.049874)
				(xy 92.449904 -71.049896) (xy 98.700082 -67.300094) (xy 104.70007 -67.300094) (xy 104.70007 -46.60011)
				(arc
					(start 74.417174 -46.60011)
					(mid 73.630436 -46.461384)
					(end 72.93864 -46.061884)
				)
				(arc
					(start 69.603874 -43.26382)
					(mid 69.39341 -43.142196)
					(end 69.15404 -43.09999)
				)
				(arc
					(start 63.5 -43.09999)
					(mid 62.297903 -43.597915)
					(end 61.799978 -44.800012)
				)
				(arc
					(start 61.799978 -52.178712)
					(mid 61.853264 -52.4466)
					(end 62.004956 -52.673758)
				)
				(arc
					(start 63.126366 -53.794914)
					(mid 63.624948 -54.541095)
					(end 63.799974 -55.421276)
				)
				(arc
					(start 63.799974 -58.799984)
					(mid 63.363567 -59.878099)
					(end 62.300104 -60.34913)
				)
				(arc
					(start 62.300104 -92.750894)
					(mid 63.3636 -93.221893)
					(end 63.799974 -94.30004)
				)
				(arc
					(start 63.799974 -97.678748)
					(mid 63.624899 -98.558908)
					(end 63.126366 -99.30511)
				)
				(arc
					(start 62.004956 -100.426266)
					(mid 61.853193 -100.653395)
					(end 61.799978 -100.921312)
				)
				(arc
					(start 61.799978 -108.300012)
					(mid 62.297903 -109.502109)
					(end 63.5 -110.000034)
				)
				(arc
					(start 69.15404 -110.000034)
					(mid 69.393378 -109.957739)
					(end 69.603874 -109.836204)
				)
				(arc
					(start 72.93864 -107.03814)
					(mid 73.63046 -106.638708)
					(end 74.417174 -106.499914)
				)
				(arc
					(start 135.582914 -106.499914)
					(mid 136.369507 -106.638696)
					(end 137.061194 -107.03814)
				)
				(arc
					(start 140.39596 -109.836204)
					(mid 140.606563 -109.957785)
					(end 140.846048 -110.000034)
				)
				(arc
					(start 146.500088 -110.000034)
					(mid 147.702185 -109.502109)
					(end 148.20011 -108.300012)
				)
				(arc
					(start 148.20011 -100.921312)
					(mid 148.146722 -100.653381)
					(end 147.994878 -100.426266)
				)
				(arc
					(start 146.873722 -99.30511)
					(mid 146.37514 -98.558929)
					(end 146.200114 -97.678748)
				)
				(arc
					(start 146.200114 -96.0501)
					(mid 147.898831 -91.948907)
					(end 151.99995 -90.25001)
				)
				(arc
					(start 157.750002 -90.25001)
					(mid 159.376326 -90.923656)
					(end 160.049972 -92.54998)
				)
				(arc
					(start 160.049972 -112.799876)
					(mid 158.93695 -115.486948)
					(end 156.249878 -116.59997)
				)
				(arc
					(start 53.749956 -116.59997)
					(mid 51.063138 -115.486843)
					(end 49.950116 -112.799876)
				)
				(arc
					(start 49.950116 -40.299894)
					(mid 51.063063 -37.613001)
					(end 53.749956 -36.500054)
				)
				(xy 104.70007 -36.500054)
			)
		)
	)
	(zone
		(layer "F.Cu")
		(hatch none 0.5)
		(connect_pads
			(clearance 0)
		)
		(min_thickness 0.25)
		(keepout
			(tracks not_allowed)
			(vias allowed)
			(pads allowed)
			(copperpour not_allowed)
			(footprints allowed)
		)
		(placement
			(enabled no)
			(sheetname "")
		)
		(fill
			(thermal_gap 0.5)
			(thermal_bridge_width 0.5)
			(island_removal_mode 0)
		)
		(polygon
			(pts
				(xy 443.349126 -114.020092) (xy 443.349126 -114.318288) (xy 443.193932 -114.473482)
				(arc
					(start 443.022228 -114.473482)
					(mid 442.498311 -114.403632)
					(end 443.022228 -114.333782)
				)
				(xy 443.13602 -114.333782) (xy 443.209426 -114.260376) (xy 443.209426 -114.020092)
				(arc
					(start 442.76518 -114.020092)
					(mid 442.381386 -114.403505)
					(end 442.764926 -114.787172)
				)
				(arc
					(start 444.034926 -114.787172)
					(mid 444.418466 -114.403632)
					(end 444.034926 -114.020092)
				)
				(xy 443.590426 -114.020092) (xy 443.590426 -114.260376) (xy 443.663832 -114.333782)
				(arc
					(start 443.777624 -114.333782)
					(mid 444.301541 -114.403632)
					(end 443.777624 -114.473482)
				)
				(xy 443.60592 -114.473482) (xy 443.450726 -114.318288) (xy 443.450726 -114.020092)
			)
		)
	)
	(zone
		(layer "F.Cu")
		(hatch none 0.5)
		(connect_pads
			(clearance 0)
		)
		(min_thickness 0.25)
		(keepout
			(tracks allowed)
			(vias allowed)
			(pads allowed)
			(copperpour allowed)
			(footprints not_allowed)
		)
		(placement
			(enabled no)
			(sheetname "")
		)
		(fill
			(thermal_gap 0.5)
			(thermal_bridge_width 0.5)
			(island_removal_mode 0)
		)
		(polygon
			(pts
				(arc
					(start 152.999948 -57.090056)
					(mid 150.459948 -54.550056)
					(end 152.999948 -52.010056)
				)
				(arc
					(start 152.999948 -52.010056)
					(mid 155.539948 -54.550056)
					(end 152.999948 -57.090056)
				)
			)
		)
	)
	(zone
		(net "P12V_NVDIMM_ABC")
		(layer "F.Cu")
		(hatch none 0.5)
		(connect_pads
			(clearance 0.5)
		)
		(min_thickness 0.25)
		(fill yes
			(thermal_gap 0.5)
			(thermal_bridge_width 0.5)
			(island_removal_mode 0)
		)
		(polygon
			(pts
				(arc
					(start 194.136772 -20.904708)
					(mid 194.109666 -21.016704)
					(end 194.20459 -21.082)
				)
				(xy 194.7164 -21.082) (xy 194.85102 -20.94738)
				(arc
					(start 194.85102 -20.023074)
					(mid 194.874957 -19.842001)
					(end 194.945 -19.673316)
				)
				(xy 194.945 -14.5542) (xy 194.8688 -14.478)
				(arc
					(start 192.442338 -14.478)
					(mid 191.653748 -14.68957)
					(end 191.185292 -14.0208)
				)
				(arc
					(start 191.185292 -13.3985)
					(mid 191.273288 -13.055766)
					(end 191.515492 -12.79779)
				)
				(xy 191.515492 -12.127992) (xy 191.516 -12.127992) (xy 191.516 -11.7348) (xy 191.58331 -11.66749)
				(arc
					(start 191.586358 -11.662664)
					(mid 191.82311 -11.50045)
					(end 192.104518 -11.557)
				)
				(xy 194.6656 -11.557) (xy 194.85102 -11.37158)
				(arc
					(start 194.85102 -10.421874)
					(mid 194.874957 -10.240801)
					(end 194.945 -10.072116)
				)
				(xy 194.945 -5.0546) (xy 194.7164 -4.826)
				(arc
					(start 192.438782 -4.826)
					(mid 191.651245 -5.032491)
					(end 191.185292 -4.364736)
				)
				(arc
					(start 191.185292 -3.7465)
					(mid 191.273288 -3.403766)
					(end 191.515492 -3.14579)
				)
				(xy 191.515492 -2.475992) (xy 191.516 -2.475992) (xy 191.516 -2.032) (xy 191.643 -1.905) (xy 191.68872 -1.905)
				(arc
					(start 191.701166 -1.897126)
					(mid 191.904002 -1.841067)
					(end 192.104518 -1.905)
				)
				(xy 194.7418 -1.905) (xy 194.85102 -1.79578)
				(arc
					(start 194.85102 -0.820674)
					(mid 194.874957 -0.639601)
					(end 194.945 -0.470916)
				)
				(xy 194.945 4.445) (xy 194.7672 4.6228) (xy 188.2394 4.6228) (xy 187.383674 3.767074) (xy 187.383674 -2.080768)
				(xy 187.218828 -2.245614) (xy 187.218828 -7.386828) (xy 187.486798 -7.654798) (xy 187.55741 -7.654798)
				(arc
					(start 187.599574 -7.612634)
					(mid 190.559664 -7.837795)
					(end 187.884562 -9.12495)
				)
				(arc
					(start 187.884562 -9.12495)
					(mid 187.772242 -9.096019)
					(end 187.706 -9.191244)
				)
				(arc
					(start 187.706 -11.85418)
					(mid 187.772234 -11.949426)
					(end 187.884562 -11.920474)
				)
				(arc
					(start 187.884562 -11.920474)
					(mid 190.570376 -12.696464)
					(end 188.227462 -14.221714)
				)
				(xy 187.883292 -14.221714) (xy 187.307728 -14.797278) (xy 187.307728 -18.783808) (xy 186.585352 -19.506184)
				(xy 184.887616 -19.506184) (xy 184.02554 -20.36826) (xy 184.02554 -24.035258) (xy 184.121298 -24.131016)
				(xy 185.371232 -24.131016) (xy 185.878216 -24.638) (xy 189.3824 -24.638) (xy 191.2112 -26.4668)
				(xy 194.2084 -26.4668) (xy 194.364102 -26.311098)
				(arc
					(start 194.350894 -26.279602)
					(mid 194.329899 -26.060919)
					(end 194.437 -25.869138)
				)
				(xy 194.437 -24.13) (xy 194.31 -24.003) (xy 193.91884 -24.003)
				(arc
					(start 193.915284 -24.04999)
					(mid 193.497036 -24.47136)
					(end 193.014854 -24.12492)
				)
				(arc
					(start 193.014854 -24.12492)
					(mid 192.9918 -24.093648)
					(end 192.953386 -24.087836)
				)
				(arc
					(start 192.953386 -24.087836)
					(mid 192.870281 -24.102704)
					(end 192.786 -24.107648)
				)
				(arc
					(start 191.2874 -24.107648)
					(mid 190.579651 -23.468703)
					(end 191.143128 -22.699472)
				)
				(xy 191.3382 -22.5044) (xy 191.3382 -22.1488) (xy 191.4398 -22.0472) (xy 191.4398 -21.2852) (xy 191.643 -21.082)
				(xy 191.75984 -21.082)
				(arc
					(start 191.77635 -21.079206)
					(mid 191.897 -21.058912)
					(end 192.01765 -21.079206)
				)
				(xy 192.025778 -21.082)
				(arc
					(start 193.57721 -21.082)
					(mid 193.672106 -21.016694)
					(end 193.645028 -20.904708)
				)
				(arc
					(start 193.645028 -20.904708)
					(mid 193.8909 -20.261121)
					(end 194.136772 -20.904708)
				)
			)
		)
		(polygon
			(pts
				(xy 184.974484 -21.62302) (xy 184.771284 -21.62302) (xy 184.771284 -21.82622) (xy 184.974484 -21.82622)
			)
		)
		(polygon
			(pts
				(xy 184.974484 -20.86102) (xy 184.771284 -20.86102) (xy 184.771284 -21.06422) (xy 184.974484 -21.06422)
			)
		)
	)
	(zone
		(net "P1V05_PCH_STBY")
		(layer "F.Cu")
		(hatch none 0.5)
		(connect_pads
			(clearance 0.5)
		)
		(min_thickness 0.25)
		(fill yes
			(thermal_gap 0.5)
			(thermal_bridge_width 0.5)
			(island_removal_mode 0)
		)
		(polygon
			(pts
				(xy 391.795 -113.919) (xy 387.096 -113.919) (xy 387.096 -113.792) (xy 387.35 -113.538) (xy 387.35 -113.284)
				(xy 387.096 -113.03) (xy 386.842 -113.03) (xy 386.715 -113.157) (xy 386.461 -113.157) (xy 386.461 -112.903)
				(xy 386.715 -112.649) (xy 391.795 -112.649)
			)
		)
	)
	(zone
		(layer "F.Cu")
		(hatch none 0.5)
		(connect_pads
			(clearance 0)
		)
		(min_thickness 0.25)
		(keepout
			(tracks allowed)
			(vias allowed)
			(pads allowed)
			(copperpour allowed)
			(footprints not_allowed)
		)
		(placement
			(enabled no)
			(sheetname "")
		)
		(fill
			(thermal_gap 0.5)
			(thermal_bridge_width 0.5)
			(island_removal_mode 0)
		)
		(polygon
			(pts
				(arc
					(start 4.629912 -47.909988)
					(mid 2.029968 -45.310044)
					(end 4.629912 -42.7101)
				)
				(arc
					(start 4.629912 -42.7101)
					(mid 7.229856 -45.310044)
					(end 4.629912 -47.909988)
				)
			)
		)
	)
	(zone
		(net "GND")
		(layer "F.Cu")
		(hatch none 0.5)
		(connect_pads
			(clearance 0.5)
		)
		(min_thickness 0.25)
		(fill yes
			(thermal_gap 0.5)
			(thermal_bridge_width 0.5)
			(island_removal_mode 0)
		)
		(polygon
			(pts
				(xy 113.383568 -72.6948) (xy 113.078768 -72.9996) (xy 113.078768 -74.7014) (xy 112.885982 -74.894186)
				(xy 98.435414 -74.894186) (xy 98.432112 -74.890884) (xy 92.939108 -74.890884) (xy 92.747592 -75.0824)
				(xy 92.747592 -76.529438) (xy 92.911168 -76.693014) (xy 98.3361 -76.693014) (xy 103.622348 -76.686664)
				(xy 107.258104 -76.686664) (xy 107.465368 -76.4794) (xy 114.907568 -76.4794) (xy 114.932968 -76.454)
				(xy 115.237768 -76.454) (xy 115.847368 -77.0636) (xy 115.847368 -80.1878) (xy 116.101368 -80.4418)
				(xy 117.422168 -80.4418) (xy 117.879368 -79.9846) (xy 117.879368 -79.248) (xy 117.803168 -79.1718)
				(xy 116.8654 -79.1718) (xy 116.5733 -78.8797) (xy 116.5733 -78.7273) (xy 116.5479 -78.7019) (xy 116.5479 -75.3237)
				(xy 116.4844 -75.2602) (xy 116.0018 -75.2602) (xy 115.6716 -74.93) (xy 115.6716 -74.3966) (xy 115.669568 -74.394822)
				(xy 115.669568 -72.8218) (xy 115.542568 -72.6948)
			)
		)
		(polygon
			(pts
				(xy 116.852192 -79.423514) (xy 116.648992 -79.423514) (xy 116.648992 -79.626714) (xy 116.852192 -79.626714)
			)
		)
		(polygon
			(pts
				(xy 107.38104 -75.693016) (xy 107.17784 -75.693016) (xy 107.17784 -75.896216) (xy 107.38104 -75.896216)
			)
		)
		(polygon
			(pts
				(xy 106.61904 -75.693016) (xy 106.41584 -75.693016) (xy 106.41584 -75.896216) (xy 106.61904 -75.896216)
			)
		)
		(polygon
			(pts
				(xy 106.13644 -75.693016) (xy 105.93324 -75.693016) (xy 105.93324 -75.896216) (xy 106.13644 -75.896216)
			)
		)
		(polygon
			(pts
				(xy 105.37444 -75.693016) (xy 105.17124 -75.693016) (xy 105.17124 -75.896216) (xy 105.37444 -75.896216)
			)
		)
		(polygon
			(pts
				(xy 104.89184 -75.693016) (xy 104.68864 -75.693016) (xy 104.68864 -75.896216) (xy 104.89184 -75.896216)
			)
		)
		(polygon
			(pts
				(xy 104.12984 -75.693016) (xy 103.92664 -75.693016) (xy 103.92664 -75.896216) (xy 104.12984 -75.896216)
			)
		)
		(polygon
			(pts
				(xy 103.64724 -75.693016) (xy 103.44404 -75.693016) (xy 103.44404 -75.896216) (xy 103.64724 -75.896216)
			)
		)
		(polygon
			(pts
				(xy 102.88524 -75.693016) (xy 102.68204 -75.693016) (xy 102.68204 -75.896216) (xy 102.88524 -75.896216)
			)
		)
		(polygon
			(pts
				(xy 102.40264 -75.693016) (xy 102.19944 -75.693016) (xy 102.19944 -75.896216) (xy 102.40264 -75.896216)
			)
		)
		(polygon
			(pts
				(xy 101.64064 -75.693016) (xy 101.43744 -75.693016) (xy 101.43744 -75.896216) (xy 101.64064 -75.896216)
			)
		)
		(polygon
			(pts
				(xy 101.15804 -75.693016) (xy 100.95484 -75.693016) (xy 100.95484 -75.896216) (xy 101.15804 -75.896216)
			)
		)
		(polygon
			(pts
				(xy 100.39604 -75.693016) (xy 100.19284 -75.693016) (xy 100.19284 -75.896216) (xy 100.39604 -75.896216)
			)
		)
		(polygon
			(pts
				(xy 99.91344 -75.693016) (xy 99.71024 -75.693016) (xy 99.71024 -75.896216) (xy 99.91344 -75.896216)
			)
		)
		(polygon
			(pts
				(xy 99.15144 -75.693016) (xy 98.94824 -75.693016) (xy 98.94824 -75.896216) (xy 99.15144 -75.896216)
			)
		)
		(polygon
			(pts
				(xy 98.66884 -75.693016) (xy 98.46564 -75.693016) (xy 98.46564 -75.896216) (xy 98.66884 -75.896216)
			)
		)
		(polygon
			(pts
				(xy 97.90684 -75.693016) (xy 97.70364 -75.693016) (xy 97.70364 -75.896216) (xy 97.90684 -75.896216)
			)
		)
		(polygon
			(pts
				(xy 97.42424 -75.693016) (xy 97.22104 -75.693016) (xy 97.22104 -75.896216) (xy 97.42424 -75.896216)
			)
		)
		(polygon
			(pts
				(xy 96.66224 -75.693016) (xy 96.45904 -75.693016) (xy 96.45904 -75.896216) (xy 96.66224 -75.896216)
			)
		)
		(polygon
			(pts
				(xy 96.17964 -75.693016) (xy 95.97644 -75.693016) (xy 95.97644 -75.896216) (xy 96.17964 -75.896216)
			)
		)
		(polygon
			(pts
				(xy 95.41764 -75.693016) (xy 95.21444 -75.693016) (xy 95.21444 -75.896216) (xy 95.41764 -75.896216)
			)
		)
		(polygon
			(pts
				(xy 94.93504 -75.693016) (xy 94.73184 -75.693016) (xy 94.73184 -75.896216) (xy 94.93504 -75.896216)
			)
		)
		(polygon
			(pts
				(xy 94.17304 -75.693016) (xy 93.96984 -75.693016) (xy 93.96984 -75.896216) (xy 94.17304 -75.896216)
			)
		)
		(polygon
			(pts
				(xy 93.69044 -75.693016) (xy 93.48724 -75.693016) (xy 93.48724 -75.896216) (xy 93.69044 -75.896216)
			)
		)
		(polygon
			(pts
				(xy 111.391192 -75.486514) (xy 111.187992 -75.486514) (xy 111.187992 -75.689714) (xy 111.391192 -75.689714)
			)
		)
		(polygon
			(pts
				(xy 110.629192 -75.486514) (xy 110.425992 -75.486514) (xy 110.425992 -75.689714) (xy 110.629192 -75.689714)
			)
		)
		(polygon
			(pts
				(xy 110.121192 -75.486514) (xy 109.917992 -75.486514) (xy 109.917992 -75.689714) (xy 110.121192 -75.689714)
			)
		)
		(polygon
			(pts
				(xy 109.359192 -75.486514) (xy 109.155992 -75.486514) (xy 109.155992 -75.689714) (xy 109.359192 -75.689714)
			)
		)
		(polygon
			(pts
				(xy 108.851192 -75.486514) (xy 108.647992 -75.486514) (xy 108.647992 -75.689714) (xy 108.851192 -75.689714)
			)
		)
		(polygon
			(pts
				(xy 108.089192 -75.486514) (xy 107.885992 -75.486514) (xy 107.885992 -75.689714) (xy 108.089192 -75.689714)
			)
		)
		(polygon
			(pts
				(xy 115.154202 -75.439016) (xy 114.951002 -75.439016) (xy 114.951002 -75.642216) (xy 115.154202 -75.642216)
			)
		)
		(polygon
			(pts
				(xy 114.392202 -75.439016) (xy 114.189002 -75.439016) (xy 114.189002 -75.642216) (xy 114.392202 -75.642216)
			)
		)
		(polygon
			(pts
				(xy 113.909602 -75.439016) (xy 113.706402 -75.439016) (xy 113.706402 -75.642216) (xy 113.909602 -75.642216)
			)
		)
		(polygon
			(pts
				(xy 113.147602 -75.439016) (xy 112.944402 -75.439016) (xy 112.944402 -75.642216) (xy 113.147602 -75.642216)
			)
		)
		(polygon
			(pts
				(xy 112.665002 -75.439016) (xy 112.461802 -75.439016) (xy 112.461802 -75.642216) (xy 112.665002 -75.642216)
			)
		)
		(polygon
			(pts
				(xy 111.903002 -75.439016) (xy 111.699802 -75.439016) (xy 111.699802 -75.642216) (xy 111.903002 -75.642216)
			)
		)
		(polygon
			(pts
				(xy 114.858292 -73.454514) (xy 114.655092 -73.454514) (xy 114.655092 -73.657714) (xy 114.858292 -73.657714)
			)
		)
		(polygon
			(pts
				(xy 114.350292 -73.454514) (xy 114.147092 -73.454514) (xy 114.147092 -73.657714) (xy 114.350292 -73.657714)
			)
		)
		(polygon
			(pts
				(xy 113.588292 -73.454514) (xy 113.385092 -73.454514) (xy 113.385092 -73.657714) (xy 113.588292 -73.657714)
			)
		)
	)
	(zone
		(net "P12V_PUMP")
		(layer "F.Cu")
		(hatch none 0.5)
		(connect_pads
			(clearance 0.5)
		)
		(min_thickness 0.25)
		(fill yes
			(thermal_gap 0.5)
			(thermal_bridge_width 0.5)
			(island_removal_mode 0)
		)
		(polygon
			(pts
				(xy 8.616696 -113.146078) (xy 10.512806 -113.146078) (xy 11.200384 -113.146078) (xy 13.770102 -115.715796)
				(xy 13.770102 -116.403374) (xy 13.770102 -119.17553) (xy 13.770102 -119.441468) (xy 13.495528 -119.716042)
				(xy 12.019788 -119.716042) (xy 11.785092 -119.481346) (xy 11.785092 -119.098568) (xy 11.785092 -116.579396)
				(xy 11.785092 -116.22786) (xy 10.44448 -114.887248) (xy 10.092944 -114.887248) (xy 8.932164 -114.887248)
				(xy 8.600186 -114.55527) (xy 8.603234 -114.552222) (xy 8.603234 -113.15954)
			)
		)
	)
	(zone
		(layer "F.Cu")
		(hatch none 0.5)
		(connect_pads
			(clearance 0)
		)
		(min_thickness 0.25)
		(keepout
			(tracks not_allowed)
			(vias allowed)
			(pads allowed)
			(copperpour not_allowed)
			(footprints allowed)
		)
		(placement
			(enabled no)
			(sheetname "")
		)
		(fill
			(thermal_gap 0.5)
			(thermal_bridge_width 0.5)
			(island_removal_mode 0)
		)
		(polygon
			(pts
				(xy 438.501536 -3.274314) (xy 438.501536 -3.004058) (xy 438.68467 -2.820924)
				(arc
					(start 438.82691 -2.820924)
					(mid 439.350827 -2.890774)
					(end 438.82691 -2.960624)
				)
				(xy 438.742582 -2.960624) (xy 438.641236 -3.06197) (xy 438.641236 -3.274314)
				(arc
					(start 439.083958 -3.274314)
					(mid 439.467752 -2.890901)
					(end 439.084212 -2.507234)
				)
				(arc
					(start 437.814212 -2.507234)
					(mid 437.430672 -2.890774)
					(end 437.814212 -3.274314)
				)
				(xy 438.260236 -3.274314) (xy 438.260236 -3.053842) (xy 438.167018 -2.960624)
				(arc
					(start 438.071514 -2.960624)
					(mid 437.547597 -2.890774)
					(end 438.071514 -2.820924)
				)
				(xy 438.22493 -2.820924) (xy 438.399936 -2.99593) (xy 438.399936 -3.274314)
			)
		)
	)
	(zone
		(net "GND")
		(layer "F.Cu")
		(hatch none 0.5)
		(connect_pads
			(clearance 0.5)
		)
		(min_thickness 0.25)
		(fill yes
			(thermal_gap 0.5)
			(thermal_bridge_width 0.5)
			(island_removal_mode 0)
		)
		(polygon
			(pts
				(xy 182.906924 -154.45232) (xy 182.906924 -155.01112) (xy 182.9816 -155.085796) (xy 182.9816 -156.47416)
				(xy 183.04256 -156.53512) (xy 184.023 -156.53512) (xy 184.176924 -156.381196) (xy 184.176924 -154.9527)
				(xy 184.176924 -153.188924) (xy 183.896 -152.908) (xy 183.134 -152.908) (xy 183.05399 -152.98801)
				(xy 183.05399 -154.305254)
			)
		)
	)
	(zone
		(layer "F.Cu")
		(hatch none 0.5)
		(connect_pads
			(clearance 0)
		)
		(min_thickness 0.25)
		(keepout
			(tracks allowed)
			(vias allowed)
			(pads allowed)
			(copperpour allowed)
			(footprints not_allowed)
		)
		(placement
			(enabled no)
			(sheetname "")
		)
		(fill
			(thermal_gap 0.5)
			(thermal_bridge_width 0.5)
			(island_removal_mode 0)
		)
		(polygon
			(pts
				(arc
					(start 435.300374 -116.196872)
					(mid 431.700432 -119.796814)
					(end 428.10049 -116.196872)
				)
				(arc
					(start 428.10049 -114.596926)
					(mid 431.700432 -110.996984)
					(end 435.300374 -114.596926)
				)
			)
		)
	)
	(zone
		(net "GND")
		(layer "F.Cu")
		(hatch none 0.5)
		(connect_pads
			(clearance 0.5)
		)
		(min_thickness 0.25)
		(fill yes
			(thermal_gap 0.5)
			(thermal_bridge_width 0.5)
			(island_removal_mode 0)
		)
		(polygon
			(pts
				(xy 98.295968 -25.277318) (xy 98.295968 -24.5364) (xy 97.954846 -24.195278) (xy 96.277938 -24.195278)
				(xy 96.271842 -24.201374) (xy 96.271842 -25.120346) (xy 96.533208 -25.381712) (xy 98.191574 -25.381712)
			)
		)
	)
	(zone
		(net "GND")
		(layer "F.Cu")
		(hatch none 0.5)
		(connect_pads
			(clearance 0.5)
		)
		(min_thickness 0.25)
		(fill yes
			(thermal_gap 0.5)
			(thermal_bridge_width 0.5)
			(island_removal_mode 0)
		)
		(polygon
			(pts
				(xy 48.7172 -91.1098) (xy 48.514 -91.313) (xy 48.514 -92.583) (xy 48.580548 -92.649548) (xy 50.428652 -92.649548)
				(xy 50.4698 -92.6084) (xy 50.4698 -91.313) (xy 50.2666 -91.1098)
			)
		)
		(polygon
			(pts
				(xy 49.911 -91.8083) (xy 49.7078 -91.8083) (xy 49.7078 -92.0115) (xy 49.911 -92.0115)
			)
		)
		(polygon
			(pts
				(xy 49.149 -91.8083) (xy 48.9458 -91.8083) (xy 48.9458 -92.0115) (xy 49.149 -92.0115)
			)
		)
	)
	(zone
		(layer "F.Cu")
		(hatch none 0.5)
		(connect_pads
			(clearance 0)
		)
		(min_thickness 0.25)
		(keepout
			(tracks not_allowed)
			(vias allowed)
			(pads allowed)
			(copperpour not_allowed)
			(footprints allowed)
		)
		(placement
			(enabled no)
			(sheetname "")
		)
		(fill
			(thermal_gap 0.5)
			(thermal_bridge_width 0.5)
			(island_removal_mode 0)
		)
		(polygon
			(pts
				(xy 368.72672 -1.349756) (xy 368.881914 -1.50495) (xy 368.881914 -1.803146) (xy 368.983514 -1.803146)
				(xy 368.983514 -1.50495) (xy 369.138708 -1.349756)
				(arc
					(start 369.310412 -1.349756)
					(mid 369.834329 -1.419606)
					(end 369.310412 -1.489456)
				)
				(xy 369.19662 -1.489456) (xy 369.123214 -1.562862) (xy 369.123214 -1.803146)
				(arc
					(start 369.56746 -1.803146)
					(mid 369.951254 -1.419733)
					(end 369.567714 -1.036066)
				)
				(arc
					(start 368.297714 -1.036066)
					(mid 367.914174 -1.419606)
					(end 368.297714 -1.803146)
				)
				(xy 368.742214 -1.803146) (xy 368.742214 -1.562862) (xy 368.668808 -1.489456)
				(arc
					(start 368.555016 -1.489456)
					(mid 368.031099 -1.419606)
					(end 368.555016 -1.349756)
				)
			)
		)
	)
	(zone
		(layer "F.Cu")
		(hatch none 0.5)
		(connect_pads
			(clearance 0)
		)
		(min_thickness 0.25)
		(keepout
			(tracks allowed)
			(vias allowed)
			(pads allowed)
			(copperpour allowed)
			(footprints allowed)
		)
		(placement
			(enabled no)
			(sheetname "")
		)
		(fill
			(thermal_gap 0.5)
			(thermal_bridge_width 0.5)
			(island_removal_mode 0)
		)
		(polygon
			(pts
				(xy 454.65746 -63.892176) (xy 457.63434 -63.892176) (xy 457.800202 -63.726314) (xy 457.800202 -61.022992)
				(xy 457.518262 -60.741052) (xy 454.60793 -60.741052) (xy 454.392284 -60.956698) (xy 454.392284 -63.627)
			)
		)
	)
	(zone
		(net "P5V_STBY")
		(layer "F.Cu")
		(hatch none 0.5)
		(connect_pads
			(clearance 0.5)
		)
		(min_thickness 0.25)
		(fill yes
			(thermal_gap 0.5)
			(thermal_bridge_width 0.5)
			(island_removal_mode 0)
		)
		(polygon
			(pts
				(xy 497.036852 -26.798778) (xy 497.036852 -26.412952) (xy 497.006118 -26.382218) (xy 496.36299 -26.382218)
				(xy 496.360196 -26.385012) (xy 495.797332 -26.385012) (xy 495.680746 -26.268426) (xy 495.680746 -25.905206)
				(xy 495.860832 -25.72512) (xy 496.97005 -25.72512) (xy 497.02847 -25.6667) (xy 497.02847 -25.44064)
				(xy 496.98021 -25.39238) (xy 495.13744 -25.39238) (xy 494.9698 -25.56002) (xy 494.9698 -25.6794)
				(xy 494.9698 -25.91562) (xy 494.78946 -26.09596) (xy 494.43132 -26.09596) (xy 494.11636 -26.41092)
				(xy 494.11636 -26.783284) (xy 494.22812 -26.895044) (xy 494.815368 -26.895044) (xy 496.940586 -26.895044)
			)
		)
	)
	(zone
		(net "PVCCIOMCP_CPU1")
		(layer "F.Cu")
		(hatch none 0.5)
		(connect_pads
			(clearance 0.5)
		)
		(min_thickness 0.25)
		(fill yes
			(thermal_gap 0.5)
			(thermal_bridge_width 0.5)
			(island_removal_mode 0)
		)
		(polygon
			(pts
				(xy 171.534582 -104.215946) (xy 171.143422 -103.824786) (xy 163.11753 -103.824786) (xy 163.054284 -103.888032)
				(xy 161.257742 -103.888032) (xy 157.818836 -103.888032) (xy 157.086808 -104.62006) (xy 157.086808 -107.860084)
				(xy 157.862524 -108.6358) (xy 163.710112 -108.6358) (xy 164.3634 -107.982512) (xy 170.167046 -107.982512)
				(xy 171.534582 -106.614468)
			)
		)
	)
	(zone
		(layer "F.Cu")
		(hatch none 0.5)
		(connect_pads
			(clearance 0)
		)
		(min_thickness 0.25)
		(keepout
			(tracks allowed)
			(vias allowed)
			(pads allowed)
			(copperpour allowed)
			(footprints not_allowed)
		)
		(placement
			(enabled no)
			(sheetname "")
		)
		(fill
			(thermal_gap 0.5)
			(thermal_bridge_width 0.5)
			(island_removal_mode 0)
		)
		(polygon
			(pts
				(arc
					(start 33.919922 -105.000044)
					(mid 35.470084 -106.550206)
					(end 33.919922 -108.100114)
				)
				(arc
					(start 33.919922 -108.100114)
					(mid 32.370014 -106.550206)
					(end 33.919922 -105.000044)
				)
			)
		)
	)
	(zone
		(net "VR_P5V_STBY_PHASE")
		(layer "F.Cu")
		(hatch none 0.5)
		(connect_pads
			(clearance 0.5)
		)
		(min_thickness 0.25)
		(fill yes
			(thermal_gap 0.5)
			(thermal_bridge_width 0.5)
			(island_removal_mode 0)
		)
		(polygon
			(pts
				(xy 394.777214 -67.51955) (xy 393.556236 -67.51955) (xy 393.446 -67.629786) (xy 393.446 -68.228464)
				(xy 393.463526 -68.24599) (xy 395.07287 -68.24599) (xy 395.67358 -68.8467) (xy 395.67358 -70.033642)
				(xy 395.72438 -70.084442) (xy 400.088608 -70.084442) (xy 400.1897 -69.98335) (xy 400.1897 -68.518024)
				(xy 399.777966 -68.10629) (xy 399.777966 -67.666108) (xy 399.631408 -67.51955)
			)
		)
		(polygon
			(pts
				(xy 396.67053 -69.17055) (xy 396.46733 -69.17055) (xy 396.46733 -69.37375) (xy 396.67053 -69.37375)
			)
		)
	)
	(zone
		(net "GND")
		(layer "F.Cu")
		(hatch none 0.5)
		(connect_pads
			(clearance 0.5)
		)
		(min_thickness 0.25)
		(fill yes
			(thermal_gap 0.5)
			(thermal_bridge_width 0.5)
			(island_removal_mode 0)
		)
		(polygon
			(pts
				(xy 166.60622 -84.2772) (xy 172.37202 -84.2772) (xy 172.70476 -83.94446) (xy 172.70476 -77.9907)
				(xy 172.40758 -77.69352) (xy 166.62146 -77.69352) (xy 166.2303 -78.08468) (xy 166.2303 -83.90128)
			)
		)
	)
	(zone
		(layer "F.Cu")
		(hatch none 0.5)
		(connect_pads
			(clearance 0)
		)
		(min_thickness 0.25)
		(keepout
			(tracks not_allowed)
			(vias allowed)
			(pads allowed)
			(copperpour not_allowed)
			(footprints allowed)
		)
		(placement
			(enabled no)
			(sheetname "")
		)
		(fill
			(thermal_gap 0.5)
			(thermal_bridge_width 0.5)
			(island_removal_mode 0)
		)
		(polygon
			(pts
				(arc
					(start 444.517526 -49.928272)
					(mid 445.041443 -49.998122)
					(end 444.517526 -50.067972)
				)
				(xy 444.403734 -50.067972) (xy 444.330328 -50.141378) (xy 444.330328 -50.381662)
				(arc
					(start 444.774574 -50.381662)
					(mid 445.158114 -49.998249)
					(end 444.774828 -49.614582)
				)
				(arc
					(start 443.504828 -49.614582)
					(mid 443.121288 -49.998122)
					(end 443.504828 -50.381662)
				)
				(xy 443.949328 -50.381662) (xy 443.949328 -50.141378) (xy 443.875922 -50.067972)
				(arc
					(start 443.76213 -50.067972)
					(mid 443.238213 -49.998122)
					(end 443.76213 -49.928272)
				)
				(xy 443.933834 -49.928272) (xy 444.089028 -50.083466) (xy 444.089028 -50.381662) (xy 444.190628 -50.381662)
				(xy 444.190628 -50.083466) (xy 444.345822 -49.928272)
			)
		)
	)
	(zone
		(layer "F.Cu")
		(hatch none 0.5)
		(connect_pads
			(clearance 0)
		)
		(min_thickness 0.25)
		(keepout
			(tracks not_allowed)
			(vias allowed)
			(pads allowed)
			(copperpour not_allowed)
			(footprints allowed)
		)
		(placement
			(enabled no)
			(sheetname "")
		)
		(fill
			(thermal_gap 0.5)
			(thermal_bridge_width 0.5)
			(island_removal_mode 0)
		)
		(polygon
			(pts
				(arc
					(start 384.429254 -34.208466)
					(mid 384.416867 -34.182137)
					(end 384.40741 -34.154618)
				)
				(xy 384.40741 -34.230564)
			)
		)
	)
	(zone
		(net "GND")
		(layer "F.Cu")
		(hatch none 0.5)
		(connect_pads
			(clearance 0.5)
		)
		(min_thickness 0.25)
		(fill yes
			(thermal_gap 0.5)
			(thermal_bridge_width 0.5)
			(island_removal_mode 0)
		)
		(polygon
			(pts
				(xy 366.2172 -158.620206) (xy 371.6782 -158.620206) (xy 372.036594 -158.620206) (xy 372.308374 -158.620206)
				(xy 372.458234 -158.470346) (xy 372.458234 -156.829252) (xy 372.694962 -156.592524) (xy 372.794022 -156.592524)
				(xy 372.866666 -156.51988) (xy 372.866666 -156.138372) (xy 372.797832 -156.069538) (xy 372.177818 -156.069538)
				(xy 371.771418 -156.475938) (xy 365.8616 -156.475938) (xy 365.857282 -156.480256) (xy 365.303562 -156.480256)
				(xy 365.12246 -156.661358) (xy 365.12246 -158.233872) (xy 365.508794 -158.620206)
			)
		)
	)
	(zone
		(layer "F.Cu")
		(hatch none 0.5)
		(connect_pads
			(clearance 0)
		)
		(min_thickness 0.25)
		(keepout
			(tracks allowed)
			(vias allowed)
			(pads allowed)
			(copperpour allowed)
			(footprints not_allowed)
		)
		(placement
			(enabled no)
			(sheetname "")
		)
		(fill
			(thermal_gap 0.5)
			(thermal_bridge_width 0.5)
			(island_removal_mode 0)
		)
		(polygon
			(pts
				(xy 163.524692 -138.566144) (xy 163.524692 -141.767306) (xy 22.52472 -141.767306) (xy 22.52472 -138.566144)
			)
		)
	)
	(zone
		(layer "F.Cu")
		(hatch none 0.5)
		(connect_pads
			(clearance 0)
		)
		(min_thickness 0.25)
		(keepout
			(tracks allowed)
			(vias allowed)
			(pads allowed)
			(copperpour allowed)
			(footprints allowed)
		)
		(placement
			(enabled no)
			(sheetname "")
		)
		(fill
			(thermal_gap 0.5)
			(thermal_bridge_width 0.5)
			(island_removal_mode 0)
		)
		(polygon
			(pts
				(xy 350.139 -4.572) (xy 352.298 -4.572) (xy 352.806 -5.08) (xy 352.806 -9.779) (xy 351.917 -10.668)
				(xy 347.853 -10.668) (xy 347.345 -10.16) (xy 347.345 -8.763) (xy 347.726 -8.382) (xy 348.110556 -8.382)
				(xy 348.18955 -8.303006) (xy 348.18955 -3.814826) (xy 348.278704 -3.725672) (xy 348.760288 -3.725672)
				(xy 349.028766 -3.99415) (xy 349.471234 -3.99415) (xy 350.049084 -4.572)
			)
		)
	)
	(zone
		(layer "F.Cu")
		(hatch none 0.5)
		(connect_pads
			(clearance 0)
		)
		(min_thickness 0.25)
		(keepout
			(tracks not_allowed)
			(vias allowed)
			(pads allowed)
			(copperpour not_allowed)
			(footprints allowed)
		)
		(placement
			(enabled no)
			(sheetname "")
		)
		(fill
			(thermal_gap 0.5)
			(thermal_bridge_width 0.5)
			(island_removal_mode 0)
		)
		(polygon
			(pts
				(arc
					(start 336.59064 -33.728406)
					(mid 335.489855 -33.864042)
					(end 336.59064 -33.999678)
				)
				(arc
					(start 336.59064 -33.999678)
					(mid 336.552183 -33.864042)
					(end 336.59064 -33.728406)
				)
			)
		)
	)
	(zone
		(layer "F.Cu")
		(hatch none 0.5)
		(connect_pads
			(clearance 0)
		)
		(min_thickness 0.25)
		(keepout
			(tracks allowed)
			(vias allowed)
			(pads allowed)
			(copperpour allowed)
			(footprints allowed)
		)
		(placement
			(enabled no)
			(sheetname "")
		)
		(fill
			(thermal_gap 0.5)
			(thermal_bridge_width 0.5)
			(island_removal_mode 0)
		)
		(polygon
			(pts
				(xy 131.442968 -49.108614) (xy 130.237992 -49.108614) (xy 128.628648 -49.108614) (xy 127.531368 -49.108614)
				(xy 127.523748 -49.11598) (xy 124.287788 -49.11598) (xy 122.857768 -50.546) (xy 122.527568 -50.546)
				(xy 119.479568 -47.498) (xy 117.955568 -47.498) (xy 117.930168 -47.4726) (xy 121.346468 -44.0563)
				(xy 122.044968 -44.0563) (xy 123.378468 -44.0563) (xy 123.518168 -44.196) (xy 128.369568 -44.196)
				(xy 129.639568 -42.926) (xy 129.639568 -42.9006) (xy 130.058668 -42.4815) (xy 130.058668 -42.4688)
				(xy 137.310368 -42.4688) (xy 137.272268 -42.5069) (xy 137.272268 -43.279314)
			)
		)
	)
	(zone
		(layer "F.Cu")
		(hatch none 0.5)
		(connect_pads
			(clearance 0)
		)
		(min_thickness 0.25)
		(keepout
			(tracks allowed)
			(vias allowed)
			(pads allowed)
			(copperpour allowed)
			(footprints allowed)
		)
		(placement
			(enabled no)
			(sheetname "")
		)
		(fill
			(thermal_gap 0.5)
			(thermal_bridge_width 0.5)
			(island_removal_mode 0)
		)
		(polygon
			(pts
				(xy 393.71397 -158.068772) (xy 393.71397 -156.007054) (xy 395.802104 -156.007054) (xy 395.802104 -158.068772)
			)
		)
	)
	(zone
		(layer "F.Cu")
		(hatch none 0.5)
		(connect_pads
			(clearance 0)
		)
		(min_thickness 0.25)
		(keepout
			(tracks allowed)
			(vias allowed)
			(pads allowed)
			(copperpour allowed)
			(footprints allowed)
		)
		(placement
			(enabled no)
			(sheetname "")
		)
		(fill
			(thermal_gap 0.5)
			(thermal_bridge_width 0.5)
			(island_removal_mode 0)
		)
		(polygon
			(pts
				(xy 178.181 -131.6228) (xy 181.1782 -131.6228) (xy 181.1782 -132.1054) (xy 179.3494 -132.1054) (xy 179.3494 -134.1374)
				(xy 178.181 -134.1374)
			)
		)
	)
	(zone
		(layer "F.Cu")
		(hatch none 0.5)
		(connect_pads
			(clearance 0)
		)
		(min_thickness 0.25)
		(keepout
			(tracks allowed)
			(vias allowed)
			(pads allowed)
			(copperpour allowed)
			(footprints allowed)
		)
		(placement
			(enabled no)
			(sheetname "")
		)
		(fill
			(thermal_gap 0.5)
			(thermal_bridge_width 0.5)
			(island_removal_mode 0)
		)
		(polygon
			(pts
				(xy 1.778 -140.6144) (xy 1.778 -136.2456) (xy 4.191 -136.2456) (xy 4.191 -140.6144)
			)
		)
	)
	(zone
		(layer "F.Cu")
		(hatch none 0.5)
		(connect_pads
			(clearance 0)
		)
		(min_thickness 0.25)
		(keepout
			(tracks not_allowed)
			(vias allowed)
			(pads allowed)
			(copperpour not_allowed)
			(footprints allowed)
		)
		(placement
			(enabled no)
			(sheetname "")
		)
		(fill
			(thermal_gap 0.5)
			(thermal_bridge_width 0.5)
			(island_removal_mode 0)
		)
		(polygon
			(pts
				(arc
					(start 472.600528 -60.59678)
					(mid 474.200474 -62.196726)
					(end 475.80042 -60.59678)
				)
				(arc
					(start 475.80042 -58.996834)
					(mid 474.200474 -57.396888)
					(end 472.600528 -58.996834)
				)
			)
		)
	)
	(zone
		(layer "F.Cu")
		(hatch none 0.5)
		(connect_pads
			(clearance 0)
		)
		(min_thickness 0.25)
		(keepout
			(tracks allowed)
			(vias allowed)
			(pads allowed)
			(copperpour allowed)
			(footprints allowed)
		)
		(placement
			(enabled no)
			(sheetname "")
		)
		(fill
			(thermal_gap 0.5)
			(thermal_bridge_width 0.5)
			(island_removal_mode 0)
		)
		(polygon
			(pts
				(xy 459.57744 -63.90894) (xy 462.55432 -63.90894) (xy 462.720182 -63.743078) (xy 462.720182 -61.039756)
				(xy 462.438242 -60.757816) (xy 459.52791 -60.757816) (xy 459.312264 -60.973462) (xy 459.312264 -63.643764)
			)
		)
	)
	(zone
		(net "P5V_STBY_DGB_FS")
		(layer "F.Cu")
		(hatch none 0.5)
		(connect_pads
			(clearance 0.5)
		)
		(min_thickness 0.25)
		(fill yes
			(thermal_gap 0.5)
			(thermal_bridge_width 0.5)
			(island_removal_mode 0)
		)
		(polygon
			(pts
				(xy 492.351568 -154.0764) (xy 493.621568 -152.8064) (xy 494.7412 -152.8064) (xy 495.0206 -153.0858)
				(xy 495.0206 -155.8036) (xy 494.7412 -156.083) (xy 493.2172 -156.083) (xy 491.8202 -157.48) (xy 490.22 -157.48)
				(xy 490.097572 -157.357572) (xy 490.097572 -155.038044) (xy 490.146594 -154.989022) (xy 490.963712 -154.989022)
				(xy 491.438946 -154.989022)
			)
		)
	)
	(zone
		(net "GND")
		(layer "F.Cu")
		(hatch none 0.5)
		(connect_pads
			(clearance 0.5)
		)
		(min_thickness 0.25)
		(fill yes
			(thermal_gap 0.5)
			(thermal_bridge_width 0.5)
			(island_removal_mode 0)
		)
		(polygon
			(pts
				(xy 176.911 -141.5415) (xy 176.911 -141.1732) (xy 176.911 -140.9192) (xy 176.276 -140.2842) (xy 176.276 -140.2715)
				(xy 176.276 -139.3825) (xy 176.403 -139.2555) (xy 179.959 -139.2555) (xy 180.086 -139.1285) (xy 180.086 -137.0965)
				(xy 180.213 -136.9695) (xy 180.8988 -136.9695) (xy 181.2671 -136.6012) (xy 182.2196 -136.6012) (xy 182.4482 -136.8298)
				(xy 182.4482 -137.3505) (xy 182.4482 -137.4394) (xy 182.7022 -137.6934) (xy 184.2262 -137.6934)
				(xy 184.3659 -137.8331) (xy 184.3659 -139.5857) (xy 184.5056 -139.7254) (xy 184.7088 -139.9286)
				(xy 184.7088 -141.6304) (xy 184.5437 -141.7955) (xy 184.277 -141.7955) (xy 177.165 -141.7955)
			)
		)
	)
	(zone
		(layer "F.Cu")
		(hatch none 0.5)
		(connect_pads
			(clearance 0)
		)
		(min_thickness 0.25)
		(keepout
			(tracks not_allowed)
			(vias allowed)
			(pads allowed)
			(copperpour not_allowed)
			(footprints allowed)
		)
		(placement
			(enabled no)
			(sheetname "")
		)
		(fill
			(thermal_gap 0.5)
			(thermal_bridge_width 0.5)
			(island_removal_mode 0)
		)
		(polygon
			(pts
				(xy 377.423172 -128.651)
				(arc
					(start 377.423172 -128.771396)
					(mid 377.366022 -129.298797)
					(end 377.308872 -128.771396)
				)
				(arc
					(start 377.308872 -128.655318)
					(mid 376.986108 -129.060656)
					(end 377.366022 -129.413)
				)
				(arc
					(start 378.026422 -129.413)
					(mid 378.359078 -129.217744)
					(end 378.35078 -128.832102)
				)
				(xy 378.35078 -128.966722)
				(arc
					(start 378.348494 -128.969008)
					(mid 378.328812 -129.020191)
					(end 378.291598 -129.060448)
				)
				(arc
					(start 378.291598 -129.060448)
					(mid 377.770001 -129.10532)
					(end 378.23648 -128.867662)
				)
				(arc
					(start 378.23648 -128.714246)
					(mid 378.174369 -128.680951)
					(end 378.107194 -128.659636)
				)
				(xy 377.6472 -128.659636)
				(arc
					(start 377.645168 -128.657604)
					(mid 377.630932 -128.654897)
					(end 377.616974 -128.651)
				)
			)
		)
	)
	(zone
		(net "AGND_HSC")
		(layer "F.Cu")
		(hatch none 0.5)
		(connect_pads
			(clearance 0.5)
		)
		(min_thickness 0.25)
		(fill yes
			(thermal_gap 0.5)
			(thermal_bridge_width 0.5)
			(island_removal_mode 0)
		)
		(polygon
			(pts
				(xy 11.938 -73.438004) (xy 11.938 -74.295) (xy 12.192 -74.549) (xy 13.843 -74.549) (xy 14.2113 -74.9173)
				(xy 14.220952 -74.926952) (xy 14.61262 -74.926952) (xy 14.65707 -74.971402) (xy 16.00581 -74.971402)
				(xy 16.12519 -75.090782) (xy 16.36649 -75.090782) (xy 16.400526 -75.124818) (xy 16.515334 -75.239626)
				(xy 16.515334 -77.302106) (xy 16.557244 -77.344016) (xy 19.680174 -77.344016) (xy 19.81581 -77.20838)
				(xy 19.81581 -74.22134) (xy 19.654012 -74.059542) (xy 16.578072 -74.059542) (xy 16.49984 -74.137774)
				(xy 16.49984 -74.665332) (xy 16.362172 -74.803) (xy 16.0274 -74.803) (xy 15.0876 -74.803) (xy 14.5034 -74.2188)
				(xy 14.071092 -73.786492) (xy 14.071092 -73.319894) (xy 14.060932 -73.309734) (xy 14.030706 -73.279508)
				(xy 12.801092 -73.279508) (xy 12.096496 -73.279508)
			)
		)
	)
	(zone
		(net "PVCCMCP_CPU1")
		(layer "F.Cu")
		(hatch none 0.5)
		(connect_pads
			(clearance 0.5)
		)
		(min_thickness 0.25)
		(fill yes
			(thermal_gap 0.5)
			(thermal_bridge_width 0.5)
			(island_removal_mode 0)
		)
		(polygon
			(pts
				(xy 156.5402 -40.9448) (xy 149.6568 -47.8282) (xy 149.6568 -57.0992) (xy 151.074374 -58.516774)
				(xy 158.195772 -58.516774) (xy 158.71952 -57.993026) (xy 158.71952 -54.065932) (xy 162.760152 -50.0253)
				(xy 168.4147 -50.0253) (xy 168.656 -49.784) (xy 168.656 -46.482) (xy 168.91 -46.228) (xy 176.53 -46.228)
				(xy 176.657 -46.228) (xy 176.911 -46.482) (xy 176.911 -46.595538) (xy 176.911 -49.898554) (xy 177.117248 -50.104802)
				(xy 177.616612 -50.104802) (xy 186.61253 -50.104802) (xy 188.552074 -48.165258) (xy 194.999864 -48.165258)
				(xy 195.248784 -47.916338) (xy 195.248784 -45.087794) (xy 194.984624 -44.823634) (xy 191.11976 -44.823634)
				(xy 191.112394 -44.831) (xy 186.948826 -44.831) (xy 186.6392 -44.521374) (xy 186.6392 -42.312082)
				(xy 186.495182 -42.168064) (xy 186.495182 -41.613074) (xy 186.6392 -41.469056) (xy 186.6392 -41.148)
				(xy 186.436 -40.9448)
			)
		)
	)
	(zone
		(layer "F.Cu")
		(hatch none 0.5)
		(connect_pads
			(clearance 0)
		)
		(min_thickness 0.25)
		(keepout
			(tracks not_allowed)
			(vias allowed)
			(pads allowed)
			(copperpour not_allowed)
			(footprints allowed)
		)
		(placement
			(enabled no)
			(sheetname "")
		)
		(fill
			(thermal_gap 0.5)
			(thermal_bridge_width 0.5)
			(island_removal_mode 0)
		)
		(polygon
			(pts
				(xy 369.751864 -7.193026) (xy 370.01831 -7.193026) (xy 370.01831 -8.386826) (xy 369.751864 -8.386826)
			)
		)
	)
	(zone
		(net "GND")
		(layer "F.Cu")
		(hatch none 0.5)
		(connect_pads
			(clearance 0.5)
		)
		(min_thickness 0.25)
		(fill yes
			(thermal_gap 0.5)
			(thermal_bridge_width 0.5)
			(island_removal_mode 0)
		)
		(polygon
			(pts
				(xy 91.369642 -134.177024) (xy 92.6084 -134.177024) (xy 92.6592 -134.227824) (xy 92.6592 -134.7216)
				(xy 92.558616 -134.822184) (xy 92.32265 -134.822184) (xy 91.229434 -135.9154) (xy 78.9178 -135.9154)
				(xy 78.555596 -136.277604) (xy 78.555596 -136.340596) (xy 78.428596 -136.467596) (xy 78.428596 -137.801604)
				(xy 78.3336 -137.8966) (xy 77.978 -137.8966) (xy 77.8256 -137.7442) (xy 77.8256 -135.001) (xy 77.8764 -134.9502)
				(xy 78.014576 -134.812024) (xy 79.093568 -134.812024) (xy 79.322168 -134.812024) (xy 90.650568 -134.812024)
				(xy 90.688668 -134.812024) (xy 90.690192 -134.8105) (xy 90.740738 -134.759954) (xy 90.898218 -134.759954)
				(xy 91.036648 -134.759954) (xy 91.308682 -134.48792) (xy 91.308682 -134.237984)
			)
		)
	)
	(zone
		(layer "F.Cu")
		(hatch none 0.5)
		(connect_pads
			(clearance 0)
		)
		(min_thickness 0.25)
		(keepout
			(tracks allowed)
			(vias allowed)
			(pads allowed)
			(copperpour allowed)
			(footprints allowed)
		)
		(placement
			(enabled no)
			(sheetname "")
		)
		(fill
			(thermal_gap 0.5)
			(thermal_bridge_width 0.5)
			(island_removal_mode 0)
		)
		(polygon
			(pts
				(xy 29.083 -91.5924) (xy 29.083 -87.757) (xy 31.242 -87.757) (xy 31.242 -91.5924)
			)
		)
	)
	(zone
		(net "PVCCIO_CPU1")
		(layer "F.Cu")
		(hatch none 0.5)
		(connect_pads
			(clearance 0.5)
		)
		(min_thickness 0.25)
		(fill yes
			(thermal_gap 0.5)
			(thermal_bridge_width 0.5)
			(island_removal_mode 0)
		)
		(polygon
			(pts
				(xy 112.951768 -76.912216) (xy 112.951768 -80.096614) (xy 114.924078 -80.096614) (xy 115.607592 -79.4131)
				(xy 115.607592 -77.420216) (xy 115.099592 -76.912216)
			)
		)
		(polygon
			(pts
				(xy 115.085368 -79.0575) (xy 114.882168 -79.0575) (xy 114.882168 -79.2607) (xy 115.085368 -79.2607)
			)
		)
		(polygon
			(pts
				(xy 114.323368 -79.0575) (xy 114.120168 -79.0575) (xy 114.120168 -79.2607) (xy 114.323368 -79.2607)
			)
		)
		(polygon
			(pts
				(xy 113.815368 -79.0575) (xy 113.612168 -79.0575) (xy 113.612168 -79.2607) (xy 113.815368 -79.2607)
			)
		)
		(polygon
			(pts
				(xy 115.154202 -77.725016) (xy 114.951002 -77.725016) (xy 114.951002 -77.928216) (xy 115.154202 -77.928216)
			)
		)
		(polygon
			(pts
				(xy 114.392202 -77.725016) (xy 114.189002 -77.725016) (xy 114.189002 -77.928216) (xy 114.392202 -77.928216)
			)
		)
		(polygon
			(pts
				(xy 113.909602 -77.725016) (xy 113.706402 -77.725016) (xy 113.706402 -77.928216) (xy 113.909602 -77.928216)
			)
		)
	)
	(zone
		(net "GND")
		(layer "F.Cu")
		(hatch none 0.5)
		(connect_pads
			(clearance 0.5)
		)
		(min_thickness 0.25)
		(fill yes
			(thermal_gap 0.5)
			(thermal_bridge_width 0.5)
			(island_removal_mode 0)
		)
		(polygon
			(pts
				(xy 2.496312 -133.9088) (xy 2.328672 -134.07644) (xy 2.328672 -134.7216) (xy 1.8034 -135.246872)
				(xy 1.8034 -136.381998) (xy 1.7526 -136.432798) (xy 0.822198 -136.432798) (xy 0.82042 -136.43102)
				(xy 0.408178 -136.43102) (xy 0.4064 -136.432798) (xy 0.247904 -136.432798) (xy 0.120904 -136.559798)
				(xy 0.120904 -138.210798) (xy 0.146304 -138.236198) (xy 1.746504 -138.236198) (xy 2.102104 -138.236198)
				(xy 2.293874 -138.236198) (xy 2.483104 -138.425428) (xy 2.483104 -138.617198) (xy 2.483104 -142.4432)
				(xy 2.490724 -142.45082) (xy 2.490724 -142.778988) (xy 2.267204 -143.002508) (xy 2.267204 -143.746728)
				(xy 1.8288 -144.185132) (xy 1.8288 -144.6022) (xy 1.8034 -144.6276) (xy 1.8034 -145.542) (xy 1.7526 -145.5928)
				(xy 0.4191 -145.5928) (xy 0.41275 -145.58645) (xy 0.4064 -145.5928) (xy 0.1778 -145.5928) (xy 0.127 -145.6436)
				(xy 0.127 -147.2946) (xy 0.1524 -147.32) (xy 2.286 -147.32) (xy 2.4892 -147.5232) (xy 2.4892 -149.993096)
				(xy 1.943862 -150.538434) (xy 1.943862 -150.852632) (xy 1.99263 -150.9014) (xy 8.883142 -150.9014)
				(xy 9.203944 -150.580598) (xy 9.203944 -150.078948) (xy 8.864092 -149.739096) (xy 4.840732 -149.739096)
				(xy 4.6482 -149.546564) (xy 4.6482 -145.191988) (xy 4.99491 -144.845278) (xy 6.445758 -144.845278)
				(xy 6.669786 -144.62125) (xy 6.669786 -143.687546) (xy 6.520434 -143.538194) (xy 5.745988 -143.538194)
				(xy 5.601716 -143.393922) (xy 5.601716 -142.404084) (xy 5.7912 -142.2146) (xy 8.9916 -142.2146)
				(xy 9.3472 -142.5702) (xy 9.3472 -143.7386) (xy 9.779 -144.1704) (xy 10.414 -144.1704) (xy 11.1252 -144.8816)
				(xy 11.1252 -150.03272) (xy 10.21588 -150.94204) (xy 10.21588 -153.47188) (xy 10.287 -153.543) (xy 11.303 -153.543)
				(xy 11.43 -153.67) (xy 11.43 -154.504898) (xy 11.491214 -154.566112) (xy 12.399518 -154.566112)
				(xy 12.408154 -154.557476) (xy 12.408154 -153.799032) (xy 12.319 -153.709878) (xy 12.319 -143.8402)
				(xy 12.5222 -143.637) (xy 12.5222 -135.1788) (xy 12.520422 -135.177022) (xy 12.520422 -134.98957)
				(xy 12.296394 -134.765542) (xy 8.82396 -134.765542) (xy 8.725154 -134.864348) (xy 8.624062 -134.864348)
				(xy 8.529574 -134.76986) (xy 5.771388 -134.76986) (xy 5.601462 -134.939786) (xy 5.58927 -134.951978)
				(xy 4.677918 -134.951978) (xy 4.67487 -134.94893) (xy 4.318 -134.59206) (xy 4.318 -134.493) (xy 4.318 -134.0866)
				(xy 4.1402 -133.9088)
			)
		)
		(polygon
			(pts
				(xy 5.461 -143.2052) (xy 5.2578 -143.2052) (xy 5.2578 -143.4084) (xy 5.461 -143.4084)
			)
		)
		(polygon
			(pts
				(xy 4.5974 -143.2052) (xy 4.3942 -143.2052) (xy 4.3942 -143.4084) (xy 4.5974 -143.4084)
			)
		)
		(polygon
			(pts
				(xy 5.461 -142.3416) (xy 5.2578 -142.3416) (xy 5.2578 -142.5448) (xy 5.461 -142.5448)
			)
		)
		(polygon
			(pts
				(xy 4.5974 -142.3416) (xy 4.3942 -142.3416) (xy 4.3942 -142.5448) (xy 4.5974 -142.5448)
			)
		)
		(polygon
			(pts
				(xy 4.2672 -134.7216) (xy 4.064 -134.7216) (xy 4.064 -134.9248) (xy 4.2672 -134.9248)
			)
		)
		(polygon
			(pts
				(xy 3.4036 -134.7216) (xy 3.2004 -134.7216) (xy 3.2004 -134.9248) (xy 3.4036 -134.9248)
			)
		)
	)
	(zone
		(net "PVDDQ_DEF")
		(layer "F.Cu")
		(hatch none 0.5)
		(connect_pads
			(clearance 0.5)
		)
		(min_thickness 0.25)
		(fill yes
			(thermal_gap 0.5)
			(thermal_bridge_width 0.5)
			(island_removal_mode 0)
		)
		(polygon
			(pts
				(xy 178.922172 -151.0538) (xy 178.922172 -151.805132) (xy 179.733956 -152.616916) (xy 180.851048 -152.616916)
				(xy 181.994048 -151.473916) (xy 181.994048 -150.955248) (xy 181.967886 -150.929086) (xy 179.046886 -150.929086)
			)
		)
	)
	(zone
		(layer "F.Cu")
		(hatch none 0.5)
		(connect_pads
			(clearance 0)
		)
		(min_thickness 0.25)
		(keepout
			(tracks allowed)
			(vias allowed)
			(pads allowed)
			(copperpour allowed)
			(footprints allowed)
		)
		(placement
			(enabled no)
			(sheetname "")
		)
		(fill
			(thermal_gap 0.5)
			(thermal_bridge_width 0.5)
			(island_removal_mode 0)
		)
		(polygon
			(pts
				(xy 325.0819 -113.538) (xy 325.0819 -111.252) (xy 327.0885 -111.252) (xy 327.0885 -113.538)
			)
		)
	)
	(zone
		(layer "F.Cu")
		(hatch none 0.5)
		(connect_pads
			(clearance 0)
		)
		(min_thickness 0.25)
		(keepout
			(tracks allowed)
			(vias allowed)
			(pads allowed)
			(copperpour allowed)
			(footprints not_allowed)
		)
		(placement
			(enabled no)
			(sheetname "")
		)
		(fill
			(thermal_gap 0.5)
			(thermal_bridge_width 0.5)
			(island_removal_mode 0)
		)
		(polygon
			(pts
				(xy 498.199918 -123.686824) (xy 492.19993 -123.686824) (xy 492.19993 -124.35205) (xy 492.468916 -124.35205)
				(xy 492.468916 -129.051304) (xy 492.19993 -129.051304) (xy 492.19993 -129.696718) (xy 498.199918 -129.696718)
			)
		)
	)
	(zone
		(net "GND")
		(layer "F.Cu")
		(hatch none 0.5)
		(connect_pads
			(clearance 0.5)
		)
		(min_thickness 0.25)
		(fill yes
			(thermal_gap 0.5)
			(thermal_bridge_width 0.5)
			(island_removal_mode 0)
		)
		(polygon
			(pts
				(xy 345.08694 -27.9654) (xy 345.2114 -27.84094) (xy 345.2114 -26.43886) (xy 345.08694 -26.3144)
				(xy 343.27846 -26.3144) (xy 343.11336 -26.4795) (xy 343.11336 -27.5082) (xy 342.98636 -27.6352)
				(xy 342.1634 -27.6352) (xy 342.1126 -27.686) (xy 342.1126 -27.9146) (xy 342.1634 -27.9654)
			)
		)
	)
	(zone
		(layer "F.Cu")
		(hatch none 0.5)
		(connect_pads
			(clearance 0)
		)
		(min_thickness 0.25)
		(keepout
			(tracks not_allowed)
			(vias allowed)
			(pads allowed)
			(copperpour not_allowed)
			(footprints allowed)
		)
		(placement
			(enabled no)
			(sheetname "")
		)
		(fill
			(thermal_gap 0.5)
			(thermal_bridge_width 0.5)
			(island_removal_mode 0)
		)
		(polygon
			(pts
				(arc
					(start 291.999924 -39.010082)
					(mid 294.539924 -41.550082)
					(end 291.999924 -44.090082)
				)
				(arc
					(start 291.999924 -44.090082)
					(mid 289.459924 -41.550082)
					(end 291.999924 -39.010082)
				)
			)
		)
	)
	(zone
		(layer "F.Cu")
		(hatch none 0.5)
		(connect_pads
			(clearance 0)
		)
		(min_thickness 0.25)
		(keepout
			(tracks allowed)
			(vias allowed)
			(pads allowed)
			(copperpour allowed)
			(footprints allowed)
		)
		(placement
			(enabled no)
			(sheetname "")
		)
		(fill
			(thermal_gap 0.5)
			(thermal_bridge_width 0.5)
			(island_removal_mode 0)
		)
		(polygon
			(pts
				(xy 291.7698 -29.464) (xy 291.7698 -27.432) (xy 293.9288 -27.432) (xy 293.9288 -29.464)
			)
		)
	)
	(zone
		(layer "F.Cu")
		(hatch none 0.5)
		(connect_pads
			(clearance 0)
		)
		(min_thickness 0.25)
		(keepout
			(tracks allowed)
			(vias allowed)
			(pads allowed)
			(copperpour allowed)
			(footprints allowed)
		)
		(placement
			(enabled no)
			(sheetname "")
		)
		(fill
			(thermal_gap 0.5)
			(thermal_bridge_width 0.5)
			(island_removal_mode 0)
		)
		(polygon
			(pts
				(xy 195.6308 -66.0146) (xy 195.6308 -63.5254) (xy 197.5612 -63.5254) (xy 197.5612 -66.0146)
			)
		)
	)
	(zone
		(layer "F.Cu")
		(hatch none 0.5)
		(connect_pads
			(clearance 0)
		)
		(min_thickness 0.25)
		(keepout
			(tracks allowed)
			(vias allowed)
			(pads allowed)
			(copperpour allowed)
			(footprints allowed)
		)
		(placement
			(enabled no)
			(sheetname "")
		)
		(fill
			(thermal_gap 0.5)
			(thermal_bridge_width 0.5)
			(island_removal_mode 0)
		)
		(polygon
			(pts
				(xy 342.547702 -25.911556) (xy 342.547702 -24.13381) (xy 345.251024 -24.13381) (xy 345.251024 -25.911556)
			)
		)
	)
	(zone
		(layer "F.Cu")
		(hatch none 0.5)
		(connect_pads
			(clearance 0)
		)
		(min_thickness 0.25)
		(keepout
			(tracks allowed)
			(vias allowed)
			(pads allowed)
			(copperpour allowed)
			(footprints allowed)
		)
		(placement
			(enabled no)
			(sheetname "")
		)
		(fill
			(thermal_gap 0.5)
			(thermal_bridge_width 0.5)
			(island_removal_mode 0)
		)
		(polygon
			(pts
				(xy 494.534952 -59.529218) (xy 494.534952 -54.602634) (xy 497.001292 -54.602634) (xy 497.001292 -59.541918)
				(xy 494.800636 -59.541918) (xy 494.514886 -59.827668) (xy 494.514886 -61.877448) (xy 494.304066 -62.088268)
				(xy 489.757466 -62.088268) (xy 489.491782 -61.822584) (xy 489.491782 -61.215778) (xy 489.45165 -61.175646)
				(xy 487.797602 -59.521598) (xy 487.797602 -54.448456) (xy 488.880404 -53.365654) (xy 494.39449 -53.365654)
				(xy 494.514886 -53.48605) (xy 494.514886 -54.478682) (xy 494.454688 -54.53888) (xy 489.692442 -54.53888)
				(xy 489.46181 -54.769512) (xy 489.46181 -59.348878) (xy 489.862876 -59.749944) (xy 494.314226 -59.749944)
			)
		)
	)
	(zone
		(layer "F.Cu")
		(hatch none 0.5)
		(connect_pads
			(clearance 0)
		)
		(min_thickness 0.25)
		(keepout
			(tracks not_allowed)
			(vias allowed)
			(pads allowed)
			(copperpour not_allowed)
			(footprints allowed)
		)
		(placement
			(enabled no)
			(sheetname "")
		)
		(fill
			(thermal_gap 0.5)
			(thermal_bridge_width 0.5)
			(island_removal_mode 0)
		)
		(polygon
			(pts
				(arc
					(start 1.928622 -153.15565)
					(mid 1.338214 -153.485632)
					(end 0.671576 -153.599896)
				)
				(arc
					(start 0 -153.599896)
					(mid -1.500124 -155.10002)
					(end 0 -156.59989)
				)
				(arc
					(start 0.671576 -156.59989)
					(mid 1.338247 -156.714274)
					(end 1.928622 -157.04439)
				)
				(arc
					(start 1.928622 -157.04439)
					(mid 5.999742 -155.10002)
					(end 1.928622 -153.15565)
				)
			)
		)
	)
	(zone
		(layer "F.Cu")
		(hatch none 0.5)
		(connect_pads
			(clearance 0)
		)
		(min_thickness 0.25)
		(keepout
			(tracks allowed)
			(vias allowed)
			(pads allowed)
			(copperpour allowed)
			(footprints not_allowed)
		)
		(placement
			(enabled no)
			(sheetname "")
		)
		(fill
			(thermal_gap 0.5)
			(thermal_bridge_width 0.5)
			(island_removal_mode 0)
		)
		(polygon
			(pts
				(arc
					(start 435.300374 -58.996834)
					(mid 431.700432 -55.396892)
					(end 428.10049 -58.996834)
				)
				(xy 428.10049 -60.236862) (xy 422.70045 -60.236862) (xy 422.70045 -51.676808) (xy 430.950624 -51.676808)
				(xy 432.95062 -51.676808) (xy 432.95062 -44.676822) (xy 474.950536 -44.676822) (xy 474.950536 -51.676808)
				(arc
					(start 474.950536 -55.475886)
					(mid 471.935581 -56.198633)
					(end 470.600532 -58.996834)
				)
				(arc
					(start 470.600532 -60.59678)
					(mid 474.200474 -64.196722)
					(end 477.800416 -60.59678)
				)
				(arc
					(start 477.800416 -58.996834)
					(mid 477.06223 -56.812816)
					(end 475.150434 -55.5244)
				)
				(xy 475.150434 -51.676808) (xy 488.100624 -51.676808) (xy 502.000012 -51.676808)
				(arc
					(start 502.000012 -61.68009)
					(mid 501.707119 -62.387195)
					(end 501.000014 -62.680088)
				)
				(arc
					(start 480.480116 -62.680088)
					(mid 479.773011 -62.972981)
					(end 479.480118 -63.680086)
				)
				(arc
					(start 479.480118 -66.879978)
					(mid 479.187225 -67.587083)
					(end 478.48012 -67.879976)
				)
				(arc
					(start 428.209964 -67.879976)
					(mid 427.502859 -68.172869)
					(end 427.209966 -68.879974)
				)
				(arc
					(start 427.209966 -108.879894)
					(mid 427.502859 -109.586999)
					(end 428.209964 -109.879892)
				)
				(arc
					(start 501.000014 -109.879892)
					(mid 501.707119 -110.172785)
					(end 502.000012 -110.87989)
				)
				(xy 502.000012 -115.20678) (xy 500.300498 -115.20678)
				(arc
					(start 500.300498 -114.596926)
					(mid 496.700556 -110.996984)
					(end 493.100614 -114.596926)
				)
				(arc
					(start 493.100614 -116.196872)
					(mid 496.700556 -119.796814)
					(end 500.300498 -116.196872)
				)
				(xy 500.300498 -115.406678) (xy 502.000012 -115.406678) (xy 502.000012 -120.986804) (xy 497.8019 -120.986804)
				(xy 497.8019 -123.686824) (xy 492.131858 -123.686824) (xy 492.01197 -123.686824) (xy 492.01197 -120.406922)
				(xy 487.312716 -120.406922) (xy 487.312716 -121.376694) (xy 484.400606 -121.376694) (xy 484.400606 -123.686824)
				(xy 422.70045 -123.686824) (xy 422.70045 -115.241832) (xy 428.10049 -115.241832)
				(arc
					(start 428.10049 -116.196872)
					(mid 431.700432 -119.796814)
					(end 435.300374 -116.196872)
				)
				(arc
					(start 435.300374 -114.596926)
					(mid 431.700432 -110.996984)
					(end 428.10049 -114.596926)
				)
				(xy 428.10049 -115.04168) (xy 422.70045 -115.04168) (xy 422.70045 -60.43676) (xy 428.10049 -60.43676)
				(arc
					(start 428.10049 -60.59678)
					(mid 431.700432 -64.196722)
					(end 435.300374 -60.59678)
				)
			)
		)
	)
	(zone
		(layer "F.Cu")
		(hatch none 0.5)
		(connect_pads
			(clearance 0)
		)
		(min_thickness 0.25)
		(keepout
			(tracks allowed)
			(vias allowed)
			(pads allowed)
			(copperpour allowed)
			(footprints not_allowed)
		)
		(placement
			(enabled no)
			(sheetname "")
		)
		(fill
			(thermal_gap 0.5)
			(thermal_bridge_width 0.5)
			(island_removal_mode 0)
		)
		(polygon
			(pts
				(arc
					(start 318.000126 -57.090056)
					(mid 315.460126 -54.550056)
					(end 318.000126 -52.010056)
				)
				(arc
					(start 318.000126 -52.010056)
					(mid 320.540126 -54.550056)
					(end 318.000126 -57.090056)
				)
			)
		)
	)
	(zone
		(layer "F.Cu")
		(hatch none 0.5)
		(connect_pads
			(clearance 0)
		)
		(min_thickness 0.25)
		(keepout
			(tracks not_allowed)
			(vias allowed)
			(pads allowed)
			(copperpour not_allowed)
			(footprints allowed)
		)
		(placement
			(enabled no)
			(sheetname "")
		)
		(fill
			(thermal_gap 0.5)
			(thermal_bridge_width 0.5)
			(island_removal_mode 0)
		)
		(polygon
			(pts
				(xy -5.999988 2.500122) (xy -5.999988 -2.500122)
				(arc
					(start -4.898898 -2.500122)
					(mid -5.499955 0)
					(end -4.898898 2.500122)
				)
			)
		)
	)
	(zone
		(net "PVDDQ_ABC")
		(layer "F.Cu")
		(hatch none 0.5)
		(connect_pads
			(clearance 0.5)
		)
		(min_thickness 0.25)
		(fill yes
			(thermal_gap 0.5)
			(thermal_bridge_width 0.5)
			(island_removal_mode 0)
		)
		(polygon
			(pts
				(xy 264.125456 -66.963544) (xy 264.0584 -67.0306) (xy 264.0584 -70.274688) (xy 265.289284 -70.274688)
				(xy 265.289284 -68.876672) (xy 265.294364 -68.871592) (xy 267.512546 -68.871592) (xy 267.531596 -68.852796)
				(xy 267.601192 -68.7832) (xy 272.950686 -68.7832) (xy 273.21129 -68.522596) (xy 273.21129 -67.728084)
				(xy 273.569938 -67.369436) (xy 273.569938 -67.07251) (xy 273.463512 -66.966084) (xy 266.815316 -66.966084)
				(xy 266.812522 -66.963544)
			)
		)
		(polygon
			(pts
				(xy 264.999724 -69.403214) (xy 264.796524 -69.403214) (xy 264.796524 -69.606414) (xy 264.999724 -69.606414)
			)
		)
		(polygon
			(pts
				(xy 264.999724 -68.920614) (xy 264.796524 -68.920614) (xy 264.796524 -69.123814) (xy 264.999724 -69.123814)
			)
		)
		(polygon
			(pts
				(xy 264.999724 -68.158614) (xy 264.796524 -68.158614) (xy 264.796524 -68.361814) (xy 264.999724 -68.361814)
			)
		)
		(polygon
			(pts
				(xy 267.628624 -67.866514) (xy 267.425424 -67.866514) (xy 267.425424 -68.069714) (xy 267.628624 -68.069714)
			)
		)
		(polygon
			(pts
				(xy 266.866624 -67.866514) (xy 266.663424 -67.866514) (xy 266.663424 -68.069714) (xy 266.866624 -68.069714)
			)
		)
		(polygon
			(pts
				(xy 266.384024 -67.866514) (xy 266.180824 -67.866514) (xy 266.180824 -68.069714) (xy 266.384024 -68.069714)
			)
		)
		(polygon
			(pts
				(xy 265.622024 -67.866514) (xy 265.418824 -67.866514) (xy 265.418824 -68.069714) (xy 265.622024 -68.069714)
			)
		)
		(polygon
			(pts
				(xy 272.617438 -67.819016) (xy 272.414238 -67.819016) (xy 272.414238 -68.022216) (xy 272.617438 -68.022216)
			)
		)
		(polygon
			(pts
				(xy 271.855438 -67.819016) (xy 271.652238 -67.819016) (xy 271.652238 -68.022216) (xy 271.855438 -68.022216)
			)
		)
		(polygon
			(pts
				(xy 271.372838 -67.819016) (xy 271.169638 -67.819016) (xy 271.169638 -68.022216) (xy 271.372838 -68.022216)
			)
		)
		(polygon
			(pts
				(xy 270.610838 -67.819016) (xy 270.407638 -67.819016) (xy 270.407638 -68.022216) (xy 270.610838 -68.022216)
			)
		)
		(polygon
			(pts
				(xy 270.128238 -67.819016) (xy 269.925038 -67.819016) (xy 269.925038 -68.022216) (xy 270.128238 -68.022216)
			)
		)
		(polygon
			(pts
				(xy 269.366238 -67.819016) (xy 269.163038 -67.819016) (xy 269.163038 -68.022216) (xy 269.366238 -68.022216)
			)
		)
		(polygon
			(pts
				(xy 268.883638 -67.819016) (xy 268.680438 -67.819016) (xy 268.680438 -68.022216) (xy 268.883638 -68.022216)
			)
		)
		(polygon
			(pts
				(xy 268.121638 -67.819016) (xy 267.918438 -67.819016) (xy 267.918438 -68.022216) (xy 268.121638 -68.022216)
			)
		)
	)
	(zone
		(net "PVDDQ_KLM")
		(layer "F.Cu")
		(hatch none 0.5)
		(connect_pads
			(clearance 0.5)
		)
		(min_thickness 0.25)
		(fill yes
			(thermal_gap 0.5)
			(thermal_bridge_width 0.5)
			(island_removal_mode 0)
		)
		(polygon
			(pts
				(xy 78.865984 -146.238722) (xy 90.964512 -146.238722) (xy 93.628972 -146.238722) (xy 93.840554 -146.02714)
				(xy 93.840554 -143.993108) (xy 93.612716 -143.76527) (xy 90.938096 -143.76527) (xy 78.745334 -143.76527)
				(xy 78.735174 -143.77543) (xy 78.735174 -146.107912)
			)
		)
	)
	(zone
		(layer "F.Cu")
		(hatch none 0.5)
		(connect_pads
			(clearance 0)
		)
		(min_thickness 0.25)
		(keepout
			(tracks allowed)
			(vias allowed)
			(pads allowed)
			(copperpour allowed)
			(footprints allowed)
		)
		(placement
			(enabled no)
			(sheetname "")
		)
		(fill
			(thermal_gap 0.5)
			(thermal_bridge_width 0.5)
			(island_removal_mode 0)
		)
		(polygon
			(pts
				(xy 247.396 -102.235) (xy 250.825 -102.235) (xy 250.825 -102.362) (xy 250.825 -104.775) (xy 250.825 -105.029)
				(xy 250.825 -105.537) (xy 245.999 -110.363) (xy 245.999 -110.998) (xy 245.364 -111.633) (xy 245.237 -111.633)
				(xy 240.919 -107.315) (xy 240.919 -106.045) (xy 243.078 -106.045) (xy 246.253 -102.87) (xy 246.38 -102.743)
				(xy 247.396 -102.743)
			)
		)
	)
	(zone
		(layer "F.Cu")
		(hatch none 0.5)
		(connect_pads
			(clearance 0)
		)
		(min_thickness 0.25)
		(keepout
			(tracks allowed)
			(vias allowed)
			(pads allowed)
			(copperpour allowed)
			(footprints allowed)
		)
		(placement
			(enabled no)
			(sheetname "")
		)
		(fill
			(thermal_gap 0.5)
			(thermal_bridge_width 0.5)
			(island_removal_mode 0)
		)
		(polygon
			(pts
				(xy 238.856012 -45.928788) (xy 237.871 -44.958) (xy 237.109 -44.958) (xy 237.109 -49.657) (xy 237.109 -49.784)
				(xy 240.284 -49.784) (xy 240.411 -49.911) (xy 245.4402 -49.911) (xy 245.4402 -48.0822) (xy 243.205 -45.847)
				(xy 243.078 -45.847) (xy 243.078 -45.928788) (xy 241.2238 -45.928788)
			)
		)
	)
	(zone
		(net "GND")
		(layer "F.Cu")
		(hatch none 0.5)
		(connect_pads
			(clearance 0.5)
		)
		(min_thickness 0.25)
		(fill yes
			(thermal_gap 0.5)
			(thermal_bridge_width 0.5)
			(island_removal_mode 0)
		)
		(polygon
			(pts
				(xy 272.020792 -80.5942) (xy 272.014696 -80.600296) (xy 261.562088 -80.600296) (xy 261.562088 -81.464912)
				(xy 261.790688 -81.693512) (xy 261.790688 -82.720688) (xy 261.9502 -82.8802) (xy 262.6106 -82.8802)
				(xy 262.89 -83.1596) (xy 262.89 -83.5406) (xy 263.1567 -83.8073) (xy 263.173464 -83.824064) (xy 267.61567 -83.824064)
				(xy 267.629894 -83.80984) (xy 267.6398 -83.80984) (xy 267.64234 -83.81238) (xy 267.7668 -83.93684)
				(xy 271.772126 -83.93684) (xy 272.619216 -83.93684) (xy 272.710656 -83.8454) (xy 274.1422 -83.8454)
				(xy 274.7264 -83.2612) (xy 279.273 -83.2612) (xy 280.0858 -82.4484) (xy 280.0858 -80.7212) (xy 279.9588 -80.5942)
			)
		)
		(polygon
			(pts
				(xy 272.72361 -82.947002) (xy 272.52041 -82.947002) (xy 272.52041 -83.150202) (xy 272.72361 -83.150202)
			)
		)
		(polygon
			(pts
				(xy 271.96161 -82.947002) (xy 271.75841 -82.947002) (xy 271.75841 -83.150202) (xy 271.96161 -83.150202)
			)
		)
		(polygon
			(pts
				(xy 271.47901 -82.947002) (xy 271.27581 -82.947002) (xy 271.27581 -83.150202) (xy 271.47901 -83.150202)
			)
		)
		(polygon
			(pts
				(xy 270.71701 -82.947002) (xy 270.51381 -82.947002) (xy 270.51381 -83.150202) (xy 270.71701 -83.150202)
			)
		)
		(polygon
			(pts
				(xy 270.23441 -82.947002) (xy 270.03121 -82.947002) (xy 270.03121 -83.150202) (xy 270.23441 -83.150202)
			)
		)
		(polygon
			(pts
				(xy 269.47241 -82.947002) (xy 269.26921 -82.947002) (xy 269.26921 -83.150202) (xy 269.47241 -83.150202)
			)
		)
		(polygon
			(pts
				(xy 268.98981 -82.947002) (xy 268.78661 -82.947002) (xy 268.78661 -83.150202) (xy 268.98981 -83.150202)
			)
		)
		(polygon
			(pts
				(xy 268.22781 -82.947002) (xy 268.02461 -82.947002) (xy 268.02461 -83.150202) (xy 268.22781 -83.150202)
			)
		)
		(polygon
			(pts
				(xy 274.91563 -82.853022) (xy 274.71243 -82.853022) (xy 274.71243 -83.056222) (xy 274.91563 -83.056222)
			)
		)
		(polygon
			(pts
				(xy 274.15363 -82.853022) (xy 273.95043 -82.853022) (xy 273.95043 -83.056222) (xy 274.15363 -83.056222)
			)
		)
		(polygon
			(pts
				(xy 267.7414 -82.8167) (xy 267.5382 -82.8167) (xy 267.5382 -83.0199) (xy 267.7414 -83.0199)
			)
		)
		(polygon
			(pts
				(xy 266.9794 -82.8167) (xy 266.7762 -82.8167) (xy 266.7762 -83.0199) (xy 266.9794 -83.0199)
			)
		)
		(polygon
			(pts
				(xy 266.4968 -82.8167) (xy 266.2936 -82.8167) (xy 266.2936 -83.0199) (xy 266.4968 -83.0199)
			)
		)
		(polygon
			(pts
				(xy 265.7348 -82.8167) (xy 265.5316 -82.8167) (xy 265.5316 -83.0199) (xy 265.7348 -83.0199)
			)
		)
		(polygon
			(pts
				(xy 265.2522 -82.8167) (xy 265.049 -82.8167) (xy 265.049 -83.0199) (xy 265.2522 -83.0199)
			)
		)
		(polygon
			(pts
				(xy 264.4902 -82.8167) (xy 264.287 -82.8167) (xy 264.287 -83.0199) (xy 264.4902 -83.0199)
			)
		)
		(polygon
			(pts
				(xy 264.0076 -82.7659) (xy 263.8044 -82.7659) (xy 263.8044 -82.9691) (xy 264.0076 -82.9691)
			)
		)
		(polygon
			(pts
				(xy 263.2456 -82.7659) (xy 263.0424 -82.7659) (xy 263.0424 -82.9691) (xy 263.2456 -82.9691)
			)
		)
		(polygon
			(pts
				(xy 262.615934 -81.89849) (xy 262.412734 -81.89849) (xy 262.412734 -82.10169) (xy 262.615934 -82.10169)
			)
		)
		(polygon
			(pts
				(xy 279.3238 -81.3435) (xy 279.1206 -81.3435) (xy 279.1206 -81.5467) (xy 279.3238 -81.5467)
			)
		)
		(polygon
			(pts
				(xy 278.8158 -81.3435) (xy 278.6126 -81.3435) (xy 278.6126 -81.5467) (xy 278.8158 -81.5467)
			)
		)
		(polygon
			(pts
				(xy 278.0538 -81.3435) (xy 277.8506 -81.3435) (xy 277.8506 -81.5467) (xy 278.0538 -81.5467)
			)
		)
		(polygon
			(pts
				(xy 277.5458 -81.3435) (xy 277.3426 -81.3435) (xy 277.3426 -81.5467) (xy 277.5458 -81.5467)
			)
		)
		(polygon
			(pts
				(xy 276.7838 -81.3435) (xy 276.5806 -81.3435) (xy 276.5806 -81.5467) (xy 276.7838 -81.5467)
			)
		)
		(polygon
			(pts
				(xy 276.2758 -81.3435) (xy 276.0726 -81.3435) (xy 276.0726 -81.5467) (xy 276.2758 -81.5467)
			)
		)
		(polygon
			(pts
				(xy 275.5138 -81.3435) (xy 275.3106 -81.3435) (xy 275.3106 -81.5467) (xy 275.5138 -81.5467)
			)
		)
		(polygon
			(pts
				(xy 275.0058 -81.3435) (xy 274.8026 -81.3435) (xy 274.8026 -81.5467) (xy 275.0058 -81.5467)
			)
		)
		(polygon
			(pts
				(xy 274.2438 -81.3435) (xy 274.0406 -81.3435) (xy 274.0406 -81.5467) (xy 274.2438 -81.5467)
			)
		)
		(polygon
			(pts
				(xy 273.7358 -81.3435) (xy 273.5326 -81.3435) (xy 273.5326 -81.5467) (xy 273.7358 -81.5467)
			)
		)
		(polygon
			(pts
				(xy 272.9738 -81.3435) (xy 272.7706 -81.3435) (xy 272.7706 -81.5467) (xy 272.9738 -81.5467)
			)
		)
		(polygon
			(pts
				(xy 272.4658 -81.3435) (xy 272.2626 -81.3435) (xy 272.2626 -81.5467) (xy 272.4658 -81.5467)
			)
		)
		(polygon
			(pts
				(xy 271.7038 -81.3435) (xy 271.5006 -81.3435) (xy 271.5006 -81.5467) (xy 271.7038 -81.5467)
			)
		)
		(polygon
			(pts
				(xy 271.1958 -81.3435) (xy 270.9926 -81.3435) (xy 270.9926 -81.5467) (xy 271.1958 -81.5467)
			)
		)
		(polygon
			(pts
				(xy 270.4338 -81.3435) (xy 270.2306 -81.3435) (xy 270.2306 -81.5467) (xy 270.4338 -81.5467)
			)
		)
		(polygon
			(pts
				(xy 269.9258 -81.3435) (xy 269.7226 -81.3435) (xy 269.7226 -81.5467) (xy 269.9258 -81.5467)
			)
		)
		(polygon
			(pts
				(xy 269.1638 -81.3435) (xy 268.9606 -81.3435) (xy 268.9606 -81.5467) (xy 269.1638 -81.5467)
			)
		)
		(polygon
			(pts
				(xy 268.6558 -81.3435) (xy 268.4526 -81.3435) (xy 268.4526 -81.5467) (xy 268.6558 -81.5467)
			)
		)
		(polygon
			(pts
				(xy 267.8938 -81.3435) (xy 267.6906 -81.3435) (xy 267.6906 -81.5467) (xy 267.8938 -81.5467)
			)
		)
		(polygon
			(pts
				(xy 267.4112 -81.3435) (xy 267.208 -81.3435) (xy 267.208 -81.5467) (xy 267.4112 -81.5467)
			)
		)
		(polygon
			(pts
				(xy 266.6492 -81.3435) (xy 266.446 -81.3435) (xy 266.446 -81.5467) (xy 266.6492 -81.5467)
			)
		)
		(polygon
			(pts
				(xy 266.1666 -81.3435) (xy 265.9634 -81.3435) (xy 265.9634 -81.5467) (xy 266.1666 -81.5467)
			)
		)
		(polygon
			(pts
				(xy 265.4046 -81.3435) (xy 265.2014 -81.3435) (xy 265.2014 -81.5467) (xy 265.4046 -81.5467)
			)
		)
		(polygon
			(pts
				(xy 264.922 -81.3435) (xy 264.7188 -81.3435) (xy 264.7188 -81.5467) (xy 264.922 -81.5467)
			)
		)
		(polygon
			(pts
				(xy 264.16 -81.3435) (xy 263.9568 -81.3435) (xy 263.9568 -81.5467) (xy 264.16 -81.5467)
			)
		)
		(polygon
			(pts
				(xy 263.6774 -81.3435) (xy 263.4742 -81.3435) (xy 263.4742 -81.5467) (xy 263.6774 -81.5467)
			)
		)
		(polygon
			(pts
				(xy 262.9154 -81.3435) (xy 262.7122 -81.3435) (xy 262.7122 -81.5467) (xy 262.9154 -81.5467)
			)
		)
		(polygon
			(pts
				(xy 262.4328 -81.3435) (xy 262.2296 -81.3435) (xy 262.2296 -81.5467) (xy 262.4328 -81.5467)
			)
		)
	)
	(zone
		(net "P12V_STBY")
		(layer "F.Cu")
		(hatch none 0.5)
		(connect_pads
			(clearance 0.5)
		)
		(min_thickness 0.25)
		(fill yes
			(thermal_gap 0.5)
			(thermal_bridge_width 0.5)
			(island_removal_mode 0)
		)
		(polygon
			(pts
				(xy 42.023538 -32.421068) (xy 44.52112 -34.91865) (xy 44.52112 -40.15994) (xy 44.276518 -40.404542)
				(xy 37.790628 -40.404542) (xy 32.4104 -35.024314) (xy 30.033214 -35.024314) (xy 29.68244 -34.67354)
				(xy 29.458412 -34.449512) (xy 29.458412 -33.132776) (xy 29.714952 -32.876236) (xy 29.9466 -32.876236)
				(xy 31.380176 -32.876236) (xy 31.429706 -32.826706) (xy 31.835344 -32.421068) (xy 32.983932 -32.421068)
			)
		)
	)
	(zone
		(layer "F.Cu")
		(hatch none 0.5)
		(connect_pads
			(clearance 0)
		)
		(min_thickness 0.25)
		(keepout
			(tracks allowed)
			(vias allowed)
			(pads allowed)
			(copperpour allowed)
			(footprints not_allowed)
		)
		(placement
			(enabled no)
			(sheetname "")
		)
		(fill
			(thermal_gap 0.5)
			(thermal_bridge_width 0.5)
			(island_removal_mode 0)
		)
		(polygon
			(pts
				(arc
					(start -0.500126 -54.909974)
					(mid -2.00025 -56.410098)
					(end -3.50012 -54.909974)
				)
				(arc
					(start -3.50012 -54.909974)
					(mid -2.00025 -53.410104)
					(end -0.500126 -54.909974)
				)
			)
		)
	)
	(zone
		(layer "F.Cu")
		(hatch none 0.5)
		(connect_pads
			(clearance 0)
		)
		(min_thickness 0.25)
		(keepout
			(tracks allowed)
			(vias allowed)
			(pads allowed)
			(copperpour allowed)
			(footprints allowed)
		)
		(placement
			(enabled no)
			(sheetname "")
		)
		(fill
			(thermal_gap 0.5)
			(thermal_bridge_width 0.5)
			(island_removal_mode 0)
		)
		(polygon
			(pts
				(xy 136.345168 -29.3116) (xy 136.345168 -27.2288) (xy 137.996168 -27.2288) (xy 137.996168 -29.3116)
			)
		)
	)
	(zone
		(net "GND")
		(layer "F.Cu")
		(hatch none 0.5)
		(connect_pads
			(clearance 0.5)
		)
		(min_thickness 0.25)
		(fill yes
			(thermal_gap 0.5)
			(thermal_bridge_width 0.5)
			(island_removal_mode 0)
		)
		(polygon
			(pts
				(xy 5.0292 -17.737328) (xy 5.0292 -20.4978) (xy 5.067808 -20.536408) (xy 5.067808 -20.92325) (xy 5.067808 -22.568408)
				(xy 5.4864 -22.987) (xy 8.001 -22.987) (xy 8.56234 -22.42566) (xy 8.56234 -20.93087) (xy 8.56234 -20.17014)
				(xy 8.4328 -20.0406) (xy 7.3914 -20.0406) (xy 7.2136 -19.8628) (xy 7.2136 -14.732) (xy 7.366 -14.5796)
				(xy 7.366 -14.105128) (xy 7.314946 -14.054074) (xy 6.99135 -13.730478) (xy 6.99135 -12.88034) (xy 7.1882 -12.68349)
				(xy 7.1882 -11.9634) (xy 7.1882 -7.39648) (xy 7.19074 -7.39394) (xy 7.19074 -6.91134) (xy 7.19074 -6.848602)
				(xy 7.161022 -6.818884) (xy 6.68782 -6.818884) (xy 6.686296 -6.818884) (xy 6.513068 -6.645656) (xy 6.513068 -6.644386)
				(xy 6.513068 -6.308344) (xy 6.553962 -6.26745) (xy 6.553962 -5.755894) (xy 6.553962 -5.260594) (xy 6.483096 -5.189728)
				(xy 5.662676 -5.189728) (xy 5.073904 -5.189728) (xy 4.855972 -5.40766) (xy 4.855972 -6.11886) (xy 4.84759 -6.127242)
				(xy 4.84632 -6.128512) (xy 4.3688 -6.606286) (xy 4.3688 -6.8326) (xy 4.3688 -7.6962) (xy 4.318 -7.747)
				(xy 3.302 -7.747) (xy 3.30073 -7.74573) (xy 2.94767 -7.74573) (xy 2.9464 -7.747) (xy 2.7432 -7.747)
				(xy 2.667 -7.8232) (xy 2.667 -9.398) (xy 2.7686 -9.4996) (xy 4.7752 -9.4996) (xy 5.0292 -9.7536)
				(xy 5.0292 -12.2428) (xy 5.0292 -12.464288) (xy 4.92633 -12.567158) (xy 4.92633 -14.040104) (xy 4.640834 -14.3256)
				(xy 4.435856 -14.530578) (xy 4.435856 -15.47114) (xy 4.349242 -15.557754) (xy 3.402076 -15.557754)
				(xy 2.76479 -15.557754) (xy 2.6924 -15.630144) (xy 2.6924 -17.0688) (xy 2.6924 -17.451832) (xy 2.763012 -17.522444)
				(xy 4.814316 -17.522444)
			)
		)
	)
	(zone
		(layer "F.Cu")
		(hatch none 0.5)
		(connect_pads
			(clearance 0)
		)
		(min_thickness 0.25)
		(keepout
			(tracks not_allowed)
			(vias allowed)
			(pads allowed)
			(copperpour not_allowed)
			(footprints allowed)
		)
		(placement
			(enabled no)
			(sheetname "")
		)
		(fill
			(thermal_gap 0.5)
			(thermal_bridge_width 0.5)
			(island_removal_mode 0)
		)
		(polygon
			(pts
				(xy 426.241718 -2.820924) (xy 426.396912 -2.976118) (xy 426.396912 -3.274314) (xy 426.498512 -3.274314)
				(xy 426.498512 -2.976118) (xy 426.653706 -2.820924)
				(arc
					(start 426.82541 -2.820924)
					(mid 427.349327 -2.890774)
					(end 426.82541 -2.960624)
				)
				(xy 426.711618 -2.960624) (xy 426.638212 -3.03403) (xy 426.638212 -3.274314)
				(arc
					(start 427.082458 -3.274314)
					(mid 427.466252 -2.890901)
					(end 427.082712 -2.507234)
				)
				(arc
					(start 425.812712 -2.507234)
					(mid 425.429172 -2.890774)
					(end 425.812712 -3.274314)
				)
				(xy 426.257212 -3.274314) (xy 426.257212 -3.03403) (xy 426.183806 -2.960624)
				(arc
					(start 426.070014 -2.960624)
					(mid 425.546097 -2.890774)
					(end 426.070014 -2.820924)
				)
			)
		)
	)
	(zone
		(net "P12V_STBY")
		(layer "F.Cu")
		(hatch none 0.5)
		(connect_pads
			(clearance 0.5)
		)
		(min_thickness 0.25)
		(fill yes
			(thermal_gap 0.5)
			(thermal_bridge_width 0.5)
			(island_removal_mode 0)
		)
		(polygon
			(pts
				(xy 201.422 -126.238) (xy 201.803 -125.857) (xy 201.803 -121.2088) (xy 200.493884 -119.899684) (xy 199.963532 -119.899684)
				(xy 191.758316 -119.899684) (xy 189.130178 -119.899684) (xy 188.58738 -120.442482) (xy 188.58738 -126.535434)
				(xy 188.58738 -127.714248) (xy 188.812932 -127.9398) (xy 190.127636 -127.9398) (xy 191.013842 -127.053594)
				(xy 191.829436 -126.238) (xy 191.837564 -126.229872) (xy 193.70802 -126.229872) (xy 193.716402 -126.238)
			)
		)
	)
	(zone
		(net "PVDDQ_ABC")
		(layer "F.Cu")
		(hatch none 0.5)
		(connect_pads
			(clearance 0.5)
		)
		(min_thickness 0.25)
		(fill yes
			(thermal_gap 0.5)
			(thermal_bridge_width 0.5)
			(island_removal_mode 0)
		)
		(polygon
			(pts
				(xy 243.84 -9.271) (xy 255.5494 -9.271) (xy 255.5748 -9.2964) (xy 255.5748 -10.6172) (xy 255.6764 -10.7188)
				(xy 256.159 -10.7188) (xy 256.2352 -10.6426) (xy 256.2352 -9.4488) (xy 256.413 -9.271) (xy 258.572 -9.271)
				(xy 258.699 -9.144) (xy 258.699 -7.112) (xy 258.572 -6.985) (xy 243.713 -6.985) (xy 243.586 -7.112)
				(xy 243.586 -9.017)
			)
		)
	)
	(zone
		(layer "F.Cu")
		(hatch none 0.5)
		(connect_pads
			(clearance 0)
		)
		(min_thickness 0.25)
		(keepout
			(tracks not_allowed)
			(vias allowed)
			(pads allowed)
			(copperpour not_allowed)
			(footprints allowed)
		)
		(placement
			(enabled no)
			(sheetname "")
		)
		(fill
			(thermal_gap 0.5)
			(thermal_bridge_width 0.5)
			(island_removal_mode 0)
		)
		(polygon
			(pts
				(xy 423.841672 -1.514094) (xy 423.996866 -1.669288) (xy 423.996866 -1.967484) (xy 424.098466 -1.967484)
				(xy 424.098466 -1.669288) (xy 424.25366 -1.514094)
				(arc
					(start 424.425364 -1.514094)
					(mid 424.949281 -1.583944)
					(end 424.425364 -1.653794)
				)
				(xy 424.311572 -1.653794) (xy 424.238166 -1.7272) (xy 424.238166 -1.967484)
				(arc
					(start 424.682666 -1.967484)
					(mid 425.066206 -1.583944)
					(end 424.682666 -1.200404)
				)
				(arc
					(start 423.41292 -1.200404)
					(mid 423.02938 -1.583817)
					(end 423.412666 -1.967484)
				)
				(xy 423.857166 -1.967484) (xy 423.857166 -1.7272) (xy 423.78376 -1.653794)
				(arc
					(start 423.669968 -1.653794)
					(mid 423.146051 -1.583944)
					(end 423.669968 -1.514094)
				)
			)
		)
	)
	(zone
		(layer "F.Cu")
		(hatch none 0.5)
		(connect_pads
			(clearance 0)
		)
		(min_thickness 0.25)
		(keepout
			(tracks not_allowed)
			(vias allowed)
			(pads allowed)
			(copperpour not_allowed)
			(footprints allowed)
		)
		(placement
			(enabled no)
			(sheetname "")
		)
		(fill
			(thermal_gap 0.5)
			(thermal_bridge_width 0.5)
			(island_removal_mode 0)
		)
		(polygon
			(pts
				(arc
					(start 11.84275 -35.753802)
					(mid 11.9126 -35.229885)
					(end 11.98245 -35.753802)
				)
				(xy 11.98245 -35.867594) (xy 12.055856 -35.941) (xy 12.29614 -35.941)
				(arc
					(start 12.29614 -35.496754)
					(mid 11.912727 -35.11296)
					(end 11.52906 -35.4965)
				)
				(arc
					(start 11.52906 -36.7665)
					(mid 11.9126 -37.15004)
					(end 12.29614 -36.7665)
				)
				(xy 12.29614 -36.322) (xy 12.055856 -36.322) (xy 11.98245 -36.395406)
				(arc
					(start 11.98245 -36.509198)
					(mid 11.9126 -37.033115)
					(end 11.84275 -36.509198)
				)
				(xy 11.84275 -36.337494) (xy 11.997944 -36.1823) (xy 12.29614 -36.1823) (xy 12.29614 -36.0807) (xy 11.997944 -36.0807)
				(xy 11.84275 -35.925506)
			)
		)
	)
	(zone
		(net "VR_PVTT_DEF_SNS")
		(layer "F.Cu")
		(hatch none 0.5)
		(connect_pads
			(clearance 0.5)
		)
		(min_thickness 0.25)
		(fill yes
			(thermal_gap 0.5)
			(thermal_bridge_width 0.5)
			(island_removal_mode 0)
		)
		(polygon
			(pts
				(xy 183.7436 -151.511) (xy 184.37352 -151.511) (xy 184.8358 -151.97328) (xy 186.26328 -151.97328)
				(xy 186.69 -152.4) (xy 186.69 -155.956) (xy 184.912 -157.734) (xy 184.531 -158.115) (xy 184.531 -158.369)
				(xy 184.785 -158.623) (xy 185.166 -158.623) (xy 185.42 -158.369) (xy 187.325 -156.464) (xy 187.325 -152.146)
				(xy 186.055 -150.876) (xy 183.769 -150.876) (xy 183.7182 -150.9268) (xy 183.7182 -151.4856)
			)
		)
	)
	(zone
		(net "GND")
		(layer "F.Cu")
		(hatch none 0.5)
		(connect_pads
			(clearance 0.5)
		)
		(min_thickness 0.25)
		(fill yes
			(thermal_gap 0.5)
			(thermal_bridge_width 0.5)
			(island_removal_mode 0)
		)
		(polygon
			(pts
				(xy 408.442668 -92.856812) (xy 407.672032 -92.856812) (xy 407.581862 -92.946982) (xy 407.581862 -94.896432)
				(xy 407.665936 -94.980506) (xy 408.888946 -94.980506) (xy 408.957018 -94.912434) (xy 409.08351 -94.912434)
				(xy 409.135834 -94.86011) (xy 409.135834 -94.537784) (xy 408.570938 -93.972888) (xy 408.570938 -92.985082)
			)
		)
	)
	(zone
		(layer "F.Cu")
		(hatch none 0.5)
		(connect_pads
			(clearance 0)
		)
		(min_thickness 0.25)
		(keepout
			(tracks not_allowed)
			(vias allowed)
			(pads allowed)
			(copperpour not_allowed)
			(footprints allowed)
		)
		(placement
			(enabled no)
			(sheetname "")
		)
		(fill
			(thermal_gap 0.5)
			(thermal_bridge_width 0.5)
			(island_removal_mode 0)
		)
		(polygon
			(pts
				(xy 323.9135 -120.65) (xy 323.9135 -120.142) (xy 324.2945 -120.142) (xy 324.2945 -120.65)
			)
		)
	)
	(zone
		(net "VR_PVDDQ_KLM_PH1_SW")
		(layer "F.Cu")
		(hatch none 0.5)
		(connect_pads
			(clearance 0.5)
		)
		(min_thickness 0.25)
		(fill yes
			(thermal_gap 0.5)
			(thermal_bridge_width 0.5)
			(island_removal_mode 0)
		)
		(polygon
			(pts
				(xy 4.921504 -140.79982) (xy 8.7757 -140.79982) (xy 10.036302 -140.79982) (xy 10.433304 -140.402818)
				(xy 10.433304 -136.237218) (xy 9.915906 -135.71982) (xy 8.7757 -135.71982) (xy 4.921504 -135.71982)
			)
		)
	)
	(zone
		(layer "F.Cu")
		(hatch none 0.5)
		(connect_pads
			(clearance 0)
		)
		(min_thickness 0.25)
		(keepout
			(tracks allowed)
			(vias allowed)
			(pads allowed)
			(copperpour allowed)
			(footprints allowed)
		)
		(placement
			(enabled no)
			(sheetname "")
		)
		(fill
			(thermal_gap 0.5)
			(thermal_bridge_width 0.5)
			(island_removal_mode 0)
		)
		(polygon
			(pts
				(xy 195.199 -85.09) (xy 195.199 -83.947) (xy 197.358 -83.947) (xy 197.358 -85.09)
			)
		)
	)
	(zone
		(net "GND")
		(layer "F.Cu")
		(hatch none 0.5)
		(connect_pads
			(clearance 0.5)
		)
		(min_thickness 0.25)
		(fill yes
			(thermal_gap 0.5)
			(thermal_bridge_width 0.5)
			(island_removal_mode 0)
		)
		(polygon
			(pts
				(xy 494.3602 -60.1218) (xy 489.6358 -60.1218) (xy 488.7722 -60.1218) (xy 488.696 -60.198) (xy 488.696 -62.0268)
				(xy 488.8357 -62.1665) (xy 489.4961 -62.1665) (xy 489.5215 -62.1919) (xy 494.3475 -62.1919) (xy 496.712494 -62.1919)
				(xy 497.030756 -61.873638) (xy 497.030756 -60.988956) (xy 496.9764 -60.9346) (xy 496.7732 -60.9346)
				(xy 496.3287 -60.4901) (xy 496.3287 -60.1599) (xy 496.2906 -60.1218)
			)
		)
	)
	(zone
		(layer "F.Cu")
		(hatch none 0.5)
		(connect_pads
			(clearance 0)
		)
		(min_thickness 0.25)
		(keepout
			(tracks allowed)
			(vias allowed)
			(pads allowed)
			(copperpour allowed)
			(footprints not_allowed)
		)
		(placement
			(enabled no)
			(sheetname "")
		)
		(fill
			(thermal_gap 0.5)
			(thermal_bridge_width 0.5)
			(island_removal_mode 0)
		)
		(polygon
			(pts
				(xy 187.525406 -22.919182) (xy 187.525406 5.999988) (xy 183.925464 5.999988) (xy 183.925464 -22.919182)
			)
		)
	)
	(zone
		(net "P12V_STBY")
		(layer "F.Cu")
		(hatch none 0.5)
		(connect_pads
			(clearance 0.5)
		)
		(min_thickness 0.25)
		(fill yes
			(thermal_gap 0.5)
			(thermal_bridge_width 0.5)
			(island_removal_mode 0)
		)
		(polygon
			(pts
				(xy 483.341172 -22.83714) (xy 483.387654 -22.790658) (xy 484.943658 -22.790658) (xy 485.059228 -22.906228)
				(xy 485.059228 -23.953216) (xy 485.059228 -25.699974) (xy 484.809038 -25.950164) (xy 482.316536 -25.950164)
				(xy 482.001322 -25.63495) (xy 481.93452 -25.568148) (xy 481.93452 -23.540212) (xy 481.997512 -23.47722)
				(xy 482.701092 -23.47722)
			)
		)
	)
	(zone
		(layer "F.Cu")
		(hatch none 0.5)
		(connect_pads
			(clearance 0)
		)
		(min_thickness 0.25)
		(keepout
			(tracks allowed)
			(vias allowed)
			(pads allowed)
			(copperpour allowed)
			(footprints not_allowed)
		)
		(placement
			(enabled no)
			(sheetname "")
		)
		(fill
			(thermal_gap 0.5)
			(thermal_bridge_width 0.5)
			(island_removal_mode 0)
		)
		(polygon
			(pts
				(arc
					(start 171.99991 -156.59989)
					(mid 170.50004 -155.10002)
					(end 171.99991 -153.599896)
				)
				(arc
					(start 172.671486 -153.599896)
					(mid 173.338113 -153.485602)
					(end 173.928532 -153.15565)
				)
				(arc
					(start 173.928532 -153.15565)
					(mid 177.999652 -155.10002)
					(end 173.928532 -157.04439)
				)
				(arc
					(start 173.928532 -157.04439)
					(mid 173.338136 -156.714333)
					(end 172.671486 -156.59989)
				)
			)
		)
	)
	(zone
		(layer "F.Cu")
		(hatch none 0.5)
		(connect_pads
			(clearance 0)
		)
		(min_thickness 0.25)
		(keepout
			(tracks allowed)
			(vias allowed)
			(pads allowed)
			(copperpour allowed)
			(footprints allowed)
		)
		(placement
			(enabled no)
			(sheetname "")
		)
		(fill
			(thermal_gap 0.5)
			(thermal_bridge_width 0.5)
			(island_removal_mode 0)
		)
		(polygon
			(pts
				(xy 354.715064 -138.531854) (xy 354.715064 -136.2964) (xy 357.124 -136.2964) (xy 357.124 -138.531854)
			)
		)
	)
	(zone
		(layer "F.Cu")
		(hatch none 0.5)
		(connect_pads
			(clearance 0)
		)
		(min_thickness 0.25)
		(keepout
			(tracks allowed)
			(vias allowed)
			(pads allowed)
			(copperpour allowed)
			(footprints not_allowed)
		)
		(placement
			(enabled no)
			(sheetname "")
		)
		(fill
			(thermal_gap 0.5)
			(thermal_bridge_width 0.5)
			(island_removal_mode 0)
		)
		(polygon
			(pts
				(arc
					(start 291.999924 -114.089942)
					(mid 289.459924 -111.549942)
					(end 291.999924 -109.009942)
				)
				(arc
					(start 291.999924 -109.009942)
					(mid 294.539924 -111.549942)
					(end 291.999924 -114.089942)
				)
			)
		)
	)
	(zone
		(net "P12V_NVDIMM_KLM")
		(layer "F.Cu")
		(hatch none 0.5)
		(connect_pads
			(clearance 0.5)
		)
		(min_thickness 0.25)
		(fill yes
			(thermal_gap 0.5)
			(thermal_bridge_width 0.5)
			(island_removal_mode 0)
		)
		(polygon
			(pts
				(xy 29.944568 -130.065272) (xy 29.944568 -157.799024) (xy 29.837126 -157.906466) (xy 27.00401 -157.906466)
				(xy 26.842466 -157.906466) (xy 26.416 -157.48) (xy 24.765 -157.48) (xy 24.1046 -156.8196) (xy 24.1046 -133.9088)
				(xy 24.0284 -133.8326) (xy 17.76984 -133.8326) (xy 17.40154 -134.2009) (xy 16.4973 -134.2009) (xy 16.1036 -133.8072)
				(xy 16.1036 -129.8448) (xy 16.5481 -129.4003) (xy 22.2377 -129.4003) (xy 22.3012 -129.3368) (xy 23.241 -128.397)
				(xy 28.956 -128.397) (xy 29.650436 -129.091436) (xy 29.650436 -129.77114)
			)
		)
	)
	(zone
		(layer "F.Cu")
		(hatch none 0.5)
		(connect_pads
			(clearance 0)
		)
		(min_thickness 0.25)
		(keepout
			(tracks not_allowed)
			(vias allowed)
			(pads allowed)
			(copperpour not_allowed)
			(footprints allowed)
		)
		(placement
			(enabled no)
			(sheetname "")
		)
		(fill
			(thermal_gap 0.5)
			(thermal_bridge_width 0.5)
			(island_removal_mode 0)
		)
		(polygon
			(pts
				(xy 441.833508 -9.651492) (xy 441.833508 -9.782302)
				(arc
					(start 441.908438 -9.857232)
					(mid 442.355137 -10.13872)
					(end 441.847478 -9.993884)
				)
				(xy 441.693808 -9.840214) (xy 441.693808 -9.655556) (xy 441.592208 -9.658604) (xy 441.592208 -9.839198)
				(arc
					(start 441.387992 -10.043414)
					(mid 440.871304 -10.149693)
					(end 441.33516 -9.898634)
				)
				(xy 441.452508 -9.781286) (xy 441.452508 -9.662668) (xy 441.110624 -9.672574)
				(arc
					(start 441.110624 -9.675114)
					(mid 440.738514 -10.069576)
					(end 441.132976 -10.441686)
				)
				(xy 441.132976 -10.444226) (xy 442.122814 -10.41527) (xy 442.123068 -10.415016)
				(arc
					(start 442.123068 -10.41273)
					(mid 442.495178 -10.018268)
					(end 442.100716 -9.646158)
				)
				(xy 442.100716 -9.643618)
			)
		)
	)
	(zone
		(net "GND")
		(layer "F.Cu")
		(hatch none 0.5)
		(connect_pads
			(clearance 0.5)
		)
		(min_thickness 0.25)
		(fill yes
			(thermal_gap 0.5)
			(thermal_bridge_width 0.5)
			(island_removal_mode 0)
		)
		(polygon
			(pts
				(xy 213.5886 -60.1726) (xy 213.4108 -60.3504) (xy 213.4108 -61.9506) (xy 213.5886 -62.1284) (xy 215.2142 -62.1284)
				(xy 215.5444 -61.7982) (xy 215.5444 -60.3504) (xy 215.3666 -60.1726)
			)
		)
		(polygon
			(pts
				(xy 214.9856 -60.94222) (xy 214.7824 -60.94222) (xy 214.7824 -61.34862) (xy 214.9856 -61.34862)
			)
		)
		(polygon
			(pts
				(xy 214.2236 -60.94222) (xy 214.0204 -60.94222) (xy 214.0204 -61.34862) (xy 214.2236 -61.34862)
			)
		)
	)
	(zone
		(net "GND")
		(layer "F.Cu")
		(hatch none 0.5)
		(connect_pads
			(clearance 0.5)
		)
		(min_thickness 0.25)
		(fill yes
			(thermal_gap 0.5)
			(thermal_bridge_width 0.5)
			(island_removal_mode 0)
		)
		(polygon
			(pts
				(xy 401.448016 -150.189184) (xy 404.115016 -150.189184) (xy 404.216616 -150.087584) (xy 404.216616 -148.690584)
				(xy 404.038816 -148.512784) (xy 401.346416 -148.512784) (xy 400.972528 -148.886672) (xy 400.972528 -149.87905)
				(xy 401.282662 -150.189184)
			)
		)
	)
	(zone
		(layer "F.Cu")
		(hatch none 0.5)
		(connect_pads
			(clearance 0)
		)
		(min_thickness 0.25)
		(keepout
			(tracks allowed)
			(vias allowed)
			(pads allowed)
			(copperpour allowed)
			(footprints allowed)
		)
		(placement
			(enabled no)
			(sheetname "")
		)
		(fill
			(thermal_gap 0.5)
			(thermal_bridge_width 0.5)
			(island_removal_mode 0)
		)
		(polygon
			(pts
				(xy 117.828568 -103.759) (xy 117.828568 -105.41) (xy 117.828568 -106.045) (xy 112.494568 -106.045)
				(xy 112.494568 -103.632) (xy 117.828568 -103.632)
			)
		)
	)
	(zone
		(layer "F.Cu")
		(hatch none 0.5)
		(connect_pads
			(clearance 0)
		)
		(min_thickness 0.25)
		(keepout
			(tracks not_allowed)
			(vias allowed)
			(pads allowed)
			(copperpour not_allowed)
			(footprints allowed)
		)
		(placement
			(enabled no)
			(sheetname "")
		)
		(fill
			(thermal_gap 0.5)
			(thermal_bridge_width 0.5)
			(island_removal_mode 0)
		)
		(polygon
			(pts
				(arc
					(start 358.92867 3.944366)
					(mid 358.338274 3.614309)
					(end 357.671624 3.499866)
				)
				(arc
					(start 357.000048 3.499866)
					(mid 355.500178 1.999996)
					(end 357.000048 0.499872)
				)
				(arc
					(start 357.671624 0.499872)
					(mid 358.338295 0.385488)
					(end 358.92867 0.055372)
				)
				(arc
					(start 358.92867 0.055372)
					(mid 363.000402 2.000076)
					(end 358.92867 3.944366)
				)
			)
		)
	)
	(zone
		(net "P1V2_AUX_BMC")
		(layer "F.Cu")
		(hatch none 0.5)
		(connect_pads
			(clearance 0.5)
		)
		(min_thickness 0.25)
		(fill yes
			(thermal_gap 0.5)
			(thermal_bridge_width 0.5)
			(island_removal_mode 0)
		)
		(polygon
			(pts
				(xy 435.0639 -44.9199) (xy 438.0357 -44.9199) (xy 438.531 -44.4246) (xy 443.7634 -44.4246) (xy 443.992 -44.6532)
				(xy 443.992 -44.9834) (xy 444.0936 -45.085) (xy 444.5635 -45.085) (xy 444.6905 -44.958) (xy 444.6905 -44.40174)
				(xy 444.6905 -43.66514) (xy 444.67526 -43.6499) (xy 444.51016 -43.4848) (xy 443.6364 -43.4848) (xy 443.5094 -43.4848)
				(xy 441.9981 -43.4848) (xy 441.7568 -43.7261) (xy 435.1274 -43.7261) (xy 435.0512 -43.8023) (xy 435.0512 -44.5262)
				(xy 434.9623 -44.6151) (xy 434.9623 -44.8183)
			)
		)
	)
	(zone
		(layer "F.Cu")
		(hatch none 0.5)
		(connect_pads
			(clearance 0)
		)
		(min_thickness 0.25)
		(keepout
			(tracks allowed)
			(vias allowed)
			(pads allowed)
			(copperpour allowed)
			(footprints allowed)
		)
		(placement
			(enabled no)
			(sheetname "")
		)
		(fill
			(thermal_gap 0.5)
			(thermal_bridge_width 0.5)
			(island_removal_mode 0)
		)
		(polygon
			(pts
				(xy 344.520266 -79.322676) (xy 344.520266 -77.036676) (xy 346.526866 -77.036676) (xy 346.526866 -79.322676)
			)
		)
	)
	(zone
		(layer "F.Cu")
		(hatch none 0.5)
		(connect_pads
			(clearance 0)
		)
		(min_thickness 0.25)
		(keepout
			(tracks allowed)
			(vias allowed)
			(pads allowed)
			(copperpour allowed)
			(footprints allowed)
		)
		(placement
			(enabled no)
			(sheetname "")
		)
		(fill
			(thermal_gap 0.5)
			(thermal_bridge_width 0.5)
			(island_removal_mode 0)
		)
		(polygon
			(pts
				(xy 480.2378 -49.9872) (xy 480.2378 -48.2092) (xy 489.5596 -48.2092) (xy 489.5596 -49.9872)
			)
		)
	)
	(zone
		(layer "F.Cu")
		(hatch none 0.5)
		(connect_pads
			(clearance 0)
		)
		(min_thickness 0.25)
		(keepout
			(tracks allowed)
			(vias allowed)
			(pads allowed)
			(copperpour allowed)
			(footprints allowed)
		)
		(placement
			(enabled no)
			(sheetname "")
		)
		(fill
			(thermal_gap 0.5)
			(thermal_bridge_width 0.5)
			(island_removal_mode 0)
		)
		(polygon
			(pts
				(xy 277.495 -104.521) (xy 277.495 -106.172) (xy 277.495 -106.807) (xy 271.272 -106.807) (xy 271.272 -106.172)
				(xy 271.272 -104.521) (xy 271.272 -104.14) (xy 277.495 -104.14)
			)
		)
	)
	(zone
		(net "GND")
		(layer "F.Cu")
		(hatch none 0.5)
		(connect_pads
			(clearance 0.5)
		)
		(min_thickness 0.25)
		(fill yes
			(thermal_gap 0.5)
			(thermal_bridge_width 0.5)
			(island_removal_mode 0)
		)
		(polygon
			(pts
				(xy 409.5496 -68.9864) (xy 415.3408 -68.9864) (xy 415.3916 -68.9356) (xy 415.3916 -67.564) (xy 415.3408 -67.5132)
				(xy 409.5496 -67.5132) (xy 409.4988 -67.564) (xy 409.4988 -68.9356)
			)
		)
	)
	(zone
		(layer "F.Cu")
		(hatch none 0.5)
		(connect_pads
			(clearance 0)
		)
		(min_thickness 0.25)
		(keepout
			(tracks allowed)
			(vias allowed)
			(pads allowed)
			(copperpour allowed)
			(footprints allowed)
		)
		(placement
			(enabled no)
			(sheetname "")
		)
		(fill
			(thermal_gap 0.5)
			(thermal_bridge_width 0.5)
			(island_removal_mode 0)
		)
		(polygon
			(pts
				(xy 332.3844 -118.7577) (xy 330.0984 -118.7577) (xy 330.0984 -116.7511) (xy 332.3844 -116.7511)
			)
		)
	)
	(zone
		(layer "F.Cu")
		(hatch none 0.5)
		(connect_pads
			(clearance 0)
		)
		(min_thickness 0.25)
		(keepout
			(tracks not_allowed)
			(vias allowed)
			(pads allowed)
			(copperpour not_allowed)
			(footprints allowed)
		)
		(placement
			(enabled no)
			(sheetname "")
		)
		(fill
			(thermal_gap 0.5)
			(thermal_bridge_width 0.5)
			(island_removal_mode 0)
		)
		(polygon
			(pts
				(xy 399.90268 -3.106674) (xy 400.020536 -3.22453) (xy 400.020536 -3.50774) (xy 399.968212 -3.560064)
				(xy 400.17446 -3.560064) (xy 400.122136 -3.50774) (xy 400.122136 -3.207258) (xy 400.22272 -3.106674)
				(arc
					(start 400.31289 -3.106674)
					(mid 400.836807 -3.176524)
					(end 400.31289 -3.246374)
				)
				(xy 400.280632 -3.246374) (xy 400.261836 -3.26517) (xy 400.261836 -3.449828) (xy 400.372072 -3.560064)
				(arc
					(start 400.569938 -3.560064)
					(mid 400.953732 -3.176651)
					(end 400.570192 -2.792984)
				)
				(arc
					(start 399.554192 -2.792984)
					(mid 399.170652 -3.176524)
					(end 399.554192 -3.560064)
				)
				(xy 399.7706 -3.560064) (xy 399.880836 -3.449828) (xy 399.880836 -3.282442) (xy 399.844768 -3.246374)
				(arc
					(start 399.811494 -3.246374)
					(mid 399.287577 -3.176524)
					(end 399.811494 -3.106674)
				)
			)
		)
	)
	(zone
		(layer "F.Cu")
		(hatch none 0.5)
		(connect_pads
			(clearance 0)
		)
		(min_thickness 0.25)
		(keepout
			(tracks allowed)
			(vias allowed)
			(pads allowed)
			(copperpour allowed)
			(footprints allowed)
		)
		(placement
			(enabled no)
			(sheetname "")
		)
		(fill
			(thermal_gap 0.5)
			(thermal_bridge_width 0.5)
			(island_removal_mode 0)
		)
		(polygon
			(pts
				(xy 177.673 -58.42) (xy 182.118 -58.42) (xy 182.499 -58.039) (xy 182.499 -53.34) (xy 182.118 -52.959)
				(xy 180.086 -52.959) (xy 179.959 -53.086) (xy 179.959 -56.134) (xy 179.578 -56.515) (xy 177.546 -56.515)
				(xy 177.546 -58.293)
			)
		)
	)
	(zone
		(net "VR_P5V_STBY_VSENSE")
		(layer "F.Cu")
		(hatch none 0.5)
		(connect_pads
			(clearance 0.5)
		)
		(min_thickness 0.25)
		(fill yes
			(thermal_gap 0.5)
			(thermal_bridge_width 0.5)
			(island_removal_mode 0)
		)
		(polygon
			(pts
				(xy 391.5664 -64.408304) (xy 391.5664 -66.3702) (xy 391.541 -66.3956) (xy 391.3124 -66.3956) (xy 391.291826 -66.375026)
				(xy 391.291826 -65.603374) (xy 391.241026 -65.552574) (xy 390.875774 -65.552574) (xy 390.0424 -64.7192)
				(xy 390.0424 -64.3509) (xy 390.065768 -64.327532) (xy 390.065768 -64.32296) (xy 391.370058 -64.32296)
				(xy 391.375392 -64.317626) (xy 391.475722 -64.317626)
			)
		)
	)
	(zone
		(net "VR_P5V_STBY_RT")
		(layer "F.Cu")
		(hatch none 0.5)
		(connect_pads
			(clearance 0.5)
		)
		(min_thickness 0.25)
		(fill yes
			(thermal_gap 0.5)
			(thermal_bridge_width 0.5)
			(island_removal_mode 0)
		)
		(polygon
			(pts
				(xy 391.5664 -69.98589) (xy 391.5664 -69.0118) (xy 391.541 -68.9864) (xy 391.402824 -68.9864) (xy 391.287 -68.9864)
				(xy 390.271 -70.0024) (xy 390.271 -70.118224) (xy 390.271 -71.2724) (xy 390.30783 -71.30923) (xy 390.347454 -71.30923)
				(xy 390.790938 -71.30923) (xy 390.8044 -71.295768) (xy 390.8044 -70.74789)
			)
		)
	)
	(zone
		(layer "F.Cu")
		(hatch none 0.5)
		(connect_pads
			(clearance 0)
		)
		(min_thickness 0.25)
		(keepout
			(tracks allowed)
			(vias allowed)
			(pads allowed)
			(copperpour allowed)
			(footprints not_allowed)
		)
		(placement
			(enabled no)
			(sheetname "")
		)
		(fill
			(thermal_gap 0.5)
			(thermal_bridge_width 0.5)
			(island_removal_mode 0)
		)
		(polygon
			(pts
				(xy 497.800122 -120.990106) (xy 502.000012 -120.990106) (xy 502.000012 -123.690126) (xy 497.800122 -123.690126)
			)
		)
	)
	(zone
		(layer "F.Cu")
		(hatch none 0.5)
		(connect_pads
			(clearance 0)
		)
		(min_thickness 0.25)
		(keepout
			(tracks not_allowed)
			(vias allowed)
			(pads allowed)
			(copperpour not_allowed)
			(footprints allowed)
		)
		(placement
			(enabled no)
			(sheetname "")
		)
		(fill
			(thermal_gap 0.5)
			(thermal_bridge_width 0.5)
			(island_removal_mode 0)
		)
		(polygon
			(pts
				(xy 372.15191 -7.193026) (xy 372.418356 -7.193026) (xy 372.418356 -8.386826) (xy 372.15191 -8.386826)
			)
		)
	)
	(zone
		(layer "F.Cu")
		(hatch none 0.5)
		(connect_pads
			(clearance 0)
		)
		(min_thickness 0.25)
		(keepout
			(tracks not_allowed)
			(vias allowed)
			(pads allowed)
			(copperpour not_allowed)
			(footprints allowed)
		)
		(placement
			(enabled no)
			(sheetname "")
		)
		(fill
			(thermal_gap 0.5)
			(thermal_bridge_width 0.5)
			(island_removal_mode 0)
		)
		(polygon
			(pts
				(arc
					(start 449.31965 -44.7675)
					(mid 449.843567 -44.83735)
					(end 449.31965 -44.9072)
				)
				(xy 449.272914 -44.9072) (xy 449.12915 -45.050964) (xy 449.12915 -45.22089)
				(arc
					(start 449.576952 -45.22089)
					(mid 449.960492 -44.83735)
					(end 449.576952 -44.45381)
				)
				(arc
					(start 448.307206 -44.45381)
					(mid 447.923412 -44.837223)
					(end 448.306952 -45.22089)
				)
				(xy 448.74815 -45.22089) (xy 448.74815 -45.04436) (xy 448.61099 -44.9072)
				(arc
					(start 448.564254 -44.9072)
					(mid 448.040337 -44.83735)
					(end 448.564254 -44.7675)
				)
				(xy 448.668902 -44.7675) (xy 448.88785 -44.986448) (xy 448.88785 -45.22089) (xy 448.98945 -45.22089)
				(xy 448.98945 -44.993052) (xy 449.215002 -44.7675)
			)
		)
	)
	(zone
		(layer "F.Cu")
		(hatch none 0.5)
		(connect_pads
			(clearance 0)
		)
		(min_thickness 0.25)
		(keepout
			(tracks not_allowed)
			(vias allowed)
			(pads allowed)
			(copperpour not_allowed)
			(footprints allowed)
		)
		(placement
			(enabled no)
			(sheetname "")
		)
		(fill
			(thermal_gap 0.5)
			(thermal_bridge_width 0.5)
			(island_removal_mode 0)
		)
		(polygon
			(pts
				(xy 15.329154 -29.066998) (xy 15.48765 -29.225494)
				(arc
					(start 15.48765 -29.397198)
					(mid 15.4178 -29.921115)
					(end 15.34795 -29.397198)
				)
				(xy 15.34795 -29.283406) (xy 15.271242 -29.206698) (xy 15.138908 -29.206698) (xy 15.03426 -29.311346)
				(arc
					(start 15.03426 -29.6545)
					(mid 15.4178 -30.03804)
					(end 15.80134 -29.6545)
				)
				(arc
					(start 15.80134 -28.384754)
					(mid 15.417927 -28.00096)
					(end 15.03426 -28.3845)
				)
				(xy 15.03426 -28.727654) (xy 15.132304 -28.825698) (xy 15.277846 -28.825698) (xy 15.34795 -28.755594)
				(arc
					(start 15.34795 -28.641802)
					(mid 15.4178 -28.117885)
					(end 15.48765 -28.641802)
				)
				(xy 15.48765 -28.813506) (xy 15.335758 -28.965398) (xy 15.074392 -28.965398) (xy 15.03426 -28.925266)
				(xy 15.03426 -29.113734) (xy 15.080996 -29.066998)
			)
		)
	)
	(zone
		(layer "F.Cu")
		(hatch none 0.5)
		(connect_pads
			(clearance 0)
		)
		(min_thickness 0.25)
		(keepout
			(tracks allowed)
			(vias allowed)
			(pads allowed)
			(copperpour allowed)
			(footprints allowed)
		)
		(placement
			(enabled no)
			(sheetname "")
		)
		(fill
			(thermal_gap 0.5)
			(thermal_bridge_width 0.5)
			(island_removal_mode 0)
		)
		(polygon
			(pts
				(xy 165.481 -65.024) (xy 167.386 -65.024) (xy 167.386 -67.31) (xy 165.481 -67.31)
			)
		)
	)
	(zone
		(net "PVDDQ_DEF")
		(layer "F.Cu")
		(hatch none 0.5)
		(connect_pads
			(clearance 0.5)
		)
		(min_thickness 0.25)
		(fill yes
			(thermal_gap 0.5)
			(thermal_bridge_width 0.5)
			(island_removal_mode 0)
		)
		(polygon
			(pts
				(xy 258.605528 -146.221196) (xy 258.829048 -145.997676) (xy 258.829048 -144.045686) (xy 258.548632 -143.76527)
				(xy 255.938528 -143.76527) (xy 243.745766 -143.76527) (xy 243.735606 -143.77543) (xy 243.735606 -146.107912)
				(xy 243.849144 -146.221196)
			)
		)
	)
	(zone
		(net "PVDDQ_KLM")
		(layer "F.Cu")
		(hatch none 0.5)
		(connect_pads
			(clearance 0.5)
		)
		(min_thickness 0.25)
		(fill yes
			(thermal_gap 0.5)
			(thermal_bridge_width 0.5)
			(island_removal_mode 0)
		)
		(polygon
			(pts
				(xy 112.369092 -146.218656) (xy 112.528604 -146.059144) (xy 112.528604 -143.83131) (xy 112.44326 -143.74622)
				(xy 100.825808 -143.74622) (xy 100.677726 -143.894302) (xy 100.677726 -145.960592) (xy 100.936044 -146.218656)
			)
		)
	)
	(zone
		(net "GND")
		(layer "F.Cu")
		(hatch none 0.5)
		(connect_pads
			(clearance 0.5)
		)
		(min_thickness 0.25)
		(fill yes
			(thermal_gap 0.5)
			(thermal_bridge_width 0.5)
			(island_removal_mode 0)
		)
		(polygon
			(pts
				(xy 345.2876 -92.837) (xy 344.8304 -93.2942) (xy 344.8304 -100.4062) (xy 343.9414 -101.2952) (xy 340.741 -101.2952)
				(xy 340.36 -101.6762) (xy 340.36 -105.41) (xy 340.868 -105.918) (xy 341.503 -105.918) (xy 341.63 -106.045)
				(xy 341.63 -106.7816) (xy 342.228932 -107.380532) (xy 353.30003 -107.380532) (xy 353.36861 -107.311952)
				(xy 353.36861 -104.233218) (xy 353.17557 -104.040178) (xy 351.994216 -104.040178) (xy 351.88271 -104.151684)
				(xy 345.68003 -104.151684) (xy 345.432634 -103.904288) (xy 345.432634 -102.622858) (xy 345.768168 -102.287324)
				(xy 346.921582 -102.287324) (xy 347.138244 -102.070662) (xy 347.138244 -100.916232) (xy 347.395038 -100.659438)
				(xy 347.395038 -100.635562) (xy 347.6244 -100.4062) (xy 347.6244 -99.3394) (xy 347.7006 -99.2632)
				(xy 348.7166 -99.2632) (xy 348.7674 -99.314) (xy 348.7674 -100.2284) (xy 348.7928 -100.2538) (xy 348.9452 -100.2538)
				(xy 348.9706 -100.2284) (xy 348.9706 -99.2886) (xy 348.996 -99.2632) (xy 349.25 -99.2632) (xy 349.2754 -99.2378)
				(xy 349.2754 -97.5868) (xy 349.25 -97.5614) (xy 347.2434 -97.5614) (xy 346.974922 -97.292922) (xy 346.974922 -92.974922)
				(xy 346.837 -92.837)
			)
		)
		(polygon
			(pts
				(xy 341.3379 -104.2162) (xy 341.1347 -104.2162) (xy 341.1347 -104.4194) (xy 341.3379 -104.4194)
			)
		)
		(polygon
			(pts
				(xy 341.3379 -103.4542) (xy 341.1347 -103.4542) (xy 341.1347 -103.6574) (xy 341.3379 -103.6574)
			)
		)
		(polygon
			(pts
				(xy 341.3379 -102.9716) (xy 341.1347 -102.9716) (xy 341.1347 -103.1748) (xy 341.3379 -103.1748)
			)
		)
		(polygon
			(pts
				(xy 341.3379 -102.2096) (xy 341.1347 -102.2096) (xy 341.1347 -102.4128) (xy 341.3379 -102.4128)
			)
		)
		(polygon
			(pts
				(xy 346.5576 -93.913706) (xy 346.3544 -93.913706) (xy 346.3544 -94.116906) (xy 346.5576 -94.116906)
			)
		)
		(polygon
			(pts
				(xy 346.1766 -93.853) (xy 345.9734 -93.853) (xy 345.9734 -94.0562) (xy 346.1766 -94.0562)
			)
		)
		(polygon
			(pts
				(xy 345.313 -93.853) (xy 345.1098 -93.853) (xy 345.1098 -94.0562) (xy 345.313 -94.0562)
			)
		)
		(polygon
			(pts
				(xy 346.5576 -93.405706) (xy 346.3544 -93.405706) (xy 346.3544 -93.608906) (xy 346.5576 -93.608906)
			)
		)
		(polygon
			(pts
				(xy 346.1766 -92.9894) (xy 345.9734 -92.9894) (xy 345.9734 -93.1926) (xy 346.1766 -93.1926)
			)
		)
	)
	(zone
		(layer "F.Cu")
		(hatch none 0.5)
		(connect_pads
			(clearance 0)
		)
		(min_thickness 0.25)
		(keepout
			(tracks allowed)
			(vias allowed)
			(pads allowed)
			(copperpour allowed)
			(footprints allowed)
		)
		(placement
			(enabled no)
			(sheetname "")
		)
		(fill
			(thermal_gap 0.5)
			(thermal_bridge_width 0.5)
			(island_removal_mode 0)
		)
		(polygon
			(pts
				(xy 172.8978 -85.5472) (xy 172.8978 -77.3684) (xy 172.8978 -76.86421) (xy 173.327314 -76.434696)
				(xy 175.151288 -76.434696) (xy 175.3362 -76.619608) (xy 175.3362 -77.3684) (xy 175.3362 -79.451708)
				(xy 176.727612 -79.451708) (xy 177.143918 -79.868014) (xy 177.143918 -80.936338) (xy 176.854104 -81.226152)
				(xy 175.3362 -81.226152) (xy 175.3362 -85.5472)
			)
		)
	)
	(zone
		(layer "F.Cu")
		(hatch none 0.5)
		(connect_pads
			(clearance 0)
		)
		(min_thickness 0.25)
		(keepout
			(tracks allowed)
			(vias allowed)
			(pads allowed)
			(copperpour allowed)
			(footprints not_allowed)
		)
		(placement
			(enabled no)
			(sheetname "")
		)
		(fill
			(thermal_gap 0.5)
			(thermal_bridge_width 0.5)
			(island_removal_mode 0)
		)
		(polygon
			(pts
				(xy 167.124634 -130.16611) (xy 173.624494 -130.16611) (xy 173.624494 -151.100028)
				(arc
					(start 171.99991 -151.100028)
					(mid 167.999918 -155.10002)
					(end 171.99991 -159.100012)
				)
				(xy 167.124634 -159.100012)
			)
		)
	)
	(zone
		(layer "F.Cu")
		(hatch none 0.5)
		(connect_pads
			(clearance 0)
		)
		(min_thickness 0.25)
		(keepout
			(tracks not_allowed)
			(vias allowed)
			(pads allowed)
			(copperpour not_allowed)
			(footprints allowed)
		)
		(placement
			(enabled no)
			(sheetname "")
		)
		(fill
			(thermal_gap 0.5)
			(thermal_bridge_width 0.5)
			(island_removal_mode 0)
		)
		(polygon
			(pts
				(xy 370.112544 -10.293858) (xy 370.620544 -10.293858) (xy 370.620544 -10.649458) (xy 370.112544 -10.649458)
			)
		)
	)
	(zone
		(layer "F.Cu")
		(hatch none 0.5)
		(connect_pads
			(clearance 0)
		)
		(min_thickness 0.25)
		(keepout
			(tracks allowed)
			(vias allowed)
			(pads allowed)
			(copperpour allowed)
			(footprints allowed)
		)
		(placement
			(enabled no)
			(sheetname "")
		)
		(fill
			(thermal_gap 0.5)
			(thermal_bridge_width 0.5)
			(island_removal_mode 0)
		)
		(polygon
			(pts
				(xy 445.0715 -63.029338) (xy 447.882772 -63.029338) (xy 448.098164 -62.813946) (xy 448.098164 -60.044076)
				(xy 447.832988 -59.7789) (xy 445.221106 -59.7789) (xy 444.947294 -60.052712) (xy 444.947294 -62.905132)
			)
		)
	)
	(zone
		(layer "F.Cu")
		(hatch none 0.5)
		(connect_pads
			(clearance 0)
		)
		(min_thickness 0.25)
		(keepout
			(tracks allowed)
			(vias allowed)
			(pads allowed)
			(copperpour allowed)
			(footprints allowed)
		)
		(placement
			(enabled no)
			(sheetname "")
		)
		(fill
			(thermal_gap 0.5)
			(thermal_bridge_width 0.5)
			(island_removal_mode 0)
		)
		(polygon
			(pts
				(xy 9.58342 -6.40842) (xy 11.684 -6.40842) (xy 12.27074 -5.82168) (xy 12.27074 -4.96316) (xy 12.45362 -4.78028)
				(xy 12.96416 -4.78028) (xy 13.01242 -4.73202) (xy 13.01242 -4.1656) (xy 12.90066 -4.05384) (xy 11.6967 -4.05384)
				(xy 11.48842 -4.26212) (xy 11.48842 -5.7404) (xy 11.17346 -6.05536) (xy 9.79678 -6.05536) (xy 9.58342 -5.842)
				(xy 9.58342 -4.92506) (xy 9.19734 -4.53898) (xy 9.19734 -3.98272) (xy 9.09066 -3.87604) (xy 8.51916 -3.87604)
				(xy 8.45566 -3.93954) (xy 8.45566 -4.71678) (xy 9.1313 -5.39242) (xy 9.1313 -5.9563)
			)
		)
	)
	(zone
		(net "PVPP_KLM")
		(layer "F.Cu")
		(hatch none 0.5)
		(connect_pads
			(clearance 0.5)
		)
		(min_thickness 0.25)
		(fill yes
			(thermal_gap 0.5)
			(thermal_bridge_width 0.5)
			(island_removal_mode 0)
		)
		(polygon
			(pts
				(xy 152.670764 -129.2606) (xy 152.670764 -129.684272) (xy 152.877012 -129.89052) (xy 153.000964 -129.89052)
				(xy 153.108152 -129.997708) (xy 153.108152 -130.674872) (xy 153.042112 -130.740912) (xy 152.843992 -130.740912)
				(xy 152.670764 -130.91414) (xy 152.029922 -130.91414) (xy 151.7904 -131.153662) (xy 151.7904 -131.742434)
				(xy 151.936196 -131.88823) (xy 152.373584 -131.88823) (xy 152.522174 -131.73964) (xy 152.522174 -131.450588)
				(xy 152.786334 -131.186428) (xy 153.982928 -131.186428) (xy 154.25547 -131.45897) (xy 154.25547 -134.4803)
				(xy 153.842974 -134.892796) (xy 152.744932 -134.892796) (xy 152.563322 -135.074406) (xy 152.563322 -139.168632)
				(xy 153.042112 -139.647422) (xy 153.042112 -140.373862) (xy 152.843992 -140.571982) (xy 152.03805 -140.571982)
				(xy 151.7904 -140.819632) (xy 151.7904 -141.46657) (xy 151.89454 -141.57071) (xy 152.464262 -141.57071)
				(xy 152.598628 -141.705076) (xy 152.598628 -145.737072) (xy 152.588214 -145.747486) (xy 152.588214 -148.871686)
				(xy 152.590246 -148.873718) (xy 152.994614 -149.278086) (xy 152.994614 -149.533864) (xy 152.746964 -149.781514)
				(xy 152.228042 -149.781514) (xy 151.7904 -150.219156) (xy 151.7904 -151.058118) (xy 151.853646 -151.121364)
				(xy 152.315672 -151.121364) (xy 152.480772 -150.956264) (xy 152.480772 -150.683976) (xy 152.835864 -150.328884)
				(xy 153.975054 -150.328884) (xy 154.371294 -150.725124) (xy 154.371294 -153.59761) (xy 153.925524 -154.04338)
				(xy 153.298144 -154.04338) (xy 152.662382 -154.679142) (xy 152.662382 -158.23311) (xy 152.976072 -158.5468)
				(xy 161.6964 -158.5468) (xy 163.703 -156.5402) (xy 163.703 -143.6751) (xy 163.9697 -143.4084) (xy 163.9951 -143.383)
				(xy 167.3225 -143.383) (xy 167.7924 -143.383) (xy 168.001696 -143.173704) (xy 168.001696 -143.1544)
				(xy 168.3512 -142.804896) (xy 168.3512 -134.334758) (xy 168.8592 -133.826504) (xy 168.8592 -133.121654)
				(xy 168.929304 -133.05155) (xy 169.634408 -133.05155) (xy 170.307 -132.378958) (xy 170.307 -131.6736)
				(xy 170.2562 -131.6228) (xy 169.9006 -131.6228) (xy 169.7736 -131.6228) (xy 169.7228 -131.6736)
				(xy 169.7228 -131.8006) (xy 169.4434 -132.08) (xy 168.7068 -132.08) (xy 168.656 -132.1308) (xy 168.656 -132.3086)
				(xy 168.270174 -132.694426) (xy 168.168574 -132.694426) (xy 167.213534 -132.694426) (xy 164.2872 -132.694426)
				(xy 164.10559 -132.512816) (xy 163.8808 -132.288026) (xy 163.8808 -128.6256) (xy 163.0934 -127.8382)
				(xy 162.0012 -126.746) (xy 157.0482 -126.746) (xy 155.6004 -125.2982) (xy 152.146 -125.2982) (xy 151.8666 -125.5776)
				(xy 151.8666 -128.456436)
			)
		)
	)
	(zone
		(layer "F.Cu")
		(hatch none 0.5)
		(connect_pads
			(clearance 0)
		)
		(min_thickness 0.25)
		(keepout
			(tracks allowed)
			(vias allowed)
			(pads allowed)
			(copperpour allowed)
			(footprints allowed)
		)
		(placement
			(enabled no)
			(sheetname "")
		)
		(fill
			(thermal_gap 0.5)
			(thermal_bridge_width 0.5)
			(island_removal_mode 0)
		)
		(polygon
			(pts
				(xy 16.958056 -46.969934) (xy 19.177508 -46.969934) (xy 19.287998 -46.859444) (xy 19.287998 -45.390308)
				(xy 19.01952 -45.12183) (xy 17.977104 -45.12183) (xy 17.779492 -45.319442) (xy 17.779492 -45.62729)
				(xy 17.297654 -46.109128) (xy 16.958056 -46.109128) (xy 16.737076 -46.330108) (xy 16.737076 -46.748954)
			)
		)
	)
	(zone
		(net "P1V8_PCH_STBY")
		(layer "F.Cu")
		(hatch none 0.5)
		(connect_pads
			(clearance 0.5)
		)
		(min_thickness 0.25)
		(fill yes
			(thermal_gap 0.5)
			(thermal_bridge_width 0.5)
			(island_removal_mode 0)
		)
		(polygon
			(pts
				(xy 403.96795 -141.150848) (xy 403.929088 -141.18971) (xy 403.929088 -144.190466) (xy 403.586442 -144.533112)
				(xy 403.586442 -145.530316) (xy 403.34692 -145.769838) (xy 401.780756 -145.769838) (xy 401.609052 -145.941542)
				(xy 401.609052 -148.209762) (xy 401.65909 -148.2598) (xy 402.89988 -148.2598) (xy 402.89988 -147.52955)
				(xy 403.039834 -147.389596) (xy 404.515066 -147.389596) (xy 405.771096 -146.133566) (xy 405.771096 -145.334228)
				(xy 406.444196 -144.661128) (xy 406.444196 -141.33068) (xy 406.264364 -141.150848)
			)
		)
		(polygon
			(pts
				(xy 404.57628 -144.603216) (xy 404.37308 -144.603216) (xy 404.37308 -144.806416) (xy 404.57628 -144.806416)
			)
		)
		(polygon
			(pts
				(xy 404.57628 -145.365216) (xy 404.37308 -145.365216) (xy 404.37308 -145.568416) (xy 404.57628 -145.568416)
			)
		)
	)
	(zone
		(layer "F.Cu")
		(hatch none 0.5)
		(connect_pads
			(clearance 0)
		)
		(min_thickness 0.25)
		(keepout
			(tracks allowed)
			(vias allowed)
			(pads allowed)
			(copperpour allowed)
			(footprints allowed)
		)
		(placement
			(enabled no)
			(sheetname "")
		)
		(fill
			(thermal_gap 0.5)
			(thermal_bridge_width 0.5)
			(island_removal_mode 0)
		)
		(polygon
			(pts
				(xy 478.77222 -43.42892) (xy 478.77222 -42.6974) (xy 480.42068 -42.6974) (xy 480.42068 -43.42892)
			)
		)
	)
	(zone
		(layer "F.Cu")
		(hatch none 0.5)
		(connect_pads
			(clearance 0)
		)
		(min_thickness 0.25)
		(keepout
			(tracks not_allowed)
			(vias allowed)
			(pads allowed)
			(copperpour not_allowed)
			(footprints allowed)
		)
		(placement
			(enabled no)
			(sheetname "")
		)
		(fill
			(thermal_gap 0.5)
			(thermal_bridge_width 0.5)
			(island_removal_mode 0)
		)
		(polygon
			(pts
				(xy 456.149202 -114.020092) (xy 456.149202 -114.2873) (xy 455.96302 -114.473482)
				(arc
					(start 455.822304 -114.473482)
					(mid 455.298387 -114.403632)
					(end 455.822304 -114.333782)
				)
				(xy 455.905108 -114.333782) (xy 456.009502 -114.229388) (xy 456.009502 -114.020092)
				(arc
					(start 455.565256 -114.020092)
					(mid 455.181462 -114.403505)
					(end 455.565002 -114.787172)
				)
				(arc
					(start 456.835002 -114.787172)
					(mid 457.218542 -114.403632)
					(end 456.835002 -114.020092)
				)
				(xy 456.390502 -114.020092) (xy 456.390502 -114.229388) (xy 456.494896 -114.333782)
				(arc
					(start 456.5777 -114.333782)
					(mid 457.101617 -114.403632)
					(end 456.5777 -114.473482)
				)
				(xy 456.436984 -114.473482) (xy 456.250802 -114.2873) (xy 456.250802 -114.020092)
			)
		)
	)
	(zone
		(layer "F.Cu")
		(hatch none 0.5)
		(connect_pads
			(clearance 0)
		)
		(min_thickness 0.25)
		(keepout
			(tracks allowed)
			(vias allowed)
			(pads allowed)
			(copperpour allowed)
			(footprints not_allowed)
		)
		(placement
			(enabled no)
			(sheetname "")
		)
		(fill
			(thermal_gap 0.5)
			(thermal_bridge_width 0.5)
			(island_removal_mode 0)
		)
		(polygon
			(pts
				(arc
					(start 228.499924 -42.800016)
					(mid 227.085713 -43.385801)
					(end 226.499928 -44.800012)
				)
				(arc
					(start 226.499928 -52.178712)
					(mid 226.576048 -52.561395)
					(end 226.79279 -52.885848)
				)
				(arc
					(start 227.9142 -54.007004)
					(mid 228.347763 -54.655878)
					(end 228.499924 -55.421276)
				)
				(arc
					(start 228.499924 -58.799984)
					(mid 228.133827 -59.683821)
					(end 227.24999 -60.049918)
				)
				(arc
					(start 227.24999 -60.049918)
					(mid 227.073243 -60.123287)
					(end 227.000054 -60.300108)
				)
				(arc
					(start 227.000054 -92.799916)
					(mid 227.073153 -92.976901)
					(end 227.24999 -93.050106)
				)
				(arc
					(start 227.24999 -93.050106)
					(mid 228.133827 -93.416203)
					(end 228.499924 -94.30004)
				)
				(arc
					(start 228.499924 -97.678748)
					(mid 228.347703 -98.444016)
					(end 227.9142 -99.092766)
				)
				(arc
					(start 226.79279 -100.214176)
					(mid 226.576008 -100.538613)
					(end 226.499928 -100.921312)
				)
				(arc
					(start 226.499928 -108.300012)
					(mid 227.085713 -109.714223)
					(end 228.499924 -110.300008)
				)
				(arc
					(start 234.153964 -110.300008)
					(mid 234.496009 -110.239692)
					(end 234.796838 -110.066074)
				)
				(arc
					(start 238.131604 -107.26801)
					(mid 238.733084 -106.920639)
					(end 239.417098 -106.799888)
				)
				(arc
					(start 300.582838 -106.799888)
					(mid 301.266971 -106.920613)
					(end 301.868586 -107.26801)
				)
				(arc
					(start 305.203098 -110.066074)
					(mid 305.503903 -110.23976)
					(end 305.845972 -110.300008)
				)
				(arc
					(start 311.500012 -110.300008)
					(mid 312.914223 -109.714223)
					(end 313.500008 -108.300012)
				)
				(arc
					(start 313.500008 -100.921312)
					(mid 313.423888 -100.538629)
					(end 313.207146 -100.214176)
				)
				(arc
					(start 312.085736 -99.092766)
					(mid 311.65225 -98.444009)
					(end 311.500012 -97.678748)
				)
				(arc
					(start 311.500012 -96.0501)
					(mid 313.110869 -92.16102)
					(end 316.999874 -90.549984)
				)
				(arc
					(start 322.749926 -90.549984)
					(mid 324.164137 -91.135769)
					(end 324.749922 -92.54998)
				)
				(arc
					(start 324.749922 -112.799876)
					(mid 323.724925 -115.274819)
					(end 321.250056 -116.299996)
				)
				(arc
					(start 218.74988 -116.299996)
					(mid 216.275175 -115.274729)
					(end 215.250014 -112.799876)
				)
				(arc
					(start 215.250014 -40.299894)
					(mid 216.275101 -37.825115)
					(end 218.74988 -36.800028)
				)
				(xy 320.457068 -36.800028) (xy 324.749922 -41.092882)
				(arc
					(start 324.749922 -60.550044)
					(mid 324.164137 -61.964255)
					(end 322.749926 -62.55004)
				)
				(arc
					(start 316.999874 -62.55004)
					(mid 313.110959 -60.938988)
					(end 311.500012 -57.049924)
				)
				(arc
					(start 311.500012 -55.421276)
					(mid 311.652253 -54.655911)
					(end 312.085736 -54.007004)
				)
				(arc
					(start 313.207146 -52.885848)
					(mid 313.423928 -52.561411)
					(end 313.500008 -52.178712)
				)
				(arc
					(start 313.500008 -44.800012)
					(mid 312.914223 -43.385801)
					(end 311.500012 -42.800016)
				)
				(arc
					(start 305.845972 -42.800016)
					(mid 305.503927 -42.860332)
					(end 305.203098 -43.03395)
				)
				(arc
					(start 301.868586 -45.832014)
					(mid 301.266954 -46.179265)
					(end 300.582838 -46.299882)
				)
				(arc
					(start 239.417098 -46.299882)
					(mid 238.73311 -46.17927)
					(end 238.131604 -45.832014)
				)
				(arc
					(start 234.796838 -43.03395)
					(mid 234.496033 -42.860264)
					(end 234.153964 -42.800016)
				)
			)
		)
	)
	(zone
		(net "GND")
		(layer "F.Cu")
		(hatch none 0.5)
		(connect_pads
			(clearance 0.5)
		)
		(min_thickness 0.25)
		(fill yes
			(thermal_gap 0.5)
			(thermal_bridge_width 0.5)
			(island_removal_mode 0)
		)
		(polygon
			(pts
				(xy 107.02036 -80.5942) (xy 107.014264 -80.600296) (xy 96.561656 -80.600296) (xy 96.561656 -81.464912)
				(xy 96.790256 -81.693512) (xy 96.790256 -82.720688) (xy 96.949768 -82.8802) (xy 97.610168 -82.8802)
				(xy 97.889568 -83.1596) (xy 97.889568 -83.5406) (xy 98.168968 -83.82) (xy 102.639368 -83.82) (xy 102.791768 -83.9724)
				(xy 109.014768 -83.9724) (xy 109.725968 -83.2612) (xy 114.272568 -83.2612) (xy 115.085368 -82.4484)
				(xy 115.085368 -80.7212) (xy 114.958368 -80.5942)
			)
		)
		(polygon
			(pts
				(xy 108.96981 -82.947002) (xy 108.76661 -82.947002) (xy 108.76661 -83.150202) (xy 108.96981 -83.150202)
			)
		)
		(polygon
			(pts
				(xy 108.20781 -82.947002) (xy 108.00461 -82.947002) (xy 108.00461 -83.150202) (xy 108.20781 -83.150202)
			)
		)
		(polygon
			(pts
				(xy 107.723178 -82.947002) (xy 107.519978 -82.947002) (xy 107.519978 -83.150202) (xy 107.723178 -83.150202)
			)
		)
		(polygon
			(pts
				(xy 106.961178 -82.947002) (xy 106.757978 -82.947002) (xy 106.757978 -83.150202) (xy 106.961178 -83.150202)
			)
		)
		(polygon
			(pts
				(xy 106.478578 -82.947002) (xy 106.275378 -82.947002) (xy 106.275378 -83.150202) (xy 106.478578 -83.150202)
			)
		)
		(polygon
			(pts
				(xy 105.716578 -82.947002) (xy 105.513378 -82.947002) (xy 105.513378 -83.150202) (xy 105.716578 -83.150202)
			)
		)
		(polygon
			(pts
				(xy 105.233978 -82.947002) (xy 105.030778 -82.947002) (xy 105.030778 -83.150202) (xy 105.233978 -83.150202)
			)
		)
		(polygon
			(pts
				(xy 104.471978 -82.947002) (xy 104.268778 -82.947002) (xy 104.268778 -83.150202) (xy 104.471978 -83.150202)
			)
		)
		(polygon
			(pts
				(xy 103.989378 -82.947002) (xy 103.786178 -82.947002) (xy 103.786178 -83.150202) (xy 103.989378 -83.150202)
			)
		)
		(polygon
			(pts
				(xy 103.227378 -82.947002) (xy 103.024178 -82.947002) (xy 103.024178 -83.150202) (xy 103.227378 -83.150202)
			)
		)
		(polygon
			(pts
				(xy 102.740968 -82.8167) (xy 102.537768 -82.8167) (xy 102.537768 -83.0199) (xy 102.740968 -83.0199)
			)
		)
		(polygon
			(pts
				(xy 101.978968 -82.8167) (xy 101.775768 -82.8167) (xy 101.775768 -83.0199) (xy 101.978968 -83.0199)
			)
		)
		(polygon
			(pts
				(xy 101.496368 -82.8167) (xy 101.293168 -82.8167) (xy 101.293168 -83.0199) (xy 101.496368 -83.0199)
			)
		)
		(polygon
			(pts
				(xy 100.734368 -82.8167) (xy 100.531168 -82.8167) (xy 100.531168 -83.0199) (xy 100.734368 -83.0199)
			)
		)
		(polygon
			(pts
				(xy 100.251768 -82.8167) (xy 100.048568 -82.8167) (xy 100.048568 -83.0199) (xy 100.251768 -83.0199)
			)
		)
		(polygon
			(pts
				(xy 99.489768 -82.8167) (xy 99.286568 -82.8167) (xy 99.286568 -83.0199) (xy 99.489768 -83.0199)
			)
		)
		(polygon
			(pts
				(xy 99.007168 -82.7659) (xy 98.803968 -82.7659) (xy 98.803968 -82.9691) (xy 99.007168 -82.9691)
			)
		)
		(polygon
			(pts
				(xy 98.245168 -82.7659) (xy 98.041968 -82.7659) (xy 98.041968 -82.9691) (xy 98.245168 -82.9691)
			)
		)
		(polygon
			(pts
				(xy 97.615502 -81.89849) (xy 97.412302 -81.89849) (xy 97.412302 -82.10169) (xy 97.615502 -82.10169)
			)
		)
		(polygon
			(pts
				(xy 114.323368 -81.3435) (xy 114.120168 -81.3435) (xy 114.120168 -81.5467) (xy 114.323368 -81.5467)
			)
		)
		(polygon
			(pts
				(xy 113.815368 -81.3435) (xy 113.612168 -81.3435) (xy 113.612168 -81.5467) (xy 113.815368 -81.5467)
			)
		)
		(polygon
			(pts
				(xy 113.053368 -81.3435) (xy 112.850168 -81.3435) (xy 112.850168 -81.5467) (xy 113.053368 -81.5467)
			)
		)
		(polygon
			(pts
				(xy 112.545368 -81.3435) (xy 112.342168 -81.3435) (xy 112.342168 -81.5467) (xy 112.545368 -81.5467)
			)
		)
		(polygon
			(pts
				(xy 111.783368 -81.3435) (xy 111.580168 -81.3435) (xy 111.580168 -81.5467) (xy 111.783368 -81.5467)
			)
		)
		(polygon
			(pts
				(xy 111.275368 -81.3435) (xy 111.072168 -81.3435) (xy 111.072168 -81.5467) (xy 111.275368 -81.5467)
			)
		)
		(polygon
			(pts
				(xy 110.513368 -81.3435) (xy 110.310168 -81.3435) (xy 110.310168 -81.5467) (xy 110.513368 -81.5467)
			)
		)
		(polygon
			(pts
				(xy 110.005368 -81.3435) (xy 109.802168 -81.3435) (xy 109.802168 -81.5467) (xy 110.005368 -81.5467)
			)
		)
		(polygon
			(pts
				(xy 109.243368 -81.3435) (xy 109.040168 -81.3435) (xy 109.040168 -81.5467) (xy 109.243368 -81.5467)
			)
		)
		(polygon
			(pts
				(xy 108.735368 -81.3435) (xy 108.532168 -81.3435) (xy 108.532168 -81.5467) (xy 108.735368 -81.5467)
			)
		)
		(polygon
			(pts
				(xy 107.973368 -81.3435) (xy 107.770168 -81.3435) (xy 107.770168 -81.5467) (xy 107.973368 -81.5467)
			)
		)
		(polygon
			(pts
				(xy 107.465368 -81.3435) (xy 107.262168 -81.3435) (xy 107.262168 -81.5467) (xy 107.465368 -81.5467)
			)
		)
		(polygon
			(pts
				(xy 106.703368 -81.3435) (xy 106.500168 -81.3435) (xy 106.500168 -81.5467) (xy 106.703368 -81.5467)
			)
		)
		(polygon
			(pts
				(xy 106.195368 -81.3435) (xy 105.992168 -81.3435) (xy 105.992168 -81.5467) (xy 106.195368 -81.5467)
			)
		)
		(polygon
			(pts
				(xy 105.433368 -81.3435) (xy 105.230168 -81.3435) (xy 105.230168 -81.5467) (xy 105.433368 -81.5467)
			)
		)
		(polygon
			(pts
				(xy 104.925368 -81.3435) (xy 104.722168 -81.3435) (xy 104.722168 -81.5467) (xy 104.925368 -81.5467)
			)
		)
		(polygon
			(pts
				(xy 104.163368 -81.3435) (xy 103.960168 -81.3435) (xy 103.960168 -81.5467) (xy 104.163368 -81.5467)
			)
		)
		(polygon
			(pts
				(xy 103.655368 -81.3435) (xy 103.452168 -81.3435) (xy 103.452168 -81.5467) (xy 103.655368 -81.5467)
			)
		)
		(polygon
			(pts
				(xy 102.893368 -81.3435) (xy 102.690168 -81.3435) (xy 102.690168 -81.5467) (xy 102.893368 -81.5467)
			)
		)
		(polygon
			(pts
				(xy 102.410768 -81.3435) (xy 102.207568 -81.3435) (xy 102.207568 -81.5467) (xy 102.410768 -81.5467)
			)
		)
		(polygon
			(pts
				(xy 101.648768 -81.3435) (xy 101.445568 -81.3435) (xy 101.445568 -81.5467) (xy 101.648768 -81.5467)
			)
		)
		(polygon
			(pts
				(xy 101.166168 -81.3435) (xy 100.962968 -81.3435) (xy 100.962968 -81.5467) (xy 101.166168 -81.5467)
			)
		)
		(polygon
			(pts
				(xy 100.404168 -81.3435) (xy 100.200968 -81.3435) (xy 100.200968 -81.5467) (xy 100.404168 -81.5467)
			)
		)
		(polygon
			(pts
				(xy 99.921568 -81.3435) (xy 99.718368 -81.3435) (xy 99.718368 -81.5467) (xy 99.921568 -81.5467)
			)
		)
		(polygon
			(pts
				(xy 99.159568 -81.3435) (xy 98.956368 -81.3435) (xy 98.956368 -81.5467) (xy 99.159568 -81.5467)
			)
		)
		(polygon
			(pts
				(xy 98.676968 -81.3435) (xy 98.473768 -81.3435) (xy 98.473768 -81.5467) (xy 98.676968 -81.5467)
			)
		)
		(polygon
			(pts
				(xy 97.914968 -81.3435) (xy 97.711768 -81.3435) (xy 97.711768 -81.5467) (xy 97.914968 -81.5467)
			)
		)
		(polygon
			(pts
				(xy 97.432368 -81.3435) (xy 97.229168 -81.3435) (xy 97.229168 -81.5467) (xy 97.432368 -81.5467)
			)
		)
	)
	(zone
		(layer "F.Cu")
		(hatch none 0.5)
		(connect_pads
			(clearance 0)
		)
		(min_thickness 0.25)
		(keepout
			(tracks not_allowed)
			(vias allowed)
			(pads allowed)
			(copperpour not_allowed)
			(footprints allowed)
		)
		(placement
			(enabled no)
			(sheetname "")
		)
		(fill
			(thermal_gap 0.5)
			(thermal_bridge_width 0.5)
			(island_removal_mode 0)
		)
		(polygon
			(pts
				(arc
					(start 11.84275 -25.085802)
					(mid 11.9126 -24.561885)
					(end 11.98245 -25.085802)
				)
				(xy 11.98245 -25.199594) (xy 12.055856 -25.273) (xy 12.29614 -25.273)
				(arc
					(start 12.29614 -24.8285)
					(mid 11.9126 -24.44496)
					(end 11.52906 -24.8285)
				)
				(arc
					(start 11.52906 -26.098246)
					(mid 11.912473 -26.48204)
					(end 12.29614 -26.0985)
				)
				(xy 12.29614 -25.654) (xy 12.055856 -25.654) (xy 11.98245 -25.727406)
				(arc
					(start 11.98245 -25.841198)
					(mid 11.9126 -26.365115)
					(end 11.84275 -25.841198)
				)
				(xy 11.84275 -25.669494) (xy 11.997944 -25.5143) (xy 12.29614 -25.5143) (xy 12.29614 -25.4127) (xy 11.997944 -25.4127)
				(xy 11.84275 -25.257506)
			)
		)
	)
	(zone
		(layer "F.Cu")
		(hatch none 0.5)
		(connect_pads
			(clearance 0)
		)
		(min_thickness 0.25)
		(keepout
			(tracks allowed)
			(vias allowed)
			(pads allowed)
			(copperpour allowed)
			(footprints allowed)
		)
		(placement
			(enabled no)
			(sheetname "")
		)
		(fill
			(thermal_gap 0.5)
			(thermal_bridge_width 0.5)
			(island_removal_mode 0)
		)
		(polygon
			(pts
				(xy 195.326 -69.469) (xy 198.882 -69.469) (xy 199.136 -69.723) (xy 199.136 -71.247) (xy 198.755 -71.628)
				(xy 196.977 -71.628) (xy 196.85 -71.755) (xy 196.85 -74.295) (xy 196.723 -74.422) (xy 195.072 -74.422)
				(xy 194.818 -74.168) (xy 194.31 -73.66) (xy 194.31 -69.977) (xy 194.818 -69.469)
			)
		)
	)
	(zone
		(layer "F.Cu")
		(hatch none 0.5)
		(connect_pads
			(clearance 0)
		)
		(min_thickness 0.25)
		(keepout
			(tracks allowed)
			(vias allowed)
			(pads allowed)
			(copperpour allowed)
			(footprints allowed)
		)
		(placement
			(enabled no)
			(sheetname "")
		)
		(fill
			(thermal_gap 0.5)
			(thermal_bridge_width 0.5)
			(island_removal_mode 0)
		)
		(polygon
			(pts
				(xy 11.811 -2.286) (xy 11.811 -0.762) (xy 14.478 -0.762) (xy 14.478 -2.286)
			)
		)
	)
	(zone
		(net "P3V3_DB1200_R")
		(layer "F.Cu")
		(hatch none 0.5)
		(connect_pads
			(clearance 0.5)
		)
		(min_thickness 0.25)
		(fill yes
			(thermal_gap 0.5)
			(thermal_bridge_width 0.5)
			(island_removal_mode 0)
		)
		(polygon
			(pts
				(xy 168.783 -74.7776) (xy 168.783 -75.2602) (xy 168.8338 -75.311) (xy 168.8338 -75.819) (xy 169.0116 -75.9968)
				(xy 169.0116 -76.9112) (xy 169.0878 -76.9874) (xy 169.2148 -76.9874) (xy 169.3164 -76.8858) (xy 169.3164 -75.9206)
				(xy 169.315892 -75.920092) (xy 169.346626 -75.889358) (xy 169.346626 -74.11974) (xy 169.287952 -74.061066)
				(xy 169.287952 -73.504552) (xy 169.131742 -73.348342) (xy 168.586658 -73.348342) (xy 168.4782 -73.4568)
				(xy 168.4782 -74.4728)
			)
		)
	)
	(zone
		(layer "F.Cu")
		(hatch none 0.5)
		(connect_pads
			(clearance 0)
		)
		(min_thickness 0.25)
		(keepout
			(tracks allowed)
			(vias allowed)
			(pads allowed)
			(copperpour allowed)
			(footprints allowed)
		)
		(placement
			(enabled no)
			(sheetname "")
		)
		(fill
			(thermal_gap 0.5)
			(thermal_bridge_width 0.5)
			(island_removal_mode 0)
		)
		(polygon
			(pts
				(xy 107.033568 -99.822) (xy 111.478568 -99.822) (xy 112.494568 -100.838) (xy 112.494568 -102.489)
				(xy 112.494568 -103.4542) (xy 112.494568 -103.759) (xy 112.494568 -104.14) (xy 106.271568 -104.14)
				(xy 106.271568 -103.759) (xy 106.271568 -99.822)
			)
		)
	)
	(zone
		(layer "F.Cu")
		(hatch none 0.5)
		(connect_pads
			(clearance 0)
		)
		(min_thickness 0.25)
		(keepout
			(tracks allowed)
			(vias allowed)
			(pads allowed)
			(copperpour allowed)
			(footprints allowed)
		)
		(placement
			(enabled no)
			(sheetname "")
		)
		(fill
			(thermal_gap 0.5)
			(thermal_bridge_width 0.5)
			(island_removal_mode 0)
		)
		(polygon
			(pts
				(xy 2.5908 -16.129) (xy 2.5908 -18.1356) (xy 2.5908 -19.1008) (xy 2.2352 -19.4564) (xy 0.6858 -19.4564)
				(xy 0.3048 -19.0754) (xy 0.3048 -16.129) (xy 1.651 -14.7828) (xy 1.651 -14.1478) (xy 2.286 -13.5128)
				(xy 5.08 -13.5128) (xy 5.08 -15.0368) (xy 4.826 -15.2908) (xy 2.794 -15.2908) (xy 2.667 -15.4178)
				(xy 2.667 -16.0528)
			)
		)
	)
	(zone
		(net "PVCCIOMCP_CPU0")
		(layer "F.Cu")
		(hatch none 0.5)
		(connect_pads
			(clearance 0.5)
		)
		(min_thickness 0.25)
		(fill yes
			(thermal_gap 0.5)
			(thermal_bridge_width 0.5)
			(island_removal_mode 0)
		)
		(polygon
			(pts
				(xy 346.369132 -108.331) (xy 353.10064 -108.331) (xy 353.3394 -108.56976) (xy 353.3394 -110.5408)
				(xy 352.7552 -111.125) (xy 352.7552 -113.1951) (xy 352.5901 -113.3602) (xy 352.077782 -113.3602)
				(xy 351.98304 -113.265458) (xy 351.651824 -113.265458) (xy 351.557082 -113.3602) (xy 350.760284 -113.3602)
				(xy 350.694244 -113.29416) (xy 350.397826 -113.29416) (xy 350.331786 -113.3602) (xy 349.7326 -113.3602)
				(xy 349.5548 -113.1824) (xy 349.5548 -112.84458) (xy 349.6818 -112.71758) (xy 349.800926 -112.598454)
				(xy 349.800926 -112.099598) (xy 349.6818 -111.980472) (xy 348.863666 -111.162338) (xy 348.34322 -111.162338)
				(xy 348.267782 -111.237776) (xy 348.093792 -111.411766) (xy 347.846142 -111.411766) (xy 347.703648 -111.269272)
				(xy 347.605858 -111.171482) (xy 347.2307 -111.171482) (xy 347.147896 -111.171482) (xy 346.877132 -111.442246)
				(xy 346.637864 -111.442246) (xy 346.590112 -111.394494) (xy 346.590112 -108.956856) (xy 346.315792 -108.682536)
				(xy 346.315792 -108.38434)
			)
		)
	)
	(zone
		(layer "F.Cu")
		(hatch none 0.5)
		(connect_pads
			(clearance 0)
		)
		(min_thickness 0.25)
		(keepout
			(tracks allowed)
			(vias allowed)
			(pads allowed)
			(copperpour allowed)
			(footprints not_allowed)
		)
		(placement
			(enabled no)
			(sheetname "")
		)
		(fill
			(thermal_gap 0.5)
			(thermal_bridge_width 0.5)
			(island_removal_mode 0)
		)
		(polygon
			(pts
				(arc
					(start 37.47008 -46.550072)
					(mid 33.920176 -50.099976)
					(end 30.370018 -46.550072)
				)
				(arc
					(start 30.370018 -46.550072)
					(mid 33.920176 -42.999914)
					(end 37.47008 -46.550072)
				)
			)
		)
	)
	(zone
		(layer "F.Cu")
		(hatch none 0.5)
		(connect_pads
			(clearance 0)
		)
		(min_thickness 0.25)
		(keepout
			(tracks allowed)
			(vias allowed)
			(pads allowed)
			(copperpour allowed)
			(footprints allowed)
		)
		(placement
			(enabled no)
			(sheetname "")
		)
		(fill
			(thermal_gap 0.5)
			(thermal_bridge_width 0.5)
			(island_removal_mode 0)
		)
		(polygon
			(pts
				(xy 29.083 -99.06) (xy 29.083 -95.504) (xy 31.242 -95.504) (xy 31.242 -99.06)
			)
		)
	)
	(zone
		(layer "F.Cu")
		(hatch none 0.5)
		(connect_pads
			(clearance 0)
		)
		(min_thickness 0.25)
		(keepout
			(tracks allowed)
			(vias allowed)
			(pads allowed)
			(copperpour allowed)
			(footprints allowed)
		)
		(placement
			(enabled no)
			(sheetname "")
		)
		(fill
			(thermal_gap 0.5)
			(thermal_bridge_width 0.5)
			(island_removal_mode 0)
		)
		(polygon
			(pts
				(xy 396.21714 -66.3956) (xy 396.21714 -65.15608) (xy 396.22222 -65.15608) (xy 396.22222 -64.95034)
				(xy 396.74292 -64.95034) (xy 396.74292 -66.26606) (xy 396.74292 -66.3956)
			)
		)
	)
	(zone
		(net "P12V_FAN")
		(layer "F.Cu")
		(hatch none 0.5)
		(connect_pads
			(clearance 0.5)
		)
		(min_thickness 0.25)
		(fill yes
			(thermal_gap 0.5)
			(thermal_bridge_width 0.5)
			(island_removal_mode 0)
		)
		(polygon
			(pts
				(xy 26.70048 -34.7472) (xy 29.21508 -34.7472) (xy 29.7815 -35.31362) (xy 31.8516 -35.31362) (xy 32.29356 -35.75558)
				(xy 32.29356 -40.36314) (xy 32.29356 -41.37152) (xy 31.58744 -42.07764) (xy 31.55315 -42.11193)
				(xy 29.381704 -42.11193) (xy 29.347414 -42.07764) (xy 29.251656 -41.981882) (xy 27.9527 -41.981882)
				(xy 27.937714 -41.996868) (xy 26.784808 -41.996868) (xy 26.67762 -41.88968) (xy 26.377646 -41.589706)
				(xy 26.377646 -35.070034)
			)
		)
	)
	(zone
		(layer "F.Cu")
		(hatch none 0.5)
		(connect_pads
			(clearance 0)
		)
		(min_thickness 0.25)
		(keepout
			(tracks allowed)
			(vias allowed)
			(pads allowed)
			(copperpour allowed)
			(footprints allowed)
		)
		(placement
			(enabled no)
			(sheetname "")
		)
		(fill
			(thermal_gap 0.5)
			(thermal_bridge_width 0.5)
			(island_removal_mode 0)
		)
		(polygon
			(pts
				(xy 304.927 -100.457) (xy 306.197 -100.457) (xy 306.197 -101.092) (xy 304.165 -103.124) (xy 302.133 -103.124)
				(xy 301.879 -102.87) (xy 301.752 -102.87) (xy 301.752 -102.362) (xy 303.149 -100.965) (xy 304.419 -100.965)
			)
		)
	)
	(zone
		(layer "F.Cu")
		(hatch none 0.5)
		(connect_pads
			(clearance 0)
		)
		(min_thickness 0.25)
		(keepout
			(tracks not_allowed)
			(vias allowed)
			(pads allowed)
			(copperpour not_allowed)
			(footprints allowed)
		)
		(placement
			(enabled no)
			(sheetname "")
		)
		(fill
			(thermal_gap 0.5)
			(thermal_bridge_width 0.5)
			(island_removal_mode 0)
		)
		(polygon
			(pts
				(xy 421.68445 -2.97434) (xy 421.68445 -2.726944) (xy 421.902128 -2.509266)
				(arc
					(start 421.98544 -2.509266)
					(mid 422.509357 -2.579116)
					(end 421.98544 -2.648966)
				)
				(xy 421.96004 -2.648966) (xy 421.82415 -2.784856) (xy 421.82415 -2.971546)
				(arc
					(start 422.250362 -2.962656)
					(mid 422.626279 -2.571369)
					(end 422.234868 -2.195576)
				)
				(arc
					(start 420.963852 -2.221992)
					(mid 420.588186 -2.613406)
					(end 420.9796 -2.989072)
				)
				(xy 421.44315 -2.97942) (xy 421.44315 -2.822702) (xy 421.29583 -2.675382)
				(arc
					(start 421.229028 -2.675382)
					(mid 420.705111 -2.605532)
					(end 421.229028 -2.535682)
				)
				(xy 421.353742 -2.535682) (xy 421.58285 -2.76479) (xy 421.58285 -2.976626)
			)
		)
	)
	(zone
		(net "VR_FET_SW_P12V_STBY_PVDDQ_GHJ")
		(layer "F.Cu")
		(hatch none 0.5)
		(connect_pads
			(clearance 0.5)
		)
		(min_thickness 0.25)
		(fill yes
			(thermal_gap 0.5)
			(thermal_bridge_width 0.5)
			(island_removal_mode 0)
		)
		(polygon
			(pts
				(xy 2.911856 -17.836642) (xy 4.66852 -17.836642) (xy 4.66852 -17.848072) (xy 4.78155 -17.961102)
				(xy 4.78155 -20.814792) (xy 4.771644 -20.824444) (xy 4.771644 -22.914356) (xy 4.6482 -23.0378) (xy 1.0668 -23.0378)
				(xy 0.520192 -22.491192) (xy 0.520192 -20.573746) (xy 0.520192 -19.66087) (xy 0.578104 -19.602958)
				(xy 1.091946 -19.602958) (xy 1.249172 -19.445732) (xy 2.684526 -19.445732) (xy 2.791968 -19.33829)
				(xy 2.791968 -17.95653)
			)
		)
	)
	(zone
		(layer "F.Cu")
		(hatch none 0.5)
		(connect_pads
			(clearance 0)
		)
		(min_thickness 0.25)
		(keepout
			(tracks allowed)
			(vias allowed)
			(pads allowed)
			(copperpour allowed)
			(footprints not_allowed)
		)
		(placement
			(enabled no)
			(sheetname "")
		)
		(fill
			(thermal_gap 0.5)
			(thermal_bridge_width 0.5)
			(island_removal_mode 0)
		)
		(polygon
			(pts
				(arc
					(start 428.10049 -58.996834)
					(mid 431.700432 -55.396892)
					(end 435.300374 -58.996834)
				)
				(arc
					(start 435.300374 -60.59678)
					(mid 431.700432 -64.196722)
					(end 428.10049 -60.59678)
				)
			)
		)
	)
	(zone
		(net "PVPP_ABC")
		(layer "F.Cu")
		(hatch none 0.5)
		(connect_pads
			(clearance 0.5)
		)
		(min_thickness 0.25)
		(fill yes
			(thermal_gap 0.5)
			(thermal_bridge_width 0.5)
			(island_removal_mode 0)
		)
		(polygon
			(pts
				(xy 319.331848 4.699) (xy 319.278 4.645152) (xy 319.278 2.413) (xy 317.627 0.762) (xy 317.627 -2.466848)
				(xy 317.655956 -2.466848) (xy 318.109346 -2.920238) (xy 318.109346 -3.674364) (xy 317.962534 -3.821176)
				(xy 316.909704 -3.821176) (xy 316.738 -3.99288) (xy 316.738 -4.525518) (xy 316.911482 -4.699) (xy 317.411862 -4.699)
				(xy 317.5 -4.787138) (xy 317.5 -11.176) (xy 317.689738 -11.365738) (xy 317.689738 -12.139422) (xy 318.102742 -12.552426)
				(xy 318.102742 -13.339572) (xy 317.970408 -13.471906) (xy 316.973458 -13.471906) (xy 316.865 -13.580364)
				(xy 316.865 -14.078712) (xy 317.01613 -14.229842) (xy 319.029842 -14.229842) (xy 319.278 -14.478)
				(xy 319.278 -17.018) (xy 318.897 -17.399) (xy 318.516 -17.399) (xy 317.627 -18.288) (xy 317.627 -21.844)
				(xy 318.106298 -22.323298) (xy 318.106298 -23.186644) (xy 318.007238 -23.285704) (xy 316.908434 -23.285704)
				(xy 316.865 -23.329138) (xy 316.865 -25.527) (xy 317.589408 -26.251408) (xy 319.191132 -26.251408)
				(xy 320.092324 -27.1526) (xy 320.5226 -27.1526) (xy 320.9544 -26.7208) (xy 324.7898 -26.7208) (xy 325.628 -27.559)
				(xy 325.628 -28.7274) (xy 325.620126 -28.7274) (xy 325.34352 -29.004006) (xy 324.742556 -29.004006)
				(xy 323.8754 -28.13685) (xy 323.8754 -27.0002) (xy 323.8246 -26.9494) (xy 323.4182 -26.9494) (xy 323.3674 -27.0002)
				(xy 323.3674 -29.3878) (xy 323.7484 -29.7688) (xy 325.5518 -29.7688) (xy 327.406 -31.623) (xy 335.2546 -31.623)
				(xy 335.4324 -31.4452) (xy 335.4324 -26.416) (xy 335.1784 -26.162) (xy 334.64246 -26.162) (xy 334.122014 -25.641554)
				(xy 334.122014 -24.876252) (xy 334.391 -24.607266) (xy 334.391 -24.003) (xy 334.3656 -23.9776) (xy 334.3656 -22.2758)
				(xy 329.692 -17.6022) (xy 329.692 -16.764) (xy 326.136 -13.208) (xy 326.136 3.058922) (xy 325.886318 3.308604)
				(xy 324.673468 3.308604) (xy 324.406006 3.576066) (xy 324.406006 4.054348) (xy 323.761354 4.699)
			)
		)
		(polygon
			(pts
				(xy 333.3369 -25.5397) (xy 333.1337 -25.5397) (xy 333.1337 -25.7429) (xy 333.3369 -25.7429)
			)
		)
		(polygon
			(pts
				(xy 333.3369 -24.7777) (xy 333.1337 -24.7777) (xy 333.1337 -24.9809) (xy 333.3369 -24.9809)
			)
		)
		(polygon
			(pts
				(xy 319.851532 -23.019512) (xy 319.648332 -23.019512) (xy 319.648332 -23.222712) (xy 319.851532 -23.222712)
			)
		)
		(polygon
			(pts
				(xy 319.851532 -22.257512) (xy 319.648332 -22.257512) (xy 319.648332 -22.460712) (xy 319.851532 -22.460712)
			)
		)
		(polygon
			(pts
				(xy 319.089532 -22.257512) (xy 318.886332 -22.257512) (xy 318.886332 -22.460712) (xy 319.089532 -22.460712)
			)
		)
		(polygon
			(pts
				(xy 319.953132 -13.2334) (xy 319.749932 -13.2334) (xy 319.749932 -13.4366) (xy 319.953132 -13.4366)
			)
		)
		(polygon
			(pts
				(xy 319.089532 -13.2334) (xy 318.886332 -13.2334) (xy 318.886332 -13.4366) (xy 319.089532 -13.4366)
			)
		)
		(polygon
			(pts
				(xy 319.953132 -12.4714) (xy 319.749932 -12.4714) (xy 319.749932 -12.6746) (xy 319.953132 -12.6746)
			)
		)
		(polygon
			(pts
				(xy 319.089532 -12.4714) (xy 318.886332 -12.4714) (xy 318.886332 -12.6746) (xy 319.089532 -12.6746)
			)
		)
		(polygon
			(pts
				(xy 319.851532 -3.5814) (xy 319.648332 -3.5814) (xy 319.648332 -3.7846) (xy 319.851532 -3.7846)
			)
		)
		(polygon
			(pts
				(xy 319.089532 -3.5814) (xy 318.886332 -3.5814) (xy 318.886332 -3.7846) (xy 319.089532 -3.7846)
			)
		)
		(polygon
			(pts
				(xy 319.851532 -2.8194) (xy 319.648332 -2.8194) (xy 319.648332 -3.0226) (xy 319.851532 -3.0226)
			)
		)
		(polygon
			(pts
				(xy 319.089532 -2.8194) (xy 318.886332 -2.8194) (xy 318.886332 -3.0226) (xy 319.089532 -3.0226)
			)
		)
	)
	(zone
		(net "P12V_STBY")
		(layer "F.Cu")
		(hatch none 0.5)
		(connect_pads
			(clearance 0.5)
		)
		(min_thickness 0.25)
		(fill yes
			(thermal_gap 0.5)
			(thermal_bridge_width 0.5)
			(island_removal_mode 0)
		)
		(polygon
			(pts
				(xy 494.830608 -24.5999) (xy 497.8019 -24.5999) (xy 498.0432 -24.3586) (xy 498.0432 -24.0665) (xy 498.0432 -23.9014)
				(xy 498.0432 -23.4188) (xy 497.811044 -23.186644) (xy 497.336064 -23.186644) (xy 497.18849 -23.03907)
				(xy 497.18849 -21.64969) (xy 496.65636 -21.11756) (xy 495.695732 -21.11756) (xy 495.553492 -21.2598)
				(xy 494.2078 -21.2598) (xy 494.0554 -21.4122) (xy 491.3122 -21.4122) (xy 491.109 -21.6154) (xy 491.109 -23.6728)
				(xy 491.3757 -23.9395) (xy 492.0361 -24.5999)
			)
		)
	)
	(zone
		(layer "F.Cu")
		(hatch none 0.5)
		(connect_pads
			(clearance 0)
		)
		(min_thickness 0.25)
		(keepout
			(tracks allowed)
			(vias allowed)
			(pads allowed)
			(copperpour allowed)
			(footprints allowed)
		)
		(placement
			(enabled no)
			(sheetname "")
		)
		(fill
			(thermal_gap 0.5)
			(thermal_bridge_width 0.5)
			(island_removal_mode 0)
		)
		(polygon
			(pts
				(xy 73.85558 -45.928788) (xy 72.870568 -44.958) (xy 72.108568 -44.958) (xy 72.108568 -49.657) (xy 72.108568 -49.784)
				(xy 75.283568 -49.784) (xy 75.410568 -49.911) (xy 80.439768 -49.911) (xy 80.439768 -48.0822) (xy 78.204568 -45.847)
				(xy 78.077568 -45.847) (xy 78.077568 -45.928788) (xy 76.223368 -45.928788)
			)
		)
	)
	(zone
		(layer "F.Cu")
		(hatch none 0.5)
		(connect_pads
			(clearance 0)
		)
		(min_thickness 0.25)
		(keepout
			(tracks allowed)
			(vias allowed)
			(pads allowed)
			(copperpour allowed)
			(footprints not_allowed)
		)
		(placement
			(enabled no)
			(sheetname "")
		)
		(fill
			(thermal_gap 0.5)
			(thermal_bridge_width 0.5)
			(island_removal_mode 0)
		)
		(polygon
			(pts
				(arc
					(start 248.000012 -44.090082)
					(mid 245.460012 -41.550082)
					(end 248.000012 -39.010082)
				)
				(arc
					(start 248.000012 -39.010082)
					(mid 250.540012 -41.550082)
					(end 248.000012 -44.090082)
				)
			)
		)
	)
	(zone
		(layer "F.Cu")
		(hatch none 0.5)
		(connect_pads
			(clearance 0)
		)
		(min_thickness 0.25)
		(keepout
			(tracks allowed)
			(vias allowed)
			(pads allowed)
			(copperpour allowed)
			(footprints allowed)
		)
		(placement
			(enabled no)
			(sheetname "")
		)
		(fill
			(thermal_gap 0.5)
			(thermal_bridge_width 0.5)
			(island_removal_mode 0)
		)
		(polygon
			(pts
				(xy 192.405 -23.876) (xy 192.405 -22.987) (xy 193.294 -22.987) (xy 193.294 -23.876)
			)
		)
	)
	(zone
		(net "VR_P1V05_PCH_STBY_PH1_BOOT")
		(layer "F.Cu")
		(hatch none 0.5)
		(connect_pads
			(clearance 0.5)
		)
		(min_thickness 0.25)
		(fill yes
			(thermal_gap 0.5)
			(thermal_bridge_width 0.5)
			(island_removal_mode 0)
		)
		(polygon
			(pts
				(xy 387.275578 -158.524448) (xy 387.355334 -158.604204) (xy 389.585962 -158.604204) (xy 389.870696 -158.31947)
				(xy 389.870696 -157.286452) (xy 389.817356 -157.233112) (xy 389.386826 -157.233112) (xy 389.36422 -157.255718)
				(xy 389.36422 -157.786832) (xy 389.204708 -157.946344) (xy 388.40283 -157.946344) (xy 388.210298 -157.753812)
				(xy 387.328664 -157.753812) (xy 387.275578 -157.806898)
			)
		)
	)
	(zone
		(layer "F.Cu")
		(hatch none 0.5)
		(connect_pads
			(clearance 0)
		)
		(min_thickness 0.25)
		(keepout
			(tracks not_allowed)
			(vias allowed)
			(pads allowed)
			(copperpour not_allowed)
			(footprints allowed)
		)
		(placement
			(enabled no)
			(sheetname "")
		)
		(fill
			(thermal_gap 0.5)
			(thermal_bridge_width 0.5)
			(island_removal_mode 0)
		)
		(polygon
			(pts
				(arc
					(start 463.719926 -49.927764)
					(mid 464.243843 -49.997614)
					(end 463.719926 -50.067464)
				)
				(xy 463.606134 -50.067464) (xy 463.532728 -50.14087) (xy 463.532728 -50.381154)
				(arc
					(start 463.976974 -50.381154)
					(mid 464.360514 -49.997741)
					(end 463.977228 -49.614074)
				)
				(arc
					(start 462.707228 -49.614074)
					(mid 462.323688 -49.997614)
					(end 462.707228 -50.381154)
				)
				(xy 463.151728 -50.381154) (xy 463.151728 -50.14087) (xy 463.078322 -50.067464)
				(arc
					(start 462.96453 -50.067464)
					(mid 462.440613 -49.997614)
					(end 462.96453 -49.927764)
				)
				(xy 463.136234 -49.927764) (xy 463.291428 -50.082958) (xy 463.291428 -50.381154) (xy 463.393028 -50.381154)
				(xy 463.393028 -50.082958) (xy 463.548222 -49.927764)
			)
		)
	)
	(zone
		(layer "F.Cu")
		(hatch none 0.5)
		(connect_pads
			(clearance 0)
		)
		(min_thickness 0.25)
		(keepout
			(tracks not_allowed)
			(vias allowed)
			(pads allowed)
			(copperpour not_allowed)
			(footprints allowed)
		)
		(placement
			(enabled no)
			(sheetname "")
		)
		(fill
			(thermal_gap 0.5)
			(thermal_bridge_width 0.5)
			(island_removal_mode 0)
		)
		(polygon
			(pts
				(arc
					(start 318.000126 -100.449888)
					(mid 316.100206 -98.549968)
					(end 318.000126 -96.650048)
				)
				(arc
					(start 318.000126 -96.650048)
					(mid 319.900046 -98.549968)
					(end 318.000126 -100.449888)
				)
			)
		)
	)
	(zone
		(net "GND")
		(layer "F.Cu")
		(hatch none 0.5)
		(connect_pads
			(clearance 0.5)
		)
		(min_thickness 0.25)
		(fill yes
			(thermal_gap 0.5)
			(thermal_bridge_width 0.5)
			(island_removal_mode 0)
		)
		(polygon
			(pts
				(xy 91.541092 -18.923) (xy 92.936568 -18.923) (xy 93.017848 -18.84172) (xy 93.013276 -18.837148)
				(xy 93.013276 -18.308066) (xy 92.963492 -18.258282) (xy 92.14485 -18.258282) (xy 91.666568 -17.78)
				(xy 91.549728 -17.66316) (xy 91.549728 -17.199356) (xy 91.467178 -17.116806) (xy 78.715362 -17.116806)
				(xy 78.687168 -17.145) (xy 78.687168 -17.2974) (xy 78.687168 -17.31391) (xy 78.380336 -17.620742)
				(xy 78.363826 -17.620742) (xy 78.305152 -17.620742) (xy 77.855826 -17.620742) (xy 77.823568 -17.653)
				(xy 77.823568 -18.824448) (xy 77.90688 -18.90776) (xy 78.473808 -18.90776) (xy 79.093568 -18.288)
				(xy 79.322168 -18.288) (xy 90.630248 -18.288) (xy 90.985594 -18.288) (xy 90.996262 -18.277332) (xy 91.022424 -18.277332)
				(xy 91.319096 -18.277332) (xy 91.447112 -18.405348) (xy 91.447112 -18.502376) (xy 91.447112 -18.82902)
			)
		)
	)
	(zone
		(net "GND")
		(layer "F.Cu")
		(hatch none 0.5)
		(connect_pads
			(clearance 0.5)
		)
		(min_thickness 0.25)
		(fill yes
			(thermal_gap 0.5)
			(thermal_bridge_width 0.5)
			(island_removal_mode 0)
		)
		(polygon
			(pts
				(xy 481.5586 -157.226) (xy 484.9876 -157.226) (xy 485.521 -156.6926) (xy 485.521 -151.1808) (xy 484.251 -149.9108)
				(xy 483.299516 -148.959316) (xy 482.5111 -148.959316) (xy 482.179884 -148.6281) (xy 481.976684 -148.4249)
				(xy 479.771964 -148.4249) (xy 479.568764 -148.6281) (xy 479.237548 -148.959316) (xy 479.231452 -148.965412)
				(xy 479.064828 -149.132036) (xy 479.064828 -151.931624) (xy 479.3615 -152.228296) (xy 479.5774 -152.444196)
				(xy 479.5774 -156.7815) (xy 480.0219 -157.226)
			)
		)
	)
	(zone
		(layer "F.Cu")
		(hatch none 0.5)
		(connect_pads
			(clearance 0)
		)
		(min_thickness 0.25)
		(keepout
			(tracks allowed)
			(vias allowed)
			(pads allowed)
			(copperpour allowed)
			(footprints allowed)
		)
		(placement
			(enabled no)
			(sheetname "")
		)
		(fill
			(thermal_gap 0.5)
			(thermal_bridge_width 0.5)
			(island_removal_mode 0)
		)
		(polygon
			(pts
				(xy 195.3006 -82.3468) (xy 195.3006 -79.6544) (xy 197.3834 -79.6544) (xy 197.3834 -82.3468)
			)
		)
	)
	(zone
		(net "GND")
		(layer "F.Cu")
		(hatch none 0.5)
		(connect_pads
			(clearance 0.5)
		)
		(min_thickness 0.25)
		(fill yes
			(thermal_gap 0.5)
			(thermal_bridge_width 0.5)
			(island_removal_mode 0)
		)
		(polygon
			(pts
				(xy 113.000536 -134.177024) (xy 113.933224 -134.177024) (xy 114.9858 -135.2296) (xy 114.9858 -136.4742)
				(xy 114.82197 -136.63803) (xy 113.72723 -136.63803) (xy 113.510568 -136.421368) (xy 113.510568 -136.209024)
				(xy 113.256568 -135.955024) (xy 112.748568 -135.955024) (xy 103.4415 -135.955024) (xy 103.3272 -135.840724)
				(xy 103.3272 -135.193024) (xy 103.4542 -135.066024) (xy 106.931968 -135.066024) (xy 107.185968 -134.812024)
				(xy 112.367568 -134.812024) (xy 112.621568 -134.558024) (xy 112.621568 -134.5565) (xy 112.99698 -134.181088)
				(xy 112.99698 -134.18058)
			)
		)
	)
	(zone
		(layer "F.Cu")
		(hatch none 0.5)
		(connect_pads
			(clearance 0)
		)
		(min_thickness 0.25)
		(keepout
			(tracks allowed)
			(vias allowed)
			(pads allowed)
			(copperpour allowed)
			(footprints allowed)
		)
		(placement
			(enabled no)
			(sheetname "")
		)
		(fill
			(thermal_gap 0.5)
			(thermal_bridge_width 0.5)
			(island_removal_mode 0)
		)
		(polygon
			(pts
				(xy 168.021 -70.612) (xy 168.021 -68.707) (xy 170.307 -68.707) (xy 170.307 -70.612)
			)
		)
	)
	(zone
		(layer "F.Cu")
		(hatch none 0.5)
		(connect_pads
			(clearance 0)
		)
		(min_thickness 0.25)
		(keepout
			(tracks allowed)
			(vias allowed)
			(pads allowed)
			(copperpour allowed)
			(footprints allowed)
		)
		(placement
			(enabled no)
			(sheetname "")
		)
		(fill
			(thermal_gap 0.5)
			(thermal_bridge_width 0.5)
			(island_removal_mode 0)
		)
		(polygon
			(pts
				(xy 181.0766 -49.0982) (xy 183.7055 -49.0982) (xy 183.7055 -50.2666) (xy 181.0766 -50.2666)
			)
		)
	)
	(zone
		(layer "F.Cu")
		(hatch none 0.5)
		(connect_pads
			(clearance 0)
		)
		(min_thickness 0.25)
		(keepout
			(tracks not_allowed)
			(vias allowed)
			(pads allowed)
			(copperpour not_allowed)
			(footprints allowed)
		)
		(placement
			(enabled no)
			(sheetname "")
		)
		(fill
			(thermal_gap 0.5)
			(thermal_bridge_width 0.5)
			(island_removal_mode 0)
		)
		(polygon
			(pts
				(arc
					(start 383.583688 -127.607568)
					(mid 383.560613 -127.567141)
					(end 383.548382 -127.522224)
				)
				(xy 383.546604 -127.520446) (xy 383.546604 -127.422402) (xy 383.544572 -127.390652) (xy 383.46761 -127.390652)
				(xy 383.468626 -127.396748) (xy 383.470404 -127.39878) (xy 383.470404 -127.520446)
				(arc
					(start 383.468626 -127.522224)
					(mid 383.456426 -127.567154)
					(end 383.43332 -127.607568)
				)
				(xy 383.43332 -127.610108)
				(arc
					(start 383.41554 -127.627888)
					(mid 383.002477 -127.960179)
					(end 383.334768 -127.547116)
				)
				(arc
					(start 383.335784 -127.5461)
					(mid 383.350837 -127.523478)
					(end 383.356104 -127.496824)
				)
				(arc
					(start 383.356104 -127.422402)
					(mid 383.353796 -127.405932)
					(end 383.347214 -127.390652)
				)
				(arc
					(start 383.191258 -127.390652)
					(mid 382.810004 -127.771525)
					(end 383.191004 -128.152652)
				)
				(arc
					(start 383.826004 -128.152652)
					(mid 384.207004 -127.771652)
					(end 383.826004 -127.390652)
				)
				(xy 383.659634 -127.390652) (xy 383.660142 -127.398018) (xy 383.660904 -127.39878)
				(arc
					(start 383.660904 -127.496824)
					(mid 383.666187 -127.523471)
					(end 383.681224 -127.5461)
				)
				(arc
					(start 383.68224 -127.547116)
					(mid 384.014531 -127.960179)
					(end 383.601468 -127.627888)
				)
				(xy 383.583688 -127.610108)
			)
		)
	)
	(zone
		(layer "F.Cu")
		(hatch none 0.5)
		(connect_pads
			(clearance 0)
		)
		(min_thickness 0.25)
		(keepout
			(tracks allowed)
			(vias allowed)
			(pads allowed)
			(copperpour allowed)
			(footprints allowed)
		)
		(placement
			(enabled no)
			(sheetname "")
		)
		(fill
			(thermal_gap 0.5)
			(thermal_bridge_width 0.5)
			(island_removal_mode 0)
		)
		(polygon
			(pts
				(xy 195.199 -68.707) (xy 195.199 -67.564) (xy 197.231 -67.564) (xy 197.231 -68.707)
			)
		)
	)
	(zone
		(net "GND")
		(layer "F.Cu")
		(hatch none 0.5)
		(connect_pads
			(clearance 0.5)
		)
		(min_thickness 0.25)
		(fill yes
			(thermal_gap 0.5)
			(thermal_bridge_width 0.5)
			(island_removal_mode 0)
		)
		(polygon
			(pts
				(xy 177.4444 -12.7508) (xy 177.5714 -12.6238) (xy 177.5714 -11.176) (xy 177.4698 -11.0744) (xy 175.5648 -11.0744)
				(xy 175.4124 -11.2268) (xy 175.4124 -12.2936) (xy 175.2854 -12.4206) (xy 174.4726 -12.4206) (xy 174.4472 -12.446)
				(xy 174.4472 -12.7254) (xy 174.4726 -12.7508)
			)
		)
	)
	(zone
		(net "PVCCIN_CPU0")
		(layer "F.Cu")
		(hatch none 0.5)
		(connect_pads
			(clearance 0.5)
		)
		(min_thickness 0.25)
		(fill yes
			(thermal_gap 0.5)
			(thermal_bridge_width 0.5)
			(island_removal_mode 0)
		)
		(polygon
			(pts
				(arc
					(start 273.475196 -64.125602)
					(mid 273.480967 -64.020888)
					(end 273.391122 -63.966852)
				)
				(xy 273.271742 -63.966852)
				(arc
					(start 273.240754 -64.020446)
					(mid 272.942277 -64.209257)
					(end 272.61693 -64.072008)
				)
				(arc
					(start 272.61693 -64.072008)
					(mid 272.511731 -64.155151)
					(end 272.383758 -64.195198)
				)
				(arc
					(start 272.383758 -64.195198)
					(mid 271.873917 -64.632694)
					(end 271.99971 -63.972694)
				)
				(arc
					(start 271.99971 -63.972694)
					(mid 271.970979 -63.845178)
					(end 271.988534 -63.715646)
				)
				(arc
					(start 271.650968 -63.715646)
					(mid 271.579111 -63.745674)
					(end 271.549622 -63.817754)
				)
				(arc
					(start 271.549622 -63.835026)
					(mid 271.547142 -63.871314)
					(end 271.540986 -63.907162)
				)
				(arc
					(start 271.540986 -63.907162)
					(mid 271.203194 -64.18572)
					(end 270.851122 -63.92545)
				)
				(arc
					(start 270.851122 -63.92545)
					(mid 270.842902 -63.766822)
					(end 270.904462 -63.620396)
				)
				(arc
					(start 270.904462 -63.620396)
					(mid 270.912326 -63.514928)
					(end 270.822166 -63.459614)
				)
				(arc
					(start 267.52169 -63.459614)
					(mid 267.48559 -63.474673)
					(end 267.47089 -63.510922)
				)
				(arc
					(start 267.47089 -63.510922)
					(mid 267.360763 -63.783314)
					(end 267.089636 -63.896494)
				)
				(arc
					(start 266.688062 -63.896494)
					(mid 266.615239 -63.927246)
					(end 266.586462 -64.000888)
				)
				(arc
					(start 266.586462 -64.000888)
					(mid 266.02809 -64.302597)
					(end 266.116816 -63.67399)
				)
				(xy 266.15136 -63.625984)
				(arc
					(start 266.149582 -63.61303)
					(mid 266.139758 -63.562407)
					(end 266.136882 -63.510922)
				)
				(arc
					(start 266.136882 -63.510922)
					(mid 266.122184 -63.474671)
					(end 266.086082 -63.459614)
				)
				(arc
					(start 265.80465 -63.459614)
					(mid 265.76855 -63.474673)
					(end 265.75385 -63.510922)
				)
				(arc
					(start 265.75385 -63.510922)
					(mid 265.643723 -63.783314)
					(end 265.372596 -63.896494)
				)
				(arc
					(start 264.971022 -63.896494)
					(mid 264.898199 -63.927246)
					(end 264.869422 -64.000888)
				)
				(arc
					(start 264.869422 -64.000888)
					(mid 264.31105 -64.302597)
					(end 264.399776 -63.67399)
				)
				(xy 264.43432 -63.625984)
				(arc
					(start 264.432542 -63.61303)
					(mid 264.422718 -63.562407)
					(end 264.419842 -63.510922)
				)
				(arc
					(start 264.419842 -63.510922)
					(mid 264.405144 -63.474671)
					(end 264.369042 -63.459614)
				)
				(arc
					(start 264.087864 -63.459614)
					(mid 264.051764 -63.474673)
					(end 264.037064 -63.510922)
				)
				(arc
					(start 264.037064 -63.510922)
					(mid 263.926937 -63.783314)
					(end 263.65581 -63.896494)
				)
				(arc
					(start 263.253982 -63.896494)
					(mid 263.181159 -63.927246)
					(end 263.152382 -64.000888)
				)
				(arc
					(start 263.152382 -64.000888)
					(mid 262.59401 -64.302597)
					(end 262.682736 -63.67399)
				)
				(xy 262.71728 -63.62573)
				(arc
					(start 262.715756 -63.61303)
					(mid 262.705932 -63.562407)
					(end 262.703056 -63.510922)
				)
				(arc
					(start 262.703056 -63.510922)
					(mid 262.688358 -63.474671)
					(end 262.652256 -63.459614)
				)
				(arc
					(start 262.370824 -63.459614)
					(mid 262.334724 -63.474673)
					(end 262.320024 -63.510922)
				)
				(arc
					(start 262.320024 -63.510922)
					(mid 262.209897 -63.783314)
					(end 261.93877 -63.896494)
				)
				(arc
					(start 261.36727 -63.896494)
					(mid 261.09616 -63.783296)
					(end 260.986016 -63.510922)
				)
				(arc
					(start 260.986016 -63.510922)
					(mid 260.971318 -63.474671)
					(end 260.935216 -63.459614)
				)
				(arc
					(start 260.653784 -63.459614)
					(mid 260.617684 -63.474673)
					(end 260.602984 -63.510922)
				)
				(arc
					(start 260.602984 -63.510922)
					(mid 260.492857 -63.783314)
					(end 260.22173 -63.896494)
				)
				(arc
					(start 259.846064 -63.896494)
					(mid 259.77333 -63.927155)
					(end 259.744464 -64.000634)
				)
				(arc
					(start 259.744464 -64.000634)
					(mid 259.636368 -64.276693)
					(end 259.36321 -64.391794)
				)
				(arc
					(start 258.98729 -64.391794)
					(mid 258.914721 -64.422546)
					(end 258.885944 -64.495934)
				)
				(arc
					(start 258.885944 -64.495934)
					(mid 258.777848 -64.771993)
					(end 258.50469 -64.887094)
				)
				(arc
					(start 258.129024 -64.887094)
					(mid 258.05629 -64.917755)
					(end 258.027424 -64.991234)
				)
				(arc
					(start 258.027424 -64.991234)
					(mid 257.919328 -65.267293)
					(end 257.64617 -65.382394)
				)
				(arc
					(start 257.27025 -65.382394)
					(mid 257.197681 -65.413146)
					(end 257.168904 -65.486534)
				)
				(arc
					(start 257.168904 -65.486534)
					(mid 257.060808 -65.762593)
					(end 256.78765 -65.877694)
				)
				(arc
					(start 256.411984 -65.877694)
					(mid 256.33925 -65.908355)
					(end 256.310384 -65.981834)
				)
				(arc
					(start 256.310384 -65.981834)
					(mid 256.202288 -66.257893)
					(end 255.92913 -66.372994)
				)
				(arc
					(start 255.55321 -66.372994)
					(mid 255.480641 -66.403746)
					(end 255.451864 -66.477134)
				)
				(arc
					(start 255.451864 -66.477134)
					(mid 255.343768 -66.753193)
					(end 255.07061 -66.868294)
				)
				(arc
					(start 254.695198 -66.868294)
					(mid 254.622464 -66.898955)
					(end 254.593598 -66.972434)
				)
				(arc
					(start 254.593598 -66.972434)
					(mid 254.485502 -67.248493)
					(end 254.212344 -67.363594)
				)
				(xy 253.844044 -67.363594) (xy 253.735586 -67.472052)
				(arc
					(start 253.734824 -67.491864)
					(mid 253.631398 -67.739014)
					(end 253.390908 -67.857116)
				)
				(xy 253.345188 -67.861688) (xy 253.345188 -68.084192)
				(arc
					(start 253.390908 -68.088764)
					(mid 253.735108 -68.46824)
					(end 253.390908 -68.847716)
				)
				(xy 253.345188 -68.852288) (xy 253.345188 -69.074792)
				(arc
					(start 253.390908 -69.079364)
					(mid 253.734656 -69.477404)
					(end 253.353824 -69.840094)
				)
				(xy 253.018544 -69.840094) (xy 252.87605 -69.982588) (xy 252.876304 -69.983096) (xy 252.541024 -70.318376)
				(xy 252.541024 -71.55434)
				(arc
					(start 252.580394 -71.56323)
					(mid 252.874361 -71.977902)
					(end 252.495304 -72.316594)
				)
				(arc
					(start 251.923804 -72.316594)
					(mid 251.691382 -72.237623)
					(end 251.55525 -72.033384)
				)
				(xy 251.545344 -71.995538) (xy 251.156724 -71.995538)
				(arc
					(start 251.146818 -72.033384)
					(mid 251.010643 -72.237567)
					(end 250.778264 -72.316594)
				)
				(arc
					(start 250.206764 -72.316594)
					(mid 249.974342 -72.237623)
					(end 249.83821 -72.033384)
				)
				(xy 249.828304 -71.995538) (xy 249.439684 -71.995538)
				(arc
					(start 249.429778 -72.033384)
					(mid 249.293603 -72.237567)
					(end 249.061224 -72.316594)
				)
				(arc
					(start 248.489724 -72.316594)
					(mid 248.257302 -72.237623)
					(end 248.12117 -72.033384)
				)
				(xy 248.111264 -71.995538) (xy 247.722644 -71.995538)
				(arc
					(start 247.712738 -72.033384)
					(mid 247.576563 -72.237567)
					(end 247.344184 -72.316594)
				)
				(arc
					(start 246.772684 -72.316594)
					(mid 246.540262 -72.237623)
					(end 246.40413 -72.033384)
				)
				(xy 246.394224 -71.995538) (xy 246.005604 -71.995538)
				(arc
					(start 245.995698 -72.033384)
					(mid 245.859523 -72.237567)
					(end 245.627144 -72.316594)
				)
				(arc
					(start 245.251224 -72.316594)
					(mid 245.178655 -72.347346)
					(end 245.149878 -72.420734)
				)
				(arc
					(start 245.149878 -72.420734)
					(mid 245.041782 -72.696793)
					(end 244.768624 -72.811894)
				)
				(arc
					(start 244.197124 -72.811894)
					(mid 243.81587 -72.43064)
					(end 244.197124 -72.049386)
				)
				(arc
					(start 244.57279 -72.049386)
					(mid 244.645613 -72.018634)
					(end 244.67439 -71.944992)
				)
				(arc
					(start 244.67439 -71.944992)
					(mid 244.782486 -71.668933)
					(end 245.055644 -71.553578)
				)
				(arc
					(start 245.122954 -71.553578)
					(mid 245.216786 -71.490942)
					(end 245.194836 -71.38035)
				)
				(xy 245.14048 -71.325994)
				(arc
					(start 245.055644 -71.325994)
					(mid 244.767989 -71.194959)
					(end 244.677946 -70.891908)
				)
				(xy 244.681502 -70.867016) (xy 244.64518 -70.830694)
				(arc
					(start 244.196616 -70.830694)
					(mid 244.038083 -70.796054)
					(end 243.908326 -70.698614)
				)
				(arc
					(start 243.340636 -70.698614)
					(mid 243.210873 -70.796043)
					(end 243.052346 -70.830694)
				)
				(arc
					(start 242.47983 -70.830694)
					(mid 242.321297 -70.796054)
					(end 242.19154 -70.698614)
				)
				(arc
					(start 241.623596 -70.698614)
					(mid 241.493833 -70.796043)
					(end 241.335306 -70.830694)
				)
				(arc
					(start 240.76279 -70.830694)
					(mid 240.604257 -70.796054)
					(end 240.4745 -70.698614)
				)
				(arc
					(start 239.906556 -70.698614)
					(mid 239.776793 -70.796043)
					(end 239.618266 -70.830694)
				)
				(arc
					(start 239.04575 -70.830694)
					(mid 238.887217 -70.796054)
					(end 238.75746 -70.698614)
				)
				(arc
					(start 238.189516 -70.698614)
					(mid 238.059753 -70.796043)
					(end 237.901226 -70.830694)
				)
				(arc
					(start 237.32871 -70.830694)
					(mid 237.170177 -70.796054)
					(end 237.04042 -70.698614)
				)
				(xy 236.914182 -70.698614)
				(arc
					(start 236.721142 -70.505574)
					(mid 236.623467 -70.479379)
					(end 236.55147 -70.550532)
				)
				(arc
					(start 236.55147 -70.550532)
					(mid 236.414847 -70.75267)
					(end 236.183678 -70.830694)
				)
				(arc
					(start 235.612178 -70.830694)
					(mid 235.339112 -70.715503)
					(end 235.230924 -70.439534)
				)
				(arc
					(start 235.230924 -70.439534)
					(mid 235.20217 -70.366124)
					(end 235.129578 -70.335394)
				)
				(arc
					(start 234.753658 -70.335394)
					(mid 234.480592 -70.220203)
					(end 234.372404 -69.944234)
				)
				(arc
					(start 234.372404 -69.944234)
					(mid 234.343468 -69.870901)
					(end 234.270804 -69.840348)
				)
				(arc
					(start 233.90606 -69.840094)
					(mid 233.884757 -70.111083)
					(end 233.661458 -70.266052)
				)
				(arc
					(start 233.661458 -70.266052)
					(mid 233.64667 -70.264753)
					(end 233.63301 -70.25894)
				)
				(arc
					(start 233.626406 -70.254368)
					(mid 233.615856 -70.242393)
					(end 233.609642 -70.227698)
				)
				(arc
					(start 233.609642 -70.227698)
					(mid 233.608212 -70.219373)
					(end 233.607864 -70.210934)
				)
				(xy 233.607864 -70.177914) (xy 233.607864 -70.168516) (xy 233.620056 -70.168516) (xy 233.630216 -70.168262)
				(xy 233.63809 -70.166738)
				(arc
					(start 233.642154 -70.16623)
					(mid 233.661553 -70.16199)
					(end 233.680508 -70.15607)
				)
				(arc
					(start 233.680508 -70.15607)
					(mid 233.705038 -70.145582)
					(end 233.72826 -70.132448)
				)
				(arc
					(start 233.72826 -70.132448)
					(mid 233.752032 -70.113562)
					(end 233.773472 -70.092062)
				)
				(arc
					(start 233.773472 -70.092062)
					(mid 233.789063 -70.070711)
					(end 233.80192 -70.047612)
				)
				(arc
					(start 233.80192 -70.047612)
					(mid 233.813613 -70.017098)
					(end 233.821478 -69.985382)
				)
				(arc
					(start 233.824018 -69.951854)
					(mid 233.823024 -69.928548)
					(end 233.818684 -69.905626)
				)
				(arc
					(start 233.818684 -69.905626)
					(mid 233.80893 -69.875149)
					(end 233.795316 -69.84619)
				)
				(arc
					(start 233.778298 -69.821806)
					(mid 233.703246 -69.788428)
					(end 233.637074 -69.739764)
				)
				(xy 233.63428 -69.739256) (xy 233.60761 -69.737478) (xy 233.608118 -69.722746) (xy 233.60761 -69.709284)
				(xy 233.586274 -69.682614)
				(arc
					(start 233.058462 -69.682614)
					(mid 232.923074 -69.798412)
					(end 232.749852 -69.840094)
				)
				(arc
					(start 232.10139 -69.840094)
					(mid 232.029884 -69.83328)
					(end 231.960928 -69.81317)
				)
				(xy 231.951784 -69.809614) (xy 231.636824 -69.809614) (xy 213.793578 -51.966368) (xy 209.171032 -51.966368)
				(xy 208.8515 -52.2859) (xy 208.8515 -52.417472) (xy 208.852008 -52.417472) (xy 208.852008 -53.180488)
				(xy 208.8515 -53.180488) (xy 208.8515 -53.3273) (xy 208.434432 -53.744368) (xy 208.434432 -92.291154)
				(xy 208.714848 -92.57157) (xy 212.88883 -92.57157) (xy 213.511892 -91.948508) (xy 213.511892 -91.94419)
				(xy 213.88959 -91.566492) (xy 215.42121 -91.566492) (xy 215.472264 -91.6178) (xy 225.59899 -91.6178)
				(arc
					(start 234.270804 -82.945986)
					(mid 234.343627 -82.915234)
					(end 234.372404 -82.841592)
				)
				(arc
					(start 234.372404 -82.841592)
					(mid 234.480593 -82.565701)
					(end 234.753658 -82.450686)
				)
				(arc
					(start 235.142024 -82.450686)
					(mid 235.214682 -82.419843)
					(end 235.24337 -82.346292)
				)
				(xy 235.24337 -82.336386)
				(arc
					(start 235.243624 -82.322416)
					(mid 235.213246 -82.251715)
					(end 235.142024 -82.222594)
				)
				(arc
					(start 234.753658 -82.222594)
					(mid 234.37215 -81.841086)
					(end 234.753658 -81.459578)
				)
				(arc
					(start 235.129578 -81.459578)
					(mid 235.202059 -81.428917)
					(end 235.230924 -81.355692)
				)
				(arc
					(start 235.230924 -81.355692)
					(mid 235.339113 -81.079801)
					(end 235.612178 -80.964786)
				)
				(arc
					(start 235.987844 -80.964786)
					(mid 236.060667 -80.934034)
					(end 236.089444 -80.860392)
				)
				(arc
					(start 236.089444 -80.840834)
					(mid 236.060508 -80.767501)
					(end 235.987844 -80.736948)
				)
				(arc
					(start 235.612178 -80.736694)
					(mid 235.230924 -80.35544)
					(end 235.612178 -79.974186)
				)
				(arc
					(start 236.183678 -79.974186)
					(mid 236.472278 -80.106177)
					(end 236.561122 -80.410812)
				)
				(xy 236.56036 -80.414622) (xy 236.56036 -80.468978) (xy 236.67466 -80.468978) (xy 236.920024 -80.223614)
				(xy 236.969808 -80.223614)
				(arc
					(start 236.983524 -80.194404)
					(mid 237.124289 -80.033944)
					(end 237.329218 -79.974186)
				)
				(arc
					(start 237.900718 -79.974186)
					(mid 238.105668 -80.033911)
					(end 238.246412 -80.194404)
				)
				(xy 238.260128 -80.223614) (xy 238.686848 -80.223614)
				(arc
					(start 238.700564 -80.194404)
					(mid 238.841329 -80.033944)
					(end 239.046258 -79.974186)
				)
				(arc
					(start 239.617758 -79.974186)
					(mid 239.822708 -80.033911)
					(end 239.963452 -80.194404)
				)
				(xy 239.977168 -80.223614) (xy 240.403888 -80.223614)
				(arc
					(start 240.417604 -80.194404)
					(mid 240.558369 -80.033944)
					(end 240.763298 -79.974186)
				)
				(arc
					(start 241.334798 -79.974186)
					(mid 241.539748 -80.033911)
					(end 241.680492 -80.194404)
				)
				(xy 241.694208 -80.223614) (xy 242.120928 -80.223614)
				(arc
					(start 242.134644 -80.194404)
					(mid 242.275409 -80.033944)
					(end 242.480338 -79.974186)
				)
				(arc
					(start 243.051838 -79.974186)
					(mid 243.256788 -80.033911)
					(end 243.397532 -80.194404)
				)
				(xy 243.411248 -80.223614) (xy 243.837714 -80.223614)
				(arc
					(start 243.85143 -80.194404)
					(mid 243.992195 -80.033944)
					(end 244.197124 -79.974186)
				)
				(arc
					(start 244.57279 -79.974186)
					(mid 244.645613 -79.943434)
					(end 244.67439 -79.869792)
				)
				(arc
					(start 244.67439 -79.869792)
					(mid 244.782486 -79.593733)
					(end 245.055644 -79.478378)
				)
				(arc
					(start 245.431564 -79.478378)
					(mid 245.504045 -79.447717)
					(end 245.53291 -79.374492)
				)
				(arc
					(start 245.53291 -79.354934)
					(mid 245.504156 -79.281524)
					(end 245.431564 -79.250794)
				)
				(arc
					(start 245.055644 -79.250794)
					(mid 244.782578 -79.135603)
					(end 244.67439 -78.859634)
				)
				(arc
					(start 244.67439 -78.859634)
					(mid 244.645547 -78.786133)
					(end 244.57279 -78.755494)
				)
				(arc
					(start 244.197124 -78.755494)
					(mid 243.81587 -78.37424)
					(end 244.197124 -77.992986)
				)
				(arc
					(start 244.768624 -77.992986)
					(mid 245.041601 -78.108086)
					(end 245.149878 -78.383892)
				)
				(arc
					(start 245.149878 -78.383892)
					(mid 245.178721 -78.457393)
					(end 245.251478 -78.488032)
				)
				(arc
					(start 245.627144 -78.487778)
					(mid 245.900392 -78.603046)
					(end 246.008398 -78.879192)
				)
				(arc
					(start 246.008398 -78.879192)
					(mid 246.037148 -78.95286)
					(end 246.109998 -78.983586)
				)
				(arc
					(start 246.28983 -78.983586)
					(mid 246.362653 -78.952834)
					(end 246.39143 -78.879192)
				)
				(arc
					(start 246.39143 -78.879192)
					(mid 246.499526 -78.603133)
					(end 246.772684 -78.487778)
				)
				(arc
					(start 247.344184 -78.487778)
					(mid 247.617432 -78.603046)
					(end 247.725438 -78.879192)
				)
				(arc
					(start 247.725438 -78.879192)
					(mid 247.754188 -78.95286)
					(end 247.827038 -78.983586)
				)
				(arc
					(start 248.00687 -78.983586)
					(mid 248.079693 -78.952834)
					(end 248.10847 -78.879192)
				)
				(arc
					(start 248.10847 -78.879192)
					(mid 248.216566 -78.603133)
					(end 248.489724 -78.487778)
				)
				(arc
					(start 249.061224 -78.487778)
					(mid 249.334472 -78.603046)
					(end 249.442478 -78.879192)
				)
				(arc
					(start 249.442478 -78.879192)
					(mid 249.471228 -78.95286)
					(end 249.544078 -78.983586)
				)
				(arc
					(start 249.72391 -78.983586)
					(mid 249.796733 -78.952834)
					(end 249.82551 -78.879192)
				)
				(arc
					(start 249.82551 -78.879192)
					(mid 249.933606 -78.603133)
					(end 250.206764 -78.487778)
				)
				(arc
					(start 250.778264 -78.487778)
					(mid 251.051512 -78.603046)
					(end 251.159518 -78.879192)
				)
				(arc
					(start 251.159518 -78.879192)
					(mid 251.188268 -78.95286)
					(end 251.261118 -78.983586)
				)
				(arc
					(start 251.44095 -78.983586)
					(mid 251.513773 -78.952834)
					(end 251.54255 -78.879192)
				)
				(arc
					(start 251.54255 -78.879192)
					(mid 251.650646 -78.603133)
					(end 251.923804 -78.487778)
				)
				(arc
					(start 252.495304 -78.487778)
					(mid 252.876812 -78.869286)
					(end 252.495304 -79.250794)
				)
				(arc
					(start 252.119384 -79.250794)
					(mid 252.046815 -79.281546)
					(end 252.018038 -79.354934)
				)
				(arc
					(start 252.018038 -79.374492)
					(mid 252.046881 -79.447993)
					(end 252.119638 -79.478632)
				)
				(arc
					(start 252.495304 -79.478378)
					(mid 252.876812 -79.859886)
					(end 252.495304 -80.241394)
				)
				(arc
					(start 252.45314 -80.241394)
					(mid 252.359308 -80.30403)
					(end 252.381258 -80.414622)
				)
				(xy 252.435868 -80.468978)
				(arc
					(start 252.495304 -80.468978)
					(mid 252.69298 -80.524228)
					(end 252.833378 -80.673956)
				)
				(xy 253.095252 -80.673956) (xy 253.234444 -80.813148) (xy 253.234444 -80.964786)
				(arc
					(start 253.353824 -80.964786)
					(mid 253.735078 -81.34604)
					(end 253.353824 -81.727294)
				)
				(xy 253.234444 -81.727294) (xy 253.234444 -81.955386)
				(arc
					(start 253.353824 -81.955386)
					(mid 253.735078 -82.33664)
					(end 253.353824 -82.717894)
				)
				(xy 253.234444 -82.717894) (xy 253.234444 -82.945986)
				(arc
					(start 253.353824 -82.945986)
					(mid 253.735078 -83.32724)
					(end 253.353824 -83.708494)
				)
				(xy 253.234444 -83.708494) (xy 253.234444 -83.936586)
				(arc
					(start 253.353824 -83.936586)
					(mid 253.626801 -84.051686)
					(end 253.735078 -84.327492)
				)
				(arc
					(start 253.735078 -84.327492)
					(mid 253.763921 -84.400993)
					(end 253.836678 -84.431632)
				)
				(arc
					(start 254.212344 -84.431378)
					(mid 254.485592 -84.546646)
					(end 254.593598 -84.822792)
				)
				(arc
					(start 254.593598 -84.822792)
					(mid 254.622348 -84.89646)
					(end 254.695198 -84.927186)
				)
				(arc
					(start 255.07061 -84.927186)
					(mid 255.343587 -85.042286)
					(end 255.451864 -85.318092)
				)
				(arc
					(start 255.451864 -85.318092)
					(mid 255.480707 -85.391593)
					(end 255.553464 -85.422232)
				)
				(arc
					(start 255.92913 -85.421978)
					(mid 256.202378 -85.537246)
					(end 256.310384 -85.813392)
				)
				(arc
					(start 256.310384 -85.813392)
					(mid 256.339134 -85.88706)
					(end 256.411984 -85.917786)
				)
				(arc
					(start 256.78765 -85.917786)
					(mid 257.060627 -86.032886)
					(end 257.168904 -86.308692)
				)
				(arc
					(start 257.168904 -86.308692)
					(mid 257.197747 -86.382193)
					(end 257.270504 -86.412832)
				)
				(arc
					(start 257.64617 -86.412578)
					(mid 257.919418 -86.527846)
					(end 258.027424 -86.803992)
				)
				(arc
					(start 258.027424 -86.803992)
					(mid 258.056174 -86.87766)
					(end 258.129024 -86.908386)
				)
				(arc
					(start 258.50469 -86.908386)
					(mid 258.777667 -87.023486)
					(end 258.885944 -87.299292)
				)
				(arc
					(start 258.885944 -87.299292)
					(mid 258.914787 -87.372793)
					(end 258.987544 -87.403432)
				)
				(arc
					(start 259.36321 -87.403178)
					(mid 259.636458 -87.518446)
					(end 259.744464 -87.794592)
				)
				(arc
					(start 259.744464 -87.794592)
					(mid 259.773214 -87.86826)
					(end 259.846064 -87.898986)
				)
				(arc
					(start 260.025896 -87.898986)
					(mid 260.098719 -87.868234)
					(end 260.127496 -87.794592)
				)
				(arc
					(start 260.127496 -87.794592)
					(mid 260.235592 -87.518533)
					(end 260.50875 -87.403178)
				)
				(arc
					(start 261.08025 -87.403178)
					(mid 261.353498 -87.518446)
					(end 261.461504 -87.794592)
				)
				(arc
					(start 261.461504 -87.794592)
					(mid 261.490254 -87.86826)
					(end 261.563104 -87.898986)
				)
				(arc
					(start 261.93877 -87.898986)
					(mid 262.211747 -88.014086)
					(end 262.320024 -88.289892)
				)
				(arc
					(start 262.320024 -88.289892)
					(mid 262.348867 -88.363393)
					(end 262.421624 -88.394032)
				)
				(arc
					(start 262.79729 -88.393778)
					(mid 263.04828 -88.48805)
					(end 263.175242 -88.724232)
				)
				(xy 263.177528 -88.74125) (xy 263.325864 -88.889586)
				(arc
					(start 263.65581 -88.889586)
					(mid 263.901829 -88.979585)
					(end 264.03173 -89.207086)
				)
				(xy 264.039096 -89.24925) (xy 264.41781 -89.24925) (xy 264.425176 -89.207086)
				(arc
					(start 264.432288 -89.173558)
					(mid 264.428049 -89.136431)
					(end 264.399522 -89.112344)
				)
				(arc
					(start 264.399522 -89.112344)
					(mid 264.310955 -88.484023)
					(end 264.869676 -88.785192)
				)
				(arc
					(start 264.869676 -88.785192)
					(mid 264.898337 -88.858769)
					(end 264.971022 -88.889586)
				)
				(arc
					(start 265.372596 -88.889586)
					(mid 265.618615 -88.979585)
					(end 265.748516 -89.207086)
				)
				(xy 265.755882 -89.24925) (xy 266.13485 -89.24925) (xy 266.142216 -89.207086)
				(arc
					(start 266.149328 -89.173558)
					(mid 266.145089 -89.136431)
					(end 266.116562 -89.112344)
				)
				(arc
					(start 266.116562 -89.112344)
					(mid 266.027995 -88.484023)
					(end 266.586716 -88.785192)
				)
				(arc
					(start 266.586716 -88.785192)
					(mid 266.615377 -88.858769)
					(end 266.688062 -88.889586)
				)
				(arc
					(start 267.089636 -88.889586)
					(mid 267.335655 -88.979585)
					(end 267.465556 -89.207086)
				)
				(xy 267.472922 -89.24925)
				(arc
					(start 267.640562 -89.24925)
					(mid 267.735492 -89.183855)
					(end 267.708126 -89.071958)
				)
				(arc
					(start 267.708126 -89.071958)
					(mid 267.60382 -88.939628)
					(end 267.566648 -88.775286)
				)
				(arc
					(start 267.566648 -88.165432)
					(mid 267.578904 -88.069507)
					(end 267.614908 -87.979758)
				)
				(arc
					(start 267.614908 -87.979758)
					(mid 267.948156 -87.76909)
					(end 268.281404 -87.979758)
				)
				(arc
					(start 268.281404 -87.979758)
					(mid 268.317383 -88.069514)
					(end 268.329664 -88.165432)
				)
				(arc
					(start 268.329664 -88.775286)
					(mid 268.292482 -88.939623)
					(end 268.188186 -89.071958)
				)
				(arc
					(start 268.188186 -89.071958)
					(mid 268.16095 -89.183806)
					(end 268.25575 -89.24925)
				)
				(xy 268.42339 -89.24925)
				(arc
					(start 268.428724 -89.218008)
					(mid 268.561514 -88.978377)
					(end 268.820646 -88.889586)
				)
				(arc
					(start 269.416276 -88.889586)
					(mid 269.567485 -88.920831)
					(end 269.693898 -89.009474)
				)
				(xy 269.827502 -89.009474) (xy 270.31696 -89.498678) (xy 270.321024 -89.494614) (xy 271.413986 -89.494614)
				(xy 271.6276 -89.281)
				(arc
					(start 271.752314 -89.281)
					(mid 272.052288 -88.733977)
					(end 272.352262 -89.281)
				)
				(arc
					(start 272.750788 -89.281)
					(mid 272.910808 -89.241431)
					(end 273.070828 -89.281)
				)
				(arc
					(start 273.273266 -89.281)
					(mid 273.482308 -89.216025)
					(end 273.69135 -89.281)
				)
				(arc
					(start 274.467828 -89.281)
					(mid 274.627848 -89.241431)
					(end 274.787868 -89.281)
				)
				(arc
					(start 274.990306 -89.281)
					(mid 275.199348 -89.216025)
					(end 275.40839 -89.281)
				)
				(arc
					(start 276.184614 -89.281)
					(mid 276.344634 -89.241431)
					(end 276.504654 -89.281)
				)
				(arc
					(start 276.707092 -89.281)
					(mid 276.791602 -89.237627)
					(end 276.884384 -89.217246)
				)
				(arc
					(start 276.884384 -89.217246)
					(mid 276.860224 -89.073257)
					(end 276.8981 -88.932258)
				)
				(arc
					(start 276.8981 -88.725248)
					(mid 277.203154 -88.149577)
					(end 277.508208 -88.725248)
				)
				(arc
					(start 277.508208 -88.932258)
					(mid 277.5459 -89.109316)
					(end 277.488396 -89.281)
				)
				(arc
					(start 277.901654 -89.281)
					(mid 278.061674 -89.241431)
					(end 278.221694 -89.281)
				)
				(arc
					(start 278.424132 -89.281)
					(mid 278.508642 -89.237627)
					(end 278.601424 -89.217246)
				)
				(arc
					(start 278.601424 -89.217246)
					(mid 278.731947 -88.802989)
					(end 279.164034 -88.848184)
				)
				(arc
					(start 279.213056 -88.848184)
					(mid 279.324328 -88.761055)
					(end 279.460198 -88.7222)
				)
				(arc
					(start 279.460198 -88.7222)
					(mid 279.590105 -88.307361)
					(end 280.022554 -88.352376)
				)
				(arc
					(start 280.071576 -88.352376)
					(mid 280.137989 -88.29246)
					(end 280.216864 -88.250268)
				)
				(xy 280.252932 -88.2142) (xy 280.252932 -86.294468) (xy 276.606254 -86.294468) (xy 275.971 -85.659214)
				(xy 275.971 -85.37956) (xy 274.96008 -84.36864) (xy 274.13966 -84.36864) (xy 273.98726 -84.52104)
				(xy 273.98726 -85.45068) (xy 274.071842 -85.535262) (xy 274.627594 -85.535262) (xy 274.837398 -85.745066)
				(xy 274.837398 -86.44636) (xy 274.669758 -86.614) (xy 267.816584 -86.614)
				(arc
					(start 267.6652 -86.462616)
					(mid 267.588928 -86.460546)
					(end 267.513816 -86.447122)
				)
				(xy 263.611614 -86.447122) (xy 263.61136 -86.446614) (xy 263.336024 -86.446614) (xy 262.002524 -85.113114)
				(xy 261.177024 -85.113114) (xy 260.732524 -84.668614) (xy 260.732524 -84.6582) (xy 259.726938 -83.652614)
				(xy 258.256024 -83.652614) (xy 257.367024 -82.763614) (xy 257.367024 -79.567278) (xy 257.366516 -79.567024)
				(xy 257.366516 -78.975204) (xy 257.367024 -78.97495) (xy 257.367024 -78.953614) (xy 257.494024 -78.826614)
				(xy 257.51536 -78.826614) (xy 257.642614 -78.699106) (xy 258.107434 -78.699106) (xy 258.23291 -78.824582)
				(xy 261.431532 -78.824582) (xy 261.431532 -78.954122) (xy 261.519924 -79.042514)
				(arc
					(start 261.519924 -79.103982)
					(mid 261.583886 -79.35087)
					(end 261.519924 -79.597758)
				)
				(xy 261.519924 -80.0354) (xy 268.734286 -80.0354) (xy 268.734286 -77.201268) (xy 263.38784 -77.201268)
				(xy 263.38784 -77.192124) (xy 262.805164 -77.192124) (xy 262.805164 -77.177138) (xy 262.32358 -77.177138)
				(xy 262.32358 -77.192124) (xy 261.560564 -77.192124) (xy 261.560564 -77.177138) (xy 261.07898 -77.177138)
				(xy 261.07898 -77.192124) (xy 260.315964 -77.192124) (xy 260.315964 -77.177138) (xy 259.83438 -77.177138)
				(xy 259.83438 -77.192124) (xy 259.071364 -77.192124) (xy 259.071364 -77.177138) (xy 258.58978 -77.177138)
				(xy 258.58978 -77.192124) (xy 257.826764 -77.192124) (xy 257.826764 -76.947522) (xy 257.493516 -76.947522)
				(xy 257.493516 -74.63663) (xy 257.83413 -74.63663) (xy 257.83413 -74.636376) (xy 263.537954 -74.636376)
				(xy 263.53897 -74.637646) (xy 263.541256 -74.639678) (xy 268.605 -74.639678) (xy 268.605 -72.95769)
				(xy 268.5288 -72.88149) (xy 263.395968 -72.88149) (xy 263.38403 -72.893428) (xy 258.072128 -72.893428)
				(xy 258.052824 -72.874124) (xy 257.826764 -72.874124) (xy 257.826764 -72.673718) (xy 257.493516 -72.673718)
				(xy 257.493516 -70.876668) (xy 258.119626 -70.250558) (xy 260.8326 -70.250558) (xy 261.10438 -69.978778)
				(xy 261.10438 -68.0974) (xy 261.524242 -67.677538) (xy 263.4996 -67.677538) (xy 263.671304 -67.505834)
				(xy 263.671304 -66.929) (xy 263.891014 -66.70929) (xy 264.020046 -66.70929) (xy 264.020046 -66.709036)
				(xy 275.04517 -66.709036) (xy 275.16074 -66.824606) (xy 275.16074 -68.00469) (xy 275.133308 -68.032376)
				(xy 275.133308 -68.28409) (xy 275.372576 -68.28409) (xy 276.059392 -67.59702) (xy 276.059392 -67.49542)
				(arc
					(start 276.275546 -67.27952)
					(mid 276.777191 -66.844336)
					(end 276.805898 -67.507866)
				)
				(arc
					(start 276.805898 -67.507866)
					(mid 276.938945 -67.977241)
					(end 276.489922 -68.168012)
				)
				(xy 276.373844 -68.28409) (xy 276.794976 -68.28409)
				(arc
					(start 277.094188 -67.984878)
					(mid 277.105007 -67.724125)
					(end 277.285704 -67.535806)
				)
				(arc
					(start 277.285704 -67.535806)
					(mid 277.366133 -66.815132)
					(end 277.551896 -67.515994)
				)
				(arc
					(start 277.551896 -67.515994)
					(mid 277.720515 -67.624422)
					(end 277.80742 -67.805046)
				)
				(arc
					(start 277.957788 -67.654678)
					(mid 278.437125 -67.193263)
					(end 278.495506 -67.8561)
				)
				(arc
					(start 278.495506 -67.8561)
					(mid 278.65217 -68.041505)
					(end 278.65959 -68.28409)
				)
				(xy 280.942034 -68.28409)
				(arc
					(start 281.034744 -68.19138)
					(mid 281.054717 -68.169331)
					(end 281.0764 -68.148962)
				)
				(xy 281.0764 -67.869308) (xy 281.10307 -67.842384)
				(arc
					(start 281.10307 -67.123564)
					(mid 281.038109 -67.15175)
					(end 280.968958 -67.166998)
				)
				(arc
					(start 280.968958 -67.166998)
					(mid 280.458757 -67.604345)
					(end 280.584402 -66.94424)
				)
				(arc
					(start 280.584402 -66.94424)
					(mid 280.555679 -66.814168)
					(end 280.575004 -66.682366)
				)
				(arc
					(start 280.575004 -66.682366)
					(mid 280.446997 -66.636665)
					(end 280.343102 -66.549016)
				)
				(arc
					(start 280.343102 -66.549016)
					(mid 280.23812 -66.631979)
					(end 280.110438 -66.671952)
				)
				(arc
					(start 280.110438 -66.671952)
					(mid 279.60018 -67.108906)
					(end 279.725882 -66.44894)
				)
				(arc
					(start 279.725882 -66.44894)
					(mid 279.697149 -66.318587)
					(end 279.716738 -66.186558)
				)
				(arc
					(start 279.716738 -66.186558)
					(mid 279.599961 -66.147126)
					(end 279.501854 -66.072512)
				)
				(xy 279.486868 -66.056764)
				(arc
					(start 279.481534 -66.056764)
					(mid 279.37757 -66.137391)
					(end 279.251918 -66.176398)
				)
				(arc
					(start 279.251918 -66.176398)
					(mid 278.742294 -66.614019)
					(end 278.867362 -65.953894)
				)
				(arc
					(start 278.867362 -65.953894)
					(mid 278.83854 -65.823568)
					(end 278.857964 -65.691512)
				)
				(arc
					(start 278.857964 -65.691512)
					(mid 278.730049 -65.645829)
					(end 278.626316 -65.558162)
				)
				(arc
					(start 278.626316 -65.558162)
					(mid 278.52125 -65.641317)
					(end 278.393398 -65.681352)
				)
				(arc
					(start 278.393398 -65.681352)
					(mid 277.88314 -66.118306)
					(end 278.008842 -65.45834)
				)
				(arc
					(start 278.008842 -65.45834)
					(mid 277.980213 -65.330676)
					(end 277.99792 -65.201038)
				)
				(arc
					(start 277.660862 -65.201038)
					(mid 277.588039 -65.23179)
					(end 277.559262 -65.305432)
				)
				(arc
					(start 277.559262 -65.305432)
					(mid 277.545213 -65.414871)
					(end 277.498302 -65.514728)
				)
				(arc
					(start 277.498302 -65.514728)
					(mid 277.303529 -65.657156)
					(end 277.062692 -65.64249)
				)
				(arc
					(start 277.062692 -65.64249)
					(mid 276.864646 -65.425657)
					(end 276.89683 -65.133728)
				)
				(arc
					(start 276.89683 -65.133728)
					(mid 276.978779 -65.038714)
					(end 277.0886 -64.978026)
				)
				(xy 277.123144 -64.93002)
				(arc
					(start 277.121366 -64.917066)
					(mid 277.111363 -64.86404)
					(end 277.10892 -64.810132)
				)
				(arc
					(start 277.10892 -64.810132)
					(mid 277.080073 -64.736889)
					(end 277.007574 -64.706246)
				)
				(arc
					(start 276.801834 -64.706246)
					(mid 276.731513 -64.734758)
					(end 276.700488 -64.804036)
				)
				(arc
					(start 276.700488 -64.804036)
					(mid 276.678161 -64.944844)
					(end 276.602444 -65.065656)
				)
				(arc
					(start 276.602444 -65.065656)
					(mid 276.384264 -65.173906)
					(end 276.14753 -65.116456)
				)
				(arc
					(start 276.14753 -65.116456)
					(mid 275.991437 -64.773782)
					(end 276.23008 -64.482472)
				)
				(xy 276.264624 -64.43472)
				(arc
					(start 276.262846 -64.421766)
					(mid 276.252843 -64.36874)
					(end 276.2504 -64.314832)
				)
				(arc
					(start 276.2504 -64.314832)
					(mid 276.22165 -64.241164)
					(end 276.1488 -64.210438)
				)
				(arc
					(start 275.943314 -64.210438)
					(mid 275.870403 -64.241281)
					(end 275.841714 -64.315086)
				)
				(arc
					(start 275.841714 -64.315086)
					(mid 275.386804 -64.66651)
					(end 275.192236 -64.125602)
				)
				(arc
					(start 275.192236 -64.125602)
					(mid 275.198007 -64.020888)
					(end 275.108162 -63.966852)
				)
				(xy 274.984972 -63.966852)
				(arc
					(start 274.971002 -63.995554)
					(mid 274.830279 -64.152256)
					(end 274.627848 -64.210438)
				)
				(arc
					(start 274.226274 -64.210438)
					(mid 274.153363 -64.241281)
					(end 274.124674 -64.315086)
				)
				(arc
					(start 274.124674 -64.315086)
					(mid 273.669764 -64.66651)
					(end 273.475196 -64.125602)
				)
			)
		)
		(polygon
			(pts
				(xy 214.9856 -86.7664) (xy 214.7824 -86.7664) (xy 214.7824 -86.9696) (xy 214.9856 -86.9696)
			)
		)
		(polygon
			(pts
				(xy 214.2236 -86.7664) (xy 214.0204 -86.7664) (xy 214.0204 -86.9696) (xy 214.2236 -86.9696)
			)
		)
		(polygon
			(pts
				(xy 274.91563 -85.139022) (xy 274.71243 -85.139022) (xy 274.71243 -85.342222) (xy 274.91563 -85.342222)
			)
		)
		(polygon
			(pts
				(xy 267.8938 -79.0575) (xy 267.6906 -79.0575) (xy 267.6906 -79.2607) (xy 267.8938 -79.2607)
			)
		)
		(polygon
			(pts
				(xy 267.4112 -79.0575) (xy 267.208 -79.0575) (xy 267.208 -79.2607) (xy 267.4112 -79.2607)
			)
		)
		(polygon
			(pts
				(xy 266.6492 -79.0575) (xy 266.446 -79.0575) (xy 266.446 -79.2607) (xy 266.6492 -79.2607)
			)
		)
		(polygon
			(pts
				(xy 266.1666 -79.0575) (xy 265.9634 -79.0575) (xy 265.9634 -79.2607) (xy 266.1666 -79.2607)
			)
		)
		(polygon
			(pts
				(xy 265.4046 -79.0575) (xy 265.2014 -79.0575) (xy 265.2014 -79.2607) (xy 265.4046 -79.2607)
			)
		)
		(polygon
			(pts
				(xy 264.922 -79.0575) (xy 264.7188 -79.0575) (xy 264.7188 -79.2607) (xy 264.922 -79.2607)
			)
		)
		(polygon
			(pts
				(xy 264.16 -79.0575) (xy 263.9568 -79.0575) (xy 263.9568 -79.2607) (xy 264.16 -79.2607)
			)
		)
		(polygon
			(pts
				(xy 263.6774 -79.0575) (xy 263.4742 -79.0575) (xy 263.4742 -79.2607) (xy 263.6774 -79.2607)
			)
		)
		(polygon
			(pts
				(xy 262.9154 -79.0575) (xy 262.7122 -79.0575) (xy 262.7122 -79.2607) (xy 262.9154 -79.2607)
			)
		)
		(polygon
			(pts
				(xy 262.4328 -79.0575) (xy 262.2296 -79.0575) (xy 262.2296 -79.2607) (xy 262.4328 -79.2607)
			)
		)
		(polygon
			(pts
				(xy 214.9856 -78.7527) (xy 214.7824 -78.7527) (xy 214.7824 -78.9559) (xy 214.9856 -78.9559)
			)
		)
		(polygon
			(pts
				(xy 214.2236 -78.7527) (xy 214.0204 -78.7527) (xy 214.0204 -78.9559) (xy 214.2236 -78.9559)
			)
		)
		(polygon
			(pts
				(xy 267.885672 -77.979016) (xy 267.682472 -77.979016) (xy 267.682472 -78.182216) (xy 267.885672 -78.182216)
			)
		)
		(polygon
			(pts
				(xy 267.403072 -77.979016) (xy 267.199872 -77.979016) (xy 267.199872 -78.182216) (xy 267.403072 -78.182216)
			)
		)
		(polygon
			(pts
				(xy 266.641072 -77.979016) (xy 266.437872 -77.979016) (xy 266.437872 -78.182216) (xy 266.641072 -78.182216)
			)
		)
		(polygon
			(pts
				(xy 266.158472 -77.979016) (xy 265.955272 -77.979016) (xy 265.955272 -78.182216) (xy 266.158472 -78.182216)
			)
		)
		(polygon
			(pts
				(xy 265.396472 -77.979016) (xy 265.193272 -77.979016) (xy 265.193272 -78.182216) (xy 265.396472 -78.182216)
			)
		)
		(polygon
			(pts
				(xy 264.913872 -77.979016) (xy 264.710672 -77.979016) (xy 264.710672 -78.182216) (xy 264.913872 -78.182216)
			)
		)
		(polygon
			(pts
				(xy 264.151872 -77.979016) (xy 263.948672 -77.979016) (xy 263.948672 -78.182216) (xy 264.151872 -78.182216)
			)
		)
		(polygon
			(pts
				(xy 263.669272 -77.979016) (xy 263.466072 -77.979016) (xy 263.466072 -78.182216) (xy 263.669272 -78.182216)
			)
		)
		(polygon
			(pts
				(xy 262.907272 -77.979016) (xy 262.704072 -77.979016) (xy 262.704072 -78.182216) (xy 262.907272 -78.182216)
			)
		)
		(polygon
			(pts
				(xy 262.424672 -77.979016) (xy 262.221472 -77.979016) (xy 262.221472 -78.182216) (xy 262.424672 -78.182216)
			)
		)
		(polygon
			(pts
				(xy 261.662672 -77.979016) (xy 261.459472 -77.979016) (xy 261.459472 -78.182216) (xy 261.662672 -78.182216)
			)
		)
		(polygon
			(pts
				(xy 261.180072 -77.979016) (xy 260.976872 -77.979016) (xy 260.976872 -78.182216) (xy 261.180072 -78.182216)
			)
		)
		(polygon
			(pts
				(xy 260.418072 -77.979016) (xy 260.214872 -77.979016) (xy 260.214872 -78.182216) (xy 260.418072 -78.182216)
			)
		)
		(polygon
			(pts
				(xy 259.935472 -77.979016) (xy 259.732272 -77.979016) (xy 259.732272 -78.182216) (xy 259.935472 -78.182216)
			)
		)
		(polygon
			(pts
				(xy 259.173472 -77.979016) (xy 258.970272 -77.979016) (xy 258.970272 -78.182216) (xy 259.173472 -78.182216)
			)
		)
		(polygon
			(pts
				(xy 258.690872 -77.979016) (xy 258.487672 -77.979016) (xy 258.487672 -78.182216) (xy 258.690872 -78.182216)
			)
		)
		(polygon
			(pts
				(xy 257.928872 -77.979016) (xy 257.725672 -77.979016) (xy 257.725672 -78.182216) (xy 257.928872 -78.182216)
			)
		)
		(polygon
			(pts
				(xy 267.885672 -73.661016) (xy 267.682472 -73.661016) (xy 267.682472 -73.864216) (xy 267.885672 -73.864216)
			)
		)
		(polygon
			(pts
				(xy 267.403072 -73.661016) (xy 267.199872 -73.661016) (xy 267.199872 -73.864216) (xy 267.403072 -73.864216)
			)
		)
		(polygon
			(pts
				(xy 266.641072 -73.661016) (xy 266.437872 -73.661016) (xy 266.437872 -73.864216) (xy 266.641072 -73.864216)
			)
		)
		(polygon
			(pts
				(xy 266.158472 -73.661016) (xy 265.955272 -73.661016) (xy 265.955272 -73.864216) (xy 266.158472 -73.864216)
			)
		)
		(polygon
			(pts
				(xy 265.396472 -73.661016) (xy 265.193272 -73.661016) (xy 265.193272 -73.864216) (xy 265.396472 -73.864216)
			)
		)
		(polygon
			(pts
				(xy 264.913872 -73.661016) (xy 264.710672 -73.661016) (xy 264.710672 -73.864216) (xy 264.913872 -73.864216)
			)
		)
		(polygon
			(pts
				(xy 264.151872 -73.661016) (xy 263.948672 -73.661016) (xy 263.948672 -73.864216) (xy 264.151872 -73.864216)
			)
		)
		(polygon
			(pts
				(xy 263.669272 -73.661016) (xy 263.466072 -73.661016) (xy 263.466072 -73.864216) (xy 263.669272 -73.864216)
			)
		)
		(polygon
			(pts
				(xy 262.907272 -73.661016) (xy 262.704072 -73.661016) (xy 262.704072 -73.864216) (xy 262.907272 -73.864216)
			)
		)
		(polygon
			(pts
				(xy 262.424672 -73.661016) (xy 262.221472 -73.661016) (xy 262.221472 -73.864216) (xy 262.424672 -73.864216)
			)
		)
		(polygon
			(pts
				(xy 261.662672 -73.661016) (xy 261.459472 -73.661016) (xy 261.459472 -73.864216) (xy 261.662672 -73.864216)
			)
		)
		(polygon
			(pts
				(xy 261.180072 -73.661016) (xy 260.976872 -73.661016) (xy 260.976872 -73.864216) (xy 261.180072 -73.864216)
			)
		)
		(polygon
			(pts
				(xy 260.418072 -73.661016) (xy 260.214872 -73.661016) (xy 260.214872 -73.864216) (xy 260.418072 -73.864216)
			)
		)
		(polygon
			(pts
				(xy 259.935472 -73.661016) (xy 259.732272 -73.661016) (xy 259.732272 -73.864216) (xy 259.935472 -73.864216)
			)
		)
		(polygon
			(pts
				(xy 259.173472 -73.661016) (xy 258.970272 -73.661016) (xy 258.970272 -73.864216) (xy 259.173472 -73.864216)
			)
		)
		(polygon
			(pts
				(xy 258.690872 -73.661016) (xy 258.487672 -73.661016) (xy 258.487672 -73.864216) (xy 258.690872 -73.864216)
			)
		)
		(polygon
			(pts
				(xy 257.928872 -73.661016) (xy 257.725672 -73.661016) (xy 257.725672 -73.864216) (xy 257.928872 -73.864216)
			)
		)
		(polygon
			(pts
				(xy 214.9856 -70.7009) (xy 214.7824 -70.7009) (xy 214.7824 -70.9041) (xy 214.9856 -70.9041)
			)
		)
		(polygon
			(pts
				(xy 214.2236 -70.7009) (xy 214.0204 -70.7009) (xy 214.0204 -70.9041) (xy 214.2236 -70.9041)
			)
		)
		(polygon
			(pts
				(xy 214.9856 -63.43142) (xy 214.7824 -63.43142) (xy 214.7824 -63.63462) (xy 214.9856 -63.63462)
			)
		)
		(polygon
			(pts
				(xy 214.2236 -63.43142) (xy 214.0204 -63.43142) (xy 214.0204 -63.63462) (xy 214.2236 -63.63462)
			)
		)
		(polygon
			(pts
				(xy 214.9856 -58.65622) (xy 214.7824 -58.65622) (xy 214.7824 -58.85942) (xy 214.9856 -58.85942)
			)
		)
		(polygon
			(pts
				(xy 214.2236 -58.65622) (xy 214.0204 -58.65622) (xy 214.0204 -58.85942) (xy 214.2236 -58.85942)
			)
		)
		(polygon
			(pts
				(xy 209.8421 -53.07838) (xy 209.6389 -53.07838) (xy 209.6389 -53.28158) (xy 209.8421 -53.28158)
			)
		)
		(polygon
			(pts
				(xy 209.8421 -52.31638) (xy 209.6389 -52.31638) (xy 209.6389 -52.51958) (xy 209.8421 -52.51958)
			)
		)
	)
	(zone
		(layer "F.Cu")
		(hatch none 0.5)
		(connect_pads
			(clearance 0)
		)
		(min_thickness 0.25)
		(keepout
			(tracks not_allowed)
			(vias allowed)
			(pads allowed)
			(copperpour not_allowed)
			(footprints allowed)
		)
		(placement
			(enabled no)
			(sheetname "")
		)
		(fill
			(thermal_gap 0.5)
			(thermal_bridge_width 0.5)
			(island_removal_mode 0)
		)
		(polygon
			(pts
				(arc
					(start 349.394018 -23.05939)
					(mid 349.12109 -23.686929)
					(end 349.701358 -23.324058)
				)
				(arc
					(start 349.612712 -23.34768)
					(mid 349.423609 -23.671658)
					(end 349.097854 -23.485602)
				)
				(arc
					(start 349.097092 -23.483316)
					(mid 349.166287 -23.225473)
					(end 349.424244 -23.156926)
				)
				(xy 349.399098 -23.062438)
			)
		)
	)
	(zone
		(layer "F.Cu")
		(hatch none 0.5)
		(connect_pads
			(clearance 0)
		)
		(min_thickness 0.25)
		(keepout
			(tracks allowed)
			(vias allowed)
			(pads allowed)
			(copperpour allowed)
			(footprints not_allowed)
		)
		(placement
			(enabled no)
			(sheetname "")
		)
		(fill
			(thermal_gap 0.5)
			(thermal_bridge_width 0.5)
			(island_removal_mode 0)
		)
		(polygon
			(pts
				(xy 282.550108 -71.049896) (xy 276.29993 -67.300094) (xy 263.700006 -67.300094) (xy 257.450082 -71.049896)
				(xy 257.450082 -82.049874) (xy 263.700006 -85.79993) (xy 276.29993 -85.79993) (xy 282.550108 -82.049874)
			)
		)
	)
	(zone
		(net "P12V_STBY")
		(layer "F.Cu")
		(hatch none 0.5)
		(connect_pads
			(clearance 0.5)
		)
		(min_thickness 0.25)
		(fill yes
			(thermal_gap 0.5)
			(thermal_bridge_width 0.5)
			(island_removal_mode 0)
		)
		(polygon
			(pts
				(xy 384.684016 -64.794384) (xy 384.9751 -64.5033) (xy 384.9751 -61.6585) (xy 384.8862 -61.5696)
				(xy 383.921 -61.5696) (xy 383.48412 -61.5696) (xy 383.20726 -61.84646) (xy 383.20726 -64.647064)
				(xy 383.35458 -64.794384)
			)
		)
	)
	(zone
		(layer "F.Cu")
		(hatch none 0.5)
		(connect_pads
			(clearance 0)
		)
		(min_thickness 0.25)
		(keepout
			(tracks allowed)
			(vias allowed)
			(pads allowed)
			(copperpour allowed)
			(footprints allowed)
		)
		(placement
			(enabled no)
			(sheetname "")
		)
		(fill
			(thermal_gap 0.5)
			(thermal_bridge_width 0.5)
			(island_removal_mode 0)
		)
		(polygon
			(pts
				(xy 194.818 -52.959) (xy 198.374 -52.959) (xy 198.628 -53.213) (xy 198.628 -54.737) (xy 198.247 -55.118)
				(xy 196.469 -55.118) (xy 196.342 -55.245) (xy 196.342 -57.785) (xy 196.215 -57.912) (xy 194.564 -57.912)
				(xy 194.31 -57.658) (xy 193.802 -57.15) (xy 193.802 -53.467) (xy 194.31 -52.959)
			)
		)
	)
	(zone
		(layer "F.Cu")
		(hatch none 0.5)
		(connect_pads
			(clearance 0)
		)
		(min_thickness 0.25)
		(keepout
			(tracks allowed)
			(vias allowed)
			(pads allowed)
			(copperpour allowed)
			(footprints not_allowed)
		)
		(placement
			(enabled no)
			(sheetname "")
		)
		(fill
			(thermal_gap 0.5)
			(thermal_bridge_width 0.5)
			(island_removal_mode 0)
		)
		(polygon
			(pts
				(arc
					(start 198.930006 -110.10011)
					(mid 195.380102 -106.550206)
					(end 198.930006 -103.000048)
				)
				(arc
					(start 198.930006 -103.000048)
					(mid 202.480164 -106.550206)
					(end 198.930006 -110.10011)
				)
			)
		)
	)
	(zone
		(net "GND")
		(layer "F.Cu")
		(hatch none 0.5)
		(connect_pads
			(clearance 0.5)
		)
		(min_thickness 0.25)
		(fill yes
			(thermal_gap 0.5)
			(thermal_bridge_width 0.5)
			(island_removal_mode 0)
		)
		(polygon
			(pts
				(xy 337.6803 -142.9131) (xy 337.6803 -140.0048) (xy 338.0105 -139.6746) (xy 342.392 -139.6746) (xy 342.5952 -139.8778)
				(xy 342.5952 -140.9065) (xy 342.0745 -141.4272) (xy 342.0745 -143.0655) (xy 342.0745 -143.4211)
				(xy 341.376 -144.1196) (xy 338.8868 -144.1196) (xy 338.3407 -143.5735)
			)
		)
	)
	(zone
		(layer "F.Cu")
		(hatch none 0.5)
		(connect_pads
			(clearance 0)
		)
		(min_thickness 0.25)
		(keepout
			(tracks allowed)
			(vias allowed)
			(pads allowed)
			(copperpour allowed)
			(footprints not_allowed)
		)
		(placement
			(enabled no)
			(sheetname "")
		)
		(fill
			(thermal_gap 0.5)
			(thermal_bridge_width 0.5)
			(island_removal_mode 0)
		)
		(polygon
			(pts
				(arc
					(start 3.50012 -151.100028)
					(mid 7.500112 -155.10002)
					(end 3.50012 -159.100012)
				)
				(arc
					(start 0 -159.100012)
					(mid -3.999992 -155.10002)
					(end 0 -151.100028)
				)
			)
		)
	)
	(zone
		(layer "F.Cu")
		(hatch none 0.5)
		(connect_pads
			(clearance 0)
		)
		(min_thickness 0.25)
		(keepout
			(tracks allowed)
			(vias allowed)
			(pads allowed)
			(copperpour allowed)
			(footprints allowed)
		)
		(placement
			(enabled no)
			(sheetname "")
		)
		(fill
			(thermal_gap 0.5)
			(thermal_bridge_width 0.5)
			(island_removal_mode 0)
		)
		(polygon
			(pts
				(xy 10.807954 3.905504) (xy 12.33297 3.905504) (xy 12.33297 2.381504) (xy 9.66597 2.381504) (xy 9.661906 2.37744)
				(xy 7.94893 2.37744) (xy 7.53491 2.79146) (xy 7.53491 4.642104) (xy 7.602474 4.709668) (xy 10.033 4.709668)
				(xy 10.033 4.680458)
			)
		)
	)
	(zone
		(net "PVTT_GHJ")
		(layer "F.Cu")
		(hatch none 0.5)
		(connect_pads
			(clearance 0.5)
		)
		(min_thickness 0.25)
		(fill yes
			(thermal_gap 0.5)
			(thermal_bridge_width 0.5)
			(island_removal_mode 0)
		)
		(polygon
			(pts
				(xy 94.079568 4.699) (xy 95.984568 4.699) (xy 97.618296 3.065272) (xy 97.618296 0.476504) (xy 99.261168 -1.166368)
				(xy 99.261168 -1.1938) (xy 99.261168 -1.873504) (xy 99.667568 -2.279904) (xy 99.667568 -7.3152)
				(xy 99.667568 -8.610092) (xy 99.5426 -8.73506) (xy 99.5426 -9.741662) (xy 99.667568 -9.86663) (xy 99.667568 -11.529568)
				(xy 99.831144 -11.693144) (xy 99.831144 -11.925808) (xy 99.831144 -14.949424) (xy 99.667568 -15.113)
				(xy 99.667568 -23.400766) (xy 99.666552 -23.401782) (xy 99.666552 -23.584662) (xy 99.568762 -23.682452)
				(xy 99.385882 -23.682452) (xy 97.620582 -23.682452) (xy 96.326452 -23.682452) (xy 96.266 -23.622)
				(xy 96.266 -22.352) (xy 96.393 -22.225) (xy 96.393 -18.542) (xy 94.615 -16.764) (xy 94.234 -16.764)
				(xy 94.039436 -16.569436) (xy 94.039436 -14.520164) (xy 94.0816 -14.478) (xy 95.885 -14.478) (xy 96.266 -14.859)
				(xy 97.07372 -14.859) (xy 97.2185 -14.71422) (xy 97.2185 -13.86332) (xy 97.03816 -13.68298) (xy 97.03816 -12.15898)
				(xy 96.14408 -11.2649) (xy 94.054168 -11.2649) (xy 94.003368 -11.2141) (xy 94.003368 -8.9662) (xy 93.952568 -8.9154)
				(xy 93.952568 -4.447032) (xy 94.1832 -4.2164) (xy 96.5962 -4.2164) (xy 96.7232 -4.0894) (xy 96.7232 -1.6002)
				(xy 96.34855 -1.22555) (xy 95.24746 -1.22555) (xy 95.000572 -1.472438) (xy 95.000572 -1.7272) (xy 94.873572 -1.8542)
				(xy 94.156784 -1.8542) (xy 94.047056 -1.744472) (xy 94.047056 4.666488)
			)
		)
	)
	(zone
		(layer "F.Cu")
		(hatch none 0.5)
		(connect_pads
			(clearance 0)
		)
		(min_thickness 0.25)
		(keepout
			(tracks not_allowed)
			(vias allowed)
			(pads allowed)
			(copperpour not_allowed)
			(footprints allowed)
		)
		(placement
			(enabled no)
			(sheetname "")
		)
		(fill
			(thermal_gap 0.5)
			(thermal_bridge_width 0.5)
			(island_removal_mode 0)
		)
		(polygon
			(pts
				(arc
					(start 173.928532 3.944366)
					(mid 173.338124 3.614384)
					(end 172.671486 3.50012)
				)
				(arc
					(start 171.99991 3.50012)
					(mid 170.50004 2.00025)
					(end 171.99991 0.500126)
				)
				(arc
					(start 172.671486 0.500126)
					(mid 173.338157 0.385742)
					(end 173.928532 0.055626)
				)
				(arc
					(start 173.928532 0.055626)
					(mid 177.999652 1.999996)
					(end 173.928532 3.944366)
				)
			)
		)
	)
	(zone
		(layer "F.Cu")
		(hatch none 0.5)
		(connect_pads
			(clearance 0)
		)
		(min_thickness 0.25)
		(keepout
			(tracks allowed)
			(vias allowed)
			(pads allowed)
			(copperpour allowed)
			(footprints allowed)
		)
		(placement
			(enabled no)
			(sheetname "")
		)
		(fill
			(thermal_gap 0.5)
			(thermal_bridge_width 0.5)
			(island_removal_mode 0)
		)
		(polygon
			(pts
				(xy -0.7112 -136.6774) (xy 1.5748 -136.6774) (xy 1.5748 -138.684) (xy -0.7112 -138.684)
			)
		)
	)
	(zone
		(layer "F.Cu")
		(hatch none 0.5)
		(connect_pads
			(clearance 0)
		)
		(min_thickness 0.25)
		(keepout
			(tracks not_allowed)
			(vias allowed)
			(pads allowed)
			(copperpour not_allowed)
			(footprints allowed)
		)
		(placement
			(enabled no)
			(sheetname "")
		)
		(fill
			(thermal_gap 0.5)
			(thermal_bridge_width 0.5)
			(island_removal_mode 0)
		)
		(polygon
			(pts
				(arc
					(start 380.9111 -26.008584)
					(mid 380.440947 -26.250558)
					(end 380.82982 -25.892252)
				)
				(xy 381.049276 -25.672796) (xy 381.0508 -25.554178) (xy 380.847854 -25.554178)
				(arc
					(start 380.803658 -25.509982)
					(mid 380.482493 -25.090011)
					(end 380.902464 -25.411176)
				)
				(xy 380.905766 -25.414478) (xy 381.052832 -25.414478)
				(arc
					(start 381.05461 -25.284176)
					(mid 380.676531 -24.895304)
					(end 380.28753 -25.273254)
				)
				(arc
					(start 380.2761 -26.09215)
					(mid 380.654306 -26.481024)
					(end 381.04318 -26.102818)
				)
				(xy 381.046482 -25.873202)
			)
		)
	)
	(zone
		(layer "F.Cu")
		(hatch none 0.5)
		(connect_pads
			(clearance 0)
		)
		(min_thickness 0.25)
		(keepout
			(tracks allowed)
			(vias allowed)
			(pads allowed)
			(copperpour allowed)
			(footprints allowed)
		)
		(placement
			(enabled no)
			(sheetname "")
		)
		(fill
			(thermal_gap 0.5)
			(thermal_bridge_width 0.5)
			(island_removal_mode 0)
		)
		(polygon
			(pts
				(xy 13.462 -125.857) (xy 13.462 -125.3236) (xy 13.9954 -125.3236) (xy 13.9954 -125.857)
			)
		)
	)
	(zone
		(layer "F.Cu")
		(hatch none 0.5)
		(connect_pads
			(clearance 0)
		)
		(min_thickness 0.25)
		(keepout
			(tracks not_allowed)
			(vias allowed)
			(pads allowed)
			(copperpour not_allowed)
			(footprints allowed)
		)
		(placement
			(enabled no)
			(sheetname "")
		)
		(fill
			(thermal_gap 0.5)
			(thermal_bridge_width 0.5)
			(island_removal_mode 0)
		)
		(polygon
			(pts
				(arc
					(start 446.921636 -60.315348)
					(mid 447.447464 -60.378848)
					(end 446.921636 -60.442348)
				)
				(xy 446.904364 -60.442348) (xy 446.839848 -60.506864) (xy 446.839848 -60.759086) (xy 446.86855 -60.787788)
				(arc
					(start 447.180462 -60.787788)
					(mid 447.589656 -60.378975)
					(end 447.180716 -59.969908)
				)
				(arc
					(start 445.910716 -59.969908)
					(mid 445.501776 -60.378848)
					(end 445.910716 -60.787788)
				)
				(xy 446.24879 -60.787788) (xy 446.254378 -60.7822) (xy 446.254378 -60.507118) (xy 446.189608 -60.442348)
				(arc
					(start 446.169796 -60.442348)
					(mid 445.643968 -60.378848)
					(end 446.169796 -60.315348)
				)
				(xy 446.189608 -60.315348) (xy 446.24244 -60.315348) (xy 446.279524 -60.352432) (xy 446.344294 -60.417202)
				(xy 446.381378 -60.454286) (xy 446.381378 -60.507118) (xy 446.381378 -60.7822) (xy 446.381378 -60.787788)
				(xy 446.712848 -60.787788) (xy 446.712848 -60.759086) (xy 446.712848 -60.506864) (xy 446.712848 -60.454032)
				(xy 446.749932 -60.416948) (xy 446.814448 -60.352432) (xy 446.851532 -60.315348) (xy 446.904364 -60.315348)
			)
		)
	)
	(zone
		(layer "F.Cu")
		(hatch none 0.5)
		(connect_pads
			(clearance 0)
		)
		(min_thickness 0.25)
		(keepout
			(tracks allowed)
			(vias allowed)
			(pads allowed)
			(copperpour allowed)
			(footprints allowed)
		)
		(placement
			(enabled no)
			(sheetname "")
		)
		(fill
			(thermal_gap 0.5)
			(thermal_bridge_width 0.5)
			(island_removal_mode 0)
		)
		(polygon
			(pts
				(xy 80.439768 -49.911) (xy 81.506568 -49.911) (xy 81.506568 -48.895) (xy 80.795368 -48.1838) (xy 80.439768 -48.1838)
			)
		)
	)
	(zone
		(net "PVDDQ_KLM")
		(layer "F.Cu")
		(hatch none 0.5)
		(connect_pads
			(clearance 0.5)
		)
		(min_thickness 0.25)
		(fill yes
			(thermal_gap 0.5)
			(thermal_bridge_width 0.5)
			(island_removal_mode 0)
		)
		(polygon
			(pts
				(xy 168.178734 -145.8976) (xy 168.178734 -145.92681) (xy 168.808146 -146.556222) (xy 169.318178 -146.556222)
				(xy 169.3926 -146.4818) (xy 169.3926 -143.8148) (xy 169.227246 -143.6497) (xy 167.2209 -143.6497)
				(xy 164.1475 -143.6497) (xy 163.957 -143.8402) (xy 163.957 -144.9578) (xy 163.957 -145.0848) (xy 164.1348 -145.2626)
				(xy 164.2618 -145.2626) (xy 167.543734 -145.2626) (xy 167.645334 -145.3642)
			)
		)
	)
	(zone
		(net "AGND_PVPP_DEF")
		(layer "F.Cu")
		(hatch none 0.5)
		(connect_pads
			(clearance 0.5)
		)
		(min_thickness 0.25)
		(fill yes
			(thermal_gap 0.5)
			(thermal_bridge_width 0.5)
			(island_removal_mode 0)
		)
		(polygon
			(pts
				(xy 343.789 -130.4417) (xy 344.297 -130.4417) (xy 344.424 -130.3147) (xy 344.424 -129.5781) (xy 344.747088 -129.255012)
				(xy 344.747088 -128.417828) (xy 344.69832 -128.36906) (xy 344.33002 -128.36906) (xy 344.2208 -128.47828)
				(xy 344.2208 -128.9939) (xy 344.0557 -129.159) (xy 343.662 -129.5527) (xy 343.662 -130.3147)
			)
		)
	)
	(zone
		(net "VR_PVPP_DEF_PHASE")
		(layer "F.Cu")
		(hatch none 0.5)
		(connect_pads
			(clearance 0.5)
		)
		(min_thickness 0.25)
		(fill yes
			(thermal_gap 0.5)
			(thermal_bridge_width 0.5)
			(island_removal_mode 0)
		)
		(polygon
			(pts
				(xy 336.120232 -129.999994) (xy 336.07883 -130.041396) (xy 336.078322 -130.041396) (xy 336.04073 -130.078988)
				(xy 336.04073 -131.166616) (xy 336.169 -131.294886) (xy 336.169 -136.280144) (xy 337.351878 -137.463022)
				(xy 340.813644 -137.463022) (xy 340.864952 -137.411714) (xy 340.864952 -136.560814) (xy 341.305642 -136.120124)
				(xy 342.342216 -136.120124) (xy 342.392 -136.07034) (xy 342.392 -135.1407) (xy 342.519 -135.0137)
				(xy 346.075 -135.0137) (xy 346.202 -134.8867) (xy 346.202 -132.7277) (xy 346.075 -132.6007) (xy 341.884 -132.6007)
				(xy 341.503 -132.9817) (xy 339.618828 -132.9817) (xy 339.35543 -132.718302) (xy 338.722208 -132.718302)
				(xy 336.955892 -130.951986) (xy 336.955892 -130.074162) (xy 336.881724 -129.999994)
			)
		)
		(polygon
			(pts
				(xy 340.4616 -136.8171) (xy 340.2584 -136.8171) (xy 340.2584 -137.0203) (xy 340.4616 -137.0203)
			)
		)
	)
	(zone
		(layer "F.Cu")
		(hatch none 0.5)
		(connect_pads
			(clearance 0)
		)
		(min_thickness 0.25)
		(keepout
			(tracks allowed)
			(vias allowed)
			(pads allowed)
			(copperpour allowed)
			(footprints not_allowed)
		)
		(placement
			(enabled no)
			(sheetname "")
		)
		(fill
			(thermal_gap 0.5)
			(thermal_bridge_width 0.5)
			(island_removal_mode 0)
		)
		(polygon
			(pts
				(xy 29.420058 -42.049954) (xy 38.01999 -42.049954) (xy 38.01999 -111.05007) (xy 29.420058 -111.05007)
			)
		)
	)
	(zone
		(layer "F.Cu")
		(hatch none 0.5)
		(connect_pads
			(clearance 0)
		)
		(min_thickness 0.25)
		(keepout
			(tracks allowed)
			(vias allowed)
			(pads allowed)
			(copperpour allowed)
			(footprints allowed)
		)
		(placement
			(enabled no)
			(sheetname "")
		)
		(fill
			(thermal_gap 0.5)
			(thermal_bridge_width 0.5)
			(island_removal_mode 0)
		)
		(polygon
			(pts
				(xy 67.409568 -52.705) (xy 67.409568 -52.324) (xy 69.822568 -49.911) (xy 73.505568 -49.911) (xy 73.632568 -49.911)
				(xy 73.632568 -50.546) (xy 70.598792 -53.579776) (xy 68.413122 -53.579776) (xy 67.663568 -53.582316)
				(xy 67.663568 -52.959)
			)
		)
	)
	(zone
		(layer "F.Cu")
		(hatch none 0.5)
		(connect_pads
			(clearance 0)
		)
		(min_thickness 0.25)
		(keepout
			(tracks allowed)
			(vias allowed)
			(pads allowed)
			(copperpour allowed)
			(footprints not_allowed)
		)
		(placement
			(enabled no)
			(sheetname "")
		)
		(fill
			(thermal_gap 0.5)
			(thermal_bridge_width 0.5)
			(island_removal_mode 0)
		)
		(polygon
			(pts
				(arc
					(start 33.919922 -110.10011)
					(mid 30.370018 -106.550206)
					(end 33.919922 -103.000048)
				)
				(arc
					(start 33.919922 -103.000048)
					(mid 37.47008 -106.550206)
					(end 33.919922 -110.10011)
				)
			)
		)
	)
	(zone
		(layer "F.Cu")
		(hatch none 0.5)
		(connect_pads
			(clearance 0)
		)
		(min_thickness 0.25)
		(keepout
			(tracks allowed)
			(vias allowed)
			(pads allowed)
			(copperpour allowed)
			(footprints allowed)
		)
		(placement
			(enabled no)
			(sheetname "")
		)
		(fill
			(thermal_gap 0.5)
			(thermal_bridge_width 0.5)
			(island_removal_mode 0)
		)
		(polygon
			(pts
				(xy 17.421606 -96.923606) (xy 16.8783 -96.3803) (xy 15.6337 -95.1357) (xy 15.1003 -95.1357) (xy 14.5796 -94.615)
				(xy 14.5796 -91.948) (xy 15.4178 -91.1098) (xy 15.4178 -90.5764) (xy 15.7988 -90.1954) (xy 16.6878 -90.1954)
				(xy 16.6878 -89.027) (xy 17.6276 -88.0872) (xy 20.2184 -88.0872) (xy 20.3962 -87.9094) (xy 20.3962 -87.1728)
				(xy 20.5232 -87.0458) (xy 21.844 -87.0458) (xy 21.971 -87.1728) (xy 21.971 -88.646) (xy 22.098 -88.773)
				(xy 22.098 -88.77808) (xy 22.369272 -88.77808) (xy 22.807422 -89.21623) (xy 22.807422 -90.340942)
				(xy 22.89048 -90.424) (xy 25.146 -90.424) (xy 25.273 -90.551) (xy 25.273 -91.567) (xy 24.1808 -91.567)
				(xy 23.7998 -91.948) (xy 23.7998 -94.234) (xy 24.23414 -94.66834) (xy 26.23566 -94.66834) (xy 26.53538 -94.96806)
				(xy 26.53538 -96.66732) (xy 25.5016 -97.7011) (xy 18.1991 -97.7011)
			)
		)
	)
	(zone
		(layer "F.Cu")
		(hatch none 0.5)
		(connect_pads
			(clearance 0)
		)
		(min_thickness 0.25)
		(keepout
			(tracks allowed)
			(vias allowed)
			(pads allowed)
			(copperpour allowed)
			(footprints not_allowed)
		)
		(placement
			(enabled no)
			(sheetname "")
		)
		(fill
			(thermal_gap 0.5)
			(thermal_bridge_width 0.5)
			(island_removal_mode 0)
		)
		(polygon
			(pts
				(xy 382.377188 -149.910038) (xy 393.877038 -149.910038) (xy 393.877038 -143.310102) (xy 382.377188 -143.310102)
			)
		)
	)
	(zone
		(layer "F.Cu")
		(hatch none 0.5)
		(connect_pads
			(clearance 0)
		)
		(min_thickness 0.25)
		(keepout
			(tracks allowed)
			(vias allowed)
			(pads allowed)
			(copperpour allowed)
			(footprints allowed)
		)
		(placement
			(enabled no)
			(sheetname "")
		)
		(fill
			(thermal_gap 0.5)
			(thermal_bridge_width 0.5)
			(island_removal_mode 0)
		)
		(polygon
			(pts
				(xy 106.271568 -106.807) (xy 112.494568 -106.807) (xy 112.494568 -107.95) (xy 112.494568 -112.268)
				(xy 112.494568 -113.61166) (xy 111.986568 -114.11966) (xy 111.933228 -114.173) (xy 106.271568 -114.173)
				(xy 106.144568 -114.173) (xy 106.144568 -106.807)
			)
		)
	)
	(zone
		(net "GND")
		(layer "F.Cu")
		(hatch none 0.5)
		(connect_pads
			(clearance 0.5)
		)
		(min_thickness 0.25)
		(fill yes
			(thermal_gap 0.5)
			(thermal_bridge_width 0.5)
			(island_removal_mode 0)
		)
		(polygon
			(pts
				(xy 114.2238 -4.82727) (xy 114.1222 -4.92887) (xy 114.1222 -6.6294) (xy 114.1222 -6.708394) (xy 114.063526 -6.767068)
				(xy 113.984532 -6.767068) (xy 113.975388 -6.767068) (xy 113.599468 -6.767068) (xy 113.5126 -6.6802)
				(xy 113.5126 -4.353814) (xy 113.306606 -4.14782) (xy 113.306606 -2.7178) (xy 113.350294 -2.674112)
				(xy 113.443258 -2.674112) (xy 113.479072 -2.709926) (xy 113.479072 -3.003296) (xy 113.671604 -3.195828)
				(xy 114.023394 -3.195828) (xy 114.240564 -2.978658) (xy 114.240564 -1.731772) (xy 114.244628 -1.727708)
				(xy 114.4016 -1.570482) (xy 114.4016 0.044196) (xy 114.445034 0.08763) (xy 114.94897 0.08763) (xy 115.063016 -0.026416)
				(xy 115.063016 -2.005584) (xy 115.791488 -2.733802) (xy 115.791488 -4.37769) (xy 115.786916 -4.382516)
				(xy 115.786916 -6.742684) (xy 115.7478 -6.7818) (xy 115.2906 -6.7818) (xy 115.189 -6.6802) (xy 115.189 -4.8768)
				(xy 115.189 -4.221734) (xy 114.942112 -3.974846) (xy 114.534696 -3.974846) (xy 114.31651 -4.193032)
				(xy 114.31651 -4.73456)
			)
		)
	)
	(zone
		(net "P3V3_DB1200_A")
		(layer "F.Cu")
		(hatch none 0.5)
		(connect_pads
			(clearance 0.5)
		)
		(min_thickness 0.25)
		(fill yes
			(thermal_gap 0.5)
			(thermal_bridge_width 0.5)
			(island_removal_mode 0)
		)
		(polygon
			(pts
				(xy 163.2712 -74.549) (xy 162.9918 -74.8284) (xy 162.9918 -75.9714) (xy 163.1442 -76.1238) (xy 165.4302 -76.1238)
				(xy 165.5318 -76.2254) (xy 165.5318 -76.9366) (xy 165.5826 -76.9874) (xy 165.735 -76.9874) (xy 165.8112 -76.9112)
				(xy 165.8112 -74.676) (xy 165.6842 -74.549)
			)
		)
		(polygon
			(pts
				(xy 163.9443 -75.2602) (xy 163.7411 -75.2602) (xy 163.7411 -75.4634) (xy 163.9443 -75.4634)
			)
		)
	)
	(zone
		(layer "F.Cu")
		(hatch none 0.5)
		(connect_pads
			(clearance 0)
		)
		(min_thickness 0.25)
		(keepout
			(tracks allowed)
			(vias allowed)
			(pads allowed)
			(copperpour allowed)
			(footprints allowed)
		)
		(placement
			(enabled no)
			(sheetname "")
		)
		(fill
			(thermal_gap 0.5)
			(thermal_bridge_width 0.5)
			(island_removal_mode 0)
		)
		(polygon
			(pts
				(xy 485.648 2.6162) (xy 485.648 4.953) (xy 479.9584 4.953) (xy 479.9584 2.6162)
			)
		)
	)
	(zone
		(net "P1V15_AUX_BMC")
		(layer "F.Cu")
		(hatch none 0.5)
		(connect_pads
			(clearance 0.5)
		)
		(min_thickness 0.25)
		(fill yes
			(thermal_gap 0.5)
			(thermal_bridge_width 0.5)
			(island_removal_mode 0)
		)
		(polygon
			(pts
				(xy 457.745592 -39.226998) (xy 457.669392 -39.303198) (xy 457.669392 -43.379898) (xy 457.796392 -43.506898)
				(xy 460.323692 -43.506898) (xy 460.793592 -43.036998) (xy 460.793592 -40.395398) (xy 460.768192 -40.369998)
				(xy 459.091792 -40.369998) (xy 458.431392 -39.709598) (xy 458.431392 -39.277798) (xy 458.380592 -39.226998)
			)
		)
		(polygon
			(pts
				(xy 458.469492 -42.681398) (xy 458.266292 -42.681398) (xy 458.266292 -42.884598) (xy 458.469492 -42.884598)
			)
		)
		(polygon
			(pts
				(xy 458.469492 -41.919398) (xy 458.266292 -41.919398) (xy 458.266292 -42.122598) (xy 458.469492 -42.122598)
			)
		)
	)
	(zone
		(layer "F.Cu")
		(hatch none 0.5)
		(connect_pads
			(clearance 0)
		)
		(min_thickness 0.25)
		(keepout
			(tracks allowed)
			(vias allowed)
			(pads allowed)
			(copperpour allowed)
			(footprints allowed)
		)
		(placement
			(enabled no)
			(sheetname "")
		)
		(fill
			(thermal_gap 0.5)
			(thermal_bridge_width 0.5)
			(island_removal_mode 0)
		)
		(polygon
			(pts
				(xy 484.447596 -51.38674) (xy 484.447596 -50.522124) (xy 485.591866 -50.522124) (xy 485.591866 -51.38674)
			)
		)
	)
	(zone
		(net "GND")
		(layer "F.Cu")
		(hatch none 0.5)
		(connect_pads
			(clearance 0.5)
		)
		(min_thickness 0.25)
		(fill yes
			(thermal_gap 0.5)
			(thermal_bridge_width 0.5)
			(island_removal_mode 0)
		)
		(polygon
			(pts
				(xy 333.278988 -40.7924) (xy 350.2406 -40.7924) (xy 350.3422 -40.894) (xy 350.774 -40.894) (xy 350.9772 -40.6908)
				(xy 351.4598 -40.6908) (xy 351.5614 -40.7924) (xy 351.5868 -40.7924) (xy 351.79 -40.9956) (xy 351.79 -41.5036)
				(xy 351.536 -41.7576) (xy 351.536 -42.037) (xy 351.79 -42.291) (xy 351.79 -42.799) (xy 351.5868 -43.0022)
				(xy 351.5868 -43.307) (xy 351.79 -43.5102) (xy 351.79 -44.624244) (xy 352.072956 -44.9072) (xy 354.0252 -44.9072)
				(xy 354.2792 -44.6532) (xy 354.2792 -39.3446) (xy 354.2792 -36.7284) (xy 354.24872 -36.69792) (xy 354.24872 -35.517582)
				(xy 353.746054 -35.014916) (xy 333.803498 -35.014916) (xy 333.435198 -35.383216) (xy 333.335376 -35.483038)
				(xy 333.335376 -37.054282) (xy 333.09179 -37.297868) (xy 333.09179 -37.934392) (xy 333.134208 -37.97681)
				(xy 333.134208 -38.255448) (xy 333.080868 -38.308788) (xy 333.080868 -38.851078) (xy 333.09179 -38.862)
				(xy 333.272892 -39.043102) (xy 333.272892 -39.083742) (xy 333.272892 -39.558214) (xy 333.09179 -39.739316)
				(xy 333.09179 -40.605202)
			)
		)
		(polygon
			(pts
				(xy 335.814162 -36.8427) (xy 334.954372 -36.8427) (xy 334.662018 -37.135054) (xy 334.662018 -37.54755)
				(xy 334.935322 -37.820854) (xy 335.12633 -37.629846) (xy 335.12633 -37.329618) (xy 335.218024 -37.237924)
				(xy 335.58099 -37.237924) (xy 335.814162 -37.004752)
			)
		)
		(polygon
			(pts
				(xy 335.230724 -38.724078) (xy 335.136236 -38.724078) (xy 335.040478 -38.819836) (xy 335.040478 -38.887908)
				(xy 335.068672 -38.916102) (xy 335.07172 -38.916102) (xy 335.230724 -38.757098)
			)
		)
	)
	(zone
		(net "GND")
		(layer "F.Cu")
		(hatch none 0.5)
		(connect_pads
			(clearance 0.5)
		)
		(min_thickness 0.25)
		(fill yes
			(thermal_gap 0.5)
			(thermal_bridge_width 0.5)
			(island_removal_mode 0)
		)
		(polygon
			(pts
				(xy 261.6454 -25.6794) (xy 263.017 -25.6794) (xy 263.2964 -25.4) (xy 263.2964 -24.5364) (xy 262.8138 -24.0538)
				(xy 261.3152 -24.0538) (xy 261.1882 -24.1808) (xy 261.1882 -25.2222)
			)
		)
	)
	(zone
		(net "GND")
		(layer "F.Cu")
		(hatch none 0.5)
		(connect_pads
			(clearance 0.5)
		)
		(min_thickness 0.25)
		(fill yes
			(thermal_gap 0.5)
			(thermal_bridge_width 0.5)
			(island_removal_mode 0)
		)
		(polygon
			(pts
				(xy 404.046436 -56.076596) (xy 407.903172 -56.076596) (xy 408.073606 -56.24703) (xy 408.073606 -57.396126)
				(xy 408.037284 -57.432448) (xy 404.717758 -57.432448) (xy 404.706582 -57.421272) (xy 404.01748 -57.421272)
				(xy 403.777196 -57.180988) (xy 403.77364 -57.180988) (xy 403.77364 -56.173878) (xy 403.870922 -56.076596)
			)
		)
	)
	(zone
		(net "P12V_STBY")
		(layer "F.Cu")
		(hatch none 0.5)
		(connect_pads
			(clearance 0.5)
		)
		(min_thickness 0.25)
		(fill yes
			(thermal_gap 0.5)
			(thermal_bridge_width 0.5)
			(island_removal_mode 0)
		)
		(polygon
			(pts
				(xy 22.7838 -127.5334) (xy 28.6766 -127.5334) (xy 30.607 -127.5334) (xy 36.501578 -127.5334) (xy 37.775388 -126.25959)
				(xy 37.775388 -120.365012) (xy 37.775388 -118.996714) (xy 36.951412 -118.172738) (xy 31.84525 -118.172738)
				(xy 25.534874 -118.172738) (xy 25.517348 -118.190264) (xy 24.61006 -118.190264) (xy 24.187912 -118.612412)
				(xy 24.187912 -121.422414) (xy 24.665686 -121.900188) (xy 24.665686 -122.527314) (xy 24.3713 -122.8217)
				(xy 22.431756 -122.8217) (xy 22.03196 -123.221496) (xy 22.03196 -125.96876) (xy 22.03196 -127.23876)
				(xy 22.3266 -127.5334)
			)
		)
	)
	(zone
		(layer "F.Cu")
		(hatch none 0.5)
		(connect_pads
			(clearance 0)
		)
		(min_thickness 0.25)
		(keepout
			(tracks not_allowed)
			(vias allowed)
			(pads allowed)
			(copperpour not_allowed)
			(footprints allowed)
		)
		(placement
			(enabled no)
			(sheetname "")
		)
		(fill
			(thermal_gap 0.5)
			(thermal_bridge_width 0.5)
			(island_removal_mode 0)
		)
		(polygon
			(pts
				(xy 462.54924 -114.020092) (xy 462.54924 -114.295682) (xy 462.37144 -114.473482)
				(arc
					(start 462.222342 -114.473482)
					(mid 461.698425 -114.403632)
					(end 462.222342 -114.333782)
				)
				(xy 462.313528 -114.333782) (xy 462.40954 -114.23777) (xy 462.40954 -114.020092)
				(arc
					(start 461.965294 -114.020092)
					(mid 461.5815 -114.403505)
					(end 461.96504 -114.787172)
				)
				(arc
					(start 463.23504 -114.787172)
					(mid 463.61858 -114.403632)
					(end 463.23504 -114.020092)
				)
				(xy 462.79054 -114.020092) (xy 462.79054 -114.23777) (xy 462.886552 -114.333782)
				(arc
					(start 462.977738 -114.333782)
					(mid 463.501655 -114.403632)
					(end 462.977738 -114.473482)
				)
				(xy 462.82864 -114.473482) (xy 462.65084 -114.295682) (xy 462.65084 -114.020092)
			)
		)
	)
	(zone
		(net "VR_FET_SW_P12V_STBY_PVCCIN_CPU0")
		(layer "F.Cu")
		(hatch none 0.5)
		(connect_pads
			(clearance 0.5)
		)
		(min_thickness 0.25)
		(fill yes
			(thermal_gap 0.5)
			(thermal_bridge_width 0.5)
			(island_removal_mode 0)
		)
		(polygon
			(pts
				(xy 196.487034 -83.316064) (xy 196.614034 -83.189064) (xy 196.614034 -83.17738) (xy 196.648832 -83.142582)
				(xy 196.648832 -81.817972) (xy 196.661024 -81.80578) (xy 198.6153 -81.80578) (xy 198.631048 -81.821528)
				(xy 198.631048 -84.16798) (xy 198.613014 -84.186014) (xy 198.613014 -85.104986) (xy 198.561198 -85.156802)
				(xy 198.373238 -85.156802) (xy 194.905884 -85.156802) (xy 194.905884 -85.156548) (xy 194.866006 -85.11667)
				(xy 194.866006 -84.959698) (xy 194.866006 -84.95157) (xy 194.488308 -84.573872) (xy 194.488308 -83.607148)
				(xy 194.533774 -83.561682) (xy 195.24853 -83.561682) (xy 195.277232 -83.53298) (xy 195.353432 -83.45678)
				(xy 195.355718 -83.45678) (xy 195.496434 -83.316064)
			)
		)
	)
	(zone
		(net "P1V8_MCP_CPU0")
		(layer "F.Cu")
		(hatch none 0.5)
		(connect_pads
			(clearance 0.5)
		)
		(min_thickness 0.25)
		(fill yes
			(thermal_gap 0.5)
			(thermal_bridge_width 0.5)
			(island_removal_mode 0)
		)
		(polygon
			(pts
				(xy 293.5732 -49.53) (xy 293.2176 -49.8856) (xy 293.2176 -51.970432) (xy 293.367968 -52.1208) (xy 297.204384 -52.1208)
				(xy 297.242992 -52.082192) (xy 297.242992 -51.194208) (xy 297.6372 -50.8) (xy 300.863 -50.8) (xy 301.403004 -50.8)
				(xy 302.850804 -49.3522) (xy 304.1142 -49.3522) (xy 305.435 -48.0314) (xy 314.570364 -48.0314) (xy 321.860418 -40.7416)
				(xy 330.9874 -40.7416) (xy 332.688692 -40.7416) (xy 332.835758 -40.594534) (xy 332.835758 -39.645844)
				(xy 332.835758 -39.626032) (xy 333.01051 -39.45128) (xy 333.01051 -39.157656) (xy 332.53172 -38.678866)
				(xy 332.53172 -38.645846) (xy 332.53172 -38.405054) (xy 332.394306 -38.26764) (xy 332.394306 -37.957506)
				(xy 332.617572 -37.73424) (xy 332.795372 -37.73424) (xy 332.834234 -37.695378) (xy 332.834234 -37.186362)
				(xy 332.856332 -37.164264) (xy 333.035656 -36.98494) (xy 333.035656 -36.698682) (xy 332.885796 -36.548822)
				(xy 331.215492 -36.548822) (xy 330.669392 -37.094922) (xy 329.361546 -37.094922) (xy 322.876418 -37.094922)
				(xy 322.31076 -36.529264) (xy 319.395602 -36.529264) (xy 319.33261 -36.592256) (xy 318.200786 -36.592256)
				(xy 316.772036 -38.021006) (xy 310.263794 -38.021006) (xy 301.164498 -47.120302) (xy 299.489368 -48.795432)
				(xy 299.026834 -48.795432) (xy 296.4434 -48.795432) (xy 295.759632 -49.4792) (xy 295.529 -49.4792)
				(xy 293.624 -49.4792)
			)
		)
	)
	(zone
		(layer "F.Cu")
		(hatch none 0.5)
		(connect_pads
			(clearance 0)
		)
		(min_thickness 0.25)
		(keepout
			(tracks not_allowed)
			(vias allowed)
			(pads allowed)
			(copperpour not_allowed)
			(footprints allowed)
		)
		(placement
			(enabled no)
			(sheetname "")
		)
		(fill
			(thermal_gap 0.5)
			(thermal_bridge_width 0.5)
			(island_removal_mode 0)
		)
		(polygon
			(pts
				(xy 398.636744 -103.913432) (xy 398.587976 -103.895398) (xy 398.565878 -103.848154) (xy 398.583912 -103.799386)
				(arc
					(start 398.86763 -103.66756)
					(mid 399.192055 -103.355932)
					(end 399.337784 -103.781352)
				)
				(arc
					(start 399.446496 -103.781352)
					(mid 399.435621 -103.429828)
					(end 399.12925 -103.257096)
				)
				(arc
					(start 398.138904 -103.257096)
					(mid 397.854986 -103.396606)
					(end 397.792448 -103.706676)
				)
				(arc
					(start 397.87703 -103.66756)
					(mid 398.380028 -103.502329)
					(end 397.930116 -103.781352)
				)
				(arc
					(start 397.84528 -103.820722)
					(mid 397.973286 -103.932955)
					(end 398.13865 -103.973376)
				)
				(arc
					(start 399.12925 -103.973376)
					(mid 399.31346 -103.922369)
					(end 399.445226 -103.783892)
				)
				(arc
					(start 399.335752 -103.783892)
					(mid 399.12925 -103.881859)
					(end 398.922748 -103.783892)
				)
				(xy 398.920462 -103.783892) (xy 398.920462 -103.781606)
			)
		)
	)
	(zone
		(layer "F.Cu")
		(hatch none 0.5)
		(connect_pads
			(clearance 0)
		)
		(min_thickness 0.25)
		(keepout
			(tracks allowed)
			(vias allowed)
			(pads allowed)
			(copperpour allowed)
			(footprints allowed)
		)
		(placement
			(enabled no)
			(sheetname "")
		)
		(fill
			(thermal_gap 0.5)
			(thermal_bridge_width 0.5)
			(island_removal_mode 0)
		)
		(polygon
			(pts
				(xy 74.267568 -44.323) (xy 76.680568 -41.91) (xy 77.950568 -40.64) (xy 79.093568 -40.64) (xy 80.109568 -41.656)
				(xy 76.045568 -45.72) (xy 74.267568 -45.72) (xy 73.759568 -45.212) (xy 73.759568 -44.831)
			)
		)
	)
	(zone
		(layer "F.Cu")
		(hatch none 0.5)
		(connect_pads
			(clearance 0)
		)
		(min_thickness 0.25)
		(keepout
			(tracks allowed)
			(vias allowed)
			(pads allowed)
			(copperpour allowed)
			(footprints allowed)
		)
		(placement
			(enabled no)
			(sheetname "")
		)
		(fill
			(thermal_gap 0.5)
			(thermal_bridge_width 0.5)
			(island_removal_mode 0)
		)
		(polygon
			(pts
				(xy -0.158496 -134.357618) (xy 2.000504 -134.357618) (xy 2.000504 -136.008618) (xy -0.158496 -136.008618)
			)
		)
	)
	(zone
		(layer "F.Cu")
		(hatch none 0.5)
		(connect_pads
			(clearance 0)
		)
		(min_thickness 0.25)
		(keepout
			(tracks not_allowed)
			(vias allowed)
			(pads allowed)
			(copperpour not_allowed)
			(footprints allowed)
		)
		(placement
			(enabled no)
			(sheetname "")
		)
		(fill
			(thermal_gap 0.5)
			(thermal_bridge_width 0.5)
			(island_removal_mode 0)
		)
		(polygon
			(pts
				(xy 396.01394 -32.39135) (xy 395.97838 -32.39135)
				(arc
					(start 395.866112 -32.503618)
					(mid 395.959001 -32.572535)
					(end 396.01394 -32.674306)
				)
			)
		)
	)
	(zone
		(layer "F.Cu")
		(hatch none 0.5)
		(connect_pads
			(clearance 0)
		)
		(min_thickness 0.25)
		(keepout
			(tracks not_allowed)
			(vias allowed)
			(pads allowed)
			(copperpour not_allowed)
			(footprints allowed)
		)
		(placement
			(enabled no)
			(sheetname "")
		)
		(fill
			(thermal_gap 0.5)
			(thermal_bridge_width 0.5)
			(island_removal_mode 0)
		)
		(polygon
			(pts
				(arc
					(start 248.000012 -39.010082)
					(mid 250.540012 -41.550082)
					(end 248.000012 -44.090082)
				)
				(arc
					(start 248.000012 -44.090082)
					(mid 245.460012 -41.550082)
					(end 248.000012 -39.010082)
				)
			)
		)
	)
	(zone
		(layer "F.Cu")
		(hatch none 0.5)
		(connect_pads
			(clearance 0)
		)
		(min_thickness 0.25)
		(keepout
			(tracks not_allowed)
			(vias allowed)
			(pads allowed)
			(copperpour not_allowed)
			(footprints allowed)
		)
		(placement
			(enabled no)
			(sheetname "")
		)
		(fill
			(thermal_gap 0.5)
			(thermal_bridge_width 0.5)
			(island_removal_mode 0)
		)
		(polygon
			(pts
				(xy 419.610032 -92.38615) (xy 419.726364 -92.502482)
				(arc
					(start 419.726364 -92.605352)
					(mid 419.655244 -93.129105)
					(end 419.584124 -92.605352)
				)
				(xy 419.584124 -92.56141) (xy 419.551104 -92.52839) (xy 419.399974 -92.52839) (xy 419.246304 -92.68206)
				(arc
					(start 419.246304 -92.862146)
					(mid 419.655117 -93.27134)
					(end 420.064184 -92.8624)
				)
				(arc
					(start 420.064184 -91.5924)
					(mid 419.655244 -91.18346)
					(end 419.246304 -91.5924)
				)
				(xy 419.246304 -91.770708) (xy 419.402006 -91.92641) (xy 419.551104 -91.92641) (xy 419.584124 -91.89339)
				(arc
					(start 419.584124 -91.849448)
					(mid 419.655244 -91.325695)
					(end 419.726364 -91.849448)
				)
				(xy 419.726364 -91.952318) (xy 419.610032 -92.06865) (xy 419.343078 -92.06865) (xy 419.246304 -91.971876)
				(xy 419.246304 -92.480892) (xy 419.341046 -92.38615)
			)
		)
	)
	(zone
		(net "VR_FET_SW_P12V_STBY_PVDDQ_KLM")
		(layer "F.Cu")
		(hatch none 0.5)
		(connect_pads
			(clearance 0.5)
		)
		(min_thickness 0.25)
		(fill yes
			(thermal_gap 0.5)
			(thermal_bridge_width 0.5)
			(island_removal_mode 0)
		)
		(polygon
			(pts
				(xy -0.040894 -140.076682) (xy 0.086106 -139.949682) (xy 0.086106 -139.937998) (xy 0.120904 -139.9032)
				(xy 0.120904 -138.566398) (xy 2.10312 -138.566398) (xy 2.10312 -140.928598) (xy 2.10312 -141.76248)
				(xy 2.10312 -142.193772) (xy 2.10312 -142.272766) (xy 2.050288 -142.325598) (xy 1.971294 -142.325598)
				(xy 1.540002 -142.325598) (xy 0.70612 -142.325598) (xy -1.428496 -142.325598) (xy -1.794002 -142.325598)
				(xy -1.987296 -142.132304) (xy -2.0066 -142.113) (xy -2.0066 -140.547598) (xy -1.914652 -140.455396)
				(xy -1.412748 -140.455396) (xy -1.25095 -140.293598) (xy -1.243076 -140.285724) (xy -1.174496 -140.217398)
				(xy -1.17221 -140.217398) (xy -1.031494 -140.076682)
			)
		)
	)
	(zone
		(net "GND")
		(layer "F.Cu")
		(hatch none 0.5)
		(connect_pads
			(clearance 0.5)
		)
		(min_thickness 0.25)
		(fill yes
			(thermal_gap 0.5)
			(thermal_bridge_width 0.5)
			(island_removal_mode 0)
		)
		(polygon
			(pts
				(xy 178.166776 -125.359922) (xy 178.166776 -112.861344) (xy 178.411378 -112.616742) (xy 179.114958 -112.616742)
				(xy 179.167282 -112.669066) (xy 179.167282 -123.718574) (xy 180.03012 -124.581412) (xy 180.1622 -124.713492)
				(xy 180.3146 -124.865892) (xy 180.3146 -125.9332) (xy 180.0352 -126.2126) (xy 179.8828 -126.2126)
				(xy 178.435 -126.2126) (xy 178.166776 -125.944376)
			)
		)
	)
	(zone
		(layer "F.Cu")
		(hatch none 0.5)
		(connect_pads
			(clearance 0)
		)
		(min_thickness 0.25)
		(keepout
			(tracks allowed)
			(vias allowed)
			(pads allowed)
			(copperpour allowed)
			(footprints allowed)
		)
		(placement
			(enabled no)
			(sheetname "")
		)
		(fill
			(thermal_gap 0.5)
			(thermal_bridge_width 0.5)
			(island_removal_mode 0)
		)
		(polygon
			(pts
				(xy 480.536504 -29.275786) (xy 481.660708 -29.275786) (xy 481.75037 -29.365448) (xy 482.12502 -29.365448)
				(xy 482.227128 -29.26334) (xy 482.227128 -28.63977) (xy 481.958396 -28.371038) (xy 480.597464 -28.371038)
				(xy 480.39782 -28.570682) (xy 480.39782 -29.137102)
			)
		)
	)
	(zone
		(layer "F.Cu")
		(hatch none 0.5)
		(connect_pads
			(clearance 0)
		)
		(min_thickness 0.25)
		(keepout
			(tracks allowed)
			(vias allowed)
			(pads allowed)
			(copperpour allowed)
			(footprints allowed)
		)
		(placement
			(enabled no)
			(sheetname "")
		)
		(fill
			(thermal_gap 0.5)
			(thermal_bridge_width 0.5)
			(island_removal_mode 0)
		)
		(polygon
			(pts
				(xy 470.5096 -27.9019) (xy 470.9922 -27.9019) (xy 471.17 -27.7241) (xy 471.17 -26.5811) (xy 470.8906 -26.3017)
				(xy 470.3191 -26.3017) (xy 470.2683 -26.3525) (xy 470.2683 -27.6606)
			)
		)
	)
	(zone
		(net "GND")
		(layer "F.Cu")
		(hatch none 0.5)
		(connect_pads
			(clearance 0.5)
		)
		(min_thickness 0.25)
		(fill yes
			(thermal_gap 0.5)
			(thermal_bridge_width 0.5)
			(island_removal_mode 0)
		)
		(polygon
			(pts
				(xy 468.757 -40.513) (xy 471.297 -40.513) (xy 471.424 -40.386) (xy 471.424 -38.8874) (xy 471.297 -38.7604)
				(xy 468.8586 -38.7604) (xy 468.7062 -38.9128) (xy 468.7062 -40.4622)
			)
		)
	)
	(zone
		(layer "F.Cu")
		(hatch none 0.5)
		(connect_pads
			(clearance 0)
		)
		(min_thickness 0.25)
		(keepout
			(tracks allowed)
			(vias allowed)
			(pads allowed)
			(copperpour allowed)
			(footprints allowed)
		)
		(placement
			(enabled no)
			(sheetname "")
		)
		(fill
			(thermal_gap 0.5)
			(thermal_bridge_width 0.5)
			(island_removal_mode 0)
		)
		(polygon
			(pts
				(xy 469.548464 -24.083264) (xy 470.020904 -24.083264) (xy 470.208356 -23.895812) (xy 470.208356 -22.335236)
				(xy 469.95969 -22.08657) (xy 468.924894 -22.08657) (xy 468.521288 -22.490176) (xy 468.521288 -23.549356)
				(xy 468.561166 -23.589234) (xy 469.054434 -23.589234)
			)
		)
	)
	(zone
		(layer "F.Cu")
		(hatch none 0.5)
		(connect_pads
			(clearance 0)
		)
		(min_thickness 0.25)
		(keepout
			(tracks allowed)
			(vias allowed)
			(pads allowed)
			(copperpour allowed)
			(footprints allowed)
		)
		(placement
			(enabled no)
			(sheetname "")
		)
		(fill
			(thermal_gap 0.5)
			(thermal_bridge_width 0.5)
			(island_removal_mode 0)
		)
		(polygon
			(pts
				(xy 18.161 -71.882) (xy 20.447 -71.882) (xy 20.447 -73.914) (xy 18.161 -73.914)
			)
		)
	)
	(zone
		(net "PVDDQ_ABC")
		(layer "F.Cu")
		(hatch none 0.5)
		(connect_pads
			(clearance 0.5)
		)
		(min_thickness 0.25)
		(fill yes
			(thermal_gap 0.5)
			(thermal_bridge_width 0.5)
			(island_removal_mode 0)
		)
		(polygon
			(pts
				(xy 257.78714 -12.30884) (xy 257.73507 -12.36091) (xy 257.73507 -13.48613) (xy 257.95986 -13.71092)
				(xy 257.95986 -16.93418) (xy 258.11988 -17.0942) (xy 258.57962 -17.0942) (xy 258.73964 -16.93418)
				(xy 258.73964 -14.29766) (xy 258.88696 -14.15034) (xy 259.46862 -14.15034) (xy 260.01726 -13.6017)
				(xy 260.01726 -12.35964) (xy 259.96646 -12.30884)
			)
		)
		(polygon
			(pts
				(xy 258.7117 -13.2969) (xy 258.5085 -13.2969) (xy 258.5085 -13.5001) (xy 258.7117 -13.5001)
			)
		)
	)
	(zone
		(net "GND")
		(layer "F.Cu")
		(hatch none 0.5)
		(connect_pads
			(clearance 0.5)
		)
		(min_thickness 0.25)
		(fill yes
			(thermal_gap 0.5)
			(thermal_bridge_width 0.5)
			(island_removal_mode 0)
		)
		(polygon
			(pts
				(xy 89.793318 -12.452096) (xy 89.497662 -12.747752) (xy 89.497662 -13.19149) (xy 89.565734 -13.259562)
				(xy 90.441526 -13.259562) (xy 90.578178 -13.396214) (xy 90.987626 -13.396214) (xy 91.05138 -13.33246)
				(xy 91.05138 -12.452096)
			)
		)
	)
	(zone
		(layer "F.Cu")
		(hatch none 0.5)
		(connect_pads
			(clearance 0)
		)
		(min_thickness 0.25)
		(keepout
			(tracks allowed)
			(vias allowed)
			(pads allowed)
			(copperpour allowed)
			(footprints allowed)
		)
		(placement
			(enabled no)
			(sheetname "")
		)
		(fill
			(thermal_gap 0.5)
			(thermal_bridge_width 0.5)
			(island_removal_mode 0)
		)
		(polygon
			(pts
				(xy 488.5944 -46.2788) (xy 488.5944 -44.4754) (xy 490.6264 -44.4754) (xy 490.6264 -46.2788)
			)
		)
	)
	(zone
		(net "GND")
		(layer "F.Cu")
		(hatch none 0.5)
		(connect_pads
			(clearance 0.5)
		)
		(min_thickness 0.25)
		(fill yes
			(thermal_gap 0.5)
			(thermal_bridge_width 0.5)
			(island_removal_mode 0)
		)
		(polygon
			(pts
				(xy 278.384 -72.6948) (xy 278.0792 -72.9996) (xy 278.0792 -74.7014) (xy 277.886414 -74.894186) (xy 263.435846 -74.894186)
				(xy 263.432544 -74.890884) (xy 257.93954 -74.890884) (xy 257.748024 -75.0824) (xy 257.748024 -76.529438)
				(xy 257.9116 -76.693014) (xy 263.336532 -76.693014) (xy 268.62278 -76.686664) (xy 272.258536 -76.686664)
				(xy 272.4658 -76.4794) (xy 279.908 -76.4794) (xy 279.9334 -76.454) (xy 280.2382 -76.454) (xy 280.8478 -77.0636)
				(xy 280.8478 -79.6036) (xy 281.2288 -79.9846) (xy 282.2194 -79.9846) (xy 282.4607 -80.2259) (xy 282.6385 -80.2259)
				(xy 282.8798 -79.9846) (xy 282.8798 -79.248) (xy 282.6512 -79.0194) (xy 281.559 -79.0194) (xy 281.41295 -78.87335)
				(xy 281.41295 -75.66025) (xy 281.2796 -75.5269) (xy 280.9367 -75.5269) (xy 280.67 -75.2602) (xy 280.67 -72.8218)
				(xy 280.543 -72.6948)
			)
		)
		(polygon
			(pts
				(xy 281.0256 -76.4794) (xy 280.8224 -76.4794) (xy 280.8224 -76.6826) (xy 281.0256 -76.6826)
			)
		)
		(polygon
			(pts
				(xy 281.0256 -76.0984) (xy 280.8224 -76.0984) (xy 280.8224 -76.3016) (xy 281.0256 -76.3016)
			)
		)
		(polygon
			(pts
				(xy 272.381472 -75.693016) (xy 272.178272 -75.693016) (xy 272.178272 -75.896216) (xy 272.381472 -75.896216)
			)
		)
		(polygon
			(pts
				(xy 271.619472 -75.693016) (xy 271.416272 -75.693016) (xy 271.416272 -75.896216) (xy 271.619472 -75.896216)
			)
		)
		(polygon
			(pts
				(xy 271.136872 -75.693016) (xy 270.933672 -75.693016) (xy 270.933672 -75.896216) (xy 271.136872 -75.896216)
			)
		)
		(polygon
			(pts
				(xy 270.374872 -75.693016) (xy 270.171672 -75.693016) (xy 270.171672 -75.896216) (xy 270.374872 -75.896216)
			)
		)
		(polygon
			(pts
				(xy 269.892272 -75.693016) (xy 269.689072 -75.693016) (xy 269.689072 -75.896216) (xy 269.892272 -75.896216)
			)
		)
		(polygon
			(pts
				(xy 269.130272 -75.693016) (xy 268.927072 -75.693016) (xy 268.927072 -75.896216) (xy 269.130272 -75.896216)
			)
		)
		(polygon
			(pts
				(xy 268.647672 -75.693016) (xy 268.444472 -75.693016) (xy 268.444472 -75.896216) (xy 268.647672 -75.896216)
			)
		)
		(polygon
			(pts
				(xy 267.885672 -75.693016) (xy 267.682472 -75.693016) (xy 267.682472 -75.896216) (xy 267.885672 -75.896216)
			)
		)
		(polygon
			(pts
				(xy 267.403072 -75.693016) (xy 267.199872 -75.693016) (xy 267.199872 -75.896216) (xy 267.403072 -75.896216)
			)
		)
		(polygon
			(pts
				(xy 266.641072 -75.693016) (xy 266.437872 -75.693016) (xy 266.437872 -75.896216) (xy 266.641072 -75.896216)
			)
		)
		(polygon
			(pts
				(xy 266.158472 -75.693016) (xy 265.955272 -75.693016) (xy 265.955272 -75.896216) (xy 266.158472 -75.896216)
			)
		)
		(polygon
			(pts
				(xy 265.396472 -75.693016) (xy 265.193272 -75.693016) (xy 265.193272 -75.896216) (xy 265.396472 -75.896216)
			)
		)
		(polygon
			(pts
				(xy 264.913872 -75.693016) (xy 264.710672 -75.693016) (xy 264.710672 -75.896216) (xy 264.913872 -75.896216)
			)
		)
		(polygon
			(pts
				(xy 264.151872 -75.693016) (xy 263.948672 -75.693016) (xy 263.948672 -75.896216) (xy 264.151872 -75.896216)
			)
		)
		(polygon
			(pts
				(xy 263.669272 -75.693016) (xy 263.466072 -75.693016) (xy 263.466072 -75.896216) (xy 263.669272 -75.896216)
			)
		)
		(polygon
			(pts
				(xy 262.907272 -75.693016) (xy 262.704072 -75.693016) (xy 262.704072 -75.896216) (xy 262.907272 -75.896216)
			)
		)
		(polygon
			(pts
				(xy 262.424672 -75.693016) (xy 262.221472 -75.693016) (xy 262.221472 -75.896216) (xy 262.424672 -75.896216)
			)
		)
		(polygon
			(pts
				(xy 261.662672 -75.693016) (xy 261.459472 -75.693016) (xy 261.459472 -75.896216) (xy 261.662672 -75.896216)
			)
		)
		(polygon
			(pts
				(xy 261.180072 -75.693016) (xy 260.976872 -75.693016) (xy 260.976872 -75.896216) (xy 261.180072 -75.896216)
			)
		)
		(polygon
			(pts
				(xy 260.418072 -75.693016) (xy 260.214872 -75.693016) (xy 260.214872 -75.896216) (xy 260.418072 -75.896216)
			)
		)
		(polygon
			(pts
				(xy 259.935472 -75.693016) (xy 259.732272 -75.693016) (xy 259.732272 -75.896216) (xy 259.935472 -75.896216)
			)
		)
		(polygon
			(pts
				(xy 259.173472 -75.693016) (xy 258.970272 -75.693016) (xy 258.970272 -75.896216) (xy 259.173472 -75.896216)
			)
		)
		(polygon
			(pts
				(xy 258.690872 -75.693016) (xy 258.487672 -75.693016) (xy 258.487672 -75.896216) (xy 258.690872 -75.896216)
			)
		)
		(polygon
			(pts
				(xy 276.391624 -75.486514) (xy 276.188424 -75.486514) (xy 276.188424 -75.689714) (xy 276.391624 -75.689714)
			)
		)
		(polygon
			(pts
				(xy 275.629624 -75.486514) (xy 275.426424 -75.486514) (xy 275.426424 -75.689714) (xy 275.629624 -75.689714)
			)
		)
		(polygon
			(pts
				(xy 275.121624 -75.486514) (xy 274.918424 -75.486514) (xy 274.918424 -75.689714) (xy 275.121624 -75.689714)
			)
		)
		(polygon
			(pts
				(xy 274.359624 -75.486514) (xy 274.156424 -75.486514) (xy 274.156424 -75.689714) (xy 274.359624 -75.689714)
			)
		)
		(polygon
			(pts
				(xy 273.851624 -75.486514) (xy 273.648424 -75.486514) (xy 273.648424 -75.689714) (xy 273.851624 -75.689714)
			)
		)
		(polygon
			(pts
				(xy 273.089624 -75.486514) (xy 272.886424 -75.486514) (xy 272.886424 -75.689714) (xy 273.089624 -75.689714)
			)
		)
		(polygon
			(pts
				(xy 280.154634 -75.439016) (xy 279.951434 -75.439016) (xy 279.951434 -75.642216) (xy 280.154634 -75.642216)
			)
		)
		(polygon
			(pts
				(xy 279.392634 -75.439016) (xy 279.189434 -75.439016) (xy 279.189434 -75.642216) (xy 279.392634 -75.642216)
			)
		)
		(polygon
			(pts
				(xy 278.910034 -75.439016) (xy 278.706834 -75.439016) (xy 278.706834 -75.642216) (xy 278.910034 -75.642216)
			)
		)
		(polygon
			(pts
				(xy 278.148034 -75.439016) (xy 277.944834 -75.439016) (xy 277.944834 -75.642216) (xy 278.148034 -75.642216)
			)
		)
		(polygon
			(pts
				(xy 277.665434 -75.439016) (xy 277.462234 -75.439016) (xy 277.462234 -75.642216) (xy 277.665434 -75.642216)
			)
		)
		(polygon
			(pts
				(xy 276.903434 -75.439016) (xy 276.700234 -75.439016) (xy 276.700234 -75.642216) (xy 276.903434 -75.642216)
			)
		)
		(polygon
			(pts
				(xy 279.858724 -73.454514) (xy 279.655524 -73.454514) (xy 279.655524 -73.657714) (xy 279.858724 -73.657714)
			)
		)
		(polygon
			(pts
				(xy 279.350724 -73.454514) (xy 279.147524 -73.454514) (xy 279.147524 -73.657714) (xy 279.350724 -73.657714)
			)
		)
		(polygon
			(pts
				(xy 278.588724 -73.454514) (xy 278.385524 -73.454514) (xy 278.385524 -73.657714) (xy 278.588724 -73.657714)
			)
		)
	)
	(zone
		(layer "F.Cu")
		(hatch none 0.5)
		(connect_pads
			(clearance 0)
		)
		(min_thickness 0.25)
		(keepout
			(tracks allowed)
			(vias allowed)
			(pads allowed)
			(copperpour allowed)
			(footprints not_allowed)
		)
		(placement
			(enabled no)
			(sheetname "")
		)
		(fill
			(thermal_gap 0.5)
			(thermal_bridge_width 0.5)
			(island_removal_mode 0)
		)
		(polygon
			(pts
				(xy -5.999988 -76.704952) (xy -5.999988 -106.719878) (xy 14.649958 -106.719878) (xy 14.649958 -76.704952)
			)
		)
	)
	(zone
		(layer "F.Cu")
		(hatch none 0.5)
		(connect_pads
			(clearance 0)
		)
		(min_thickness 0.25)
		(keepout
			(tracks allowed)
			(vias allowed)
			(pads allowed)
			(copperpour allowed)
			(footprints allowed)
		)
		(placement
			(enabled no)
			(sheetname "")
		)
		(fill
			(thermal_gap 0.5)
			(thermal_bridge_width 0.5)
			(island_removal_mode 0)
		)
		(polygon
			(pts
				(xy -3.02768 -148.38426) (xy -3.02768 -145.19148) (xy -2.424684 -144.588484) (xy -0.818896 -144.588484)
				(xy -0.285496 -145.121884) (xy -0.285496 -149.37232) (xy -2.03962 -149.37232)
			)
		)
	)
	(zone
		(layer "F.Cu")
		(hatch none 0.5)
		(connect_pads
			(clearance 0)
		)
		(min_thickness 0.25)
		(keepout
			(tracks allowed)
			(vias allowed)
			(pads allowed)
			(copperpour allowed)
			(footprints not_allowed)
		)
		(placement
			(enabled no)
			(sheetname "")
		)
		(fill
			(thermal_gap 0.5)
			(thermal_bridge_width 0.5)
			(island_removal_mode 0)
		)
		(polygon
			(pts
				(xy 373.076978 -150.010114) (xy 379.677168 -150.010114) (xy 379.677168 -138.51001) (xy 373.076978 -138.51001)
			)
		)
	)
	(zone
		(net "GND")
		(layer "F.Cu")
		(hatch none 0.5)
		(connect_pads
			(clearance 0.5)
		)
		(min_thickness 0.25)
		(fill yes
			(thermal_gap 0.5)
			(thermal_bridge_width 0.5)
			(island_removal_mode 0)
		)
		(polygon
			(pts
				(xy 161.3154 -103.505) (xy 162.7378 -103.505) (xy 163.3474 -103.505) (xy 167.0812 -103.505) (xy 167.117776 -103.468424)
				(xy 170.5864 -99.9998) (xy 170.8404 -99.7458) (xy 170.955716 -99.630484) (xy 170.955716 -93.144594)
				(xy 169.657522 -91.8464) (xy 169.5196 -91.8464) (xy 162.5346 -91.8464) (xy 162.306 -91.8464) (xy 161.2392 -92.9132)
				(xy 161.2392 -103.0478) (xy 161.2392 -103.4288)
			)
		)
	)
	(zone
		(layer "F.Cu")
		(hatch none 0.5)
		(connect_pads
			(clearance 0)
		)
		(min_thickness 0.25)
		(keepout
			(tracks allowed)
			(vias allowed)
			(pads allowed)
			(copperpour allowed)
			(footprints not_allowed)
		)
		(placement
			(enabled no)
			(sheetname "")
		)
		(fill
			(thermal_gap 0.5)
			(thermal_bridge_width 0.5)
			(island_removal_mode 0)
		)
		(polygon
			(pts
				(xy 17.130014 -41.810178) (xy 17.130014 -48.810164) (xy -5.999988 -48.810164) (xy -5.999988 -41.810178)
			)
		)
	)
	(zone
		(layer "F.Cu")
		(hatch none 0.5)
		(connect_pads
			(clearance 0)
		)
		(min_thickness 0.25)
		(keepout
			(tracks not_allowed)
			(vias allowed)
			(pads allowed)
			(copperpour not_allowed)
			(footprints allowed)
		)
		(placement
			(enabled no)
			(sheetname "")
		)
		(fill
			(thermal_gap 0.5)
			(thermal_bridge_width 0.5)
			(island_removal_mode 0)
		)
		(polygon
			(pts
				(arc
					(start 434.696616 -9.85901)
					(mid 435.186624 -10.052234)
					(end 434.660802 -10.020808)
				)
				(xy 434.47335 -9.833356) (xy 434.47335 -9.61136) (xy 434.37175 -9.61136) (xy 434.37175 -9.846056)
				(arc
					(start 434.227732 -9.990074)
					(mid 433.707574 -10.078302)
					(end 434.178964 -9.84123)
				)
				(xy 434.23205 -9.788144) (xy 434.23205 -9.61136)
				(arc
					(start 433.961032 -9.61136)
					(mid 433.577492 -9.9949)
					(end 433.961032 -10.37844)
				)
				(arc
					(start 434.925978 -10.37844)
					(mid 435.309772 -9.995027)
					(end 434.926232 -9.61136)
				)
				(xy 434.61305 -9.61136) (xy 434.61305 -9.775444)
			)
		)
	)
	(zone
		(net "GND")
		(layer "F.Cu")
		(hatch none 0.5)
		(connect_pads
			(clearance 0.5)
		)
		(min_thickness 0.25)
		(fill yes
			(thermal_gap 0.5)
			(thermal_bridge_width 0.5)
			(island_removal_mode 0)
		)
		(polygon
			(pts
				(xy 94.821502 -151.17191) (xy 96.208596 -151.17191) (xy 96.61398 -150.76678) (xy 96.61398 -149.168358)
				(xy 96.11614 -149.168358) (xy 96.110552 -149.173692) (xy 95.499428 -149.173692) (xy 95.35668 -149.31644)
				(xy 95.35668 -150.451058) (xy 95.27286 -150.534878) (xy 95.221298 -150.58644) (xy 94.807024 -150.58644)
				(xy 94.641924 -150.75154) (xy 94.641924 -150.992332)
			)
		)
	)
	(zone
		(layer "F.Cu")
		(hatch none 0.5)
		(connect_pads
			(clearance 0)
		)
		(min_thickness 0.25)
		(keepout
			(tracks allowed)
			(vias allowed)
			(pads allowed)
			(copperpour allowed)
			(footprints allowed)
		)
		(placement
			(enabled no)
			(sheetname "")
		)
		(fill
			(thermal_gap 0.5)
			(thermal_bridge_width 0.5)
			(island_removal_mode 0)
		)
		(polygon
			(pts
				(xy 480.2378 -49.8602) (xy 480.2378 -48.3616) (xy 489.5596 -48.3616) (xy 489.5596 -49.8602)
			)
		)
	)
	(zone
		(layer "F.Cu")
		(hatch none 0.5)
		(connect_pads
			(clearance 0)
		)
		(min_thickness 0.25)
		(keepout
			(tracks allowed)
			(vias allowed)
			(pads allowed)
			(copperpour allowed)
			(footprints allowed)
		)
		(placement
			(enabled no)
			(sheetname "")
		)
		(fill
			(thermal_gap 0.5)
			(thermal_bridge_width 0.5)
			(island_removal_mode 0)
		)
		(polygon
			(pts
				(xy 194.9831 -92.964) (xy 194.9831 -92.202) (xy 196.977 -92.202) (xy 196.977 -92.964)
			)
		)
	)
	(zone
		(net "PVDDQ_DEF")
		(layer "F.Cu")
		(hatch none 0.5)
		(connect_pads
			(clearance 0.5)
		)
		(min_thickness 0.25)
		(fill yes
			(thermal_gap 0.5)
			(thermal_bridge_width 0.5)
			(island_removal_mode 0)
		)
		(polygon
			(pts
				(xy 265.929364 -138.768836) (xy 265.678158 -139.020042) (xy 265.678158 -141.086332) (xy 265.979148 -141.387322)
				(xy 277.326598 -141.387322) (xy 277.529036 -141.184884) (xy 277.529036 -138.95705) (xy 277.340822 -138.768836)
			)
		)
		(polygon
			(pts
				(xy 275.657564 -140.6017) (xy 275.454364 -140.6017) (xy 275.454364 -140.8049) (xy 275.657564 -140.8049)
			)
		)
		(polygon
			(pts
				(xy 272.518632 -140.6017) (xy 272.315432 -140.6017) (xy 272.315432 -140.8049) (xy 272.518632 -140.8049)
			)
		)
		(polygon
			(pts
				(xy 269.216632 -140.6017) (xy 269.013432 -140.6017) (xy 269.013432 -140.8049) (xy 269.216632 -140.8049)
			)
		)
		(polygon
			(pts
				(xy 272.518632 -139.6111) (xy 272.315432 -139.6111) (xy 272.315432 -139.8143) (xy 272.518632 -139.8143)
			)
		)
		(polygon
			(pts
				(xy 269.216632 -139.6111) (xy 269.013432 -139.6111) (xy 269.013432 -139.8143) (xy 269.216632 -139.8143)
			)
		)
		(polygon
			(pts
				(xy 266.054332 -139.6111) (xy 265.851132 -139.6111) (xy 265.851132 -139.8143) (xy 266.054332 -139.8143)
			)
		)
	)
	(zone
		(layer "F.Cu")
		(hatch none 0.5)
		(connect_pads
			(clearance 0)
		)
		(min_thickness 0.25)
		(keepout
			(tracks allowed)
			(vias allowed)
			(pads allowed)
			(copperpour allowed)
			(footprints allowed)
		)
		(placement
			(enabled no)
			(sheetname "")
		)
		(fill
			(thermal_gap 0.5)
			(thermal_bridge_width 0.5)
			(island_removal_mode 0)
		)
		(polygon
			(pts
				(xy 345.7448 -148.8694) (xy 345.7448 -144.5006) (xy 348.1578 -144.5006) (xy 348.1578 -148.8694)
			)
		)
	)
	(zone
		(net "GND")
		(layer "F.Cu")
		(hatch none 0.5)
		(connect_pads
			(clearance 0.5)
		)
		(min_thickness 0.25)
		(fill yes
			(thermal_gap 0.5)
			(thermal_bridge_width 0.5)
			(island_removal_mode 0)
		)
		(polygon
			(pts
				(xy 17.653 -90.678) (xy 17.653 -94.234) (xy 21.209 -94.234) (xy 21.209 -90.678)
			)
		)
	)
	(zone
		(layer "F.Cu")
		(hatch none 0.5)
		(connect_pads
			(clearance 0)
		)
		(min_thickness 0.25)
		(keepout
			(tracks not_allowed)
			(vias allowed)
			(pads allowed)
			(copperpour not_allowed)
			(footprints allowed)
		)
		(placement
			(enabled no)
			(sheetname "")
		)
		(fill
			(thermal_gap 0.5)
			(thermal_bridge_width 0.5)
			(island_removal_mode 0)
		)
		(polygon
			(pts
				(xy 397.567912 -3.560064) (xy 397.77416 -3.560064) (xy 397.696436 -3.48234) (xy 397.696436 -3.245358)
				(xy 397.83512 -3.106674)
				(arc
					(start 397.88719 -3.106674)
					(mid 398.411096 -3.174152)
					(end 397.88846 -3.250946)
				)
				(xy 397.836136 -3.30327) (xy 397.836136 -3.424428) (xy 397.971772 -3.560064)
				(arc
					(start 398.144238 -3.560064)
					(mid 398.528032 -3.176651)
					(end 398.144492 -2.792984)
				)
				(arc
					(start 397.128492 -2.792984)
					(mid 396.744952 -3.176524)
					(end 397.128492 -3.560064)
				)
				(xy 397.3703 -3.560064) (xy 397.455136 -3.475228) (xy 397.455136 -3.320542)
				(arc
					(start 397.384778 -3.250184)
					(mid 396.861838 -3.174552)
					(end 397.385794 -3.106674)
				)
				(xy 397.43888 -3.106674) (xy 397.594836 -3.26263) (xy 397.594836 -3.53314)
			)
		)
	)
	(zone
		(layer "F.Cu")
		(hatch none 0.5)
		(connect_pads
			(clearance 0)
		)
		(min_thickness 0.25)
		(keepout
			(tracks not_allowed)
			(vias allowed)
			(pads allowed)
			(copperpour not_allowed)
			(footprints allowed)
		)
		(placement
			(enabled no)
			(sheetname "")
		)
		(fill
			(thermal_gap 0.5)
			(thermal_bridge_width 0.5)
			(island_removal_mode 0)
		)
		(polygon
			(pts
				(xy 16.599154 -34.4043) (xy 16.754348 -34.559494)
				(arc
					(start 16.754348 -34.731198)
					(mid 16.684498 -35.255115)
					(end 16.614648 -34.731198)
				)
				(xy 16.614648 -34.617406) (xy 16.541242 -34.544) (xy 16.300958 -34.544)
				(arc
					(start 16.300958 -34.9885)
					(mid 16.684498 -35.37204)
					(end 17.068038 -34.9885)
				)
				(arc
					(start 17.068038 -33.718754)
					(mid 16.684625 -33.33496)
					(end 16.300958 -33.7185)
				)
				(xy 16.300958 -34.163) (xy 16.541242 -34.163) (xy 16.614648 -34.089594)
				(arc
					(start 16.614648 -33.975802)
					(mid 16.684498 -33.451885)
					(end 16.754348 -33.975802)
				)
				(xy 16.754348 -34.147506) (xy 16.599154 -34.3027) (xy 16.300958 -34.3027) (xy 16.300958 -34.4043)
			)
		)
	)
	(zone
		(layer "F.Cu")
		(hatch none 0.5)
		(connect_pads
			(clearance 0)
		)
		(min_thickness 0.25)
		(keepout
			(tracks allowed)
			(vias allowed)
			(pads allowed)
			(copperpour allowed)
			(footprints not_allowed)
		)
		(placement
			(enabled no)
			(sheetname "")
		)
		(fill
			(thermal_gap 0.5)
			(thermal_bridge_width 0.5)
			(island_removal_mode 0)
		)
		(polygon
			(pts
				(arc
					(start 409.719526 -74.633836)
					(mid 411.969458 -76.883768)
					(end 409.719526 -79.1337)
				)
				(arc
					(start 409.719526 -79.1337)
					(mid 407.469594 -76.883768)
					(end 409.719526 -74.633836)
				)
			)
		)
	)
	(zone
		(layer "F.Cu")
		(hatch none 0.5)
		(connect_pads
			(clearance 0)
		)
		(min_thickness 0.25)
		(keepout
			(tracks allowed)
			(vias allowed)
			(pads allowed)
			(copperpour allowed)
			(footprints allowed)
		)
		(placement
			(enabled no)
			(sheetname "")
		)
		(fill
			(thermal_gap 0.5)
			(thermal_bridge_width 0.5)
			(island_removal_mode 0)
		)
		(polygon
			(pts
				(xy 344.54592 -130.377184) (xy 344.54592 -129.681224) (xy 344.790014 -129.681224) (xy 344.790014 -128.293622)
				(xy 345.337638 -128.293622) (xy 345.337638 -127.005842) (xy 346.415106 -127.005842) (xy 346.415106 -128.490726)
				(xy 347.847412 -128.490726) (xy 347.847412 -130.377184)
			)
		)
	)
	(zone
		(layer "F.Cu")
		(hatch none 0.5)
		(connect_pads
			(clearance 0)
		)
		(min_thickness 0.25)
		(keepout
			(tracks not_allowed)
			(vias allowed)
			(pads allowed)
			(copperpour not_allowed)
			(footprints allowed)
		)
		(placement
			(enabled no)
			(sheetname "")
		)
		(fill
			(thermal_gap 0.5)
			(thermal_bridge_width 0.5)
			(island_removal_mode 0)
		)
		(polygon
			(pts
				(xy 382.95961 -131.23037) (xy 382.95961 -131.332224) (xy 382.959356 -131.332478)
				(arc
					(start 382.959102 -131.356354)
					(mid 382.86018 -131.877123)
					(end 382.845056 -131.34721)
				)
				(xy 382.84531 -131.308602)
				(arc
					(start 382.84531 -131.232148)
					(mid 382.500631 -131.62917)
					(end 382.88087 -131.99237)
				)
				(arc
					(start 383.54127 -131.99237)
					(mid 383.872558 -131.799543)
					(end 383.868422 -131.416298)
				)
				(arc
					(start 383.868422 -131.416298)
					(mid 383.843912 -131.488698)
					(end 383.801366 -131.552188)
				)
				(arc
					(start 383.801366 -131.552188)
					(mid 383.303474 -131.732224)
					(end 383.742438 -131.43611)
				)
				(arc
					(start 383.742438 -131.43611)
					(mid 383.759776 -131.363292)
					(end 383.745486 -131.289806)
				)
				(arc
					(start 383.745486 -131.289806)
					(mid 383.647605 -131.245583)
					(end 383.54127 -131.23037)
				)
			)
		)
	)
	(zone
		(layer "F.Cu")
		(hatch none 0.5)
		(connect_pads
			(clearance 0)
		)
		(min_thickness 0.25)
		(keepout
			(tracks not_allowed)
			(vias allowed)
			(pads allowed)
			(copperpour not_allowed)
			(footprints allowed)
		)
		(placement
			(enabled no)
			(sheetname "")
		)
		(fill
			(thermal_gap 0.5)
			(thermal_bridge_width 0.5)
			(island_removal_mode 0)
		)
		(polygon
			(pts
				(arc
					(start 387.587236 -127.105664)
					(mid 387.919527 -127.518727)
					(end 387.506464 -127.186436)
				)
				(arc
					(start 387.424168 -127.10414)
					(mid 387.399294 -127.142667)
					(end 387.37921 -127.183896)
				)
				(xy 387.37921 -127.712978)
				(arc
					(start 387.499352 -127.83312)
					(mid 387.988084 -128.036733)
					(end 387.4643 -127.959612)
				)
				(xy 387.35 -127.845312)
				(arc
					(start 387.35 -127.964946)
					(mid 387.730873 -128.3462)
					(end 388.112 -127.9652)
				)
				(arc
					(start 388.112 -127.3302)
					(mid 387.90284 -126.990153)
					(end 387.50494 -127.023368)
				)
			)
		)
	)
	(zone
		(net "VR_PVCCIN_CPU0_PHASE1")
		(layer "F.Cu")
		(hatch none 0.5)
		(connect_pads
			(clearance 0.5)
		)
		(min_thickness 0.25)
		(fill yes
			(thermal_gap 0.5)
			(thermal_bridge_width 0.5)
			(island_removal_mode 0)
		)
		(polygon
			(pts
				(xy 201.8538 -59.655202) (xy 205.657196 -59.655202) (xy 206.64297 -59.655202) (xy 206.877666 -59.420506)
				(xy 206.877666 -54.795928) (xy 206.656432 -54.574694) (xy 205.657704 -54.574694) (xy 205.657196 -54.575202)
				(xy 201.710798 -54.575202) (xy 201.4982 -54.7878) (xy 201.4982 -59.299602)
			)
		)
	)
	(zone
		(net "GND")
		(layer "F.Cu")
		(hatch none 0.5)
		(connect_pads
			(clearance 0.5)
		)
		(min_thickness 0.25)
		(fill yes
			(thermal_gap 0.5)
			(thermal_bridge_width 0.5)
			(island_removal_mode 0)
		)
		(polygon
			(pts
				(xy 277.622 -134.177024) (xy 279.198832 -134.177024) (xy 279.198832 -134.4422) (xy 279.808432 -135.0518)
				(xy 279.808432 -135.546592) (xy 279.808432 -136.017) (xy 280.062432 -136.271) (xy 280.062432 -136.5504)
				(xy 279.985978 -136.626854) (xy 278.716486 -136.626854) (xy 278.511 -136.421368) (xy 278.511 -136.209024)
				(xy 278.257 -135.955024) (xy 277.749 -135.955024) (xy 268.327632 -135.955024) (xy 268.327632 -135.066024)
				(xy 271.9324 -135.066024) (xy 272.1864 -134.812024) (xy 277.368 -134.812024) (xy 277.622 -134.558024)
			)
		)
	)
	(zone
		(layer "F.Cu")
		(hatch none 0.5)
		(connect_pads
			(clearance 0)
		)
		(min_thickness 0.25)
		(keepout
			(tracks allowed)
			(vias allowed)
			(pads allowed)
			(copperpour allowed)
			(footprints not_allowed)
		)
		(placement
			(enabled no)
			(sheetname "")
		)
		(fill
			(thermal_gap 0.5)
			(thermal_bridge_width 0.5)
			(island_removal_mode 0)
		)
		(polygon
			(pts
				(xy 187.525406 -22.919182) (xy 328.525378 -22.919182) (xy 328.525378 -20.919186) (xy 187.525406 -20.919186)
			)
		)
	)
	(zone
		(net "PVDDQ_GHJ")
		(layer "F.Cu")
		(hatch none 0.5)
		(connect_pads
			(clearance 0.5)
		)
		(min_thickness 0.25)
		(fill yes
			(thermal_gap 0.5)
			(thermal_bridge_width 0.5)
			(island_removal_mode 0)
		)
		(polygon
			(pts
				(xy 98.92538 -66.963544) (xy 98.92538 -70.274688) (xy 100.288852 -70.274688) (xy 100.288852 -68.925948)
				(xy 100.3554 -68.8594) (xy 102.5144 -68.8594) (xy 102.5652 -68.8086) (xy 107.935776 -68.8086) (xy 108.353098 -68.391278)
				(xy 108.353098 -67.66687) (xy 108.627418 -67.39255) (xy 108.627418 -67.09918) (xy 108.491782 -66.963544)
			)
		)
		(polygon
			(pts
				(xy 99.999292 -69.403214) (xy 99.796092 -69.403214) (xy 99.796092 -69.606414) (xy 99.999292 -69.606414)
			)
		)
		(polygon
			(pts
				(xy 100.001324 -68.920614) (xy 99.798124 -68.920614) (xy 99.798124 -69.123814) (xy 100.001324 -69.123814)
			)
		)
		(polygon
			(pts
				(xy 100.001324 -68.158614) (xy 99.798124 -68.158614) (xy 99.798124 -68.361814) (xy 100.001324 -68.361814)
			)
		)
		(polygon
			(pts
				(xy 102.628192 -67.866514) (xy 102.424992 -67.866514) (xy 102.424992 -68.069714) (xy 102.628192 -68.069714)
			)
		)
		(polygon
			(pts
				(xy 101.866192 -67.866514) (xy 101.662992 -67.866514) (xy 101.662992 -68.069714) (xy 101.866192 -68.069714)
			)
		)
		(polygon
			(pts
				(xy 101.385624 -67.866514) (xy 101.182424 -67.866514) (xy 101.182424 -68.069714) (xy 101.385624 -68.069714)
			)
		)
		(polygon
			(pts
				(xy 100.623624 -67.866514) (xy 100.420424 -67.866514) (xy 100.420424 -68.069714) (xy 100.623624 -68.069714)
			)
		)
		(polygon
			(pts
				(xy 107.617006 -67.819016) (xy 107.413806 -67.819016) (xy 107.413806 -68.022216) (xy 107.617006 -68.022216)
			)
		)
		(polygon
			(pts
				(xy 106.855006 -67.819016) (xy 106.651806 -67.819016) (xy 106.651806 -68.022216) (xy 106.855006 -68.022216)
			)
		)
		(polygon
			(pts
				(xy 106.372406 -67.819016) (xy 106.169206 -67.819016) (xy 106.169206 -68.022216) (xy 106.372406 -68.022216)
			)
		)
		(polygon
			(pts
				(xy 105.610406 -67.819016) (xy 105.407206 -67.819016) (xy 105.407206 -68.022216) (xy 105.610406 -68.022216)
			)
		)
		(polygon
			(pts
				(xy 105.127806 -67.819016) (xy 104.924606 -67.819016) (xy 104.924606 -68.022216) (xy 105.127806 -68.022216)
			)
		)
		(polygon
			(pts
				(xy 104.365806 -67.819016) (xy 104.162606 -67.819016) (xy 104.162606 -68.022216) (xy 104.365806 -68.022216)
			)
		)
		(polygon
			(pts
				(xy 103.883206 -67.819016) (xy 103.680006 -67.819016) (xy 103.680006 -68.022216) (xy 103.883206 -68.022216)
			)
		)
		(polygon
			(pts
				(xy 103.121206 -67.819016) (xy 102.918006 -67.819016) (xy 102.918006 -68.022216) (xy 103.121206 -68.022216)
			)
		)
	)
	(zone
		(net "VR_FET_SW_P12V_STBY_PVCCIN_CPU1")
		(layer "F.Cu")
		(hatch none 0.5)
		(connect_pads
			(clearance 0.5)
		)
		(min_thickness 0.25)
		(fill yes
			(thermal_gap 0.5)
			(thermal_bridge_width 0.5)
			(island_removal_mode 0)
		)
		(polygon
			(pts
				(xy 31.486602 -58.932064) (xy 31.613602 -58.805064) (xy 31.613602 -58.79338) (xy 31.6484 -58.758582)
				(xy 31.6484 -57.42178) (xy 33.630616 -57.42178) (xy 33.630616 -59.78398) (xy 33.509966 -59.90463)
				(xy 33.509966 -60.081668) (xy 33.49625 -60.095384) (xy 33.49625 -60.647326) (xy 33.491424 -60.652152)
				(xy 33.390332 -60.753498) (xy 33.076388 -60.753498) (xy 32.981646 -60.658756) (xy 32.655002 -60.332112)
				(xy 32.382968 -60.332112) (xy 32.23514 -60.184284) (xy 32.058356 -60.0075) (xy 31.72206 -60.0075)
				(xy 31.49727 -60.23229) (xy 31.49727 -60.640722) (xy 31.427166 -60.710826) (xy 30.981142 -60.710826)
				(xy 30.93847 -60.753498) (xy 29.642308 -60.753498) (xy 29.3878 -60.49899) (xy 29.3878 -59.30138)
				(xy 29.516832 -59.172348) (xy 30.253432 -59.172348) (xy 30.2768 -59.14898) (xy 30.353 -59.07278)
				(xy 30.355286 -59.07278) (xy 30.496002 -58.932064)
			)
		)
	)
	(zone
		(layer "F.Cu")
		(hatch none 0.5)
		(connect_pads
			(clearance 0)
		)
		(min_thickness 0.25)
		(keepout
			(tracks allowed)
			(vias allowed)
			(pads allowed)
			(copperpour allowed)
			(footprints allowed)
		)
		(placement
			(enabled no)
			(sheetname "")
		)
		(fill
			(thermal_gap 0.5)
			(thermal_bridge_width 0.5)
			(island_removal_mode 0)
		)
		(polygon
			(pts
				(xy 62.202568 -29.591) (xy 62.202568 -27.559) (xy 64.361568 -27.559) (xy 64.361568 -29.591)
			)
		)
	)
	(zone
		(net "GND")
		(layer "F.Cu")
		(hatch none 0.5)
		(connect_pads
			(clearance 0.5)
		)
		(min_thickness 0.25)
		(fill yes
			(thermal_gap 0.5)
			(thermal_bridge_width 0.5)
			(island_removal_mode 0)
		)
		(polygon
			(pts
				(xy 434.09362 -131.638294) (xy 434.09362 -130.8989) (xy 434.22062 -130.7719) (xy 435.737 -130.7719)
				(xy 435.8386 -130.6703) (xy 435.8386 -129.9464) (xy 435.7243 -129.8321) (xy 434.01488 -129.8321)
				(xy 433.912264 -129.934716) (xy 432.093116 -129.934716) (xy 431.6222 -129.4638) (xy 431.6222 -128.534414)
				(xy 431.039016 -127.95123) (xy 430.98466 -127.896874) (xy 430.98466 -127.224028) (xy 430.98466 -127.1651)
				(xy 430.513744 -126.694184) (xy 430.216818 -126.694184) (xy 430.116996 -126.594362) (xy 430.107852 -126.585218)
				(xy 430.107852 -125.305058) (xy 430.102772 -125.299978) (xy 429.096932 -125.299978) (xy 429.081184 -125.315726)
				(xy 429.081184 -125.442218) (xy 429.081184 -126.50216) (xy 429.553878 -126.974854) (xy 429.553878 -127.48133)
				(xy 429.745648 -127.6731) (xy 429.745648 -130.431794) (xy 429.745648 -130.963416) (xy 429.7807 -130.998468)
				(xy 430.515522 -130.998468) (xy 431.206402 -131.689348) (xy 434.042566 -131.689348)
			)
		)
	)
	(zone
		(net "VR_FET_SW_P12V_STBY_PVDDQ_DEF")
		(layer "F.Cu")
		(hatch none 0.5)
		(connect_pads
			(clearance 0.5)
		)
		(min_thickness 0.25)
		(fill yes
			(thermal_gap 0.5)
			(thermal_bridge_width 0.5)
			(island_removal_mode 0)
		)
		(polygon
			(pts
				(xy 370.602764 -152.675844) (xy 370.602764 -151.343614) (xy 369.576096 -150.316946) (xy 367.309146 -150.316946)
				(xy 366.9792 -149.987) (xy 366.9792 -148.971) (xy 366.978184 -148.969984) (xy 366.978184 -148.413978)
				(xy 366.848644 -148.284438) (xy 365.307626 -148.284438) (xy 364.975648 -147.95246) (xy 364.975648 -147.372578)
				(xy 364.64367 -147.0406) (xy 355.120956 -147.0406) (xy 354.774246 -146.69389) (xy 354.774246 -144.852898)
				(xy 354.791772 -144.835372) (xy 354.791772 -142.331186) (xy 354.20935 -141.748764) (xy 354.20935 -141.03985)
				(xy 354.1395 -140.97) (xy 349.209614 -140.97) (xy 348.491302 -140.251688) (xy 347.82506 -140.251688)
				(xy 347.702124 -140.374624) (xy 347.702124 -141.195552) (xy 347.726 -141.219428) (xy 347.726 -144.8054)
				(xy 347.8276 -144.907) (xy 349.6564 -144.907) (xy 349.7072 -144.8562) (xy 349.7072 -143.5862) (xy 349.9104 -143.383)
				(xy 351.0534 -143.383) (xy 351.3582 -143.0782) (xy 353.308158 -143.0782) (xy 354.0125 -143.782542)
				(xy 354.0125 -146.459194) (xy 353.313238 -147.158456) (xy 353.313238 -148.316442) (xy 352.782378 -148.847302)
				(xy 352.233738 -148.847302) (xy 351.547938 -148.847302) (xy 350.897952 -149.497288) (xy 348.004892 -149.497288)
				(xy 347.803978 -149.697948) (xy 347.803978 -150.408132) (xy 347.7514 -150.46071) (xy 347.7514 -152.7048)
				(xy 347.853 -152.8064) (xy 349.560642 -152.8064) (xy 349.674688 -152.692354) (xy 349.674688 -151.204422)
				(xy 349.700342 -151.178768) (xy 351.068894 -151.178768) (xy 351.371662 -150.876) (xy 352.1202 -150.876)
				(xy 352.360992 -150.635208) (xy 352.360992 -150.06828) (xy 352.44532 -149.983952) (xy 353.95916 -149.983952)
				(xy 354.419408 -150.4442) (xy 362.2802 -150.4442) (xy 365.05388 -153.21788) (xy 365.05388 -155.676854)
				(xy 365.264954 -155.887928) (xy 371.475 -155.887928) (xy 371.7544 -155.608528) (xy 371.7544 -154.78506)
				(xy 371.1702 -154.20086) (xy 371.1702 -153.35504) (xy 370.602764 -152.787604)
			)
		)
	)
	(zone
		(net "GND")
		(layer "F.Cu")
		(hatch none 0.5)
		(connect_pads
			(clearance 0.5)
		)
		(min_thickness 0.25)
		(fill yes
			(thermal_gap 0.5)
			(thermal_bridge_width 0.5)
			(island_removal_mode 0)
		)
		(polygon
			(pts
				(xy 469.53043 -5.051044) (xy 469.53043 -3.855974) (xy 469.478106 -3.80365) (xy 469.391746 -3.80365)
				(xy 469.378792 -3.790696) (xy 469.03132 -3.790696) (xy 469.024208 -3.797808) (xy 469.010746 -3.81127)
				(xy 469.010746 -8.36803) (xy 469.019636 -8.37692) (xy 469.091264 -8.37692) (xy 469.096598 -8.37692)
				(xy 469.108028 -8.38835) (xy 469.530938 -8.38835) (xy 469.540082 -8.379206) (xy 469.540082 -6.929882)
				(xy 469.607646 -6.862318) (xy 469.607646 -5.12826)
			)
		)
	)
	(zone
		(layer "F.Cu")
		(hatch none 0.5)
		(connect_pads
			(clearance 0)
		)
		(min_thickness 0.25)
		(keepout
			(tracks allowed)
			(vias allowed)
			(pads allowed)
			(copperpour allowed)
			(footprints allowed)
		)
		(placement
			(enabled no)
			(sheetname "")
		)
		(fill
			(thermal_gap 0.5)
			(thermal_bridge_width 0.5)
			(island_removal_mode 0)
		)
		(polygon
			(pts
				(xy 80.871568 -52.2224) (xy 85.926168 -52.2224) (xy 85.926168 -54.1274) (xy 84.325968 -55.7276)
				(xy 81.938368 -55.7276) (xy 80.871568 -54.6608)
			)
		)
	)
	(zone
		(layer "F.Cu")
		(hatch none 0.5)
		(connect_pads
			(clearance 0)
		)
		(min_thickness 0.25)
		(keepout
			(tracks allowed)
			(vias allowed)
			(pads allowed)
			(copperpour allowed)
			(footprints allowed)
		)
		(placement
			(enabled no)
			(sheetname "")
		)
		(fill
			(thermal_gap 0.5)
			(thermal_bridge_width 0.5)
			(island_removal_mode 0)
		)
		(polygon
			(pts
				(xy 383.413 -151.8666) (xy 387.7818 -151.8666) (xy 387.7818 -154.2796) (xy 383.413 -154.2796)
			)
		)
	)
	(zone
		(layer "F.Cu")
		(hatch none 0.5)
		(connect_pads
			(clearance 0)
		)
		(min_thickness 0.25)
		(keepout
			(tracks not_allowed)
			(vias allowed)
			(pads allowed)
			(copperpour not_allowed)
			(footprints allowed)
		)
		(placement
			(enabled no)
			(sheetname "")
		)
		(fill
			(thermal_gap 0.5)
			(thermal_bridge_width 0.5)
			(island_removal_mode 0)
		)
		(polygon
			(pts
				(xy 432.047142 -9.694926) (xy 432.047142 -9.960864)
				(arc
					(start 431.876708 -10.131298)
					(mid 431.351067 -10.114118)
					(end 431.853086 -9.957308)
				)
				(xy 431.907442 -9.902952) (xy 431.907442 -9.694926)
				(arc
					(start 431.615342 -9.694926)
					(mid 431.231802 -10.078466)
					(end 431.615342 -10.462006)
				)
				(arc
					(start 432.580288 -10.462006)
					(mid 432.964082 -10.078593)
					(end 432.580542 -9.694926)
				)
				(xy 432.288442 -9.694926) (xy 432.288442 -9.889236)
				(arc
					(start 432.347624 -9.948418)
					(mid 432.842613 -10.127365)
					(end 432.316382 -10.114788)
				)
				(xy 432.148742 -9.947148) (xy 432.148742 -9.694926)
			)
		)
	)
	(zone
		(layer "F.Cu")
		(hatch none 0.5)
		(connect_pads
			(clearance 0)
		)
		(min_thickness 0.25)
		(keepout
			(tracks allowed)
			(vias allowed)
			(pads allowed)
			(copperpour allowed)
			(footprints allowed)
		)
		(placement
			(enabled no)
			(sheetname "")
		)
		(fill
			(thermal_gap 0.5)
			(thermal_bridge_width 0.5)
			(island_removal_mode 0)
		)
		(polygon
			(pts
				(xy 342.842342 -140.98016) (xy 343.88552 -140.98016) (xy 343.88552 -142.79626) (xy 342.842342 -142.79626)
			)
		)
	)
	(zone
		(layer "F.Cu")
		(hatch none 0.5)
		(connect_pads
			(clearance 0)
		)
		(min_thickness 0.25)
		(keepout
			(tracks not_allowed)
			(vias allowed)
			(pads allowed)
			(copperpour not_allowed)
			(footprints allowed)
		)
		(placement
			(enabled no)
			(sheetname "")
		)
		(fill
			(thermal_gap 0.5)
			(thermal_bridge_width 0.5)
			(island_removal_mode 0)
		)
		(polygon
			(pts
				(arc
					(start 248.000012 -109.009942)
					(mid 250.540012 -111.549942)
					(end 248.000012 -114.089942)
				)
				(arc
					(start 248.000012 -114.089942)
					(mid 245.460012 -111.549942)
					(end 248.000012 -109.009942)
				)
			)
		)
	)
	(zone
		(layer "F.Cu")
		(hatch none 0.5)
		(connect_pads
			(clearance 0)
		)
		(min_thickness 0.25)
		(keepout
			(tracks allowed)
			(vias allowed)
			(pads allowed)
			(copperpour allowed)
			(footprints allowed)
		)
		(placement
			(enabled no)
			(sheetname "")
		)
		(fill
			(thermal_gap 0.5)
			(thermal_bridge_width 0.5)
			(island_removal_mode 0)
		)
		(polygon
			(pts
				(xy 395.83106 -151.864822) (xy 395.83106 -149.782022) (xy 396.92326 -149.782022) (xy 396.92326 -151.864822)
			)
		)
	)
	(zone
		(layer "F.Cu")
		(hatch none 0.5)
		(connect_pads
			(clearance 0)
		)
		(min_thickness 0.25)
		(keepout
			(tracks allowed)
			(vias allowed)
			(pads allowed)
			(copperpour allowed)
			(footprints allowed)
		)
		(placement
			(enabled no)
			(sheetname "")
		)
		(fill
			(thermal_gap 0.5)
			(thermal_bridge_width 0.5)
			(island_removal_mode 0)
		)
		(polygon
			(pts
				(xy 195.4022 -58.0136) (xy 195.4022 -55.7276) (xy 197.4088 -55.7276) (xy 197.4088 -58.0136)
			)
		)
	)
	(zone
		(layer "F.Cu")
		(hatch none 0.5)
		(connect_pads
			(clearance 0)
		)
		(min_thickness 0.25)
		(keepout
			(tracks allowed)
			(vias allowed)
			(pads allowed)
			(copperpour allowed)
			(footprints allowed)
		)
		(placement
			(enabled no)
			(sheetname "")
		)
		(fill
			(thermal_gap 0.5)
			(thermal_bridge_width 0.5)
			(island_removal_mode 0)
		)
		(polygon
			(pts
				(xy 368.808 -117.348) (xy 368.808 -116.0018) (xy 367.3602 -114.554) (xy 367.3602 -110.7948) (xy 370.5606 -107.5944)
				(xy 370.56187 -107.5944) (xy 370.56187 -107.319318) (xy 372.16207 -105.719118) (xy 372.9228 -105.719118)
				(xy 372.9228 -92.2528) (xy 378.4346 -92.2528) (xy 378.4346 -90.7542) (xy 378.46 -90.7288) (xy 380.1364 -89.0524)
				(xy 391.922 -89.0524) (xy 392.4046 -89.0524) (xy 393.446 -90.0938) (xy 400.4564 -90.0938) (xy 402.6154 -92.2528)
				(xy 402.6154 -96.085914) (xy 404.7236 -98.194114) (xy 404.7236 -99.06) (xy 404.7236 -100.9396) (xy 404.7236 -109.982)
				(xy 404.0886 -109.982) (xy 403.9616 -110.109) (xy 403.9616 -113.03) (xy 405.003 -113.03) (xy 405.257 -113.284)
				(xy 405.257 -114.681) (xy 406.146 -114.681) (xy 406.273 -114.808) (xy 406.273 -116.713) (xy 406.4 -116.84)
				(xy 406.908 -116.84) (xy 408.432 -118.364) (xy 408.432 -119.253) (xy 407.924 -119.761) (xy 406.273 -119.761)
				(xy 406.146 -119.888) (xy 406.146 -120.65) (xy 404.495 -122.301) (xy 402.6154 -122.301) (xy 402.6154 -127.9144)
				(xy 395.8844 -127.9144) (xy 395.6304 -128.1684) (xy 395.6304 -129.5146) (xy 395.351 -129.794) (xy 394.0048 -129.794)
				(xy 393.8016 -129.9972) (xy 386.066538 -129.9972) (xy 384.240024 -131.823714) (xy 382.450594 -131.823714)
				(xy 380.62408 -129.9972) (xy 374.240044 -129.9972) (xy 373.522494 -130.71475) (xy 370.22405 -130.71475)
				(xy 369.1636 -131.7752) (xy 368.3762 -131.7752) (xy 368.3762 -127.381) (xy 368.808 -126.9492) (xy 368.808 -126.365)
				(xy 368.808 -120.5738) (xy 368.3254 -120.0912) (xy 368.2492 -120.0912) (xy 366.776 -118.618) (xy 363.855 -118.618)
				(xy 363.855 -117.602) (xy 364.109 -117.348)
			)
		)
	)
	(zone
		(layer "F.Cu")
		(hatch none 0.5)
		(connect_pads
			(clearance 0)
		)
		(min_thickness 0.25)
		(keepout
			(tracks not_allowed)
			(vias allowed)
			(pads allowed)
			(copperpour not_allowed)
			(footprints allowed)
		)
		(placement
			(enabled no)
			(sheetname "")
		)
		(fill
			(thermal_gap 0.5)
			(thermal_bridge_width 0.5)
			(island_removal_mode 0)
		)
		(polygon
			(pts
				(xy 404.625556 -2.827274) (xy 404.795736 -2.997454) (xy 404.795736 -3.280664) (xy 404.897336 -3.280664)
				(xy 404.897336 -2.980182) (xy 405.050244 -2.827274)
				(arc
					(start 405.08809 -2.827274)
					(mid 405.611958 -2.889544)
					(end 405.092662 -2.982468)
				)
				(xy 405.037036 -3.038094) (xy 405.037036 -3.280664)
				(arc
					(start 405.345138 -3.280664)
					(mid 405.728932 -2.897251)
					(end 405.345392 -2.513584)
				)
				(arc
					(start 404.329392 -2.513584)
					(mid 403.945852 -2.897124)
					(end 404.329392 -3.280664)
				)
				(xy 404.656036 -3.280664) (xy 404.656036 -3.055366)
				(arc
					(start 404.582376 -2.981706)
					(mid 404.062827 -2.889946)
					(end 404.586694 -2.827274)
				)
			)
		)
	)
	(zone
		(layer "F.Cu")
		(hatch none 0.5)
		(connect_pads
			(clearance 0)
		)
		(min_thickness 0.25)
		(keepout
			(tracks allowed)
			(vias allowed)
			(pads allowed)
			(copperpour allowed)
			(footprints allowed)
		)
		(placement
			(enabled no)
			(sheetname "")
		)
		(fill
			(thermal_gap 0.5)
			(thermal_bridge_width 0.5)
			(island_removal_mode 0)
		)
		(polygon
			(pts
				(xy 31.369 -53.213) (xy 33.528 -53.213) (xy 33.528 -54.864) (xy 31.369 -54.864)
			)
		)
	)
	(zone
		(layer "F.Cu")
		(hatch none 0.5)
		(connect_pads
			(clearance 0)
		)
		(min_thickness 0.25)
		(keepout
			(tracks allowed)
			(vias allowed)
			(pads allowed)
			(copperpour allowed)
			(footprints not_allowed)
		)
		(placement
			(enabled no)
			(sheetname "")
		)
		(fill
			(thermal_gap 0.5)
			(thermal_bridge_width 0.5)
			(island_removal_mode 0)
		)
		(polygon
			(pts
				(arc
					(start 291.999924 -44.090082)
					(mid 289.459924 -41.550082)
					(end 291.999924 -39.010082)
				)
				(arc
					(start 291.999924 -39.010082)
					(mid 294.539924 -41.550082)
					(end 291.999924 -44.090082)
				)
			)
		)
	)
	(zone
		(net "VR_FET_SW_P12V_STBY_PVCCIN_CPU0")
		(layer "F.Cu")
		(hatch none 0.5)
		(connect_pads
			(clearance 0.5)
		)
		(min_thickness 0.25)
		(fill yes
			(thermal_gap 0.5)
			(thermal_bridge_width 0.5)
			(island_removal_mode 0)
		)
		(polygon
			(pts
				(xy 187.9473 -85.1027) (xy 187.9473 -95.6437) (xy 185.801 -97.79) (xy 185.801 -103.378) (xy 186.055 -103.632)
				(xy 189.375796 -103.632) (xy 189.832996 -103.1748) (xy 197.753732 -103.1748) (xy 198.604124 -102.324662)
				(xy 198.626476 -102.30231) (xy 198.626476 -98.069908) (xy 198.618348 -98.06178) (xy 196.693536 -98.06178)
				(xy 196.636132 -98.119184) (xy 196.636132 -99.398582) (xy 196.601334 -99.43338) (xy 196.601334 -99.445064)
				(xy 196.474334 -99.572064) (xy 195.629276 -99.572064) (xy 195.04279 -100.15855) (xy 195.04279 -100.28682)
				(xy 195.02374 -100.30587) (xy 194.89547 -100.30587) (xy 194.37477 -100.30587) (xy 193.712592 -100.968048)
				(xy 193.711322 -100.968048) (xy 193.711322 -100.96881) (xy 193.549778 -101.130354) (xy 193.549778 -101.294946)
				(xy 193.269362 -101.575362) (xy 192.860168 -101.575362) (xy 192.580768 -101.295962) (xy 192.580768 -100.887022)
				(xy 193.057272 -100.410518) (xy 193.057272 -100.245164) (xy 192.3288 -99.516692) (xy 192.3288 -95.5802)
				(xy 192.3288 -95.534988) (xy 191.983106 -95.189294) (xy 191.983106 -94.799912) (xy 192.201292 -94.581726)
				(xy 192.638426 -94.581726) (xy 193.511678 -94.581726) (xy 194.732656 -93.360748) (xy 194.74434 -93.349064)
				(xy 197.998334 -93.349064) (xy 198.047864 -93.299534) (xy 198.047864 -92.550234) (xy 198.31812 -92.279978)
				(xy 198.606156 -92.279978) (xy 198.631048 -92.255086) (xy 198.631048 -89.93378) (xy 196.648832 -89.93378)
				(xy 196.648832 -91.270582) (xy 196.614034 -91.30538) (xy 196.614034 -91.317064) (xy 196.487034 -91.444064)
				(xy 195.496434 -91.444064) (xy 195.355718 -91.58478) (xy 195.353432 -91.58478) (xy 195.277232 -91.66098)
				(xy 195.272152 -91.66098) (xy 195.153026 -91.780106) (xy 194.547744 -91.780106) (xy 194.498468 -91.829382)
				(xy 194.498468 -92.494608) (xy 194.49288 -92.500196) (xy 194.383914 -92.608908) (xy 192.888108 -92.608908)
				(xy 192.834006 -92.554806) (xy 191.897 -91.6178) (xy 191.897 -88.047576) (xy 192.638934 -87.305642)
				(xy 192.638934 -85.669882) (xy 190.91148 -83.942428) (xy 188.564774 -83.942428) (xy 187.9473 -84.559902)
			)
		)
	)
	(zone
		(layer "F.Cu")
		(hatch none 0.5)
		(connect_pads
			(clearance 0)
		)
		(min_thickness 0.25)
		(keepout
			(tracks not_allowed)
			(vias allowed)
			(pads allowed)
			(copperpour not_allowed)
			(footprints allowed)
		)
		(placement
			(enabled no)
			(sheetname "")
		)
		(fill
			(thermal_gap 0.5)
			(thermal_bridge_width 0.5)
			(island_removal_mode 0)
		)
		(polygon
			(pts
				(arc
					(start 336.268568 -33.999678)
					(mid 337.369353 -33.864042)
					(end 336.268568 -33.728406)
				)
				(arc
					(start 336.268568 -33.728406)
					(mid 336.307025 -33.864042)
					(end 336.268568 -33.999678)
				)
			)
		)
	)
	(zone
		(layer "F.Cu")
		(hatch none 0.5)
		(connect_pads
			(clearance 0)
		)
		(min_thickness 0.25)
		(keepout
			(tracks allowed)
			(vias allowed)
			(pads allowed)
			(copperpour allowed)
			(footprints allowed)
		)
		(placement
			(enabled no)
			(sheetname "")
		)
		(fill
			(thermal_gap 0.5)
			(thermal_bridge_width 0.5)
			(island_removal_mode 0)
		)
		(polygon
			(pts
				(xy 278.003 -109.347) (xy 278.003 -110.617) (xy 280.0604 -112.6744) (xy 280.0604 -113.4364) (xy 281.4955 -114.8715)
				(xy 281.686 -115.062) (xy 283.21 -113.538) (xy 284.861 -115.189) (xy 286.512 -113.538) (xy 288.163 -115.189)
				(xy 290.195 -113.157) (xy 288.544 -111.506) (xy 287.02 -109.982) (xy 285.623 -109.982) (xy 283.083 -107.442)
				(xy 283.083 -106.045) (xy 282.829 -106.045) (xy 278.13 -106.045) (xy 278.003 -106.045)
			)
		)
	)
	(zone
		(net "VR_PVDDQ_ABC_PH2_SW")
		(layer "F.Cu")
		(hatch none 0.5)
		(connect_pads
			(clearance 0.5)
		)
		(min_thickness 0.25)
		(fill yes
			(thermal_gap 0.5)
			(thermal_bridge_width 0.5)
			(island_removal_mode 0)
		)
		(polygon
			(pts
				(xy 338.329016 -1.017016) (xy 338.707222 -1.395222) (xy 338.934298 -1.395222) (xy 343.152222 -1.395222)
				(xy 343.154 -1.397) (xy 343.807796 -0.743204) (xy 343.807796 3.909314) (xy 343.758774 3.958336)
				(xy 343.230962 3.958336) (xy 342.957404 3.684778) (xy 342.848946 3.57632) (xy 338.5439 3.57632)
				(xy 338.329016 3.361436)
			)
		)
	)
	(zone
		(layer "F.Cu")
		(hatch none 0.5)
		(connect_pads
			(clearance 0)
		)
		(min_thickness 0.25)
		(keepout
			(tracks allowed)
			(vias allowed)
			(pads allowed)
			(copperpour allowed)
			(footprints not_allowed)
		)
		(placement
			(enabled no)
			(sheetname "")
		)
		(fill
			(thermal_gap 0.5)
			(thermal_bridge_width 0.5)
			(island_removal_mode 0)
		)
		(polygon
			(pts
				(arc
					(start 248.000012 -39.649908)
					(mid 249.900186 -41.550082)
					(end 248.000012 -43.450002)
				)
				(arc
					(start 248.000012 -43.450002)
					(mid 246.100092 -41.550082)
					(end 248.000012 -39.649908)
				)
			)
		)
	)
	(zone
		(net "GND")
		(layer "F.Cu")
		(hatch none 0.5)
		(connect_pads
			(clearance 0.5)
		)
		(min_thickness 0.25)
		(fill yes
			(thermal_gap 0.5)
			(thermal_bridge_width 0.5)
			(island_removal_mode 0)
		)
		(polygon
			(pts
				(xy 399.4404 -122.174) (xy 399.826988 -122.174) (xy 399.9357 -122.065288) (xy 399.9357 -121.8184)
				(xy 399.6563 -121.539) (xy 399.6563 -121.1834) (xy 399.8849 -120.9548) (xy 400.0119 -120.9548) (xy 400.0627 -120.904)
				(xy 400.0627 -120.689624) (xy 400.011138 -120.638062) (xy 399.923762 -120.638062) (xy 399.7706 -120.4849)
				(xy 399.7579 -120.4722) (xy 399.7579 -120.2436) (xy 399.7706 -120.2309) (xy 399.928334 -120.073166)
				(xy 400.006566 -120.073166) (xy 400.068034 -120.073166) (xy 400.1262 -120.015) (xy 400.1262 -119.7356)
				(xy 400.1262 -119.6975) (xy 400.0754 -119.6467) (xy 400.0373 -119.6467) (xy 399.9103 -119.6467)
				(xy 399.7579 -119.4943) (xy 399.7579 -119.2403) (xy 399.923 -119.0752) (xy 400.029172 -119.0752)
				(xy 400.0627 -119.041672) (xy 400.0627 -118.98376) (xy 400.0627 -118.872508) (xy 399.884392 -118.6942)
				(xy 399.77314 -118.6942) (xy 399.32864 -118.6942) (xy 398.90954 -119.1133) (xy 397.45158 -119.1133)
				(xy 397.4211 -119.14378) (xy 397.4211 -119.270272) (xy 397.4211 -119.2784) (xy 397.525748 -119.383048)
				(xy 397.525748 -119.403114) (xy 397.525748 -119.611648) (xy 398.01292 -120.09882) (xy 398.01292 -120.53062)
				(xy 398.15643 -120.67413) (xy 399.02003 -120.67413) (xy 399.2372 -120.8913) (xy 399.3007 -120.8913)
				(xy 399.5039 -121.0945) (xy 399.5039 -121.158) (xy 399.5039 -121.412) (xy 399.3388 -121.5771) (xy 399.3388 -122.0724)
			)
		)
	)
	(zone
		(net "P5V_STBY")
		(layer "F.Cu")
		(hatch none 0.5)
		(connect_pads
			(clearance 0.5)
		)
		(min_thickness 0.25)
		(fill yes
			(thermal_gap 0.5)
			(thermal_bridge_width 0.5)
			(island_removal_mode 0)
		)
		(polygon
			(pts
				(xy 344.5002 -115.727988) (xy 344.5002 -112.903) (xy 344.596212 -112.806988) (xy 344.7034 -112.6998)
				(xy 345.1606 -112.6998) (xy 345.45905 -112.99825) (xy 345.45905 -113.303304) (xy 345.7194 -113.563654)
				(xy 345.7194 -113.771934) (xy 345.52636 -113.964974) (xy 345.52636 -114.63274) (xy 345.567508 -114.673888)
				(xy 345.7194 -114.82578) (xy 345.7194 -114.8588) (xy 345.7194 -115.081558) (xy 345.587066 -115.213892)
				(xy 345.532964 -115.267994) (xy 345.532964 -115.845082) (xy 345.587066 -115.899184) (xy 345.7194 -116.031518)
				(xy 345.7194 -116.40693) (xy 345.686126 -116.440204) (xy 345.212416 -116.440204)
			)
		)
	)
	(zone
		(layer "F.Cu")
		(hatch none 0.5)
		(connect_pads
			(clearance 0)
		)
		(min_thickness 0.25)
		(keepout
			(tracks allowed)
			(vias allowed)
			(pads allowed)
			(copperpour allowed)
			(footprints not_allowed)
		)
		(placement
			(enabled no)
			(sheetname "")
		)
		(fill
			(thermal_gap 0.5)
			(thermal_bridge_width 0.5)
			(island_removal_mode 0)
		)
		(polygon
			(pts
				(xy 187.525406 -159.100012) (xy 187.525406 -130.16611) (xy 183.925464 -130.16611) (xy 183.925464 -159.100012)
			)
		)
	)
	(zone
		(net "PVDDQ_DEF")
		(layer "F.Cu")
		(hatch none 0.5)
		(connect_pads
			(clearance 0.5)
		)
		(min_thickness 0.25)
		(fill yes
			(thermal_gap 0.5)
			(thermal_bridge_width 0.5)
			(island_removal_mode 0)
		)
		(polygon
			(pts
				(xy 258.0386 -138.7348) (xy 257.9624 -138.811) (xy 257.9624 -139.2936) (xy 257.7592 -139.4968) (xy 257.7592 -140.4874)
				(xy 257.9624 -140.6906) (xy 259.9182 -140.6906) (xy 260.0198 -140.589) (xy 260.0198 -139.065) (xy 259.6896 -138.7348)
			)
		)
		(polygon
			(pts
				(xy 258.6101 -139.5349) (xy 258.4069 -139.5349) (xy 258.4069 -139.7381) (xy 258.6101 -139.7381)
			)
		)
	)
	(zone
		(net "PVPP_ABC")
		(layer "F.Cu")
		(hatch none 0.5)
		(connect_pads
			(clearance 0.5)
		)
		(min_thickness 0.25)
		(fill yes
			(thermal_gap 0.5)
			(thermal_bridge_width 0.5)
			(island_removal_mode 0)
		)
		(polygon
			(pts
				(xy 426.6438 -123.2408) (xy 425.979336 -122.576336) (xy 425.830238 -122.576336) (xy 425.5262 -122.880374)
				(xy 425.5262 -123.0757) (xy 426.1866 -123.7361) (xy 426.203364 -123.752864) (xy 426.203364 -125.366272)
				(xy 426.277786 -125.440694) (xy 426.277786 -130.824986) (xy 426.339 -130.8862) (xy 426.9232 -130.8862)
				(xy 427.4058 -130.4036) (xy 427.4058 -124.2314) (xy 427.4058 -124.0028)
			)
		)
	)
	(zone
		(net "P3V3")
		(layer "F.Cu")
		(hatch none 0.5)
		(connect_pads
			(clearance 0.5)
		)
		(min_thickness 0.25)
		(fill yes
			(thermal_gap 0.5)
			(thermal_bridge_width 0.5)
			(island_removal_mode 0)
		)
		(polygon
			(pts
				(xy 177.927 -84.5566) (xy 179.832 -84.5566) (xy 179.8574 -84.5312) (xy 180.0606 -84.5312) (xy 181.2036 -83.3882)
				(xy 181.2036 -82.0674) (xy 180.8988 -81.7626) (xy 179.8574 -81.7626) (xy 179.2224 -81.7626) (xy 178.3334 -82.6516)
				(xy 177.9016 -82.6516) (xy 177.6476 -82.9056) (xy 177.6476 -84.455) (xy 177.7492 -84.5566)
			)
		)
	)
	(zone
		(layer "F.Cu")
		(hatch none 0.5)
		(connect_pads
			(clearance 0)
		)
		(min_thickness 0.25)
		(keepout
			(tracks not_allowed)
			(vias allowed)
			(pads allowed)
			(copperpour not_allowed)
			(footprints allowed)
		)
		(placement
			(enabled no)
			(sheetname "")
		)
		(fill
			(thermal_gap 0.5)
			(thermal_bridge_width 0.5)
			(island_removal_mode 0)
		)
		(polygon
			(pts
				(arc
					(start 127 -109.650022)
					(mid 128.900174 -111.550196)
					(end 127 -113.450116)
				)
				(arc
					(start 127 -113.450116)
					(mid 125.10008 -111.550196)
					(end 127 -109.650022)
				)
			)
		)
	)
	(zone
		(layer "F.Cu")
		(hatch none 0.5)
		(connect_pads
			(clearance 0)
		)
		(min_thickness 0.25)
		(keepout
			(tracks allowed)
			(vias allowed)
			(pads allowed)
			(copperpour allowed)
			(footprints not_allowed)
		)
		(placement
			(enabled no)
			(sheetname "")
		)
		(fill
			(thermal_gap 0.5)
			(thermal_bridge_width 0.5)
			(island_removal_mode 0)
		)
		(polygon
			(pts
				(xy 187.525406 -132.166106) (xy 328.525378 -132.166106) (xy 328.525378 -130.16611) (xy 187.525406 -130.16611)
			)
		)
	)
	(zone
		(layer "F.Cu")
		(hatch none 0.5)
		(connect_pads
			(clearance 0)
		)
		(min_thickness 0.25)
		(keepout
			(tracks allowed)
			(vias allowed)
			(pads allowed)
			(copperpour allowed)
			(footprints not_allowed)
		)
		(placement
			(enabled no)
			(sheetname "")
		)
		(fill
			(thermal_gap 0.5)
			(thermal_bridge_width 0.5)
			(island_removal_mode 0)
		)
		(polygon
			(pts
				(xy 173.624494 -22.919182) (xy 167.124634 -22.919182) (xy 167.124634 5.999988)
				(arc
					(start 171.99991 5.999988)
					(mid 168.003634 1.827629)
					(end 172.344334 -1.985264)
				)
				(xy 173.624494 -1.985264)
			)
		)
	)
	(zone
		(layer "F.Cu")
		(hatch none 0.5)
		(connect_pads
			(clearance 0)
		)
		(min_thickness 0.25)
		(keepout
			(tracks allowed)
			(vias allowed)
			(pads allowed)
			(copperpour allowed)
			(footprints allowed)
		)
		(placement
			(enabled no)
			(sheetname "")
		)
		(fill
			(thermal_gap 0.5)
			(thermal_bridge_width 0.5)
			(island_removal_mode 0)
		)
		(polygon
			(pts
				(xy 195.326 -85.725) (xy 198.882 -85.725) (xy 199.136 -85.979) (xy 199.136 -87.503) (xy 198.755 -87.884)
				(xy 196.977 -87.884) (xy 196.85 -88.011) (xy 196.85 -90.551) (xy 196.723 -90.678) (xy 195.072 -90.678)
				(xy 194.818 -90.424) (xy 194.31 -89.916) (xy 194.31 -86.233) (xy 194.818 -85.725)
			)
		)
	)
	(zone
		(layer "F.Cu")
		(hatch none 0.5)
		(connect_pads
			(clearance 0)
		)
		(min_thickness 0.25)
		(keepout
			(tracks not_allowed)
			(vias allowed)
			(pads allowed)
			(copperpour not_allowed)
			(footprints allowed)
		)
		(placement
			(enabled no)
			(sheetname "")
		)
		(fill
			(thermal_gap 0.5)
			(thermal_bridge_width 0.5)
			(island_removal_mode 0)
		)
		(polygon
			(pts
				(arc
					(start 291.999924 -43.450002)
					(mid 290.100004 -41.550082)
					(end 291.999924 -39.649908)
				)
				(arc
					(start 291.999924 -39.649908)
					(mid 293.900098 -41.550082)
					(end 291.999924 -43.450002)
				)
			)
		)
	)
	(zone
		(net "GND")
		(layer "F.Cu")
		(hatch none 0.5)
		(connect_pads
			(clearance 0.5)
		)
		(min_thickness 0.25)
		(fill yes
			(thermal_gap 0.5)
			(thermal_bridge_width 0.5)
			(island_removal_mode 0)
		)
		(polygon
			(pts
				(xy 346.329 4.2418) (xy 346.329 2.024126) (xy 346.54109 1.812036) (xy 348.576646 1.812036) (xy 348.6912 1.697482)
				(xy 348.6912 0.9906) (xy 348.6912 -0.036068) (xy 348.678754 -0.048514) (xy 348.480634 -0.048514)
				(xy 348.479364 -0.049784) (xy 347.113098 -0.049784) (xy 347.079824 -0.083058) (xy 347.004132 -0.15875)
				(xy 347.004132 -1.311656) (xy 346.817188 -1.4986) (xy 346.481654 -1.834134) (xy 346.481654 -2.65049)
				(xy 346.449904 -2.68224) (xy 346.449904 -3.262122) (xy 346.3544 -3.357626) (xy 346.3544 -3.37312)
				(xy 346.3544 -3.4798) (xy 346.3544 -3.556) (xy 346.3544 -6.0198) (xy 346.7354 -6.4008) (xy 348.488 -6.4008)
				(xy 348.6912 -6.604) (xy 348.6912 -7.9756) (xy 348.5896 -8.0772) (xy 348.5134 -8.0772) (xy 348.4372 -8.1534)
				(xy 348.1324 -8.1534) (xy 347.0656 -8.1534) (xy 347.0402 -8.1788) (xy 347.0402 -8.9916) (xy 347.0402 -9.321038)
				(xy 346.576142 -9.785096) (xy 346.576142 -10.400792) (xy 346.512134 -10.4648) (xy 345.92514 -10.4648)
				(xy 345.397074 -9.936734) (xy 342.968326 -9.936734) (xy 342.85428 -9.822688) (xy 342.85428 -9.060688)
				(xy 342.961468 -8.9535) (xy 344.0811 -8.9535) (xy 344.2208 -8.8138) (xy 344.2208 -3.5814) (xy 344.3732 -3.429)
				(xy 344.3732 -1.4986) (xy 344.2208 -1.3462) (xy 344.2208 -1.341882) (xy 344.142568 -1.26365) (xy 344.142568 4.229862)
				(xy 344.10396 4.26847) (xy 342.914478 4.26847) (xy 342.826848 4.18084) (xy 342.826848 3.968242)
				(xy 342.683338 3.824732) (xy 341.712042 3.824732) (xy 341.358728 4.178046) (xy 341.358728 5.29844)
				(xy 341.53983 5.479542) (xy 342.367108 5.479542) (xy 346.20962 5.479542) (xy 346.267278 5.421884)
				(xy 346.267278 4.847082) (xy 346.329 4.78536)
			)
		)
	)
	(zone
		(layer "F.Cu")
		(hatch none 0.5)
		(connect_pads
			(clearance 0)
		)
		(min_thickness 0.25)
		(keepout
			(tracks not_allowed)
			(vias allowed)
			(pads allowed)
			(copperpour not_allowed)
			(footprints allowed)
		)
		(placement
			(enabled no)
			(sheetname "")
		)
		(fill
			(thermal_gap 0.5)
			(thermal_bridge_width 0.5)
			(island_removal_mode 0)
		)
		(polygon
			(pts
				(arc
					(start 325.627238 -148.44014)
					(mid 328.18851 -151.283469)
					(end 326.016112 -148.133054)
				)
				(arc
					(start 326.016112 -148.133054)
					(mid 325.93942 -148.435755)
					(end 325.627238 -148.44014)
				)
			)
		)
	)
	(zone
		(net "GND")
		(layer "F.Cu")
		(hatch none 0.5)
		(connect_pads
			(clearance 0.5)
		)
		(min_thickness 0.25)
		(fill yes
			(thermal_gap 0.5)
			(thermal_bridge_width 0.5)
			(island_removal_mode 0)
		)
		(polygon
			(pts
				(xy 355.499924 -26.971752) (xy 352.8314 -26.971752) (xy 352.8314 -26.93543) (xy 352.525076 -26.629106)
				(xy 352.525076 -24.036782) (xy 352.57232 -23.989538) (xy 355.343968 -23.989538) (xy 355.63683 -24.2824)
				(xy 355.63683 -26.834846)
			)
		)
	)
	(zone
		(net "GND")
		(layer "F.Cu")
		(hatch none 0.5)
		(connect_pads
			(clearance 0.5)
		)
		(min_thickness 0.25)
		(fill yes
			(thermal_gap 0.5)
			(thermal_bridge_width 0.5)
			(island_removal_mode 0)
		)
		(polygon
			(pts
				(xy 461.137 -41.8846) (xy 462.661 -41.8846) (xy 462.7626 -41.783) (xy 462.7626 -39.2938) (xy 462.6356 -39.1668)
				(xy 461.1624 -39.1668) (xy 461.01 -39.3192) (xy 461.01 -41.7576)
			)
		)
	)
	(zone
		(layer "F.Cu")
		(hatch none 0.5)
		(connect_pads
			(clearance 0)
		)
		(min_thickness 0.25)
		(keepout
			(tracks not_allowed)
			(vias allowed)
			(pads allowed)
			(copperpour not_allowed)
			(footprints allowed)
		)
		(placement
			(enabled no)
			(sheetname "")
		)
		(fill
			(thermal_gap 0.5)
			(thermal_bridge_width 0.5)
			(island_removal_mode 0)
		)
		(polygon
			(pts
				(xy 423.940986 -3.789172) (xy 424.207686 -3.789172) (xy 424.207686 -4.982972) (xy 423.940986 -4.982972)
			)
		)
	)
	(zone
		(net "GND")
		(layer "F.Cu")
		(hatch none 0.5)
		(connect_pads
			(clearance 0.5)
		)
		(min_thickness 0.25)
		(fill yes
			(thermal_gap 0.5)
			(thermal_bridge_width 0.5)
			(island_removal_mode 0)
		)
		(polygon
			(pts
				(xy 260.424676 -149.226524) (xy 260.4008 -149.2504) (xy 260.4008 -150.285958) (xy 260.4008 -150.286212)
				(xy 260.4008 -150.394924) (xy 260.281166 -150.514558) (xy 260.1722 -150.514558) (xy 259.789676 -150.514558)
				(xy 259.691124 -150.61311) (xy 259.691124 -150.940008) (xy 259.843778 -151.092662) (xy 259.844032 -151.092408)
				(xy 261.051294 -151.092408) (xy 261.353046 -150.790656) (xy 261.353046 -149.264624) (xy 261.314946 -149.226524)
			)
		)
	)
	(zone
		(layer "F.Cu")
		(hatch none 0.5)
		(connect_pads
			(clearance 0)
		)
		(min_thickness 0.25)
		(keepout
			(tracks allowed)
			(vias allowed)
			(pads allowed)
			(copperpour allowed)
			(footprints not_allowed)
		)
		(placement
			(enabled no)
			(sheetname "")
		)
		(fill
			(thermal_gap 0.5)
			(thermal_bridge_width 0.5)
			(island_removal_mode 0)
		)
		(polygon
			(pts
				(xy 422.70045 -131.508246) (xy 453.990456 -131.508246) (xy 453.990456 -142.328392) (xy 434.85689 -142.328392)
				(xy 434.85689 -141.590268) (xy 418.999924 -141.590268) (xy 418.999924 -137.329926) (xy 414.98012 -137.329926)
				(xy 414.98012 -118.090188) (xy 422.70045 -118.090188)
			)
		)
	)
	(zone
		(net "VR_FET_SW_P12V_STBY_PVDDQ_DEF")
		(layer "F.Cu")
		(hatch none 0.5)
		(connect_pads
			(clearance 0.5)
		)
		(min_thickness 0.25)
		(fill yes
			(thermal_gap 0.5)
			(thermal_bridge_width 0.5)
			(island_removal_mode 0)
		)
		(polygon
			(pts
				(xy 376.817382 -153.629868) (xy 376.7328 -153.71445) (xy 376.7328 -155.621736) (xy 376.770646 -155.659582)
				(xy 378.186442 -155.659582) (xy 378.2822 -155.75534) (xy 378.2822 -156.566362) (xy 378.4092 -156.693362)
				(xy 380.097792 -156.693362) (xy 380.785624 -156.00553) (xy 380.785624 -154.195526) (xy 380.615698 -154.0256)
				(xy 379.384814 -154.0256) (xy 378.989082 -153.629868)
			)
		)
	)
	(zone
		(layer "F.Cu")
		(hatch none 0.5)
		(connect_pads
			(clearance 0)
		)
		(min_thickness 0.25)
		(keepout
			(tracks allowed)
			(vias allowed)
			(pads allowed)
			(copperpour allowed)
			(footprints not_allowed)
		)
		(placement
			(enabled no)
			(sheetname "")
		)
		(fill
			(thermal_gap 0.5)
			(thermal_bridge_width 0.5)
			(island_removal_mode 0)
		)
		(polygon
			(pts
				(arc
					(start 471.000074 -156.59989)
					(mid 469.500204 -155.10002)
					(end 471.000074 -153.599896)
				)
				(arc
					(start 471.67165 -153.599896)
					(mid 472.338277 -153.485602)
					(end 472.928696 -153.15565)
				)
				(arc
					(start 472.928696 -153.15565)
					(mid 476.999816 -155.10002)
					(end 472.928696 -157.04439)
				)
				(arc
					(start 472.928696 -157.04439)
					(mid 472.3383 -156.714333)
					(end 471.67165 -156.59989)
				)
			)
		)
	)
	(zone
		(layer "F.Cu")
		(hatch none 0.5)
		(connect_pads
			(clearance 0)
		)
		(min_thickness 0.25)
		(keepout
			(tracks allowed)
			(vias allowed)
			(pads allowed)
			(copperpour allowed)
			(footprints allowed)
		)
		(placement
			(enabled no)
			(sheetname "")
		)
		(fill
			(thermal_gap 0.5)
			(thermal_bridge_width 0.5)
			(island_removal_mode 0)
		)
		(polygon
			(pts
				(xy 246.253 -99.9236) (xy 251.3076 -99.9236) (xy 251.5616 -100.1776) (xy 251.5616 -102.235) (xy 247.396 -102.235)
				(xy 247.396 -102.743) (xy 246.253 -102.743) (xy 246.253 -102.235)
			)
		)
	)
	(zone
		(layer "F.Cu")
		(hatch none 0.5)
		(connect_pads
			(clearance 0)
		)
		(min_thickness 0.25)
		(keepout
			(tracks not_allowed)
			(vias allowed)
			(pads allowed)
			(copperpour not_allowed)
			(footprints allowed)
		)
		(placement
			(enabled no)
			(sheetname "")
		)
		(fill
			(thermal_gap 0.5)
			(thermal_bridge_width 0.5)
			(island_removal_mode 0)
		)
		(polygon
			(pts
				(arc
					(start 446.383918 -7.966202)
					(mid 446.062753 -7.546231)
					(end 446.482724 -7.867396)
				)
				(xy 446.63487 -8.019542)
				(arc
					(start 446.63487 -7.735062)
					(mid 446.251457 -7.351268)
					(end 445.86779 -7.734808)
				)
				(arc
					(start 445.86779 -8.700008)
					(mid 446.25133 -9.083548)
					(end 446.63487 -8.700008)
				)
				(xy 446.63487 -8.415274)
				(arc
					(start 446.482724 -8.56742)
					(mid 446.062753 -8.888585)
					(end 446.383918 -8.468614)
				)
				(xy 446.585594 -8.266938) (xy 446.63487 -8.266938) (xy 446.63487 -8.165338) (xy 446.583054 -8.165338)
			)
		)
	)
	(zone
		(net "GND")
		(layer "F.Cu")
		(hatch none 0.5)
		(connect_pads
			(clearance 0.5)
		)
		(min_thickness 0.25)
		(fill yes
			(thermal_gap 0.5)
			(thermal_bridge_width 0.5)
			(island_removal_mode 0)
		)
		(polygon
			(pts
				(xy -5.03174 15.24) (xy -5.03174 8.763) (xy 413.4358 8.763) (xy 501.2182 8.763) (xy 501.2182 8.7884)
				(xy 501.2182 15.24)
			)
		)
		(polygon
			(pts
				(xy 413.1818 14.5288) (xy 352.0948 14.5288) (xy 352.0948 9.4742) (xy 413.1818 9.4742) (xy 424.283632 9.4742)
				(xy 424.283632 14.5288)
			)
		)
		(polygon
			(pts
				(xy 344.593672 14.639036) (xy 287.44037 14.639036) (xy 287.44037 9.50214) (xy 344.593672 9.50214)
				(xy 348.223078 9.50214) (xy 348.223078 14.639036)
			)
		)
		(polygon
			(pts
				(xy 189.6618 14.5288) (xy 117.221 14.5288) (xy 117.221 9.4742) (xy 189.6618 9.4742) (xy 198.934578 9.4742)
				(xy 198.934578 14.5288)
			)
		)
		(polygon
			(pts
				(xy 100.1776 14.61262) (xy 8.848344 14.61262) (xy 8.848344 9.4742) (xy 36.957 9.4742) (xy 36.957 9.9187)
				(xy 100.838 9.9187) (xy 101.0158 9.9187) (xy 114.39652 9.9187) (xy 114.39652 14.605) (xy 101.0158 14.605)
				(xy 100.1776 14.605)
			)
		)
		(polygon
			(pts
				(xy 273.4818 14.5034) (xy 201.7014 14.5034) (xy 201.7014 9.4234) (xy 273.4818 9.4234) (xy 283.28239 9.4234)
				(xy 283.28239 14.5034)
			)
		)
	)
	(zone
		(net "PVDDQ_KLM")
		(layer "F.Cu")
		(hatch none 0.5)
		(connect_pads
			(clearance 0.5)
		)
		(min_thickness 0.25)
		(fill yes
			(thermal_gap 0.5)
			(thermal_bridge_width 0.5)
			(island_removal_mode 0)
		)
		(polygon
			(pts
				(xy 89.216992 -149.300692) (xy 89.614248 -149.300692)
				(arc
					(start 89.772998 -149.142196)
					(mid 89.80252 -149.074428)
					(end 89.778332 -149.004528)
				)
				(arc
					(start 89.778332 -149.004528)
					(mid 89.697236 -148.827169)
					(end 89.72169 -148.633688)
				)
				(arc
					(start 89.72169 -148.633688)
					(mid 89.713081 -148.537904)
					(end 89.628472 -148.49221)
				)
				(arc
					(start 88.77046 -148.49221)
					(mid 88.68587 -148.537916)
					(end 88.677242 -148.633688)
				)
				(arc
					(start 88.677242 -148.633688)
					(mid 88.349582 -149.129586)
					(end 88.021922 -148.633688)
				)
				(arc
					(start 88.021922 -148.633688)
					(mid 88.013313 -148.537904)
					(end 87.928704 -148.49221)
				)
				(arc
					(start 87.920322 -148.49221)
					(mid 87.835732 -148.537916)
					(end 87.827104 -148.633688)
				)
				(arc
					(start 87.827104 -148.633688)
					(mid 87.499444 -149.129586)
					(end 87.171784 -148.633688)
				)
				(arc
					(start 87.171784 -148.633688)
					(mid 87.163175 -148.537904)
					(end 87.078566 -148.49221)
				)
				(arc
					(start 86.221316 -148.49221)
					(mid 86.136699 -148.537574)
					(end 86.12759 -148.63318)
				)
				(arc
					(start 86.12759 -148.63318)
					(mid 85.799422 -149.127427)
					(end 85.471254 -148.63318)
				)
				(arc
					(start 85.471254 -148.63318)
					(mid 85.462195 -148.537542)
					(end 85.377528 -148.49221)
				)
				(arc
					(start 85.371178 -148.49221)
					(mid 85.286561 -148.537574)
					(end 85.277452 -148.63318)
				)
				(arc
					(start 85.277452 -148.63318)
					(mid 84.949284 -149.127427)
					(end 84.621116 -148.63318)
				)
				(arc
					(start 84.621116 -148.63318)
					(mid 84.612057 -148.537542)
					(end 84.52739 -148.49221)
				)
				(arc
					(start 83.67141 -148.49221)
					(mid 83.586793 -148.537574)
					(end 83.577684 -148.63318)
				)
				(arc
					(start 83.577684 -148.63318)
					(mid 83.249516 -149.127427)
					(end 82.921348 -148.63318)
				)
				(arc
					(start 82.921348 -148.63318)
					(mid 82.912289 -148.537542)
					(end 82.827622 -148.49221)
				)
				(arc
					(start 82.821272 -148.49221)
					(mid 82.736655 -148.537574)
					(end 82.727546 -148.63318)
				)
				(arc
					(start 82.727546 -148.63318)
					(mid 82.399378 -149.127427)
					(end 82.07121 -148.63318)
				)
				(arc
					(start 82.07121 -148.63318)
					(mid 82.062151 -148.537542)
					(end 81.977484 -148.49221)
				)
				(arc
					(start 81.12125 -148.49221)
					(mid 81.036633 -148.537574)
					(end 81.027524 -148.63318)
				)
				(arc
					(start 81.027524 -148.63318)
					(mid 80.699356 -149.127427)
					(end 80.371188 -148.63318)
				)
				(arc
					(start 80.371188 -148.63318)
					(mid 80.362129 -148.537542)
					(end 80.277462 -148.49221)
				)
				(arc
					(start 79.421228 -148.49221)
					(mid 79.336611 -148.537574)
					(end 79.327502 -148.63318)
				)
				(arc
					(start 79.327502 -148.63318)
					(mid 79.255543 -149.018629)
					(end 78.872842 -149.10435)
				)
				(arc
					(start 78.872842 -149.10435)
					(mid 78.779172 -149.115637)
					(end 78.735174 -149.199092)
				)
				(xy 78.735174 -149.300692) (xy 79.932276 -149.300692) (xy 79.932276 -149.427692) (xy 80.313276 -149.427692)
				(xy 80.313276 -150.190708) (xy 79.932276 -150.190708) (xy 79.932276 -150.317708) (xy 79.06512 -150.317708)
				(arc
					(start 78.927198 -150.45563)
					(mid 78.852397 -150.516771)
					(end 78.766924 -150.561802)
				)
				(xy 78.735174 -150.574756) (xy 78.735174 -150.834852) (xy 78.865984 -150.965662)
				(arc
					(start 79.398114 -150.965662)
					(mid 79.475664 -150.929702)
					(end 79.49819 -150.847298)
				)
				(arc
					(start 79.49819 -150.847298)
					(mid 79.849472 -150.432771)
					(end 80.200754 -150.847298)
				)
				(arc
					(start 80.200754 -150.847298)
					(mid 80.223379 -150.929618)
					(end 80.30083 -150.965662)
				)
				(arc
					(start 81.098136 -150.965662)
					(mid 81.175686 -150.929702)
					(end 81.198212 -150.847298)
				)
				(arc
					(start 81.198212 -150.847298)
					(mid 81.549494 -150.432771)
					(end 81.900776 -150.847298)
				)
				(arc
					(start 81.900776 -150.847298)
					(mid 81.923401 -150.929618)
					(end 82.000852 -150.965662)
				)
				(xy 82.063336 -150.965662) (xy 82.063336 -150.906734)
				(arc
					(start 82.060796 -150.899114)
					(mid 82.372704 -150.433803)
					(end 82.75066 -150.847298)
				)
				(arc
					(start 82.75066 -150.847298)
					(mid 82.773285 -150.929618)
					(end 82.850736 -150.965662)
				)
				(arc
					(start 83.648042 -150.965662)
					(mid 83.725592 -150.929702)
					(end 83.748118 -150.847298)
				)
				(arc
					(start 83.748118 -150.847298)
					(mid 84.0994 -150.432771)
					(end 84.450682 -150.847298)
				)
				(arc
					(start 84.450682 -150.847298)
					(mid 84.473307 -150.929618)
					(end 84.550758 -150.965662)
				)
				(xy 84.613496 -150.965662) (xy 84.613496 -150.906734)
				(arc
					(start 84.610956 -150.899114)
					(mid 84.922864 -150.433803)
					(end 85.30082 -150.847298)
				)
				(arc
					(start 85.30082 -150.847298)
					(mid 85.323445 -150.929618)
					(end 85.400896 -150.965662)
				)
				(arc
					(start 86.198202 -150.965662)
					(mid 86.275752 -150.929702)
					(end 86.298278 -150.847298)
				)
				(arc
					(start 86.298278 -150.847298)
					(mid 86.64956 -150.432771)
					(end 87.000842 -150.847298)
				)
				(arc
					(start 87.000842 -150.847298)
					(mid 87.023467 -150.929618)
					(end 87.100918 -150.965662)
				)
				(xy 87.163402 -150.965662) (xy 87.163402 -150.906734)
				(arc
					(start 87.160862 -150.899114)
					(mid 87.47277 -150.433803)
					(end 87.850726 -150.847298)
				)
				(arc
					(start 87.850726 -150.847298)
					(mid 87.873351 -150.929618)
					(end 87.950802 -150.965662)
				)
				(xy 88.46947 -150.965662) (xy 88.47709 -150.958042)
				(arc
					(start 88.746838 -150.958042)
					(mid 88.823804 -150.922766)
					(end 88.847168 -150.841456)
				)
				(arc
					(start 88.847168 -150.841456)
					(mid 89.199466 -150.432678)
					(end 89.551764 -150.841456)
				)
				(arc
					(start 89.551764 -150.841456)
					(mid 89.575247 -150.922663)
					(end 89.652094 -150.958042)
				)
				(xy 89.685876 -150.958042) (xy 89.716356 -150.916894)
				(arc
					(start 89.708736 -150.892256)
					(mid 89.693723 -150.773817)
					(end 89.718642 -150.657052)
				)
				(arc
					(start 89.718642 -150.657052)
					(mid 90.02302 -150.433621)
					(end 90.357198 -150.6093)
				)
				(arc
					(start 90.357198 -150.6093)
					(mid 90.399362 -150.721561)
					(end 90.401902 -150.841456)
				)
				(arc
					(start 90.401902 -150.841456)
					(mid 90.425385 -150.922663)
					(end 90.502232 -150.958042)
				)
				(arc
					(start 91.461082 -150.958042)
					(mid 91.538048 -150.922766)
					(end 91.561412 -150.841456)
				)
				(arc
					(start 91.561412 -150.841456)
					(mid 91.652757 -150.532499)
					(end 91.948 -150.40356)
				)
				(xy 91.948 -149.492208) (xy 91.821 -149.365208) (xy 91.38666 -149.365208) (xy 91.38666 -148.984208)
				(xy 91.25966 -148.984208) (xy 91.25966 -148.49221)
				(arc
					(start 90.470228 -148.49221)
					(mid 90.385638 -148.537916)
					(end 90.37701 -148.633688)
				)
				(arc
					(start 90.37701 -148.633688)
					(mid 90.394393 -148.685241)
					(end 90.40368 -148.738844)
				)
				(arc
					(start 90.40368 -148.738844)
					(mid 90.404955 -148.791875)
					(end 90.398346 -148.844508)
				)
				(arc
					(start 90.398346 -148.844508)
					(mid 90.421496 -148.926266)
					(end 90.498676 -148.961856)
				)
				(arc
					(start 90.626692 -148.961856)
					(mid 91.032581 -149.182957)
					(end 91.066874 -149.643846)
				)
				(xy 91.066874 -150.18512)
				(arc
					(start 90.91041 -150.341584)
					(mid 90.611728 -150.474335)
					(end 90.32494 -150.317708)
				)
				(xy 89.216992 -150.317708) (xy 89.216992 -150.190708) (xy 88.835992 -150.190708) (xy 88.835992 -149.427692)
				(xy 89.216992 -149.427692)
			)
		)
		(polygon
			(pts
				(xy 88.0491 -150.2029) (xy 87.8459 -150.2029) (xy 87.8459 -150.4061) (xy 88.0491 -150.4061)
			)
		)
		(polygon
			(pts
				(xy 88.0491 -149.2123) (xy 87.8459 -149.2123) (xy 87.8459 -149.4155) (xy 88.0491 -149.4155)
			)
		)
		(polygon
			(pts
				(xy 84.402168 -149.2123) (xy 84.198968 -149.2123) (xy 84.198968 -149.4155) (xy 84.402168 -149.4155)
			)
		)
		(polygon
			(pts
				(xy 81.303368 -149.2123) (xy 81.100168 -149.2123) (xy 81.100168 -149.4155) (xy 81.303368 -149.4155)
			)
		)
	)
	(zone
		(net "PVTT_GHJ")
		(layer "F.Cu")
		(hatch none 0.5)
		(connect_pads
			(clearance 0.5)
		)
		(min_thickness 0.25)
		(fill yes
			(thermal_gap 0.5)
			(thermal_bridge_width 0.5)
			(island_removal_mode 0)
		)
		(polygon
			(pts
				(xy 167.5638 -3.81) (xy 169.2656 -3.81) (xy 169.3164 -3.7592) (xy 169.3164 -3.5814) (xy 169.291 -3.556)
				(xy 168.6814 -3.556) (xy 168.67505 -3.54965) (xy 168.62425 -3.54965) (xy 167.894 -2.8194) (xy 167.894 -2.7686)
				(xy 166.9034 -1.778) (xy 165.354 -1.778) (xy 164.737542 -1.778) (xy 164.689028 -1.826514) (xy 164.689028 -3.487928)
				(xy 164.7571 -3.556) (xy 165.3032 -3.556) (xy 167.3098 -3.556) (xy 167.4114 -3.6576)
			)
		)
	)
	(zone
		(layer "F.Cu")
		(hatch none 0.5)
		(connect_pads
			(clearance 0)
		)
		(min_thickness 0.25)
		(keepout
			(tracks not_allowed)
			(vias allowed)
			(pads allowed)
			(copperpour not_allowed)
			(footprints allowed)
		)
		(placement
			(enabled no)
			(sheetname "")
		)
		(fill
			(thermal_gap 0.5)
			(thermal_bridge_width 0.5)
			(island_removal_mode 0)
		)
		(polygon
			(pts
				(arc
					(start 291.999924 -109.650022)
					(mid 293.900098 -111.550196)
					(end 291.999924 -113.450116)
				)
				(arc
					(start 291.999924 -113.450116)
					(mid 290.100004 -111.550196)
					(end 291.999924 -109.650022)
				)
			)
		)
	)
	(zone
		(net "VR_P5V_STBY_VIN")
		(layer "F.Cu")
		(hatch none 0.5)
		(connect_pads
			(clearance 0.5)
		)
		(min_thickness 0.25)
		(fill yes
			(thermal_gap 0.5)
			(thermal_bridge_width 0.5)
			(island_removal_mode 0)
		)
		(polygon
			(pts
				(xy 390.906 -65.946782) (xy 390.906 -66.7766) (xy 390.906 -66.809112) (xy 390.882886 -66.832226)
				(xy 390.04113 -66.832226) (xy 390.023604 -66.8147) (xy 390.023604 -66.21526) (xy 390.023604 -65.843404)
				(xy 389.87476 -65.69456) (xy 389.169148 -65.69456) (xy 389.115046 -65.640458) (xy 389.115046 -64.376554)
				(xy 389.1534 -64.3382) (xy 389.165592 -64.326008) (xy 389.389112 -64.326008) (xy 389.7757 -64.326008)
				(xy 389.790686 -64.340994) (xy 389.790686 -64.818768) (xy 389.790686 -64.831468)
			)
		)
	)
	(zone
		(net "P1V8_MCP_CPU1")
		(layer "F.Cu")
		(hatch none 0.5)
		(connect_pads
			(clearance 0.5)
		)
		(min_thickness 0.25)
		(fill yes
			(thermal_gap 0.5)
			(thermal_bridge_width 0.5)
			(island_removal_mode 0)
		)
		(polygon
			(pts
				(xy 165.404546 -33.909) (xy 165.074346 -34.2392) (xy 148.8186 -34.2392) (xy 145.4404 -37.6174) (xy 145.4404 -38.862)
				(xy 138.592052 -45.710348) (xy 134.581138 -45.710348) (xy 130.860038 -49.431448) (xy 128.368552 -49.431448)
				(xy 128.1684 -49.6316) (xy 128.1684 -52.0954) (xy 131.952492 -52.0954) (xy 132.115052 -51.93284)
				(xy 132.115052 -51.203098) (xy 132.564886 -50.753264) (xy 135.962136 -50.753264) (xy 137.8712 -48.8442)
				(xy 144.855692 -48.8442) (xy 153.136092 -40.5638) (xy 163.322 -40.5638) (xy 164.338 -39.5478) (xy 166.270432 -39.5478)
				(xy 166.473886 -39.751254) (xy 166.473886 -40.1447) (xy 166.705026 -40.37584) (xy 167.479218 -40.37584)
				(xy 167.622474 -40.232584) (xy 167.622474 -36.604956) (xy 167.39362 -36.376102) (xy 167.39362 -35.37839)
				(xy 167.247824 -35.232594) (xy 167.247824 -33.923224) (xy 167.2336 -33.909)
			)
		)
		(polygon
			(pts
				(xy 165.077394 -35.0139) (xy 164.874194 -35.0139) (xy 164.874194 -35.2171) (xy 165.077394 -35.2171)
			)
		)
		(polygon
			(pts
				(xy 164.086794 -35.0139) (xy 163.670742 -35.0139) (xy 163.670742 -35.2171) (xy 164.086794 -35.2171)
			)
		)
		(polygon
			(pts
				(xy 162.883342 -35.0139) (xy 162.680142 -35.0139) (xy 162.680142 -35.2171) (xy 162.883342 -35.2171)
			)
		)
	)
	(zone
		(layer "F.Cu")
		(hatch none 0.5)
		(connect_pads
			(clearance 0)
		)
		(min_thickness 0.25)
		(keepout
			(tracks allowed)
			(vias allowed)
			(pads allowed)
			(copperpour allowed)
			(footprints allowed)
		)
		(placement
			(enabled no)
			(sheetname "")
		)
		(fill
			(thermal_gap 0.5)
			(thermal_bridge_width 0.5)
			(island_removal_mode 0)
		)
		(polygon
			(pts
				(xy 171.429426 -67.986148) (xy 173.83887 -67.986148) (xy 173.957234 -67.867784) (xy 173.957234 -64.229234)
				(xy 173.6852 -63.9572) (xy 172.1104 -63.9572) (xy 171.239942 -64.827658) (xy 171.239942 -67.796664)
			)
		)
	)
	(zone
		(net "PVDDQ_ABC")
		(layer "F.Cu")
		(hatch none 0.5)
		(connect_pads
			(clearance 0.5)
		)
		(min_thickness 0.25)
		(fill yes
			(thermal_gap 0.5)
			(thermal_bridge_width 0.5)
			(island_removal_mode 0)
		)
		(polygon
			(pts
				(xy 183.981598 0.393192) (xy 183.981598 -0.114808) (xy 184.032398 -0.165608) (xy 186.597798 -0.165608)
				(xy 186.879992 -0.165608) (xy 187.071 0.0254) (xy 187.071 2.4638) (xy 186.8932 2.6416) (xy 186.5376 2.6416)
				(xy 186.230006 2.6416) (xy 184.616598 1.028192)
			)
		)
	)
	(zone
		(layer "F.Cu")
		(hatch none 0.5)
		(connect_pads
			(clearance 0)
		)
		(min_thickness 0.25)
		(keepout
			(tracks not_allowed)
			(vias allowed)
			(pads allowed)
			(copperpour not_allowed)
			(footprints allowed)
		)
		(placement
			(enabled no)
			(sheetname "")
		)
		(fill
			(thermal_gap 0.5)
			(thermal_bridge_width 0.5)
			(island_removal_mode 0)
		)
		(polygon
			(pts
				(arc
					(start 451.721474 -60.315348)
					(mid 452.247302 -60.378848)
					(end 451.721474 -60.442348)
				)
				(xy 451.704202 -60.442348) (xy 451.639686 -60.506864) (xy 451.639686 -60.759086) (xy 451.668388 -60.787788)
				(arc
					(start 451.980554 -60.787788)
					(mid 452.389494 -60.378848)
					(end 451.980554 -59.969908)
				)
				(arc
					(start 450.710808 -59.969908)
					(mid 450.301614 -60.378721)
					(end 450.710554 -60.787788)
				)
				(xy 451.028308 -60.787788) (xy 451.054216 -60.76188) (xy 451.054216 -60.507118) (xy 450.989446 -60.442348)
				(arc
					(start 450.969634 -60.442348)
					(mid 450.443806 -60.378848)
					(end 450.969634 -60.315348)
				)
				(xy 450.989446 -60.315348) (xy 451.042278 -60.315348) (xy 451.079362 -60.352432) (xy 451.144132 -60.417202)
				(xy 451.181216 -60.454286) (xy 451.181216 -60.507118) (xy 451.181216 -60.76188) (xy 451.181216 -60.787788)
				(xy 451.512686 -60.787788) (xy 451.512686 -60.759086) (xy 451.512686 -60.506864) (xy 451.512686 -60.454032)
				(xy 451.54977 -60.416948) (xy 451.614286 -60.352432) (xy 451.65137 -60.315348) (xy 451.704202 -60.315348)
			)
		)
	)
	(zone
		(layer "F.Cu")
		(hatch none 0.5)
		(connect_pads
			(clearance 0)
		)
		(min_thickness 0.25)
		(keepout
			(tracks allowed)
			(vias allowed)
			(pads allowed)
			(copperpour allowed)
			(footprints not_allowed)
		)
		(placement
			(enabled no)
			(sheetname "")
		)
		(fill
			(thermal_gap 0.5)
			(thermal_bridge_width 0.5)
			(island_removal_mode 0)
		)
		(polygon
			(pts
				(arc
					(start 0 -5.500116)
					(mid -5.500116 0)
					(end 0 5.500116)
				)
				(arc
					(start 0 5.500116)
					(mid 5.500116 0)
					(end 0 -5.500116)
				)
			)
		)
	)
	(zone
		(net "GND")
		(layer "F.Cu")
		(hatch none 0.5)
		(connect_pads
			(clearance 0.5)
		)
		(min_thickness 0.25)
		(fill yes
			(thermal_gap 0.5)
			(thermal_bridge_width 0.5)
			(island_removal_mode 0)
		)
		(polygon
			(pts
				(xy 335.6864 -27.7114) (xy 335.6864 -32.92348) (xy 335.96834 -33.20542) (xy 337.06054 -33.20542)
				(xy 338.14512 -34.29) (xy 352.171 -34.29) (xy 352.4758 -33.9852) (xy 352.4758 -32.766) (xy 352.4758 -31.75)
				(xy 351.8154 -31.0896) (xy 351.8154 -29.972) (xy 351.6884 -29.845) (xy 350.3295 -29.845) (xy 349.9104 -29.4259)
				(xy 349.9104 -28.844748) (xy 349.9104 -28.61056) (xy 349.886778 -28.586938) (xy 349.31223 -28.586938)
				(xy 349.209868 -28.6893) (xy 349.1738 -28.6893) (xy 347.9038 -28.6893) (xy 347.7768 -28.8163) (xy 347.7768 -30.8483)
				(xy 347.6498 -30.9753) (xy 344.0938 -30.9753) (xy 343.9668 -31.1023) (xy 343.9668 -31.9913) (xy 344.6018 -32.6263)
				(xy 344.6018 -33.3502) (xy 344.424 -33.528) (xy 339.09 -33.528) (xy 338.963 -33.528) (xy 337.2866 -31.8516)
				(xy 337.2866 -26.2382) (xy 337.2104 -26.162) (xy 336.169 -26.162) (xy 335.8642 -26.162) (xy 335.6864 -26.3398)
			)
		)
	)
	(zone
		(layer "F.Cu")
		(hatch none 0.5)
		(connect_pads
			(clearance 0)
		)
		(min_thickness 0.25)
		(keepout
			(tracks allowed)
			(vias allowed)
			(pads allowed)
			(copperpour allowed)
			(footprints allowed)
		)
		(placement
			(enabled no)
			(sheetname "")
		)
		(fill
			(thermal_gap 0.5)
			(thermal_bridge_width 0.5)
			(island_removal_mode 0)
		)
		(polygon
			(pts
				(xy 321.2084 -120.9675) (xy 318.9224 -120.9675) (xy 318.9224 -118.9609) (xy 321.2084 -118.9609)
			)
		)
	)
	(zone
		(net "GND")
		(layer "F.Cu")
		(hatch none 0.5)
		(connect_pads
			(clearance 0.5)
		)
		(min_thickness 0.25)
		(fill yes
			(thermal_gap 0.5)
			(thermal_bridge_width 0.5)
			(island_removal_mode 0)
		)
		(polygon
			(pts
				(xy 357.52024 -139.94257) (xy 357.52024 -136.38657) (xy 361.07624 -136.38657) (xy 361.07624 -139.94257)
			)
		)
	)
	(zone
		(net "PVCCIO_CPU0")
		(layer "F.Cu")
		(hatch none 0.5)
		(connect_pads
			(clearance 0.5)
		)
		(min_thickness 0.25)
		(fill yes
			(thermal_gap 0.5)
			(thermal_bridge_width 0.5)
			(island_removal_mode 0)
		)
		(polygon
			(pts
				(xy 277.9522 -76.912216) (xy 277.9522 -80.096614) (xy 279.92451 -80.096614) (xy 280.608024 -79.4131)
				(xy 280.608024 -77.420216) (xy 280.100024 -76.912216)
			)
		)
		(polygon
			(pts
				(xy 280.0858 -79.0575) (xy 279.8826 -79.0575) (xy 279.8826 -79.2607) (xy 280.0858 -79.2607)
			)
		)
		(polygon
			(pts
				(xy 279.3238 -79.0575) (xy 279.1206 -79.0575) (xy 279.1206 -79.2607) (xy 279.3238 -79.2607)
			)
		)
		(polygon
			(pts
				(xy 278.8158 -79.0575) (xy 278.6126 -79.0575) (xy 278.6126 -79.2607) (xy 278.8158 -79.2607)
			)
		)
		(polygon
			(pts
				(xy 280.154634 -77.725016) (xy 279.951434 -77.725016) (xy 279.951434 -77.928216) (xy 280.154634 -77.928216)
			)
		)
		(polygon
			(pts
				(xy 279.392634 -77.725016) (xy 279.189434 -77.725016) (xy 279.189434 -77.928216) (xy 279.392634 -77.928216)
			)
		)
		(polygon
			(pts
				(xy 278.910034 -77.725016) (xy 278.706834 -77.725016) (xy 278.706834 -77.928216) (xy 278.910034 -77.928216)
			)
		)
	)
	(zone
		(layer "F.Cu")
		(hatch none 0.5)
		(connect_pads
			(clearance 0)
		)
		(min_thickness 0.25)
		(keepout
			(tracks allowed)
			(vias allowed)
			(pads allowed)
			(copperpour allowed)
			(footprints allowed)
		)
		(placement
			(enabled no)
			(sheetname "")
		)
		(fill
			(thermal_gap 0.5)
			(thermal_bridge_width 0.5)
			(island_removal_mode 0)
		)
		(polygon
			(pts
				(xy 391.51306 -5.609082) (xy 391.51306 -2.572512) (xy 469.222836 -2.572512) (xy 469.222836 -5.609082)
			)
		)
	)
	(zone
		(net "GND")
		(layer "F.Cu")
		(hatch none 0.5)
		(connect_pads
			(clearance 0.5)
		)
		(min_thickness 0.25)
		(fill yes
			(thermal_gap 0.5)
			(thermal_bridge_width 0.5)
			(island_removal_mode 0)
		)
		(polygon
			(pts
				(xy 257.7084 -78.994) (xy 257.6068 -79.0956) (xy 257.6068 -80.4672) (xy 257.7465 -80.6069) (xy 259.038344 -80.6069)
				(xy 259.05968 -80.6069) (xy 259.075428 -80.622648) (xy 261.134352 -80.622648) (xy 261.1501 -80.6069)
				(xy 261.2136 -80.5434) (xy 261.2136 -79.207106) (xy 261.137908 -79.131414) (xy 258.150614 -79.131414)
				(xy 258.1402 -79.121) (xy 258.0132 -78.994)
			)
		)
		(polygon
			(pts
				(xy 260.418072 -79.630016) (xy 260.214872 -79.630016) (xy 260.214872 -79.833216) (xy 260.418072 -79.833216)
			)
		)
		(polygon
			(pts
				(xy 259.935472 -79.630016) (xy 259.732272 -79.630016) (xy 259.732272 -79.833216) (xy 259.935472 -79.833216)
			)
		)
		(polygon
			(pts
				(xy 259.173472 -79.630016) (xy 258.970272 -79.630016) (xy 258.970272 -79.833216) (xy 259.173472 -79.833216)
			)
		)
		(polygon
			(pts
				(xy 258.690872 -79.617316) (xy 258.487672 -79.617316) (xy 258.487672 -79.820516) (xy 258.690872 -79.820516)
			)
		)
		(polygon
			(pts
				(xy 257.928872 -79.617316) (xy 257.725672 -79.617316) (xy 257.725672 -79.820516) (xy 257.928872 -79.820516)
			)
		)
	)
	(zone
		(layer "F.Cu")
		(hatch none 0.5)
		(connect_pads
			(clearance 0)
		)
		(min_thickness 0.25)
		(keepout
			(tracks not_allowed)
			(vias allowed)
			(pads allowed)
			(copperpour not_allowed)
			(footprints allowed)
		)
		(placement
			(enabled no)
			(sheetname "")
		)
		(fill
			(thermal_gap 0.5)
			(thermal_bridge_width 0.5)
			(island_removal_mode 0)
		)
		(polygon
			(pts
				(xy 325.1835 -121.412) (xy 325.1835 -121.92) (xy 324.8025 -121.92) (xy 324.8025 -121.412)
			)
		)
	)
	(zone
		(layer "F.Cu")
		(hatch none 0.5)
		(connect_pads
			(clearance 0)
		)
		(min_thickness 0.25)
		(keepout
			(tracks not_allowed)
			(vias allowed)
			(pads allowed)
			(copperpour not_allowed)
			(footprints allowed)
		)
		(placement
			(enabled no)
			(sheetname "")
		)
		(fill
			(thermal_gap 0.5)
			(thermal_bridge_width 0.5)
			(island_removal_mode 0)
		)
		(polygon
			(pts
				(arc
					(start 318.000126 -56.449976)
					(mid 316.100206 -54.550056)
					(end 318.000126 -52.649882)
				)
				(arc
					(start 318.000126 -52.649882)
					(mid 319.9003 -54.550056)
					(end 318.000126 -56.449976)
				)
			)
		)
	)
	(zone
		(net "GND")
		(layer "F.Cu")
		(hatch none 0.5)
		(connect_pads
			(clearance 0.5)
		)
		(min_thickness 0.25)
		(fill yes
			(thermal_gap 0.5)
			(thermal_bridge_width 0.5)
			(island_removal_mode 0)
		)
		(polygon
			(pts
				(xy 406.5778 -50.3174) (xy 407.8224 -50.3174) (xy 408.0002 -50.1396) (xy 408.0002 -49.7078) (xy 408.1526 -49.5554)
				(xy 410.3878 -49.5554) (xy 410.6418 -49.8094) (xy 410.6418 -52.8574) (xy 410.7942 -53.0098) (xy 412.697422 -53.0098)
				(xy 413.218376 -52.488846) (xy 413.218376 -51.55184) (xy 413.4866 -51.283616) (xy 413.787336 -50.98288)
				(xy 413.787336 -49.911) (xy 413.4104 -49.911) (xy 413.0802 -49.911) (xy 413.030416 -49.960784) (xy 413.030416 -50.491898)
				(xy 412.932626 -50.589688) (xy 412.029148 -50.589688) (xy 412.002986 -50.563526) (xy 412.002986 -50.563018)
				(xy 411.989778 -50.54981) (xy 411.989778 -49.50968) (xy 412.198058 -49.3014) (xy 412.198058 -48.37049)
				(xy 412.147512 -48.319944) (xy 410.858716 -48.319944) (xy 410.80055 -48.378364) (xy 409.915614 -48.378364)
				(xy 407.8986 -48.378364) (xy 407.171652 -48.378364) (xy 405.536146 -48.378364) (xy 404.829518 -49.084992)
				(xy 404.43658 -49.084992) (xy 404.375112 -49.023524) (xy 404.375112 -49.022) (xy 403.064472 -47.71136)
				(xy 402.561806 -47.71136) (xy 402.530564 -47.742602) (xy 402.530564 -49.729644) (xy 402.57222 -49.7713)
				(xy 405.179022 -49.7713) (xy 405.318722 -49.6316) (xy 406.443434 -49.6316) (xy 406.4762 -49.664366)
				(xy 406.4762 -49.772824) (xy 406.490678 -49.787302) (xy 406.490678 -50.230278)
			)
		)
	)
	(zone
		(layer "F.Cu")
		(hatch none 0.5)
		(connect_pads
			(clearance 0)
		)
		(min_thickness 0.25)
		(keepout
			(tracks allowed)
			(vias allowed)
			(pads allowed)
			(copperpour allowed)
			(footprints allowed)
		)
		(placement
			(enabled no)
			(sheetname "")
		)
		(fill
			(thermal_gap 0.5)
			(thermal_bridge_width 0.5)
			(island_removal_mode 0)
		)
		(polygon
			(pts
				(xy 401.8534 -100.33) (xy 404.6728 -100.33) (xy 405.4856 -101.1428) (xy 409.0416 -101.1428) (xy 409.448 -100.7364)
				(xy 409.448 -98.6282) (xy 408.4574 -97.6376) (xy 403.733 -97.6376) (xy 401.701 -99.6696) (xy 401.701 -100.1776)
			)
		)
	)
	(zone
		(net "GND")
		(layer "F.Cu")
		(hatch none 0.5)
		(connect_pads
			(clearance 0.5)
		)
		(min_thickness 0.25)
		(fill yes
			(thermal_gap 0.5)
			(thermal_bridge_width 0.5)
			(island_removal_mode 0)
		)
		(polygon
			(pts
				(xy 165.872922 -147.445222) (xy 165.252146 -147.445222) (xy 165.125146 -147.572222) (xy 165.125146 -148.461222)
				(xy 165.379146 -148.715222) (xy 167.054784 -148.715222) (xy 167.125396 -148.64461) (xy 167.481758 -148.64461)
				(xy 167.665146 -148.461222) (xy 167.665146 -147.699222) (xy 167.538908 -147.572984) (xy 166.00043 -147.572984)
				(xy 165.993064 -147.565618) (xy 165.993064 -147.565364)
			)
		)
	)
	(zone
		(net "SATA6G_S1_TX_C_DP")
		(layer "F.Cu")
		(hatch none 0.5)
		(connect_pads
			(clearance 0.5)
		)
		(min_thickness 0.25)
		(fill yes
			(thermal_gap 0.5)
			(thermal_bridge_width 0.5)
			(island_removal_mode 0)
		)
		(polygon
			(pts
				(arc
					(start 430.232058 -136.344914)
					(mid 429.408082 -136.344914)
					(end 430.232058 -136.344914)
				)
			)
		)
	)
	(zone
		(layer "F.Cu")
		(hatch none 0.5)
		(connect_pads
			(clearance 0)
		)
		(min_thickness 0.25)
		(keepout
			(tracks not_allowed)
			(vias allowed)
			(pads allowed)
			(copperpour not_allowed)
			(footprints allowed)
		)
		(placement
			(enabled no)
			(sheetname "")
		)
		(fill
			(thermal_gap 0.5)
			(thermal_bridge_width 0.5)
			(island_removal_mode 0)
		)
		(polygon
			(pts
				(xy 373.653558 -1.349756) (xy 373.808752 -1.50495) (xy 373.808752 -1.803146) (xy 373.910352 -1.803146)
				(xy 373.910352 -1.50495) (xy 374.065546 -1.349756)
				(arc
					(start 374.23725 -1.349756)
					(mid 374.761167 -1.419606)
					(end 374.23725 -1.489456)
				)
				(xy 374.123458 -1.489456) (xy 374.050052 -1.562862) (xy 374.050052 -1.803146)
				(arc
					(start 374.494298 -1.803146)
					(mid 374.878092 -1.419733)
					(end 374.494552 -1.036066)
				)
				(arc
					(start 373.224552 -1.036066)
					(mid 372.841012 -1.419606)
					(end 373.224552 -1.803146)
				)
				(xy 373.669052 -1.803146) (xy 373.669052 -1.562862) (xy 373.595646 -1.489456)
				(arc
					(start 373.481854 -1.489456)
					(mid 372.957937 -1.419606)
					(end 373.481854 -1.349756)
				)
			)
		)
	)
	(zone
		(layer "F.Cu")
		(hatch none 0.5)
		(connect_pads
			(clearance 0)
		)
		(min_thickness 0.25)
		(keepout
			(tracks allowed)
			(vias allowed)
			(pads allowed)
			(copperpour allowed)
			(footprints allowed)
		)
		(placement
			(enabled no)
			(sheetname "")
		)
		(fill
			(thermal_gap 0.5)
			(thermal_bridge_width 0.5)
			(island_removal_mode 0)
		)
		(polygon
			(pts
				(xy 344.7796 -85.7758) (xy 344.7796 -83.8708) (xy 349.1484 -83.8708) (xy 349.1484 -85.7758)
			)
		)
	)
	(zone
		(layer "F.Cu")
		(hatch none 0.5)
		(connect_pads
			(clearance 0)
		)
		(min_thickness 0.25)
		(keepout
			(tracks not_allowed)
			(vias allowed)
			(pads allowed)
			(copperpour not_allowed)
			(footprints allowed)
		)
		(placement
			(enabled no)
			(sheetname "")
		)
		(fill
			(thermal_gap 0.5)
			(thermal_bridge_width 0.5)
			(island_removal_mode 0)
		)
		(polygon
			(pts
				(xy 424.823636 -9.639808) (xy 424.823636 -9.84377) (xy 424.574208 -10.093198)
				(arc
					(start 424.487594 -10.093198)
					(mid 423.963677 -10.023348)
					(end 424.487594 -9.953498)
				)
				(xy 424.516296 -9.953498) (xy 424.683936 -9.785858) (xy 424.683936 -9.639808)
				(arc
					(start 424.230292 -9.639808)
					(mid 423.846752 -10.023348)
					(end 424.230292 -10.406888)
				)
				(arc
					(start 425.500038 -10.406888)
					(mid 425.883832 -10.023475)
					(end 425.500292 -9.639808)
				)
				(xy 425.064936 -9.639808) (xy 425.064936 -9.80313) (xy 425.215304 -9.953498)
				(arc
					(start 425.24299 -9.953498)
					(mid 425.766907 -10.023348)
					(end 425.24299 -10.093198)
				)
				(xy 425.157392 -10.093198) (xy 424.925236 -9.861042) (xy 424.925236 -9.639808)
			)
		)
	)
	(zone
		(net "GND")
		(layer "F.Cu")
		(hatch none 0.5)
		(connect_pads
			(clearance 0.5)
		)
		(min_thickness 0.25)
		(fill yes
			(thermal_gap 0.5)
			(thermal_bridge_width 0.5)
			(island_removal_mode 0)
		)
		(polygon
			(pts
				(xy 357.3526 -18.415) (xy 359.75036 -18.415) (xy 360.03738 -18.12798) (xy 360.03738 -16.790162)
				(xy 360.688382 -16.13916) (xy 360.688382 -12.29614) (xy 360.462322 -12.07008) (xy 358.800146 -12.07008)
				(xy 358.797098 -12.067032) (xy 357.564436 -12.067032) (xy 357.124 -12.507468) (xy 357.124 -18.1864)
			)
		)
	)
	(zone
		(layer "F.Cu")
		(hatch none 0.5)
		(connect_pads
			(clearance 0)
		)
		(min_thickness 0.25)
		(keepout
			(tracks allowed)
			(vias allowed)
			(pads allowed)
			(copperpour allowed)
			(footprints not_allowed)
		)
		(placement
			(enabled no)
			(sheetname "")
		)
		(fill
			(thermal_gap 0.5)
			(thermal_bridge_width 0.5)
			(island_removal_mode 0)
		)
		(polygon
			(pts
				(arc
					(start -5.999988 -152.599898)
					(mid -4.658223 -155.09995)
					(end -5.999988 -157.599888)
				)
			)
		)
	)
	(zone
		(layer "F.Cu")
		(hatch none 0.5)
		(connect_pads
			(clearance 0)
		)
		(min_thickness 0.25)
		(keepout
			(tracks not_allowed)
			(vias allowed)
			(pads allowed)
			(copperpour not_allowed)
			(footprints allowed)
		)
		(placement
			(enabled no)
			(sheetname "")
		)
		(fill
			(thermal_gap 0.5)
			(thermal_bridge_width 0.5)
			(island_removal_mode 0)
		)
		(polygon
			(pts
				(arc
					(start 0 -5.500116)
					(mid -5.500116 0)
					(end 0 5.500116)
				)
				(arc
					(start 0 5.500116)
					(mid 5.500116 0)
					(end 0 -5.500116)
				)
			)
		)
	)
	(zone
		(layer "F.Cu")
		(hatch none 0.5)
		(connect_pads
			(clearance 0)
		)
		(min_thickness 0.25)
		(keepout
			(tracks allowed)
			(vias allowed)
			(pads allowed)
			(copperpour allowed)
			(footprints not_allowed)
		)
		(placement
			(enabled no)
			(sheetname "")
		)
		(fill
			(thermal_gap 0.5)
			(thermal_bridge_width 0.5)
			(island_removal_mode 0)
		)
		(polygon
			(pts
				(xy 453.990456 -131.500118) (xy 465.74202 -131.500118) (xy 465.74202 -136.53008) (xy 466.620098 -136.53008)
				(xy 466.620098 -154.610054) (xy 453.990456 -154.610054)
			)
		)
	)
	(zone
		(net "PVCCMCP_CPU1")
		(layer "F.Cu")
		(hatch none 0.5)
		(connect_pads
			(clearance 0.5)
		)
		(min_thickness 0.25)
		(fill yes
			(thermal_gap 0.5)
			(thermal_bridge_width 0.5)
			(island_removal_mode 0)
		)
		(polygon
			(pts
				(xy 104.061768 -72.898) (xy 103.909368 -73.0504) (xy 103.909368 -74.422) (xy 104.137968 -74.6506)
				(xy 104.264968 -74.6506) (xy 104.341168 -74.7268) (xy 112.596168 -74.7268) (xy 112.850168 -74.4728)
				(xy 112.850168 -73.2282) (xy 112.519968 -72.898)
			)
		)
		(polygon
			(pts
				(xy 112.46104 -73.661016) (xy 112.25784 -73.661016) (xy 112.25784 -73.864216) (xy 112.46104 -73.864216)
			)
		)
		(polygon
			(pts
				(xy 111.69904 -73.661016) (xy 111.49584 -73.661016) (xy 111.49584 -73.864216) (xy 111.69904 -73.864216)
			)
		)
		(polygon
			(pts
				(xy 111.19104 -73.661016) (xy 110.98784 -73.661016) (xy 110.98784 -73.864216) (xy 111.19104 -73.864216)
			)
		)
		(polygon
			(pts
				(xy 110.42904 -73.661016) (xy 110.22584 -73.661016) (xy 110.22584 -73.864216) (xy 110.42904 -73.864216)
			)
		)
		(polygon
			(pts
				(xy 109.92104 -73.661016) (xy 109.71784 -73.661016) (xy 109.71784 -73.864216) (xy 109.92104 -73.864216)
			)
		)
		(polygon
			(pts
				(xy 109.15904 -73.661016) (xy 108.95584 -73.661016) (xy 108.95584 -73.864216) (xy 109.15904 -73.864216)
			)
		)
		(polygon
			(pts
				(xy 108.65104 -73.661016) (xy 108.44784 -73.661016) (xy 108.44784 -73.864216) (xy 108.65104 -73.864216)
			)
		)
		(polygon
			(pts
				(xy 107.88904 -73.661016) (xy 107.68584 -73.661016) (xy 107.68584 -73.864216) (xy 107.88904 -73.864216)
			)
		)
		(polygon
			(pts
				(xy 107.38104 -73.6219) (xy 107.17784 -73.6219) (xy 107.17784 -73.8251) (xy 107.38104 -73.8251)
			)
		)
		(polygon
			(pts
				(xy 106.61904 -73.6219) (xy 106.41584 -73.6219) (xy 106.41584 -73.8251) (xy 106.61904 -73.8251)
			)
		)
		(polygon
			(pts
				(xy 106.11104 -73.6219) (xy 105.90784 -73.6219) (xy 105.90784 -73.8251) (xy 106.11104 -73.8251)
			)
		)
		(polygon
			(pts
				(xy 105.34904 -73.6219) (xy 105.14584 -73.6219) (xy 105.14584 -73.8251) (xy 105.34904 -73.8251)
			)
		)
		(polygon
			(pts
				(xy 104.84104 -73.6219) (xy 104.63784 -73.6219) (xy 104.63784 -73.8251) (xy 104.84104 -73.8251)
			)
		)
	)
	(zone
		(layer "F.Cu")
		(hatch none 0.5)
		(connect_pads
			(clearance 0)
		)
		(min_thickness 0.25)
		(keepout
			(tracks allowed)
			(vias allowed)
			(pads allowed)
			(copperpour allowed)
			(footprints allowed)
		)
		(placement
			(enabled no)
			(sheetname "")
		)
		(fill
			(thermal_gap 0.5)
			(thermal_bridge_width 0.5)
			(island_removal_mode 0)
		)
		(polygon
			(pts
				(xy 373.126 -158.877) (xy 380.111 -158.877) (xy 380.492 -158.496) (xy 380.492 -153.924) (xy 380.492 -153.3652)
				(xy 380.1618 -153.035) (xy 372.4656 -153.035) (xy 372.364 -153.1366) (xy 372.364 -153.67) (xy 372.364 -158.115)
			)
		)
	)
	(zone
		(net "GND")
		(layer "F.Cu")
		(hatch none 0.5)
		(connect_pads
			(clearance 0.5)
		)
		(min_thickness 0.25)
		(fill yes
			(thermal_gap 0.5)
			(thermal_bridge_width 0.5)
			(island_removal_mode 0)
		)
		(polygon
			(pts
				(xy 344.653616 -140.314934) (xy 344.278458 -140.690092) (xy 344.278458 -141.664182) (xy 344.708988 -142.094712)
				(xy 344.708988 -142.448788) (xy 345.2368 -142.9766) (xy 345.2368 -148.1836) (xy 344.5002 -148.9202)
				(xy 344.5002 -150.1902) (xy 345.2368 -150.9268) (xy 345.2368 -156.254196) (xy 345.633548 -156.650944)
				(xy 345.633548 -157.637734) (xy 345.806014 -157.8102) (xy 347.512386 -157.8102) (xy 347.802962 -157.519624)
				(xy 347.802962 -156.361384) (xy 348.0562 -156.108146) (xy 348.0562 -155.0924) (xy 348.1705 -154.9781)
				(xy 349.5929 -154.9781) (xy 349.7326 -154.8384) (xy 349.7326 -153.3906) (xy 349.5294 -153.1874)
				(xy 347.726 -153.1874) (xy 347.4212 -152.8826) (xy 347.4212 -149.502622) (xy 347.581982 -149.34184)
				(xy 347.581982 -148.745448) (xy 348.0562 -148.27123) (xy 348.0562 -147.1168) (xy 348.107 -147.066)
				(xy 349.688658 -147.066) (xy 349.74149 -147.013168) (xy 349.74149 -145.312384) (xy 349.717106 -145.288)
				(xy 347.599 -145.288) (xy 347.3958 -145.0848) (xy 347.3958 -141.834362) (xy 347.352112 -141.790674)
				(xy 347.352112 -140.941044) (xy 347.340174 -140.929106) (xy 347.340174 -140.339572) (xy 347.315536 -140.314934)
			)
		)
		(polygon
			(pts
				(xy 346.603828 -157.4546) (xy 346.400628 -157.4546) (xy 346.400628 -157.6578) (xy 346.603828 -157.6578)
			)
		)
		(polygon
			(pts
				(xy 346.603828 -156.591) (xy 346.400628 -156.591) (xy 346.400628 -156.7942) (xy 346.603828 -156.7942)
			)
		)
		(polygon
			(pts
				(xy 345.2622 -141.5542) (xy 345.059 -141.5542) (xy 345.059 -141.7574) (xy 345.2622 -141.7574)
			)
		)
		(polygon
			(pts
				(xy 345.2622 -140.6906) (xy 345.059 -140.6906) (xy 345.059 -140.8938) (xy 345.2622 -140.8938)
			)
		)
	)
	(zone
		(net "GND")
		(layer "F.Cu")
		(hatch none 0.5)
		(connect_pads
			(clearance 0.5)
		)
		(min_thickness 0.25)
		(fill yes
			(thermal_gap 0.5)
			(thermal_bridge_width 0.5)
			(island_removal_mode 0)
		)
		(polygon
			(pts
				(xy 400.23034 -31.02864) (xy 399.62074 -31.02864) (xy 396.10792 -31.02864) (xy 395.93774 -31.19882)
				(xy 395.55547 -31.19882) (xy 395.4145 -31.05785) (xy 395.4145 -30.76702) (xy 395.4145 -30.24378)
				(xy 395.97076 -29.68752) (xy 399.61312 -29.68752) (xy 399.873724 -29.68752) (xy 400.33956 -30.153356)
				(xy 400.33956 -30.158182) (xy 400.556476 -30.375098) (xy 400.556476 -30.931104) (xy 400.448018 -31.039562)
				(xy 400.241262 -31.039562)
			)
		)
	)
	(zone
		(layer "F.Cu")
		(hatch none 0.5)
		(connect_pads
			(clearance 0)
		)
		(min_thickness 0.25)
		(keepout
			(tracks not_allowed)
			(vias allowed)
			(pads allowed)
			(copperpour not_allowed)
			(footprints allowed)
		)
		(placement
			(enabled no)
			(sheetname "")
		)
		(fill
			(thermal_gap 0.5)
			(thermal_bridge_width 0.5)
			(island_removal_mode 0)
		)
		(polygon
			(pts
				(arc
					(start 384.769106 -23.635716)
					(mid 384.420872 -23.219918)
					(end 384.005074 -23.568152)
				)
				(xy 384.002534 -23.567898) (xy 383.975356 -23.873206) (xy 384.017012 -23.873206)
				(arc
					(start 384.155696 -23.734522)
					(mid 384.575667 -23.413357)
					(end 384.254502 -23.833328)
				)
				(xy 384.074924 -24.012906) (xy 383.96291 -24.012906) (xy 383.95402 -24.114506) (xy 383.99593 -24.114506)
				(arc
					(start 384.172714 -24.29129)
					(mid 384.493879 -24.711261)
					(end 384.073908 -24.390096)
				)
				(xy 383.94132 -24.257508) (xy 383.920746 -24.488648)
				(arc
					(start 383.923286 -24.488902)
					(mid 384.27152 -24.9047)
					(end 384.687318 -24.556466)
				)
				(xy 384.689858 -24.55672) (xy 384.771646 -23.636224) (xy 384.771392 -23.63597)
			)
		)
	)
	(zone
		(layer "F.Cu")
		(hatch none 0.5)
		(connect_pads
			(clearance 0)
		)
		(min_thickness 0.25)
		(keepout
			(tracks allowed)
			(vias allowed)
			(pads allowed)
			(copperpour allowed)
			(footprints allowed)
		)
		(placement
			(enabled no)
			(sheetname "")
		)
		(fill
			(thermal_gap 0.5)
			(thermal_bridge_width 0.5)
			(island_removal_mode 0)
		)
		(polygon
			(pts
				(xy 113.002568 -109.347) (xy 113.002568 -110.617) (xy 115.059968 -112.6744) (xy 115.059968 -113.4364)
				(xy 116.495068 -114.8715) (xy 116.685568 -115.062) (xy 118.209568 -113.538) (xy 119.860568 -115.189)
				(xy 121.511568 -113.538) (xy 123.162568 -115.189) (xy 125.194568 -113.157) (xy 123.543568 -111.506)
				(xy 122.019568 -109.982) (xy 120.622568 -109.982) (xy 118.082568 -107.442) (xy 118.082568 -106.045)
				(xy 117.828568 -106.045) (xy 113.129568 -106.045) (xy 113.002568 -106.045)
			)
		)
	)
	(zone
		(net "PVDDQ_ABC")
		(layer "F.Cu")
		(hatch none 0.5)
		(connect_pads
			(clearance 0.5)
		)
		(min_thickness 0.25)
		(fill yes
			(thermal_gap 0.5)
			(thermal_bridge_width 0.5)
			(island_removal_mode 0)
		)
		(polygon
			(pts
				(xy 244.348 -11.4808) (xy 243.586 -12.2428) (xy 243.586 -14.2621) (xy 243.713 -14.3891) (xy 256.41046 -14.3891)
				(xy 256.65684 -14.14272) (xy 256.65684 -11.67384) (xy 256.4638 -11.4808)
			)
		)
		(polygon
			(pts
				(xy 253.049532 -13.3477) (xy 252.846332 -13.3477) (xy 252.846332 -13.5509) (xy 253.049532 -13.5509)
			)
		)
		(polygon
			(pts
				(xy 253.049532 -12.3571) (xy 252.846332 -12.3571) (xy 252.846332 -12.5603) (xy 253.049532 -12.5603)
			)
		)
		(polygon
			(pts
				(xy 249.4026 -12.3571) (xy 249.1994 -12.3571) (xy 249.1994 -12.5603) (xy 249.4026 -12.5603)
			)
		)
	)
	(zone
		(net "P12V_STBY")
		(layer "F.Cu")
		(hatch none 0.5)
		(connect_pads
			(clearance 0.5)
		)
		(min_thickness 0.25)
		(fill yes
			(thermal_gap 0.5)
			(thermal_bridge_width 0.5)
			(island_removal_mode 0)
		)
		(polygon
			(pts
				(xy 356.108 -23.8252) (xy 356.108 -20.574) (xy 356.7684 -19.9136) (xy 357.3526 -19.3294) (xy 358.5718 -19.3294)
				(xy 358.8766 -19.6342) (xy 358.8766 -20.1168) (xy 358.8766 -23.1394) (xy 357.9622 -24.0538) (xy 356.3366 -24.0538)
			)
		)
	)
	(zone
		(layer "F.Cu")
		(hatch none 0.5)
		(connect_pads
			(clearance 0)
		)
		(min_thickness 0.25)
		(keepout
			(tracks allowed)
			(vias allowed)
			(pads allowed)
			(copperpour allowed)
			(footprints not_allowed)
		)
		(placement
			(enabled no)
			(sheetname "")
		)
		(fill
			(thermal_gap 0.5)
			(thermal_bridge_width 0.5)
			(island_removal_mode 0)
		)
		(polygon
			(pts
				(arc
					(start 171.99991 0.500126)
					(mid 170.499786 2.00025)
					(end 171.99991 3.50012)
				)
				(arc
					(start 172.671486 3.50012)
					(mid 173.338113 3.614414)
					(end 173.928532 3.944366)
				)
				(arc
					(start 173.928532 3.944366)
					(mid 177.999652 1.999996)
					(end 173.928532 0.055626)
				)
				(arc
					(start 173.928532 0.055626)
					(mid 173.338136 0.385683)
					(end 172.671486 0.500126)
				)
			)
		)
	)
	(zone
		(layer "F.Cu")
		(hatch none 0.5)
		(connect_pads
			(clearance 0)
		)
		(min_thickness 0.25)
		(keepout
			(tracks allowed)
			(vias allowed)
			(pads allowed)
			(copperpour allowed)
			(footprints not_allowed)
		)
		(placement
			(enabled no)
			(sheetname "")
		)
		(fill
			(thermal_gap 0.5)
			(thermal_bridge_width 0.5)
			(island_removal_mode 0)
		)
		(polygon
			(pts
				(arc
					(start 198.930006 -42.999914)
					(mid 202.480164 -46.550072)
					(end 198.930006 -50.099976)
				)
				(arc
					(start 198.930006 -50.099976)
					(mid 195.380102 -46.550072)
					(end 198.930006 -42.999914)
				)
			)
		)
	)
	(zone
		(layer "F.Cu")
		(hatch none 0.5)
		(connect_pads
			(clearance 0)
		)
		(min_thickness 0.25)
		(keepout
			(tracks allowed)
			(vias allowed)
			(pads allowed)
			(copperpour allowed)
			(footprints not_allowed)
		)
		(placement
			(enabled no)
			(sheetname "")
		)
		(fill
			(thermal_gap 0.5)
			(thermal_bridge_width 0.5)
			(island_removal_mode 0)
		)
		(polygon
			(pts
				(arc
					(start 152.999948 -52.649882)
					(mid 154.900122 -54.550056)
					(end 152.999948 -56.449976)
				)
				(arc
					(start 152.999948 -56.449976)
					(mid 151.100028 -54.550056)
					(end 152.999948 -52.649882)
				)
			)
		)
	)
	(zone
		(layer "F.Cu")
		(hatch none 0.5)
		(connect_pads
			(clearance 0)
		)
		(min_thickness 0.25)
		(keepout
			(tracks allowed)
			(vias allowed)
			(pads allowed)
			(copperpour allowed)
			(footprints allowed)
		)
		(placement
			(enabled no)
			(sheetname "")
		)
		(fill
			(thermal_gap 0.5)
			(thermal_bridge_width 0.5)
			(island_removal_mode 0)
		)
		(polygon
			(pts
				(xy 347.091 -150.749) (xy 353.06 -150.749) (xy 353.441 -150.368) (xy 353.441 -145.415) (xy 352.806 -144.78)
				(xy 347.599 -144.78) (xy 346.837 -145.542) (xy 346.837 -150.495)
			)
		)
	)
	(zone
		(net "PVCCIO_CPU1")
		(layer "F.Cu")
		(hatch none 0.5)
		(connect_pads
			(clearance 0.5)
		)
		(min_thickness 0.25)
		(fill yes
			(thermal_gap 0.5)
			(thermal_bridge_width 0.5)
			(island_removal_mode 0)
		)
		(polygon
			(pts
				(xy 113.281968 -70.432168) (xy 113.281968 -72.044814) (xy 113.408968 -72.171814) (xy 115.531392 -72.171814)
				(xy 115.836192 -72.476614) (xy 116.0272 -72.476614) (xy 116.0272 -74.095102) (xy 116.096542 -74.164444)
				(xy 116.473224 -74.164444) (xy 116.5606 -74.077068) (xy 116.5606 -72.0344) (xy 116.494814 -71.968614)
				(xy 116.394992 -71.968614) (xy 115.912392 -71.968614) (xy 115.734592 -71.790814) (xy 115.734592 -70.190614)
				(xy 115.131342 -69.587364) (xy 115.038378 -69.4944) (xy 115.012978 -69.469) (xy 113.7666 -69.469)
				(xy 113.6396 -69.596) (xy 109.8296 -69.596) (xy 109.474 -69.596) (xy 108.458 -69.596) (xy 108.458 -70.104)
				(xy 109.4232 -70.104) (xy 109.4486 -70.0786) (xy 109.5248 -70.1548) (xy 111.1504 -70.1548) (xy 113.0046 -70.1548)
			)
		)
	)
	(zone
		(layer "F.Cu")
		(hatch none 0.5)
		(connect_pads
			(clearance 0)
		)
		(min_thickness 0.25)
		(keepout
			(tracks not_allowed)
			(vias allowed)
			(pads allowed)
			(copperpour not_allowed)
			(footprints allowed)
		)
		(placement
			(enabled no)
			(sheetname "")
		)
		(fill
			(thermal_gap 0.5)
			(thermal_bridge_width 0.5)
			(island_removal_mode 0)
		)
		(polygon
			(pts
				(arc
					(start 318.000126 -96.009968)
					(mid 320.540126 -98.549968)
					(end 318.000126 -101.089968)
				)
				(arc
					(start 318.000126 -101.089968)
					(mid 315.460126 -98.549968)
					(end 318.000126 -96.009968)
				)
			)
		)
	)
	(zone
		(layer "F.Cu")
		(hatch none 0.5)
		(connect_pads
			(clearance 0)
		)
		(min_thickness 0.25)
		(keepout
			(tracks allowed)
			(vias allowed)
			(pads allowed)
			(copperpour allowed)
			(footprints allowed)
		)
		(placement
			(enabled no)
			(sheetname "")
		)
		(fill
			(thermal_gap 0.5)
			(thermal_bridge_width 0.5)
			(island_removal_mode 0)
		)
		(polygon
			(pts
				(xy 495.46256 -126.618238) (xy 497.264436 -126.618238) (xy 497.494052 -126.388622) (xy 498.098064 -125.78461)
				(xy 498.098064 -125.063504) (xy 497.79428 -124.75972) (xy 497.23421 -124.75972) (xy 495.293142 -124.75972)
				(xy 495.225578 -124.827284) (xy 495.225578 -126.381256)
			)
		)
	)
	(zone
		(layer "F.Cu")
		(hatch none 0.5)
		(connect_pads
			(clearance 0)
		)
		(min_thickness 0.25)
		(keepout
			(tracks not_allowed)
			(vias allowed)
			(pads allowed)
			(copperpour not_allowed)
			(footprints allowed)
		)
		(placement
			(enabled no)
			(sheetname "")
		)
		(fill
			(thermal_gap 0.5)
			(thermal_bridge_width 0.5)
			(island_removal_mode 0)
		)
		(polygon
			(pts
				(xy 427.223936 -9.639808) (xy 427.223936 -9.90727) (xy 427.038008 -10.093198)
				(arc
					(start 426.887894 -10.093198)
					(mid 426.363977 -10.023348)
					(end 426.887894 -9.953498)
				)
				(xy 426.980096 -9.953498) (xy 427.084236 -9.849358) (xy 427.084236 -9.639808)
				(arc
					(start 426.630592 -9.639808)
					(mid 426.247052 -10.023348)
					(end 426.630592 -10.406888)
				)
				(arc
					(start 427.900338 -10.406888)
					(mid 428.284132 -10.023475)
					(end 427.900592 -9.639808)
				)
				(xy 427.465236 -9.639808) (xy 427.465236 -9.84123) (xy 427.577504 -9.953498)
				(arc
					(start 427.64329 -9.953498)
					(mid 428.167207 -10.023348)
					(end 427.64329 -10.093198)
				)
				(xy 427.519592 -10.093198) (xy 427.325536 -9.899142) (xy 427.325536 -9.639808)
			)
		)
	)
	(zone
		(layer "F.Cu")
		(hatch none 0.5)
		(connect_pads
			(clearance 0)
		)
		(min_thickness 0.25)
		(keepout
			(tracks allowed)
			(vias allowed)
			(pads allowed)
			(copperpour allowed)
			(footprints allowed)
		)
		(placement
			(enabled no)
			(sheetname "")
		)
		(fill
			(thermal_gap 0.5)
			(thermal_bridge_width 0.5)
			(island_removal_mode 0)
		)
		(polygon
			(pts
				(xy 412.115 -100.2538) (xy 412.115 -99.0854) (xy 413.6136 -99.0854) (xy 413.6136 -100.2538)
			)
		)
	)
	(zone
		(layer "F.Cu")
		(hatch none 0.5)
		(connect_pads
			(clearance 0)
		)
		(min_thickness 0.25)
		(keepout
			(tracks not_allowed)
			(vias allowed)
			(pads allowed)
			(copperpour not_allowed)
			(footprints allowed)
		)
		(placement
			(enabled no)
			(sheetname "")
		)
		(fill
			(thermal_gap 0.5)
			(thermal_bridge_width 0.5)
			(island_removal_mode 0)
		)
		(polygon
			(pts
				(xy 401.065492 -10.295636) (xy 401.573492 -10.295636) (xy 401.573492 -10.651236) (xy 401.065492 -10.651236)
			)
		)
	)
	(zone
		(net "PVCCMCP_CPU0")
		(layer "F.Cu")
		(hatch none 0.5)
		(connect_pads
			(clearance 0.5)
		)
		(min_thickness 0.25)
		(fill yes
			(thermal_gap 0.5)
			(thermal_bridge_width 0.5)
			(island_removal_mode 0)
		)
		(polygon
			(pts
				(xy 269.0622 -72.898) (xy 268.9098 -73.0504) (xy 268.9098 -74.3712) (xy 269.1638 -74.6252) (xy 277.6982 -74.6252)
				(xy 277.7617 -74.5617) (xy 277.7617 -73.1393) (xy 277.5204 -72.898)
			)
		)
		(polygon
			(pts
				(xy 277.461472 -73.661016) (xy 277.258272 -73.661016) (xy 277.258272 -73.864216) (xy 277.461472 -73.864216)
			)
		)
		(polygon
			(pts
				(xy 276.699472 -73.661016) (xy 276.496272 -73.661016) (xy 276.496272 -73.864216) (xy 276.699472 -73.864216)
			)
		)
		(polygon
			(pts
				(xy 276.191472 -73.661016) (xy 275.988272 -73.661016) (xy 275.988272 -73.864216) (xy 276.191472 -73.864216)
			)
		)
		(polygon
			(pts
				(xy 275.429472 -73.661016) (xy 275.226272 -73.661016) (xy 275.226272 -73.864216) (xy 275.429472 -73.864216)
			)
		)
		(polygon
			(pts
				(xy 274.921472 -73.661016) (xy 274.718272 -73.661016) (xy 274.718272 -73.864216) (xy 274.921472 -73.864216)
			)
		)
		(polygon
			(pts
				(xy 274.159472 -73.661016) (xy 273.956272 -73.661016) (xy 273.956272 -73.864216) (xy 274.159472 -73.864216)
			)
		)
		(polygon
			(pts
				(xy 273.651472 -73.661016) (xy 273.448272 -73.661016) (xy 273.448272 -73.864216) (xy 273.651472 -73.864216)
			)
		)
		(polygon
			(pts
				(xy 272.889472 -73.661016) (xy 272.686272 -73.661016) (xy 272.686272 -73.864216) (xy 272.889472 -73.864216)
			)
		)
		(polygon
			(pts
				(xy 272.381472 -73.6219) (xy 272.178272 -73.6219) (xy 272.178272 -73.8251) (xy 272.381472 -73.8251)
			)
		)
		(polygon
			(pts
				(xy 271.619472 -73.6219) (xy 271.416272 -73.6219) (xy 271.416272 -73.8251) (xy 271.619472 -73.8251)
			)
		)
		(polygon
			(pts
				(xy 271.111472 -73.6219) (xy 270.908272 -73.6219) (xy 270.908272 -73.8251) (xy 271.111472 -73.8251)
			)
		)
		(polygon
			(pts
				(xy 270.349472 -73.6219) (xy 270.146272 -73.6219) (xy 270.146272 -73.8251) (xy 270.349472 -73.8251)
			)
		)
		(polygon
			(pts
				(xy 269.841472 -73.6219) (xy 269.638272 -73.6219) (xy 269.638272 -73.8251) (xy 269.841472 -73.8251)
			)
		)
	)
	(zone
		(layer "F.Cu")
		(hatch none 0.5)
		(connect_pads
			(clearance 0)
		)
		(min_thickness 0.25)
		(keepout
			(tracks allowed)
			(vias allowed)
			(pads allowed)
			(copperpour allowed)
			(footprints allowed)
		)
		(placement
			(enabled no)
			(sheetname "")
		)
		(fill
			(thermal_gap 0.5)
			(thermal_bridge_width 0.5)
			(island_removal_mode 0)
		)
		(polygon
			(pts
				(xy 246.253 -99.9236) (xy 251.3076 -99.9236) (xy 251.3076 -98.0186) (xy 249.7074 -96.4184) (xy 247.3198 -96.4184)
				(xy 246.253 -97.4852)
			)
		)
	)
	(zone
		(net "GND")
		(layer "F.Cu")
		(hatch none 0.5)
		(connect_pads
			(clearance 0.5)
		)
		(min_thickness 0.25)
		(fill yes
			(thermal_gap 0.5)
			(thermal_bridge_width 0.5)
			(island_removal_mode 0)
		)
		(polygon
			(pts
				(xy 144.169892 -130.012186) (xy 148.895816 -130.012186) (xy 149.347682 -129.56032) (xy 149.347682 -125.493272)
				(xy 148.481542 -124.627132) (xy 144.640554 -124.627132) (xy 143.849852 -125.417834) (xy 143.849852 -129.692146)
			)
		)
	)
	(zone
		(layer "F.Cu")
		(hatch none 0.5)
		(connect_pads
			(clearance 0)
		)
		(min_thickness 0.25)
		(keepout
			(tracks allowed)
			(vias allowed)
			(pads allowed)
			(copperpour allowed)
			(footprints not_allowed)
		)
		(placement
			(enabled no)
			(sheetname "")
		)
		(fill
			(thermal_gap 0.5)
			(thermal_bridge_width 0.5)
			(island_removal_mode 0)
		)
		(polygon
			(pts
				(xy 187.525406 -141.767306) (xy 187.525406 -138.566144) (xy 328.525378 -138.566144) (xy 328.525378 -141.767306)
			)
		)
	)
	(zone
		(layer "F.Cu")
		(hatch none 0.5)
		(connect_pads
			(clearance 0)
		)
		(min_thickness 0.25)
		(keepout
			(tracks allowed)
			(vias allowed)
			(pads allowed)
			(copperpour allowed)
			(footprints not_allowed)
		)
		(placement
			(enabled no)
			(sheetname "")
		)
		(fill
			(thermal_gap 0.5)
			(thermal_bridge_width 0.5)
			(island_removal_mode 0)
		)
		(polygon
			(pts
				(arc
					(start 33.919922 -50.099976)
					(mid 30.370018 -46.550072)
					(end 33.919922 -42.999914)
				)
				(arc
					(start 33.919922 -42.999914)
					(mid 37.47008 -46.550072)
					(end 33.919922 -50.099976)
				)
			)
		)
	)
	(zone
		(layer "F.Cu")
		(hatch none 0.5)
		(connect_pads
			(clearance 0)
		)
		(min_thickness 0.25)
		(keepout
			(tracks allowed)
			(vias allowed)
			(pads allowed)
			(copperpour allowed)
			(footprints not_allowed)
		)
		(placement
			(enabled no)
			(sheetname "")
		)
		(fill
			(thermal_gap 0.5)
			(thermal_bridge_width 0.5)
			(island_removal_mode 0)
		)
		(polygon
			(pts
				(xy 328.525378 5.999988) (xy 332.425294 5.999988) (xy 332.425294 -22.919182) (xy 328.525378 -22.919182)
			)
		)
	)
	(zone
		(net "VR_PVDDQ_ABC_PH1_SW")
		(layer "F.Cu")
		(hatch none 0.5)
		(connect_pads
			(clearance 0.5)
		)
		(min_thickness 0.25)
		(fill yes
			(thermal_gap 0.5)
			(thermal_bridge_width 0.5)
			(island_removal_mode 0)
		)
		(polygon
			(pts
				(xy 338.380578 -3.884422) (xy 338.201 -4.064) (xy 338.201 -7.9756) (xy 338.6328 -8.4074) (xy 338.7598 -8.5344)
				(xy 343.8144 -8.5344) (xy 343.8906 -8.4582) (xy 343.8906 -7.7978) (xy 343.8906 -4.087622) (xy 343.8906 -3.556)
				(xy 343.8144 -3.4798) (xy 338.7852 -3.4798)
			)
		)
	)
	(zone
		(net "VR_PVDDQ_KLM_PH2_SW")
		(layer "F.Cu")
		(hatch none 0.5)
		(connect_pads
			(clearance 0.5)
		)
		(min_thickness 0.25)
		(fill yes
			(thermal_gap 0.5)
			(thermal_bridge_width 0.5)
			(island_removal_mode 0)
		)
		(polygon
			(pts
				(xy 10.09396 -149.26564) (xy 10.3632 -148.9964) (xy 10.3632 -145.4404) (xy 9.9568 -145.034) (xy 5.1562 -145.034)
				(xy 5.08 -145.034) (xy 4.9784 -145.1356) (xy 4.9784 -149.352) (xy 5.1054 -149.479) (xy 9.8806 -149.479)
			)
		)
	)
	(zone
		(layer "F.Cu")
		(hatch none 0.5)
		(connect_pads
			(clearance 0)
		)
		(min_thickness 0.25)
		(keepout
			(tracks allowed)
			(vias allowed)
			(pads allowed)
			(copperpour allowed)
			(footprints not_allowed)
		)
		(placement
			(enabled no)
			(sheetname "")
		)
		(fill
			(thermal_gap 0.5)
			(thermal_bridge_width 0.5)
			(island_removal_mode 0)
		)
		(polygon
			(pts
				(xy 453.989948 -125.499876) (xy 453.989948 -131.500118) (xy 465.739988 -131.500118) (xy 465.739988 -125.499876)
			)
		)
	)
	(zone
		(net "GND")
		(layer "F.Cu")
		(hatch none 0.5)
		(connect_pads
			(clearance 0.5)
		)
		(min_thickness 0.25)
		(fill yes
			(thermal_gap 0.5)
			(thermal_bridge_width 0.5)
			(island_removal_mode 0)
		)
		(polygon
			(pts
				(xy 333.123032 -126.921768) (xy 332.396338 -127.648462) (xy 331.506576 -127.648462) (xy 331.4446 -127.710438)
				(xy 331.4446 -128.5748) (xy 331.520292 -128.650492) (xy 334.509872 -128.650492) (xy 334.6323 -128.528064)
				(xy 335.675986 -128.528064) (xy 335.73339 -128.47066) (xy 335.73339 -127.421386) (xy 335.233772 -126.921768)
			)
		)
		(polygon
			(pts
				(xy 335.013046 -127.537464) (xy 334.809846 -127.537464) (xy 334.809846 -127.740664) (xy 335.013046 -127.740664)
			)
		)
	)
	(zone
		(net "GND")
		(layer "F.Cu")
		(hatch none 0.5)
		(connect_pads
			(clearance 0.5)
		)
		(min_thickness 0.25)
		(fill yes
			(thermal_gap 0.5)
			(thermal_bridge_width 0.5)
			(island_removal_mode 0)
		)
		(polygon
			(pts
				(xy 77.6986 -4.853178) (xy 77.597 -4.954778) (xy 77.597 -5.9182) (xy 77.4954 -6.0198) (xy 77.1398 -6.0198)
				(xy 76.962 -5.842) (xy 76.962 -4.801616) (xy 76.83881 -4.678426) (xy 76.83881 -4.049014) (xy 76.050648 -3.260852)
				(xy 76.050648 -2.055876) (xy 76.165964 -1.94056) (xy 77.026516 -1.94056) (xy 78.229968 -1.94056)
				(xy 78.417674 -2.128266) (xy 78.417674 -4.671568) (xy 78.306168 -4.783328) (xy 77.76845 -4.783328)
			)
		)
	)
	(zone
		(layer "F.Cu")
		(hatch none 0.5)
		(connect_pads
			(clearance 0)
		)
		(min_thickness 0.25)
		(keepout
			(tracks allowed)
			(vias allowed)
			(pads allowed)
			(copperpour allowed)
			(footprints not_allowed)
		)
		(placement
			(enabled no)
			(sheetname "")
		)
		(fill
			(thermal_gap 0.5)
			(thermal_bridge_width 0.5)
			(island_removal_mode 0)
		)
		(polygon
			(pts
				(arc
					(start 33.919922 -103.000048)
					(mid 37.47008 -106.550206)
					(end 33.919922 -110.10011)
				)
				(arc
					(start 33.919922 -110.10011)
					(mid 30.370018 -106.550206)
					(end 33.919922 -103.000048)
				)
			)
		)
	)
	(zone
		(layer "F.Cu")
		(hatch none 0.5)
		(connect_pads
			(clearance 0)
		)
		(min_thickness 0.25)
		(keepout
			(tracks allowed)
			(vias allowed)
			(pads allowed)
			(copperpour allowed)
			(footprints not_allowed)
		)
		(placement
			(enabled no)
			(sheetname "")
		)
		(fill
			(thermal_gap 0.5)
			(thermal_bridge_width 0.5)
			(island_removal_mode 0)
		)
		(polygon
			(pts
				(xy 328.525378 -1.716786) (xy 187.525406 -1.716786) (xy 187.525406 -4.917948) (xy 328.525378 -4.917948)
			)
		)
	)
	(zone
		(layer "F.Cu")
		(hatch none 0.5)
		(connect_pads
			(clearance 0)
		)
		(min_thickness 0.25)
		(keepout
			(tracks allowed)
			(vias allowed)
			(pads allowed)
			(copperpour allowed)
			(footprints not_allowed)
		)
		(placement
			(enabled no)
			(sheetname "")
		)
		(fill
			(thermal_gap 0.5)
			(thermal_bridge_width 0.5)
			(island_removal_mode 0)
		)
		(polygon
			(pts
				(arc
					(start 357.000048 -156.59989)
					(mid 355.500178 -155.10002)
					(end 357.000048 -153.599896)
				)
				(arc
					(start 357.671624 -153.599896)
					(mid 358.338251 -153.485602)
					(end 358.92867 -153.15565)
				)
				(arc
					(start 358.92867 -153.15565)
					(mid 362.99979 -155.10002)
					(end 358.92867 -157.04439)
				)
				(arc
					(start 358.92867 -157.04439)
					(mid 358.338274 -156.714333)
					(end 357.671624 -156.59989)
				)
			)
		)
	)
	(zone
		(net "PVCCIO_CPU0")
		(layer "F.Cu")
		(hatch none 0.5)
		(connect_pads
			(clearance 0.5)
		)
		(min_thickness 0.25)
		(fill yes
			(thermal_gap 0.5)
			(thermal_bridge_width 0.5)
			(island_removal_mode 0)
		)
		(polygon
			(pts
				(xy 278.570436 -69.587364) (xy 278.4348 -69.723) (xy 273.304 -69.723) (xy 273.304 -70.231) (xy 274.2184 -70.231)
				(xy 274.2692 -70.2818) (xy 277.043642 -70.2818) (xy 278.2824 -71.520558) (xy 278.2824 -72.044814)
				(xy 278.4094 -72.171814) (xy 280.531824 -72.171814) (xy 280.924 -72.56399) (xy 280.924 -75.1078)
				(xy 281.051 -75.2348) (xy 281.4066 -75.2348) (xy 281.4828 -75.1586) (xy 281.4828 -72.0344) (xy 281.417014 -71.968614)
				(xy 280.912824 -71.968614) (xy 280.735024 -71.790814) (xy 280.735024 -71.210424) (xy 280.214832 -70.690232)
				(xy 280.214832 -69.670168) (xy 280.131774 -69.587364)
			)
		)
		(polygon
			(pts
				(xy 279.858724 -71.168514) (xy 279.655524 -71.168514) (xy 279.655524 -71.371714) (xy 279.858724 -71.371714)
			)
		)
		(polygon
			(pts
				(xy 279.350724 -71.168514) (xy 279.147524 -71.168514) (xy 279.147524 -71.371714) (xy 279.350724 -71.371714)
			)
		)
		(polygon
			(pts
				(xy 278.588724 -71.168514) (xy 278.385524 -71.168514) (xy 278.385524 -71.371714) (xy 278.588724 -71.371714)
			)
		)
	)
	(zone
		(layer "F.Cu")
		(hatch none 0.5)
		(connect_pads
			(clearance 0)
		)
		(min_thickness 0.25)
		(keepout
			(tracks allowed)
			(vias allowed)
			(pads allowed)
			(copperpour allowed)
			(footprints allowed)
		)
		(placement
			(enabled no)
			(sheetname "")
		)
		(fill
			(thermal_gap 0.5)
			(thermal_bridge_width 0.5)
			(island_removal_mode 0)
		)
		(polygon
			(pts
				(xy 347.1418 -100.2284) (xy 347.1418 -95.8596) (xy 349.5548 -95.8596) (xy 349.5548 -100.2284)
			)
		)
	)
	(zone
		(layer "F.Cu")
		(hatch none 0.5)
		(connect_pads
			(clearance 0)
		)
		(min_thickness 0.25)
		(keepout
			(tracks allowed)
			(vias allowed)
			(pads allowed)
			(copperpour allowed)
			(footprints allowed)
		)
		(placement
			(enabled no)
			(sheetname "")
		)
		(fill
			(thermal_gap 0.5)
			(thermal_bridge_width 0.5)
			(island_removal_mode 0)
		)
		(polygon
			(pts
				(xy 81.252568 -101.981) (xy 81.252568 -99.9236) (xy 81.252568 -98.552) (xy 75.664568 -98.552) (xy 75.664568 -98.7044)
				(xy 75.664568 -101.981) (xy 75.664568 -102.489) (xy 78.331568 -102.489) (xy 78.839568 -102.997)
				(xy 79.474568 -102.997) (xy 80.109568 -103.632) (xy 80.236568 -103.632) (xy 81.125568 -102.743)
				(xy 81.252568 -102.743) (xy 81.252568 -102.235)
			)
		)
	)
	(zone
		(layer "F.Cu")
		(hatch none 0.5)
		(connect_pads
			(clearance 0)
		)
		(min_thickness 0.25)
		(keepout
			(tracks not_allowed)
			(vias allowed)
			(pads allowed)
			(copperpour not_allowed)
			(footprints allowed)
		)
		(placement
			(enabled no)
			(sheetname "")
		)
		(fill
			(thermal_gap 0.5)
			(thermal_bridge_width 0.5)
			(island_removal_mode 0)
		)
		(polygon
			(pts
				(arc
					(start -3.50012 -54.909974)
					(mid -2.00025 -53.410104)
					(end -0.500126 -54.909974)
				)
				(arc
					(start -0.500126 -54.909974)
					(mid -2.00025 -56.410098)
					(end -3.50012 -54.909974)
				)
			)
		)
	)
	(zone
		(layer "F.Cu")
		(hatch none 0.5)
		(connect_pads
			(clearance 0)
		)
		(min_thickness 0.25)
		(keepout
			(tracks allowed)
			(vias allowed)
			(pads allowed)
			(copperpour allowed)
			(footprints allowed)
		)
		(placement
			(enabled no)
			(sheetname "")
		)
		(fill
			(thermal_gap 0.5)
			(thermal_bridge_width 0.5)
			(island_removal_mode 0)
		)
		(polygon
			(pts
				(xy 467.493096 -23.63216) (xy 469.037416 -23.63216) (xy 469.66505 -24.259794) (xy 469.66505 -24.26208)
				(xy 470.56548 -24.26208) (xy 471.13444 -24.83104) (xy 471.13444 -26.12898) (xy 470.994994 -26.268426)
				(xy 469.538812 -26.268426) (xy 466.152484 -26.268426) (xy 466.05063 -26.166572) (xy 466.05063 -25.555702)
				(xy 467.171278 -24.435054) (xy 467.171278 -23.953978)
			)
		)
	)
	(zone
		(net "GND")
		(layer "F.Cu")
		(hatch none 0.5)
		(connect_pads
			(clearance 0.5)
		)
		(min_thickness 0.25)
		(fill yes
			(thermal_gap 0.5)
			(thermal_bridge_width 0.5)
			(island_removal_mode 0)
		)
		(polygon
			(pts
				(xy 391.70991 -114.681) (xy 391.642854 -114.748056) (xy 391.603992 -114.748056) (xy 391.567416 -114.784632)
				(xy 391.105644 -114.784632) (xy 391.057638 -114.736626) (xy 390.851136 -114.736626) (xy 390.833102 -114.75466)
				(xy 390.80186 -114.785902) (xy 390.309354 -114.785902) (xy 390.260586 -114.737134) (xy 390.049004 -114.737134)
				(xy 390.04875 -114.737388) (xy 390.011666 -114.737388) (xy 389.957056 -114.791998) (xy 389.51662 -114.791998)
				(xy 389.461502 -114.73688) (xy 389.250428 -114.73688) (xy 389.232648 -114.75466) (xy 389.202168 -114.78514)
				(xy 388.707376 -114.78514) (xy 388.659624 -114.737388) (xy 388.448042 -114.737388) (xy 388.43077 -114.75466)
				(xy 388.2009 -114.75466) (xy 388.187692 -114.767868) (xy 387.842506 -115.1128) (xy 387.50113 -115.1128)
				(xy 387.42493 -115.189) (xy 387.400038 -115.213892) (xy 387.293612 -115.213892) (xy 387.266688 -115.186968)
				(xy 387.266688 -115.105688) (xy 387.266688 -114.930174) (xy 387.227572 -114.891058) (xy 387.227572 -114.314732)
				(xy 387.227572 -114.182398) (xy 387.227318 -114.182144) (xy 387.236462 -114.173) (xy 391.771886 -114.173)
				(xy 391.784586 -114.1857) (xy 391.784586 -114.606324)
			)
		)
	)
	(zone
		(net "PVNN_PCH_STBY")
		(layer "F.Cu")
		(hatch none 0.5)
		(connect_pads
			(clearance 0.5)
		)
		(min_thickness 0.25)
		(fill yes
			(thermal_gap 0.5)
			(thermal_bridge_width 0.5)
			(island_removal_mode 0)
		)
		(polygon
			(pts
				(xy 369.316 -102.877366) (xy 369.316 -102.0572) (xy 369.316 -101.963728) (xy 369.170204 -101.817932)
				(xy 367.83137 -101.817932) (xy 367.7158 -101.933502) (xy 367.7158 -102.0826) (xy 367.7158 -102.861872)
				(xy 367.83391 -102.979982) (xy 369.213384 -102.979982)
			)
		)
	)
	(zone
		(net "GND")
		(layer "F.Cu")
		(hatch none 0.5)
		(connect_pads
			(clearance 0.5)
		)
		(min_thickness 0.25)
		(fill yes
			(thermal_gap 0.5)
			(thermal_bridge_width 0.5)
			(island_removal_mode 0)
		)
		(polygon
			(pts
				(xy 21.8948 -111.887) (xy 20.1168 -111.887) (xy 19.304 -111.887) (xy 18.7198 -111.3028) (xy 18.150078 -110.733078)
				(xy 18.150078 -106.852974) (xy 18.434558 -106.568494) (xy 18.913094 -106.568494) (xy 18.9484 -106.6038)
				(xy 21.916898 -106.6038) (xy 21.916898 -109.939836) (xy 22.403308 -110.426246) (xy 22.403308 -111.601758)
				(xy 22.118066 -111.887)
			)
		)
	)
	(zone
		(net "GND")
		(layer "F.Cu")
		(hatch none 0.5)
		(connect_pads
			(clearance 0.5)
		)
		(min_thickness 0.25)
		(fill yes
			(thermal_gap 0.5)
			(thermal_bridge_width 0.5)
			(island_removal_mode 0)
		)
		(polygon
			(pts
				(xy 405.080216 -152.144984) (xy 404.953216 -152.271984) (xy 404.953216 -153.110184) (xy 404.724616 -153.338784)
				(xy 402.898102 -153.338784) (xy 402.757132 -153.479754) (xy 401.98802 -153.479754) (xy 401.943316 -153.524458)
				(xy 401.943316 -154.547316) (xy 402.082 -154.686) (xy 402.971 -154.686) (xy 402.971 -154.684984)
				(xy 405.486616 -154.684984) (xy 406.197816 -153.973784) (xy 406.197816 -152.525984) (xy 405.816816 -152.144984)
			)
		)
		(polygon
			(pts
				(xy 405.931116 -152.983184) (xy 405.727916 -152.983184) (xy 405.727916 -153.186384) (xy 405.931116 -153.186384)
			)
		)
		(polygon
			(pts
				(xy 402.8186 -154.2669) (xy 402.6154 -154.2669) (xy 402.6154 -154.4701) (xy 402.8186 -154.4701)
			)
		)
	)
	(zone
		(net "GND")
		(layer "F.Cu")
		(hatch none 0.5)
		(connect_pads
			(clearance 0.5)
		)
		(min_thickness 0.25)
		(fill yes
			(thermal_gap 0.5)
			(thermal_bridge_width 0.5)
			(island_removal_mode 0)
		)
		(polygon
			(pts
				(xy 453.4662 -21.1582) (xy 453.389492 -21.234908) (xy 453.389492 -23.927308) (xy 452.882 -24.4348)
				(xy 452.882 -26.3398) (xy 452.8185 -26.4033) (xy 452.8185 -27.1653) (xy 452.9328 -27.2796) (xy 454.0885 -27.2796)
				(xy 454.2917 -27.0764) (xy 454.2917 -26.8351) (xy 454.3552 -26.7716) (xy 455.0918 -26.7716) (xy 455.6125 -26.2509)
				(xy 455.6125 -25.287732) (xy 455.534268 -25.2095) (xy 455.534268 -24.13) (xy 455.356468 -23.9522)
				(xy 455.168 -23.9522) (xy 455.113644 -23.897844) (xy 455.113644 -21.336) (xy 454.935844 -21.1582)
			)
		)
		(polygon
			(pts
				(xy 454.7616 -25.1206) (xy 454.5584 -25.1206) (xy 454.5584 -25.3238) (xy 454.7616 -25.3238)
			)
		)
		(polygon
			(pts
				(xy 454.7616 -24.3586) (xy 454.5584 -24.3586) (xy 454.5584 -24.5618) (xy 454.7616 -24.5618)
			)
		)
	)
	(zone
		(net "PVTT_KLM")
		(layer "F.Cu")
		(hatch none 0.5)
		(connect_pads
			(clearance 0.5)
		)
		(min_thickness 0.25)
		(fill yes
			(thermal_gap 0.5)
			(thermal_bridge_width 0.5)
			(island_removal_mode 0)
		)
		(polygon
			(pts
				(xy 168.542462 -146.671538) (xy 167.40124 -145.530316) (xy 165.284912 -145.530316) (xy 164.781484 -145.530316)
				(xy 164.6428 -145.669) (xy 164.6428 -146.812) (xy 164.846 -147.0152) (xy 165.7858 -147.0152) (xy 166.0144 -146.7866)
				(xy 167.4114 -146.7866) (xy 167.64 -147.0152) (xy 167.689022 -147.064222) (xy 169.443146 -147.064222)
				(xy 169.443146 -146.7866) (xy 168.656 -146.7866) (xy 168.542462 -146.673062)
			)
		)
	)
	(zone
		(net "GND")
		(layer "F.Cu")
		(hatch none 0.5)
		(connect_pads
			(clearance 0.5)
		)
		(min_thickness 0.25)
		(fill yes
			(thermal_gap 0.5)
			(thermal_bridge_width 0.5)
			(island_removal_mode 0)
		)
		(polygon
			(pts
				(xy 143.442182 -121.433082) (xy 143.442182 -112.61852) (xy 145.489422 -110.57128) (xy 148.01088 -110.57128)
				(xy 149.979888 -112.540288) (xy 149.979888 -113.905792) (xy 148.355558 -115.530122) (xy 148.355558 -121.030746)
				(xy 147.64004 -121.746264) (xy 143.755364 -121.746264)
			)
		)
	)
	(zone
		(layer "F.Cu")
		(hatch none 0.5)
		(connect_pads
			(clearance 0)
		)
		(min_thickness 0.25)
		(keepout
			(tracks allowed)
			(vias allowed)
			(pads allowed)
			(copperpour allowed)
			(footprints allowed)
		)
		(placement
			(enabled no)
			(sheetname "")
		)
		(fill
			(thermal_gap 0.5)
			(thermal_bridge_width 0.5)
			(island_removal_mode 0)
		)
		(polygon
			(pts
				(xy 361.5436 -139.4206) (xy 361.5436 -137.3378) (xy 362.6358 -137.3378) (xy 362.6358 -139.4206)
			)
		)
	)
	(zone
		(net "P3V3_STBY")
		(layer "F.Cu")
		(hatch none 0.5)
		(connect_pads
			(clearance 0.5)
		)
		(min_thickness 0.25)
		(fill yes
			(thermal_gap 0.5)
			(thermal_bridge_width 0.5)
			(island_removal_mode 0)
		)
		(polygon
			(pts
				(xy 482.727 -117.9068) (xy 482.727 -114.9096) (xy 483.5398 -114.0968) (xy 483.5398 -111.0488) (xy 483.5906 -110.998)
				(xy 484.0097 -110.998) (xy 484.0478 -111.0361) (xy 484.0478 -114.4016) (xy 483.2604 -115.189) (xy 483.2604 -118.5418)
				(xy 483.4255 -118.7069) (xy 484.0351 -118.7069) (xy 484.3272 -118.999) (xy 484.3272 -120.4214) (xy 483.997 -120.7516)
				(xy 480.9236 -120.7516) (xy 480.6188 -120.4468) (xy 480.6188 -119.8626) (xy 480.6188 -118.999) (xy 480.949 -118.6688)
				(xy 482.5238 -118.6688) (xy 482.727 -118.4656)
			)
		)
	)
	(zone
		(net "P1V2_AUX_BMC")
		(layer "F.Cu")
		(hatch none 0.5)
		(connect_pads
			(clearance 0.5)
		)
		(min_thickness 0.25)
		(fill yes
			(thermal_gap 0.5)
			(thermal_bridge_width 0.5)
			(island_removal_mode 0)
		)
		(polygon
			(pts
				(xy 450.1515 -28.5115) (xy 449.834 -28.829) (xy 449.834 -30.226) (xy 450.469 -30.861) (xy 451.866 -30.861)
				(xy 451.866 -30.988) (xy 451.937628 -31.059628) (xy 451.917562 -31.079948) (xy 451.917562 -36.096448)
				(xy 451.993762 -36.172648) (xy 452.904352 -36.172648) (xy 453.009 -36.068) (xy 453.009 -33.528)
				(xy 453.771 -32.766) (xy 453.771 -31.623) (xy 453.263 -31.115) (xy 452.755 -31.115) (xy 452.628 -30.988)
				(xy 452.628 -28.5496) (xy 452.5899 -28.5115)
			)
		)
	)
	(zone
		(layer "F.Cu")
		(hatch none 0.5)
		(connect_pads
			(clearance 0)
		)
		(min_thickness 0.25)
		(keepout
			(tracks allowed)
			(vias allowed)
			(pads allowed)
			(copperpour allowed)
			(footprints allowed)
		)
		(placement
			(enabled no)
			(sheetname "")
		)
		(fill
			(thermal_gap 0.5)
			(thermal_bridge_width 0.5)
			(island_removal_mode 0)
		)
		(polygon
			(pts
				(xy 195.072 -93.726) (xy 198.628 -93.726) (xy 198.882 -93.98) (xy 198.882 -95.504) (xy 198.501 -95.885)
				(xy 196.723 -95.885) (xy 196.596 -96.012) (xy 196.596 -98.552) (xy 196.469 -98.679) (xy 194.818 -98.679)
				(xy 194.564 -98.425) (xy 194.056 -97.917) (xy 194.056 -94.234) (xy 194.564 -93.726)
			)
		)
	)
	(zone
		(layer "F.Cu")
		(hatch none 0.5)
		(connect_pads
			(clearance 0)
		)
		(min_thickness 0.25)
		(keepout
			(tracks not_allowed)
			(vias allowed)
			(pads allowed)
			(copperpour not_allowed)
			(footprints allowed)
		)
		(placement
			(enabled no)
			(sheetname "")
		)
		(fill
			(thermal_gap 0.5)
			(thermal_bridge_width 0.5)
			(island_removal_mode 0)
		)
		(polygon
			(pts
				(xy 16.678656 -23.01875) (xy 16.83385 -23.173944) (xy 16.83385 -23.47214) (xy 16.93545 -23.47214)
				(xy 16.93545 -23.173944) (xy 17.090644 -23.01875)
				(arc
					(start 17.198848 -23.01875)
					(mid 17.722765 -23.0886)
					(end 17.198848 -23.15845)
				)
				(xy 17.148556 -23.15845) (xy 17.07515 -23.231856) (xy 17.07515 -23.47214)
				(arc
					(start 17.45615 -23.47214)
					(mid 17.83969 -23.0886)
					(end 17.45615 -22.70506)
				)
				(arc
					(start 16.186404 -22.70506)
					(mid 15.80261 -23.088473)
					(end 16.18615 -23.47214)
				)
				(xy 16.66748 -23.47214) (xy 16.69415 -23.44547) (xy 16.69415 -23.231856) (xy 16.620744 -23.15845)
				(arc
					(start 16.443452 -23.15845)
					(mid 15.919535 -23.0886)
					(end 16.443452 -23.01875)
				)
			)
		)
	)
	(zone
		(net "VR_FET_SW_P12V_STBY_PVPP_GHJ")
		(layer "F.Cu")
		(hatch none 0.5)
		(connect_pads
			(clearance 0.5)
		)
		(min_thickness 0.25)
		(fill yes
			(thermal_gap 0.5)
			(thermal_bridge_width 0.5)
			(island_removal_mode 0)
		)
		(polygon
			(pts
				(xy 180.1876 -12.7) (xy 181.483 -12.7) (xy 181.671468 -12.888468) (xy 182.252112 -12.888468) (xy 182.59806 -13.234416)
				(xy 182.59806 -13.297662) (xy 182.59806 -13.518388) (xy 182.600092 -13.52042) (xy 182.600092 -13.815568)
				(xy 182.639208 -13.854684) (xy 185.785506 -13.854684) (xy 185.8518 -13.78839) (xy 185.8518 -13.462)
				(xy 185.8518 -12.152376) (xy 185.547 -11.847576) (xy 185.538364 -11.83894) (xy 184.00522 -11.83894)
				(xy 183.965596 -11.83894) (xy 183.675528 -11.548872) (xy 183.674512 -11.547856) (xy 183.674512 -10.273792)
				(xy 183.683656 -10.264648) (xy 183.685434 -10.264648) (xy 184.063894 -10.264648) (xy 184.18048 -10.148062)
				(xy 184.18048 -9.668256) (xy 184.18048 -8.53948) (xy 184.18048 -8.381746) (xy 183.996584 -8.19785)
				(xy 182.210964 -8.19785) (xy 181.390798 -9.018016) (xy 181.229 -9.018016) (xy 180.010054 -9.018016)
				(xy 179.659788 -9.368282) (xy 179.531518 -9.368282) (xy 178.816 -10.0838) (xy 178.816 -11.049) (xy 178.689 -11.176)
				(xy 177.9524 -11.176) (xy 177.8762 -11.2522) (xy 177.8762 -12.573) (xy 177.927 -12.6238) (xy 180.1114 -12.6238)
			)
		)
	)
	(zone
		(layer "F.Cu")
		(hatch none 0.5)
		(connect_pads
			(clearance 0)
		)
		(min_thickness 0.25)
		(keepout
			(tracks allowed)
			(vias allowed)
			(pads allowed)
			(copperpour allowed)
			(footprints not_allowed)
		)
		(placement
			(enabled no)
			(sheetname "")
		)
		(fill
			(thermal_gap 0.5)
			(thermal_bridge_width 0.5)
			(island_removal_mode 0)
		)
		(polygon
			(pts
				(xy 183.925464 -130.16611) (xy 183.925464 -159.100012)
				(arc
					(start 175.50003 -159.100012)
					(mid 179.374599 -156.093828)
					(end 177.42535 -151.593804)
				)
				(xy 177.42535 -130.16611)
			)
		)
	)
	(zone
		(net "PVCCIOMCP_CPU1")
		(layer "F.Cu")
		(hatch none 0.5)
		(connect_pads
			(clearance 0.5)
		)
		(min_thickness 0.25)
		(fill yes
			(thermal_gap 0.5)
			(thermal_bridge_width 0.5)
			(island_removal_mode 0)
		)
		(polygon
			(pts
				(xy 184.449212 -112.948212) (xy 185.259472 -113.758472) (xy 189.376304 -113.758472) (xy 190.405512 -114.78768)
				(xy 193.223896 -114.78768) (xy 195.57746 -112.434116) (xy 195.57746 -108.09986) (xy 195.3006 -107.823)
				(xy 193.421 -105.9434) (xy 193.421 -104.0384) (xy 193.1162 -103.7336) (xy 190.5 -103.7336) (xy 190.49746 -103.73614)
				(xy 189.991492 -103.73614) (xy 189.78626 -103.73614) (xy 188.6204 -104.902) (xy 186.030616 -104.902)
				(xy 183.795416 -107.1372) (xy 182.1688 -108.763816) (xy 182.05704 -108.875576) (xy 182.05704 -110.699042)
				(xy 182.21325 -110.855252) (xy 184.294526 -110.855252) (xy 184.449212 -111.009938)
			)
		)
	)
	(zone
		(net "P3V3")
		(layer "F.Cu")
		(hatch none 0.5)
		(connect_pads
			(clearance 0.5)
		)
		(min_thickness 0.25)
		(fill yes
			(thermal_gap 0.5)
			(thermal_bridge_width 0.5)
			(island_removal_mode 0)
		)
		(polygon
			(pts
				(xy 391.292588 -25.68702) (xy 389.616188 -25.68702) (xy 389.565388 -25.63622) (xy 389.565388 -23.98522)
				(xy 389.666988 -23.88362) (xy 391.17778 -23.88362) (xy 391.3886 -23.6728) (xy 391.3886 -22.4282)
				(xy 391.2362 -22.2758) (xy 389.6614 -22.2758) (xy 389.5598 -22.1742) (xy 389.5598 -21.4122) (xy 389.636 -21.336)
				(xy 391.996168 -21.336) (xy 392.410188 -21.75002) (xy 392.410188 -24.16302) (xy 392.410188 -25.318212)
				(xy 392.04138 -25.68702)
			)
		)
	)
	(zone
		(layer "F.Cu")
		(hatch none 0.5)
		(connect_pads
			(clearance 0)
		)
		(min_thickness 0.25)
		(keepout
			(tracks allowed)
			(vias allowed)
			(pads allowed)
			(copperpour allowed)
			(footprints allowed)
		)
		(placement
			(enabled no)
			(sheetname "")
		)
		(fill
			(thermal_gap 0.5)
			(thermal_bridge_width 0.5)
			(island_removal_mode 0)
		)
		(polygon
			(pts
				(xy 245.4402 -49.911) (xy 246.507 -49.911) (xy 246.507 -48.895) (xy 245.7958 -48.1838) (xy 245.4402 -48.1838)
			)
		)
	)
	(zone
		(layer "F.Cu")
		(hatch none 0.5)
		(connect_pads
			(clearance 0)
		)
		(min_thickness 0.25)
		(keepout
			(tracks allowed)
			(vias allowed)
			(pads allowed)
			(copperpour allowed)
			(footprints allowed)
		)
		(placement
			(enabled no)
			(sheetname "")
		)
		(fill
			(thermal_gap 0.5)
			(thermal_bridge_width 0.5)
			(island_removal_mode 0)
		)
		(polygon
			(pts
				(xy 239.268 -44.323) (xy 241.681 -41.91) (xy 242.951 -40.64) (xy 244.094 -40.64) (xy 245.11 -41.656)
				(xy 241.046 -45.72) (xy 239.268 -45.72) (xy 238.76 -45.212) (xy 238.76 -44.831)
			)
		)
	)
	(zone
		(net "PVPP_DEF")
		(layer "F.Cu")
		(hatch none 0.5)
		(connect_pads
			(clearance 0.5)
		)
		(min_thickness 0.25)
		(fill yes
			(thermal_gap 0.5)
			(thermal_bridge_width 0.5)
			(island_removal_mode 0)
		)
		(polygon
			(pts
				(xy 316.658498 -125.68936) (xy 316.5856 -125.762258) (xy 316.5856 -128.2192) (xy 317.627 -129.2606)
				(xy 317.627 -129.622296) (xy 317.84036 -129.835656) (xy 318.067944 -129.835656) (xy 318.201294 -129.969006)
				(xy 318.201294 -130.787394) (xy 318.472312 -131.058412) (xy 318.891412 -131.058412) (xy 319.3542 -131.5212)
				(xy 319.3542 -134.5184) (xy 319.0494 -134.8232) (xy 318.2874 -134.8232) (xy 317.6524 -135.4582)
				(xy 317.6524 -139.3952) (xy 317.9064 -139.6492) (xy 318.1604 -139.6492) (xy 318.3636 -139.8524)
				(xy 318.3636 -140.6398) (xy 318.2874 -140.716) (xy 316.865 -140.716) (xy 316.67704 -140.90396) (xy 316.67704 -141.43736)
				(xy 316.794134 -141.5542) (xy 317.4492 -141.5542) (xy 317.627 -141.732) (xy 317.627 -148.9456) (xy 318.104012 -149.422612)
				(xy 318.104012 -150.208234) (xy 318.161416 -150.265638) (xy 318.873378 -150.265638) (xy 319.3542 -150.74646)
				(xy 319.3542 -153.67) (xy 318.9732 -154.051) (xy 317.9318 -154.051) (xy 317.6524 -154.3304) (xy 317.6524 -157.8864)
				(xy 317.8556 -158.0896) (xy 325.215758 -158.0896) (xy 325.526146 -157.779212) (xy 325.526146 -138.938254)
				(xy 326.009 -138.4554) (xy 333.4766 -138.4554) (xy 334.264 -137.668) (xy 334.264 -132.334) (xy 335.759806 -130.838194)
				(xy 335.759806 -129.946908) (xy 335.854802 -129.851912) (xy 336.472022 -129.851912) (xy 336.54746 -129.776728)
				(xy 336.54746 -128.86436) (xy 336.526124 -128.843024) (xy 335.976976 -128.843024) (xy 335.78292 -129.03708)
				(xy 334.862424 -129.03708) (xy 334.485742 -129.413508) (xy 328.869802 -129.413508) (xy 328.612754 -129.670556)
				(xy 328.612754 -131.575556) (xy 327.78446 -132.40385) (xy 326.11314 -132.40385) (xy 325.37527 -133.14172)
				(xy 323.64934 -133.14172) (xy 322.624958 -132.117338) (xy 322.624958 -131.551934) (xy 322.204588 -131.131564)
				(xy 322.197476 -131.131564) (xy 321.949064 -130.883152) (xy 320.622676 -130.883152) (xy 320.477134 -130.73761)
				(xy 320.477134 -129.958084) (xy 320.604134 -129.831084) (xy 321.80022 -129.831084) (xy 321.88404 -129.747264)
				(xy 321.88404 -127.630682) (xy 319.942718 -125.68936)
			)
		)
		(polygon
			(pts
				(xy 319.851532 -150.1394) (xy 319.648332 -150.1394) (xy 319.648332 -150.3426) (xy 319.851532 -150.3426)
			)
		)
		(polygon
			(pts
				(xy 319.851532 -149.3774) (xy 319.648332 -149.3774) (xy 319.648332 -149.5806) (xy 319.851532 -149.5806)
			)
		)
		(polygon
			(pts
				(xy 319.089532 -149.3774) (xy 318.886332 -149.3774) (xy 318.886332 -149.5806) (xy 319.089532 -149.5806)
			)
		)
		(polygon
			(pts
				(xy 319.953132 -140.4874) (xy 319.749932 -140.4874) (xy 319.749932 -140.6906) (xy 319.953132 -140.6906)
			)
		)
		(polygon
			(pts
				(xy 319.953132 -139.7254) (xy 319.749932 -139.7254) (xy 319.749932 -139.9286) (xy 319.953132 -139.9286)
			)
		)
		(polygon
			(pts
				(xy 319.089532 -139.7254) (xy 318.886332 -139.7254) (xy 318.886332 -139.9286) (xy 319.089532 -139.9286)
			)
		)
		(polygon
			(pts
				(xy 319.6971 -130.6322) (xy 319.4939 -130.6322) (xy 319.4939 -130.8354) (xy 319.6971 -130.8354)
			)
		)
		(polygon
			(pts
				(xy 319.1891 -130.6322) (xy 318.9859 -130.6322) (xy 318.9859 -130.8354) (xy 319.1891 -130.8354)
			)
		)
		(polygon
			(pts
				(xy 319.6971 -129.8702) (xy 319.4939 -129.8702) (xy 319.4939 -130.0734) (xy 319.6971 -130.0734)
			)
		)
		(polygon
			(pts
				(xy 335.013046 -129.823464) (xy 334.809846 -129.823464) (xy 334.809846 -130.026664) (xy 335.013046 -130.026664)
			)
		)
		(polygon
			(pts
				(xy 336.1182 -129.2479) (xy 335.915 -129.2479) (xy 335.915 -129.4511) (xy 336.1182 -129.4511)
			)
		)
	)
	(zone
		(layer "F.Cu")
		(hatch none 0.5)
		(connect_pads
			(clearance 0)
		)
		(min_thickness 0.25)
		(keepout
			(tracks allowed)
			(vias allowed)
			(pads allowed)
			(copperpour allowed)
			(footprints allowed)
		)
		(placement
			(enabled no)
			(sheetname "")
		)
		(fill
			(thermal_gap 0.5)
			(thermal_bridge_width 0.5)
			(island_removal_mode 0)
		)
		(polygon
			(pts
				(xy 118.717568 -103.505) (xy 119.098568 -103.505) (xy 119.352568 -103.251) (xy 119.352568 -102.743)
				(xy 119.098568 -102.489) (xy 118.971568 -102.489) (xy 118.717568 -102.743)
			)
		)
	)
	(zone
		(net "GND")
		(layer "F.Cu")
		(hatch none 0.5)
		(connect_pads
			(clearance 0.5)
		)
		(min_thickness 0.25)
		(fill yes
			(thermal_gap 0.5)
			(thermal_bridge_width 0.5)
			(island_removal_mode 0)
		)
		(polygon
			(pts
				(xy 261.330948 -128.902714) (xy 262.287258 -128.902714) (xy 262.47598 -129.091436) (xy 262.922766 -129.091436)
				(xy 263.334754 -128.679448) (xy 263.334754 -127.694944) (xy 263.139174 -127.499364) (xy 261.610094 -127.499364)
				(xy 261.309866 -127.799592) (xy 261.309866 -128.881632)
			)
		)
	)
	(zone
		(layer "F.Cu")
		(hatch none 0.5)
		(connect_pads
			(clearance 0)
		)
		(min_thickness 0.25)
		(keepout
			(tracks allowed)
			(vias allowed)
			(pads allowed)
			(copperpour allowed)
			(footprints not_allowed)
		)
		(placement
			(enabled no)
			(sheetname "")
		)
		(fill
			(thermal_gap 0.5)
			(thermal_bridge_width 0.5)
			(island_removal_mode 0)
		)
		(polygon
			(pts
				(arc
					(start 127 -39.649908)
					(mid 128.900174 -41.550082)
					(end 127 -43.450002)
				)
				(arc
					(start 127 -43.450002)
					(mid 125.10008 -41.550082)
					(end 127 -39.649908)
				)
			)
		)
	)
	(zone
		(net "P1V15_AUX_BMC")
		(layer "F.Cu")
		(hatch none 0.5)
		(connect_pads
			(clearance 0.5)
		)
		(min_thickness 0.25)
		(fill yes
			(thermal_gap 0.5)
			(thermal_bridge_width 0.5)
			(island_removal_mode 0)
		)
		(polygon
			(pts
				(xy 418.45865 -37.86505) (xy 418.334698 -37.740844) (xy 418.205412 -37.611558) (xy 418.205412 -36.552378)
				(xy 418.205412 -33.118298) (xy 418.06749 -32.980376) (xy 417.77666 -32.980376) (xy 417.55695 -32.760666)
				(xy 417.55695 -32.455866) (xy 417.773866 -32.23895) (xy 417.965128 -32.23895) (xy 418.205412 -31.998666)
				(xy 418.205412 -31.998412) (xy 418.510212 -31.693612) (xy 418.510212 -31.211012) (xy 418.434012 -31.134812)
				(xy 416.579812 -31.134812) (xy 416.046412 -31.668212) (xy 415.741612 -31.668212) (xy 415.182812 -31.109412)
				(xy 415.036 -31.109412) (xy 414.909 -31.236412) (xy 414.909 -32.004) (xy 414.812988 -32.100012)
				(xy 413.862012 -32.100012) (xy 413.049212 -32.100012) (xy 412.465012 -31.515812) (xy 412.465012 -31.261812)
				(xy 412.465012 -30.930342) (xy 412.380938 -30.846268) (xy 411.737302 -30.846268) (xy 411.677612 -30.906212)
				(xy 411.677612 -32.175958) (xy 411.875224 -32.37357) (xy 411.875224 -32.6898) (xy 411.677612 -32.887412)
				(xy 411.677612 -32.905954) (xy 411.677612 -33.778444) (xy 411.871414 -33.972246) (xy 411.871414 -34.300922)
				(xy 411.677612 -34.494724) (xy 411.677612 -35.399726) (xy 411.858714 -35.580828) (xy 411.858714 -35.900106)
				(xy 411.677612 -36.081208) (xy 411.677612 -37.840412) (xy 412.592012 -38.754812) (xy 413.52851 -38.754812)
				(xy 413.674052 -38.60927) (xy 413.674052 -38.46068) (xy 413.520636 -38.307264) (xy 413.520636 -37.979858)
				(xy 413.737806 -37.762688) (xy 414.054036 -37.762688) (xy 414.517332 -38.225984) (xy 415.161984 -38.225984)
				(xy 415.259012 -38.323012) (xy 415.309812 -38.373812) (xy 415.309812 -38.653212) (xy 414.903412 -39.059612)
				(xy 414.903412 -39.567612) (xy 414.954212 -39.618412) (xy 415.17062 -39.618412) (xy 415.747708 -39.041324)
				(xy 415.747708 -38.827964) (xy 415.677858 -38.758114) (xy 415.677858 -38.313106) (xy 415.76498 -38.225984)
				(xy 416.120834 -38.225984) (xy 416.624262 -38.729412) (xy 418.357812 -38.729412) (xy 418.45865 -38.62832)
			)
		)
	)
	(zone
		(layer "F.Cu")
		(hatch none 0.5)
		(connect_pads
			(clearance 0)
		)
		(min_thickness 0.25)
		(keepout
			(tracks allowed)
			(vias allowed)
			(pads allowed)
			(copperpour allowed)
			(footprints allowed)
		)
		(placement
			(enabled no)
			(sheetname "")
		)
		(fill
			(thermal_gap 0.5)
			(thermal_bridge_width 0.5)
			(island_removal_mode 0)
		)
		(polygon
			(pts
				(xy 347.091 -158.369) (xy 353.06 -158.369) (xy 353.441 -157.988) (xy 353.441 -153.035) (xy 352.125534 -151.719534)
				(xy 348.279466 -151.719534) (xy 346.837 -153.162) (xy 346.837 -158.115)
			)
		)
	)
	(zone
		(layer "F.Cu")
		(hatch none 0.5)
		(connect_pads
			(clearance 0)
		)
		(min_thickness 0.25)
		(keepout
			(tracks allowed)
			(vias allowed)
			(pads allowed)
			(copperpour allowed)
			(footprints allowed)
		)
		(placement
			(enabled no)
			(sheetname "")
		)
		(fill
			(thermal_gap 0.5)
			(thermal_bridge_width 0.5)
			(island_removal_mode 0)
		)
		(polygon
			(pts
				(xy 318.5414 -123.1011) (xy 320.8274 -123.1011) (xy 320.8274 -125.1077) (xy 318.5414 -125.1077)
			)
		)
	)
	(zone
		(net "GND")
		(layer "F.Cu")
		(hatch none 0.5)
		(connect_pads
			(clearance 0.5)
		)
		(min_thickness 0.25)
		(fill yes
			(thermal_gap 0.5)
			(thermal_bridge_width 0.5)
			(island_removal_mode 0)
		)
		(polygon
			(pts
				(xy 167.513 -68.707) (xy 170.942 -68.707) (xy 171.069 -68.58) (xy 171.069 -65.151) (xy 170.815 -64.897)
				(xy 167.513 -64.897) (xy 167.259 -65.151) (xy 167.259 -68.453)
			)
		)
	)
	(zone
		(net "P12V_STBY")
		(layer "F.Cu")
		(hatch none 0.5)
		(connect_pads
			(clearance 0.5)
		)
		(min_thickness 0.25)
		(fill yes
			(thermal_gap 0.5)
			(thermal_bridge_width 0.5)
			(island_removal_mode 0)
		)
		(polygon
			(pts
				(xy 486.2322 -115.1382) (xy 487.807 -115.1382) (xy 488.061 -114.8842) (xy 488.061 -111.0615) (xy 488.0229 -111.0234)
				(xy 485.9782 -111.0234) (xy 485.9274 -111.0742) (xy 485.9274 -114.8334)
			)
		)
	)
	(zone
		(layer "F.Cu")
		(hatch none 0.5)
		(connect_pads
			(clearance 0)
		)
		(min_thickness 0.25)
		(keepout
			(tracks allowed)
			(vias allowed)
			(pads allowed)
			(copperpour allowed)
			(footprints not_allowed)
		)
		(placement
			(enabled no)
			(sheetname "")
		)
		(fill
			(thermal_gap 0.5)
			(thermal_bridge_width 0.5)
			(island_removal_mode 0)
		)
		(polygon
			(pts
				(arc
					(start 465.019898 -26.919936)
					(mid 461.419702 -30.520132)
					(end 465.019898 -34.120074)
				)
				(xy 466.419946 -34.120074) (xy 466.419946 -41.676828) (xy 430.950624 -41.676828) (xy 430.950624 -42.44594)
				(xy 388.753858 -42.44594) (xy 388.753858 -18.595848) (xy 502.000012 -18.595848) (xy 502.000012 -42.44594)
				(xy 497.000022 -42.44594) (xy 497.000022 -34.120074)
				(arc
					(start 498.020086 -34.120074)
					(mid 501.759536 -30.520137)
					(end 498.020086 -26.919936)
				)
				(arc
					(start 495.020092 -26.919936)
					(mid 491.419896 -30.520132)
					(end 495.020092 -34.120074)
				)
				(xy 496.899946 -34.120074) (xy 496.899946 -42.44594) (xy 474.950536 -42.44594) (xy 474.950536 -41.676828)
				(xy 466.520022 -41.676828) (xy 466.520022 -34.120074)
				(arc
					(start 468.019892 -34.120074)
					(mid 471.619834 -30.520132)
					(end 468.019892 -26.919936)
				)
			)
		)
	)
	(zone
		(layer "F.Cu")
		(hatch none 0.5)
		(connect_pads
			(clearance 0)
		)
		(min_thickness 0.25)
		(keepout
			(tracks not_allowed)
			(vias allowed)
			(pads allowed)
			(copperpour not_allowed)
			(footprints allowed)
		)
		(placement
			(enabled no)
			(sheetname "")
		)
		(fill
			(thermal_gap 0.5)
			(thermal_bridge_width 0.5)
			(island_removal_mode 0)
		)
		(polygon
			(pts
				(xy 409.326588 -1.3081) (xy 409.481782 -1.463294) (xy 409.481782 -1.76149) (xy 409.583382 -1.76149)
				(xy 409.583382 -1.463294) (xy 409.738576 -1.3081)
				(arc
					(start 409.91028 -1.3081)
					(mid 410.434197 -1.37795)
					(end 409.91028 -1.4478)
				)
				(xy 409.796488 -1.4478) (xy 409.723082 -1.521206) (xy 409.723082 -1.76149)
				(arc
					(start 410.167328 -1.76149)
					(mid 410.550868 -1.378077)
					(end 410.167582 -0.99441)
				)
				(arc
					(start 408.897582 -0.99441)
					(mid 408.514042 -1.37795)
					(end 408.897582 -1.76149)
				)
				(xy 409.342082 -1.76149) (xy 409.342082 -1.521206) (xy 409.268676 -1.4478)
				(arc
					(start 409.154884 -1.4478)
					(mid 408.630967 -1.37795)
					(end 409.154884 -1.3081)
				)
			)
		)
	)
	(zone
		(layer "F.Cu")
		(hatch none 0.5)
		(connect_pads
			(clearance 0)
		)
		(min_thickness 0.25)
		(keepout
			(tracks not_allowed)
			(vias allowed)
			(pads allowed)
			(copperpour not_allowed)
			(footprints allowed)
		)
		(placement
			(enabled no)
			(sheetname "")
		)
		(fill
			(thermal_gap 0.5)
			(thermal_bridge_width 0.5)
			(island_removal_mode 0)
		)
		(polygon
			(pts
				(xy 397.689324 -105.612438) (xy 397.640556 -105.630472)
				(arc
					(start 397.356584 -105.498392)
					(mid 396.906701 -105.219383)
					(end 397.40967 -105.3846)
				)
				(xy 397.693388 -105.516426) (xy 397.711422 -105.565194)
				(arc
					(start 398.008856 -105.565194)
					(mid 398.026889 -105.090188)
					(end 398.40027 -105.3846)
				)
				(arc
					(start 398.484852 -105.423716)
					(mid 398.422339 -105.113787)
					(end 398.13865 -104.974136)
				)
				(arc
					(start 397.148304 -104.974136)
					(mid 396.78991 -105.332149)
					(end 397.14805 -105.690416)
				)
				(arc
					(start 398.13865 -105.690416)
					(mid 398.303997 -105.649963)
					(end 398.43202 -105.537762)
				)
				(arc
					(start 398.347184 -105.498392)
					(mid 398.192839 -105.593321)
					(end 398.013428 -105.567734)
				)
				(xy 397.711168 -105.567734) (xy 397.711168 -105.565702)
			)
		)
	)
	(zone
		(net "GND")
		(layer "F.Cu")
		(hatch none 0.5)
		(connect_pads
			(clearance 0.5)
		)
		(min_thickness 0.25)
		(fill yes
			(thermal_gap 0.5)
			(thermal_bridge_width 0.5)
			(island_removal_mode 0)
		)
		(polygon
			(pts
				(xy 261.041134 -3.971544) (xy 261.80542 -3.971544) (xy 261.86892 -3.908044) (xy 261.86892 -1.747012)
				(xy 261.505954 -1.384046) (xy 260.319012 -1.384046) (xy 260.198616 -1.504442) (xy 260.198616 -1.983486)
				(xy 260.706362 -2.491232) (xy 260.706362 -2.603246) (xy 260.706362 -3.914902) (xy 260.763004 -3.971544)
			)
		)
	)
	(zone
		(net "P12V_STBY")
		(layer "F.Cu")
		(hatch none 0.5)
		(connect_pads
			(clearance 0.5)
		)
		(min_thickness 0.25)
		(fill yes
			(thermal_gap 0.5)
			(thermal_bridge_width 0.5)
			(island_removal_mode 0)
		)
		(polygon
			(pts
				(xy 329.438 -113.919) (xy 329.2348 -114.1222) (xy 329.2348 -115.7986) (xy 329.946 -116.5098) (xy 338.0994 -116.5098)
				(xy 338.733384 -115.875816) (xy 338.799678 -115.809522) (xy 338.799678 -115.382294) (xy 338.734654 -115.31727)
				(xy 338.733384 -115.31727) (xy 338.599272 -115.183158) (xy 338.599272 -114.653314) (xy 338.733384 -114.519202)
				(xy 338.802218 -114.450368) (xy 338.802218 -114.122962) (xy 338.598256 -113.919) (xy 338.504276 -113.919)
			)
		)
	)
	(zone
		(net "GND")
		(layer "F.Cu")
		(hatch none 0.5)
		(connect_pads
			(clearance 0.5)
		)
		(min_thickness 0.25)
		(fill yes
			(thermal_gap 0.5)
			(thermal_bridge_width 0.5)
			(island_removal_mode 0)
		)
		(polygon
			(pts
				(xy 416.7632 -85.7885) (xy 419.2524 -85.7885) (xy 419.3794 -85.9155) (xy 420.1795 -85.9155) (xy 420.3065 -85.7885)
				(xy 420.9415 -85.7885) (xy 421.005 -85.725) (xy 421.005 -85.2678) (xy 421.005 -84.2391) (xy 420.746428 -83.980528)
				(xy 419.951154 -83.980528) (xy 418.883338 -83.980528) (xy 418.875718 -83.980528) (xy 418.86759 -83.9724)
				(xy 417.3601 -83.9724) (xy 417.068 -83.6803) (xy 417.068 -83.185) (xy 417.0172 -83.1342) (xy 416.6108 -83.1342)
				(xy 416.56 -83.185) (xy 416.56 -85.5853)
			)
		)
	)
	(zone
		(layer "F.Cu")
		(hatch none 0.5)
		(connect_pads
			(clearance 0)
		)
		(min_thickness 0.25)
		(keepout
			(tracks allowed)
			(vias allowed)
			(pads allowed)
			(copperpour allowed)
			(footprints allowed)
		)
		(placement
			(enabled no)
			(sheetname "")
		)
		(fill
			(thermal_gap 0.5)
			(thermal_bridge_width 0.5)
			(island_removal_mode 0)
		)
		(polygon
			(pts
				(xy 480.2378 -49.9872) (xy 480.2378 -48.3616) (xy 489.5596 -48.3616) (xy 489.5596 -49.9872)
			)
		)
	)
	(zone
		(layer "F.Cu")
		(hatch none 0.5)
		(connect_pads
			(clearance 0)
		)
		(min_thickness 0.25)
		(keepout
			(tracks allowed)
			(vias allowed)
			(pads allowed)
			(copperpour allowed)
			(footprints allowed)
		)
		(placement
			(enabled no)
			(sheetname "")
		)
		(fill
			(thermal_gap 0.5)
			(thermal_bridge_width 0.5)
			(island_removal_mode 0)
		)
		(polygon
			(pts
				(xy 276.7076 -45.9486) (xy 279.4 -43.2562) (xy 279.4 -41.3004) (xy 279.908 -40.7924) (xy 286.1564 -40.7924)
				(xy 286.3596 -40.9956) (xy 286.7914 -40.9956) (xy 287.0962 -41.3004) (xy 287.5534 -41.3004) (xy 288.2138 -41.9608)
				(xy 288.2138 -42.1894) (xy 286.4485 -43.9547) (xy 282.0162 -48.387) (xy 281.94 -48.514) (xy 281.94 -49.149)
				(xy 281.559 -49.53) (xy 281.559 -49.657) (xy 276.606 -49.657) (xy 276.606 -45.974) (xy 276.6314 -45.9486)
			)
		)
	)
	(zone
		(layer "F.Cu")
		(hatch none 0.5)
		(connect_pads
			(clearance 0)
		)
		(min_thickness 0.25)
		(keepout
			(tracks allowed)
			(vias allowed)
			(pads allowed)
			(copperpour allowed)
			(footprints allowed)
		)
		(placement
			(enabled no)
			(sheetname "")
		)
		(fill
			(thermal_gap 0.5)
			(thermal_bridge_width 0.5)
			(island_removal_mode 0)
		)
		(polygon
			(pts
				(xy -1.143 -145.669) (xy -1.143 -144.399) (xy 1.651 -144.399) (xy 1.651 -145.669)
			)
		)
	)
	(zone
		(net "P5V_STBY_USBC")
		(layer "F.Cu")
		(hatch none 0.5)
		(connect_pads
			(clearance 0.5)
		)
		(min_thickness 0.25)
		(fill yes
			(thermal_gap 0.5)
			(thermal_bridge_width 0.5)
			(island_removal_mode 0)
		)
		(polygon
			(pts
				(xy 495.951002 -58.510678) (xy 498.459506 -58.510678) (xy 498.808756 -58.859928) (xy 500.371872 -58.859928)
				(xy 500.8118 -58.42) (xy 500.8118 -55.772558) (xy 500.7102 -55.670958) (xy 499.269004 -55.670958)
				(xy 498.33276 -55.670958) (xy 495.951002 -55.670958) (xy 495.832638 -55.789322) (xy 495.832638 -58.392314)
			)
		)
	)
	(zone
		(net "VR_PVDDQ_DEF_PH1_SW")
		(layer "F.Cu")
		(hatch none 0.5)
		(connect_pads
			(clearance 0.5)
		)
		(min_thickness 0.25)
		(fill yes
			(thermal_gap 0.5)
			(thermal_bridge_width 0.5)
			(island_removal_mode 0)
		)
		(polygon
			(pts
				(xy 339.217 -152.019) (xy 339.217 -156.083) (xy 339.63229 -156.49829) (xy 342.27389 -156.49829)
				(xy 342.616028 -156.840428) (xy 343.939368 -156.840428) (xy 344.932 -155.847796) (xy 344.932 -155.4226)
				(xy 344.932 -152.146) (xy 344.932 -151.13) (xy 344.8558 -151.0538) (xy 339.4964 -151.0538) (xy 339.217 -151.3332)
			)
		)
	)
	(zone
		(layer "F.Cu")
		(hatch none 0.5)
		(connect_pads
			(clearance 0)
		)
		(min_thickness 0.25)
		(keepout
			(tracks allowed)
			(vias allowed)
			(pads allowed)
			(copperpour allowed)
			(footprints allowed)
		)
		(placement
			(enabled no)
			(sheetname "")
		)
		(fill
			(thermal_gap 0.5)
			(thermal_bridge_width 0.5)
			(island_removal_mode 0)
		)
		(polygon
			(pts
				(xy 345.6432 -8.7122) (xy 345.6432 -4.3434) (xy 348.0562 -4.3434) (xy 348.0562 -8.7122)
			)
		)
	)
	(zone
		(net "PVDDQ_DEF")
		(layer "F.Cu")
		(hatch none 0.5)
		(connect_pads
			(clearance 0.5)
		)
		(min_thickness 0.25)
		(fill yes
			(thermal_gap 0.5)
			(thermal_bridge_width 0.5)
			(island_removal_mode 0)
		)
		(polygon
			(pts
				(xy 277.37562 -146.21256) (xy 277.529036 -146.059144) (xy 277.529036 -143.83131) (xy 277.40864 -143.71066)
				(xy 265.8618 -143.71066) (xy 265.678158 -143.894302) (xy 265.678158 -145.960592) (xy 265.930126 -146.21256)
			)
		)
	)
	(zone
		(layer "F.Cu")
		(hatch none 0.5)
		(connect_pads
			(clearance 0)
		)
		(min_thickness 0.25)
		(keepout
			(tracks allowed)
			(vias allowed)
			(pads allowed)
			(copperpour allowed)
			(footprints allowed)
		)
		(placement
			(enabled no)
			(sheetname "")
		)
		(fill
			(thermal_gap 0.5)
			(thermal_bridge_width 0.5)
			(island_removal_mode 0)
		)
		(polygon
			(pts
				(xy 272.034 -99.822) (xy 276.479 -99.822) (xy 277.495 -100.838) (xy 277.495 -102.489) (xy 277.495 -103.4542)
				(xy 277.495 -103.759) (xy 277.495 -104.14) (xy 271.272 -104.14) (xy 271.272 -103.759) (xy 271.272 -99.822)
			)
		)
	)
	(zone
		(layer "F.Cu")
		(hatch none 0.5)
		(connect_pads
			(clearance 0)
		)
		(min_thickness 0.25)
		(keepout
			(tracks allowed)
			(vias allowed)
			(pads allowed)
			(copperpour allowed)
			(footprints allowed)
		)
		(placement
			(enabled no)
			(sheetname "")
		)
		(fill
			(thermal_gap 0.5)
			(thermal_bridge_width 0.5)
			(island_removal_mode 0)
		)
		(polygon
			(pts
				(xy 281.6733 -50.165) (xy 281.6733 -49.6443) (xy 282.0162 -49.3014) (xy 282.1051 -49.3014) (xy 282.1051 -48.8569)
				(xy 282.321 -48.641) (xy 283.464 -47.498) (xy 284.48 -47.498) (xy 287.274 -50.292) (xy 287.274 -52.705)
				(xy 285.115 -54.864) (xy 283.21 -54.864) (xy 281.6733 -53.3273) (xy 281.305 -52.959) (xy 281.305 -50.5333)
			)
		)
	)
	(zone
		(layer "F.Cu")
		(hatch none 0.5)
		(connect_pads
			(clearance 0)
		)
		(min_thickness 0.25)
		(keepout
			(tracks allowed)
			(vias allowed)
			(pads allowed)
			(copperpour allowed)
			(footprints not_allowed)
		)
		(placement
			(enabled no)
			(sheetname "")
		)
		(fill
			(thermal_gap 0.5)
			(thermal_bridge_width 0.5)
			(island_removal_mode 0)
		)
		(polygon
			(pts
				(xy 22.52472 4.683252) (xy 22.52472 5.999988) (xy 163.524692 5.999988) (xy 163.524692 4.683252)
			)
		)
	)
	(zone
		(net "PVDDQ_ABC")
		(layer "F.Cu")
		(hatch none 0.5)
		(connect_pads
			(clearance 0.5)
		)
		(min_thickness 0.25)
		(fill yes
			(thermal_gap 0.5)
			(thermal_bridge_width 0.5)
			(island_removal_mode 0)
		)
		(polygon
			(pts
				(xy 332.139036 5.207) (xy 336.296 5.207) (xy 336.8802 4.6228) (xy 337.8708 3.6322) (xy 337.8708 -10.3124)
				(xy 338.455 -10.8966) (xy 338.455 -12.446) (xy 337.312 -12.446) (xy 336.55 -12.446) (xy 335.915 -13.081)
				(xy 332.105 -13.081) (xy 331.86243 -13.32357) (xy 328.91857 -13.32357) (xy 328.676 -13.081) (xy 328.676 2.753106)
				(xy 329.472544 3.54965) (xy 330.269342 3.54965) (xy 330.481686 3.54965) (xy 330.680822 3.748786)
			)
		)
	)
	(zone
		(layer "F.Cu")
		(hatch none 0.5)
		(connect_pads
			(clearance 0)
		)
		(min_thickness 0.25)
		(keepout
			(tracks not_allowed)
			(vias allowed)
			(pads allowed)
			(copperpour not_allowed)
			(footprints allowed)
		)
		(placement
			(enabled no)
			(sheetname "")
		)
		(fill
			(thermal_gap 0.5)
			(thermal_bridge_width 0.5)
			(island_removal_mode 0)
		)
		(polygon
			(pts
				(arc
					(start 458.919834 -44.7675)
					(mid 459.443751 -44.83735)
					(end 458.919834 -44.9072)
				)
				(xy 458.873098 -44.9072) (xy 458.732636 -45.047662) (xy 458.732636 -45.22089)
				(arc
					(start 459.176882 -45.22089)
					(mid 459.560422 -44.837477)
					(end 459.177136 -44.45381)
				)
				(arc
					(start 457.907136 -44.45381)
					(mid 457.523596 -44.83735)
					(end 457.907136 -45.22089)
				)
				(xy 458.351636 -45.22089) (xy 458.351636 -45.047662) (xy 458.211174 -44.9072)
				(arc
					(start 458.164438 -44.9072)
					(mid 457.640521 -44.83735)
					(end 458.164438 -44.7675)
				)
				(xy 458.269086 -44.7675) (xy 458.491336 -44.98975) (xy 458.491336 -45.22089) (xy 458.592936 -45.22089)
				(xy 458.592936 -44.98975) (xy 458.815186 -44.7675)
			)
		)
	)
	(zone
		(net "VR_FET_SW_P12V_STBY_PVDDQ_GHJ")
		(layer "F.Cu")
		(hatch none 0.5)
		(connect_pads
			(clearance 0.5)
		)
		(min_thickness 0.25)
		(fill yes
			(thermal_gap 0.5)
			(thermal_bridge_width 0.5)
			(island_removal_mode 0)
		)
		(polygon
			(pts
				(xy 2.524506 -11.386058) (xy 2.651506 -11.259058) (xy 2.651506 -11.247374) (xy 2.686304 -11.212576)
				(xy 2.686304 -9.875774) (xy 4.66852 -9.875774) (xy 4.66852 -12.237974) (xy 4.537202 -12.369292)
				(xy 4.537202 -13.018262) (xy 4.503928 -13.051536) (xy 1.93548 -13.051536) (xy 1.70942 -12.825476)
				(xy 1.70942 -11.482578) (xy 1.80594 -11.386058)
			)
		)
	)
	(zone
		(layer "F.Cu")
		(hatch none 0.5)
		(connect_pads
			(clearance 0)
		)
		(min_thickness 0.25)
		(keepout
			(tracks not_allowed)
			(vias allowed)
			(pads allowed)
			(copperpour not_allowed)
			(footprints allowed)
		)
		(placement
			(enabled no)
			(sheetname "")
		)
		(fill
			(thermal_gap 0.5)
			(thermal_bridge_width 0.5)
			(island_removal_mode 0)
		)
		(polygon
			(pts
				(arc
					(start 446.119758 -44.7675)
					(mid 446.643675 -44.83735)
					(end 446.119758 -44.9072)
				)
				(xy 446.073022 -44.9072) (xy 445.94145 -45.038772) (xy 445.94145 -45.22089)
				(arc
					(start 446.37706 -45.22089)
					(mid 446.7606 -44.83735)
					(end 446.37706 -44.45381)
				)
				(arc
					(start 445.107314 -44.45381)
					(mid 444.723774 -44.837223)
					(end 445.10706 -45.22089)
				)
				(xy 445.56045 -45.22089) (xy 445.56045 -45.056552) (xy 445.411098 -44.9072)
				(arc
					(start 445.364362 -44.9072)
					(mid 444.840445 -44.83735)
					(end 445.364362 -44.7675)
				)
				(xy 445.46901 -44.7675) (xy 445.70015 -44.99864) (xy 445.70015 -45.22089) (xy 445.80175 -45.22089)
				(xy 445.80175 -44.98086) (xy 446.01511 -44.7675)
			)
		)
	)
	(zone
		(layer "F.Cu")
		(hatch none 0.5)
		(connect_pads
			(clearance 0)
		)
		(min_thickness 0.25)
		(keepout
			(tracks not_allowed)
			(vias allowed)
			(pads allowed)
			(copperpour not_allowed)
			(footprints allowed)
		)
		(placement
			(enabled no)
			(sheetname "")
		)
		(fill
			(thermal_gap 0.5)
			(thermal_bridge_width 0.5)
			(island_removal_mode 0)
		)
		(polygon
			(pts
				(xy 446.549018 -114.020092) (xy 446.549018 -114.328448) (xy 446.403984 -114.473482)
				(arc
					(start 446.22212 -114.473482)
					(mid 445.698203 -114.403632)
					(end 446.22212 -114.333782)
				)
				(xy 446.346072 -114.333782) (xy 446.409318 -114.270536) (xy 446.409318 -114.020092)
				(arc
					(start 445.965072 -114.020092)
					(mid 445.581532 -114.403505)
					(end 445.964818 -114.787172)
				)
				(arc
					(start 447.234818 -114.787172)
					(mid 447.618358 -114.403632)
					(end 447.234818 -114.020092)
				)
				(xy 446.790318 -114.020092) (xy 446.790318 -114.270536) (xy 446.853564 -114.333782)
				(arc
					(start 446.977516 -114.333782)
					(mid 447.501433 -114.403632)
					(end 446.977516 -114.473482)
				)
				(xy 446.795652 -114.473482) (xy 446.650618 -114.328448) (xy 446.650618 -114.020092)
			)
		)
	)
	(zone
		(net "GND")
		(layer "F.Cu")
		(hatch none 0.5)
		(connect_pads
			(clearance 0.5)
		)
		(min_thickness 0.25)
		(fill yes
			(thermal_gap 0.5)
			(thermal_bridge_width 0.5)
			(island_removal_mode 0)
		)
		(polygon
			(pts
				(xy 341.96528 -132.27558) (xy 343.789 -132.27558) (xy 343.90584 -132.15874) (xy 343.90584 -130.7592)
				(xy 343.79408 -130.64744) (xy 341.93734 -130.64744) (xy 341.79002 -130.79476) (xy 341.79002 -131.92633)
				(xy 340.800182 -131.92633) (xy 340.800182 -132.27558)
			)
		)
	)
	(zone
		(layer "F.Cu")
		(hatch none 0.5)
		(connect_pads
			(clearance 0)
		)
		(min_thickness 0.25)
		(keepout
			(tracks allowed)
			(vias allowed)
			(pads allowed)
			(copperpour allowed)
			(footprints allowed)
		)
		(placement
			(enabled no)
			(sheetname "")
		)
		(fill
			(thermal_gap 0.5)
			(thermal_bridge_width 0.5)
			(island_removal_mode 0)
		)
		(polygon
			(pts
				(xy 102.526338 -50.030634) (xy 88.330024 -50.030634) (xy 87.991188 -49.691798) (xy 87.991188 -47.712122)
				(xy 88.425274 -47.278036) (xy 91.241118 -47.278036) (xy 92.405454 -46.1137) (xy 95.840804 -46.1137)
				(xy 95.880682 -46.073822) (xy 98.29419 -46.073822) (xy 98.704654 -46.484286) (xy 102.293928 -46.484286)
				(xy 103.04526 -47.235618) (xy 103.04526 -49.511712)
			)
		)
	)
	(zone
		(net "P12V_STBY")
		(layer "F.Cu")
		(hatch none 0.5)
		(connect_pads
			(clearance 0.5)
		)
		(min_thickness 0.25)
		(fill yes
			(thermal_gap 0.5)
			(thermal_bridge_width 0.5)
			(island_removal_mode 0)
		)
		(polygon
			(pts
				(xy 354.7618 -33.107376) (xy 354.50653 -33.362646) (xy 353.228148 -33.362646) (xy 352.9838 -33.118298)
				(xy 352.9838 -32.2453) (xy 352.9838 -31.8643) (xy 352.9838 -31.6992) (xy 352.2218 -30.9372) (xy 352.2218 -29.972)
				(xy 352.3488 -29.845) (xy 353.6188 -29.845) (xy 354.7618 -30.988)
			)
		)
	)
	(zone
		(layer "F.Cu")
		(hatch none 0.5)
		(connect_pads
			(clearance 0)
		)
		(min_thickness 0.25)
		(keepout
			(tracks allowed)
			(vias allowed)
			(pads allowed)
			(copperpour allowed)
			(footprints allowed)
		)
		(placement
			(enabled no)
			(sheetname "")
		)
		(fill
			(thermal_gap 0.5)
			(thermal_bridge_width 0.5)
			(island_removal_mode 0)
		)
		(polygon
			(pts
				(xy 116.672868 -50.165) (xy 116.672868 -49.6443) (xy 117.015768 -49.3014) (xy 117.104668 -49.3014)
				(xy 117.104668 -48.8569) (xy 117.320568 -48.641) (xy 118.463568 -47.498) (xy 119.479568 -47.498)
				(xy 122.273568 -50.292) (xy 122.273568 -52.705) (xy 120.114568 -54.864) (xy 118.209568 -54.864)
				(xy 116.672868 -53.3273) (xy 116.304568 -52.959) (xy 116.304568 -50.5333)
			)
		)
	)
	(zone
		(net "GND")
		(layer "F.Cu")
		(hatch none 0.5)
		(connect_pads
			(clearance 0.5)
		)
		(min_thickness 0.25)
		(fill yes
			(thermal_gap 0.5)
			(thermal_bridge_width 0.5)
			(island_removal_mode 0)
		)
		(polygon
			(pts
				(xy 6.096 -132.207) (xy 6.477 -132.207) (xy 7.239 -131.445) (xy 7.239 -131.064) (xy 7.112 -130.937)
				(xy 5.842 -130.937) (xy 5.7912 -130.9878) (xy 5.7912 -131.9022)
			)
		)
	)
	(zone
		(layer "F.Cu")
		(hatch none 0.5)
		(connect_pads
			(clearance 0)
		)
		(min_thickness 0.25)
		(keepout
			(tracks not_allowed)
			(vias allowed)
			(pads allowed)
			(copperpour not_allowed)
			(footprints allowed)
		)
		(placement
			(enabled no)
			(sheetname "")
		)
		(fill
			(thermal_gap 0.5)
			(thermal_bridge_width 0.5)
			(island_removal_mode 0)
		)
		(polygon
			(pts
				(xy 384.40741 -34.898076)
				(arc
					(start 384.40741 -34.974022)
					(mid 384.416854 -34.946498)
					(end 384.429254 -34.920174)
				)
			)
		)
	)
	(zone
		(layer "F.Cu")
		(hatch none 0.5)
		(connect_pads
			(clearance 0)
		)
		(min_thickness 0.25)
		(keepout
			(tracks allowed)
			(vias allowed)
			(pads allowed)
			(copperpour allowed)
			(footprints not_allowed)
		)
		(placement
			(enabled no)
			(sheetname "")
		)
		(fill
			(thermal_gap 0.5)
			(thermal_bridge_width 0.5)
			(island_removal_mode 0)
		)
		(polygon
			(pts
				(xy 48.547274 -22.919182) (xy 48.547274 -130.16611) (xy 161.247328 -130.16611) (xy 161.247328 -117.80012)
				(xy 48.747426 -117.80012) (xy 48.747426 -35.299904) (xy 161.247328 -35.299904) (xy 161.247328 -22.919182)
			)
		)
	)
	(zone
		(net "PVDDQ_ABC")
		(layer "F.Cu")
		(hatch none 0.5)
		(connect_pads
			(clearance 0.5)
		)
		(min_thickness 0.25)
		(fill yes
			(thermal_gap 0.5)
			(thermal_bridge_width 0.5)
			(island_removal_mode 0)
		)
		(polygon
			(pts
				(xy 258.826 -2.518664) (xy 258.698492 -2.39141) (xy 258.698492 -2.159) (xy 258.571492 -2.032) (xy 258.3561 -2.032)
				(arc
					(start 257.966464 -2.421636)
					(mid 257.907107 -2.541603)
					(end 257.81 -2.633726)
				)
				(arc
					(start 257.81 -4.009898)
					(mid 257.965816 -4.219823)
					(end 257.949954 -4.480814)
				)
				(arc
					(start 257.949954 -4.480814)
					(mid 257.95818 -4.576851)
					(end 258.042918 -4.6228)
				)
				(xy 258.5466 -4.6228) (xy 258.698492 -4.470654) (xy 258.698492 -4.21259) (xy 258.699 -4.212336)
				(xy 258.699 -4.064) (xy 258.8514 -3.9116) (xy 259.926328 -3.9116) (xy 260.00583 -3.832098) (xy 260.00583 -2.98323)
				(xy 260.003544 -2.980944) (xy 260.003544 -2.756408) (xy 259.858256 -2.61112) (xy 258.918456 -2.61112)
			)
		)
		(polygon
			(pts
				(xy 258.5847 -3.715512) (xy 258.3815 -3.715512) (xy 258.3815 -3.918712) (xy 258.5847 -3.918712)
			)
		)
		(polygon
			(pts
				(xy 258.5847 -2.724912) (xy 258.3815 -2.724912) (xy 258.3815 -2.928112) (xy 258.5847 -2.928112)
			)
		)
	)
	(zone
		(layer "F.Cu")
		(hatch none 0.5)
		(connect_pads
			(clearance 0)
		)
		(min_thickness 0.25)
		(keepout
			(tracks allowed)
			(vias allowed)
			(pads allowed)
			(copperpour allowed)
			(footprints allowed)
		)
		(placement
			(enabled no)
			(sheetname "")
		)
		(fill
			(thermal_gap 0.5)
			(thermal_bridge_width 0.5)
			(island_removal_mode 0)
		)
		(polygon
			(pts
				(xy 358.714548 -79.55915) (xy 358.714548 -77.27315) (xy 360.721148 -77.27315) (xy 360.721148 -79.55915)
			)
		)
	)
	(zone
		(net "P12V_STBY")
		(layer "F.Cu")
		(hatch none 0.5)
		(connect_pads
			(clearance 0.5)
		)
		(min_thickness 0.25)
		(fill yes
			(thermal_gap 0.5)
			(thermal_bridge_width 0.5)
			(island_removal_mode 0)
		)
		(polygon
			(pts
				(xy -1.270508 -20.271232) (xy -1.270508 -18.772632) (xy -1.854708 -18.188432) (xy -2.350008 -17.693132)
				(xy -4.267708 -17.693132) (xy -4.775708 -18.201132) (xy -4.775708 -18.594832) (xy -4.775708 -20.798282)
				(xy -4.775708 -21.579332) (xy -4.4196 -21.93544) (xy -1.46812 -21.93544) (xy -1.270508 -21.737828)
			)
		)
	)
	(zone
		(layer "F.Cu")
		(hatch none 0.5)
		(connect_pads
			(clearance 0)
		)
		(min_thickness 0.25)
		(keepout
			(tracks not_allowed)
			(vias allowed)
			(pads allowed)
			(copperpour not_allowed)
			(footprints allowed)
		)
		(placement
			(enabled no)
			(sheetname "")
		)
		(fill
			(thermal_gap 0.5)
			(thermal_bridge_width 0.5)
			(island_removal_mode 0)
		)
		(polygon
			(pts
				(arc
					(start 248.000012 -109.650022)
					(mid 249.900186 -111.550196)
					(end 248.000012 -113.450116)
				)
				(arc
					(start 248.000012 -113.450116)
					(mid 246.100092 -111.550196)
					(end 248.000012 -109.650022)
				)
			)
		)
	)
	(zone
		(layer "F.Cu")
		(hatch none 0.5)
		(connect_pads
			(clearance 0)
		)
		(min_thickness 0.25)
		(keepout
			(tracks allowed)
			(vias allowed)
			(pads allowed)
			(copperpour allowed)
			(footprints not_allowed)
		)
		(placement
			(enabled no)
			(sheetname "")
		)
		(fill
			(thermal_gap 0.5)
			(thermal_bridge_width 0.5)
			(island_removal_mode 0)
		)
		(polygon
			(pts
				(arc
					(start 477.800416 -60.59678)
					(mid 474.200474 -64.196722)
					(end 470.600532 -60.59678)
				)
				(arc
					(start 470.600532 -58.996834)
					(mid 474.200474 -55.396892)
					(end 477.800416 -58.996834)
				)
			)
		)
	)
	(zone
		(layer "F.Cu")
		(hatch none 0.5)
		(connect_pads
			(clearance 0)
		)
		(min_thickness 0.25)
		(keepout
			(tracks allowed)
			(vias allowed)
			(pads allowed)
			(copperpour allowed)
			(footprints allowed)
		)
		(placement
			(enabled no)
			(sheetname "")
		)
		(fill
			(thermal_gap 0.5)
			(thermal_bridge_width 0.5)
			(island_removal_mode 0)
		)
		(polygon
			(pts
				(xy 271.018 -42.037) (xy 270.3576 -41.273476) (xy 270.3576 -40.1574) (xy 270.383 -40.132) (xy 270.819372 -40.132)
				(xy 274.3708 -40.132) (xy 274.5486 -40.3098) (xy 274.6629 -40.3098) (xy 276.987 -40.3098) (xy 277.1648 -40.4876)
				(xy 277.1648 -40.9448) (xy 276.352 -41.7576) (xy 276.352 -49.657) (xy 271.018 -49.657)
			)
		)
	)
	(zone
		(layer "F.Cu")
		(hatch none 0.5)
		(connect_pads
			(clearance 0)
		)
		(min_thickness 0.25)
		(keepout
			(tracks not_allowed)
			(vias allowed)
			(pads allowed)
			(copperpour not_allowed)
			(footprints allowed)
		)
		(placement
			(enabled no)
			(sheetname "")
		)
		(fill
			(thermal_gap 0.5)
			(thermal_bridge_width 0.5)
			(island_removal_mode 0)
		)
		(polygon
			(pts
				(arc
					(start 472.928696 -153.15565)
					(mid 472.338288 -153.485632)
					(end 471.67165 -153.599896)
				)
				(arc
					(start 471.000074 -153.599896)
					(mid 469.49995 -155.10002)
					(end 471.000074 -156.59989)
				)
				(arc
					(start 471.67165 -156.59989)
					(mid 472.338321 -156.714274)
					(end 472.928696 -157.04439)
				)
				(arc
					(start 472.928696 -157.04439)
					(mid 476.999816 -155.10002)
					(end 472.928696 -153.15565)
				)
			)
		)
	)
	(zone
		(layer "F.Cu")
		(hatch none 0.5)
		(connect_pads
			(clearance 0)
		)
		(min_thickness 0.25)
		(keepout
			(tracks not_allowed)
			(vias allowed)
			(pads allowed)
			(copperpour not_allowed)
			(footprints allowed)
		)
		(placement
			(enabled no)
			(sheetname "")
		)
		(fill
			(thermal_gap 0.5)
			(thermal_bridge_width 0.5)
			(island_removal_mode 0)
		)
		(polygon
			(pts
				(arc
					(start 358.92867 -153.15565)
					(mid 358.338262 -153.485632)
					(end 357.671624 -153.599896)
				)
				(arc
					(start 357.000048 -153.599896)
					(mid 355.499924 -155.10002)
					(end 357.000048 -156.59989)
				)
				(arc
					(start 357.671624 -156.59989)
					(mid 358.338295 -156.714274)
					(end 358.92867 -157.04439)
				)
				(arc
					(start 358.92867 -157.04439)
					(mid 362.99979 -155.10002)
					(end 358.92867 -153.15565)
				)
			)
		)
	)
	(zone
		(net "P5V_STBY")
		(layer "F.Cu")
		(hatch none 0.5)
		(connect_pads
			(clearance 0.5)
		)
		(min_thickness 0.25)
		(fill yes
			(thermal_gap 0.5)
			(thermal_bridge_width 0.5)
			(island_removal_mode 0)
		)
		(polygon
			(pts
				(xy 487.2482 -118.1862) (xy 487.2482 -115.9256) (xy 487.2482 -115.7478) (xy 487.1466 -115.6462)
				(xy 485.267 -115.6462) (xy 485.1146 -115.7986) (xy 485.1146 -118.1481) (xy 485.10825 -118.15445)
				(xy 485.10825 -118.45925) (xy 484.886 -118.6815) (xy 484.886 -120.68048) (xy 485.13492 -120.9294)
				(xy 485.6988 -120.9294) (xy 485.96296 -120.66524) (xy 486.73512 -120.66524) (xy 487.3752 -120.02516)
				(xy 487.3752 -119.261382) (xy 487.3752 -119.2022) (xy 487.3752 -118.3132)
			)
		)
	)
	(zone
		(net "P5V_STBY")
		(layer "F.Cu")
		(hatch none 0.5)
		(connect_pads
			(clearance 0.5)
		)
		(min_thickness 0.25)
		(fill yes
			(thermal_gap 0.5)
			(thermal_bridge_width 0.5)
			(island_removal_mode 0)
		)
		(polygon
			(pts
				(xy 434.83276 -124.72162) (xy 432.93284 -124.72162) (xy 432.396392 -125.258068) (xy 431.124868 -125.258068)
				(xy 431.061368 -125.258068) (xy 430.919128 -125.258068) (xy 430.87163 -125.305566) (xy 430.87163 -126.597156)
				(xy 431.36312 -127.088646) (xy 431.370486 -127.096012) (xy 431.370486 -127.878586) (xy 431.425858 -127.933958)
				(xy 431.96002 -128.46812) (xy 431.96002 -129.05486) (xy 431.96002 -129.3241) (xy 432.20132 -129.5654)
				(xy 434.08473 -129.5654) (xy 434.14442 -129.50571) (xy 434.14442 -129.4384) (xy 434.14442 -128.39954)
				(xy 435.23408 -127.30988) (xy 435.43474 -127.30988) (xy 435.82336 -126.92126) (xy 435.82336 -124.80798)
				(xy 435.737 -124.72162)
			)
		)
	)
	(zone
		(layer "F.Cu")
		(hatch none 0.5)
		(connect_pads
			(clearance 0)
		)
		(min_thickness 0.25)
		(keepout
			(tracks allowed)
			(vias allowed)
			(pads allowed)
			(copperpour allowed)
			(footprints allowed)
		)
		(placement
			(enabled no)
			(sheetname "")
		)
		(fill
			(thermal_gap 0.5)
			(thermal_bridge_width 0.5)
			(island_removal_mode 0)
		)
		(polygon
			(pts
				(xy 490.7026 -34.925) (xy 491.3884 -34.925) (xy 491.4392 -34.8742) (xy 491.4392 -34.4932) (xy 491.3376 -34.3916)
				(xy 489.966 -34.3916) (xy 489.8644 -34.29) (xy 489.5596 -34.29) (xy 489.5088 -34.3408) (xy 489.5088 -34.8742)
				(xy 489.585 -34.9504) (xy 490.6772 -34.9504)
			)
		)
	)
	(zone
		(net "P12V_STBY")
		(layer "F.Cu")
		(hatch none 0.5)
		(connect_pads
			(clearance 0.5)
		)
		(min_thickness 0.25)
		(fill yes
			(thermal_gap 0.5)
			(thermal_bridge_width 0.5)
			(island_removal_mode 0)
		)
		(polygon
			(pts
				(xy 177.56505 -25.857708) (xy 176.378108 -25.857708) (xy 176.37506 -25.85466) (xy 175.501554 -25.85466)
				(xy 175.2854 -26.070814) (xy 175.2854 -32.4104) (xy 175.2854 -32.9184) (xy 176.53 -34.163) (xy 185.928 -34.163)
				(xy 186.182 -33.909) (xy 186.182 -33.655) (xy 186.182 -32.512) (xy 186.182 -32.385) (xy 187.452 -31.115)
				(xy 190.9572 -31.115) (xy 192.024 -32.1818) (xy 192.1764 -32.3342) (xy 192.1764 -33.655) (xy 192.1764 -33.909)
				(xy 192.4304 -34.163) (xy 199.6948 -34.163) (xy 200.4187 -33.4391) (xy 200.4187 -32.3088) (xy 200.4187 -27.4574)
				(xy 199.9615 -27.0002) (xy 191.3382 -27.0002) (xy 189.357 -25.019) (xy 186.553094 -25.019) (xy 185.655458 -25.916636)
				(xy 184.191656 -25.916636) (xy 184.01792 -26.090372) (xy 183.80075 -26.307542) (xy 179.251356 -26.307542)
				(xy 178.64709 -26.307542) (xy 178.197256 -25.857708)
			)
		)
	)
	(zone
		(layer "F.Cu")
		(hatch none 0.5)
		(connect_pads
			(clearance 0)
		)
		(min_thickness 0.25)
		(keepout
			(tracks not_allowed)
			(vias allowed)
			(pads allowed)
			(copperpour not_allowed)
			(footprints allowed)
		)
		(placement
			(enabled no)
			(sheetname "")
		)
		(fill
			(thermal_gap 0.5)
			(thermal_bridge_width 0.5)
			(island_removal_mode 0)
		)
		(polygon
			(pts
				(xy 436.793132 -9.74598) (xy 436.793132 -9.990074)
				(arc
					(start 436.626762 -10.156444)
					(mid 436.100768 -10.186963)
					(end 436.591202 -9.994392)
				)
				(xy 436.653432 -9.932162) (xy 436.653432 -9.74598)
				(arc
					(start 436.361332 -9.74598)
					(mid 435.977792 -10.12952)
					(end 436.361332 -10.51306)
				)
				(arc
					(start 437.326278 -10.51306)
					(mid 437.709818 -10.129647)
					(end 437.326532 -9.74598)
				)
				(xy 437.034432 -9.74598) (xy 437.034432 -9.936226)
				(arc
					(start 437.095138 -9.996932)
					(mid 437.587928 -10.183274)
					(end 437.06161 -10.161016)
				)
				(xy 436.894732 -9.994138) (xy 436.894732 -9.74598)
			)
		)
	)
	(zone
		(net "GND")
		(layer "F.Cu")
		(hatch none 0.5)
		(connect_pads
			(clearance 0.5)
		)
		(min_thickness 0.25)
		(fill yes
			(thermal_gap 0.5)
			(thermal_bridge_width 0.5)
			(island_removal_mode 0)
		)
		(polygon
			(pts
				(xy 168.59758 -129.081784) (xy 165.293294 -129.081784) (xy 164.905436 -129.469642) (xy 164.905436 -131.846828)
				(xy 164.97173 -131.913122) (xy 168.313354 -131.913122) (xy 168.649142 -131.577334) (xy 169.395394 -131.577334)
				(xy 169.4434 -131.529328) (xy 169.4434 -129.927604) (xy 169.236644 -129.720848)
			)
		)
	)
	(zone
		(layer "F.Cu")
		(hatch none 0.5)
		(connect_pads
			(clearance 0)
		)
		(min_thickness 0.25)
		(keepout
			(tracks not_allowed)
			(vias allowed)
			(pads allowed)
			(copperpour not_allowed)
			(footprints allowed)
		)
		(placement
			(enabled no)
			(sheetname "")
		)
		(fill
			(thermal_gap 0.5)
			(thermal_bridge_width 0.5)
			(island_removal_mode 0)
		)
		(polygon
			(pts
				(xy 411.715712 -2.66192) (xy 412.022036 -2.968244) (xy 412.022036 -3.11531) (xy 412.123636 -3.11531)
				(xy 412.123636 -2.968244) (xy 412.42996 -2.66192)
				(arc
					(start 412.44139 -2.66192)
					(mid 412.96468 -2.713497)
					(end 412.453328 -2.836164)
				)
				(xy 412.263336 -3.026156) (xy 412.263336 -3.11531)
				(arc
					(start 412.698438 -3.11531)
					(mid 413.082232 -2.731897)
					(end 412.698692 -2.34823)
				)
				(arc
					(start 411.428692 -2.34823)
					(mid 411.045152 -2.73177)
					(end 411.428692 -3.11531)
				)
				(xy 411.882336 -3.11531) (xy 411.882336 -3.026156)
				(arc
					(start 411.67939 -2.822956)
					(mid 411.162236 -2.721099)
					(end 411.685994 -2.66192)
				)
			)
		)
	)
	(zone
		(layer "F.Cu")
		(hatch none 0.5)
		(connect_pads
			(clearance 0)
		)
		(min_thickness 0.25)
		(keepout
			(tracks allowed)
			(vias allowed)
			(pads allowed)
			(copperpour allowed)
			(footprints allowed)
		)
		(placement
			(enabled no)
			(sheetname "")
		)
		(fill
			(thermal_gap 0.5)
			(thermal_bridge_width 0.5)
			(island_removal_mode 0)
		)
		(polygon
			(pts
				(xy 80.871568 -52.2224) (xy 85.926168 -52.2224) (xy 86.180168 -51.9684) (xy 86.180168 -49.911) (xy 80.871568 -49.911)
			)
		)
	)
	(zone
		(net "P1V05_PCH_STBY_KR_PLL")
		(layer "F.Cu")
		(hatch none 0.5)
		(connect_pads
			(clearance 0.5)
		)
		(min_thickness 0.25)
		(fill yes
			(thermal_gap 0.5)
			(thermal_bridge_width 0.5)
			(island_removal_mode 0)
		)
		(polygon
			(pts
				(xy 393.446 -112.268) (xy 392.049 -112.268) (xy 392.049 -111.379) (xy 392.176 -111.252) (xy 392.43 -110.998)
				(xy 392.97102 -110.998) (xy 393.827 -110.14202) (xy 394.09624 -110.14202) (xy 394.46708 -110.51286)
				(xy 394.46708 -111.15294) (xy 394.28928 -111.33074) (xy 394.0683 -111.33074) (xy 393.954 -111.44504)
				(xy 393.954 -111.76)
			)
		)
	)
	(zone
		(net "GND")
		(layer "F.Cu")
		(hatch none 0.5)
		(connect_pads
			(clearance 0.5)
		)
		(min_thickness 0.25)
		(fill yes
			(thermal_gap 0.5)
			(thermal_bridge_width 0.5)
			(island_removal_mode 0)
		)
		(polygon
			(pts
				(xy 96.873568 -68.1482) (xy 96.543368 -68.4784) (xy 96.543368 -70.149466) (xy 96.187768 -70.505066)
				(xy 93.224604 -70.505066) (xy 92.747592 -70.982078) (xy 92.747592 -72.251824) (xy 92.842588 -72.34682)
				(xy 107.330748 -72.34682) (xy 107.338368 -72.3392) (xy 112.418368 -72.3392) (xy 112.824768 -71.9328)
				(xy 112.824768 -70.7644) (xy 112.646968 -70.5866) (xy 109.5756 -70.5866) (xy 109.347 -70.358) (xy 108.204 -70.358)
				(xy 108.204 -69.4436) (xy 108.092748 -69.332348) (xy 100.69322 -69.332348) (xy 100.505768 -69.5198)
				(xy 100.505768 -70.3326) (xy 100.333302 -70.505066) (xy 98.727768 -70.505066) (xy 98.499168 -70.276466)
				(xy 98.499168 -68.3514) (xy 98.295968 -68.1482)
			)
		)
		(polygon
			(pts
				(xy 112.46104 -71.375016) (xy 112.25784 -71.375016) (xy 112.25784 -71.578216) (xy 112.46104 -71.578216)
			)
		)
		(polygon
			(pts
				(xy 111.69904 -71.375016) (xy 111.49584 -71.375016) (xy 111.49584 -71.578216) (xy 111.69904 -71.578216)
			)
		)
		(polygon
			(pts
				(xy 111.19104 -71.375016) (xy 110.98784 -71.375016) (xy 110.98784 -71.578216) (xy 111.19104 -71.578216)
			)
		)
		(polygon
			(pts
				(xy 110.42904 -71.375016) (xy 110.22584 -71.375016) (xy 110.22584 -71.578216) (xy 110.42904 -71.578216)
			)
		)
		(polygon
			(pts
				(xy 109.92104 -71.375016) (xy 109.71784 -71.375016) (xy 109.71784 -71.578216) (xy 109.92104 -71.578216)
			)
		)
		(polygon
			(pts
				(xy 109.15904 -71.375016) (xy 108.95584 -71.375016) (xy 108.95584 -71.578216) (xy 109.15904 -71.578216)
			)
		)
		(polygon
			(pts
				(xy 108.65104 -71.375016) (xy 108.44784 -71.375016) (xy 108.44784 -71.578216) (xy 108.65104 -71.578216)
			)
		)
		(polygon
			(pts
				(xy 107.88904 -71.375016) (xy 107.68584 -71.375016) (xy 107.68584 -71.578216) (xy 107.88904 -71.578216)
			)
		)
		(polygon
			(pts
				(xy 103.64724 -71.375016) (xy 103.44404 -71.375016) (xy 103.44404 -71.578216) (xy 103.64724 -71.578216)
			)
		)
		(polygon
			(pts
				(xy 102.88524 -71.375016) (xy 102.68204 -71.375016) (xy 102.68204 -71.578216) (xy 102.88524 -71.578216)
			)
		)
		(polygon
			(pts
				(xy 102.40264 -71.375016) (xy 102.19944 -71.375016) (xy 102.19944 -71.578216) (xy 102.40264 -71.578216)
			)
		)
		(polygon
			(pts
				(xy 101.64064 -71.375016) (xy 101.43744 -71.375016) (xy 101.43744 -71.578216) (xy 101.64064 -71.578216)
			)
		)
		(polygon
			(pts
				(xy 101.15804 -71.375016) (xy 100.95484 -71.375016) (xy 100.95484 -71.578216) (xy 101.15804 -71.578216)
			)
		)
		(polygon
			(pts
				(xy 100.39604 -71.375016) (xy 100.19284 -71.375016) (xy 100.19284 -71.578216) (xy 100.39604 -71.578216)
			)
		)
		(polygon
			(pts
				(xy 99.91344 -71.375016) (xy 99.71024 -71.375016) (xy 99.71024 -71.578216) (xy 99.91344 -71.578216)
			)
		)
		(polygon
			(pts
				(xy 99.15144 -71.375016) (xy 98.94824 -71.375016) (xy 98.94824 -71.578216) (xy 99.15144 -71.578216)
			)
		)
		(polygon
			(pts
				(xy 98.66884 -71.375016) (xy 98.46564 -71.375016) (xy 98.46564 -71.578216) (xy 98.66884 -71.578216)
			)
		)
		(polygon
			(pts
				(xy 97.90684 -71.375016) (xy 97.70364 -71.375016) (xy 97.70364 -71.578216) (xy 97.90684 -71.578216)
			)
		)
		(polygon
			(pts
				(xy 97.42424 -71.375016) (xy 97.22104 -71.375016) (xy 97.22104 -71.578216) (xy 97.42424 -71.578216)
			)
		)
		(polygon
			(pts
				(xy 96.66224 -71.375016) (xy 96.45904 -71.375016) (xy 96.45904 -71.578216) (xy 96.66224 -71.578216)
			)
		)
		(polygon
			(pts
				(xy 96.17964 -71.375016) (xy 95.97644 -71.375016) (xy 95.97644 -71.578216) (xy 96.17964 -71.578216)
			)
		)
		(polygon
			(pts
				(xy 95.41764 -71.375016) (xy 95.21444 -71.375016) (xy 95.21444 -71.578216) (xy 95.41764 -71.578216)
			)
		)
		(polygon
			(pts
				(xy 94.93504 -71.375016) (xy 94.73184 -71.375016) (xy 94.73184 -71.578216) (xy 94.93504 -71.578216)
			)
		)
		(polygon
			(pts
				(xy 94.17304 -71.375016) (xy 93.96984 -71.375016) (xy 93.96984 -71.578216) (xy 94.17304 -71.578216)
			)
		)
		(polygon
			(pts
				(xy 93.69044 -71.375016) (xy 93.48724 -71.375016) (xy 93.48724 -71.578216) (xy 93.69044 -71.578216)
			)
		)
		(polygon
			(pts
				(xy 107.38104 -71.3359) (xy 107.17784 -71.3359) (xy 107.17784 -71.5391) (xy 107.38104 -71.5391)
			)
		)
		(polygon
			(pts
				(xy 106.61904 -71.3359) (xy 106.41584 -71.3359) (xy 106.41584 -71.5391) (xy 106.61904 -71.5391)
			)
		)
		(polygon
			(pts
				(xy 106.11104 -71.3359) (xy 105.90784 -71.3359) (xy 105.90784 -71.5391) (xy 106.11104 -71.5391)
			)
		)
		(polygon
			(pts
				(xy 105.34904 -71.3359) (xy 105.14584 -71.3359) (xy 105.14584 -71.5391) (xy 105.34904 -71.5391)
			)
		)
		(polygon
			(pts
				(xy 104.84104 -71.3359) (xy 104.63784 -71.3359) (xy 104.63784 -71.5391) (xy 104.84104 -71.5391)
			)
		)
		(polygon
			(pts
				(xy 104.07904 -71.3359) (xy 103.87584 -71.3359) (xy 103.87584 -71.5391) (xy 104.07904 -71.5391)
			)
		)
		(polygon
			(pts
				(xy 97.713292 -70.165214) (xy 97.510092 -70.165214) (xy 97.510092 -70.368414) (xy 97.713292 -70.368414)
			)
		)
		(polygon
			(pts
				(xy 102.628192 -70.152514) (xy 102.424992 -70.152514) (xy 102.424992 -70.355714) (xy 102.628192 -70.355714)
			)
		)
		(polygon
			(pts
				(xy 101.866192 -70.152514) (xy 101.662992 -70.152514) (xy 101.662992 -70.355714) (xy 101.866192 -70.355714)
			)
		)
		(polygon
			(pts
				(xy 101.385624 -70.152514) (xy 101.182424 -70.152514) (xy 101.182424 -70.355714) (xy 101.385624 -70.355714)
			)
		)
		(polygon
			(pts
				(xy 107.617006 -70.105016) (xy 107.413806 -70.105016) (xy 107.413806 -70.308216) (xy 107.617006 -70.308216)
			)
		)
		(polygon
			(pts
				(xy 106.855006 -70.105016) (xy 106.651806 -70.105016) (xy 106.651806 -70.308216) (xy 106.855006 -70.308216)
			)
		)
		(polygon
			(pts
				(xy 106.372406 -70.105016) (xy 106.169206 -70.105016) (xy 106.169206 -70.308216) (xy 106.372406 -70.308216)
			)
		)
		(polygon
			(pts
				(xy 105.610406 -70.105016) (xy 105.407206 -70.105016) (xy 105.407206 -70.308216) (xy 105.610406 -70.308216)
			)
		)
		(polygon
			(pts
				(xy 105.127806 -70.105016) (xy 104.924606 -70.105016) (xy 104.924606 -70.308216) (xy 105.127806 -70.308216)
			)
		)
		(polygon
			(pts
				(xy 104.365806 -70.105016) (xy 104.162606 -70.105016) (xy 104.162606 -70.308216) (xy 104.365806 -70.308216)
			)
		)
		(polygon
			(pts
				(xy 103.883206 -70.105016) (xy 103.680006 -70.105016) (xy 103.680006 -70.308216) (xy 103.883206 -70.308216)
			)
		)
		(polygon
			(pts
				(xy 103.121206 -70.105016) (xy 102.918006 -70.105016) (xy 102.918006 -70.308216) (xy 103.121206 -70.308216)
			)
		)
		(polygon
			(pts
				(xy 97.713292 -69.403214) (xy 97.510092 -69.403214) (xy 97.510092 -69.606414) (xy 97.713292 -69.606414)
			)
		)
		(polygon
			(pts
				(xy 97.715324 -68.920614) (xy 97.512124 -68.920614) (xy 97.512124 -69.123814) (xy 97.715324 -69.123814)
			)
		)
	)
	(zone
		(net "VR_PVDDQ_GHJ_PH2_SW")
		(layer "F.Cu")
		(hatch none 0.5)
		(connect_pads
			(clearance 0.5)
		)
		(min_thickness 0.25)
		(fill yes
			(thermal_gap 0.5)
			(thermal_bridge_width 0.5)
			(island_removal_mode 0)
		)
		(polygon
			(pts
				(xy 7.5184 -15.3416) (xy 7.5184 -19.5326) (xy 7.6454 -19.6596) (xy 8.255 -19.6596) (xy 8.4074 -19.5072)
				(xy 10.8204 -19.5072) (xy 11.5824 -18.7452) (xy 12.6746 -18.7452) (xy 12.954 -18.4658) (xy 12.954 -15.3924)
				(xy 12.192 -14.6304) (xy 11.753596 -14.191996) (xy 11.3538 -13.7922) (xy 11.3284 -13.7922) (xy 11.136122 -13.599922)
				(xy 9.04494 -13.599922) (xy 8.802878 -13.599922) (xy 8.801862 -13.598906) (xy 8.45058 -13.598906)
				(xy 7.620508 -14.428978) (xy 7.620508 -14.782292) (xy 7.5184 -14.8844)
			)
		)
	)
	(zone
		(layer "F.Cu")
		(hatch none 0.5)
		(connect_pads
			(clearance 0)
		)
		(min_thickness 0.25)
		(keepout
			(tracks allowed)
			(vias allowed)
			(pads allowed)
			(copperpour allowed)
			(footprints allowed)
		)
		(placement
			(enabled no)
			(sheetname "")
		)
		(fill
			(thermal_gap 0.5)
			(thermal_bridge_width 0.5)
			(island_removal_mode 0)
		)
		(polygon
			(pts
				(xy 29.083 -58.42) (xy 29.083 -54.864) (xy 31.242 -54.864) (xy 31.242 -58.42)
			)
		)
	)
	(zone
		(net "P12V_STBY")
		(layer "F.Cu")
		(hatch none 0.5)
		(connect_pads
			(clearance 0.5)
		)
		(min_thickness 0.25)
		(fill yes
			(thermal_gap 0.5)
			(thermal_bridge_width 0.5)
			(island_removal_mode 0)
		)
		(polygon
			(pts
				(xy 184.9882 -140.5382) (xy 184.9882 -139.6746) (xy 184.658 -139.3444) (xy 184.658 -137.7442) (xy 184.6834 -137.7188)
				(xy 186.0296 -137.7188) (xy 186.2582 -137.9474) (xy 186.2582 -141.34846) (xy 185.81116 -141.7955)
				(xy 185.155586 -141.7955) (xy 184.9882 -141.628114)
			)
		)
	)
	(zone
		(layer "F.Cu")
		(hatch none 0.5)
		(connect_pads
			(clearance 0)
		)
		(min_thickness 0.25)
		(keepout
			(tracks not_allowed)
			(vias allowed)
			(pads allowed)
			(copperpour not_allowed)
			(footprints allowed)
		)
		(placement
			(enabled no)
			(sheetname "")
		)
		(fill
			(thermal_gap 0.5)
			(thermal_bridge_width 0.5)
			(island_removal_mode 0)
		)
		(polygon
			(pts
				(arc
					(start 198.930006 -50.099976)
					(mid 195.380102 -46.550072)
					(end 198.930006 -42.999914)
				)
				(arc
					(start 198.930006 -42.999914)
					(mid 202.480164 -46.550072)
					(end 198.930006 -50.099976)
				)
			)
		)
	)
	(zone
		(layer "F.Cu")
		(hatch none 0.5)
		(connect_pads
			(clearance 0)
		)
		(min_thickness 0.25)
		(keepout
			(tracks allowed)
			(vias allowed)
			(pads allowed)
			(copperpour allowed)
			(footprints allowed)
		)
		(placement
			(enabled no)
			(sheetname "")
		)
		(fill
			(thermal_gap 0.5)
			(thermal_bridge_width 0.5)
			(island_removal_mode 0)
		)
		(polygon
			(pts
				(xy 379.095 -154.051) (xy 379.095 -153.416) (xy 379.857 -153.416) (xy 379.857 -154.051)
			)
		)
	)
	(zone
		(layer "F.Cu")
		(hatch none 0.5)
		(connect_pads
			(clearance 0)
		)
		(min_thickness 0.25)
		(keepout
			(tracks allowed)
			(vias allowed)
			(pads allowed)
			(copperpour allowed)
			(footprints allowed)
		)
		(placement
			(enabled no)
			(sheetname "")
		)
		(fill
			(thermal_gap 0.5)
			(thermal_bridge_width 0.5)
			(island_removal_mode 0)
		)
		(polygon
			(pts
				(xy 245.872 -52.2224) (xy 250.9266 -52.2224) (xy 250.9266 -54.1274) (xy 249.3264 -55.7276) (xy 246.9388 -55.7276)
				(xy 245.872 -54.6608)
			)
		)
	)
	(zone
		(net "GND")
		(layer "F.Cu")
		(hatch none 0.5)
		(connect_pads
			(clearance 0.5)
		)
		(min_thickness 0.25)
		(fill yes
			(thermal_gap 0.5)
			(thermal_bridge_width 0.5)
			(island_removal_mode 0)
		)
		(polygon
			(pts
				(xy 29.3624 -42.62882) (xy 29.49702 -42.4942) (xy 30.4292 -42.4942) (xy 30.5562 -42.6212) (xy 30.5562 -42.8244)
				(xy 30.55493 -42.8244) (xy 30.55493 -45.3898) (xy 30.55493 -46.53407) (xy 30.353 -46.736) (xy 30.2006 -46.8884)
				(xy 28.2448 -46.8884) (xy 28.010104 -46.653704) (xy 27.96286 -46.60646) (xy 27.96286 -42.766742)
				(xy 27.980386 -42.749216) (xy 29.242004 -42.749216)
			)
		)
	)
	(zone
		(layer "F.Cu")
		(hatch none 0.5)
		(connect_pads
			(clearance 0)
		)
		(min_thickness 0.25)
		(keepout
			(tracks not_allowed)
			(vias allowed)
			(pads allowed)
			(copperpour not_allowed)
			(footprints allowed)
		)
		(placement
			(enabled no)
			(sheetname "")
		)
		(fill
			(thermal_gap 0.5)
			(thermal_bridge_width 0.5)
			(island_removal_mode 0)
		)
		(polygon
			(pts
				(xy 380.56312 -130.713988)
				(arc
					(start 380.56312 -130.834384)
					(mid 380.50597 -131.361785)
					(end 380.44882 -130.834384)
				)
				(arc
					(start 380.44882 -130.718306)
					(mid 380.126056 -131.123644)
					(end 380.50597 -131.475988)
				)
				(arc
					(start 381.16637 -131.475988)
					(mid 381.52216 -131.231275)
					(end 381.420878 -130.811524)
				)
				(arc
					(start 381.420878 -131.015232)
					(mid 380.955737 -131.258601)
					(end 381.306578 -130.868166)
				)
				(arc
					(start 381.306578 -130.802888)
					(mid 381.298582 -130.76333)
					(end 381.275844 -130.72999)
				)
				(arc
					(start 381.275844 -130.72999)
					(mid 381.221691 -130.718)
					(end 381.16637 -130.713988)
				)
			)
		)
	)
	(zone
		(layer "F.Cu")
		(hatch none 0.5)
		(connect_pads
			(clearance 0)
		)
		(min_thickness 0.25)
		(keepout
			(tracks not_allowed)
			(vias allowed)
			(pads allowed)
			(copperpour not_allowed)
			(footprints allowed)
		)
		(placement
			(enabled no)
			(sheetname "")
		)
		(fill
			(thermal_gap 0.5)
			(thermal_bridge_width 0.5)
			(island_removal_mode 0)
		)
		(polygon
			(pts
				(arc
					(start 442.919866 -44.7675)
					(mid 443.443783 -44.83735)
					(end 442.919866 -44.9072)
				)
				(xy 442.87313 -44.9072) (xy 442.732668 -45.047662) (xy 442.732668 -45.22089)
				(arc
					(start 443.177168 -45.22089)
					(mid 443.560708 -44.83735)
					(end 443.177168 -44.45381)
				)
				(arc
					(start 441.907422 -44.45381)
					(mid 441.523882 -44.837223)
					(end 441.907168 -45.22089)
				)
				(xy 442.351668 -45.22089) (xy 442.351668 -45.047662) (xy 442.211206 -44.9072)
				(arc
					(start 442.16447 -44.9072)
					(mid 441.640553 -44.83735)
					(end 442.16447 -44.7675)
				)
				(xy 442.269118 -44.7675) (xy 442.491368 -44.98975) (xy 442.491368 -45.22089) (xy 442.592968 -45.22089)
				(xy 442.592968 -44.98975) (xy 442.815218 -44.7675)
			)
		)
	)
	(zone
		(layer "F.Cu")
		(hatch none 0.5)
		(connect_pads
			(clearance 0)
		)
		(min_thickness 0.25)
		(keepout
			(tracks allowed)
			(vias allowed)
			(pads allowed)
			(copperpour allowed)
			(footprints allowed)
		)
		(placement
			(enabled no)
			(sheetname "")
		)
		(fill
			(thermal_gap 0.5)
			(thermal_bridge_width 0.5)
			(island_removal_mode 0)
		)
		(polygon
			(pts
				(xy 117.574568 -24.511) (xy 117.574568 -22.479) (xy 119.733568 -22.479) (xy 119.733568 -24.511)
			)
		)
	)
	(zone
		(net "GND")
		(layer "F.Cu")
		(hatch none 0.5)
		(connect_pads
			(clearance 0.5)
		)
		(min_thickness 0.25)
		(fill yes
			(thermal_gap 0.5)
			(thermal_bridge_width 0.5)
			(island_removal_mode 0)
		)
		(polygon
			(pts
				(xy 471.3478 -23.5712) (xy 473.81541 -23.5712) (xy 474.090746 -23.295864) (xy 474.998288 -23.295864)
				(xy 475.5134 -22.780752) (xy 475.5134 -22.6314) (xy 475.615 -22.5298) (xy 478.14992 -22.5298) (xy 479.423476 -21.256244)
				(xy 479.433636 -21.256244) (xy 479.530156 -21.256244) (xy 479.719386 -21.256244) (xy 482.934772 -21.256244)
				(xy 484.087424 -22.408896) (xy 484.752904 -22.408896) (xy 485.0384 -22.1234) (xy 485.0384 -20.2438)
				(xy 484.6574 -19.8628) (xy 483.865428 -19.8628) (xy 483.74427 -19.983958) (xy 483.310692 -19.983958)
				(xy 482.952552 -19.625818) (xy 481.481638 -19.625818) (xy 481.234242 -19.625818) (xy 481.015294 -19.40687)
				(xy 481.015294 -19.248882) (xy 480.951286 -19.184874) (xy 479.25355 -19.184874) (xy 478.575624 -19.8628)
				(xy 478.555304 -19.88312) (xy 476.794068 -19.88312) (xy 476.79356 -19.882612) (xy 475.696788 -19.882612)
				(xy 475.0562 -20.5232) (xy 474.4974 -21.082) (xy 471.9574 -21.082) (xy 471.8812 -21.1582) (xy 471.8812 -21.6662)
				(xy 471.7796 -21.7678) (xy 471.357452 -21.7678) (xy 471.2462 -21.879052) (xy 471.174826 -21.950426)
				(xy 471.174826 -23.398226)
			)
		)
	)
	(zone
		(layer "F.Cu")
		(hatch none 0.5)
		(connect_pads
			(clearance 0)
		)
		(min_thickness 0.25)
		(keepout
			(tracks not_allowed)
			(vias allowed)
			(pads allowed)
			(copperpour not_allowed)
			(footprints allowed)
		)
		(placement
			(enabled no)
			(sheetname "")
		)
		(fill
			(thermal_gap 0.5)
			(thermal_bridge_width 0.5)
			(island_removal_mode 0)
		)
		(polygon
			(pts
				(arc
					(start 127 -39.010082)
					(mid 129.54 -41.550082)
					(end 127 -44.090082)
				)
				(arc
					(start 127 -44.090082)
					(mid 124.46 -41.550082)
					(end 127 -39.010082)
				)
			)
		)
	)
	(zone
		(net "VR_PVDDQ_ABC_VDD")
		(layer "F.Cu")
		(hatch none 0.5)
		(connect_pads
			(clearance 0.5)
		)
		(min_thickness 0.25)
		(fill yes
			(thermal_gap 0.5)
			(thermal_bridge_width 0.5)
			(island_removal_mode 0)
		)
		(polygon
			(pts
				(xy 346.8624 -16.6878) (xy 347.7006 -16.6878) (xy 347.8276 -16.8148) (xy 348.3356 -16.8148) (xy 348.8182 -17.2974)
				(xy 349.4278 -17.2974) (xy 350.2152 -17.2974) (xy 350.3041 -17.3863) (xy 350.3041 -17.9959) (xy 350.266 -18.034)
				(xy 347.98 -18.034) (xy 347.599 -17.653) (xy 347.599 -16.9418) (xy 347.5228 -16.8656) (xy 346.8878 -16.8656)
				(xy 346.8116 -16.7894) (xy 346.8116 -16.7386)
			)
		)
	)
	(zone
		(net "GND")
		(layer "F.Cu")
		(hatch none 0.5)
		(connect_pads
			(clearance 0.5)
		)
		(min_thickness 0.25)
		(fill yes
			(thermal_gap 0.5)
			(thermal_bridge_width 0.5)
			(island_removal_mode 0)
		)
		(polygon
			(pts
				(xy 279.817068 -150.992078) (xy 278.43734 -150.992078) (xy 278.374856 -150.92934) (xy 278.35987 -150.914354)
				(xy 278.35987 -150.604474) (xy 278.23033 -150.474934) (xy 278.23033 -150.46198) (xy 278.23033 -148.578062)
				(xy 278.43734 -148.371052) (xy 279.861264 -148.371052) (xy 280.06167 -148.571458) (xy 280.06167 -150.747476)
			)
		)
	)
	(zone
		(layer "F.Cu")
		(hatch none 0.5)
		(connect_pads
			(clearance 0)
		)
		(min_thickness 0.25)
		(keepout
			(tracks allowed)
			(vias allowed)
			(pads allowed)
			(copperpour allowed)
			(footprints allowed)
		)
		(placement
			(enabled no)
			(sheetname "")
		)
		(fill
			(thermal_gap 0.5)
			(thermal_bridge_width 0.5)
			(island_removal_mode 0)
		)
		(polygon
			(pts
				(xy 168.6052 -4.4704) (xy 169.5323 -4.4704) (xy 169.5323 -6.25475) (xy 168.6052 -6.25475)
			)
		)
	)
	(zone
		(layer "F.Cu")
		(hatch none 0.5)
		(connect_pads
			(clearance 0)
		)
		(min_thickness 0.25)
		(keepout
			(tracks allowed)
			(vias allowed)
			(pads allowed)
			(copperpour allowed)
			(footprints allowed)
		)
		(placement
			(enabled no)
			(sheetname "")
		)
		(fill
			(thermal_gap 0.5)
			(thermal_bridge_width 0.5)
			(island_removal_mode 0)
		)
		(polygon
			(pts
				(xy 396.3924 -154.305) (xy 396.3924 -152.3746) (xy 399.3642 -152.3746) (xy 399.3642 -154.305)
			)
		)
	)
	(zone
		(layer "F.Cu")
		(hatch none 0.5)
		(connect_pads
			(clearance 0)
		)
		(min_thickness 0.25)
		(keepout
			(tracks not_allowed)
			(vias allowed)
			(pads allowed)
			(copperpour not_allowed)
			(footprints allowed)
		)
		(placement
			(enabled no)
			(sheetname "")
		)
		(fill
			(thermal_gap 0.5)
			(thermal_bridge_width 0.5)
			(island_removal_mode 0)
		)
		(polygon
			(pts
				(arc
					(start 447.71437 -49.928272)
					(mid 448.238287 -49.998122)
					(end 447.71437 -50.067972)
				)
				(xy 447.600578 -50.067972) (xy 447.52006 -50.14849) (xy 447.52006 -50.381662)
				(arc
					(start 447.971418 -50.381662)
					(mid 448.355212 -49.998249)
					(end 447.971672 -49.614582)
				)
				(arc
					(start 446.701672 -49.614582)
					(mid 446.318132 -49.998122)
					(end 446.701672 -50.381662)
				)
				(xy 447.13906 -50.381662) (xy 447.13906 -50.141378) (xy 447.065654 -50.067972)
				(arc
					(start 446.958974 -50.067972)
					(mid 446.435057 -49.998122)
					(end 446.958974 -49.928272)
				)
				(xy 447.123566 -49.928272) (xy 447.27876 -50.083466) (xy 447.27876 -50.381662) (xy 447.38036 -50.381662)
				(xy 447.38036 -50.090578) (xy 447.542666 -49.928272)
			)
		)
	)
	(zone
		(layer "F.Cu")
		(hatch none 0.5)
		(connect_pads
			(clearance 0)
		)
		(min_thickness 0.25)
		(keepout
			(tracks not_allowed)
			(vias allowed)
			(pads allowed)
			(copperpour not_allowed)
			(footprints allowed)
		)
		(placement
			(enabled no)
			(sheetname "")
		)
		(fill
			(thermal_gap 0.5)
			(thermal_bridge_width 0.5)
			(island_removal_mode 0)
		)
		(polygon
			(pts
				(xy 361.934252 -3.320542) (xy 361.934252 -3.046476) (xy 362.113576 -2.867152)
				(arc
					(start 362.312966 -2.867152)
					(mid 362.836883 -2.937002)
					(end 362.312966 -3.006852)
				)
				(xy 362.171488 -3.006852) (xy 362.073952 -3.104388) (xy 362.073952 -3.320542)
				(arc
					(start 362.570014 -3.320542)
					(mid 362.953808 -2.937129)
					(end 362.570268 -2.553462)
				)
				(arc
					(start 361.300268 -2.553462)
					(mid 360.916728 -2.937002)
					(end 361.300268 -3.320542)
				)
				(xy 361.692952 -3.320542) (xy 361.692952 -3.080512) (xy 361.619292 -3.006852)
				(arc
					(start 361.55757 -3.006852)
					(mid 361.033653 -2.937002)
					(end 361.55757 -2.867152)
				)
				(xy 361.677204 -2.867152) (xy 361.832652 -3.0226) (xy 361.832652 -3.320542)
			)
		)
	)
	(zone
		(net "VR_PVCCIN_CPU1_VDD")
		(layer "F.Cu")
		(hatch none 0.5)
		(connect_pads
			(clearance 0.5)
		)
		(min_thickness 0.25)
		(fill yes
			(thermal_gap 0.5)
			(thermal_bridge_width 0.5)
			(island_removal_mode 0)
		)
		(polygon
			(pts
				(xy 17.29105 -95.96755) (xy 16.129 -97.1296) (xy 16.129 -98.1456) (xy 15.8496 -98.425) (xy 15.8496 -98.9584)
				(xy 15.6972 -99.1108) (xy 15.494 -99.1108) (xy 15.3162 -99.2886) (xy 15.3162 -99.855274) (xy 15.3162 -99.864418)
				(xy 15.375382 -99.9236) (xy 15.395956 -99.9236) (xy 15.9004 -99.9236) (xy 15.9766 -99.8474) (xy 15.9766 -99.3648)
				(xy 16.383 -98.9584) (xy 16.637 -98.9584) (xy 16.6624 -98.933) (xy 16.6624 -97.6376) (xy 17.702022 -96.597978)
				(xy 17.702022 -95.110554) (xy 17.681956 -95.090488) (xy 17.610074 -95.090488) (xy 17.5895 -95.111062)
				(xy 17.5895 -95.758) (xy 17.5895 -95.767144) (xy 17.389094 -95.96755) (xy 17.37995 -95.96755)
			)
		)
	)
	(zone
		(layer "F.Cu")
		(hatch none 0.5)
		(connect_pads
			(clearance 0)
		)
		(min_thickness 0.25)
		(keepout
			(tracks allowed)
			(vias allowed)
			(pads allowed)
			(copperpour allowed)
			(footprints not_allowed)
		)
		(placement
			(enabled no)
			(sheetname "")
		)
		(fill
			(thermal_gap 0.5)
			(thermal_bridge_width 0.5)
			(island_removal_mode 0)
		)
		(polygon
			(pts
				(arc
					(start 177.42535 -151.593804)
					(mid 176.493849 -151.22543)
					(end 175.50003 -151.100028)
				)
				(xy 173.624494 -151.100028) (xy 173.624494 -130.16611) (xy 177.42535 -130.16611)
			)
		)
	)
	(zone
		(layer "F.Cu")
		(hatch none 0.5)
		(connect_pads
			(clearance 0)
		)
		(min_thickness 0.25)
		(keepout
			(tracks allowed)
			(vias allowed)
			(pads allowed)
			(copperpour allowed)
			(footprints not_allowed)
		)
		(placement
			(enabled no)
			(sheetname "")
		)
		(fill
			(thermal_gap 0.5)
			(thermal_bridge_width 0.5)
			(island_removal_mode 0)
		)
		(polygon
			(pts
				(xy 163.524692 5.999988) (xy 167.124634 5.999988) (xy 167.124634 -22.919182) (xy 163.524692 -22.919182)
			)
		)
	)
	(zone
		(layer "F.Cu")
		(hatch none 0.5)
		(connect_pads
			(clearance 0)
		)
		(min_thickness 0.25)
		(keepout
			(tracks allowed)
			(vias allowed)
			(pads allowed)
			(copperpour allowed)
			(footprints not_allowed)
		)
		(placement
			(enabled no)
			(sheetname "")
		)
		(fill
			(thermal_gap 0.5)
			(thermal_bridge_width 0.5)
			(island_removal_mode 0)
		)
		(polygon
			(pts
				(xy 22.52472 -159.100012) (xy 22.52472 -130.16611) (xy 18.924524 -130.16611) (xy 18.924524 -159.100012)
			)
		)
	)
	(zone
		(layer "F.Cu")
		(hatch none 0.5)
		(connect_pads
			(clearance 0)
		)
		(min_thickness 0.25)
		(keepout
			(tracks allowed)
			(vias allowed)
			(pads allowed)
			(copperpour allowed)
			(footprints allowed)
		)
		(placement
			(enabled no)
			(sheetname "")
		)
		(fill
			(thermal_gap 0.5)
			(thermal_bridge_width 0.5)
			(island_removal_mode 0)
		)
		(polygon
			(pts
				(xy 1.524 -142.494) (xy 1.524 -141.097) (xy 2.794 -141.097) (xy 2.794 -142.494)
			)
		)
	)
	(zone
		(net "VR_FET_SW_P5V_STBY_PVIN")
		(layer "F.Cu")
		(hatch none 0.5)
		(connect_pads
			(clearance 0.5)
		)
		(min_thickness 0.25)
		(fill yes
			(thermal_gap 0.5)
			(thermal_bridge_width 0.5)
			(island_removal_mode 0)
		)
		(polygon
			(pts
				(xy 383.8702 -68.58) (xy 388.848092 -68.58) (xy 389.6106 -67.817492) (xy 390.046972 -67.817492)
				(xy 390.8806 -67.817492) (xy 390.906 -67.792092) (xy 390.906 -67.10934) (xy 390.883902 -67.087242)
				(xy 389.85317 -67.087242) (xy 389.744458 -66.97853) (xy 389.744458 -66.82613) (xy 389.744458 -66.181732)
				(xy 389.630158 -66.067432) (xy 389.408162 -66.067432) (xy 389.404606 -66.070988) (xy 388.871968 -66.070988)
				(xy 388.81558 -66.0146) (xy 388.33298 -65.532) (xy 383.43332 -65.532) (xy 383.407412 -65.557908)
				(xy 383.407412 -68.117212)
			)
		)
	)
	(zone
		(layer "F.Cu")
		(hatch none 0.5)
		(connect_pads
			(clearance 0)
		)
		(min_thickness 0.25)
		(keepout
			(tracks allowed)
			(vias allowed)
			(pads allowed)
			(copperpour allowed)
			(footprints allowed)
		)
		(placement
			(enabled no)
			(sheetname "")
		)
		(fill
			(thermal_gap 0.5)
			(thermal_bridge_width 0.5)
			(island_removal_mode 0)
		)
		(polygon
			(pts
				(xy 282.575 -24.511) (xy 282.575 -22.479) (xy 284.734 -22.479) (xy 284.734 -24.511)
			)
		)
	)
	(zone
		(net "GND")
		(layer "F.Cu")
		(hatch none 0.5)
		(connect_pads
			(clearance 0.5)
		)
		(min_thickness 0.25)
		(fill yes
			(thermal_gap 0.5)
			(thermal_bridge_width 0.5)
			(island_removal_mode 0)
		)
		(polygon
			(pts
				(xy 278.946102 -4.787138) (xy 278.307038 -4.14782) (xy 278.307038 -2.516886) (xy 278.376888 -2.447036)
				(xy 278.473154 -2.447036) (xy 278.509984 -2.483866) (xy 278.509984 -2.634742) (xy 278.479504 -2.665222)
				(xy 278.479504 -2.977388) (xy 278.694134 -3.192018) (xy 279.005284 -3.192018) (xy 279.229312 -2.96799)
				(xy 279.229312 -2.669794) (xy 279.192482 -2.632964) (xy 279.192482 -1.936496) (xy 279.269698 -1.85928)
				(xy 279.66162 -1.85928) (xy 280.0858 -2.283714) (xy 280.0858 -3.37566) (xy 280.094182 -3.384042)
				(xy 280.169874 -3.459734) (xy 280.700734 -3.459734) (xy 280.8478 -3.6068) (xy 280.8478 -3.9116)
				(xy 280.611326 -4.148074) (xy 280.131774 -4.148074) (xy 280.016966 -4.148074) (xy 280.016966 -4.183634)
				(xy 279.413462 -4.787138)
			)
		)
	)
	(zone
		(net "GND")
		(layer "F.Cu")
		(hatch none 0.5)
		(connect_pads
			(clearance 0.5)
		)
		(min_thickness 0.25)
		(fill yes
			(thermal_gap 0.5)
			(thermal_bridge_width 0.5)
			(island_removal_mode 0)
		)
		(polygon
			(pts
				(xy 176.315624 -15.835376) (xy 176.403 -15.748) (xy 179.959 -15.748) (xy 180.086 -15.621) (xy 180.086 -13.589)
				(xy 180.086 -13.551408) (xy 180.174646 -13.462762) (xy 181.482238 -13.462762) (xy 181.505098 -13.439902)
				(xy 181.605682 -13.339318) (xy 181.609746 -13.335254) (xy 181.672484 -13.272516) (xy 182.23103 -13.272516)
				(xy 182.252366 -13.293852) (xy 182.252366 -13.342366) (xy 182.252366 -13.378942) (xy 182.252366 -13.843)
				(xy 182.252366 -14.231366) (xy 182.372 -14.351) (xy 182.374032 -14.353032) (xy 182.630572 -14.609572)
				(xy 183.91759 -14.609572) (xy 184.032906 -14.724888) (xy 184.032906 -15.630906) (xy 184.15 -15.748)
				(xy 184.785 -16.383) (xy 184.785 -17.78) (xy 184.785 -18.058384) (xy 183.120792 -19.722592) (xy 182.752492 -19.722592)
				(xy 182.735728 -19.722592) (xy 181.783736 -18.7706) (xy 181.734714 -18.721578) (xy 181.333648 -18.721578)
				(xy 181.037992 -19.017234) (xy 181.037992 -19.432524) (xy 181.344316 -19.738848) (xy 181.436264 -19.830796)
				(xy 181.437026 -19.830796) (xy 181.437026 -19.896582) (xy 181.394608 -19.939) (xy 181.394608 -19.962876)
				(xy 181.646576 -20.214844) (xy 182.14213 -20.214844) (xy 182.288688 -20.361402) (xy 182.288688 -20.554696)
				(xy 181.40934 -21.434044) (xy 180.704744 -21.434044) (xy 180.403246 -21.132546) (xy 180.36794 -21.132546)
				(xy 179.6288 -21.132546) (xy 178.552094 -22.209252) (xy 178.452526 -22.209252) (xy 178.011328 -22.209252)
				(xy 177.155348 -22.209252) (xy 176.657 -22.7076) (xy 176.657 -23.241) (xy 176.853596 -23.437596)
				(xy 177.518568 -23.437596) (xy 179.263802 -23.437596) (xy 179.95011 -24.123904) (xy 181.178962 -24.123904)
				(xy 181.232048 -24.17699) (xy 181.232048 -24.650446) (xy 181.168294 -24.7142) (xy 179.584858 -24.7142)
				(xy 178.89982 -24.029162) (xy 177.296572 -24.029162) (xy 176.953164 -24.029162) (xy 176.39919 -23.475188)
				(xy 176.39919 -23.348442) (xy 176.155096 -23.104348) (xy 175.041052 -23.104348) (xy 174.9806 -23.1648)
				(xy 174.879 -23.2664) (xy 174.879 -25.273) (xy 175.0314 -25.4254) (xy 175.0314 -28.2956) (xy 174.6504 -28.6766)
				(xy 171.069 -28.6766) (xy 170.688 -28.2956) (xy 170.688 -27.4574) (xy 170.688 -21.717) (xy 170.688 -18.669)
				(xy 170.942 -18.415) (xy 171.106338 -18.250662) (xy 176.79162 -18.250662) (xy 177.08245 -17.959832)
				(xy 177.08245 -17.402048) (xy 176.96053 -17.279874) (xy 176.435258 -17.279874) (xy 176.269396 -17.114012)
				(xy 176.269396 -16.78813) (xy 176.315624 -16.741902) (xy 176.315624 -16.59001)
			)
		)
	)
	(zone
		(net "GND")
		(layer "F.Cu")
		(hatch none 0.5)
		(connect_pads
			(clearance 0.5)
		)
		(min_thickness 0.25)
		(fill yes
			(thermal_gap 0.5)
			(thermal_bridge_width 0.5)
			(island_removal_mode 0)
		)
		(polygon
			(pts
				(xy 350.96958 -131.06908) (xy 351.29089 -130.74777) (xy 351.29089 -130.747262) (xy 351.406206 -130.631946)
				(xy 351.406206 -129.361184) (xy 351.487994 -129.279396) (xy 352.612452 -129.279396) (xy 352.764598 -129.431542)
				(xy 352.764598 -131.401566) (xy 352.617786 -131.548378) (xy 351.079054 -131.548378) (xy 351.0026 -131.548378)
				(xy 350.91497 -131.460748) (xy 350.91497 -131.12369)
			)
		)
	)
	(zone
		(net "P5V_HDD_SATA")
		(layer "F.Cu")
		(hatch none 0.5)
		(connect_pads
			(clearance 0.5)
		)
		(min_thickness 0.25)
		(fill yes
			(thermal_gap 0.5)
			(thermal_bridge_width 0.5)
			(island_removal_mode 0)
		)
		(polygon
			(pts
				(xy 448.183 -129.921) (xy 448.183 -127.9525) (xy 447.8147 -127.5842) (xy 446.34404 -127.5842) (xy 444.373 -129.55524)
				(xy 443.84722 -130.08102) (xy 443.020958 -130.08102) (xy 441.82792 -130.08102) (xy 441.44184 -130.4671)
				(xy 441.44184 -131.660138) (xy 441.44184 -134.973314) (xy 441.44184 -136.738106) (xy 441.819538 -137.115804)
				(xy 443.605666 -137.115804) (xy 443.80277 -136.9187) (xy 443.80277 -135.74776) (xy 444.02121 -135.52932)
				(xy 444.237364 -135.313166) (xy 444.242698 -135.313166) (xy 446.03416 -135.313166) (xy 446.405 -134.942326)
				(xy 446.405 -130.429) (xy 446.786 -130.048) (xy 446.813432 -130.020568) (xy 448.083432 -130.020568)
			)
		)
	)
	(zone
		(layer "F.Cu")
		(hatch none 0.5)
		(connect_pads
			(clearance 0)
		)
		(min_thickness 0.25)
		(keepout
			(tracks not_allowed)
			(vias allowed)
			(pads allowed)
			(copperpour not_allowed)
			(footprints allowed)
		)
		(placement
			(enabled no)
			(sheetname "")
		)
		(fill
			(thermal_gap 0.5)
			(thermal_bridge_width 0.5)
			(island_removal_mode 0)
		)
		(polygon
			(pts
				(arc
					(start 369.48999 -84.309966)
					(mid 371.08003 -85.900006)
					(end 369.48999 -87.490046)
				)
				(arc
					(start 369.48999 -87.490046)
					(mid 367.89995 -85.900006)
					(end 369.48999 -84.309966)
				)
			)
		)
	)
	(zone
		(net "GND")
		(layer "F.Cu")
		(hatch none 0.5)
		(connect_pads
			(clearance 0.5)
		)
		(min_thickness 0.25)
		(fill yes
			(thermal_gap 0.5)
			(thermal_bridge_width 0.5)
			(island_removal_mode 0)
		)
		(polygon
			(pts
				(xy 385.985512 -113.124488) (xy 386.207 -112.903) (xy 386.207 -112.776) (xy 386.588 -112.395) (xy 391.795 -112.395)
				(xy 391.795 -111.76) (xy 387.096 -111.76) (xy 386.969 -111.633) (xy 386.965952 -111.629952) (xy 386.965952 -107.626912)
				(xy 386.965952 -107.400852) (xy 387.305804 -107.061) (xy 387.42493 -107.061) (xy 387.444488 -107.041442)
				(xy 387.444488 -106.934762) (xy 387.617462 -106.761788) (xy 387.857492 -106.761788) (xy 388.030466 -106.934762)
				(xy 388.030466 -107.040934) (xy 388.050532 -107.061) (xy 388.221474 -107.061) (xy 388.245096 -107.037378)
				(xy 388.245096 -106.933238) (xy 388.41553 -106.762804) (xy 388.659878 -106.762804) (xy 388.831836 -106.934762)
				(xy 388.831836 -107.049824) (xy 388.843012 -107.061) (xy 389.02767 -107.061) (xy 389.044434 -107.044236)
				(xy 389.044434 -106.933492) (xy 389.214868 -106.763058) (xy 389.458962 -106.763058) (xy 389.632444 -106.93654)
				(xy 389.632444 -107.047538) (xy 389.645906 -107.061) (xy 389.822436 -107.061) (xy 389.844534 -107.038902)
				(xy 389.844534 -106.934254) (xy 390.016746 -106.762042) (xy 390.25957 -106.762042) (xy 390.432544 -106.935016)
				(xy 390.432544 -107.042966) (xy 390.450578 -107.061) (xy 390.619234 -107.061) (xy 390.644126 -107.036108)
				(xy 390.644126 -106.93527) (xy 390.816592 -106.762804) (xy 391.05967 -106.762804) (xy 391.231882 -106.935016)
				(xy 391.231882 -107.043982) (xy 391.2489 -107.061) (xy 391.541 -107.061) (xy 391.668 -107.188) (xy 391.668 -111.125)
				(xy 391.922 -111.125) (xy 392.176 -110.871) (xy 392.176 -107.145328) (xy 391.715244 -106.684572)
				(xy 391.715244 -106.62412) (xy 391.696194 -106.60507) (xy 391.69594 -106.60507) (xy 391.658094 -106.567224)
				(xy 391.611104 -106.567224) (xy 391.571734 -106.527854) (xy 391.105898 -106.527854) (xy 391.057638 -106.576114)
				(xy 391.030714 -106.576114) (xy 390.816846 -106.576114) (xy 390.76884 -106.528108) (xy 390.30402 -106.528108)
				(xy 390.256014 -106.576114) (xy 390.227566 -106.576114) (xy 390.041892 -106.576114) (xy 390.012174 -106.576114)
				(xy 389.960866 -106.524806) (xy 389.512302 -106.524806) (xy 389.462264 -106.574844) (xy 389.438642 -106.574844)
				(xy 389.240268 -106.574844) (xy 389.217662 -106.574844) (xy 389.168386 -106.525568) (xy 388.708138 -106.525568)
				(xy 388.598918 -106.634788) (xy 388.580884 -106.634788) (xy 387.707886 -106.634788) (xy 387.626098 -106.553)
				(xy 387.096 -106.553) (xy 387.05663 -106.553) (xy 387.035802 -106.573828) (xy 386.974588 -106.573828)
				(xy 386.614416 -106.934) (xy 386.334 -106.934) (xy 384.175 -104.775) (xy 384.048 -104.775) (xy 384.043936 -104.770936)
				(xy 384.04292 -104.771952) (xy 383.216404 -104.771952) (xy 383.2098 -104.765348) (xy 382.740916 -104.765348)
				(xy 382.68148 -104.705912) (xy 382.68148 -104.464866) (xy 382.68148 -104.456738) (xy 382.80213 -104.336088)
				(xy 382.810258 -104.336088) (xy 382.929638 -104.336088) (xy 382.967992 -104.297734) (xy 382.967992 -103.5812)
				(xy 382.891792 -103.505) (xy 382.5748 -103.505) (xy 382.450848 -103.628952) (xy 382.450848 -103.959152)
				(xy 382.4224 -103.9876) (xy 382.2446 -104.1654) (xy 381.4826 -104.1654) (xy 381.171958 -104.476042)
				(xy 381.171958 -104.692958) (xy 381.516128 -105.037128) (xy 381.702564 -105.037128) (xy 381.804926 -105.13949)
				(xy 381.808736 -105.1433) (xy 382.12522 -105.1433) (xy 382.322578 -105.340658) (xy 382.322832 -105.340658)
				(xy 382.629664 -105.64749) (xy 383.082292 -105.64749) (xy 383.178558 -105.551224) (xy 383.489708 -105.551224)
				(xy 383.604516 -105.666032) (xy 383.89687 -105.666032) (xy 384.17246 -105.390442) (xy 384.282442 -105.390442)
				(xy 384.429 -105.537) (xy 386.461 -107.569) (xy 386.461 -111.379) (xy 385.699 -112.141) (xy 385.29133 -112.54867)
				(xy 385.209542 -112.54867) (xy 382.348232 -112.54867) (xy 382.044702 -112.24514) (xy 381.687578 -112.24514)
				(xy 381.55372 -112.378998) (xy 381.55372 -112.490758) (xy 382.044702 -112.98174) (xy 382.959864 -112.98174)
				(xy 383.232152 -113.254028) (xy 383.370328 -113.254028) (xy 383.459736 -113.16462) (xy 383.99085 -113.16462)
				(xy 384.106928 -113.280698) (xy 384.106928 -113.733072) (xy 384.057144 -113.782856) (xy 384.057144 -113.801144)
				(xy 384.057144 -114.544856) (xy 384.048 -114.554) (xy 383.667 -114.935) (xy 383.54 -115.062) (xy 383.512822 -115.089178)
				(xy 383.201164 -115.089178) (xy 383.17932 -115.067334) (xy 382.31064 -115.067334) (xy 382.290066 -115.087908)
				(xy 382.290066 -115.291108) (xy 382.091438 -115.489736) (xy 382.091438 -115.567714) (xy 382.112266 -115.588542)
				(xy 382.61925 -115.588542) (xy 382.662938 -115.544854) (xy 382.67894 -115.544854) (xy 382.889506 -115.544854)
				(xy 382.914652 -115.57) (xy 383.032 -115.57) (xy 384.175 -115.57) (xy 384.556 -115.189) (xy 384.556 -114.554)
				(xy 384.76936 -114.34064) (xy 384.76936 -113.57356) (xy 385.218432 -113.124488)
			)
		)
	)
	(zone
		(layer "F.Cu")
		(hatch none 0.5)
		(connect_pads
			(clearance 0)
		)
		(min_thickness 0.25)
		(keepout
			(tracks allowed)
			(vias allowed)
			(pads allowed)
			(copperpour allowed)
			(footprints not_allowed)
		)
		(placement
			(enabled no)
			(sheetname "")
		)
		(fill
			(thermal_gap 0.5)
			(thermal_bridge_width 0.5)
			(island_removal_mode 0)
		)
		(polygon
			(pts
				(xy 22.52472 -22.919182) (xy 163.524692 -22.919182) (xy 163.524692 -20.919186) (xy 22.52472 -20.919186)
			)
		)
	)
	(zone
		(layer "F.Cu")
		(hatch none 0.5)
		(connect_pads
			(clearance 0)
		)
		(min_thickness 0.25)
		(keepout
			(tracks allowed)
			(vias allowed)
			(pads allowed)
			(copperpour allowed)
			(footprints not_allowed)
		)
		(placement
			(enabled no)
			(sheetname "")
		)
		(fill
			(thermal_gap 0.5)
			(thermal_bridge_width 0.5)
			(island_removal_mode 0)
		)
		(polygon
			(pts
				(arc
					(start 175.50003 5.999988)
					(mid 179.500022 1.999996)
					(end 175.50003 -1.999996)
				)
				(arc
					(start 171.99991 -1.999996)
					(mid 167.999918 1.999996)
					(end 171.99991 5.999988)
				)
			)
		)
	)
	(zone
		(layer "F.Cu")
		(hatch none 0.5)
		(connect_pads
			(clearance 0)
		)
		(min_thickness 0.25)
		(keepout
			(tracks allowed)
			(vias allowed)
			(pads allowed)
			(copperpour allowed)
			(footprints allowed)
		)
		(placement
			(enabled no)
			(sheetname "")
		)
		(fill
			(thermal_gap 0.5)
			(thermal_bridge_width 0.5)
			(island_removal_mode 0)
		)
		(polygon
			(pts
				(xy 178.308 -56.7944) (xy 178.308 -54.5084) (xy 180.3146 -54.5084) (xy 180.3146 -56.7944)
			)
		)
	)
	(zone
		(layer "F.Cu")
		(hatch none 0.5)
		(connect_pads
			(clearance 0)
		)
		(min_thickness 0.25)
		(keepout
			(tracks allowed)
			(vias allowed)
			(pads allowed)
			(copperpour allowed)
			(footprints allowed)
		)
		(placement
			(enabled no)
			(sheetname "")
		)
		(fill
			(thermal_gap 0.5)
			(thermal_bridge_width 0.5)
			(island_removal_mode 0)
		)
		(polygon
			(pts
				(xy 480.558348 -31.260034) (xy 482.05771 -31.260034) (xy 482.245162 -31.072582) (xy 482.245162 -30.471364)
				(xy 482.11486 -30.341062) (xy 481.721922 -30.341062) (xy 481.618036 -30.444948) (xy 480.52355 -30.444948)
				(xy 480.417886 -30.550612) (xy 480.417886 -31.119572)
			)
		)
	)
	(zone
		(net "P12V_STBY")
		(layer "F.Cu")
		(hatch none 0.5)
		(connect_pads
			(clearance 0.5)
		)
		(min_thickness 0.25)
		(fill yes
			(thermal_gap 0.5)
			(thermal_bridge_width 0.5)
			(island_removal_mode 0)
		)
		(polygon
			(pts
				(xy 439.2168 -53.0098) (xy 439.3565 -53.1495) (xy 439.3565 -53.8353) (xy 439.1152 -54.0766) (xy 437.9468 -54.0766)
				(xy 437.134 -54.0766) (xy 436.2196 -53.1622) (xy 436.2196 -52.0446) (xy 437.0578 -51.2064) (xy 437.0578 -51.0286)
				(xy 437.2356 -50.8508) (xy 438.404 -50.8508) (xy 438.4802 -50.927) (xy 438.4802 -52.9336) (xy 438.5564 -53.0098)
			)
		)
	)
	(zone
		(net "P3V3")
		(layer "F.Cu")
		(hatch none 0.5)
		(connect_pads
			(clearance 0.5)
		)
		(min_thickness 0.25)
		(fill yes
			(thermal_gap 0.5)
			(thermal_bridge_width 0.5)
			(island_removal_mode 0)
		)
		(polygon
			(pts
				(xy 391.143744 -38.423596) (xy 391.074148 -38.354) (xy 389.5598 -38.354) (xy 389.06704 -38.354)
				(xy 388.92988 -38.354) (xy 388.81812 -38.46576) (xy 388.81812 -39.624) (xy 388.96798 -39.77386)
				(xy 389.08228 -39.77386) (xy 389.57504 -39.77386) (xy 389.79602 -39.99484) (xy 389.79602 -40.66286)
				(xy 390.06526 -40.9321) (xy 391.032238 -40.9321) (xy 391.139172 -40.825166) (xy 391.139172 -38.837616)
				(xy 391.143744 -38.833044)
			)
		)
	)
	(zone
		(net "VR_FET_SW_P12V_STBY_PVDDQ_KLM")
		(layer "F.Cu")
		(hatch none 0.5)
		(connect_pads
			(clearance 0.5)
		)
		(min_thickness 0.25)
		(fill yes
			(thermal_gap 0.5)
			(thermal_bridge_width 0.5)
			(island_removal_mode 0)
		)
		(polygon
			(pts
				(xy -0.040894 -149.220682) (xy 0.086106 -149.093682) (xy 0.086106 -149.081998) (xy 0.120904 -149.0472)
				(xy 0.120904 -147.710398) (xy 2.10312 -147.710398) (xy 2.10312 -150.00478) (xy 2.045208 -150.062692)
				(xy 1.633728 -150.062692) (xy 1.554988 -150.141432) (xy 1.554988 -150.62073) (xy 1.554988 -150.923244)
				(xy 1.389888 -151.088344) (xy -0.699008 -151.088344) (xy -0.798068 -151.187404) (xy -1.2827 -151.187404)
				(xy -1.283462 -151.186642) (xy -1.463802 -151.186642) (xy -1.807464 -150.84298) (xy -1.807464 -149.950932)
				(xy -1.077214 -149.220682) (xy -0.88138 -149.220682)
			)
		)
	)
	(zone
		(net "GND")
		(layer "F.Cu")
		(hatch none 0.5)
		(connect_pads
			(clearance 0.5)
		)
		(min_thickness 0.25)
		(fill yes
			(thermal_gap 0.5)
			(thermal_bridge_width 0.5)
			(island_removal_mode 0)
		)
		(polygon
			(pts
				(xy 358.309672 -146.550634) (xy 358.468168 -146.392138) (xy 358.468168 -144.6403) (xy 358.99725 -144.111218)
				(xy 358.99725 -143.152368) (xy 358.99725 -141.501622) (xy 358.727248 -141.23162) (xy 356.078282 -141.23162)
				(xy 355.844856 -141.465046) (xy 355.844856 -141.7828) (xy 356.1334 -142.071344) (xy 356.1334 -142.101824)
				(xy 356.1334 -142.4686) (xy 355.0412 -143.5608) (xy 355.036882 -143.5608) (xy 355.036882 -145.092928)
				(xy 355.036882 -146.495516) (xy 355.10597 -146.564604) (xy 355.206046 -146.66468) (xy 358.195626 -146.66468)
			)
		)
	)
	(zone
		(layer "F.Cu")
		(hatch none 0.5)
		(connect_pads
			(clearance 0)
		)
		(min_thickness 0.25)
		(keepout
			(tracks allowed)
			(vias allowed)
			(pads allowed)
			(copperpour allowed)
			(footprints allowed)
		)
		(placement
			(enabled no)
			(sheetname "")
		)
		(fill
			(thermal_gap 0.5)
			(thermal_bridge_width 0.5)
			(island_removal_mode 0)
		)
		(polygon
			(pts
				(xy 392.501374 -78.815438) (xy 392.501374 -77.8637) (xy 393.387326 -77.8637) (xy 393.387326 -78.815438)
			)
		)
	)
	(zone
		(layer "F.Cu")
		(hatch none 0.5)
		(connect_pads
			(clearance 0)
		)
		(min_thickness 0.25)
		(keepout
			(tracks allowed)
			(vias allowed)
			(pads allowed)
			(copperpour allowed)
			(footprints allowed)
		)
		(placement
			(enabled no)
			(sheetname "")
		)
		(fill
			(thermal_gap 0.5)
			(thermal_bridge_width 0.5)
			(island_removal_mode 0)
		)
		(polygon
			(pts
				(xy 197.5866 -59.2836) (xy 197.5866 -54.9148) (xy 199.9996 -54.9148) (xy 199.9996 -59.2836)
			)
		)
	)
	(zone
		(layer "F.Cu")
		(hatch none 0.5)
		(connect_pads
			(clearance 0)
		)
		(min_thickness 0.25)
		(keepout
			(tracks allowed)
			(vias allowed)
			(pads allowed)
			(copperpour allowed)
			(footprints allowed)
		)
		(placement
			(enabled no)
			(sheetname "")
		)
		(fill
			(thermal_gap 0.5)
			(thermal_bridge_width 0.5)
			(island_removal_mode 0)
		)
		(polygon
			(pts
				(xy 270.383 -51.562) (xy 271.145 -51.562) (xy 271.399 -51.816) (xy 271.399 -52.197) (xy 270.256 -52.197)
				(xy 270.256 -51.689)
			)
		)
	)
	(zone
		(net "GND")
		(layer "F.Cu")
		(hatch none 0.5)
		(connect_pads
			(clearance 0.5)
		)
		(min_thickness 0.25)
		(fill yes
			(thermal_gap 0.5)
			(thermal_bridge_width 0.5)
			(island_removal_mode 0)
		)
		(polygon
			(pts
				(xy 455.676 -129.779268) (xy 455.676 -126.6698) (xy 456.2348 -126.111) (xy 458.7494 -126.111) (xy 459.2066 -126.5682)
				(xy 459.2066 -129.558034) (xy 458.89037 -129.874264) (xy 455.770996 -129.874264)
			)
		)
	)
	(zone
		(layer "F.Cu")
		(hatch none 0.5)
		(connect_pads
			(clearance 0)
		)
		(min_thickness 0.25)
		(keepout
			(tracks allowed)
			(vias allowed)
			(pads allowed)
			(copperpour allowed)
			(footprints not_allowed)
		)
		(placement
			(enabled no)
			(sheetname "")
		)
		(fill
			(thermal_gap 0.5)
			(thermal_bridge_width 0.5)
			(island_removal_mode 0)
		)
		(polygon
			(pts
				(xy 328.525378 -130.16611) (xy 332.725268 -130.16611) (xy 332.725268 -159.100012) (xy 328.525378 -159.100012)
			)
		)
	)
	(zone
		(net "GND")
		(layer "F.Cu")
		(hatch none 0.5)
		(connect_pads
			(clearance 0.5)
		)
		(min_thickness 0.25)
		(fill yes
			(thermal_gap 0.5)
			(thermal_bridge_width 0.5)
			(island_removal_mode 0)
		)
		(polygon
			(pts
				(xy 452.4883 -28.1305) (xy 450.224652 -28.1305) (xy 449.893436 -28.1305) (xy 449.067936 -28.956)
				(xy 449.067936 -29.694886) (xy 448.951858 -29.810964) (xy 448.118484 -29.810964) (xy 448.064382 -29.756862)
				(xy 448.064382 -28.973272) (xy 447.945764 -28.854654) (xy 447.945764 -28.001976) (xy 447.708274 -27.764486)
				(xy 446.893188 -27.764486) (xy 446.71869 -27.938984) (xy 445.504316 -27.938984) (xy 445.394588 -27.829256)
				(xy 445.394588 -27.565604) (xy 445.395604 -27.564588) (xy 445.395604 -27.179016) (xy 445.546734 -27.027886)
				(xy 447.849244 -27.027886) (xy 448.027298 -26.849832) (xy 448.606672 -26.270458) (xy 448.990466 -26.270458)
				(xy 450.102224 -27.382216) (xy 450.205094 -27.485086) (xy 452.37527 -27.485086) (xy 452.5645 -27.674316)
				(xy 452.5645 -28.0543)
			)
		)
	)
	(zone
		(layer "F.Cu")
		(hatch none 0.5)
		(connect_pads
			(clearance 0)
		)
		(min_thickness 0.25)
		(keepout
			(tracks allowed)
			(vias allowed)
			(pads allowed)
			(copperpour allowed)
			(footprints not_allowed)
		)
		(placement
			(enabled no)
			(sheetname "")
		)
		(fill
			(thermal_gap 0.5)
			(thermal_bridge_width 0.5)
			(island_removal_mode 0)
		)
		(polygon
			(pts
				(arc
					(start 471.000074 0.500126)
					(mid 469.49995 2.00025)
					(end 471.000074 3.50012)
				)
				(arc
					(start 471.67165 3.50012)
					(mid 472.338277 3.614414)
					(end 472.928696 3.944366)
				)
				(arc
					(start 472.928696 3.944366)
					(mid 476.999816 1.999996)
					(end 472.928696 0.055626)
				)
				(arc
					(start 472.928696 0.055626)
					(mid 472.3383 0.385683)
					(end 471.67165 0.500126)
				)
			)
		)
	)
	(zone
		(layer "F.Cu")
		(hatch none 0.5)
		(connect_pads
			(clearance 0)
		)
		(min_thickness 0.25)
		(keepout
			(tracks allowed)
			(vias allowed)
			(pads allowed)
			(copperpour allowed)
			(footprints allowed)
		)
		(placement
			(enabled no)
			(sheetname "")
		)
		(fill
			(thermal_gap 0.5)
			(thermal_bridge_width 0.5)
			(island_removal_mode 0)
		)
		(polygon
			(pts
				(xy 112.494568 -103.378) (xy 112.494568 -100.838) (xy 113.510568 -99.822) (xy 116.685568 -99.822)
				(xy 117.828568 -100.965) (xy 117.828568 -103.378) (xy 117.828568 -103.505) (xy 117.828568 -103.632)
				(xy 112.494568 -103.632) (xy 112.494568 -103.505)
			)
		)
	)
	(zone
		(net "PWRGD_P5V_STBY_R")
		(layer "F.Cu")
		(hatch none 0.5)
		(connect_pads
			(clearance 0.5)
		)
		(min_thickness 0.25)
		(fill yes
			(thermal_gap 0.5)
			(thermal_bridge_width 0.5)
			(island_removal_mode 0)
		)
		(polygon
			(pts
				(xy 392.811 -68.9864) (xy 392.7856 -69.0118) (xy 392.7856 -69.902832) (xy 392.7856 -70.0024) (xy 392.7348 -70.0532)
				(xy 392.694668 -70.093332) (xy 391.936732 -70.093332) (xy 391.777474 -70.093332) (xy 391.149332 -70.721474)
				(xy 391.149332 -71.30161) (xy 391.15746 -71.309738) (xy 393.4587 -71.309738) (xy 393.5222 -71.246238)
				(xy 393.5222 -70.443344) (xy 393.0904 -70.011544) (xy 393.0904 -69.0372) (xy 393.0396 -68.9864)
			)
		)
	)
	(zone
		(layer "F.Cu")
		(hatch none 0.5)
		(connect_pads
			(clearance 0)
		)
		(min_thickness 0.25)
		(keepout
			(tracks allowed)
			(vias allowed)
			(pads allowed)
			(copperpour allowed)
			(footprints allowed)
		)
		(placement
			(enabled no)
			(sheetname "")
		)
		(fill
			(thermal_gap 0.5)
			(thermal_bridge_width 0.5)
			(island_removal_mode 0)
		)
		(polygon
			(pts
				(xy 358.121966 -135.8646) (xy 358.121966 -134.112) (xy 360.553 -134.112) (xy 360.553 -135.8646)
			)
		)
	)
	(zone
		(layer "F.Cu")
		(hatch none 0.5)
		(connect_pads
			(clearance 0)
		)
		(min_thickness 0.25)
		(keepout
			(tracks allowed)
			(vias allowed)
			(pads allowed)
			(copperpour allowed)
			(footprints not_allowed)
		)
		(placement
			(enabled no)
			(sheetname "")
		)
		(fill
			(thermal_gap 0.5)
			(thermal_bridge_width 0.5)
			(island_removal_mode 0)
		)
		(polygon
			(pts
				(arc
					(start 7.23011 -45.310044)
					(mid 4.630166 -47.909988)
					(end 2.029968 -45.310044)
				)
				(arc
					(start 2.029968 -45.310044)
					(mid 4.630166 -42.709846)
					(end 7.23011 -45.310044)
				)
			)
		)
	)
	(zone
		(layer "F.Cu")
		(hatch none 0.5)
		(connect_pads
			(clearance 0)
		)
		(min_thickness 0.25)
		(keepout
			(tracks allowed)
			(vias allowed)
			(pads allowed)
			(copperpour allowed)
			(footprints not_allowed)
		)
		(placement
			(enabled no)
			(sheetname "")
		)
		(fill
			(thermal_gap 0.5)
			(thermal_bridge_width 0.5)
			(island_removal_mode 0)
		)
		(polygon
			(pts
				(arc
					(start 248.000012 -109.650022)
					(mid 249.900186 -111.550196)
					(end 248.000012 -113.450116)
				)
				(arc
					(start 248.000012 -113.450116)
					(mid 246.100092 -111.550196)
					(end 248.000012 -109.650022)
				)
			)
		)
	)
	(zone
		(layer "F.Cu")
		(hatch none 0.5)
		(connect_pads
			(clearance 0)
		)
		(min_thickness 0.25)
		(keepout
			(tracks allowed)
			(vias allowed)
			(pads allowed)
			(copperpour allowed)
			(footprints allowed)
		)
		(placement
			(enabled no)
			(sheetname "")
		)
		(fill
			(thermal_gap 0.5)
			(thermal_bridge_width 0.5)
			(island_removal_mode 0)
		)
		(polygon
			(pts
				(xy 381.231902 -35.063176) (xy 381.231902 -34.186368) (xy 381.140716 -34.095182) (xy 379.414786 -34.095182)
				(xy 379.134878 -33.815274) (xy 379.134878 -32.298894) (xy 379.28296 -32.150812) (xy 381.231902 -32.150812)
				(xy 384.689096 -32.150812) (xy 384.689096 -35.063176)
			)
		)
	)
	(zone
		(net "GND")
		(layer "F.Cu")
		(hatch none 0.5)
		(connect_pads
			(clearance 0.5)
		)
		(min_thickness 0.25)
		(fill yes
			(thermal_gap 0.5)
			(thermal_bridge_width 0.5)
			(island_removal_mode 0)
		)
		(polygon
			(pts
				(xy 94.435168 -12.1158) (xy 95.49638 -12.1158) (xy 95.5929 -12.21232) (xy 95.63735 -12.25677) (xy 95.63735 -14.04493)
				(xy 96.24441 -14.65199) (xy 96.589088 -14.65199) (xy 96.94164 -14.65199) (xy 97.015808 -14.577568)
				(xy 97.015808 -13.924788) (xy 96.88576 -13.79474) (xy 96.88576 -12.367006) (xy 95.974154 -11.4554)
				(xy 94.03588 -11.4554) (xy 93.97238 -11.5189) (xy 93.97238 -12.04468) (xy 94.0435 -12.1158)
			)
		)
	)
	(zone
		(net "PVDDQ_ABC")
		(layer "F.Cu")
		(hatch none 0.5)
		(connect_pads
			(clearance 0.5)
		)
		(min_thickness 0.25)
		(fill yes
			(thermal_gap 0.5)
			(thermal_bridge_width 0.5)
			(island_removal_mode 0)
		)
		(polygon
			(pts
				(xy 255.027176 -2.768092) (xy 255.027176 -2.674874)
				(arc
					(start 254.98552 -2.667254)
					(mid 254.720853 -2.453449)
					(end 254.756412 -2.115058)
				)
				(arc
					(start 254.756412 -2.115058)
					(mid 254.762739 -2.01021)
					(end 254.672846 -1.9558)
				)
				(xy 254.5334 -1.816354) (xy 254.5334 -0.6096) (xy 254.4318 -0.508) (xy 254.0254 -0.508) (xy 253.873 -0.6604)
				(xy 253.873 -1.80975)
				(arc
					(start 253.72695 -1.9558)
					(mid 253.636992 -2.010176)
					(end 253.643384 -2.115058)
				)
				(arc
					(start 253.643384 -2.115058)
					(mid 253.350014 -2.673136)
					(end 253.056644 -2.115058)
				)
				(arc
					(start 253.056644 -2.115058)
					(mid 253.062971 -2.01021)
					(end 252.973078 -1.9558)
				)
				(arc
					(start 252.876812 -1.9558)
					(mid 252.786854 -2.010176)
					(end 252.793246 -2.115058)
				)
				(arc
					(start 252.793246 -2.115058)
					(mid 252.499876 -2.673136)
					(end 252.206506 -2.115058)
				)
				(arc
					(start 252.206506 -2.115058)
					(mid 252.212833 -2.01021)
					(end 252.12294 -1.9558)
				)
				(arc
					(start 251.17806 -1.9558)
					(mid 251.088461 -2.009975)
					(end 251.09424 -2.11455)
				)
				(arc
					(start 251.09424 -2.11455)
					(mid 250.799854 -2.671082)
					(end 250.505468 -2.11455)
				)
				(arc
					(start 250.505468 -2.11455)
					(mid 250.511299 -2.009948)
					(end 250.421648 -1.9558)
				)
				(arc
					(start 250.327922 -1.9558)
					(mid 250.238323 -2.009975)
					(end 250.244102 -2.11455)
				)
				(arc
					(start 250.244102 -2.11455)
					(mid 249.949716 -2.671082)
					(end 249.65533 -2.11455)
				)
				(arc
					(start 249.65533 -2.11455)
					(mid 249.661161 -2.009948)
					(end 249.57151 -1.9558)
				)
				(arc
					(start 248.628154 -1.9558)
					(mid 248.538555 -2.009975)
					(end 248.544334 -2.11455)
				)
				(arc
					(start 248.544334 -2.11455)
					(mid 248.249948 -2.671082)
					(end 247.955562 -2.11455)
				)
				(arc
					(start 247.955562 -2.11455)
					(mid 247.961393 -2.009948)
					(end 247.871742 -1.9558)
				)
				(arc
					(start 247.778016 -1.9558)
					(mid 247.688417 -2.009975)
					(end 247.694196 -2.11455)
				)
				(arc
					(start 247.694196 -2.11455)
					(mid 247.39981 -2.671082)
					(end 247.105424 -2.11455)
				)
				(arc
					(start 247.105424 -2.11455)
					(mid 247.111255 -2.009948)
					(end 247.021604 -1.9558)
				)
				(arc
					(start 246.077994 -1.9558)
					(mid 245.988395 -2.009975)
					(end 245.994174 -2.11455)
				)
				(arc
					(start 245.994174 -2.11455)
					(mid 245.699788 -2.671082)
					(end 245.405402 -2.11455)
				)
				(arc
					(start 245.405402 -2.11455)
					(mid 245.411233 -2.009948)
					(end 245.321582 -1.9558)
				)
				(arc
					(start 244.377972 -1.9558)
					(mid 244.288373 -2.009975)
					(end 244.294152 -2.11455)
				)
				(arc
					(start 244.294152 -2.11455)
					(mid 244.307935 -2.136552)
					(end 244.32006 -2.159508)
				)
				(arc
					(start 244.32006 -2.159508)
					(mid 244.209724 -2.60248)
					(end 243.754148 -2.572766)
				)
				(arc
					(start 243.754148 -2.572766)
					(mid 243.645402 -2.557148)
					(end 243.586 -2.649474)
				)
				(xy 243.586 -2.996692) (xy 243.788692 -2.996692) (xy 243.788692 -2.844292) (xy 244.932708 -2.844292)
				(xy 244.932708 -2.971292) (xy 245.313708 -2.971292) (xy 245.313708 -3.734308) (xy 244.932708 -3.734308)
				(xy 244.932708 -3.861308) (xy 243.788692 -3.861308) (xy 243.788692 -3.708908) (xy 243.586 -3.708908)
				(xy 243.586 -4.2672) (xy 243.9416 -4.6228)
				(arc
					(start 244.43309 -4.6228)
					(mid 244.517367 -4.577566)
					(end 244.526816 -4.482338)
				)
				(arc
					(start 244.526816 -4.482338)
					(mid 244.849904 -3.976327)
					(end 245.172992 -4.482338)
				)
				(arc
					(start 245.172992 -4.482338)
					(mid 245.182359 -4.57762)
					(end 245.266718 -4.6228)
				)
				(arc
					(start 246.133112 -4.6228)
					(mid 246.217389 -4.577566)
					(end 246.226838 -4.482338)
				)
				(arc
					(start 246.226838 -4.482338)
					(mid 246.549926 -3.976327)
					(end 246.873014 -4.482338)
				)
				(arc
					(start 246.873014 -4.482338)
					(mid 246.882381 -4.57762)
					(end 246.96674 -4.6228)
				)
				(arc
					(start 246.982996 -4.6228)
					(mid 247.067273 -4.577566)
					(end 247.076722 -4.482338)
				)
				(arc
					(start 247.076722 -4.482338)
					(mid 247.39981 -3.976327)
					(end 247.722898 -4.482338)
				)
				(arc
					(start 247.722898 -4.482338)
					(mid 247.732265 -4.57762)
					(end 247.816624 -4.6228)
				)
				(xy 247.8532 -4.6228) (xy 247.904 -4.6736) (xy 247.904 -5.9436) (xy 248.0818 -6.1214) (xy 248.4374 -6.1214)
				(xy 248.5898 -5.969) (xy 248.5898 -4.716018)
				(arc
					(start 248.683018 -4.6228)
					(mid 248.767295 -4.577566)
					(end 248.776744 -4.482338)
				)
				(arc
					(start 248.776744 -4.482338)
					(mid 249.099832 -3.976327)
					(end 249.42292 -4.482338)
				)
				(arc
					(start 249.42292 -4.482338)
					(mid 249.432287 -4.57762)
					(end 249.516646 -4.6228)
				)
				(arc
					(start 249.533156 -4.6228)
					(mid 249.617433 -4.577566)
					(end 249.626882 -4.482338)
				)
				(arc
					(start 249.626882 -4.482338)
					(mid 249.94997 -3.976327)
					(end 250.273058 -4.482338)
				)
				(arc
					(start 250.273058 -4.482338)
					(mid 250.282425 -4.57762)
					(end 250.366784 -4.6228)
				)
				(arc
					(start 251.233178 -4.6228)
					(mid 251.317455 -4.577566)
					(end 251.326904 -4.482338)
				)
				(arc
					(start 251.326904 -4.482338)
					(mid 251.649992 -3.976327)
					(end 251.97308 -4.482338)
				)
				(arc
					(start 251.97308 -4.482338)
					(mid 251.982447 -4.57762)
					(end 252.066806 -4.6228)
				)
				(arc
					(start 252.083062 -4.6228)
					(mid 252.167339 -4.577566)
					(end 252.176788 -4.482338)
				)
				(arc
					(start 252.176788 -4.482338)
					(mid 252.499876 -3.976327)
					(end 252.822964 -4.482338)
				)
				(arc
					(start 252.822964 -4.482338)
					(mid 252.832331 -4.57762)
					(end 252.91669 -4.6228)
				)
				(xy 252.9586 -4.6228) (xy 253.0602 -4.7244) (xy 253.0602 -5.9944) (xy 253.1618 -6.096) (xy 253.5174 -6.096)
				(xy 253.6698 -5.9436) (xy 253.6698 -4.736084) (xy 253.8222 -4.583684) (xy 253.8222 -3.7338) (xy 253.836424 -3.719576)
				(xy 253.836424 -2.971292) (xy 254.217424 -2.971292) (xy 254.217424 -2.9718) (xy 254.66675 -2.9718)
				(xy 254.870458 -2.768092)
			)
		)
		(polygon
			(pts
				(xy 253.049532 -3.7465) (xy 252.846332 -3.7465) (xy 252.846332 -3.9497) (xy 253.049532 -3.9497)
			)
		)
		(polygon
			(pts
				(xy 253.049532 -2.7559) (xy 252.846332 -2.7559) (xy 252.846332 -2.9591) (xy 253.049532 -2.9591)
			)
		)
		(polygon
			(pts
				(xy 249.4026 -2.7559) (xy 249.1994 -2.7559) (xy 249.1994 -2.9591) (xy 249.4026 -2.9591)
			)
		)
		(polygon
			(pts
				(xy 246.3038 -2.7559) (xy 246.1006 -2.7559) (xy 246.1006 -2.9591) (xy 246.3038 -2.9591)
			)
		)
	)
	(zone
		(net "PVCCMCP_CPU0")
		(layer "F.Cu")
		(hatch none 0.5)
		(connect_pads
			(clearance 0.5)
		)
		(min_thickness 0.25)
		(fill yes
			(thermal_gap 0.5)
			(thermal_bridge_width 0.5)
			(island_removal_mode 0)
		)
		(polygon
			(pts
				(xy 316.1284 -60.2234) (xy 313.36996 -60.2234) (xy 312.39968 -59.25312) (xy 312.39968 -50.82032)
				(xy 312.990992 -50.229008) (xy 322.3006 -40.9194) (xy 332.3844 -40.9194) (xy 332.486 -41.021) (xy 332.9178 -41.021)
				(xy 333.4512 -41.021) (xy 350.1136 -41.021) (xy 350.2406 -41.148) (xy 350.3168 -41.148) (xy 350.8756 -41.148)
				(xy 351.0534 -40.9702) (xy 351.3328 -40.9702) (xy 351.5106 -41.148) (xy 351.5106 -41.3766) (xy 351.282 -41.6052)
				(xy 351.282 -41.7576) (xy 351.282 -42.1132) (xy 351.536 -42.3672) (xy 351.536 -42.6974) (xy 351.2312 -43.0022)
				(xy 351.2312 -43.307) (xy 351.536 -43.6118) (xy 351.536 -44.63415) (xy 351.056448 -45.113448) (xy 331.238352 -45.113448)
				(xy 327.2028 -49.149)
			)
		)
	)
	(zone
		(layer "F.Cu")
		(hatch none 0.5)
		(connect_pads
			(clearance 0)
		)
		(min_thickness 0.25)
		(keepout
			(tracks not_allowed)
			(vias allowed)
			(pads allowed)
			(copperpour not_allowed)
			(footprints allowed)
		)
		(placement
			(enabled no)
			(sheetname "")
		)
		(fill
			(thermal_gap 0.5)
			(thermal_bridge_width 0.5)
			(island_removal_mode 0)
		)
		(polygon
			(pts
				(xy 416.646614 -2.75082) (xy 416.852862 -2.957068) (xy 416.852862 -3.20421) (xy 416.954462 -3.20421)
				(xy 416.954462 -2.931668) (xy 417.13531 -2.75082)
				(arc
					(start 417.284408 -2.75082)
					(mid 417.808325 -2.82067)
					(end 417.284408 -2.89052)
				)
				(xy 417.193222 -2.89052) (xy 417.094162 -2.98958) (xy 417.094162 -3.20421)
				(arc
					(start 417.541456 -3.20421)
					(mid 417.92525 -2.820797)
					(end 417.54171 -2.43713)
				)
				(arc
					(start 416.27171 -2.43713)
					(mid 415.88817 -2.82067)
					(end 416.27171 -3.20421)
				)
				(xy 416.713162 -3.20421) (xy 416.713162 -3.01498) (xy 416.588702 -2.89052)
				(arc
					(start 416.529012 -2.89052)
					(mid 416.005095 -2.82067)
					(end 416.529012 -2.75082)
				)
			)
		)
	)
	(zone
		(layer "F.Cu")
		(hatch none 0.5)
		(connect_pads
			(clearance 0)
		)
		(min_thickness 0.25)
		(keepout
			(tracks allowed)
			(vias allowed)
			(pads allowed)
			(copperpour allowed)
			(footprints allowed)
		)
		(placement
			(enabled no)
			(sheetname "")
		)
		(fill
			(thermal_gap 0.5)
			(thermal_bridge_width 0.5)
			(island_removal_mode 0)
		)
		(polygon
			(pts
				(xy 232.918 -82.423) (xy 233.68 -82.423) (xy 233.934 -82.677) (xy 233.934 -83.058) (xy 232.791 -83.058)
				(xy 232.791 -82.55)
			)
		)
	)
	(zone
		(layer "F.Cu")
		(hatch none 0.5)
		(connect_pads
			(clearance 0)
		)
		(min_thickness 0.25)
		(keepout
			(tracks not_allowed)
			(vias allowed)
			(pads allowed)
			(copperpour not_allowed)
			(footprints allowed)
		)
		(placement
			(enabled no)
			(sheetname "")
		)
		(fill
			(thermal_gap 0.5)
			(thermal_bridge_width 0.5)
			(island_removal_mode 0)
		)
		(polygon
			(pts
				(arc
					(start 472.928696 3.944366)
					(mid 472.338288 3.614384)
					(end 471.67165 3.50012)
				)
				(arc
					(start 471.000074 3.50012)
					(mid 469.500204 2.00025)
					(end 471.000074 0.500126)
				)
				(arc
					(start 471.67165 0.500126)
					(mid 472.338321 0.385742)
					(end 472.928696 0.055626)
				)
				(arc
					(start 472.928696 0.055626)
					(mid 476.999816 1.999996)
					(end 472.928696 3.944366)
				)
			)
		)
	)
	(zone
		(layer "F.Cu")
		(hatch none 0.5)
		(connect_pads
			(clearance 0)
		)
		(min_thickness 0.25)
		(keepout
			(tracks allowed)
			(vias allowed)
			(pads allowed)
			(copperpour allowed)
			(footprints not_allowed)
		)
		(placement
			(enabled no)
			(sheetname "")
		)
		(fill
			(thermal_gap 0.5)
			(thermal_bridge_width 0.5)
			(island_removal_mode 0)
		)
		(polygon
			(pts
				(arc
					(start 56.999886 -79.090012)
					(mid 54.459886 -76.550012)
					(end 56.999886 -74.010012)
				)
				(arc
					(start 56.999886 -74.010012)
					(mid 59.539886 -76.550012)
					(end 56.999886 -79.090012)
				)
			)
		)
	)
	(zone
		(net "GND")
		(layer "F.Cu")
		(hatch none 0.5)
		(connect_pads
			(clearance 0.5)
		)
		(min_thickness 0.25)
		(fill yes
			(thermal_gap 0.5)
			(thermal_bridge_width 0.5)
			(island_removal_mode 0)
		)
		(polygon
			(pts
				(xy 161.6837 -113.378488) (xy 173.854872 -113.378488) (xy 174.451264 -113.97488) (xy 174.451264 -115.93195)
				(xy 174.680626 -116.161312) (xy 176.02581 -116.161312) (xy 176.3014 -115.885722) (xy 176.3014 -112.659668)
				(xy 176.668176 -112.292892) (xy 179.191158 -112.292892) (xy 179.19446 -112.29594) (xy 180.03774 -112.29594)
				(xy 180.58003 -112.83823) (xy 180.58003 -115.610894) (xy 180.916326 -115.94719) (xy 181.33441 -115.94719)
				(xy 181.4576 -115.824) (xy 181.4576 -113.792) (xy 183.8706 -113.792) (xy 184.179972 -113.482628)
				(xy 184.179972 -113.033556) (xy 184.179972 -111.35106) (xy 183.931306 -111.102394) (xy 181.887622 -111.102394)
				(xy 181.4576 -110.672372) (xy 181.4576 -108.897928) (xy 181.4576 -108.458) (xy 181.588664 -108.326936)
				(xy 183.782208 -106.133392) (xy 183.782208 -105.675938) (xy 183.49087 -105.3846) (xy 179.1208 -105.3846)
				(xy 178.8668 -105.1306) (xy 178.035966 -105.1306) (xy 176.9872 -104.081834) (xy 175.493172 -104.081834)
				(xy 175.493172 -104.082088) (xy 175.487584 -104.082088) (xy 175.471328 -104.098344) (xy 174.488348 -105.081324)
				(xy 174.445422 -105.081324) (xy 172.972476 -105.081324) (xy 172.9232 -105.1306) (xy 172.632624 -105.421176)
				(xy 172.632624 -106.919776) (xy 172.1104 -107.442) (xy 171.0436 -108.5088) (xy 165.8366 -108.5088)
				(xy 165.481 -108.8644) (xy 165.2778 -109.0676) (xy 165.2778 -110.109) (xy 164.8714 -110.5154) (xy 163.0553 -110.5154)
				(xy 162.871658 -110.331758) (xy 160.272222 -110.331758) (xy 159.83458 -110.7694) (xy 159.83458 -112.63122)
				(xy 160.581848 -113.378488)
			)
		)
		(polygon
			(pts
				(xy 177.22469 -106.114342) (xy 175.72863 -106.114342) (xy 175.60036 -106.242612) (xy 175.60036 -109.193584)
				(xy 175.606964 -109.200188) (xy 176.094644 -109.200188) (xy 177.290476 -108.004356) (xy 177.290476 -106.180128)
			)
		)
		(polygon
			(pts
				(xy 173.679866 -108.746036) (xy 173.484286 -108.746036) (xy 173.270418 -108.959904) (xy 173.270418 -109.772704)
				(xy 173.949614 -110.4519) (xy 173.949614 -110.26394) (xy 173.690534 -110.00486) (xy 173.690534 -109.643926)
				(xy 173.95063 -109.38383) (xy 173.95063 -109.0168)
			)
		)
	)
	(zone
		(layer "F.Cu")
		(hatch none 0.5)
		(connect_pads
			(clearance 0)
		)
		(min_thickness 0.25)
		(keepout
			(tracks allowed)
			(vias allowed)
			(pads allowed)
			(copperpour allowed)
			(footprints allowed)
		)
		(placement
			(enabled no)
			(sheetname "")
		)
		(fill
			(thermal_gap 0.5)
			(thermal_bridge_width 0.5)
			(island_removal_mode 0)
		)
		(polygon
			(pts
				(xy 78.331568 -45.72) (xy 81.506568 -48.895) (xy 81.506568 -49.784) (xy 81.506568 -49.911) (xy 85.443568 -49.911)
				(xy 85.443568 -49.784) (xy 85.443568 -47.371) (xy 85.443568 -47.117) (xy 85.443568 -46.99) (xy 80.109568 -41.656)
				(xy 76.045568 -45.72) (xy 76.299568 -45.72)
			)
		)
	)
	(zone
		(net "P12V_FAN")
		(layer "F.Cu")
		(hatch none 0.5)
		(connect_pads
			(clearance 0.5)
		)
		(min_thickness 0.25)
		(fill yes
			(thermal_gap 0.5)
			(thermal_bridge_width 0.5)
			(island_removal_mode 0)
		)
		(polygon
			(pts
				(xy -0.096774 -111.670592) (xy -0.096774 -107.370626) (xy 0.069342 -107.20451) (xy 0.402082 -107.20451)
				(xy 6.367018 -107.20451) (xy 6.368034 -107.205526) (xy 7.459726 -107.205526) (xy 7.815834 -107.561634)
				(xy 7.815834 -108.653326) (xy 7.815834 -112.368076) (xy 7.6962 -112.48771) (xy 7.6962 -113.62436)
				(xy 7.6962 -113.70056) (xy 7.6962 -116.332) (xy 7.6962 -117.2337) (xy 7.564882 -117.365018) (xy 6.941058 -117.365018)
				(xy 5.229352 -117.365018) (xy 5.055108 -117.365018) (xy 4.702556 -117.012466) (xy 4.702556 -112.843056)
				(xy 4.783836 -112.761776) (xy 5.032502 -112.51311) (xy 5.130292 -112.41532) (xy 5.130292 -112.0013)
				(xy 4.972304 -111.843312) (xy 0.918718 -111.843312) (xy 0.91694 -111.845344) (xy 0.077978 -111.845344)
			)
		)
	)
	(zone
		(layer "F.Cu")
		(hatch none 0.5)
		(connect_pads
			(clearance 0)
		)
		(min_thickness 0.25)
		(keepout
			(tracks allowed)
			(vias allowed)
			(pads allowed)
			(copperpour allowed)
			(footprints allowed)
		)
		(placement
			(enabled no)
			(sheetname "")
		)
		(fill
			(thermal_gap 0.5)
			(thermal_bridge_width 0.5)
			(island_removal_mode 0)
		)
		(polygon
			(pts
				(xy 478.1804 -15.2908) (xy 478.1804 -11.0998) (xy 480.06 -11.0998) (xy 480.06 -15.2908)
			)
		)
	)
	(zone
		(net "PVDDQ_DEF")
		(layer "F.Cu")
		(hatch none 0.5)
		(connect_pads
			(clearance 0.5)
		)
		(min_thickness 0.25)
		(fill yes
			(thermal_gap 0.5)
			(thermal_bridge_width 0.5)
			(island_removal_mode 0)
		)
		(polygon
			(pts
				(xy 243.745766 -148.49221) (xy 243.735606 -148.50237) (xy 243.735606 -150.834852) (xy 243.866416 -150.965662)
				(xy 253.469902 -150.965662) (xy 253.477522 -150.958042) (xy 256.1336 -150.958042) (xy 256.1336 -148.64461)
				(xy 255.9812 -148.49221)
			)
		)
		(polygon
			(pts
				(xy 253.049532 -150.2029) (xy 252.846332 -150.2029) (xy 252.846332 -150.4061) (xy 253.049532 -150.4061)
			)
		)
		(polygon
			(pts
				(xy 246.2784 -150.2029) (xy 246.0752 -150.2029) (xy 246.0752 -150.4061) (xy 246.2784 -150.4061)
			)
		)
		(polygon
			(pts
				(xy 253.049532 -149.2123) (xy 252.846332 -149.2123) (xy 252.846332 -149.4155) (xy 253.049532 -149.4155)
			)
		)
		(polygon
			(pts
				(xy 249.4026 -149.2123) (xy 249.1994 -149.2123) (xy 249.1994 -149.4155) (xy 249.4026 -149.4155)
			)
		)
		(polygon
			(pts
				(xy 246.2784 -149.2123) (xy 246.0752 -149.2123) (xy 246.0752 -149.4155) (xy 246.2784 -149.4155)
			)
		)
	)
	(zone
		(layer "F.Cu")
		(hatch none 0.5)
		(connect_pads
			(clearance 0)
		)
		(min_thickness 0.25)
		(keepout
			(tracks allowed)
			(vias allowed)
			(pads allowed)
			(copperpour allowed)
			(footprints allowed)
		)
		(placement
			(enabled no)
			(sheetname "")
		)
		(fill
			(thermal_gap 0.5)
			(thermal_bridge_width 0.5)
			(island_removal_mode 0)
		)
		(polygon
			(pts
				(xy 195.6054 -90.5002) (xy 195.6054 -88.2142) (xy 197.3326 -88.2142) (xy 197.3326 -90.5002)
			)
		)
	)
	(zone
		(net "P3V3_STBY")
		(layer "F.Cu")
		(hatch none 0.5)
		(connect_pads
			(clearance 0.5)
		)
		(min_thickness 0.25)
		(fill yes
			(thermal_gap 0.5)
			(thermal_bridge_width 0.5)
			(island_removal_mode 0)
		)
		(polygon
			(pts
				(xy 415.9377 -86.7918) (xy 415.9377 -86.2076) (xy 415.9758 -86.1695) (xy 421.1828 -86.1695) (xy 421.2971 -86.0552)
				(xy 421.2971 -85.1662) (xy 421.2844 -85.1535) (xy 421.2844 -83.9216) (xy 421.1447 -83.7819) (xy 420.3192 -83.7819)
				(xy 420.2303 -83.693) (xy 420.2303 -83.3247) (xy 420.2811 -83.2739) (xy 421.5384 -83.2739) (xy 421.7162 -83.4517)
				(xy 421.7162 -84.0359) (xy 421.8178 -84.1375) (xy 422.7068 -84.1375) (xy 422.9481 -84.3788) (xy 422.9481 -87.0331)
				(xy 422.529 -87.4522) (xy 419.80358 -87.4522) (xy 419.5826 -87.4522) (xy 419.08984 -87.94496) (xy 418.48024 -87.94496)
				(xy 418.4269 -87.89162) (xy 418.4269 -87.6554) (xy 418.4269 -87.4522) (xy 418.3507 -87.376) (xy 418.1983 -87.2236)
				(xy 416.9791 -87.2236) (xy 416.7886 -87.0331) (xy 416.6997 -86.9442) (xy 416.0901 -86.9442)
			)
		)
	)
	(zone
		(net "GND")
		(layer "F.Cu")
		(hatch none 0.5)
		(connect_pads
			(clearance 0.5)
		)
		(min_thickness 0.25)
		(fill yes
			(thermal_gap 0.5)
			(thermal_bridge_width 0.5)
			(island_removal_mode 0)
		)
		(polygon
			(pts
				(xy 174.348394 -4.792726) (xy 175.469042 -4.792726) (xy 175.601884 -4.659884) (xy 175.601884 -3.007614)
				(xy 175.113442 -2.519172) (xy 174.390812 -2.519172) (xy 174.25797 -2.652014) (xy 174.25797 -4.702302)
			)
		)
	)
	(zone
		(layer "F.Cu")
		(hatch none 0.5)
		(connect_pads
			(clearance 0)
		)
		(min_thickness 0.25)
		(keepout
			(tracks not_allowed)
			(vias allowed)
			(pads allowed)
			(copperpour not_allowed)
			(footprints allowed)
		)
		(placement
			(enabled no)
			(sheetname "")
		)
		(fill
			(thermal_gap 0.5)
			(thermal_bridge_width 0.5)
			(island_removal_mode 0)
		)
		(polygon
			(pts
				(xy 415.19475 -9.741408) (xy 415.19475 -10.058146) (xy 415.058098 -10.194798)
				(arc
					(start 414.886394 -10.194798)
					(mid 414.362477 -10.124948)
					(end 414.886394 -10.055098)
				)
				(xy 415.000186 -10.055098) (xy 415.05505 -10.000234) (xy 415.05505 -9.741408)
				(arc
					(start 414.629092 -9.741408)
					(mid 414.245552 -10.124948)
					(end 414.629092 -10.508488)
				)
				(arc
					(start 415.898838 -10.508488)
					(mid 416.282632 -10.125075)
					(end 415.899092 -9.741408)
				)
				(xy 415.43605 -9.741408) (xy 415.43605 -9.96315) (xy 415.527998 -10.055098)
				(arc
					(start 415.64179 -10.055098)
					(mid 416.165707 -10.124948)
					(end 415.64179 -10.194798)
				)
				(xy 415.470086 -10.194798) (xy 415.29635 -10.021062) (xy 415.29635 -9.741408)
			)
		)
	)
	(zone
		(layer "F.Cu")
		(hatch none 0.5)
		(connect_pads
			(clearance 0)
		)
		(min_thickness 0.25)
		(keepout
			(tracks not_allowed)
			(vias allowed)
			(pads allowed)
			(copperpour not_allowed)
			(footprints allowed)
		)
		(placement
			(enabled no)
			(sheetname "")
		)
		(fill
			(thermal_gap 0.5)
			(thermal_bridge_width 0.5)
			(island_removal_mode 0)
		)
		(polygon
			(pts
				(xy 422.414192 -9.639808) (xy 422.414192 -9.938004) (xy 422.258998 -10.093198)
				(arc
					(start 422.087294 -10.093198)
					(mid 421.563377 -10.023348)
					(end 422.087294 -9.953498)
				)
				(xy 422.201086 -9.953498) (xy 422.274492 -9.880092) (xy 422.274492 -9.639808)
				(arc
					(start 421.829992 -9.639808)
					(mid 421.446452 -10.023348)
					(end 421.829992 -10.406888)
				)
				(arc
					(start 423.099738 -10.406888)
					(mid 423.483532 -10.023475)
					(end 423.099992 -9.639808)
				)
				(xy 422.655492 -9.639808) (xy 422.655492 -9.880092) (xy 422.728898 -9.953498)
				(arc
					(start 422.84269 -9.953498)
					(mid 423.366607 -10.023348)
					(end 422.84269 -10.093198)
				)
				(xy 422.670986 -10.093198) (xy 422.515792 -9.938004) (xy 422.515792 -9.639808)
			)
		)
	)
	(zone
		(layer "F.Cu")
		(hatch none 0.5)
		(connect_pads
			(clearance 0)
		)
		(min_thickness 0.25)
		(keepout
			(tracks allowed)
			(vias allowed)
			(pads allowed)
			(copperpour allowed)
			(footprints allowed)
		)
		(placement
			(enabled no)
			(sheetname "")
		)
		(fill
			(thermal_gap 0.5)
			(thermal_bridge_width 0.5)
			(island_removal_mode 0)
		)
		(polygon
			(pts
				(xy 393.613132 -155.79979) (xy 393.613132 -151.95423) (xy 391.546588 -151.95423) (xy 391.546588 -155.79979)
			)
		)
	)
	(zone
		(layer "F.Cu")
		(hatch none 0.5)
		(connect_pads
			(clearance 0)
		)
		(min_thickness 0.25)
		(keepout
			(tracks allowed)
			(vias allowed)
			(pads allowed)
			(copperpour allowed)
			(footprints allowed)
		)
		(placement
			(enabled no)
			(sheetname "")
		)
		(fill
			(thermal_gap 0.5)
			(thermal_bridge_width 0.5)
			(island_removal_mode 0)
		)
		(polygon
			(pts
				(xy 81.252568 -99.9236) (xy 86.307168 -99.9236) (xy 86.307168 -98.0186) (xy 84.706968 -96.4184)
				(xy 82.319368 -96.4184) (xy 81.252568 -97.4852)
			)
		)
	)
	(zone
		(layer "F.Cu")
		(hatch none 0.5)
		(connect_pads
			(clearance 0.5)
		)
		(min_thickness 0.25)
		(fill
			(thermal_gap 0.5)
			(thermal_bridge_width 0.5)
			(island_removal_mode 0)
		)
		(polygon
			(pts
				(xy 31.486602 -75.188064) (xy 31.613602 -75.061064) (xy 31.613602 -75.04938) (xy 31.6484 -75.014582)
				(xy 31.6484 -73.67778) (xy 33.630616 -73.67778) (xy 33.630616 -76.03998) (xy 33.458658 -76.211938)
				(xy 33.458658 -76.95057) (xy 33.428686 -76.980542) (xy 31.085028 -76.980542) (xy 30.907736 -76.80325)
				(xy 28.92425 -76.80325) (xy 28.829 -76.708) (xy 28.829 -76.206858) (xy 28.871926 -76.163932) (xy 30.334204 -76.163932)
				(xy 30.548326 -75.94981) (xy 30.548326 -75.259692) (xy 30.619954 -75.188064)
			)
		)
	)
	(zone
		(layer "F.Cu")
		(hatch none 0.5)
		(connect_pads
			(clearance 0)
		)
		(min_thickness 0.25)
		(keepout
			(tracks not_allowed)
			(vias allowed)
			(pads allowed)
			(copperpour not_allowed)
			(footprints allowed)
		)
		(placement
			(enabled no)
			(sheetname "")
		)
		(fill
			(thermal_gap 0.5)
			(thermal_bridge_width 0.5)
			(island_removal_mode 0)
		)
		(polygon
			(pts
				(arc
					(start 493.100614 -114.596926)
					(mid 496.700556 -110.996984)
					(end 500.300498 -114.596926)
				)
				(arc
					(start 500.300498 -116.196872)
					(mid 496.700556 -119.796814)
					(end 493.100614 -116.196872)
				)
			)
		)
	)
	(zone
		(net "GND")
		(layer "F.Cu")
		(hatch none 0.5)
		(connect_pads
			(clearance 0.5)
		)
		(min_thickness 0.25)
		(fill yes
			(thermal_gap 0.5)
			(thermal_bridge_width 0.5)
			(island_removal_mode 0)
		)
		(polygon
			(pts
				(xy 261.874 -68.1482) (xy 261.5438 -68.4784) (xy 261.5438 -70.149466) (xy 261.1882 -70.505066) (xy 258.225036 -70.505066)
				(xy 257.748024 -70.982078) (xy 257.748024 -72.251824) (xy 257.84302 -72.34682) (xy 272.33118 -72.34682)
				(xy 272.3388 -72.3392) (xy 277.4188 -72.3392) (xy 277.8252 -71.9328) (xy 277.8252 -71.368158) (xy 277.043642 -70.5866)
				(xy 274.2438 -70.5866) (xy 274.2311 -70.5739) (xy 273.1135 -70.5739) (xy 272.902426 -70.362826)
				(xy 272.902426 -69.718174) (xy 272.5166 -69.332348) (xy 265.693652 -69.332348) (xy 265.5062 -69.5198)
				(xy 265.5062 -70.3326) (xy 265.333734 -70.505066) (xy 263.7282 -70.505066) (xy 263.4996 -70.276466)
				(xy 263.4996 -68.3514) (xy 263.2964 -68.1482)
			)
		)
		(polygon
			(pts
				(xy 277.461472 -71.375016) (xy 277.258272 -71.375016) (xy 277.258272 -71.578216) (xy 277.461472 -71.578216)
			)
		)
		(polygon
			(pts
				(xy 276.699472 -71.375016) (xy 276.496272 -71.375016) (xy 276.496272 -71.578216) (xy 276.699472 -71.578216)
			)
		)
		(polygon
			(pts
				(xy 276.191472 -71.375016) (xy 275.988272 -71.375016) (xy 275.988272 -71.578216) (xy 276.191472 -71.578216)
			)
		)
		(polygon
			(pts
				(xy 275.429472 -71.375016) (xy 275.226272 -71.375016) (xy 275.226272 -71.578216) (xy 275.429472 -71.578216)
			)
		)
		(polygon
			(pts
				(xy 274.921472 -71.375016) (xy 274.718272 -71.375016) (xy 274.718272 -71.578216) (xy 274.921472 -71.578216)
			)
		)
		(polygon
			(pts
				(xy 274.159472 -71.375016) (xy 273.956272 -71.375016) (xy 273.956272 -71.578216) (xy 274.159472 -71.578216)
			)
		)
		(polygon
			(pts
				(xy 273.651472 -71.375016) (xy 273.448272 -71.375016) (xy 273.448272 -71.578216) (xy 273.651472 -71.578216)
			)
		)
		(polygon
			(pts
				(xy 272.889472 -71.375016) (xy 272.686272 -71.375016) (xy 272.686272 -71.578216) (xy 272.889472 -71.578216)
			)
		)
		(polygon
			(pts
				(xy 268.647672 -71.375016) (xy 268.444472 -71.375016) (xy 268.444472 -71.578216) (xy 268.647672 -71.578216)
			)
		)
		(polygon
			(pts
				(xy 267.885672 -71.375016) (xy 267.682472 -71.375016) (xy 267.682472 -71.578216) (xy 267.885672 -71.578216)
			)
		)
		(polygon
			(pts
				(xy 267.403072 -71.375016) (xy 267.199872 -71.375016) (xy 267.199872 -71.578216) (xy 267.403072 -71.578216)
			)
		)
		(polygon
			(pts
				(xy 266.641072 -71.375016) (xy 266.437872 -71.375016) (xy 266.437872 -71.578216) (xy 266.641072 -71.578216)
			)
		)
		(polygon
			(pts
				(xy 266.158472 -71.375016) (xy 265.955272 -71.375016) (xy 265.955272 -71.578216) (xy 266.158472 -71.578216)
			)
		)
		(polygon
			(pts
				(xy 265.396472 -71.375016) (xy 265.193272 -71.375016) (xy 265.193272 -71.578216) (xy 265.396472 -71.578216)
			)
		)
		(polygon
			(pts
				(xy 264.913872 -71.375016) (xy 264.710672 -71.375016) (xy 264.710672 -71.578216) (xy 264.913872 -71.578216)
			)
		)
		(polygon
			(pts
				(xy 264.151872 -71.375016) (xy 263.948672 -71.375016) (xy 263.948672 -71.578216) (xy 264.151872 -71.578216)
			)
		)
		(polygon
			(pts
				(xy 263.669272 -71.375016) (xy 263.466072 -71.375016) (xy 263.466072 -71.578216) (xy 263.669272 -71.578216)
			)
		)
		(polygon
			(pts
				(xy 262.907272 -71.375016) (xy 262.704072 -71.375016) (xy 262.704072 -71.578216) (xy 262.907272 -71.578216)
			)
		)
		(polygon
			(pts
				(xy 262.424672 -71.375016) (xy 262.221472 -71.375016) (xy 262.221472 -71.578216) (xy 262.424672 -71.578216)
			)
		)
		(polygon
			(pts
				(xy 261.662672 -71.375016) (xy 261.459472 -71.375016) (xy 261.459472 -71.578216) (xy 261.662672 -71.578216)
			)
		)
		(polygon
			(pts
				(xy 261.180072 -71.375016) (xy 260.976872 -71.375016) (xy 260.976872 -71.578216) (xy 261.180072 -71.578216)
			)
		)
		(polygon
			(pts
				(xy 260.418072 -71.375016) (xy 260.214872 -71.375016) (xy 260.214872 -71.578216) (xy 260.418072 -71.578216)
			)
		)
		(polygon
			(pts
				(xy 259.935472 -71.375016) (xy 259.732272 -71.375016) (xy 259.732272 -71.578216) (xy 259.935472 -71.578216)
			)
		)
		(polygon
			(pts
				(xy 259.173472 -71.375016) (xy 258.970272 -71.375016) (xy 258.970272 -71.578216) (xy 259.173472 -71.578216)
			)
		)
		(polygon
			(pts
				(xy 258.690872 -71.375016) (xy 258.487672 -71.375016) (xy 258.487672 -71.578216) (xy 258.690872 -71.578216)
			)
		)
		(polygon
			(pts
				(xy 272.381472 -71.3359) (xy 272.178272 -71.3359) (xy 272.178272 -71.5391) (xy 272.381472 -71.5391)
			)
		)
		(polygon
			(pts
				(xy 271.619472 -71.3359) (xy 271.416272 -71.3359) (xy 271.416272 -71.5391) (xy 271.619472 -71.5391)
			)
		)
		(polygon
			(pts
				(xy 271.111472 -71.3359) (xy 270.908272 -71.3359) (xy 270.908272 -71.5391) (xy 271.111472 -71.5391)
			)
		)
		(polygon
			(pts
				(xy 270.349472 -71.3359) (xy 270.146272 -71.3359) (xy 270.146272 -71.5391) (xy 270.349472 -71.5391)
			)
		)
		(polygon
			(pts
				(xy 269.841472 -71.3359) (xy 269.638272 -71.3359) (xy 269.638272 -71.5391) (xy 269.841472 -71.5391)
			)
		)
		(polygon
			(pts
				(xy 269.079472 -71.3359) (xy 268.876272 -71.3359) (xy 268.876272 -71.5391) (xy 269.079472 -71.5391)
			)
		)
		(polygon
			(pts
				(xy 262.713724 -70.165214) (xy 262.510524 -70.165214) (xy 262.510524 -70.368414) (xy 262.713724 -70.368414)
			)
		)
		(polygon
			(pts
				(xy 267.628624 -70.152514) (xy 267.425424 -70.152514) (xy 267.425424 -70.355714) (xy 267.628624 -70.355714)
			)
		)
		(polygon
			(pts
				(xy 266.866624 -70.152514) (xy 266.663424 -70.152514) (xy 266.663424 -70.355714) (xy 266.866624 -70.355714)
			)
		)
		(polygon
			(pts
				(xy 266.384024 -70.152514) (xy 266.180824 -70.152514) (xy 266.180824 -70.355714) (xy 266.384024 -70.355714)
			)
		)
		(polygon
			(pts
				(xy 272.617438 -70.105016) (xy 272.414238 -70.105016) (xy 272.414238 -70.308216) (xy 272.617438 -70.308216)
			)
		)
		(polygon
			(pts
				(xy 271.855438 -70.105016) (xy 271.652238 -70.105016) (xy 271.652238 -70.308216) (xy 271.855438 -70.308216)
			)
		)
		(polygon
			(pts
				(xy 271.372838 -70.105016) (xy 271.169638 -70.105016) (xy 271.169638 -70.308216) (xy 271.372838 -70.308216)
			)
		)
		(polygon
			(pts
				(xy 270.610838 -70.105016) (xy 270.407638 -70.105016) (xy 270.407638 -70.308216) (xy 270.610838 -70.308216)
			)
		)
		(polygon
			(pts
				(xy 270.128238 -70.105016) (xy 269.925038 -70.105016) (xy 269.925038 -70.308216) (xy 270.128238 -70.308216)
			)
		)
		(polygon
			(pts
				(xy 269.366238 -70.105016) (xy 269.163038 -70.105016) (xy 269.163038 -70.308216) (xy 269.366238 -70.308216)
			)
		)
		(polygon
			(pts
				(xy 268.883638 -70.105016) (xy 268.680438 -70.105016) (xy 268.680438 -70.308216) (xy 268.883638 -70.308216)
			)
		)
		(polygon
			(pts
				(xy 268.121638 -70.105016) (xy 267.918438 -70.105016) (xy 267.918438 -70.308216) (xy 268.121638 -70.308216)
			)
		)
		(polygon
			(pts
				(xy 262.713724 -69.403214) (xy 262.510524 -69.403214) (xy 262.510524 -69.606414) (xy 262.713724 -69.606414)
			)
		)
		(polygon
			(pts
				(xy 262.713724 -68.920614) (xy 262.510524 -68.920614) (xy 262.510524 -69.123814) (xy 262.713724 -69.123814)
			)
		)
	)
	(zone
		(layer "F.Cu")
		(hatch none 0.5)
		(connect_pads
			(clearance 0)
		)
		(min_thickness 0.25)
		(keepout
			(tracks not_allowed)
			(vias allowed)
			(pads allowed)
			(copperpour not_allowed)
			(footprints allowed)
		)
		(placement
			(enabled no)
			(sheetname "")
		)
		(fill
			(thermal_gap 0.5)
			(thermal_bridge_width 0.5)
			(island_removal_mode 0)
		)
		(polygon
			(pts
				(xy 414.499806 -2.11709) (xy 414.499806 -1.885442) (xy 414.721548 -1.6637)
				(arc
					(start 414.81629 -1.6637)
					(mid 415.340207 -1.73355)
					(end 414.81629 -1.8034)
				)
				(xy 414.77946 -1.8034) (xy 414.639506 -1.943354) (xy 414.639506 -2.11709)
				(arc
					(start 415.073338 -2.11709)
					(mid 415.457132 -1.733677)
					(end 415.073592 -1.35001)
				)
				(arc
					(start 413.803592 -1.35001)
					(mid 413.420052 -1.73355)
					(end 413.803592 -2.11709)
				)
				(xy 414.258506 -2.11709) (xy 414.258506 -1.88722) (xy 414.174686 -1.8034)
				(arc
					(start 414.060894 -1.8034)
					(mid 413.536977 -1.73355)
					(end 414.060894 -1.6637)
				)
				(xy 414.232598 -1.6637) (xy 414.398206 -1.829308) (xy 414.398206 -2.11709)
			)
		)
	)
	(zone
		(net "GND")
		(layer "F.Cu")
		(hatch none 0.5)
		(connect_pads
			(clearance 0.5)
		)
		(min_thickness 0.25)
		(fill yes
			(thermal_gap 0.5)
			(thermal_bridge_width 0.5)
			(island_removal_mode 0)
		)
		(polygon
			(pts
				(xy 493.014 -55.499) (xy 488.442 -55.499) (xy 487.4006 -55.499) (xy 487.092498 -55.190898) (xy 487.092498 -53.768498)
				(xy 487.273092 -53.587904) (xy 493.553496 -53.587904) (xy 493.904524 -53.938678) (xy 493.904524 -54.732428)
				(xy 493.782604 -54.854348) (xy 493.306862 -54.854348) (xy 493.278922 -54.882288) (xy 493.117124 -55.044086)
				(xy 493.117124 -55.395876) (xy 493.117124 -55.472076) (xy 493.1156 -55.4736) (xy 493.0902 -55.499)
			)
		)
	)
	(zone
		(layer "F.Cu")
		(hatch none 0.5)
		(connect_pads
			(clearance 0)
		)
		(min_thickness 0.25)
		(keepout
			(tracks allowed)
			(vias allowed)
			(pads allowed)
			(copperpour allowed)
			(footprints not_allowed)
		)
		(placement
			(enabled no)
			(sheetname "")
		)
		(fill
			(thermal_gap 0.5)
			(thermal_bridge_width 0.5)
			(island_removal_mode 0)
		)
		(polygon
			(pts
				(xy 494.17986 -62.680088) (xy 489.17987 -62.680088) (xy 489.17987 -51.676808) (xy 494.17986 -51.676808)
			)
		)
	)
	(zone
		(net "GND")
		(layer "F.Cu")
		(hatch none 0.5)
		(connect_pads
			(clearance 0.5)
		)
		(min_thickness 0.25)
		(fill yes
			(thermal_gap 0.5)
			(thermal_bridge_width 0.5)
			(island_removal_mode 0)
		)
		(polygon
			(pts
				(xy 187.3631 -135.1407) (xy 187.198 -135.3058) (xy 186.6392 -135.3058) (xy 185.7248 -135.3058) (xy 185.356246 -134.937246)
				(xy 184.600342 -134.937246) (xy 184.404 -134.740904) (xy 184.404 -133.985) (xy 184.404 -131.523486)
				(xy 184.448704 -131.478782) (xy 185.961782 -131.478782) (xy 186.182 -131.699) (xy 186.182 -132.461)
				(xy 187.57773 -133.85673) (xy 187.57773 -134.92607)
			)
		)
	)
	(zone
		(layer "F.Cu")
		(hatch none 0.5)
		(connect_pads
			(clearance 0)
		)
		(min_thickness 0.25)
		(keepout
			(tracks not_allowed)
			(vias allowed)
			(pads allowed)
			(copperpour not_allowed)
			(footprints allowed)
		)
		(placement
			(enabled no)
			(sheetname "")
		)
		(fill
			(thermal_gap 0.5)
			(thermal_bridge_width 0.5)
			(island_removal_mode 0)
		)
		(polygon
			(pts
				(arc
					(start 439.71972 -44.7675)
					(mid 440.243637 -44.83735)
					(end 439.71972 -44.9072)
				)
				(xy 439.672984 -44.9072) (xy 439.532522 -45.047662) (xy 439.532522 -45.22089)
				(arc
					(start 439.977022 -45.22089)
					(mid 440.360562 -44.83735)
					(end 439.977022 -44.45381)
				)
				(arc
					(start 438.707276 -44.45381)
					(mid 438.323736 -44.837223)
					(end 438.707022 -45.22089)
				)
				(xy 439.151522 -45.22089) (xy 439.151522 -45.047662) (xy 439.01106 -44.9072)
				(arc
					(start 438.964324 -44.9072)
					(mid 438.440407 -44.83735)
					(end 438.964324 -44.7675)
				)
				(xy 439.068972 -44.7675) (xy 439.291222 -44.98975) (xy 439.291222 -45.22089) (xy 439.392822 -45.22089)
				(xy 439.392822 -44.98975) (xy 439.615072 -44.7675)
			)
		)
	)
	(zone
		(layer "F.Cu")
		(hatch none 0.5)
		(connect_pads
			(clearance 0)
		)
		(min_thickness 0.25)
		(keepout
			(tracks allowed)
			(vias allowed)
			(pads allowed)
			(copperpour allowed)
			(footprints not_allowed)
		)
		(placement
			(enabled no)
			(sheetname "")
		)
		(fill
			(thermal_gap 0.5)
			(thermal_bridge_width 0.5)
			(island_removal_mode 0)
		)
		(polygon
			(pts
				(xy 17.130014 -41.810178) (xy 17.130014 -44.260008) (xy 29.420058 -44.260008) (xy 29.420058 -42.049954)
				(xy 33.749996 -42.049954) (xy 33.749996 -29.420058) (xy 14.510004 -29.420058) (xy 14.510004 -41.810178)
			)
		)
	)
	(zone
		(net "GND")
		(layer "F.Cu")
		(hatch none 0.5)
		(connect_pads
			(clearance 0.5)
		)
		(min_thickness 0.25)
		(fill yes
			(thermal_gap 0.5)
			(thermal_bridge_width 0.5)
			(island_removal_mode 0)
		)
		(polygon
			(pts
				(xy 114.816636 -150.992078) (xy 113.436908 -150.992078) (xy 113.35639 -150.91156) (xy 113.35639 -150.901908)
				(xy 113.35639 -150.638002) (xy 113.351564 -150.633176) (xy 113.318798 -150.60041) (xy 113.229898 -150.51151)
				(xy 113.157 -150.438612) (xy 113.157 -149.1234) (xy 113.229898 -149.050502) (xy 113.357406 -148.922994)
				(xy 113.357406 -148.626576) (xy 113.35766 -148.626322) (xy 113.35766 -148.403818) (xy 113.390426 -148.371052)
				(xy 113.436908 -148.371052) (xy 114.860832 -148.371052) (xy 115.061238 -148.571458) (xy 115.061238 -150.747476)
			)
		)
	)
	(zone
		(net "PVDDQ_DEF")
		(layer "F.Cu")
		(hatch none 0.5)
		(connect_pads
			(clearance 0.5)
		)
		(min_thickness 0.25)
		(fill yes
			(thermal_gap 0.5)
			(thermal_bridge_width 0.5)
			(island_removal_mode 0)
		)
		(polygon
			(pts
				(xy 243.98859 -138.89101) (xy 243.795804 -139.083796) (xy 243.795804 -141.293596) (xy 243.866416 -141.364462)
				(xy 256.2098 -141.364462) (xy 256.3622 -141.212062) (xy 256.3622 -139.14501) (xy 256.1082 -138.89101)
			)
		)
		(polygon
			(pts
				(xy 253.049532 -140.6017) (xy 252.846332 -140.6017) (xy 252.846332 -140.8049) (xy 253.049532 -140.8049)
			)
		)
		(polygon
			(pts
				(xy 246.2784 -140.6017) (xy 246.0752 -140.6017) (xy 246.0752 -140.8049) (xy 246.2784 -140.8049)
			)
		)
		(polygon
			(pts
				(xy 253.049532 -139.6111) (xy 252.846332 -139.6111) (xy 252.846332 -139.8143) (xy 253.049532 -139.8143)
			)
		)
		(polygon
			(pts
				(xy 249.428 -139.6111) (xy 249.2248 -139.6111) (xy 249.2248 -139.8143) (xy 249.428 -139.8143)
			)
		)
		(polygon
			(pts
				(xy 246.2784 -139.6111) (xy 246.0752 -139.6111) (xy 246.0752 -139.8143) (xy 246.2784 -139.8143)
			)
		)
	)
	(zone
		(layer "F.Cu")
		(hatch none 0.5)
		(connect_pads
			(clearance 0)
		)
		(min_thickness 0.25)
		(keepout
			(tracks allowed)
			(vias allowed)
			(pads allowed)
			(copperpour allowed)
			(footprints not_allowed)
		)
		(placement
			(enabled no)
			(sheetname "")
		)
		(fill
			(thermal_gap 0.5)
			(thermal_bridge_width 0.5)
			(island_removal_mode 0)
		)
		(polygon
			(pts
				(arc
					(start 127 -114.089942)
					(mid 124.46 -111.549942)
					(end 127 -109.009942)
				)
				(arc
					(start 127 -109.009942)
					(mid 129.54 -111.549942)
					(end 127 -114.089942)
				)
			)
		)
	)
	(zone
		(net "GND")
		(layer "F.Cu")
		(hatch none 0.5)
		(connect_pads
			(clearance 0.5)
		)
		(min_thickness 0.25)
		(fill yes
			(thermal_gap 0.5)
			(thermal_bridge_width 0.5)
			(island_removal_mode 0)
		)
		(polygon
			(pts
				(xy 48.59782 -60.0964) (xy 48.36922 -60.325) (xy 48.36922 -61.8998) (xy 48.59782 -62.1284) (xy 50.2158 -62.1284)
				(xy 50.4698 -61.8744) (xy 50.4698 -60.2996) (xy 50.2666 -60.0964)
			)
		)
		(polygon
			(pts
				(xy 49.911 -60.883292) (xy 49.7078 -60.883292) (xy 49.7078 -61.340492) (xy 49.911 -61.340492)
			)
		)
		(polygon
			(pts
				(xy 49.149 -60.883292) (xy 48.9458 -60.883292) (xy 48.9458 -61.340492) (xy 49.149 -61.340492)
			)
		)
	)
	(zone
		(net "GND")
		(layer "F.Cu")
		(hatch none 0.5)
		(connect_pads
			(clearance 0.5)
		)
		(min_thickness 0.25)
		(fill yes
			(thermal_gap 0.5)
			(thermal_bridge_width 0.5)
			(island_removal_mode 0)
		)
		(polygon
			(pts
				(xy 413.004 -127.2286) (xy 412.9024 -127.127) (xy 412.0896 -127.127) (xy 412.0388 -127.1778) (xy 412.0388 -130.3528)
				(xy 412.2166 -130.5306) (xy 413.512 -130.5306) (xy 413.6136 -130.429) (xy 413.6136 -129.5654) (xy 413.004 -128.9558)
			)
		)
	)
	(zone
		(layer "F.Cu")
		(hatch none 0.5)
		(connect_pads
			(clearance 0)
		)
		(min_thickness 0.25)
		(keepout
			(tracks not_allowed)
			(vias allowed)
			(pads allowed)
			(copperpour not_allowed)
			(footprints allowed)
		)
		(placement
			(enabled no)
			(sheetname "")
		)
		(fill
			(thermal_gap 0.5)
			(thermal_bridge_width 0.5)
			(island_removal_mode 0)
		)
		(polygon
			(pts
				(arc
					(start 409.719526 -74.633836)
					(mid 411.969458 -76.883768)
					(end 409.719526 -79.1337)
				)
				(arc
					(start 409.719526 -79.1337)
					(mid 407.469594 -76.883768)
					(end 409.719526 -74.633836)
				)
			)
		)
	)
	(zone
		(layer "F.Cu")
		(hatch none 0.5)
		(connect_pads
			(clearance 0)
		)
		(min_thickness 0.25)
		(keepout
			(tracks allowed)
			(vias allowed)
			(pads allowed)
			(copperpour allowed)
			(footprints allowed)
		)
		(placement
			(enabled no)
			(sheetname "")
		)
		(fill
			(thermal_gap 0.5)
			(thermal_bridge_width 0.5)
			(island_removal_mode 0)
		)
		(polygon
			(pts
				(xy 346.583 -17.272) (xy 346.583 -13.716) (xy 348.742 -13.716) (xy 349.232474 -13.716) (xy 350.700594 -13.716)
				(xy 350.899984 -13.91539) (xy 350.899984 -15.292324) (xy 350.779588 -15.41272) (xy 350.23044 -15.41272)
				(xy 350.030288 -15.212568) (xy 349.322898 -15.212568) (xy 348.84868 -15.212568) (xy 348.742 -15.319248)
				(xy 348.742 -17.272)
			)
		)
	)
	(zone
		(layer "F.Cu")
		(hatch none 0.5)
		(connect_pads
			(clearance 0)
		)
		(min_thickness 0.25)
		(keepout
			(tracks not_allowed)
			(vias allowed)
			(pads allowed)
			(copperpour not_allowed)
			(footprints allowed)
		)
		(placement
			(enabled no)
			(sheetname "")
		)
		(fill
			(thermal_gap 0.5)
			(thermal_bridge_width 0.5)
			(island_removal_mode 0)
		)
		(polygon
			(pts
				(xy 417.540186 -7.192772) (xy 417.806886 -7.192772) (xy 417.806886 -8.386572) (xy 417.540186 -8.386572)
			)
		)
	)
	(zone
		(layer "F.Cu")
		(hatch none 0.5)
		(connect_pads
			(clearance 0)
		)
		(min_thickness 0.25)
		(keepout
			(tracks allowed)
			(vias allowed)
			(pads allowed)
			(copperpour allowed)
			(footprints allowed)
		)
		(placement
			(enabled no)
			(sheetname "")
		)
		(fill
			(thermal_gap 0.5)
			(thermal_bridge_width 0.5)
			(island_removal_mode 0)
		)
		(polygon
			(pts
				(xy 398.108932 -155.84424) (xy 398.108932 -155.089352) (xy 398.875504 -155.089352) (xy 398.875504 -155.84424)
			)
		)
	)
	(zone
		(layer "F.Cu")
		(hatch none 0.5)
		(connect_pads
			(clearance 0)
		)
		(min_thickness 0.25)
		(keepout
			(tracks allowed)
			(vias allowed)
			(pads allowed)
			(copperpour allowed)
			(footprints allowed)
		)
		(placement
			(enabled no)
			(sheetname "")
		)
		(fill
			(thermal_gap 0.5)
			(thermal_bridge_width 0.5)
			(island_removal_mode 0)
		)
		(polygon
			(pts
				(xy 267.52677 -50.030634) (xy 253.330456 -50.030634) (xy 252.99162 -49.691798) (xy 252.99162 -47.712122)
				(xy 253.425706 -47.278036) (xy 256.24155 -47.278036) (xy 257.405886 -46.1137) (xy 260.841236 -46.1137)
				(xy 260.881114 -46.073822) (xy 263.294622 -46.073822) (xy 263.705086 -46.484286) (xy 267.29436 -46.484286)
				(xy 268.045692 -47.235618) (xy 268.045692 -49.511712)
			)
		)
	)
	(zone
		(layer "F.Cu")
		(hatch none 0.5)
		(connect_pads
			(clearance 0)
		)
		(min_thickness 0.25)
		(keepout
			(tracks allowed)
			(vias allowed)
			(pads allowed)
			(copperpour allowed)
			(footprints allowed)
		)
		(placement
			(enabled no)
			(sheetname "")
		)
		(fill
			(thermal_gap 0.5)
			(thermal_bridge_width 0.5)
			(island_removal_mode 0)
		)
		(polygon
			(pts
				(xy 197.6374 -83.7692) (xy 197.6374 -79.4004) (xy 200.0504 -79.4004) (xy 200.0504 -83.7692)
			)
		)
	)
	(zone
		(layer "F.Cu")
		(hatch none 0.5)
		(connect_pads
			(clearance 0)
		)
		(min_thickness 0.25)
		(keepout
			(tracks allowed)
			(vias allowed)
			(pads allowed)
			(copperpour allowed)
			(footprints allowed)
		)
		(placement
			(enabled no)
			(sheetname "")
		)
		(fill
			(thermal_gap 0.5)
			(thermal_bridge_width 0.5)
			(island_removal_mode 0)
		)
		(polygon
			(pts
				(xy 245.872 -49.911) (xy 245.872 -52.2224) (xy 244.6274 -53.467) (xy 242.4938 -53.467) (xy 241.2238 -52.197)
				(xy 241.2238 -50.9778) (xy 240.792 -50.546) (xy 240.792 -49.911) (xy 241.173 -49.911) (xy 241.2238 -49.911)
			)
		)
	)
	(zone
		(net "GND")
		(layer "F.Cu")
		(hatch none 0.5)
		(connect_pads
			(clearance 0.5)
		)
		(min_thickness 0.25)
		(fill yes
			(thermal_gap 0.5)
			(thermal_bridge_width 0.5)
			(island_removal_mode 0)
		)
		(polygon
			(pts
				(xy 367.2332 -102.108) (xy 367.0046 -101.8794) (xy 365.252 -101.8794) (xy 365.185706 -101.945694)
				(xy 365.185706 -103.547672) (xy 365.223298 -103.585264) (xy 365.997744 -103.585264) (xy 366.459008 -103.124)
				(xy 367.1062 -103.124) (xy 367.2332 -102.997)
			)
		)
	)
	(zone
		(layer "F.Cu")
		(hatch none 0.5)
		(connect_pads
			(clearance 0)
		)
		(min_thickness 0.25)
		(keepout
			(tracks not_allowed)
			(vias allowed)
			(pads allowed)
			(copperpour not_allowed)
			(footprints allowed)
		)
		(placement
			(enabled no)
			(sheetname "")
		)
		(fill
			(thermal_gap 0.5)
			(thermal_bridge_width 0.5)
			(island_removal_mode 0)
		)
		(polygon
			(pts
				(xy 403.138386 -7.192772) (xy 403.405086 -7.192772) (xy 403.405086 -8.386572) (xy 403.138386 -8.386572)
			)
		)
	)
	(zone
		(layer "F.Cu")
		(hatch none 0.5)
		(connect_pads
			(clearance 0)
		)
		(min_thickness 0.25)
		(keepout
			(tracks allowed)
			(vias allowed)
			(pads allowed)
			(copperpour allowed)
			(footprints allowed)
		)
		(placement
			(enabled no)
			(sheetname "")
		)
		(fill
			(thermal_gap 0.5)
			(thermal_bridge_width 0.5)
			(island_removal_mode 0)
		)
		(polygon
			(pts
				(xy 231.902 -60.132722) (xy 230.493824 -60.132722) (xy 230.127556 -59.766454) (xy 230.127556 -54.102)
				(xy 230.124 -54.098444) (xy 230.124 -53.34) (xy 233.68 -49.784) (xy 240.284 -49.784) (xy 240.411 -49.911)
				(xy 241.173 -49.911) (xy 246.38 -49.911) (xy 251.206 -49.911) (xy 251.206 -49.657) (xy 281.559 -49.657)
				(xy 281.559 -49.53) (xy 281.94 -49.149) (xy 281.94 -48.514) (xy 282.956 -47.498) (xy 284.48 -47.498)
				(xy 287.5661 -50.5841) (xy 287.8201 -50.5841) (xy 289.295586 -49.108614) (xy 292.5318 -49.108614)
				(xy 292.787578 -49.364392) (xy 293.1795 -49.364392) (xy 300.396148 -49.364392) (xy 301.171102 -50.1396)
				(xy 304.673 -50.1396) (xy 304.673 -50.038) (xy 306.197 -48.514) (xy 309.753 -48.514) (xy 312.166 -50.927)
				(xy 312.166 -55.4228) (xy 310.6928 -56.896) (xy 310.6928 -64.7446) (xy 311.6072 -65.659) (xy 311.6072 -66.7258)
				(xy 311.604406 -66.7258) (xy 310.334406 -67.9958) (xy 310.334406 -100.129594) (xy 303.276 -107.188)
				(xy 299.72 -103.632) (xy 299.466 -103.886) (xy 282.829 -103.886) (xy 282.829 -105.029) (xy 282.829 -106.045)
				(xy 278.13 -106.045) (xy 278.003 -106.045) (xy 278.003 -106.807) (xy 270.764 -106.807) (xy 270.764 -106.172)
				(xy 270.764 -102.743) (xy 251.587 -102.743) (xy 251.587 -102.235) (xy 247.396 -102.235) (xy 247.396 -102.743)
				(xy 246.126 -102.743) (xy 245.237 -103.632) (xy 245.11 -103.632) (xy 244.475 -102.997) (xy 243.84 -102.997)
				(xy 243.332 -102.489) (xy 240.665 -102.489) (xy 240.665 -101.981) (xy 232.41 -101.981) (xy 232.41 -101.346)
				(xy 231.902 -101.346) (xy 231.902 -89.051638)
			)
		)
	)
	(zone
		(net "PVSA_CPU1")
		(layer "F.Cu")
		(hatch none 0.5)
		(connect_pads
			(clearance 0.5)
		)
		(min_thickness 0.25)
		(fill yes
			(thermal_gap 0.5)
			(thermal_bridge_width 0.5)
			(island_removal_mode 0)
		)
		(polygon
			(pts
				(xy 92.747592 -81.112614) (xy 92.747592 -82.968592) (xy 93.1164 -83.3374) (xy 94.7166 -83.3374)
				(xy 95.638366 -84.259166) (xy 97.490788 -84.259166) (xy 97.490788 -83.41106) (xy 96.74606 -83.41106)
				(xy 96.720914 -83.385914) (xy 96.720914 -83.180936) (xy 96.48698 -82.947002) (xy 96.48698 -81.770474)
				(xy 95.82912 -81.112614)
			)
		)
		(polygon
			(pts
				(xy 96.17964 -81.916016) (xy 95.97644 -81.916016) (xy 95.97644 -82.119216) (xy 96.17964 -82.119216)
			)
		)
		(polygon
			(pts
				(xy 95.41764 -81.916016) (xy 95.21444 -81.916016) (xy 95.21444 -82.119216) (xy 95.41764 -82.119216)
			)
		)
		(polygon
			(pts
				(xy 94.98584 -81.916016) (xy 94.78264 -81.916016) (xy 94.78264 -82.119216) (xy 94.98584 -82.119216)
			)
		)
		(polygon
			(pts
				(xy 94.22384 -81.916016) (xy 94.02064 -81.916016) (xy 94.02064 -82.119216) (xy 94.22384 -82.119216)
			)
		)
		(polygon
			(pts
				(xy 93.79204 -81.916016) (xy 93.58884 -81.916016) (xy 93.58884 -82.119216) (xy 93.79204 -82.119216)
			)
		)
	)
	(zone
		(layer "F.Cu")
		(hatch none 0.5)
		(connect_pads
			(clearance 0)
		)
		(min_thickness 0.25)
		(keepout
			(tracks allowed)
			(vias allowed)
			(pads allowed)
			(copperpour allowed)
			(footprints allowed)
		)
		(placement
			(enabled no)
			(sheetname "")
		)
		(fill
			(thermal_gap 0.5)
			(thermal_bridge_width 0.5)
			(island_removal_mode 0)
		)
		(polygon
			(pts
				(xy 123.289568 -103.886) (xy 117.828568 -103.886) (xy 117.828568 -106.045) (xy 118.336568 -106.045)
				(xy 119.733568 -107.442)
			)
		)
	)
	(zone
		(net "VR_P5V_STBY_COMP")
		(layer "F.Cu")
		(hatch none 0.5)
		(connect_pads
			(clearance 0.5)
		)
		(min_thickness 0.25)
		(fill yes
			(thermal_gap 0.5)
			(thermal_bridge_width 0.5)
			(island_removal_mode 0)
		)
		(polygon
			(pts
				(xy 393.4714 -65.550288) (xy 393.4714 -66.3448) (xy 393.4206 -66.3956) (xy 392.811 -66.3956) (xy 392.784584 -66.369184)
				(xy 392.784584 -65.462404) (xy 392.34618 -65.024) (xy 391.8458 -65.024) (xy 391.8204 -64.9986) (xy 391.6934 -64.9986)
				(xy 391.6172 -64.9224) (xy 391.6172 -64.4906) (xy 391.654284 -64.453516) (xy 391.702798 -64.453516)
				(xy 392.250676 -64.453516) (xy 392.41476 -64.6176) (xy 392.9507 -64.6176) (xy 393.067794 -64.734694)
				(xy 393.067794 -65.146682)
			)
		)
	)
	(zone
		(layer "F.Cu")
		(hatch none 0.5)
		(connect_pads
			(clearance 0)
		)
		(min_thickness 0.25)
		(keepout
			(tracks not_allowed)
			(vias allowed)
			(pads allowed)
			(copperpour not_allowed)
			(footprints allowed)
		)
		(placement
			(enabled no)
			(sheetname "")
		)
		(fill
			(thermal_gap 0.5)
			(thermal_bridge_width 0.5)
			(island_removal_mode 0)
		)
		(polygon
			(pts
				(arc
					(start 474.49994 5.999988)
					(mid 478.499932 1.999996)
					(end 474.49994 -1.999996)
				)
				(arc
					(start 471.000074 -1.999996)
					(mid 467.000082 1.999996)
					(end 471.000074 5.999988)
				)
			)
		)
	)
	(zone
		(net "GND")
		(layer "F.Cu")
		(hatch none 0.5)
		(connect_pads
			(clearance 0.5)
		)
		(min_thickness 0.25)
		(fill yes
			(thermal_gap 0.5)
			(thermal_bridge_width 0.5)
			(island_removal_mode 0)
		)
		(polygon
			(pts
				(xy 452.054976 -11.821414) (xy 452.054976 -13.86332) (xy 453.025002 -14.833346) (xy 453.044052 -14.833346)
				(xy 454.845166 -16.63446) (xy 460.57947 -16.63446) (xy 461.513682 -15.700248) (xy 461.513682 -11.37158)
				(xy 461.513682 -11.120882) (xy 461.01 -10.6172) (xy 452.5264 -10.6172) (xy 452.054976 -11.088624)
			)
		)
	)
	(zone
		(net "GND")
		(layer "F.Cu")
		(hatch none 0.5)
		(connect_pads
			(clearance 0.5)
		)
		(min_thickness 0.25)
		(fill yes
			(thermal_gap 0.5)
			(thermal_bridge_width 0.5)
			(island_removal_mode 0)
		)
		(polygon
			(pts
				(xy 309.5498 -125.476) (xy 312.6994 -125.476) (xy 314.0456 -126.8222) (xy 314.0456 -129.7686) (xy 313.9186 -129.8956)
				(xy 309.334916 -129.8956) (xy 309.0672 -129.627884) (xy 309.0672 -125.9586)
			)
		)
	)
	(zone
		(net "PVDDQ_ABC")
		(layer "F.Cu")
		(hatch none 0.5)
		(connect_pads
			(clearance 0.5)
		)
		(min_thickness 0.25)
		(fill yes
			(thermal_gap 0.5)
			(thermal_bridge_width 0.5)
			(island_removal_mode 0)
		)
		(polygon
			(pts
				(xy 266.5603 -9.271) (xy 270.7767 -9.271) (xy 270.9418 -9.4361) (xy 270.9418 -10.5156) (xy 271.1069 -10.6807)
				(xy 271.2847 -10.6807) (xy 271.4498 -10.5156) (xy 271.4498 -9.4615) (xy 271.6403 -9.271) (xy 277.3172 -9.271)
				(xy 277.5712 -9.017) (xy 277.5712 -7.4168) (xy 277.0886 -6.9342) (xy 266.573 -6.9342) (xy 265.7094 -7.7978)
				(xy 265.7094 -9.1059) (xy 265.8491 -9.2456) (xy 265.8491 -10.5664) (xy 265.9634 -10.6807) (xy 266.2301 -10.6807)
				(xy 266.3571 -10.5537) (xy 266.3571 -9.4742) (xy 266.446 -9.3853)
			)
		)
	)
	(zone
		(layer "F.Cu")
		(hatch none 0.5)
		(connect_pads
			(clearance 0)
		)
		(min_thickness 0.25)
		(keepout
			(tracks allowed)
			(vias allowed)
			(pads allowed)
			(copperpour allowed)
			(footprints allowed)
		)
		(placement
			(enabled no)
			(sheetname "")
		)
		(fill
			(thermal_gap 0.5)
			(thermal_bridge_width 0.5)
			(island_removal_mode 0)
		)
		(polygon
			(pts
				(xy 300.355 -104.902) (xy 299.339 -103.886) (xy 288.29 -103.886) (xy 284.6705 -107.5055) (xy 286.131 -108.966)
				(xy 287.147 -108.966) (xy 287.401 -108.966) (xy 293.116 -108.966) (xy 294.64 -110.49) (xy 294.894 -110.744)
				(xy 294.894 -110.998) (xy 295.656 -111.76) (xy 297.434 -111.76) (xy 298.45 -110.744) (xy 300.736 -108.458)
				(xy 301.752 -107.442) (xy 301.752 -107.061) (xy 300.355 -105.664)
			)
		)
	)
	(zone
		(layer "F.Cu")
		(hatch none 0.5)
		(connect_pads
			(clearance 0)
		)
		(min_thickness 0.25)
		(keepout
			(tracks allowed)
			(vias allowed)
			(pads allowed)
			(copperpour allowed)
			(footprints allowed)
		)
		(placement
			(enabled no)
			(sheetname "")
		)
		(fill
			(thermal_gap 0.5)
			(thermal_bridge_width 0.5)
			(island_removal_mode 0)
		)
		(polygon
			(pts
				(xy 349.95485 -144.756378) (xy 349.95485 -142.988792) (xy 353.69246 -142.988792) (xy 353.69246 -144.756378)
			)
		)
	)
	(zone
		(layer "F.Cu")
		(hatch none 0.5)
		(connect_pads
			(clearance 0)
		)
		(min_thickness 0.25)
		(keepout
			(tracks allowed)
			(vias allowed)
			(pads allowed)
			(copperpour allowed)
			(footprints allowed)
		)
		(placement
			(enabled no)
			(sheetname "")
		)
		(fill
			(thermal_gap 0.5)
			(thermal_bridge_width 0.5)
			(island_removal_mode 0)
		)
		(polygon
			(pts
				(xy 391.175494 -9.82345) (xy 391.175494 -7.085584) (xy 469.147652 -7.085584) (xy 470.435178 -7.085584)
				(xy 470.81186 -7.462266) (xy 470.81186 -8.374888) (xy 470.50198 -8.684768) (xy 469.212676 -8.684768)
				(xy 469.147652 -8.749792) (xy 469.147652 -9.82345)
			)
		)
	)
	(zone
		(layer "F.Cu")
		(hatch none 0.5)
		(connect_pads
			(clearance 0)
		)
		(min_thickness 0.25)
		(keepout
			(tracks allowed)
			(vias allowed)
			(pads allowed)
			(copperpour allowed)
			(footprints not_allowed)
		)
		(placement
			(enabled no)
			(sheetname "")
		)
		(fill
			(thermal_gap 0.5)
			(thermal_bridge_width 0.5)
			(island_removal_mode 0)
		)
		(polygon
			(pts
				(arc
					(start 406.489916 -132.310124)
					(mid 408.079956 -133.900164)
					(end 406.489916 -135.48995)
				)
				(arc
					(start 406.489916 -135.48995)
					(mid 404.90013 -133.900164)
					(end 406.489916 -132.310124)
				)
			)
		)
	)
	(zone
		(layer "F.Cu")
		(hatch none 0.5)
		(connect_pads
			(clearance 0)
		)
		(min_thickness 0.25)
		(keepout
			(tracks allowed)
			(vias allowed)
			(pads allowed)
			(copperpour allowed)
			(footprints not_allowed)
		)
		(placement
			(enabled no)
			(sheetname "")
		)
		(fill
			(thermal_gap 0.5)
			(thermal_bridge_width 0.5)
			(island_removal_mode 0)
		)
		(polygon
			(pts
				(arc
					(start 83.000088 -39.649908)
					(mid 84.900262 -41.550082)
					(end 83.000088 -43.450002)
				)
				(arc
					(start 83.000088 -43.450002)
					(mid 81.100168 -41.550082)
					(end 83.000088 -39.649908)
				)
			)
		)
	)
	(zone
		(layer "F.Cu")
		(hatch none 0.5)
		(connect_pads
			(clearance 0)
		)
		(min_thickness 0.25)
		(keepout
			(tracks allowed)
			(vias allowed)
			(pads allowed)
			(copperpour allowed)
			(footprints allowed)
		)
		(placement
			(enabled no)
			(sheetname "")
		)
		(fill
			(thermal_gap 0.5)
			(thermal_bridge_width 0.5)
			(island_removal_mode 0)
		)
		(polygon
			(pts
				(xy 5.334 -2.921) (xy 5.334 -1.397) (xy 8.001 -1.397) (xy 8.001 -2.921)
			)
		)
	)
	(zone
		(layer "F.Cu")
		(hatch none 0.5)
		(connect_pads
			(clearance 0)
		)
		(min_thickness 0.25)
		(keepout
			(tracks allowed)
			(vias allowed)
			(pads allowed)
			(copperpour allowed)
			(footprints allowed)
		)
		(placement
			(enabled no)
			(sheetname "")
		)
		(fill
			(thermal_gap 0.5)
			(thermal_bridge_width 0.5)
			(island_removal_mode 0)
		)
		(polygon
			(pts
				(xy 271.272 -106.807) (xy 277.495 -106.807) (xy 277.495 -107.95) (xy 277.495 -112.268) (xy 277.495 -113.61166)
				(xy 276.987 -114.11966) (xy 276.93366 -114.173) (xy 271.272 -114.173) (xy 271.145 -114.173) (xy 271.145 -106.807)
			)
		)
	)
	(zone
		(net "P1V05_PCH_STBY")
		(layer "F.Cu")
		(hatch none 0.5)
		(connect_pads
			(clearance 0.5)
		)
		(min_thickness 0.25)
		(fill yes
			(thermal_gap 0.5)
			(thermal_bridge_width 0.5)
			(island_removal_mode 0)
		)
		(polygon
			(pts
				(xy 404.635462 -116.412772) (xy 404.421086 -116.627148) (xy 403.204172 -116.627148) (xy 403.180804 -116.60378)
				(xy 401.753832 -116.60378) (xy 401.59051 -116.767102) (xy 401.59051 -118.22684) (xy 402.03247 -118.6688)
				(xy 405.5872 -118.6688) (xy 405.638 -118.618) (xy 405.638 -116.491766) (xy 405.559006 -116.412772)
			)
		)
		(polygon
			(pts
				(xy 404.8506 -117.2464) (xy 404.6474 -117.2464) (xy 404.6474 -117.4496) (xy 404.8506 -117.4496)
			)
		)
		(polygon
			(pts
				(xy 404.8506 -117.7544) (xy 404.6474 -117.7544) (xy 404.6474 -117.9576) (xy 404.8506 -117.9576)
			)
		)
	)
	(zone
		(layer "F.Cu")
		(hatch none 0.5)
		(connect_pads
			(clearance 0)
		)
		(min_thickness 0.25)
		(keepout
			(tracks not_allowed)
			(vias allowed)
			(pads allowed)
			(copperpour not_allowed)
			(footprints allowed)
		)
		(placement
			(enabled no)
			(sheetname "")
		)
		(fill
			(thermal_gap 0.5)
			(thermal_bridge_width 0.5)
			(island_removal_mode 0)
		)
		(polygon
			(pts
				(arc
					(start 11.84275 -28.641802)
					(mid 11.9126 -28.117885)
					(end 11.98245 -28.641802)
				)
				(xy 11.98245 -28.755594) (xy 12.055856 -28.829) (xy 12.29614 -28.829)
				(arc
					(start 12.29614 -28.384754)
					(mid 11.912727 -28.00096)
					(end 11.52906 -28.3845)
				)
				(arc
					(start 11.52906 -29.6545)
					(mid 11.9126 -30.03804)
					(end 12.29614 -29.6545)
				)
				(xy 12.29614 -29.21) (xy 12.055856 -29.21) (xy 11.98245 -29.283406)
				(arc
					(start 11.98245 -29.397198)
					(mid 11.9126 -29.921115)
					(end 11.84275 -29.397198)
				)
				(xy 11.84275 -29.225494) (xy 11.997944 -29.0703) (xy 12.29614 -29.0703) (xy 12.29614 -28.9687) (xy 11.997944 -28.9687)
				(xy 11.84275 -28.813506)
			)
		)
	)
	(zone
		(net "PVDDQ_KLM")
		(layer "F.Cu")
		(hatch none 0.5)
		(connect_pads
			(clearance 0.5)
		)
		(min_thickness 0.25)
		(fill yes
			(thermal_gap 0.5)
			(thermal_bridge_width 0.5)
			(island_removal_mode 0)
		)
		(polygon
			(pts
				(arc
					(start 107.25277 -148.48078)
					(mid 107.050105 -149.129487)
					(end 106.84637 -148.481034)
				)
				(xy 106.86796 -148.466048) (xy 106.86796 -148.370036)
				(arc
					(start 105.693718 -148.370036)
					(mid 105.601374 -148.429823)
					(end 105.617518 -148.538692)
				)
				(arc
					(start 105.617518 -148.538692)
					(mid 105.349802 -149.129413)
					(end 105.082086 -148.538692)
				)
				(arc
					(start 105.082086 -148.538692)
					(mid 105.098315 -148.429785)
					(end 105.005886 -148.370036)
				)
				(arc
					(start 104.84358 -148.370036)
					(mid 104.751236 -148.429823)
					(end 104.76738 -148.538692)
				)
				(arc
					(start 104.76738 -148.538692)
					(mid 104.499664 -149.129413)
					(end 104.231948 -148.538692)
				)
				(arc
					(start 104.231948 -148.538692)
					(mid 104.248177 -148.429785)
					(end 104.155748 -148.370036)
				)
				(arc
					(start 103.143558 -148.370036)
					(mid 103.051214 -148.429823)
					(end 103.067358 -148.538692)
				)
				(arc
					(start 103.067358 -148.538692)
					(mid 102.799642 -149.129413)
					(end 102.531926 -148.538692)
				)
				(arc
					(start 102.531926 -148.538692)
					(mid 102.548155 -148.429785)
					(end 102.455726 -148.370036)
				)
				(arc
					(start 102.293674 -148.370036)
					(mid 102.20133 -148.429823)
					(end 102.217474 -148.538692)
				)
				(arc
					(start 102.217474 -148.538692)
					(mid 101.949758 -149.129413)
					(end 101.682042 -148.538692)
				)
				(arc
					(start 101.682042 -148.538692)
					(mid 101.698271 -148.429785)
					(end 101.605842 -148.370036)
				)
				(xy 100.928932 -148.370036) (xy 100.677726 -148.621242)
				(arc
					(start 100.677726 -150.457916)
					(mid 100.739948 -150.551575)
					(end 100.850446 -150.53056)
				)
				(arc
					(start 100.850446 -150.53056)
					(mid 101.273295 -150.474449)
					(end 101.446584 -150.864316)
				)
				(arc
					(start 101.446584 -150.864316)
					(mid 101.466206 -150.950274)
					(end 101.545644 -150.988522)
				)
				(arc
					(start 102.352602 -150.988522)
					(mid 102.431785 -150.950582)
					(end 102.451916 -150.865078)
				)
				(arc
					(start 102.451916 -150.865078)
					(mid 102.799642 -150.432901)
					(end 103.147368 -150.865078)
				)
				(arc
					(start 103.147368 -150.865078)
					(mid 103.16743 -150.950637)
					(end 103.246682 -150.988522)
				)
				(xy 103.323136 -150.988522) (xy 103.323136 -150.927816)
				(arc
					(start 103.319326 -150.918672)
					(mid 103.621045 -150.430003)
					(end 103.996744 -150.864316)
				)
				(arc
					(start 103.996744 -150.864316)
					(mid 104.016366 -150.950274)
					(end 104.095804 -150.988522)
				)
				(arc
					(start 104.902762 -150.988522)
					(mid 104.981945 -150.950582)
					(end 105.002076 -150.865078)
				)
				(arc
					(start 105.002076 -150.865078)
					(mid 105.349802 -150.432901)
					(end 105.697528 -150.865078)
				)
				(arc
					(start 105.697528 -150.865078)
					(mid 105.71759 -150.950637)
					(end 105.796842 -150.988522)
				)
				(arc
					(start 106.602784 -150.988522)
					(mid 106.681967 -150.950582)
					(end 106.702098 -150.865078)
				)
				(arc
					(start 106.702098 -150.865078)
					(mid 107.049824 -150.432901)
					(end 107.39755 -150.865078)
				)
				(arc
					(start 107.39755 -150.865078)
					(mid 107.417612 -150.950637)
					(end 107.496864 -150.988522)
				)
				(xy 107.573064 -150.988522) (xy 107.573064 -150.927816)
				(arc
					(start 107.569254 -150.918672)
					(mid 107.870973 -150.430003)
					(end 108.246672 -150.864316)
				)
				(arc
					(start 108.246672 -150.864316)
					(mid 108.266294 -150.950274)
					(end 108.345732 -150.988522)
				)
				(arc
					(start 109.153198 -150.988522)
					(mid 109.232631 -150.95027)
					(end 109.252258 -150.864316)
				)
				(arc
					(start 109.252258 -150.864316)
					(mid 109.599476 -150.428921)
					(end 109.946694 -150.864316)
				)
				(arc
					(start 109.946694 -150.864316)
					(mid 109.966316 -150.950274)
					(end 110.045754 -150.988522)
				)
				(arc
					(start 110.852458 -150.988522)
					(mid 110.931389 -150.95058)
					(end 110.951518 -150.865332)
				)
				(arc
					(start 110.951518 -150.865332)
					(mid 111.299498 -150.433215)
					(end 111.647478 -150.865332)
				)
				(arc
					(start 111.647478 -150.865332)
					(mid 111.667581 -150.9506)
					(end 111.746538 -150.988522)
				)
				(xy 112.326166 -150.988522) (xy 112.528604 -150.786084) (xy 112.528604 -150.490936) (xy 112.47882 -150.441152)
				(xy 111.831628 -150.441152) (xy 111.699548 -150.309072) (xy 111.698024 -150.309072) (xy 111.697516 -150.30958)
				(xy 111.448596 -150.30958) (xy 111.43615 -150.297134) (xy 111.43615 -149.307296) (xy 111.571024 -149.172422)
				(xy 112.517936 -149.172422) (xy 112.528604 -149.161754) (xy 112.528604 -148.55825) (xy 112.34039 -148.370036)
				(arc
					(start 111.643922 -148.370036)
					(mid 111.551578 -148.429823)
					(end 111.567722 -148.538692)
				)
				(arc
					(start 111.567722 -148.538692)
					(mid 111.300006 -149.129413)
					(end 111.03229 -148.538692)
				)
				(arc
					(start 111.03229 -148.538692)
					(mid 111.048519 -148.429785)
					(end 110.95609 -148.370036)
				)
				(arc
					(start 110.793784 -148.370036)
					(mid 110.70144 -148.429823)
					(end 110.717584 -148.538692)
				)
				(arc
					(start 110.717584 -148.538692)
					(mid 110.449868 -149.129413)
					(end 110.182152 -148.538692)
				)
				(arc
					(start 110.182152 -148.538692)
					(mid 110.198381 -148.429785)
					(end 110.105952 -148.370036)
				)
				(arc
					(start 109.093762 -148.370036)
					(mid 109.001418 -148.429823)
					(end 109.017562 -148.538692)
				)
				(arc
					(start 109.017562 -148.538692)
					(mid 108.749846 -149.129413)
					(end 108.48213 -148.538692)
				)
				(arc
					(start 108.48213 -148.538692)
					(mid 108.498359 -148.429785)
					(end 108.40593 -148.370036)
				)
				(xy 107.23118 -148.370036) (xy 107.23118 -148.465794)
			)
		)
		(polygon
			(pts
				(xy 110.657132 -150.2029) (xy 110.453932 -150.2029) (xy 110.453932 -150.4061) (xy 110.657132 -150.4061)
			)
		)
		(polygon
			(pts
				(xy 107.5182 -150.2029) (xy 107.315 -150.2029) (xy 107.315 -150.4061) (xy 107.5182 -150.4061)
			)
		)
		(polygon
			(pts
				(xy 104.2162 -150.2029) (xy 104.013 -150.2029) (xy 104.013 -150.4061) (xy 104.2162 -150.4061)
			)
		)
		(polygon
			(pts
				(xy 107.5182 -149.2123) (xy 107.315 -149.2123) (xy 107.315 -149.4155) (xy 107.5182 -149.4155)
			)
		)
		(polygon
			(pts
				(xy 104.2162 -149.2123) (xy 104.013 -149.2123) (xy 104.013 -149.4155) (xy 104.2162 -149.4155)
			)
		)
		(polygon
			(pts
				(xy 101.0539 -149.2123) (xy 100.8507 -149.2123) (xy 100.8507 -149.4155) (xy 101.0539 -149.4155)
			)
		)
	)
	(zone
		(net "PVCCIO_CPU0")
		(layer "F.Cu")
		(hatch none 0.5)
		(connect_pads
			(clearance 0.5)
		)
		(min_thickness 0.25)
		(fill yes
			(thermal_gap 0.5)
			(thermal_bridge_width 0.5)
			(island_removal_mode 0)
		)
		(polygon
			(pts
				(xy 332.74 -94.869) (xy 331.2414 -96.3676) (xy 331.2414 -106.5276) (xy 329.2602 -108.5088) (xy 329.2602 -109.3978)
				(xy 329.311 -109.4486) (xy 330.0222 -109.4486) (xy 332.0542 -107.4166) (xy 339.5472 -107.4166) (xy 339.8266 -107.1372)
				(xy 339.8266 -101.2444) (xy 339.0646 -100.4824) (xy 339.0646 -95.2246) (xy 338.709 -94.869)
			)
		)
		(polygon
			(pts
				(xy 339.0519 -104.2162) (xy 338.8487 -104.2162) (xy 338.8487 -104.4194) (xy 339.0519 -104.4194)
			)
		)
		(polygon
			(pts
				(xy 339.0519 -103.4542) (xy 338.8487 -103.4542) (xy 338.8487 -103.6574) (xy 339.0519 -103.6574)
			)
		)
		(polygon
			(pts
				(xy 339.0519 -102.9716) (xy 338.8487 -102.9716) (xy 338.8487 -103.1748) (xy 339.0519 -103.1748)
			)
		)
		(polygon
			(pts
				(xy 339.0519 -102.2096) (xy 338.8487 -102.2096) (xy 338.8487 -102.4128) (xy 339.0519 -102.4128)
			)
		)
	)
	(zone
		(layer "F.Cu")
		(hatch none 0.5)
		(connect_pads
			(clearance 0)
		)
		(min_thickness 0.25)
		(keepout
			(tracks not_allowed)
			(vias allowed)
			(pads allowed)
			(copperpour not_allowed)
			(footprints allowed)
		)
		(placement
			(enabled no)
			(sheetname "")
		)
		(fill
			(thermal_gap 0.5)
			(thermal_bridge_width 0.5)
			(island_removal_mode 0)
		)
		(polygon
			(pts
				(arc
					(start 384.92049 -34.154618)
					(mid 384.767655 -34.327427)
					(end 384.537204 -34.316416)
				)
				(xy 384.420364 -34.433002) (xy 384.40741 -34.433002) (xy 384.40741 -34.682684)
				(arc
					(start 384.537204 -34.812224)
					(mid 384.76767 -34.801178)
					(end 384.92049 -34.974022)
				)
			)
		)
	)
	(zone
		(layer "F.Cu")
		(hatch none 0.5)
		(connect_pads
			(clearance 0)
		)
		(min_thickness 0.25)
		(keepout
			(tracks not_allowed)
			(vias allowed)
			(pads allowed)
			(copperpour not_allowed)
			(footprints allowed)
		)
		(placement
			(enabled no)
			(sheetname "")
		)
		(fill
			(thermal_gap 0.5)
			(thermal_bridge_width 0.5)
			(island_removal_mode 0)
		)
		(polygon
			(pts
				(xy 461.15605 -63.588138) (xy 461.118966 -63.551054) (xy 461.118966 -63.498222) (xy 461.118966 -63.235332)
				(xy 461.118966 -63.217552) (xy 460.787496 -63.217552) (xy 460.787496 -63.246254) (xy 460.787496 -63.498476)
				(xy 460.787496 -63.551308) (xy 460.750412 -63.588392) (xy 460.685896 -63.652908) (xy 460.648812 -63.689992)
				(xy 460.59598 -63.689992)
				(arc
					(start 460.578708 -63.689992)
					(mid 460.05288 -63.626492)
					(end 460.578708 -63.562992)
				)
				(xy 460.59598 -63.562992) (xy 460.660496 -63.498476) (xy 460.660496 -63.246254) (xy 460.631794 -63.217552)
				(arc
					(start 460.319882 -63.217552)
					(mid 459.910688 -63.626365)
					(end 460.319628 -64.035432)
				)
				(arc
					(start 461.589628 -64.035432)
					(mid 461.998568 -63.626492)
					(end 461.589628 -63.217552)
				)
				(xy 461.263746 -63.217552) (xy 461.245966 -63.235332) (xy 461.245966 -63.498222) (xy 461.310736 -63.562992)
				(arc
					(start 461.330548 -63.562992)
					(mid 461.856376 -63.626492)
					(end 461.330548 -63.689992)
				)
				(xy 461.310736 -63.689992) (xy 461.257904 -63.689992) (xy 461.22082 -63.652908)
			)
		)
	)
	(zone
		(layer "F.Cu")
		(hatch none 0.5)
		(connect_pads
			(clearance 0)
		)
		(min_thickness 0.25)
		(keepout
			(tracks allowed)
			(vias allowed)
			(pads allowed)
			(copperpour allowed)
			(footprints not_allowed)
		)
		(placement
			(enabled no)
			(sheetname "")
		)
		(fill
			(thermal_gap 0.5)
			(thermal_bridge_width 0.5)
			(island_removal_mode 0)
		)
		(polygon
			(pts
				(arc
					(start 127 -109.650022)
					(mid 128.900174 -111.550196)
					(end 127 -113.450116)
				)
				(arc
					(start 127 -113.450116)
					(mid 125.10008 -111.550196)
					(end 127 -109.650022)
				)
			)
		)
	)
	(zone
		(net "GND")
		(layer "F.Cu")
		(hatch none 0.5)
		(connect_pads
			(clearance 0.5)
		)
		(min_thickness 0.25)
		(fill yes
			(thermal_gap 0.5)
			(thermal_bridge_width 0.5)
			(island_removal_mode 0)
		)
		(polygon
			(pts
				(xy 171.3992 -6.0452) (xy 171.3992 -4.4196) (xy 171.3992 -4.39166) (xy 171.3992 -4.35864) (xy 171.40555 -4.35229)
				(xy 171.40555 -4.04241) (xy 171.3865 -4.02336) (xy 171.37126 -4.00812) (xy 171.37126 -4.0005) (xy 171.37126 -2.22631)
				(xy 171.284392 -2.139442) (xy 169.680382 -2.139442) (xy 169.5704 -2.249424) (xy 169.5704 -3.81)
				(xy 169.3545 -4.0259) (xy 167.495982 -4.0259) (xy 167.203882 -4.318) (xy 167.1574 -4.318) (xy 165.8112 -4.318)
				(xy 165.6715 -4.1783) (xy 165.227 -4.1783) (xy 165.1 -4.3053) (xy 165.1 -4.445) (xy 165.1 -5.1054)
				(xy 165.3286 -5.334) (xy 167.259 -5.334) (xy 168.275 -4.318) (xy 168.3893 -4.318) (xy 168.4401 -4.2672)
				(xy 169.1513 -4.2672) (xy 169.2021 -4.318) (xy 169.3672 -4.318) (xy 169.4434 -4.318) (xy 169.5704 -4.445)
				(xy 169.5704 -4.5212) (xy 169.5704 -5.9944) (xy 169.7736 -6.1976) (xy 171.2468 -6.1976)
			)
		)
	)
	(zone
		(net "GND")
		(layer "F.Cu")
		(hatch none 0.5)
		(connect_pads
			(clearance 0.5)
		)
		(min_thickness 0.25)
		(fill yes
			(thermal_gap 0.5)
			(thermal_bridge_width 0.5)
			(island_removal_mode 0)
		)
		(polygon
			(pts
				(xy 406.057862 -123.419362) (xy 406.051512 -123.425712) (xy 404.538688 -123.425712) (xy 404.49627 -123.46813)
				(xy 404.49627 -124.530866) (xy 404.525226 -124.559822) (xy 404.525226 -125.536706) (xy 404.744936 -125.756416)
				(xy 404.744936 -126.159514) (xy 404.48865 -126.4158) (xy 403.31644 -126.4158) (xy 403.2504 -126.48184)
				(xy 403.2504 -127.370078) (xy 403.258274 -127.377952) (xy 406.784048 -127.377952) (xy 407.1366 -127.0254)
				(xy 407.1366 -126.3396) (xy 407.546556 -125.929644) (xy 407.546556 -125.481334) (xy 407.7462 -125.28169)
				(xy 409.877514 -125.28169) (xy 409.944062 -125.348238) (xy 410.681424 -125.348238) (xy 410.691076 -125.338586)
				(xy 410.691076 -124.83465) (xy 410.87548 -124.650246) (xy 410.996384 -124.650246) (xy 411.2006 -124.44603)
				(xy 411.2006 -123.646692) (xy 410.97327 -123.419362)
			)
		)
		(polygon
			(pts
				(xy 407.8986 -124.2949) (xy 407.6954 -124.2949) (xy 407.6954 -124.4981) (xy 407.8986 -124.4981)
			)
		)
		(polygon
			(pts
				(xy 408.6606 -124.2949) (xy 408.4574 -124.2949) (xy 408.4574 -124.4981) (xy 408.6606 -124.4981)
			)
		)
		(polygon
			(pts
				(xy 409.1686 -124.2949) (xy 408.9654 -124.2949) (xy 408.9654 -124.4981) (xy 409.1686 -124.4981)
			)
		)
		(polygon
			(pts
				(xy 409.9306 -124.2949) (xy 409.7274 -124.2949) (xy 409.7274 -124.4981) (xy 409.9306 -124.4981)
			)
		)
		(polygon
			(pts
				(xy 405.4348 -126.3904) (xy 405.2316 -126.3904) (xy 405.2316 -126.5936) (xy 405.4348 -126.5936)
			)
		)
		(polygon
			(pts
				(xy 405.9936 -126.3904) (xy 405.7904 -126.3904) (xy 405.7904 -126.5936) (xy 405.9936 -126.5936)
			)
		)
		(polygon
			(pts
				(xy 406.7556 -126.3904) (xy 406.5524 -126.3904) (xy 406.5524 -126.5936) (xy 406.7556 -126.5936)
			)
		)
	)
	(zone
		(layer "F.Cu")
		(hatch none 0.5)
		(connect_pads
			(clearance 0)
		)
		(min_thickness 0.25)
		(keepout
			(tracks not_allowed)
			(vias allowed)
			(pads allowed)
			(copperpour not_allowed)
			(footprints allowed)
		)
		(placement
			(enabled no)
			(sheetname "")
		)
		(fill
			(thermal_gap 0.5)
			(thermal_bridge_width 0.5)
			(island_removal_mode 0)
		)
		(polygon
			(pts
				(xy 455.237088 -121.35866) (xy 455.237088 -121.601738) (xy 455.026776 -121.81205)
				(arc
					(start 454.910952 -121.81205)
					(mid 454.387035 -121.7422)
					(end 454.910952 -121.67235)
				)
				(xy 454.968864 -121.67235) (xy 455.097388 -121.543826) (xy 455.097388 -121.35866)
				(arc
					(start 454.653904 -121.35866)
					(mid 454.27011 -121.742073)
					(end 454.65365 -122.12574)
				)
				(arc
					(start 455.92365 -122.12574)
					(mid 456.30719 -121.7422)
					(end 455.92365 -121.35866)
				)
				(xy 455.478388 -121.35866) (xy 455.478388 -121.542048) (xy 455.60869 -121.67235)
				(arc
					(start 455.666348 -121.67235)
					(mid 456.190265 -121.7422)
					(end 455.666348 -121.81205)
				)
				(xy 455.550778 -121.81205) (xy 455.338688 -121.59996) (xy 455.338688 -121.35866)
			)
		)
	)
	(zone
		(net "P12V_STBY")
		(layer "F.Cu")
		(hatch none 0.5)
		(connect_pads
			(clearance 0.5)
		)
		(min_thickness 0.25)
		(fill yes
			(thermal_gap 0.5)
			(thermal_bridge_width 0.5)
			(island_removal_mode 0)
		)
		(polygon
			(pts
				(xy 20.3454 -65.7098) (xy 21.6662 -65.7098) (xy 22.0091 -66.0527) (xy 25.1206 -66.0527) (xy 25.4 -65.7733)
				(xy 25.4 -65.2526) (xy 25.4 -61.9506) (xy 25.0698 -61.6204) (xy 20.4216 -61.6204) (xy 20.2692 -61.7728)
				(xy 20.2692 -65.6336)
			)
		)
	)
	(zone
		(net "P12V_NVDIMM_GHJ")
		(layer "F.Cu")
		(hatch none 0.5)
		(connect_pads
			(clearance 0.5)
		)
		(min_thickness 0.25)
		(fill yes
			(thermal_gap 0.5)
			(thermal_bridge_width 0.5)
			(island_removal_mode 0)
		)
		(polygon
			(pts
				(xy 25.482042 4.806442) (xy 25.019 4.3434) (xy 25.019 -18.91538) (xy 24.662892 -19.271488) (xy 23.343616 -19.271488)
				(xy 22.918674 -19.69643) (xy 22.918674 -20.033234) (xy 21.9456 -21.006308) (xy 21.9456 -24.199596)
				(xy 23.77694 -26.030936) (xy 27.529536 -26.030936) (xy 27.813 -26.3144) (xy 27.813 -27.3812) (xy 28.0416 -27.6098)
				(xy 30.27553 -27.6098) (xy 30.3784 -27.50693) (xy 30.734 -27.50693) (xy 31.0134 -27.78633) (xy 31.0134 -30.48)
				(xy 31.185104 -30.651704) (xy 34.550096 -30.651704) (xy 34.5948 -30.607) (xy 34.5948 -27.720036)
				(xy 30.84068 -23.965916) (xy 29.252926 -23.965916) (xy 28.992068 -24.226774) (xy 27.43327 -24.226774)
				(xy 26.826718 -23.620222) (xy 26.826718 -22.6822) (xy 27.05862 -22.450298) (xy 27.05862 -21.39188)
				(xy 27.05862 -21.356066) (xy 27.510486 -20.9042) (xy 27.5463 -20.9042) (xy 29.90342 -20.9042) (xy 30.00248 -20.80514)
				(xy 30.00248 -14.54658) (xy 29.69514 -14.23924) (xy 26.87574 -14.23924) (xy 26.460958 -13.824458)
				(xy 26.460958 -11.672062) (xy 26.81224 -11.32078) (xy 29.86786 -11.32078) (xy 29.96692 -11.22172)
				(xy 29.96692 -4.9657) (xy 29.8196 -4.81838) (xy 26.98496 -4.81838) (xy 26.460958 -4.294378) (xy 26.460958 -2.34188)
				(xy 26.841958 -1.96088) (xy 29.80436 -1.96088) (xy 29.95422 -1.81102) (xy 29.95422 4.70154) (xy 29.849318 4.806442)
			)
		)
		(polygon
			(pts
				(xy 29.978096 -26.604722) (xy 29.774896 -26.604722) (xy 29.774896 -26.807922) (xy 29.978096 -26.807922)
			)
		)
		(polygon
			(pts
				(xy 29.216096 -26.604722) (xy 29.012896 -26.604722) (xy 29.012896 -26.807922) (xy 29.216096 -26.807922)
			)
		)
	)
	(zone
		(layer "F.Cu")
		(hatch none 0.5)
		(connect_pads
			(clearance 0)
		)
		(min_thickness 0.25)
		(keepout
			(tracks allowed)
			(vias allowed)
			(pads allowed)
			(copperpour allowed)
			(footprints allowed)
		)
		(placement
			(enabled no)
			(sheetname "")
		)
		(fill
			(thermal_gap 0.5)
			(thermal_bridge_width 0.5)
			(island_removal_mode 0)
		)
		(polygon
			(pts
				(xy 278.6888 4.7752) (xy 278.6888 5.2324) (xy 280.6446 5.2324) (xy 280.6446 4.7752)
			)
		)
	)
	(zone
		(net "GND")
		(layer "F.Cu")
		(hatch none 0.5)
		(connect_pads
			(clearance 0.5)
		)
		(min_thickness 0.25)
		(fill yes
			(thermal_gap 0.5)
			(thermal_bridge_width 0.5)
			(island_removal_mode 0)
		)
		(polygon
			(pts
				(xy 329.2348 -113.157) (xy 329.438 -113.3602) (xy 338.327238 -113.3602) (xy 338.410296 -113.3602)
				(xy 339.061552 -114.011456) (xy 339.061552 -114.558826) (xy 338.867242 -114.753136) (xy 338.867242 -115.06073)
				(xy 338.9884 -115.181888) (xy 339.060282 -115.25377) (xy 339.060282 -115.908582) (xy 338.9884 -115.980464)
				(xy 338.858606 -116.110258) (xy 338.858606 -116.379244) (xy 338.963762 -116.4844) (xy 339.0646 -116.4844)
				(xy 340.6394 -116.4844) (xy 341.39886 -115.72494) (xy 341.39886 -113.007394) (xy 341.9856 -112.4204)
				(xy 342.6206 -112.4204) (xy 343.234264 -113.029746) (xy 343.234264 -113.220754) (xy 343.436702 -113.423192)
				(xy 343.436702 -113.880392) (xy 343.234264 -114.08283) (xy 343.234264 -114.509042) (xy 343.437718 -114.712496)
				(xy 343.437718 -115.18392) (xy 343.23909 -115.382548) (xy 343.23909 -115.754658) (xy 343.417652 -115.93322)
				(xy 343.662254 -115.93322) (xy 344.245184 -115.35029) (xy 344.245184 -112.785906) (xy 344.415618 -112.615472)
				(xy 344.58783 -112.44326) (xy 345.26474 -112.44326) (xy 345.764612 -112.943132) (xy 345.764612 -113.098072)
				(xy 345.764612 -113.244376) (xy 345.975432 -113.455196) (xy 345.975432 -113.95837) (xy 345.78671 -114.147092)
				(xy 345.78671 -114.529362) (xy 345.974416 -114.717068) (xy 345.974416 -115.235736) (xy 345.79179 -115.418362)
				(xy 345.79179 -115.73637) (xy 345.993212 -115.937792) (xy 346.341954 -115.937792) (xy 346.992702 -115.287044)
				(xy 346.992702 -114.615722) (xy 346.920566 -114.543586) (xy 346.920566 -114.097562) (xy 346.992702 -114.025426)
				(xy 347.166946 -113.851182) (xy 347.245686 -113.851182) (xy 347.834458 -113.26241) (xy 348.185486 -113.26241)
				(xy 348.200218 -113.277142) (xy 348.200218 -113.280444) (xy 348.320614 -113.40084) (xy 348.885764 -113.40084)
				(xy 349.29572 -112.990884) (xy 349.29572 -112.73155) (xy 349.536004 -112.491266) (xy 349.536004 -112.173258)
				(xy 349.387414 -112.024668) (xy 348.784926 -111.42218) (xy 348.488 -111.42218) (xy 348.365572 -111.544608)
				(xy 348.243652 -111.666528) (xy 347.738192 -111.666528) (xy 347.501718 -111.430054) (xy 347.24848 -111.430054)
				(xy 347.041724 -111.63681) (xy 346.634816 -111.63681) (xy 346.618306 -111.6203) (xy 346.361004 -111.362998)
				(xy 346.361004 -110.891066) (xy 346.548456 -110.703614) (xy 346.548456 -110.242604) (xy 346.36329 -110.057438)
				(xy 346.36329 -109.689646) (xy 346.560394 -109.492542) (xy 346.560394 -109.028738) (xy 345.837256 -108.3056)
				(xy 344.4748 -108.3056) (xy 342.5952 -108.3056) (xy 341.48141 -108.3056) (xy 341.374984 -108.412026)
				(xy 340.6394 -108.412026) (xy 340.532974 -108.3056) (xy 339.7758 -108.3056) (xy 339.530182 -108.551218)
				(xy 339.530182 -110.083854) (xy 339.4964 -110.117636) (xy 338.684362 -110.929674) (xy 338.290154 -110.929674)
				(xy 338.030058 -110.669578) (xy 338.030058 -110.25124) (xy 338.264246 -110.017052) (xy 338.264246 -108.394246)
				(xy 338.1756 -108.3056) (xy 336.97037 -108.3056) (xy 331.527912 -108.3056) (xy 330.714858 -109.118654)
				(xy 330.714858 -109.120178) (xy 330.714858 -109.15269) (xy 330.714858 -110.150402) (xy 330.69784 -110.16742)
				(xy 330.058268 -110.806992) (xy 330.058268 -111.995458) (xy 329.18146 -112.872266) (xy 329.18146 -113.10366)
			)
		)
	)
	(zone
		(layer "F.Cu")
		(hatch none 0.5)
		(connect_pads
			(clearance 0)
		)
		(min_thickness 0.25)
		(keepout
			(tracks allowed)
			(vias allowed)
			(pads allowed)
			(copperpour allowed)
			(footprints allowed)
		)
		(placement
			(enabled no)
			(sheetname "")
		)
		(fill
			(thermal_gap 0.5)
			(thermal_bridge_width 0.5)
			(island_removal_mode 0)
		)
		(polygon
			(pts
				(xy 197.612 -67.3862) (xy 197.612 -63.0174) (xy 200.025 -63.0174) (xy 200.025 -67.3862)
			)
		)
	)
	(zone
		(net "GND")
		(layer "F.Cu")
		(hatch none 0.5)
		(connect_pads
			(clearance 0.5)
		)
		(min_thickness 0.25)
		(fill yes
			(thermal_gap 0.5)
			(thermal_bridge_width 0.5)
			(island_removal_mode 0)
		)
		(polygon
			(pts
				(xy 483.5398 -118.1481) (xy 483.5398 -115.2652) (xy 484.3018 -114.5032) (xy 484.3018 -111.0742)
				(xy 484.302308 -111.073692) (xy 484.302308 -111.042704) (xy 484.333296 -111.011716) (xy 484.364284 -111.011716)
				(xy 484.364792 -111.012224) (xy 485.611424 -111.012224) (xy 485.648 -111.0488) (xy 485.648 -114.1984)
				(xy 484.8606 -114.9858) (xy 484.8606 -118.1481) (xy 484.7717 -118.237) (xy 483.6287 -118.237)
			)
		)
	)
	(zone
		(net "GND")
		(layer "F.Cu")
		(hatch none 0.5)
		(connect_pads
			(clearance 0.5)
		)
		(min_thickness 0.25)
		(fill yes
			(thermal_gap 0.5)
			(thermal_bridge_width 0.5)
			(island_removal_mode 0)
		)
		(polygon
			(pts
				(xy 183.074564 -148.853144) (xy 183.07812 -148.8567) (xy 183.160924 -148.8567) (xy 184.176924 -148.8567)
				(xy 184.303924 -148.8567) (xy 184.436512 -148.724112) (xy 184.9374 -148.724112) (xy 185.065924 -148.852636)
				(xy 185.065924 -148.9837) (xy 185.065924 -150.5077) (xy 184.938924 -150.6347) (xy 179.858924 -150.6347)
				(xy 179.2605 -150.6347) (xy 179.0954 -150.4696) (xy 179.0954 -148.9964) (xy 179.2351 -148.8567)
				(xy 179.985924 -148.8567) (xy 181.2036 -148.8567) (xy 182.6387 -148.8567) (xy 182.642256 -148.853144)
			)
		)
	)
	(zone
		(net "VR_FET_SW_P12V_STBY_PVCCIN_CPU1")
		(layer "F.Cu")
		(hatch none 0.5)
		(connect_pads
			(clearance 0.5)
		)
		(min_thickness 0.25)
		(fill yes
			(thermal_gap 0.5)
			(thermal_bridge_width 0.5)
			(island_removal_mode 0)
		)
		(polygon
			(pts
				(xy 24.511 -48.5648) (xy 24.3332 -48.7426) (xy 24.3332 -50.769774) (xy 23.707852 -51.395122) (xy 23.707852 -52.438046)
				(xy 23.917656 -52.64785) (xy 24.191976 -52.64785) (xy 25.07361 -52.64785) (xy 27.510486 -52.64785)
				(xy 29.106622 -51.051714) (xy 29.106622 -50.965862) (xy 29.106622 -49.375822) (xy 28.2956 -48.5648)
			)
		)
	)
	(zone
		(net "PVPP_GHJ")
		(layer "F.Cu")
		(hatch none 0.5)
		(connect_pads
			(clearance 0.5)
		)
		(min_thickness 0.25)
		(fill yes
			(thermal_gap 0.5)
			(thermal_bridge_width 0.5)
			(island_removal_mode 0)
		)
		(polygon
			(pts
				(xy 132.402834 -51.70551) (xy 132.402834 -51.292252) (xy 132.779516 -50.91557) (xy 136.707118 -50.91557)
				(xy 136.874504 -50.91557) (xy 137.0711 -51.112166) (xy 137.0711 -51.51374) (xy 136.891268 -51.693572)
				(xy 136.172702 -51.693572) (xy 136.051798 -51.572668) (xy 135.378698 -51.572668) (xy 134.885684 -52.065682)
				(xy 134.506462 -52.065682) (xy 134.366762 -52.205382) (xy 133.527038 -52.205382) (xy 133.387338 -52.065682)
				(xy 133.31444 -52.065682) (xy 133.307074 -52.073048) (xy 132.770372 -52.073048)
			)
		)
	)
	(zone
		(net "VR_PVPP_ABC_PHASE")
		(layer "F.Cu")
		(hatch none 0.5)
		(connect_pads
			(clearance 0.5)
		)
		(min_thickness 0.25)
		(fill yes
			(thermal_gap 0.5)
			(thermal_bridge_width 0.5)
			(island_removal_mode 0)
		)
		(polygon
			(pts
				(xy 337.730846 -24.855932) (xy 337.6422 -24.944578) (xy 337.6422 -31.5976) (xy 339.15985 -33.11525)
				(xy 342.138 -33.11525) (xy 342.3158 -32.93745) (xy 342.3158 -32.2453) (xy 342.5698 -31.9913) (xy 343.5858 -31.9913)
				(xy 343.7128 -31.8643) (xy 343.7128 -30.8483) (xy 343.8398 -30.7213) (xy 347.3958 -30.7213) (xy 347.5228 -30.5943)
				(xy 347.5228 -28.4353) (xy 347.3958 -28.3083) (xy 343.2048 -28.3083) (xy 342.8238 -28.6893) (xy 341.8078 -28.6893)
				(xy 340.96325 -27.84475) (xy 340.138004 -27.84475) (xy 338.67852 -26.385266) (xy 338.67852 -24.882602)
				(xy 338.65185 -24.855932)
			)
		)
	)
	(zone
		(layer "F.Cu")
		(hatch none 0.5)
		(connect_pads
			(clearance 0)
		)
		(min_thickness 0.25)
		(keepout
			(tracks allowed)
			(vias allowed)
			(pads allowed)
			(copperpour allowed)
			(footprints allowed)
		)
		(placement
			(enabled no)
			(sheetname "")
		)
		(fill
			(thermal_gap 0.5)
			(thermal_bridge_width 0.5)
			(island_removal_mode 0)
		)
		(polygon
			(pts
				(xy 481.371148 -33.463992) (xy 482.324156 -33.463992) (xy 482.324156 -35.030156) (xy 481.371148 -35.030156)
			)
		)
	)
	(zone
		(layer "F.Cu")
		(hatch none 0.5)
		(connect_pads
			(clearance 0)
		)
		(min_thickness 0.25)
		(keepout
			(tracks allowed)
			(vias allowed)
			(pads allowed)
			(copperpour allowed)
			(footprints allowed)
		)
		(placement
			(enabled no)
			(sheetname "")
		)
		(fill
			(thermal_gap 0.5)
			(thermal_bridge_width 0.5)
			(island_removal_mode 0)
		)
		(polygon
			(pts
				(xy 43.533568 -24.511) (xy 43.533568 -22.479) (xy 45.692568 -22.479) (xy 45.692568 -24.511)
			)
		)
	)
	(zone
		(layer "F.Cu")
		(hatch none 0.5)
		(connect_pads
			(clearance 0)
		)
		(min_thickness 0.25)
		(keepout
			(tracks allowed)
			(vias allowed)
			(pads allowed)
			(copperpour allowed)
			(footprints not_allowed)
		)
		(placement
			(enabled no)
			(sheetname "")
		)
		(fill
			(thermal_gap 0.5)
			(thermal_bridge_width 0.5)
			(island_removal_mode 0)
		)
		(polygon
			(pts
				(arc
					(start 198.930006 -105.000044)
					(mid 200.480168 -106.550206)
					(end 198.930006 -108.100114)
				)
				(arc
					(start 198.930006 -108.100114)
					(mid 197.380098 -106.550206)
					(end 198.930006 -105.000044)
				)
			)
		)
	)
	(zone
		(net "GND")
		(layer "F.Cu")
		(hatch none 0.5)
		(connect_pads
			(clearance 0.5)
		)
		(min_thickness 0.25)
		(fill yes
			(thermal_gap 0.5)
			(thermal_bridge_width 0.5)
			(island_removal_mode 0)
		)
		(polygon
			(pts
				(xy 482.49459 -45.76318) (xy 485.93883 -45.76318) (xy 486.03789 -45.66412) (xy 486.03789 -42.26052)
				(xy 485.94899 -42.17162) (xy 482.58095 -42.17162) (xy 482.46411 -42.28846) (xy 482.46411 -45.7327)
			)
		)
	)
	(zone
		(net "P3V3_STBY")
		(layer "F.Cu")
		(hatch none 0.5)
		(connect_pads
			(clearance 0.5)
		)
		(min_thickness 0.25)
		(fill yes
			(thermal_gap 0.5)
			(thermal_bridge_width 0.5)
			(island_removal_mode 0)
		)
		(polygon
			(pts
				(xy 430.9618 -47.965868) (xy 432.086258 -47.965868) (xy 432.725068 -47.965868) (xy 432.8668 -48.1076)
				(xy 432.8668 -49.2252) (xy 431.927 -50.165) (xy 431.927 -50.7492) (xy 431.8508 -50.8254) (xy 430.7332 -50.8254)
				(xy 430.657 -50.7492) (xy 430.657 -49.6824) (xy 430.8348 -49.5046) (xy 430.8348 -48.092868)
			)
		)
	)
	(zone
		(layer "F.Cu")
		(hatch none 0.5)
		(connect_pads
			(clearance 0.5)
		)
		(min_thickness 0.25)
		(fill
			(thermal_gap 0.5)
			(thermal_bridge_width 0.5)
			(island_removal_mode 0)
		)
		(polygon
			(pts
				(xy 31.486602 -91.444064) (xy 31.613602 -91.317064) (xy 31.613602 -91.30538) (xy 31.6484 -91.270582)
				(xy 31.6484 -89.93378) (xy 33.630616 -89.93378) (xy 33.630616 -92.29598) (xy 33.434782 -92.491814)
				(xy 33.434782 -93.18879) (xy 33.35147 -93.272102) (xy 33.127188 -93.272102) (xy 32.71012 -92.855034)
				(xy 31.987998 -92.855034) (xy 31.636716 -93.206316) (xy 31.332424 -93.206316) (xy 29.452316 -93.206316)
				(xy 29.302964 -93.056964) (xy 28.829 -92.583) (xy 28.829 -92.03944) (xy 28.8798 -91.98864) (xy 30.189424 -91.98864)
				(xy 30.357064 -91.821) (xy 30.734 -91.444064)
			)
		)
	)
	(zone
		(net "GND")
		(layer "F.Cu")
		(hatch none 0.5)
		(connect_pads
			(clearance 0.5)
		)
		(min_thickness 0.25)
		(fill yes
			(thermal_gap 0.5)
			(thermal_bridge_width 0.5)
			(island_removal_mode 0)
		)
		(polygon
			(pts
				(xy 396.13713 -138.988292) (xy 395.689328 -139.436094) (xy 395.689328 -143.350234) (xy 395.734794 -143.3957)
				(xy 395.734794 -146.107658) (xy 395.530324 -146.312128) (xy 395.530324 -147.423124) (xy 395.5796 -147.4724)
				(xy 397.1036 -147.4724) (xy 398.011396 -146.564604) (xy 398.011396 -145.146268) (xy 398.714468 -144.443196)
				(xy 400.532346 -144.443196) (xy 401.597622 -145.508472) (xy 403.013672 -145.508472) (xy 403.071584 -145.45056)
				(xy 403.071584 -144.700498) (xy 403.174962 -144.59712) (xy 403.174962 -141.06144) (xy 402.919692 -140.80617)
				(xy 401.604734 -140.80617) (xy 399.786856 -138.988292)
			)
		)
		(polygon
			(pts
				(xy 396.5194 -146.5326) (xy 396.3162 -146.5326) (xy 396.3162 -146.7358) (xy 396.5194 -146.7358)
			)
		)
		(polygon
			(pts
				(xy 402.29028 -144.603216) (xy 402.08708 -144.603216) (xy 402.08708 -144.806416) (xy 402.29028 -144.806416)
			)
		)
	)
	(zone
		(layer "F.Cu")
		(hatch none 0.5)
		(connect_pads
			(clearance 0)
		)
		(min_thickness 0.25)
		(keepout
			(tracks not_allowed)
			(vias allowed)
			(pads allowed)
			(copperpour not_allowed)
			(footprints allowed)
		)
		(placement
			(enabled no)
			(sheetname "")
		)
		(fill
			(thermal_gap 0.5)
			(thermal_bridge_width 0.5)
			(island_removal_mode 0)
		)
		(polygon
			(pts
				(arc
					(start 416.652456 -91.83243)
					(mid 416.534 -91.317363)
					(end 416.783266 -91.783408)
				)
				(xy 416.935158 -91.9353) (xy 417.036504 -91.9353)
				(arc
					(start 417.036504 -91.567)
					(mid 416.627564 -91.15806)
					(end 416.218624 -91.567)
				)
				(arc
					(start 416.218624 -92.836746)
					(mid 416.627437 -93.24594)
					(end 417.036504 -92.837)
				)
				(xy 417.036504 -92.521024) (xy 417.033456 -92.521024)
				(arc
					(start 416.855656 -92.698824)
					(mid 416.438992 -93.025572)
					(end 416.76574 -92.608908)
				)
				(xy 416.94354 -92.431108) (xy 416.980624 -92.394024) (xy 416.980624 -92.39377) (xy 417.033456 -92.39377)
				(xy 417.033456 -92.394024) (xy 417.036504 -92.394024) (xy 417.036504 -92.0623) (xy 416.935158 -92.0623)
				(xy 416.935158 -92.062554) (xy 416.882326 -92.062554) (xy 416.882326 -92.0623) (xy 416.844988 -92.025216)
			)
		)
	)
	(zone
		(net "P3V3_STBY")
		(layer "F.Cu")
		(hatch none 0.5)
		(connect_pads
			(clearance 0.5)
		)
		(min_thickness 0.25)
		(fill yes
			(thermal_gap 0.5)
			(thermal_bridge_width 0.5)
			(island_removal_mode 0)
		)
		(polygon
			(pts
				(xy 464.03006 -11.4808) (xy 463.69986 -11.811) (xy 463.69859 -11.811) (xy 461.97139 -13.5382) (xy 461.97139 -15.51559)
				(xy 460.083408 -17.403572) (xy 453.25157 -17.403572) (xy 453.246998 -17.399) (xy 450.723 -17.399)
				(xy 450.469 -17.653) (xy 450.469 -20.447) (xy 450.529706 -20.507706) (xy 451.444106 -20.507706)
				(xy 451.8406 -20.9042) (xy 455.1934 -20.9042) (xy 455.355452 -21.066252) (xy 455.350372 -21.071332)
				(xy 455.350372 -23.5966) (xy 455.3966 -23.5966) (xy 456.059032 -24.259032) (xy 456.059032 -25.146)
				(xy 455.93 -25.275032) (xy 455.93 -25.908) (xy 456.057 -26.035) (xy 457.73848 -26.035) (xy 458.1525 -26.44902)
				(xy 458.65542 -26.44902) (xy 459.06944 -26.035) (xy 462.661 -26.035) (xy 462.9912 -25.7048) (xy 462.9912 -22.01164)
				(xy 463.01787 -21.98497) (xy 463.55127 -21.98497) (xy 464.1088 -21.42744) (xy 464.1088 -20.2692)
				(xy 464.3628 -20.0152) (xy 465.1248 -20.0152) (xy 465.2518 -20.1422) (xy 465.2518 -20.6502) (xy 465.3026 -20.701)
				(xy 465.963 -20.701) (xy 466.09 -20.574) (xy 466.09 -18.161) (xy 466.979 -17.272) (xy 467.487 -17.272)
				(xy 467.872572 -16.886428) (xy 467.872572 -12.995402) (xy 467.63178 -12.75461) (xy 467.63178 -11.54938)
				(xy 467.5632 -11.4808)
			)
		)
		(polygon
			(pts
				(xy 457.0476 -25.1206) (xy 456.8444 -25.1206) (xy 456.8444 -25.3238) (xy 457.0476 -25.3238)
			)
		)
		(polygon
			(pts
				(xy 457.0476 -24.3586) (xy 456.8444 -24.3586) (xy 456.8444 -24.5618) (xy 457.0476 -24.5618)
			)
		)
	)
	(zone
		(layer "F.Cu")
		(hatch none 0.5)
		(connect_pads
			(clearance 0)
		)
		(min_thickness 0.25)
		(keepout
			(tracks not_allowed)
			(vias allowed)
			(pads allowed)
			(copperpour not_allowed)
			(footprints allowed)
		)
		(placement
			(enabled no)
			(sheetname "")
		)
		(fill
			(thermal_gap 0.5)
			(thermal_bridge_width 0.5)
			(island_removal_mode 0)
		)
		(polygon
			(pts
				(xy 384.212592 -27.090624)
				(arc
					(start 384.406902 -27.284934)
					(mid 384.728067 -27.704905)
					(end 384.308096 -27.38374)
				)
				(xy 384.15595 -27.231594)
				(arc
					(start 384.15595 -27.516328)
					(mid 384.53949 -27.899868)
					(end 384.92303 -27.516328)
				)
				(arc
					(start 384.92303 -26.551382)
					(mid 384.539617 -26.167842)
					(end 384.15595 -26.551128)
				)
				(xy 384.15595 -26.835862)
				(arc
					(start 384.308096 -26.683716)
					(mid 384.728067 -26.362551)
					(end 384.406902 -26.782522)
				)
				(xy 384.2004 -26.989024) (xy 384.15595 -26.989024) (xy 384.15595 -27.090624)
			)
		)
	)
	(zone
		(net "VR_FET_SW_P12V_STBY_P3V3_STBY")
		(layer "F.Cu")
		(hatch none 0.5)
		(connect_pads
			(clearance 0.5)
		)
		(min_thickness 0.25)
		(fill yes
			(thermal_gap 0.5)
			(thermal_bridge_width 0.5)
			(island_removal_mode 0)
		)
		(polygon
			(pts
				(xy 472.052904 -23.876) (xy 473.94622 -23.876) (xy 474.14053 -23.68169) (xy 474.949012 -23.68169)
				(xy 475.089982 -23.68169) (xy 475.323916 -23.447756) (xy 475.323916 -22.830536) (xy 475.386146 -22.768306)
				(xy 478.272094 -22.768306) (xy 479.500692 -21.539708) (xy 479.805492 -21.539708) (xy 479.843338 -21.539708)
				(xy 482.5492 -21.539708) (xy 482.727508 -21.539708) (xy 482.7778 -21.59) (xy 482.7778 -22.8346)
				(xy 482.5492 -23.0632) (xy 482.4476 -23.1648) (xy 481.815902 -23.1648) (xy 481.6602 -23.320502)
				(xy 481.63226 -23.348442) (xy 481.63226 -25.173432) (xy 481.509578 -25.296114) (xy 479.508312 -25.296114)
				(xy 479.007932 -24.795734) (xy 476.186246 -24.795734) (xy 474.573854 -26.408126) (xy 473.845636 -26.408126)
				(xy 473.490036 -26.408126) (xy 473.188284 -26.709878) (xy 472.29903 -26.709878) (xy 472.2622 -26.709878)
				(xy 472.1225 -26.570178) (xy 472.1225 -25.6794) (xy 472.02217 -25.57907) (xy 472.02217 -24.60498)
				(xy 471.984324 -24.567134) (xy 471.984324 -23.94458)
			)
		)
	)
	(zone
		(net "P1V8_PCH_STBY")
		(layer "F.Cu")
		(hatch none 0.5)
		(connect_pads
			(clearance 0.5)
		)
		(min_thickness 0.25)
		(fill yes
			(thermal_gap 0.5)
			(thermal_bridge_width 0.5)
			(island_removal_mode 0)
		)
		(polygon
			(pts
				(xy 400.61642 -127.9144) (xy 400.33702 -128.1938) (xy 400.33702 -128.704594) (xy 399.78965 -129.251964)
				(xy 399.075402 -129.251964) (xy 398.538954 -128.715516) (xy 398.194276 -128.715516) (xy 398.108678 -128.801114)
				(xy 398.108678 -129.805938) (xy 398.89684 -130.5941) (xy 402.4757 -130.5941) (xy 403.987 -129.0828)
				(xy 408.6352 -129.0828) (xy 409.6893 -130.1369) (xy 410.7307 -130.1369) (xy 410.8958 -129.9718)
				(xy 410.8958 -128.651) (xy 410.1592 -127.9144)
			)
		)
		(polygon
			(pts
				(xy 403.352 -128.6764) (xy 403.1488 -128.6764) (xy 403.1488 -128.8796) (xy 403.352 -128.8796)
			)
		)
		(polygon
			(pts
				(xy 404.114 -128.6764) (xy 403.9108 -128.6764) (xy 403.9108 -128.8796) (xy 404.114 -128.8796)
			)
		)
		(polygon
			(pts
				(xy 404.6728 -128.6764) (xy 404.4696 -128.6764) (xy 404.4696 -128.8796) (xy 404.6728 -128.8796)
			)
		)
		(polygon
			(pts
				(xy 405.4348 -128.6764) (xy 405.2316 -128.6764) (xy 405.2316 -128.8796) (xy 405.4348 -128.8796)
			)
		)
		(polygon
			(pts
				(xy 405.9936 -128.6764) (xy 405.7904 -128.6764) (xy 405.7904 -128.8796) (xy 405.9936 -128.8796)
			)
		)
		(polygon
			(pts
				(xy 406.7556 -128.6764) (xy 406.5524 -128.6764) (xy 406.5524 -128.8796) (xy 406.7556 -128.8796)
			)
		)
		(polygon
			(pts
				(xy 399.6944 -129.6035) (xy 399.4912 -129.6035) (xy 399.4912 -129.8067) (xy 399.6944 -129.8067)
			)
		)
		(polygon
			(pts
				(xy 400.4564 -129.6035) (xy 400.2532 -129.6035) (xy 400.2532 -129.8067) (xy 400.4564 -129.8067)
			)
		)
		(polygon
			(pts
				(xy 400.9644 -129.6035) (xy 400.7612 -129.6035) (xy 400.7612 -129.8067) (xy 400.9644 -129.8067)
			)
		)
		(polygon
			(pts
				(xy 401.7264 -129.6035) (xy 401.5232 -129.6035) (xy 401.5232 -129.8067) (xy 401.7264 -129.8067)
			)
		)
	)
	(zone
		(layer "F.Cu")
		(hatch none 0.5)
		(connect_pads
			(clearance 0)
		)
		(min_thickness 0.25)
		(keepout
			(tracks allowed)
			(vias allowed)
			(pads allowed)
			(copperpour allowed)
			(footprints not_allowed)
		)
		(placement
			(enabled no)
			(sheetname "")
		)
		(fill
			(thermal_gap 0.5)
			(thermal_bridge_width 0.5)
			(island_removal_mode 0)
		)
		(polygon
			(pts
				(xy 326.247506 -119.823992) (xy 326.247506 -33.1978) (xy 358.68737 -33.1978) (xy 358.68737 -118.000018)
				(xy 353.579938 -118.000018) (xy 353.579938 -119.823992)
			)
		)
	)
	(zone
		(net "P3V3_STBY")
		(layer "F.Cu")
		(hatch none 0.5)
		(connect_pads
			(clearance 0.5)
		)
		(min_thickness 0.25)
		(fill yes
			(thermal_gap 0.5)
			(thermal_bridge_width 0.5)
			(island_removal_mode 0)
		)
		(polygon
			(pts
				(xy 463.028792 -39.861998) (xy 462.977992 -39.912798) (xy 462.977992 -42.150792) (xy 463.2452 -42.418)
				(xy 468.4776 -42.418) (xy 468.6046 -42.291) (xy 470.7128 -42.291) (xy 470.8906 -42.1132) (xy 470.8906 -41.7322)
				(xy 470.789 -41.6306) (xy 470.789 -40.767) (xy 470.7382 -40.7162) (xy 466.7758 -40.7162) (xy 466.6488 -40.8432)
				(xy 464.8962 -40.8432) (xy 464.016598 -39.963598) (xy 463.816192 -39.963598) (xy 463.714592 -39.861998)
			)
		)
		(polygon
			(pts
				(xy 465.8106 -41.6179) (xy 465.6074 -41.6179) (xy 465.6074 -41.8211) (xy 465.8106 -41.8211)
			)
		)
		(polygon
			(pts
				(xy 465.0486 -41.6179) (xy 464.8454 -41.6179) (xy 464.8454 -41.8211) (xy 465.0486 -41.8211)
			)
		)
	)
	(zone
		(layer "F.Cu")
		(hatch none 0.5)
		(connect_pads
			(clearance 0)
		)
		(min_thickness 0.25)
		(keepout
			(tracks allowed)
			(vias allowed)
			(pads allowed)
			(copperpour allowed)
			(footprints allowed)
		)
		(placement
			(enabled no)
			(sheetname "")
		)
		(fill
			(thermal_gap 0.5)
			(thermal_bridge_width 0.5)
			(island_removal_mode 0)
		)
		(polygon
			(pts
				(xy 434.213 -129.54) (xy 434.213 -128.397) (xy 435.229 -128.397) (xy 435.243224 -128.382776) (xy 436.490872 -128.382776)
				(xy 436.75046 -128.642364) (xy 436.75046 -129.168906) (xy 436.379366 -129.54) (xy 435.229 -129.54)
			)
		)
	)
	(zone
		(layer "F.Cu")
		(hatch none 0.5)
		(connect_pads
			(clearance 0)
		)
		(min_thickness 0.25)
		(keepout
			(tracks allowed)
			(vias allowed)
			(pads allowed)
			(copperpour allowed)
			(footprints not_allowed)
		)
		(placement
			(enabled no)
			(sheetname "")
		)
		(fill
			(thermal_gap 0.5)
			(thermal_bridge_width 0.5)
			(island_removal_mode 0)
		)
		(polygon
			(pts
				(xy 485.306116 -124.35205) (xy 487.312716 -124.35205) (xy 487.312716 -122.34545) (xy 492.01197 -122.34545)
				(xy 492.01197 -124.35205) (xy 492.468916 -124.35205) (xy 492.468916 -129.051304) (xy 492.01197 -129.051304)
				(xy 492.01197 -129.50825) (xy 487.312716 -129.50825) (xy 487.312716 -129.051304) (xy 485.306116 -129.051304)
			)
		)
	)
	(zone
		(layer "F.Cu")
		(hatch none 0.5)
		(connect_pads
			(clearance 0)
		)
		(min_thickness 0.25)
		(keepout
			(tracks not_allowed)
			(vias allowed)
			(pads allowed)
			(copperpour not_allowed)
			(footprints allowed)
		)
		(placement
			(enabled no)
			(sheetname "")
		)
		(fill
			(thermal_gap 0.5)
			(thermal_bridge_width 0.5)
			(island_removal_mode 0)
		)
		(polygon
			(pts
				(arc
					(start 248.000012 -39.649908)
					(mid 249.900186 -41.550082)
					(end 248.000012 -43.450002)
				)
				(arc
					(start 248.000012 -43.450002)
					(mid 246.100092 -41.550082)
					(end 248.000012 -39.649908)
				)
			)
		)
	)
	(zone
		(net "VR_PVDDQ_DEF_VDD")
		(layer "F.Cu")
		(hatch none 0.5)
		(connect_pads
			(clearance 0.5)
		)
		(min_thickness 0.25)
		(fill yes
			(thermal_gap 0.5)
			(thermal_bridge_width 0.5)
			(island_removal_mode 0)
		)
		(polygon
			(pts
				(xy 353.9998 -136.017) (xy 355.7778 -136.017) (xy 355.956616 -136.195816) (xy 355.956616 -136.643618)
				(xy 356.193598 -136.8806) (xy 356.3112 -136.8806) (xy 357.0986 -136.8806) (xy 357.140764 -136.8806)
				(xy 357.205534 -136.81583) (xy 357.205534 -136.716008) (xy 357.149146 -136.65962) (xy 356.429056 -136.65962)
				(xy 356.2604 -136.491218) (xy 356.2604 -136.4488) (xy 356.2604 -135.89) (xy 355.864668 -135.494268)
				(xy 354.076 -135.494268) (xy 354.035868 -135.494268) (xy 353.7585 -135.2169) (xy 353.7585 -134.9375)
				(xy 353.6823 -134.8613) (xy 352.9457 -134.8613) (xy 352.7298 -135.0772) (xy 352.7298 -136.3218)
				(xy 352.7552 -136.3472) (xy 353.6696 -136.3472)
			)
		)
	)
	(zone
		(layer "F.Cu")
		(hatch none 0.5)
		(connect_pads
			(clearance 0)
		)
		(min_thickness 0.25)
		(keepout
			(tracks allowed)
			(vias allowed)
			(pads allowed)
			(copperpour allowed)
			(footprints allowed)
		)
		(placement
			(enabled no)
			(sheetname "")
		)
		(fill
			(thermal_gap 0.5)
			(thermal_bridge_width 0.5)
			(island_removal_mode 0)
		)
		(polygon
			(pts
				(xy 135.354568 -104.902) (xy 134.338568 -103.886) (xy 123.289568 -103.886) (xy 119.670068 -107.5055)
				(xy 121.130568 -108.966) (xy 122.146568 -108.966) (xy 122.400568 -108.966) (xy 128.115568 -108.966)
				(xy 129.639568 -110.49) (xy 129.893568 -110.744) (xy 129.893568 -110.998) (xy 130.655568 -111.76)
				(xy 132.433568 -111.76) (xy 133.449568 -110.744) (xy 135.735568 -108.458) (xy 136.751568 -107.442)
				(xy 136.751568 -107.061) (xy 135.354568 -105.664)
			)
		)
	)
	(zone
		(layer "F.Cu")
		(hatch none 0.5)
		(connect_pads
			(clearance 0)
		)
		(min_thickness 0.25)
		(keepout
			(tracks allowed)
			(vias allowed)
			(pads allowed)
			(copperpour allowed)
			(footprints allowed)
		)
		(placement
			(enabled no)
			(sheetname "")
		)
		(fill
			(thermal_gap 0.5)
			(thermal_bridge_width 0.5)
			(island_removal_mode 0)
		)
		(polygon
			(pts
				(xy 31.369 -61.341) (xy 33.528 -61.341) (xy 33.528 -62.992) (xy 31.369 -62.992)
			)
		)
	)
	(zone
		(net "P12V_STBY")
		(layer "F.Cu")
		(hatch none 0.5)
		(connect_pads
			(clearance 0.5)
		)
		(min_thickness 0.25)
		(fill yes
			(thermal_gap 0.5)
			(thermal_bridge_width 0.5)
			(island_removal_mode 0)
		)
		(polygon
			(pts
				(xy 7.783322 -129.198878) (xy 7.5184 -129.4638) (xy 7.5184 -129.921) (xy 7.5184 -133.30682) (xy 8.22198 -134.0104)
				(xy 8.9154 -134.0104) (xy 10.8712 -134.0104) (xy 11.0236 -133.858) (xy 11.0236 -130.5052) (xy 10.6426 -130.1242)
				(xy 10.6426 -128.818894) (xy 10.420096 -128.59639) (xy 9.04621 -128.59639) (xy 8.865616 -128.59639)
				(xy 8.263128 -129.198878)
			)
		)
	)
	(zone
		(layer "F.Cu")
		(hatch none 0.5)
		(connect_pads
			(clearance 0)
		)
		(min_thickness 0.25)
		(keepout
			(tracks not_allowed)
			(vias allowed)
			(pads allowed)
			(copperpour not_allowed)
			(footprints allowed)
		)
		(placement
			(enabled no)
			(sheetname "")
		)
		(fill
			(thermal_gap 0.5)
			(thermal_bridge_width 0.5)
			(island_removal_mode 0)
		)
		(polygon
			(pts
				(arc
					(start 395.693646 -25.879298)
					(mid 395.625694 -25.849227)
					(end 395.568678 -25.801574)
				)
				(xy 395.5669 -25.803352) (xy 395.5669 -25.879298)
			)
		)
	)
	(zone
		(net "GND")
		(layer "F.Cu")
		(hatch none 0.5)
		(connect_pads
			(clearance 0.5)
		)
		(min_thickness 0.25)
		(fill yes
			(thermal_gap 0.5)
			(thermal_bridge_width 0.5)
			(island_removal_mode 0)
		)
		(polygon
			(pts
				(xy 114.816636 -141.390878) (xy 113.436908 -141.390878) (xy 113.363248 -141.317218) (xy 113.363248 -141.032738)
				(xy 113.229898 -140.899388) (xy 113.229898 -138.976862) (xy 113.436908 -138.769852) (xy 114.860832 -138.769852)
				(xy 115.061238 -138.970258) (xy 115.061238 -141.146276)
			)
		)
	)
	(zone
		(layer "F.Cu")
		(hatch none 0.5)
		(connect_pads
			(clearance 0)
		)
		(min_thickness 0.25)
		(keepout
			(tracks not_allowed)
			(vias allowed)
			(pads allowed)
			(copperpour not_allowed)
			(footprints allowed)
		)
		(placement
			(enabled no)
			(sheetname "")
		)
		(fill
			(thermal_gap 0.5)
			(thermal_bridge_width 0.5)
			(island_removal_mode 0)
		)
		(polygon
			(pts
				(arc
					(start 441.3377 -49.911254)
					(mid 441.861617 -49.981104)
					(end 441.3377 -50.050954)
				)
				(xy 441.223908 -50.050954) (xy 441.140342 -50.13452) (xy 441.140342 -50.364644)
				(arc
					(start 441.594748 -50.364644)
					(mid 441.978542 -49.981231)
					(end 441.595002 -49.597564)
				)
				(arc
					(start 440.325002 -49.597564)
					(mid 439.941462 -49.981104)
					(end 440.325002 -50.364644)
				)
				(xy 440.759342 -50.364644) (xy 440.759342 -50.12436) (xy 440.685936 -50.050954)
				(arc
					(start 440.582304 -50.050954)
					(mid 440.058387 -49.981104)
					(end 440.582304 -49.911254)
				)
				(xy 440.743848 -49.911254) (xy 440.899042 -50.066448) (xy 440.899042 -50.364644) (xy 441.000642 -50.364644)
				(xy 441.000642 -50.076608) (xy 441.165996 -49.911254)
			)
		)
	)
	(zone
		(net "GND")
		(layer "F.Cu")
		(hatch none 0.5)
		(connect_pads
			(clearance 0.5)
		)
		(min_thickness 0.25)
		(fill yes
			(thermal_gap 0.5)
			(thermal_bridge_width 0.5)
			(island_removal_mode 0)
		)
		(polygon
			(pts
				(xy 167.252904 -9.63168) (xy 167.229536 -9.655048) (xy 167.229536 -10.446512) (xy 168.186608 -11.403584)
				(xy 168.186608 -12.282678) (xy 168.393618 -12.489688) (xy 169.387012 -12.489688) (xy 169.530268 -12.346432)
				(xy 169.530268 -11.859006) (xy 168.68267 -11.011408) (xy 168.681908 -11.011408) (xy 168.127934 -10.457434)
				(xy 168.127934 -9.677146) (xy 168.082468 -9.63168)
			)
		)
	)
	(zone
		(net "PVPP_GHJ")
		(layer "F.Cu")
		(hatch none 0.5)
		(connect_pads
			(clearance 0.5)
		)
		(min_thickness 0.25)
		(fill yes
			(thermal_gap 0.5)
			(thermal_bridge_width 0.5)
			(island_removal_mode 0)
		)
		(polygon
			(pts
				(xy 154.4574 5.334) (xy 154.190192 5.066792) (xy 154.190192 2.32791) (xy 154.00147 2.139188) (xy 151.779986 2.139188)
				(xy 151.7015 2.060702) (xy 151.7015 0.986536) (xy 151.848058 0.839978) (xy 152.251664 0.839978)
				(xy 152.498298 0.593344) (xy 152.498298 -2.319274) (xy 153.101294 -2.92227) (xy 153.101294 -3.682746)
				(xy 152.969722 -3.814318) (xy 151.855932 -3.814318) (xy 151.7015 -3.96875) (xy 151.7015 -4.66852)
				(xy 151.820372 -4.787392) (xy 152.47874 -4.787392) (xy 152.492456 -4.801108) (xy 152.492456 -7.218934)
				(xy 152.251664 -7.459726) (xy 151.858726 -7.459726) (xy 151.7015 -7.616952) (xy 151.7015 -8.67791)
				(xy 151.798528 -8.774938) (xy 152.256998 -8.774938) (xy 152.482042 -8.999982) (xy 152.482042 -11.955018)
				(xy 153.100024 -12.573) (xy 153.100024 -13.349986) (xy 152.978104 -13.471906) (xy 151.772366 -13.471906)
				(xy 151.7015 -13.542772) (xy 151.7015 -14.318488) (xy 151.775668 -14.392656) (xy 154.182572 -14.392656)
				(xy 154.20594 -14.416024) (xy 154.20594 -16.833596) (xy 153.967942 -17.071594) (xy 151.774652 -17.071594)
				(xy 151.7015 -17.144746) (xy 151.7015 -18.334482) (xy 151.751284 -18.384266) (xy 152.289002 -18.384266)
				(xy 152.482042 -18.577306) (xy 152.482042 -21.753576) (xy 153.095198 -22.366732) (xy 153.095198 -23.181564)
				(xy 153.008584 -23.268178) (xy 151.835104 -23.268178) (xy 151.7015 -23.401782) (xy 151.7015 -25.039574)
				(xy 152.047194 -25.385268) (xy 152.894538 -25.385268) (xy 154.229308 -26.720292) (xy 155.686252 -26.720292)
				(xy 155.8798 -26.91384) (xy 157.80004 -26.91384) (xy 158.5214 -27.6352) (xy 158.5214 -28.2956) (xy 158.9024 -28.6766)
				(xy 168.0464 -28.6766) (xy 168.4274 -28.2956) (xy 168.4274 -17.888966) (xy 168.09593 -17.557496)
				(xy 168.09593 -12.580112) (xy 167.718994 -12.203176) (xy 167.718994 -11.490706) (xy 166.697914 -10.469626)
				(xy 166.697914 -9.492742) (xy 166.898828 -9.291828) (xy 167.152066 -9.291828) (xy 167.207438 -9.236456)
				(xy 167.207438 -8.471662) (xy 167.130476 -8.3947) (xy 165.347142 -8.3947) (xy 165.084252 -8.13181)
				(xy 165.084252 -7.900924) (xy 163.322 -6.138672) (xy 163.322 -5.996686) (xy 163.322 4.826) (xy 162.814 5.334)
			)
		)
		(polygon
			(pts
				(xy 154.7622 -23.0251) (xy 154.559 -23.0251) (xy 154.559 -23.2283) (xy 154.7622 -23.2283)
			)
		)
		(polygon
			(pts
				(xy 154.7622 -22.2631) (xy 154.559 -22.2631) (xy 154.559 -22.4663) (xy 154.7622 -22.4663)
			)
		)
		(polygon
			(pts
				(xy 154.0764 -22.2631) (xy 153.8732 -22.2631) (xy 153.8732 -22.4663) (xy 154.0764 -22.4663)
			)
		)
		(polygon
			(pts
				(xy 154.9527 -13.2334) (xy 154.7495 -13.2334) (xy 154.7495 -13.4366) (xy 154.9527 -13.4366)
			)
		)
		(polygon
			(pts
				(xy 154.0891 -13.2334) (xy 153.8859 -13.2334) (xy 153.8859 -13.4366) (xy 154.0891 -13.4366)
			)
		)
		(polygon
			(pts
				(xy 154.9527 -12.4714) (xy 154.7495 -12.4714) (xy 154.7495 -12.6746) (xy 154.9527 -12.6746)
			)
		)
		(polygon
			(pts
				(xy 154.0891 -12.4714) (xy 153.8859 -12.4714) (xy 153.8859 -12.6746) (xy 154.0891 -12.6746)
			)
		)
		(polygon
			(pts
				(xy 165.928548 -10.3505) (xy 165.725348 -10.3505) (xy 165.725348 -10.5537) (xy 165.928548 -10.5537)
			)
		)
		(polygon
			(pts
				(xy 165.928548 -9.5885) (xy 165.725348 -9.5885) (xy 165.725348 -9.7917) (xy 165.928548 -9.7917)
			)
		)
		(polygon
			(pts
				(xy 166.825422 -8.658352) (xy 166.622222 -8.658352) (xy 166.622222 -8.861552) (xy 166.825422 -8.861552)
			)
		)
		(polygon
			(pts
				(xy 154.8511 -3.5814) (xy 154.6479 -3.5814) (xy 154.6479 -3.7846) (xy 154.8511 -3.7846)
			)
		)
		(polygon
			(pts
				(xy 154.0891 -3.5814) (xy 153.8859 -3.5814) (xy 153.8859 -3.7846) (xy 154.0891 -3.7846)
			)
		)
		(polygon
			(pts
				(xy 154.8511 -2.8194) (xy 154.6479 -2.8194) (xy 154.6479 -3.0226) (xy 154.8511 -3.0226)
			)
		)
		(polygon
			(pts
				(xy 154.0891 -2.8194) (xy 153.8859 -2.8194) (xy 153.8859 -3.0226) (xy 154.0891 -3.0226)
			)
		)
	)
	(zone
		(layer "F.Cu")
		(hatch none 0.5)
		(connect_pads
			(clearance 0)
		)
		(min_thickness 0.25)
		(keepout
			(tracks not_allowed)
			(vias allowed)
			(pads allowed)
			(copperpour not_allowed)
			(footprints allowed)
		)
		(placement
			(enabled no)
			(sheetname "")
		)
		(fill
			(thermal_gap 0.5)
			(thermal_bridge_width 0.5)
			(island_removal_mode 0)
		)
		(polygon
			(pts
				(xy 392.63828 -3.106674) (xy 392.819636 -3.28803) (xy 392.819636 -3.50774) (xy 392.767312 -3.560064)
				(xy 392.97356 -3.560064) (xy 392.921236 -3.50774) (xy 392.921236 -3.28803) (xy 393.102592 -3.106674)
				(arc
					(start 393.11199 -3.106674)
					(mid 393.635307 -3.15794)
					(end 393.124436 -3.282442)
				)
				(xy 393.060936 -3.345942) (xy 393.060936 -3.449828) (xy 393.171172 -3.560064)
				(arc
					(start 393.369038 -3.560064)
					(mid 393.752832 -3.176651)
					(end 393.369292 -2.792984)
				)
				(arc
					(start 392.353292 -2.792984)
					(mid 391.969752 -3.176524)
					(end 392.353292 -3.560064)
				)
				(xy 392.5697 -3.560064) (xy 392.679936 -3.449828) (xy 392.679936 -3.345942)
				(arc
					(start 392.603228 -3.269234)
					(mid 392.086986 -3.164516)
					(end 392.610594 -3.106674)
				)
			)
		)
	)
	(zone
		(layer "F.Cu")
		(hatch none 0.5)
		(connect_pads
			(clearance 0)
		)
		(min_thickness 0.25)
		(keepout
			(tracks allowed)
			(vias allowed)
			(pads allowed)
			(copperpour allowed)
			(footprints allowed)
		)
		(placement
			(enabled no)
			(sheetname "")
		)
		(fill
			(thermal_gap 0.5)
			(thermal_bridge_width 0.5)
			(island_removal_mode 0)
		)
		(polygon
			(pts
				(xy 195.326 -61.341) (xy 198.882 -61.341) (xy 199.136 -61.595) (xy 199.136 -63.119) (xy 198.755 -63.5)
				(xy 196.977 -63.5) (xy 196.85 -63.627) (xy 196.85 -66.167) (xy 196.723 -66.294) (xy 195.072 -66.294)
				(xy 194.818 -66.04) (xy 194.31 -65.532) (xy 194.31 -61.849) (xy 194.818 -61.341)
			)
		)
	)
	(zone
		(net "GND")
		(layer "F.Cu")
		(hatch none 0.5)
		(connect_pads
			(clearance 0.5)
		)
		(min_thickness 0.25)
		(fill yes
			(thermal_gap 0.5)
			(thermal_bridge_width 0.5)
			(island_removal_mode 0)
		)
		(polygon
			(pts
				(xy 180.958998 -0.470408) (xy 180.958998 -2.070608) (xy 181.111398 -2.223008) (xy 182.889398 -2.223008)
				(xy 182.89778 -2.223008) (xy 183.2864 -2.223008) (xy 183.346598 -2.223008) (xy 183.422798 -2.223008)
				(xy 184.974992 -2.223008) (xy 185.039 -2.159) (xy 185.039 -0.521208) (xy 184.912 -0.394208) (xy 183.397398 -0.394208)
				(xy 183.371998 -0.394208) (xy 183.346598 -0.368808) (xy 183.270398 -0.292608) (xy 183.232298 -0.254508)
				(xy 183.232298 1.777492) (xy 182.990998 2.018792) (xy 182.990998 3.33756) (xy 183.068468 3.41503)
				(xy 183.068468 4.188206) (xy 182.96128 4.295394) (xy 182.875682 4.295394) (xy 181.816502 4.295394)
				(xy 181.195726 3.674618) (xy 181.085236 3.674618) (xy 181.085236 3.124454) (xy 181.085236 2.18694)
				(xy 181.098952 2.173224) (xy 181.718966 2.173224) (xy 181.721506 2.170684) (xy 181.774592 2.170684)
				(xy 181.985666 1.95961) (xy 182.332376 1.95961) (xy 182.990998 1.300988) (xy 182.990998 0.901192)
				(xy 182.990998 0.6731) (xy 183.0451 0.618998) (xy 183.0451 0.016002) (xy 182.990998 -0.0381) (xy 182.990998 -0.191008)
				(xy 182.990998 -0.267208) (xy 182.863998 -0.394208) (xy 182.787798 -0.394208) (xy 181.035198 -0.394208)
			)
		)
	)
	(zone
		(layer "F.Cu")
		(hatch none 0.5)
		(connect_pads
			(clearance 0)
		)
		(min_thickness 0.25)
		(keepout
			(tracks allowed)
			(vias allowed)
			(pads allowed)
			(copperpour allowed)
			(footprints allowed)
		)
		(placement
			(enabled no)
			(sheetname "")
		)
		(fill
			(thermal_gap 0.5)
			(thermal_bridge_width 0.5)
			(island_removal_mode 0)
		)
		(polygon
			(pts
				(xy 105.382568 -51.562) (xy 106.144568 -51.562) (xy 106.398568 -51.816) (xy 106.398568 -52.197)
				(xy 105.255568 -52.197) (xy 105.255568 -51.689)
			)
		)
	)
	(zone
		(layer "F.Cu")
		(hatch none 0.5)
		(connect_pads
			(clearance 0)
		)
		(min_thickness 0.25)
		(keepout
			(tracks not_allowed)
			(vias allowed)
			(pads allowed)
			(copperpour not_allowed)
			(footprints allowed)
		)
		(placement
			(enabled no)
			(sheetname "")
		)
		(fill
			(thermal_gap 0.5)
			(thermal_bridge_width 0.5)
			(island_removal_mode 0)
		)
		(polygon
			(pts
				(arc
					(start 396.01394 -31.677356)
					(mid 395.970518 -31.764656)
					(end 395.898624 -31.830518)
				)
				(xy 396.01394 -31.945834)
			)
		)
	)
	(zone
		(net "P5V_STBY_USBC")
		(layer "F.Cu")
		(hatch none 0.5)
		(connect_pads
			(clearance 0.5)
		)
		(min_thickness 0.25)
		(fill yes
			(thermal_gap 0.5)
			(thermal_bridge_width 0.5)
			(island_removal_mode 0)
		)
		(polygon
			(pts
				(xy 492.887 -56.261) (xy 488.315 -56.261) (xy 487.197654 -56.261) (xy 486.537 -56.261) (xy 485.482392 -56.261)
				(xy 485.104186 -56.639206) (xy 485.104186 -58.35269) (xy 485.665272 -58.913776) (xy 488.529376 -58.913776)
				(xy 488.738418 -59.122818) (xy 489.1786 -59.563) (xy 493.649 -59.563) (xy 493.776 -59.436) (xy 493.776 -58.42)
				(xy 493.395 -58.039) (xy 493.2553 -57.8993) (xy 493.2553 -56.4515) (xy 493.0648 -56.261)
			)
		)
	)
	(zone
		(net "GND")
		(layers "F.Cu" "B.Cu")
		(hatch none 0.5)
		(connect_pads
			(clearance 0.5)
		)
		(min_thickness 0.25)
		(fill yes
			(thermal_gap 0.5)
			(thermal_bridge_width 0.5)
			(island_removal_mode 0)
		)
		(polygon
			(pts
				(xy 48.641 -84.03082) (xy 48.4378 -84.23402) (xy 48.4378 -85.50402) (xy 48.641 -85.70722) (xy 50.2158 -85.70722)
				(xy 50.3936 -85.52942) (xy 50.3936 -84.23402) (xy 50.1904 -84.03082)
			)
		)
		(polygon
			(pts
				(xy 49.911 -84.72932) (xy 49.7078 -84.72932) (xy 49.7078 -84.93252) (xy 49.911 -84.93252)
			)
		)
		(polygon
			(pts
				(xy 49.149 -84.72932) (xy 48.9458 -84.72932) (xy 48.9458 -84.93252) (xy 49.149 -84.93252)
			)
		)
	)
	(zone
		(layers "F.Cu" "B.Cu")
		(hatch none 0.5)
		(connect_pads
			(clearance 0)
		)
		(min_thickness 0.25)
		(keepout
			(tracks not_allowed)
			(vias allowed)
			(pads allowed)
			(copperpour not_allowed)
			(footprints allowed)
		)
		(placement
			(enabled no)
			(sheetname "")
		)
		(fill yes
			(thermal_gap 0.5)
			(thermal_bridge_width 0.5)
			(island_removal_mode 0)
		)
		(polygon
			(pts
				(arc
					(start 498.300502 -114.596926)
					(mid 496.700556 -112.99698)
					(end 495.10061 -114.596926)
				)
				(arc
					(start 495.10061 -116.196872)
					(mid 496.700556 -117.796818)
					(end 498.300502 -116.196872)
				)
			)
		)
	)
	(zone
		(net "GND")
		(layers "F.Cu" "B.Cu")
		(hatch none 0.5)
		(connect_pads
			(clearance 0.5)
		)
		(min_thickness 0.25)
		(fill yes
			(thermal_gap 0.5)
			(thermal_bridge_width 0.5)
			(island_removal_mode 0)
		)
		(polygon
			(pts
				(xy 213.995 -83.82) (xy 213.7664 -84.0486) (xy 213.7664 -85.217) (xy 213.9696 -85.4202) (xy 215.1888 -85.4202)
				(xy 215.5444 -85.0646) (xy 215.5444 -84.0486) (xy 215.3158 -83.82)
			)
		)
		(polygon
			(pts
				(xy 214.9856 -84.4804) (xy 214.7824 -84.4804) (xy 214.7824 -84.6836) (xy 214.9856 -84.6836)
			)
		)
		(polygon
			(pts
				(xy 214.2236 -84.4804) (xy 214.0204 -84.4804) (xy 214.0204 -84.6836) (xy 214.2236 -84.6836)
			)
		)
	)
	(zone
		(layers "F.Cu" "B.Cu")
		(hatch none 0.5)
		(connect_pads
			(clearance 0)
		)
		(min_thickness 0.25)
		(keepout
			(tracks allowed)
			(vias allowed)
			(pads allowed)
			(copperpour allowed)
			(footprints not_allowed)
		)
		(placement
			(enabled no)
			(sheetname "")
		)
		(fill yes
			(thermal_gap 0.5)
			(thermal_bridge_width 0.5)
			(island_removal_mode 0)
		)
		(polygon
			(pts
				(arc
					(start 498.300502 -114.596926)
					(mid 496.700556 -112.99698)
					(end 495.10061 -114.596926)
				)
				(arc
					(start 495.10061 -116.196872)
					(mid 496.700556 -117.796818)
					(end 498.300502 -116.196872)
				)
			)
		)
	)
	(zone
		(layers "F.Cu" "B.Cu")
		(hatch none 0.5)
		(connect_pads
			(clearance 0)
		)
		(min_thickness 0.25)
		(keepout
			(tracks allowed)
			(vias allowed)
			(pads allowed)
			(copperpour allowed)
			(footprints not_allowed)
		)
		(placement
			(enabled no)
			(sheetname "")
		)
		(fill yes
			(thermal_gap 0.5)
			(thermal_bridge_width 0.5)
			(island_removal_mode 0)
		)
		(polygon
			(pts
				(arc
					(start 467.320122 -28.919932)
					(mid 468.920322 -30.520132)
					(end 467.320122 -32.120078)
				)
				(arc
					(start 465.719922 -32.120078)
					(mid 464.119976 -30.520132)
					(end 465.719922 -28.919932)
				)
			)
		)
	)
	(zone
		(layers "F.Cu" "B.Cu")
		(hatch none 0.5)
		(connect_pads
			(clearance 0)
		)
		(min_thickness 0.25)
		(keepout
			(tracks allowed)
			(vias allowed)
			(pads allowed)
			(copperpour allowed)
			(footprints not_allowed)
		)
		(placement
			(enabled no)
			(sheetname "")
		)
		(fill yes
			(thermal_gap 0.5)
			(thermal_bridge_width 0.5)
			(island_removal_mode 0)
		)
		(polygon
			(pts
				(arc
					(start 433.300378 -114.596926)
					(mid 431.700432 -112.99698)
					(end 430.100486 -114.596926)
				)
				(arc
					(start 430.100486 -116.196872)
					(mid 431.700432 -117.796818)
					(end 433.300378 -116.196872)
				)
			)
		)
	)
	(zone
		(net "GND")
		(layers "F.Cu" "B.Cu")
		(hatch none 0.5)
		(connect_pads
			(clearance 0.5)
		)
		(min_thickness 0.25)
		(fill yes
			(thermal_gap 0.5)
			(thermal_bridge_width 0.5)
			(island_removal_mode 0)
		)
		(polygon
			(pts
				(arc
					(start -5.184648 -161.9504)
					(mid -5.224047 -162.020639)
					(end -5.237734 -162.100006)
				)
				(arc
					(start -5.237734 -168.099994)
					(mid -5.1681 -168.268104)
					(end -4.99999 -168.337738)
				)
				(xy 501.0404 -168.337738) (xy 501.0404 -161.9504)
			)
		)
		(polygon
			(pts
				(xy 388.5946 -162.5346) (xy 382.778 -162.5346) (xy 382.778 -167.5384) (xy 388.5946 -167.5384)
			)
		)
		(polygon
			(pts
				(xy 322.2498 -162.5346) (xy 316.23 -162.5346) (xy 316.23 -167.5384) (xy 322.2498 -167.5384)
			)
		)
		(polygon
			(pts
				(xy 308.9656 -162.5346) (xy 302.5648 -162.5346) (xy 302.5648 -167.5384) (xy 308.9656 -167.5384)
			)
		)
		(polygon
			(pts
				(xy 242.3922 -162.5346) (xy 236.4486 -162.5346) (xy 236.4486 -167.5384) (xy 242.3922 -167.5384)
			)
		)
		(polygon
			(pts
				(xy 229.362 -162.5346) (xy 156.3624 -162.5346) (xy 156.3624 -167.5384) (xy 229.362 -167.5384)
			)
		)
		(polygon
			(pts
				(xy 149.2758 -162.5346) (xy 143.4338 -162.5346) (xy 143.4338 -167.5384) (xy 149.2758 -167.5384)
			)
		)
		(polygon
			(pts
				(xy 114.935 -162.5346) (xy 108.6104 -162.5346) (xy 108.6104 -167.5384) (xy 114.935 -167.5384)
			)
		)
		(polygon
			(pts
				(xy 101.7524 -162.5346) (xy 95.377 -162.5346) (xy 95.377 -167.5384) (xy 101.7524 -167.5384)
			)
		)
		(polygon
			(pts
				(xy 67.9704 -162.5346) (xy 60.9092 -162.5346) (xy 60.9092 -167.5384) (xy 67.9704 -167.5384)
			)
		)
		(polygon
			(pts
				(xy 54.1782 -162.5346) (xy 13.0048 -162.5346) (xy 13.0048 -167.5384) (xy 54.1782 -167.5384)
			)
		)
	)
	(zone
		(layers "F.Cu" "B.Cu")
		(hatch none 0.5)
		(connect_pads
			(clearance 0)
		)
		(min_thickness 0.25)
		(keepout
			(tracks allowed)
			(vias allowed)
			(pads allowed)
			(copperpour allowed)
			(footprints allowed)
		)
		(placement
			(enabled no)
			(sheetname "")
		)
		(fill yes
			(thermal_gap 0.5)
			(thermal_bridge_width 0.5)
			(island_removal_mode 0)
		)
		(polygon
			(pts
				(xy 31.369 -77.597) (xy 33.528 -77.597) (xy 33.528 -79.248) (xy 31.369 -79.248)
			)
		)
	)
	(zone
		(layers "F.Cu" "B.Cu")
		(hatch none 0.5)
		(connect_pads
			(clearance 0)
		)
		(min_thickness 0.25)
		(keepout
			(tracks not_allowed)
			(vias allowed)
			(pads allowed)
			(copperpour not_allowed)
			(footprints allowed)
		)
		(placement
			(enabled no)
			(sheetname "")
		)
		(fill yes
			(thermal_gap 0.5)
			(thermal_bridge_width 0.5)
			(island_removal_mode 0)
		)
		(polygon
			(pts
				(arc
					(start 465.719922 -32.120078)
					(mid 464.119976 -30.520132)
					(end 465.719922 -28.919932)
				)
				(arc
					(start 467.320122 -28.919932)
					(mid 468.920322 -30.520132)
					(end 467.320122 -32.120078)
				)
			)
		)
	)
	(zone
		(net "GND")
		(layers "F.Cu" "B.Cu")
		(hatch none 0.5)
		(connect_pads
			(clearance 0.5)
		)
		(min_thickness 0.25)
		(fill yes
			(thermal_gap 0.5)
			(thermal_bridge_width 0.5)
			(island_removal_mode 0)
		)
		(polygon
			(pts
				(xy 213.995 -67.7418) (xy 213.7664 -67.9704) (xy 213.7664 -69.1388) (xy 213.9696 -69.342) (xy 215.1888 -69.342)
				(xy 215.5444 -68.9864) (xy 215.5444 -67.9704) (xy 215.3158 -67.7418)
			)
		)
		(polygon
			(pts
				(xy 214.9856 -68.4149) (xy 214.7824 -68.4149) (xy 214.7824 -68.6181) (xy 214.9856 -68.6181)
			)
		)
		(polygon
			(pts
				(xy 214.2236 -68.4149) (xy 214.0204 -68.4149) (xy 214.0204 -68.6181) (xy 214.2236 -68.6181)
			)
		)
	)
	(zone
		(net "GND")
		(layers "F.Cu" "B.Cu")
		(hatch none 0.5)
		(connect_pads
			(clearance 0.5)
		)
		(min_thickness 0.25)
		(fill yes
			(thermal_gap 0.5)
			(thermal_bridge_width 0.5)
			(island_removal_mode 0)
		)
		(polygon
			(pts
				(xy 213.995 -75.7936) (xy 213.7664 -76.0222) (xy 213.7664 -77.1906) (xy 213.9696 -77.3938) (xy 215.1888 -77.3938)
				(xy 215.5444 -77.0382) (xy 215.5444 -76.0222) (xy 215.3158 -75.7936)
			)
		)
		(polygon
			(pts
				(xy 214.9856 -76.4667) (xy 214.7824 -76.4667) (xy 214.7824 -76.6699) (xy 214.9856 -76.6699)
			)
		)
		(polygon
			(pts
				(xy 214.2236 -76.4667) (xy 214.0204 -76.4667) (xy 214.0204 -76.6699) (xy 214.2236 -76.6699)
			)
		)
	)
	(zone
		(layers "F.Cu" "B.Cu")
		(hatch none 0.5)
		(connect_pads
			(clearance 0)
		)
		(min_thickness 0.25)
		(keepout
			(tracks allowed)
			(vias allowed)
			(pads allowed)
			(copperpour allowed)
			(footprints not_allowed)
		)
		(placement
			(enabled no)
			(sheetname "")
		)
		(fill yes
			(thermal_gap 0.5)
			(thermal_bridge_width 0.5)
			(island_removal_mode 0)
		)
		(polygon
			(pts
				(arc
					(start 475.80042 -58.996834)
					(mid 474.200474 -57.396888)
					(end 472.600528 -58.996834)
				)
				(arc
					(start 472.600528 -60.59678)
					(mid 474.200474 -62.196726)
					(end 475.80042 -60.59678)
				)
			)
		)
	)
	(zone
		(layers "F.Cu" "B.Cu")
		(hatch none 0.5)
		(connect_pads
			(clearance 0)
		)
		(min_thickness 0.25)
		(keepout
			(tracks allowed)
			(vias allowed)
			(pads allowed)
			(copperpour allowed)
			(footprints allowed)
		)
		(placement
			(enabled no)
			(sheetname "")
		)
		(fill yes
			(thermal_gap 0.5)
			(thermal_bridge_width 0.5)
			(island_removal_mode 0)
		)
		(polygon
			(pts
				(xy 31.369 -93.853) (xy 33.528 -93.853) (xy 33.528 -95.504) (xy 31.369 -95.504)
			)
		)
	)
	(zone
		(layers "F.Cu" "B.Cu")
		(hatch none 0.5)
		(connect_pads
			(clearance 0)
		)
		(min_thickness 0.25)
		(keepout
			(tracks not_allowed)
			(vias allowed)
			(pads allowed)
			(copperpour not_allowed)
			(footprints allowed)
		)
		(placement
			(enabled no)
			(sheetname "")
		)
		(fill yes
			(thermal_gap 0.5)
			(thermal_bridge_width 0.5)
			(island_removal_mode 0)
		)
		(polygon
			(pts
				(arc
					(start 433.300378 -58.996834)
					(mid 431.700432 -57.396888)
					(end 430.100486 -58.996834)
				)
				(arc
					(start 430.100486 -60.59678)
					(mid 431.700432 -62.196726)
					(end 433.300378 -60.59678)
				)
			)
		)
	)
	(zone
		(layers "F.Cu" "B.Cu")
		(hatch none 0.5)
		(connect_pads
			(clearance 0)
		)
		(min_thickness 0.25)
		(keepout
			(tracks allowed)
			(vias allowed)
			(pads allowed)
			(copperpour allowed)
			(footprints not_allowed)
		)
		(placement
			(enabled no)
			(sheetname "")
		)
		(fill yes
			(thermal_gap 0.5)
			(thermal_bridge_width 0.5)
			(island_removal_mode 0)
		)
		(polygon
			(pts
				(arc
					(start 433.300378 -58.996834)
					(mid 431.700432 -57.396888)
					(end 430.100486 -58.996834)
				)
				(arc
					(start 430.100486 -60.59678)
					(mid 431.700432 -62.196726)
					(end 433.300378 -60.59678)
				)
			)
		)
	)
	(zone
		(net "GND")
		(layers "F.Cu" "B.Cu")
		(hatch none 0.5)
		(connect_pads
			(clearance 0.5)
		)
		(min_thickness 0.25)
		(fill yes
			(thermal_gap 0.5)
			(thermal_bridge_width 0.5)
			(island_removal_mode 0)
		)
		(polygon
			(pts
				(xy 48.641 -75.7174) (xy 48.4378 -75.9206) (xy 48.4378 -77.1906) (xy 48.641 -77.3938) (xy 50.2158 -77.3938)
				(xy 50.3936 -77.216) (xy 50.3936 -75.9206) (xy 50.1904 -75.7174)
			)
		)
		(polygon
			(pts
				(xy 49.911 -76.4159) (xy 49.7078 -76.4159) (xy 49.7078 -76.6191) (xy 49.911 -76.6191)
			)
		)
		(polygon
			(pts
				(xy 49.149 -76.4159) (xy 48.9458 -76.4159) (xy 48.9458 -76.6191) (xy 49.149 -76.6191)
			)
		)
	)
	(zone
		(net "GND")
		(layers "F.Cu" "B.Cu")
		(hatch none 0.5)
		(connect_pads
			(clearance 0.5)
		)
		(min_thickness 0.25)
		(fill yes
			(thermal_gap 0.5)
			(thermal_bridge_width 0.5)
			(island_removal_mode 0)
		)
		(polygon
			(pts
				(xy 48.641 -68.3514) (xy 48.4378 -68.5546) (xy 48.4378 -69.8246) (xy 48.641 -70.0278) (xy 50.2158 -70.0278)
				(xy 50.3936 -69.85) (xy 50.3936 -68.5546) (xy 50.1904 -68.3514)
			)
		)
		(polygon
			(pts
				(xy 49.911 -69.0499) (xy 49.7078 -69.0499) (xy 49.7078 -69.2531) (xy 49.911 -69.2531)
			)
		)
		(polygon
			(pts
				(xy 49.149 -69.0499) (xy 48.9458 -69.0499) (xy 48.9458 -69.2531) (xy 49.149 -69.2531)
			)
		)
	)
	(zone
		(layers "F.Cu" "B.Cu")
		(hatch none 0.5)
		(connect_pads
			(clearance 0)
		)
		(min_thickness 0.25)
		(keepout
			(tracks allowed)
			(vias allowed)
			(pads allowed)
			(copperpour allowed)
			(footprints allowed)
		)
		(placement
			(enabled no)
			(sheetname "")
		)
		(fill yes
			(thermal_gap 0.5)
			(thermal_bridge_width 0.5)
			(island_removal_mode 0)
		)
		(polygon
			(pts
				(xy 173.228 -136.398) (xy 173.228 -133.223) (xy 175.387 -133.223) (xy 175.387 -136.398)
			)
		)
	)
	(zone
		(layers "F.Cu" "B.Cu")
		(hatch none 0.5)
		(connect_pads
			(clearance 0)
		)
		(min_thickness 0.25)
		(keepout
			(tracks not_allowed)
			(vias allowed)
			(pads allowed)
			(copperpour not_allowed)
			(footprints allowed)
		)
		(placement
			(enabled no)
			(sheetname "")
		)
		(fill yes
			(thermal_gap 0.5)
			(thermal_bridge_width 0.5)
			(island_removal_mode 0)
		)
		(polygon
			(pts
				(arc
					(start 460.509112 -49.927764)
					(mid 461.033029 -49.997614)
					(end 460.509112 -50.067464)
				)
				(xy 460.39532 -50.067464) (xy 460.321914 -50.14087) (xy 460.321914 -50.381154)
				(arc
					(start 460.76616 -50.381154)
					(mid 461.149954 -49.997741)
					(end 460.766414 -49.614074)
				)
				(arc
					(start 459.496414 -49.614074)
					(mid 459.112874 -49.997614)
					(end 459.496414 -50.381154)
				)
				(xy 459.940914 -50.381154) (xy 459.940914 -50.14087) (xy 459.867508 -50.067464)
				(arc
					(start 459.753716 -50.067464)
					(mid 459.229799 -49.997614)
					(end 459.753716 -49.927764)
				)
				(xy 459.92542 -49.927764) (xy 460.080614 -50.082958) (xy 460.080614 -50.381154) (xy 460.182214 -50.381154)
				(xy 460.182214 -50.082958) (xy 460.337408 -49.927764)
			)
		)
	)
	(zone
		(layers "F.Cu" "B.Cu")
		(hatch none 0.5)
		(connect_pads
			(clearance 0)
		)
		(min_thickness 0.25)
		(keepout
			(tracks not_allowed)
			(vias allowed)
			(pads allowed)
			(copperpour not_allowed)
			(footprints allowed)
		)
		(placement
			(enabled no)
			(sheetname "")
		)
		(fill yes
			(thermal_gap 0.5)
			(thermal_bridge_width 0.5)
			(island_removal_mode 0)
		)
		(polygon
			(pts
				(arc
					(start 454.108312 -49.927764)
					(mid 454.632229 -49.997614)
					(end 454.108312 -50.067464)
				)
				(xy 453.99452 -50.067464) (xy 453.921114 -50.14087) (xy 453.921114 -50.381154)
				(arc
					(start 454.36536 -50.381154)
					(mid 454.749154 -49.997741)
					(end 454.365614 -49.614074)
				)
				(arc
					(start 453.095614 -49.614074)
					(mid 452.712074 -49.997614)
					(end 453.095614 -50.381154)
				)
				(xy 453.540114 -50.381154) (xy 453.540114 -50.14087) (xy 453.466708 -50.067464)
				(arc
					(start 453.352916 -50.067464)
					(mid 452.828999 -49.997614)
					(end 453.352916 -49.927764)
				)
				(xy 453.52462 -49.927764) (xy 453.679814 -50.082958) (xy 453.679814 -50.381154) (xy 453.781414 -50.381154)
				(xy 453.781414 -50.082958) (xy 453.936608 -49.927764)
			)
		)
	)
	(zone
		(layers "F.Cu" "B.Cu" "In1.Cu" "In2.Cu" "In3.Cu" "In4.Cu" "In5.Cu" "In6.Cu"
			"In7.Cu" "In8.Cu" "In9.Cu" "In10.Cu" "In11.Cu" "In12.Cu"
		)
		(hatch none 0.5)
		(connect_pads
			(clearance 0)
		)
		(min_thickness 0.25)
		(keepout
			(tracks not_allowed)
			(vias allowed)
			(pads allowed)
			(copperpour not_allowed)
			(footprints allowed)
		)
		(placement
			(enabled no)
			(sheetname "")
		)
		(fill yes
			(thermal_gap 0.5)
			(thermal_bridge_width 0.5)
			(island_removal_mode 0)
		)
		(polygon
			(pts
				(arc
					(start 426.749972 -148.458174)
					(mid 426.994066 -149.266148)
					(end 427.80204 -149.022054)
				)
				(arc
					(start 428.552102 -147.622006)
					(mid 428.308008 -146.814032)
					(end 427.500034 -147.058126)
				)
			)
		)
	)
	(zone
		(layers "F.Cu" "B.Cu" "In1.Cu" "In2.Cu" "In3.Cu" "In4.Cu" "In5.Cu" "In6.Cu"
			"In7.Cu" "In8.Cu" "In9.Cu" "In10.Cu" "In11.Cu" "In12.Cu"
		)
		(hatch none 0.5)
		(connect_pads
			(clearance 0)
		)
		(min_thickness 0.25)
		(keepout
			(tracks not_allowed)
			(vias allowed)
			(pads allowed)
			(copperpour not_allowed)
			(footprints allowed)
		)
		(placement
			(enabled no)
			(sheetname "")
		)
		(fill yes
			(thermal_gap 0.5)
			(thermal_bridge_width 0.5)
			(island_removal_mode 0)
		)
		(polygon
			(pts
				(arc
					(start 414.749996 -152.258014)
					(mid 414.99409 -153.065988)
					(end 415.802064 -152.821894)
				)
				(arc
					(start 416.552126 -151.421846)
					(mid 416.308032 -150.613872)
					(end 415.500058 -150.857966)
				)
			)
		)
	)
	(zone
		(layers "F.Cu" "B.Cu" "In1.Cu" "In2.Cu" "In3.Cu" "In4.Cu" "In5.Cu" "In6.Cu"
			"In7.Cu" "In8.Cu" "In9.Cu" "In10.Cu" "In11.Cu" "In12.Cu"
		)
		(hatch none 0.5)
		(connect_pads
			(clearance 0)
		)
		(min_thickness 0.25)
		(keepout
			(tracks not_allowed)
			(vias allowed)
			(pads allowed)
			(copperpour not_allowed)
			(footprints allowed)
		)
		(placement
			(enabled no)
			(sheetname "")
		)
		(fill yes
			(thermal_gap 0.5)
			(thermal_bridge_width 0.5)
			(island_removal_mode 0)
		)
		(polygon
			(pts
				(arc
					(start 424.499786 -144.658334)
					(mid 424.744388 -145.466308)
					(end 425.552362 -145.221706)
				)
				(arc
					(start 426.30217 -143.821658)
					(mid 426.057568 -143.013684)
					(end 425.249594 -143.258286)
				)
			)
		)
	)
	(zone
		(layers "F.Cu" "B.Cu" "In1.Cu" "In2.Cu" "In3.Cu" "In4.Cu" "In5.Cu" "In6.Cu"
			"In7.Cu" "In8.Cu" "In9.Cu" "In10.Cu" "In11.Cu" "In12.Cu"
		)
		(hatch none 0.5)
		(connect_pads
			(clearance 0)
		)
		(min_thickness 0.25)
		(keepout
			(tracks not_allowed)
			(vias allowed)
			(pads allowed)
			(copperpour not_allowed)
			(footprints allowed)
		)
		(placement
			(enabled no)
			(sheetname "")
		)
		(fill yes
			(thermal_gap 0.5)
			(thermal_bridge_width 0.5)
			(island_removal_mode 0)
		)
		(polygon
			(pts
				(arc
					(start 424.499786 -156.058362)
					(mid 424.744388 -156.866336)
					(end 425.552362 -156.621734)
				)
				(arc
					(start 426.30217 -155.221686)
					(mid 426.057568 -154.413712)
					(end 425.249594 -154.658314)
				)
			)
		)
	)
	(zone
		(layers "F.Cu" "B.Cu" "In1.Cu" "In2.Cu" "In3.Cu" "In4.Cu" "In5.Cu" "In6.Cu"
			"In7.Cu" "In8.Cu" "In9.Cu" "In10.Cu" "In11.Cu" "In12.Cu"
		)
		(hatch none 0.5)
		(connect_pads
			(clearance 0)
		)
		(min_thickness 0.25)
		(keepout
			(tracks not_allowed)
			(vias allowed)
			(pads allowed)
			(copperpour not_allowed)
			(footprints allowed)
		)
		(placement
			(enabled no)
			(sheetname "")
		)
		(fill yes
			(thermal_gap 0.5)
			(thermal_bridge_width 0.5)
			(island_removal_mode 0)
		)
		(polygon
			(pts
				(arc
					(start 420.158926 -146.9009)
					(mid 419.777926 -146.5199)
					(end 419.396926 -146.9009)
				)
				(arc
					(start 419.396926 -147.9169)
					(mid 419.777926 -148.2979)
					(end 420.158926 -147.9169)
				)
			)
		)
	)
	(zone
		(layers "F.Cu" "B.Cu" "In1.Cu" "In2.Cu" "In3.Cu" "In4.Cu" "In5.Cu" "In6.Cu"
			"In7.Cu" "In8.Cu" "In9.Cu" "In10.Cu" "In11.Cu" "In12.Cu"
		)
		(hatch none 0.5)
		(connect_pads
			(clearance 0)
		)
		(min_thickness 0.25)
		(keepout
			(tracks not_allowed)
			(vias allowed)
			(pads allowed)
			(copperpour not_allowed)
			(footprints allowed)
		)
		(placement
			(enabled no)
			(sheetname "")
		)
		(fill yes
			(thermal_gap 0.5)
			(thermal_bridge_width 0.5)
			(island_removal_mode 0)
		)
		(polygon
			(pts
				(arc
					(start 412.49981 -144.658334)
					(mid 412.744412 -145.466308)
					(end 413.552386 -145.221706)
				)
				(arc
					(start 414.302194 -143.821658)
					(mid 414.057592 -143.013684)
					(end 413.249618 -143.258286)
				)
			)
		)
	)
	(zone
		(layers "F.Cu" "B.Cu" "In1.Cu" "In2.Cu" "In3.Cu" "In4.Cu" "In5.Cu" "In6.Cu"
			"In7.Cu" "In8.Cu" "In9.Cu" "In10.Cu" "In11.Cu" "In12.Cu"
		)
		(hatch none 0.5)
		(connect_pads
			(clearance 0)
		)
		(min_thickness 0.25)
		(keepout
			(tracks not_allowed)
			(vias allowed)
			(pads allowed)
			(copperpour not_allowed)
			(footprints allowed)
		)
		(placement
			(enabled no)
			(sheetname "")
		)
		(fill yes
			(thermal_gap 0.5)
			(thermal_bridge_width 0.5)
			(island_removal_mode 0)
		)
		(polygon
			(pts
				(arc
					(start 412.49981 -152.258268)
					(mid 412.744412 -153.066242)
					(end 413.552386 -152.82164)
				)
				(arc
					(start 414.302194 -151.421592)
					(mid 414.057592 -150.613618)
					(end 413.249618 -150.85822)
				)
			)
		)
	)
	(zone
		(layers "F.Cu" "B.Cu" "In1.Cu" "In2.Cu" "In3.Cu" "In4.Cu" "In5.Cu" "In6.Cu"
			"In7.Cu" "In8.Cu" "In9.Cu" "In10.Cu" "In11.Cu" "In12.Cu"
		)
		(hatch none 0.5)
		(connect_pads
			(clearance 0)
		)
		(min_thickness 0.25)
		(keepout
			(tracks not_allowed)
			(vias allowed)
			(pads allowed)
			(copperpour not_allowed)
			(footprints allowed)
		)
		(placement
			(enabled no)
			(sheetname "")
		)
		(fill yes
			(thermal_gap 0.5)
			(thermal_bridge_width 0.5)
			(island_removal_mode 0)
		)
		(polygon
			(pts
				(arc
					(start 426.749972 -156.058108)
					(mid 426.994066 -156.866082)
					(end 427.80204 -156.621988)
				)
				(arc
					(start 428.552102 -155.22194)
					(mid 428.308008 -154.413966)
					(end 427.500034 -154.65806)
				)
			)
		)
	)
	(zone
		(layers "F.Cu" "B.Cu" "In1.Cu" "In2.Cu" "In3.Cu" "In4.Cu" "In5.Cu" "In6.Cu"
			"In7.Cu" "In8.Cu" "In9.Cu" "In10.Cu" "In11.Cu" "In12.Cu"
		)
		(hatch none 0.5)
		(connect_pads
			(clearance 0)
		)
		(min_thickness 0.25)
		(keepout
			(tracks not_allowed)
			(vias allowed)
			(pads allowed)
			(copperpour not_allowed)
			(footprints allowed)
		)
		(placement
			(enabled no)
			(sheetname "")
		)
		(fill yes
			(thermal_gap 0.5)
			(thermal_bridge_width 0.5)
			(island_removal_mode 0)
		)
		(polygon
			(pts
				(arc
					(start 424.499786 -152.258268)
					(mid 424.744388 -153.066242)
					(end 425.552362 -152.82164)
				)
				(arc
					(start 426.30217 -151.421592)
					(mid 426.057568 -150.613618)
					(end 425.249594 -150.85822)
				)
			)
		)
	)
	(zone
		(layers "F.Cu" "B.Cu" "In1.Cu" "In2.Cu" "In3.Cu" "In4.Cu" "In5.Cu" "In6.Cu"
			"In7.Cu" "In8.Cu" "In9.Cu" "In10.Cu" "In11.Cu" "In12.Cu"
		)
		(hatch none 0.5)
		(connect_pads
			(clearance 0)
		)
		(min_thickness 0.25)
		(keepout
			(tracks not_allowed)
			(vias allowed)
			(pads allowed)
			(copperpour not_allowed)
			(footprints allowed)
		)
		(placement
			(enabled no)
			(sheetname "")
		)
		(fill yes
			(thermal_gap 0.5)
			(thermal_bridge_width 0.5)
			(island_removal_mode 0)
		)
		(polygon
			(pts
				(arc
					(start 414.749996 -148.458174)
					(mid 414.99409 -149.266148)
					(end 415.802064 -149.022054)
				)
				(arc
					(start 416.552126 -147.622006)
					(mid 416.308032 -146.814032)
					(end 415.500058 -147.058126)
				)
			)
		)
	)
	(zone
		(layers "F.Cu" "B.Cu" "In1.Cu" "In2.Cu" "In3.Cu" "In4.Cu" "In5.Cu" "In6.Cu"
			"In7.Cu" "In8.Cu" "In9.Cu" "In10.Cu" "In11.Cu" "In12.Cu"
		)
		(hatch none 0.5)
		(connect_pads
			(clearance 0)
		)
		(min_thickness 0.25)
		(keepout
			(tracks not_allowed)
			(vias allowed)
			(pads allowed)
			(copperpour not_allowed)
			(footprints allowed)
		)
		(placement
			(enabled no)
			(sheetname "")
		)
		(fill yes
			(thermal_gap 0.5)
			(thermal_bridge_width 0.5)
			(island_removal_mode 0)
		)
		(polygon
			(pts
				(arc
					(start 426.749972 -144.65808)
					(mid 426.994066 -145.466054)
					(end 427.80204 -145.22196)
				)
				(arc
					(start 428.552102 -143.821912)
					(mid 428.308008 -143.013938)
					(end 427.500034 -143.258032)
				)
			)
		)
	)
	(zone
		(layers "F.Cu" "B.Cu" "In1.Cu" "In2.Cu" "In3.Cu" "In4.Cu" "In5.Cu" "In6.Cu"
			"In7.Cu" "In8.Cu" "In9.Cu" "In10.Cu" "In11.Cu" "In12.Cu"
		)
		(hatch none 0.5)
		(connect_pads
			(clearance 0)
		)
		(min_thickness 0.25)
		(keepout
			(tracks not_allowed)
			(vias allowed)
			(pads allowed)
			(copperpour not_allowed)
			(footprints allowed)
		)
		(placement
			(enabled no)
			(sheetname "")
		)
		(fill yes
			(thermal_gap 0.5)
			(thermal_bridge_width 0.5)
			(island_removal_mode 0)
		)
		(polygon
			(pts
				(arc
					(start 414.749996 -144.65808)
					(mid 414.99409 -145.466054)
					(end 415.802064 -145.22196)
				)
				(arc
					(start 416.552126 -143.821912)
					(mid 416.308032 -143.013938)
					(end 415.500058 -143.258032)
				)
			)
		)
	)
	(zone
		(layers "F.Cu" "B.Cu" "In1.Cu" "In2.Cu" "In3.Cu" "In4.Cu" "In5.Cu" "In6.Cu"
			"In7.Cu" "In8.Cu" "In9.Cu" "In10.Cu" "In11.Cu" "In12.Cu"
		)
		(hatch none 0.5)
		(connect_pads
			(clearance 0)
		)
		(min_thickness 0.25)
		(keepout
			(tracks not_allowed)
			(vias allowed)
			(pads allowed)
			(copperpour not_allowed)
			(footprints allowed)
		)
		(placement
			(enabled no)
			(sheetname "")
		)
		(fill yes
			(thermal_gap 0.5)
			(thermal_bridge_width 0.5)
			(island_removal_mode 0)
		)
		(polygon
			(pts
				(arc
					(start 426.749972 -152.258014)
					(mid 426.994066 -153.065988)
					(end 427.80204 -152.821894)
				)
				(arc
					(start 428.552102 -151.421846)
					(mid 428.308008 -150.613872)
					(end 427.500034 -150.857966)
				)
			)
		)
	)
	(zone
		(layers "F.Cu" "B.Cu" "In1.Cu" "In2.Cu" "In3.Cu" "In4.Cu" "In5.Cu" "In6.Cu"
			"In7.Cu" "In8.Cu" "In9.Cu" "In10.Cu" "In11.Cu" "In12.Cu"
		)
		(hatch none 0.5)
		(connect_pads
			(clearance 0)
		)
		(min_thickness 0.25)
		(keepout
			(tracks not_allowed)
			(vias allowed)
			(pads allowed)
			(copperpour not_allowed)
			(footprints allowed)
		)
		(placement
			(enabled no)
			(sheetname "")
		)
		(fill yes
			(thermal_gap 0.5)
			(thermal_bridge_width 0.5)
			(island_removal_mode 0)
		)
		(polygon
			(pts
				(arc
					(start 412.49981 -156.058362)
					(mid 412.744412 -156.866336)
					(end 413.552386 -156.621734)
				)
				(arc
					(start 414.302194 -155.221686)
					(mid 414.057592 -154.413712)
					(end 413.249618 -154.658314)
				)
			)
		)
	)
	(zone
		(layers "F.Cu" "B.Cu" "In1.Cu" "In2.Cu" "In3.Cu" "In4.Cu" "In5.Cu" "In6.Cu"
			"In7.Cu" "In8.Cu" "In9.Cu" "In10.Cu" "In11.Cu" "In12.Cu"
		)
		(hatch none 0.5)
		(connect_pads
			(clearance 0)
		)
		(min_thickness 0.25)
		(keepout
			(tracks not_allowed)
			(vias allowed)
			(pads allowed)
			(copperpour not_allowed)
			(footprints allowed)
		)
		(placement
			(enabled no)
			(sheetname "")
		)
		(fill yes
			(thermal_gap 0.5)
			(thermal_bridge_width 0.5)
			(island_removal_mode 0)
		)
		(polygon
			(pts
				(arc
					(start 412.49981 -148.458428)
					(mid 412.744412 -149.266402)
					(end 413.552386 -149.0218)
				)
				(arc
					(start 414.302194 -147.621752)
					(mid 414.057592 -146.813778)
					(end 413.249618 -147.05838)
				)
			)
		)
	)
	(zone
		(layers "F.Cu" "B.Cu" "In1.Cu" "In2.Cu" "In3.Cu" "In4.Cu" "In5.Cu" "In6.Cu"
			"In7.Cu" "In8.Cu" "In9.Cu" "In10.Cu" "In11.Cu" "In12.Cu"
		)
		(hatch none 0.5)
		(connect_pads
			(clearance 0)
		)
		(min_thickness 0.25)
		(keepout
			(tracks not_allowed)
			(vias allowed)
			(pads allowed)
			(copperpour not_allowed)
			(footprints allowed)
		)
		(placement
			(enabled no)
			(sheetname "")
		)
		(fill yes
			(thermal_gap 0.5)
			(thermal_bridge_width 0.5)
			(island_removal_mode 0)
		)
		(polygon
			(pts
				(arc
					(start 414.749996 -156.058108)
					(mid 414.99409 -156.866082)
					(end 415.802064 -156.621988)
				)
				(arc
					(start 416.552126 -155.22194)
					(mid 416.308032 -154.413966)
					(end 415.500058 -154.65806)
				)
			)
		)
	)
	(zone
		(layers "F.Cu" "B.Cu" "In1.Cu" "In2.Cu" "In3.Cu" "In4.Cu" "In5.Cu" "In6.Cu"
			"In7.Cu" "In8.Cu" "In9.Cu" "In10.Cu" "In11.Cu" "In12.Cu"
		)
		(hatch none 0.5)
		(connect_pads
			(clearance 0)
		)
		(min_thickness 0.25)
		(keepout
			(tracks not_allowed)
			(vias allowed)
			(pads allowed)
			(copperpour not_allowed)
			(footprints allowed)
		)
		(placement
			(enabled no)
			(sheetname "")
		)
		(fill yes
			(thermal_gap 0.5)
			(thermal_bridge_width 0.5)
			(island_removal_mode 0)
		)
		(polygon
			(pts
				(arc
					(start 424.499786 -148.458428)
					(mid 424.744388 -149.266402)
					(end 425.552362 -149.0218)
				)
				(arc
					(start 426.30217 -147.621752)
					(mid 426.057568 -146.813778)
					(end 425.249594 -147.05838)
				)
			)
		)
	)
	(zone
		(layers "F.Cu" "B.Cu" "In1.Cu" "In2.Cu" "In3.Cu" "In4.Cu" "In5.Cu" "In6.Cu"
			"In7.Cu" "In8.Cu" "In9.Cu" "In10.Cu" "In11.Cu" "In12.Cu"
		)
		(name "Package Keepin")
		(hatch none 0.5)
		(connect_pads
			(clearance 0)
		)
		(min_thickness 0.25)
		(keepout
			(tracks allowed)
			(vias allowed)
			(pads allowed)
			(copperpour allowed)
			(footprints allowed)
		)
		(placement
			(enabled no)
			(sheetname "")
		)
		(fill
			(thermal_gap 0.5)
			(thermal_bridge_width 0.5)
			(island_removal_mode 0)
		)
		(polygon
			(pts
				(xy -0.996188 0.996188) (xy -0.996188 -154.096212) (xy 496.996212 -154.096212) (xy 496.996212 -114.883692)
				(arc
					(start 428.209964 -114.883692)
					(mid 423.964638 -113.12522)
					(end 422.206166 -108.879894)
				)
				(arc
					(start 422.206166 -68.879974)
					(mid 423.964638 -64.634648)
					(end 428.209964 -62.876176)
				)
				(arc
					(start 474.53042 -62.876176)
					(mid 476.529251 -59.159487)
					(end 480.480116 -57.676288)
				)
				(xy 496.996212 -57.676288) (xy 496.996212 -19.003772)
				(arc
					(start 484.349552 -19.003772)
					(mid 480.458122 -17.391784)
					(end 478.846134 -13.500354)
				)
				(xy 478.846134 0.996188)
			)
		)
	)
	(zone
		(layers "F.Cu" "B.Cu" "In1.Cu" "In2.Cu" "In3.Cu" "In4.Cu" "In5.Cu" "In6.Cu"
			"In7.Cu" "In8.Cu" "In9.Cu" "In10.Cu" "In11.Cu" "In12.Cu"
		)
		(hatch none 0.5)
		(connect_pads
			(clearance 0)
		)
		(min_thickness 0.25)
		(keepout
			(tracks not_allowed)
			(vias allowed)
			(pads allowed)
			(copperpour not_allowed)
			(footprints allowed)
		)
		(placement
			(enabled no)
			(sheetname "")
		)
		(fill
			(thermal_gap 0.5)
			(thermal_bridge_width 0.5)
			(island_removal_mode 0)
		)
		(polygon
			(pts
				(arc
					(start 0 -153.09342)
					(mid -2.006346 -155.10002)
					(end 0 -157.10662)
				)
				(arc
					(start 0.689102 -157.10662)
					(mid 1.151358 -157.178861)
					(end 1.56972 -157.388306)
				)
				(arc
					(start 1.56972 -157.388306)
					(mid 6.502673 -155.100117)
					(end 1.569974 -152.811734)
				)
				(arc
					(start 1.569974 -152.811734)
					(mid 1.150302 -153.021265)
					(end 0.686816 -153.09342)
				)
			)
		)
	)
	(zone
		(layers "F.Cu" "B.Cu" "In1.Cu" "In2.Cu" "In3.Cu" "In4.Cu" "In5.Cu" "In6.Cu"
			"In7.Cu" "In8.Cu" "In9.Cu" "In10.Cu" "In11.Cu" "In12.Cu"
		)
		(hatch none 0.5)
		(connect_pads
			(clearance 0)
		)
		(min_thickness 0.25)
		(keepout
			(tracks not_allowed)
			(vias allowed)
			(pads allowed)
			(copperpour not_allowed)
			(footprints allowed)
		)
		(placement
			(enabled no)
			(sheetname "")
		)
		(fill
			(thermal_gap 0.5)
			(thermal_bridge_width 0.5)
			(island_removal_mode 0)
		)
		(polygon
			(pts
				(arc
					(start 171.99991 -153.09342)
					(mid 169.993564 -155.10002)
					(end 171.99991 -157.10662)
				)
				(arc
					(start 172.689012 -157.10662)
					(mid 173.151268 -157.178861)
					(end 173.56963 -157.388306)
				)
				(arc
					(start 173.56963 -157.388306)
					(mid 178.502583 -155.100117)
					(end 173.569884 -152.811734)
				)
				(arc
					(start 173.569884 -152.811734)
					(mid 173.150212 -153.021265)
					(end 172.686726 -153.09342)
				)
			)
		)
	)
	(zone
		(layers "F.Cu" "B.Cu" "In1.Cu" "In2.Cu" "In3.Cu" "In4.Cu" "In5.Cu" "In6.Cu"
			"In7.Cu" "In8.Cu" "In9.Cu" "In10.Cu" "In11.Cu" "In12.Cu"
		)
		(name "Route Keepin")
		(hatch none 0.5)
		(connect_pads
			(clearance 0)
		)
		(min_thickness 0.25)
		(keepout
			(tracks allowed)
			(vias allowed)
			(pads allowed)
			(copperpour allowed)
			(footprints allowed)
		)
		(placement
			(enabled no)
			(sheetname "")
		)
		(fill
			(thermal_gap 0.5)
			(thermal_bridge_width 0.5)
			(island_removal_mode 0)
		)
		(polygon
			(pts
				(arc
					(start 483.392734 2.500122)
					(mid 483.673128 3.1768)
					(end 484.349806 3.457194)
				)
				(arc
					(start 501.000014 3.457194)
					(mid 501.38383 3.616176)
					(end 501.542812 3.999992)
				)
				(arc
					(start 501.542812 4.99999)
					(mid 501.38383 5.383806)
					(end 501.000014 5.542788)
				)
				(arc
					(start -4.99999 5.542788)
					(mid -5.383806 5.383806)
					(end -5.542788 4.99999)
				)
				(arc
					(start -5.542788 -158.100014)
					(mid -5.383806 -158.48383)
					(end -4.99999 -158.642812)
				)
				(arc
					(start 501.000014 -158.642812)
					(mid 501.38383 -158.48383)
					(end 501.542812 -158.100014)
				)
				(arc
					(start 501.542812 -110.87989)
					(mid 501.38383 -110.496074)
					(end 501.000014 -110.337092)
				)
				(arc
					(start 428.209964 -110.337092)
					(mid 427.179569 -109.910289)
					(end 426.752766 -108.879894)
				)
				(arc
					(start 426.752766 -68.879974)
					(mid 427.179569 -67.849579)
					(end 428.209964 -67.422776)
				)
				(arc
					(start 478.48012 -67.422776)
					(mid 478.863936 -67.263794)
					(end 479.022918 -66.879978)
				)
				(arc
					(start 479.022918 -63.680086)
					(mid 479.449721 -62.649691)
					(end 480.480116 -62.222888)
				)
				(arc
					(start 501.000014 -62.222888)
					(mid 501.38383 -62.063906)
					(end 501.542812 -61.68009)
				)
				(arc
					(start 501.542812 -14.99997)
					(mid 501.38383 -14.616154)
					(end 501.000014 -14.457172)
				)
				(arc
					(start 484.349806 -14.457172)
					(mid 483.673128 -14.176778)
					(end 483.392734 -13.5001)
				)
			)
		)
	)
	(zone
		(layers "F.Cu" "B.Cu" "In1.Cu" "In2.Cu" "In3.Cu" "In4.Cu" "In5.Cu" "In6.Cu"
			"In7.Cu" "In8.Cu" "In9.Cu" "In10.Cu" "In11.Cu" "In12.Cu"
		)
		(hatch none 0.5)
		(connect_pads
			(clearance 0)
		)
		(min_thickness 0.25)
		(keepout
			(tracks not_allowed)
			(vias allowed)
			(pads allowed)
			(copperpour not_allowed)
			(footprints allowed)
		)
		(placement
			(enabled no)
			(sheetname "")
		)
		(fill
			(thermal_gap 0.5)
			(thermal_bridge_width 0.5)
			(island_removal_mode 0)
		)
		(polygon
			(pts
				(arc
					(start 171.99991 4.006596)
					(mid 169.993564 1.999996)
					(end 171.99991 -0.006604)
				)
				(arc
					(start 172.689012 -0.006604)
					(mid 173.151268 -0.078845)
					(end 173.56963 -0.28829)
				)
				(arc
					(start 173.56963 -0.28829)
					(mid 178.502583 1.999899)
					(end 173.569884 4.288282)
				)
				(arc
					(start 173.569884 4.288282)
					(mid 173.150212 4.078751)
					(end 172.686726 4.006596)
				)
			)
		)
	)
	(zone
		(layers "F.Cu" "B.Cu" "In1.Cu" "In2.Cu" "In3.Cu" "In4.Cu" "In5.Cu" "In6.Cu"
			"In7.Cu" "In8.Cu" "In9.Cu" "In10.Cu" "In11.Cu" "In12.Cu"
		)
		(hatch none 0.5)
		(connect_pads
			(clearance 0)
		)
		(min_thickness 0.25)
		(keepout
			(tracks not_allowed)
			(vias allowed)
			(pads allowed)
			(copperpour not_allowed)
			(footprints allowed)
		)
		(placement
			(enabled no)
			(sheetname "")
		)
		(fill
			(thermal_gap 0.5)
			(thermal_bridge_width 0.5)
			(island_removal_mode 0)
		)
		(polygon
			(pts
				(arc
					(start 357.000048 -153.09342)
					(mid 354.993702 -155.10002)
					(end 357.000048 -157.10662)
				)
				(arc
					(start 357.68915 -157.10662)
					(mid 358.151406 -157.178861)
					(end 358.569768 -157.388306)
				)
				(arc
					(start 358.569768 -157.388306)
					(mid 363.502721 -155.100117)
					(end 358.570022 -152.811734)
				)
				(arc
					(start 358.570022 -152.811734)
					(mid 358.15035 -153.021265)
					(end 357.686864 -153.09342)
				)
			)
		)
	)
	(zone
		(layers "F.Cu" "B.Cu" "In1.Cu" "In2.Cu" "In3.Cu" "In4.Cu" "In5.Cu" "In6.Cu"
			"In7.Cu" "In8.Cu" "In9.Cu" "In10.Cu" "In11.Cu" "In12.Cu"
		)
		(hatch none 0.5)
		(connect_pads
			(clearance 0)
		)
		(min_thickness 0.25)
		(keepout
			(tracks not_allowed)
			(vias allowed)
			(pads allowed)
			(copperpour not_allowed)
			(footprints allowed)
		)
		(placement
			(enabled no)
			(sheetname "")
		)
		(fill
			(thermal_gap 0.5)
			(thermal_bridge_width 0.5)
			(island_removal_mode 0)
		)
		(polygon
			(pts
				(arc
					(start 357.000048 4.006596)
					(mid 354.993702 1.999996)
					(end 357.000048 -0.006604)
				)
				(arc
					(start 357.68915 -0.006604)
					(mid 358.151406 -0.078845)
					(end 358.569768 -0.28829)
				)
				(arc
					(start 358.569768 -0.28829)
					(mid 363.502721 1.999899)
					(end 358.570022 4.288282)
				)
				(arc
					(start 358.570022 4.288282)
					(mid 358.15035 4.078751)
					(end 357.686864 4.006596)
				)
			)
		)
	)
	(zone
		(layers "F.Cu" "B.Cu" "In1.Cu" "In2.Cu" "In3.Cu" "In4.Cu" "In5.Cu" "In6.Cu"
			"In7.Cu" "In8.Cu" "In9.Cu" "In10.Cu" "In11.Cu" "In12.Cu"
		)
		(hatch none 0.5)
		(connect_pads
			(clearance 0)
		)
		(min_thickness 0.25)
		(keepout
			(tracks not_allowed)
			(vias allowed)
			(pads allowed)
			(copperpour not_allowed)
			(footprints allowed)
		)
		(placement
			(enabled no)
			(sheetname "")
		)
		(fill
			(thermal_gap 0.5)
			(thermal_bridge_width 0.5)
			(island_removal_mode 0)
		)
		(polygon
			(pts
				(arc
					(start 471.000074 -153.09342)
					(mid 468.993728 -155.10002)
					(end 471.000074 -157.10662)
				)
				(arc
					(start 471.689176 -157.10662)
					(mid 472.151432 -157.178861)
					(end 472.569794 -157.388306)
				)
				(arc
					(start 472.569794 -157.388306)
					(mid 477.502747 -155.100117)
					(end 472.570048 -152.811734)
				)
				(arc
					(start 472.570048 -152.811734)
					(mid 472.150376 -153.021265)
					(end 471.68689 -153.09342)
				)
			)
		)
	)
	(zone
		(layers "F.Cu" "B.Cu" "In1.Cu" "In2.Cu" "In3.Cu" "In4.Cu" "In5.Cu" "In6.Cu"
			"In7.Cu" "In8.Cu" "In9.Cu" "In10.Cu" "In11.Cu" "In12.Cu"
		)
		(hatch none 0.5)
		(connect_pads
			(clearance 0)
		)
		(min_thickness 0.25)
		(keepout
			(tracks not_allowed)
			(vias allowed)
			(pads allowed)
			(copperpour not_allowed)
			(footprints allowed)
		)
		(placement
			(enabled no)
			(sheetname "")
		)
		(fill
			(thermal_gap 0.5)
			(thermal_bridge_width 0.5)
			(island_removal_mode 0)
		)
		(polygon
			(pts
				(arc
					(start 471.000074 4.006596)
					(mid 468.993728 1.999996)
					(end 471.000074 -0.006604)
				)
				(arc
					(start 471.689176 -0.006604)
					(mid 472.151432 -0.078845)
					(end 472.569794 -0.28829)
				)
				(arc
					(start 472.569794 -0.28829)
					(mid 477.502747 1.999899)
					(end 472.570048 4.288282)
				)
				(arc
					(start 472.570048 4.288282)
					(mid 472.150376 4.078751)
					(end 471.68689 4.006596)
				)
			)
		)
	)
	(zone
		(layers "F.Cu" "B.Cu" "In1.Cu" "In2.Cu" "In3.Cu" "In5.Cu" "In6.Cu" "In7.Cu"
			"In8.Cu" "In9.Cu" "In10.Cu" "In12.Cu"
		)
		(hatch none 0.5)
		(connect_pads
			(clearance 0)
		)
		(min_thickness 0.25)
		(keepout
			(tracks not_allowed)
			(vias allowed)
			(pads allowed)
			(copperpour not_allowed)
			(footprints allowed)
		)
		(placement
			(enabled no)
			(sheetname "")
		)
		(fill yes
			(thermal_gap 0.5)
			(thermal_bridge_width 0.5)
			(island_removal_mode 0)
		)
		(polygon
			(pts
				(arc
					(start 358.34574 -109.16285)
					(mid 357.9622 -108.77931)
					(end 357.57866 -109.16285)
				)
				(arc
					(start 357.57866 -110.432596)
					(mid 357.960803 -110.816388)
					(end 358.34574 -110.43539)
				)
				(arc
					(start 358.2289 -110.43539)
					(mid 357.9622 -110.699562)
					(end 357.6955 -110.43539)
				)
				(arc
					(start 357.6955 -110.43285)
					(mid 357.9622 -110.16615)
					(end 358.2289 -110.43285)
				)
				(xy 358.34574 -110.43285) (xy 358.34574 -109.16539)
				(arc
					(start 358.2289 -109.16539)
					(mid 357.9622 -109.429562)
					(end 357.6955 -109.16539)
				)
				(arc
					(start 357.6955 -109.16285)
					(mid 357.9622 -108.89615)
					(end 358.2289 -109.16285)
				)
			)
		)
	)
	(zone
		(layers "F.Cu" "B.Cu" "In1.Cu" "In2.Cu" "In3.Cu" "In5.Cu" "In6.Cu" "In7.Cu"
			"In8.Cu" "In9.Cu" "In10.Cu" "In12.Cu"
		)
		(hatch none 0.5)
		(connect_pads
			(clearance 0)
		)
		(min_thickness 0.25)
		(keepout
			(tracks not_allowed)
			(vias allowed)
			(pads allowed)
			(copperpour not_allowed)
			(footprints allowed)
		)
		(placement
			(enabled no)
			(sheetname "")
		)
		(fill yes
			(thermal_gap 0.5)
			(thermal_bridge_width 0.5)
			(island_removal_mode 0)
		)
		(polygon
			(pts
				(arc
					(start 357.801672 -105.81005)
					(mid 357.418132 -105.42651)
					(end 357.034592 -105.81005)
				)
				(arc
					(start 357.034592 -107.079796)
					(mid 357.416735 -107.463588)
					(end 357.801672 -107.08259)
				)
				(arc
					(start 357.684832 -107.08259)
					(mid 357.418132 -107.346762)
					(end 357.151432 -107.08259)
				)
				(arc
					(start 357.151432 -107.08005)
					(mid 357.418132 -106.81335)
					(end 357.684832 -107.08005)
				)
				(xy 357.801672 -107.08005) (xy 357.801672 -105.81259)
				(arc
					(start 357.684832 -105.81259)
					(mid 357.418132 -106.076762)
					(end 357.151432 -105.81259)
				)
				(arc
					(start 357.151432 -105.81005)
					(mid 357.418132 -105.54335)
					(end 357.684832 -105.81005)
				)
			)
		)
	)
	(zone
		(layers "F.Cu" "B.Cu" "In1.Cu" "In2.Cu" "In3.Cu" "In5.Cu" "In6.Cu" "In7.Cu"
			"In8.Cu" "In9.Cu" "In10.Cu" "In12.Cu"
		)
		(hatch none 0.5)
		(connect_pads
			(clearance 0)
		)
		(min_thickness 0.25)
		(keepout
			(tracks not_allowed)
			(vias allowed)
			(pads allowed)
			(copperpour not_allowed)
			(footprints allowed)
		)
		(placement
			(enabled no)
			(sheetname "")
		)
		(fill yes
			(thermal_gap 0.5)
			(thermal_bridge_width 0.5)
			(island_removal_mode 0)
		)
		(polygon
			(pts
				(arc
					(start 356.68839 -115.204494)
					(mid 356.30485 -114.820954)
					(end 355.92131 -115.204494)
				)
				(arc
					(start 355.92131 -116.220494)
					(mid 356.30358 -116.604032)
					(end 356.68839 -116.223034)
				)
				(arc
					(start 356.57155 -116.223034)
					(mid 356.30485 -116.487206)
					(end 356.03815 -116.223034)
				)
				(arc
					(start 356.03815 -116.220494)
					(mid 356.30485 -115.953794)
					(end 356.57155 -116.220494)
				)
				(xy 356.68839 -116.220494) (xy 356.68839 -115.207034)
				(arc
					(start 356.57155 -115.207034)
					(mid 356.30485 -115.471206)
					(end 356.03815 -115.207034)
				)
				(arc
					(start 356.03815 -115.204494)
					(mid 356.30485 -114.937794)
					(end 356.57155 -115.204494)
				)
			)
		)
	)
	(zone
		(layers "F.Cu" "B.Cu" "In1.Cu" "In2.Cu" "In3.Cu" "In5.Cu" "In6.Cu" "In7.Cu"
			"In8.Cu" "In9.Cu" "In10.Cu" "In12.Cu"
		)
		(hatch none 0.5)
		(connect_pads
			(clearance 0)
		)
		(min_thickness 0.25)
		(keepout
			(tracks not_allowed)
			(vias allowed)
			(pads allowed)
			(copperpour not_allowed)
			(footprints allowed)
		)
		(placement
			(enabled no)
			(sheetname "")
		)
		(fill yes
			(thermal_gap 0.5)
			(thermal_bridge_width 0.5)
			(island_removal_mode 0)
		)
		(polygon
			(pts
				(arc
					(start 354.80879 -115.204494)
					(mid 354.42525 -114.820954)
					(end 354.04171 -115.204494)
				)
				(arc
					(start 354.04171 -116.22024)
					(mid 354.423853 -116.604032)
					(end 354.80879 -116.223034)
				)
				(arc
					(start 354.69195 -116.223034)
					(mid 354.42525 -116.487206)
					(end 354.15855 -116.223034)
				)
				(arc
					(start 354.15855 -116.220494)
					(mid 354.42525 -115.953794)
					(end 354.69195 -116.220494)
				)
				(xy 354.80879 -116.220494) (xy 354.80879 -115.207034)
				(arc
					(start 354.69195 -115.207034)
					(mid 354.42525 -115.471206)
					(end 354.15855 -115.207034)
				)
				(arc
					(start 354.15855 -115.204494)
					(mid 354.42525 -114.937794)
					(end 354.69195 -115.204494)
				)
			)
		)
	)
	(zone
		(layers "F.Cu" "B.Cu" "In1.Cu" "In2.Cu" "In3.Cu" "In5.Cu" "In6.Cu" "In7.Cu"
			"In8.Cu" "In9.Cu" "In10.Cu" "In12.Cu"
		)
		(hatch none 0.5)
		(connect_pads
			(clearance 0)
		)
		(min_thickness 0.25)
		(keepout
			(tracks not_allowed)
			(vias allowed)
			(pads allowed)
			(copperpour not_allowed)
			(footprints allowed)
		)
		(placement
			(enabled no)
			(sheetname "")
		)
		(fill yes
			(thermal_gap 0.5)
			(thermal_bridge_width 0.5)
			(island_removal_mode 0)
		)
		(polygon
			(pts
				(arc
					(start 357.360982 -103.703374)
					(mid 356.977442 -103.319834)
					(end 356.593902 -103.703374)
				)
				(arc
					(start 356.593902 -104.97312)
					(mid 356.976045 -105.356912)
					(end 357.360982 -104.975914)
				)
				(arc
					(start 357.244142 -104.975914)
					(mid 356.977442 -105.240086)
					(end 356.710742 -104.975914)
				)
				(arc
					(start 356.710742 -104.973374)
					(mid 356.977442 -104.706674)
					(end 357.244142 -104.973374)
				)
				(xy 357.360982 -104.973374) (xy 357.360982 -103.705914)
				(arc
					(start 357.244142 -103.705914)
					(mid 356.977442 -103.970086)
					(end 356.710742 -103.705914)
				)
				(arc
					(start 356.710742 -103.703374)
					(mid 356.977442 -103.436674)
					(end 357.244142 -103.703374)
				)
			)
		)
	)
	(zone
		(layers "F.Cu" "B.Cu" "In1.Cu" "In2.Cu" "In3.Cu" "In5.Cu" "In6.Cu" "In7.Cu"
			"In8.Cu" "In9.Cu" "In10.Cu" "In12.Cu"
		)
		(hatch none 0.5)
		(connect_pads
			(clearance 0)
		)
		(min_thickness 0.25)
		(keepout
			(tracks not_allowed)
			(vias allowed)
			(pads allowed)
			(copperpour not_allowed)
			(footprints allowed)
		)
		(placement
			(enabled no)
			(sheetname "")
		)
		(fill yes
			(thermal_gap 0.5)
			(thermal_bridge_width 0.5)
			(island_removal_mode 0)
		)
		(polygon
			(pts
				(arc
					(start 356.338632 -109.16285)
					(mid 355.955092 -108.77931)
					(end 355.571552 -109.16285)
				)
				(arc
					(start 355.571552 -110.432596)
					(mid 355.953695 -110.816388)
					(end 356.338632 -110.43539)
				)
				(arc
					(start 356.221792 -110.43539)
					(mid 355.955092 -110.699562)
					(end 355.688392 -110.43539)
				)
				(arc
					(start 355.688392 -110.43285)
					(mid 355.955092 -110.16615)
					(end 356.221792 -110.43285)
				)
				(xy 356.338632 -110.43285) (xy 356.338632 -109.16539)
				(arc
					(start 356.221792 -109.16539)
					(mid 355.955092 -109.429562)
					(end 355.688392 -109.16539)
				)
				(arc
					(start 355.688392 -109.16285)
					(mid 355.955092 -108.89615)
					(end 356.221792 -109.16285)
				)
			)
		)
	)
	(zone
		(layers "F.Cu" "B.Cu" "In1.Cu" "In2.Cu" "In3.Cu" "In5.Cu" "In6.Cu" "In7.Cu"
			"In8.Cu" "In9.Cu" "In10.Cu" "In12.Cu"
		)
		(hatch none 0.5)
		(connect_pads
			(clearance 0)
		)
		(min_thickness 0.25)
		(keepout
			(tracks not_allowed)
			(vias allowed)
			(pads allowed)
			(copperpour not_allowed)
			(footprints allowed)
		)
		(placement
			(enabled no)
			(sheetname "")
		)
		(fill yes
			(thermal_gap 0.5)
			(thermal_bridge_width 0.5)
			(island_removal_mode 0)
		)
		(polygon
			(pts
				(arc
					(start 359.138728 -105.92816)
					(mid 359.405428 -105.66146)
					(end 359.672128 -105.92816)
				)
				(xy 359.791762 -105.92816) (xy 359.791254 -105.915206)
				(arc
					(start 359.788714 -105.915206)
					(mid 359.392474 -105.544874)
					(end 359.022142 -105.941114)
				)
				(xy 359.019602 -105.941114) (xy 359.061258 -107.186984) (xy 359.061512 -107.187238)
				(arc
					(start 359.063798 -107.187238)
					(mid 359.452292 -107.557753)
					(end 359.830624 -107.176824)
				)
				(arc
					(start 359.713784 -107.176824)
					(mid 359.447084 -107.440996)
					(end 359.180384 -107.176824)
				)
				(arc
					(start 359.180384 -107.174284)
					(mid 359.447084 -106.907584)
					(end 359.713784 -107.174284)
				)
				(xy 359.830624 -107.174284) (xy 359.83037 -107.16133) (xy 359.83291 -107.16133) (xy 359.791762 -105.9307)
				(arc
					(start 359.672128 -105.9307)
					(mid 359.405428 -106.194872)
					(end 359.138728 -105.9307)
				)
			)
		)
	)
	(zone
		(layers "F.Cu" "B.Cu" "In1.Cu" "In2.Cu" "In3.Cu" "In5.Cu" "In6.Cu" "In7.Cu"
			"In8.Cu" "In9.Cu" "In10.Cu" "In12.Cu"
		)
		(hatch none 0.5)
		(connect_pads
			(clearance 0)
		)
		(min_thickness 0.25)
		(keepout
			(tracks not_allowed)
			(vias allowed)
			(pads allowed)
			(copperpour not_allowed)
			(footprints allowed)
		)
		(placement
			(enabled no)
			(sheetname "")
		)
		(fill yes
			(thermal_gap 0.5)
			(thermal_bridge_width 0.5)
			(island_removal_mode 0)
		)
		(polygon
			(pts
				(arc
					(start 358.64419 -115.204494)
					(mid 358.26065 -114.820954)
					(end 357.87711 -115.204494)
				)
				(arc
					(start 357.87711 -116.220494)
					(mid 358.25938 -116.604032)
					(end 358.64419 -116.223034)
				)
				(arc
					(start 358.52735 -116.223034)
					(mid 358.26065 -116.487206)
					(end 357.99395 -116.223034)
				)
				(arc
					(start 357.99395 -116.220494)
					(mid 358.26065 -115.953794)
					(end 358.52735 -116.220494)
				)
				(xy 358.64419 -116.220494) (xy 358.64419 -115.207034)
				(arc
					(start 358.52735 -115.207034)
					(mid 358.26065 -115.471206)
					(end 357.99395 -115.207034)
				)
				(arc
					(start 357.99395 -115.204494)
					(mid 358.26065 -114.937794)
					(end 358.52735 -115.204494)
				)
			)
		)
	)
	(zone
		(layers "F.Cu" "In1.Cu" "In2.Cu" "In3.Cu" "In4.Cu" "In5.Cu" "In6.Cu" "In7.Cu"
			"In8.Cu" "In9.Cu" "In10.Cu" "In12.Cu"
		)
		(hatch none 0.5)
		(connect_pads
			(clearance 0)
		)
		(min_thickness 0.25)
		(keepout
			(tracks not_allowed)
			(vias allowed)
			(pads allowed)
			(copperpour not_allowed)
			(footprints allowed)
		)
		(placement
			(enabled no)
			(sheetname "")
		)
		(fill yes
			(thermal_gap 0.5)
			(thermal_bridge_width 0.5)
			(island_removal_mode 0)
		)
		(polygon
			(pts
				(arc
					(start 388.117842 -29.405326)
					(mid 387.734302 -29.021786)
					(end 387.350762 -29.405326)
				)
				(arc
					(start 387.350762 -30.675326)
					(mid 387.733032 -31.058864)
					(end 388.117842 -30.677866)
				)
				(arc
					(start 388.001002 -30.677866)
					(mid 387.734302 -30.942038)
					(end 387.467602 -30.677866)
				)
				(arc
					(start 387.467602 -30.675326)
					(mid 387.734302 -30.408626)
					(end 388.001002 -30.675326)
				)
				(xy 388.117842 -30.675326) (xy 388.117842 -29.407866)
				(arc
					(start 388.001002 -29.407866)
					(mid 387.734302 -29.672038)
					(end 387.467602 -29.407866)
				)
				(arc
					(start 387.467602 -29.405326)
					(mid 387.734302 -29.138626)
					(end 388.001002 -29.405326)
				)
			)
		)
	)
	(zone
		(layers "F.Cu" "In1.Cu" "In2.Cu" "In3.Cu" "In4.Cu" "In5.Cu" "In6.Cu" "In7.Cu"
			"In8.Cu" "In9.Cu" "In10.Cu" "In12.Cu"
		)
		(hatch none 0.5)
		(connect_pads
			(clearance 0)
		)
		(min_thickness 0.25)
		(keepout
			(tracks not_allowed)
			(vias allowed)
			(pads allowed)
			(copperpour not_allowed)
			(footprints allowed)
		)
		(placement
			(enabled no)
			(sheetname "")
		)
		(fill yes
			(thermal_gap 0.5)
			(thermal_bridge_width 0.5)
			(island_removal_mode 0)
		)
		(polygon
			(pts
				(arc
					(start 388.176516 -23.68931)
					(mid 387.792976 -23.30577)
					(end 387.409436 -23.68931)
				)
				(arc
					(start 387.409436 -24.95931)
					(mid 387.791706 -25.342848)
					(end 388.176516 -24.96185)
				)
				(arc
					(start 388.059676 -24.96185)
					(mid 387.792976 -25.226022)
					(end 387.526276 -24.96185)
				)
				(arc
					(start 387.526276 -24.95931)
					(mid 387.792976 -24.69261)
					(end 388.059676 -24.95931)
				)
				(xy 388.176516 -24.95931) (xy 388.176516 -23.69185)
				(arc
					(start 388.059676 -23.69185)
					(mid 387.792976 -23.956022)
					(end 387.526276 -23.69185)
				)
				(arc
					(start 387.526276 -23.68931)
					(mid 387.792976 -23.42261)
					(end 388.059676 -23.68931)
				)
			)
		)
	)
	(zone
		(layers "F.Cu" "In1.Cu" "In2.Cu" "In3.Cu" "In4.Cu" "In5.Cu" "In6.Cu" "In7.Cu"
			"In8.Cu" "In9.Cu" "In10.Cu" "In12.Cu"
		)
		(hatch none 0.5)
		(connect_pads
			(clearance 0)
		)
		(min_thickness 0.25)
		(keepout
			(tracks not_allowed)
			(vias allowed)
			(pads allowed)
			(copperpour not_allowed)
			(footprints allowed)
		)
		(placement
			(enabled no)
			(sheetname "")
		)
		(fill yes
			(thermal_gap 0.5)
			(thermal_bridge_width 0.5)
			(island_removal_mode 0)
		)
		(polygon
			(pts
				(xy 388.12089 -26.405332) (xy 388.11962 -26.382472) (xy 388.119366 -26.382218)
				(arc
					(start 388.11708 -26.382472)
					(mid 387.711442 -26.022554)
					(end 387.351524 -26.428192)
				)
				(xy 387.348984 -26.428446) (xy 387.425184 -27.698446)
				(arc
					(start 387.427724 -27.698192)
					(mid 387.820668 -28.058418)
					(end 388.194042 -27.677872)
				)
				(arc
					(start 388.077202 -27.677872)
					(mid 387.810502 -27.942044)
					(end 387.543802 -27.677872)
				)
				(arc
					(start 387.543802 -27.675332)
					(mid 387.810502 -27.408632)
					(end 388.077202 -27.675332)
				)
				(xy 388.194042 -27.675332) (xy 388.19328 -27.652472) (xy 388.19582 -27.652218) (xy 388.121144 -26.407872)
				(arc
					(start 388.001002 -26.407872)
					(mid 387.734302 -26.672044)
					(end 387.467602 -26.407872)
				)
				(arc
					(start 387.467602 -26.405332)
					(mid 387.734302 -26.138632)
					(end 388.001002 -26.405332)
				)
			)
		)
	)
	(zone
		(layers "F.Cu" "In1.Cu" "In2.Cu" "In3.Cu" "In4.Cu" "In5.Cu" "In6.Cu" "In7.Cu"
			"In8.Cu" "In10.Cu" "In11.Cu" "In12.Cu"
		)
		(hatch none 0.5)
		(connect_pads
			(clearance 0)
		)
		(min_thickness 0.25)
		(keepout
			(tracks not_allowed)
			(vias allowed)
			(pads allowed)
			(copperpour not_allowed)
			(footprints allowed)
		)
		(placement
			(enabled no)
			(sheetname "")
		)
		(fill yes
			(thermal_gap 0.5)
			(thermal_bridge_width 0.5)
			(island_removal_mode 0)
		)
		(polygon
			(pts
				(arc
					(start 422.19626 -149.0345)
					(mid 421.81272 -148.65096)
					(end 421.42918 -149.0345)
				)
				(arc
					(start 421.42918 -150.050246)
					(mid 421.811323 -150.434038)
					(end 422.19626 -150.05304)
				)
				(arc
					(start 422.07942 -150.05304)
					(mid 421.81272 -150.317212)
					(end 421.54602 -150.05304)
				)
				(arc
					(start 421.54602 -150.0505)
					(mid 421.81272 -149.7838)
					(end 422.07942 -150.0505)
				)
				(xy 422.19626 -150.0505) (xy 422.19626 -149.03704)
				(arc
					(start 422.07942 -149.03704)
					(mid 421.81272 -149.301212)
					(end 421.54602 -149.03704)
				)
				(arc
					(start 421.54602 -149.0345)
					(mid 421.81272 -148.7678)
					(end 422.07942 -149.0345)
				)
			)
		)
	)
	(zone
		(layers "F.Cu" "In1.Cu" "In2.Cu" "In3.Cu" "In4.Cu" "In5.Cu" "In6.Cu" "In7.Cu"
			"In8.Cu" "In10.Cu" "In11.Cu" "In12.Cu"
		)
		(hatch none 0.5)
		(connect_pads
			(clearance 0)
		)
		(min_thickness 0.25)
		(keepout
			(tracks not_allowed)
			(vias allowed)
			(pads allowed)
			(copperpour not_allowed)
			(footprints allowed)
		)
		(placement
			(enabled no)
			(sheetname "")
		)
		(fill yes
			(thermal_gap 0.5)
			(thermal_bridge_width 0.5)
			(island_removal_mode 0)
		)
		(polygon
			(pts
				(arc
					(start 16.026892 -38.090602)
					(mid 15.643352 -38.474142)
					(end 16.026892 -38.857682)
				)
				(arc
					(start 17.296638 -38.857682)
					(mid 17.567106 -38.746332)
					(end 17.680432 -38.476682)
				)
				(arc
					(start 17.563592 -38.476682)
					(mid 17.296892 -38.740854)
					(end 17.030192 -38.476682)
				)
				(arc
					(start 16.293592 -38.476682)
					(mid 16.026892 -38.740854)
					(end 15.760192 -38.476682)
				)
				(arc
					(start 15.760192 -38.474142)
					(mid 16.026892 -38.207442)
					(end 16.293592 -38.474142)
				)
				(arc
					(start 17.030192 -38.474142)
					(mid 17.296892 -38.207442)
					(end 17.563592 -38.474142)
				)
				(arc
					(start 17.680432 -38.474142)
					(mid 17.568096 -38.202938)
					(end 17.296892 -38.090602)
				)
			)
		)
	)
	(zone
		(layers "F.Cu" "In1.Cu" "In2.Cu" "In3.Cu" "In4.Cu" "In5.Cu" "In6.Cu" "In7.Cu"
			"In8.Cu" "In10.Cu" "In11.Cu" "In12.Cu"
		)
		(hatch none 0.5)
		(connect_pads
			(clearance 0)
		)
		(min_thickness 0.25)
		(keepout
			(tracks not_allowed)
			(vias allowed)
			(pads allowed)
			(copperpour not_allowed)
			(footprints allowed)
		)
		(placement
			(enabled no)
			(sheetname "")
		)
		(fill yes
			(thermal_gap 0.5)
			(thermal_bridge_width 0.5)
			(island_removal_mode 0)
		)
		(polygon
			(pts
				(arc
					(start 409.963366 -148.845016)
					(mid 409.579826 -148.461476)
					(end 409.196286 -148.845016)
				)
				(arc
					(start 409.196286 -149.860762)
					(mid 409.578429 -150.244554)
					(end 409.963366 -149.863556)
				)
				(arc
					(start 409.846526 -149.863556)
					(mid 409.579826 -150.127728)
					(end 409.313126 -149.863556)
				)
				(arc
					(start 409.313126 -149.861016)
					(mid 409.579826 -149.594316)
					(end 409.846526 -149.861016)
				)
				(xy 409.963366 -149.861016) (xy 409.963366 -148.847556)
				(arc
					(start 409.846526 -148.847556)
					(mid 409.579826 -149.111728)
					(end 409.313126 -148.847556)
				)
				(arc
					(start 409.313126 -148.845016)
					(mid 409.579826 -148.578316)
					(end 409.846526 -148.845016)
				)
			)
		)
	)
	(zone
		(layers "F.Cu" "In1.Cu" "In2.Cu" "In3.Cu" "In4.Cu" "In5.Cu" "In6.Cu" "In7.Cu"
			"In8.Cu" "In10.Cu" "In11.Cu" "In12.Cu"
		)
		(hatch none 0.5)
		(connect_pads
			(clearance 0)
		)
		(min_thickness 0.25)
		(keepout
			(tracks not_allowed)
			(vias allowed)
			(pads allowed)
			(copperpour not_allowed)
			(footprints allowed)
		)
		(placement
			(enabled no)
			(sheetname "")
		)
		(fill yes
			(thermal_gap 0.5)
			(thermal_bridge_width 0.5)
			(island_removal_mode 0)
		)
		(polygon
			(pts
				(arc
					(start 410.174186 -152.2095)
					(mid 409.790646 -151.82596)
					(end 409.407106 -152.2095)
				)
				(arc
					(start 409.407106 -153.225246)
					(mid 409.789249 -153.609038)
					(end 410.174186 -153.22804)
				)
				(arc
					(start 410.057346 -153.22804)
					(mid 409.790646 -153.492212)
					(end 409.523946 -153.22804)
				)
				(arc
					(start 409.523946 -153.2255)
					(mid 409.790646 -152.9588)
					(end 410.057346 -153.2255)
				)
				(xy 410.174186 -153.2255) (xy 410.174186 -152.21204)
				(arc
					(start 410.057346 -152.21204)
					(mid 409.790646 -152.476212)
					(end 409.523946 -152.21204)
				)
				(arc
					(start 409.523946 -152.2095)
					(mid 409.790646 -151.9428)
					(end 410.057346 -152.2095)
				)
			)
		)
	)
	(zone
		(layers "F.Cu" "In1.Cu" "In2.Cu" "In3.Cu" "In4.Cu" "In5.Cu" "In6.Cu" "In7.Cu"
			"In8.Cu" "In10.Cu" "In11.Cu" "In12.Cu"
		)
		(hatch none 0.5)
		(connect_pads
			(clearance 0)
		)
		(min_thickness 0.25)
		(keepout
			(tracks not_allowed)
			(vias allowed)
			(pads allowed)
			(copperpour not_allowed)
			(footprints allowed)
		)
		(placement
			(enabled no)
			(sheetname "")
		)
		(fill yes
			(thermal_gap 0.5)
			(thermal_bridge_width 0.5)
			(island_removal_mode 0)
		)
		(polygon
			(pts
				(arc
					(start 407.778966 -150.5585)
					(mid 407.395426 -150.17496)
					(end 407.011886 -150.5585)
				)
				(arc
					(start 407.011886 -151.574246)
					(mid 407.394029 -151.958038)
					(end 407.778966 -151.57704)
				)
				(arc
					(start 407.662126 -151.57704)
					(mid 407.395426 -151.841212)
					(end 407.128726 -151.57704)
				)
				(arc
					(start 407.128726 -151.5745)
					(mid 407.395426 -151.3078)
					(end 407.662126 -151.5745)
				)
				(xy 407.778966 -151.5745) (xy 407.778966 -150.56104)
				(arc
					(start 407.662126 -150.56104)
					(mid 407.395426 -150.825212)
					(end 407.128726 -150.56104)
				)
				(arc
					(start 407.128726 -150.5585)
					(mid 407.395426 -150.2918)
					(end 407.662126 -150.5585)
				)
			)
		)
	)
	(zone
		(layers "F.Cu" "In1.Cu" "In2.Cu" "In3.Cu" "In4.Cu" "In5.Cu" "In6.Cu" "In7.Cu"
			"In8.Cu" "In10.Cu" "In11.Cu" "In12.Cu"
		)
		(hatch none 0.5)
		(connect_pads
			(clearance 0)
		)
		(min_thickness 0.25)
		(keepout
			(tracks not_allowed)
			(vias allowed)
			(pads allowed)
			(copperpour not_allowed)
			(footprints allowed)
		)
		(placement
			(enabled no)
			(sheetname "")
		)
		(fill yes
			(thermal_gap 0.5)
			(thermal_bridge_width 0.5)
			(island_removal_mode 0)
		)
		(polygon
			(pts
				(arc
					(start 421.609266 -152.9715)
					(mid 421.225726 -152.58796)
					(end 420.842186 -152.9715)
				)
				(arc
					(start 420.842186 -153.987246)
					(mid 421.224329 -154.371038)
					(end 421.609266 -153.99004)
				)
				(arc
					(start 421.492426 -153.99004)
					(mid 421.225726 -154.254212)
					(end 420.959026 -153.99004)
				)
				(arc
					(start 420.959026 -153.9875)
					(mid 421.225726 -153.7208)
					(end 421.492426 -153.9875)
				)
				(xy 421.609266 -153.9875) (xy 421.609266 -152.97404)
				(arc
					(start 421.492426 -152.97404)
					(mid 421.225726 -153.238212)
					(end 420.959026 -152.97404)
				)
				(arc
					(start 420.959026 -152.9715)
					(mid 421.225726 -152.7048)
					(end 421.492426 -152.9715)
				)
			)
		)
	)
	(zone
		(layers "F.Cu" "In1.Cu" "In2.Cu" "In3.Cu" "In4.Cu" "In5.Cu" "In6.Cu" "In7.Cu"
			"In8.Cu" "In10.Cu" "In11.Cu" "In12.Cu"
		)
		(hatch none 0.5)
		(connect_pads
			(clearance 0)
		)
		(min_thickness 0.25)
		(keepout
			(tracks not_allowed)
			(vias allowed)
			(pads allowed)
			(copperpour not_allowed)
			(footprints allowed)
		)
		(placement
			(enabled no)
			(sheetname "")
		)
		(fill yes
			(thermal_gap 0.5)
			(thermal_bridge_width 0.5)
			(island_removal_mode 0)
		)
		(polygon
			(pts
				(arc
					(start 419.704266 -154.7368)
					(mid 419.320726 -154.35326)
					(end 418.937186 -154.7368)
				)
				(arc
					(start 418.937186 -156.006546)
					(mid 419.319329 -156.390338)
					(end 419.704266 -156.00934)
				)
				(arc
					(start 419.587426 -156.00934)
					(mid 419.320726 -156.273512)
					(end 419.054026 -156.00934)
				)
				(arc
					(start 419.054026 -156.0068)
					(mid 419.320726 -155.7401)
					(end 419.587426 -156.0068)
				)
				(xy 419.704266 -156.0068) (xy 419.704266 -154.73934)
				(arc
					(start 419.587426 -154.73934)
					(mid 419.320726 -155.003512)
					(end 419.054026 -154.73934)
				)
				(arc
					(start 419.054026 -154.7368)
					(mid 419.320726 -154.4701)
					(end 419.587426 -154.7368)
				)
			)
		)
	)
	(zone
		(layers "F.Cu" "In1.Cu" "In2.Cu" "In3.Cu" "In4.Cu" "In5.Cu" "In6.Cu" "In7.Cu"
			"In8.Cu" "In10.Cu" "In11.Cu" "In12.Cu"
		)
		(hatch none 0.5)
		(connect_pads
			(clearance 0)
		)
		(min_thickness 0.25)
		(keepout
			(tracks not_allowed)
			(vias allowed)
			(pads allowed)
			(copperpour not_allowed)
			(footprints allowed)
		)
		(placement
			(enabled no)
			(sheetname "")
		)
		(fill yes
			(thermal_gap 0.5)
			(thermal_bridge_width 0.5)
			(island_removal_mode 0)
		)
		(polygon
			(pts
				(arc
					(start 420.118286 -150.8633)
					(mid 419.734746 -150.47976)
					(end 419.351206 -150.8633)
				)
				(arc
					(start 419.351206 -151.879046)
					(mid 419.733349 -152.262838)
					(end 420.118286 -151.88184)
				)
				(arc
					(start 420.001446 -151.88184)
					(mid 419.734746 -152.146012)
					(end 419.468046 -151.88184)
				)
				(arc
					(start 419.468046 -151.8793)
					(mid 419.734746 -151.6126)
					(end 420.001446 -151.8793)
				)
				(xy 420.118286 -151.8793) (xy 420.118286 -150.86584)
				(arc
					(start 420.001446 -150.86584)
					(mid 419.734746 -151.130012)
					(end 419.468046 -150.86584)
				)
				(arc
					(start 419.468046 -150.8633)
					(mid 419.734746 -150.5966)
					(end 420.001446 -150.8633)
				)
			)
		)
	)
	(zone
		(layers "F.Cu" "In1.Cu" "In2.Cu" "In3.Cu" "In4.Cu" "In5.Cu" "In6.Cu" "In7.Cu"
			"In8.Cu" "In10.Cu" "In11.Cu" "In12.Cu"
		)
		(hatch none 0.5)
		(connect_pads
			(clearance 0)
		)
		(min_thickness 0.25)
		(keepout
			(tracks not_allowed)
			(vias allowed)
			(pads allowed)
			(copperpour not_allowed)
			(footprints allowed)
		)
		(placement
			(enabled no)
			(sheetname "")
		)
		(fill yes
			(thermal_gap 0.5)
			(thermal_bridge_width 0.5)
			(island_removal_mode 0)
		)
		(polygon
			(pts
				(arc
					(start 12.016486 -38.822884)
					(mid 11.632946 -39.206424)
					(end 12.016486 -39.589964)
				)
				(arc
					(start 13.032232 -39.589964)
					(mid 13.3027 -39.478614)
					(end 13.416026 -39.208964)
				)
				(arc
					(start 13.299186 -39.208964)
					(mid 13.032486 -39.473136)
					(end 12.765786 -39.208964)
				)
				(arc
					(start 12.283186 -39.208964)
					(mid 12.016486 -39.473136)
					(end 11.749786 -39.208964)
				)
				(arc
					(start 11.749786 -39.206424)
					(mid 12.016486 -38.939724)
					(end 12.283186 -39.206424)
				)
				(arc
					(start 12.765786 -39.206424)
					(mid 13.032486 -38.939724)
					(end 13.299186 -39.206424)
				)
				(arc
					(start 13.416026 -39.206424)
					(mid 13.30369 -38.93522)
					(end 13.032486 -38.822884)
				)
			)
		)
	)
	(zone
		(layers "F.Cu" "In1.Cu" "In2.Cu" "In3.Cu" "In4.Cu" "In5.Cu" "In6.Cu" "In7.Cu"
			"In8.Cu" "In10.Cu" "In11.Cu" "In12.Cu"
		)
		(hatch none 0.5)
		(connect_pads
			(clearance 0)
		)
		(min_thickness 0.25)
		(keepout
			(tracks not_allowed)
			(vias allowed)
			(pads allowed)
			(copperpour not_allowed)
			(footprints allowed)
		)
		(placement
			(enabled no)
			(sheetname "")
		)
		(fill yes
			(thermal_gap 0.5)
			(thermal_bridge_width 0.5)
			(island_removal_mode 0)
		)
		(polygon
			(pts
				(arc
					(start 407.766266 -153.5303)
					(mid 407.382726 -153.14676)
					(end 406.999186 -153.5303)
				)
				(arc
					(start 406.999186 -154.546046)
					(mid 407.381329 -154.929838)
					(end 407.766266 -154.54884)
				)
				(arc
					(start 407.649426 -154.54884)
					(mid 407.382726 -154.813012)
					(end 407.116026 -154.54884)
				)
				(arc
					(start 407.116026 -154.5463)
					(mid 407.382726 -154.2796)
					(end 407.649426 -154.5463)
				)
				(xy 407.766266 -154.5463) (xy 407.766266 -153.53284)
				(arc
					(start 407.649426 -153.53284)
					(mid 407.382726 -153.797012)
					(end 407.116026 -153.53284)
				)
				(arc
					(start 407.116026 -153.5303)
					(mid 407.382726 -153.2636)
					(end 407.649426 -153.5303)
				)
			)
		)
	)
	(zone
		(layers "F.Cu" "In1.Cu" "In2.Cu" "In3.Cu" "In5.Cu" "In6.Cu" "In7.Cu" "In8.Cu"
			"In9.Cu" "In10.Cu" "In11.Cu" "In12.Cu"
		)
		(hatch none 0.5)
		(connect_pads
			(clearance 0)
		)
		(min_thickness 0.25)
		(keepout
			(tracks not_allowed)
			(vias allowed)
			(pads allowed)
			(copperpour not_allowed)
			(footprints allowed)
		)
		(placement
			(enabled no)
			(sheetname "")
		)
		(fill yes
			(thermal_gap 0.5)
			(thermal_bridge_width 0.5)
			(island_removal_mode 0)
		)
		(polygon
			(pts
				(arc
					(start 453.269604 -123.80468)
					(mid 452.88581 -124.188093)
					(end 453.26935 -124.57176)
				)
				(arc
					(start 454.53935 -124.57176)
					(mid 454.809654 -124.46032)
					(end 454.92289 -124.19076)
				)
				(arc
					(start 454.80605 -124.19076)
					(mid 454.53935 -124.454932)
					(end 454.27265 -124.19076)
				)
				(arc
					(start 453.53605 -124.19076)
					(mid 453.26935 -124.454932)
					(end 453.00265 -124.19076)
				)
				(arc
					(start 453.00265 -124.18822)
					(mid 453.26935 -123.92152)
					(end 453.53605 -124.18822)
				)
				(arc
					(start 454.27265 -124.18822)
					(mid 454.53935 -123.92152)
					(end 454.80605 -124.18822)
				)
				(arc
					(start 454.92289 -124.18822)
					(mid 454.810554 -123.917016)
					(end 454.53935 -123.80468)
				)
			)
		)
	)
	(zone
		(layers "F.Cu" "In1.Cu" "In2.Cu" "In3.Cu" "In5.Cu" "In6.Cu" "In7.Cu" "In8.Cu"
			"In9.Cu" "In10.Cu" "In11.Cu" "In12.Cu"
		)
		(hatch none 0.5)
		(connect_pads
			(clearance 0)
		)
		(min_thickness 0.25)
		(keepout
			(tracks not_allowed)
			(vias allowed)
			(pads allowed)
			(copperpour not_allowed)
			(footprints allowed)
		)
		(placement
			(enabled no)
			(sheetname "")
		)
		(fill yes
			(thermal_gap 0.5)
			(thermal_bridge_width 0.5)
			(island_removal_mode 0)
		)
		(polygon
			(pts
				(arc
					(start 12.89685 -106.42473)
					(mid 12.51331 -106.04119)
					(end 12.12977 -106.42473)
				)
				(arc
					(start 12.12977 -107.694476)
					(mid 12.511913 -108.078268)
					(end 12.89685 -107.69727)
				)
				(arc
					(start 12.78001 -107.69727)
					(mid 12.51331 -107.961442)
					(end 12.24661 -107.69727)
				)
				(arc
					(start 12.24661 -107.69473)
					(mid 12.51331 -107.42803)
					(end 12.78001 -107.69473)
				)
				(xy 12.89685 -107.69473) (xy 12.89685 -106.42727)
				(arc
					(start 12.78001 -106.42727)
					(mid 12.51331 -106.691442)
					(end 12.24661 -106.42727)
				)
				(arc
					(start 12.24661 -106.42473)
					(mid 12.51331 -106.15803)
					(end 12.78001 -106.42473)
				)
			)
		)
	)
	(zone
		(layers "F.Cu" "In1.Cu" "In2.Cu" "In3.Cu" "In5.Cu" "In6.Cu" "In7.Cu" "In8.Cu"
			"In9.Cu" "In10.Cu" "In11.Cu" "In12.Cu"
		)
		(hatch none 0.5)
		(connect_pads
			(clearance 0)
		)
		(min_thickness 0.25)
		(keepout
			(tracks not_allowed)
			(vias allowed)
			(pads allowed)
			(copperpour not_allowed)
			(footprints allowed)
		)
		(placement
			(enabled no)
			(sheetname "")
		)
		(fill yes
			(thermal_gap 0.5)
			(thermal_bridge_width 0.5)
			(island_removal_mode 0)
		)
		(polygon
			(pts
				(arc
					(start 2.739898 -111.82985)
					(mid 2.356104 -112.213263)
					(end 2.739644 -112.59693)
				)
				(arc
					(start 4.009644 -112.59693)
					(mid 4.279948 -112.48549)
					(end 4.393184 -112.21593)
				)
				(arc
					(start 4.276344 -112.21593)
					(mid 4.009644 -112.480102)
					(end 3.742944 -112.21593)
				)
				(arc
					(start 3.006344 -112.21593)
					(mid 2.739644 -112.480102)
					(end 2.472944 -112.21593)
				)
				(arc
					(start 2.472944 -112.21339)
					(mid 2.739644 -111.94669)
					(end 3.006344 -112.21339)
				)
				(arc
					(start 3.742944 -112.21339)
					(mid 4.009644 -111.94669)
					(end 4.276344 -112.21339)
				)
				(arc
					(start 4.393184 -112.21339)
					(mid 4.280848 -111.942186)
					(end 4.009644 -111.82985)
				)
			)
		)
	)
	(zone
		(layers "F.Cu" "In1.Cu" "In2.Cu" "In3.Cu" "In5.Cu" "In6.Cu" "In7.Cu" "In8.Cu"
			"In9.Cu" "In10.Cu" "In11.Cu" "In12.Cu"
		)
		(hatch none 0.5)
		(connect_pads
			(clearance 0)
		)
		(min_thickness 0.25)
		(keepout
			(tracks not_allowed)
			(vias allowed)
			(pads allowed)
			(copperpour not_allowed)
			(footprints allowed)
		)
		(placement
			(enabled no)
			(sheetname "")
		)
		(fill yes
			(thermal_gap 0.5)
			(thermal_bridge_width 0.5)
			(island_removal_mode 0)
		)
		(polygon
			(pts
				(arc
					(start 442.754004 -125.70206)
					(mid 442.37021 -126.085473)
					(end 442.75375 -126.46914)
				)
				(arc
					(start 444.02375 -126.46914)
					(mid 444.294054 -126.3577)
					(end 444.40729 -126.08814)
				)
				(arc
					(start 444.29045 -126.08814)
					(mid 444.02375 -126.352312)
					(end 443.75705 -126.08814)
				)
				(arc
					(start 443.02045 -126.08814)
					(mid 442.75375 -126.352312)
					(end 442.48705 -126.08814)
				)
				(arc
					(start 442.48705 -126.0856)
					(mid 442.75375 -125.8189)
					(end 443.02045 -126.0856)
				)
				(arc
					(start 443.75705 -126.0856)
					(mid 444.02375 -125.8189)
					(end 444.29045 -126.0856)
				)
				(arc
					(start 444.40729 -126.0856)
					(mid 444.294954 -125.814396)
					(end 444.02375 -125.70206)
				)
			)
		)
	)
	(zone
		(layers "F.Cu" "In1.Cu" "In2.Cu" "In3.Cu" "In5.Cu" "In6.Cu" "In7.Cu" "In8.Cu"
			"In9.Cu" "In10.Cu" "In11.Cu" "In12.Cu"
		)
		(hatch none 0.5)
		(connect_pads
			(clearance 0)
		)
		(min_thickness 0.25)
		(keepout
			(tracks not_allowed)
			(vias allowed)
			(pads allowed)
			(copperpour not_allowed)
			(footprints allowed)
		)
		(placement
			(enabled no)
			(sheetname "")
		)
		(fill yes
			(thermal_gap 0.5)
			(thermal_bridge_width 0.5)
			(island_removal_mode 0)
		)
		(polygon
			(pts
				(arc
					(start 3.054604 -107.52836)
					(mid 2.67081 -107.911773)
					(end 3.05435 -108.29544)
				)
				(arc
					(start 4.32435 -108.29544)
					(mid 4.594654 -108.184)
					(end 4.70789 -107.91444)
				)
				(arc
					(start 4.59105 -107.91444)
					(mid 4.32435 -108.178612)
					(end 4.05765 -107.91444)
				)
				(arc
					(start 3.32105 -107.91444)
					(mid 3.05435 -108.178612)
					(end 2.78765 -107.91444)
				)
				(arc
					(start 2.78765 -107.9119)
					(mid 3.05435 -107.6452)
					(end 3.32105 -107.9119)
				)
				(arc
					(start 4.05765 -107.9119)
					(mid 4.32435 -107.6452)
					(end 4.59105 -107.9119)
				)
				(arc
					(start 4.70789 -107.9119)
					(mid 4.595554 -107.640696)
					(end 4.32435 -107.52836)
				)
			)
		)
	)
	(zone
		(layers "F.Cu" "In1.Cu" "In2.Cu" "In3.Cu" "In5.Cu" "In6.Cu" "In7.Cu" "In8.Cu"
			"In9.Cu" "In10.Cu" "In11.Cu" "In12.Cu"
		)
		(hatch none 0.5)
		(connect_pads
			(clearance 0)
		)
		(min_thickness 0.25)
		(keepout
			(tracks not_allowed)
			(vias allowed)
			(pads allowed)
			(copperpour not_allowed)
			(footprints allowed)
		)
		(placement
			(enabled no)
			(sheetname "")
		)
		(fill yes
			(thermal_gap 0.5)
			(thermal_bridge_width 0.5)
			(island_removal_mode 0)
		)
		(polygon
			(pts
				(arc
					(start 443.51575 -53.370734)
					(mid 443.13221 -53.754274)
					(end 443.51575 -54.137814)
				)
				(arc
					(start 444.785496 -54.137814)
					(mid 445.055964 -54.026464)
					(end 445.16929 -53.756814)
				)
				(arc
					(start 445.05245 -53.756814)
					(mid 444.78575 -54.020986)
					(end 444.51905 -53.756814)
				)
				(arc
					(start 443.78245 -53.756814)
					(mid 443.51575 -54.020986)
					(end 443.24905 -53.756814)
				)
				(arc
					(start 443.24905 -53.754274)
					(mid 443.51575 -53.487574)
					(end 443.78245 -53.754274)
				)
				(arc
					(start 444.51905 -53.754274)
					(mid 444.78575 -53.487574)
					(end 445.05245 -53.754274)
				)
				(arc
					(start 445.16929 -53.754274)
					(mid 445.056954 -53.48307)
					(end 444.78575 -53.370734)
				)
			)
		)
	)
	(zone
		(layers "F.Cu" "In1.Cu" "In2.Cu" "In3.Cu" "In5.Cu" "In6.Cu" "In7.Cu" "In8.Cu"
			"In9.Cu" "In10.Cu" "In11.Cu" "In12.Cu"
		)
		(hatch none 0.5)
		(connect_pads
			(clearance 0)
		)
		(min_thickness 0.25)
		(keepout
			(tracks not_allowed)
			(vias allowed)
			(pads allowed)
			(copperpour not_allowed)
			(footprints allowed)
		)
		(placement
			(enabled no)
			(sheetname "")
		)
		(fill yes
			(thermal_gap 0.5)
			(thermal_bridge_width 0.5)
			(island_removal_mode 0)
		)
		(polygon
			(pts
				(arc
					(start 6.593078 -111.595916)
					(mid 6.209538 -111.212376)
					(end 5.825998 -111.595916)
				)
				(arc
					(start 5.825998 -112.865916)
					(mid 6.208268 -113.249454)
					(end 6.593078 -112.868456)
				)
				(arc
					(start 6.476238 -112.868456)
					(mid 6.209538 -113.132628)
					(end 5.942838 -112.868456)
				)
				(arc
					(start 5.942838 -112.865916)
					(mid 6.209538 -112.599216)
					(end 6.476238 -112.865916)
				)
				(xy 6.593078 -112.865916) (xy 6.593078 -111.598456)
				(arc
					(start 6.476238 -111.598456)
					(mid 6.209538 -111.862628)
					(end 5.942838 -111.598456)
				)
				(arc
					(start 5.942838 -111.595916)
					(mid 6.209538 -111.329216)
					(end 6.476238 -111.595916)
				)
			)
		)
	)
	(zone
		(layers "F.Cu" "In1.Cu" "In2.Cu" "In3.Cu" "In5.Cu" "In6.Cu" "In7.Cu" "In8.Cu"
			"In9.Cu" "In10.Cu" "In11.Cu" "In12.Cu"
		)
		(hatch none 0.5)
		(connect_pads
			(clearance 0)
		)
		(min_thickness 0.25)
		(keepout
			(tracks not_allowed)
			(vias allowed)
			(pads allowed)
			(copperpour not_allowed)
			(footprints allowed)
		)
		(placement
			(enabled no)
			(sheetname "")
		)
		(fill yes
			(thermal_gap 0.5)
			(thermal_bridge_width 0.5)
			(island_removal_mode 0)
		)
		(polygon
			(pts
				(arc
					(start 0.514604 -107.52836)
					(mid 0.13081 -107.911773)
					(end 0.51435 -108.29544)
				)
				(arc
					(start 1.78435 -108.29544)
					(mid 2.054654 -108.184)
					(end 2.16789 -107.91444)
				)
				(arc
					(start 2.05105 -107.91444)
					(mid 1.78435 -108.178612)
					(end 1.51765 -107.91444)
				)
				(arc
					(start 0.78105 -107.91444)
					(mid 0.51435 -108.178612)
					(end 0.24765 -107.91444)
				)
				(arc
					(start 0.24765 -107.9119)
					(mid 0.51435 -107.6452)
					(end 0.78105 -107.9119)
				)
				(arc
					(start 1.51765 -107.9119)
					(mid 1.78435 -107.6452)
					(end 2.05105 -107.9119)
				)
				(arc
					(start 2.16789 -107.9119)
					(mid 2.055554 -107.640696)
					(end 1.78435 -107.52836)
				)
			)
		)
	)
	(zone
		(layers "F.Cu" "In1.Cu" "In2.Cu" "In3.Cu" "In5.Cu" "In6.Cu" "In7.Cu" "In8.Cu"
			"In9.Cu" "In10.Cu" "In11.Cu" "In12.Cu"
		)
		(hatch none 0.5)
		(connect_pads
			(clearance 0)
		)
		(min_thickness 0.25)
		(keepout
			(tracks not_allowed)
			(vias allowed)
			(pads allowed)
			(copperpour not_allowed)
			(footprints allowed)
		)
		(placement
			(enabled no)
			(sheetname "")
		)
		(fill yes
			(thermal_gap 0.5)
			(thermal_bridge_width 0.5)
			(island_removal_mode 0)
		)
		(polygon
			(pts
				(arc
					(start 16.82369 -99.47783)
					(mid 16.44015 -99.09429)
					(end 16.05661 -99.47783)
				)
				(arc
					(start 16.05661 -100.74783)
					(mid 16.43888 -101.131368)
					(end 16.82369 -100.75037)
				)
				(arc
					(start 16.70685 -100.75037)
					(mid 16.44015 -101.014542)
					(end 16.17345 -100.75037)
				)
				(arc
					(start 16.17345 -100.74783)
					(mid 16.44015 -100.48113)
					(end 16.70685 -100.74783)
				)
				(xy 16.82369 -100.74783) (xy 16.82369 -99.48037)
				(arc
					(start 16.70685 -99.48037)
					(mid 16.44015 -99.744542)
					(end 16.17345 -99.48037)
				)
				(arc
					(start 16.17345 -99.47783)
					(mid 16.44015 -99.21113)
					(end 16.70685 -99.47783)
				)
			)
		)
	)
	(zone
		(layers "F.Cu" "In1.Cu" "In2.Cu" "In3.Cu" "In5.Cu" "In6.Cu" "In7.Cu" "In8.Cu"
			"In9.Cu" "In10.Cu" "In11.Cu" "In12.Cu"
		)
		(hatch none 0.5)
		(connect_pads
			(clearance 0)
		)
		(min_thickness 0.25)
		(keepout
			(tracks not_allowed)
			(vias allowed)
			(pads allowed)
			(copperpour not_allowed)
			(footprints allowed)
		)
		(placement
			(enabled no)
			(sheetname "")
		)
		(fill yes
			(thermal_gap 0.5)
			(thermal_bridge_width 0.5)
			(island_removal_mode 0)
		)
		(polygon
			(pts
				(arc
					(start 453.11695 -53.370734)
					(mid 452.73341 -53.754274)
					(end 453.11695 -54.137814)
				)
				(arc
					(start 454.386696 -54.137814)
					(mid 454.657164 -54.026464)
					(end 454.77049 -53.756814)
				)
				(arc
					(start 454.65365 -53.756814)
					(mid 454.38695 -54.020986)
					(end 454.12025 -53.756814)
				)
				(arc
					(start 453.38365 -53.756814)
					(mid 453.11695 -54.020986)
					(end 452.85025 -53.756814)
				)
				(arc
					(start 452.85025 -53.754274)
					(mid 453.11695 -53.487574)
					(end 453.38365 -53.754274)
				)
				(arc
					(start 454.12025 -53.754274)
					(mid 454.38695 -53.487574)
					(end 454.65365 -53.754274)
				)
				(arc
					(start 454.77049 -53.754274)
					(mid 454.658154 -53.48307)
					(end 454.38695 -53.370734)
				)
			)
		)
	)
	(zone
		(layers "F.Cu" "In1.Cu" "In2.Cu" "In3.Cu" "In5.Cu" "In6.Cu" "In7.Cu" "In8.Cu"
			"In9.Cu" "In10.Cu" "In11.Cu" "In12.Cu"
		)
		(hatch none 0.5)
		(connect_pads
			(clearance 0)
		)
		(min_thickness 0.25)
		(keepout
			(tracks not_allowed)
			(vias allowed)
			(pads allowed)
			(copperpour not_allowed)
			(footprints allowed)
		)
		(placement
			(enabled no)
			(sheetname "")
		)
		(fill yes
			(thermal_gap 0.5)
			(thermal_bridge_width 0.5)
			(island_removal_mode 0)
		)
		(polygon
			(pts
				(arc
					(start 14.704822 -103.673402)
					(mid 14.681576 -103.541862)
					(end 14.614652 -103.42626)
				)
				(xy 14.281658 -103.031036)
				(arc
					(start 14.044676 -103.031036)
					(mid 13.777976 -103.295208)
					(end 13.511276 -103.031036)
				)
				(arc
					(start 13.511276 -103.028496)
					(mid 13.777976 -102.761796)
					(end 14.044676 -103.028496)
				)
				(xy 14.279372 -103.028496)
				(arc
					(start 14.076934 -102.788466)
					(mid 13.534438 -102.732389)
					(end 13.484606 -103.275638)
				)
				(arc
					(start 14.027912 -103.920544)
					(mid 14.451636 -104.034169)
					(end 14.704822 -103.675942)
				)
				(arc
					(start 14.587982 -103.675942)
					(mid 14.321282 -103.940114)
					(end 14.054582 -103.675942)
				)
				(arc
					(start 14.054582 -103.673402)
					(mid 14.321282 -103.406702)
					(end 14.587982 -103.673402)
				)
			)
		)
	)
	(zone
		(layers "F.Cu" "In1.Cu" "In2.Cu" "In3.Cu" "In5.Cu" "In6.Cu" "In7.Cu" "In8.Cu"
			"In9.Cu" "In10.Cu" "In11.Cu" "In12.Cu"
		)
		(hatch none 0.5)
		(connect_pads
			(clearance 0)
		)
		(min_thickness 0.25)
		(keepout
			(tracks not_allowed)
			(vias allowed)
			(pads allowed)
			(copperpour not_allowed)
			(footprints allowed)
		)
		(placement
			(enabled no)
			(sheetname "")
		)
		(fill yes
			(thermal_gap 0.5)
			(thermal_bridge_width 0.5)
			(island_removal_mode 0)
		)
		(polygon
			(pts
				(arc
					(start 15.741396 -103.031544)
					(mid 16.008096 -102.764844)
					(end 16.274796 -103.031544)
				)
				(xy 16.548608 -103.031544)
				(arc
					(start 16.879824 -102.697788)
					(mid 16.961761 -102.574854)
					(end 16.991076 -102.430072)
				)
				(arc
					(start 16.874236 -102.430072)
					(mid 16.607536 -102.694244)
					(end 16.340836 -102.430072)
				)
				(arc
					(start 16.340836 -102.427532)
					(mid 16.607536 -102.160832)
					(end 16.874236 -102.427532)
				)
				(arc
					(start 16.991076 -102.427532)
					(mid 16.753647 -102.072913)
					(end 16.335248 -102.157276)
				)
				(arc
					(start 15.741396 -102.755954)
					(mid 15.735205 -103.301005)
					(end 16.280384 -103.3018)
				)
				(xy 16.546068 -103.034084)
				(arc
					(start 16.274796 -103.034084)
					(mid 16.008096 -103.298256)
					(end 15.741396 -103.034084)
				)
			)
		)
	)
	(zone
		(layers "F.Cu" "In1.Cu" "In2.Cu" "In3.Cu" "In5.Cu" "In6.Cu" "In7.Cu" "In8.Cu"
			"In9.Cu" "In10.Cu" "In11.Cu" "In12.Cu"
		)
		(hatch none 0.5)
		(connect_pads
			(clearance 0)
		)
		(min_thickness 0.25)
		(keepout
			(tracks not_allowed)
			(vias allowed)
			(pads allowed)
			(copperpour not_allowed)
			(footprints allowed)
		)
		(placement
			(enabled no)
			(sheetname "")
		)
		(fill yes
			(thermal_gap 0.5)
			(thermal_bridge_width 0.5)
			(island_removal_mode 0)
		)
		(polygon
			(pts
				(arc
					(start 445.408304 -125.703584)
					(mid 445.02451 -126.086997)
					(end 445.40805 -126.470664)
				)
				(arc
					(start 446.67805 -126.470664)
					(mid 446.948354 -126.359224)
					(end 447.06159 -126.089664)
				)
				(arc
					(start 446.94475 -126.089664)
					(mid 446.67805 -126.353836)
					(end 446.41135 -126.089664)
				)
				(arc
					(start 445.67475 -126.089664)
					(mid 445.40805 -126.353836)
					(end 445.14135 -126.089664)
				)
				(arc
					(start 445.14135 -126.087124)
					(mid 445.40805 -125.820424)
					(end 445.67475 -126.087124)
				)
				(arc
					(start 446.41135 -126.087124)
					(mid 446.67805 -125.820424)
					(end 446.94475 -126.087124)
				)
				(arc
					(start 447.06159 -126.087124)
					(mid 446.949254 -125.81592)
					(end 446.67805 -125.703584)
				)
			)
		)
	)
	(zone
		(layers "F.Cu" "In1.Cu" "In2.Cu" "In3.Cu" "In5.Cu" "In6.Cu" "In7.Cu" "In8.Cu"
			"In9.Cu" "In10.Cu" "In11.Cu" "In12.Cu"
		)
		(hatch none 0.5)
		(connect_pads
			(clearance 0)
		)
		(min_thickness 0.25)
		(keepout
			(tracks not_allowed)
			(vias allowed)
			(pads allowed)
			(copperpour not_allowed)
			(footprints allowed)
		)
		(placement
			(enabled no)
			(sheetname "")
		)
		(fill yes
			(thermal_gap 0.5)
			(thermal_bridge_width 0.5)
			(island_removal_mode 0)
		)
		(polygon
			(pts
				(arc
					(start 448.392804 -123.40463)
					(mid 448.00901 -123.788043)
					(end 448.39255 -124.17171)
				)
				(arc
					(start 449.66255 -124.17171)
					(mid 449.932854 -124.06027)
					(end 450.04609 -123.79071)
				)
				(arc
					(start 449.92925 -123.79071)
					(mid 449.66255 -124.054882)
					(end 449.39585 -123.79071)
				)
				(arc
					(start 448.65925 -123.79071)
					(mid 448.39255 -124.054882)
					(end 448.12585 -123.79071)
				)
				(arc
					(start 448.12585 -123.78817)
					(mid 448.39255 -123.52147)
					(end 448.65925 -123.78817)
				)
				(arc
					(start 449.39585 -123.78817)
					(mid 449.66255 -123.52147)
					(end 449.92925 -123.78817)
				)
				(arc
					(start 450.04609 -123.78817)
					(mid 449.933754 -123.516966)
					(end 449.66255 -123.40463)
				)
			)
		)
	)
	(zone
		(layers "F.Cu" "In1.Cu" "In2.Cu" "In3.Cu" "In5.Cu" "In6.Cu" "In7.Cu" "In8.Cu"
			"In9.Cu" "In10.Cu" "In11.Cu" "In12.Cu"
		)
		(hatch none 0.5)
		(connect_pads
			(clearance 0)
		)
		(min_thickness 0.25)
		(keepout
			(tracks not_allowed)
			(vias allowed)
			(pads allowed)
			(copperpour not_allowed)
			(footprints allowed)
		)
		(placement
			(enabled no)
			(sheetname "")
		)
		(fill yes
			(thermal_gap 0.5)
			(thermal_bridge_width 0.5)
			(island_removal_mode 0)
		)
		(polygon
			(pts
				(arc
					(start 449.91655 -53.370734)
					(mid 449.53301 -53.754274)
					(end 449.91655 -54.137814)
				)
				(arc
					(start 451.186296 -54.137814)
					(mid 451.456764 -54.026464)
					(end 451.57009 -53.756814)
				)
				(arc
					(start 451.45325 -53.756814)
					(mid 451.18655 -54.020986)
					(end 450.91985 -53.756814)
				)
				(arc
					(start 450.18325 -53.756814)
					(mid 449.91655 -54.020986)
					(end 449.64985 -53.756814)
				)
				(arc
					(start 449.64985 -53.754274)
					(mid 449.91655 -53.487574)
					(end 450.18325 -53.754274)
				)
				(arc
					(start 450.91985 -53.754274)
					(mid 451.18655 -53.487574)
					(end 451.45325 -53.754274)
				)
				(arc
					(start 451.57009 -53.754274)
					(mid 451.457754 -53.48307)
					(end 451.18655 -53.370734)
				)
			)
		)
	)
	(zone
		(layers "F.Cu" "In1.Cu" "In2.Cu" "In3.Cu" "In5.Cu" "In6.Cu" "In7.Cu" "In8.Cu"
			"In9.Cu" "In10.Cu" "In11.Cu" "In12.Cu"
		)
		(hatch none 0.5)
		(connect_pads
			(clearance 0)
		)
		(min_thickness 0.25)
		(keepout
			(tracks not_allowed)
			(vias allowed)
			(pads allowed)
			(copperpour not_allowed)
			(footprints allowed)
		)
		(placement
			(enabled no)
			(sheetname "")
		)
		(fill yes
			(thermal_gap 0.5)
			(thermal_bridge_width 0.5)
			(island_removal_mode 0)
		)
		(polygon
			(pts
				(arc
					(start 446.71615 -53.370734)
					(mid 446.33261 -53.754274)
					(end 446.71615 -54.137814)
				)
				(arc
					(start 447.985896 -54.137814)
					(mid 448.256364 -54.026464)
					(end 448.36969 -53.756814)
				)
				(arc
					(start 448.25285 -53.756814)
					(mid 447.98615 -54.020986)
					(end 447.71945 -53.756814)
				)
				(arc
					(start 446.98285 -53.756814)
					(mid 446.71615 -54.020986)
					(end 446.44945 -53.756814)
				)
				(arc
					(start 446.44945 -53.754274)
					(mid 446.71615 -53.487574)
					(end 446.98285 -53.754274)
				)
				(arc
					(start 447.71945 -53.754274)
					(mid 447.98615 -53.487574)
					(end 448.25285 -53.754274)
				)
				(arc
					(start 448.36969 -53.754274)
					(mid 448.257354 -53.48307)
					(end 447.98615 -53.370734)
				)
			)
		)
	)
	(zone
		(layers "F.Cu" "In1.Cu" "In2.Cu" "In3.Cu" "In5.Cu" "In6.Cu" "In7.Cu" "In8.Cu"
			"In9.Cu" "In10.Cu" "In11.Cu" "In12.Cu"
		)
		(hatch none 0.5)
		(connect_pads
			(clearance 0)
		)
		(min_thickness 0.25)
		(keepout
			(tracks not_allowed)
			(vias allowed)
			(pads allowed)
			(copperpour not_allowed)
			(footprints allowed)
		)
		(placement
			(enabled no)
			(sheetname "")
		)
		(fill yes
			(thermal_gap 0.5)
			(thermal_bridge_width 0.5)
			(island_removal_mode 0)
		)
		(polygon
			(pts
				(arc
					(start 456.216004 -123.80468)
					(mid 455.83221 -124.188093)
					(end 456.21575 -124.57176)
				)
				(arc
					(start 457.48575 -124.57176)
					(mid 457.756054 -124.46032)
					(end 457.86929 -124.19076)
				)
				(arc
					(start 457.75245 -124.19076)
					(mid 457.48575 -124.454932)
					(end 457.21905 -124.19076)
				)
				(arc
					(start 456.48245 -124.19076)
					(mid 456.21575 -124.454932)
					(end 455.94905 -124.19076)
				)
				(arc
					(start 455.94905 -124.18822)
					(mid 456.21575 -123.92152)
					(end 456.48245 -124.18822)
				)
				(arc
					(start 457.21905 -124.18822)
					(mid 457.48575 -123.92152)
					(end 457.75245 -124.18822)
				)
				(arc
					(start 457.86929 -124.18822)
					(mid 457.756954 -123.917016)
					(end 457.48575 -123.80468)
				)
			)
		)
	)
	(zone
		(layers "F.Cu" "In1.Cu" "In2.Cu" "In3.Cu" "In5.Cu" "In6.Cu" "In7.Cu" "In8.Cu"
			"In9.Cu" "In10.Cu" "In11.Cu" "In12.Cu"
		)
		(hatch none 0.5)
		(connect_pads
			(clearance 0)
		)
		(min_thickness 0.25)
		(keepout
			(tracks not_allowed)
			(vias allowed)
			(pads allowed)
			(copperpour not_allowed)
			(footprints allowed)
		)
		(placement
			(enabled no)
			(sheetname "")
		)
		(fill yes
			(thermal_gap 0.5)
			(thermal_bridge_width 0.5)
			(island_removal_mode 0)
		)
		(polygon
			(pts
				(arc
					(start 456.317604 -53.523134)
					(mid 455.934064 -53.906674)
					(end 456.317604 -54.290214)
				)
				(arc
					(start 457.58735 -54.290214)
					(mid 457.857818 -54.178864)
					(end 457.971144 -53.909214)
				)
				(arc
					(start 457.854304 -53.909214)
					(mid 457.587604 -54.173386)
					(end 457.320904 -53.909214)
				)
				(arc
					(start 456.584304 -53.909214)
					(mid 456.317604 -54.173386)
					(end 456.050904 -53.909214)
				)
				(arc
					(start 456.050904 -53.906674)
					(mid 456.317604 -53.639974)
					(end 456.584304 -53.906674)
				)
				(arc
					(start 457.320904 -53.906674)
					(mid 457.587604 -53.639974)
					(end 457.854304 -53.906674)
				)
				(arc
					(start 457.971144 -53.906674)
					(mid 457.858808 -53.63547)
					(end 457.587604 -53.523134)
				)
			)
		)
	)
	(zone
		(layers "F.Cu" "In1.Cu" "In2.Cu" "In3.Cu" "In5.Cu" "In6.Cu" "In7.Cu" "In8.Cu"
			"In9.Cu" "In10.Cu" "In11.Cu" "In12.Cu"
		)
		(hatch none 0.5)
		(connect_pads
			(clearance 0)
		)
		(min_thickness 0.25)
		(keepout
			(tracks not_allowed)
			(vias allowed)
			(pads allowed)
			(copperpour not_allowed)
			(footprints allowed)
		)
		(placement
			(enabled no)
			(sheetname "")
		)
		(fill yes
			(thermal_gap 0.5)
			(thermal_bridge_width 0.5)
			(island_removal_mode 0)
		)
		(polygon
			(pts
				(arc
					(start 459.51775 -53.523134)
					(mid 459.13421 -53.906674)
					(end 459.51775 -54.290214)
				)
				(arc
					(start 460.787496 -54.290214)
					(mid 461.057964 -54.178864)
					(end 461.17129 -53.909214)
				)
				(arc
					(start 461.05445 -53.909214)
					(mid 460.78775 -54.173386)
					(end 460.52105 -53.909214)
				)
				(arc
					(start 459.78445 -53.909214)
					(mid 459.51775 -54.173386)
					(end 459.25105 -53.909214)
				)
				(arc
					(start 459.25105 -53.906674)
					(mid 459.51775 -53.639974)
					(end 459.78445 -53.906674)
				)
				(arc
					(start 460.52105 -53.906674)
					(mid 460.78775 -53.639974)
					(end 461.05445 -53.906674)
				)
				(arc
					(start 461.17129 -53.906674)
					(mid 461.058954 -53.63547)
					(end 460.78775 -53.523134)
				)
			)
		)
	)
	(zone
		(layers "F.Cu" "In1.Cu" "In2.Cu" "In3.Cu" "In5.Cu" "In6.Cu" "In7.Cu" "In8.Cu"
			"In9.Cu" "In10.Cu" "In11.Cu" "In12.Cu"
		)
		(hatch none 0.5)
		(connect_pads
			(clearance 0)
		)
		(min_thickness 0.25)
		(keepout
			(tracks not_allowed)
			(vias allowed)
			(pads allowed)
			(copperpour not_allowed)
			(footprints allowed)
		)
		(placement
			(enabled no)
			(sheetname "")
		)
		(fill yes
			(thermal_gap 0.5)
			(thermal_bridge_width 0.5)
			(island_removal_mode 0)
		)
		(polygon
			(pts
				(arc
					(start 462.70799 -53.505354)
					(mid 462.32445 -53.888894)
					(end 462.70799 -54.272434)
				)
				(arc
					(start 463.977736 -54.272434)
					(mid 464.248204 -54.161084)
					(end 464.36153 -53.891434)
				)
				(arc
					(start 464.24469 -53.891434)
					(mid 463.97799 -54.155606)
					(end 463.71129 -53.891434)
				)
				(arc
					(start 462.97469 -53.891434)
					(mid 462.70799 -54.155606)
					(end 462.44129 -53.891434)
				)
				(arc
					(start 462.44129 -53.888894)
					(mid 462.70799 -53.622194)
					(end 462.97469 -53.888894)
				)
				(arc
					(start 463.71129 -53.888894)
					(mid 463.97799 -53.622194)
					(end 464.24469 -53.888894)
				)
				(arc
					(start 464.36153 -53.888894)
					(mid 464.249194 -53.61769)
					(end 463.97799 -53.505354)
				)
			)
		)
	)
	(zone
		(layers "F.Cu" "In1.Cu" "In2.Cu" "In3.Cu" "In5.Cu" "In6.Cu" "In7.Cu" "In8.Cu"
			"In9.Cu" "In10.Cu" "In11.Cu" "In12.Cu"
		)
		(hatch none 0.5)
		(connect_pads
			(clearance 0)
		)
		(min_thickness 0.25)
		(keepout
			(tracks not_allowed)
			(vias allowed)
			(pads allowed)
			(copperpour not_allowed)
			(footprints allowed)
		)
		(placement
			(enabled no)
			(sheetname "")
		)
		(fill yes
			(thermal_gap 0.5)
			(thermal_bridge_width 0.5)
			(island_removal_mode 0)
		)
		(polygon
			(pts
				(arc
					(start 458.971904 -123.75388)
					(mid 458.58811 -124.137293)
					(end 458.97165 -124.52096)
				)
				(arc
					(start 460.24165 -124.52096)
					(mid 460.511954 -124.40952)
					(end 460.62519 -124.13996)
				)
				(arc
					(start 460.50835 -124.13996)
					(mid 460.24165 -124.404132)
					(end 459.97495 -124.13996)
				)
				(arc
					(start 459.23835 -124.13996)
					(mid 458.97165 -124.404132)
					(end 458.70495 -124.13996)
				)
				(arc
					(start 458.70495 -124.13742)
					(mid 458.97165 -123.87072)
					(end 459.23835 -124.13742)
				)
				(arc
					(start 459.97495 -124.13742)
					(mid 460.24165 -123.87072)
					(end 460.50835 -124.13742)
				)
				(arc
					(start 460.62519 -124.13742)
					(mid 460.512854 -123.866216)
					(end 460.24165 -123.75388)
				)
			)
		)
	)
	(zone
		(layers "F.Cu" "In1.Cu" "In2.Cu" "In3.Cu" "In5.Cu" "In6.Cu" "In7.Cu" "In8.Cu"
			"In9.Cu" "In10.Cu" "In11.Cu" "In12.Cu"
		)
		(hatch none 0.5)
		(connect_pads
			(clearance 0)
		)
		(min_thickness 0.25)
		(keepout
			(tracks not_allowed)
			(vias allowed)
			(pads allowed)
			(copperpour not_allowed)
			(footprints allowed)
		)
		(placement
			(enabled no)
			(sheetname "")
		)
		(fill yes
			(thermal_gap 0.5)
			(thermal_bridge_width 0.5)
			(island_removal_mode 0)
		)
		(polygon
			(pts
				(arc
					(start 439.07456 -126.63805)
					(mid 438.690766 -127.021463)
					(end 439.074306 -127.40513)
				)
				(arc
					(start 440.344306 -127.40513)
					(mid 440.61461 -127.29369)
					(end 440.727846 -127.02413)
				)
				(arc
					(start 440.611006 -127.02413)
					(mid 440.344306 -127.288302)
					(end 440.077606 -127.02413)
				)
				(arc
					(start 439.341006 -127.02413)
					(mid 439.074306 -127.288302)
					(end 438.807606 -127.02413)
				)
				(arc
					(start 438.807606 -127.02159)
					(mid 439.074306 -126.75489)
					(end 439.341006 -127.02159)
				)
				(arc
					(start 440.077606 -127.02159)
					(mid 440.344306 -126.75489)
					(end 440.611006 -127.02159)
				)
				(arc
					(start 440.727846 -127.02159)
					(mid 440.61551 -126.750386)
					(end 440.344306 -126.63805)
				)
			)
		)
	)
	(zone
		(layers "F.Cu" "In1.Cu" "In2.Cu" "In3.Cu" "In5.Cu" "In6.Cu" "In7.Cu" "In8.Cu"
			"In9.Cu" "In10.Cu" "In11.Cu" "In12.Cu"
		)
		(hatch none 0.5)
		(connect_pads
			(clearance 0)
		)
		(min_thickness 0.25)
		(keepout
			(tracks not_allowed)
			(vias allowed)
			(pads allowed)
			(copperpour not_allowed)
			(footprints allowed)
		)
		(placement
			(enabled no)
			(sheetname "")
		)
		(fill yes
			(thermal_gap 0.5)
			(thermal_bridge_width 0.5)
			(island_removal_mode 0)
		)
		(polygon
			(pts
				(arc
					(start 440.304936 -53.370734)
					(mid 439.921396 -53.754274)
					(end 440.304936 -54.137814)
				)
				(arc
					(start 441.574682 -54.137814)
					(mid 441.84515 -54.026464)
					(end 441.958476 -53.756814)
				)
				(arc
					(start 441.841636 -53.756814)
					(mid 441.574936 -54.020986)
					(end 441.308236 -53.756814)
				)
				(arc
					(start 440.571636 -53.756814)
					(mid 440.304936 -54.020986)
					(end 440.038236 -53.756814)
				)
				(arc
					(start 440.038236 -53.754274)
					(mid 440.304936 -53.487574)
					(end 440.571636 -53.754274)
				)
				(arc
					(start 441.308236 -53.754274)
					(mid 441.574936 -53.487574)
					(end 441.841636 -53.754274)
				)
				(arc
					(start 441.958476 -53.754274)
					(mid 441.84614 -53.48307)
					(end 441.574936 -53.370734)
				)
			)
		)
	)
	(zone
		(layers "F.Cu" "In1.Cu" "In2.Cu" "In3.Cu" "In5.Cu" "In6.Cu" "In7.Cu" "In8.Cu"
			"In9.Cu" "In10.Cu" "In11.Cu" "In12.Cu"
		)
		(hatch none 0.5)
		(connect_pads
			(clearance 0)
		)
		(min_thickness 0.25)
		(keepout
			(tracks not_allowed)
			(vias allowed)
			(pads allowed)
			(copperpour not_allowed)
			(footprints allowed)
		)
		(placement
			(enabled no)
			(sheetname "")
		)
		(fill yes
			(thermal_gap 0.5)
			(thermal_bridge_width 0.5)
			(island_removal_mode 0)
		)
		(polygon
			(pts
				(arc
					(start 462.058004 -123.80468)
					(mid 461.67421 -124.188093)
					(end 462.05775 -124.57176)
				)
				(arc
					(start 463.32775 -124.57176)
					(mid 463.598054 -124.46032)
					(end 463.71129 -124.19076)
				)
				(arc
					(start 463.59445 -124.19076)
					(mid 463.32775 -124.454932)
					(end 463.06105 -124.19076)
				)
				(arc
					(start 462.32445 -124.19076)
					(mid 462.05775 -124.454932)
					(end 461.79105 -124.19076)
				)
				(arc
					(start 461.79105 -124.18822)
					(mid 462.05775 -123.92152)
					(end 462.32445 -124.18822)
				)
				(arc
					(start 463.06105 -124.18822)
					(mid 463.32775 -123.92152)
					(end 463.59445 -124.18822)
				)
				(arc
					(start 463.71129 -124.18822)
					(mid 463.598954 -123.917016)
					(end 463.32775 -123.80468)
				)
			)
		)
	)
	(zone
		(layers "F.Cu" "In1.Cu" "In2.Cu" "In3.Cu" "In5.Cu" "In6.Cu" "In7.Cu" "In8.Cu"
			"In9.Cu" "In10.Cu" "In11.Cu" "In12.Cu"
		)
		(hatch none 0.5)
		(connect_pads
			(clearance 0)
		)
		(min_thickness 0.25)
		(keepout
			(tracks not_allowed)
			(vias allowed)
			(pads allowed)
			(copperpour not_allowed)
			(footprints allowed)
		)
		(placement
			(enabled no)
			(sheetname "")
		)
		(fill yes
			(thermal_gap 0.5)
			(thermal_bridge_width 0.5)
			(island_removal_mode 0)
		)
		(polygon
			(pts
				(arc
					(start 15.87881 -107.77347)
					(mid 15.49527 -107.38993)
					(end 15.11173 -107.77347)
				)
				(arc
					(start 15.11173 -109.043216)
					(mid 15.493873 -109.427008)
					(end 15.87881 -109.04601)
				)
				(arc
					(start 15.76197 -109.04601)
					(mid 15.49527 -109.310182)
					(end 15.22857 -109.04601)
				)
				(arc
					(start 15.22857 -109.04347)
					(mid 15.49527 -108.77677)
					(end 15.76197 -109.04347)
				)
				(xy 15.87881 -109.04347) (xy 15.87881 -107.77601)
				(arc
					(start 15.76197 -107.77601)
					(mid 15.49527 -108.040182)
					(end 15.22857 -107.77601)
				)
				(arc
					(start 15.22857 -107.77347)
					(mid 15.49527 -107.50677)
					(end 15.76197 -107.77347)
				)
			)
		)
	)
	(zone
		(layers "F.Cu" "In1.Cu" "In3.Cu" "In4.Cu" "In5.Cu" "In6.Cu" "In7.Cu" "In8.Cu"
			"In9.Cu" "In10.Cu" "In11.Cu" "In12.Cu"
		)
		(hatch none 0.5)
		(connect_pads
			(clearance 0)
		)
		(min_thickness 0.25)
		(keepout
			(tracks not_allowed)
			(vias allowed)
			(pads allowed)
			(copperpour not_allowed)
			(footprints allowed)
		)
		(placement
			(enabled no)
			(sheetname "")
		)
		(fill yes
			(thermal_gap 0.5)
			(thermal_bridge_width 0.5)
			(island_removal_mode 0)
		)
		(polygon
			(pts
				(arc
					(start 408.306016 -146.939)
					(mid 407.922476 -146.55546)
					(end 407.538936 -146.939)
				)
				(arc
					(start 407.538936 -147.954746)
					(mid 407.921079 -148.338538)
					(end 408.306016 -147.95754)
				)
				(arc
					(start 408.189176 -147.95754)
					(mid 407.922476 -148.221712)
					(end 407.655776 -147.95754)
				)
				(arc
					(start 407.655776 -147.955)
					(mid 407.922476 -147.6883)
					(end 408.189176 -147.955)
				)
				(xy 408.306016 -147.955) (xy 408.306016 -146.94154)
				(arc
					(start 408.189176 -146.94154)
					(mid 407.922476 -147.205712)
					(end 407.655776 -146.94154)
				)
				(arc
					(start 407.655776 -146.939)
					(mid 407.922476 -146.6723)
					(end 408.189176 -146.939)
				)
			)
		)
	)
	(zone
		(layers "F.Cu" "In1.Cu" "In3.Cu" "In4.Cu" "In5.Cu" "In6.Cu" "In7.Cu" "In8.Cu"
			"In9.Cu" "In10.Cu" "In11.Cu" "In12.Cu"
		)
		(hatch none 0.5)
		(connect_pads
			(clearance 0)
		)
		(min_thickness 0.25)
		(keepout
			(tracks not_allowed)
			(vias allowed)
			(pads allowed)
			(copperpour not_allowed)
			(footprints allowed)
		)
		(placement
			(enabled no)
			(sheetname "")
		)
		(fill yes
			(thermal_gap 0.5)
			(thermal_bridge_width 0.5)
			(island_removal_mode 0)
		)
		(polygon
			(pts
				(arc
					(start 341.291672 -67.71259)
					(mid 340.908132 -68.09613)
					(end 341.291672 -68.47967)
				)
				(arc
					(start 342.256618 -68.47967)
					(mid 342.527086 -68.36832)
					(end 342.640412 -68.09867)
				)
				(arc
					(start 342.523572 -68.09867)
					(mid 342.256872 -68.362842)
					(end 341.990172 -68.09867)
				)
				(arc
					(start 341.558372 -68.09867)
					(mid 341.291672 -68.362842)
					(end 341.024972 -68.09867)
				)
				(arc
					(start 341.024972 -68.09613)
					(mid 341.291672 -67.82943)
					(end 341.558372 -68.09613)
				)
				(arc
					(start 341.990172 -68.09613)
					(mid 342.256872 -67.82943)
					(end 342.523572 -68.09613)
				)
				(arc
					(start 342.640412 -68.09613)
					(mid 342.528076 -67.824926)
					(end 342.256872 -67.71259)
				)
			)
		)
	)
	(zone
		(layers "F.Cu" "In1.Cu" "In3.Cu" "In4.Cu" "In5.Cu" "In6.Cu" "In7.Cu" "In8.Cu"
			"In9.Cu" "In10.Cu" "In11.Cu" "In12.Cu"
		)
		(hatch none 0.5)
		(connect_pads
			(clearance 0)
		)
		(min_thickness 0.25)
		(keepout
			(tracks not_allowed)
			(vias allowed)
			(pads allowed)
			(copperpour not_allowed)
			(footprints allowed)
		)
		(placement
			(enabled no)
			(sheetname "")
		)
		(fill yes
			(thermal_gap 0.5)
			(thermal_bridge_width 0.5)
			(island_removal_mode 0)
		)
		(polygon
			(pts
				(arc
					(start 413.157416 -141.0208)
					(mid 412.773876 -140.63726)
					(end 412.390336 -141.0208)
				)
				(arc
					(start 412.390336 -142.0368)
					(mid 412.772606 -142.420338)
					(end 413.157416 -142.03934)
				)
				(arc
					(start 413.040576 -142.03934)
					(mid 412.773876 -142.303512)
					(end 412.507176 -142.03934)
				)
				(arc
					(start 412.507176 -142.0368)
					(mid 412.773876 -141.7701)
					(end 413.040576 -142.0368)
				)
				(xy 413.157416 -142.0368) (xy 413.157416 -141.02334)
				(arc
					(start 413.040576 -141.02334)
					(mid 412.773876 -141.287512)
					(end 412.507176 -141.02334)
				)
				(arc
					(start 412.507176 -141.0208)
					(mid 412.773876 -140.7541)
					(end 413.040576 -141.0208)
				)
			)
		)
	)
	(zone
		(layers "F.Cu" "In1.Cu" "In3.Cu" "In4.Cu" "In5.Cu" "In6.Cu" "In7.Cu" "In8.Cu"
			"In9.Cu" "In10.Cu" "In11.Cu" "In12.Cu"
		)
		(hatch none 0.5)
		(connect_pads
			(clearance 0)
		)
		(min_thickness 0.25)
		(keepout
			(tracks not_allowed)
			(vias allowed)
			(pads allowed)
			(copperpour not_allowed)
			(footprints allowed)
		)
		(placement
			(enabled no)
			(sheetname "")
		)
		(fill yes
			(thermal_gap 0.5)
			(thermal_bridge_width 0.5)
			(island_removal_mode 0)
		)
		(polygon
			(pts
				(arc
					(start 421.32377 -139.59586)
					(mid 420.965376 -139.953873)
					(end 421.323516 -140.31214)
				)
				(arc
					(start 422.593516 -140.31214)
					(mid 422.84586 -140.20814)
					(end 422.951656 -139.95654)
				)
				(arc
					(start 422.860216 -139.95654)
					(mid 422.593516 -140.220712)
					(end 422.326816 -139.95654)
				)
				(arc
					(start 421.590216 -139.95654)
					(mid 421.323516 -140.220712)
					(end 421.056816 -139.95654)
				)
				(arc
					(start 421.056816 -139.954)
					(mid 421.323516 -139.6873)
					(end 421.590216 -139.954)
				)
				(arc
					(start 422.326816 -139.954)
					(mid 422.593516 -139.6873)
					(end 422.860216 -139.954)
				)
				(arc
					(start 422.951656 -139.954)
					(mid 422.846759 -139.700757)
					(end 422.593516 -139.59586)
				)
			)
		)
	)
	(zone
		(layers "F.Cu" "In1.Cu" "In3.Cu" "In4.Cu" "In5.Cu" "In6.Cu" "In7.Cu" "In8.Cu"
			"In9.Cu" "In10.Cu" "In11.Cu" "In12.Cu"
		)
		(hatch none 0.5)
		(connect_pads
			(clearance 0)
		)
		(min_thickness 0.25)
		(keepout
			(tracks not_allowed)
			(vias allowed)
			(pads allowed)
			(copperpour not_allowed)
			(footprints allowed)
		)
		(placement
			(enabled no)
			(sheetname "")
		)
		(fill yes
			(thermal_gap 0.5)
			(thermal_bridge_width 0.5)
			(island_removal_mode 0)
		)
		(polygon
			(pts
				(arc
					(start 337.863434 -69.72935)
					(mid 337.479894 -70.11289)
					(end 337.863434 -70.49643)
				)
				(arc
					(start 338.754466 -70.49643)
					(mid 339.024934 -70.38508)
					(end 339.13826 -70.11543)
				)
				(arc
					(start 339.02142 -70.11543)
					(mid 338.75472 -70.379602)
					(end 338.48802 -70.11543)
				)
				(arc
					(start 338.130134 -70.11543)
					(mid 337.863434 -70.379602)
					(end 337.596734 -70.11543)
				)
				(arc
					(start 337.596734 -70.11289)
					(mid 337.863434 -69.84619)
					(end 338.130134 -70.11289)
				)
				(arc
					(start 338.48802 -70.11289)
					(mid 338.75472 -69.84619)
					(end 339.02142 -70.11289)
				)
				(arc
					(start 339.13826 -70.11289)
					(mid 339.025924 -69.841686)
					(end 338.75472 -69.72935)
				)
			)
		)
	)
	(zone
		(layers "F.Cu" "In1.Cu" "In3.Cu" "In4.Cu" "In5.Cu" "In6.Cu" "In7.Cu" "In8.Cu"
			"In9.Cu" "In10.Cu" "In11.Cu" "In12.Cu"
		)
		(hatch none 0.5)
		(connect_pads
			(clearance 0)
		)
		(min_thickness 0.25)
		(keepout
			(tracks not_allowed)
			(vias allowed)
			(pads allowed)
			(copperpour not_allowed)
			(footprints allowed)
		)
		(placement
			(enabled no)
			(sheetname "")
		)
		(fill yes
			(thermal_gap 0.5)
			(thermal_bridge_width 0.5)
			(island_removal_mode 0)
		)
		(polygon
			(pts
				(arc
					(start 334.962754 -71.42988)
					(mid 334.579214 -71.81342)
					(end 334.962754 -72.19696)
				)
				(arc
					(start 335.853786 -72.19696)
					(mid 336.124254 -72.08561)
					(end 336.23758 -71.81596)
				)
				(arc
					(start 336.12074 -71.81596)
					(mid 335.85404 -72.080132)
					(end 335.58734 -71.81596)
				)
				(arc
					(start 335.229454 -71.81596)
					(mid 334.962754 -72.080132)
					(end 334.696054 -71.81596)
				)
				(arc
					(start 334.696054 -71.81342)
					(mid 334.962754 -71.54672)
					(end 335.229454 -71.81342)
				)
				(arc
					(start 335.58734 -71.81342)
					(mid 335.85404 -71.54672)
					(end 336.12074 -71.81342)
				)
				(arc
					(start 336.23758 -71.81342)
					(mid 336.125244 -71.542216)
					(end 335.85404 -71.42988)
				)
			)
		)
	)
	(zone
		(layers "F.Cu" "In1.Cu" "In3.Cu" "In4.Cu" "In5.Cu" "In6.Cu" "In7.Cu" "In8.Cu"
			"In9.Cu" "In10.Cu" "In11.Cu" "In12.Cu"
		)
		(hatch none 0.5)
		(connect_pads
			(clearance 0)
		)
		(min_thickness 0.25)
		(keepout
			(tracks not_allowed)
			(vias allowed)
			(pads allowed)
			(copperpour not_allowed)
			(footprints allowed)
		)
		(placement
			(enabled no)
			(sheetname "")
		)
		(fill yes
			(thermal_gap 0.5)
			(thermal_bridge_width 0.5)
			(island_removal_mode 0)
		)
		(polygon
			(pts
				(arc
					(start 339.457792 -68.64223)
					(mid 339.074252 -69.02577)
					(end 339.457792 -69.40931)
				)
				(arc
					(start 340.422738 -69.40931)
					(mid 340.693206 -69.29796)
					(end 340.806532 -69.02831)
				)
				(arc
					(start 340.689692 -69.02831)
					(mid 340.422992 -69.292482)
					(end 340.156292 -69.02831)
				)
				(arc
					(start 339.724492 -69.02831)
					(mid 339.457792 -69.292482)
					(end 339.191092 -69.02831)
				)
				(arc
					(start 339.191092 -69.02577)
					(mid 339.457792 -68.75907)
					(end 339.724492 -69.02577)
				)
				(arc
					(start 340.156292 -69.02577)
					(mid 340.422992 -68.75907)
					(end 340.689692 -69.02577)
				)
				(arc
					(start 340.806532 -69.02577)
					(mid 340.694196 -68.754566)
					(end 340.422992 -68.64223)
				)
			)
		)
	)
	(zone
		(layers "F.Cu" "In1.Cu" "In3.Cu" "In4.Cu" "In5.Cu" "In6.Cu" "In7.Cu" "In8.Cu"
			"In9.Cu" "In10.Cu" "In11.Cu" "In12.Cu"
		)
		(hatch none 0.5)
		(connect_pads
			(clearance 0)
		)
		(min_thickness 0.25)
		(keepout
			(tracks not_allowed)
			(vias allowed)
			(pads allowed)
			(copperpour not_allowed)
			(footprints allowed)
		)
		(placement
			(enabled no)
			(sheetname "")
		)
		(fill yes
			(thermal_gap 0.5)
			(thermal_bridge_width 0.5)
			(island_removal_mode 0)
		)
		(polygon
			(pts
				(arc
					(start 336.228436 -70.650862)
					(mid 335.844896 -71.034402)
					(end 336.228436 -71.417942)
				)
				(arc
					(start 337.119468 -71.417942)
					(mid 337.389936 -71.306592)
					(end 337.503262 -71.036942)
				)
				(arc
					(start 337.386422 -71.036942)
					(mid 337.119722 -71.301114)
					(end 336.853022 -71.036942)
				)
				(arc
					(start 336.495136 -71.036942)
					(mid 336.228436 -71.301114)
					(end 335.961736 -71.036942)
				)
				(arc
					(start 335.961736 -71.034402)
					(mid 336.228436 -70.767702)
					(end 336.495136 -71.034402)
				)
				(arc
					(start 336.853022 -71.034402)
					(mid 337.119722 -70.767702)
					(end 337.386422 -71.034402)
				)
				(arc
					(start 337.503262 -71.034402)
					(mid 337.390926 -70.763198)
					(end 337.119722 -70.650862)
				)
			)
		)
	)
	(zone
		(layers "F.Cu" "In1.Cu" "In3.Cu" "In4.Cu" "In5.Cu" "In6.Cu" "In7.Cu" "In8.Cu"
			"In9.Cu" "In10.Cu" "In11.Cu" "In12.Cu"
		)
		(hatch none 0.5)
		(connect_pads
			(clearance 0)
		)
		(min_thickness 0.25)
		(keepout
			(tracks not_allowed)
			(vias allowed)
			(pads allowed)
			(copperpour not_allowed)
			(footprints allowed)
		)
		(placement
			(enabled no)
			(sheetname "")
		)
		(fill yes
			(thermal_gap 0.5)
			(thermal_bridge_width 0.5)
			(island_removal_mode 0)
		)
		(polygon
			(pts
				(arc
					(start 408.696922 -141.641576)
					(mid 408.313382 -141.258036)
					(end 407.929842 -141.641576)
				)
				(arc
					(start 407.929842 -142.657322)
					(mid 408.311985 -143.041114)
					(end 408.696922 -142.660116)
				)
				(arc
					(start 408.580082 -142.660116)
					(mid 408.313382 -142.924288)
					(end 408.046682 -142.660116)
				)
				(arc
					(start 408.046682 -142.657576)
					(mid 408.313382 -142.390876)
					(end 408.580082 -142.657576)
				)
				(xy 408.696922 -142.657576) (xy 408.696922 -141.644116)
				(arc
					(start 408.580082 -141.644116)
					(mid 408.313382 -141.908288)
					(end 408.046682 -141.644116)
				)
				(arc
					(start 408.046682 -141.641576)
					(mid 408.313382 -141.374876)
					(end 408.580082 -141.641576)
				)
			)
		)
	)
	(zone
		(layers "F.Cu" "In1.Cu" "In3.Cu" "In4.Cu" "In5.Cu" "In6.Cu" "In7.Cu" "In8.Cu"
			"In9.Cu" "In10.Cu" "In11.Cu" "In12.Cu"
		)
		(hatch none 0.5)
		(connect_pads
			(clearance 0)
		)
		(min_thickness 0.25)
		(keepout
			(tracks not_allowed)
			(vias allowed)
			(pads allowed)
			(copperpour not_allowed)
			(footprints allowed)
		)
		(placement
			(enabled no)
			(sheetname "")
		)
		(fill yes
			(thermal_gap 0.5)
			(thermal_bridge_width 0.5)
			(island_removal_mode 0)
		)
		(polygon
			(pts
				(arc
					(start 426.720254 -139.454636)
					(mid 426.33646 -139.838049)
					(end 426.72 -140.221716)
				)
				(arc
					(start 427.99 -140.221716)
					(mid 428.260304 -140.110276)
					(end 428.37354 -139.840716)
				)
				(arc
					(start 428.2567 -139.840716)
					(mid 427.99 -140.104888)
					(end 427.7233 -139.840716)
				)
				(arc
					(start 426.9867 -139.840716)
					(mid 426.72 -140.104888)
					(end 426.4533 -139.840716)
				)
				(arc
					(start 426.4533 -139.838176)
					(mid 426.72 -139.571476)
					(end 426.9867 -139.838176)
				)
				(arc
					(start 427.7233 -139.838176)
					(mid 427.99 -139.571476)
					(end 428.2567 -139.838176)
				)
				(arc
					(start 428.37354 -139.838176)
					(mid 428.261204 -139.566972)
					(end 427.99 -139.454636)
				)
			)
		)
	)
	(zone
		(layers "F.Cu" "In1.Cu" "In3.Cu" "In4.Cu" "In5.Cu" "In6.Cu" "In7.Cu" "In8.Cu"
			"In9.Cu" "In10.Cu" "In11.Cu" "In12.Cu"
		)
		(hatch none 0.5)
		(connect_pads
			(clearance 0)
		)
		(min_thickness 0.25)
		(keepout
			(tracks not_allowed)
			(vias allowed)
			(pads allowed)
			(copperpour not_allowed)
			(footprints allowed)
		)
		(placement
			(enabled no)
			(sheetname "")
		)
		(fill yes
			(thermal_gap 0.5)
			(thermal_bridge_width 0.5)
			(island_removal_mode 0)
		)
		(polygon
			(pts
				(arc
					(start 407.24709 -144.35455)
					(mid 406.86355 -143.97101)
					(end 406.48001 -144.35455)
				)
				(arc
					(start 406.48001 -145.370296)
					(mid 406.862153 -145.754088)
					(end 407.24709 -145.37309)
				)
				(arc
					(start 407.13025 -145.37309)
					(mid 406.86355 -145.637262)
					(end 406.59685 -145.37309)
				)
				(arc
					(start 406.59685 -145.37055)
					(mid 406.86355 -145.10385)
					(end 407.13025 -145.37055)
				)
				(xy 407.24709 -145.37055) (xy 407.24709 -144.35709)
				(arc
					(start 407.13025 -144.35709)
					(mid 406.86355 -144.621262)
					(end 406.59685 -144.35709)
				)
				(arc
					(start 406.59685 -144.35455)
					(mid 406.86355 -144.08785)
					(end 407.13025 -144.35455)
				)
			)
		)
	)
	(zone
		(layers "F.Cu" "In1.Cu" "In3.Cu" "In4.Cu" "In5.Cu" "In6.Cu" "In7.Cu" "In8.Cu"
			"In9.Cu" "In10.Cu" "In11.Cu" "In12.Cu"
		)
		(hatch none 0.5)
		(connect_pads
			(clearance 0)
		)
		(min_thickness 0.25)
		(keepout
			(tracks not_allowed)
			(vias allowed)
			(pads allowed)
			(copperpour not_allowed)
			(footprints allowed)
		)
		(placement
			(enabled no)
			(sheetname "")
		)
		(fill yes
			(thermal_gap 0.5)
			(thermal_bridge_width 0.5)
			(island_removal_mode 0)
		)
		(polygon
			(pts
				(arc
					(start 349.890588 -67.07886)
					(mid 349.507048 -67.4624)
					(end 349.890588 -67.84594)
				)
				(arc
					(start 350.78162 -67.84594)
					(mid 351.052088 -67.73459)
					(end 351.165414 -67.46494)
				)
				(arc
					(start 351.048574 -67.46494)
					(mid 350.781874 -67.729112)
					(end 350.515174 -67.46494)
				)
				(arc
					(start 350.157288 -67.46494)
					(mid 349.890588 -67.729112)
					(end 349.623888 -67.46494)
				)
				(arc
					(start 349.623888 -67.4624)
					(mid 349.890588 -67.1957)
					(end 350.157288 -67.4624)
				)
				(arc
					(start 350.515174 -67.4624)
					(mid 350.781874 -67.1957)
					(end 351.048574 -67.4624)
				)
				(arc
					(start 351.165414 -67.4624)
					(mid 351.053078 -67.191196)
					(end 350.781874 -67.07886)
				)
			)
		)
	)
	(zone
		(layers "F.Cu" "In1.Cu" "In3.Cu" "In4.Cu" "In5.Cu" "In6.Cu" "In7.Cu" "In8.Cu"
			"In9.Cu" "In10.Cu" "In11.Cu" "In12.Cu"
		)
		(hatch none 0.5)
		(connect_pads
			(clearance 0)
		)
		(min_thickness 0.25)
		(keepout
			(tracks not_allowed)
			(vias allowed)
			(pads allowed)
			(copperpour not_allowed)
			(footprints allowed)
		)
		(placement
			(enabled no)
			(sheetname "")
		)
		(fill yes
			(thermal_gap 0.5)
			(thermal_bridge_width 0.5)
			(island_removal_mode 0)
		)
		(polygon
			(pts
				(arc
					(start 346.152216 -67.05981)
					(mid 345.768676 -67.443223)
					(end 346.151962 -67.82689)
				)
				(arc
					(start 347.043248 -67.82689)
					(mid 347.313552 -67.71545)
					(end 347.426788 -67.44589)
				)
				(arc
					(start 347.309948 -67.44589)
					(mid 347.043248 -67.710062)
					(end 346.776548 -67.44589)
				)
				(arc
					(start 346.418662 -67.44589)
					(mid 346.151962 -67.710062)
					(end 345.885262 -67.44589)
				)
				(arc
					(start 345.885262 -67.44335)
					(mid 346.151962 -67.17665)
					(end 346.418662 -67.44335)
				)
				(arc
					(start 346.776548 -67.44335)
					(mid 347.043248 -67.17665)
					(end 347.309948 -67.44335)
				)
				(arc
					(start 347.426788 -67.44335)
					(mid 347.314452 -67.172146)
					(end 347.043248 -67.05981)
				)
			)
		)
	)
	(zone
		(layers "F.Cu" "In1.Cu" "In3.Cu" "In4.Cu" "In5.Cu" "In6.Cu" "In7.Cu" "In8.Cu"
			"In9.Cu" "In10.Cu" "In11.Cu" "In12.Cu"
		)
		(hatch none 0.5)
		(connect_pads
			(clearance 0)
		)
		(min_thickness 0.25)
		(keepout
			(tracks not_allowed)
			(vias allowed)
			(pads allowed)
			(copperpour not_allowed)
			(footprints allowed)
		)
		(placement
			(enabled no)
			(sheetname "")
		)
		(fill yes
			(thermal_gap 0.5)
			(thermal_bridge_width 0.5)
			(island_removal_mode 0)
		)
		(polygon
			(pts
				(arc
					(start 424.078654 -139.454636)
					(mid 423.69486 -139.838049)
					(end 424.0784 -140.221716)
				)
				(arc
					(start 425.3484 -140.221716)
					(mid 425.618704 -140.110276)
					(end 425.73194 -139.840716)
				)
				(arc
					(start 425.6151 -139.840716)
					(mid 425.3484 -140.104888)
					(end 425.0817 -139.840716)
				)
				(arc
					(start 424.3451 -139.840716)
					(mid 424.0784 -140.104888)
					(end 423.8117 -139.840716)
				)
				(arc
					(start 423.8117 -139.838176)
					(mid 424.0784 -139.571476)
					(end 424.3451 -139.838176)
				)
				(arc
					(start 425.0817 -139.838176)
					(mid 425.3484 -139.571476)
					(end 425.6151 -139.838176)
				)
				(arc
					(start 425.73194 -139.838176)
					(mid 425.619604 -139.566972)
					(end 425.3484 -139.454636)
				)
			)
		)
	)
	(zone
		(layers "F.Cu" "In1.Cu" "In3.Cu" "In4.Cu" "In5.Cu" "In6.Cu" "In7.Cu" "In8.Cu"
			"In9.Cu" "In10.Cu" "In11.Cu" "In12.Cu"
		)
		(hatch none 0.5)
		(connect_pads
			(clearance 0)
		)
		(min_thickness 0.25)
		(keepout
			(tracks not_allowed)
			(vias allowed)
			(pads allowed)
			(copperpour not_allowed)
			(footprints allowed)
		)
		(placement
			(enabled no)
			(sheetname "")
		)
		(fill yes
			(thermal_gap 0.5)
			(thermal_bridge_width 0.5)
			(island_removal_mode 0)
		)
		(polygon
			(pts
				(arc
					(start 343.526872 -67.10299)
					(mid 343.143332 -67.48653)
					(end 343.526872 -67.87007)
				)
				(arc
					(start 344.491818 -67.87007)
					(mid 344.762286 -67.75872)
					(end 344.875612 -67.48907)
				)
				(arc
					(start 344.758772 -67.48907)
					(mid 344.492072 -67.753242)
					(end 344.225372 -67.48907)
				)
				(arc
					(start 343.793572 -67.48907)
					(mid 343.526872 -67.753242)
					(end 343.260172 -67.48907)
				)
				(arc
					(start 343.260172 -67.48653)
					(mid 343.526872 -67.21983)
					(end 343.793572 -67.48653)
				)
				(arc
					(start 344.225372 -67.48653)
					(mid 344.492072 -67.21983)
					(end 344.758772 -67.48653)
				)
				(arc
					(start 344.875612 -67.48653)
					(mid 344.763276 -67.215326)
					(end 344.492072 -67.10299)
				)
			)
		)
	)
	(zone
		(layers "F.Cu" "In1.Cu" "In3.Cu" "In4.Cu" "In5.Cu" "In6.Cu" "In7.Cu" "In8.Cu"
			"In9.Cu" "In10.Cu" "In11.Cu" "In12.Cu"
		)
		(hatch none 0.5)
		(connect_pads
			(clearance 0)
		)
		(min_thickness 0.25)
		(keepout
			(tracks not_allowed)
			(vias allowed)
			(pads allowed)
			(copperpour not_allowed)
			(footprints allowed)
		)
		(placement
			(enabled no)
			(sheetname "")
		)
		(fill yes
			(thermal_gap 0.5)
			(thermal_bridge_width 0.5)
			(island_removal_mode 0)
		)
		(polygon
			(pts
				(arc
					(start 420.161466 -146.9009)
					(mid 419.777926 -146.51736)
					(end 419.394386 -146.9009)
				)
				(arc
					(start 419.394386 -147.916646)
					(mid 419.776529 -148.300438)
					(end 420.161466 -147.91944)
				)
				(arc
					(start 420.044626 -147.91944)
					(mid 419.777926 -148.183612)
					(end 419.511226 -147.91944)
				)
				(arc
					(start 419.511226 -147.9169)
					(mid 419.777926 -147.6502)
					(end 420.044626 -147.9169)
				)
				(xy 420.161466 -147.9169) (xy 420.161466 -146.90344)
				(arc
					(start 420.044626 -146.90344)
					(mid 419.777926 -147.167612)
					(end 419.511226 -146.90344)
				)
				(arc
					(start 419.511226 -146.9009)
					(mid 419.777926 -146.6342)
					(end 420.044626 -146.9009)
				)
			)
		)
	)
	(zone
		(layers "F.Cu" "In2.Cu" "In4.Cu" "In9.Cu")
		(hatch none 0.5)
		(connect_pads
			(clearance 0)
		)
		(min_thickness 0.25)
		(keepout
			(tracks not_allowed)
			(vias allowed)
			(pads allowed)
			(copperpour not_allowed)
			(footprints allowed)
		)
		(placement
			(enabled no)
			(sheetname "")
		)
		(fill yes
			(thermal_gap 0.5)
			(thermal_bridge_width 0.5)
			(island_removal_mode 0)
		)
		(polygon
			(pts
				(arc
					(start 396.01394 -33.988502)
					(mid 395.7574 -34.1823)
					(end 395.50086 -33.988502)
				)
				(arc
					(start 395.50086 -34.985452)
					(mid 395.7574 -34.791654)
					(end 396.01394 -34.985452)
				)
			)
		)
	)
	(zone
		(layer "B.Cu")
		(hatch none 0.5)
		(connect_pads
			(clearance 0)
		)
		(min_thickness 0.25)
		(keepout
			(tracks allowed)
			(vias allowed)
			(pads allowed)
			(copperpour allowed)
			(footprints not_allowed)
		)
		(placement
			(enabled no)
			(sheetname "")
		)
		(fill
			(thermal_gap 0.5)
			(thermal_bridge_width 0.5)
			(island_removal_mode 0)
		)
		(polygon
			(pts
				(arc
					(start 317.959994 -60.41009)
					(mid 317.667101 -59.702985)
					(end 316.959996 -59.410092)
				)
				(arc
					(start 311.339992 -59.410092)
					(mid 310.632887 -59.702985)
					(end 310.339994 -60.41009)
				)
				(arc
					(start 310.339994 -67.55003)
					(mid 310.632887 -68.257135)
					(end 311.339992 -68.550028)
				)
				(arc
					(start 316.959996 -68.550028)
					(mid 317.667101 -68.257135)
					(end 317.959994 -67.55003)
				)
			)
		)
	)
	(zone
		(net "P3V3_STBY")
		(layer "B.Cu")
		(hatch none 0.5)
		(connect_pads
			(clearance 0.5)
		)
		(min_thickness 0.25)
		(fill yes
			(thermal_gap 0.5)
			(thermal_bridge_width 0.5)
			(island_removal_mode 0)
		)
		(polygon
			(pts
				(xy 438.8485 -48.3616) (xy 439.4835 -48.3616) (xy 439.801 -48.6791) (xy 439.801 -49.8348) (xy 439.6232 -50.0126)
				(xy 439.3946 -50.0126) (xy 438.8485 -49.4665)
			)
		)
	)
	(zone
		(layer "B.Cu")
		(hatch none 0.5)
		(connect_pads
			(clearance 0)
		)
		(min_thickness 0.25)
		(keepout
			(tracks allowed)
			(vias allowed)
			(pads allowed)
			(copperpour allowed)
			(footprints not_allowed)
		)
		(placement
			(enabled no)
			(sheetname "")
		)
		(fill
			(thermal_gap 0.5)
			(thermal_bridge_width 0.5)
			(island_removal_mode 0)
		)
		(polygon
			(pts
				(arc
					(start 497.320062 -28.919932)
					(mid 498.920262 -30.520132)
					(end 497.320062 -32.120078)
				)
				(arc
					(start 495.720116 -32.120078)
					(mid 494.12017 -30.520132)
					(end 495.720116 -28.919932)
				)
			)
		)
	)
	(zone
		(net "GND")
		(layer "B.Cu")
		(hatch none 0.5)
		(connect_pads
			(clearance 0.5)
		)
		(min_thickness 0.25)
		(fill yes
			(thermal_gap 0.5)
			(thermal_bridge_width 0.5)
			(island_removal_mode 0)
		)
		(polygon
			(pts
				(xy 346.557092 -10.456418) (xy 346.557092 -8.46709) (xy 346.302838 -8.212836) (xy 346.302838 -3.296158)
				(xy 346.303092 -3.295904) (xy 346.303092 -3.225292) (xy 346.373704 -3.225292) (xy 346.624148 -2.974848)
				(xy 346.624148 -0.494792) (xy 346.277692 -0.148336) (xy 346.277692 0.407924) (xy 346.198952 0.407924)
				(xy 346.198952 1.678432) (xy 346.277692 1.678432) (xy 346.277692 2.058924) (xy 346.198952 2.058924)
				(xy 346.198952 3.329432) (xy 346.277692 3.329432) (xy 346.277692 3.735324) (xy 346.198952 3.735324)
				(xy 346.198952 5.0292) (xy 346.185998 5.0292) (xy 345.933776 5.281422) (xy 340.383622 5.281422)
				(xy 340.1314 5.0292) (xy 339.598 4.4958) (xy 339.598 -4.5212) (xy 339.598 -9.472422) (xy 340.759034 -10.633456)
				(xy 346.380054 -10.633456)
			)
		)
	)
	(zone
		(layer "B.Cu")
		(hatch none 0.5)
		(connect_pads
			(clearance 0)
		)
		(min_thickness 0.25)
		(keepout
			(tracks allowed)
			(vias allowed)
			(pads allowed)
			(copperpour allowed)
			(footprints not_allowed)
		)
		(placement
			(enabled no)
			(sheetname "")
		)
		(fill
			(thermal_gap 0.5)
			(thermal_bridge_width 0.5)
			(island_removal_mode 0)
		)
		(polygon
			(pts
				(xy 418.980112 -124.359924) (xy 456.87996 -124.359924) (xy 456.87996 -150.18004) (xy 418.980112 -150.18004)
			)
		)
	)
	(zone
		(net "P1V15_AUX_BMC")
		(layer "B.Cu")
		(hatch none 0.5)
		(connect_pads
			(clearance 0.5)
		)
		(min_thickness 0.25)
		(fill yes
			(thermal_gap 0.5)
			(thermal_bridge_width 0.5)
			(island_removal_mode 0)
		)
		(polygon
			(pts
				(xy 416.896042 -31.414212) (xy 416.777678 -31.532576) (xy 416.777678 -31.860236) (xy 416.334956 -32.302958)
				(xy 415.83356 -32.302958) (xy 415.80308 -32.333438) (xy 414.886902 -32.333438) (xy 414.811464 -32.258)
				(xy 414.811464 -32.187134) (xy 414.724342 -32.100012) (xy 414.426146 -32.100012) (xy 414.274254 -31.94812)
				(xy 413.430212 -31.94812) (xy 413.267398 -32.110934) (xy 412.806134 -32.110934) (xy 412.693866 -31.998666)
				(xy 412.693866 -31.78683) (xy 412.421324 -31.514288) (xy 412.060136 -31.514288) (xy 411.969458 -31.604966)
				(xy 411.969458 -35.802316) (xy 412.051246 -35.884104) (xy 412.051246 -35.917124) (xy 412.095188 -35.961066)
				(xy 413.59455 -35.961066) (xy 413.603948 -35.951668) (xy 416.3822 -35.951668) (xy 416.703002 -36.27247)
				(xy 416.703002 -36.739322) (xy 416.520122 -36.922202) (xy 416.107118 -36.922202) (xy 416.04184 -36.98748)
				(xy 416.04184 -37.6555) (xy 415.96564 -37.7317) (xy 415.4678 -37.7317) (xy 414.987486 -37.7317)
				(xy 414.77184 -37.516054) (xy 413.907732 -37.516054) (xy 413.677608 -37.28593) (xy 413.139128 -37.28593)
				(xy 413.134556 -37.290502) (xy 412.65602 -37.290502) (xy 412.416752 -37.051234) (xy 412.058104 -37.051234)
				(xy 411.969458 -37.13988) (xy 411.969458 -37.725858) (xy 412.846012 -38.602412) (xy 414.954212 -38.602412)
				(xy 415.157412 -38.805612) (xy 415.157412 -39.085012) (xy 415.238184 -39.165784) (xy 415.736786 -39.165784)
				(xy 415.894012 -39.008812) (xy 415.894012 -38.678612) (xy 416.021012 -38.551612) (xy 416.405314 -38.551612)
				(xy 416.690302 -38.266624) (xy 416.690302 -37.856414) (xy 416.935412 -37.611304) (xy 417.375086 -37.611304)
				(xy 417.471098 -37.515292) (xy 417.471098 -36.34994) (xy 418.121338 -35.6997) (xy 418.121338 -31.533338)
				(xy 418.002212 -31.414212)
			)
		)
	)
	(zone
		(net "GND")
		(layer "B.Cu")
		(hatch none 0.5)
		(connect_pads
			(clearance 0.5)
		)
		(min_thickness 0.25)
		(fill yes
			(thermal_gap 0.5)
			(thermal_bridge_width 0.5)
			(island_removal_mode 0)
		)
		(polygon
			(pts
				(xy 113.08969 -82.51571) (xy 116.50345 -82.51571) (xy 116.664994 -82.354166) (xy 116.664994 -81.458054)
				(xy 116.575586 -81.368646) (xy 115.047776 -81.368646) (xy 114.99469 -81.31556) (xy 114.99469 -81.168494)
				(xy 114.703606 -80.87741) (xy 96.98609 -80.87741) (xy 96.949768 -80.913732) (xy 96.949768 -80.9752)
				(xy 96.949768 -82.3468) (xy 97.432368 -82.8294) (xy 97.991168 -82.8294) (xy 98.524568 -83.3628)
				(xy 98.524568 -84.201) (xy 98.702368 -84.3788) (xy 99.565968 -84.3788) (xy 99.819968 -84.1248) (xy 100.150168 -83.7946)
				(xy 110.502192 -83.7946) (xy 110.654592 -83.6422) (xy 111.162592 -83.1342) (xy 112.4712 -83.1342)
			)
		)
	)
	(zone
		(net "P1V8_PCH_STBY")
		(layer "B.Cu")
		(hatch none 0.5)
		(connect_pads
			(clearance 0.5)
		)
		(min_thickness 0.25)
		(fill yes
			(thermal_gap 0.5)
			(thermal_bridge_width 0.5)
			(island_removal_mode 0)
		)
		(polygon
			(pts
				(xy 386.297424 -106.211624) (xy 386.1054 -106.0196) (xy 386.1054 -105.791) (xy 385.826 -105.5116)
				(xy 385.572 -105.5116) (xy 385.445 -105.6386) (xy 385.191 -105.6386) (xy 384.683 -105.1306) (xy 384.683 -104.775)
				(xy 384.683 -104.1654) (xy 385.0894 -103.759) (xy 385.6482 -103.759) (xy 386.2578 -104.3686) (xy 386.3848 -104.4956)
				(xy 386.3848 -104.648) (xy 386.9944 -105.2576) (xy 387.029452 -105.292652) (xy 387.161278 -105.424478)
				(xy 390.374124 -105.424478) (xy 390.766046 -105.8164) (xy 390.779 -105.8164) (xy 391.16 -105.8164)
				(xy 391.370566 -105.605834) (xy 391.37209 -105.605834) (xy 392.086846 -104.891078) (xy 392.299952 -104.891078)
				(xy 392.35634 -104.947466) (xy 392.418316 -105.009442) (xy 392.418316 -105.970324) (xy 392.145774 -106.242866)
				(xy 391.253726 -106.242866) (xy 391.01903 -106.477562) (xy 390.804654 -106.477562) (xy 390.62914 -106.302048)
				(xy 389.683244 -106.302048) (xy 389.540496 -106.444796) (xy 389.22833 -106.444796) (xy 388.949692 -106.166158)
				(xy 387.9723 -106.166158) (xy 387.926834 -106.211624)
			)
		)
	)
	(zone
		(net "P12V_STBY")
		(layer "B.Cu")
		(hatch none 0.5)
		(connect_pads
			(clearance 0.5)
		)
		(min_thickness 0.25)
		(fill yes
			(thermal_gap 0.5)
			(thermal_bridge_width 0.5)
			(island_removal_mode 0)
		)
		(polygon
			(pts
				(xy 481.06838 -20.828) (xy 481.311458 -20.828) (xy 481.9396 -20.828) (xy 484.02367 -20.828) (xy 484.067104 -20.871688)
				(xy 484.067104 -22.460458) (xy 484.381048 -22.774402) (xy 484.749602 -22.774402) (xy 485.04094 -23.06574)
				(xy 485.04094 -24.081994) (xy 485.04094 -25.120854) (xy 485.04094 -25.6413) (xy 484.730044 -25.952196)
				(xy 482.364034 -25.952196) (xy 481.888038 -25.4762) (xy 480.967796 -24.555958) (xy 480.967796 -20.928584)
			)
		)
	)
	(zone
		(layer "B.Cu")
		(hatch none 0.5)
		(connect_pads
			(clearance 0)
		)
		(min_thickness 0.25)
		(keepout
			(tracks not_allowed)
			(vias allowed)
			(pads allowed)
			(copperpour not_allowed)
			(footprints allowed)
		)
		(placement
			(enabled no)
			(sheetname "")
		)
		(fill
			(thermal_gap 0.5)
			(thermal_bridge_width 0.5)
			(island_removal_mode 0)
		)
		(polygon
			(pts
				(arc
					(start 493.100614 -116.196872)
					(mid 496.700556 -119.796814)
					(end 500.300498 -116.196872)
				)
				(arc
					(start 500.300498 -114.596926)
					(mid 496.700556 -110.996984)
					(end 493.100614 -114.596926)
				)
			)
		)
	)
	(zone
		(layer "B.Cu")
		(hatch none 0.5)
		(connect_pads
			(clearance 0)
		)
		(min_thickness 0.25)
		(keepout
			(tracks allowed)
			(vias allowed)
			(pads allowed)
			(copperpour allowed)
			(footprints not_allowed)
		)
		(placement
			(enabled no)
			(sheetname "")
		)
		(fill
			(thermal_gap 0.5)
			(thermal_bridge_width 0.5)
			(island_removal_mode 0)
		)
		(polygon
			(pts
				(xy -5.999988 2.500122) (xy -5.999988 -2.500122)
				(arc
					(start -4.038854 -2.500122)
					(mid -4.75001 0)
					(end -4.038854 2.500122)
				)
			)
		)
	)
	(zone
		(layer "B.Cu")
		(hatch none 0.5)
		(connect_pads
			(clearance 0)
		)
		(min_thickness 0.25)
		(keepout
			(tracks allowed)
			(vias allowed)
			(pads allowed)
			(copperpour allowed)
			(footprints allowed)
		)
		(placement
			(enabled no)
			(sheetname "")
		)
		(fill
			(thermal_gap 0.5)
			(thermal_bridge_width 0.5)
			(island_removal_mode 0)
		)
		(polygon
			(pts
				(xy 132.24764 -49.86274) (xy 132.24764 -49.19726) (xy 133.00202 -49.19726) (xy 133.00202 -49.86274)
			)
		)
	)
	(zone
		(net "PVDDQ_ABC")
		(layer "B.Cu")
		(hatch none 0.5)
		(connect_pads
			(clearance 0.5)
		)
		(min_thickness 0.25)
		(fill yes
			(thermal_gap 0.5)
			(thermal_bridge_width 0.5)
			(island_removal_mode 0)
		)
		(polygon
			(pts
				(xy 185.02122 2.5908) (xy 184.90946 2.47904) (xy 184.90946 1.87198) (xy 184.79008 1.7526) (xy 183.4515 1.7526)
				(xy 183.2864 1.5875) (xy 183.2864 -0.0762) (xy 183.528208 -0.318008) (xy 187.18403 -0.318008) (xy 187.389262 -0.112776)
				(xy 187.389262 0.836422) (xy 187.203842 1.021842) (xy 187.203842 2.381758) (xy 186.9948 2.5908)
			)
		)
		(polygon
			(pts
				(xy 185.73369 0.685292) (xy 185.53049 0.685292) (xy 185.53049 0.482092) (xy 185.73369 0.482092)
			)
		)
		(polygon
			(pts
				(xy 184.97169 0.685292) (xy 184.76849 0.685292) (xy 184.76849 0.482092) (xy 184.97169 0.482092)
			)
		)
		(polygon
			(pts
				(xy 184.15889 0.685292) (xy 183.95569 0.685292) (xy 183.95569 0.482092) (xy 184.15889 0.482092)
			)
		)
	)
	(zone
		(layer "B.Cu")
		(hatch none 0.5)
		(connect_pads
			(clearance 0)
		)
		(min_thickness 0.25)
		(keepout
			(tracks allowed)
			(vias allowed)
			(pads allowed)
			(copperpour allowed)
			(footprints not_allowed)
		)
		(placement
			(enabled no)
			(sheetname "")
		)
		(fill
			(thermal_gap 0.5)
			(thermal_bridge_width 0.5)
			(island_removal_mode 0)
		)
		(polygon
			(pts
				(arc
					(start 198.930006 -42.999914)
					(mid 195.379848 -46.550072)
					(end 198.930006 -50.099976)
				)
				(arc
					(start 198.930006 -50.099976)
					(mid 202.47991 -46.550072)
					(end 198.930006 -42.999914)
				)
			)
		)
	)
	(zone
		(net "P1V05_PCH_STBY_VCCA_PLL1")
		(layer "B.Cu")
		(hatch none 0.5)
		(connect_pads
			(clearance 0.5)
		)
		(min_thickness 0.25)
		(fill yes
			(thermal_gap 0.5)
			(thermal_bridge_width 0.5)
			(island_removal_mode 0)
		)
		(polygon
			(pts
				(xy 377.409202 -136.179814) (xy 377.409202 -137.30732) (xy 377.5583 -137.456418) (xy 377.5583 -138.833606)
				(xy 377.662694 -138.938) (xy 378.4346 -138.938) (xy 378.515626 -138.856974) (xy 378.515626 -138.290554)
				(xy 378.820172 -137.986008) (xy 379.818392 -137.986008) (xy 380.0348 -137.7696) (xy 380.0348 -136.9822)
				(xy 379.8824 -136.8298) (xy 378.6124 -136.8298) (xy 378.4346 -136.652) (xy 378.4346 -136.2456) (xy 378.368814 -136.179814)
			)
		)
		(polygon
			(pts
				(xy 378.5489 -137.3632) (xy 378.3457 -137.3632) (xy 378.3457 -137.5664) (xy 378.5489 -137.5664)
			)
		)
		(polygon
			(pts
				(xy 378.4473 -136.9949) (xy 378.2441 -136.9949) (xy 378.2441 -137.1981) (xy 378.4473 -137.1981)
			)
		)
	)
	(zone
		(net "P5V_STBY_DGB_FS")
		(layer "B.Cu")
		(hatch none 0.5)
		(connect_pads
			(clearance 0.5)
		)
		(min_thickness 0.25)
		(fill yes
			(thermal_gap 0.5)
			(thermal_bridge_width 0.5)
			(island_removal_mode 0)
		)
		(polygon
			(pts
				(xy 482.1682 -158.623) (xy 491.3884 -158.623) (xy 494.8936 -155.1178) (xy 494.8936 -153.4922) (xy 494.4618 -153.0604)
				(xy 493.0902 -153.0604) (xy 489.5596 -156.591) (xy 487.9594 -156.591) (xy 486.8418 -155.4734) (xy 485.6226 -155.4734)
				(xy 485.2797 -155.8163) (xy 483.1334 -155.8163) (xy 482.0031 -155.8163) (xy 481.7999 -156.0195)
				(xy 481.7999 -158.2547)
			)
		)
	)
	(zone
		(net "VR_FET_SW_P12V_STBY_PVCCIN_CPU0")
		(layer "B.Cu")
		(hatch none 0.5)
		(connect_pads
			(clearance 0.5)
		)
		(min_thickness 0.25)
		(fill yes
			(thermal_gap 0.5)
			(thermal_bridge_width 0.5)
			(island_removal_mode 0)
		)
		(polygon
			(pts
				(xy 182.5498 -59.2836) (xy 186.730386 -59.2836) (xy 187.076588 -59.629802) (xy 187.076588 -59.631326)
				(xy 187.376562 -59.9313) (xy 190.212218 -59.9313) (xy 190.652146 -59.491372) (xy 190.652146 -57.209182)
				(xy 190.909448 -56.95188) (xy 190.909448 -55.930546) (xy 189.900814 -54.921912) (xy 189.900814 -53.764688)
				(xy 189.603126 -53.467) (xy 188.341 -53.467) (xy 188.214 -53.594) (xy 188.214 -53.848) (xy 187.96 -54.102)
				(xy 186.182 -54.102) (xy 185.409332 -53.329332) (xy 183.515 -51.435) (xy 183.3626 -51.2826) (xy 181.737 -51.2826)
				(xy 181.0512 -50.5968) (xy 178.4604 -50.5968) (xy 178.054 -51.0032) (xy 178.054 -55.7784) (xy 178.6636 -56.388)
				(xy 178.6636 -58.3946) (xy 178.4985 -58.5597) (xy 177.8381 -58.5597) (xy 177.4952 -58.9026) (xy 177.26914 -59.12866)
				(xy 177.26914 -60.67552) (xy 177.45202 -60.8584) (xy 177.4952 -60.8584) (xy 181.7116 -60.8584) (xy 182.372 -60.198)
				(xy 182.372 -59.4614)
			)
		)
	)
	(zone
		(net "P12V_NVDIMM_KLM")
		(layer "B.Cu")
		(hatch none 0.5)
		(connect_pads
			(clearance 0.5)
		)
		(min_thickness 0.25)
		(fill yes
			(thermal_gap 0.5)
			(thermal_bridge_width 0.5)
			(island_removal_mode 0)
		)
		(polygon
			(pts
				(xy 29.944568 -127.811784) (xy 29.944568 -152.8064) (xy 29.817568 -152.9334) (xy 24.940768 -152.9334)
				(xy 24.356568 -152.3492) (xy 24.356568 -130.884422) (xy 25.049226 -130.191764) (xy 27.428952 -127.811784)
			)
		)
	)
	(zone
		(net "GND")
		(layer "B.Cu")
		(hatch none 0.5)
		(connect_pads
			(clearance 0.5)
		)
		(min_thickness 0.25)
		(fill yes
			(thermal_gap 0.5)
			(thermal_bridge_width 0.5)
			(island_removal_mode 0)
		)
		(polygon
			(pts
				(xy 8.327136 -2.527046) (xy 11.733022 -2.527046) (xy 11.999722 -2.260346) (xy 11.999722 0.127254)
				(xy 11.136122 0.990854) (xy 11.028172 1.098804) (xy 11.028172 1.77165) (xy 10.742168 2.057654) (xy 9.98347 2.057654)
				(xy 9.912604 1.986788) (xy 9.912604 1.552194) (xy 9.877044 1.516634) (xy 8.513826 1.516634) (xy 8.284972 1.28778)
				(xy 8.284972 -0.882396) (xy 8.16356 -1.003808) (xy 8.16356 -2.36347)
			)
		)
	)
	(zone
		(net "PVTT_DEF")
		(layer "B.Cu")
		(hatch none 0.5)
		(connect_pads
			(clearance 0.5)
		)
		(min_thickness 0.25)
		(fill yes
			(thermal_gap 0.5)
			(thermal_bridge_width 0.5)
			(island_removal_mode 0)
		)
		(polygon
			(pts
				(xy 259.8166 -125.1204) (xy 259.5118 -125.4252) (xy 259.5118 -126.3396) (xy 258.987036 -126.864364)
				(xy 258.987036 -133.6802) (xy 259.139436 -133.8326) (xy 261.1882 -133.8326) (xy 261.9756 -134.62)
				(xy 261.9756 -137.4648) (xy 261.5946 -137.8458) (xy 260.985 -137.8458) (xy 260.9596 -137.8712) (xy 260.5024 -137.8712)
				(xy 259.6134 -136.9822) (xy 259.164836 -136.9822) (xy 258.987036 -137.16) (xy 258.987036 -138.7094)
				(xy 259.9944 -138.7094) (xy 260.3754 -138.3284) (xy 261.7216 -138.3284) (xy 262.255 -138.8618) (xy 262.255 -140.7922)
				(xy 261.8994 -141.1478) (xy 260.0706 -141.1478) (xy 259.6388 -141.5796) (xy 259.063236 -141.5796)
				(xy 258.987036 -141.6558) (xy 258.987036 -143.391636) (xy 259.0292 -143.4338) (xy 261.5184 -143.4338)
				(xy 261.8486 -143.764) (xy 261.8486 -147.066) (xy 261.6708 -147.2438) (xy 260.477 -147.2438) (xy 260.16458 -146.93138)
				(xy 260.16458 -146.80438) (xy 259.7658 -146.4056) (xy 259.1308 -146.4056) (xy 258.987036 -146.549364)
				(xy 258.987036 -147.908772) (xy 259.55879 -148.480526) (xy 259.55879 -148.91766) (xy 259.64007 -148.99894)
				(xy 261.33044 -148.99894) (xy 261.4168 -149.0853) (xy 261.4168 -150.4188) (xy 261.07898 -150.75662)
				(xy 260.67766 -151.15794) (xy 259.103876 -151.15794) (xy 258.987036 -151.27478) (xy 258.987036 -153.331164)
				(xy 258.6482 -153.67) (xy 252.8062 -153.67) (xy 250.76277 -155.71343) (xy 250.7615 -155.71343) (xy 250.52655 -155.94838)
				(xy 196.84492 -155.94838) (xy 196.6341 -156.1592) (xy 188.416946 -156.1592) (xy 186.765946 -154.5082)
				(xy 184.575196 -154.5082) (xy 183.165496 -153.0985) (xy 183.165496 -152.098502) (xy 182.86222 -151.795226)
				(xy 182.338472 -151.795226) (xy 181.372256 -152.761696) (xy 181.16931 -152.964642) (xy 181.019958 -152.964642)
				(xy 180.3654 -153.6192) (xy 180.3654 -156.9974) (xy 181.8894 -158.5214) (xy 183.8706 -158.5214)
				(xy 184.531 -157.861) (xy 185.547 -157.861) (xy 186.0296 -158.3436) (xy 253.365 -158.3436) (xy 254.5334 -157.1752)
				(xy 255.6256 -157.1752) (xy 255.8288 -157.3784) (xy 255.8288 -158.3436) (xy 256.0066 -158.5214)
				(xy 262.382 -158.5214) (xy 262.6106 -158.2928) (xy 262.6106 -156.591) (xy 262.07974 -156.06014)
				(xy 262.07974 -150.75916) (xy 262.09117 -150.74773) (xy 262.09117 -148.42363) (xy 262.1026 -148.4122)
				(xy 262.1026 -143.0528) (xy 261.8994 -142.8496) (xy 261.8994 -141.5034) (xy 262.4836 -140.9192)
				(xy 262.4836 -134.5946) (xy 261.0231 -133.1341) (xy 261.0231 -126.6317) (xy 260.6548 -126.2634)
				(xy 260.6548 -125.3744) (xy 260.4008 -125.1204)
			)
		)
		(polygon
			(pts
				(xy 256.18948 -157.32252) (xy 255.98628 -157.32252) (xy 255.98628 -157.83052) (xy 256.18948 -157.83052)
			)
		)
		(polygon
			(pts
				(xy 261.0866 -156.2608) (xy 257.5052 -156.2608) (xy 257.3528 -156.4132) (xy 257.3528 -157.6324)
				(xy 257.5052 -157.7848) (xy 261.1628 -157.7848) (xy 261.2898 -157.6578) (xy 261.2898 -156.464)
			)
		)
		(polygon
			(pts
				(xy 260.4643 -126.5301) (xy 260.2611 -126.5301) (xy 260.2611 -126.7333) (xy 260.4643 -126.7333)
			)
		)
		(polygon
			(pts
				(xy 260.4643 -125.5395) (xy 260.2611 -125.5395) (xy 260.2611 -125.7427) (xy 260.4643 -125.7427)
			)
		)
	)
	(zone
		(net "VR_FET_SW_P12V_STBY_PVCCIN_CPU1")
		(layer "B.Cu")
		(hatch none 0.5)
		(connect_pads
			(clearance 0.5)
		)
		(min_thickness 0.25)
		(fill yes
			(thermal_gap 0.5)
			(thermal_bridge_width 0.5)
			(island_removal_mode 0)
		)
		(polygon
			(pts
				(xy 33.049464 -55.909464) (xy 32.553402 -55.909464) (xy 32.248602 -56.214264) (xy 32.248602 -56.950864)
				(xy 32.020002 -57.179464) (xy 31.740602 -57.179464) (xy 31.588202 -57.331864) (xy 31.588202 -58.79338)
				(xy 31.143702 -59.23788) (xy 30.7213 -59.23788) (xy 30.55239 -59.40679) (xy 30.55239 -60.52439)
				(xy 30.75178 -60.72378) (xy 33.0962 -60.72378) (xy 33.098232 -60.721748) (xy 33.27527 -60.721748)
				(xy 33.3248 -60.672218) (xy 33.3248 -60.5028) (xy 33.3248 -56.1848)
			)
		)
	)
	(zone
		(net "PVTT_KLM")
		(layer "B.Cu")
		(hatch none 0.5)
		(connect_pads
			(clearance 0.5)
		)
		(min_thickness 0.25)
		(fill yes
			(thermal_gap 0.5)
			(thermal_bridge_width 0.5)
			(island_removal_mode 0)
		)
		(polygon
			(pts
				(xy 94.20479 -125.76556) (xy 93.96857 -126.00178) (xy 93.96857 -134.089902) (xy 94.399862 -134.521194)
				(xy 96.405954 -134.521194) (xy 96.724978 -134.840218) (xy 96.724978 -137.159238) (xy 96.033844 -137.850372)
				(xy 95.479108 -137.850372) (xy 95.20174 -137.573004) (xy 95.20174 -136.678924) (xy 94.87281 -136.349994)
				(xy 94.42069 -136.349994) (xy 93.96857 -136.802114) (xy 93.96857 -138.7856) (xy 94.5642 -138.7856)
				(xy 95.0722 -138.2776) (xy 96.1136 -138.2776) (xy 96.62922 -138.79322) (xy 96.62922 -140.77188)
				(xy 96.4819 -140.9192) (xy 94.2848 -140.9192) (xy 93.96857 -141.23543) (xy 93.96857 -143.604742)
				(xy 94.254574 -143.890746) (xy 96.258126 -143.890746) (xy 96.643698 -144.276318) (xy 96.643698 -146.822922)
				(xy 96.2025 -147.26412) (xy 95.553784 -147.26412) (xy 94.737428 -146.447764) (xy 94.19463 -146.447764)
				(xy 94.02445 -146.617944) (xy 94.02445 -148.258784) (xy 93.89872 -148.384768) (xy 93.89872 -148.898864)
				(xy 93.958156 -148.9583) (xy 96.40951 -148.9583) (xy 96.473772 -149.022562) (xy 96.473772 -149.117812)
				(xy 96.47428 -149.11832) (xy 96.47428 -150.37308) (xy 96.29648 -150.55088) (xy 94.064582 -150.55088)
				(xy 93.896942 -150.71852) (xy 93.896942 -153.52903) (xy 93.414088 -154.011884) (xy 92.813124 -154.011884)
				(xy 91.16568 -155.659328) (xy 91.16568 -157.61462) (xy 91.421204 -157.870144) (xy 92.0242 -157.870144)
				(xy 92.1258 -157.768544) (xy 92.1258 -156.4132) (xy 92.2782 -156.2608) (xy 94.4118 -156.2608) (xy 94.53626 -156.13634)
				(xy 94.53626 -154.99715) (xy 94.867222 -154.666188) (xy 95.247206 -154.666188) (xy 95.470218 -154.8892)
				(xy 95.470218 -157.469332) (xy 95.658178 -157.657292) (xy 96.807528 -157.657292) (xy 96.928178 -157.536642)
				(xy 96.928178 -155.988258) (xy 97.182178 -155.734258) (xy 97.182178 -128.920494) (xy 97.196656 -128.906016)
				(xy 97.196656 -127.84836) (xy 96.4946 -127.146304) (xy 96.4946 -125.96368) (xy 96.29648 -125.76556)
			)
		)
		(polygon
			(pts
				(xy 95.68942 -126.82728) (xy 95.48622 -126.82728) (xy 95.48622 -127.03048) (xy 95.68942 -127.03048)
			)
		)
	)
	(zone
		(net "P3V3_STBY")
		(layer "B.Cu")
		(hatch none 0.5)
		(connect_pads
			(clearance 0.5)
		)
		(min_thickness 0.25)
		(fill yes
			(thermal_gap 0.5)
			(thermal_bridge_width 0.5)
			(island_removal_mode 0)
		)
		(polygon
			(pts
				(xy 469.773 -62.9412) (xy 469.773 -55.7276) (xy 469.773 -54.878732) (xy 469.773 -54.5592) (xy 469.879934 -54.452266)
				(xy 470.199466 -54.452266) (xy 470.625932 -54.0258) (xy 471.4748 -54.0258) (xy 473.5576 -54.0258)
				(xy 474.0402 -53.5432) (xy 477.6216 -53.5432) (xy 477.9899 -53.9115) (xy 477.9899 -54.4195) (xy 478.3074 -54.737)
				(xy 479.533458 -54.737) (xy 479.660458 -54.61) (xy 479.660458 -54.203854) (xy 479.774504 -54.089808)
				(xy 480.699064 -54.089808) (xy 481.107242 -53.68163) (xy 482.02088 -53.68163) (xy 482.2317 -53.89245)
				(xy 482.2317 -54.6989) (xy 482.2317 -55.193692) (xy 482.057456 -55.367936) (xy 482.009958 -55.367936)
				(xy 482.00437 -55.362348) (xy 481.096066 -55.362348) (xy 480.726242 -55.732172) (xy 479.741738 -55.732172)
				(xy 479.584258 -55.889652) (xy 479.584258 -56.730392) (xy 479.741992 -56.888126) (xy 480.110038 -56.888126)
				(xy 480.1997 -56.977788) (xy 480.1997 -57.565036) (xy 480.112578 -57.652158) (xy 479.176334 -57.652158)
				(xy 478.9805 -57.456324) (xy 478.9805 -56.8071) (xy 478.7646 -56.5912) (xy 476.9866 -56.5912) (xy 475.7801 -55.3847)
				(xy 472.707462 -55.3847) (xy 470.5858 -57.506362) (xy 470.5858 -62.9285) (xy 470.5096 -63.0047)
				(xy 469.8365 -63.0047)
			)
		)
	)
	(zone
		(net "GND")
		(layer "B.Cu")
		(hatch none 0.5)
		(connect_pads
			(clearance 0.5)
		)
		(min_thickness 0.25)
		(fill yes
			(thermal_gap 0.5)
			(thermal_bridge_width 0.5)
			(island_removal_mode 0)
		)
		(polygon
			(pts
				(xy 421.3606 -82.1055) (xy 421.0431 -82.1055) (xy 420.37 -82.1055) (xy 420.3065 -82.169) (xy 420.3065 -82.71256)
				(xy 420.3065 -83.7438) (xy 420.0779 -83.9724) (xy 419.7223 -83.9724) (xy 419.650418 -83.9724) (xy 419.5953 -84.027518)
				(xy 419.5953 -84.429346) (xy 419.660832 -84.494878) (xy 419.765226 -84.494878) (xy 419.766242 -84.495894)
				(xy 421.425116 -84.495894) (xy 421.5892 -84.33181) (xy 421.5892 -84.0105) (xy 421.5892 -82.3341)
			)
		)
	)
	(zone
		(net "PVDDQ_DEF")
		(layer "B.Cu")
		(hatch none 0.5)
		(connect_pads
			(clearance 0.5)
		)
		(min_thickness 0.25)
		(fill yes
			(thermal_gap 0.5)
			(thermal_bridge_width 0.5)
			(island_removal_mode 0)
		)
		(polygon
			(pts
				(xy 267.667994 -157.812994) (xy 268.096238 -157.812994) (xy 268.605 -157.812994) (xy 268.605254 -157.812994)
				(xy 269.875 -157.812994) (xy 270.002 -157.685994) (xy 270.002 -156.3624) (xy 270.0528 -156.3116)
				(xy 271.8562 -156.3116) (xy 271.9578 -156.4132) (xy 271.9578 -157.226) (xy 272.480024 -157.748224)
				(xy 275.372576 -157.748224) (xy 275.6154 -157.5054) (xy 275.7424 -157.6324) (xy 276.86 -157.6324)
				(xy 276.9616 -157.5308) (xy 276.9616 -156.498036) (xy 277.529036 -155.9306) (xy 277.529036 -155.660344)
				(xy 277.529036 -153.43251) (xy 277.340822 -153.244296) (xy 265.929364 -153.244296) (xy 265.678158 -153.495502)
				(xy 265.678158 -155.561792) (xy 265.678158 -156.534358) (xy 266.956794 -157.812994)
			)
		)
	)
	(zone
		(layer "B.Cu")
		(hatch none 0.5)
		(connect_pads
			(clearance 0)
		)
		(min_thickness 0.25)
		(keepout
			(tracks not_allowed)
			(vias allowed)
			(pads allowed)
			(copperpour not_allowed)
			(footprints allowed)
		)
		(placement
			(enabled no)
			(sheetname "")
		)
		(fill
			(thermal_gap 0.5)
			(thermal_bridge_width 0.5)
			(island_removal_mode 0)
		)
		(polygon
			(pts
				(xy 344.776806 -60.622434) (xy 344.268806 -60.622434) (xy 344.268806 -61.003434) (xy 344.776806 -61.003434)
			)
		)
	)
	(zone
		(net "PVDDQ_KLM")
		(layer "B.Cu")
		(hatch none 0.5)
		(connect_pads
			(clearance 0.5)
		)
		(min_thickness 0.25)
		(fill yes
			(thermal_gap 0.5)
			(thermal_bridge_width 0.5)
			(island_removal_mode 0)
		)
		(polygon
			(pts
				(xy 107.6198 -148.5138) (xy 107.4674 -148.6662) (xy 107.4674 -148.8948) (xy 106.8578 -149.5044)
				(xy 100.880926 -149.5044) (xy 100.677726 -149.7076) (xy 100.677726 -150.687532) (xy 100.978716 -150.988522)
				(xy 112.326166 -150.988522) (xy 112.528604 -150.786084) (xy 112.528604 -148.672804) (xy 112.3696 -148.5138)
			)
		)
		(polygon
			(pts
				(xy 107.5182 -150.0886) (xy 107.315 -150.0886) (xy 107.315 -150.2918) (xy 107.5182 -150.2918)
			)
		)
		(polygon
			(pts
				(xy 107.5182 -149.3266) (xy 107.315 -149.3266) (xy 107.315 -149.5298) (xy 107.5182 -149.5298)
			)
		)
	)
	(zone
		(layer "B.Cu")
		(hatch none 0.5)
		(connect_pads
			(clearance 0)
		)
		(min_thickness 0.25)
		(keepout
			(tracks not_allowed)
			(vias allowed)
			(pads allowed)
			(copperpour not_allowed)
			(footprints allowed)
		)
		(placement
			(enabled no)
			(sheetname "")
		)
		(fill
			(thermal_gap 0.5)
			(thermal_bridge_width 0.5)
			(island_removal_mode 0)
		)
		(polygon
			(pts
				(arc
					(start 350.121982 -67.329812)
					(mid 349.702011 -67.650977)
					(end 350.023176 -67.231006)
				)
				(xy 350.145858 -67.108324) (xy 350.145858 -67.07886)
				(arc
					(start 349.890588 -67.07886)
					(mid 349.507048 -67.4624)
					(end 349.890588 -67.84594)
				)
				(arc
					(start 350.78162 -67.84594)
					(mid 351.165414 -67.462527)
					(end 350.781874 -67.07886)
				)
				(xy 350.526858 -67.07886) (xy 350.526858 -67.108578)
				(arc
					(start 350.649286 -67.231006)
					(mid 350.970451 -67.650977)
					(end 350.55048 -67.329812)
				)
				(xy 350.387158 -67.16649) (xy 350.387158 -67.07886) (xy 350.285558 -67.07886) (xy 350.285558 -67.166236)
			)
		)
	)
	(zone
		(net "GND")
		(layer "B.Cu")
		(hatch none 0.5)
		(connect_pads
			(clearance 0.5)
		)
		(min_thickness 0.25)
		(fill yes
			(thermal_gap 0.5)
			(thermal_bridge_width 0.5)
			(island_removal_mode 0)
		)
		(polygon
			(pts
				(xy 77.028802 -146.241008) (xy 78.284324 -146.241008) (xy 78.433168 -146.092164) (xy 78.433168 -143.782034)
				(xy 78.219554 -143.56842) (xy 77.054964 -143.56842) (xy 76.8477 -143.775684) (xy 76.8477 -146.059906)
			)
		)
	)
	(zone
		(layer "B.Cu")
		(hatch none 0.5)
		(connect_pads
			(clearance 0)
		)
		(min_thickness 0.25)
		(keepout
			(tracks allowed)
			(vias allowed)
			(pads allowed)
			(copperpour allowed)
			(footprints allowed)
		)
		(placement
			(enabled no)
			(sheetname "")
		)
		(fill
			(thermal_gap 0.5)
			(thermal_bridge_width 0.5)
			(island_removal_mode 0)
		)
		(polygon
			(pts
				(xy 143.36522 -105.179622) (xy 129.6162 -105.179622) (xy 127.404622 -107.3912) (xy 120.410732 -107.3912)
				(xy 117.8814 -104.861868) (xy 89.507568 -104.861868) (xy 87.740236 -106.6292) (xy 85.621368 -106.6292)
				(xy 82.711036 -103.718868) (xy 71.038974 -103.718868) (xy 67.863974 -100.543868) (xy 67.863974 -88.13292)
				(xy 66.4337 -88.13292) (xy 66.21272 -87.91194) (xy 66.21272 -87.63) (xy 67.08902 -86.7537) (xy 67.863974 -86.7537)
				(xy 67.863974 -55.204868) (xy 71.985632 -51.083464) (xy 71.041768 -50.1396) (xy 140.993368 -50.1396)
				(xy 145.692368 -54.8386) (xy 145.692368 -54.864) (xy 147.574 -54.864) (xy 148.717 -56.007) (xy 148.717 -65.405)
				(xy 145.796 -68.326) (xy 145.796 -72.136) (xy 145.415 -72.136) (xy 145.415 -103.251) (xy 144.018 -104.648)
				(xy 143.896842 -104.648)
			)
		)
	)
	(zone
		(net "PVDDQ_ABC")
		(layer "B.Cu")
		(hatch none 0.5)
		(connect_pads
			(clearance 0.5)
		)
		(min_thickness 0.25)
		(fill yes
			(thermal_gap 0.5)
			(thermal_bridge_width 0.5)
			(island_removal_mode 0)
		)
		(polygon
			(pts
				(xy 245.6434 -24.2824) (xy 245.491 -24.4348) (xy 245.491 -25.781) (xy 245.3132 -25.9588) (xy 244.3988 -25.9588)
				(xy 244.2464 -25.8064) (xy 244.2464 -24.4094) (xy 244.1448 -24.3078) (xy 243.7892 -24.3078) (xy 243.7384 -24.3586)
				(xy 243.7384 -26.6192) (xy 244.0686 -26.9494) (xy 244.0686 -28.1432) (xy 244.1956 -28.2702) (xy 245.0084 -28.2702)
				(xy 245.6688 -27.6098) (xy 245.872 -27.6098) (xy 245.9228 -27.559) (xy 245.9228 -24.3586) (xy 245.8466 -24.2824)
			)
		)
		(polygon
			(pts
				(xy 245.0465 -27.2161) (xy 244.8433 -27.2161) (xy 244.8433 -27.4193) (xy 245.0465 -27.4193)
			)
		)
		(polygon
			(pts
				(xy 245.3767 -26.6065) (xy 245.1735 -26.6065) (xy 245.1735 -26.8097) (xy 245.3767 -26.8097)
			)
		)
	)
	(zone
		(net "AGND_HSC")
		(layer "B.Cu")
		(hatch none 0.5)
		(connect_pads
			(clearance 0.5)
		)
		(min_thickness 0.25)
		(fill yes
			(thermal_gap 0.5)
			(thermal_bridge_width 0.5)
			(island_removal_mode 0)
		)
		(polygon
			(pts
				(xy 18.908776 -73.508108) (xy 18.908776 -73.887584) (xy 18.78076 -74.0156) (xy 16.8402 -74.0156)
				(xy 16.074644 -73.250044) (xy 12.149582 -73.250044) (xy 11.951208 -73.448418) (xy 11.951208 -74.306938)
				(xy 12.163806 -74.306938) (xy 12.432538 -74.57567) (xy 13.934186 -74.57567) (xy 14.110716 -74.7522)
				(xy 14.6812 -74.7522) (xy 16.087852 -74.7522) (xy 16.420084 -75.084432) (xy 16.420084 -76.07935)
				(xy 16.39443 -76.105004) (xy 16.39443 -76.879704) (xy 16.331692 -76.942442) (xy 16.058134 -77.216)
				(xy 15.2908 -77.216) (xy 14.659356 -77.847444) (xy 14.659356 -79.05623) (xy 13.198856 -80.51673)
				(xy 13.198856 -82.258916) (xy 13.401548 -82.461608) (xy 13.86205 -82.461608) (xy 14.1732 -82.772758)
				(xy 14.1732 -83.7438) (xy 13.7922 -84.1248) (xy 12.969748 -84.1248) (xy 12.8016 -84.292948) (xy 12.8016 -85.2424)
				(xy 12.9286 -85.3694) (xy 14.708378 -85.3694) (xy 15.6591 -84.418678) (xy 15.6591 -83.6549) (xy 15.6718 -83.6422)
				(xy 15.6718 -80.6196) (xy 16.081248 -80.210152) (xy 16.081756 -80.210152) (xy 16.155162 -80.136746)
				(xy 16.294608 -79.9973) (xy 18.037556 -79.9973) (xy 18.177002 -80.136746) (xy 18.774664 -80.734408)
				(xy 19.555714 -80.734408) (xy 19.720306 -80.899) (xy 22.59203 -80.899) (xy 22.730714 -80.760316)
				(xy 22.730714 -80.02143) (xy 22.476206 -79.766922) (xy 22.476206 -79.230982) (xy 22.592538 -79.11465)
				(xy 23.10511 -79.11465) (xy 23.143972 -79.075788) (xy 23.143972 -78.436978) (xy 23.076154 -78.36916)
				(xy 22.253702 -78.36916) (xy 21.853906 -78.768956) (xy 21.853906 -79.100934) (xy 21.589492 -79.365348)
				(xy 21.221954 -79.365348) (xy 20.993354 -79.136748) (xy 20.993354 -79.090266) (xy 20.360132 -78.457044)
				(xy 19.844258 -78.457044) (xy 19.705574 -78.31836) (xy 19.705574 -77.780134) (xy 19.838924 -77.646784)
				(xy 20.802854 -77.646784) (xy 20.9804 -77.469238) (xy 20.9804 -76.2508) (xy 20.9804 -75.7682) (xy 21.3614 -75.3872)
				(xy 23.241 -75.3872) (xy 23.368 -75.5142) (xy 23.368 -76.3524) (xy 23.4188 -76.4032) (xy 24.1554 -76.4032)
				(xy 24.511 -76.0476) (xy 24.511 -71.755) (xy 24.2316 -71.4756) (xy 22.069298 -71.4756) (xy 20.99818 -72.546718)
				(xy 20.6629 -72.546718) (xy 19.870166 -72.546718)
			)
		)
		(polygon
			(pts
				(xy 17.8054 -77.2541) (xy 17.4244 -77.2541) (xy 17.1196 -77.5589) (xy 17.1196 -79.0702) (xy 17.3863 -79.3369)
				(xy 17.8435 -79.3369) (xy 18.0721 -79.1083) (xy 18.0721 -77.5208)
			)
		)
		(polygon
			(pts
				(xy 23.113238 -74.045572) (xy 21.661882 -74.045572) (xy 21.130514 -74.57694) (xy 21.130514 -74.916538)
				(xy 21.359114 -75.145138) (xy 21.733002 -75.145138) (xy 22.069044 -74.809096) (xy 23.169118 -74.809096)
				(xy 23.208488 -74.769726) (xy 23.208488 -74.140822)
			)
		)
		(polygon
			(pts
				(xy 22.5806 -80.2894) (xy 22.3774 -80.2894) (xy 22.3774 -80.4926) (xy 22.5806 -80.4926)
			)
		)
		(polygon
			(pts
				(xy 22.0726 -80.2894) (xy 21.8694 -80.2894) (xy 21.8694 -80.4926) (xy 22.0726 -80.4926)
			)
		)
		(polygon
			(pts
				(xy 22.0726 -79.6544) (xy 21.8694 -79.6544) (xy 21.8694 -79.8576) (xy 22.0726 -79.8576)
			)
		)
		(polygon
			(pts
				(xy 22.9616 -78.7654) (xy 22.7584 -78.7654) (xy 22.7584 -78.9686) (xy 22.9616 -78.9686)
			)
		)
		(polygon
			(pts
				(xy 22.4536 -78.7654) (xy 22.2504 -78.7654) (xy 22.2504 -78.9686) (xy 22.4536 -78.9686)
			)
		)
	)
	(zone
		(layer "B.Cu")
		(hatch none 0.5)
		(connect_pads
			(clearance 0)
		)
		(min_thickness 0.25)
		(keepout
			(tracks allowed)
			(vias allowed)
			(pads allowed)
			(copperpour allowed)
			(footprints not_allowed)
		)
		(placement
			(enabled no)
			(sheetname "")
		)
		(fill
			(thermal_gap 0.5)
			(thermal_bridge_width 0.5)
			(island_removal_mode 0)
		)
		(polygon
			(pts
				(arc
					(start 61.861954 -119.800116)
					(mid 65.479222 -125.508518)
					(end 69.096128 -119.800116)
				)
			)
		)
	)
	(zone
		(layer "B.Cu")
		(hatch none 0.5)
		(connect_pads
			(clearance 0)
		)
		(min_thickness 0.25)
		(keepout
			(tracks allowed)
			(vias allowed)
			(pads allowed)
			(copperpour allowed)
			(footprints not_allowed)
		)
		(placement
			(enabled no)
			(sheetname "")
		)
		(fill
			(thermal_gap 0.5)
			(thermal_bridge_width 0.5)
			(island_removal_mode 0)
		)
		(polygon
			(pts
				(xy 339.320124 -25.733248) (xy 339.320124 5.999988) (xy 336.820002 5.999988) (xy 336.820002 -25.733248)
			)
		)
	)
	(zone
		(layer "B.Cu")
		(hatch none 0.5)
		(connect_pads
			(clearance 0)
		)
		(min_thickness 0.25)
		(keepout
			(tracks not_allowed)
			(vias allowed)
			(pads allowed)
			(copperpour not_allowed)
			(footprints allowed)
		)
		(placement
			(enabled no)
			(sheetname "")
		)
		(fill
			(thermal_gap 0.5)
			(thermal_bridge_width 0.5)
			(island_removal_mode 0)
		)
		(polygon
			(pts
				(arc
					(start 152.999948 -101.089968)
					(mid 155.539948 -98.549968)
					(end 152.999948 -96.009968)
				)
				(arc
					(start 152.999948 -96.009968)
					(mid 150.459948 -98.549968)
					(end 152.999948 -101.089968)
				)
			)
		)
	)
	(zone
		(net "PVDDQ_DEF")
		(layer "B.Cu")
		(hatch none 0.5)
		(connect_pads
			(clearance 0.5)
		)
		(min_thickness 0.25)
		(fill yes
			(thermal_gap 0.5)
			(thermal_bridge_width 0.5)
			(island_removal_mode 0)
		)
		(polygon
			(pts
				(xy 265.929364 -143.643096) (xy 265.678158 -143.894302) (xy 265.678158 -145.960592) (xy 265.979148 -146.261582)
				(xy 277.326598 -146.261582) (xy 277.529036 -146.059144) (xy 277.529036 -143.83131) (xy 277.340822 -143.643096)
			)
		)
		(polygon
			(pts
				(xy 272.518632 -145.4023) (xy 272.315432 -145.4023) (xy 272.315432 -145.6055) (xy 272.518632 -145.6055)
			)
		)
		(polygon
			(pts
				(xy 269.216632 -145.4023) (xy 269.013432 -145.4023) (xy 269.013432 -145.6055) (xy 269.216632 -145.6055)
			)
		)
		(polygon
			(pts
				(xy 266.054332 -145.4023) (xy 265.851132 -145.4023) (xy 265.851132 -145.6055) (xy 266.054332 -145.6055)
			)
		)
		(polygon
			(pts
				(xy 275.657564 -144.4117) (xy 275.454364 -144.4117) (xy 275.454364 -144.6149) (xy 275.657564 -144.6149)
			)
		)
		(polygon
			(pts
				(xy 272.518632 -144.4117) (xy 272.315432 -144.4117) (xy 272.315432 -144.6149) (xy 272.518632 -144.6149)
			)
		)
		(polygon
			(pts
				(xy 269.216632 -144.4117) (xy 269.013432 -144.4117) (xy 269.013432 -144.6149) (xy 269.216632 -144.6149)
			)
		)
	)
	(zone
		(layer "B.Cu")
		(hatch none 0.5)
		(connect_pads
			(clearance 0)
		)
		(min_thickness 0.25)
		(keepout
			(tracks allowed)
			(vias allowed)
			(pads allowed)
			(copperpour allowed)
			(footprints not_allowed)
		)
		(placement
			(enabled no)
			(sheetname "")
		)
		(fill
			(thermal_gap 0.5)
			(thermal_bridge_width 0.5)
			(island_removal_mode 0)
		)
		(polygon
			(pts
				(xy 171.809918 -25.733248) (xy 179.23002 -25.733248)
				(arc
					(start 179.23002 0.555244)
					(mid 177.760683 -1.299941)
					(end 175.50003 -1.999996)
				)
				(arc
					(start 171.99991 -1.999996)
					(mid 171.904887 -1.998837)
					(end 171.809918 -1.995424)
				)
			)
		)
	)
	(zone
		(net "P1V05_PCH_STBY_KR_PLL")
		(layer "B.Cu")
		(hatch none 0.5)
		(connect_pads
			(clearance 0.5)
		)
		(min_thickness 0.25)
		(fill yes
			(thermal_gap 0.5)
			(thermal_bridge_width 0.5)
			(island_removal_mode 0)
		)
		(polygon
			(pts
				(xy 403.164802 -110.500922) (xy 402.591016 -111.074708) (xy 402.472144 -111.193326) (xy 400.713956 -111.193326)
				(xy 400.64563 -111.125) (xy 399.882614 -111.125) (xy 399.535904 -111.47171) (xy 395.05255 -111.47171)
				(xy 394.266928 -110.686088) (xy 393.97686 -110.686088) (xy 393.416282 -111.246666) (xy 392.14044 -111.246666)
				(xy 391.997184 -111.389922) (xy 391.997184 -111.513112) (xy 392.12647 -111.642398) (xy 392.12647 -112.061498)
				(xy 392.12012 -112.061498) (xy 391.981436 -112.200182) (xy 391.981436 -112.418876) (xy 392.08456 -112.522)
				(xy 392.457686 -112.522) (xy 392.535918 -112.443768) (xy 393.41298 -112.443768) (xy 394.030708 -113.061496)
				(xy 394.030708 -113.926366) (xy 394.213334 -114.108992) (xy 403.164548 -114.108992) (xy 404.47087 -112.80267)
				(xy 404.47087 -112.59693) (xy 404.5458 -112.522) (xy 406.528016 -112.522) (xy 406.73401 -112.315752)
				(xy 406.73401 -110.701582) (xy 406.53335 -110.500922)
			)
		)
		(polygon
			(pts
				(xy 401.755356 -111.979456) (xy 401.552156 -111.979456) (xy 401.552156 -112.182656) (xy 401.755356 -112.182656)
			)
		)
		(polygon
			(pts
				(xy 400.993356 -111.979456) (xy 400.790156 -111.979456) (xy 400.790156 -112.182656) (xy 400.993356 -112.182656)
			)
		)
	)
	(zone
		(layer "B.Cu")
		(hatch none 0.5)
		(connect_pads
			(clearance 0)
		)
		(min_thickness 0.25)
		(keepout
			(tracks not_allowed)
			(vias allowed)
			(pads allowed)
			(copperpour not_allowed)
			(footprints allowed)
		)
		(placement
			(enabled no)
			(sheetname "")
		)
		(fill
			(thermal_gap 0.5)
			(thermal_bridge_width 0.5)
			(island_removal_mode 0)
		)
		(polygon
			(pts
				(arc
					(start 56.999886 -78.449932)
					(mid 58.899806 -76.550012)
					(end 56.999886 -74.650092)
				)
				(arc
					(start 56.999886 -74.650092)
					(mid 55.099966 -76.550012)
					(end 56.999886 -78.449932)
				)
			)
		)
	)
	(zone
		(layer "B.Cu")
		(hatch none 0.5)
		(connect_pads
			(clearance 0)
		)
		(min_thickness 0.25)
		(keepout
			(tracks allowed)
			(vias allowed)
			(pads allowed)
			(copperpour allowed)
			(footprints not_allowed)
		)
		(placement
			(enabled no)
			(sheetname "")
		)
		(fill
			(thermal_gap 0.5)
			(thermal_bridge_width 0.5)
			(island_removal_mode 0)
		)
		(polygon
			(pts
				(arc
					(start 234.097068 -33.299908)
					(mid 230.480162 -27.591736)
					(end 226.862894 -33.299908)
				)
			)
		)
	)
	(zone
		(net "GND")
		(layer "B.Cu")
		(hatch none 0.5)
		(connect_pads
			(clearance 0.5)
		)
		(min_thickness 0.25)
		(fill yes
			(thermal_gap 0.5)
			(thermal_bridge_width 0.5)
			(island_removal_mode 0)
		)
		(polygon
			(pts
				(xy 21.602192 3.213608) (xy 20.999704 3.816096) (xy 20.047204 3.816096) (xy 19.6469 4.2164) (xy 15.64386 4.2164)
				(xy 15.31874 3.89128) (xy 15.21968 3.79222) (xy 15.21968 0.70866) (xy 14.859 0.34798) (xy 14.859 -0.531876)
				(xy 15.360142 -1.033018) (xy 20.446746 -1.033018) (xy 21.602192 0.122428)
			)
		)
	)
	(zone
		(net "GND")
		(layer "B.Cu")
		(hatch none 0.5)
		(connect_pads
			(clearance 0.5)
		)
		(min_thickness 0.25)
		(fill yes
			(thermal_gap 0.5)
			(thermal_bridge_width 0.5)
			(island_removal_mode 0)
		)
		(polygon
			(pts
				(xy 177.9778 -89.916) (xy 177.9778 -86.6902) (xy 181.7116 -86.6902) (xy 181.7116 -89.916)
			)
		)
	)
	(zone
		(layer "B.Cu")
		(hatch none 0.5)
		(connect_pads
			(clearance 0)
		)
		(min_thickness 0.25)
		(keepout
			(tracks allowed)
			(vias allowed)
			(pads allowed)
			(copperpour allowed)
			(footprints not_allowed)
		)
		(placement
			(enabled no)
			(sheetname "")
		)
		(fill
			(thermal_gap 0.5)
			(thermal_bridge_width 0.5)
			(island_removal_mode 0)
		)
		(polygon
			(pts
				(arc
					(start -5.999988 -158.100014)
					(mid -5.707095 -158.807119)
					(end -4.99999 -159.100012)
				)
				(arc
					(start 501.000014 -159.100012)
					(mid 501.707119 -158.807119)
					(end 502.000012 -158.100014)
				)
				(arc
					(start 502.000012 -110.87989)
					(mid 501.707119 -110.172785)
					(end 501.000014 -109.879892)
				)
				(arc
					(start 428.209964 -109.879892)
					(mid 427.502859 -109.586999)
					(end 427.209966 -108.879894)
				)
				(arc
					(start 427.209966 -68.879974)
					(mid 427.502859 -68.172869)
					(end 428.209964 -67.879976)
				)
				(arc
					(start 478.48012 -67.879976)
					(mid 479.187225 -67.587083)
					(end 479.480118 -66.879978)
				)
				(arc
					(start 479.480118 -63.680086)
					(mid 479.773011 -62.972981)
					(end 480.480116 -62.680088)
				)
				(arc
					(start 501.000014 -62.680088)
					(mid 501.707119 -62.387195)
					(end 502.000012 -61.68009)
				)
				(arc
					(start 502.000012 -14.99997)
					(mid 501.707119 -14.292865)
					(end 501.000014 -13.999972)
				)
				(arc
					(start 484.35006 -13.999972)
					(mid 483.996597 -13.853563)
					(end 483.849934 -13.5001)
				)
				(arc
					(start 483.849934 2.500122)
					(mid 483.996418 2.853764)
					(end 484.35006 2.999994)
				)
				(arc
					(start 501.000014 2.999994)
					(mid 501.707119 3.292887)
					(end 502.000012 3.999992)
				)
				(arc
					(start 502.000012 4.99999)
					(mid 501.707119 5.707095)
					(end 501.000014 5.999988)
				)
				(arc
					(start -4.99999 5.999988)
					(mid -5.707095 5.707095)
					(end -5.999988 4.99999)
				)
			)
		)
	)
	(zone
		(layer "B.Cu")
		(hatch none 0.5)
		(connect_pads
			(clearance 0)
		)
		(min_thickness 0.25)
		(keepout
			(tracks allowed)
			(vias allowed)
			(pads allowed)
			(copperpour allowed)
			(footprints allowed)
		)
		(placement
			(enabled no)
			(sheetname "")
		)
		(fill
			(thermal_gap 0.5)
			(thermal_bridge_width 0.5)
			(island_removal_mode 0)
		)
		(polygon
			(pts
				(xy 127.339344 -34.97072) (xy 127.339344 -33.897062) (xy 128.340358 -33.897062) (xy 128.340358 -34.97072)
			)
		)
	)
	(zone
		(layer "B.Cu")
		(hatch none 0.5)
		(connect_pads
			(clearance 0)
		)
		(min_thickness 0.25)
		(keepout
			(tracks allowed)
			(vias allowed)
			(pads allowed)
			(copperpour allowed)
			(footprints not_allowed)
		)
		(placement
			(enabled no)
			(sheetname "")
		)
		(fill
			(thermal_gap 0.5)
			(thermal_bridge_width 0.5)
			(island_removal_mode 0)
		)
		(polygon
			(pts
				(xy 163.52012 -16.131794) (xy 22.519894 -16.131794) (xy 22.519894 -19.31289) (xy 163.52012 -19.31289)
			)
		)
	)
	(zone
		(net "GND")
		(layer "B.Cu")
		(hatch none 0.5)
		(connect_pads
			(clearance 0.5)
		)
		(min_thickness 0.25)
		(fill yes
			(thermal_gap 0.5)
			(thermal_bridge_width 0.5)
			(island_removal_mode 0)
		)
		(polygon
			(pts
				(xy 281.22626 -71.586598) (xy 281.109928 -71.70293) (xy 281.109928 -72.579992) (xy 280.919428 -72.770492)
				(xy 278.308816 -72.770492) (xy 278.065738 -73.01357) (xy 278.065738 -74.503788) (xy 278.116792 -74.554588)
				(xy 278.116792 -74.626724) (xy 277.88362 -74.859896) (xy 258.19354 -74.859896) (xy 257.879088 -75.174348)
				(xy 257.879088 -76.551536) (xy 257.894074 -76.566522) (xy 280.757376 -76.566522) (xy 280.918158 -76.727304)
				(xy 280.918158 -79.14259) (xy 281.236674 -79.461106) (xy 281.532584 -79.461106) (xy 281.69108 -79.619602)
				(xy 281.69108 -80.105758) (xy 281.881326 -80.296004) (xy 282.652978 -80.296004) (xy 282.76931 -80.179672)
				(xy 282.76931 -79.39786) (xy 282.61056 -79.23911) (xy 281.796744 -79.23911) (xy 281.638248 -79.080614)
				(xy 281.638248 -71.660512) (xy 281.564334 -71.586598)
			)
		)
		(polygon
			(pts
				(xy 280.836624 -75.423014) (xy 280.633424 -75.423014) (xy 280.633424 -75.626214) (xy 280.836624 -75.626214)
			)
		)
		(polygon
			(pts
				(xy 280.074624 -75.423014) (xy 279.871424 -75.423014) (xy 279.871424 -75.626214) (xy 280.074624 -75.626214)
			)
		)
		(polygon
			(pts
				(xy 280.836624 -73.581514) (xy 280.633424 -73.581514) (xy 280.633424 -73.784714) (xy 280.836624 -73.784714)
			)
		)
		(polygon
			(pts
				(xy 280.074624 -73.581514) (xy 279.871424 -73.581514) (xy 279.871424 -73.784714) (xy 280.074624 -73.784714)
			)
		)
	)
	(zone
		(net "GND")
		(layer "B.Cu")
		(hatch none 0.5)
		(connect_pads
			(clearance 0.5)
		)
		(min_thickness 0.25)
		(fill yes
			(thermal_gap 0.5)
			(thermal_bridge_width 0.5)
			(island_removal_mode 0)
		)
		(polygon
			(pts
				(xy 489.077254 -112.826546) (xy 489.204 -112.6998) (xy 489.204 -110.5154) (xy 489.331 -110.3884)
				(xy 490.601 -110.3884) (xy 491.236 -110.3884) (xy 491.363 -110.5154) (xy 491.363 -113.2586) (xy 490.9566 -113.665)
				(xy 490.3216 -113.665) (xy 490.0676 -113.665) (xy 489.5342 -114.1984) (xy 489.1278 -114.1984) (xy 489.079032 -114.149632)
				(xy 489.077254 -114.147854) (xy 489.077254 -113.500916)
			)
		)
	)
	(zone
		(net "PVCCIO_CPU1")
		(layer "B.Cu")
		(hatch none 0.5)
		(connect_pads
			(clearance 0.5)
		)
		(min_thickness 0.25)
		(fill yes
			(thermal_gap 0.5)
			(thermal_bridge_width 0.5)
			(island_removal_mode 0)
		)
		(polygon
			(pts
				(xy 114.693954 -77.048614) (xy 114.526568 -77.216) (xy 114.526568 -78.6384) (xy 114.9604 -79.072232)
				(xy 114.9604 -80.465168) (xy 115.099592 -80.604614) (xy 115.349782 -80.854804) (xy 117.315488 -80.854804)
				(xy 117.389148 -80.781144) (xy 117.389148 -80.47228) (xy 117.268498 -80.35163) (xy 116.910104 -80.35163)
				(xy 116.369592 -79.811118) (xy 116.369592 -79.715614) (xy 116.115592 -79.715614) (xy 115.599972 -79.199994)
				(xy 115.607592 -79.192628) (xy 115.607592 -78.318614) (xy 115.734592 -78.191614) (xy 115.734592 -77.048614)
			)
		)
		(polygon
			(pts
				(xy 115.074192 -77.709014) (xy 114.870992 -77.709014) (xy 114.870992 -77.912214) (xy 115.074192 -77.912214)
			)
		)
	)
	(zone
		(layer "B.Cu")
		(hatch none 0.5)
		(connect_pads
			(clearance 0)
		)
		(min_thickness 0.25)
		(keepout
			(tracks allowed)
			(vias allowed)
			(pads allowed)
			(copperpour allowed)
			(footprints not_allowed)
		)
		(placement
			(enabled no)
			(sheetname "")
		)
		(fill
			(thermal_gap 0.5)
			(thermal_bridge_width 0.5)
			(island_removal_mode 0)
		)
		(polygon
			(pts
				(arc
					(start 360.499914 -2.00025)
					(mid 364.50016 1.999996)
					(end 360.499914 5.999988)
				)
				(arc
					(start 357.000048 5.999988)
					(mid 353.000056 1.999996)
					(end 357.000048 -2.00025)
				)
			)
		)
	)
	(zone
		(layer "B.Cu")
		(hatch none 0.5)
		(connect_pads
			(clearance 0)
		)
		(min_thickness 0.25)
		(keepout
			(tracks not_allowed)
			(vias allowed)
			(pads allowed)
			(copperpour not_allowed)
			(footprints allowed)
		)
		(placement
			(enabled no)
			(sheetname "")
		)
		(fill
			(thermal_gap 0.5)
			(thermal_bridge_width 0.5)
			(island_removal_mode 0)
		)
		(polygon
			(pts
				(arc
					(start 381.49911 -28.176982)
					(mid 381.11557 -27.793442)
					(end 380.73203 -28.176982)
				)
				(arc
					(start 380.73203 -29.054552)
					(mid 381.1143 -29.43809)
					(end 381.49911 -29.057092)
				)
				(arc
					(start 381.43307 -29.057092)
					(mid 381.11557 -29.372062)
					(end 380.79807 -29.057092)
				)
				(arc
					(start 380.79807 -29.054552)
					(mid 381.11557 -28.737052)
					(end 381.43307 -29.054552)
				)
				(xy 381.49911 -29.054552) (xy 381.49911 -28.179522)
				(arc
					(start 381.38227 -28.179522)
					(mid 381.11557 -28.443694)
					(end 380.84887 -28.179522)
				)
				(arc
					(start 380.84887 -28.176982)
					(mid 381.11557 -27.910282)
					(end 381.38227 -28.176982)
				)
			)
		)
	)
	(zone
		(net "P1V8_PCH_STBY")
		(layer "B.Cu")
		(hatch none 0.5)
		(connect_pads
			(clearance 0.5)
		)
		(min_thickness 0.25)
		(fill yes
			(thermal_gap 0.5)
			(thermal_bridge_width 0.5)
			(island_removal_mode 0)
		)
		(polygon
			(pts
				(xy 410.1592 -128.8288) (xy 409.956 -129.032) (xy 409.956 -130.175) (xy 410.591 -130.81) (xy 410.591 -130.9878)
				(xy 410.718 -131.1148) (xy 411.3276 -131.1148) (xy 411.48 -130.9624) (xy 411.48 -129.032) (xy 411.2768 -128.8288)
			)
		)
		(polygon
			(pts
				(xy 410.6926 -129.6924) (xy 410.4894 -129.6924) (xy 410.4894 -129.8956) (xy 410.6926 -129.8956)
			)
		)
		(polygon
			(pts
				(xy 410.6926 -130.1242) (xy 410.4894 -130.1242) (xy 410.4894 -130.3274) (xy 410.6926 -130.3274)
			)
		)
	)
	(zone
		(net "VR_FET_SW_P12V_STBY_PVPP_DEF")
		(layer "B.Cu")
		(hatch none 0.5)
		(connect_pads
			(clearance 0.5)
		)
		(min_thickness 0.25)
		(fill yes
			(thermal_gap 0.5)
			(thermal_bridge_width 0.5)
			(island_removal_mode 0)
		)
		(polygon
			(pts
				(xy 343.79408 -133.930644) (xy 352.068638 -133.930644) (xy 352.360738 -133.638544) (xy 352.360738 -131.816602)
				(xy 352.226626 -131.68249) (xy 351.064068 -131.68249) (xy 350.085914 -130.704336) (xy 349.765112 -130.704336)
				(xy 347.698568 -130.704336) (xy 346.192094 -132.21081) (xy 343.778332 -132.21081) (xy 343.549478 -132.439664)
				(xy 343.549478 -133.686042)
			)
		)
	)
	(zone
		(layer "B.Cu")
		(hatch none 0.5)
		(connect_pads
			(clearance 0)
		)
		(min_thickness 0.25)
		(keepout
			(tracks allowed)
			(vias allowed)
			(pads allowed)
			(copperpour allowed)
			(footprints allowed)
		)
		(placement
			(enabled no)
			(sheetname "")
		)
		(fill
			(thermal_gap 0.5)
			(thermal_bridge_width 0.5)
			(island_removal_mode 0)
		)
		(polygon
			(pts
				(xy 254.508 -102.880668) (xy 254.508 -126.619) (xy 236.347 -126.619) (xy 236.347 -104.394) (xy 249.047 -101.854)
			)
		)
	)
	(zone
		(layer "B.Cu")
		(hatch none 0.5)
		(connect_pads
			(clearance 0)
		)
		(min_thickness 0.25)
		(keepout
			(tracks not_allowed)
			(vias allowed)
			(pads allowed)
			(copperpour not_allowed)
			(footprints allowed)
		)
		(placement
			(enabled no)
			(sheetname "")
		)
		(fill
			(thermal_gap 0.5)
			(thermal_bridge_width 0.5)
			(island_removal_mode 0)
		)
		(polygon
			(pts
				(arc
					(start 248.000012 -44.090082)
					(mid 250.540012 -41.550082)
					(end 248.000012 -39.010082)
				)
				(arc
					(start 248.000012 -39.010082)
					(mid 245.460012 -41.550082)
					(end 248.000012 -44.090082)
				)
			)
		)
	)
	(zone
		(net "GND")
		(layer "B.Cu")
		(hatch none 0.5)
		(connect_pads
			(clearance 0.5)
		)
		(min_thickness 0.25)
		(fill yes
			(thermal_gap 0.5)
			(thermal_bridge_width 0.5)
			(island_removal_mode 0)
		)
		(polygon
			(pts
				(xy 486.196894 -54.0258) (xy 487.0196 -54.0258) (xy 488.7468 -54.0258) (xy 488.768898 -54.0258)
				(xy 488.845098 -53.9496) (xy 489.149898 -53.6448) (xy 490.0168 -53.6448) (xy 490.0676 -53.6956)
				(xy 490.0676 -54.365144) (xy 488.914694 -55.51805) (xy 485.932988 -55.51805) (xy 485.612694 -55.51805)
				(xy 485.52608 -55.431436) (xy 485.52608 -54.515004) (xy 486.015284 -54.0258)
			)
		)
	)
	(zone
		(layer "B.Cu")
		(hatch none 0.5)
		(connect_pads
			(clearance 0)
		)
		(min_thickness 0.25)
		(keepout
			(tracks not_allowed)
			(vias allowed)
			(pads allowed)
			(copperpour not_allowed)
			(footprints allowed)
		)
		(placement
			(enabled no)
			(sheetname "")
		)
		(fill
			(thermal_gap 0.5)
			(thermal_bridge_width 0.5)
			(island_removal_mode 0)
		)
		(polygon
			(pts
				(arc
					(start 435.300374 -58.996834)
					(mid 431.700432 -55.396892)
					(end 428.10049 -58.996834)
				)
				(arc
					(start 428.10049 -60.59678)
					(mid 431.700432 -64.196722)
					(end 435.300374 -60.59678)
				)
			)
		)
	)
	(zone
		(net "P1V05_PCH_STBY_WM20_PLL")
		(layer "B.Cu")
		(hatch none 0.5)
		(connect_pads
			(clearance 0.5)
		)
		(min_thickness 0.25)
		(fill yes
			(thermal_gap 0.5)
			(thermal_bridge_width 0.5)
			(island_removal_mode 0)
		)
		(polygon
			(pts
				(xy 388.036562 -115.200684) (xy 387.823202 -115.414044) (xy 387.823202 -117.609874) (xy 387.976364 -117.763036)
				(xy 393.36218 -117.763036) (xy 394.57884 -118.979696) (xy 394.57884 -121.31421) (xy 395.11605 -121.85142)
				(xy 396.80261 -121.85142) (xy 398.464786 -123.513596) (xy 400.7358 -123.513596) (xy 401.059396 -123.19)
				(xy 403.7076 -123.19) (xy 404.044404 -123.526804) (xy 404.044404 -124.513086) (xy 404.594568 -125.06325)
				(xy 408.31008 -125.06325) (xy 408.557984 -125.311154) (xy 409.751784 -125.311154) (xy 409.785312 -125.277626)
				(xy 409.785312 -124.238512) (xy 409.586938 -124.040138) (xy 409.586938 -123.070366) (xy 409.48864 -122.972068)
				(xy 407.689304 -122.972068) (xy 407.36139 -122.6439) (xy 405.9555 -122.6439) (xy 405.3586 -122.047)
				(xy 405.3586 -120.523) (xy 404.026116 -119.190516) (xy 401.80641 -119.190516) (xy 400.21002 -117.59438)
				(xy 399.50898 -117.59438) (xy 399.4404 -117.5258) (xy 399.4404 -116.824506) (xy 398.795494 -116.1796)
				(xy 389.519414 -116.1796) (xy 388.540498 -115.200684)
			)
		)
		(polygon
			(pts
				(xy 408.9019 -124.2695) (xy 408.6987 -124.2695) (xy 408.6987 -124.4727) (xy 408.9019 -124.4727)
			)
		)
		(polygon
			(pts
				(xy 408.8003 -123.9012) (xy 408.5971 -123.9012) (xy 408.5971 -124.1044) (xy 408.8003 -124.1044)
			)
		)
		(polygon
			(pts
				(xy 408.8003 -123.1392) (xy 408.5971 -123.1392) (xy 408.5971 -123.3424) (xy 408.8003 -123.3424)
			)
		)
	)
	(zone
		(layer "B.Cu")
		(hatch none 0.5)
		(connect_pads
			(clearance 0)
		)
		(min_thickness 0.25)
		(keepout
			(tracks not_allowed)
			(vias allowed)
			(pads allowed)
			(copperpour not_allowed)
			(footprints allowed)
		)
		(placement
			(enabled no)
			(sheetname "")
		)
		(fill
			(thermal_gap 0.5)
			(thermal_bridge_width 0.5)
			(island_removal_mode 0)
		)
		(polygon
			(pts
				(arc
					(start 358.92867 -157.04439)
					(mid 358.338274 -156.714333)
					(end 357.671624 -156.59989)
				)
				(arc
					(start 357.000048 -156.59989)
					(mid 355.500178 -155.10002)
					(end 357.000048 -153.599896)
				)
				(arc
					(start 357.671624 -153.599896)
					(mid 358.338251 -153.485602)
					(end 358.92867 -153.15565)
				)
				(arc
					(start 358.92867 -153.15565)
					(mid 362.99979 -155.10002)
					(end 358.92867 -157.04439)
				)
			)
		)
	)
	(zone
		(net "GND")
		(layer "B.Cu")
		(hatch none 0.5)
		(connect_pads
			(clearance 0.5)
		)
		(min_thickness 0.25)
		(fill yes
			(thermal_gap 0.5)
			(thermal_bridge_width 0.5)
			(island_removal_mode 0)
		)
		(polygon
			(pts
				(xy 275.1582 3.0734) (xy 277.9014 3.0734) (xy 278.4602 2.5146) (xy 278.4602 1.016) (xy 279.2476 0.2286)
				(xy 284.3784 0.2286) (xy 285.1658 1.016) (xy 285.1658 4.191) (xy 284.7086 4.6482) (xy 275.463 4.6482)
				(xy 275.1582 4.3434)
			)
		)
	)
	(zone
		(net "GND")
		(layer "B.Cu")
		(hatch none 0.5)
		(connect_pads
			(clearance 0.5)
		)
		(min_thickness 0.25)
		(fill yes
			(thermal_gap 0.5)
			(thermal_bridge_width 0.5)
			(island_removal_mode 0)
		)
		(polygon
			(pts
				(xy 394.589 -25.146) (xy 394.589 -24.892) (xy 395.097 -24.384) (xy 395.351 -24.384) (xy 395.859 -23.876)
				(xy 395.859 -22.479) (xy 395.786864 -22.406864) (xy 395.694408 -22.314408) (xy 395.694408 -20.377912)
				(xy 395.722094 -20.350226) (xy 396.202408 -20.350226) (xy 397.03375 -21.181568) (xy 397.03375 -22.00275)
				(xy 397.129 -22.098) (xy 397.129 -22.479) (xy 397.129 -24.257) (xy 396.113 -25.273) (xy 394.716 -25.273)
			)
		)
	)
	(zone
		(net "PVDDQ_ABC")
		(layer "B.Cu")
		(hatch none 0.5)
		(connect_pads
			(clearance 0.5)
		)
		(min_thickness 0.25)
		(fill yes
			(thermal_gap 0.5)
			(thermal_bridge_width 0.5)
			(island_removal_mode 0)
		)
		(polygon
			(pts
				(xy 247.880632 -23.700232) (xy 255.950212 -23.700232) (xy 256.44348 -23.206964) (xy 256.44348 -21.542502)
				(xy 256.237994 -21.337016) (xy 244.977412 -21.337016) (xy 243.600478 -22.71395) (xy 243.600478 -23.0632)
				(xy 243.676678 -23.1394) (xy 246.6086 -23.1394) (xy 247.0658 -22.6822) (xy 247.1166 -22.6822) (xy 247.6246 -23.1902)
				(xy 247.6246 -23.4442)
			)
		)
	)
	(zone
		(layer "B.Cu")
		(hatch none 0.5)
		(connect_pads
			(clearance 0)
		)
		(min_thickness 0.25)
		(keepout
			(tracks not_allowed)
			(vias allowed)
			(pads allowed)
			(copperpour not_allowed)
			(footprints allowed)
		)
		(placement
			(enabled no)
			(sheetname "")
		)
		(fill
			(thermal_gap 0.5)
			(thermal_bridge_width 0.5)
			(island_removal_mode 0)
		)
		(polygon
			(pts
				(arc
					(start 384.672078 -26.782522)
					(mid 384.350913 -26.362551)
					(end 384.770884 -26.683716)
				)
				(xy 384.92303 -26.835862)
				(arc
					(start 384.92303 -26.551382)
					(mid 384.539617 -26.167842)
					(end 384.15595 -26.551128)
				)
				(arc
					(start 384.15595 -27.516328)
					(mid 384.53949 -27.899868)
					(end 384.92303 -27.516328)
				)
				(xy 384.92303 -27.231594)
				(arc
					(start 384.770884 -27.38374)
					(mid 384.350913 -27.704905)
					(end 384.672078 -27.284934)
				)
				(xy 384.872484 -27.084528) (xy 384.92303 -27.084528) (xy 384.92303 -26.982928) (xy 384.872484 -26.982928)
			)
		)
	)
	(zone
		(net "GND")
		(layer "B.Cu")
		(hatch none 0.5)
		(connect_pads
			(clearance 0.5)
		)
		(min_thickness 0.25)
		(fill yes
			(thermal_gap 0.5)
			(thermal_bridge_width 0.5)
			(island_removal_mode 0)
		)
		(polygon
			(pts
				(xy 242.174522 -19.108928) (xy 243.112798 -19.108928) (xy 243.442744 -18.778982) (xy 243.442744 -16.740632)
				(xy 243.08689 -16.384778) (xy 242.200176 -16.384778) (xy 241.837972 -16.746982) (xy 241.173 -17.411954)
				(xy 241.173 -18.8976) (xy 241.374676 -19.099276) (xy 242.165124 -19.099276)
			)
		)
	)
	(zone
		(net "PVDDQ_KLM")
		(layer "B.Cu")
		(hatch none 0.5)
		(connect_pads
			(clearance 0.5)
		)
		(min_thickness 0.25)
		(fill yes
			(thermal_gap 0.5)
			(thermal_bridge_width 0.5)
			(island_removal_mode 0)
		)
		(polygon
			(pts
				(xy 22.38248 -155.28798) (xy 22.38248 -138.61796) (xy 22.38121 -138.61669) (xy 22.38121 -137.69721)
				(xy 21.082 -136.398) (xy 20.4343 -135.7503) (xy 18.8341 -135.7503) (xy 17.87779 -134.79399) (xy 16.43126 -134.79399)
				(xy 15.458948 -135.766302) (xy 15.458948 -156.78277) (xy 15.73657 -157.060392) (xy 16.940276 -157.060392)
				(xy 21.245576 -157.060392) (xy 22.38248 -155.923488)
			)
		)
	)
	(zone
		(layer "B.Cu")
		(hatch none 0.5)
		(connect_pads
			(clearance 0)
		)
		(min_thickness 0.25)
		(keepout
			(tracks allowed)
			(vias allowed)
			(pads allowed)
			(copperpour allowed)
			(footprints not_allowed)
		)
		(placement
			(enabled no)
			(sheetname "")
		)
		(fill
			(thermal_gap 0.5)
			(thermal_bridge_width 0.5)
			(island_removal_mode 0)
		)
		(polygon
			(pts
				(arc
					(start 175.50003 -159.100012)
					(mid 179.500022 -155.10002)
					(end 175.50003 -151.100028)
				)
				(arc
					(start 171.99991 -151.100028)
					(mid 167.999918 -155.10002)
					(end 171.99991 -159.100012)
				)
			)
		)
	)
	(zone
		(layer "B.Cu")
		(hatch none 0.5)
		(connect_pads
			(clearance 0)
		)
		(min_thickness 0.25)
		(keepout
			(tracks allowed)
			(vias allowed)
			(pads allowed)
			(copperpour allowed)
			(footprints not_allowed)
		)
		(placement
			(enabled no)
			(sheetname "")
		)
		(fill
			(thermal_gap 0.5)
			(thermal_bridge_width 0.5)
			(island_removal_mode 0)
		)
		(polygon
			(pts
				(arc
					(start 0.249936 -54.909974)
					(mid -1.999996 -52.660042)
					(end -4.249928 -54.909974)
				)
				(arc
					(start -4.249928 -54.909974)
					(mid -1.999996 -57.159906)
					(end 0.249936 -54.909974)
				)
			)
		)
	)
	(zone
		(layer "B.Cu")
		(hatch none 0.5)
		(connect_pads
			(clearance 0)
		)
		(min_thickness 0.25)
		(keepout
			(tracks not_allowed)
			(vias allowed)
			(pads allowed)
			(copperpour not_allowed)
			(footprints allowed)
		)
		(placement
			(enabled no)
			(sheetname "")
		)
		(fill
			(thermal_gap 0.5)
			(thermal_bridge_width 0.5)
			(island_removal_mode 0)
		)
		(polygon
			(pts
				(xy 348.967806 -60.622434) (xy 348.459806 -60.622434) (xy 348.459806 -61.003434) (xy 348.967806 -61.003434)
			)
		)
	)
	(zone
		(net "GND")
		(layer "B.Cu")
		(hatch none 0.5)
		(connect_pads
			(clearance 0.5)
		)
		(min_thickness 0.25)
		(fill yes
			(thermal_gap 0.5)
			(thermal_bridge_width 0.5)
			(island_removal_mode 0)
		)
		(polygon
			(pts
				(xy 480.511866 -40.09898) (xy 480.511866 -40.776906) (xy 480.872546 -41.137586) (xy 480.872546 -41.911778)
				(xy 480.621848 -42.162476) (xy 480.621848 -44.427648) (xy 481.1776 -44.9834) (xy 481.1776 -45.8216)
				(xy 481.3554 -45.9994) (xy 481.7364 -45.9994) (xy 482.8286 -47.0916) (xy 482.8286 -47.7266) (xy 482.9937 -47.8917)
				(xy 485.8893 -47.8917) (xy 486.41 -48.4124) (xy 487.045 -48.4124) (xy 487.223816 -48.233584) (xy 487.223816 -45.084746)
				(xy 487.541316 -44.767246) (xy 487.541316 -43.301666) (xy 487.379772 -43.140122) (xy 487.379772 -41.991534)
				(xy 487.711242 -41.660064) (xy 487.711242 -40.572182) (xy 487.477054 -40.337994) (xy 486.196132 -40.337994)
				(xy 486.11409 -40.420036) (xy 486.11409 -40.65397) (xy 486.043986 -40.724074) (xy 485.326436 -40.724074)
				(xy 485.260142 -40.65778) (xy 485.260142 -40.470582) (xy 485.034082 -40.244522) (xy 483.5525 -40.244522)
				(xy 483.489 -40.308022) (xy 483.489 -41.0718) (xy 483.1715 -41.3893) (xy 482.7143 -41.3893) (xy 482.3968 -41.0718)
				(xy 482.3968 -40.8051) (xy 482.3968 -40.2336) (xy 481.8126 -39.6494) (xy 481.8126 -39.1287) (xy 481.6983 -39.0144)
				(xy 481.4189 -39.0144) (xy 480.9236 -38.5191) (xy 480.9236 -38.26764) (xy 480.8855 -38.22954) (xy 480.41052 -38.22954)
				(xy 480.32924 -38.31082) (xy 480.32924 -38.88232) (xy 480.60864 -39.16172) (xy 480.60864 -40.002206)
			)
		)
		(polygon
			(pts
				(xy 486.451402 -47.642272) (xy 486.248202 -47.642272) (xy 486.248202 -47.845472) (xy 486.451402 -47.845472)
			)
		)
		(polygon
			(pts
				(xy 486.451402 -47.134272) (xy 486.248202 -47.134272) (xy 486.248202 -47.337472) (xy 486.451402 -47.337472)
			)
		)
		(polygon
			(pts
				(xy 485.7496 -46.6344) (xy 485.5464 -46.6344) (xy 485.5464 -46.8376) (xy 485.7496 -46.8376)
			)
		)
		(polygon
			(pts
				(xy 484.9876 -46.6344) (xy 484.7844 -46.6344) (xy 484.7844 -46.8376) (xy 484.9876 -46.8376)
			)
		)
		(polygon
			(pts
				(xy 486.451402 -46.372272) (xy 486.248202 -46.372272) (xy 486.248202 -46.575472) (xy 486.451402 -46.575472)
			)
		)
		(polygon
			(pts
				(xy 486.451402 -45.864272) (xy 486.248202 -45.864272) (xy 486.248202 -46.067472) (xy 486.451402 -46.067472)
			)
		)
		(polygon
			(pts
				(xy 482.1682 -45.6438) (xy 481.965 -45.6438) (xy 481.965 -45.847) (xy 482.1682 -45.847)
			)
		)
		(polygon
			(pts
				(xy 486.451402 -45.102272) (xy 486.248202 -45.102272) (xy 486.248202 -45.305472) (xy 486.451402 -45.305472)
			)
		)
		(polygon
			(pts
				(xy 482.1682 -44.8818) (xy 481.965 -44.8818) (xy 481.965 -45.085) (xy 482.1682 -45.085)
			)
		)
		(polygon
			(pts
				(xy 486.6005 -42.799) (xy 486.3973 -42.799) (xy 486.3973 -43.0022) (xy 486.6005 -43.0022)
			)
		)
		(polygon
			(pts
				(xy 486.6005 -42.037) (xy 486.3973 -42.037) (xy 486.3973 -42.2402) (xy 486.6005 -42.2402)
			)
		)
		(polygon
			(pts
				(xy 481.8507 -41.8084) (xy 481.6475 -41.8084) (xy 481.6475 -42.0116) (xy 481.8507 -42.0116)
			)
		)
		(polygon
			(pts
				(xy 486.156 -41.4655) (xy 485.9528 -41.4655) (xy 485.9528 -41.6687) (xy 486.156 -41.6687)
			)
		)
		(polygon
			(pts
				(xy 485.394 -41.4655) (xy 485.1908 -41.4655) (xy 485.1908 -41.6687) (xy 485.394 -41.6687)
			)
		)
		(polygon
			(pts
				(xy 481.8507 -41.0464) (xy 481.6475 -41.0464) (xy 481.6475 -41.2496) (xy 481.8507 -41.2496)
			)
		)
	)
	(zone
		(net "PVCCMCP_CPU0")
		(layer "B.Cu")
		(hatch none 0.5)
		(connect_pads
			(clearance 0.5)
		)
		(min_thickness 0.25)
		(fill yes
			(thermal_gap 0.5)
			(thermal_bridge_width 0.5)
			(island_removal_mode 0)
		)
		(polygon
			(pts
				(xy 272.7198 -77.1652) (xy 279.0952 -77.1652) (xy 279.097232 -77.167232) (xy 279.343358 -77.167232)
				(xy 279.389332 -77.213206) (xy 279.389332 -78.206092) (xy 279.261824 -78.3336) (xy 279.019 -78.3336)
				(xy 277.876 -78.3336) (xy 277.749 -78.4606) (xy 277.749 -78.867) (xy 278.003 -79.121) (xy 279.5016 -79.121)
				(xy 279.6286 -79.248) (xy 279.6286 -79.9846) (xy 279.527 -80.0862) (xy 272.8214 -80.0862) (xy 272.7706 -80.0354)
				(xy 272.74774 -80.05826) (xy 269.17396 -80.05826) (xy 268.98981 -79.87411) (xy 268.98981 -78.487524)
				(xy 268.750542 -78.248256) (xy 268.750542 -77.303122) (xy 268.888464 -77.1652)
			)
		)
	)
	(zone
		(layer "B.Cu")
		(hatch none 0.5)
		(connect_pads
			(clearance 0)
		)
		(min_thickness 0.25)
		(keepout
			(tracks allowed)
			(vias allowed)
			(pads allowed)
			(copperpour allowed)
			(footprints not_allowed)
		)
		(placement
			(enabled no)
			(sheetname "")
		)
		(fill
			(thermal_gap 0.5)
			(thermal_bridge_width 0.5)
			(island_removal_mode 0)
		)
		(polygon
			(pts
				(xy 336.810096 5.999988) (xy 336.810096 -25.733248) (xy 330.160122 -25.733248) (xy 330.160122 5.999988)
			)
		)
	)
	(zone
		(net "P3V3_STBY")
		(layer "B.Cu")
		(hatch none 0.5)
		(connect_pads
			(clearance 0.5)
		)
		(min_thickness 0.25)
		(fill yes
			(thermal_gap 0.5)
			(thermal_bridge_width 0.5)
			(island_removal_mode 0)
		)
		(polygon
			(pts
				(xy 379.0188 -87.5538) (xy 382.397 -87.5538) (xy 382.5494 -87.4014) (xy 382.5494 -86.54034) (xy 382.36525 -86.35619)
				(xy 381.91821 -86.35619) (xy 381.2286 -87.0458) (xy 379.095 -87.0458) (xy 378.9934 -87.1474) (xy 378.9934 -87.5284)
			)
		)
	)
	(zone
		(layer "B.Cu")
		(hatch none 0.5)
		(connect_pads
			(clearance 0)
		)
		(min_thickness 0.25)
		(keepout
			(tracks allowed)
			(vias allowed)
			(pads allowed)
			(copperpour allowed)
			(footprints allowed)
		)
		(placement
			(enabled no)
			(sheetname "")
		)
		(fill
			(thermal_gap 0.5)
			(thermal_bridge_width 0.5)
			(island_removal_mode 0)
		)
		(polygon
			(pts
				(xy 253.130812 -26.213816) (xy 253.130812 -50.864516) (xy 254.843534 -52.577238) (xy 284.156404 -52.577238)
				(xy 284.723332 -52.01031) (xy 284.723332 -26.269442) (xy 277.253192 -26.269442) (xy 277.23592 -26.286714)
				(xy 266.915646 -28.862274) (xy 253.77902 -26.21788) (xy 253.144274 -26.215086)
			)
		)
	)
	(zone
		(net "P3V3_STBY")
		(layer "B.Cu")
		(hatch none 0.5)
		(connect_pads
			(clearance 0.5)
		)
		(min_thickness 0.25)
		(fill yes
			(thermal_gap 0.5)
			(thermal_bridge_width 0.5)
			(island_removal_mode 0)
		)
		(polygon
			(pts
				(xy 420.4589 -75.3237) (xy 422.2877 -75.3237) (xy 423.0243 -75.3237) (xy 423.0624 -75.2856) (xy 423.0624 -74.0791)
				(xy 422.8338 -73.8505) (xy 421.513 -73.8505) (xy 421.086534 -73.8505) (xy 420.139876 -72.904096)
				(xy 420.10838 -72.8726) (xy 419.94582 -72.8726) (xy 419.6461 -72.8726) (xy 419.1 -72.8726) (xy 418.8714 -73.1012)
				(xy 418.7952 -73.1774) (xy 418.7952 -73.7235) (xy 418.77615 -73.74255) (xy 418.6682 -73.8505) (xy 418.0713 -73.8505)
				(xy 417.4109 -73.8505) (xy 417.322 -73.9394) (xy 417.322 -74.7776) (xy 417.3347 -74.7903) (xy 418.0459 -75.5015)
				(xy 419.0365 -75.5015) (xy 419.0619 -75.4761) (xy 419.0746 -75.4761) (xy 419.0746 -73.5711) (xy 419.2016 -73.4441)
				(xy 419.7731 -73.4441) (xy 420.1668 -73.8378) (xy 420.1668 -74.676) (xy 420.37 -74.8792) (xy 420.37 -75.2348)
			)
		)
	)
	(zone
		(net "GND")
		(layer "B.Cu")
		(hatch none 0.5)
		(connect_pads
			(clearance 0.5)
		)
		(min_thickness 0.25)
		(fill yes
			(thermal_gap 0.5)
			(thermal_bridge_width 0.5)
			(island_removal_mode 0)
		)
		(polygon
			(pts
				(xy 194.1576 -51.1683) (xy 194.1576 -48.501554) (xy 194.070732 -48.414686) (xy 190.192914 -48.414686)
				(xy 188.2775 -50.3301) (xy 187.833 -50.7746) (xy 187.833 -51.562) (xy 187.198 -52.197) (xy 186.309 -52.197)
				(xy 186.182 -52.324) (xy 186.182 -53.721) (xy 186.309 -53.848) (xy 187.706 -53.848) (xy 187.96 -53.594)
				(xy 187.96 -53.34) (xy 188.087 -53.213) (xy 189.931548 -53.213) (xy 190.308484 -53.589936) (xy 190.308484 -54.89448)
				(xy 190.372746 -54.958742) (xy 191.63411 -54.958742) (xy 191.799718 -54.793134) (xy 191.799718 -53.526182)
				(xy 192.1637 -53.1622) (xy 192.7606 -52.5653)
			)
		)
	)
	(zone
		(layer "B.Cu")
		(hatch none 0.5)
		(connect_pads
			(clearance 0)
		)
		(min_thickness 0.25)
		(keepout
			(tracks allowed)
			(vias allowed)
			(pads allowed)
			(copperpour allowed)
			(footprints allowed)
		)
		(placement
			(enabled no)
			(sheetname "")
		)
		(fill
			(thermal_gap 0.5)
			(thermal_bridge_width 0.5)
			(island_removal_mode 0)
		)
		(polygon
			(pts
				(xy 308.365652 -105.179622) (xy 288.299652 -105.179622) (xy 288.617406 -104.861868) (xy 254.508 -104.861868)
				(xy 252.740668 -106.6292) (xy 250.6218 -106.6292) (xy 247.711468 -103.718868) (xy 236.039406 -103.718868)
				(xy 232.864406 -100.543868) (xy 232.864406 -55.204868) (xy 236.986064 -51.083464) (xy 236.0422 -50.1396)
				(xy 281.432 -50.1396) (xy 281.432 -49.022) (xy 283.845 -49.022) (xy 283.845 -50.1396) (xy 305.9938 -50.1396)
				(xy 310.6928 -54.8386) (xy 310.6928 -64.7446) (xy 311.6072 -65.659) (xy 311.6072 -66.7258) (xy 311.785 -66.9036)
				(xy 311.785 -69.85) (xy 312.547 -69.85) (xy 312.547 -71.247) (xy 310.334406 -71.247) (xy 310.334406 -103.210868)
			)
		)
	)
	(zone
		(net "GND")
		(layer "B.Cu")
		(hatch none 0.5)
		(connect_pads
			(clearance 0.5)
		)
		(min_thickness 0.25)
		(fill yes
			(thermal_gap 0.5)
			(thermal_bridge_width 0.5)
			(island_removal_mode 0)
		)
		(polygon
			(pts
				(xy 422.8211 -72.984868) (xy 422.619678 -72.7837) (xy 421.1701 -72.7837) (xy 420.724076 -72.7837)
				(xy 420.658036 -72.84974) (xy 420.658036 -73.033636) (xy 420.9415 -73.3171) (xy 422.783 -73.3171)
				(xy 422.8211 -73.279)
			)
		)
	)
	(zone
		(layer "B.Cu")
		(hatch none 0.5)
		(connect_pads
			(clearance 0)
		)
		(min_thickness 0.25)
		(keepout
			(tracks allowed)
			(vias allowed)
			(pads allowed)
			(copperpour allowed)
			(footprints allowed)
		)
		(placement
			(enabled no)
			(sheetname "")
		)
		(fill
			(thermal_gap 0.5)
			(thermal_bridge_width 0.5)
			(island_removal_mode 0)
		)
		(polygon
			(pts
				(xy 475.2594 -13.6906) (xy 477.2406 -13.6906) (xy 477.2406 -14.478) (xy 475.2594 -14.478)
			)
		)
	)
	(zone
		(layer "B.Cu")
		(hatch none 0.5)
		(connect_pads
			(clearance 0)
		)
		(min_thickness 0.25)
		(keepout
			(tracks not_allowed)
			(vias allowed)
			(pads allowed)
			(copperpour not_allowed)
			(footprints allowed)
		)
		(placement
			(enabled no)
			(sheetname "")
		)
		(fill
			(thermal_gap 0.5)
			(thermal_bridge_width 0.5)
			(island_removal_mode 0)
		)
		(polygon
			(pts
				(arc
					(start -4.249928 -54.909974)
					(mid -1.999996 -57.159906)
					(end 0.249936 -54.909974)
				)
				(arc
					(start 0.249936 -54.909974)
					(mid -1.999996 -52.660042)
					(end -4.249928 -54.909974)
				)
			)
		)
	)
	(zone
		(layer "B.Cu")
		(hatch none 0.5)
		(connect_pads
			(clearance 0)
		)
		(min_thickness 0.25)
		(keepout
			(tracks not_allowed)
			(vias allowed)
			(pads allowed)
			(copperpour not_allowed)
			(footprints allowed)
		)
		(placement
			(enabled no)
			(sheetname "")
		)
		(fill
			(thermal_gap 0.5)
			(thermal_bridge_width 0.5)
			(island_removal_mode 0)
		)
		(polygon
			(pts
				(xy 346.173806 -60.622434) (xy 345.665806 -60.622434) (xy 345.665806 -61.003434) (xy 346.173806 -61.003434)
			)
		)
	)
	(zone
		(net "PVDDQ_DEF")
		(layer "B.Cu")
		(hatch none 0.5)
		(connect_pads
			(clearance 0.5)
		)
		(min_thickness 0.25)
		(fill yes
			(thermal_gap 0.5)
			(thermal_bridge_width 0.5)
			(island_removal_mode 0)
		)
		(polygon
			(pts
				(xy 258.88696 -148.44776) (xy 258.05892 -149.2758) (xy 257.5687 -149.2758) (xy 257.43916 -149.40534)
				(xy 257.43916 -150.16734) (xy 257.54076 -150.26894) (xy 257.86334 -150.26894) (xy 258.17068 -150.57628)
				(xy 258.17068 -151.02078) (xy 258.191 -151.0411) (xy 258.6863 -151.0411) (xy 259.53466 -150.19274)
				(xy 259.53466 -148.96338) (xy 259.01904 -148.44776)
			)
		)
		(polygon
			(pts
				(xy 258.4323 -150.0632) (xy 258.2291 -150.0632) (xy 258.2291 -150.2664) (xy 258.4323 -150.2664)
			)
		)
		(polygon
			(pts
				(xy 258.4323 -149.3012) (xy 258.2291 -149.3012) (xy 258.2291 -149.5044) (xy 258.4323 -149.5044)
			)
		)
	)
	(zone
		(layer "B.Cu")
		(hatch none 0.5)
		(connect_pads
			(clearance 0)
		)
		(min_thickness 0.25)
		(keepout
			(tracks not_allowed)
			(vias allowed)
			(pads allowed)
			(copperpour not_allowed)
			(footprints allowed)
		)
		(placement
			(enabled no)
			(sheetname "")
		)
		(fill
			(thermal_gap 0.5)
			(thermal_bridge_width 0.5)
			(island_removal_mode 0)
		)
		(polygon
			(pts
				(xy 346.086176 -77.059536) (xy 345.578176 -77.059536) (xy 345.578176 -77.440536) (xy 346.086176 -77.440536)
			)
		)
	)
	(zone
		(net "GND")
		(layer "B.Cu")
		(hatch none 0.5)
		(connect_pads
			(clearance 0.5)
		)
		(min_thickness 0.25)
		(fill yes
			(thermal_gap 0.5)
			(thermal_bridge_width 0.5)
			(island_removal_mode 0)
		)
		(polygon
			(pts
				(xy 406.028652 -116.335556) (xy 405.968708 -116.3955) (xy 405.968708 -117.499638) (xy 405.722074 -117.746272)
				(xy 403.656292 -117.746272) (xy 403.591014 -117.81155) (xy 403.591014 -117.946932) (xy 403.591014 -118.142766)
				(xy 403.427692 -118.306088) (xy 403.231858 -118.306088) (xy 402.86432 -118.306088) (xy 402.7678 -118.402608)
				(xy 402.7678 -118.894098) (xy 402.83892 -118.965218) (xy 406.670002 -118.965218) (xy 406.78989 -118.84533)
				(xy 407.438352 -118.84533) (xy 407.84653 -118.437152) (xy 409.019756 -118.437152) (xy 409.2448 -118.662196)
				(xy 409.2448 -119.9388) (xy 408.92095 -120.26265) (xy 408.92095 -121.50725) (xy 408.992832 -121.579132)
				(xy 409.637992 -121.579132) (xy 410.236924 -120.9802) (xy 412.3182 -120.9802) (xy 412.92018 -120.37822)
				(xy 412.92018 -117.080792) (xy 412.174944 -116.335556)
			)
		)
		(polygon
			(pts
				(xy 408.1526 -117.448584) (xy 407.9494 -117.448584) (xy 407.9494 -117.651784) (xy 408.1526 -117.651784)
			)
		)
		(polygon
			(pts
				(xy 403.7076 -118.5164) (xy 403.5044 -118.5164) (xy 403.5044 -118.7196) (xy 403.7076 -118.7196)
			)
		)
		(polygon
			(pts
				(xy 404.4696 -118.5164) (xy 404.2664 -118.5164) (xy 404.2664 -118.7196) (xy 404.4696 -118.7196)
			)
		)
		(polygon
			(pts
				(xy 404.9776 -118.5164) (xy 404.7744 -118.5164) (xy 404.7744 -118.7196) (xy 404.9776 -118.7196)
			)
		)
		(polygon
			(pts
				(xy 405.7396 -118.5164) (xy 405.5364 -118.5164) (xy 405.5364 -118.7196) (xy 405.7396 -118.7196)
			)
		)
		(polygon
			(pts
				(xy 410.6926 -118.5164) (xy 409.9052 -118.5164) (xy 409.829 -118.5926) (xy 409.829 -118.7704) (xy 410.2354 -119.1768)
				(xy 410.2354 -119.6086) (xy 410.4132 -119.7864) (xy 411.5562 -119.7864) (xy 411.7594 -119.5832)
				(xy 411.7594 -119.2022) (xy 411.5308 -118.9736) (xy 410.8704 -118.9736) (xy 410.7434 -118.8466)
				(xy 410.7434 -118.5672)
			)
		)
	)
	(zone
		(net "GND")
		(layer "B.Cu")
		(hatch none 0.5)
		(connect_pads
			(clearance 0.5)
		)
		(min_thickness 0.25)
		(fill yes
			(thermal_gap 0.5)
			(thermal_bridge_width 0.5)
			(island_removal_mode 0)
		)
		(polygon
			(pts
				(xy 40.823642 -48.551338) (xy 40.823642 -41.465246) (xy 40.428164 -41.069768) (xy 37.839396 -41.069768)
				(xy 37.486336 -41.422828) (xy 37.486336 -48.551338) (xy 37.486844 -48.551338) (xy 37.486844 -48.96358)
				(xy 37.58311 -49.059846) (xy 38.29177 -49.059846) (xy 38.36289 -49.130966) (xy 38.36289 -49.132236)
				(xy 38.596316 -49.365662) (xy 40.40251 -49.365662) (xy 40.823642 -48.94453)
			)
		)
	)
	(zone
		(net "GND")
		(layer "B.Cu")
		(hatch none 0.5)
		(connect_pads
			(clearance 0.5)
		)
		(min_thickness 0.25)
		(fill yes
			(thermal_gap 0.5)
			(thermal_bridge_width 0.5)
			(island_removal_mode 0)
		)
		(polygon
			(pts
				(xy 10.668 -121.5898) (xy 10.668 -120.8532) (xy 10.1981 -120.3833) (xy 6.4008 -120.3833) (xy 5.7531 -121.031)
				(xy 5.7531 -123.2281) (xy 5.8674 -123.3424) (xy 6.7056 -123.3424) (xy 6.8072 -123.2408) (xy 6.8072 -121.666)
				(xy 6.9342 -121.539) (xy 9.1948 -121.539) (xy 9.2964 -121.6406) (xy 9.2964 -122.8344) (xy 9.4234 -122.9614)
				(xy 10.286238 -122.9614) (xy 10.668 -122.579638)
			)
		)
	)
	(zone
		(layer "B.Cu")
		(hatch none 0.5)
		(connect_pads
			(clearance 0)
		)
		(min_thickness 0.25)
		(keepout
			(tracks not_allowed)
			(vias allowed)
			(pads allowed)
			(copperpour not_allowed)
			(footprints allowed)
		)
		(placement
			(enabled no)
			(sheetname "")
		)
		(fill
			(thermal_gap 0.5)
			(thermal_bridge_width 0.5)
			(island_removal_mode 0)
		)
		(polygon
			(pts
				(arc
					(start 384.92049 -34.154618)
					(mid 384.66395 -34.348416)
					(end 384.40741 -34.154618)
				)
				(arc
					(start 384.40741 -34.859976)
					(mid 384.66395 -34.729492)
					(end 384.92049 -34.859976)
				)
			)
		)
	)
	(zone
		(layer "B.Cu")
		(hatch none 0.5)
		(connect_pads
			(clearance 0)
		)
		(min_thickness 0.25)
		(keepout
			(tracks not_allowed)
			(vias allowed)
			(pads allowed)
			(copperpour not_allowed)
			(footprints allowed)
		)
		(placement
			(enabled no)
			(sheetname "")
		)
		(fill
			(thermal_gap 0.5)
			(thermal_bridge_width 0.5)
			(island_removal_mode 0)
		)
		(polygon
			(pts
				(arc
					(start 453.348344 -53.621686)
					(mid 452.928373 -53.942851)
					(end 453.249538 -53.52288)
				)
				(xy 453.401684 -53.370734)
				(arc
					(start 453.11695 -53.370734)
					(mid 452.73341 -53.754274)
					(end 453.11695 -54.137814)
				)
				(arc
					(start 454.386696 -54.137814)
					(mid 454.77049 -53.754401)
					(end 454.38695 -53.370734)
				)
				(xy 454.102216 -53.370734)
				(arc
					(start 454.254362 -53.52288)
					(mid 454.575527 -53.942851)
					(end 454.155556 -53.621686)
				)
				(xy 453.904604 -53.370734) (xy 453.599296 -53.370734)
			)
		)
	)
	(zone
		(net "GND")
		(layer "B.Cu")
		(hatch none 0.5)
		(connect_pads
			(clearance 0.5)
		)
		(min_thickness 0.25)
		(fill yes
			(thermal_gap 0.5)
			(thermal_bridge_width 0.5)
			(island_removal_mode 0)
		)
		(polygon
			(pts
				(xy 77.195172 -9.496806) (xy 78.133448 -9.496806) (xy 78.463394 -9.16686) (xy 78.463394 -7.12851)
				(xy 78.10754 -6.772656) (xy 77.220826 -6.772656) (xy 76.858622 -7.13486) (xy 76.2 -7.793482) (xy 76.2 -9.2964)
				(xy 76.399644 -9.496044) (xy 77.194156 -9.496044)
			)
		)
	)
	(zone
		(layer "B.Cu")
		(hatch none 0.5)
		(connect_pads
			(clearance 0)
		)
		(min_thickness 0.25)
		(keepout
			(tracks not_allowed)
			(vias allowed)
			(pads allowed)
			(copperpour not_allowed)
			(footprints allowed)
		)
		(placement
			(enabled no)
			(sheetname "")
		)
		(fill
			(thermal_gap 0.5)
			(thermal_bridge_width 0.5)
			(island_removal_mode 0)
		)
		(polygon
			(pts
				(xy 457.7588 -51.848258) (xy 457.2508 -51.848258) (xy 457.2508 -52.229258) (xy 457.7588 -52.229258)
			)
		)
	)
	(zone
		(net "PVDDQ_KLM")
		(layer "B.Cu")
		(hatch none 0.5)
		(connect_pads
			(clearance 0.5)
		)
		(min_thickness 0.25)
		(fill yes
			(thermal_gap 0.5)
			(thermal_bridge_width 0.5)
			(island_removal_mode 0)
		)
		(polygon
			(pts
				(xy 100.928932 -134.041896) (xy 100.677726 -134.293102) (xy 100.677726 -136.359392) (xy 100.978716 -136.660382)
				(xy 112.326166 -136.660382) (xy 112.528604 -136.457944) (xy 112.528604 -134.23011) (xy 112.34039 -134.041896)
			)
		)
		(polygon
			(pts
				(xy 111.038132 -135.8011) (xy 110.834932 -135.8011) (xy 110.834932 -136.0043) (xy 111.038132 -136.0043)
			)
		)
		(polygon
			(pts
				(xy 107.5182 -135.8011) (xy 107.315 -135.8011) (xy 107.315 -136.0043) (xy 107.5182 -136.0043)
			)
		)
		(polygon
			(pts
				(xy 104.2162 -135.8011) (xy 104.013 -135.8011) (xy 104.013 -136.0043) (xy 104.2162 -136.0043)
			)
		)
		(polygon
			(pts
				(xy 111.038132 -134.8105) (xy 110.834932 -134.8105) (xy 110.834932 -135.0137) (xy 111.038132 -135.0137)
			)
		)
		(polygon
			(pts
				(xy 107.5182 -134.8105) (xy 107.315 -134.8105) (xy 107.315 -135.0137) (xy 107.5182 -135.0137)
			)
		)
		(polygon
			(pts
				(xy 104.2162 -134.8105) (xy 104.013 -134.8105) (xy 104.013 -135.0137) (xy 104.2162 -135.0137)
			)
		)
	)
	(zone
		(layer "B.Cu")
		(hatch none 0.5)
		(connect_pads
			(clearance 0)
		)
		(min_thickness 0.25)
		(keepout
			(tracks allowed)
			(vias allowed)
			(pads allowed)
			(copperpour allowed)
			(footprints not_allowed)
		)
		(placement
			(enabled no)
			(sheetname "")
		)
		(fill
			(thermal_gap 0.5)
			(thermal_bridge_width 0.5)
			(island_removal_mode 0)
		)
		(polygon
			(pts
				(arc
					(start 130.795014 -90.199972)
					(mid 131.254624 -90.009596)
					(end 131.445 -89.549986)
				)
				(arc
					(start 131.445 -85.199982)
					(mid 131.254624 -84.740372)
					(end 130.795014 -84.549996)
				)
				(arc
					(start 129.094992 -84.549996)
					(mid 128.635382 -84.740372)
					(end 128.445006 -85.199982)
				)
				(arc
					(start 128.445006 -89.549986)
					(mid 128.635382 -90.009596)
					(end 129.094992 -90.199972)
				)
			)
		)
	)
	(zone
		(layer "B.Cu")
		(hatch none 0.5)
		(connect_pads
			(clearance 0)
		)
		(min_thickness 0.25)
		(keepout
			(tracks not_allowed)
			(vias allowed)
			(pads allowed)
			(copperpour not_allowed)
			(footprints allowed)
		)
		(placement
			(enabled no)
			(sheetname "")
		)
		(fill
			(thermal_gap 0.5)
			(thermal_bridge_width 0.5)
			(island_removal_mode 0)
		)
		(polygon
			(pts
				(xy 395.50086 -34.900616)
				(arc
					(start 395.50086 -34.985452)
					(mid 395.511611 -34.954839)
					(end 395.526006 -34.925762)
				)
			)
		)
	)
	(zone
		(layer "B.Cu")
		(hatch none 0.5)
		(connect_pads
			(clearance 0)
		)
		(min_thickness 0.25)
		(keepout
			(tracks allowed)
			(vias allowed)
			(pads allowed)
			(copperpour allowed)
			(footprints not_allowed)
		)
		(placement
			(enabled no)
			(sheetname "")
		)
		(fill
			(thermal_gap 0.5)
			(thermal_bridge_width 0.5)
			(island_removal_mode 0)
		)
		(polygon
			(pts
				(arc
					(start 131.445 -63.550038)
					(mid 131.254624 -63.090428)
					(end 130.795014 -62.900052)
				)
				(arc
					(start 129.094992 -62.900052)
					(mid 128.635382 -63.090428)
					(end 128.445006 -63.550038)
				)
				(arc
					(start 128.445006 -67.900042)
					(mid 128.635382 -68.359652)
					(end 129.094992 -68.550028)
				)
				(arc
					(start 130.795014 -68.550028)
					(mid 131.254624 -68.359652)
					(end 131.445 -67.900042)
				)
			)
		)
	)
	(zone
		(net "P5V_TPS2061")
		(layer "B.Cu")
		(hatch none 0.5)
		(connect_pads
			(clearance 0.5)
		)
		(min_thickness 0.25)
		(fill yes
			(thermal_gap 0.5)
			(thermal_bridge_width 0.5)
			(island_removal_mode 0)
		)
		(polygon
			(pts
				(xy 464.7946 -128.6764) (xy 465.2518 -128.6764) (xy 465.2518 -122.7074) (xy 464.6422 -122.0978)
				(xy 463.5754 -122.0978) (xy 463.3468 -122.3264) (xy 463.3468 -123.2662) (xy 463.804 -123.7234) (xy 463.804 -127.1778)
				(xy 463.9945 -127.3683) (xy 464.2866 -127.3683) (xy 464.6168 -127.6985) (xy 464.6168 -128.4986)
			)
		)
	)
	(zone
		(net "GND")
		(layer "B.Cu")
		(hatch none 0.5)
		(connect_pads
			(clearance 0.5)
		)
		(min_thickness 0.25)
		(fill yes
			(thermal_gap 0.5)
			(thermal_bridge_width 0.5)
			(island_removal_mode 0)
		)
		(polygon
			(pts
				(xy 413.475932 -36.265612) (xy 413.438848 -36.228528) (xy 412.926022 -36.228528) (xy 412.233872 -36.228528)
				(xy 412.1404 -36.322) (xy 412.1404 -36.8046) (xy 412.287212 -36.951412) (xy 412.907734 -36.951412)
				(xy 414.202372 -36.951412) (xy 414.39592 -37.14496) (xy 414.74644 -37.14496) (xy 415.111184 -37.509704)
				(xy 415.565844 -37.509704) (xy 415.66338 -37.509704) (xy 415.66338 -36.92144) (xy 415.816288 -36.768532)
				(xy 416.23107 -36.768532) (xy 416.392106 -36.768532) (xy 416.4711 -36.689284) (xy 416.4711 -36.6395)
				(xy 416.4711 -36.393374) (xy 416.343338 -36.265612)
			)
		)
	)
	(zone
		(layer "B.Cu")
		(hatch none 0.5)
		(connect_pads
			(clearance 0)
		)
		(min_thickness 0.25)
		(keepout
			(tracks not_allowed)
			(vias allowed)
			(pads allowed)
			(copperpour not_allowed)
			(footprints allowed)
		)
		(placement
			(enabled no)
			(sheetname "")
		)
		(fill
			(thermal_gap 0.5)
			(thermal_bridge_width 0.5)
			(island_removal_mode 0)
		)
		(polygon
			(pts
				(xy 443.33795 -125.707902) (xy 443.33795 -126.000256) (xy 443.182756 -126.15545)
				(arc
					(start 443.011052 -126.15545)
					(mid 442.487135 -126.0856)
					(end 443.011052 -126.01575)
				)
				(xy 443.124844 -126.01575) (xy 443.19825 -125.942344) (xy 443.19825 -125.70206)
				(arc
					(start 442.754004 -125.70206)
					(mid 442.37021 -126.085473)
					(end 442.75375 -126.46914)
				)
				(arc
					(start 444.02375 -126.46914)
					(mid 444.40729 -126.0856)
					(end 444.02375 -125.70206)
				)
				(xy 443.57925 -125.70206) (xy 443.57925 -125.942344) (xy 443.652656 -126.01575)
				(arc
					(start 443.766448 -126.01575)
					(mid 444.290365 -126.0856)
					(end 443.766448 -126.15545)
				)
				(xy 443.594744 -126.15545) (xy 443.43955 -126.000256) (xy 443.43955 -125.70206) (xy 443.341252 -125.70206)
			)
		)
	)
	(zone
		(net "PVCCIO_CPU0")
		(layer "B.Cu")
		(hatch none 0.5)
		(connect_pads
			(clearance 0.5)
		)
		(min_thickness 0.25)
		(fill yes
			(thermal_gap 0.5)
			(thermal_bridge_width 0.5)
			(island_removal_mode 0)
		)
		(polygon
			(pts
				(xy 284.734 -101.092) (xy 291.719 -101.092) (xy 292.186868 -101.559868) (xy 295.125902 -101.559868)
				(xy 295.656254 -102.09022) (xy 295.95064 -102.09022) (xy 296.449242 -102.588822) (xy 296.831004 -102.588822)
				(xy 296.86504 -102.588822) (xy 297.364404 -102.089458) (xy 297.67403 -102.089458) (xy 298.170346 -102.585774)
				(xy 298.203366 -102.585774) (xy 298.634404 -102.585774) (xy 299.26026 -103.21163) (xy 303.18837 -103.21163)
				(xy 306.578 -99.822) (xy 306.578 -97.409) (xy 306.578 -93.6879) (xy 306.578 -87.617046) (xy 305.73853 -86.777576)
				(xy 305.67757 -86.716616) (xy 305.481482 -86.520528) (xy 305.125882 -86.520528) (xy 305.09464 -86.489286)
				(xy 304.8762 -86.270846) (xy 304.8762 -83.079844) (xy 304.8762 -82.267552) (xy 304.754788 -82.14614)
				(xy 304.679096 -82.070448) (xy 304.212752 -82.070448) (xy 303.976024 -81.83372) (xy 303.67986 -81.537556)
				(xy 303.375314 -81.537556) (xy 303.144428 -81.30667) (xy 303.144428 -80.437736) (xy 296.181272 -73.47458)
				(xy 290.2585 -73.47458) (xy 289.45586 -72.67194) (xy 287.11906 -72.67194) (xy 285.9024 -73.8886)
				(xy 285.9024 -73.9521) (xy 285.9024 -76.10221) (xy 286.291274 -76.491084) (xy 286.629602 -76.491084)
				(xy 287.127188 -76.98867) (xy 287.405318 -76.98867) (xy 288.544 -78.127352) (xy 288.544 -78.486)
				(xy 288.544 -80.655922) (xy 288.761932 -80.873854) (xy 288.761932 -81.469738) (xy 288.544 -81.68767)
				(xy 288.544 -86.995) (xy 284.226 -91.313) (xy 284.226 -100.584)
			)
		)
	)
	(zone
		(net "GND")
		(layer "B.Cu")
		(hatch none 0.5)
		(connect_pads
			(clearance 0.5)
		)
		(min_thickness 0.25)
		(fill yes
			(thermal_gap 0.5)
			(thermal_bridge_width 0.5)
			(island_removal_mode 0)
		)
		(polygon
			(pts
				(xy 463.89036 -40.25138) (xy 466.79612 -40.25138) (xy 466.87994 -40.16756) (xy 466.87994 -38.88232)
				(xy 466.67928 -38.68166) (xy 465.48548 -38.68166) (xy 464.8327 -39.33444) (xy 463.94116 -39.33444)
				(xy 463.82432 -39.45128) (xy 463.82432 -40.18534)
			)
		)
	)
	(zone
		(net "GND")
		(layer "B.Cu")
		(hatch none 0.5)
		(connect_pads
			(clearance 0.5)
		)
		(min_thickness 0.25)
		(fill yes
			(thermal_gap 0.5)
			(thermal_bridge_width 0.5)
			(island_removal_mode 0)
		)
		(polygon
			(pts
				(xy 165.6842 -85.0392) (xy 168.0972 -85.0392) (xy 168.402 -84.7344) (xy 172.4152 -84.7344) (xy 172.6438 -84.963)
				(xy 173.101 -84.963) (xy 173.2153 -84.8487) (xy 173.2153 -78.4987) (xy 173.2153 -78.2701) (xy 172.72 -77.7748)
				(xy 172.4914 -77.7748) (xy 166.5732 -77.7748) (xy 166.0906 -77.7748) (xy 165.608 -78.2574) (xy 165.608 -78.74)
				(xy 165.608 -84.963)
			)
		)
	)
	(zone
		(layer "B.Cu")
		(hatch none 0.5)
		(connect_pads
			(clearance 0)
		)
		(min_thickness 0.25)
		(keepout
			(tracks not_allowed)
			(vias allowed)
			(pads allowed)
			(copperpour not_allowed)
			(footprints allowed)
		)
		(placement
			(enabled no)
			(sheetname "")
		)
		(fill
			(thermal_gap 0.5)
			(thermal_bridge_width 0.5)
			(island_removal_mode 0)
		)
		(polygon
			(pts
				(arc
					(start 419.704266 -154.7368)
					(mid 419.320726 -154.35326)
					(end 418.937186 -154.7368)
				)
				(arc
					(start 418.937186 -156.006546)
					(mid 419.320599 -156.39034)
					(end 419.704266 -156.0068)
				)
				(xy 419.704266 -155.575)
				(arc
					(start 419.435026 -155.575)
					(mid 419.403595 -155.588019)
					(end 419.390576 -155.61945)
				)
				(arc
					(start 419.390576 -155.697174)
					(mid 419.320726 -156.324207)
					(end 419.250876 -155.697174)
				)
				(xy 419.250876 -155.590494)
				(arc
					(start 419.25367 -155.5877)
					(mid 419.304838 -155.489262)
					(end 419.403276 -155.438094)
				)
				(xy 419.40607 -155.4353) (xy 419.704266 -155.4353) (xy 419.704266 -155.3337) (xy 419.40607 -155.3337)
				(arc
					(start 419.403276 -155.330906)
					(mid 419.304838 -155.279738)
					(end 419.25367 -155.1813)
				)
				(xy 419.250876 -155.178506)
				(arc
					(start 419.250876 -155.046426)
					(mid 419.320726 -154.419393)
					(end 419.390576 -155.046426)
				)
				(arc
					(start 419.390576 -155.14955)
					(mid 419.403595 -155.180981)
					(end 419.435026 -155.194)
				)
				(xy 419.704266 -155.194)
			)
		)
	)
	(zone
		(layer "B.Cu")
		(hatch none 0.5)
		(connect_pads
			(clearance 0)
		)
		(min_thickness 0.25)
		(keepout
			(tracks allowed)
			(vias allowed)
			(pads allowed)
			(copperpour allowed)
			(footprints not_allowed)
		)
		(placement
			(enabled no)
			(sheetname "")
		)
		(fill
			(thermal_gap 0.5)
			(thermal_bridge_width 0.5)
			(island_removal_mode 0)
		)
		(polygon
			(pts
				(arc
					(start 222.000064 -74.010012)
					(mid 219.460064 -76.550012)
					(end 222.000064 -79.090012)
				)
				(arc
					(start 222.000064 -79.090012)
					(mid 224.540064 -76.550012)
					(end 222.000064 -74.010012)
				)
			)
		)
	)
	(zone
		(layer "B.Cu")
		(hatch none 0.5)
		(connect_pads
			(clearance 0.5)
		)
		(min_thickness 0.25)
		(fill
			(thermal_gap 0.5)
			(thermal_bridge_width 0.5)
			(island_removal_mode 0)
		)
		(polygon
			(pts
				(xy 33.1724 -80.326484) (xy 32.553402 -80.326484) (xy 32.311594 -80.568292) (xy 32.311594 -81.653888)
				(xy 32.172402 -81.79308) (xy 31.770574 -81.79308) (xy 31.588202 -81.975452) (xy 31.588202 -82.901536)
				(xy 30.834838 -83.6549) (xy 30.657292 -83.832446) (xy 30.657292 -84.941918) (xy 30.856174 -85.1408)
				(xy 33.1724 -85.1408) (xy 33.2994 -85.0138) (xy 33.2994 -80.453484)
			)
		)
	)
	(zone
		(layer "B.Cu")
		(hatch none 0.5)
		(connect_pads
			(clearance 0)
		)
		(min_thickness 0.25)
		(keepout
			(tracks allowed)
			(vias allowed)
			(pads allowed)
			(copperpour allowed)
			(footprints not_allowed)
		)
		(placement
			(enabled no)
			(sheetname "")
		)
		(fill
			(thermal_gap 0.5)
			(thermal_bridge_width 0.5)
			(island_removal_mode 0)
		)
		(polygon
			(pts
				(arc
					(start 152.999948 -52.649882)
					(mid 151.099774 -54.550056)
					(end 152.999948 -56.449976)
				)
				(arc
					(start 152.999948 -56.449976)
					(mid 154.899868 -54.550056)
					(end 152.999948 -52.649882)
				)
			)
		)
	)
	(zone
		(layer "B.Cu")
		(hatch none 0.5)
		(connect_pads
			(clearance 0)
		)
		(min_thickness 0.25)
		(keepout
			(tracks not_allowed)
			(vias allowed)
			(pads allowed)
			(copperpour not_allowed)
			(footprints allowed)
		)
		(placement
			(enabled no)
			(sheetname "")
		)
		(fill
			(thermal_gap 0.5)
			(thermal_bridge_width 0.5)
			(island_removal_mode 0)
		)
		(polygon
			(pts
				(arc
					(start 175.50003 -159.100012)
					(mid 179.500022 -155.10002)
					(end 175.50003 -151.100028)
				)
				(arc
					(start 171.99991 -151.100028)
					(mid 167.999918 -155.10002)
					(end 171.99991 -159.100012)
				)
			)
		)
	)
	(zone
		(net "GND")
		(layer "B.Cu")
		(hatch none 0.5)
		(connect_pads
			(clearance 0.5)
		)
		(min_thickness 0.25)
		(fill yes
			(thermal_gap 0.5)
			(thermal_bridge_width 0.5)
			(island_removal_mode 0)
		)
		(polygon
			(pts
				(xy 93.393768 -80.839056) (xy 96.490536 -80.839056) (xy 96.585786 -80.743806) (xy 96.585786 -79.63408)
				(xy 96.088962 -79.137256) (xy 93.108526 -79.137256) (xy 92.981526 -79.010256) (xy 92.833698 -79.010256)
				(xy 92.72778 -79.116174) (xy 92.72778 -80.173068)
			)
		)
	)
	(zone
		(net "P1V2_AUX_BMC")
		(layer "B.Cu")
		(hatch none 0.5)
		(connect_pads
			(clearance 0.5)
		)
		(min_thickness 0.25)
		(fill yes
			(thermal_gap 0.5)
			(thermal_bridge_width 0.5)
			(island_removal_mode 0)
		)
		(polygon
			(pts
				(xy 441.579 -24.0284) (xy 441.4266 -24.1808) (xy 441.4266 -25.1714) (xy 441.6552 -25.4) (xy 443.738 -25.4)
				(xy 443.8015 -25.4635) (xy 444.1825 -25.4635) (xy 445.8081 -27.0891) (xy 447.4337 -27.0891) (xy 447.9417 -27.5971)
				(xy 447.9417 -29.8069) (xy 447.9798 -29.845) (xy 448.41414 -29.845) (xy 448.655694 -30.086554) (xy 448.655694 -32.098742)
				(xy 448.655694 -37.453824) (xy 448.396868 -37.71265) (xy 448.396868 -41.455848) (xy 446.25006 -43.602656)
				(xy 436.350664 -43.602656) (xy 436.095648 -43.34764) (xy 436.095648 -41.888918) (xy 435.955186 -41.748456)
				(xy 435.199028 -41.748456) (xy 435.162706 -41.784778) (xy 435.162706 -44.181522) (xy 436.056532 -45.075348)
				(xy 437.818022 -45.075348) (xy 438.380124 -44.513246) (xy 438.380124 -44.50207) (xy 438.396888 -44.485306)
				(xy 443.572646 -44.485306) (xy 444.104522 -45.017182) (xy 444.53302 -45.017182) (xy 444.673482 -44.87672)
				(xy 444.673482 -44.646342) (xy 444.943484 -44.37634) (xy 447.460624 -44.37634) (xy 451.86219 -44.37634)
				(xy 452.4883 -43.75023) (xy 452.4883 -42.714418) (xy 452.4883 -41.882568) (xy 452.4883 -39.348664)
				(xy 452.4883 -32.418274) (xy 452.132192 -32.062166) (xy 452.132192 -30.762448) (xy 451.884542 -30.514798)
				(xy 451.235318 -29.865574) (xy 450.624448 -29.254704) (xy 449.841366 -29.254704) (xy 449.235068 -28.648406)
				(xy 449.235068 -27.478228) (xy 447.52514 -25.7683) (xy 447.52514 -24.74214) (xy 446.9003 -24.1173)
				(xy 445.7827 -24.1173) (xy 445.6938 -24.0284)
			)
		)
	)
	(zone
		(layer "B.Cu")
		(hatch none 0.5)
		(connect_pads
			(clearance 0)
		)
		(min_thickness 0.25)
		(keepout
			(tracks allowed)
			(vias allowed)
			(pads allowed)
			(copperpour allowed)
			(footprints not_allowed)
		)
		(placement
			(enabled no)
			(sheetname "")
		)
		(fill
			(thermal_gap 0.5)
			(thermal_bridge_width 0.5)
			(island_removal_mode 0)
		)
		(polygon
			(pts
				(arc
					(start 58.040016 -84.549996)
					(mid 57.332911 -84.842889)
					(end 57.040018 -85.549994)
				)
				(arc
					(start 57.040018 -92.689934)
					(mid 57.332911 -93.397039)
					(end 58.040016 -93.689932)
				)
				(arc
					(start 63.66002 -93.689932)
					(mid 64.367125 -93.397039)
					(end 64.660018 -92.689934)
				)
				(arc
					(start 64.660018 -85.549994)
					(mid 64.367125 -84.842889)
					(end 63.66002 -84.549996)
				)
			)
		)
	)
	(zone
		(net "P5V")
		(layer "B.Cu")
		(hatch none 0.5)
		(connect_pads
			(clearance 0.5)
		)
		(min_thickness 0.25)
		(fill yes
			(thermal_gap 0.5)
			(thermal_bridge_width 0.5)
			(island_removal_mode 0)
		)
		(polygon
			(pts
				(xy 466.217 -125.857) (xy 468.249 -125.857) (xy 468.503 -125.603) (xy 468.503 -124.714) (xy 468.122 -124.333)
				(xy 466.1916 -124.333) (xy 466.0392 -124.4854) (xy 466.0392 -125.6792)
			)
		)
	)
	(zone
		(net "GND")
		(layer "B.Cu")
		(hatch none 0.5)
		(connect_pads
			(clearance 0.5)
		)
		(min_thickness 0.25)
		(fill yes
			(thermal_gap 0.5)
			(thermal_bridge_width 0.5)
			(island_removal_mode 0)
		)
		(polygon
			(pts
				(xy 455.1426 -42.57294) (xy 456.79614 -42.57294) (xy 457.04252 -42.32656) (xy 457.04252 -41.06926)
				(xy 456.90536 -40.9321) (xy 455.18832 -40.9321) (xy 455.01814 -41.10228) (xy 455.01814 -42.44848)
			)
		)
	)
	(zone
		(layer "B.Cu")
		(hatch none 0.5)
		(connect_pads
			(clearance 0)
		)
		(min_thickness 0.25)
		(keepout
			(tracks allowed)
			(vias allowed)
			(pads allowed)
			(copperpour allowed)
			(footprints not_allowed)
		)
		(placement
			(enabled no)
			(sheetname "")
		)
		(fill
			(thermal_gap 0.5)
			(thermal_bridge_width 0.5)
			(island_removal_mode 0)
		)
		(polygon
			(pts
				(arc
					(start 127 -113.450116)
					(mid 128.89992 -111.550196)
					(end 127 -109.650022)
				)
				(arc
					(start 127 -109.650022)
					(mid 125.099826 -111.550196)
					(end 127 -113.450116)
				)
			)
		)
	)
	(zone
		(net "GND")
		(layer "B.Cu")
		(hatch none 0.5)
		(connect_pads
			(clearance 0.5)
		)
		(min_thickness 0.25)
		(fill yes
			(thermal_gap 0.5)
			(thermal_bridge_width 0.5)
			(island_removal_mode 0)
		)
		(polygon
			(pts
				(xy -5.03174 15.24) (xy -5.03174 8.763) (xy 413.4358 8.763) (xy 501.2182 8.763) (xy 501.2182 8.7884)
				(xy 501.2182 15.24)
			)
		)
		(polygon
			(pts
				(xy 189.6618 14.5288) (xy 142.7734 14.5288) (xy 142.7734 9.4742) (xy 189.6618 9.4742) (xy 189.6618 9.4996)
				(xy 196.6976 9.4996) (xy 198.0438 9.4996) (xy 198.934578 9.4996) (xy 198.934578 14.5034) (xy 198.0438 14.5034)
				(xy 196.6976 14.5034) (xy 189.6618 14.5034)
			)
		)
		(polygon
			(pts
				(xy 100.1776 14.61262) (xy 34.544 14.61262) (xy 34.544 9.4742) (xy 36.957 9.4742) (xy 36.957 9.9187)
				(xy 100.838 9.9187) (xy 100.838 9.9314) (xy 110.6678 9.9314) (xy 113.1824 9.9314) (xy 113.5126 9.9314)
				(xy 114.39652 9.9314) (xy 114.39652 14.605) (xy 113.5126 14.605) (xy 110.6678 14.605) (xy 100.1776 14.605)
			)
		)
		(polygon
			(pts
				(xy 367.853722 9.4742) (xy 416.3568 9.4742) (xy 418.8714 9.4742) (xy 424.283632 9.4742) (xy 424.283632 14.5288)
				(xy 418.8714 14.5288) (xy 416.3568 14.5288) (xy 367.853722 14.5288)
			)
		)
		(polygon
			(pts
				(xy 273.4818 14.5034) (xy 227.0506 14.5034) (xy 227.0506 9.4234) (xy 273.4818 9.4234) (xy 283.28239 9.4234)
				(xy 283.28239 14.5034) (xy 281.8638 14.5034) (xy 281.14752 14.5034) (xy 281.145996 14.5034)
			)
		)
	)
	(zone
		(net "PVDDQ_ABC")
		(layer "B.Cu")
		(hatch none 0.5)
		(connect_pads
			(clearance 0.5)
		)
		(min_thickness 0.25)
		(fill yes
			(thermal_gap 0.5)
			(thermal_bridge_width 0.5)
			(island_removal_mode 0)
		)
		(polygon
			(pts
				(xy 269.4686 -24.2316) (xy 269.2146 -24.4856) (xy 269.2146 -26.1874) (xy 268.9098 -26.4922) (xy 266.7 -26.4922)
				(xy 266.3444 -26.1366) (xy 265.7094 -26.1366) (xy 265.5316 -26.3144) (xy 265.5316 -27.3558) (xy 265.7094 -27.5336)
				(xy 272.401538 -27.5336) (xy 272.48866 -27.620722) (xy 273.070574 -27.620722) (xy 274.26031 -28.810458)
				(xy 274.936458 -28.810458) (xy 274.955 -28.829) (xy 277.0124 -28.829) (xy 277.0886 -28.7528) (xy 277.0886 -28.0162)
				(xy 277.0632 -27.9908) (xy 277.0632 -26.6192) (xy 277.4188 -26.2636) (xy 277.4188 -24.4348) (xy 277.2156 -24.2316)
				(xy 277.0378 -24.2316) (xy 276.9108 -24.3586) (xy 276.9108 -25.8064) (xy 276.7584 -25.9588) (xy 275.8186 -25.9588)
				(xy 275.6916 -25.8318) (xy 275.6916 -24.5364) (xy 275.5392 -24.384) (xy 275.3106 -24.384) (xy 275.2344 -24.4602)
				(xy 275.2344 -25.6794) (xy 274.465288 -26.448512) (xy 271.698212 -26.448512) (xy 271.4498 -26.2001)
				(xy 271.4498 -24.3586) (xy 271.3482 -24.257) (xy 271.1196 -24.257) (xy 270.9418 -24.4348) (xy 270.9418 -26.2128)
				(xy 270.6116 -26.543) (xy 269.9258 -26.543) (xy 269.7226 -26.3398) (xy 269.7226 -24.3586) (xy 269.5956 -24.2316)
			)
		)
		(polygon
			(pts
				(xy 276.3647 -27.6987) (xy 276.1615 -27.6987) (xy 276.1615 -27.9019) (xy 276.3647 -27.9019)
			)
		)
	)
	(zone
		(net "P12V_HDD_SATA")
		(layer "B.Cu")
		(hatch none 0.5)
		(connect_pads
			(clearance 0.5)
		)
		(min_thickness 0.25)
		(fill yes
			(thermal_gap 0.5)
			(thermal_bridge_width 0.5)
			(island_removal_mode 0)
		)
		(polygon
			(pts
				(xy 451.866 -136.5758) (xy 451.866 -135.4836) (xy 453.2376 -134.112) (xy 453.2376 -132.5626) (xy 453.0344 -132.3594)
				(xy 451.8406 -132.3594) (xy 450.0118 -132.3594) (xy 449.6054 -132.7658) (xy 446.1764 -132.7658)
				(xy 445.9478 -132.9944) (xy 445.9478 -137.16) (xy 446.2526 -137.4648) (xy 449.707 -137.4648) (xy 449.9356 -137.2362)
				(xy 451.2056 -137.2362)
			)
		)
	)
	(zone
		(layer "B.Cu")
		(hatch none 0.5)
		(connect_pads
			(clearance 0)
		)
		(min_thickness 0.25)
		(keepout
			(tracks allowed)
			(vias allowed)
			(pads allowed)
			(copperpour allowed)
			(footprints allowed)
		)
		(placement
			(enabled no)
			(sheetname "")
		)
		(fill
			(thermal_gap 0.5)
			(thermal_bridge_width 0.5)
			(island_removal_mode 0)
		)
		(polygon
			(pts
				(xy 147.066 -85.471) (xy 147.066 -84.709) (xy 147.828 -84.709) (xy 147.828 -85.471)
			)
		)
	)
	(zone
		(net "P12V_STBY")
		(layer "B.Cu")
		(hatch none 0.5)
		(connect_pads
			(clearance 0.5)
		)
		(min_thickness 0.25)
		(fill yes
			(thermal_gap 0.5)
			(thermal_bridge_width 0.5)
			(island_removal_mode 0)
		)
		(polygon
			(pts
				(xy 20.828 -56.515) (xy 23.3172 -56.515) (xy 23.4569 -56.3753) (xy 25.3873 -56.3753) (xy 25.527 -56.2356)
				(xy 25.527 -54.0004) (xy 24.4602 -52.9336) (xy 21.4122 -52.9336) (xy 20.447 -53.8988) (xy 20.447 -56.134)
			)
		)
	)
	(zone
		(layer "B.Cu")
		(hatch none 0.5)
		(connect_pads
			(clearance 0)
		)
		(min_thickness 0.25)
		(keepout
			(tracks not_allowed)
			(vias allowed)
			(pads allowed)
			(copperpour not_allowed)
			(footprints allowed)
		)
		(placement
			(enabled no)
			(sheetname "")
		)
		(fill
			(thermal_gap 0.5)
			(thermal_bridge_width 0.5)
			(island_removal_mode 0)
		)
		(polygon
			(pts
				(xy -5.999988 2.500122) (xy -5.999988 -2.500122)
				(arc
					(start -4.038854 -2.500122)
					(mid -4.75001 0)
					(end -4.038854 2.500122)
				)
			)
		)
	)
	(zone
		(net "PVDDQ_ABC")
		(layer "B.Cu")
		(hatch none 0.5)
		(connect_pads
			(clearance 0.5)
		)
		(min_thickness 0.25)
		(fill yes
			(thermal_gap 0.5)
			(thermal_bridge_width 0.5)
			(island_removal_mode 0)
		)
		(polygon
			(pts
				(xy 263.844024 -69.809614) (xy 264.980674 -69.809614) (xy 265.069828 -69.72046) (xy 265.069828 -69.09181)
				(xy 265.368024 -68.793614) (xy 265.495024 -68.666614) (xy 266.892024 -68.666614) (xy 266.896596 -68.662296)
				(xy 272.193004 -68.662296) (xy 274.04695 -68.662296) (xy 274.073366 -68.63588) (xy 274.073366 -67.688968)
				(xy 274.049998 -67.6656) (xy 273.774408 -67.39001) (xy 273.774408 -66.950844) (xy 273.710146 -66.886582)
				(xy 271.284446 -66.886582) (xy 271.282414 -66.888614) (xy 266.892024 -66.888614) (xy 263.971024 -66.888614)
				(xy 263.844024 -67.015614)
			)
		)
	)
	(zone
		(net "GND")
		(layer "B.Cu")
		(hatch none 0.5)
		(connect_pads
			(clearance 0.5)
		)
		(min_thickness 0.25)
		(fill yes
			(thermal_gap 0.5)
			(thermal_bridge_width 0.5)
			(island_removal_mode 0)
		)
		(polygon
			(pts
				(xy 436.1815 -51.1556) (xy 436.1815 -51.6509) (xy 436.2831 -51.7525) (xy 439.5978 -51.7525) (xy 440.0042 -51.3461)
				(xy 440.0042 -50.4063) (xy 439.8518 -50.2539) (xy 439.1152 -50.2539) (xy 438.6961 -49.8348) (xy 438.0992 -49.8348)
				(xy 437.896 -50.038) (xy 437.896 -50.8508) (xy 437.6674 -51.0794) (xy 437.0705 -51.0794) (xy 436.2577 -51.0794)
			)
		)
	)
	(zone
		(net "PVCCIN_CPU1")
		(layer "B.Cu")
		(hatch none 0.5)
		(connect_pads
			(clearance 0.5)
		)
		(min_thickness 0.25)
		(fill yes
			(thermal_gap 0.5)
			(thermal_bridge_width 0.5)
			(island_removal_mode 0)
		)
		(polygon
			(pts
				(xy 44.117768 -52.832) (xy 43.6118 -53.337968) (xy 43.6118 -91.948) (xy 43.627294 -91.963494) (xy 43.627294 -92.309696)
				(xy 43.879008 -92.56141) (xy 48.020732 -92.56141) (xy 48.205898 -92.376244) (xy 48.205898 -90.74023)
				(xy 48.575722 -90.370406) (xy 51.615594 -90.370406) (xy 64.429386 -77.556614) (xy 69.137022 -77.556614)
				(xy 73.29424 -80.096614) (xy 79.920592 -80.096614) (xy 79.920592 -80.071214) (xy 81.038192 -78.953614)
				(xy 86.143592 -78.953614) (xy 86.956392 -79.766414) (xy 88.150192 -79.766414) (xy 88.505792 -80.122014)
				(xy 89.775792 -80.122014) (xy 90.029792 -79.868014) (xy 91.807792 -79.868014) (xy 92.2655 -80.325468)
				(xy 92.276168 -80.3148) (xy 92.657168 -80.3148) (xy 92.657168 -79.7306) (xy 92.453968 -79.5274)
				(xy 92.453968 -79.0194) (xy 92.707968 -78.7654) (xy 93.038168 -78.7654) (xy 93.266768 -78.994) (xy 96.825054 -78.994)
				(xy 97.097088 -79.266034) (xy 97.097088 -80.096614) (xy 103.778558 -80.096614) (xy 103.778558 -78.59268)
				(xy 103.484172 -78.298294) (xy 103.484172 -77.302614) (xy 92.747592 -77.302614) (xy 92.657168 -77.21219)
				(xy 92.657168 -74.7268) (xy 92.707968 -74.676) (xy 103.706168 -74.676) (xy 103.706168 -74.2188)
				(xy 103.452168 -73.9648) (xy 103.452168 -72.984614) (xy 92.874592 -72.984614) (xy 92.874592 -72.222614)
				(xy 92.834968 -72.18299) (xy 92.834968 -70.602094) (xy 93.356176 -70.080886) (xy 95.753682 -70.080886)
				(xy 95.959168 -69.8754) (xy 95.959168 -68.6054) (xy 96.543368 -68.0212) (xy 98.092768 -68.0212)
				(xy 98.346768 -67.7672) (xy 98.346768 -67.1322) (xy 98.854768 -66.6242) (xy 109.21111 -66.6242)
				(xy 109.509814 -66.922904) (xy 109.509814 -68.58508) (xy 109.591348 -68.666614) (xy 111.0996 -68.666614)
				(xy 111.14278 -68.62318) (xy 111.14278 -67.16522) (xy 111.6076 -66.7004) (xy 112.6998 -66.7004)
				(xy 114.158014 -68.158614) (xy 115.734592 -68.158614) (xy 115.861592 -68.031614) (xy 115.861592 -67.523614)
				(xy 114.718592 -67.015614) (xy 113.067592 -66.126614) (xy 108.876592 -63.586614) (xy 106.717592 -63.586614)
				(xy 106.072178 -62.9412) (xy 102.014274 -62.9412) (xy 102.014274 -62.885828) (xy 101.57206 -62.443614)
				(xy 95.287592 -62.443614) (xy 93.890592 -63.840614) (xy 91.064588 -63.840614) (xy 84.841588 -70.063614)
				(xy 71.411592 -70.063614) (xy 71.030592 -69.682614) (xy 66.393568 -69.682614) (xy 65.697354 -68.9864)
				(xy 65.6844 -68.9864) (xy 63.6016 -66.9036) (xy 63.6016 -65.5066) (xy 63.5508 -65.4558) (xy 63.0174 -65.4558)
				(xy 62.865 -65.3034) (xy 62.865 -60.504832) (xy 55.192168 -52.832)
			)
		)
		(polygon
			(pts
				(xy 49.911 -87.01532) (xy 49.7078 -87.01532) (xy 49.7078 -87.21852) (xy 49.911 -87.21852)
			)
		)
		(polygon
			(pts
				(xy 49.149 -87.01532) (xy 48.9458 -87.01532) (xy 48.9458 -87.21852) (xy 49.149 -87.21852)
			)
		)
		(polygon
			(pts
				(xy 49.911 -84.72932) (xy 49.7078 -84.72932) (xy 49.7078 -84.93252) (xy 49.911 -84.93252)
			)
		)
		(polygon
			(pts
				(xy 49.149 -84.72932) (xy 48.9458 -84.72932) (xy 48.9458 -84.93252) (xy 49.149 -84.93252)
			)
		)
		(polygon
			(pts
				(xy 49.911 -78.7019) (xy 49.7078 -78.7019) (xy 49.7078 -78.9051) (xy 49.911 -78.9051)
			)
		)
		(polygon
			(pts
				(xy 49.149 -78.7019) (xy 48.9458 -78.7019) (xy 48.9458 -78.9051) (xy 49.149 -78.9051)
			)
		)
		(polygon
			(pts
				(xy 49.911 -76.4159) (xy 49.7078 -76.4159) (xy 49.7078 -76.6191) (xy 49.911 -76.6191)
			)
		)
		(polygon
			(pts
				(xy 49.149 -76.4159) (xy 48.9458 -76.4159) (xy 48.9458 -76.6191) (xy 49.149 -76.6191)
			)
		)
		(polygon
			(pts
				(xy 49.911 -71.3359) (xy 49.7078 -71.3359) (xy 49.7078 -71.5391) (xy 49.911 -71.5391)
			)
		)
		(polygon
			(pts
				(xy 49.149 -71.3359) (xy 48.9458 -71.3359) (xy 48.9458 -71.5391) (xy 49.149 -71.5391)
			)
		)
		(polygon
			(pts
				(xy 49.911 -69.0499) (xy 49.7078 -69.0499) (xy 49.7078 -69.2531) (xy 49.911 -69.2531)
			)
		)
		(polygon
			(pts
				(xy 49.149 -69.0499) (xy 48.9458 -69.0499) (xy 48.9458 -69.2531) (xy 49.149 -69.2531)
			)
		)
		(polygon
			(pts
				(xy 63.0936 -65.8368) (xy 62.8904 -65.8368) (xy 62.8904 -66.04) (xy 63.0936 -66.04)
			)
		)
		(polygon
			(pts
				(xy 49.911 -63.423292) (xy 49.7078 -63.423292) (xy 49.7078 -63.626492) (xy 49.911 -63.626492)
			)
		)
		(polygon
			(pts
				(xy 49.149 -63.423292) (xy 48.9458 -63.423292) (xy 48.9458 -63.626492) (xy 49.149 -63.626492)
			)
		)
		(polygon
			(pts
				(xy 49.911 -60.883292) (xy 49.7078 -60.883292) (xy 49.7078 -61.340492) (xy 49.911 -61.340492)
			)
		)
		(polygon
			(pts
				(xy 49.149 -60.883292) (xy 48.9458 -60.883292) (xy 48.9458 -61.340492) (xy 49.149 -61.340492)
			)
		)
		(polygon
			(pts
				(xy 49.911 -58.597292) (xy 49.7078 -58.597292) (xy 49.7078 -58.800492) (xy 49.911 -58.800492)
			)
		)
		(polygon
			(pts
				(xy 49.149 -58.597292) (xy 48.9458 -58.597292) (xy 48.9458 -58.800492) (xy 49.149 -58.800492)
			)
		)
	)
	(zone
		(net "GND")
		(layer "B.Cu")
		(hatch none 0.5)
		(connect_pads
			(clearance 0.5)
		)
		(min_thickness 0.25)
		(fill yes
			(thermal_gap 0.5)
			(thermal_bridge_width 0.5)
			(island_removal_mode 0)
		)
		(polygon
			(pts
				(xy 242.029234 -146.241008) (xy 243.284756 -146.241008) (xy 243.4336 -146.092164) (xy 243.4336 -143.782034)
				(xy 243.219986 -143.56842) (xy 242.055396 -143.56842) (xy 241.848132 -143.775684) (xy 241.848132 -146.059906)
			)
		)
	)
	(zone
		(net "P5V_USB")
		(layer "B.Cu")
		(hatch none 0.5)
		(connect_pads
			(clearance 0.5)
		)
		(min_thickness 0.25)
		(fill yes
			(thermal_gap 0.5)
			(thermal_bridge_width 0.5)
			(island_removal_mode 0)
		)
		(polygon
			(pts
				(xy 465.3026 -131.2418) (xy 465.3026 -129.7686) (xy 465.3026 -129.5146) (xy 465.1502 -129.3622)
				(xy 463.2579 -129.3622) (xy 463.1055 -129.5146) (xy 463.1055 -131.0005) (xy 463.4738 -131.3688)
				(xy 465.1756 -131.3688)
			)
		)
	)
	(zone
		(net "GND")
		(layer "B.Cu")
		(hatch none 0.5)
		(connect_pads
			(clearance 0.5)
		)
		(min_thickness 0.25)
		(fill yes
			(thermal_gap 0.5)
			(thermal_bridge_width 0.5)
			(island_removal_mode 0)
		)
		(polygon
			(pts
				(xy 472.8718 -43.1038) (xy 472.8718 -40.8432) (xy 473.6592 -40.0558) (xy 476.1992 -40.0558) (xy 476.3516 -40.2082)
				(xy 476.3516 -43.8658) (xy 476.1992 -44.0182) (xy 474.6752 -44.0182) (xy 473.964 -43.307) (xy 473.075 -43.307)
			)
		)
	)
	(zone
		(net "P3V3_STBY")
		(layer "B.Cu")
		(hatch none 0.5)
		(connect_pads
			(clearance 0.5)
		)
		(min_thickness 0.25)
		(fill yes
			(thermal_gap 0.5)
			(thermal_bridge_width 0.5)
			(island_removal_mode 0)
		)
		(polygon
			(pts
				(xy 420.19982 -81.8769) (xy 420.35095 -81.72577) (xy 421.82923 -81.72577) (xy 421.8559 -81.6991)
				(xy 421.8559 -81.30794) (xy 421.767 -81.21904) (xy 421.26535 -81.21904) (xy 421.07231 -81.026) (xy 420.37 -81.026)
				(xy 420.0525 -81.3435) (xy 419.6461 -81.3435) (xy 419.456108 -81.533492) (xy 418.97554 -81.533492)
				(xy 418.9095 -81.599532) (xy 418.9095 -81.67751) (xy 418.9095 -82.121756) (xy 419.00983 -82.222086)
				(xy 419.393878 -82.222086) (xy 419.695884 -81.92008) (xy 420.15664 -81.92008)
			)
		)
	)
	(zone
		(layer "B.Cu")
		(hatch none 0.5)
		(connect_pads
			(clearance 0)
		)
		(min_thickness 0.25)
		(keepout
			(tracks not_allowed)
			(vias allowed)
			(pads allowed)
			(copperpour not_allowed)
			(footprints allowed)
		)
		(placement
			(enabled no)
			(sheetname "")
		)
		(fill
			(thermal_gap 0.5)
			(thermal_bridge_width 0.5)
			(island_removal_mode 0)
		)
		(polygon
			(pts
				(arc
					(start 406.489916 -137.489946)
					(mid 410.079952 -133.89991)
					(end 406.489916 -130.309874)
				)
				(arc
					(start 406.489916 -130.309874)
					(mid 402.89988 -133.89991)
					(end 406.489916 -137.489946)
				)
			)
		)
	)
	(zone
		(layer "B.Cu")
		(hatch none 0.5)
		(connect_pads
			(clearance 0)
		)
		(min_thickness 0.25)
		(keepout
			(tracks allowed)
			(vias allowed)
			(pads allowed)
			(copperpour allowed)
			(footprints not_allowed)
		)
		(placement
			(enabled no)
			(sheetname "")
		)
		(fill
			(thermal_gap 0.5)
			(thermal_bridge_width 0.5)
			(island_removal_mode 0)
		)
		(polygon
			(pts
				(arc
					(start 33.919922 -44.99991)
					(mid 32.36976 -46.550072)
					(end 33.919922 -48.09998)
				)
				(arc
					(start 33.919922 -48.09998)
					(mid 35.46983 -46.550072)
					(end 33.919922 -44.99991)
				)
			)
		)
	)
	(zone
		(layer "B.Cu")
		(hatch none 0.5)
		(connect_pads
			(clearance 0)
		)
		(min_thickness 0.25)
		(keepout
			(tracks allowed)
			(vias allowed)
			(pads allowed)
			(copperpour allowed)
			(footprints allowed)
		)
		(placement
			(enabled no)
			(sheetname "")
		)
		(fill
			(thermal_gap 0.5)
			(thermal_bridge_width 0.5)
			(island_removal_mode 0)
		)
		(polygon
			(pts
				(xy 160.782 -103.124) (xy 160.782 -102.362) (xy 161.544 -102.362) (xy 161.544 -103.124)
			)
		)
	)
	(zone
		(net "PVCCMCP_CPU0")
		(layer "B.Cu")
		(hatch none 0.5)
		(connect_pads
			(clearance 0.5)
		)
		(min_thickness 0.25)
		(fill yes
			(thermal_gap 0.5)
			(thermal_bridge_width 0.5)
			(island_removal_mode 0)
		)
		(polygon
			(pts
				(xy 317.48222 -58.34888) (xy 319.73012 -58.34888) (xy 327.6854 -50.3936) (xy 335.6102 -50.3936)
				(xy 338.0867 -47.9171) (xy 344.5129 -47.9171) (xy 347.1672 -45.2628) (xy 350.6724 -45.2628) (xy 351.155 -44.7802)
				(xy 351.155 -41.8846) (xy 350.8248 -41.5544) (xy 334.260698 -41.5544) (xy 333.066136 -42.748962)
				(xy 327.710038 -42.748962) (xy 325.64832 -44.81068) (xy 320.52768 -44.81068) (xy 313.271916 -52.066444)
				(xy 313.271916 -55.047134) (xy 314.18657 -55.961788) (xy 314.6298 -55.961788) (xy 316.050676 -57.382664)
				(xy 316.516004 -57.382664)
			)
		)
	)
	(zone
		(layer "B.Cu")
		(hatch none 0.5)
		(connect_pads
			(clearance 0)
		)
		(min_thickness 0.25)
		(keepout
			(tracks not_allowed)
			(vias allowed)
			(pads allowed)
			(copperpour not_allowed)
			(footprints allowed)
		)
		(placement
			(enabled no)
			(sheetname "")
		)
		(fill
			(thermal_gap 0.5)
			(thermal_bridge_width 0.5)
			(island_removal_mode 0)
		)
		(polygon
			(pts
				(xy 16.460978 -102.961694) (xy 16.539718 -103.040434) (xy 16.611346 -102.968298) (xy 16.537686 -102.894638)
				(arc
					(start 16.537686 -102.684834)
					(mid 16.607536 -102.160917)
					(end 16.677386 -102.684834)
				)
				(xy 16.677386 -102.836726) (xy 16.709898 -102.869238)
				(arc
					(start 16.879824 -102.697788)
					(mid 16.877792 -102.155244)
					(end 16.335248 -102.157276)
				)
				(arc
					(start 15.741396 -102.755954)
					(mid 15.735205 -103.301005)
					(end 16.280384 -103.3018)
				)
				(xy 16.44142 -103.139748) (xy 16.403066 -103.101394)
				(arc
					(start 16.265398 -103.101394)
					(mid 15.741481 -103.031544)
					(end 16.265398 -102.961694)
				)
			)
		)
	)
	(zone
		(net "PVDDQ_GHJ")
		(layer "B.Cu")
		(hatch none 0.5)
		(connect_pads
			(clearance 0.5)
		)
		(min_thickness 0.25)
		(fill yes
			(thermal_gap 0.5)
			(thermal_bridge_width 0.5)
			(island_removal_mode 0)
		)
		(polygon
			(pts
				(xy 107.643168 0.1778) (xy 112.316768 0.1778) (xy 112.570768 0.4318) (xy 112.570768 1.651) (xy 112.62106 1.651)
				(xy 112.62106 2.52476) (xy 112.42802 2.7178) (xy 111.887 2.7178) (xy 111.887 2.6924) (xy 101.877368 2.6924)
				(xy 101.775768 2.5908) (xy 101.775768 1.6256) (xy 101.877368 1.524) (xy 101.978968 1.524) (xy 102.334568 1.1684)
				(xy 105.052368 1.1684) (xy 105.712768 1.8288) (xy 106.703368 1.8288) (xy 107.338368 1.1938) (xy 107.338368 0.4826)
			)
		)
	)
	(zone
		(net "P5V_STBY")
		(layer "B.Cu")
		(hatch none 0.5)
		(connect_pads
			(clearance 0.5)
		)
		(min_thickness 0.25)
		(fill yes
			(thermal_gap 0.5)
			(thermal_bridge_width 0.5)
			(island_removal_mode 0)
		)
		(polygon
			(pts
				(xy 487.21518 -118.289578) (xy 487.121962 -118.19636) (xy 485.214676 -118.19636) (xy 484.99395 -118.417086)
				(xy 484.99395 -119.04472) (xy 484.41102 -119.62765) (xy 484.41102 -121.49836) (xy 484.56088 -121.64822)
				(xy 486.11282 -121.64822) (xy 486.23982 -121.52122) (xy 486.23982 -120.55094) (xy 486.47604 -120.31472)
				(xy 487.21518 -119.57558)
			)
		)
	)
	(zone
		(net "GND")
		(layer "B.Cu")
		(hatch none 0.5)
		(connect_pads
			(clearance 0.5)
		)
		(min_thickness 0.25)
		(fill yes
			(thermal_gap 0.5)
			(thermal_bridge_width 0.5)
			(island_removal_mode 0)
		)
		(polygon
			(pts
				(xy 95.602298 -137.593578) (xy 95.92056 -137.593578) (xy 96.551496 -136.962896) (xy 96.551496 -134.867396)
				(xy 96.482916 -134.798816) (xy 96.00311 -134.798816) (xy 95.828358 -134.973568) (xy 95.828358 -136.103868)
				(xy 95.458534 -136.473692) (xy 95.458534 -137.44956) (xy 95.602298 -137.593324)
			)
		)
	)
	(zone
		(layer "B.Cu")
		(hatch none 0.5)
		(connect_pads
			(clearance 0)
		)
		(min_thickness 0.25)
		(keepout
			(tracks allowed)
			(vias allowed)
			(pads allowed)
			(copperpour allowed)
			(footprints not_allowed)
		)
		(placement
			(enabled no)
			(sheetname "")
		)
		(fill
			(thermal_gap 0.5)
			(thermal_bridge_width 0.5)
			(island_removal_mode 0)
		)
		(polygon
			(pts
				(arc
					(start 470.600532 -60.59678)
					(mid 474.200474 -64.196722)
					(end 477.800416 -60.59678)
				)
				(arc
					(start 477.800416 -58.996834)
					(mid 474.200474 -55.396892)
					(end 470.600532 -58.996834)
				)
			)
		)
	)
	(zone
		(net "GND")
		(layer "B.Cu")
		(hatch none 0.5)
		(connect_pads
			(clearance 0.5)
		)
		(min_thickness 0.25)
		(fill yes
			(thermal_gap 0.5)
			(thermal_bridge_width 0.5)
			(island_removal_mode 0)
		)
		(polygon
			(pts
				(xy 259.969 -19.8755) (xy 260.263132 -19.8755) (xy 261.911338 -18.227294) (xy 261.911338 -17.087088)
				(xy 261.75716 -16.93291) (xy 261.08914 -16.93291) (xy 260.95579 -17.06626) (xy 260.95579 -17.693132)
				(xy 260.113272 -18.53565) (xy 259.93852 -18.53565) (xy 259.8039 -18.67027) (xy 259.8039 -19.7104)
			)
		)
	)
	(zone
		(net "GND")
		(layer "B.Cu")
		(hatch none 0.5)
		(connect_pads
			(clearance 0.5)
		)
		(min_thickness 0.25)
		(fill yes
			(thermal_gap 0.5)
			(thermal_bridge_width 0.5)
			(island_removal_mode 0)
		)
		(polygon
			(pts
				(xy 482.4222 -27.234642) (xy 482.4222 -26.215086) (xy 482.456998 -26.180288) (xy 484.853488 -26.180288)
				(xy 485.0892 -26.416) (xy 485.0892 -27.0002) (xy 484.8098 -27.2796) (xy 482.467158 -27.2796)
			)
		)
	)
	(zone
		(net "PVNN_PCH_STBY")
		(layer "B.Cu")
		(hatch none 0.5)
		(connect_pads
			(clearance 0.5)
		)
		(min_thickness 0.25)
		(fill yes
			(thermal_gap 0.5)
			(thermal_bridge_width 0.5)
			(island_removal_mode 0)
		)
		(polygon
			(pts
				(xy 380.45263 -137.09777) (xy 380.359666 -137.190734) (xy 380.359666 -137.818876) (xy 379.875542 -138.303)
				(xy 378.9172 -138.303) (xy 378.6886 -138.5316) (xy 378.6886 -138.9126) (xy 378.403104 -139.198096)
				(xy 377.443492 -139.198096) (xy 376.802904 -138.557508) (xy 376.005598 -138.557508) (xy 375.740422 -138.292332)
				(xy 375.740422 -137.749534) (xy 375.658888 -137.668) (xy 373.609616 -137.668) (xy 373.497856 -137.77976)
				(xy 373.497856 -138.48715) (xy 372.945406 -139.0396) (xy 370.49583 -139.0396) (xy 369.590828 -138.134598)
				(xy 368.591846 -138.134598) (xy 368.065304 -138.66114) (xy 368.065304 -138.90752) (xy 367.2078 -139.765024)
				(xy 367.2078 -143.475202) (xy 367.369598 -143.637) (xy 372.608094 -143.637) (xy 373.190262 -143.054832)
				(xy 382.852168 -143.054832) (xy 383.286 -142.621) (xy 383.286 -139.1158) (xy 383.6162 -138.7856)
				(xy 385.501388 -138.7856) (xy 385.680204 -138.606784) (xy 385.680204 -137.301986) (xy 385.475988 -137.09777)
			)
		)
		(polygon
			(pts
				(xy 375.0056 -138.4554) (xy 374.8024 -138.4554) (xy 374.8024 -138.6586) (xy 375.0056 -138.6586)
			)
		)
		(polygon
			(pts
				(xy 374.4976 -138.4554) (xy 374.2944 -138.4554) (xy 374.2944 -138.6586) (xy 374.4976 -138.6586)
			)
		)
		(polygon
			(pts
				(xy 385.191 -137.8839) (xy 384.9878 -137.8839) (xy 384.9878 -138.0871) (xy 385.191 -138.0871)
			)
		)
		(polygon
			(pts
				(xy 384.429 -137.8839) (xy 384.2258 -137.8839) (xy 384.2258 -138.0871) (xy 384.429 -138.0871)
			)
		)
		(polygon
			(pts
				(xy 383.921 -137.8839) (xy 383.7178 -137.8839) (xy 383.7178 -138.0871) (xy 383.921 -138.0871)
			)
		)
		(polygon
			(pts
				(xy 383.159 -137.8839) (xy 382.9558 -137.8839) (xy 382.9558 -138.0871) (xy 383.159 -138.0871)
			)
		)
		(polygon
			(pts
				(xy 382.5748 -137.8839) (xy 382.3716 -137.8839) (xy 382.3716 -138.0871) (xy 382.5748 -138.0871)
			)
		)
		(polygon
			(pts
				(xy 381.8128 -137.8839) (xy 381.6096 -137.8839) (xy 381.6096 -138.0871) (xy 381.8128 -138.0871)
			)
		)
		(polygon
			(pts
				(xy 381.3302 -137.8839) (xy 381.127 -137.8839) (xy 381.127 -138.0871) (xy 381.3302 -138.0871)
			)
		)
	)
	(zone
		(layer "B.Cu")
		(hatch none 0.5)
		(connect_pads
			(clearance 0.5)
		)
		(min_thickness 0.25)
		(fill
			(thermal_gap 0.5)
			(thermal_bridge_width 0.5)
			(island_removal_mode 0)
		)
		(polygon
			(pts
				(xy 32.29991 -88.707976) (xy 32.29991 -89.47023) (xy 32.0548 -89.71534) (xy 32.029146 -89.71534)
				(xy 31.555944 -89.71534) (xy 31.214568 -90.056716) (xy 29.109924 -90.056716) (xy 26.796746 -92.369894)
				(xy 26.796746 -98.23704) (xy 25.356566 -99.67722) (xy 25.356566 -102.8319) (xy 27.39136 -104.866694)
				(xy 27.500072 -104.866694) (xy 27.830272 -104.536494) (xy 27.830272 -104.146604) (xy 27.711654 -104.027986)
				(xy 27.711654 -103.268526) (xy 29.58338 -101.3968) (xy 33.1724 -101.3968) (xy 33.204912 -101.3968)
				(xy 33.340294 -101.261418) (xy 33.340294 -96.650556) (xy 33.328356 -96.638618) (xy 32.33166 -96.638618)
				(xy 32.3088 -96.661478) (xy 32.3088 -96.827086) (xy 32.3088 -97.6884) (xy 32.021272 -97.975928)
				(xy 30.258258 -97.975928) (xy 30.101794 -98.132392) (xy 30.098238 -98.132392) (xy 30.062678 -98.167952)
				(xy 29.15412 -98.167952) (xy 28.683712 -97.697544) (xy 28.683712 -96.868488) (xy 29.725366 -95.826834)
				(xy 29.725366 -94.45752) (xy 29.516324 -94.248478) (xy 29.516324 -93.490796) (xy 29.803598 -93.203522)
				(xy 33.212278 -93.203522) (xy 33.3248 -93.091) (xy 33.3248 -88.556084) (xy 33.283144 -88.514428)
				(xy 32.323786 -88.514428) (xy 32.29991 -88.538304)
			)
		)
	)
	(zone
		(layer "B.Cu")
		(hatch none 0.5)
		(connect_pads
			(clearance 0)
		)
		(min_thickness 0.25)
		(keepout
			(tracks not_allowed)
			(vias allowed)
			(pads allowed)
			(copperpour not_allowed)
			(footprints allowed)
		)
		(placement
			(enabled no)
			(sheetname "")
		)
		(fill
			(thermal_gap 0.5)
			(thermal_bridge_width 0.5)
			(island_removal_mode 0)
		)
		(polygon
			(pts
				(arc
					(start 420.161466 -146.9009)
					(mid 419.777926 -146.51736)
					(end 419.394386 -146.9009)
				)
				(arc
					(start 419.394386 -147.916646)
					(mid 419.777799 -148.30044)
					(end 420.161466 -147.9169)
				)
				(xy 420.161466 -147.574)
				(arc
					(start 419.892226 -147.574)
					(mid 419.860795 -147.587019)
					(end 419.847776 -147.61845)
				)
				(arc
					(start 419.847776 -147.659598)
					(mid 419.777926 -148.183515)
					(end 419.708076 -147.659598)
				)
				(xy 419.708076 -147.589494)
				(arc
					(start 419.71087 -147.5867)
					(mid 419.762038 -147.488262)
					(end 419.860476 -147.437094)
				)
				(xy 419.86327 -147.4343) (xy 420.161466 -147.4343) (xy 420.161466 -147.3327) (xy 419.86327 -147.3327)
				(arc
					(start 419.860476 -147.329906)
					(mid 419.762038 -147.278738)
					(end 419.71087 -147.1803)
				)
				(xy 419.708076 -147.177506)
				(arc
					(start 419.708076 -147.158202)
					(mid 419.777403 -146.634286)
					(end 419.848792 -147.157948)
				)
				(arc
					(start 419.848792 -147.157948)
					(mid 419.864323 -147.183137)
					(end 419.892226 -147.193)
				)
				(xy 420.161466 -147.193)
			)
		)
	)
	(zone
		(net "P5V_STBY_USBC")
		(layer "B.Cu")
		(hatch none 0.5)
		(connect_pads
			(clearance 0.5)
		)
		(min_thickness 0.25)
		(fill yes
			(thermal_gap 0.5)
			(thermal_bridge_width 0.5)
			(island_removal_mode 0)
		)
		(polygon
			(pts
				(xy 499.2624 -55.753) (xy 499.1862 -55.8292) (xy 499.1862 -56.896) (xy 498.699028 -57.383172) (xy 497.245894 -57.383172)
				(xy 495.650266 -58.9788) (xy 493.9284 -58.9788) (xy 493.3315 -58.3819) (xy 493.3315 -57.7723) (xy 493.141 -57.5818)
				(xy 492.1504 -57.5818) (xy 491.998 -57.7342) (xy 491.998 -58.9534) (xy 493.099344 -60.054744) (xy 496.221512 -60.054744)
				(xy 496.954302 -59.321954) (xy 499.892574 -59.321954) (xy 500.3038 -58.910728) (xy 500.787924 -58.426604)
				(xy 500.787924 -56.894476) (xy 500.7864 -56.892952) (xy 500.7864 -55.8038) (xy 500.7356 -55.753)
			)
		)
	)
	(zone
		(net "GND")
		(layer "B.Cu")
		(hatch none 0.5)
		(connect_pads
			(clearance 0.5)
		)
		(min_thickness 0.25)
		(fill yes
			(thermal_gap 0.5)
			(thermal_bridge_width 0.5)
			(island_removal_mode 0)
		)
		(polygon
			(pts
				(xy 280.524712 -136.648698) (xy 278.706326 -136.648698) (xy 278.505666 -136.448038) (xy 278.505666 -134.234936)
				(xy 278.712676 -134.027926) (xy 280.499058 -134.027926) (xy 280.744676 -134.273544) (xy 280.744676 -136.428734)
			)
		)
	)
	(zone
		(layer "B.Cu")
		(hatch none 0.5)
		(connect_pads
			(clearance 0)
		)
		(min_thickness 0.25)
		(keepout
			(tracks not_allowed)
			(vias allowed)
			(pads allowed)
			(copperpour not_allowed)
			(footprints allowed)
		)
		(placement
			(enabled no)
			(sheetname "")
		)
		(fill
			(thermal_gap 0.5)
			(thermal_bridge_width 0.5)
			(island_removal_mode 0)
		)
		(polygon
			(pts
				(arc
					(start 430.100486 -116.196872)
					(mid 431.700432 -117.796818)
					(end 433.300378 -116.196872)
				)
				(arc
					(start 433.300378 -114.596926)
					(mid 431.700432 -112.99698)
					(end 430.100486 -114.596926)
				)
			)
		)
	)
	(zone
		(layer "B.Cu")
		(hatch none 0.5)
		(connect_pads
			(clearance 0)
		)
		(min_thickness 0.25)
		(keepout
			(tracks not_allowed)
			(vias allowed)
			(pads allowed)
			(copperpour not_allowed)
			(footprints allowed)
		)
		(placement
			(enabled no)
			(sheetname "")
		)
		(fill
			(thermal_gap 0.5)
			(thermal_bridge_width 0.5)
			(island_removal_mode 0)
		)
		(polygon
			(pts
				(arc
					(start 198.930006 -50.099976)
					(mid 202.47991 -46.550072)
					(end 198.930006 -42.999914)
				)
				(arc
					(start 198.930006 -42.999914)
					(mid 195.379848 -46.550072)
					(end 198.930006 -50.099976)
				)
			)
		)
	)
	(zone
		(net "GND")
		(layer "B.Cu")
		(hatch none 0.5)
		(connect_pads
			(clearance 0.5)
		)
		(min_thickness 0.25)
		(fill yes
			(thermal_gap 0.5)
			(thermal_bridge_width 0.5)
			(island_removal_mode 0)
		)
		(polygon
			(pts
				(xy 388.7216 -112.522) (xy 389.7122 -112.522) (xy 390.017 -112.8268) (xy 390.2456 -112.8268) (xy 390.3218 -112.7506)
				(xy 390.779 -112.7506) (xy 390.8552 -112.8268) (xy 391.0076 -112.8268) (xy 391.16 -112.6744) (xy 391.5283 -112.6744)
				(xy 391.57402 -112.62868) (xy 391.814304 -112.38865) (xy 391.814304 -112.147096) (xy 391.936224 -112.025176)
				(xy 391.936224 -111.74222) (xy 391.816844 -111.62284) (xy 391.653522 -111.62284) (xy 391.453624 -111.822738)
				(xy 391.451592 -111.822738) (xy 391.313924 -111.960406) (xy 390.539732 -111.960406) (xy 390.226804 -111.647478)
				(xy 390.05002 -111.647478) (xy 389.902192 -111.795306) (xy 389.572754 -111.795306) (xy 389.424926 -111.647478)
				(xy 389.251952 -111.647478) (xy 389.114538 -111.784892) (xy 389.025384 -111.784892) (xy 389.024876 -111.7854)
				(xy 387.973062 -111.7854) (xy 387.835394 -111.647732) (xy 387.642354 -111.647732) (xy 387.504686 -111.7854)
				(xy 387.1722 -111.7854) (xy 387.0452 -111.6584) (xy 387.044946 -111.6584) (xy 387.034024 -111.647478)
				(xy 386.848858 -111.647478) (xy 386.050028 -111.647478) (xy 385.92887 -111.768636) (xy 385.92887 -112.52327)
				(xy 386.150358 -112.744758) (xy 386.6515 -112.744758) (xy 386.770626 -112.863884) (xy 387.038088 -112.863884)
				(xy 387.250686 -112.651286) (xy 387.474714 -112.651286) (xy 387.477 -112.649) (xy 387.6294 -112.649)
				(xy 387.8326 -112.8522) (xy 388.3914 -112.8522)
			)
		)
	)
	(zone
		(layer "B.Cu")
		(hatch none 0.5)
		(connect_pads
			(clearance 0)
		)
		(min_thickness 0.25)
		(keepout
			(tracks not_allowed)
			(vias allowed)
			(pads allowed)
			(copperpour not_allowed)
			(footprints allowed)
		)
		(placement
			(enabled no)
			(sheetname "")
		)
		(fill
			(thermal_gap 0.5)
			(thermal_bridge_width 0.5)
			(island_removal_mode 0)
		)
		(polygon
			(pts
				(xy 457.105258 -53.523134) (xy 456.842622 -53.523134)
				(arc
					(start 456.563222 -53.802534)
					(mid 456.108141 -54.071897)
					(end 456.4761 -53.692044)
				)
				(xy 456.64501 -53.523134)
				(arc
					(start 456.317604 -53.523134)
					(mid 455.934064 -53.906674)
					(end 456.317604 -54.290214)
				)
				(arc
					(start 457.58735 -54.290214)
					(mid 457.971144 -53.906801)
					(end 457.587604 -53.523134)
				)
				(xy 457.30287 -53.523134)
				(arc
					(start 457.455016 -53.67528)
					(mid 457.776181 -54.095251)
					(end 457.35621 -53.774086)
				)
			)
		)
	)
	(zone
		(net "GND")
		(layer "B.Cu")
		(hatch none 0.5)
		(connect_pads
			(clearance 0.5)
		)
		(min_thickness 0.25)
		(fill yes
			(thermal_gap 0.5)
			(thermal_bridge_width 0.5)
			(island_removal_mode 0)
		)
		(polygon
			(pts
				(xy 447.7766 -66.3956) (xy 447.9036 -66.2686) (xy 449.8594 -66.2686) (xy 450.342 -65.786) (xy 450.342 -63.373)
				(xy 450.2531 -63.2841) (xy 450.0626 -63.0936) (xy 447.8655 -63.0936) (xy 447.675 -63.2841) (xy 447.675 -65.151)
				(xy 447.4337 -65.3923) (xy 442.7728 -65.3923) (xy 442.7347 -65.4304) (xy 442.7347 -65.9765) (xy 443.1538 -66.3956)
				(xy 445.516 -66.3956)
			)
		)
	)
	(zone
		(layer "B.Cu")
		(hatch none 0.5)
		(connect_pads
			(clearance 0)
		)
		(min_thickness 0.25)
		(keepout
			(tracks allowed)
			(vias allowed)
			(pads allowed)
			(copperpour allowed)
			(footprints not_allowed)
		)
		(placement
			(enabled no)
			(sheetname "")
		)
		(fill
			(thermal_gap 0.5)
			(thermal_bridge_width 0.5)
			(island_removal_mode 0)
		)
		(polygon
			(pts
				(arc
					(start 226.862894 -119.800116)
					(mid 230.480162 -125.508518)
					(end 234.097068 -119.800116)
				)
			)
		)
	)
	(zone
		(net "P12V_FAN")
		(layer "B.Cu")
		(hatch none 0.5)
		(connect_pads
			(clearance 0.5)
		)
		(min_thickness 0.25)
		(fill yes
			(thermal_gap 0.5)
			(thermal_bridge_width 0.5)
			(island_removal_mode 0)
		)
		(polygon
			(pts
				(xy 30.2006 -42.545) (xy 31.3182 -42.545) (xy 32.3596 -41.5036) (xy 32.3596 -41.2242) (xy 29.3878 -38.2524)
				(xy 29.3878 -36.6776) (xy 28.7274 -36.0172) (xy 27.3558 -36.0172) (xy 26.924 -36.449) (xy 26.924 -39.2684)
			)
		)
	)
	(zone
		(layer "B.Cu")
		(hatch none 0.5)
		(connect_pads
			(clearance 0)
		)
		(min_thickness 0.25)
		(keepout
			(tracks not_allowed)
			(vias allowed)
			(pads allowed)
			(copperpour not_allowed)
			(footprints allowed)
		)
		(placement
			(enabled no)
			(sheetname "")
		)
		(fill
			(thermal_gap 0.5)
			(thermal_bridge_width 0.5)
			(island_removal_mode 0)
		)
		(polygon
			(pts
				(xy 344.56116 -85.48116) (xy 344.56116 -89.42324) (xy 345.417902 -89.42324) (xy 345.417902 -89.3064)
				(xy 344.678 -89.3064) (xy 344.678 -85.598) (xy 348.3864 -85.598) (xy 348.3864 -89.3064) (xy 347.246448 -89.3064)
				(xy 347.246448 -89.42324) (xy 348.50324 -89.42324) (xy 348.50324 -85.48116)
			)
		)
	)
	(zone
		(net "GND")
		(layer "B.Cu")
		(hatch none 0.5)
		(connect_pads
			(clearance 0.5)
		)
		(min_thickness 0.25)
		(fill yes
			(thermal_gap 0.5)
			(thermal_bridge_width 0.5)
			(island_removal_mode 0)
		)
		(polygon
			(pts
				(xy 116.225828 -71.586598) (xy 116.109496 -71.70293) (xy 116.109496 -72.579992) (xy 115.918996 -72.770492)
				(xy 113.308384 -72.770492) (xy 113.065306 -73.01357) (xy 113.065306 -74.503788) (xy 113.192306 -74.630788)
				(xy 114.790982 -74.630788) (xy 115.010692 -74.411078) (xy 115.621054 -74.411078) (xy 115.85575 -74.176382)
				(xy 116.479066 -74.176382) (xy 116.5606 -74.094848) (xy 116.5606 -71.662798) (xy 116.4844 -71.586598)
			)
		)
		(polygon
			(pts
				(xy 115.836192 -73.581514) (xy 115.632992 -73.581514) (xy 115.632992 -73.784714) (xy 115.836192 -73.784714)
			)
		)
		(polygon
			(pts
				(xy 115.074192 -73.581514) (xy 114.870992 -73.581514) (xy 114.870992 -73.784714) (xy 115.074192 -73.784714)
			)
		)
	)
	(zone
		(layer "B.Cu")
		(hatch none 0.5)
		(connect_pads
			(clearance 0)
		)
		(min_thickness 0.25)
		(keepout
			(tracks allowed)
			(vias allowed)
			(pads allowed)
			(copperpour allowed)
			(footprints allowed)
		)
		(placement
			(enabled no)
			(sheetname "")
		)
		(fill
			(thermal_gap 0.5)
			(thermal_bridge_width 0.5)
			(island_removal_mode 0)
		)
		(polygon
			(pts
				(xy 236.347 -104.394) (xy 236.347 -126.619) (xy 207.518 -126.619) (xy 207.518 -107.823) (xy 229.489 -103.505)
				(xy 235.204 -104.648)
			)
		)
	)
	(zone
		(net "GND")
		(layer "B.Cu")
		(hatch none 0.5)
		(connect_pads
			(clearance 0.5)
		)
		(min_thickness 0.25)
		(fill yes
			(thermal_gap 0.5)
			(thermal_bridge_width 0.5)
			(island_removal_mode 0)
		)
		(polygon
			(pts
				(xy 95.993204 -8.765032) (xy 96.814894 -8.765032) (xy 96.969072 -8.610854) (xy 96.969072 -5.990844)
				(xy 96.917764 -5.939536) (xy 96.5581 -5.939536) (xy 95.952056 -6.54558) (xy 95.952056 -8.723884)
			)
		)
	)
	(zone
		(net "BMC_M_VREFCA")
		(layer "B.Cu")
		(hatch none 0.5)
		(connect_pads
			(clearance 0.5)
		)
		(min_thickness 0.25)
		(fill yes
			(thermal_gap 0.5)
			(thermal_bridge_width 0.5)
			(island_removal_mode 0)
		)
		(polygon
			(pts
				(xy 443.7888 -30.6832) (xy 444.2206 -30.6832) (xy 444.5254 -30.3784) (xy 444.5254 -30.0609) (xy 444.754 -29.8323)
				(xy 447.5099 -29.8323) (xy 447.548 -29.7942) (xy 447.548 -27.3939) (xy 447.4337 -27.2796) (xy 446.8368 -27.2796)
				(xy 446.7479 -27.3685) (xy 446.7479 -27.9019) (xy 447.0527 -28.2067) (xy 447.0527 -29.2608) (xy 446.9511 -29.3624)
				(xy 443.8523 -29.3624) (xy 443.6872 -29.5275) (xy 443.6872 -30.5816)
			)
		)
	)
	(zone
		(net "VR_FET_SW_P12V_STBY_PVPP_GHJ")
		(layer "B.Cu")
		(hatch none 0.5)
		(connect_pads
			(clearance 0.5)
		)
		(min_thickness 0.25)
		(fill yes
			(thermal_gap 0.5)
			(thermal_bridge_width 0.5)
			(island_removal_mode 0)
		)
		(polygon
			(pts
				(xy 181.82209 -12.91209) (xy 182.33517 -12.91209) (xy 182.604664 -13.181584) (xy 182.604664 -13.948664)
				(xy 182.753 -14.097) (xy 186.944 -14.097) (xy 187.325 -13.716) (xy 187.325 -12.319) (xy 187.071 -12.065)
				(xy 186.81954 -11.81354) (xy 183.940704 -11.81354) (xy 183.672226 -11.545062) (xy 183.672226 -10.277602)
				(xy 183.684672 -10.265156) (xy 184.053226 -10.265156) (xy 184.12587 -10.192512) (xy 184.187592 -10.13079)
				(xy 184.187592 -8.673592) (xy 184.12587 -8.61187) (xy 183.896 -8.382) (xy 180.594 -8.382) (xy 180.180996 -8.795004)
				(xy 180.180996 -9.557004) (xy 180.180996 -12.44219) (xy 180.650896 -12.91209)
			)
		)
	)
	(zone
		(net "PVDDQ_KLM")
		(layer "B.Cu")
		(hatch none 0.5)
		(connect_pads
			(clearance 0.5)
		)
		(min_thickness 0.25)
		(fill yes
			(thermal_gap 0.5)
			(thermal_bridge_width 0.5)
			(island_removal_mode 0)
		)
		(polygon
			(pts
				(xy 78.735174 -138.940286) (xy 78.735174 -141.233652) (xy 78.865984 -141.364462) (xy 93.606366 -141.364462)
				(xy 93.783912 -141.186916) (xy 93.783912 -140.94206) (xy 93.984572 -140.7414) (xy 94.361 -140.7414)
				(xy 94.4118 -140.7922) (xy 94.60992 -140.7922) (xy 94.76994 -140.63218) (xy 94.76994 -139.2936)
				(xy 94.51594 -139.0396) (xy 93.734636 -139.0396) (xy 93.635322 -138.940286)
			)
		)
		(polygon
			(pts
				(xy 88.0491 -140.4874) (xy 87.8459 -140.4874) (xy 87.8459 -140.6906) (xy 88.0491 -140.6906)
			)
		)
		(polygon
			(pts
				(xy 87.704168 -140.4874) (xy 87.500968 -140.4874) (xy 87.500968 -140.6906) (xy 87.704168 -140.6906)
			)
		)
		(polygon
			(pts
				(xy 84.402168 -140.4874) (xy 84.198968 -140.4874) (xy 84.198968 -140.6906) (xy 84.402168 -140.6906)
			)
		)
		(polygon
			(pts
				(xy 93.60408 -140.44168) (xy 93.40088 -140.44168) (xy 93.40088 -140.64488) (xy 93.60408 -140.64488)
			)
		)
		(polygon
			(pts
				(xy 88.0491 -139.7254) (xy 87.8459 -139.7254) (xy 87.8459 -139.9286) (xy 88.0491 -139.9286)
			)
		)
		(polygon
			(pts
				(xy 87.704168 -139.7254) (xy 87.500968 -139.7254) (xy 87.500968 -139.9286) (xy 87.704168 -139.9286)
			)
		)
		(polygon
			(pts
				(xy 84.402168 -139.7254) (xy 84.198968 -139.7254) (xy 84.198968 -139.9286) (xy 84.402168 -139.9286)
			)
		)
		(polygon
			(pts
				(xy 93.60408 -139.67968) (xy 93.40088 -139.67968) (xy 93.40088 -139.88288) (xy 93.60408 -139.88288)
			)
		)
	)
	(zone
		(net "GND")
		(layer "B.Cu")
		(hatch none 0.5)
		(connect_pads
			(clearance 0.5)
		)
		(min_thickness 0.25)
		(fill yes
			(thermal_gap 0.5)
			(thermal_bridge_width 0.5)
			(island_removal_mode 0)
		)
		(polygon
			(pts
				(xy 159.1818 -59.44362) (xy 159.1818 -63.255652) (xy 159.349948 -63.4238) (xy 160.0962 -63.4238)
				(xy 160.736788 -63.4238) (xy 160.956244 -63.204344) (xy 160.956244 -59.691524) (xy 160.956244 -59.450732)
				(xy 160.823148 -59.317636) (xy 159.307784 -59.317636)
			)
		)
	)
	(zone
		(layer "B.Cu")
		(hatch none 0.5)
		(connect_pads
			(clearance 0)
		)
		(min_thickness 0.25)
		(keepout
			(tracks allowed)
			(vias allowed)
			(pads allowed)
			(copperpour allowed)
			(footprints allowed)
		)
		(placement
			(enabled no)
			(sheetname "")
		)
		(fill
			(thermal_gap 0.5)
			(thermal_bridge_width 0.5)
			(island_removal_mode 0)
		)
		(polygon
			(pts
				(xy 183.769 -124.46) (xy 183.769 -101.346) (xy 145.415 -101.346) (xy 145.415 -103.251) (xy 144.018 -104.648)
				(xy 144.018 -105.156) (xy 158.623 -119.507)
			)
		)
	)
	(zone
		(layer "B.Cu")
		(hatch none 0.5)
		(connect_pads
			(clearance 0)
		)
		(min_thickness 0.25)
		(keepout
			(tracks not_allowed)
			(vias allowed)
			(pads allowed)
			(copperpour not_allowed)
			(footprints allowed)
		)
		(placement
			(enabled no)
			(sheetname "")
		)
		(fill
			(thermal_gap 0.5)
			(thermal_bridge_width 0.5)
			(island_removal_mode 0)
		)
		(polygon
			(pts
				(arc
					(start 421.609266 -152.9715)
					(mid 421.225726 -152.58796)
					(end 420.842186 -152.9715)
				)
				(arc
					(start 420.842186 -153.987246)
					(mid 421.225599 -154.37104)
					(end 421.609266 -153.9875)
				)
				(xy 421.609266 -153.67)
				(arc
					(start 421.340026 -153.67)
					(mid 421.308595 -153.683019)
					(end 421.295576 -153.71445)
				)
				(arc
					(start 421.295576 -153.730198)
					(mid 421.225726 -154.254115)
					(end 421.155876 -153.730198)
				)
				(xy 421.155876 -153.685494)
				(arc
					(start 421.15867 -153.6827)
					(mid 421.209838 -153.584262)
					(end 421.308276 -153.533094)
				)
				(xy 421.31107 -153.5303) (xy 421.609266 -153.5303) (xy 421.609266 -153.4287) (xy 421.31107 -153.4287)
				(arc
					(start 421.308276 -153.425906)
					(mid 421.21195 -153.376817)
					(end 421.159686 -153.282142)
				)
				(arc
					(start 421.159686 -153.282142)
					(mid 421.216177 -152.654059)
					(end 421.310308 -153.27757)
				)
				(arc
					(start 421.310308 -153.27757)
					(mid 421.324111 -153.286025)
					(end 421.340026 -153.289)
				)
				(xy 421.609266 -153.289)
			)
		)
	)
	(zone
		(layer "B.Cu")
		(hatch none 0.5)
		(connect_pads
			(clearance 0)
		)
		(min_thickness 0.25)
		(keepout
			(tracks not_allowed)
			(vias allowed)
			(pads allowed)
			(copperpour not_allowed)
			(footprints allowed)
		)
		(placement
			(enabled no)
			(sheetname "")
		)
		(fill
			(thermal_gap 0.5)
			(thermal_bridge_width 0.5)
			(island_removal_mode 0)
		)
		(polygon
			(pts
				(arc
					(start 422.19626 -149.0345)
					(mid 421.81272 -148.65096)
					(end 421.42918 -149.0345)
				)
				(arc
					(start 421.42918 -150.050246)
					(mid 421.812593 -150.43404)
					(end 422.19626 -150.0505)
				)
				(xy 422.19626 -149.732492)
				(arc
					(start 421.92702 -149.732492)
					(mid 421.895589 -149.745511)
					(end 421.88257 -149.776942)
				)
				(arc
					(start 421.88257 -149.793198)
					(mid 421.81272 -150.317115)
					(end 421.74287 -149.793198)
				)
				(xy 421.74287 -149.747986)
				(arc
					(start 421.745664 -149.745192)
					(mid 421.796832 -149.646754)
					(end 421.89527 -149.595586)
				)
				(xy 421.898064 -149.592792) (xy 422.19626 -149.592792) (xy 422.19626 -149.491192) (xy 421.898064 -149.491192)
				(arc
					(start 421.89527 -149.488398)
					(mid 421.799141 -149.4395)
					(end 421.746934 -149.345142)
				)
				(arc
					(start 421.746934 -149.345142)
					(mid 421.802393 -148.717181)
					(end 421.897556 -149.340316)
				)
				(arc
					(start 421.897556 -149.340316)
					(mid 421.911265 -149.3486)
					(end 421.92702 -149.351492)
				)
				(xy 422.19626 -149.351492)
			)
		)
	)
	(zone
		(net "GND")
		(layer "B.Cu")
		(hatch none 0.5)
		(connect_pads
			(clearance 0.5)
		)
		(min_thickness 0.25)
		(fill yes
			(thermal_gap 0.5)
			(thermal_bridge_width 0.5)
			(island_removal_mode 0)
		)
		(polygon
			(pts
				(xy 34.791142 -51.7144) (xy 33.812734 -52.692808) (xy 33.812734 -52.967128) (xy 33.814004 -52.967128)
				(xy 33.814004 -53.480208) (xy 34.0741 -53.740304) (xy 34.0741 -53.747162) (xy 34.106358 -53.77942)
				(xy 34.106358 -60.687712) (xy 33.860486 -60.933584) (xy 33.860486 -61.044328) (xy 33.864804 -61.044328)
				(xy 33.864804 -61.552836) (xy 33.860486 -61.552836) (xy 33.860486 -61.701426) (xy 34.0868 -61.92774)
				(xy 34.0868 -64.138556) (xy 34.103056 -64.138556) (xy 34.103056 -65.409572) (xy 34.0868 -65.409572)
				(xy 34.0868 -65.789556) (xy 34.103056 -65.789556) (xy 34.103056 -67.060572) (xy 34.0868 -67.060572)
				(xy 34.0868 -67.465956) (xy 34.103056 -67.465956) (xy 34.103056 -68.736972) (xy 34.0868 -68.736972)
				(xy 34.0868 -68.791074) (xy 33.731708 -69.14642) (xy 33.731708 -69.676772) (xy 34.097468 -70.042786)
				(xy 34.097468 -72.266556) (xy 34.103056 -72.266556) (xy 34.103056 -73.537572) (xy 34.097468 -73.537572)
				(xy 34.097468 -73.917556) (xy 34.103056 -73.917556) (xy 34.103056 -75.188572) (xy 34.097468 -75.188572)
				(xy 34.097468 -75.593956) (xy 34.103056 -75.593956) (xy 34.103056 -76.864972) (xy 34.097468 -76.864972)
				(xy 34.097468 -77.058266) (xy 33.814004 -77.341984) (xy 33.814004 -77.873352) (xy 34.0614 -78.120748)
				(xy 34.0614 -80.394556) (xy 34.103056 -80.394556) (xy 34.103056 -81.665572) (xy 34.0614 -81.665572)
				(xy 34.0614 -82.045556) (xy 34.103056 -82.045556) (xy 34.103056 -83.316572) (xy 34.0614 -83.316572)
				(xy 34.0614 -83.721956) (xy 34.103056 -83.721956) (xy 34.103056 -85.005672) (xy 33.808162 -85.300566)
				(xy 33.808162 -85.479128) (xy 33.814004 -85.479128) (xy 33.814004 -86.003892) (xy 34.0868 -86.276688)
				(xy 34.0868 -88.522556) (xy 34.103056 -88.522556) (xy 34.103056 -89.793572) (xy 34.0868 -89.793572)
				(xy 34.0868 -90.173556) (xy 34.103056 -90.173556) (xy 34.103056 -91.444572) (xy 34.0868 -91.444572)
				(xy 34.0868 -91.849956) (xy 34.103056 -91.849956) (xy 34.103056 -93.01988) (xy 34.103056 -93.08338)
				(xy 34.166302 -93.146626) (xy 43.185588 -93.146626) (xy 43.3324 -92.999814) (xy 43.3324 -92.846144)
				(xy 43.3324 -53.265832) (xy 42.542968 -52.4764) (xy 41.272968 -52.4764) (xy 40.510968 -51.7144)
			)
		)
	)
	(zone
		(layer "B.Cu")
		(hatch none 0.5)
		(connect_pads
			(clearance 0)
		)
		(min_thickness 0.25)
		(keepout
			(tracks not_allowed)
			(vias allowed)
			(pads allowed)
			(copperpour not_allowed)
			(footprints allowed)
		)
		(placement
			(enabled no)
			(sheetname "")
		)
		(fill
			(thermal_gap 0.5)
			(thermal_bridge_width 0.5)
			(island_removal_mode 0)
		)
		(polygon
			(pts
				(arc
					(start 13.708126 -103.285798)
					(mid 13.777976 -102.761881)
					(end 13.847826 -103.285798)
				)
				(xy 13.847826 -103.40086) (xy 13.707872 -103.540814) (xy 13.773658 -103.618792) (xy 13.92174 -103.47071)
				(arc
					(start 14.148054 -103.47071)
					(mid 14.548443 -103.813008)
					(end 14.062202 -103.61041)
				)
				(xy 13.979652 -103.61041) (xy 13.864082 -103.72598)
				(arc
					(start 14.027912 -103.920544)
					(mid 14.568424 -103.966772)
					(end 14.614652 -103.42626)
				)
				(arc
					(start 14.076934 -102.788466)
					(mid 13.534438 -102.732389)
					(end 13.484606 -103.275638)
				)
				(xy 13.617702 -103.433626) (xy 13.708126 -103.342948)
			)
		)
	)
	(zone
		(layer "B.Cu")
		(hatch none 0.5)
		(connect_pads
			(clearance 0)
		)
		(min_thickness 0.25)
		(keepout
			(tracks not_allowed)
			(vias allowed)
			(pads allowed)
			(copperpour not_allowed)
			(footprints allowed)
		)
		(placement
			(enabled no)
			(sheetname "")
		)
		(fill
			(thermal_gap 0.5)
			(thermal_bridge_width 0.5)
			(island_removal_mode 0)
		)
		(polygon
			(pts
				(arc
					(start 248.000012 -114.089942)
					(mid 250.540012 -111.549942)
					(end 248.000012 -109.009942)
				)
				(arc
					(start 248.000012 -109.009942)
					(mid 245.460012 -111.549942)
					(end 248.000012 -114.089942)
				)
			)
		)
	)
	(zone
		(layer "B.Cu")
		(hatch none 0.5)
		(connect_pads
			(clearance 0)
		)
		(min_thickness 0.25)
		(keepout
			(tracks not_allowed)
			(vias allowed)
			(pads allowed)
			(copperpour not_allowed)
			(footprints allowed)
		)
		(placement
			(enabled no)
			(sheetname "")
		)
		(fill
			(thermal_gap 0.5)
			(thermal_bridge_width 0.5)
			(island_removal_mode 0)
		)
		(polygon
			(pts
				(xy 356.88778 -82.34426) (xy 359.32872 -82.34426) (xy 361.6198 -80.05318) (xy 361.6198 -76.454)
				(xy 360.6292 -75.4634) (xy 350.2152 -75.4634) (xy 350.1136 -75.565) (xy 350.1136 -76.24826) (xy 350.150684 -76.285344)
				(xy 352.253804 -76.285344) (xy 352.3996 -76.43114) (xy 360.5911 -76.43114) (xy 360.78414 -76.62418)
				(xy 360.78414 -79.72806)
				(arc
					(start 359.325926 -81.186274)
					(mid 359.241607 -81.529691)
					(end 358.89819 -81.61401)
				)
				(xy 358.73436 -81.77784) (xy 356.90556 -81.77784) (xy 356.80904 -81.87436) (xy 356.80904 -82.26552)
			)
		)
	)
	(zone
		(layer "B.Cu")
		(hatch none 0.5)
		(connect_pads
			(clearance 0)
		)
		(min_thickness 0.25)
		(keepout
			(tracks allowed)
			(vias allowed)
			(pads allowed)
			(copperpour allowed)
			(footprints not_allowed)
		)
		(placement
			(enabled no)
			(sheetname "")
		)
		(fill
			(thermal_gap 0.5)
			(thermal_bridge_width 0.5)
			(island_removal_mode 0)
		)
		(polygon
			(pts
				(xy 9.569958 -159.100012) (xy 12.07008 -159.100012) (xy 12.07008 -127.364998) (xy 9.569958 -127.364998)
			)
		)
	)
	(zone
		(layer "B.Cu")
		(hatch none 0.5)
		(connect_pads
			(clearance 0)
		)
		(min_thickness 0.25)
		(keepout
			(tracks not_allowed)
			(vias allowed)
			(pads allowed)
			(copperpour not_allowed)
			(footprints allowed)
		)
		(placement
			(enabled no)
			(sheetname "")
		)
		(fill
			(thermal_gap 0.5)
			(thermal_bridge_width 0.5)
			(island_removal_mode 0)
		)
		(polygon
			(pts
				(xy 454.4822 -51.695858) (xy 453.9742 -51.695858) (xy 453.9742 -52.076858) (xy 454.4822 -52.076858)
			)
		)
	)
	(zone
		(net "P12V_NVDIMM_DEF")
		(layer "B.Cu")
		(hatch none 0.5)
		(connect_pads
			(clearance 0.5)
		)
		(min_thickness 0.25)
		(fill yes
			(thermal_gap 0.5)
			(thermal_bridge_width 0.5)
			(island_removal_mode 0)
		)
		(polygon
			(pts
				(xy 194.945 -127.811784) (xy 194.945 -136.0424) (xy 194.8942 -136.0932) (xy 193.9036 -136.0932)
				(xy 193.6242 -136.3726) (xy 193.6242 -136.4488) (xy 194.056 -136.8806) (xy 194.8434 -136.8806) (xy 194.945 -136.9822)
				(xy 194.945 -152.8064) (xy 194.818 -152.9334) (xy 194.7926 -152.9334) (xy 194.5132 -153.2128) (xy 193.9036 -153.2128)
				(xy 193.2686 -153.8478) (xy 192.8622 -153.8478) (xy 191.9478 -152.9334) (xy 189.9412 -152.9334)
				(xy 189.357 -152.3492) (xy 189.357 -130.51282) (xy 191.31153 -128.55829) (xy 193.27495 -128.55829)
				(xy 194.021456 -127.811784)
			)
		)
	)
	(zone
		(layer "B.Cu")
		(hatch none 0.5)
		(connect_pads
			(clearance 0)
		)
		(min_thickness 0.25)
		(keepout
			(tracks allowed)
			(vias allowed)
			(pads allowed)
			(copperpour allowed)
			(footprints allowed)
		)
		(placement
			(enabled no)
			(sheetname "")
		)
		(fill
			(thermal_gap 0.5)
			(thermal_bridge_width 0.5)
			(island_removal_mode 0)
		)
		(polygon
			(pts
				(xy 371.094 -118.618) (xy 371.094 -117.348) (xy 372.7958 -117.348) (xy 372.7958 -118.618)
			)
		)
	)
	(zone
		(net "GND")
		(layer "B.Cu")
		(hatch none 0.5)
		(connect_pads
			(clearance 0.5)
		)
		(min_thickness 0.25)
		(fill yes
			(thermal_gap 0.5)
			(thermal_bridge_width 0.5)
			(island_removal_mode 0)
		)
		(polygon
			(pts
				(xy 147.47367 -124.554996) (xy 149.151594 -122.877072) (xy 149.151594 -115.643914) (xy 149.856698 -114.93881)
				(xy 149.856698 -113.346484) (xy 148.719286 -112.209072) (xy 144.420336 -112.209072) (xy 141.79169 -114.837718)
				(xy 141.79169 -123.694444) (xy 142.652242 -124.554996)
			)
		)
	)
	(zone
		(net "PVCCIO_CPU0")
		(layer "B.Cu")
		(hatch none 0.5)
		(connect_pads
			(clearance 0.5)
		)
		(min_thickness 0.25)
		(fill yes
			(thermal_gap 0.5)
			(thermal_bridge_width 0.5)
			(island_removal_mode 0)
		)
		(polygon
			(pts
				(xy 267.520674 -56.99252) (xy 280.50998 -56.99252) (xy 286.61868 -63.10122) (xy 291.93744 -63.10122)
				(xy 292.00983 -63.02883) (xy 295.402 -63.02883) (xy 300.26483 -58.166) (xy 302.845724 -58.166) (xy 303.022 -57.989724)
				(xy 303.022 -57.658) (xy 303.022 -56.475122) (xy 302.884078 -56.3372) (xy 299.5422 -56.3372) (xy 298.069 -54.864)
				(xy 297.883326 -54.864) (xy 297.66641 -54.647084) (xy 297.170094 -54.647084) (xy 296.953178 -54.864)
				(xy 294.894 -54.864) (xy 293.25189 -56.50611) (xy 293.22014 -56.47436) (xy 286.68726 -56.47436)
				(xy 284.22346 -54.01056) (xy 271.613376 -54.01056) (xy 270.713962 -53.111146) (xy 250.594368 -53.111146)
				(xy 249.012202 -53.111146) (xy 248.112788 -54.01056) (xy 232.6386 -54.01056) (xy 232.50906 -54.1401)
				(xy 231.8131 -54.1401) (xy 231.648 -54.3052) (xy 231.1527 -54.3052) (xy 230.85806 -54.01056) (xy 228.64826 -54.01056)
				(xy 228.25456 -54.40426) (xy 228.25456 -56.37276) (xy 228.87432 -56.99252) (xy 230.112824 -58.231024)
				(xy 231.786176 -59.904376) (xy 259.351272 -59.904376) (xy 261.024624 -58.231024) (xy 266.28217 -58.231024)
			)
		)
		(polygon
			(pts
				(arc
					(start 260.263386 -55.48122)
					(mid 260.158151 -55.479115)
					(end 260.10743 -55.57139)
				)
				(arc
					(start 260.10743 -55.57139)
					(mid 260.04664 -55.819031)
					(end 259.862828 -55.995824)
				)
				(arc
					(start 259.862828 -55.995824)
					(mid 259.8085 -56.08574)
					(end 259.862828 -56.175656)
				)
				(arc
					(start 259.862828 -56.175656)
					(mid 260.046643 -56.352149)
					(end 260.107684 -56.599582)
				)
				(arc
					(start 260.107684 -56.599582)
					(mid 260.158273 -56.691872)
					(end 260.263386 -56.689752)
				)
				(arc
					(start 260.263386 -56.689752)
					(mid 260.50875 -56.618421)
					(end 260.754114 -56.689752)
				)
				(arc
					(start 260.754114 -56.689752)
					(mid 260.85912 -56.691686)
					(end 260.909816 -56.599582)
				)
				(arc
					(start 260.909816 -56.599582)
					(mid 260.970787 -56.352109)
					(end 261.154672 -56.175656)
				)
				(arc
					(start 261.154672 -56.175656)
					(mid 261.209 -56.08574)
					(end 261.154672 -55.995824)
				)
				(arc
					(start 261.154672 -55.995824)
					(mid 260.970728 -55.819107)
					(end 260.91007 -55.57139)
				)
				(arc
					(start 260.91007 -55.57139)
					(mid 260.859388 -55.479046)
					(end 260.754114 -55.48122)
				)
				(arc
					(start 260.754114 -55.48122)
					(mid 260.50875 -55.552551)
					(end 260.263386 -55.48122)
				)
			)
		)
	)
	(zone
		(layer "B.Cu")
		(hatch none 0.5)
		(connect_pads
			(clearance 0)
		)
		(min_thickness 0.25)
		(keepout
			(tracks allowed)
			(vias allowed)
			(pads allowed)
			(copperpour allowed)
			(footprints allowed)
		)
		(placement
			(enabled no)
			(sheetname "")
		)
		(fill
			(thermal_gap 0.5)
			(thermal_bridge_width 0.5)
			(island_removal_mode 0)
		)
		(polygon
			(pts
				(xy 311.658 -86.741) (xy 311.658 -85.979) (xy 312.42 -85.979) (xy 312.42 -86.741)
			)
		)
	)
	(zone
		(layer "B.Cu")
		(hatch none 0.5)
		(connect_pads
			(clearance 0)
		)
		(min_thickness 0.25)
		(keepout
			(tracks allowed)
			(vias allowed)
			(pads allowed)
			(copperpour allowed)
			(footprints not_allowed)
		)
		(placement
			(enabled no)
			(sheetname "")
		)
		(fill
			(thermal_gap 0.5)
			(thermal_bridge_width 0.5)
			(island_removal_mode 0)
		)
		(polygon
			(pts
				(xy 22.519894 -0.109982) (xy 163.52012 -0.109982) (xy 163.52012 5.999988) (xy 22.519894 5.999988)
			)
		)
	)
	(zone
		(net "PVDDQ_DEF")
		(layer "B.Cu")
		(hatch none 0.5)
		(connect_pads
			(clearance 0.5)
		)
		(min_thickness 0.25)
		(fill yes
			(thermal_gap 0.5)
			(thermal_bridge_width 0.5)
			(island_removal_mode 0)
		)
		(polygon
			(pts
				(xy 180.514244 -150.447756) (xy 180.1114 -150.8506) (xy 179.6542 -150.8506) (xy 179.4764 -151.0284)
				(xy 179.4764 -152.385268) (xy 179.757832 -152.6667) (xy 181.072028 -152.6667) (xy 182.525162 -151.213566)
				(xy 182.525162 -150.447756)
			)
		)
		(polygon
			(pts
				(xy 181.890162 -151.219408) (xy 181.686962 -151.219408) (xy 181.686962 -151.422608) (xy 181.890162 -151.422608)
			)
		)
		(polygon
			(pts
				(xy 181.356254 -151.158448) (xy 181.153054 -151.158448) (xy 181.153054 -151.361648) (xy 181.356254 -151.361648)
			)
		)
		(polygon
			(pts
				(xy 180.594254 -151.158448) (xy 180.391054 -151.158448) (xy 180.391054 -151.361648) (xy 180.594254 -151.361648)
			)
		)
	)
	(zone
		(net "GND")
		(layer "B.Cu")
		(hatch none 0.5)
		(connect_pads
			(clearance 0.5)
		)
		(min_thickness 0.25)
		(fill yes
			(thermal_gap 0.5)
			(thermal_bridge_width 0.5)
			(island_removal_mode 0)
		)
		(polygon
			(pts
				(xy 278.8412 -22.5552) (xy 278.5872 -22.8092) (xy 278.5872 -25.6286) (xy 277.876 -26.3398) (xy 277.876 -27.7368)
				(xy 277.8887 -27.7495) (xy 277.8887 -28.3083) (xy 277.6982 -28.4988) (xy 277.6982 -28.575) (xy 278.1046 -28.9814)
				(xy 279.9588 -28.9814) (xy 280.797 -28.1432) (xy 280.797 -22.8346) (xy 280.6446 -22.6822) (xy 280.289 -22.6822)
				(xy 280.1874 -22.7838) (xy 280.1874 -23.1394) (xy 280.2636 -23.2156) (xy 280.2636 -26.035) (xy 280.0858 -26.2128)
				(xy 279.2984 -26.2128) (xy 279.146 -26.0604) (xy 279.146 -23.5966) (xy 279.2984 -23.4442) (xy 279.2984 -22.7076)
				(xy 279.146 -22.5552)
			)
		)
		(polygon
			(pts
				(xy 278.6507 -27.6987) (xy 278.4475 -27.6987) (xy 278.4475 -27.9019) (xy 278.6507 -27.9019)
			)
		)
	)
	(zone
		(net "GND")
		(layer "B.Cu")
		(hatch none 0.5)
		(connect_pads
			(clearance 0.5)
		)
		(min_thickness 0.25)
		(fill yes
			(thermal_gap 0.5)
			(thermal_bridge_width 0.5)
			(island_removal_mode 0)
		)
		(polygon
			(pts
				(xy 374.406922 -132.627878) (xy 375.408952 -132.627878) (xy 375.477024 -132.69595) (xy 375.702576 -132.921502)
				(xy 375.702576 -134.132066) (xy 375.662698 -134.171944) (xy 375.154444 -134.171944) (xy 375.107454 -134.218934)
				(xy 375.100088 -134.218934) (xy 373.945404 -134.218934) (xy 373.9007 -134.17423) (xy 373.9007 -133.963664)
				(xy 373.9007 -133.1341)
			)
		)
	)
	(zone
		(net "GND")
		(layer "B.Cu")
		(hatch none 0.5)
		(connect_pads
			(clearance 0.5)
		)
		(min_thickness 0.25)
		(fill yes
			(thermal_gap 0.5)
			(thermal_bridge_width 0.5)
			(island_removal_mode 0)
		)
		(polygon
			(pts
				(xy 475.476824 -13.531088) (xy 477.025208 -13.531088) (xy 477.110806 -13.44549) (xy 477.110806 -12.632182)
				(xy 476.980758 -12.502134) (xy 475.47657 -12.502134) (xy 475.356428 -12.622276) (xy 475.356428 -13.410692)
			)
		)
	)
	(zone
		(layer "B.Cu")
		(hatch none 0.5)
		(connect_pads
			(clearance 0)
		)
		(min_thickness 0.25)
		(keepout
			(tracks not_allowed)
			(vias allowed)
			(pads allowed)
			(copperpour not_allowed)
			(footprints allowed)
		)
		(placement
			(enabled no)
			(sheetname "")
		)
		(fill
			(thermal_gap 0.5)
			(thermal_bridge_width 0.5)
			(island_removal_mode 0)
		)
		(polygon
			(pts
				(arc
					(start 471.000074 -151.100028)
					(mid 467.000082 -155.10002)
					(end 471.000074 -159.100012)
				)
				(arc
					(start 474.49994 -159.100012)
					(mid 478.499932 -155.10002)
					(end 474.49994 -151.100028)
				)
			)
		)
	)
	(zone
		(net "P3V3")
		(layer "B.Cu")
		(hatch none 0.5)
		(connect_pads
			(clearance 0.5)
		)
		(min_thickness 0.25)
		(fill yes
			(thermal_gap 0.5)
			(thermal_bridge_width 0.5)
			(island_removal_mode 0)
		)
		(polygon
			(pts
				(xy 465.902548 -19.358356) (xy 465.902548 -18.650712) (xy 466.1154 -18.43786) (xy 466.360256 -18.193004)
				(xy 466.360256 -17.600168) (xy 466.62086 -17.339564) (xy 466.708744 -17.25168) (xy 466.708744 -16.475202)
				(xy 466.708744 -15.573756) (xy 466.748368 -15.534132) (xy 467.681056 -15.534132) (xy 468.152988 -15.0622)
				(xy 469.0618 -15.0622) (xy 471.2208 -15.0622) (xy 471.6018 -15.4432) (xy 472.8972 -15.4432) (xy 473.075 -15.621)
				(xy 473.075 -16.383) (xy 472.948 -16.51) (xy 472.843352 -16.614648) (xy 471.014552 -16.614648) (xy 469.3666 -18.2626)
				(xy 469.3666 -19.27098) (xy 468.62238 -20.0152) (xy 466.1154 -20.0152) (xy 465.902548 -19.802348)
			)
		)
	)
	(zone
		(layer "B.Cu")
		(hatch none 0.5)
		(connect_pads
			(clearance 0)
		)
		(min_thickness 0.25)
		(keepout
			(tracks not_allowed)
			(vias allowed)
			(pads allowed)
			(copperpour not_allowed)
			(footprints allowed)
		)
		(placement
			(enabled no)
			(sheetname "")
		)
		(fill
			(thermal_gap 0.5)
			(thermal_bridge_width 0.5)
			(island_removal_mode 0)
		)
		(polygon
			(pts
				(arc
					(start 462.939384 -53.756306)
					(mid 462.519413 -54.077471)
					(end 462.840578 -53.6575)
				)
				(xy 462.992724 -53.505354)
				(arc
					(start 462.70799 -53.505354)
					(mid 462.32445 -53.888894)
					(end 462.70799 -54.272434)
				)
				(arc
					(start 463.977736 -54.272434)
					(mid 464.36153 -53.889021)
					(end 463.97799 -53.505354)
				)
				(xy 463.65541 -53.505354)
				(arc
					(start 463.822288 -53.672232)
					(mid 464.185216 -54.056368)
					(end 463.733896 -53.781452)
				)
				(xy 463.457798 -53.505354) (xy 463.190336 -53.505354)
			)
		)
	)
	(zone
		(net "P1V05_PCH_STBY")
		(layer "B.Cu")
		(hatch none 0.5)
		(connect_pads
			(clearance 0.5)
		)
		(min_thickness 0.25)
		(fill yes
			(thermal_gap 0.5)
			(thermal_bridge_width 0.5)
			(island_removal_mode 0)
		)
		(polygon
			(pts
				(xy 396.86738 -106.5022) (xy 398.379696 -106.5022) (xy 399.065496 -107.188) (xy 399.6944 -107.188)
				(xy 400.331432 -107.188) (xy 400.64817 -107.504738) (xy 400.64817 -108.452158) (xy 400.580352 -108.519976)
				(xy 399.090896 -108.519976) (xy 398.771872 -108.839) (xy 394.97 -108.839) (xy 394.3096 -109.4994)
				(xy 394.3096 -110.363) (xy 394.1064 -110.5662) (xy 393.799822 -110.5662) (xy 393.295124 -111.070898)
				(xy 392.701526 -111.070898) (xy 392.072622 -111.070898) (xy 391.521696 -111.621824) (xy 390.512046 -111.621824)
				(xy 390.453626 -111.563404) (xy 390.453626 -111.37392) (xy 391.085324 -110.742222) (xy 391.085324 -110.642654)
				(xy 391.245598 -110.48238) (xy 391.645648 -110.48238) (xy 391.776204 -110.351824) (xy 392.001756 -110.351824)
				(xy 392.2649 -110.351824) (xy 392.72591 -110.351824) (xy 392.828272 -110.249716) (xy 392.828272 -106.942128)
				(xy 392.8618 -106.9086) (xy 393.2682 -106.5022) (xy 393.3698 -106.4006) (xy 393.626086 -106.4006)
				(xy 394.561822 -105.464864) (xy 395.830044 -105.464864) (xy 396.198852 -105.833672)
			)
		)
	)
	(zone
		(net "GND")
		(layer "B.Cu")
		(hatch none 0.5)
		(connect_pads
			(clearance 0.5)
		)
		(min_thickness 0.25)
		(fill yes
			(thermal_gap 0.5)
			(thermal_bridge_width 0.5)
			(island_removal_mode 0)
		)
		(polygon
			(pts
				(xy 365.158528 -101.61905) (xy 364.74781 -102.029768) (xy 364.74781 -104.80421) (xy 365.23422 -105.29062)
				(xy 367.0427 -105.29062) (xy 367.07318 -105.3211) (xy 367.940844 -105.3211) (xy 367.983262 -105.278682)
				(xy 367.983262 -103.310436) (xy 367.228882 -102.556056) (xy 367.228882 -101.758242) (xy 367.08969 -101.61905)
			)
		)
		(polygon
			(pts
				(xy 367.1951 -104.4194) (xy 366.9919 -104.4194) (xy 366.9919 -104.6226) (xy 367.1951 -104.6226)
			)
		)
		(polygon
			(pts
				(xy 367.1951 -103.1494) (xy 366.9919 -103.1494) (xy 366.9919 -103.3526) (xy 367.1951 -103.3526)
			)
		)
		(polygon
			(pts
				(xy 366.445038 -102.45979) (xy 366.241838 -102.45979) (xy 366.241838 -102.66299) (xy 366.445038 -102.66299)
			)
		)
	)
	(zone
		(net "GND")
		(layer "B.Cu")
		(hatch none 0.5)
		(connect_pads
			(clearance 0.5)
		)
		(min_thickness 0.25)
		(fill yes
			(thermal_gap 0.5)
			(thermal_bridge_width 0.5)
			(island_removal_mode 0)
		)
		(polygon
			(pts
				(xy 338.0105 -155.9941) (xy 338.0105 -143.701516) (xy 337.617816 -143.308832) (xy 337.617816 -139.876784)
				(xy 338.201 -139.2936) (xy 345.059 -139.2936) (xy 346.1004 -140.335) (xy 347.599 -140.335) (xy 347.659452 -140.395452)
				(xy 347.659452 -141.924532) (xy 347.345 -142.238984) (xy 347.345 -146.0246) (xy 347.328744 -146.040856)
				(xy 347.328744 -148.116544) (xy 347.5863 -148.3741) (xy 347.5863 -149.3139) (xy 347.4212 -149.479)
				(xy 347.218 -149.6822) (xy 347.218 -155.9306) (xy 347.21165 -155.93695) (xy 347.8149 -156.5402)
				(xy 347.8149 -157.5689) (xy 347.6498 -157.734) (xy 339.2678 -157.734) (xy 338.0105 -156.4767)
			)
		)
	)
	(zone
		(layer "B.Cu")
		(hatch none 0.5)
		(connect_pads
			(clearance 0)
		)
		(min_thickness 0.25)
		(keepout
			(tracks not_allowed)
			(vias allowed)
			(pads allowed)
			(copperpour not_allowed)
			(footprints allowed)
		)
		(placement
			(enabled no)
			(sheetname "")
		)
		(fill
			(thermal_gap 0.5)
			(thermal_bridge_width 0.5)
			(island_removal_mode 0)
		)
		(polygon
			(pts
				(arc
					(start 440.53633 -53.621686)
					(mid 440.116359 -53.942851)
					(end 440.437524 -53.52288)
				)
				(xy 440.58967 -53.370734)
				(arc
					(start 440.304936 -53.370734)
					(mid 439.921396 -53.754274)
					(end 440.304936 -54.137814)
				)
				(arc
					(start 441.574682 -54.137814)
					(mid 441.958222 -53.754401)
					(end 441.574936 -53.370734)
				)
				(xy 441.290202 -53.370734)
				(arc
					(start 441.442348 -53.52288)
					(mid 441.763513 -53.942851)
					(end 441.343542 -53.621686)
				)
				(xy 441.09259 -53.370734) (xy 440.787282 -53.370734)
			)
		)
	)
	(zone
		(net "P3V3_STBY")
		(layer "B.Cu")
		(hatch none 0.5)
		(connect_pads
			(clearance 0.5)
		)
		(min_thickness 0.25)
		(fill yes
			(thermal_gap 0.5)
			(thermal_bridge_width 0.5)
			(island_removal_mode 0)
		)
		(polygon
			(pts
				(xy 399.34134 -54.3941) (xy 397.3195 -54.3941) (xy 397.1925 -54.5211) (xy 397.1925 -55.0672) (xy 397.1925 -55.1561)
				(xy 397.4084 -55.372) (xy 400.5326 -55.372) (xy 401.0406 -55.88) (xy 402.5392 -55.88) (xy 402.6408 -55.7784)
				(xy 402.6408 -54.7116) (xy 402.6408 -54.2036) (xy 402.40204 -53.96484) (xy 399.7706 -53.96484)
			)
		)
	)
	(zone
		(net "PVNN_PCH_STBY")
		(layer "B.Cu")
		(hatch none 0.5)
		(connect_pads
			(clearance 0.5)
		)
		(min_thickness 0.25)
		(fill yes
			(thermal_gap 0.5)
			(thermal_bridge_width 0.5)
			(island_removal_mode 0)
		)
		(polygon
			(pts
				(xy 382.502664 -106.174286) (xy 381.043434 -106.174286) (xy 380.596648 -105.7275)
				(arc
					(start 376.509788 -105.7275)
					(mid 376.428 -105.73637)
					(end 376.346212 -105.7275)
				)
				(xy 374.451372 -105.7275) (xy 374.353582 -105.825544) (xy 374.159018 -106.020108) (xy 370.95557 -106.020108)
				(xy 370.645436 -105.709974) (xy 370.645436 -101.684836) (xy 370.548916 -101.588316) (xy 367.948718 -101.588316)
				(xy 367.74247 -101.794564) (xy 367.74247 -102.59568) (xy 368.456972 -103.310182) (xy 368.456972 -107.689396)
				(xy 370.237512 -109.469936) (xy 374.856248 -109.469936) (xy 375.035318 -109.649006) (xy 375.960386 -109.649006)
				(xy 376.617738 -108.991654) (xy 376.62104 -108.991654) (xy 376.635772 -108.976922) (xy 377.074684 -108.976922)
				(xy 377.840494 -109.742732) (xy 378.642372 -109.742732) (xy 378.663454 -109.73816)
				(arc
					(start 378.66828 -109.736128)
					(mid 378.844955 -109.704488)
					(end 379.016514 -109.75721)
				)
				(xy 379.37059 -109.75721) (xy 379.811534 -109.316266) (xy 383.955036 -109.316266) (xy 384.036824 -109.398054)
				(xy 384.036824 -110.272576) (xy 383.8702 -110.4392) (xy 383.413 -110.4392) (xy 383.2352 -110.617)
				(xy 383.2352 -110.7186) (xy 383.286 -110.7694) (xy 383.286 -111.3282) (xy 383.1844 -111.4298) (xy 383.1844 -112.2934)
				(xy 383.286762 -112.395762) (xy 383.312162 -112.395762) (xy 383.516378 -112.191292) (xy 383.5654 -112.191292)
				(xy 383.5654 -112.141) (xy 383.6416 -112.0648) (xy 383.680208 -112.0648) (xy 383.680462 -112.064292)
				(xy 383.824988 -112.064292) (xy 383.825242 -112.0648) (xy 383.8448 -112.0648) (xy 383.858008 -112.078008)
				(xy 383.858008 -112.325658) (xy 383.942336 -112.409986) (xy 384.313176 -112.409986) (xy 384.419348 -112.303814)
				(xy 384.419348 -112.099852) (xy 384.43916 -112.08004) (xy 384.449066 -112.064292) (xy 384.625088 -112.064292)
				(xy 384.625342 -112.0648) (xy 384.6576 -112.0648) (xy 384.691128 -112.098328) (xy 384.691128 -112.420146)
				(xy 384.75412 -112.483138) (xy 385.121658 -112.483138) (xy 385.193032 -112.411764) (xy 385.193032 -112.15243)
				(xy 385.249166 -112.064292) (xy 385.445508 -112.064292) (xy 385.749292 -111.760254) (xy 385.978654 -111.530892)
				(xy 386.813044 -111.530892) (xy 386.837428 -111.506508) (xy 386.837428 -111.268256) (xy 386.846318 -111.259366)
				(xy 387.030214 -111.259366) (xy 387.083046 -111.312198) (xy 387.083046 -111.564166) (xy 387.231636 -111.712756)
				(xy 387.439408 -111.712756) (xy 387.590284 -111.56188) (xy 387.590284 -111.321596) (xy 387.620764 -111.291116)
				(xy 387.649974 -111.261652) (xy 387.824472 -111.261652) (xy 387.84784 -111.28502) (xy 387.84784 -111.49076)
				(xy 387.883908 -111.526828) (xy 387.887718 -111.530892) (xy 388.638288 -111.530892) (xy 388.81812 -111.710724)
				(xy 389.044688 -111.710724) (xy 389.193278 -111.562134) (xy 389.193278 -111.298736) (xy 389.229854 -111.26216)
				(xy 389.445754 -111.26216) (xy 389.483092 -111.299498) (xy 389.483092 -111.560356) (xy 389.632444 -111.709708)
				(xy 389.847582 -111.709708) (xy 390.018524 -111.538766) (xy 390.018524 -111.295434) (xy 390.050782 -111.263176)
				(xy 390.245092 -111.263176) (xy 390.362186 -111.146082) (xy 390.362186 -110.969044) (xy 390.230106 -110.836964)
				(xy 390.138412 -110.836964) (xy 390.0932 -110.791752) (xy 390.0932 -110.147354) (xy 390.65835 -109.582204)
				(xy 391.20953 -109.582204) (xy 391.55878 -109.232954) (xy 391.55878 -108.930694) (xy 391.44956 -108.821474)
				(xy 391.192512 -108.821474) (xy 391.147046 -108.776008) (xy 391.147046 -108.561378) (xy 391.247884 -108.46054)
				(xy 391.428478 -108.46054) (xy 391.509758 -108.37926) (xy 391.509758 -108.154724) (xy 391.426954 -108.07192)
				(xy 391.3632 -108.07192) (xy 391.3632 -108.070142) (xy 391.220198 -108.070142) (xy 391.143744 -107.993688)
				(xy 391.143744 -107.726988) (xy 391.181336 -107.689396) (xy 391.366756 -107.689396) (xy 391.540746 -107.515406)
				(xy 391.540746 -107.357672) (xy 391.410698 -107.227624) (xy 391.185908 -107.227624) (xy 391.023094 -107.390438)
				(xy 390.799066 -107.390438) (xy 390.654286 -107.245658) (xy 390.39546 -107.245658) (xy 390.300464 -107.340654)
				(xy 390.300464 -107.615736) (xy 390.2456 -107.6706) (xy 390.0678 -107.6706) (xy 389.99795 -107.60075)
				(xy 389.99795 -107.403138) (xy 389.897112 -107.3023) (xy 389.617204 -107.3023) (xy 389.526272 -107.393232)
				(xy 389.230108 -107.393232) (xy 389.090154 -107.253278) (xy 388.771384 -107.253278) (xy 388.645908 -107.378754)
				(xy 388.645908 -109.215174) (xy 388.536688 -109.324394) (xy 388.51586 -109.324394) (xy 388.515606 -109.32414)
				(xy 387.802628 -109.32414) (xy 387.73608 -109.390688) (xy 387.73608 -110.305088) (xy 387.627368 -110.4138)
				(xy 386.2578 -110.4138) (xy 386.1816 -110.3376) (xy 386.1816 -109.3978) (xy 386.181092 -109.397292)
				(xy 386.1816 -109.397292) (xy 386.1816 -109.174026) (xy 385.808474 -108.8009) (xy 385.63804 -108.8009)
				(xy 385.546092 -108.742734) (xy 385.546092 -108.5342) (xy 385.588256 -108.492036) (xy 385.868418 -108.492036)
				(xy 385.904232 -108.456222) (xy 385.904232 -108.09605) (xy 385.85775 -108.049568) (xy 385.569968 -108.049568)
				(xy 385.54025 -108.01985) (xy 385.54025 -107.70235) (xy 385.5974 -107.6452) (xy 385.81457 -107.6452)
				(xy 385.901184 -107.558586) (xy 385.901184 -107.30357) (xy 385.798568 -107.2007) (xy 385.58978 -107.2007)
				(xy 385.54279 -107.15371) (xy 385.54279 -106.911394) (xy 385.271264 -106.639868) (xy 385.271264 -106.507026)
				(xy 385.16306 -106.398822) (xy 384.55854 -106.398822) (xy 384.44424 -106.284522) (xy 384.44424 -105.870248)
				(xy 384.269996 -105.696004) (xy 384.003042 -105.696004) (xy 383.920238 -105.778808) (xy 383.920238 -105.976674)
				(xy 383.839974 -106.056938) (xy 383.644902 -106.056938) (xy 383.557018 -105.969054) (xy 383.557018 -105.771188)
				(xy 383.44983 -105.664) (xy 383.218436 -105.664) (xy 383.099564 -105.782872) (xy 383.099564 -106.007408)
				(xy 383.037842 -106.06913) (xy 382.681734 -106.06913) (xy 382.680972 -106.068368) (xy 382.608582 -106.068368)
			)
		)
		(polygon
			(pts
				(xy 385.3815 -110.1598) (xy 385.1783 -110.1598) (xy 385.1783 -110.363) (xy 385.3815 -110.363)
			)
		)
		(polygon
			(pts
				(xy 384.8735 -110.1344) (xy 384.6703 -110.1344) (xy 384.6703 -110.3376) (xy 384.8735 -110.3376)
			)
		)
		(polygon
			(pts
				(xy 388.62 -110.0963) (xy 388.4168 -110.0963) (xy 388.4168 -110.2995) (xy 388.62 -110.2995)
			)
		)
		(polygon
			(pts
				(xy 385.3815 -109.3978) (xy 385.1783 -109.3978) (xy 385.1783 -109.601) (xy 385.3815 -109.601)
			)
		)
		(polygon
			(pts
				(xy 384.8735 -109.3724) (xy 384.6703 -109.3724) (xy 384.6703 -109.5756) (xy 384.8735 -109.5756)
			)
		)
		(polygon
			(pts
				(xy 369.4811 -105.1814) (xy 369.2779 -105.1814) (xy 369.2779 -105.3846) (xy 369.4811 -105.3846)
			)
		)
		(polygon
			(pts
				(xy 369.824 -105.156) (xy 369.6208 -105.156) (xy 369.6208 -105.3592) (xy 369.824 -105.3592)
			)
		)
		(polygon
			(pts
				(xy 369.4811 -104.4194) (xy 369.2779 -104.4194) (xy 369.2779 -104.6226) (xy 369.4811 -104.6226)
			)
		)
		(polygon
			(pts
				(xy 369.824 -104.394) (xy 369.6208 -104.394) (xy 369.6208 -104.5972) (xy 369.824 -104.5972)
			)
		)
		(polygon
			(pts
				(xy 369.4811 -103.9114) (xy 369.2779 -103.9114) (xy 369.2779 -104.1146) (xy 369.4811 -104.1146)
			)
		)
		(polygon
			(pts
				(xy 369.824 -103.886) (xy 369.6208 -103.886) (xy 369.6208 -104.0892) (xy 369.824 -104.0892)
			)
		)
		(polygon
			(pts
				(xy 369.4811 -103.1494) (xy 369.2779 -103.1494) (xy 369.2779 -103.3526) (xy 369.4811 -103.3526)
			)
		)
		(polygon
			(pts
				(xy 369.824 -103.124) (xy 369.6208 -103.124) (xy 369.6208 -103.3272) (xy 369.824 -103.3272)
			)
		)
		(polygon
			(pts
				(xy 368.731038 -102.45979) (xy 368.527838 -102.45979) (xy 368.527838 -102.66299) (xy 368.731038 -102.66299)
			)
		)
		(polygon
			(pts
				(xy 368.731038 -101.69779) (xy 368.527838 -101.69779) (xy 368.527838 -101.90099) (xy 368.731038 -101.90099)
			)
		)
	)
	(zone
		(net "GND")
		(layer "B.Cu")
		(hatch none 0.5)
		(connect_pads
			(clearance 0.5)
		)
		(min_thickness 0.25)
		(fill yes
			(thermal_gap 0.5)
			(thermal_bridge_width 0.5)
			(island_removal_mode 0)
		)
		(polygon
			(pts
				(xy 452.180198 -137.379202) (xy 452.180198 -139.0142) (xy 452.230998 -139.065) (xy 453.8726 -139.065)
				(xy 454.025 -139.2174) (xy 454.025 -139.6746) (xy 453.6186 -140.081) (xy 453.6186 -140.462) (xy 453.8472 -140.6906)
				(xy 453.8472 -140.8684) (xy 453.8472 -141.0716) (xy 454.152 -141.3764) (xy 455.1426 -141.3764) (xy 455.2696 -141.2494)
				(xy 455.2696 -140.850112) (xy 455.2696 -139.5476) (xy 455.5744 -139.2428) (xy 455.5744 -135.21563)
				(xy 455.400156 -135.041386) (xy 453.044814 -135.041386) (xy 452.8185 -135.2677) (xy 452.8185 -136.7409)
			)
		)
	)
	(zone
		(net "PVDDQ_ABC")
		(layer "B.Cu")
		(hatch none 0.5)
		(connect_pads
			(clearance 0.5)
		)
		(min_thickness 0.25)
		(fill yes
			(thermal_gap 0.5)
			(thermal_bridge_width 0.5)
			(island_removal_mode 0)
		)
		(polygon
			(pts
				(xy 330.581 4.572) (xy 329.438 3.429) (xy 329.438 -4.0386) (xy 329.8698 -4.4704) (xy 331.343 -4.4704)
				(xy 331.6478 -4.7752) (xy 331.6478 -5.8166) (xy 332.2574 -6.4262) (xy 332.2574 -10.2108) (xy 332.0034 -10.4648)
				(xy 332.0034 -12.2936) (xy 332.7908 -13.081) (xy 335.915 -13.081) (xy 336.4865 -12.5095) (xy 338.6455 -12.5095)
				(xy 338.709 -12.446) (xy 338.709 -11.43) (xy 337.693 -10.414) (xy 337.693 4.2164) (xy 337.3374 4.572)
			)
		)
		(polygon
			(pts
				(xy 337.9851 -11.4554) (xy 337.7819 -11.4554) (xy 337.7819 -11.6586) (xy 337.9851 -11.6586)
			)
		)
	)
	(zone
		(net "GND")
		(layer "B.Cu")
		(hatch none 0.5)
		(connect_pads
			(clearance 0.5)
		)
		(min_thickness 0.25)
		(fill yes
			(thermal_gap 0.5)
			(thermal_bridge_width 0.5)
			(island_removal_mode 0)
		)
		(polygon
			(pts
				(xy 458.8764 -137.1092) (xy 461.6958 -137.1092) (xy 461.772 -137.033) (xy 461.772 -136.7282) (xy 461.6958 -136.652)
				(xy 460.883 -136.652) (xy 460.7052 -136.4742) (xy 460.7052 -135.2804) (xy 460.629 -135.2042) (xy 458.851 -135.2042)
				(xy 458.7748 -135.2804) (xy 458.7748 -137.0076)
			)
		)
	)
	(zone
		(net "GND")
		(layer "B.Cu")
		(hatch none 0.5)
		(connect_pads
			(clearance 0.5)
		)
		(min_thickness 0.25)
		(fill yes
			(thermal_gap 0.5)
			(thermal_bridge_width 0.5)
			(island_removal_mode 0)
		)
		(polygon
			(pts
				(xy 48.598328 -60.0964) (xy 48.369728 -60.325) (xy 48.369728 -61.8998) (xy 48.598328 -62.1284) (xy 50.2158 -62.1284)
				(xy 50.4698 -61.8744) (xy 50.4698 -60.2996) (xy 50.2666 -60.0964)
			)
		)
		(polygon
			(pts
				(xy 49.911 -60.883292) (xy 49.7078 -60.883292) (xy 49.7078 -61.340492) (xy 49.911 -61.340492)
			)
		)
		(polygon
			(pts
				(xy 49.149 -60.883292) (xy 48.9458 -60.883292) (xy 48.9458 -61.340492) (xy 49.149 -61.340492)
			)
		)
	)
	(zone
		(layer "B.Cu")
		(hatch none 0.5)
		(connect_pads
			(clearance 0)
		)
		(min_thickness 0.25)
		(keepout
			(tracks not_allowed)
			(vias allowed)
			(pads allowed)
			(copperpour not_allowed)
			(footprints allowed)
		)
		(placement
			(enabled no)
			(sheetname "")
		)
		(fill
			(thermal_gap 0.5)
			(thermal_bridge_width 0.5)
			(island_removal_mode 0)
		)
		(polygon
			(pts
				(xy 344.689176 -77.059536) (xy 344.181176 -77.059536) (xy 344.181176 -77.440536) (xy 344.689176 -77.440536)
			)
		)
	)
	(zone
		(layer "B.Cu")
		(hatch none 0.5)
		(connect_pads
			(clearance 0)
		)
		(min_thickness 0.25)
		(keepout
			(tracks allowed)
			(vias allowed)
			(pads allowed)
			(copperpour allowed)
			(footprints not_allowed)
		)
		(placement
			(enabled no)
			(sheetname "")
		)
		(fill
			(thermal_gap 0.5)
			(thermal_bridge_width 0.5)
			(island_removal_mode 0)
		)
		(polygon
			(pts
				(arc
					(start 501.000014 -62.680088)
					(mid 501.707119 -62.387195)
					(end 502.000012 -61.68009)
				)
				(xy 502.000012 -57.179972) (xy 492.000032 -57.179972) (xy 492.000032 -62.680088)
			)
		)
	)
	(zone
		(layer "B.Cu")
		(hatch none 0.5)
		(connect_pads
			(clearance 0)
		)
		(min_thickness 0.25)
		(keepout
			(tracks allowed)
			(vias allowed)
			(pads allowed)
			(copperpour allowed)
			(footprints not_allowed)
		)
		(placement
			(enabled no)
			(sheetname "")
		)
		(fill
			(thermal_gap 0.5)
			(thermal_bridge_width 0.5)
			(island_removal_mode 0)
		)
		(polygon
			(pts
				(arc
					(start 369.48999 -89.490042)
					(mid 373.080026 -85.900006)
					(end 369.48999 -82.30997)
				)
				(arc
					(start 369.48999 -82.30997)
					(mid 365.899954 -85.900006)
					(end 369.48999 -89.490042)
				)
			)
		)
	)
	(zone
		(layer "B.Cu")
		(hatch none 0.5)
		(connect_pads
			(clearance 0)
		)
		(min_thickness 0.25)
		(keepout
			(tracks not_allowed)
			(vias allowed)
			(pads allowed)
			(copperpour not_allowed)
			(footprints allowed)
		)
		(placement
			(enabled no)
			(sheetname "")
		)
		(fill
			(thermal_gap 0.5)
			(thermal_bridge_width 0.5)
			(island_removal_mode 0)
		)
		(polygon
			(pts
				(arc
					(start 450.147944 -53.621686)
					(mid 449.727973 -53.942851)
					(end 450.049138 -53.52288)
				)
				(xy 450.201284 -53.370734)
				(arc
					(start 449.91655 -53.370734)
					(mid 449.53301 -53.754274)
					(end 449.91655 -54.137814)
				)
				(arc
					(start 451.186296 -54.137814)
					(mid 451.57009 -53.754401)
					(end 451.18655 -53.370734)
				)
				(xy 450.863208 -53.370734)
				(arc
					(start 451.030594 -53.53812)
					(mid 451.393522 -53.922256)
					(end 450.942202 -53.64734)
				)
				(xy 450.665596 -53.370734) (xy 450.398896 -53.370734)
			)
		)
	)
	(zone
		(layer "B.Cu")
		(hatch none 0.5)
		(connect_pads
			(clearance 0)
		)
		(min_thickness 0.25)
		(keepout
			(tracks not_allowed)
			(vias allowed)
			(pads allowed)
			(copperpour not_allowed)
			(footprints allowed)
		)
		(placement
			(enabled no)
			(sheetname "")
		)
		(fill
			(thermal_gap 0.5)
			(thermal_bridge_width 0.5)
			(island_removal_mode 0)
		)
		(polygon
			(pts
				(xy 12.473686 -38.822884) (xy 12.473686 -39.12108) (xy 12.318492 -39.276274)
				(arc
					(start 12.273788 -39.276274)
					(mid 11.749852 -39.211194)
					(end 12.270994 -39.126414)
				)
				(xy 12.333986 -39.063168) (xy 12.333986 -38.823392) (xy 12.333478 -38.822884)
				(arc
					(start 12.016486 -38.822884)
					(mid 11.632946 -39.206424)
					(end 12.016486 -39.589964)
				)
				(arc
					(start 13.032232 -39.589964)
					(mid 13.416026 -39.206551)
					(end 13.032486 -38.822884)
				)
				(xy 12.714986 -38.822884) (xy 12.714986 -38.95598)
				(arc
					(start 12.813284 -39.054278)
					(mid 13.286757 -39.286588)
					(end 12.765786 -39.204392)
				)
				(xy 12.575286 -39.013892) (xy 12.575286 -38.822884)
			)
		)
	)
	(zone
		(layer "B.Cu")
		(hatch none 0.5)
		(connect_pads
			(clearance 0)
		)
		(min_thickness 0.25)
		(keepout
			(tracks not_allowed)
			(vias allowed)
			(pads allowed)
			(copperpour not_allowed)
			(footprints allowed)
		)
		(placement
			(enabled no)
			(sheetname "")
		)
		(fill
			(thermal_gap 0.5)
			(thermal_bridge_width 0.5)
			(island_removal_mode 0)
		)
		(polygon
			(pts
				(xy 347.570806 -59.733434) (xy 347.062806 -59.733434) (xy 347.062806 -60.114434) (xy 347.570806 -60.114434)
			)
		)
	)
	(zone
		(layer "B.Cu")
		(hatch none 0.5)
		(connect_pads
			(clearance 0)
		)
		(min_thickness 0.25)
		(keepout
			(tracks allowed)
			(vias allowed)
			(pads allowed)
			(copperpour allowed)
			(footprints not_allowed)
		)
		(placement
			(enabled no)
			(sheetname "")
		)
		(fill
			(thermal_gap 0.5)
			(thermal_bridge_width 0.5)
			(island_removal_mode 0)
		)
		(polygon
			(pts
				(arc
					(start 127 -109.009942)
					(mid 124.46 -111.549942)
					(end 127 -114.089942)
				)
				(arc
					(start 127 -114.089942)
					(mid 129.54 -111.549942)
					(end 127 -109.009942)
				)
			)
		)
	)
	(zone
		(net "P1V05_PCH_STBY_VCCA_XTAL")
		(layer "B.Cu")
		(hatch none 0.5)
		(connect_pads
			(clearance 0.5)
		)
		(min_thickness 0.25)
		(fill yes
			(thermal_gap 0.5)
			(thermal_bridge_width 0.5)
			(island_removal_mode 0)
		)
		(polygon
			(pts
				(xy 381.2286 -132.6896) (xy 380.9746 -132.9436) (xy 379.9078 -132.9436) (xy 379.7046 -133.1468)
				(xy 377.9012 -133.1468) (xy 377.698 -133.35) (xy 377.698 -134.326884) (xy 377.7488 -134.377684)
				(xy 378.54636 -134.377684) (xy 378.547122 -134.376922) (xy 378.576078 -134.376922) (xy 378.7902 -134.1628)
				(xy 382.9812 -134.1628) (xy 383.159 -133.985) (xy 383.159 -133.0198) (xy 382.8288 -132.6896)
			)
		)
		(polygon
			(pts
				(xy 381.0635 -133.7691) (xy 380.8603 -133.7691) (xy 380.8603 -133.9723) (xy 381.0635 -133.9723)
			)
		)
		(polygon
			(pts
				(xy 380.1237 -133.7691) (xy 379.9205 -133.7691) (xy 379.9205 -133.9723) (xy 380.1237 -133.9723)
			)
		)
		(polygon
			(pts
				(xy 378.6759 -133.4262) (xy 378.4727 -133.4262) (xy 378.4727 -133.6294) (xy 378.6759 -133.6294)
			)
		)
	)
	(zone
		(layer "B.Cu")
		(hatch none 0.5)
		(connect_pads
			(clearance 0)
		)
		(min_thickness 0.25)
		(keepout
			(tracks allowed)
			(vias allowed)
			(pads allowed)
			(copperpour allowed)
			(footprints allowed)
		)
		(placement
			(enabled no)
			(sheetname "")
		)
		(fill
			(thermal_gap 0.5)
			(thermal_bridge_width 0.5)
			(island_removal_mode 0)
		)
		(polygon
			(pts
				(xy 387.604 -128.397) (xy 387.604 -127.508) (xy 388.493 -127.508) (xy 388.493 -128.397)
			)
		)
	)
	(zone
		(net "PVDDQ_KLM")
		(layer "B.Cu")
		(hatch none 0.5)
		(connect_pads
			(clearance 0.5)
		)
		(min_thickness 0.25)
		(fill yes
			(thermal_gap 0.5)
			(thermal_bridge_width 0.5)
			(island_removal_mode 0)
		)
		(polygon
			(pts
				(xy 78.980284 -143.53032) (xy 78.735174 -143.77543) (xy 78.735174 -146.211036) (xy 78.959456 -146.435318)
				(xy 93.983302 -146.435318) (xy 94.615 -145.80362) (xy 94.615 -144.362932) (xy 94.462092 -144.210024)
				(xy 94.030546 -144.210024) (xy 93.490542 -143.67002) (xy 91.799156 -143.67002) (xy 91.659456 -143.53032)
			)
		)
		(polygon
			(pts
				(xy 88.0491 -145.4023) (xy 87.8459 -145.4023) (xy 87.8459 -145.6055) (xy 88.0491 -145.6055)
			)
		)
		(polygon
			(pts
				(xy 84.402168 -145.4023) (xy 84.198968 -145.4023) (xy 84.198968 -145.6055) (xy 84.402168 -145.6055)
			)
		)
		(polygon
			(pts
				(xy 81.303368 -145.4023) (xy 81.100168 -145.4023) (xy 81.100168 -145.6055) (xy 81.303368 -145.6055)
			)
		)
		(polygon
			(pts
				(xy 93.632528 -145.29054) (xy 93.429328 -145.29054) (xy 93.429328 -145.49374) (xy 93.632528 -145.49374)
			)
		)
		(polygon
			(pts
				(xy 88.0491 -144.4117) (xy 87.8459 -144.4117) (xy 87.8459 -144.6149) (xy 88.0491 -144.6149)
			)
		)
		(polygon
			(pts
				(xy 81.303368 -144.4117) (xy 81.100168 -144.4117) (xy 81.100168 -144.6149) (xy 81.303368 -144.6149)
			)
		)
		(polygon
			(pts
				(xy 93.632528 -144.29994) (xy 93.429328 -144.29994) (xy 93.429328 -144.50314) (xy 93.632528 -144.50314)
			)
		)
	)
	(zone
		(net "PVCCIN_CPU1")
		(layer "B.Cu")
		(hatch none 0.5)
		(connect_pads
			(clearance 0.5)
		)
		(min_thickness 0.25)
		(fill yes
			(thermal_gap 0.5)
			(thermal_bridge_width 0.5)
			(island_removal_mode 0)
		)
		(polygon
			(pts
				(xy 94.689168 -88.1126) (xy 95.451168 -88.1126) (xy 95.730568 -87.8332) (xy 96.822768 -87.8332)
				(xy 97.279968 -88.2904) (xy 97.686368 -88.2904) (xy 97.914968 -88.519) (xy 102.512368 -88.519) (xy 103.045768 -89.0524)
				(xy 113.129568 -89.0524) (xy 115.186968 -86.995) (xy 115.186968 -86.4616) (xy 114.577368 -85.852)
				(xy 113.5888 -85.852) (xy 112.9538 -85.217) (xy 112.9538 -84.3534) (xy 112.4712 -83.8708) (xy 111.1504 -83.8708)
				(xy 110.831122 -84.190078) (xy 110.831122 -86.022434) (xy 110.264194 -86.589362) (xy 110.124748 -86.589362)
				(xy 109.868208 -86.589362) (xy 108.43514 -86.589362) (xy 100.087684 -86.589362) (xy 98.131122 -84.6328)
				(xy 90.269568 -84.6328) (xy 90.066368 -84.836) (xy 92.479368 -87.249) (xy 93.825568 -87.249)
			)
		)
	)
	(zone
		(layer "B.Cu")
		(hatch none 0.5)
		(connect_pads
			(clearance 0)
		)
		(min_thickness 0.25)
		(keepout
			(tracks not_allowed)
			(vias allowed)
			(pads allowed)
			(copperpour not_allowed)
			(footprints allowed)
		)
		(placement
			(enabled no)
			(sheetname "")
		)
		(fill
			(thermal_gap 0.5)
			(thermal_bridge_width 0.5)
			(island_removal_mode 0)
		)
		(polygon
			(pts
				(arc
					(start 222.000064 -78.449932)
					(mid 223.899984 -76.550012)
					(end 222.000064 -74.650092)
				)
				(arc
					(start 222.000064 -74.650092)
					(mid 220.100144 -76.550012)
					(end 222.000064 -78.449932)
				)
			)
		)
	)
	(zone
		(net "AGND_P3V3_STBY")
		(layer "B.Cu")
		(hatch none 0.5)
		(connect_pads
			(clearance 0.5)
		)
		(min_thickness 0.25)
		(fill yes
			(thermal_gap 0.5)
			(thermal_bridge_width 0.5)
			(island_removal_mode 0)
		)
		(polygon
			(pts
				(xy 463.8294 -24.779224) (xy 463.8294 -25.8064) (xy 464.2358 -26.2128) (xy 465.4042 -26.2128) (xy 466.2678 -25.3492)
				(xy 466.2678 -24.5618) (xy 466.6234 -24.2062) (xy 467.741 -24.2062) (xy 468.2236 -23.7236) (xy 468.2236 -21.2598)
				(xy 468.0204 -21.0566) (xy 465.5058 -21.0566) (xy 465.1502 -21.4122) (xy 465.1502 -23.4188) (xy 465.1502 -23.458424)
			)
		)
	)
	(zone
		(layer "B.Cu")
		(hatch none 0.5)
		(connect_pads
			(clearance 0)
		)
		(min_thickness 0.25)
		(keepout
			(tracks not_allowed)
			(vias allowed)
			(pads allowed)
			(copperpour not_allowed)
			(footprints allowed)
		)
		(placement
			(enabled no)
			(sheetname "")
		)
		(fill
			(thermal_gap 0.5)
			(thermal_bridge_width 0.5)
			(island_removal_mode 0)
		)
		(polygon
			(pts
				(xy 387.409436 -24.171656) (xy 387.409436 -24.476964)
				(arc
					(start 387.623304 -24.690832)
					(mid 388.017552 -25.183886)
					(end 387.524498 -24.789638)
				)
				(xy 387.409436 -24.674576)
				(arc
					(start 387.409436 -24.95931)
					(mid 387.792976 -25.34285)
					(end 388.176516 -24.95931)
				)
				(arc
					(start 388.176516 -23.689564)
					(mid 387.793103 -23.30577)
					(end 387.409436 -23.68931)
				)
				(xy 387.409436 -23.974044)
				(arc
					(start 387.561582 -23.821898)
					(mid 387.981553 -23.500733)
					(end 387.660388 -23.920704)
				)
			)
		)
	)
	(zone
		(net "PVCCMCP_CPU1")
		(layer "B.Cu")
		(hatch none 0.5)
		(connect_pads
			(clearance 0.5)
		)
		(min_thickness 0.25)
		(fill yes
			(thermal_gap 0.5)
			(thermal_bridge_width 0.5)
			(island_removal_mode 0)
		)
		(polygon
			(pts
				(xy 182.9562 -50.1396) (xy 183.4388 -50.6222) (xy 183.4388 -50.673) (xy 184.531 -51.7652) (xy 184.5818 -51.816)
				(xy 184.7342 -51.9684) (xy 184.9374 -51.9684) (xy 186.944 -51.9684) (xy 187.3758 -51.5366) (xy 187.3758 -50.4952)
				(xy 189.716156 -48.154844) (xy 195.042028 -48.154844) (xy 195.31203 -47.884842) (xy 195.31203 -45.593)
				(xy 195.18503 -45.466) (xy 194.31 -45.466) (xy 192.818004 -46.957996) (xy 184.625996 -46.957996)
				(xy 176.846992 -48.578008) (xy 176.192688 -49.232312) (xy 176.192688 -49.359312) (xy 176.972722 -50.1396)
			)
		)
	)
	(zone
		(layer "B.Cu")
		(hatch none 0.5)
		(connect_pads
			(clearance 0)
		)
		(min_thickness 0.25)
		(keepout
			(tracks not_allowed)
			(vias allowed)
			(pads allowed)
			(copperpour not_allowed)
			(footprints allowed)
		)
		(placement
			(enabled no)
			(sheetname "")
		)
		(fill
			(thermal_gap 0.5)
			(thermal_bridge_width 0.5)
			(island_removal_mode 0)
		)
		(polygon
			(pts
				(arc
					(start 336.45983 -70.901814)
					(mid 336.039859 -71.222979)
					(end 336.361024 -70.803008)
				)
				(xy 336.42935 -70.734682) (xy 336.42935 -70.650862)
				(arc
					(start 336.228436 -70.650862)
					(mid 335.844896 -71.034402)
					(end 336.228436 -71.417942)
				)
				(arc
					(start 337.119468 -71.417942)
					(mid 337.503262 -71.034529)
					(end 337.119722 -70.650862)
				)
				(xy 336.834988 -70.650862)
				(arc
					(start 336.987134 -70.803008)
					(mid 337.308299 -71.222979)
					(end 336.888328 -70.901814)
				)
				(xy 336.67065 -70.684136) (xy 336.67065 -70.650862) (xy 336.56905 -70.650862) (xy 336.56905 -70.792594)
			)
		)
	)
	(zone
		(layer "B.Cu")
		(hatch none 0.5)
		(connect_pads
			(clearance 0)
		)
		(min_thickness 0.25)
		(keepout
			(tracks not_allowed)
			(vias allowed)
			(pads allowed)
			(copperpour not_allowed)
			(footprints allowed)
		)
		(placement
			(enabled no)
			(sheetname "")
		)
		(fill
			(thermal_gap 0.5)
			(thermal_bridge_width 0.5)
			(island_removal_mode 0)
		)
		(polygon
			(pts
				(arc
					(start 175.50003 -1.999996)
					(mid 179.500022 1.999996)
					(end 175.50003 5.999988)
				)
				(arc
					(start 171.99991 5.999988)
					(mid 167.999918 1.999996)
					(end 171.99991 -1.999996)
				)
			)
		)
	)
	(zone
		(layer "B.Cu")
		(hatch none 0.5)
		(connect_pads
			(clearance 0)
		)
		(min_thickness 0.25)
		(keepout
			(tracks allowed)
			(vias allowed)
			(pads allowed)
			(copperpour allowed)
			(footprints not_allowed)
		)
		(placement
			(enabled no)
			(sheetname "")
		)
		(fill
			(thermal_gap 0.5)
			(thermal_bridge_width 0.5)
			(island_removal_mode 0)
		)
		(polygon
			(pts
				(arc
					(start 248.000012 -44.090082)
					(mid 250.540012 -41.550082)
					(end 248.000012 -39.010082)
				)
				(arc
					(start 248.000012 -39.010082)
					(mid 245.460012 -41.550082)
					(end 248.000012 -44.090082)
				)
			)
		)
	)
	(zone
		(net "PVPP_GHJ")
		(layer "B.Cu")
		(hatch none 0.5)
		(connect_pads
			(clearance 0.5)
		)
		(min_thickness 0.25)
		(fill yes
			(thermal_gap 0.5)
			(thermal_bridge_width 0.5)
			(island_removal_mode 0)
		)
		(polygon
			(pts
				(xy 154.051 3.4925) (xy 153.58364 3.02514) (xy 153.58364 1.97358) (xy 153.3652 1.75514) (xy 153.3652 1.397)
				(xy 152.19426 0.22606) (xy 152.19426 -4.689094) (xy 151.896572 -4.689094) (xy 151.799798 -4.785868)
				(xy 151.799798 -6.403086) (xy 152.18664 -6.789928) (xy 152.19426 -6.789928) (xy 152.19426 -13.3604)
				(xy 151.8412 -13.71346) (xy 151.8412 -16.129) (xy 152.19426 -16.48206) (xy 152.19426 -22.67458)
				(xy 153.0858 -23.56612) (xy 154.1907 -23.56612) (xy 154.3939 -23.76932) (xy 154.3939 -25.7302) (xy 154.4447 -25.781)
				(xy 155.702 -25.781) (xy 155.7528 -25.7302) (xy 155.7528 -23.79472) (xy 155.9814 -23.56612) (xy 159.99968 -23.56612)
				(xy 160.4391 -23.1267) (xy 160.4391 -21.9075) (xy 161.3789 -20.9677) (xy 163.0299 -20.9677) (xy 163.5379 -21.4757)
				(xy 163.5379 -23.5712) (xy 163.6903 -23.7236) (xy 164.1094 -23.7236) (xy 165.819074 -23.336504)
				(xy 166.105078 -23.0505) (xy 166.105078 -22.577044) (xy 168.148 -20.534122) (xy 168.148 -17.907)
				(xy 167.513 -17.272) (xy 167.513 -8.9408) (xy 167.2336 -8.6614) (xy 162.7632 -8.6614) (xy 161.135568 -7.033768)
				(xy 161.135568 3.032252) (xy 160.67532 3.4925)
			)
		)
		(polygon
			(pts
				(xy 154.8511 -18.0594) (xy 154.6479 -18.0594) (xy 154.6479 -18.2626) (xy 154.8511 -18.2626)
			)
		)
		(polygon
			(pts
				(xy 154.0891 -18.0594) (xy 153.8859 -18.0594) (xy 153.8859 -18.2626) (xy 154.0891 -18.2626)
			)
		)
		(polygon
			(pts
				(xy 154.8511 -17.2974) (xy 154.6479 -17.2974) (xy 154.6479 -17.5006) (xy 154.8511 -17.5006)
			)
		)
		(polygon
			(pts
				(xy 154.0891 -17.2974) (xy 153.8859 -17.2974) (xy 153.8859 -17.5006) (xy 154.0891 -17.5006)
			)
		)
		(polygon
			(pts
				(xy 154.8511 -8.4074) (xy 154.6479 -8.4074) (xy 154.6479 -8.6106) (xy 154.8511 -8.6106)
			)
		)
		(polygon
			(pts
				(xy 154.0891 -8.4074) (xy 153.8859 -8.4074) (xy 153.8859 -8.6106) (xy 154.0891 -8.6106)
			)
		)
		(polygon
			(pts
				(xy 154.8511 -7.6454) (xy 154.6479 -7.6454) (xy 154.6479 -7.8486) (xy 154.8511 -7.8486)
			)
		)
		(polygon
			(pts
				(xy 154.0891 -7.6454) (xy 153.8859 -7.6454) (xy 153.8859 -7.8486) (xy 154.0891 -7.8486)
			)
		)
		(polygon
			(pts
				(xy 154.8511 1.4224) (xy 154.6479 1.4224) (xy 154.6479 1.2192) (xy 154.8511 1.2192)
			)
		)
		(polygon
			(pts
				(xy 154.3431 1.4224) (xy 154.1399 1.4224) (xy 154.1399 1.2192) (xy 154.3431 1.2192)
			)
		)
		(polygon
			(pts
				(xy 154.8511 2.1844) (xy 154.6479 2.1844) (xy 154.6479 1.9812) (xy 154.8511 1.9812)
			)
		)
		(polygon
			(pts
				(xy 154.3431 2.1844) (xy 154.1399 2.1844) (xy 154.1399 1.9812) (xy 154.3431 1.9812)
			)
		)
	)
	(zone
		(net "P12V_STBY")
		(layer "B.Cu")
		(hatch none 0.5)
		(connect_pads
			(clearance 0.5)
		)
		(min_thickness 0.25)
		(fill yes
			(thermal_gap 0.5)
			(thermal_bridge_width 0.5)
			(island_removal_mode 0)
		)
		(polygon
			(pts
				(xy 3.345688 -116.5352) (xy 0.8382 -116.5352) (xy 0.451358 -116.5352) (xy -0.053848 -116.030248)
				(xy -1.470152 -116.030248) (xy -1.5748 -115.9256) (xy -1.5748 -115.7478) (xy -1.5748 -115.248436)
				(xy -1.566418 -115.240054) (xy -1.566418 -113.483898) (xy -1.566418 -112.691418) (xy -1.4478 -112.5728)
				(xy -1.241298 -112.5728) (xy 1.752854 -112.5728) (xy 2.432812 -113.252504) (xy 2.432812 -113.507012)
				(xy 3.39979 -114.47399) (xy 3.39979 -116.481098)
			)
		)
	)
	(zone
		(layer "B.Cu")
		(hatch none 0.5)
		(connect_pads
			(clearance 0)
		)
		(min_thickness 0.25)
		(keepout
			(tracks allowed)
			(vias allowed)
			(pads allowed)
			(copperpour allowed)
			(footprints not_allowed)
		)
		(placement
			(enabled no)
			(sheetname "")
		)
		(fill
			(thermal_gap 0.5)
			(thermal_bridge_width 0.5)
			(island_removal_mode 0)
		)
		(polygon
			(pts
				(arc
					(start 493.100614 -116.196872)
					(mid 496.700556 -119.796814)
					(end 500.300498 -116.196872)
				)
				(arc
					(start 500.300498 -114.596926)
					(mid 496.700556 -110.996984)
					(end 493.100614 -114.596926)
				)
			)
		)
	)
	(zone
		(layer "B.Cu")
		(hatch none 0.5)
		(connect_pads
			(clearance 0)
		)
		(min_thickness 0.25)
		(keepout
			(tracks allowed)
			(vias allowed)
			(pads allowed)
			(copperpour allowed)
			(footprints allowed)
		)
		(placement
			(enabled no)
			(sheetname "")
		)
		(fill
			(thermal_gap 0.5)
			(thermal_bridge_width 0.5)
			(island_removal_mode 0)
		)
		(polygon
			(pts
				(xy 314.96 -87.884) (xy 314.96 -87.122) (xy 315.722 -87.122) (xy 315.722 -87.884)
			)
		)
	)
	(zone
		(net "PVDDQ_DEF")
		(layer "B.Cu")
		(hatch none 0.5)
		(connect_pads
			(clearance 0.5)
		)
		(min_thickness 0.25)
		(fill yes
			(thermal_gap 0.5)
			(thermal_bridge_width 0.5)
			(island_removal_mode 0)
		)
		(polygon
			(pts
				(xy 329.863958 -139.4333) (xy 329.583288 -139.71397) (xy 329.583288 -146.330416) (xy 329.0951 -146.818604)
				(xy 329.0951 -152.5905) (xy 329.819 -153.3144) (xy 329.819 -155.0162) (xy 331.1906 -156.3878) (xy 331.1906 -156.464)
				(xy 332.105 -156.464) (xy 332.74 -157.099) (xy 337.312 -157.099) (xy 337.693 -156.718) (xy 337.693 -143.891)
				(xy 336.677 -142.875) (xy 336.677 -139.9286) (xy 336.1817 -139.4333)
			)
		)
		(polygon
			(pts
				(xy 331.8256 -155.2829) (xy 331.6224 -155.2829) (xy 331.6224 -155.4861) (xy 331.8256 -155.4861)
			)
		)
		(polygon
			(pts
				(xy 331.0636 -155.2829) (xy 330.8604 -155.2829) (xy 330.8604 -155.4861) (xy 331.0636 -155.4861)
			)
		)
	)
	(zone
		(net "VR_FET_SW_P12V_STBY_PVDDQ_GHJ")
		(layer "B.Cu")
		(hatch none 0.5)
		(connect_pads
			(clearance 0.5)
		)
		(min_thickness 0.25)
		(fill yes
			(thermal_gap 0.5)
			(thermal_bridge_width 0.5)
			(island_removal_mode 0)
		)
		(polygon
			(pts
				(xy -2.6416 -5.3848) (xy -2.921 -5.6642) (xy -2.921 -14.605) (xy -3.913886 -15.597886) (xy -3.913886 -16.371062)
				(xy -3.913886 -16.537178) (xy -3.765804 -16.68526) (xy -3.14452 -16.68526) (xy -2.79908 -17.0307)
				(xy -2.79908 -18.701512) (xy -2.79908 -18.923) (xy -1.98628 -19.7358) (xy -0.61849 -19.7358) (xy -0.398526 -19.955764)
				(xy 0.67691 -21.0312) (xy 0.677418 -21.0312) (xy 0.677418 -22.264116) (xy 1.093216 -22.679914) (xy 3.992118 -22.679914)
				(xy 4.428236 -22.243796) (xy 4.428236 -16.246348) (xy 4.428236 -15.926816) (xy 4.13004 -15.62862)
				(xy 2.91846 -15.62862) (xy 2.81686 -15.73022) (xy 2.7305 -15.81658) (xy 2.7305 -16.463518) (xy 2.373122 -16.820896)
				(xy 1.227836 -16.820896) (xy 0.940562 -17.10817) (xy 0.615696 -17.10817) (xy 0.236474 -16.728948)
				(xy 0.192278 -16.728948) (xy -0.644652 -16.728948) (xy -0.910844 -16.462756) (xy -0.910844 -15.218156)
				(xy -0.910336 -15.217648) (xy -0.910336 -15.204186) (xy -0.633984 -14.927834) (xy -0.620522 -14.927834)
				(xy 1.375156 -14.927834) (xy 1.505458 -14.797532) (xy 1.505458 -14.142974) (xy 1.505458 -13.954252)
				(xy 2.602992 -12.856718) (xy 4.48056 -12.856718) (xy 4.51104 -12.826238) (xy 4.51104 -12.2809) (xy 4.3688 -12.13866)
				(xy 4.3688 -12.13612) (xy 4.3307 -12.09802) (xy 4.3307 -7.12343) (xy 4.3307 -7.073138) (xy 4.296918 -7.039356)
				(xy 3.358134 -7.039356) (xy 3.327146 -7.070344) (xy 3.31343 -7.08406) (xy 3.31343 -8.510524) (xy 3.328162 -8.525256)
				(xy 3.328162 -8.56488) (xy 3.328162 -8.720582) (xy 3.31343 -8.735314) (xy 3.31343 -8.941562) (xy 3.31343 -9.148318)
				(xy 3.31343 -9.348216) (xy 3.31343 -9.45642) (xy 3.039872 -9.729978) (xy 2.931668 -9.729978) (xy 2.566924 -10.094722)
				(xy 0.052324 -10.094722) (xy 0.041402 -10.0838) (xy -0.633984 -9.408414) (xy -0.633984 -7.822184)
				(xy -0.633984 -5.804916) (xy -1.0541 -5.3848)
			)
		)
	)
	(zone
		(layer "B.Cu")
		(hatch none 0.5)
		(connect_pads
			(clearance 0)
		)
		(min_thickness 0.25)
		(keepout
			(tracks not_allowed)
			(vias allowed)
			(pads allowed)
			(copperpour not_allowed)
			(footprints allowed)
		)
		(placement
			(enabled no)
			(sheetname "")
		)
		(fill
			(thermal_gap 0.5)
			(thermal_bridge_width 0.5)
			(island_removal_mode 0)
		)
		(polygon
			(pts
				(arc
					(start 443.747144 -53.621686)
					(mid 443.327173 -53.942851)
					(end 443.648338 -53.52288)
				)
				(xy 443.800484 -53.370734)
				(arc
					(start 443.51575 -53.370734)
					(mid 443.13221 -53.754274)
					(end 443.51575 -54.137814)
				)
				(arc
					(start 444.785496 -54.137814)
					(mid 445.16929 -53.754401)
					(end 444.78575 -53.370734)
				)
				(xy 444.501016 -53.370734)
				(arc
					(start 444.653162 -53.52288)
					(mid 444.974327 -53.942851)
					(end 444.554356 -53.621686)
				)
				(xy 444.303404 -53.370734) (xy 443.998096 -53.370734)
			)
		)
	)
	(zone
		(net "PVDDQ_KLM")
		(layer "B.Cu")
		(hatch none 0.5)
		(connect_pads
			(clearance 0.5)
		)
		(min_thickness 0.25)
		(fill yes
			(thermal_gap 0.5)
			(thermal_bridge_width 0.5)
			(island_removal_mode 0)
		)
		(polygon
			(pts
				(xy 104.31526 -131.819396) (xy 112.401096 -131.819396) (xy 112.750346 -131.470146) (xy 112.750346 -129.702814)
				(xy 112.42167 -129.374138) (xy 107.469432 -129.374138) (xy 107.3658 -129.47777) (xy 107.3658 -130.0988)
				(xy 106.87812 -130.58648) (xy 106.092752 -130.58648) (xy 105.866692 -130.81254) (xy 105.065068 -130.81254)
				(xy 104.880156 -130.627628) (xy 104.407716 -130.627628) (xy 104.31526 -130.720084)
			)
		)
	)
	(zone
		(layer "B.Cu")
		(hatch none 0.5)
		(connect_pads
			(clearance 0)
		)
		(min_thickness 0.25)
		(keepout
			(tracks allowed)
			(vias allowed)
			(pads allowed)
			(copperpour allowed)
			(footprints not_allowed)
		)
		(placement
			(enabled no)
			(sheetname "")
		)
		(fill
			(thermal_gap 0.5)
			(thermal_bridge_width 0.5)
			(island_removal_mode 0)
		)
		(polygon
			(pts
				(xy 163.52012 -143.386302) (xy 22.519894 -143.386302) (xy 22.519894 -146.567398) (xy 163.52012 -146.567398)
			)
		)
	)
	(zone
		(net "P1V2_AUX_BMC")
		(layer "B.Cu")
		(hatch none 0.5)
		(connect_pads
			(clearance 0.5)
		)
		(min_thickness 0.25)
		(fill yes
			(thermal_gap 0.5)
			(thermal_bridge_width 0.5)
			(island_removal_mode 0)
		)
		(polygon
			(pts
				(xy 467.884764 -35.597592) (xy 467.884764 -36.792154) (xy 468.141304 -37.048694) (xy 471.48877 -37.048694)
				(xy 471.974926 -37.048694) (xy 472.09202 -36.9316) (xy 472.09202 -35.0393) (xy 471.94978 -34.89706)
				(xy 470.74582 -34.89706) (xy 470.7382 -34.90468) (xy 468.03564 -34.90468) (xy 467.884764 -35.055556)
			)
		)
		(polygon
			(pts
				(xy 468.887302 -36.715192) (xy 468.684102 -36.715192) (xy 468.684102 -36.918392) (xy 468.887302 -36.918392)
			)
		)
		(polygon
			(pts
				(xy 468.887302 -35.953192) (xy 468.684102 -35.953192) (xy 468.684102 -36.156392) (xy 468.887302 -36.156392)
			)
		)
	)
	(zone
		(layer "B.Cu")
		(hatch none 0.5)
		(connect_pads
			(clearance 0.5)
		)
		(min_thickness 0.25)
		(fill
			(thermal_gap 0.5)
			(thermal_bridge_width 0.5)
			(island_removal_mode 0)
		)
		(polygon
			(pts
				(xy 33.2994 -72.198484) (xy 32.553402 -72.198484) (xy 32.318452 -72.433434) (xy 32.318452 -73.550018)
				(xy 32.192214 -73.676256) (xy 31.787084 -73.676256) (xy 31.588202 -73.875138) (xy 31.588202 -74.887582)
				(xy 30.948884 -75.5269) (xy 30.743144 -75.73264) (xy 30.743144 -76.734162) (xy 31.021782 -77.0128)
				(xy 33.1216 -77.0128) (xy 33.3248 -76.8096) (xy 33.3248 -72.223884)
			)
		)
	)
	(zone
		(net "P3V3_STBY")
		(layer "B.Cu")
		(hatch none 0.5)
		(connect_pads
			(clearance 0.5)
		)
		(min_thickness 0.25)
		(fill yes
			(thermal_gap 0.5)
			(thermal_bridge_width 0.5)
			(island_removal_mode 0)
		)
		(polygon
			(pts
				(xy 491.2614 -27.813) (xy 490.728 -27.813) (xy 490.601 -27.686) (xy 490.601 -25.8826) (xy 490.728 -25.7556)
				(xy 492.252 -25.7556) (xy 492.6076 -25.7556) (xy 492.7727 -25.9207) (xy 492.7727 -26.9367) (xy 492.6076 -27.1018)
				(xy 492.5441 -27.1272) (xy 492.4679 -27.1526) (xy 492.4044 -27.1526) (xy 492.379 -27.178) (xy 491.8964 -27.178)
			)
		)
	)
	(zone
		(net "GND")
		(layer "B.Cu")
		(hatch none 0.5)
		(connect_pads
			(clearance 0.5)
		)
		(min_thickness 0.25)
		(fill yes
			(thermal_gap 0.5)
			(thermal_bridge_width 0.5)
			(island_removal_mode 0)
		)
		(polygon
			(pts
				(xy 356.663752 -97.009712) (xy 357.349044 -97.009712) (xy 357.367332 -96.991424) (xy 357.542592 -96.991424)
				(xy 357.677466 -96.85655) (xy 357.677466 -92.685362) (xy 356.94112 -91.949016) (xy 353.593908 -91.949016)
				(xy 353.331272 -92.211652) (xy 353.331272 -92.765626) (xy 353.418902 -92.853256) (xy 353.776026 -93.21038)
				(xy 355.868986 -93.21038) (xy 356.437692 -93.779086) (xy 356.437692 -96.783652)
			)
		)
	)
	(zone
		(layer "B.Cu")
		(hatch none 0.5)
		(connect_pads
			(clearance 0)
		)
		(min_thickness 0.25)
		(keepout
			(tracks not_allowed)
			(vias allowed)
			(pads allowed)
			(copperpour not_allowed)
			(footprints allowed)
		)
		(placement
			(enabled no)
			(sheetname "")
		)
		(fill
			(thermal_gap 0.5)
			(thermal_bridge_width 0.5)
			(island_removal_mode 0)
		)
		(polygon
			(pts
				(arc
					(start 248.000012 -43.450002)
					(mid 249.899932 -41.550082)
					(end 248.000012 -39.649908)
				)
				(arc
					(start 248.000012 -39.649908)
					(mid 246.099838 -41.550082)
					(end 248.000012 -43.450002)
				)
			)
		)
	)
	(zone
		(net "PVDDQ_GHJ")
		(layer "B.Cu")
		(hatch none 0.5)
		(connect_pads
			(clearance 0.5)
		)
		(min_thickness 0.25)
		(fill yes
			(thermal_gap 0.5)
			(thermal_bridge_width 0.5)
			(island_removal_mode 0)
		)
		(polygon
			(pts
				(xy 112.265968 -2.1082) (xy 100.743512 -2.1082) (xy 100.743512 -2.9464) (xy 101.454712 -3.6576)
				(xy 101.454712 -4.3942) (xy 101.628956 -4.568444) (xy 101.628956 -5.794756) (xy 101.727 -5.8928)
				(xy 102.1334 -5.8928) (xy 102.267512 -5.758688) (xy 102.267512 -4.5974) (xy 102.343712 -4.5212)
				(xy 112.164368 -4.5212) (xy 112.395 -4.290568) (xy 112.395 -3.937) (xy 112.3188 -3.8608) (xy 111.5695 -3.8608)
				(xy 111.4425 -3.7338) (xy 111.4425 -2.9718) (xy 111.5695 -2.8448) (xy 112.3569 -2.8448) (xy 112.451134 -2.750566)
				(xy 112.451134 -2.293366)
			)
		)
	)
	(zone
		(layer "B.Cu")
		(hatch none 0.5)
		(connect_pads
			(clearance 0)
		)
		(min_thickness 0.25)
		(keepout
			(tracks allowed)
			(vias allowed)
			(pads allowed)
			(copperpour allowed)
			(footprints not_allowed)
		)
		(placement
			(enabled no)
			(sheetname "")
		)
		(fill
			(thermal_gap 0.5)
			(thermal_bridge_width 0.5)
			(island_removal_mode 0)
		)
		(polygon
			(pts
				(xy 328.520044 -143.386302) (xy 187.520072 -143.386302) (xy 187.520072 -146.567398) (xy 328.520044 -146.567398)
			)
		)
	)
	(zone
		(layer "B.Cu")
		(hatch none 0.5)
		(connect_pads
			(clearance 0)
		)
		(min_thickness 0.25)
		(keepout
			(tracks not_allowed)
			(vias allowed)
			(pads allowed)
			(copperpour not_allowed)
			(footprints allowed)
		)
		(placement
			(enabled no)
			(sheetname "")
		)
		(fill
			(thermal_gap 0.5)
			(thermal_bridge_width 0.5)
			(island_removal_mode 0)
		)
		(polygon
			(pts
				(xy 445.99225 -125.703584) (xy 445.99225 -126.00178) (xy 445.837056 -126.156974)
				(arc
					(start 445.665352 -126.156974)
					(mid 445.141435 -126.087124)
					(end 445.665352 -126.017274)
				)
				(xy 445.779144 -126.017274) (xy 445.85255 -125.943868) (xy 445.85255 -125.703584)
				(arc
					(start 445.408304 -125.703584)
					(mid 445.02451 -126.086997)
					(end 445.40805 -126.470664)
				)
				(arc
					(start 446.67805 -126.470664)
					(mid 447.06159 -126.087124)
					(end 446.67805 -125.703584)
				)
				(xy 446.23355 -125.703584) (xy 446.23355 -125.943868) (xy 446.306956 -126.017274)
				(arc
					(start 446.420748 -126.017274)
					(mid 446.944665 -126.087124)
					(end 446.420748 -126.156974)
				)
				(xy 446.249044 -126.156974) (xy 446.09385 -126.00178) (xy 446.09385 -125.703584)
			)
		)
	)
	(zone
		(net "P1V05_PCH_STBY")
		(layer "B.Cu")
		(hatch none 0.5)
		(connect_pads
			(clearance 0.5)
		)
		(min_thickness 0.25)
		(fill yes
			(thermal_gap 0.5)
			(thermal_bridge_width 0.5)
			(island_removal_mode 0)
		)
		(polygon
			(pts
				(xy 371.38483 -135.89) (xy 371.639592 -135.635238) (xy 372.766082 -135.635238) (xy 372.829328 -135.571992)
				(xy 372.829328 -134.638034) (xy 372.76786 -134.576566) (xy 370.783104 -134.576566) (xy 370.416074 -134.576566)
				(xy 370.164868 -134.827772) (xy 370.164868 -135.727948) (xy 370.32692 -135.89)
			)
		)
	)
	(zone
		(layer "B.Cu")
		(hatch none 0.5)
		(connect_pads
			(clearance 0)
		)
		(min_thickness 0.25)
		(keepout
			(tracks not_allowed)
			(vias allowed)
			(pads allowed)
			(copperpour not_allowed)
			(footprints allowed)
		)
		(placement
			(enabled no)
			(sheetname "")
		)
		(fill
			(thermal_gap 0.5)
			(thermal_bridge_width 0.5)
			(island_removal_mode 0)
		)
		(polygon
			(pts
				(arc
					(start 0 4.750054)
					(mid -4.750054 0)
					(end 0 -4.750054)
				)
				(arc
					(start 3.50012 -4.750054)
					(mid 8.250174 0)
					(end 3.50012 4.750054)
				)
			)
		)
	)
	(zone
		(layer "B.Cu")
		(hatch none 0.5)
		(connect_pads
			(clearance 0)
		)
		(min_thickness 0.25)
		(keepout
			(tracks not_allowed)
			(vias allowed)
			(pads allowed)
			(copperpour not_allowed)
			(footprints allowed)
		)
		(placement
			(enabled no)
			(sheetname "")
		)
		(fill
			(thermal_gap 0.5)
			(thermal_bridge_width 0.5)
			(island_removal_mode 0)
		)
		(polygon
			(pts
				(arc
					(start 83.000088 -43.450002)
					(mid 84.900008 -41.550082)
					(end 83.000088 -39.649908)
				)
				(arc
					(start 83.000088 -39.649908)
					(mid 81.099914 -41.550082)
					(end 83.000088 -43.450002)
				)
			)
		)
	)
	(zone
		(layer "B.Cu")
		(hatch none 0.5)
		(connect_pads
			(clearance 0)
		)
		(min_thickness 0.25)
		(keepout
			(tracks allowed)
			(vias allowed)
			(pads allowed)
			(copperpour allowed)
			(footprints not_allowed)
		)
		(placement
			(enabled no)
			(sheetname "")
		)
		(fill
			(thermal_gap 0.5)
			(thermal_bridge_width 0.5)
			(island_removal_mode 0)
		)
		(polygon
			(pts
				(arc
					(start 472.928696 0.055626)
					(mid 472.3383 0.385683)
					(end 471.67165 0.500126)
				)
				(arc
					(start 471.000074 0.500126)
					(mid 469.49995 2.00025)
					(end 471.000074 3.50012)
				)
				(arc
					(start 471.67165 3.50012)
					(mid 472.338277 3.614414)
					(end 472.928696 3.944366)
				)
				(arc
					(start 472.928696 3.944366)
					(mid 476.999816 1.999996)
					(end 472.928696 0.055626)
				)
			)
		)
	)
	(zone
		(layer "B.Cu")
		(hatch none 0.5)
		(connect_pads
			(clearance 0)
		)
		(min_thickness 0.25)
		(keepout
			(tracks allowed)
			(vias allowed)
			(pads allowed)
			(copperpour allowed)
			(footprints not_allowed)
		)
		(placement
			(enabled no)
			(sheetname "")
		)
		(fill
			(thermal_gap 0.5)
			(thermal_bridge_width 0.5)
			(island_removal_mode 0)
		)
		(polygon
			(pts
				(arc
					(start 83.000088 -39.010082)
					(mid 80.460088 -41.550082)
					(end 83.000088 -44.090082)
				)
				(arc
					(start 83.000088 -44.090082)
					(mid 85.540088 -41.550082)
					(end 83.000088 -39.010082)
				)
			)
		)
	)
	(zone
		(net "P1V05_PCH_STBY_ISCLK_PLL")
		(layer "B.Cu")
		(hatch none 0.5)
		(connect_pads
			(clearance 0.5)
		)
		(min_thickness 0.25)
		(fill yes
			(thermal_gap 0.5)
			(thermal_bridge_width 0.5)
			(island_removal_mode 0)
		)
		(polygon
			(pts
				(xy 373.77116 -129.0701) (xy 373.57304 -129.26822) (xy 373.57304 -130.69316) (xy 373.0117 -131.2545)
				(xy 373.0117 -131.715002) (xy 372.9736 -131.753102) (xy 372.968012 -131.753102) (xy 372.6307 -132.090414)
				(xy 371.668802 -132.090414) (xy 371.668802 -133.058408) (xy 371.72011 -133.109716) (xy 372.225316 -133.109716)
				(xy 372.491 -133.3754) (xy 372.491 -134.225284) (xy 373.413274 -134.225284) (xy 373.53367 -134.104888)
				(xy 373.53367 -133.04393) (xy 374.337326 -132.240274) (xy 375.560844 -132.240274) (xy 375.733818 -132.0673)
				(xy 375.733818 -131.284218) (xy 375.3866 -130.937) (xy 374.69572 -130.937) (xy 374.45696 -130.69824)
				(xy 374.45696 -129.24028) (xy 374.28678 -129.0701)
			)
		)
		(polygon
			(pts
				(xy 372.7069 -132.9055) (xy 372.5037 -132.9055) (xy 372.5037 -133.1087) (xy 372.7069 -133.1087)
			)
		)
	)
	(zone
		(layer "B.Cu")
		(hatch none 0.5)
		(connect_pads
			(clearance 0)
		)
		(min_thickness 0.25)
		(keepout
			(tracks allowed)
			(vias allowed)
			(pads allowed)
			(copperpour allowed)
			(footprints allowed)
		)
		(placement
			(enabled no)
			(sheetname "")
		)
		(fill
			(thermal_gap 0.5)
			(thermal_bridge_width 0.5)
			(island_removal_mode 0)
		)
		(polygon
			(pts
				(xy 13.462 -103.759) (xy 13.462 -102.87) (xy 14.478 -102.87) (xy 14.478 -103.759)
			)
		)
	)
	(zone
		(layer "B.Cu")
		(hatch none 0.5)
		(connect_pads
			(clearance 0)
		)
		(min_thickness 0.25)
		(keepout
			(tracks allowed)
			(vias allowed)
			(pads allowed)
			(copperpour allowed)
			(footprints not_allowed)
		)
		(placement
			(enabled no)
			(sheetname "")
		)
		(fill
			(thermal_gap 0.5)
			(thermal_bridge_width 0.5)
			(island_removal_mode 0)
		)
		(polygon
			(pts
				(arc
					(start 294.094916 -62.900052)
					(mid 293.635306 -63.090428)
					(end 293.44493 -63.550038)
				)
				(arc
					(start 293.44493 -67.900042)
					(mid 293.635306 -68.359652)
					(end 294.094916 -68.550028)
				)
				(arc
					(start 295.794938 -68.550028)
					(mid 296.254548 -68.359652)
					(end 296.444924 -67.900042)
				)
				(arc
					(start 296.444924 -63.550038)
					(mid 296.254548 -63.090428)
					(end 295.794938 -62.900052)
				)
			)
		)
	)
	(zone
		(net "VR_FET_SW_P12V_STBY_PVDDQ_KLM")
		(layer "B.Cu")
		(hatch none 0.5)
		(connect_pads
			(clearance 0.5)
		)
		(min_thickness 0.25)
		(fill yes
			(thermal_gap 0.5)
			(thermal_bridge_width 0.5)
			(island_removal_mode 0)
		)
		(polygon
			(pts
				(xy -0.8128 -138.43) (xy -1.27 -138.8872) (xy -1.27 -139.7508) (xy -1.8542 -140.335) (xy -1.8542 -142.0622)
				(xy -1.651 -142.2654) (xy 1.4732 -142.2654) (xy 1.837182 -141.901418) (xy 1.8415 -141.8971) (xy 1.8415 -137.1473)
				(xy 1.8542 -137.1346) (xy 1.8542 -136.652) (xy 1.7018 -136.4996) (xy 1.0668 -136.4996) (xy 0.8255 -136.7409)
				(xy 0.8255 -138.2649) (xy 0.6604 -138.43)
			)
		)
	)
	(zone
		(net "P12V_STBY")
		(layer "B.Cu")
		(hatch none 0.5)
		(connect_pads
			(clearance 0.5)
		)
		(min_thickness 0.25)
		(fill yes
			(thermal_gap 0.5)
			(thermal_bridge_width 0.5)
			(island_removal_mode 0)
		)
		(polygon
			(pts
				(xy 436.3085 -52.1335) (xy 439.6105 -52.1335) (xy 439.6613 -52.1843) (xy 439.6613 -52.7304) (xy 439.4581 -52.9336)
				(xy 439.4581 -53.4162) (xy 439.7121 -53.6702) (xy 439.7121 -53.9623) (xy 439.547 -54.1274) (xy 436.91048 -54.1274)
				(xy 436.2196 -53.43652) (xy 436.2196 -52.2224)
			)
		)
	)
	(zone
		(layer "B.Cu")
		(hatch none 0.5)
		(connect_pads
			(clearance 0)
		)
		(min_thickness 0.25)
		(keepout
			(tracks not_allowed)
			(vias allowed)
			(pads allowed)
			(copperpour not_allowed)
			(footprints allowed)
		)
		(placement
			(enabled no)
			(sheetname "")
		)
		(fill
			(thermal_gap 0.5)
			(thermal_bridge_width 0.5)
			(island_removal_mode 0)
		)
		(polygon
			(pts
				(arc
					(start 463.667602 -49.927764)
					(mid 464.294635 -49.997614)
					(end 463.667602 -50.067464)
				)
				(xy 463.606134 -50.067464) (xy 463.532728 -50.14087) (xy 463.532728 -50.381154)
				(arc
					(start 463.976974 -50.381154)
					(mid 464.360514 -49.997741)
					(end 463.977228 -49.614074)
				)
				(arc
					(start 462.707228 -49.614074)
					(mid 462.323688 -49.997614)
					(end 462.707228 -50.381154)
				)
				(xy 463.151728 -50.381154) (xy 463.151728 -50.14087) (xy 463.078322 -50.067464)
				(arc
					(start 462.96453 -50.067464)
					(mid 462.440613 -49.997614)
					(end 462.96453 -49.927764)
				)
				(xy 463.136234 -49.927764) (xy 463.291428 -50.082958) (xy 463.291428 -50.381154) (xy 463.393028 -50.381154)
				(xy 463.393028 -50.082958) (xy 463.548222 -49.927764)
			)
		)
	)
	(zone
		(net "P12V_STBY")
		(layer "B.Cu")
		(hatch none 0.5)
		(connect_pads
			(clearance 0.5)
		)
		(min_thickness 0.25)
		(fill yes
			(thermal_gap 0.5)
			(thermal_bridge_width 0.5)
			(island_removal_mode 0)
		)
		(polygon
			(pts
				(xy 356.3112 -24.0284) (xy 358.3686 -24.0284) (xy 358.642666 -24.0284) (xy 359.580942 -24.966676)
				(xy 367.387632 -24.966676) (xy 367.60023 -24.753824) (xy 367.60023 -19.676364) (xy 367.304066 -19.3802)
				(xy 363.3978 -19.3802) (xy 357.3018 -19.3802) (xy 356.1588 -20.5232) (xy 356.1588 -23.876)
			)
		)
	)
	(zone
		(layer "B.Cu")
		(hatch none 0.5)
		(connect_pads
			(clearance 0)
		)
		(min_thickness 0.25)
		(keepout
			(tracks not_allowed)
			(vias allowed)
			(pads allowed)
			(copperpour not_allowed)
			(footprints allowed)
		)
		(placement
			(enabled no)
			(sheetname "")
		)
		(fill
			(thermal_gap 0.5)
			(thermal_bridge_width 0.5)
			(island_removal_mode 0)
		)
		(polygon
			(pts
				(arc
					(start 472.928696 -157.04439)
					(mid 472.3383 -156.714333)
					(end 471.67165 -156.59989)
				)
				(arc
					(start 471.000074 -156.59989)
					(mid 469.500204 -155.10002)
					(end 471.000074 -153.599896)
				)
				(arc
					(start 471.67165 -153.599896)
					(mid 472.338277 -153.485602)
					(end 472.928696 -153.15565)
				)
				(arc
					(start 472.928696 -153.15565)
					(mid 476.999816 -155.10002)
					(end 472.928696 -157.04439)
				)
			)
		)
	)
	(zone
		(net "PVDDQ_ABC")
		(layer "B.Cu")
		(hatch none 0.5)
		(connect_pads
			(clearance 0.5)
		)
		(min_thickness 0.25)
		(fill yes
			(thermal_gap 0.5)
			(thermal_bridge_width 0.5)
			(island_removal_mode 0)
		)
		(polygon
			(pts
				(xy 265.7602 -6.858) (xy 265.6078 -7.0104) (xy 265.6078 -9.3472) (xy 265.8364 -9.5758) (xy 277.241 -9.5758)
				(xy 277.5204 -9.2964) (xy 277.5204 -7.1882) (xy 277.1902 -6.858)
			)
		)
		(polygon
			(pts
				(xy 272.518632 -8.5471) (xy 272.315432 -8.5471) (xy 272.315432 -8.7503) (xy 272.518632 -8.7503)
			)
		)
		(polygon
			(pts
				(xy 269.216632 -8.5471) (xy 269.013432 -8.5471) (xy 269.013432 -8.7503) (xy 269.216632 -8.7503)
			)
		)
		(polygon
			(pts
				(xy 266.054332 -8.5471) (xy 265.851132 -8.5471) (xy 265.851132 -8.7503) (xy 266.054332 -8.7503)
			)
		)
		(polygon
			(pts
				(xy 275.657564 -7.5565) (xy 275.454364 -7.5565) (xy 275.454364 -7.7597) (xy 275.657564 -7.7597)
			)
		)
		(polygon
			(pts
				(xy 272.518632 -7.5565) (xy 272.315432 -7.5565) (xy 272.315432 -7.7597) (xy 272.518632 -7.7597)
			)
		)
		(polygon
			(pts
				(xy 269.216632 -7.5565) (xy 269.013432 -7.5565) (xy 269.013432 -7.7597) (xy 269.216632 -7.7597)
			)
		)
	)
	(zone
		(layer "B.Cu")
		(hatch none 0.5)
		(connect_pads
			(clearance 0)
		)
		(min_thickness 0.25)
		(keepout
			(tracks allowed)
			(vias allowed)
			(pads allowed)
			(copperpour allowed)
			(footprints allowed)
		)
		(placement
			(enabled no)
			(sheetname "")
		)
		(fill
			(thermal_gap 0.5)
			(thermal_bridge_width 0.5)
			(island_removal_mode 0)
		)
		(polygon
			(pts
				(xy 370.8908 -115.57) (xy 370.8908 -114.3) (xy 372.5926 -114.3) (xy 372.5926 -115.57)
			)
		)
	)
	(zone
		(layer "B.Cu")
		(hatch none 0.5)
		(connect_pads
			(clearance 0)
		)
		(min_thickness 0.25)
		(keepout
			(tracks allowed)
			(vias allowed)
			(pads allowed)
			(copperpour allowed)
			(footprints allowed)
		)
		(placement
			(enabled no)
			(sheetname "")
		)
		(fill
			(thermal_gap 0.5)
			(thermal_bridge_width 0.5)
			(island_removal_mode 0)
		)
		(polygon
			(pts
				(xy 368.935 -118.491) (xy 368.935 -117.221) (xy 370.6368 -117.221) (xy 370.6368 -118.491)
			)
		)
	)
	(zone
		(net "GND")
		(layer "B.Cu")
		(hatch none 0.5)
		(connect_pads
			(clearance 0.5)
		)
		(min_thickness 0.25)
		(fill yes
			(thermal_gap 0.5)
			(thermal_bridge_width 0.5)
			(island_removal_mode 0)
		)
		(polygon
			(pts
				(xy 497.709698 -46.574964) (xy 497.709698 -46.998382) (xy 497.770404 -47.059088) (xy 499.493032 -47.059088)
				(xy 499.553738 -46.998382) (xy 499.553738 -46.595284) (xy 499.484142 -46.525688) (xy 497.758974 -46.525688)
			)
		)
	)
	(zone
		(layer "B.Cu")
		(hatch none 0.5)
		(connect_pads
			(clearance 0)
		)
		(min_thickness 0.25)
		(keepout
			(tracks not_allowed)
			(vias allowed)
			(pads allowed)
			(copperpour not_allowed)
			(footprints allowed)
		)
		(placement
			(enabled no)
			(sheetname "")
		)
		(fill
			(thermal_gap 0.5)
			(thermal_bridge_width 0.5)
			(island_removal_mode 0)
		)
		(polygon
			(pts
				(xy 345.646502 -89.3064) (xy 346.617798 -89.3064) (xy 346.617798 -89.42324) (xy 345.646502 -89.42324)
			)
		)
	)
	(zone
		(net "PVDDQ_GHJ")
		(layer "B.Cu")
		(hatch none 0.5)
		(connect_pads
			(clearance 0.5)
		)
		(min_thickness 0.25)
		(fill yes
			(thermal_gap 0.5)
			(thermal_bridge_width 0.5)
			(island_removal_mode 0)
		)
		(polygon
			(pts
				(xy 80.642968 -24.2824) (xy 80.490568 -24.4348) (xy 80.490568 -25.781) (xy 80.312768 -25.9588) (xy 79.398368 -25.9588)
				(xy 79.245968 -25.8064) (xy 79.245968 -24.4094) (xy 79.144368 -24.3078) (xy 78.788768 -24.3078)
				(xy 78.737968 -24.3586) (xy 78.737968 -26.6192) (xy 79.068168 -26.9494) (xy 79.068168 -28.211526)
				(xy 79.179166 -28.322524) (xy 81.003902 -28.322524) (xy 81.162906 -28.16352) (xy 81.162906 -26.593292)
				(xy 80.922368 -26.352754) (xy 80.922368 -24.3586) (xy 80.846168 -24.2824)
			)
		)
		(polygon
			(pts
				(xy 80.376268 -27.5971) (xy 80.173068 -27.5971) (xy 80.173068 -27.8003) (xy 80.376268 -27.8003)
			)
		)
		(polygon
			(pts
				(xy 80.046068 -27.2161) (xy 79.842868 -27.2161) (xy 79.842868 -27.4193) (xy 80.046068 -27.4193)
			)
		)
		(polygon
			(pts
				(xy 80.376268 -26.6065) (xy 80.173068 -26.6065) (xy 80.173068 -26.8097) (xy 80.376268 -26.8097)
			)
		)
	)
	(zone
		(layer "B.Cu")
		(hatch none 0.5)
		(connect_pads
			(clearance 0)
		)
		(min_thickness 0.25)
		(keepout
			(tracks allowed)
			(vias allowed)
			(pads allowed)
			(copperpour allowed)
			(footprints not_allowed)
		)
		(placement
			(enabled no)
			(sheetname "")
		)
		(fill
			(thermal_gap 0.5)
			(thermal_bridge_width 0.5)
			(island_removal_mode 0)
		)
		(polygon
			(pts
				(arc
					(start 173.928532 -157.04439)
					(mid 173.338136 -156.714333)
					(end 172.671486 -156.59989)
				)
				(arc
					(start 171.99991 -156.59989)
					(mid 170.50004 -155.10002)
					(end 171.99991 -153.599896)
				)
				(arc
					(start 172.671486 -153.599896)
					(mid 173.338113 -153.485602)
					(end 173.928532 -153.15565)
				)
				(arc
					(start 173.928532 -153.15565)
					(mid 177.999652 -155.10002)
					(end 173.928532 -157.04439)
				)
			)
		)
	)
	(zone
		(layer "B.Cu")
		(hatch none 0.5)
		(connect_pads
			(clearance 0)
		)
		(min_thickness 0.25)
		(keepout
			(tracks not_allowed)
			(vias allowed)
			(pads allowed)
			(copperpour not_allowed)
			(footprints allowed)
		)
		(placement
			(enabled no)
			(sheetname "")
		)
		(fill
			(thermal_gap 0.5)
			(thermal_bridge_width 0.5)
			(island_removal_mode 0)
		)
		(polygon
			(pts
				(arc
					(start 357.000048 5.999988)
					(mid 353.000056 1.999996)
					(end 357.000048 -2.00025)
				)
				(arc
					(start 360.499914 -2.00025)
					(mid 364.50016 1.999996)
					(end 360.499914 5.999988)
				)
			)
		)
	)
	(zone
		(net "VR_FET_SW_P12V_STBY_PVPP_ABC")
		(layer "B.Cu")
		(hatch none 0.5)
		(connect_pads
			(clearance 0.5)
		)
		(min_thickness 0.25)
		(fill yes
			(thermal_gap 0.5)
			(thermal_bridge_width 0.5)
			(island_removal_mode 0)
		)
		(polygon
			(pts
				(xy 347.9546 -28.067) (xy 350.2914 -28.067) (xy 350.393 -28.1686) (xy 350.393 -28.956) (xy 350.52 -29.083)
				(xy 351.79 -29.083) (xy 352.0186 -29.3116) (xy 354.9904 -29.3116) (xy 355.727 -28.575) (xy 355.727 -27.686)
				(xy 355.4984 -27.4574) (xy 355.35235 -27.31135) (xy 352.114104 -27.31135) (xy 351.936558 -27.133804)
				(xy 351.936558 -22.303486) (xy 351.870772 -22.2377) (xy 350.999552 -22.2377) (xy 350.901 -22.336252)
				(xy 350.901 -23.693882) (xy 350.853502 -23.74138) (xy 350.42094 -24.173942) (xy 350.4184 -24.173942)
				(xy 350.386142 -24.2062) (xy 348.637352 -24.2062) (xy 348.4118 -24.2062) (xy 348.107 -24.511) (xy 347.250766 -25.367234)
				(xy 347.250766 -27.363166)
			)
		)
	)
	(zone
		(net "GND")
		(layer "B.Cu")
		(hatch none 0.5)
		(connect_pads
			(clearance 0.5)
		)
		(min_thickness 0.25)
		(fill yes
			(thermal_gap 0.5)
			(thermal_bridge_width 0.5)
			(island_removal_mode 0)
		)
		(polygon
			(pts
				(xy 370.586 -136.271) (xy 370.299996 -136.557004) (xy 370.299996 -138.157458) (xy 370.578634 -138.436096)
				(xy 371.467888 -138.436096) (xy 371.533674 -138.37031) (xy 371.533674 -137.091674) (xy 371.348 -136.906)
				(xy 371.348 -136.398) (xy 371.221 -136.271)
			)
		)
		(polygon
			(pts
				(xy 370.6876 -137.5664) (xy 370.4844 -137.5664) (xy 370.4844 -137.7696) (xy 370.6876 -137.7696)
			)
		)
	)
	(zone
		(layer "B.Cu")
		(hatch none 0.5)
		(connect_pads
			(clearance 0)
		)
		(min_thickness 0.25)
		(keepout
			(tracks not_allowed)
			(vias allowed)
			(pads allowed)
			(copperpour not_allowed)
			(footprints allowed)
		)
		(placement
			(enabled no)
			(sheetname "")
		)
		(fill
			(thermal_gap 0.5)
			(thermal_bridge_width 0.5)
			(island_removal_mode 0)
		)
		(polygon
			(pts
				(arc
					(start 426.720254 -139.454636)
					(mid 426.33646 -139.838049)
					(end 426.72 -140.221716)
				)
				(xy 427.1645 -140.221716)
				(arc
					(start 427.1645 -139.965176)
					(mid 427.147761 -139.924765)
					(end 427.10735 -139.908026)
				)
				(arc
					(start 426.977302 -139.908026)
					(mid 426.453385 -139.838176)
					(end 426.977302 -139.768326)
				)
				(xy 427.136306 -139.768326)
				(arc
					(start 427.138846 -139.770866)
					(mid 427.246541 -139.825985)
					(end 427.30166 -139.93368)
				)
				(xy 427.3042 -139.93622) (xy 427.3042 -140.221716) (xy 427.4058 -140.221716) (xy 427.4058 -139.93622)
				(arc
					(start 427.40834 -139.93368)
					(mid 427.463459 -139.825985)
					(end 427.571154 -139.770866)
				)
				(xy 427.573694 -139.768326)
				(arc
					(start 427.732698 -139.768326)
					(mid 428.256615 -139.838176)
					(end 427.732698 -139.908026)
				)
				(arc
					(start 427.60265 -139.908026)
					(mid 427.562239 -139.924765)
					(end 427.5455 -139.965176)
				)
				(xy 427.5455 -140.221716)
				(arc
					(start 427.99 -140.221716)
					(mid 428.37354 -139.838176)
					(end 427.99 -139.454636)
				)
			)
		)
	)
	(zone
		(net "PVTT_ABC")
		(layer "B.Cu")
		(hatch none 0.5)
		(connect_pads
			(clearance 0.5)
		)
		(min_thickness 0.25)
		(fill yes
			(thermal_gap 0.5)
			(thermal_bridge_width 0.5)
			(island_removal_mode 0)
		)
		(polygon
			(pts
				(xy 181.774592 5.52196) (xy 181.4449 5.192268) (xy 181.4449 3.501644) (xy 181.70398 3.242564) (xy 183.345836 3.242564)
				(xy 183.6928 2.8956) (xy 183.6928 1.99644) (xy 183.71058 1.97866) (xy 184.71388 1.97866) (xy 184.77738 2.04216)
				(xy 184.77738 2.73304) (xy 184.93994 2.8956) (xy 188.25464 2.8956) (xy 188.50864 3.1496) (xy 196.977 3.1496)
				(xy 200.1012 0.0254) (xy 258.953 0.0254) (xy 258.953 -1.960372) (xy 259.012182 -2.019554) (xy 259.404104 -2.411476)
				(xy 260.411214 -2.411476) (xy 260.666738 -2.667) (xy 260.666738 -4.021074) (xy 260.55955 -4.128262)
				(xy 259.017008 -4.128262) (xy 258.953 -4.19227) (xy 258.953 -4.522724) (xy 259.018278 -4.588002)
				(xy 259.018278 -4.710684) (xy 258.953 -4.775962) (xy 258.953 -6.2992) (xy 259.1308 -6.477) (xy 260.477 -6.477)
				(xy 260.477 -8.9916) (xy 259.6642 -9.8044) (xy 259.207 -9.8044) (xy 258.953 -10.0584) (xy 258.953 -12.02309)
				(xy 259.102098 -12.172188) (xy 259.864352 -12.172188) (xy 260.001004 -12.30884) (xy 260.001004 -14.010386)
				(xy 259.6642 -14.34719) (xy 259.168646 -14.34719) (xy 258.955032 -14.560804) (xy 258.953 -14.560804)
				(xy 258.953 -16.1544) (xy 259.0292 -16.2306) (xy 261.5946 -16.2306) (xy 262.001 -16.637) (xy 262.001 -16.6878)
				(xy 262.1026 -16.7894) (xy 262.1026 -19.4564) (xy 261.4549 -20.1041) (xy 260.2865 -20.1041) (xy 260.2738 -20.1168)
				(xy 259.7277 -20.1168) (xy 259.5372 -19.9263) (xy 259.5372 -19.431) (xy 259.4356 -19.3294) (xy 259.1562 -19.3294)
				(xy 259.0546 -19.431) (xy 259.0546 -25.7048) (xy 259.1054 -25.7556) (xy 260.1468 -25.7556) (xy 260.223 -25.8318)
				(xy 260.223 -26.6192) (xy 260.2738 -26.67) (xy 261.2898 -26.67) (xy 261.5692 -26.9494) (xy 262.382 -26.9494)
				(xy 262.4328 -26.8986) (xy 262.4328 -24.9174) (xy 261.493 -23.9776) (xy 261.493 -21.8186) (xy 262.5852 -20.7264)
				(xy 262.5852 -16.7386) (xy 262.636 -16.6878) (xy 262.636 -15.4432) (xy 261.6581 -14.4653) (xy 261.6581 -4.4323)
				(xy 261.5692 -4.3434) (xy 261.5692 0.185674) (xy 261.550912 0.203708) (xy 261.550912 0.676402) (xy 260.503924 1.72339)
				(xy 260.448044 1.77927) (xy 260.448044 2.346198) (xy 260.503924 2.402078) (xy 260.503924 2.955798)
				(xy 260.50113 2.958592) (xy 260.50113 5.41147) (xy 260.39064 5.52196)
			)
		)
		(polygon
			(pts
				(xy 261.2263 -25.8445) (xy 261.0231 -25.8445) (xy 261.0231 -26.0477) (xy 261.2263 -26.0477)
			)
		)
		(polygon
			(pts
				(xy 260.266434 2.377694) (xy 260.063234 2.377694) (xy 260.063234 1.869694) (xy 260.266434 1.869694)
			)
		)
	)
	(zone
		(layer "B.Cu")
		(hatch none 0.5)
		(connect_pads
			(clearance 0)
		)
		(min_thickness 0.25)
		(keepout
			(tracks allowed)
			(vias allowed)
			(pads allowed)
			(copperpour allowed)
			(footprints allowed)
		)
		(placement
			(enabled no)
			(sheetname "")
		)
		(fill
			(thermal_gap 0.5)
			(thermal_bridge_width 0.5)
			(island_removal_mode 0)
		)
		(polygon
			(pts
				(xy 145.415 -74.549) (xy 145.415 -101.346) (xy 177.546 -101.346) (xy 177.546 -96.774) (xy 173.101 -89.662)
				(xy 164.084 -89.662) (xy 162.433 -88.773) (xy 158.369 -67.183) (xy 158.46552 -67.08648) (xy 158.46552 -65.40246)
				(xy 149.46503 -56.40197) (xy 148.85797 -56.40197) (xy 148.844 -56.388) (xy 148.717 -56.388) (xy 148.717 -65.405)
				(xy 145.796 -68.326) (xy 145.796 -72.136) (xy 145.415 -72.136)
			)
		)
	)
	(zone
		(layer "B.Cu")
		(hatch none 0.5)
		(connect_pads
			(clearance 0)
		)
		(min_thickness 0.25)
		(keepout
			(tracks not_allowed)
			(vias allowed)
			(pads allowed)
			(copperpour not_allowed)
			(footprints allowed)
		)
		(placement
			(enabled no)
			(sheetname "")
		)
		(fill
			(thermal_gap 0.5)
			(thermal_bridge_width 0.5)
			(island_removal_mode 0)
		)
		(polygon
			(pts
				(arc
					(start 459.774798 -53.835808)
					(mid 459.288796 -54.043849)
					(end 459.70063 -53.712364)
				)
				(xy 459.88986 -53.523134)
				(arc
					(start 459.51775 -53.523134)
					(mid 459.13421 -53.906674)
					(end 459.51775 -54.290214)
				)
				(arc
					(start 460.787496 -54.290214)
					(mid 461.17129 -53.906801)
					(end 460.78775 -53.523134)
				)
				(xy 460.503016 -53.523134)
				(arc
					(start 460.655162 -53.67528)
					(mid 460.976327 -54.095251)
					(end 460.556356 -53.774086)
				)
				(xy 460.305404 -53.523134) (xy 460.084932 -53.523134) (xy 460.084932 -53.525674)
			)
		)
	)
	(zone
		(net "PVDDQ_ABC")
		(layer "B.Cu")
		(hatch none 0.5)
		(connect_pads
			(clearance 0.5)
		)
		(min_thickness 0.25)
		(fill yes
			(thermal_gap 0.5)
			(thermal_bridge_width 0.5)
			(island_removal_mode 0)
		)
		(polygon
			(pts
				(xy 265.743944 -21.3106) (xy 265.743944 -22.1488) (xy 266.455144 -22.86) (xy 266.455144 -23.5966)
				(xy 266.615672 -23.757128) (xy 266.615672 -25.722072) (xy 266.7 -25.8064) (xy 267.1064 -25.8064)
				(xy 267.2588 -25.654) (xy 267.2588 -23.9268) (xy 267.3858 -23.7998) (xy 269.1384 -23.7998) (xy 269.2146 -23.876)
				(xy 269.2146 -25.9842) (xy 269.2908 -26.0604) (xy 269.6718 -26.0604) (xy 269.7734 -25.9588) (xy 269.7734 -23.876)
				(xy 269.8496 -23.7998) (xy 270.891 -23.7998) (xy 270.9418 -23.8506) (xy 270.9418 -24.9682) (xy 271.0434 -25.0698)
				(xy 271.3228 -25.0698) (xy 271.4498 -24.9428) (xy 271.4498 -23.9014) (xy 271.5514 -23.7998) (xy 273.4056 -23.7998)
				(xy 273.4564 -23.8506) (xy 273.4564 -25.7048) (xy 273.5072 -25.7556) (xy 273.9898 -25.7556) (xy 274.0406 -25.7048)
				(xy 274.0406 -23.9014) (xy 274.1422 -23.7998) (xy 275.1074 -23.7998) (xy 275.1582 -23.8506) (xy 275.1582 -24.9936)
				(xy 275.2344 -25.0698) (xy 275.6408 -25.0698) (xy 275.7424 -24.9682) (xy 275.7424 -23.9014) (xy 275.844 -23.7998)
				(xy 276.8092 -23.7998) (xy 276.86 -23.8506) (xy 276.86 -25.019) (xy 276.9108 -25.0698) (xy 277.368 -25.0698)
				(xy 277.4696 -24.9682) (xy 277.4696 -23.6728) (xy 277.8506 -23.2918) (xy 277.8506 -21.5138) (xy 277.5712 -21.2344)
				(xy 277.5458 -21.2344) (xy 277.4442 -21.1328) (xy 277.4442 -20.0914) (xy 277.3172 -19.9644) (xy 277.0124 -19.9644)
				(xy 276.86 -20.1168) (xy 276.86 -21.0566) (xy 276.6822 -21.2344) (xy 275.0312 -21.2344) (xy 274.9042 -21.1074)
				(xy 274.9042 -20.193) (xy 274.701 -19.9898) (xy 274.447 -19.9898) (xy 274.2946 -20.1422) (xy 274.2946 -21.082)
				(xy 274.1422 -21.2344) (xy 273.304 -21.2344) (xy 273.177 -21.1074) (xy 273.177 -20.1676) (xy 272.9738 -19.9644)
				(xy 272.7706 -19.9644) (xy 272.5928 -20.1422) (xy 272.5928 -21.1328) (xy 272.4912 -21.2344) (xy 271.6276 -21.2344)
				(xy 271.5006 -21.1074) (xy 271.5006 -20.0914) (xy 271.3736 -19.9644) (xy 271.0434 -19.9644) (xy 270.891 -20.1168)
				(xy 270.891 -21.1328) (xy 270.7894 -21.2344) (xy 269.0876 -21.2344) (xy 268.9606 -21.1074) (xy 268.9606 -20.0914)
				(xy 268.8336 -19.9644) (xy 268.478 -19.9644) (xy 268.3256 -20.1168) (xy 268.3256 -21.1328) (xy 268.224 -21.2344)
				(xy 266.4968 -21.2344) (xy 266.4206 -21.1582) (xy 266.4206 -20.066) (xy 266.319 -19.9644) (xy 265.938 -19.9644)
				(xy 265.743944 -20.158456)
			)
		)
	)
	(zone
		(net "PVDDQ_DEF")
		(layer "B.Cu")
		(hatch none 0.5)
		(connect_pads
			(clearance 0.5)
		)
		(min_thickness 0.25)
		(fill yes
			(thermal_gap 0.5)
			(thermal_bridge_width 0.5)
			(island_removal_mode 0)
		)
		(polygon
			(pts
				(xy 267.17625 -86.329266) (xy 265.524234 -86.329266) (xy 265.227308 -86.329266) (xy 264.891266 -86.329266)
				(xy 264.0584 -85.4964) (xy 264.0584 -84.7598) (xy 264.276586 -84.541614) (xy 265.559286 -84.541614)
				(xy 268.162024 -84.541614) (xy 273.677634 -84.541614) (xy 273.678904 -84.542884) (xy 275.486114 -84.542884)
				(xy 275.529548 -84.586318) (xy 275.529548 -85.549232) (xy 275.49856 -85.58022) (xy 274.807934 -85.58022)
				(xy 274.692872 -85.695282) (xy 274.692872 -86.14918) (xy 274.482052 -86.36) (xy 272.4658 -86.36)
				(xy 267.705586 -86.36) (xy 267.679424 -86.333838) (xy 267.180822 -86.333838)
			)
		)
	)
	(zone
		(layer "B.Cu")
		(hatch none 0.5)
		(connect_pads
			(clearance 0)
		)
		(min_thickness 0.25)
		(keepout
			(tracks allowed)
			(vias allowed)
			(pads allowed)
			(copperpour allowed)
			(footprints not_allowed)
		)
		(placement
			(enabled no)
			(sheetname "")
		)
		(fill
			(thermal_gap 0.5)
			(thermal_bridge_width 0.5)
			(island_removal_mode 0)
		)
		(polygon
			(pts
				(arc
					(start 435.300374 -58.996834)
					(mid 431.700432 -55.396892)
					(end 428.10049 -58.996834)
				)
				(arc
					(start 428.10049 -60.59678)
					(mid 431.700432 -64.196722)
					(end 435.300374 -60.59678)
				)
			)
		)
	)
	(zone
		(layer "B.Cu")
		(hatch none 0.5)
		(connect_pads
			(clearance 0)
		)
		(min_thickness 0.25)
		(keepout
			(tracks not_allowed)
			(vias allowed)
			(pads allowed)
			(copperpour not_allowed)
			(footprints allowed)
		)
		(placement
			(enabled no)
			(sheetname "")
		)
		(fill
			(thermal_gap 0.5)
			(thermal_bridge_width 0.5)
			(island_removal_mode 0)
		)
		(polygon
			(pts
				(arc
					(start 4.067048 -107.84205)
					(mid 4.590965 -107.9119)
					(end 4.067048 -107.98175)
				)
				(xy 3.953256 -107.98175) (xy 3.87985 -108.055156) (xy 3.87985 -108.29544)
				(arc
					(start 4.32435 -108.29544)
					(mid 4.70789 -107.9119)
					(end 4.32435 -107.52836)
				)
				(arc
					(start 3.054604 -107.52836)
					(mid 2.67081 -107.911773)
					(end 3.05435 -108.29544)
				)
				(xy 3.49885 -108.29544) (xy 3.49885 -108.055156) (xy 3.425444 -107.98175)
				(arc
					(start 3.311652 -107.98175)
					(mid 2.787735 -107.9119)
					(end 3.311652 -107.84205)
				)
				(xy 3.483356 -107.84205) (xy 3.63855 -107.997244) (xy 3.63855 -108.29544) (xy 3.74015 -108.29544)
				(xy 3.74015 -107.997244) (xy 3.895344 -107.84205)
			)
		)
	)
	(zone
		(net "P3V3_STBY")
		(layer "B.Cu")
		(hatch none 0.5)
		(connect_pads
			(clearance 0.5)
		)
		(min_thickness 0.25)
		(fill yes
			(thermal_gap 0.5)
			(thermal_bridge_width 0.5)
			(island_removal_mode 0)
		)
		(polygon
			(pts
				(xy 456.6412 -19.05) (xy 456.5142 -18.923) (xy 456.5142 -18.161) (xy 456.6158 -18.0594) (xy 459.6638 -18.0594)
				(xy 460.33944 -18.0594) (xy 460.36484 -18.0594) (xy 461.1116 -17.31264) (xy 461.1116 -17.28724)
				(xy 461.1116 -16.6116) (xy 461.1116 -15.0114) (xy 461.3402 -14.7828) (xy 462.394808 -14.7828) (xy 462.531968 -14.64564)
				(xy 463.036158 -14.14145) (xy 463.036158 -13.73632) (xy 463.042 -13.730478) (xy 463.042 -11.6586)
				(xy 463.03946 -11.65606) (xy 463.03946 -11.426952) (xy 463.03946 -11.356086) (xy 463.03438 -11.351006)
				(xy 462.673446 -10.990072) (xy 462.673446 -10.480548) (xy 462.75752 -10.396474) (xy 464.040474 -10.396474)
				(xy 464.41614 -10.77214) (xy 465.18068 -11.53668) (xy 465.328 -11.684) (xy 465.328 -12.9794) (xy 466.319616 -13.971016)
				(xy 466.319616 -17.8816) (xy 465.16925 -19.031966) (xy 464.228434 -19.031966) (xy 463.3976 -19.8628)
				(xy 463.3976 -20.701) (xy 462.9912 -21.1074) (xy 462.9912 -23.2156) (xy 462.8388 -23.368) (xy 462.298542 -23.368)
				(xy 461.504538 -24.162004) (xy 461.249014 -24.417528) (xy 459.20279 -24.417528) (xy 458.977492 -24.19223)
				(xy 458.977492 -23.850092) (xy 458.977492 -21.386292)
			)
		)
	)
	(zone
		(net "VR_PVCCIO_CPU0_VDD")
		(layer "B.Cu")
		(hatch none 0.5)
		(connect_pads
			(clearance 0.5)
		)
		(min_thickness 0.25)
		(fill yes
			(thermal_gap 0.5)
			(thermal_bridge_width 0.5)
			(island_removal_mode 0)
		)
		(polygon
			(pts
				(xy 348.741492 -86.233) (xy 349.8596 -86.233) (xy 350.1644 -85.9282) (xy 350.2406 -85.9282) (xy 350.6978 -85.471)
				(xy 351.155 -85.471) (xy 351.4598 -85.471) (xy 351.4852 -85.4456) (xy 351.4852 -84.9376) (xy 351.2058 -84.6582)
				(xy 351.2058 -83.3628) (xy 351.155 -83.312) (xy 350.647 -83.312) (xy 350.3422 -83.6168) (xy 350.3422 -83.7184)
				(xy 350.3422 -84.7852) (xy 349.9612 -85.1662) (xy 349.8977 -85.2297) (xy 349.8977 -85.4583) (xy 349.47479 -85.88121)
				(xy 348.713298 -85.88121) (xy 348.615508 -85.979) (xy 348.615508 -86.107016)
			)
		)
	)
	(zone
		(net "PVDDQ_DEF")
		(layer "B.Cu")
		(hatch none 0.5)
		(connect_pads
			(clearance 0.5)
		)
		(min_thickness 0.25)
		(fill yes
			(thermal_gap 0.5)
			(thermal_bridge_width 0.5)
			(island_removal_mode 0)
		)
		(polygon
			(pts
				(xy 244.004338 -125.011688) (xy 243.857272 -125.158754) (xy 243.857272 -126.995174) (xy 244.008656 -127.146558)
				(xy 246.308626 -127.146558) (xy 246.504714 -126.95047) (xy 246.504714 -125.216666) (xy 246.299736 -125.011688)
			)
		)
		(polygon
			(pts
				(xy 245.472712 -125.94971) (xy 245.269512 -125.94971) (xy 245.269512 -126.15291) (xy 245.472712 -126.15291)
			)
		)
		(polygon
			(pts
				(xy 245.0973 -125.94971) (xy 244.8941 -125.94971) (xy 244.8941 -126.15291) (xy 245.0973 -126.15291)
			)
		)
	)
	(zone
		(layer "B.Cu")
		(hatch none 0.5)
		(connect_pads
			(clearance 0)
		)
		(min_thickness 0.25)
		(keepout
			(tracks allowed)
			(vias allowed)
			(pads allowed)
			(copperpour allowed)
			(footprints allowed)
		)
		(placement
			(enabled no)
			(sheetname "")
		)
		(fill
			(thermal_gap 0.5)
			(thermal_bridge_width 0.5)
			(island_removal_mode 0)
		)
		(polygon
			(pts
				(xy 311.912 -92.583) (xy 311.912 -91.821) (xy 312.674 -91.821) (xy 312.674 -92.583)
			)
		)
	)
	(zone
		(net "GND")
		(layer "B.Cu")
		(hatch none 0.5)
		(connect_pads
			(clearance 0.5)
		)
		(min_thickness 0.25)
		(fill yes
			(thermal_gap 0.5)
			(thermal_bridge_width 0.5)
			(island_removal_mode 0)
		)
		(polygon
			(pts
				(xy 482.2444 -110.4646) (xy 481.9904 -110.7186) (xy 481.9904 -114.1222) (xy 481.838 -114.2746) (xy 481.838 -114.8334)
				(xy 481.711 -114.9604) (xy 481.5586 -114.9604) (xy 481.1522 -115.3668) (xy 481.1522 -115.57) (xy 481.203 -115.6208)
				(xy 481.203 -115.824) (xy 481.0506 -115.9764) (xy 480.2378 -115.9764) (xy 479.9584 -116.2558) (xy 479.9584 -117.0686)
				(xy 479.9584 -118.745) (xy 480.3013 -119.0879) (xy 484.5939 -119.0879) (xy 484.8479 -118.8339) (xy 484.8479 -117.5385)
				(xy 485.3686 -117.0178) (xy 485.3686 -114.8588) (xy 485.0638 -114.554) (xy 484.378 -114.554) (xy 484.124 -114.3)
				(xy 483.6414 -114.3) (xy 483.5906 -114.3508) (xy 483.5906 -114.8842) (xy 483.489 -114.9858) (xy 483.489 -115.697)
				(xy 483.3112 -115.8748) (xy 482.7524 -115.8748) (xy 482.5492 -115.6716) (xy 482.5492 -115.4938)
				(xy 482.5492 -114.173) (xy 482.6254 -114.0968) (xy 483.1588 -114.0968) (xy 483.2604 -113.9952) (xy 483.2604 -113.6396)
				(xy 483.108 -113.4872) (xy 483.108 -112.5982) (xy 483.235 -112.4712) (xy 483.8192 -112.4712) (xy 483.87 -112.4204)
				(xy 483.87 -110.5662) (xy 483.7684 -110.4646)
			)
		)
	)
	(zone
		(layer "B.Cu")
		(hatch none 0.5)
		(connect_pads
			(clearance 0)
		)
		(min_thickness 0.25)
		(keepout
			(tracks allowed)
			(vias allowed)
			(pads allowed)
			(copperpour allowed)
			(footprints not_allowed)
		)
		(placement
			(enabled no)
			(sheetname "")
		)
		(fill
			(thermal_gap 0.5)
			(thermal_bridge_width 0.5)
			(island_removal_mode 0)
		)
		(polygon
			(pts
				(arc
					(start 81.555082 -63.550038)
					(mid 81.364706 -63.090428)
					(end 80.905096 -62.900052)
				)
				(arc
					(start 79.205074 -62.900052)
					(mid 78.745464 -63.090428)
					(end 78.555088 -63.550038)
				)
				(arc
					(start 78.555088 -67.900042)
					(mid 78.745464 -68.359652)
					(end 79.205074 -68.550028)
				)
				(arc
					(start 80.905096 -68.550028)
					(mid 81.364706 -68.359652)
					(end 81.555082 -67.900042)
				)
			)
		)
	)
	(zone
		(layer "B.Cu")
		(hatch none 0.5)
		(connect_pads
			(clearance 0)
		)
		(min_thickness 0.25)
		(keepout
			(tracks allowed)
			(vias allowed)
			(pads allowed)
			(copperpour allowed)
			(footprints not_allowed)
		)
		(placement
			(enabled no)
			(sheetname "")
		)
		(fill
			(thermal_gap 0.5)
			(thermal_bridge_width 0.5)
			(island_removal_mode 0)
		)
		(polygon
			(pts
				(arc
					(start 291.999924 -109.009942)
					(mid 289.459924 -111.549942)
					(end 291.999924 -114.089942)
				)
				(arc
					(start 291.999924 -114.089942)
					(mid 294.539924 -111.549942)
					(end 291.999924 -109.009942)
				)
			)
		)
	)
	(zone
		(net "GND")
		(layer "B.Cu")
		(hatch none 0.5)
		(connect_pads
			(clearance 0.5)
		)
		(min_thickness 0.25)
		(fill yes
			(thermal_gap 0.5)
			(thermal_bridge_width 0.5)
			(island_removal_mode 0)
		)
		(polygon
			(pts
				(xy 78.026768 -125.0442) (xy 77.137768 -125.9332) (xy 77.137768 -126.4412) (xy 77.874368 -127.1778)
				(xy 77.874368 -127.6858) (xy 77.848968 -127.7112) (xy 77.848968 -130.4036) (xy 78.026768 -130.5814)
				(xy 78.433168 -130.5814) (xy 78.610968 -130.4036) (xy 78.610968 -129.921) (xy 78.382368 -129.6924)
				(xy 78.382368 -126.873) (xy 78.610968 -126.6444) (xy 78.610968 -125.1204) (xy 78.534768 -125.0442)
			)
		)
		(polygon
			(pts
				(xy 77.810868 -126.2761) (xy 77.607668 -126.2761) (xy 77.607668 -126.4793) (xy 77.810868 -126.4793)
			)
		)
	)
	(zone
		(layer "B.Cu")
		(hatch none 0.5)
		(connect_pads
			(clearance 0)
		)
		(min_thickness 0.25)
		(keepout
			(tracks not_allowed)
			(vias allowed)
			(pads allowed)
			(copperpour not_allowed)
			(footprints allowed)
		)
		(placement
			(enabled no)
			(sheetname "")
		)
		(fill
			(thermal_gap 0.5)
			(thermal_bridge_width 0.5)
			(island_removal_mode 0)
		)
		(polygon
			(pts
				(arc
					(start 250.59005 -41.550082)
					(mid 245.410482 -41.550082)
					(end 250.59005 -41.550082)
				)
			)
		)
	)
	(zone
		(layer "B.Cu")
		(hatch none 0.5)
		(connect_pads
			(clearance 0)
		)
		(min_thickness 0.25)
		(keepout
			(tracks not_allowed)
			(vias allowed)
			(pads allowed)
			(copperpour not_allowed)
			(footprints allowed)
		)
		(placement
			(enabled no)
			(sheetname "")
		)
		(fill
			(thermal_gap 0.5)
			(thermal_bridge_width 0.5)
			(island_removal_mode 0)
		)
		(polygon
			(pts
				(arc
					(start 420.118286 -150.8633)
					(mid 419.734746 -150.47976)
					(end 419.351206 -150.8633)
				)
				(arc
					(start 419.351206 -151.879046)
					(mid 419.734619 -152.26284)
					(end 420.118286 -151.8793)
				)
				(xy 420.118286 -151.527002)
				(arc
					(start 419.849046 -151.527002)
					(mid 419.81825 -151.539399)
					(end 419.804596 -151.569674)
				)
				(arc
					(start 419.804596 -151.569674)
					(mid 419.734746 -152.196707)
					(end 419.664896 -151.569674)
				)
				(xy 419.664896 -151.542496)
				(arc
					(start 419.66769 -151.539702)
					(mid 419.718858 -151.441264)
					(end 419.817296 -151.390096)
				)
				(xy 419.82009 -151.387302) (xy 420.118286 -151.387302) (xy 420.118286 -151.285702) (xy 419.82009 -151.285702)
				(arc
					(start 419.817296 -151.282908)
					(mid 419.718858 -151.23174)
					(end 419.66769 -151.133302)
				)
				(xy 419.664896 -151.130508)
				(arc
					(start 419.664896 -151.120602)
					(mid 419.732775 -150.596693)
					(end 419.808406 -151.119586)
				)
				(arc
					(start 419.808406 -151.119586)
					(mid 419.824807 -151.138826)
					(end 419.849046 -151.146002)
				)
				(xy 420.118286 -151.146002)
			)
		)
	)
	(zone
		(layer "B.Cu")
		(hatch none 0.5)
		(connect_pads
			(clearance 0)
		)
		(min_thickness 0.25)
		(keepout
			(tracks allowed)
			(vias allowed)
			(pads allowed)
			(copperpour allowed)
			(footprints not_allowed)
		)
		(placement
			(enabled no)
			(sheetname "")
		)
		(fill
			(thermal_gap 0.5)
			(thermal_bridge_width 0.5)
			(island_removal_mode 0)
		)
		(polygon
			(pts
				(arc
					(start 245.90502 -68.550028)
					(mid 246.36463 -68.359652)
					(end 246.555006 -67.900042)
				)
				(arc
					(start 246.555006 -63.550038)
					(mid 246.36463 -63.090428)
					(end 245.90502 -62.900052)
				)
				(arc
					(start 244.204998 -62.900052)
					(mid 243.745388 -63.090428)
					(end 243.555012 -63.550038)
				)
				(arc
					(start 243.555012 -67.900042)
					(mid 243.745388 -68.359652)
					(end 244.204998 -68.550028)
				)
			)
		)
	)
	(zone
		(layer "B.Cu")
		(hatch none 0.5)
		(connect_pads
			(clearance 0)
		)
		(min_thickness 0.25)
		(keepout
			(tracks not_allowed)
			(vias allowed)
			(pads allowed)
			(copperpour not_allowed)
			(footprints allowed)
		)
		(placement
			(enabled no)
			(sheetname "")
		)
		(fill
			(thermal_gap 0.5)
			(thermal_bridge_width 0.5)
			(island_removal_mode 0)
		)
		(polygon
			(pts
				(arc
					(start 410.093922 -152.527)
					(mid 410.102493 -152.525922)
					(end 410.110686 -152.52319)
				)
				(xy 410.127958 -152.51049) (xy 410.174186 -152.464008)
				(arc
					(start 410.174186 -152.2095)
					(mid 409.790646 -151.82596)
					(end 409.407106 -152.2095)
				)
				(arc
					(start 409.407106 -153.225246)
					(mid 409.790519 -153.60904)
					(end 410.174186 -153.2255)
				)
				(xy 410.174186 -152.970992) (xy 410.127958 -152.92451)
				(arc
					(start 410.110686 -152.91181)
					(mid 410.101867 -152.90897)
					(end 410.092652 -152.908)
				)
				(arc
					(start 409.904946 -152.908)
					(mid 409.873515 -152.921019)
					(end 409.860496 -152.95245)
				)
				(arc
					(start 409.860496 -152.968198)
					(mid 409.790646 -153.492115)
					(end 409.720796 -152.968198)
				)
				(xy 409.720796 -152.923494)
				(arc
					(start 409.72359 -152.9207)
					(mid 409.774758 -152.822262)
					(end 409.873196 -152.771094)
				)
				(xy 409.87599 -152.7683) (xy 410.121608 -152.7683)
				(arc
					(start 410.124402 -152.771094)
					(mid 410.141249 -152.774753)
					(end 410.157676 -152.779984)
				)
				(xy 410.166058 -152.778968) (xy 410.174186 -152.78481) (xy 410.174186 -152.65019) (xy 410.166058 -152.656032)
				(arc
					(start 410.157676 -152.655016)
					(mid 410.141246 -152.660237)
					(end 410.124402 -152.663906)
				)
				(xy 410.121608 -152.6667) (xy 409.87599 -152.6667)
				(arc
					(start 409.873196 -152.663906)
					(mid 409.774758 -152.612738)
					(end 409.72359 -152.5143)
				)
				(xy 409.720796 -152.511506)
				(arc
					(start 409.720796 -152.466802)
					(mid 409.790646 -151.942885)
					(end 409.860496 -152.466802)
				)
				(arc
					(start 409.860496 -152.48255)
					(mid 409.873515 -152.513981)
					(end 409.904946 -152.527)
				)
				(xy 410.092652 -152.527)
			)
		)
	)
	(zone
		(layer "B.Cu")
		(hatch none 0.5)
		(connect_pads
			(clearance 0)
		)
		(min_thickness 0.25)
		(keepout
			(tracks not_allowed)
			(vias allowed)
			(pads allowed)
			(copperpour not_allowed)
			(footprints allowed)
		)
		(placement
			(enabled no)
			(sheetname "")
		)
		(fill
			(thermal_gap 0.5)
			(thermal_bridge_width 0.5)
			(island_removal_mode 0)
		)
		(polygon
			(pts
				(arc
					(start 387.502908 -26.53792)
					(mid 387.922879 -26.216755)
					(end 387.601714 -26.636726)
				)
				(xy 387.375146 -26.863294) (xy 387.392926 -27.15895)
				(arc
					(start 387.64083 -27.406854)
					(mid 388.035078 -27.899908)
					(end 387.542024 -27.50566)
				)
				(xy 387.405372 -27.369008) (xy 387.425184 -27.698446)
				(arc
					(start 387.427724 -27.698192)
					(mid 387.833362 -28.05811)
					(end 388.19328 -27.652472)
				)
				(xy 388.19582 -27.652218) (xy 388.11962 -26.382472) (xy 388.119366 -26.382218)
				(arc
					(start 388.11708 -26.382472)
					(mid 387.711442 -26.022554)
					(end 387.351524 -26.428192)
				)
				(xy 387.348984 -26.428446) (xy 387.36397 -26.676858)
			)
		)
	)
	(zone
		(layer "B.Cu")
		(hatch none 0.5)
		(connect_pads
			(clearance 0)
		)
		(min_thickness 0.25)
		(keepout
			(tracks not_allowed)
			(vias allowed)
			(pads allowed)
			(copperpour not_allowed)
			(footprints allowed)
		)
		(placement
			(enabled no)
			(sheetname "")
		)
		(fill
			(thermal_gap 0.5)
			(thermal_bridge_width 0.5)
			(island_removal_mode 0)
		)
		(polygon
			(pts
				(arc
					(start -0.94996 -54.909974)
					(mid -1.999996 -53.859938)
					(end -3.050032 -54.909974)
				)
				(arc
					(start -3.050032 -54.909974)
					(mid -1.999996 -55.96001)
					(end -0.94996 -54.909974)
				)
			)
		)
	)
	(zone
		(net "GND")
		(layer "B.Cu")
		(hatch none 0.5)
		(connect_pads
			(clearance 0.5)
		)
		(min_thickness 0.25)
		(fill yes
			(thermal_gap 0.5)
			(thermal_bridge_width 0.5)
			(island_removal_mode 0)
		)
		(polygon
			(pts
				(xy 168.275 -16.129) (xy 168.275 -11.049) (xy 168.529 -10.795) (xy 169.291 -10.795) (xy 169.545 -11.049)
				(xy 169.545 -16.383) (xy 170.1927 -17.0307) (xy 170.1927 -17.4625) (xy 169.9006 -17.7546) (xy 168.8846 -17.7546)
				(xy 168.656 -17.526) (xy 168.275 -17.145) (xy 168.275 -16.764)
			)
		)
	)
	(zone
		(layer "B.Cu")
		(hatch none 0.5)
		(connect_pads
			(clearance 0)
		)
		(min_thickness 0.25)
		(keepout
			(tracks allowed)
			(vias allowed)
			(pads allowed)
			(copperpour allowed)
			(footprints not_allowed)
		)
		(placement
			(enabled no)
			(sheetname "")
		)
		(fill
			(thermal_gap 0.5)
			(thermal_bridge_width 0.5)
			(island_removal_mode 0)
		)
		(polygon
			(pts
				(arc
					(start 406.489916 -130.309874)
					(mid 402.89988 -133.89991)
					(end 406.489916 -137.489946)
				)
				(arc
					(start 406.489916 -137.489946)
					(mid 410.079952 -133.89991)
					(end 406.489916 -130.309874)
				)
			)
		)
	)
	(zone
		(net "GND")
		(layer "B.Cu")
		(hatch none 0.5)
		(connect_pads
			(clearance 0.5)
		)
		(min_thickness 0.25)
		(fill yes
			(thermal_gap 0.5)
			(thermal_bridge_width 0.5)
			(island_removal_mode 0)
		)
		(polygon
			(pts
				(xy 9.2202 -6.0452) (xy 8.7376 -6.0452) (xy 7.886954 -5.194554) (xy 5.732272 -5.194554) (xy 5.604002 -5.322824)
				(xy 5.604002 -6.528308) (xy 5.0927 -7.03961) (xy 5.0927 -7.4295) (xy 5.1054 -7.4422) (xy 5.1054 -12.09294)
				(xy 4.892548 -12.305792) (xy 4.892548 -12.839192) (xy 4.8514 -12.88034) (xy 4.8514 -12.968986) (xy 4.8514 -13.605256)
				(xy 4.8514 -14.08176) (xy 5.1816 -14.41196) (xy 5.1816 -20.679918) (xy 5.187188 -20.685506) (xy 5.187188 -22.078188)
				(xy 5.204968 -22.095968) (xy 6.223 -23.114) (xy 8.128 -23.114) (xy 9.144 -22.098) (xy 12.7 -22.098)
				(xy 13.6398 -21.1582) (xy 13.6398 -19.7104) (xy 13.6398 -6.5278) (xy 13.3985 -6.2865) (xy 9.4615 -6.2865)
			)
		)
	)
	(zone
		(net "GND")
		(layer "B.Cu")
		(hatch none 0.5)
		(connect_pads
			(clearance 0.5)
		)
		(min_thickness 0.25)
		(fill yes
			(thermal_gap 0.5)
			(thermal_bridge_width 0.5)
			(island_removal_mode 0)
		)
		(polygon
			(pts
				(xy 376.15622 -132.25653) (xy 376.014996 -132.397754) (xy 376.014996 -134.11835) (xy 376.248168 -134.351522)
				(xy 377.11253 -134.351522) (xy 377.155456 -134.308596) (xy 377.155456 -133.508496) (xy 377.248674 -133.415278)
				(xy 377.248674 -132.371846) (xy 377.133358 -132.25653)
			)
		)
		(polygon
			(pts
				(xy 376.3899 -133.4262) (xy 376.1867 -133.4262) (xy 376.1867 -133.6294) (xy 376.3899 -133.6294)
			)
		)
	)
	(zone
		(net "GND")
		(layer "B.Cu")
		(hatch none 0.5)
		(connect_pads
			(clearance 0.5)
		)
		(min_thickness 0.25)
		(fill yes
			(thermal_gap 0.5)
			(thermal_bridge_width 0.5)
			(island_removal_mode 0)
		)
		(polygon
			(pts
				(xy 277.9268 -157.6324) (xy 281.4066 -157.6324) (xy 281.7876 -157.2514) (xy 281.7876 -155.3972)
				(xy 281.559 -155.1686) (xy 279.7302 -155.1686) (xy 278.6126 -156.2862) (xy 277.8506 -156.2862) (xy 277.7744 -156.3624)
				(xy 277.7744 -157.48)
			)
		)
	)
	(zone
		(layer "B.Cu")
		(hatch none 0.5)
		(connect_pads
			(clearance 0)
		)
		(min_thickness 0.25)
		(keepout
			(tracks allowed)
			(vias allowed)
			(pads allowed)
			(copperpour allowed)
			(footprints allowed)
		)
		(placement
			(enabled no)
			(sheetname "")
		)
		(fill
			(thermal_gap 0.5)
			(thermal_bridge_width 0.5)
			(island_removal_mode 0)
		)
		(polygon
			(pts
				(xy 479.933 -133.9469) (xy 479.933 -133.02742) (xy 481.41636 -133.02742) (xy 481.41636 -133.9469)
			)
		)
	)
	(zone
		(layer "B.Cu")
		(hatch none 0.5)
		(connect_pads
			(clearance 0)
		)
		(min_thickness 0.25)
		(keepout
			(tracks allowed)
			(vias allowed)
			(pads allowed)
			(copperpour allowed)
			(footprints allowed)
		)
		(placement
			(enabled no)
			(sheetname "")
		)
		(fill
			(thermal_gap 0.5)
			(thermal_bridge_width 0.5)
			(island_removal_mode 0)
		)
		(polygon
			(pts
				(xy 150.749 -93.599) (xy 150.749 -92.837) (xy 151.511 -92.837) (xy 151.511 -93.599)
			)
		)
	)
	(zone
		(layer "B.Cu")
		(hatch none 0.5)
		(connect_pads
			(clearance 0)
		)
		(min_thickness 0.25)
		(keepout
			(tracks allowed)
			(vias allowed)
			(pads allowed)
			(copperpour allowed)
			(footprints not_allowed)
		)
		(placement
			(enabled no)
			(sheetname "")
		)
		(fill
			(thermal_gap 0.5)
			(thermal_bridge_width 0.5)
			(island_removal_mode 0)
		)
		(polygon
			(pts
				(xy 187.520072 5.999988) (xy 185.879994 5.999988) (xy 185.879994 -25.729946) (xy 187.520072 -25.729946)
			)
		)
	)
	(zone
		(net "PVDDQ_DEF")
		(layer "B.Cu")
		(hatch none 0.5)
		(connect_pads
			(clearance 0.5)
		)
		(min_thickness 0.25)
		(fill yes
			(thermal_gap 0.5)
			(thermal_bridge_width 0.5)
			(island_removal_mode 0)
		)
		(polygon
			(pts
				(xy 243.922804 -148.542248) (xy 243.735606 -148.729446) (xy 243.735606 -150.834852) (xy 243.866416 -150.965662)
				(xy 253.469902 -150.965662) (xy 253.477522 -150.958042) (xy 256.1336 -150.958042) (xy 256.286 -150.805642)
				(xy 256.286 -148.796502) (xy 256.031746 -148.542248)
			)
		)
		(polygon
			(pts
				(xy 253.049532 -150.0886) (xy 252.846332 -150.0886) (xy 252.846332 -150.2918) (xy 253.049532 -150.2918)
			)
		)
		(polygon
			(pts
				(xy 252.7046 -150.0886) (xy 252.5014 -150.0886) (xy 252.5014 -150.2918) (xy 252.7046 -150.2918)
			)
		)
		(polygon
			(pts
				(xy 249.4026 -150.0886) (xy 249.1994 -150.0886) (xy 249.1994 -150.2918) (xy 249.4026 -150.2918)
			)
		)
		(polygon
			(pts
				(xy 253.049532 -149.3266) (xy 252.846332 -149.3266) (xy 252.846332 -149.5298) (xy 253.049532 -149.5298)
			)
		)
		(polygon
			(pts
				(xy 252.7046 -149.3266) (xy 252.5014 -149.3266) (xy 252.5014 -149.5298) (xy 252.7046 -149.5298)
			)
		)
		(polygon
			(pts
				(xy 249.4026 -149.3266) (xy 249.1994 -149.3266) (xy 249.1994 -149.5298) (xy 249.4026 -149.5298)
			)
		)
	)
	(zone
		(layer "B.Cu")
		(hatch none 0.5)
		(connect_pads
			(clearance 0)
		)
		(min_thickness 0.25)
		(keepout
			(tracks not_allowed)
			(vias allowed)
			(pads allowed)
			(copperpour not_allowed)
			(footprints allowed)
		)
		(placement
			(enabled no)
			(sheetname "")
		)
		(fill
			(thermal_gap 0.5)
			(thermal_bridge_width 0.5)
			(island_removal_mode 0)
		)
		(polygon
			(pts
				(arc
					(start 15.42542 -108.030772)
					(mid 15.492496 -107.50687)
					(end 15.570454 -108.029248)
				)
				(xy 15.759176 -108.21797) (xy 15.87881 -108.21797)
				(arc
					(start 15.87881 -107.77347)
					(mid 15.49527 -107.38993)
					(end 15.11173 -107.77347)
				)
				(arc
					(start 15.11173 -109.043216)
					(mid 15.495143 -109.42701)
					(end 15.87881 -109.04347)
				)
				(xy 15.87881 -108.59897) (xy 15.756636 -108.59897)
				(arc
					(start 15.568422 -108.78693)
					(mid 15.494076 -109.310162)
					(end 15.42542 -108.786168)
				)
				(xy 15.42542 -108.732574) (xy 15.698724 -108.45927) (xy 15.87881 -108.45927) (xy 15.87881 -108.35767)
				(xy 15.701264 -108.35767) (xy 15.42542 -108.081826)
			)
		)
	)
	(zone
		(net "PVDDQ_KLM")
		(layer "B.Cu")
		(hatch none 0.5)
		(connect_pads
			(clearance 0.5)
		)
		(min_thickness 0.25)
		(fill yes
			(thermal_gap 0.5)
			(thermal_bridge_width 0.5)
			(island_removal_mode 0)
		)
		(polygon
			(pts
				(xy 100.978716 -155.862782) (xy 102.183438 -155.862782) (xy 102.614984 -156.294328) (xy 102.614984 -157.329378)
				(xy 102.881938 -157.596332) (xy 111.5822 -157.596332) (xy 111.592868 -157.607) (xy 111.76 -157.607)
				(xy 111.907574 -157.459426) (xy 111.907574 -156.687774) (xy 112.528604 -156.066744) (xy 112.528604 -155.660344)
				(xy 112.528604 -153.43251) (xy 112.34039 -153.244296) (xy 100.928932 -153.244296) (xy 100.677726 -153.495502)
				(xy 100.677726 -155.561792)
			)
		)
	)
	(zone
		(layer "B.Cu")
		(hatch none 0.5)
		(connect_pads
			(clearance 0)
		)
		(min_thickness 0.25)
		(keepout
			(tracks allowed)
			(vias allowed)
			(pads allowed)
			(copperpour allowed)
			(footprints allowed)
		)
		(placement
			(enabled no)
			(sheetname "")
		)
		(fill
			(thermal_gap 0.5)
			(thermal_bridge_width 0.5)
			(island_removal_mode 0)
		)
		(polygon
			(pts
				(xy 403.733 -125.73) (xy 403.733 -124.968) (xy 404.622 -124.968) (xy 404.622 -125.73)
			)
		)
	)
	(zone
		(layer "B.Cu")
		(hatch none 0.5)
		(connect_pads
			(clearance 0)
		)
		(min_thickness 0.25)
		(keepout
			(tracks allowed)
			(vias allowed)
			(pads allowed)
			(copperpour allowed)
			(footprints allowed)
		)
		(placement
			(enabled no)
			(sheetname "")
		)
		(fill
			(thermal_gap 0.5)
			(thermal_bridge_width 0.5)
			(island_removal_mode 0)
		)
		(polygon
			(pts
				(xy 151.765 -61.468) (xy 151.765 -60.706) (xy 152.527 -60.706) (xy 152.527 -61.468)
			)
		)
	)
	(zone
		(net "PVDDQ_KLM")
		(layer "B.Cu")
		(hatch none 0.5)
		(connect_pads
			(clearance 0.5)
		)
		(min_thickness 0.25)
		(fill yes
			(thermal_gap 0.5)
			(thermal_bridge_width 0.5)
			(island_removal_mode 0)
		)
		(polygon
			(pts
				(xy 100.928932 -143.643096) (xy 100.677726 -143.894302) (xy 100.677726 -145.960592) (xy 100.978716 -146.261582)
				(xy 112.326166 -146.261582) (xy 112.528604 -146.059144) (xy 112.528604 -143.83131) (xy 112.34039 -143.643096)
			)
		)
		(polygon
			(pts
				(xy 107.5182 -145.4023) (xy 107.315 -145.4023) (xy 107.315 -145.6055) (xy 107.5182 -145.6055)
			)
		)
		(polygon
			(pts
				(xy 104.2162 -145.4023) (xy 104.013 -145.4023) (xy 104.013 -145.6055) (xy 104.2162 -145.6055)
			)
		)
		(polygon
			(pts
				(xy 101.0539 -145.4023) (xy 100.8507 -145.4023) (xy 100.8507 -145.6055) (xy 101.0539 -145.6055)
			)
		)
		(polygon
			(pts
				(xy 110.657132 -144.4117) (xy 110.453932 -144.4117) (xy 110.453932 -144.6149) (xy 110.657132 -144.6149)
			)
		)
		(polygon
			(pts
				(xy 107.5182 -144.4117) (xy 107.315 -144.4117) (xy 107.315 -144.6149) (xy 107.5182 -144.6149)
			)
		)
		(polygon
			(pts
				(xy 104.2162 -144.4117) (xy 104.013 -144.4117) (xy 104.013 -144.6149) (xy 104.2162 -144.6149)
			)
		)
	)
	(zone
		(net "PVPP_KLM")
		(layer "B.Cu")
		(hatch none 0.5)
		(connect_pads
			(clearance 0.5)
		)
		(min_thickness 0.25)
		(fill yes
			(thermal_gap 0.5)
			(thermal_bridge_width 0.5)
			(island_removal_mode 0)
		)
		(polygon
			(pts
				(xy 158.262828 -123.7234) (xy 157.756098 -124.23013) (xy 157.756098 -124.876306) (xy 157.4165 -125.215904)
				(xy 152.813004 -125.215904) (xy 151.756618 -126.27229) (xy 151.756618 -157.344618) (xy 152.019 -157.607)
				(xy 163.015676 -157.607) (xy 164.17163 -156.451046) (xy 164.17163 -144.74063) (xy 164.0586 -144.6276)
				(xy 164.0586 -144.2212) (xy 164.2872 -143.9926) (xy 171.1198 -143.9926) (xy 171.2722 -143.8402)
				(xy 171.2722 -141.689328) (xy 168.6052 -139.022328) (xy 168.6052 -134.441438) (xy 169.087038 -133.9596)
				(xy 169.087038 -132.889244) (xy 167.515794 -131.318) (xy 164.973 -131.318) (xy 164.211 -130.556)
				(xy 164.211 -127.368554) (xy 162.05835 -125.215904) (xy 161.497772 -125.215904) (xy 161.097214 -124.815346)
				(xy 161.097214 -123.7996) (xy 161.021014 -123.7234)
			)
		)
		(polygon
			(pts
				(xy 154.722068 -155.061412) (xy 154.518868 -155.061412) (xy 154.518868 -155.264612) (xy 154.722068 -155.264612)
			)
		)
		(polygon
			(pts
				(xy 154.341068 -155.061412) (xy 154.137868 -155.061412) (xy 154.137868 -155.264612) (xy 154.341068 -155.264612)
			)
		)
		(polygon
			(pts
				(xy 154.722068 -154.299412) (xy 154.518868 -154.299412) (xy 154.518868 -154.502612) (xy 154.722068 -154.502612)
			)
		)
		(polygon
			(pts
				(xy 154.341068 -154.299412) (xy 154.137868 -154.299412) (xy 154.137868 -154.502612) (xy 154.341068 -154.502612)
			)
		)
		(polygon
			(pts
				(xy 154.950668 -145.257012) (xy 154.747468 -145.257012) (xy 154.747468 -145.460212) (xy 154.950668 -145.460212)
			)
		)
		(polygon
			(pts
				(xy 154.569668 -145.257012) (xy 154.366468 -145.257012) (xy 154.366468 -145.460212) (xy 154.569668 -145.460212)
			)
		)
		(polygon
			(pts
				(xy 154.950668 -144.495012) (xy 154.747468 -144.495012) (xy 154.747468 -144.698212) (xy 154.950668 -144.698212)
			)
		)
		(polygon
			(pts
				(xy 154.569668 -144.495012) (xy 154.366468 -144.495012) (xy 154.366468 -144.698212) (xy 154.569668 -144.698212)
			)
		)
		(polygon
			(pts
				(xy 154.950668 -135.655812) (xy 154.747468 -135.655812) (xy 154.747468 -135.859012) (xy 154.950668 -135.859012)
			)
		)
		(polygon
			(pts
				(xy 154.569668 -135.655812) (xy 154.366468 -135.655812) (xy 154.366468 -135.859012) (xy 154.569668 -135.859012)
			)
		)
		(polygon
			(pts
				(xy 154.950668 -134.893812) (xy 154.747468 -134.893812) (xy 154.747468 -135.097012) (xy 154.950668 -135.097012)
			)
		)
		(polygon
			(pts
				(xy 154.569668 -134.893812) (xy 154.366468 -134.893812) (xy 154.366468 -135.097012) (xy 154.569668 -135.097012)
			)
		)
	)
	(zone
		(net "PVDDQ_KLM")
		(layer "B.Cu")
		(hatch none 0.5)
		(connect_pads
			(clearance 0.5)
		)
		(min_thickness 0.25)
		(fill yes
			(thermal_gap 0.5)
			(thermal_bridge_width 0.5)
			(island_removal_mode 0)
		)
		(polygon
			(pts
				(xy 78.917038 -131.77266) (xy 93.495622 -131.77266) (xy 93.663262 -131.60502) (xy 93.663262 -129.580386)
				(xy 93.509592 -129.426716) (xy 79.559404 -129.426716) (xy 78.763622 -130.222498) (xy 78.763622 -131.619244)
			)
		)
	)
	(zone
		(layer "B.Cu")
		(hatch none 0.5)
		(connect_pads
			(clearance 0)
		)
		(min_thickness 0.25)
		(keepout
			(tracks not_allowed)
			(vias allowed)
			(pads allowed)
			(copperpour not_allowed)
			(footprints allowed)
		)
		(placement
			(enabled no)
			(sheetname "")
		)
		(fill
			(thermal_gap 0.5)
			(thermal_bridge_width 0.5)
			(island_removal_mode 0)
		)
		(polygon
			(pts
				(arc
					(start 409.719526 -72.883776)
					(mid 405.719534 -76.883768)
					(end 409.719526 -80.88376)
				)
				(arc
					(start 409.719526 -80.88376)
					(mid 413.719518 -76.883768)
					(end 409.719526 -72.883776)
				)
			)
		)
	)
	(zone
		(layer "B.Cu")
		(hatch none 0.5)
		(connect_pads
			(clearance 0)
		)
		(min_thickness 0.25)
		(keepout
			(tracks not_allowed)
			(vias allowed)
			(pads allowed)
			(copperpour not_allowed)
			(footprints allowed)
		)
		(placement
			(enabled no)
			(sheetname "")
		)
		(fill
			(thermal_gap 0.5)
			(thermal_bridge_width 0.5)
			(island_removal_mode 0)
		)
		(polygon
			(pts
				(arc
					(start 222.000064 -79.090012)
					(mid 224.540064 -76.550012)
					(end 222.000064 -74.010012)
				)
				(arc
					(start 222.000064 -74.010012)
					(mid 219.460064 -76.550012)
					(end 222.000064 -79.090012)
				)
			)
		)
	)
	(zone
		(net "GND")
		(layer "B.Cu")
		(hatch none 0.5)
		(connect_pads
			(clearance 0.5)
		)
		(min_thickness 0.25)
		(fill yes
			(thermal_gap 0.5)
			(thermal_bridge_width 0.5)
			(island_removal_mode 0)
		)
		(polygon
			(pts
				(xy 335.58988 -51.54168) (xy 331.567536 -51.54168) (xy 329.84948 -51.54168) (xy 329.5015 -51.54168)
				(xy 329.34402 -51.69916) (xy 329.34402 -55.92318) (xy 328.79538 -56.47182) (xy 328.79538 -56.79948)
				(xy 328.84618 -56.85028) (xy 330.93152 -56.85028) (xy 331.855572 -55.926228) (xy 332.45806 -55.926228)
				(xy 335.448148 -55.926228) (xy 335.673446 -55.70093) (xy 335.673446 -54.876954) (xy 336.7786 -53.7718)
				(xy 336.7786 -52.7304)
			)
		)
	)
	(zone
		(layer "B.Cu")
		(hatch none 0.5)
		(connect_pads
			(clearance 0)
		)
		(min_thickness 0.25)
		(keepout
			(tracks allowed)
			(vias allowed)
			(pads allowed)
			(copperpour allowed)
			(footprints allowed)
		)
		(placement
			(enabled no)
			(sheetname "")
		)
		(fill
			(thermal_gap 0.5)
			(thermal_bridge_width 0.5)
			(island_removal_mode 0)
		)
		(polygon
			(pts
				(xy 304.6476 -50.6476) (xy 304.6476 -50.3936) (xy 302.9966 -48.7426) (xy 292.354 -48.7426) (xy 291.9476 -49.149)
				(xy 291.9476 -50.9524) (xy 292.1 -50.8) (xy 304.4952 -50.8)
			)
		)
	)
	(zone
		(net "PVCCIO_CPU1")
		(layer "B.Cu")
		(hatch none 0.5)
		(connect_pads
			(clearance 0.5)
		)
		(min_thickness 0.25)
		(fill yes
			(thermal_gap 0.5)
			(thermal_bridge_width 0.5)
			(island_removal_mode 0)
		)
		(polygon
			(pts
				(xy 113.067592 -69.158612) (xy 113.067592 -72.095614) (xy 113.183416 -72.211184) (xy 115.7224 -72.211184)
				(xy 115.7224 -71.374) (xy 115.5954 -71.247) (xy 115.3922 -71.247) (xy 115.164616 -71.019416) (xy 115.164616 -70.991984)
				(xy 115.150392 -70.978014) (xy 115.150392 -70.470014) (xy 115.480592 -70.139814) (xy 115.480592 -69.936614)
				(xy 114.718592 -69.174614) (xy 114.472212 -69.174614) (xy 114.472212 -69.158612)
			)
		)
		(polygon
			(pts
				(xy 115.074192 -71.295514) (xy 114.870992 -71.295514) (xy 114.870992 -71.498714) (xy 115.074192 -71.498714)
			)
		)
	)
	(zone
		(layer "B.Cu")
		(hatch none 0.5)
		(connect_pads
			(clearance 0)
		)
		(min_thickness 0.25)
		(keepout
			(tracks allowed)
			(vias allowed)
			(pads allowed)
			(copperpour allowed)
			(footprints allowed)
		)
		(placement
			(enabled no)
			(sheetname "")
		)
		(fill
			(thermal_gap 0.5)
			(thermal_bridge_width 0.5)
			(island_removal_mode 0)
		)
		(polygon
			(pts
				(xy 284.723332 -26.269442) (xy 284.723332 -52.01031) (xy 287.736788 -52.010818) (xy 296.211498 -43.742102)
				(xy 296.211498 -30.073092) (xy 296.022522 -29.884116) (xy 288.449512 -28.604718) (xy 288.222182 -28.604718)
				(xy 285.888938 -26.271474) (xy 285.560516 -26.271474) (xy 285.556198 -26.275792) (xy 284.729682 -26.275792)
			)
		)
	)
	(zone
		(layer "B.Cu")
		(hatch none 0.5)
		(connect_pads
			(clearance 0)
		)
		(min_thickness 0.25)
		(keepout
			(tracks allowed)
			(vias allowed)
			(pads allowed)
			(copperpour allowed)
			(footprints not_allowed)
		)
		(placement
			(enabled no)
			(sheetname "")
		)
		(fill
			(thermal_gap 0.5)
			(thermal_bridge_width 0.5)
			(island_removal_mode 0)
		)
		(polygon
			(pts
				(arc
					(start 300.137068 -33.299908)
					(mid 296.520162 -27.591736)
					(end 292.902894 -33.299908)
				)
			)
		)
	)
	(zone
		(layer "B.Cu")
		(hatch none 0.5)
		(connect_pads
			(clearance 0)
		)
		(min_thickness 0.25)
		(keepout
			(tracks not_allowed)
			(vias allowed)
			(pads allowed)
			(copperpour not_allowed)
			(footprints allowed)
		)
		(placement
			(enabled no)
			(sheetname "")
		)
		(fill
			(thermal_gap 0.5)
			(thermal_bridge_width 0.5)
			(island_removal_mode 0)
		)
		(polygon
			(pts
				(xy 439.658506 -126.63805) (xy 439.658506 -126.936246) (xy 439.503312 -127.09144)
				(arc
					(start 439.331608 -127.09144)
					(mid 438.807691 -127.02159)
					(end 439.331608 -126.95174)
				)
				(xy 439.4454 -126.95174) (xy 439.518806 -126.878334) (xy 439.518806 -126.63805)
				(arc
					(start 439.07456 -126.63805)
					(mid 438.690766 -127.021463)
					(end 439.074306 -127.40513)
				)
				(arc
					(start 440.344306 -127.40513)
					(mid 440.727846 -127.02159)
					(end 440.344306 -126.63805)
				)
				(xy 439.899806 -126.63805) (xy 439.899806 -126.878334) (xy 439.973212 -126.95174)
				(arc
					(start 440.087004 -126.95174)
					(mid 440.610921 -127.02159)
					(end 440.087004 -127.09144)
				)
				(xy 439.9153 -127.09144) (xy 439.760106 -126.936246) (xy 439.760106 -126.63805)
			)
		)
	)
	(zone
		(layer "B.Cu")
		(hatch none 0.5)
		(connect_pads
			(clearance 0)
		)
		(min_thickness 0.25)
		(keepout
			(tracks allowed)
			(vias allowed)
			(pads allowed)
			(copperpour allowed)
			(footprints not_allowed)
		)
		(placement
			(enabled no)
			(sheetname "")
		)
		(fill
			(thermal_gap 0.5)
			(thermal_bridge_width 0.5)
			(island_removal_mode 0)
		)
		(polygon
			(pts
				(arc
					(start 152.999948 -101.089968)
					(mid 155.539948 -98.549968)
					(end 152.999948 -96.009968)
				)
				(arc
					(start 152.999948 -96.009968)
					(mid 150.459948 -98.549968)
					(end 152.999948 -101.089968)
				)
			)
		)
	)
	(zone
		(layer "B.Cu")
		(hatch none 0.5)
		(connect_pads
			(clearance 0)
		)
		(min_thickness 0.25)
		(keepout
			(tracks not_allowed)
			(vias allowed)
			(pads allowed)
			(copperpour not_allowed)
			(footprints allowed)
		)
		(placement
			(enabled no)
			(sheetname "")
		)
		(fill
			(thermal_gap 0.5)
			(thermal_bridge_width 0.5)
			(island_removal_mode 0)
		)
		(polygon
			(pts
				(arc
					(start -5.999988 -157.599888)
					(mid -4.658434 -155.09995)
					(end -5.999988 -152.599898)
				)
			)
		)
	)
	(zone
		(net "GND")
		(layer "B.Cu")
		(hatch none 0.5)
		(connect_pads
			(clearance 0.5)
		)
		(min_thickness 0.25)
		(fill yes
			(thermal_gap 0.5)
			(thermal_bridge_width 0.5)
			(island_removal_mode 0)
		)
		(polygon
			(pts
				(xy 260.56971 -137.644886) (xy 260.884162 -137.644886) (xy 261.798562 -136.730486) (xy 261.798562 -134.834884)
				(xy 261.711186 -134.747508) (xy 260.976618 -134.747508) (xy 260.81736 -134.906766) (xy 260.81736 -136.155176)
				(xy 260.452616 -136.51992) (xy 260.452616 -137.527792)
			)
		)
	)
	(zone
		(layer "B.Cu")
		(hatch none 0.5)
		(connect_pads
			(clearance 0)
		)
		(min_thickness 0.25)
		(keepout
			(tracks allowed)
			(vias allowed)
			(pads allowed)
			(copperpour allowed)
			(footprints allowed)
		)
		(placement
			(enabled no)
			(sheetname "")
		)
		(fill
			(thermal_gap 0.5)
			(thermal_bridge_width 0.5)
			(island_removal_mode 0)
		)
		(polygon
			(pts
				(xy 4.445 -122.301) (xy 4.445 -121.031) (xy 5.588 -121.031) (xy 5.588 -122.301)
			)
		)
	)
	(zone
		(layer "B.Cu")
		(hatch none 0.5)
		(connect_pads
			(clearance 0)
		)
		(min_thickness 0.25)
		(keepout
			(tracks not_allowed)
			(vias allowed)
			(pads allowed)
			(copperpour not_allowed)
			(footprints allowed)
		)
		(placement
			(enabled no)
			(sheetname "")
		)
		(fill
			(thermal_gap 0.5)
			(thermal_bridge_width 0.5)
			(island_removal_mode 0)
		)
		(polygon
			(pts
				(xy 348.967806 -59.733434) (xy 348.459806 -59.733434) (xy 348.459806 -60.114434) (xy 348.967806 -60.114434)
			)
		)
	)
	(zone
		(net "PVCCIO_CPU0")
		(layer "B.Cu")
		(hatch none 0.5)
		(connect_pads
			(clearance 0.5)
		)
		(min_thickness 0.25)
		(fill yes
			(thermal_gap 0.5)
			(thermal_bridge_width 0.5)
			(island_removal_mode 0)
		)
		(polygon
			(pts
				(xy 278.068024 -69.158612) (xy 278.068024 -72.095614) (xy 278.322024 -72.349614) (xy 280.735024 -72.349614)
				(xy 280.735024 -71.384414) (xy 280.608024 -71.257414) (xy 280.430224 -71.257414) (xy 280.150824 -70.978014)
				(xy 280.150824 -70.142354) (xy 280.26106 -70.032118) (xy 280.26106 -69.592952) (xy 279.82672 -69.158612)
			)
		)
		(polygon
			(pts
				(xy 280.074624 -71.295514) (xy 279.871424 -71.295514) (xy 279.871424 -71.498714) (xy 280.074624 -71.498714)
			)
		)
	)
	(zone
		(layer "B.Cu")
		(hatch none 0.5)
		(connect_pads
			(clearance 0)
		)
		(min_thickness 0.25)
		(keepout
			(tracks allowed)
			(vias allowed)
			(pads allowed)
			(copperpour allowed)
			(footprints not_allowed)
		)
		(placement
			(enabled no)
			(sheetname "")
		)
		(fill
			(thermal_gap 0.5)
			(thermal_bridge_width 0.5)
			(island_removal_mode 0)
		)
		(polygon
			(pts
				(arc
					(start 4.629912 -41.710102)
					(mid 1.02997 -45.310044)
					(end 4.629912 -48.909986)
				)
				(arc
					(start 4.629912 -48.909986)
					(mid 8.229854 -45.310044)
					(end 4.629912 -41.710102)
				)
			)
		)
	)
	(zone
		(layer "B.Cu")
		(hatch none 0.5)
		(connect_pads
			(clearance 0)
		)
		(min_thickness 0.25)
		(keepout
			(tracks not_allowed)
			(vias allowed)
			(pads allowed)
			(copperpour not_allowed)
			(footprints allowed)
		)
		(placement
			(enabled no)
			(sheetname "")
		)
		(fill
			(thermal_gap 0.5)
			(thermal_bridge_width 0.5)
			(island_removal_mode 0)
		)
		(polygon
			(pts
				(arc
					(start 171.99991 0.500126)
					(mid 170.499786 2.00025)
					(end 171.99991 3.50012)
				)
				(arc
					(start 172.671486 3.50012)
					(mid 173.338113 3.614414)
					(end 173.928532 3.944366)
				)
				(arc
					(start 173.928532 3.944366)
					(mid 177.999652 1.999996)
					(end 173.928532 0.055626)
				)
				(arc
					(start 173.928532 0.055626)
					(mid 173.338136 0.385683)
					(end 172.671486 0.500126)
				)
			)
		)
	)
	(zone
		(net "PVDDQ_DEF")
		(layer "B.Cu")
		(hatch none 0.5)
		(connect_pads
			(clearance 0.5)
		)
		(min_thickness 0.25)
		(fill yes
			(thermal_gap 0.5)
			(thermal_bridge_width 0.5)
			(island_removal_mode 0)
		)
		(polygon
			(pts
				(xy 267.208 -124.3076) (xy 267.183616 -124.331984) (xy 267.183616 -124.924058) (xy 267.088874 -125.0188)
				(xy 267.08862 -125.018546) (xy 266.954254 -125.018546) (xy 266.954 -125.0188) (xy 266.3063 -125.0188)
				(xy 265.8999 -125.4252) (xy 265.8999 -126.5809) (xy 265.811 -126.6698) (xy 265.811 -129.7432) (xy 265.9126 -129.8448)
				(xy 266.2428 -129.8448) (xy 266.3952 -129.6924) (xy 266.3952 -127.3302) (xy 266.6238 -127.1016)
				(xy 268.2748 -127.1016) (xy 268.3764 -127.2032) (xy 268.3764 -130.3274) (xy 268.5288 -130.4798)
				(xy 268.7574 -130.4798) (xy 268.9098 -130.3274) (xy 268.9098 -127.2794) (xy 269.113 -127.0762) (xy 270.8148 -127.0762)
				(xy 270.9418 -127.2032) (xy 270.9418 -129.6924) (xy 271.1196 -129.8702) (xy 271.272 -129.8702) (xy 271.4244 -129.7178)
				(xy 271.4244 -127.2794) (xy 271.5768 -127.127) (xy 272.542 -127.127) (xy 272.6436 -127.2286) (xy 272.6436 -129.794)
				(xy 272.8214 -129.9718) (xy 273.0754 -129.9718) (xy 273.304 -129.7432) (xy 273.304 -127.080518)
				(xy 275.518372 -127.080518) (xy 275.630132 -126.968758) (xy 277.20798 -126.968758) (xy 277.31974 -126.856998)
				(xy 277.31974 -125.2093) (xy 277.09622 -124.98578) (xy 270.331692 -124.98578) (xy 269.653512 -124.3076)
			)
		)
		(polygon
			(pts
				(xy 276.590252 -126.08814) (xy 276.387052 -126.08814) (xy 276.387052 -126.29134) (xy 276.590252 -126.29134)
			)
		)
		(polygon
			(pts
				(xy 276.590252 -125.09754) (xy 276.387052 -125.09754) (xy 276.387052 -125.30074) (xy 276.590252 -125.30074)
			)
		)
	)
	(zone
		(layer "B.Cu")
		(hatch none 0.5)
		(connect_pads
			(clearance 0)
		)
		(min_thickness 0.25)
		(keepout
			(tracks not_allowed)
			(vias allowed)
			(pads allowed)
			(copperpour not_allowed)
			(footprints allowed)
		)
		(placement
			(enabled no)
			(sheetname "")
		)
		(fill
			(thermal_gap 0.5)
			(thermal_bridge_width 0.5)
			(island_removal_mode 0)
		)
		(polygon
			(pts
				(arc
					(start 381.35179 -22.016974)
					(mid 380.96825 -21.633434)
					(end 380.58471 -22.016974)
				)
				(arc
					(start 380.58471 -22.982174)
					(mid 380.96698 -23.365712)
					(end 381.35179 -22.984714)
				)
				(arc
					(start 381.28575 -22.984714)
					(mid 380.96825 -23.299684)
					(end 380.65075 -22.984714)
				)
				(arc
					(start 380.65075 -22.982174)
					(mid 380.96825 -22.664674)
					(end 381.28575 -22.982174)
				)
				(xy 381.35179 -22.982174) (xy 381.35179 -22.019514)
				(arc
					(start 381.23495 -22.019514)
					(mid 380.96825 -22.283686)
					(end 380.70155 -22.019514)
				)
				(arc
					(start 380.70155 -22.016974)
					(mid 380.96825 -21.750274)
					(end 381.23495 -22.016974)
				)
			)
		)
	)
	(zone
		(layer "B.Cu")
		(hatch none 0.5)
		(connect_pads
			(clearance 0)
		)
		(min_thickness 0.25)
		(keepout
			(tracks allowed)
			(vias allowed)
			(pads allowed)
			(copperpour allowed)
			(footprints not_allowed)
		)
		(placement
			(enabled no)
			(sheetname "")
		)
		(fill
			(thermal_gap 0.5)
			(thermal_bridge_width 0.5)
			(island_removal_mode 0)
		)
		(polygon
			(pts
				(arc
					(start 222.000064 -78.449932)
					(mid 223.899984 -76.550012)
					(end 222.000064 -74.650092)
				)
				(arc
					(start 222.000064 -74.650092)
					(mid 220.100144 -76.550012)
					(end 222.000064 -78.449932)
				)
			)
		)
	)
	(zone
		(net "P3V3_STBY")
		(layer "B.Cu")
		(hatch none 0.5)
		(connect_pads
			(clearance 0.5)
		)
		(min_thickness 0.25)
		(fill yes
			(thermal_gap 0.5)
			(thermal_bridge_width 0.5)
			(island_removal_mode 0)
		)
		(polygon
			(pts
				(xy 268.72692 -91.79814) (xy 266.90574 -93.61932) (xy 257.47726 -93.61932) (xy 257.05943 -93.20149)
				(xy 257.04292 -93.20149) (xy 256.9591 -93.11767) (xy 244.56517 -93.11767) (xy 244.48135 -93.20149)
				(xy 242.25885 -93.20149) (xy 241.58194 -93.8784) (xy 228.1428 -93.8784) (xy 228.0158 -93.8784) (xy 227.838 -93.7006)
				(xy 227.838 -90.043) (xy 227.39858 -90.043) (xy 227.24999 -90.19159) (xy 227.24999 -96.87687) (xy 227.84054 -97.46742)
				(xy 244.13464 -97.46742) (xy 245.15572 -98.4885) (xy 257.49504 -98.4885) (xy 258.51612 -97.46742)
				(xy 268.88186 -97.46742) (xy 271.0307 -95.31858) (xy 271.0307 -91.90228) (xy 270.82242 -91.694)
				(xy 268.83106 -91.694)
			)
		)
	)
	(zone
		(net "VR_FET_SW_P12V_STBY_PVDDQ_KLM")
		(layer "B.Cu")
		(hatch none 0.5)
		(connect_pads
			(clearance 0.5)
		)
		(min_thickness 0.25)
		(fill yes
			(thermal_gap 0.5)
			(thermal_bridge_width 0.5)
			(island_removal_mode 0)
		)
		(polygon
			(pts
				(xy 16.1544 -129.0066) (xy 16.1544 -126.8984) (xy 15.6464 -126.3904) (xy 14.0208 -126.3904) (xy 13.3604 -127.0508)
				(xy 13.3604 -128.1176) (xy 13.3604 -128.84785) (xy 13.69695 -129.1844) (xy 15.9766 -129.1844)
			)
		)
	)
	(zone
		(layer "B.Cu")
		(hatch none 0.5)
		(connect_pads
			(clearance 0)
		)
		(min_thickness 0.25)
		(keepout
			(tracks not_allowed)
			(vias allowed)
			(pads allowed)
			(copperpour not_allowed)
			(footprints allowed)
		)
		(placement
			(enabled no)
			(sheetname "")
		)
		(fill
			(thermal_gap 0.5)
			(thermal_bridge_width 0.5)
			(island_removal_mode 0)
		)
		(polygon
			(pts
				(arc
					(start 407.24709 -144.35455)
					(mid 406.86355 -143.97101)
					(end 406.48001 -144.35455)
				)
				(arc
					(start 406.48001 -145.370296)
					(mid 406.863423 -145.75409)
					(end 407.24709 -145.37055)
				)
				(xy 407.24709 -145.05305)
				(arc
					(start 406.97785 -145.05305)
					(mid 406.946419 -145.066069)
					(end 406.9334 -145.0975)
				)
				(arc
					(start 406.9334 -145.113248)
					(mid 406.86355 -145.637165)
					(end 406.7937 -145.113248)
				)
				(xy 406.7937 -145.068544)
				(arc
					(start 406.796494 -145.06575)
					(mid 406.847662 -144.967312)
					(end 406.9461 -144.916144)
				)
				(xy 406.948894 -144.91335) (xy 407.24709 -144.91335) (xy 407.24709 -144.81175) (xy 406.948894 -144.81175)
				(arc
					(start 406.9461 -144.808956)
					(mid 406.847662 -144.757788)
					(end 406.796494 -144.65935)
				)
				(xy 406.7937 -144.656556)
				(arc
					(start 406.7937 -144.611852)
					(mid 406.86355 -144.087935)
					(end 406.9334 -144.611852)
				)
				(arc
					(start 406.9334 -144.6276)
					(mid 406.946419 -144.659031)
					(end 406.97785 -144.67205)
				)
				(xy 407.24709 -144.67205)
			)
		)
	)
	(zone
		(layer "B.Cu")
		(hatch none 0.5)
		(connect_pads
			(clearance 0)
		)
		(min_thickness 0.25)
		(keepout
			(tracks allowed)
			(vias allowed)
			(pads allowed)
			(copperpour allowed)
			(footprints not_allowed)
		)
		(placement
			(enabled no)
			(sheetname "")
		)
		(fill
			(thermal_gap 0.5)
			(thermal_bridge_width 0.5)
			(island_removal_mode 0)
		)
		(polygon
			(pts
				(xy 187.520072 -136.966198) (xy 187.520072 -133.785102) (xy 328.520044 -133.785102) (xy 328.520044 -136.966198)
			)
		)
	)
	(zone
		(layer "B.Cu")
		(hatch none 0.5)
		(connect_pads
			(clearance 0)
		)
		(min_thickness 0.25)
		(keepout
			(tracks allowed)
			(vias allowed)
			(pads allowed)
			(copperpour allowed)
			(footprints not_allowed)
		)
		(placement
			(enabled no)
			(sheetname "")
		)
		(fill
			(thermal_gap 0.5)
			(thermal_bridge_width 0.5)
			(island_removal_mode 0)
		)
		(polygon
			(pts
				(arc
					(start 175.50003 -1.999996)
					(mid 179.500022 1.999996)
					(end 175.50003 5.999988)
				)
				(arc
					(start 171.99991 5.999988)
					(mid 167.999918 1.999996)
					(end 171.99991 -1.999996)
				)
			)
		)
	)
	(zone
		(layer "B.Cu")
		(hatch none 0.5)
		(connect_pads
			(clearance 0)
		)
		(min_thickness 0.25)
		(keepout
			(tracks not_allowed)
			(vias allowed)
			(pads allowed)
			(copperpour not_allowed)
			(footprints allowed)
		)
		(placement
			(enabled no)
			(sheetname "")
		)
		(fill
			(thermal_gap 0.5)
			(thermal_bridge_width 0.5)
			(island_removal_mode 0)
		)
		(polygon
			(pts
				(arc
					(start 16.523462 -99.731068)
					(mid 16.292642 -99.255488)
					(end 16.64208 -99.652074)
				)
				(xy 16.82369 -99.833684)
				(arc
					(start 16.82369 -99.478084)
					(mid 16.440277 -99.09429)
					(end 16.05661 -99.47783)
				)
				(arc
					(start 16.05661 -100.74783)
					(mid 16.44015 -101.13137)
					(end 16.82369 -100.74783)
				)
				(xy 16.82369 -100.463096)
				(arc
					(start 16.671544 -100.615242)
					(mid 16.251573 -100.936407)
					(end 16.572738 -100.516436)
				)
				(xy 16.82369 -100.265484) (xy 16.82369 -100.031296)
			)
		)
	)
	(zone
		(net "GND")
		(layer "B.Cu")
		(hatch none 0.5)
		(connect_pads
			(clearance 0.5)
		)
		(min_thickness 0.25)
		(fill yes
			(thermal_gap 0.5)
			(thermal_bridge_width 0.5)
			(island_removal_mode 0)
		)
		(polygon
			(pts
				(xy 380.0602 -109.4486) (xy 379.6538 -109.855) (xy 379.6538 -111.8362) (xy 380.0348 -112.2172) (xy 382.5748 -112.2172)
				(xy 383.0066 -111.7854) (xy 383.0066 -111.3028) (xy 383.1336 -111.1758) (xy 383.1336 -110.998) (xy 383.032 -110.8964)
				(xy 383.032 -110.4392) (xy 383.2352 -110.236) (xy 383.4384 -110.236) (xy 383.4892 -110.1852) (xy 383.4892 -109.5502)
				(xy 383.3876 -109.4486)
			)
		)
	)
	(zone
		(layer "B.Cu")
		(hatch none 0.5)
		(connect_pads
			(clearance 0)
		)
		(min_thickness 0.25)
		(keepout
			(tracks not_allowed)
			(vias allowed)
			(pads allowed)
			(copperpour not_allowed)
			(footprints allowed)
		)
		(placement
			(enabled no)
			(sheetname "")
		)
		(fill
			(thermal_gap 0.5)
			(thermal_bridge_width 0.5)
			(island_removal_mode 0)
		)
		(polygon
			(pts
				(arc
					(start 407.778966 -150.5585)
					(mid 407.395426 -150.17496)
					(end 407.011886 -150.5585)
				)
				(arc
					(start 407.011886 -151.574246)
					(mid 407.395299 -151.95804)
					(end 407.778966 -151.5745)
				)
				(xy 407.778966 -151.257)
				(arc
					(start 407.509726 -151.257)
					(mid 407.478295 -151.270019)
					(end 407.465276 -151.30145)
				)
				(arc
					(start 407.465276 -151.317198)
					(mid 407.395426 -151.841115)
					(end 407.325576 -151.317198)
				)
				(xy 407.325576 -151.272494)
				(arc
					(start 407.32837 -151.2697)
					(mid 407.379538 -151.171262)
					(end 407.477976 -151.120094)
				)
				(xy 407.48077 -151.1173) (xy 407.778966 -151.1173) (xy 407.778966 -151.0157) (xy 407.48077 -151.0157)
				(arc
					(start 407.477976 -151.012906)
					(mid 407.38165 -150.963817)
					(end 407.329386 -150.869142)
				)
				(arc
					(start 407.329386 -150.869142)
					(mid 407.385877 -150.241059)
					(end 407.480008 -150.86457)
				)
				(arc
					(start 407.480008 -150.86457)
					(mid 407.493811 -150.873025)
					(end 407.509726 -150.876)
				)
				(xy 407.778966 -150.876)
			)
		)
	)
	(zone
		(net "PVDDQ_DEF")
		(layer "B.Cu")
		(hatch none 0.5)
		(connect_pads
			(clearance 0.5)
		)
		(min_thickness 0.25)
		(fill yes
			(thermal_gap 0.5)
			(thermal_bridge_width 0.5)
			(island_removal_mode 0)
		)
		(polygon
			(pts
				(xy 269.247366 -131.798822) (xy 277.28164 -131.798822) (xy 277.528274 -131.552188) (xy 277.528274 -129.723388)
				(xy 277.528274 -128.303274) (xy 277.2918 -128.0668) (xy 276.987 -128.0668) (xy 276.7584 -128.2954)
				(xy 276.7584 -129.1844) (xy 276.6314 -129.3114) (xy 275.0566 -129.3114) (xy 274.955 -129.2098) (xy 274.955 -128.1938)
				(xy 274.828 -128.0668) (xy 274.4216 -128.0668) (xy 274.32 -128.1684) (xy 274.32 -129.1336) (xy 274.1422 -129.3114)
				(xy 272.679668 -129.3114) (xy 272.411698 -129.57937) (xy 272.411698 -130.524504) (xy 272.247106 -130.689096)
				(xy 271.096486 -130.689096) (xy 271.055338 -130.647948) (xy 270.891 -130.647948) (xy 270.644366 -130.894582)
				(xy 270.08963 -130.894582) (xy 269.781528 -130.58648) (xy 269.452598 -130.58648) (xy 269.16507 -130.874008)
				(xy 269.16507 -131.716526)
			)
		)
	)
	(zone
		(layer "B.Cu")
		(hatch none 0.5)
		(connect_pads
			(clearance 0)
		)
		(min_thickness 0.25)
		(keepout
			(tracks not_allowed)
			(vias allowed)
			(pads allowed)
			(copperpour not_allowed)
			(footprints allowed)
		)
		(placement
			(enabled no)
			(sheetname "")
		)
		(fill
			(thermal_gap 0.5)
			(thermal_bridge_width 0.5)
			(island_removal_mode 0)
		)
		(polygon
			(pts
				(arc
					(start 12.44346 -106.682032)
					(mid 12.51331 -106.158115)
					(end 12.58316 -106.682032)
				)
				(xy 12.58316 -106.687874) (xy 12.764516 -106.86923) (xy 12.89685 -106.86923)
				(arc
					(start 12.89685 -106.42473)
					(mid 12.51331 -106.04119)
					(end 12.12977 -106.42473)
				)
				(arc
					(start 12.12977 -107.694476)
					(mid 12.513183 -108.07827)
					(end 12.89685 -107.69473)
				)
				(xy 12.89685 -107.25023) (xy 12.736576 -107.25023) (xy 12.58316 -107.403646)
				(arc
					(start 12.58316 -107.437428)
					(mid 12.51331 -107.961345)
					(end 12.44346 -107.437428)
				)
				(xy 12.44346 -107.345734) (xy 12.678664 -107.11053) (xy 12.89685 -107.11053) (xy 12.89685 -107.00893)
				(xy 12.706604 -107.00893) (xy 12.44346 -106.745786)
			)
		)
	)
	(zone
		(net "PVCCIN_CPU0")
		(layer "B.Cu")
		(hatch none 0.5)
		(connect_pads
			(clearance 0.5)
		)
		(min_thickness 0.25)
		(fill yes
			(thermal_gap 0.5)
			(thermal_bridge_width 0.5)
			(island_removal_mode 0)
		)
		(polygon
			(pts
				(xy 259.7912 -88.1126) (xy 260.5532 -88.1126) (xy 260.8326 -87.8332) (xy 261.9248 -87.8332) (xy 262.382 -88.2904)
				(xy 262.7884 -88.2904) (xy 263.017 -88.519) (xy 267.6144 -88.519) (xy 268.1478 -89.0524) (xy 278.2316 -89.0524)
				(xy 280.1874 -87.0966) (xy 280.1874 -86.36) (xy 279.6794 -85.852) (xy 278.3078 -85.852) (xy 276.987 -84.5312)
				(xy 276.987 -82.804) (xy 276.8854 -82.7024) (xy 276.3266 -82.7024) (xy 276.0472 -82.9818) (xy 276.0472 -84.1248)
				(xy 275.913088 -84.258912) (xy 275.913088 -85.497416) (xy 275.913088 -85.538056) (xy 275.614892 -85.836252)
				(xy 274.995386 -85.836252) (xy 274.954746 -85.876892) (xy 274.954746 -86.283038) (xy 274.649184 -86.5886)
				(xy 274.585176 -86.5886) (xy 272.5928 -86.5886) (xy 264.8204 -86.5886) (xy 264.668 -86.4362) (xy 263.5504 -86.4362)
				(xy 261.747 -84.6328) (xy 255.3716 -84.6328) (xy 255.1684 -84.836) (xy 257.5814 -87.249) (xy 258.9276 -87.249)
			)
		)
	)
	(zone
		(layer "B.Cu")
		(hatch none 0.5)
		(connect_pads
			(clearance 0)
		)
		(min_thickness 0.25)
		(keepout
			(tracks not_allowed)
			(vias allowed)
			(pads allowed)
			(copperpour not_allowed)
			(footprints allowed)
		)
		(placement
			(enabled no)
			(sheetname "")
		)
		(fill
			(thermal_gap 0.5)
			(thermal_bridge_width 0.5)
			(island_removal_mode 0)
		)
		(polygon
			(pts
				(arc
					(start 472.928696 0.055626)
					(mid 472.3383 0.385683)
					(end 471.67165 0.500126)
				)
				(arc
					(start 471.000074 0.500126)
					(mid 469.49995 2.00025)
					(end 471.000074 3.50012)
				)
				(arc
					(start 471.67165 3.50012)
					(mid 472.338277 3.614414)
					(end 472.928696 3.944366)
				)
				(arc
					(start 472.928696 3.944366)
					(mid 476.999816 1.999996)
					(end 472.928696 0.055626)
				)
			)
		)
	)
	(zone
		(layer "B.Cu")
		(hatch none 0.5)
		(connect_pads
			(clearance 0)
		)
		(min_thickness 0.25)
		(keepout
			(tracks allowed)
			(vias allowed)
			(pads allowed)
			(copperpour allowed)
			(footprints not_allowed)
		)
		(placement
			(enabled no)
			(sheetname "")
		)
		(fill
			(thermal_gap 0.5)
			(thermal_bridge_width 0.5)
			(island_removal_mode 0)
		)
		(polygon
			(pts
				(arc
					(start 83.000088 -109.009942)
					(mid 80.460088 -111.549942)
					(end 83.000088 -114.089942)
				)
				(arc
					(start 83.000088 -114.089942)
					(mid 85.540088 -111.549942)
					(end 83.000088 -109.009942)
				)
			)
		)
	)
	(zone
		(net "PVCCIO_CPU1")
		(layer "B.Cu")
		(hatch none 0.5)
		(connect_pads
			(clearance 0.5)
		)
		(min_thickness 0.25)
		(fill yes
			(thermal_gap 0.5)
			(thermal_bridge_width 0.5)
			(island_removal_mode 0)
		)
		(polygon
			(pts
				(xy 139.7 -72.009) (xy 139.7 -70.866) (xy 138.811 -69.977) (xy 138.811 -66.802) (xy 138.684 -66.675)
				(xy 135.128 -66.675) (xy 134.62 -66.167) (xy 134.0612 -66.167) (xy 133.477 -65.5828) (xy 133.2992 -65.5828)
				(xy 132.8166 -65.1002) (xy 132.3594 -65.1002) (xy 132.0292 -64.77) (xy 131.445 -64.77) (xy 130.7846 -65.4304)
				(xy 130.7846 -66.2686) (xy 131.572 -67.056) (xy 131.7752 -67.056) (xy 132.2578 -67.5386) (xy 132.6134 -67.5386)
				(xy 133.0452 -67.9704) (xy 133.5024 -67.9704) (xy 133.731 -68.199) (xy 133.731 -71.501) (xy 134.366 -72.136)
				(xy 139.573 -72.136)
			)
		)
	)
	(zone
		(layer "B.Cu")
		(hatch none 0.5)
		(connect_pads
			(clearance 0)
		)
		(min_thickness 0.25)
		(keepout
			(tracks allowed)
			(vias allowed)
			(pads allowed)
			(copperpour allowed)
			(footprints not_allowed)
		)
		(placement
			(enabled no)
			(sheetname "")
		)
		(fill
			(thermal_gap 0.5)
			(thermal_bridge_width 0.5)
			(island_removal_mode 0)
		)
		(polygon
			(pts
				(xy 187.520072 -9.71169) (xy 187.520072 -6.530594) (xy 328.520044 -6.530594) (xy 328.520044 -9.71169)
			)
		)
	)
	(zone
		(layer "B.Cu")
		(hatch none 0.5)
		(connect_pads
			(clearance 0)
		)
		(min_thickness 0.25)
		(keepout
			(tracks allowed)
			(vias allowed)
			(pads allowed)
			(copperpour allowed)
			(footprints not_allowed)
		)
		(placement
			(enabled no)
			(sheetname "")
		)
		(fill
			(thermal_gap 0.5)
			(thermal_bridge_width 0.5)
			(island_removal_mode 0)
		)
		(polygon
			(pts
				(arc
					(start 310.339994 -92.689934)
					(mid 310.632887 -93.397039)
					(end 311.339992 -93.689932)
				)
				(arc
					(start 316.959996 -93.689932)
					(mid 317.667101 -93.397039)
					(end 317.959994 -92.689934)
				)
				(arc
					(start 317.959994 -85.549994)
					(mid 317.667101 -84.842889)
					(end 316.959996 -84.549996)
				)
				(arc
					(start 311.339992 -84.549996)
					(mid 310.632887 -84.842889)
					(end 310.339994 -85.549994)
				)
			)
		)
	)
	(zone
		(net "GND")
		(layer "B.Cu")
		(hatch none 0.5)
		(connect_pads
			(clearance 0.5)
		)
		(min_thickness 0.25)
		(fill yes
			(thermal_gap 0.5)
			(thermal_bridge_width 0.5)
			(island_removal_mode 0)
		)
		(polygon
			(pts
				(xy 177.3682 -139.2555) (xy 179.705 -139.2555) (xy 180.1495 -138.811) (xy 180.1495 -137.795) (xy 180.1495 -137.0203)
				(xy 180.5686 -136.6012) (xy 182.118 -136.6012) (xy 182.2196 -136.7028) (xy 182.2196 -137.287) (xy 182.2831 -137.3505)
				(xy 182.626 -137.6934) (xy 184.1754 -137.6934) (xy 184.3024 -137.8204) (xy 184.3024 -139.3952) (xy 184.785 -139.8778)
				(xy 184.785 -141.2875) (xy 181.8005 -144.272) (xy 175.387 -144.272) (xy 175.2346 -144.1196) (xy 175.2346 -141.9479)
				(xy 175.2346 -141.3891)
			)
		)
	)
	(zone
		(net "P12V_STBY")
		(layer "B.Cu")
		(hatch none 0.5)
		(connect_pads
			(clearance 0.5)
		)
		(min_thickness 0.25)
		(fill yes
			(thermal_gap 0.5)
			(thermal_bridge_width 0.5)
			(island_removal_mode 0)
		)
		(polygon
			(pts
				(xy 440.6392 -65.7733) (xy 442.214 -65.7733) (xy 442.3537 -65.6336) (xy 442.3537 -65.151) (xy 442.4934 -65.0113)
				(xy 447.3829 -65.0113) (xy 447.421 -64.9732) (xy 447.421 -63.9318) (xy 447.3956 -63.9064) (xy 443.5094 -63.9064)
				(xy 443.23 -63.627) (xy 443.23 -62.5094) (xy 443.0776 -62.357) (xy 440.563 -62.357) (xy 440.309 -62.611)
				(xy 440.309 -65.4431)
			)
		)
	)
	(zone
		(net "GND")
		(layer "B.Cu")
		(hatch none 0.5)
		(connect_pads
			(clearance 0.5)
		)
		(min_thickness 0.25)
		(fill yes
			(thermal_gap 0.5)
			(thermal_bridge_width 0.5)
			(island_removal_mode 0)
		)
		(polygon
			(pts
				(xy 387.597396 -26.7208) (xy 387.556502 -26.761694) (xy 387.124702 -26.761694) (xy 386.997702 -26.634694)
				(xy 386.997702 -25.694894) (xy 387.124702 -25.567894) (xy 387.378702 -25.567894) (xy 387.531102 -25.415494)
				(xy 387.531102 -22.316694) (xy 388.089902 -21.757894) (xy 388.751826 -21.757894) (xy 388.851902 -21.85797)
				(xy 388.851902 -21.8694) (xy 389.359902 -21.3614) (xy 389.9408 -21.3614) (xy 390.017 -21.4376) (xy 390.017 -26.416)
				(xy 389.7122 -26.7208)
			)
		)
	)
	(zone
		(layer "B.Cu")
		(hatch none 0.5)
		(connect_pads
			(clearance 0)
		)
		(min_thickness 0.25)
		(keepout
			(tracks allowed)
			(vias allowed)
			(pads allowed)
			(copperpour allowed)
			(footprints allowed)
		)
		(placement
			(enabled no)
			(sheetname "")
		)
		(fill
			(thermal_gap 0.5)
			(thermal_bridge_width 0.5)
			(island_removal_mode 0)
		)
		(polygon
			(pts
				(xy 148.082 -91.821) (xy 148.082 -91.059) (xy 148.844 -91.059) (xy 148.844 -91.821)
			)
		)
	)
	(zone
		(layer "B.Cu")
		(hatch none 0.5)
		(connect_pads
			(clearance 0)
		)
		(min_thickness 0.25)
		(keepout
			(tracks allowed)
			(vias allowed)
			(pads allowed)
			(copperpour allowed)
			(footprints allowed)
		)
		(placement
			(enabled no)
			(sheetname "")
		)
		(fill
			(thermal_gap 0.5)
			(thermal_bridge_width 0.5)
			(island_removal_mode 0)
		)
		(polygon
			(pts
				(xy 152.273 -88.265) (xy 152.273 -87.503) (xy 153.035 -87.503) (xy 153.035 -88.265)
			)
		)
	)
	(zone
		(layer "B.Cu")
		(hatch none 0.5)
		(connect_pads
			(clearance 0)
		)
		(min_thickness 0.25)
		(keepout
			(tracks not_allowed)
			(vias allowed)
			(pads allowed)
			(copperpour not_allowed)
			(footprints allowed)
		)
		(placement
			(enabled no)
			(sheetname "")
		)
		(fill
			(thermal_gap 0.5)
			(thermal_bridge_width 0.5)
			(island_removal_mode 0)
		)
		(polygon
			(pts
				(xy 453.4662 -51.695858) (xy 452.9582 -51.695858) (xy 452.9582 -52.076858) (xy 453.4662 -52.076858)
			)
		)
	)
	(zone
		(net "P5V_VGA_D")
		(layer "B.Cu")
		(hatch none 0.5)
		(connect_pads
			(clearance 0.5)
		)
		(min_thickness 0.25)
		(fill yes
			(thermal_gap 0.5)
			(thermal_bridge_width 0.5)
			(island_removal_mode 0)
		)
		(polygon
			(pts
				(xy 483.905306 -52.970684) (xy 483.905306 -54.713632) (xy 483.976426 -54.784752) (xy 484.824024 -54.784752)
				(xy 485.840532 -53.768244) (xy 486.932732 -53.768244) (xy 487.02849 -53.67274) (xy 487.02849 -52.390548)
				(xy 485.41178 -50.774092) (xy 485.265984 -50.628296) (xy 484.153718 -50.628296) (xy 484.007922 -50.774092)
				(xy 483.905306 -50.876708) (xy 483.905306 -52.5526)
			)
		)
	)
	(zone
		(net "P3V3_STBY")
		(layer "B.Cu")
		(hatch none 0.5)
		(connect_pads
			(clearance 0.5)
		)
		(min_thickness 0.25)
		(fill yes
			(thermal_gap 0.5)
			(thermal_bridge_width 0.5)
			(island_removal_mode 0)
		)
		(polygon
			(pts
				(xy 405.948388 -92.855288) (xy 405.614632 -93.189044) (xy 405.614632 -94.41307) (xy 406.082754 -94.881192)
				(xy 407.070052 -94.881192) (xy 407.103326 -94.847918) (xy 407.103326 -92.910152) (xy 407.048462 -92.855288)
			)
		)
		(polygon
			(pts
				(xy 406.3111 -93.560392) (xy 406.1079 -93.560392) (xy 406.1079 -93.763592) (xy 406.3111 -93.763592)
			)
		)
		(polygon
			(pts
				(xy 406.3111 -93.992192) (xy 406.1079 -93.992192) (xy 406.1079 -94.195392) (xy 406.3111 -94.195392)
			)
		)
	)
	(zone
		(layer "B.Cu")
		(hatch none 0.5)
		(connect_pads
			(clearance 0)
		)
		(min_thickness 0.25)
		(keepout
			(tracks allowed)
			(vias allowed)
			(pads allowed)
			(copperpour allowed)
			(footprints not_allowed)
		)
		(placement
			(enabled no)
			(sheetname "")
		)
		(fill
			(thermal_gap 0.5)
			(thermal_bridge_width 0.5)
			(island_removal_mode 0)
		)
		(polygon
			(pts
				(arc
					(start 409.719526 -79.1337)
					(mid 411.969458 -76.883768)
					(end 409.719526 -74.633836)
				)
				(arc
					(start 409.719526 -74.633836)
					(mid 407.469594 -76.883768)
					(end 409.719526 -79.1337)
				)
			)
		)
	)
	(zone
		(layer "B.Cu")
		(hatch none 0.5)
		(connect_pads
			(clearance 0)
		)
		(min_thickness 0.25)
		(keepout
			(tracks allowed)
			(vias allowed)
			(pads allowed)
			(copperpour allowed)
			(footprints not_allowed)
		)
		(placement
			(enabled no)
			(sheetname "")
		)
		(fill
			(thermal_gap 0.5)
			(thermal_bridge_width 0.5)
			(island_removal_mode 0)
		)
		(polygon
			(pts
				(arc
					(start -0.94996 -54.909974)
					(mid -1.999996 -53.859938)
					(end -3.050032 -54.909974)
				)
				(arc
					(start -3.050032 -54.909974)
					(mid -1.999996 -55.96001)
					(end -0.94996 -54.909974)
				)
			)
		)
	)
	(zone
		(layer "B.Cu")
		(hatch none 0.5)
		(connect_pads
			(clearance 0)
		)
		(min_thickness 0.25)
		(keepout
			(tracks allowed)
			(vias allowed)
			(pads allowed)
			(copperpour allowed)
			(footprints not_allowed)
		)
		(placement
			(enabled no)
			(sheetname "")
		)
		(fill
			(thermal_gap 0.5)
			(thermal_bridge_width 0.5)
			(island_removal_mode 0)
		)
		(polygon
			(pts
				(arc
					(start 127.901954 -119.800116)
					(mid 131.519222 -125.508518)
					(end 135.136128 -119.800116)
				)
			)
		)
	)
	(zone
		(net "GND")
		(layer "B.Cu")
		(hatch none 0.5)
		(connect_pads
			(clearance 0.5)
		)
		(min_thickness 0.25)
		(fill yes
			(thermal_gap 0.5)
			(thermal_bridge_width 0.5)
			(island_removal_mode 0)
		)
		(polygon
			(pts
				(xy 94.96552 -19.90217) (xy 95.325184 -19.90217) (xy 96.770444 -18.457164) (xy 96.770444 -16.80972)
				(xy 96.147128 -16.80972) (xy 96.127824 -16.829024) (xy 95.736156 -16.829024) (xy 95.51416 -17.05102)
				(xy 95.51416 -18.443194) (xy 95.047816 -18.443194) (xy 94.821756 -18.669254) (xy 94.821756 -19.758406)
			)
		)
	)
	(zone
		(layer "B.Cu")
		(hatch none 0.5)
		(connect_pads
			(clearance 0)
		)
		(min_thickness 0.25)
		(keepout
			(tracks allowed)
			(vias allowed)
			(pads allowed)
			(copperpour allowed)
			(footprints allowed)
		)
		(placement
			(enabled no)
			(sheetname "")
		)
		(fill
			(thermal_gap 0.5)
			(thermal_bridge_width 0.5)
			(island_removal_mode 0)
		)
		(polygon
			(pts
				(xy 319.72885 -123.160282) (xy 319.72885 -120.591834) (xy 321.892676 -120.591834) (xy 321.892676 -123.160282)
			)
		)
	)
	(zone
		(net "GND")
		(layer "B.Cu")
		(hatch none 0.5)
		(connect_pads
			(clearance 0.5)
		)
		(min_thickness 0.25)
		(fill yes
			(thermal_gap 0.5)
			(thermal_bridge_width 0.5)
			(island_removal_mode 0)
		)
		(polygon
			(pts
				(xy 8.75792 -155.92298) (xy 12.18692 -155.92298) (xy 12.29614 -155.81376) (xy 12.29614 -135.89)
				(xy 11.66622 -135.26008) (xy 7.91972 -135.26008) (xy 7.263892 -134.604252) (xy 7.00024 -134.3406)
				(xy 4.1402 -134.3406) (xy 4.0132 -134.3406) (xy 3.753104 -134.080504) (xy 2.681986 -134.080504)
				(xy 2.619248 -134.143242) (xy 2.619248 -142.446248) (xy 2.619248 -142.637764) (xy 2.287524 -142.969488)
				(xy 2.287524 -143.693134) (xy 2.54 -143.94561) (xy 2.54 -144.526) (xy 2.54 -145.8976) (xy 2.5654 -145.923)
				(xy 2.5654 -150.5712) (xy 2.667 -150.6728) (xy 3.2004 -150.6728) (xy 5.5372 -150.6728) (xy 8.21436 -153.34996)
				(xy 8.21436 -155.37942)
			)
		)
	)
	(zone
		(layer "B.Cu")
		(hatch none 0.5)
		(connect_pads
			(clearance 0)
		)
		(min_thickness 0.25)
		(keepout
			(tracks not_allowed)
			(vias allowed)
			(pads allowed)
			(copperpour not_allowed)
			(footprints allowed)
		)
		(placement
			(enabled no)
			(sheetname "")
		)
		(fill
			(thermal_gap 0.5)
			(thermal_bridge_width 0.5)
			(island_removal_mode 0)
		)
		(polygon
			(pts
				(arc
					(start 358.92867 0.055372)
					(mid 358.338274 0.385429)
					(end 357.671624 0.499872)
				)
				(arc
					(start 357.000048 0.499872)
					(mid 355.499924 1.999996)
					(end 357.000048 3.499866)
				)
				(arc
					(start 357.671624 3.499866)
					(mid 358.338295 3.61425)
					(end 358.92867 3.944366)
				)
				(arc
					(start 358.92867 3.944366)
					(mid 363.000204 2.000076)
					(end 358.92867 0.055372)
				)
			)
		)
	)
	(zone
		(net "P1V05_PCH_STBY")
		(layer "B.Cu")
		(hatch none 0.5)
		(connect_pads
			(clearance 0.5)
		)
		(min_thickness 0.25)
		(fill yes
			(thermal_gap 0.5)
			(thermal_bridge_width 0.5)
			(island_removal_mode 0)
		)
		(polygon
			(pts
				(xy 409.753816 -121.718324) (xy 409.753816 -121.722134) (xy 409.517596 -121.958354) (xy 408.922474 -121.958354)
				(xy 408.724608 -121.760488) (xy 408.724608 -121.679208) (xy 408.5844 -121.539) (xy 407.67 -121.539)
				(xy 407.6319 -121.5771) (xy 407.6319 -122.4661) (xy 407.850848 -122.685048) (xy 411.040326 -122.685048)
				(xy 411.22219 -122.503184) (xy 412.669736 -122.503184) (xy 413.04972 -122.1232) (xy 413.2834 -122.1232)
				(xy 414.2994 -122.1232) (xy 414.4264 -121.9962) (xy 414.4264 -120.8532) (xy 414.254696 -120.681496)
				(xy 412.820104 -120.681496) (xy 412.3182 -121.1834) (xy 410.28874 -121.1834)
			)
		)
	)
	(zone
		(layer "B.Cu")
		(hatch none 0.5)
		(connect_pads
			(clearance 0)
		)
		(min_thickness 0.25)
		(keepout
			(tracks allowed)
			(vias allowed)
			(pads allowed)
			(copperpour allowed)
			(footprints not_allowed)
		)
		(placement
			(enabled no)
			(sheetname "")
		)
		(fill
			(thermal_gap 0.5)
			(thermal_bridge_width 0.5)
			(island_removal_mode 0)
		)
		(polygon
			(pts
				(arc
					(start 135.136128 -33.299908)
					(mid 131.519222 -27.591736)
					(end 127.901954 -33.299908)
				)
			)
		)
	)
	(zone
		(net "PVCCIO_CPU0")
		(layer "B.Cu")
		(hatch none 0.5)
		(connect_pads
			(clearance 0.5)
		)
		(min_thickness 0.25)
		(fill yes
			(thermal_gap 0.5)
			(thermal_bridge_width 0.5)
			(island_removal_mode 0)
		)
		(polygon
			(pts
				(xy 279.692862 -76.922884) (xy 279.613106 -77.00264) (xy 279.613106 -78.166468) (xy 279.527 -78.252574)
				(xy 279.527 -78.6384) (xy 279.960832 -79.072232) (xy 279.960832 -80.465168) (xy 280.100024 -80.604614)
				(xy 281.370024 -80.604614) (xy 281.370024 -79.715614) (xy 281.116024 -79.715614) (xy 280.600404 -79.199994)
				(xy 280.608024 -79.192628) (xy 280.608024 -78.318614) (xy 280.746962 -78.179676) (xy 280.746962 -76.93279)
				(xy 280.737056 -76.922884)
			)
		)
		(polygon
			(pts
				(xy 280.074624 -77.709014) (xy 279.871424 -77.709014) (xy 279.871424 -77.912214) (xy 280.074624 -77.912214)
			)
		)
	)
	(zone
		(layer "B.Cu")
		(hatch none 0.5)
		(connect_pads
			(clearance 0)
		)
		(min_thickness 0.25)
		(keepout
			(tracks not_allowed)
			(vias allowed)
			(pads allowed)
			(copperpour not_allowed)
			(footprints allowed)
		)
		(placement
			(enabled no)
			(sheetname "")
		)
		(fill
			(thermal_gap 0.5)
			(thermal_bridge_width 0.5)
			(island_removal_mode 0)
		)
		(polygon
			(pts
				(arc
					(start 380.34214 -26.097484)
					(mid 380.65964 -25.779984)
					(end 380.97714 -26.097484)
				)
				(xy 381.04318 -26.097484) (xy 381.05461 -25.284176) (xy 381.05461 -25.281128)
				(arc
					(start 380.93777 -25.281128)
					(mid 380.67107 -25.5453)
					(end 380.40437 -25.281128)
				)
				(arc
					(start 380.40437 -25.278588)
					(mid 380.67107 -25.011888)
					(end 380.93777 -25.278588)
				)
				(arc
					(start 381.05461 -25.278588)
					(mid 380.673737 -24.895057)
					(end 380.28753 -25.273254)
				)
				(arc
					(start 380.2761 -26.09215)
					(mid 380.654306 -26.481024)
					(end 381.04318 -26.102818)
				)
				(xy 381.04318 -26.100024)
				(arc
					(start 380.97714 -26.100024)
					(mid 380.65964 -26.414994)
					(end 380.34214 -26.100024)
				)
			)
		)
	)
	(zone
		(layer "B.Cu")
		(hatch none 0.5)
		(connect_pads
			(clearance 0)
		)
		(min_thickness 0.25)
		(keepout
			(tracks allowed)
			(vias allowed)
			(pads allowed)
			(copperpour allowed)
			(footprints not_allowed)
		)
		(placement
			(enabled no)
			(sheetname "")
		)
		(fill
			(thermal_gap 0.5)
			(thermal_bridge_width 0.5)
			(island_removal_mode 0)
		)
		(polygon
			(pts
				(arc
					(start 57.040018 -67.55003)
					(mid 57.332911 -68.257135)
					(end 58.040016 -68.550028)
				)
				(arc
					(start 63.66002 -68.550028)
					(mid 64.367125 -68.257135)
					(end 64.660018 -67.55003)
				)
				(arc
					(start 64.660018 -60.41009)
					(mid 64.367125 -59.702985)
					(end 63.66002 -59.410092)
				)
				(arc
					(start 58.040016 -59.410092)
					(mid 57.332911 -59.702985)
					(end 57.040018 -60.41009)
				)
			)
		)
	)
	(zone
		(layer "B.Cu")
		(hatch none 0.5)
		(connect_pads
			(clearance 0)
		)
		(min_thickness 0.25)
		(keepout
			(tracks allowed)
			(vias allowed)
			(pads allowed)
			(copperpour allowed)
			(footprints allowed)
		)
		(placement
			(enabled no)
			(sheetname "")
		)
		(fill
			(thermal_gap 0.5)
			(thermal_bridge_width 0.5)
			(island_removal_mode 0)
		)
		(polygon
			(pts
				(xy 489.446316 -56.782462) (xy 489.446316 -55.033164) (xy 492.425228 -55.033164) (xy 492.425228 -56.782462)
			)
		)
	)
	(zone
		(net "GND")
		(layer "B.Cu")
		(hatch none 0.5)
		(connect_pads
			(clearance 0.5)
		)
		(min_thickness 0.25)
		(fill yes
			(thermal_gap 0.5)
			(thermal_bridge_width 0.5)
			(island_removal_mode 0)
		)
		(polygon
			(pts
				(xy -5.4864 -50.0634) (xy -5.4864 -59.1566) (xy -5.4864 -86.7156) (xy -4.8768 -87.3252) (xy 1.3462 -87.3252)
				(xy 2.247646 -86.423754) (xy 2.247646 -69.049646) (xy 1.778 -68.58) (xy 1.6002 -68.4022) (xy 1.2446 -68.0466)
				(xy 1.2446 -62.6618) (xy 1.6002 -62.3062) (xy 1.6002 -60.3758) (xy 1.778 -60.198) (xy 1.778 -58.4454)
				(xy 1.778 -58.3438) (xy 1.778 -51.745388) (xy 1.4224 -51.389788) (xy 1.4224 -50.945542) (xy 1.4224 -50.419)
				(xy 1.4224 -49.8094) (xy 1.4224 -49.112424) (xy 1.868424 -48.6664) (xy 2.5654 -48.6664) (xy 12.4206 -48.6664)
				(xy 13.5636 -47.5234) (xy 13.5636 -43.688) (xy 13.2842 -43.4086) (xy -4.9022 -43.4086) (xy -5.4864 -43.9928)
			)
		)
	)
	(zone
		(layer "B.Cu")
		(hatch none 0.5)
		(connect_pads
			(clearance 0)
		)
		(min_thickness 0.25)
		(keepout
			(tracks allowed)
			(vias allowed)
			(pads allowed)
			(copperpour allowed)
			(footprints not_allowed)
		)
		(placement
			(enabled no)
			(sheetname "")
		)
		(fill
			(thermal_gap 0.5)
			(thermal_bridge_width 0.5)
			(island_removal_mode 0)
		)
		(polygon
			(pts
				(arc
					(start 3.50012 -159.100012)
					(mid 7.500112 -155.10002)
					(end 3.50012 -151.100028)
				)
				(arc
					(start 0 -151.100028)
					(mid -3.999992 -155.10002)
					(end 0 -159.100012)
				)
			)
		)
	)
	(zone
		(layer "B.Cu")
		(hatch none 0.5)
		(connect_pads
			(clearance 0)
		)
		(min_thickness 0.25)
		(keepout
			(tracks allowed)
			(vias allowed)
			(pads allowed)
			(copperpour allowed)
			(footprints not_allowed)
		)
		(placement
			(enabled no)
			(sheetname "")
		)
		(fill
			(thermal_gap 0.5)
			(thermal_bridge_width 0.5)
			(island_removal_mode 0)
		)
		(polygon
			(pts
				(arc
					(start 248.000012 -113.450116)
					(mid 249.899932 -111.550196)
					(end 248.000012 -109.650022)
				)
				(arc
					(start 248.000012 -109.650022)
					(mid 246.099838 -111.550196)
					(end 248.000012 -113.450116)
				)
			)
		)
	)
	(zone
		(net "PVCCIO_CPU1")
		(layer "B.Cu")
		(hatch none 0.5)
		(connect_pads
			(clearance 0.5)
		)
		(min_thickness 0.25)
		(fill yes
			(thermal_gap 0.5)
			(thermal_bridge_width 0.5)
			(island_removal_mode 0)
		)
		(polygon
			(pts
				(xy 165.4048 -52.828444) (xy 162.121088 -52.828444) (xy 161.456624 -53.492908) (xy 161.456624 -59.814968)
				(xy 161.456624 -62.650624) (xy 161.5694 -62.7634) (xy 166.0652 -62.7634) (xy 166.3446 -62.484) (xy 166.53764 -62.290706)
				(xy 166.53764 -53.207666) (xy 166.158418 -52.828444)
			)
		)
	)
	(zone
		(net "GND")
		(layer "B.Cu")
		(hatch none 0.5)
		(connect_pads
			(clearance 0.5)
		)
		(min_thickness 0.25)
		(fill yes
			(thermal_gap 0.5)
			(thermal_bridge_width 0.5)
			(island_removal_mode 0)
		)
		(polygon
			(pts
				(xy 388.7978 -114.5032) (xy 388.9756 -114.5032) (xy 388.976108 -114.503708) (xy 389.108188 -114.503708)
				(xy 389.194548 -114.590068) (xy 389.194548 -114.801396) (xy 389.241792 -114.84864) (xy 389.436102 -114.84864)
				(xy 389.474964 -114.809778) (xy 389.474964 -114.715036) (xy 389.474964 -114.594894) (xy 389.541258 -114.5286)
				(xy 389.585454 -114.484404) (xy 390.57453 -114.484404) (xy 390.796526 -114.7064) (xy 390.796526 -114.811302)
				(xy 390.835388 -114.850164) (xy 391.030714 -114.850164) (xy 391.074656 -114.806222) (xy 391.074656 -114.690144)
				(xy 391.2362 -114.5286) (xy 391.414 -114.5286) (xy 391.4902 -114.6048) (xy 391.4902 -115.0366) (xy 391.387838 -115.138962)
				(xy 391.204196 -115.138962) (xy 391.027158 -115.316) (xy 388.813802 -115.316) (xy 388.643876 -115.146074)
				(xy 388.309104 -115.146074) (xy 388.250938 -115.146074) (xy 388.17042 -115.065556) (xy 388.17042 -114.80038)
				(xy 388.170928 -114.799872) (xy 388.170928 -114.645948) (xy 388.313676 -114.5032)
			)
		)
	)
	(zone
		(layer "B.Cu")
		(hatch none 0.5)
		(connect_pads
			(clearance 0)
		)
		(min_thickness 0.25)
		(keepout
			(tracks allowed)
			(vias allowed)
			(pads allowed)
			(copperpour allowed)
			(footprints not_allowed)
		)
		(placement
			(enabled no)
			(sheetname "")
		)
		(fill
			(thermal_gap 0.5)
			(thermal_bridge_width 0.5)
			(island_removal_mode 0)
		)
		(polygon
			(pts
				(xy 171.309792 -159.100012)
				(arc
					(start 171.309792 -159.040068)
					(mid 168.0078 -154.848426)
					(end 171.809918 -151.1046)
				)
				(xy 171.809918 -127.364998) (xy 165.159944 -127.364998) (xy 165.159944 -159.100012)
			)
		)
	)
	(zone
		(layer "B.Cu")
		(hatch none 0.5)
		(connect_pads
			(clearance 0)
		)
		(min_thickness 0.25)
		(keepout
			(tracks allowed)
			(vias allowed)
			(pads allowed)
			(copperpour allowed)
			(footprints allowed)
		)
		(placement
			(enabled no)
			(sheetname "")
		)
		(fill
			(thermal_gap 0.5)
			(thermal_bridge_width 0.5)
			(island_removal_mode 0)
		)
		(polygon
			(pts
				(xy 344.9574 -84.8868) (xy 344.9574 -83.6168) (xy 346.6592 -83.6168) (xy 347.8022 -83.6168) (xy 348.488 -84.3026)
				(xy 348.488 -85.2932) (xy 348.3356 -85.4456) (xy 345.0336 -85.4456) (xy 344.9574 -85.3694)
			)
		)
	)
	(zone
		(net "P5V_STBY")
		(layer "B.Cu")
		(hatch none 0.5)
		(connect_pads
			(clearance 0.5)
		)
		(min_thickness 0.25)
		(fill yes
			(thermal_gap 0.5)
			(thermal_bridge_width 0.5)
			(island_removal_mode 0)
		)
		(polygon
			(pts
				(xy 466.1662 -124.1298) (xy 467.6902 -124.1298) (xy 467.868 -123.952) (xy 467.868 -122.8344) (xy 467.7029 -122.6693)
				(xy 466.1281 -122.6693) (xy 466.0392 -122.7582) (xy 466.0392 -124.0028)
			)
		)
	)
	(zone
		(layer "B.Cu")
		(hatch none 0.5)
		(connect_pads
			(clearance 0)
		)
		(min_thickness 0.25)
		(keepout
			(tracks not_allowed)
			(vias allowed)
			(pads allowed)
			(copperpour not_allowed)
			(footprints allowed)
		)
		(placement
			(enabled no)
			(sheetname "")
		)
		(fill
			(thermal_gap 0.5)
			(thermal_bridge_width 0.5)
			(island_removal_mode 0)
		)
		(polygon
			(pts
				(xy 462.64195 -123.80468) (xy 462.64195 -124.102876) (xy 462.486756 -124.25807)
				(arc
					(start 462.315052 -124.25807)
					(mid 461.791135 -124.18822)
					(end 462.315052 -124.11837)
				)
				(xy 462.428844 -124.11837) (xy 462.50225 -124.044964) (xy 462.50225 -123.80468)
				(arc
					(start 462.058004 -123.80468)
					(mid 461.67421 -124.188093)
					(end 462.05775 -124.57176)
				)
				(arc
					(start 463.32775 -124.57176)
					(mid 463.71129 -124.18822)
					(end 463.32775 -123.80468)
				)
				(xy 462.88325 -123.80468) (xy 462.88325 -124.044964) (xy 462.956656 -124.11837)
				(arc
					(start 463.070448 -124.11837)
					(mid 463.594365 -124.18822)
					(end 463.070448 -124.25807)
				)
				(xy 462.898744 -124.25807) (xy 462.74355 -124.102876) (xy 462.74355 -123.80468)
			)
		)
	)
	(zone
		(net "P1V05_PCH_STBY")
		(layer "B.Cu")
		(hatch none 0.5)
		(connect_pads
			(clearance 0.5)
		)
		(min_thickness 0.25)
		(fill yes
			(thermal_gap 0.5)
			(thermal_bridge_width 0.5)
			(island_removal_mode 0)
		)
		(polygon
			(pts
				(xy 376.138186 -134.655814) (xy 375.9708 -134.8232) (xy 375.9708 -135.579612) (xy 376.1994 -135.808212)
				(xy 377.176538 -135.808212) (xy 377.341384 -135.643366) (xy 378.340874 -135.643366) (xy 378.37872 -135.60552)
				(xy 378.37872 -134.749794) (xy 378.28474 -134.655814)
			)
		)
	)
	(zone
		(layer "B.Cu")
		(hatch none 0.5)
		(connect_pads
			(clearance 0)
		)
		(min_thickness 0.25)
		(keepout
			(tracks not_allowed)
			(vias allowed)
			(pads allowed)
			(copperpour not_allowed)
			(footprints allowed)
		)
		(placement
			(enabled no)
			(sheetname "")
		)
		(fill
			(thermal_gap 0.5)
			(thermal_bridge_width 0.5)
			(island_removal_mode 0)
		)
		(polygon
			(pts
				(arc
					(start 447.71437 -49.928272)
					(mid 448.238287 -49.998122)
					(end 447.71437 -50.067972)
				)
				(xy 447.618866 -50.067972) (xy 447.52006 -50.166778) (xy 447.52006 -50.381662)
				(arc
					(start 447.971418 -50.381662)
					(mid 448.355212 -49.998249)
					(end 447.971672 -49.614582)
				)
				(arc
					(start 446.701672 -49.614582)
					(mid 446.318132 -49.998122)
					(end 446.701672 -50.381662)
				)
				(xy 447.13906 -50.381662) (xy 447.13906 -50.141378) (xy 447.065654 -50.067972)
				(arc
					(start 446.958974 -50.067972)
					(mid 446.435057 -49.998122)
					(end 446.958974 -49.928272)
				)
				(xy 447.123566 -49.928272) (xy 447.27876 -50.083466) (xy 447.27876 -50.381662) (xy 447.38036 -50.381662)
				(xy 447.38036 -50.108866) (xy 447.560954 -49.928272)
			)
		)
	)
	(zone
		(layer "B.Cu")
		(hatch none 0.5)
		(connect_pads
			(clearance 0)
		)
		(min_thickness 0.25)
		(keepout
			(tracks allowed)
			(vias allowed)
			(pads allowed)
			(copperpour allowed)
			(footprints allowed)
		)
		(placement
			(enabled no)
			(sheetname "")
		)
		(fill
			(thermal_gap 0.5)
			(thermal_bridge_width 0.5)
			(island_removal_mode 0)
		)
		(polygon
			(pts
				(xy 370.967 -117.094) (xy 370.967 -115.824) (xy 372.6688 -115.824) (xy 372.6688 -117.094)
			)
		)
	)
	(zone
		(layer "B.Cu")
		(hatch none 0.5)
		(connect_pads
			(clearance 0)
		)
		(min_thickness 0.25)
		(keepout
			(tracks not_allowed)
			(vias allowed)
			(pads allowed)
			(copperpour not_allowed)
			(footprints allowed)
		)
		(placement
			(enabled no)
			(sheetname "")
		)
		(fill
			(thermal_gap 0.5)
			(thermal_bridge_width 0.5)
			(island_removal_mode 0)
		)
		(polygon
			(pts
				(arc
					(start 357.000048 -151.100028)
					(mid 353.000056 -155.10002)
					(end 357.000048 -159.100012)
				)
				(arc
					(start 360.499914 -159.100012)
					(mid 364.499906 -155.10002)
					(end 360.499914 -151.100028)
				)
			)
		)
	)
	(zone
		(net "GND")
		(layer "B.Cu")
		(hatch none 0.5)
		(connect_pads
			(clearance 0.5)
		)
		(min_thickness 0.25)
		(fill yes
			(thermal_gap 0.5)
			(thermal_bridge_width 0.5)
			(island_removal_mode 0)
		)
		(polygon
			(pts
				(xy 96.383094 -146.388074) (xy 96.383094 -144.503394) (xy 96.305624 -144.425924) (xy 95.859092 -144.425924)
				(xy 95.609156 -144.425924) (xy 95.57766 -144.45742) (xy 95.57766 -145.6944) (xy 95.43796 -145.8341)
				(xy 95.43796 -145.99793) (xy 95.43796 -146.812) (xy 95.5929 -146.96694) (xy 95.8977 -146.96694)
				(xy 96.1263 -146.96694) (xy 96.383094 -146.710146)
			)
		)
	)
	(zone
		(layer "B.Cu")
		(hatch none 0.5)
		(connect_pads
			(clearance 0)
		)
		(min_thickness 0.25)
		(keepout
			(tracks not_allowed)
			(vias allowed)
			(pads allowed)
			(copperpour not_allowed)
			(footprints allowed)
		)
		(placement
			(enabled no)
			(sheetname "")
		)
		(fill
			(thermal_gap 0.5)
			(thermal_bridge_width 0.5)
			(island_removal_mode 0)
		)
		(polygon
			(pts
				(arc
					(start 408.306016 -146.939)
					(mid 407.922476 -146.55546)
					(end 407.538936 -146.939)
				)
				(arc
					(start 407.538936 -147.954746)
					(mid 407.922349 -148.33854)
					(end 408.306016 -147.955)
				)
				(arc
					(start 408.306016 -147.648422)
					(mid 408.292402 -147.640307)
					(end 408.276806 -147.6375)
				)
				(arc
					(start 408.036776 -147.6375)
					(mid 408.005345 -147.650519)
					(end 407.992326 -147.68195)
				)
				(arc
					(start 407.992326 -147.697698)
					(mid 407.922476 -148.221615)
					(end 407.852626 -147.697698)
				)
				(xy 407.852626 -147.652994)
				(arc
					(start 407.85542 -147.6502)
					(mid 407.906588 -147.551762)
					(end 408.005026 -147.500594)
				)
				(xy 408.00782 -147.4978) (xy 408.305762 -147.4978) (xy 408.306016 -147.498054) (xy 408.306016 -147.395946)
				(xy 408.305762 -147.3962) (xy 408.00782 -147.3962)
				(arc
					(start 408.005026 -147.393406)
					(mid 407.906588 -147.342238)
					(end 407.85542 -147.2438)
				)
				(xy 407.852626 -147.241006)
				(arc
					(start 407.852626 -147.196302)
					(mid 407.922476 -146.672385)
					(end 407.992326 -147.196302)
				)
				(arc
					(start 407.992326 -147.21205)
					(mid 408.005345 -147.243481)
					(end 408.036776 -147.2565)
				)
				(arc
					(start 408.276806 -147.2565)
					(mid 408.292396 -147.253677)
					(end 408.306016 -147.245578)
				)
			)
		)
	)
	(zone
		(layer "B.Cu")
		(hatch none 0.5)
		(connect_pads
			(clearance 0)
		)
		(min_thickness 0.25)
		(keepout
			(tracks not_allowed)
			(vias allowed)
			(pads allowed)
			(copperpour not_allowed)
			(footprints allowed)
		)
		(placement
			(enabled no)
			(sheetname "")
		)
		(fill
			(thermal_gap 0.5)
			(thermal_bridge_width 0.5)
			(island_removal_mode 0)
		)
		(polygon
			(pts
				(arc
					(start 339.689186 -68.893182)
					(mid 339.269215 -69.214347)
					(end 339.59038 -68.794376)
				)
				(xy 339.742526 -68.64223)
				(arc
					(start 339.457792 -68.64223)
					(mid 339.074252 -69.02577)
					(end 339.457792 -69.40931)
				)
				(arc
					(start 340.422738 -69.40931)
					(mid 340.806532 -69.025897)
					(end 340.422992 -68.64223)
				)
				(xy 340.138258 -68.64223)
				(arc
					(start 340.290404 -68.794376)
					(mid 340.611569 -69.214347)
					(end 340.191598 -68.893182)
				)
				(xy 339.985604 -68.687188) (xy 339.985604 -68.64223) (xy 339.884004 -68.64223) (xy 339.884004 -68.698364)
			)
		)
	)
	(zone
		(net "PVDDQ_DEF")
		(layer "B.Cu")
		(hatch none 0.5)
		(connect_pads
			(clearance 0.5)
		)
		(min_thickness 0.25)
		(fill yes
			(thermal_gap 0.5)
			(thermal_bridge_width 0.5)
			(island_removal_mode 0)
		)
		(polygon
			(pts
				(xy 243.83365 -138.961114) (xy 243.735606 -139.059158) (xy 243.735606 -141.233652) (xy 243.866416 -141.364462)
				(xy 258.606798 -141.364462) (xy 258.784344 -141.186916) (xy 258.784344 -140.8938) (xy 258.911344 -140.7668)
				(xy 259.9944 -140.7668) (xy 260.1976 -140.5636) (xy 260.1976 -139.5476) (xy 260.096 -139.446) (xy 259.5626 -139.446)
				(xy 259.077714 -138.961114)
			)
		)
		(polygon
			(pts
				(xy 253.049532 -140.4874) (xy 252.846332 -140.4874) (xy 252.846332 -140.6906) (xy 253.049532 -140.6906)
			)
		)
		(polygon
			(pts
				(xy 252.7046 -140.4874) (xy 252.5014 -140.4874) (xy 252.5014 -140.6906) (xy 252.7046 -140.6906)
			)
		)
		(polygon
			(pts
				(xy 249.4026 -140.4874) (xy 249.1994 -140.4874) (xy 249.1994 -140.6906) (xy 249.4026 -140.6906)
			)
		)
		(polygon
			(pts
				(xy 258.7625 -140.462) (xy 258.5593 -140.462) (xy 258.5593 -140.6652) (xy 258.7625 -140.6652)
			)
		)
		(polygon
			(pts
				(xy 253.049532 -139.7254) (xy 252.846332 -139.7254) (xy 252.846332 -139.9286) (xy 253.049532 -139.9286)
			)
		)
		(polygon
			(pts
				(xy 252.7046 -139.7254) (xy 252.5014 -139.7254) (xy 252.5014 -139.9286) (xy 252.7046 -139.9286)
			)
		)
		(polygon
			(pts
				(xy 249.4026 -139.7254) (xy 249.1994 -139.7254) (xy 249.1994 -139.9286) (xy 249.4026 -139.9286)
			)
		)
		(polygon
			(pts
				(xy 258.7625 -139.7) (xy 258.5593 -139.7) (xy 258.5593 -139.9032) (xy 258.7625 -139.9032)
			)
		)
	)
	(zone
		(layer "B.Cu")
		(hatch none 0.5)
		(connect_pads
			(clearance 0)
		)
		(min_thickness 0.25)
		(keepout
			(tracks not_allowed)
			(vias allowed)
			(pads allowed)
			(copperpour not_allowed)
			(footprints allowed)
		)
		(placement
			(enabled no)
			(sheetname "")
		)
		(fill
			(thermal_gap 0.5)
			(thermal_bridge_width 0.5)
			(island_removal_mode 0)
		)
		(polygon
			(pts
				(xy 469.015826 -21.288756) (xy 469.291162 -21.288756) (xy 470.83218 -19.747738) (xy 470.83218 -18.782792)
				(xy 471.62466 -17.990312) (xy 473.335858 -17.990312) (xy 473.517722 -17.808448) (xy 473.517722 -17.425416)
				(xy 473.320364 -17.228058) (xy 471.309192 -17.228058) (xy 470.070434 -18.466816) (xy 470.070434 -19.431762)
				(xy 468.751412 -20.750784) (xy 468.751412 -21.024342)
			)
		)
	)
	(zone
		(net "GND")
		(layer "B.Cu")
		(hatch none 0.5)
		(connect_pads
			(clearance 0.5)
		)
		(min_thickness 0.25)
		(fill yes
			(thermal_gap 0.5)
			(thermal_bridge_width 0.5)
			(island_removal_mode 0)
		)
		(polygon
			(pts
				(xy 169.875962 -145.339562) (xy 169.772838 -145.44294) (xy 169.772838 -146.997928) (xy 169.899838 -147.124928)
				(xy 171.423838 -147.124928) (xy 171.550838 -146.997928) (xy 171.550838 -145.541238) (xy 171.349162 -145.339562)
			)
		)
		(polygon
			(pts
				(xy 170.870626 -146.230848) (xy 170.667426 -146.230848) (xy 170.667426 -146.434048) (xy 170.870626 -146.434048)
			)
		)
	)
	(zone
		(net "GND")
		(layer "B.Cu")
		(hatch none 0.5)
		(connect_pads
			(clearance 0.5)
		)
		(min_thickness 0.25)
		(fill yes
			(thermal_gap 0.5)
			(thermal_bridge_width 0.5)
			(island_removal_mode 0)
		)
		(polygon
			(pts
				(xy 243.0272 -125.0442) (xy 242.1382 -125.9332) (xy 242.1382 -126.4412) (xy 242.8748 -127.1778)
				(xy 242.8748 -127.6858) (xy 242.8494 -127.7112) (xy 242.8494 -130.4036) (xy 243.0272 -130.5814)
				(xy 243.4336 -130.5814) (xy 243.6114 -130.4036) (xy 243.6114 -129.921) (xy 243.3828 -129.6924) (xy 243.3828 -126.873)
				(xy 243.6114 -126.6444) (xy 243.6114 -125.1204) (xy 243.5352 -125.0442)
			)
		)
	)
	(zone
		(layer "B.Cu")
		(hatch none 0.5)
		(connect_pads
			(clearance 0)
		)
		(min_thickness 0.25)
		(keepout
			(tracks not_allowed)
			(vias allowed)
			(pads allowed)
			(copperpour not_allowed)
			(footprints allowed)
		)
		(placement
			(enabled no)
			(sheetname "")
		)
		(fill
			(thermal_gap 0.5)
			(thermal_bridge_width 0.5)
			(island_removal_mode 0)
		)
		(polygon
			(pts
				(arc
					(start 83.000088 -44.090082)
					(mid 85.540088 -41.550082)
					(end 83.000088 -39.010082)
				)
				(arc
					(start 83.000088 -39.010082)
					(mid 80.460088 -41.550082)
					(end 83.000088 -44.090082)
				)
			)
		)
	)
	(zone
		(net "VR_FET_SW_P12V_STBY_PVCCIN_CPU0")
		(layer "B.Cu")
		(hatch none 0.5)
		(connect_pads
			(clearance 0.5)
		)
		(min_thickness 0.25)
		(fill yes
			(thermal_gap 0.5)
			(thermal_bridge_width 0.5)
			(island_removal_mode 0)
		)
		(polygon
			(pts
				(xy 198.2216 -101.24694) (xy 198.2216 -95.1992) (xy 198.3486 -95.0722) (xy 198.3486 -56.106822)
				(xy 196.902578 -56.106822) (xy 196.596 -56.4134) (xy 194.4624 -56.4134) (xy 193.7004 -57.1754) (xy 193.7004 -57.9882)
				(xy 193.7004 -58.2676) (xy 192.500504 -59.467496) (xy 192.500504 -60.94476) (xy 191.4906 -61.954664)
				(xy 191.4906 -77.7748) (xy 187.5282 -81.7372) (xy 187.5282 -97.88271) (xy 188.4045 -98.75901) (xy 188.4045 -100.884228)
				(xy 188.68263 -101.162358) (xy 190.087758 -101.162358) (xy 194.715638 -101.162358) (xy 194.92468 -101.3714)
				(xy 198.09714 -101.3714)
			)
		)
		(polygon
			(pts
				(xy 196.230748 -79.530956)
				(arc
					(start 196.557138 -79.530956)
					(mid 196.759731 -79.421784)
					(end 196.9897 -79.4131)
				)
				(arc
					(start 196.9897 -79.4131)
					(mid 197.046848 -79.380248)
					(end 197.023228 -79.318612)
				)
				(xy 196.998082 -79.30388) (xy 196.98589 -79.29626) (xy 196.85762 -79.29626) (xy 196.85762 -79.168244)
				(arc
					(start 196.850254 -79.156052)
					(mid 196.799038 -79.04033)
					(end 196.78142 -78.915006)
				)
				(arc
					(start 196.78142 -78.841854)
					(mid 196.751121 -78.769729)
					(end 196.67855 -78.740508)
				)
				(arc
					(start 196.67855 -78.740508)
					(mid 196.637288 -78.739389)
					(end 196.596254 -78.73492)
				)
				(arc
					(start 196.596254 -78.73492)
					(mid 196.511277 -78.761527)
					(end 196.479922 -78.844902)
				)
				(arc
					(start 196.479922 -78.844902)
					(mid 196.128118 -79.367517)
					(end 195.547488 -79.123032)
				)
				(arc
					(start 195.547488 -79.123032)
					(mid 195.500909 -79.095524)
					(end 195.456048 -79.125572)
				)
				(arc
					(start 195.443094 -79.15275)
					(mid 195.560005 -79.460534)
					(end 195.507102 -79.785464)
				)
				(arc
					(start 195.507102 -79.785464)
					(mid 195.510814 -79.833919)
					(end 195.553584 -79.857092)
				)
				(xy 195.555108 -79.857092) (xy 195.555108 -79.984092) (xy 195.681092 -79.984092) (xy 195.681092 -79.857092)
				(xy 195.904612 -79.857092)
			)
		)
		(polygon
			(pts
				(xy 196.433948 -87.658956) (xy 196.55663 -87.658956)
				(arc
					(start 196.5706 -87.647526)
					(mid 196.768276 -87.547557)
					(end 196.9897 -87.5411)
				)
				(arc
					(start 196.9897 -87.5411)
					(mid 197.046848 -87.508248)
					(end 197.023228 -87.446612)
				)
				(xy 196.998082 -87.43188) (xy 196.98589 -87.42426) (xy 196.85762 -87.42426) (xy 196.85762 -87.296244)
				(arc
					(start 196.850254 -87.284052)
					(mid 196.799038 -87.16833)
					(end 196.78142 -87.043006)
				)
				(arc
					(start 196.78142 -86.96579)
					(mid 196.751931 -86.894218)
					(end 196.680582 -86.86419)
				)
				(arc
					(start 196.680582 -86.86419)
					(mid 196.650677 -86.86304)
					(end 196.620892 -86.860126)
				)
				(arc
					(start 196.620892 -86.860126)
					(mid 196.538799 -86.886706)
					(end 196.506846 -86.966806)
				)
				(arc
					(start 196.506846 -86.966806)
					(mid 196.238863 -87.436074)
					(end 195.701158 -87.381842)
				)
				(arc
					(start 195.701158 -87.381842)
					(mid 195.624735 -87.360118)
					(end 195.556124 -87.40013)
				)
				(arc
					(start 195.525898 -87.437722)
					(mid 195.562652 -87.679637)
					(end 195.505324 -87.917528)
				)
				(arc
					(start 195.505324 -87.917528)
					(mid 195.512241 -88.014546)
					(end 195.597526 -88.061292)
				)
				(xy 195.682108 -88.061292) (xy 195.682108 -88.188292) (xy 195.808092 -88.188292) (xy 195.808092 -88.061292)
				(xy 196.031612 -88.061292)
			)
		)
		(polygon
			(pts
				(xy 196.357748 -95.786956)
				(arc
					(start 196.544438 -95.786956)
					(mid 196.747031 -95.677784)
					(end 196.977 -95.6691)
				)
				(arc
					(start 196.977 -95.6691)
					(mid 197.034148 -95.636248)
					(end 197.010528 -95.574612)
				)
				(xy 196.985382 -95.55988) (xy 196.97319 -95.55226) (xy 196.84492 -95.55226) (xy 196.84492 -95.424244)
				(arc
					(start 196.837554 -95.412052)
					(mid 196.786338 -95.29633)
					(end 196.76872 -95.171006)
				)
				(arc
					(start 196.76872 -95.055436)
					(mid 196.754287 -95.019967)
					(end 196.71919 -95.004636)
				)
				(arc
					(start 196.71919 -95.004636)
					(mid 196.641295 -94.996856)
					(end 196.56552 -94.977204)
				)
				(arc
					(start 196.56552 -94.977204)
					(mid 196.471885 -94.991764)
					(end 196.4309 -95.07728)
				)
				(arc
					(start 196.4309 -95.07728)
					(mid 196.190426 -95.522804)
					(end 195.68414 -95.524828)
				)
				(arc
					(start 195.68414 -95.524828)
					(mid 195.572584 -95.530716)
					(end 195.533772 -95.635572)
				)
				(arc
					(start 195.533772 -95.635572)
					(mid 195.547374 -95.843985)
					(end 195.492624 -96.045528)
				)
				(arc
					(start 195.492624 -96.045528)
					(mid 195.499541 -96.142546)
					(end 195.584826 -96.189292)
				)
				(xy 195.605908 -96.189292) (xy 195.605908 -96.316292) (xy 195.731892 -96.316292) (xy 195.731892 -96.189292)
				(xy 195.955412 -96.189292)
			)
		)
		(polygon
			(pts
				(xy 196.357748 -63.274956)
				(arc
					(start 196.557138 -63.274956)
					(mid 196.759731 -63.165784)
					(end 196.9897 -63.1571)
				)
				(arc
					(start 196.9897 -63.1571)
					(mid 197.046848 -63.124248)
					(end 197.023228 -63.062612)
				)
				(xy 196.998082 -63.04788) (xy 196.98589 -63.04026) (xy 196.85762 -63.04026) (xy 196.85762 -62.912244)
				(arc
					(start 196.850254 -62.900052)
					(mid 196.799038 -62.78433)
					(end 196.78142 -62.659006)
				)
				(arc
					(start 196.78142 -62.635892)
					(mid 196.749749 -62.562186)
					(end 196.674486 -62.534546)
				)
				(arc
					(start 196.674486 -62.534546)
					(mid 196.639163 -62.535261)
					(end 196.603874 -62.53353)
				)
				(arc
					(start 196.603874 -62.53353)
					(mid 196.528814 -62.557847)
					(end 196.493892 -62.628526)
				)
				(arc
					(start 196.493892 -62.628526)
					(mid 196.155468 -63.069127)
					(end 195.62064 -62.919102)
				)
				(arc
					(start 195.62064 -62.919102)
					(mid 195.561403 -62.884816)
					(end 195.493894 -62.895988)
				)
				(arc
					(start 195.493894 -62.895988)
					(mid 195.536577 -62.842203)
					(end 195.535296 -62.77356)
				)
				(arc
					(start 195.535296 -62.77356)
					(mid 195.507691 -62.664652)
					(end 195.505324 -62.552326)
				)
				(arc
					(start 195.505324 -62.552326)
					(mid 195.466971 -62.463105)
					(end 195.371212 -62.446916)
				)
				(arc
					(start 195.371212 -62.446916)
					(mid 195.260207 -62.470876)
					(end 195.146676 -62.468252)
				)
				(arc
					(start 195.146676 -62.468252)
					(mid 195.076349 -62.484149)
					(end 195.034154 -62.542674)
				)
				(arc
					(start 195.034154 -62.542674)
					(mid 194.97904 -62.685341)
					(end 194.894708 -62.81293)
				)
				(arc
					(start 194.894708 -62.81293)
					(mid 194.974767 -63.10654)
					(end 194.909186 -63.403734)
				)
				(arc
					(start 194.909186 -63.403734)
					(mid 194.913949 -63.502215)
					(end 195.000118 -63.550292)
				)
				(xy 195.527676 -63.550292)
				(arc
					(start 195.53428 -63.511176)
					(mid 195.558386 -63.591649)
					(end 195.634864 -63.626492)
				)
				(xy 195.656708 -63.626492) (xy 195.656708 -63.753492) (xy 195.782692 -63.753492) (xy 195.782692 -63.626492)
				(xy 196.006212 -63.626492)
			)
		)
		(polygon
			(pts
				(arc
					(start 196.620892 -70.583044)
					(mid 196.529757 -70.603077)
					(end 196.493384 -70.688962)
				)
				(arc
					(start 196.493384 -70.688962)
					(mid 196.053227 -71.219301)
					(end 195.508372 -70.797166)
				)
				(arc
					(start 195.508372 -70.797166)
					(mid 195.461338 -70.725278)
					(end 195.376038 -70.715124)
				)
				(arc
					(start 195.376038 -70.715124)
					(mid 195.224533 -70.739458)
					(end 195.073016 -70.715124)
				)
				(arc
					(start 195.073016 -70.715124)
					(mid 195.035465 -70.71754)
					(end 195.00977 -70.745096)
				)
				(arc
					(start 195.00977 -70.745096)
					(mid 194.960088 -70.847623)
					(end 194.894708 -70.94093)
				)
				(arc
					(start 194.894708 -70.94093)
					(mid 194.974948 -71.246865)
					(end 194.897756 -71.553578)
				)
				(arc
					(start 194.897756 -71.553578)
					(mid 194.899657 -71.653947)
					(end 194.98691 -71.703692)
				)
				(xy 195.631308 -71.703692) (xy 195.631308 -71.779892) (xy 196.08419 -71.779892) (xy 196.334126 -71.529956)
				(arc
					(start 196.482716 -71.529956)
					(mid 196.822426 -71.306529)
					(end 197.212458 -71.421498)
				)
				(arc
					(start 197.212458 -71.421498)
					(mid 197.27828 -71.371577)
					(end 197.35165 -71.333614)
				)
				(arc
					(start 197.35165 -71.333614)
					(mid 197.380696 -71.272581)
					(end 197.323202 -71.23684)
				)
				(arc
					(start 197.323202 -71.23684)
					(mid 197.154956 -71.236727)
					(end 196.998082 -71.17588)
				)
				(xy 196.98589 -71.16826) (xy 196.85762 -71.16826) (xy 196.85762 -71.040244)
				(arc
					(start 196.850254 -71.028052)
					(mid 196.799038 -70.91233)
					(end 196.78142 -70.787006)
				)
				(xy 196.78142 -70.66661) (xy 196.713856 -70.599046)
				(arc
					(start 196.696076 -70.597014)
					(mid 196.658212 -70.591491)
					(end 196.620892 -70.583044)
				)
			)
		)
	)
	(zone
		(net "PVDDQ_KLM")
		(layer "B.Cu")
		(hatch none 0.5)
		(connect_pads
			(clearance 0.5)
		)
		(min_thickness 0.25)
		(fill yes
			(thermal_gap 0.5)
			(thermal_bridge_width 0.5)
			(island_removal_mode 0)
		)
		(polygon
			(pts
				(xy 112.860328 -124.22124) (xy 112.095788 -124.98578) (xy 105.33126 -124.98578) (xy 104.65308 -124.3076)
				(xy 101.674168 -124.3076) (xy 101.369368 -124.6124) (xy 101.369368 -126.111) (xy 100.810568 -126.6698)
				(xy 100.810568 -129.7432) (xy 100.912168 -129.8448) (xy 101.242368 -129.8448) (xy 101.394768 -129.6924)
				(xy 101.394768 -127.3302) (xy 101.623368 -127.1016) (xy 103.274368 -127.1016) (xy 103.375968 -127.2032)
				(xy 103.375968 -130.3274) (xy 103.528368 -130.4798) (xy 103.756968 -130.4798) (xy 103.909368 -130.3274)
				(xy 103.909368 -127.2794) (xy 104.112568 -127.0762) (xy 105.814368 -127.0762) (xy 105.941368 -127.2032)
				(xy 105.941368 -129.6924) (xy 106.119168 -129.8702) (xy 106.271568 -129.8702) (xy 106.423968 -129.7178)
				(xy 106.423968 -127.2794) (xy 106.576368 -127.127) (xy 107.541568 -127.127) (xy 107.643168 -127.2286)
				(xy 107.643168 -129.794) (xy 107.820968 -129.9718) (xy 108.074968 -129.9718) (xy 108.303568 -129.7432)
				(xy 108.303568 -127.080518) (xy 110.51794 -127.080518) (xy 110.6297 -126.968758) (xy 112.421162 -126.968758)
				(xy 112.53724 -126.85268) (xy 112.53724 -125.74524) (xy 113.0935 -125.18898) (xy 113.78946 -125.18898)
				(xy 113.92916 -125.04928) (xy 113.92916 -124.38126) (xy 113.92535 -124.37745) (xy 113.92535 -124.11075)
				(xy 113.8682 -124.0536) (xy 113.027968 -124.0536)
			)
		)
	)
	(zone
		(net "GND")
		(layer "B.Cu")
		(hatch none 0.5)
		(connect_pads
			(clearance 0.5)
		)
		(min_thickness 0.25)
		(fill yes
			(thermal_gap 0.5)
			(thermal_bridge_width 0.5)
			(island_removal_mode 0)
		)
		(polygon
			(pts
				(xy 193.6242 -102.9208) (xy 195.707 -102.9208) (xy 196.22643 -102.9208) (xy 196.227446 -102.919784)
				(xy 196.337682 -102.919784) (xy 196.426582 -102.830884) (xy 196.426582 -102.720648) (xy 196.426582 -102.276656)
				(xy 196.426582 -102.1334) (xy 196.299582 -102.0064) (xy 196.156326 -102.0064) (xy 195.834 -102.0064)
				(xy 194.681856 -102.0064) (xy 194.11442 -101.438964) (xy 193.629534 -101.438964) (xy 193.4972 -101.571298)
				(xy 193.4972 -101.8794) (xy 193.4972 -102.7938)
			)
		)
	)
	(zone
		(layer "B.Cu")
		(hatch none 0.5)
		(connect_pads
			(clearance 0)
		)
		(min_thickness 0.25)
		(keepout
			(tracks not_allowed)
			(vias allowed)
			(pads allowed)
			(copperpour not_allowed)
			(footprints allowed)
		)
		(placement
			(enabled no)
			(sheetname "")
		)
		(fill
			(thermal_gap 0.5)
			(thermal_bridge_width 0.5)
			(island_removal_mode 0)
		)
		(polygon
			(pts
				(xy 3.565144 -112.356646) (xy 3.565144 -112.460532) (xy 3.701542 -112.59693)
				(arc
					(start 4.009644 -112.59693)
					(mid 4.393184 -112.21339)
					(end 4.009644 -111.82985)
				)
				(arc
					(start 2.739898 -111.82985)
					(mid 2.356104 -112.213263)
					(end 2.739644 -112.59693)
				)
				(xy 3.184144 -112.59693) (xy 3.184144 -112.356646) (xy 3.110738 -112.28324)
				(arc
					(start 2.996946 -112.28324)
					(mid 2.473029 -112.21339)
					(end 2.996946 -112.14354)
				)
				(xy 3.16865 -112.14354) (xy 3.323844 -112.298734) (xy 3.323844 -112.560608) (xy 3.360166 -112.59693)
				(xy 3.50393 -112.59693) (xy 3.425444 -112.518444) (xy 3.425444 -112.298734) (xy 3.580638 -112.14354)
				(arc
					(start 3.752342 -112.14354)
					(mid 4.276259 -112.21339)
					(end 3.752342 -112.28324)
				)
				(xy 3.63855 -112.28324)
			)
		)
	)
	(zone
		(layer "B.Cu")
		(hatch none 0.5)
		(connect_pads
			(clearance 0)
		)
		(min_thickness 0.25)
		(keepout
			(tracks allowed)
			(vias allowed)
			(pads allowed)
			(copperpour allowed)
			(footprints not_allowed)
		)
		(placement
			(enabled no)
			(sheetname "")
		)
		(fill
			(thermal_gap 0.5)
			(thermal_bridge_width 0.5)
			(island_removal_mode 0)
		)
		(polygon
			(pts
				(arc
					(start 179.23002 -153.655268)
					(mid 179.50003 -155.10002)
					(end 179.23002 -156.544772)
				)
				(xy 179.23002 -159.100012) (xy 185.879994 -159.100012) (xy 185.879994 -127.364998) (xy 179.23002 -127.364998)
			)
		)
	)
	(zone
		(layer "B.Cu")
		(hatch none 0.5)
		(connect_pads
			(clearance 0)
		)
		(min_thickness 0.25)
		(keepout
			(tracks not_allowed)
			(vias allowed)
			(pads allowed)
			(copperpour not_allowed)
			(footprints allowed)
		)
		(placement
			(enabled no)
			(sheetname "")
		)
		(fill
			(thermal_gap 0.5)
			(thermal_bridge_width 0.5)
			(island_removal_mode 0)
		)
		(polygon
			(pts
				(xy 443.169802 -114.333782) (xy 443.33922 -114.5032) (xy 443.33922 -114.787172) (xy 443.44082 -114.787172)
				(xy 443.44082 -114.498882) (xy 443.60592 -114.333782)
				(arc
					(start 443.777624 -114.333782)
					(mid 444.301541 -114.403632)
					(end 443.777624 -114.473482)
				)
				(xy 443.663832 -114.473482) (xy 443.58052 -114.556794) (xy 443.58052 -114.787172)
				(arc
					(start 444.034926 -114.787172)
					(mid 444.418466 -114.403632)
					(end 444.034926 -114.020092)
				)
				(arc
					(start 442.76518 -114.020092)
					(mid 442.381386 -114.403505)
					(end 442.764926 -114.787172)
				)
				(xy 443.19952 -114.787172) (xy 443.19952 -114.561112) (xy 443.11189 -114.473482)
				(arc
					(start 443.022228 -114.473482)
					(mid 442.498311 -114.403632)
					(end 443.022228 -114.333782)
				)
			)
		)
	)
	(zone
		(layer "B.Cu")
		(hatch none 0.5)
		(connect_pads
			(clearance 0)
		)
		(min_thickness 0.25)
		(keepout
			(tracks allowed)
			(vias allowed)
			(pads allowed)
			(copperpour allowed)
			(footprints not_allowed)
		)
		(placement
			(enabled no)
			(sheetname "")
		)
		(fill
			(thermal_gap 0.5)
			(thermal_bridge_width 0.5)
			(island_removal_mode 0)
		)
		(polygon
			(pts
				(arc
					(start 152.999948 -57.090056)
					(mid 155.539948 -54.550056)
					(end 152.999948 -52.010056)
				)
				(arc
					(start 152.999948 -52.010056)
					(mid 150.459948 -54.550056)
					(end 152.999948 -57.090056)
				)
			)
		)
	)
	(zone
		(net "PVCCIO_CPU0")
		(layer "B.Cu")
		(hatch none 0.5)
		(connect_pads
			(clearance 0.5)
		)
		(min_thickness 0.25)
		(fill yes
			(thermal_gap 0.5)
			(thermal_bridge_width 0.5)
			(island_removal_mode 0)
		)
		(polygon
			(pts
				(xy 340.129622 -94.296992) (xy 340.129622 -98.769678) (xy 340.756748 -99.396804) (xy 340.756748 -106.791252)
				(xy 339.9536 -107.5944) (xy 334.7212 -107.5944) (xy 333.9973 -107.5944) (xy 333.2734 -106.8705)
				(xy 333.2734 -106.488738) (xy 334.138524 -105.623614) (xy 334.138524 -92.327476) (xy 334.518 -91.948)
				(xy 337.78063 -91.948)
			)
		)
	)
	(zone
		(layer "B.Cu")
		(hatch none 0.5)
		(connect_pads
			(clearance 0)
		)
		(min_thickness 0.25)
		(keepout
			(tracks not_allowed)
			(vias allowed)
			(pads allowed)
			(copperpour not_allowed)
			(footprints allowed)
		)
		(placement
			(enabled no)
			(sheetname "")
		)
		(fill
			(thermal_gap 0.5)
			(thermal_bridge_width 0.5)
			(island_removal_mode 0)
		)
		(polygon
			(pts
				(xy 459.43774 -114.787172) (xy 459.43774 -114.50193) (xy 459.605888 -114.333782)
				(arc
					(start 459.777592 -114.333782)
					(mid 460.301509 -114.403632)
					(end 459.777592 -114.473482)
				)
				(xy 459.6638 -114.473482) (xy 459.57744 -114.559842) (xy 459.57744 -114.787172)
				(arc
					(start 460.034894 -114.787172)
					(mid 460.418434 -114.403632)
					(end 460.034894 -114.020092)
				)
				(arc
					(start 458.765148 -114.020092)
					(mid 458.381354 -114.403505)
					(end 458.764894 -114.787172)
				)
				(xy 459.19644 -114.787172) (xy 459.19644 -114.547142) (xy 459.12278 -114.473482)
				(arc
					(start 459.022196 -114.473482)
					(mid 458.498279 -114.403632)
					(end 459.022196 -114.333782)
				)
				(xy 459.180692 -114.333782) (xy 459.33614 -114.48923) (xy 459.33614 -114.787172)
			)
		)
	)
	(zone
		(layer "B.Cu")
		(hatch none 0.5)
		(connect_pads
			(clearance 0)
		)
		(min_thickness 0.25)
		(keepout
			(tracks not_allowed)
			(vias allowed)
			(pads allowed)
			(copperpour not_allowed)
			(footprints allowed)
		)
		(placement
			(enabled no)
			(sheetname "")
		)
		(fill
			(thermal_gap 0.5)
			(thermal_bridge_width 0.5)
			(island_removal_mode 0)
		)
		(polygon
			(pts
				(arc
					(start 250.59005 -111.550196)
					(mid 245.410482 -111.550196)
					(end 250.59005 -111.550196)
				)
			)
		)
	)
	(zone
		(net "PVDDQ_GHJ")
		(layer "B.Cu")
		(hatch none 0.5)
		(connect_pads
			(clearance 0.5)
		)
		(min_thickness 0.25)
		(fill yes
			(thermal_gap 0.5)
			(thermal_bridge_width 0.5)
			(island_removal_mode 0)
		)
		(polygon
			(pts
				(xy 21.8694 -18.669) (xy 21.8694 -1.701546) (xy 21.53539 -1.367536) (xy 17.257776 -1.367536) (xy 16.8402 -1.785112)
				(xy 16.8402 -3.556) (xy 16.002 -4.3942) (xy 15.35557 -4.3942) (xy 14.985492 -4.764278) (xy 14.605 -5.14477)
				(xy 14.605 -21.463) (xy 15.113 -21.971) (xy 15.748 -21.971) (xy 20.32 -21.971) (xy 20.701 -21.59)
				(xy 21.8694 -20.4216)
			)
		)
	)
	(zone
		(layer "B.Cu")
		(hatch none 0.5)
		(connect_pads
			(clearance 0)
		)
		(min_thickness 0.25)
		(keepout
			(tracks allowed)
			(vias allowed)
			(pads allowed)
			(copperpour allowed)
			(footprints not_allowed)
		)
		(placement
			(enabled no)
			(sheetname "")
		)
		(fill
			(thermal_gap 0.5)
			(thermal_bridge_width 0.5)
			(island_removal_mode 0)
		)
		(polygon
			(pts
				(arc
					(start 358.929178 -157.04439)
					(mid 358.338665 -156.714257)
					(end 357.671878 -156.59989)
				)
				(arc
					(start 357.000048 -156.59989)
					(mid 355.500178 -155.10002)
					(end 357.000048 -153.599896)
				)
				(arc
					(start 357.671878 -153.599896)
					(mid 358.338659 -153.485669)
					(end 358.929178 -153.15565)
				)
				(arc
					(start 358.929178 -153.15565)
					(mid 363.000298 -155.10002)
					(end 358.929178 -157.04439)
				)
			)
		)
	)
	(zone
		(net "GND")
		(layer "B.Cu")
		(hatch none 0.5)
		(connect_pads
			(clearance 0.5)
		)
		(min_thickness 0.25)
		(fill yes
			(thermal_gap 0.5)
			(thermal_bridge_width 0.5)
			(island_removal_mode 0)
		)
		(polygon
			(pts
				(xy 278.258016 -18.766028) (xy 278.258016 -16.80083) (xy 278.591772 -16.467074) (xy 279.86609 -16.467074)
				(xy 280.060908 -16.661892) (xy 280.415492 -16.661892) (xy 280.7716 -17.018) (xy 280.7716 -17.3482)
				(xy 280.4922 -17.6276) (xy 280.32329 -17.6276) (xy 280.19629 -17.7546) (xy 280.059638 -17.891252)
				(xy 280.059638 -18.934938) (xy 279.917906 -19.07667) (xy 278.568658 -19.07667)
			)
		)
	)
	(zone
		(layer "B.Cu")
		(hatch none 0.5)
		(connect_pads
			(clearance 0)
		)
		(min_thickness 0.25)
		(keepout
			(tracks not_allowed)
			(vias allowed)
			(pads allowed)
			(copperpour not_allowed)
			(footprints allowed)
		)
		(placement
			(enabled no)
			(sheetname "")
		)
		(fill
			(thermal_gap 0.5)
			(thermal_bridge_width 0.5)
			(island_removal_mode 0)
		)
		(polygon
			(pts
				(arc
					(start 129.58953 -41.550336)
					(mid 124.409962 -41.550336)
					(end 129.58953 -41.550336)
				)
			)
		)
	)
	(zone
		(net "GND")
		(layer "B.Cu")
		(hatch none 0.5)
		(connect_pads
			(clearance 0.5)
		)
		(min_thickness 0.25)
		(fill yes
			(thermal_gap 0.5)
			(thermal_bridge_width 0.5)
			(island_removal_mode 0)
		)
		(polygon
			(pts
				(xy 370.28882 -132.10413) (xy 370.147596 -132.245354) (xy 370.147596 -133.96595) (xy 370.380768 -134.199122)
				(xy 371.87505 -134.199122) (xy 371.9576 -134.116572) (xy 371.9576 -133.480048) (xy 371.877082 -133.39953)
				(xy 371.876828 -133.39953) (xy 371.843554 -133.366256) (xy 371.458744 -133.366256) (xy 371.381274 -133.288786)
				(xy 371.381274 -132.219446) (xy 371.265958 -132.10413)
			)
		)
		(polygon
			(pts
				(xy 371.2083 -133.3246) (xy 371.0051 -133.3246) (xy 371.0051 -133.5278) (xy 371.2083 -133.5278)
			)
		)
	)
	(zone
		(layer "B.Cu")
		(hatch none 0.5)
		(connect_pads
			(clearance 0)
		)
		(min_thickness 0.25)
		(keepout
			(tracks not_allowed)
			(vias allowed)
			(pads allowed)
			(copperpour not_allowed)
			(footprints allowed)
		)
		(placement
			(enabled no)
			(sheetname "")
		)
		(fill
			(thermal_gap 0.5)
			(thermal_bridge_width 0.5)
			(island_removal_mode 0)
		)
		(polygon
			(pts
				(arc
					(start 248.000012 -113.450116)
					(mid 249.899932 -111.550196)
					(end 248.000012 -109.650022)
				)
				(arc
					(start 248.000012 -109.650022)
					(mid 246.099838 -111.550196)
					(end 248.000012 -113.450116)
				)
			)
		)
	)
	(zone
		(layer "B.Cu")
		(hatch none 0.5)
		(connect_pads
			(clearance 0)
		)
		(min_thickness 0.25)
		(keepout
			(tracks allowed)
			(vias allowed)
			(pads allowed)
			(copperpour allowed)
			(footprints not_allowed)
		)
		(placement
			(enabled no)
			(sheetname "")
		)
		(fill
			(thermal_gap 0.5)
			(thermal_bridge_width 0.5)
			(island_removal_mode 0)
		)
		(polygon
			(pts
				(xy 187.520072 -0.109982) (xy 328.520044 -0.109982) (xy 328.520044 5.999988) (xy 187.520072 5.999988)
			)
		)
	)
	(zone
		(net "VR_FET_SW_P12V_STBY_PVCCIO_CPU0")
		(layer "B.Cu")
		(hatch none 0.5)
		(connect_pads
			(clearance 0.5)
		)
		(min_thickness 0.25)
		(fill yes
			(thermal_gap 0.5)
			(thermal_bridge_width 0.5)
			(island_removal_mode 0)
		)
		(polygon
			(pts
				(xy 348.288864 -102.307644) (xy 348.288864 -101.99878) (xy 349.320866 -100.966778) (xy 349.320866 -99.650296)
				(xy 348.897194 -99.226624) (xy 347.874336 -99.226624) (xy 347.6625 -99.014788) (xy 347.6625 -94.26448)
				(xy 347.6625 -93.981524) (xy 348.276926 -93.367098) (xy 353.478338 -93.367098) (xy 355.500686 -93.367098)
				(xy 355.50094 -93.367352) (xy 355.741224 -93.367352) (xy 356.131368 -93.757496) (xy 356.131368 -96.776286)
				(xy 356.131368 -102.894384) (xy 355.11486 -103.910892) (xy 353.162108 -103.910892) (xy 345.787472 -103.910892)
				(xy 345.72448 -103.8479) (xy 345.72448 -102.73411) (xy 345.819222 -102.639368) (xy 347.95714 -102.639368)
			)
		)
		(polygon
			(pts
				(arc
					(start 352.7806 -97.619058)
					(mid 352.7806 -99.383342)
					(end 352.7806 -97.619058)
				)
			)
		)
	)
	(zone
		(net "PVSA_CPU0")
		(layer "B.Cu")
		(hatch none 0.5)
		(connect_pads
			(clearance 0.5)
		)
		(min_thickness 0.25)
		(fill yes
			(thermal_gap 0.5)
			(thermal_bridge_width 0.5)
			(island_removal_mode 0)
		)
		(polygon
			(pts
				(xy 229.910386 -77.810614) (xy 215.8746 -91.8464) (xy 215.8746 -93.1672) (xy 215.0618 -93.98) (xy 214.025226 -93.98)
				(xy 212.927946 -92.88272) (xy 208.61528 -92.88272) (xy 208.00568 -93.49232) (xy 208.00568 -100.9523)
				(xy 209.08518 -102.0318) (xy 212.0646 -102.0318) (xy 212.56625 -101.53015) (xy 213.64575 -101.53015)
				(xy 223.647 -91.5289) (xy 223.647 -89.4334) (xy 226.507294 -86.573106) (xy 228.508306 -86.573106)
				(xy 228.7524 -86.8172) (xy 228.7524 -87.089234) (xy 228.810312 -87.147146) (xy 229.286054 -87.147146)
				(xy 230.9368 -85.4964) (xy 230.9368 -85.1408) (xy 232.043986 -84.033614) (xy 236.412024 -84.033614)
				(xy 254.170688 -84.044536) (xy 254.601218 -84.475066) (xy 258.002024 -84.475066) (xy 258.164076 -84.313014)
				(xy 258.789424 -84.313014) (xy 258.865624 -84.389214) (xy 258.865624 -84.398866) (xy 258.941824 -84.475066)
				(xy 262.719566 -84.475066) (xy 262.777224 -84.417408) (xy 262.777224 -83.1088) (xy 262.2042 -83.1088)
				(xy 261.571232 -82.475832) (xy 261.571232 -81.684368) (xy 261.380224 -81.493614) (xy 258.20243 -81.493614)
				(xy 256.608834 -79.900018) (xy 255.29159 -79.900018) (xy 254.834898 -80.35671) (xy 253.15672 -80.35671)
				(xy 252.896624 -80.096614) (xy 251.919994 -80.096614) (xy 251.030994 -79.207614) (xy 246.191024 -79.207614)
				(xy 245.048024 -80.350614) (xy 238.317024 -80.350614) (xy 233.872024 -77.810614)
			)
		)
		(polygon
			(pts
				(xy 214.9856 -94.7801) (xy 214.7824 -94.7801) (xy 214.7824 -94.9833) (xy 214.9856 -94.9833)
			)
		)
		(polygon
			(pts
				(xy 214.2236 -94.7801) (xy 214.0204 -94.7801) (xy 214.0204 -94.9833) (xy 214.2236 -94.9833)
			)
		)
	)
	(zone
		(layer "B.Cu")
		(hatch none 0.5)
		(connect_pads
			(clearance 0)
		)
		(min_thickness 0.25)
		(keepout
			(tracks not_allowed)
			(vias allowed)
			(pads allowed)
			(copperpour not_allowed)
			(footprints allowed)
		)
		(placement
			(enabled no)
			(sheetname "")
		)
		(fill
			(thermal_gap 0.5)
			(thermal_bridge_width 0.5)
			(island_removal_mode 0)
		)
		(polygon
			(pts
				(arc
					(start 441.405772 -49.793144)
					(mid 441.831335 -50.104732)
					(end 441.33262 -49.932844)
				)
				(xy 441.20308 -49.932844) (xy 441.125356 -50.010568) (xy 441.125356 -50.364644)
				(arc
					(start 441.594748 -50.364644)
					(mid 441.978542 -49.981231)
					(end 441.595002 -49.597564)
				)
				(arc
					(start 440.325002 -49.597564)
					(mid 439.941462 -49.981104)
					(end 440.325002 -50.364644)
				)
				(xy 440.744356 -50.364644) (xy 440.744356 -50.035206) (xy 440.641994 -49.932844)
				(arc
					(start 440.587384 -49.932844)
					(mid 440.088609 -50.104764)
					(end 440.514232 -49.793144)
				)
				(xy 440.699906 -49.793144) (xy 440.884056 -49.977294) (xy 440.884056 -50.364644) (xy 440.985656 -50.364644)
				(xy 440.985656 -49.952656) (xy 441.145168 -49.793144)
			)
		)
	)
	(zone
		(layer "B.Cu")
		(hatch none 0.5)
		(connect_pads
			(clearance 0)
		)
		(min_thickness 0.25)
		(keepout
			(tracks allowed)
			(vias allowed)
			(pads allowed)
			(copperpour allowed)
			(footprints not_allowed)
		)
		(placement
			(enabled no)
			(sheetname "")
		)
		(fill
			(thermal_gap 0.5)
			(thermal_bridge_width 0.5)
			(island_removal_mode 0)
		)
		(polygon
			(pts
				(xy 330.160122 5.999988) (xy 330.160122 -25.729946) (xy 328.520044 -25.729946) (xy 328.520044 5.999988)
			)
		)
	)
	(zone
		(layer "B.Cu")
		(hatch none 0.5)
		(connect_pads
			(clearance 0)
		)
		(min_thickness 0.25)
		(keepout
			(tracks not_allowed)
			(vias allowed)
			(pads allowed)
			(copperpour not_allowed)
			(footprints allowed)
		)
		(placement
			(enabled no)
			(sheetname "")
		)
		(fill
			(thermal_gap 0.5)
			(thermal_bridge_width 0.5)
			(island_removal_mode 0)
		)
		(polygon
			(pts
				(arc
					(start 152.999948 -56.449976)
					(mid 154.899868 -54.550056)
					(end 152.999948 -52.649882)
				)
				(arc
					(start 152.999948 -52.649882)
					(mid 151.099774 -54.550056)
					(end 152.999948 -56.449976)
				)
			)
		)
	)
	(zone
		(net "GND")
		(layer "B.Cu")
		(hatch none 0.5)
		(connect_pads
			(clearance 0.5)
		)
		(min_thickness 0.25)
		(fill yes
			(thermal_gap 0.5)
			(thermal_bridge_width 0.5)
			(island_removal_mode 0)
		)
		(polygon
			(pts
				(xy 413.556958 -33.0962) (xy 413.296862 -33.356296) (xy 413.296862 -34.187892) (xy 412.94685 -34.537904)
				(xy 412.94685 -35.17646) (xy 413.06242 -35.29203) (xy 413.88284 -35.29203) (xy 414.340294 -34.834576)
				(xy 414.340294 -34.722816) (xy 414.364678 -34.698432) (xy 415.129726 -34.698432) (xy 415.150046 -34.718752)
				(xy 415.150046 -34.917634) (xy 415.405062 -35.17265) (xy 416.510978 -35.17265) (xy 416.802316 -35.463988)
				(xy 417.260786 -35.463988) (xy 417.285932 -35.438842) (xy 417.285932 -34.896298) (xy 417.127944 -34.73831)
				(xy 416.93338 -34.73831) (xy 416.788854 -34.593784) (xy 416.788854 -33.79978) (xy 416.994848 -33.593786)
				(xy 417.10864 -33.593786) (xy 417.141152 -33.561274) (xy 417.141152 -33.115504) (xy 417.121848 -33.0962)
			)
		)
		(polygon
			(pts
				(xy 414.464246 -33.715452) (xy 414.261046 -33.715452) (xy 414.261046 -33.918652) (xy 414.464246 -33.918652)
			)
		)
		(polygon
			(pts
				(xy 415.226246 -33.715452) (xy 415.023046 -33.715452) (xy 415.023046 -33.918652) (xy 415.226246 -33.918652)
			)
		)
	)
	(zone
		(net "GND")
		(layer "B.Cu")
		(hatch none 0.5)
		(connect_pads
			(clearance 0.5)
		)
		(min_thickness 0.25)
		(fill yes
			(thermal_gap 0.5)
			(thermal_bridge_width 0.5)
			(island_removal_mode 0)
		)
		(polygon
			(pts
				(xy 114.867182 -9.577324) (xy 113.488978 -9.577324) (xy 113.210594 -9.29894) (xy 113.210594 -7.192518)
				(xy 113.54435 -6.858762) (xy 114.818668 -6.858762) (xy 115.148868 -7.188962) (xy 115.392962 -7.188962)
				(xy 115.7732 -7.5692) (xy 115.7732 -7.7724) (xy 115.4811 -8.0645) (xy 115.148868 -8.0645) (xy 115.148868 -9.295638)
			)
		)
	)
	(zone
		(layer "B.Cu")
		(hatch none 0.5)
		(connect_pads
			(clearance 0)
		)
		(min_thickness 0.25)
		(keepout
			(tracks allowed)
			(vias allowed)
			(pads allowed)
			(copperpour allowed)
			(footprints not_allowed)
		)
		(placement
			(enabled no)
			(sheetname "")
		)
		(fill
			(thermal_gap 0.5)
			(thermal_bridge_width 0.5)
			(island_removal_mode 0)
		)
		(polygon
			(pts
				(xy 179.23002 5.999988)
				(arc
					(start 175.50003 5.999988)
					(mid 177.760436 5.300072)
					(end 179.229766 3.445256)
				)
				(xy 179.23002 3.445256)
			)
		)
	)
	(zone
		(net "P3V3_STBY")
		(layer "B.Cu")
		(hatch none 0.5)
		(connect_pads
			(clearance 0.5)
		)
		(min_thickness 0.25)
		(fill yes
			(thermal_gap 0.5)
			(thermal_bridge_width 0.5)
			(island_removal_mode 0)
		)
		(polygon
			(pts
				(xy 402.420074 -28.298394) (xy 402.137626 -28.580842) (xy 402.137626 -29.96946) (xy 402.2217 -30.053534)
				(xy 402.939758 -30.053534) (xy 403.147276 -30.261052) (xy 403.147276 -31.056072) (xy 403.460204 -31.369)
				(xy 404.454868 -31.369) (xy 404.5458 -31.278068) (xy 404.5458 -29.7942) (xy 404.4696 -29.718) (xy 404.3426 -29.718)
				(xy 404.2664 -29.6418) (xy 404.2664 -29.0576) (xy 404.523956 -28.800044) (xy 404.523956 -28.342844)
				(xy 404.479252 -28.298394)
			)
		)
		(polygon
			(pts
				(xy 403.038056 -29.057346) (xy 402.834856 -29.057346) (xy 402.834856 -29.260546) (xy 403.038056 -29.260546)
			)
		)
	)
	(zone
		(layer "B.Cu")
		(hatch none 0.5)
		(connect_pads
			(clearance 0)
		)
		(min_thickness 0.25)
		(keepout
			(tracks not_allowed)
			(vias allowed)
			(pads allowed)
			(copperpour not_allowed)
			(footprints allowed)
		)
		(placement
			(enabled no)
			(sheetname "")
		)
		(fill
			(thermal_gap 0.5)
			(thermal_bridge_width 0.5)
			(island_removal_mode 0)
		)
		(polygon
			(pts
				(arc
					(start 424.078654 -139.454636)
					(mid 423.69486 -139.838049)
					(end 424.0784 -140.221716)
				)
				(xy 424.523408 -140.221716) (xy 424.5229 -140.221208)
				(arc
					(start 424.5229 -139.965176)
					(mid 424.506161 -139.924765)
					(end 424.46575 -139.908026)
				)
				(arc
					(start 424.335702 -139.908026)
					(mid 423.811785 -139.838176)
					(end 424.335702 -139.768326)
				)
				(xy 424.494706 -139.768326)
				(arc
					(start 424.497246 -139.770866)
					(mid 424.604941 -139.825985)
					(end 424.66006 -139.93368)
				)
				(xy 424.6626 -139.93622) (xy 424.6626 -140.163296) (xy 424.663108 -140.163804) (xy 424.663108 -140.221716)
				(xy 424.764708 -140.221716) (xy 424.764708 -140.12164) (xy 424.7642 -140.121132) (xy 424.7642 -139.93622)
				(arc
					(start 424.76674 -139.93368)
					(mid 424.821859 -139.825985)
					(end 424.929554 -139.770866)
				)
				(xy 424.932094 -139.768326)
				(arc
					(start 425.091098 -139.768326)
					(mid 425.615015 -139.838176)
					(end 425.091098 -139.908026)
				)
				(arc
					(start 424.96105 -139.908026)
					(mid 424.920639 -139.924765)
					(end 424.9039 -139.965176)
				)
				(xy 424.9039 -140.06322) (xy 424.904408 -140.063728) (xy 424.904408 -140.221716)
				(arc
					(start 425.3484 -140.221716)
					(mid 425.73194 -139.838176)
					(end 425.3484 -139.454636)
				)
			)
		)
	)
	(zone
		(layer "B.Cu")
		(hatch none 0.5)
		(connect_pads
			(clearance 0.5)
		)
		(min_thickness 0.25)
		(fill
			(thermal_gap 0.5)
			(thermal_bridge_width 0.5)
			(island_removal_mode 0)
		)
		(polygon
			(pts
				(xy 348.869 -0.7112) (xy 349.1484 -0.9906) (xy 349.1484 -2.6924) (xy 348.6658 -3.175) (xy 347.091 -3.175)
				(xy 347.0529 -3.2131) (xy 347.0529 -8.0518) (xy 347.42882 -8.42772) (xy 348.47784 -8.42772) (xy 349.5929 -8.42772)
				(xy 349.83674 -8.67156) (xy 349.83674 -11.10234) (xy 351.7392 -13.0048) (xy 351.7646 -13.0048) (xy 352.187256 -13.427456)
				(xy 352.187256 -15.404592) (xy 351.4598 -16.132048) (xy 351.4598 -19.939) (xy 352.2218 -20.701)
				(xy 355.7016 -20.701) (xy 355.8286 -20.574) (xy 355.8286 -20.2438) (xy 356.3874 -19.685) (xy 356.3874 -7.940802)
				(xy 354.928424 -6.481826) (xy 354.928424 -4.027932) (xy 354.09632 -3.195828) (xy 354.09632 -0.90932)
				(xy 352.9838 0.2032) (xy 352.9838 4.699) (xy 352.6282 5.0546) (xy 348.361 5.0546) (xy 347.3958 5.0546)
				(xy 347.0402 4.699) (xy 347.0402 -0.3429) (xy 347.4085 -0.7112)
			)
		)
	)
	(zone
		(net "P3V3_STBY")
		(layer "B.Cu")
		(hatch none 0.5)
		(connect_pads
			(clearance 0.5)
		)
		(min_thickness 0.25)
		(fill yes
			(thermal_gap 0.5)
			(thermal_bridge_width 0.5)
			(island_removal_mode 0)
		)
		(polygon
			(pts
				(xy 483.6414 -114.0968) (xy 483.9208 -114.0968) (xy 484.0986 -113.919) (xy 484.0986 -113.03) (xy 483.87 -112.8014)
				(xy 483.4128 -112.8014) (xy 483.362 -112.8522) (xy 483.362 -113.411) (xy 483.5398 -113.5888) (xy 483.5398 -113.9952)
			)
		)
	)
	(zone
		(net "P5V_STBY_USBC")
		(layer "B.Cu")
		(hatch none 0.5)
		(connect_pads
			(clearance 0.5)
		)
		(min_thickness 0.25)
		(fill yes
			(thermal_gap 0.5)
			(thermal_bridge_width 0.5)
			(island_removal_mode 0)
		)
		(polygon
			(pts
				(xy 486.395776 -57.645808) (xy 486.30459 -57.736994) (xy 485.32542 -57.736994) (xy 484.925116 -57.736994)
				(xy 484.869744 -57.681622) (xy 484.869744 -56.579516) (xy 485.015286 -56.433974) (xy 485.277414 -56.433974)
				(xy 485.707944 -56.433974) (xy 485.901746 -56.240172) (xy 486.430828 -56.240172) (xy 487.09961 -56.240172)
				(xy 488.884214 -56.240172) (xy 488.970066 -56.326024) (xy 488.970066 -57.367424) (xy 488.961938 -57.375552)
				(xy 488.691682 -57.645808)
			)
		)
	)
	(zone
		(layer "B.Cu")
		(hatch none 0.5)
		(connect_pads
			(clearance 0)
		)
		(min_thickness 0.25)
		(keepout
			(tracks allowed)
			(vias allowed)
			(pads allowed)
			(copperpour allowed)
			(footprints not_allowed)
		)
		(placement
			(enabled no)
			(sheetname "")
		)
		(fill
			(thermal_gap 0.5)
			(thermal_bridge_width 0.5)
			(island_removal_mode 0)
		)
		(polygon
			(pts
				(arc
					(start 318.000126 -52.649882)
					(mid 316.099952 -54.550056)
					(end 318.000126 -56.449976)
				)
				(arc
					(start 318.000126 -56.449976)
					(mid 319.900046 -54.550056)
					(end 318.000126 -52.649882)
				)
			)
		)
	)
	(zone
		(net "GND")
		(layer "B.Cu")
		(hatch none 0.5)
		(connect_pads
			(clearance 0.5)
		)
		(min_thickness 0.25)
		(fill yes
			(thermal_gap 0.5)
			(thermal_bridge_width 0.5)
			(island_removal_mode 0)
		)
		(polygon
			(pts
				(xy 479.625152 -32.438848) (xy 479.625152 -31.803848) (xy 480.63277 -30.79623) (xy 480.63277 -28.61437)
				(xy 480.3394 -28.321) (xy 475.9452 -28.321) (xy 475.68358 -28.58262) (xy 475.68358 -29.068776) (xy 475.053406 -29.69895)
				(xy 475.053406 -31.651194) (xy 474.6752 -32.0294) (xy 474.6752 -32.9438) (xy 474.7514 -33.02) (xy 475.996 -33.02)
				(xy 476.4532 -33.4772) (xy 479.069654 -33.4772) (xy 479.2472 -33.299654) (xy 479.2472 -32.8168)
			)
		)
	)
	(zone
		(layer "B.Cu")
		(hatch none 0.5)
		(connect_pads
			(clearance 0)
		)
		(min_thickness 0.25)
		(keepout
			(tracks allowed)
			(vias allowed)
			(pads allowed)
			(copperpour allowed)
			(footprints not_allowed)
		)
		(placement
			(enabled no)
			(sheetname "")
		)
		(fill
			(thermal_gap 0.5)
			(thermal_bridge_width 0.5)
			(island_removal_mode 0)
		)
		(polygon
			(pts
				(xy 22.519894 5.999988) (xy 18.720054 5.999988) (xy 18.720054 -25.729946) (xy 22.519894 -25.729946)
			)
		)
	)
	(zone
		(net "PVDDQ_DEF")
		(layer "B.Cu")
		(hatch none 0.5)
		(connect_pads
			(clearance 0.5)
		)
		(min_thickness 0.25)
		(fill yes
			(thermal_gap 0.5)
			(thermal_bridge_width 0.5)
			(island_removal_mode 0)
		)
		(polygon
			(pts
				(xy 243.980716 -143.53032) (xy 243.735606 -143.77543) (xy 243.735606 -146.211036) (xy 243.959888 -146.435318)
				(xy 258.555744 -146.435318) (xy 258.993386 -145.997676) (xy 259.56895 -145.997676) (xy 259.979668 -145.586958)
				(xy 259.979668 -144.045686) (xy 259.733034 -143.799052) (xy 258.849622 -143.799052) (xy 258.58089 -143.53032)
			)
		)
		(polygon
			(pts
				(xy 253.049532 -145.4023) (xy 252.846332 -145.4023) (xy 252.846332 -145.6055) (xy 253.049532 -145.6055)
			)
		)
		(polygon
			(pts
				(xy 249.4026 -145.4023) (xy 249.1994 -145.4023) (xy 249.1994 -145.6055) (xy 249.4026 -145.6055)
			)
		)
		(polygon
			(pts
				(xy 246.3038 -145.4023) (xy 246.1006 -145.4023) (xy 246.1006 -145.6055) (xy 246.3038 -145.6055)
			)
		)
		(polygon
			(pts
				(xy 258.7498 -145.2753) (xy 258.5466 -145.2753) (xy 258.5466 -145.4785) (xy 258.7498 -145.4785)
			)
		)
		(polygon
			(pts
				(xy 253.049532 -144.4117) (xy 252.846332 -144.4117) (xy 252.846332 -144.6149) (xy 253.049532 -144.6149)
			)
		)
		(polygon
			(pts
				(xy 246.3038 -144.4117) (xy 246.1006 -144.4117) (xy 246.1006 -144.6149) (xy 246.3038 -144.6149)
			)
		)
		(polygon
			(pts
				(xy 258.7498 -144.2847) (xy 258.5466 -144.2847) (xy 258.5466 -144.4879) (xy 258.7498 -144.4879)
			)
		)
	)
	(zone
		(net "VR_FET_SW_P12V_STBY_PVCCIN_CPU1")
		(layer "B.Cu")
		(hatch none 0.5)
		(connect_pads
			(clearance 0.5)
		)
		(min_thickness 0.25)
		(fill yes
			(thermal_gap 0.5)
			(thermal_bridge_width 0.5)
			(island_removal_mode 0)
		)
		(polygon
			(pts
				(xy 33.02 -64.070484) (xy 32.553402 -64.070484) (xy 32.294576 -64.070484) (xy 32.248602 -64.116458)
				(xy 32.248602 -64.375284) (xy 32.248602 -65.111884) (xy 32.020002 -65.340484) (xy 31.740602 -65.340484)
				(xy 31.588202 -65.492884) (xy 30.716474 -66.364612) (xy 30.716474 -67.520058) (xy 30.716474 -68.711572)
				(xy 30.889702 -68.8848) (xy 33.0962 -68.8848) (xy 33.220406 -68.8848) (xy 33.346898 -68.758308)
				(xy 33.346898 -64.13119) (xy 33.286192 -64.070484)
			)
		)
	)
	(zone
		(layer "B.Cu")
		(hatch none 0.5)
		(connect_pads
			(clearance 0)
		)
		(min_thickness 0.25)
		(keepout
			(tracks allowed)
			(vias allowed)
			(pads allowed)
			(copperpour allowed)
			(footprints not_allowed)
		)
		(placement
			(enabled no)
			(sheetname "")
		)
		(fill
			(thermal_gap 0.5)
			(thermal_bridge_width 0.5)
			(island_removal_mode 0)
		)
		(polygon
			(pts
				(arc
					(start 358.929178 0.055372)
					(mid 358.338665 0.385505)
					(end 357.671878 0.499872)
				)
				(arc
					(start 357.000048 0.499872)
					(mid 355.499924 1.999996)
					(end 357.000048 3.499866)
				)
				(arc
					(start 357.671878 3.499866)
					(mid 358.338652 3.614271)
					(end 358.929178 3.944366)
				)
				(arc
					(start 358.929178 3.944366)
					(mid 363.000712 2.000076)
					(end 358.929178 0.055372)
				)
			)
		)
	)
	(zone
		(layer "B.Cu")
		(hatch none 0.5)
		(connect_pads
			(clearance 0)
		)
		(min_thickness 0.25)
		(keepout
			(tracks not_allowed)
			(vias allowed)
			(pads allowed)
			(copperpour not_allowed)
			(footprints allowed)
		)
		(placement
			(enabled no)
			(sheetname "")
		)
		(fill
			(thermal_gap 0.5)
			(thermal_bridge_width 0.5)
			(island_removal_mode 0)
		)
		(polygon
			(pts
				(xy 456.79995 -123.80468) (xy 456.79995 -124.102876) (xy 456.644756 -124.25807)
				(arc
					(start 456.473052 -124.25807)
					(mid 455.949135 -124.18822)
					(end 456.473052 -124.11837)
				)
				(xy 456.586844 -124.11837) (xy 456.66025 -124.044964) (xy 456.66025 -123.80468)
				(arc
					(start 456.216004 -123.80468)
					(mid 455.83221 -124.188093)
					(end 456.21575 -124.57176)
				)
				(arc
					(start 457.48575 -124.57176)
					(mid 457.86929 -124.18822)
					(end 457.48575 -123.80468)
				)
				(xy 457.04125 -123.80468) (xy 457.04125 -124.044964) (xy 457.114656 -124.11837)
				(arc
					(start 457.228448 -124.11837)
					(mid 457.752365 -124.18822)
					(end 457.228448 -124.25807)
				)
				(xy 457.056744 -124.25807) (xy 456.90155 -124.102876) (xy 456.90155 -123.80468)
			)
		)
	)
	(zone
		(net "GND")
		(layer "B.Cu")
		(hatch none 0.5)
		(connect_pads
			(clearance 0.5)
		)
		(min_thickness 0.25)
		(fill yes
			(thermal_gap 0.5)
			(thermal_bridge_width 0.5)
			(island_removal_mode 0)
		)
		(polygon
			(pts
				(xy 412.672784 -123.266708) (xy 411.076394 -123.266708) (xy 411.022546 -123.21286) (xy 410.126688 -123.21286)
				(xy 410.098748 -123.2408) (xy 410.098748 -124.021088) (xy 409.955746 -124.16409) (xy 409.955746 -124.841)
				(xy 410.02585 -124.91085) (xy 410.94025 -124.91085) (xy 411.099 -125.0696) (xy 411.099 -125.1458)
				(xy 411.099 -125.1966) (xy 411.099 -125.8189) (xy 411.1625 -125.8824) (xy 412.0896 -125.8824) (xy 412.294832 -125.677168)
				(xy 412.294832 -125.27407) (xy 412.524702 -125.0442) (xy 413.2199 -125.0442) (xy 413.385 -124.8791)
				(xy 413.45485 -124.80925) (xy 413.45485 -124.70765) (xy 413.45485 -124.66955) (xy 413.7279 -124.3965)
				(xy 413.766 -124.3965) (xy 414.2105 -124.3965) (xy 414.3375 -124.2695) (xy 414.4264 -124.1806) (xy 414.4264 -123.2535)
				(xy 414.3629 -123.19) (xy 413.004 -123.19) (xy 412.927292 -123.266708)
			)
		)
		(polygon
			(pts
				(xy 411.0863 -123.9012) (xy 410.8831 -123.9012) (xy 410.8831 -124.1044) (xy 411.0863 -124.1044)
			)
		)
	)
	(zone
		(net "GND")
		(layer "B.Cu")
		(hatch none 0.5)
		(connect_pads
			(clearance 0.5)
		)
		(min_thickness 0.25)
		(fill yes
			(thermal_gap 0.5)
			(thermal_bridge_width 0.5)
			(island_removal_mode 0)
		)
		(polygon
			(pts
				(xy 390.786112 -110.769146) (xy 390.786112 -110.420404) (xy 390.955022 -110.25124) (xy 392.370564 -110.25124)
				(xy 392.44016 -110.181644) (xy 392.44016 -109.7788) (xy 392.6078 -109.61116) (xy 392.6078 -108.547408)
				(xy 392.461242 -108.40085) (xy 392.461242 -108.084366) (xy 392.105642 -107.728766) (xy 392.105642 -106.54284)
				(xy 392.04646 -106.483658) (xy 392.04646 -106.48188) (xy 391.3505 -106.48188) (xy 391.20064 -106.63174)
				(xy 391.18286 -106.63174) (xy 391.03808 -106.77652) (xy 391.03808 -106.8324) (xy 391.0203 -106.85018)
				(xy 390.797288 -106.85018) (xy 390.777984 -106.830876) (xy 390.712198 -106.76509) (xy 390.712198 -106.653076)
				(xy 390.595104 -106.535982) (xy 389.79856 -106.535982) (xy 389.457184 -106.877358) (xy 389.225028 -106.877358)
				(xy 389.14197 -106.7943) (xy 389.14197 -106.613198) (xy 389.005572 -106.4768) (xy 388.57174 -106.4768)
				(xy 388.49046 -106.55808) (xy 388.47014 -106.55808) (xy 387.9977 -106.55808) (xy 387.98246 -106.55808)
				(xy 387.90118 -106.4768) (xy 386.0927 -106.4768) (xy 385.953 -106.6165) (xy 385.953 -107.1372) (xy 386.1308 -107.315)
				(xy 386.1308 -107.5944) (xy 385.953 -107.7722) (xy 385.953 -107.95) (xy 386.1308 -108.1278) (xy 386.1308 -108.4072)
				(xy 385.953 -108.585) (xy 385.953 -108.7374) (xy 386.461 -109.2454) (xy 386.461 -110.0328) (xy 386.6642 -110.236)
				(xy 387.5278 -110.236) (xy 387.5786 -110.1852) (xy 387.5786 -109.3724) (xy 387.7056 -109.2454) (xy 388.2644 -109.2454)
				(xy 388.5438 -108.966) (xy 388.5438 -107.2388) (xy 388.6454 -107.1372) (xy 389.1534 -107.1372) (xy 389.255 -107.2388)
				(xy 389.4074 -107.2388) (xy 389.509 -107.1372) (xy 389.9408 -107.1372) (xy 390.3218 -107.1372) (xy 390.32434 -107.1372)
				(xy 390.39038 -107.07116) (xy 391.1346 -107.07116) (xy 391.428224 -107.07116) (xy 391.468864 -107.1118)
				(xy 391.6426 -107.285536) (xy 391.6426 -108.4834) (xy 391.5918 -108.5342) (xy 391.5918 -108.7882)
				(xy 391.7696 -108.966) (xy 391.7696 -109.3978) (xy 391.319512 -109.847888) (xy 390.768332 -109.847888)
				(xy 390.279128 -110.337092) (xy 390.279128 -110.758224) (xy 390.431274 -110.91037) (xy 390.644888 -110.91037)
			)
		)
		(polygon
			(pts
				(xy 392.24839 -109.72292) (xy 392.04519 -109.72292) (xy 392.04519 -109.92612) (xy 392.24839 -109.92612)
			)
		)
	)
	(zone
		(layer "B.Cu")
		(hatch none 0.5)
		(connect_pads
			(clearance 0)
		)
		(min_thickness 0.25)
		(keepout
			(tracks allowed)
			(vias allowed)
			(pads allowed)
			(copperpour allowed)
			(footprints not_allowed)
		)
		(placement
			(enabled no)
			(sheetname "")
		)
		(fill
			(thermal_gap 0.5)
			(thermal_bridge_width 0.5)
			(island_removal_mode 0)
		)
		(polygon
			(pts
				(arc
					(start 222.039942 -92.689934)
					(mid 222.332835 -93.397039)
					(end 223.03994 -93.689932)
				)
				(arc
					(start 228.659944 -93.689932)
					(mid 229.367049 -93.397039)
					(end 229.659942 -92.689934)
				)
				(arc
					(start 229.659942 -85.549994)
					(mid 229.367049 -84.842889)
					(end 228.659944 -84.549996)
				)
				(arc
					(start 223.03994 -84.549996)
					(mid 222.332835 -84.842889)
					(end 222.039942 -85.549994)
				)
			)
		)
	)
	(zone
		(net "P12V_STBY")
		(layer "B.Cu")
		(hatch none 0.5)
		(connect_pads
			(clearance 0.5)
		)
		(min_thickness 0.25)
		(fill yes
			(thermal_gap 0.5)
			(thermal_bridge_width 0.5)
			(island_removal_mode 0)
		)
		(polygon
			(pts
				(xy 10.28319 -129.621788) (xy 9.940036 -129.964942) (xy 9.940036 -131.693158) (xy 10.117836 -131.870958)
				(xy 10.762742 -131.870958) (xy 11.02995 -132.138166) (xy 11.02995 -133.8326) (xy 10.861548 -134.000748)
				(xy 8.9154 -134.000748) (xy 8.628126 -133.713474) (xy 8.628126 -130.556) (xy 8.424672 -130.3528)
				(xy 8.255 -130.3528) (xy 7.681468 -130.3528) (xy 7.503414 -130.174746) (xy 7.503414 -128.92913)
				(xy 7.891272 -128.541272) (xy 7.8994 -128.5494) (xy 10.0076 -128.5494) (xy 10.28319 -128.82499)
			)
		)
	)
	(zone
		(net "P3V3_STBY")
		(layer "B.Cu")
		(hatch none 0.5)
		(connect_pads
			(clearance 0.5)
		)
		(min_thickness 0.25)
		(fill yes
			(thermal_gap 0.5)
			(thermal_bridge_width 0.5)
			(island_removal_mode 0)
		)
		(polygon
			(pts
				(xy 471.313002 -40.855392) (xy 469.379808 -40.855392) (xy 469.0872 -41.148) (xy 467.8934 -41.148)
				(xy 467.106 -41.148) (xy 466.66404 -40.70604) (xy 463.90052 -40.70604) (xy 463.62874 -40.97782)
				(xy 463.62874 -42.47896) (xy 463.9183 -42.76852) (xy 466.852 -42.76852) (xy 467.405974 -42.214546)
				(xy 467.94928 -42.214546) (xy 471.27668 -42.214546) (xy 471.47988 -42.011346) (xy 471.47988 -41.02227)
			)
		)
	)
	(zone
		(layer "B.Cu")
		(hatch none 0.5)
		(connect_pads
			(clearance 0)
		)
		(min_thickness 0.25)
		(keepout
			(tracks allowed)
			(vias allowed)
			(pads allowed)
			(copperpour allowed)
			(footprints allowed)
		)
		(placement
			(enabled no)
			(sheetname "")
		)
		(fill
			(thermal_gap 0.5)
			(thermal_bridge_width 0.5)
			(island_removal_mode 0)
		)
		(polygon
			(pts
				(xy 137.623042 -33.693608) (xy 137.623042 -32.82315) (xy 138.66749 -32.82315) (xy 138.66749 -33.693608)
			)
		)
	)
	(zone
		(layer "B.Cu")
		(hatch none 0.5)
		(connect_pads
			(clearance 0)
		)
		(min_thickness 0.25)
		(keepout
			(tracks allowed)
			(vias allowed)
			(pads allowed)
			(copperpour allowed)
			(footprints allowed)
		)
		(placement
			(enabled no)
			(sheetname "")
		)
		(fill
			(thermal_gap 0.5)
			(thermal_bridge_width 0.5)
			(island_removal_mode 0)
		)
		(polygon
			(pts
				(xy 283.083 -106.807) (xy 283.083 -125.73) (xy 290.576 -124.206) (xy 293.116 -124.714) (xy 296.672 -123.952)
				(xy 299.212 -124.46) (xy 304.292 -123.444) (xy 307.848 -123.444) (xy 307.848 -102.235) (xy 306.90312 -101.51872)
				(xy 306.82438 -101.7143) (xy 304.73396 -103.7082) (xy 302.120808 -104.28986) (xy 292.481 -102.362)
				(xy 286.766 -103.505)
			)
		)
	)
	(zone
		(net "GND")
		(layer "B.Cu")
		(hatch none 0.5)
		(connect_pads
			(clearance 0.5)
		)
		(min_thickness 0.25)
		(fill yes
			(thermal_gap 0.5)
			(thermal_bridge_width 0.5)
			(island_removal_mode 0)
		)
		(polygon
			(pts
				(xy 416.4838 -76.4032) (xy 417.4871 -76.4032) (xy 418.0586 -76.9747) (xy 418.0967 -77.0128) (xy 419.7223 -77.0128)
				(xy 419.7604 -76.9747) (xy 420.0398 -76.6953) (xy 420.0398 -76.2762) (xy 420.243 -76.073) (xy 421.2971 -76.073)
				(xy 421.513 -76.2889) (xy 421.513 -76.4032) (xy 421.513 -77.7494) (xy 420.9669 -78.2955) (xy 419.6588 -78.2955)
				(xy 419.405054 -78.041754) (xy 416.800792 -78.041754) (xy 416.366452 -77.607414) (xy 416.3187 -77.559662)
				(xy 416.3187 -76.5683) (xy 416.3187 -76.4413) (xy 416.3568 -76.4032)
			)
		)
	)
	(zone
		(layer "B.Cu")
		(hatch none 0.5)
		(connect_pads
			(clearance 0)
		)
		(min_thickness 0.25)
		(keepout
			(tracks allowed)
			(vias allowed)
			(pads allowed)
			(copperpour allowed)
			(footprints not_allowed)
		)
		(placement
			(enabled no)
			(sheetname "")
		)
		(fill
			(thermal_gap 0.5)
			(thermal_bridge_width 0.5)
			(island_removal_mode 0)
		)
		(polygon
			(pts
				(arc
					(start 318.000126 -57.090056)
					(mid 320.540126 -54.550056)
					(end 318.000126 -52.010056)
				)
				(arc
					(start 318.000126 -52.010056)
					(mid 315.460126 -54.550056)
					(end 318.000126 -57.090056)
				)
			)
		)
	)
	(zone
		(net "GND")
		(layer "B.Cu")
		(hatch none 0.5)
		(connect_pads
			(clearance 0.5)
		)
		(min_thickness 0.25)
		(fill yes
			(thermal_gap 0.5)
			(thermal_bridge_width 0.5)
			(island_removal_mode 0)
		)
		(polygon
			(pts
				(xy 412.0642 -128.905) (xy 411.988 -128.9812) (xy 411.988 -130.9878) (xy 412.0134 -131.0132) (xy 413.3088 -131.0132)
				(xy 413.5374 -130.7846) (xy 413.5374 -129.032) (xy 413.4104 -128.905)
			)
		)
		(polygon
			(pts
				(xy 412.9786 -129.6924) (xy 412.7754 -129.6924) (xy 412.7754 -129.8956) (xy 412.9786 -129.8956)
			)
		)
		(polygon
			(pts
				(xy 412.9786 -130.1242) (xy 412.7754 -130.1242) (xy 412.7754 -130.3274) (xy 412.9786 -130.3274)
			)
		)
	)
	(zone
		(layer "B.Cu")
		(hatch none 0.5)
		(connect_pads
			(clearance 0)
		)
		(min_thickness 0.25)
		(keepout
			(tracks allowed)
			(vias allowed)
			(pads allowed)
			(copperpour allowed)
			(footprints allowed)
		)
		(placement
			(enabled no)
			(sheetname "")
		)
		(fill
			(thermal_gap 0.5)
			(thermal_bridge_width 0.5)
			(island_removal_mode 0)
		)
		(polygon
			(pts
				(xy 187.203588 -24.958802) (xy 187.203588 -47.23892) (xy 156.360876 -52.156614) (xy 149.85746 -52.156614)
				(xy 149.850348 -52.163726) (xy 148.770848 -51.084226) (xy 148.770848 -27.745944) (xy 175.834294 -22.663404)
			)
		)
	)
	(zone
		(layer "B.Cu")
		(hatch none 0.5)
		(connect_pads
			(clearance 0)
		)
		(min_thickness 0.25)
		(keepout
			(tracks allowed)
			(vias allowed)
			(pads allowed)
			(copperpour allowed)
			(footprints not_allowed)
		)
		(placement
			(enabled no)
			(sheetname "")
		)
		(fill
			(thermal_gap 0.5)
			(thermal_bridge_width 0.5)
			(island_removal_mode 0)
		)
		(polygon
			(pts
				(arc
					(start 369.48999 -84.309966)
					(mid 367.89995 -85.900006)
					(end 369.48999 -87.490046)
				)
				(arc
					(start 369.48999 -87.490046)
					(mid 371.08003 -85.900006)
					(end 369.48999 -84.309966)
				)
			)
		)
	)
	(zone
		(layer "B.Cu")
		(hatch none 0.5)
		(connect_pads
			(clearance 0)
		)
		(min_thickness 0.25)
		(keepout
			(tracks allowed)
			(vias allowed)
			(pads allowed)
			(copperpour allowed)
			(footprints allowed)
		)
		(placement
			(enabled no)
			(sheetname "")
		)
		(fill
			(thermal_gap 0.5)
			(thermal_bridge_width 0.5)
			(island_removal_mode 0)
		)
		(polygon
			(pts
				(xy 335.661 -84.10956) (xy 335.661 -82.80146) (xy 336.31886 -82.80146) (xy 336.31886 -84.10956)
			)
		)
	)
	(zone
		(layer "B.Cu")
		(hatch none 0.5)
		(connect_pads
			(clearance 0)
		)
		(min_thickness 0.25)
		(keepout
			(tracks not_allowed)
			(vias allowed)
			(pads allowed)
			(copperpour not_allowed)
			(footprints allowed)
		)
		(placement
			(enabled no)
			(sheetname "")
		)
		(fill
			(thermal_gap 0.5)
			(thermal_bridge_width 0.5)
			(island_removal_mode 0)
		)
		(polygon
			(pts
				(xy 12.863068 -30.84195) (xy 13.168376 -31.147258)
				(arc
					(start 13.168376 -31.175198)
					(mid 13.109999 -31.698923)
					(end 13.005816 -31.18231)
				)
				(xy 12.805156 -30.98165) (xy 12.714986 -30.98165)
				(arc
					(start 12.714986 -31.432246)
					(mid 13.098399 -31.81604)
					(end 13.482066 -31.4325)
				)
				(arc
					(start 13.482066 -30.1625)
					(mid 13.098526 -29.77896)
					(end 12.714986 -30.1625)
				)
				(xy 12.714986 -30.60065) (xy 12.886944 -30.60065) (xy 13.028676 -30.458918)
				(arc
					(start 13.028676 -30.419802)
					(mid 13.098526 -29.895885)
					(end 13.168376 -30.419802)
				)
				(xy 13.168376 -30.51683) (xy 12.944856 -30.74035) (xy 12.714986 -30.74035) (xy 12.714986 -30.84195)
			)
		)
	)
	(zone
		(net "P1V8_MCP_CPU0")
		(layer "B.Cu")
		(hatch none 0.5)
		(connect_pads
			(clearance 0.5)
		)
		(min_thickness 0.25)
		(fill yes
			(thermal_gap 0.5)
			(thermal_bridge_width 0.5)
			(island_removal_mode 0)
		)
		(polygon
			(pts
				(xy 324.826376 -37.987224) (xy 324.38848 -37.987224) (xy 324.069456 -37.6682) (xy 321.578986 -37.6682)
				(arc
					(start 321.568064 -37.673534)
					(mid 321.402456 -37.712817)
					(end 321.236848 -37.673534)
				)
				(xy 321.225926 -37.6682) (xy 320.943986 -37.6682)
				(arc
					(start 320.933064 -37.673534)
					(mid 320.767456 -37.712817)
					(end 320.601848 -37.673534)
				)
				(xy 320.590926 -37.6682) (xy 318.236092 -37.6682) (xy 316.22619 -39.678102) (xy 311.577736 -39.678102)
				(xy 311.277 -39.978838) (xy 311.277 -47.02556) (xy 311.54116 -47.28972) (xy 315.653166 -47.28972)
				(xy 319.517776 -43.42511) (xy 326.248014 -43.42511)
				(arc
					(start 326.259444 -43.390312)
					(mid 326.58697 -42.930151)
					(end 327.117456 -42.736262)
				)
				(xy 327.137014 -42.735246) (xy 327.414382 -42.457878) (xy 332.156562 -42.457878)
				(arc
					(start 332.308454 -42.305986)
					(mid 332.338218 -42.232668)
					(end 332.306422 -42.16019)
				)
				(arc
					(start 332.306422 -42.16019)
					(mid 332.298952 -41.631512)
					(end 332.82763 -41.638982)
				)
				(arc
					(start 332.82763 -41.638982)
					(mid 332.900107 -41.670819)
					(end 332.973426 -41.641014)
				)
				(xy 334.059784 -40.554656) (xy 334.059784 -37.745924) (xy 333.88046 -37.5666) (xy 330.562204 -37.5666)
				(xy 330.073 -37.077396) (xy 325.736204 -37.077396)
			)
		)
		(polygon
			(pts
				(xy 333.316326 -39.933118) (xy 333.113126 -39.933118) (xy 333.113126 -40.136318) (xy 333.316326 -40.136318)
			)
		)
		(polygon
			(pts
				(xy 333.316326 -38.653466) (xy 333.113126 -38.653466) (xy 333.113126 -39.145718) (xy 333.316326 -39.145718)
			)
		)
	)
	(zone
		(layer "B.Cu")
		(hatch none 0.5)
		(connect_pads
			(clearance 0)
		)
		(min_thickness 0.25)
		(keepout
			(tracks allowed)
			(vias allowed)
			(pads allowed)
			(copperpour allowed)
			(footprints not_allowed)
		)
		(placement
			(enabled no)
			(sheetname "")
		)
		(fill
			(thermal_gap 0.5)
			(thermal_bridge_width 0.5)
			(island_removal_mode 0)
		)
		(polygon
			(pts
				(arc
					(start 275.782786 -85.749892)
					(mid 276.049924 -85.713541)
					(end 276.297644 -85.607144)
				)
				(arc
					(start 282.064968 -82.141822)
					(mid 282.420312 -81.77704)
					(end 282.550108 -81.284572)
				)
				(arc
					(start 282.550108 -71.816214)
					(mid 282.420436 -71.323675)
					(end 282.064968 -70.958964)
				)
				(arc
					(start 276.304756 -67.497706)
					(mid 276.056908 -67.391313)
					(end 275.789644 -67.354958)
				)
				(arc
					(start 264.211562 -67.354196)
					(mid 263.944278 -67.390649)
					(end 263.69645 -67.497198)
				)
				(arc
					(start 257.934968 -70.958964)
					(mid 257.579624 -71.323746)
					(end 257.450082 -71.816214)
				)
				(arc
					(start 257.450082 -81.284572)
					(mid 257.579721 -81.776986)
					(end 257.934968 -82.141822)
				)
				(arc
					(start 263.702292 -85.607144)
					(mid 263.950135 -85.713564)
					(end 264.217404 -85.749892)
				)
			)
		)
	)
	(zone
		(net "GND")
		(layer "B.Cu")
		(hatch none 0.5)
		(connect_pads
			(clearance 0.5)
		)
		(min_thickness 0.25)
		(fill yes
			(thermal_gap 0.5)
			(thermal_bridge_width 0.5)
			(island_removal_mode 0)
		)
		(polygon
			(pts
				(xy 278.01189 -82.51571) (xy 281.194256 -82.51571) (xy 281.839162 -81.870804) (xy 282.198572 -81.870804)
				(xy 282.261818 -81.807558) (xy 282.261818 -81.342484) (xy 282.2194 -81.300066) (xy 280.126694 -81.300066)
				(xy 279.704038 -80.87741) (xy 261.986522 -80.87741) (xy 261.9502 -80.913732) (xy 261.9502 -80.9752)
				(xy 261.9502 -82.3468) (xy 262.4328 -82.8294) (xy 262.9916 -82.8294) (xy 263.525 -83.3628) (xy 263.525 -84.201)
				(xy 263.7028 -84.3788) (xy 264.5664 -84.3788) (xy 264.8204 -84.1248) (xy 265.1506 -83.7946) (xy 275.502624 -83.7946)
				(xy 275.655024 -83.6422) (xy 275.8694 -83.427824) (xy 276.036024 -83.2612) (xy 277.2664 -83.2612)
			)
		)
	)
	(zone
		(layer "B.Cu")
		(hatch none 0.5)
		(connect_pads
			(clearance 0)
		)
		(min_thickness 0.25)
		(keepout
			(tracks not_allowed)
			(vias allowed)
			(pads allowed)
			(copperpour not_allowed)
			(footprints allowed)
		)
		(placement
			(enabled no)
			(sheetname "")
		)
		(fill
			(thermal_gap 0.5)
			(thermal_bridge_width 0.5)
			(island_removal_mode 0)
		)
		(polygon
			(pts
				(xy 344.776806 -59.733434) (xy 344.268806 -59.733434) (xy 344.268806 -60.114434) (xy 344.776806 -60.114434)
			)
		)
	)
	(zone
		(layer "B.Cu")
		(hatch none 0.5)
		(connect_pads
			(clearance 0)
		)
		(min_thickness 0.25)
		(keepout
			(tracks not_allowed)
			(vias allowed)
			(pads allowed)
			(copperpour not_allowed)
			(footprints allowed)
		)
		(placement
			(enabled no)
			(sheetname "")
		)
		(fill
			(thermal_gap 0.5)
			(thermal_bridge_width 0.5)
			(island_removal_mode 0)
		)
		(polygon
			(pts
				(xy 462.628742 -114.787172) (xy 462.628742 -114.511074) (xy 462.806034 -114.333782)
				(arc
					(start 462.977738 -114.333782)
					(mid 463.501655 -114.403632)
					(end 462.977738 -114.473482)
				)
				(xy 462.863946 -114.473482) (xy 462.768442 -114.568986) (xy 462.768442 -114.787172)
				(arc
					(start 463.23504 -114.787172)
					(mid 463.61858 -114.403632)
					(end 463.23504 -114.020092)
				)
				(arc
					(start 461.965294 -114.020092)
					(mid 461.5815 -114.403505)
					(end 461.96504 -114.787172)
				)
				(xy 462.387442 -114.787172) (xy 462.387442 -114.555778) (xy 462.305146 -114.473482)
				(arc
					(start 462.222342 -114.473482)
					(mid 461.698425 -114.403632)
					(end 462.222342 -114.333782)
				)
				(xy 462.363058 -114.333782) (xy 462.527142 -114.497866) (xy 462.527142 -114.787172)
			)
		)
	)
	(zone
		(layer "B.Cu")
		(hatch none 0.5)
		(connect_pads
			(clearance 0)
		)
		(min_thickness 0.25)
		(keepout
			(tracks allowed)
			(vias allowed)
			(pads allowed)
			(copperpour allowed)
			(footprints not_allowed)
		)
		(placement
			(enabled no)
			(sheetname "")
		)
		(fill
			(thermal_gap 0.5)
			(thermal_bridge_width 0.5)
			(island_removal_mode 0)
		)
		(polygon
			(pts
				(arc
					(start 2.830068 0)
					(mid 0 2.830068)
					(end -2.830068 0)
				)
				(arc
					(start -2.830068 0)
					(mid 0 -2.830068)
					(end 2.830068 0)
				)
			)
		)
	)
	(zone
		(layer "B.Cu")
		(hatch none 0.5)
		(connect_pads
			(clearance 0)
		)
		(min_thickness 0.25)
		(keepout
			(tracks allowed)
			(vias allowed)
			(pads allowed)
			(copperpour allowed)
			(footprints allowed)
		)
		(placement
			(enabled no)
			(sheetname "")
		)
		(fill
			(thermal_gap 0.5)
			(thermal_bridge_width 0.5)
			(island_removal_mode 0)
		)
		(polygon
			(pts
				(xy 348.6404 -85.471) (xy 349.377 -85.471) (xy 349.377 -84.455) (xy 349.631 -84.201) (xy 350.266 -84.201)
				(xy 350.7232 -84.6582) (xy 350.7232 -85.471) (xy 350.7232 -89.5604) (xy 348.6404 -89.5604)
			)
		)
	)
	(zone
		(net "GND")
		(layer "B.Cu")
		(hatch none 0.5)
		(connect_pads
			(clearance 0.5)
		)
		(min_thickness 0.25)
		(fill yes
			(thermal_gap 0.5)
			(thermal_bridge_width 0.5)
			(island_removal_mode 0)
		)
		(polygon
			(pts
				(xy 468.135208 -38.874192) (xy 467.8426 -39.1668) (xy 467.8426 -40.5765) (xy 467.8934 -40.6273)
				(xy 469.0745 -40.6273) (xy 469.2142 -40.4876) (xy 471.3097 -40.4876) (xy 471.5764 -40.2209) (xy 471.5764 -39.0017)
				(xy 471.448892 -38.874192)
			)
		)
		(polygon
			(pts
				(xy 468.757 -39.6367) (xy 468.5538 -39.6367) (xy 468.5538 -39.8399) (xy 468.757 -39.8399)
			)
		)
	)
	(zone
		(layer "B.Cu")
		(hatch none 0.5)
		(connect_pads
			(clearance 0)
		)
		(min_thickness 0.25)
		(keepout
			(tracks allowed)
			(vias allowed)
			(pads allowed)
			(copperpour allowed)
			(footprints not_allowed)
		)
		(placement
			(enabled no)
			(sheetname "")
		)
		(fill
			(thermal_gap 0.5)
			(thermal_bridge_width 0.5)
			(island_removal_mode 0)
		)
		(polygon
			(pts
				(arc
					(start 69.096128 -33.299908)
					(mid 65.479222 -27.591736)
					(end 61.861954 -33.299908)
				)
			)
		)
	)
	(zone
		(layer "B.Cu")
		(hatch none 0.5)
		(connect_pads
			(clearance 0)
		)
		(min_thickness 0.25)
		(keepout
			(tracks allowed)
			(vias allowed)
			(pads allowed)
			(copperpour allowed)
			(footprints not_allowed)
		)
		(placement
			(enabled no)
			(sheetname "")
		)
		(fill
			(thermal_gap 0.5)
			(thermal_bridge_width 0.5)
			(island_removal_mode 0)
		)
		(polygon
			(pts
				(arc
					(start 471.000074 5.999988)
					(mid 467.000082 1.999996)
					(end 471.000074 -1.999996)
				)
				(arc
					(start 474.49994 -1.999996)
					(mid 478.499932 1.999996)
					(end 474.49994 5.999988)
				)
			)
		)
	)
	(zone
		(net "PVDDQ_GHJ")
		(layer "B.Cu")
		(hatch none 0.5)
		(connect_pads
			(clearance 0.5)
		)
		(min_thickness 0.25)
		(fill yes
			(thermal_gap 0.5)
			(thermal_bridge_width 0.5)
			(island_removal_mode 0)
		)
		(polygon
			(pts
				(xy 98.843592 -69.809614) (xy 100.048314 -69.809614) (xy 100.151438 -69.70649) (xy 100.151438 -69.009768)
				(xy 100.151438 -68.98386) (xy 100.455222 -68.680076) (xy 109.064044 -68.680076) (xy 109.082078 -68.662042)
				(xy 109.082078 -68.598796) (xy 109.082078 -67.692016) (xy 109.048042 -67.65798) (xy 108.639864 -67.249802)
				(xy 108.639864 -67.024504) (xy 108.503974 -66.888614) (xy 106.157014 -66.888614) (xy 101.891592 -66.888614)
				(xy 98.970592 -66.888614) (xy 98.843592 -67.015614)
			)
		)
	)
	(zone
		(net "GND")
		(layer "B.Cu")
		(hatch none 0.5)
		(connect_pads
			(clearance 0.5)
		)
		(min_thickness 0.25)
		(fill yes
			(thermal_gap 0.5)
			(thermal_bridge_width 0.5)
			(island_removal_mode 0)
		)
		(polygon
			(pts
				(xy 453.9615 -23.9141) (xy 454.5584 -23.9141) (xy 454.638664 -23.833836) (xy 454.638664 -20.565364)
				(xy 454.5076 -20.4343) (xy 453.4916 -20.4343) (xy 453.4154 -20.5105) (xy 453.4154 -21.4122) (xy 453.4154 -21.4757)
				(xy 453.8599 -21.9202) (xy 453.8599 -23.8125)
			)
		)
	)
	(zone
		(net "GND")
		(layer "B.Cu")
		(hatch none 0.5)
		(connect_pads
			(clearance 0.5)
		)
		(min_thickness 0.25)
		(fill yes
			(thermal_gap 0.5)
			(thermal_bridge_width 0.5)
			(island_removal_mode 0)
		)
		(polygon
			(pts
				(xy 401.592034 -123.4948) (xy 403.5806 -123.4948) (xy 403.7584 -123.6726) (xy 403.7584 -124.5362)
				(xy 403.4536 -124.841) (xy 403.0472 -124.841) (xy 401.79752 -124.841) (xy 401.518882 -124.562362)
				(xy 401.518882 -123.567952)
			)
		)
	)
	(zone
		(net "GND")
		(layer "B.Cu")
		(hatch none 0.5)
		(connect_pads
			(clearance 0.5)
		)
		(min_thickness 0.25)
		(fill yes
			(thermal_gap 0.5)
			(thermal_bridge_width 0.5)
			(island_removal_mode 0)
		)
		(polygon
			(pts
				(xy 424.7388 -43.3578) (xy 424.4213 -43.0403) (xy 422.802304 -43.0403) (xy 422.3004 -42.538396)
				(xy 422.3004 -41.656) (xy 422.3258 -41.6306) (xy 424.4594 -41.6306) (xy 424.7134 -41.8846) (xy 425.6786 -41.8846)
				(xy 425.8564 -42.0624) (xy 425.8564 -42.651426) (xy 426.384974 -43.18) (xy 426.384974 -43.591988)
				(xy 426.339508 -43.637708) (xy 425.018708 -43.637708)
			)
		)
	)
	(zone
		(net "P12V_MB0_SW")
		(layer "B.Cu")
		(hatch none 0.5)
		(connect_pads
			(clearance 0.5)
		)
		(min_thickness 0.25)
		(fill yes
			(thermal_gap 0.5)
			(thermal_bridge_width 0.5)
			(island_removal_mode 0)
		)
		(polygon
			(pts
				(xy 11.4808 -67.7164) (xy 18.693892 -67.7164) (xy 19.038824 -67.7164) (xy 19.366992 -67.388232)
				(xy 19.366992 -57.369202) (xy 19.057112 -57.059322) (xy 18.71599 -56.7182) (xy 11.8364 -56.7182)
				(xy 10.6934 -57.8612) (xy 10.6934 -63.9826) (xy 10.795 -64.0842) (xy 14.097 -64.0842) (xy 14.351 -64.3382)
				(xy 14.351 -65.6082) (xy 14.224 -65.7352) (xy 10.795 -65.7352) (xy 10.668 -65.8622) (xy 10.668 -66.9036)
			)
		)
	)
	(zone
		(layer "B.Cu")
		(hatch none 0.5)
		(connect_pads
			(clearance 0)
		)
		(min_thickness 0.25)
		(keepout
			(tracks not_allowed)
			(vias allowed)
			(pads allowed)
			(copperpour not_allowed)
			(footprints allowed)
		)
		(placement
			(enabled no)
			(sheetname "")
		)
		(fill
			(thermal_gap 0.5)
			(thermal_bridge_width 0.5)
			(island_removal_mode 0)
		)
		(polygon
			(pts
				(arc
					(start 291.999924 -113.450116)
					(mid 293.899844 -111.550196)
					(end 291.999924 -109.650022)
				)
				(arc
					(start 291.999924 -109.650022)
					(mid 290.09975 -111.550196)
					(end 291.999924 -113.450116)
				)
			)
		)
	)
	(zone
		(layer "B.Cu")
		(hatch none 0.5)
		(connect_pads
			(clearance 0)
		)
		(min_thickness 0.25)
		(keepout
			(tracks allowed)
			(vias allowed)
			(pads allowed)
			(copperpour allowed)
			(footprints not_allowed)
		)
		(placement
			(enabled no)
			(sheetname "")
		)
		(fill
			(thermal_gap 0.5)
			(thermal_bridge_width 0.5)
			(island_removal_mode 0)
		)
		(polygon
			(pts
				(arc
					(start 294.094916 -84.549996)
					(mid 293.635306 -84.740372)
					(end 293.44493 -85.199982)
				)
				(arc
					(start 293.44493 -89.549986)
					(mid 293.635306 -90.009596)
					(end 294.094916 -90.199972)
				)
				(arc
					(start 295.794938 -90.199972)
					(mid 296.254548 -90.009596)
					(end 296.444924 -89.549986)
				)
				(arc
					(start 296.444924 -85.199982)
					(mid 296.254548 -84.740372)
					(end 295.794938 -84.549996)
				)
			)
		)
	)
	(zone
		(layer "B.Cu")
		(hatch none 0.5)
		(connect_pads
			(clearance 0)
		)
		(min_thickness 0.25)
		(keepout
			(tracks not_allowed)
			(vias allowed)
			(pads allowed)
			(copperpour not_allowed)
			(footprints allowed)
		)
		(placement
			(enabled no)
			(sheetname "")
		)
		(fill
			(thermal_gap 0.5)
			(thermal_bridge_width 0.5)
			(island_removal_mode 0)
		)
		(polygon
			(pts
				(arc
					(start 127 -43.450002)
					(mid 128.89992 -41.550082)
					(end 127 -39.649908)
				)
				(arc
					(start 127 -39.649908)
					(mid 125.099826 -41.550082)
					(end 127 -43.450002)
				)
			)
		)
	)
	(zone
		(layer "B.Cu")
		(hatch none 0.5)
		(connect_pads
			(clearance 0)
		)
		(min_thickness 0.25)
		(keepout
			(tracks not_allowed)
			(vias allowed)
			(pads allowed)
			(copperpour not_allowed)
			(footprints allowed)
		)
		(placement
			(enabled no)
			(sheetname "")
		)
		(fill
			(thermal_gap 0.5)
			(thermal_bridge_width 0.5)
			(island_removal_mode 0)
		)
		(polygon
			(pts
				(arc
					(start 431.888646 -138.461242)
					(mid 431.504852 -138.844655)
					(end 431.888392 -139.228322)
				)
				(arc
					(start 432.48199 -139.228322)
					(mid 432.474679 -139.191484)
					(end 432.47056 -139.154154)
				)
				(xy 432.469544 -139.153138)
				(arc
					(start 432.469544 -138.971782)
					(mid 432.452805 -138.931371)
					(end 432.412394 -138.914632)
				)
				(arc
					(start 432.145694 -138.914632)
					(mid 431.621777 -138.844782)
					(end 432.145694 -138.774932)
				)
				(xy 432.44135 -138.774932)
				(arc
					(start 432.44389 -138.777472)
					(mid 432.551585 -138.832591)
					(end 432.606704 -138.940286)
				)
				(xy 432.609244 -138.942826)
				(arc
					(start 432.609244 -139.124436)
					(mid 432.613995 -139.177221)
					(end 432.62804 -139.228322)
				)
				(arc
					(start 432.740816 -139.228322)
					(mid 432.723644 -139.193602)
					(end 432.713638 -139.156186)
				)
				(xy 432.710844 -139.153392) (xy 432.710844 -138.942826)
				(arc
					(start 432.713384 -138.940286)
					(mid 432.768503 -138.832591)
					(end 432.876198 -138.777472)
				)
				(xy 432.878738 -138.774932)
				(arc
					(start 432.90109 -138.774932)
					(mid 433.425073 -138.845036)
					(end 432.90109 -138.91514)
				)
				(arc
					(start 432.90109 -138.91514)
					(mid 432.864951 -138.93379)
					(end 432.850544 -138.971782)
				)
				(xy 432.850544 -139.094972) (xy 432.850798 -139.095226) (xy 432.850798 -139.124182)
				(arc
					(start 432.850798 -139.12469)
					(mid 432.855196 -139.146424)
					(end 432.867562 -139.164822)
				)
				(xy 432.931062 -139.228322)
				(arc
					(start 433.158392 -139.228322)
					(mid 433.541932 -138.844782)
					(end 433.158392 -138.461242)
				)
			)
		)
	)
	(zone
		(net "GND")
		(layer "B.Cu")
		(hatch none 0.5)
		(connect_pads
			(clearance 0.5)
		)
		(min_thickness 0.25)
		(fill yes
			(thermal_gap 0.5)
			(thermal_bridge_width 0.5)
			(island_removal_mode 0)
		)
		(polygon
			(pts
				(xy 393.939268 -153.110946) (xy 393.939268 -151.701754) (xy 394.033502 -151.60752) (xy 397.09852 -151.60752)
				(xy 397.730726 -152.239726) (xy 397.730726 -153.8224) (xy 397.721328 -153.831544) (xy 397.730726 -153.840942)
				(xy 397.730726 -155.160726) (xy 397.730726 -155.471622) (xy 397.51127 -155.691078) (xy 396.24 -155.691078)
				(xy 395.107922 -154.559) (xy 394.143484 -154.559) (xy 394.01115 -154.426666) (xy 394.01115 -153.182828)
			)
		)
	)
	(zone
		(layer "B.Cu")
		(hatch none 0.5)
		(connect_pads
			(clearance 0)
		)
		(min_thickness 0.25)
		(keepout
			(tracks not_allowed)
			(vias allowed)
			(pads allowed)
			(copperpour not_allowed)
			(footprints allowed)
		)
		(placement
			(enabled no)
			(sheetname "")
		)
		(fill
			(thermal_gap 0.5)
			(thermal_bridge_width 0.5)
			(island_removal_mode 0)
		)
		(polygon
			(pts
				(arc
					(start 497.320062 -28.919932)
					(mid 498.920262 -30.520132)
					(end 497.320062 -32.120078)
				)
				(arc
					(start 495.720116 -32.120078)
					(mid 494.12017 -30.520132)
					(end 495.720116 -28.919932)
				)
			)
		)
	)
	(zone
		(layer "B.Cu")
		(hatch none 0.5)
		(connect_pads
			(clearance 0)
		)
		(min_thickness 0.25)
		(keepout
			(tracks allowed)
			(vias allowed)
			(pads allowed)
			(copperpour allowed)
			(footprints not_allowed)
		)
		(placement
			(enabled no)
			(sheetname "")
		)
		(fill
			(thermal_gap 0.5)
			(thermal_bridge_width 0.5)
			(island_removal_mode 0)
		)
		(polygon
			(pts
				(arc
					(start 56.999886 -79.090012)
					(mid 59.539886 -76.550012)
					(end 56.999886 -74.010012)
				)
				(arc
					(start 56.999886 -74.010012)
					(mid 54.459886 -76.550012)
					(end 56.999886 -79.090012)
				)
			)
		)
	)
	(zone
		(layer "B.Cu")
		(hatch none 0.5)
		(connect_pads
			(clearance 0)
		)
		(min_thickness 0.25)
		(keepout
			(tracks not_allowed)
			(vias allowed)
			(pads allowed)
			(copperpour not_allowed)
			(footprints allowed)
		)
		(placement
			(enabled no)
			(sheetname "")
		)
		(fill
			(thermal_gap 0.5)
			(thermal_bridge_width 0.5)
			(island_removal_mode 0)
		)
		(polygon
			(pts
				(arc
					(start 369.48999 -87.490046)
					(mid 371.08003 -85.900006)
					(end 369.48999 -84.309966)
				)
				(arc
					(start 369.48999 -84.309966)
					(mid 367.89995 -85.900006)
					(end 369.48999 -87.490046)
				)
			)
		)
	)
	(zone
		(net "GND")
		(layer "B.Cu")
		(hatch none 0.5)
		(connect_pads
			(clearance 0.5)
		)
		(min_thickness 0.25)
		(fill yes
			(thermal_gap 0.5)
			(thermal_bridge_width 0.5)
			(island_removal_mode 0)
		)
		(polygon
			(pts
				(xy 169.926 -2.159) (xy 169.7482 -2.3368) (xy 169.7482 -2.6416) (xy 170.0022 -2.8956) (xy 170.0022 -5.0038)
				(xy 169.545 -5.461) (xy 169.545 -5.9182) (xy 169.8371 -6.2103) (xy 172.4279 -6.2103) (xy 172.4914 -6.1468)
				(xy 172.4914 -5.1435) (xy 171.5008 -4.1529) (xy 171.5008 -2.3368) (xy 171.323 -2.159)
			)
		)
		(polygon
			(pts
				(xy 171.7548 -5.830824) (xy 171.5516 -5.830824) (xy 171.5516 -6.034024) (xy 171.7548 -6.034024)
			)
		)
		(polygon
			(pts
				(xy 171.7548 -5.068824) (xy 171.5516 -5.068824) (xy 171.5516 -5.272024) (xy 171.7548 -5.272024)
			)
		)
		(polygon
			(pts
				(xy 170.9801 -4.9784) (xy 170.7769 -4.9784) (xy 170.7769 -5.1816) (xy 170.9801 -5.1816)
			)
		)
		(polygon
			(pts
				(xy 170.9801 -4.2164) (xy 170.7769 -4.2164) (xy 170.7769 -4.4196) (xy 170.9801 -4.4196)
			)
		)
		(polygon
			(pts
				(xy 170.9801 -3.7338) (xy 170.7769 -3.7338) (xy 170.7769 -3.937) (xy 170.9801 -3.937)
			)
		)
		(polygon
			(pts
				(xy 170.9801 -2.9718) (xy 170.7769 -2.9718) (xy 170.7769 -3.175) (xy 170.9801 -3.175)
			)
		)
	)
	(zone
		(layer "B.Cu")
		(hatch none 0.5)
		(connect_pads
			(clearance 0)
		)
		(min_thickness 0.25)
		(keepout
			(tracks allowed)
			(vias allowed)
			(pads allowed)
			(copperpour allowed)
			(footprints allowed)
		)
		(placement
			(enabled no)
			(sheetname "")
		)
		(fill
			(thermal_gap 0.5)
			(thermal_bridge_width 0.5)
			(island_removal_mode 0)
		)
		(polygon
			(pts
				(xy 187.203588 -47.23892) (xy 198.467218 -43.922442) (xy 201.936096 -45.158914) (xy 205.039976 -47.960788)
				(xy 205.13802 -48.058832) (xy 210.977226 -48.058832) (xy 210.977226 -25.95753) (xy 210.952588 -25.95753)
				(xy 210.952588 -25.960324) (xy 210.04149 -25.960324) (xy 193.839338 -26.028904) (xy 187.206636 -24.955754)
				(xy 187.203588 -24.958802)
			)
		)
	)
	(zone
		(net "PVDDQ_KLM")
		(layer "B.Cu")
		(hatch none 0.5)
		(connect_pads
			(clearance 0.5)
		)
		(min_thickness 0.25)
		(fill yes
			(thermal_gap 0.5)
			(thermal_bridge_width 0.5)
			(island_removal_mode 0)
		)
		(polygon
			(pts
				(xy 79.21244 -124.650754) (xy 78.956154 -124.90704) (xy 78.956154 -126.96825) (xy 79.166974 -127.17907)
				(xy 81.152746 -127.17907) (xy 81.341722 -126.990094) (xy 81.341722 -124.889006) (xy 81.10347 -124.650754)
			)
		)
		(polygon
			(pts
				(xy 80.096868 -126.2761) (xy 79.893668 -126.2761) (xy 79.893668 -126.4793) (xy 80.096868 -126.4793)
			)
		)
		(polygon
			(pts
				(xy 80.47228 -126.04115) (xy 80.26908 -126.04115) (xy 80.26908 -126.24435) (xy 80.47228 -126.24435)
			)
		)
		(polygon
			(pts
				(xy 80.096868 -125.2855) (xy 79.893668 -125.2855) (xy 79.893668 -125.4887) (xy 80.096868 -125.4887)
			)
		)
		(polygon
			(pts
				(xy 80.47228 -125.05055) (xy 80.26908 -125.05055) (xy 80.26908 -125.25375) (xy 80.47228 -125.25375)
			)
		)
	)
	(zone
		(layer "B.Cu")
		(hatch none 0.5)
		(connect_pads
			(clearance 0)
		)
		(min_thickness 0.25)
		(keepout
			(tracks allowed)
			(vias allowed)
			(pads allowed)
			(copperpour allowed)
			(footprints allowed)
		)
		(placement
			(enabled no)
			(sheetname "")
		)
		(fill
			(thermal_gap 0.5)
			(thermal_bridge_width 0.5)
			(island_removal_mode 0)
		)
		(polygon
			(pts
				(xy 474.788484 -124.897388) (xy 474.788484 -122.593862) (xy 476.61703 -122.593862) (xy 476.61703 -124.897388)
			)
		)
	)
	(zone
		(layer "B.Cu")
		(hatch none 0.5)
		(connect_pads
			(clearance 0)
		)
		(min_thickness 0.25)
		(keepout
			(tracks allowed)
			(vias allowed)
			(pads allowed)
			(copperpour allowed)
			(footprints allowed)
		)
		(placement
			(enabled no)
			(sheetname "")
		)
		(fill
			(thermal_gap 0.5)
			(thermal_bridge_width 0.5)
			(island_removal_mode 0)
		)
		(polygon
			(pts
				(xy 254.508 -102.87) (xy 254.508 -124.46) (xy 260.731 -123.19) (xy 278.257 -126.619) (xy 283.083 -125.73)
				(xy 283.083 -106.807) (xy 278.892 -107.696)
			)
		)
	)
	(zone
		(net "GND")
		(layer "B.Cu")
		(hatch none 0.5)
		(connect_pads
			(clearance 0.5)
		)
		(min_thickness 0.25)
		(fill yes
			(thermal_gap 0.5)
			(thermal_bridge_width 0.5)
			(island_removal_mode 0)
		)
		(polygon
			(pts
				(xy 242.195604 -9.496806) (xy 243.13388 -9.496806) (xy 243.463826 -9.16686) (xy 243.463826 -7.12851)
				(xy 243.107972 -6.772656) (xy 242.221258 -6.772656) (xy 241.859054 -7.13486) (xy 241.859054 -7.416546)
				(xy 241.173 -8.1026) (xy 241.173 -9.2456) (xy 241.422428 -9.495028) (xy 242.193572 -9.495028)
			)
		)
	)
	(zone
		(layer "B.Cu")
		(hatch none 0.5)
		(connect_pads
			(clearance 0)
		)
		(min_thickness 0.25)
		(keepout
			(tracks not_allowed)
			(vias allowed)
			(pads allowed)
			(copperpour not_allowed)
			(footprints allowed)
		)
		(placement
			(enabled no)
			(sheetname "")
		)
		(fill
			(thermal_gap 0.5)
			(thermal_bridge_width 0.5)
			(island_removal_mode 0)
		)
		(polygon
			(pts
				(xy 384.684016 -23.800054) (xy 384.757168 -23.800054) (xy 384.771646 -23.636224) (xy 384.771392 -23.63597)
				(arc
					(start 384.769106 -23.635716)
					(mid 384.420872 -23.219918)
					(end 384.005074 -23.568152)
				)
				(xy 384.002534 -23.567898) (xy 383.920746 -24.488648)
				(arc
					(start 383.923286 -24.488902)
					(mid 384.111948 -24.853882)
					(end 384.522472 -24.83866)
				)
				(arc
					(start 384.43789 -24.754078)
					(mid 384.116725 -24.334107)
					(end 384.536696 -24.655272)
				)
				(arc
					(start 384.621278 -24.739854)
					(mid 384.666155 -24.652428)
					(end 384.687318 -24.556466)
				)
				(xy 384.689858 -24.55672) (xy 384.744722 -23.939754) (xy 384.626104 -23.939754)
				(arc
					(start 384.519678 -23.833328)
					(mid 384.198513 -23.413357)
					(end 384.618484 -23.734522)
				)
			)
		)
	)
	(zone
		(net "P3V3_STBY")
		(layer "B.Cu")
		(hatch none 0.5)
		(connect_pads
			(clearance 0.5)
		)
		(min_thickness 0.25)
		(fill yes
			(thermal_gap 0.5)
			(thermal_bridge_width 0.5)
			(island_removal_mode 0)
		)
		(polygon
			(pts
				(xy 7.3914 -131.3688) (xy 7.3914 -131.99872) (xy 7.438898 -132.046218) (xy 8.251698 -132.046218)
				(xy 8.403844 -132.198364) (xy 8.403844 -133.208014) (xy 7.728458 -133.8834) (xy 5.7912 -133.8834)
				(xy 1.3208 -133.8834) (xy 1.0922 -133.8834) (xy 0.3556 -134.62) (xy -3.8354 -134.62) (xy -5.3594 -133.096)
				(xy -5.3594 -129.7178) (xy -5.08 -129.4384) (xy -3.9878 -129.4384) (xy -3.5814 -129.8448) (xy -3.5814 -130.429)
				(xy -3.683 -130.5306) (xy -4.064 -130.5306) (xy -4.3942 -130.8608) (xy -4.3942 -132.0292) (xy -3.5814 -132.842)
				(xy -0.508 -132.842) (xy -0.381 -132.715) (xy -0.381 -132.207) (xy -0.254 -132.08) (xy 0.127 -132.08)
				(xy 0.381 -131.826) (xy 0.381 -130.81) (xy 0.7366 -130.4544) (xy 2.6416 -130.4544) (xy 5.2578 -130.4544)
				(xy 5.969 -131.1656) (xy 6.3246 -131.1656) (xy 7.1882 -131.1656)
			)
		)
	)
	(zone
		(net "GND")
		(layer "B.Cu")
		(hatch none 0.5)
		(connect_pads
			(clearance 0.5)
		)
		(min_thickness 0.25)
		(fill yes
			(thermal_gap 0.5)
			(thermal_bridge_width 0.5)
			(island_removal_mode 0)
		)
		(polygon
			(pts
				(xy 458.765148 -23.661624) (xy 456.868276 -23.661624) (xy 456.792838 -23.737062) (xy 456.792838 -25.60701)
				(xy 456.846178 -25.66035) (xy 458.714094 -25.66035) (xy 458.86497 -25.509474) (xy 458.86497 -23.761446)
			)
		)
	)
	(zone
		(net "PVDDQ_DEF")
		(layer "B.Cu")
		(hatch none 0.5)
		(connect_pads
			(clearance 0.5)
		)
		(min_thickness 0.25)
		(fill yes
			(thermal_gap 0.5)
			(thermal_bridge_width 0.5)
			(island_removal_mode 0)
		)
		(polygon
			(pts
				(xy 243.944648 -133.965188) (xy 243.735606 -134.17423) (xy 243.735606 -136.657842) (xy 243.91112 -136.833356)
				(xy 258.602988 -136.833356) (xy 258.89077 -136.545574) (xy 259.69214 -136.545574) (xy 259.938774 -136.29894)
				(xy 259.938774 -135.045704) (xy 259.445506 -134.552436) (xy 259.034534 -134.552436) (xy 258.76758 -134.285482)
				(xy 258.76758 -134.100316) (xy 258.632452 -133.965188)
			)
		)
		(polygon
			(pts
				(xy 253.049532 -135.8011) (xy 252.846332 -135.8011) (xy 252.846332 -136.0043) (xy 253.049532 -136.0043)
			)
		)
		(polygon
			(pts
				(xy 249.4026 -135.8011) (xy 249.1994 -135.8011) (xy 249.1994 -136.0043) (xy 249.4026 -136.0043)
			)
		)
		(polygon
			(pts
				(xy 246.3038 -135.8011) (xy 246.1006 -135.8011) (xy 246.1006 -136.0043) (xy 246.3038 -136.0043)
			)
		)
		(polygon
			(pts
				(xy 258.8641 -135.7249) (xy 258.6609 -135.7249) (xy 258.6609 -135.9281) (xy 258.8641 -135.9281)
			)
		)
		(polygon
			(pts
				(xy 253.049532 -134.8105) (xy 252.846332 -134.8105) (xy 252.846332 -135.0137) (xy 253.049532 -135.0137)
			)
		)
		(polygon
			(pts
				(xy 246.3038 -134.8105) (xy 246.1006 -134.8105) (xy 246.1006 -135.0137) (xy 246.3038 -135.0137)
			)
		)
		(polygon
			(pts
				(xy 258.8641 -134.7343) (xy 258.6609 -134.7343) (xy 258.6609 -134.9375) (xy 258.8641 -134.9375)
			)
		)
	)
	(zone
		(net "P3V3_STBY")
		(layer "B.Cu")
		(hatch none 0.5)
		(connect_pads
			(clearance 0.5)
		)
		(min_thickness 0.25)
		(fill yes
			(thermal_gap 0.5)
			(thermal_bridge_width 0.5)
			(island_removal_mode 0)
		)
		(polygon
			(pts
				(xy 409.57246 -22.521418) (xy 409.481274 -22.612604) (xy 409.481274 -23.368508) (xy 409.124912 -23.72487)
				(xy 409.124912 -24.636222) (xy 409.203144 -24.714454) (xy 410.026104 -24.714454) (xy 410.154374 -24.842724)
				(xy 410.154374 -25.423876) (xy 410.29255 -25.562052) (xy 411.075886 -25.562052) (xy 411.646116 -24.992076)
				(xy 411.646116 -22.632162) (xy 411.535372 -22.521418)
			)
		)
		(polygon
			(pts
				(xy 410.463746 -23.276052) (xy 410.260546 -23.276052) (xy 410.260546 -23.479252) (xy 410.463746 -23.479252)
			)
		)
		(polygon
			(pts
				(xy 410.8196 -23.3934) (xy 410.6164 -23.3934) (xy 410.6164 -23.5966) (xy 410.8196 -23.5966)
			)
		)
		(polygon
			(pts
				(xy 411.213046 -24.546052) (xy 411.009846 -24.546052) (xy 411.009846 -24.749252) (xy 411.213046 -24.749252)
			)
		)
	)
	(zone
		(net "PVDDQ_GHJ")
		(layer "B.Cu")
		(hatch none 0.5)
		(connect_pads
			(clearance 0.5)
		)
		(min_thickness 0.25)
		(fill yes
			(thermal_gap 0.5)
			(thermal_bridge_width 0.5)
			(island_removal_mode 0)
		)
		(polygon
			(pts
				(xy 100.806504 -11.78179) (xy 106.395774 -11.78179) (xy 106.498644 -11.88466) (xy 106.498644 -12.090146)
				(xy 105.388918 -13.199872) (xy 101.279198 -13.199872) (xy 100.806504 -12.727178)
			)
		)
	)
	(zone
		(layer "B.Cu")
		(hatch none 0.5)
		(connect_pads
			(clearance 0)
		)
		(min_thickness 0.25)
		(keepout
			(tracks allowed)
			(vias allowed)
			(pads allowed)
			(copperpour allowed)
			(footprints not_allowed)
		)
		(placement
			(enabled no)
			(sheetname "")
		)
		(fill
			(thermal_gap 0.5)
			(thermal_bridge_width 0.5)
			(island_removal_mode 0)
		)
		(polygon
			(pts
				(arc
					(start 83.000088 -113.450116)
					(mid 84.900008 -111.550196)
					(end 83.000088 -109.650022)
				)
				(arc
					(start 83.000088 -109.650022)
					(mid 81.099914 -111.550196)
					(end 83.000088 -113.450116)
				)
			)
		)
	)
	(zone
		(layer "B.Cu")
		(hatch none 0.5)
		(connect_pads
			(clearance 0)
		)
		(min_thickness 0.25)
		(keepout
			(tracks not_allowed)
			(vias allowed)
			(pads allowed)
			(copperpour not_allowed)
			(footprints allowed)
		)
		(placement
			(enabled no)
			(sheetname "")
		)
		(fill
			(thermal_gap 0.5)
			(thermal_bridge_width 0.5)
			(island_removal_mode 0)
		)
		(polygon
			(pts
				(xy 344.181176 -78.329536) (xy 344.689176 -78.329536) (xy 344.689176 -77.948536) (xy 344.181176 -77.948536)
			)
		)
	)
	(zone
		(layer "B.Cu")
		(hatch none 0.5)
		(connect_pads
			(clearance 0)
		)
		(min_thickness 0.25)
		(keepout
			(tracks allowed)
			(vias allowed)
			(pads allowed)
			(copperpour allowed)
			(footprints not_allowed)
		)
		(placement
			(enabled no)
			(sheetname "")
		)
		(fill
			(thermal_gap 0.5)
			(thermal_bridge_width 0.5)
			(island_removal_mode 0)
		)
		(polygon
			(pts
				(arc
					(start 291.999924 -44.090082)
					(mid 294.539924 -41.550082)
					(end 291.999924 -39.010082)
				)
				(arc
					(start 291.999924 -39.010082)
					(mid 289.459924 -41.550082)
					(end 291.999924 -44.090082)
				)
			)
		)
	)
	(zone
		(net "PVDDQ_ABC")
		(layer "B.Cu")
		(hatch none 0.5)
		(connect_pads
			(clearance 0.5)
		)
		(min_thickness 0.25)
		(fill yes
			(thermal_gap 0.5)
			(thermal_bridge_width 0.5)
			(island_removal_mode 0)
		)
		(polygon
			(pts
				(xy 277.6982 -2.54) (xy 277.2664 -2.1082) (xy 265.743944 -2.1082) (xy 265.743944 -2.9464) (xy 266.455144 -3.6576)
				(xy 266.455144 -4.3942) (xy 266.6492 -4.588256) (xy 266.6492 -5.7912) (xy 266.7762 -5.9182) (xy 267.1318 -5.9182)
				(xy 267.267944 -5.782056) (xy 267.267944 -4.5974) (xy 267.344144 -4.5212) (xy 277.1648 -4.5212)
				(xy 277.6982 -3.9878)
			)
		)
	)
	(zone
		(net "GND")
		(layer "B.Cu")
		(hatch none 0.5)
		(connect_pads
			(clearance 0.5)
		)
		(min_thickness 0.25)
		(fill yes
			(thermal_gap 0.5)
			(thermal_bridge_width 0.5)
			(island_removal_mode 0)
		)
		(polygon
			(pts
				(xy 366.122712 -158.642558) (xy 371.865398 -158.642558) (xy 371.954298 -158.553658) (xy 371.954298 -156.481018)
				(xy 371.836188 -156.362908) (xy 366.086136 -156.362908) (xy 365.337344 -156.362908) (xy 365.145574 -156.554678)
				(xy 365.145574 -158.401766) (xy 365.386366 -158.642558)
			)
		)
	)
	(zone
		(layer "B.Cu")
		(hatch none 0.5)
		(connect_pads
			(clearance 0)
		)
		(min_thickness 0.25)
		(keepout
			(tracks not_allowed)
			(vias allowed)
			(pads allowed)
			(copperpour not_allowed)
			(footprints allowed)
		)
		(placement
			(enabled no)
			(sheetname "")
		)
		(fill
			(thermal_gap 0.5)
			(thermal_bridge_width 0.5)
			(island_removal_mode 0)
		)
		(polygon
			(pts
				(arc
					(start 127 -113.450116)
					(mid 128.89992 -111.550196)
					(end 127 -109.650022)
				)
				(arc
					(start 127 -109.650022)
					(mid 125.099826 -111.550196)
					(end 127 -113.450116)
				)
			)
		)
	)
	(zone
		(net "P3V3_STBY_MNG")
		(layer "B.Cu")
		(hatch none 0.5)
		(connect_pads
			(clearance 0.5)
		)
		(min_thickness 0.25)
		(fill yes
			(thermal_gap 0.5)
			(thermal_bridge_width 0.5)
			(island_removal_mode 0)
		)
		(polygon
			(pts
				(xy 474.451172 -25.904952) (xy 474.160596 -26.195528) (xy 474.160596 -27.437334) (xy 474.467682 -27.74442)
				(xy 475.279974 -27.74442) (xy 475.500954 -27.9654) (xy 476.831152 -27.9654) (xy 477.190816 -27.605736)
				(xy 477.190816 -26.60396) (xy 476.940118 -26.353262) (xy 476.940118 -26.025348) (xy 476.819722 -25.904952)
			)
		)
		(polygon
			(pts
				(xy 474.57106 -26.75382) (xy 474.36786 -26.75382) (xy 474.36786 -26.95702) (xy 474.57106 -26.95702)
			)
		)
	)
	(zone
		(layer "B.Cu")
		(hatch none 0.5)
		(connect_pads
			(clearance 0)
		)
		(min_thickness 0.25)
		(keepout
			(tracks allowed)
			(vias allowed)
			(pads allowed)
			(copperpour allowed)
			(footprints not_allowed)
		)
		(placement
			(enabled no)
			(sheetname "")
		)
		(fill
			(thermal_gap 0.5)
			(thermal_bridge_width 0.5)
			(island_removal_mode 0)
		)
		(polygon
			(pts
				(xy 22.519894 -9.71169) (xy 22.519894 -6.530594) (xy 163.52012 -6.530594) (xy 163.52012 -9.71169)
			)
		)
	)
	(zone
		(layer "B.Cu")
		(hatch none 0.5)
		(connect_pads
			(clearance 0)
		)
		(min_thickness 0.25)
		(keepout
			(tracks not_allowed)
			(vias allowed)
			(pads allowed)
			(copperpour not_allowed)
			(footprints allowed)
		)
		(placement
			(enabled no)
			(sheetname "")
		)
		(fill
			(thermal_gap 0.5)
			(thermal_bridge_width 0.5)
			(island_removal_mode 0)
		)
		(polygon
			(pts
				(arc
					(start 320.58991 -98.550222)
					(mid 315.410342 -98.550222)
					(end 320.58991 -98.550222)
				)
			)
		)
	)
	(zone
		(layer "B.Cu")
		(hatch none 0.5)
		(connect_pads
			(clearance 0)
		)
		(min_thickness 0.25)
		(keepout
			(tracks allowed)
			(vias allowed)
			(pads allowed)
			(copperpour allowed)
			(footprints not_allowed)
		)
		(placement
			(enabled no)
			(sheetname "")
		)
		(fill
			(thermal_gap 0.5)
			(thermal_bridge_width 0.5)
			(island_removal_mode 0)
		)
		(polygon
			(pts
				(arc
					(start 1.92913 -157.04439)
					(mid 1.338734 -156.714333)
					(end 0.672084 -156.59989)
				)
				(arc
					(start 0 -156.59989)
					(mid -1.49987 -155.10002)
					(end 0 -153.599896)
				)
				(arc
					(start 0.672084 -153.599896)
					(mid 1.338711 -153.485602)
					(end 1.92913 -153.15565)
				)
				(arc
					(start 1.92913 -153.15565)
					(mid 6.00025 -155.10002)
					(end 1.92913 -157.04439)
				)
			)
		)
	)
	(zone
		(layer "B.Cu")
		(hatch none 0.5)
		(connect_pads
			(clearance 0)
		)
		(min_thickness 0.25)
		(keepout
			(tracks allowed)
			(vias allowed)
			(pads allowed)
			(copperpour allowed)
			(footprints allowed)
		)
		(placement
			(enabled no)
			(sheetname "")
		)
		(fill
			(thermal_gap 0.5)
			(thermal_bridge_width 0.5)
			(island_removal_mode 0)
		)
		(polygon
			(pts
				(xy 363.0422 -112.2426) (xy 363.0422 -110.9726) (xy 364.744 -110.9726) (xy 364.744 -112.2426)
			)
		)
	)
	(zone
		(net "P3V3")
		(layer "B.Cu")
		(hatch none 0.5)
		(connect_pads
			(clearance 0.5)
		)
		(min_thickness 0.25)
		(fill yes
			(thermal_gap 0.5)
			(thermal_bridge_width 0.5)
			(island_removal_mode 0)
		)
		(polygon
			(pts
				(xy 480.822 -115.6716) (xy 480.9744 -115.5192) (xy 480.9744 -115.2398) (xy 481.43541 -114.77879)
				(xy 481.43541 -114.48161) (xy 481.43541 -114.24539) (xy 481.6348 -114.046) (xy 481.6348 -111.51362)
				(xy 481.2792 -111.15802) (xy 478.79 -111.15802) (xy 478.663 -111.28502) (xy 478.663 -113.95202)
				(xy 477.901 -114.71402) (xy 477.901 -115.5446) (xy 478.0534 -115.697) (xy 480.7966 -115.697)
			)
		)
	)
	(zone
		(net "GND")
		(layer "B.Cu")
		(hatch none 0.5)
		(connect_pads
			(clearance 0.5)
		)
		(min_thickness 0.25)
		(fill yes
			(thermal_gap 0.5)
			(thermal_bridge_width 0.5)
			(island_removal_mode 0)
		)
		(polygon
			(pts
				(xy 265.1252 -126.5174) (xy 264.6172 -127.0254) (xy 264.6172 -127.381) (xy 264.0076 -127.9906) (xy 263.1694 -128.8288)
				(xy 263.144 -128.8288) (xy 262.8392 -129.1336) (xy 262.6106 -129.1336) (xy 262.3566 -128.8796) (xy 262.3566 -128.8288)
				(xy 262.3566 -127.254) (xy 262.3566 -125.349) (xy 263.2456 -124.46) (xy 263.6774 -124.46) (xy 263.7282 -124.5108)
				(xy 263.7282 -124.8918) (xy 263.9314 -125.095) (xy 264.9474 -125.095) (xy 265.1252 -125.2728)
			)
		)
	)
	(zone
		(layer "B.Cu")
		(hatch none 0.5)
		(connect_pads
			(clearance 0)
		)
		(min_thickness 0.25)
		(keepout
			(tracks not_allowed)
			(vias allowed)
			(pads allowed)
			(copperpour not_allowed)
			(footprints allowed)
		)
		(placement
			(enabled no)
			(sheetname "")
		)
		(fill
			(thermal_gap 0.5)
			(thermal_bridge_width 0.5)
			(island_removal_mode 0)
		)
		(polygon
			(pts
				(arc
					(start 291.999924 -39.010082)
					(mid 289.459924 -41.550082)
					(end 291.999924 -44.090082)
				)
				(arc
					(start 291.999924 -44.090082)
					(mid 294.539924 -41.550082)
					(end 291.999924 -39.010082)
				)
			)
		)
	)
	(zone
		(net "GND")
		(layer "B.Cu")
		(hatch none 0.5)
		(connect_pads
			(clearance 0.5)
		)
		(min_thickness 0.25)
		(fill yes
			(thermal_gap 0.5)
			(thermal_bridge_width 0.5)
			(island_removal_mode 0)
		)
		(polygon
			(pts
				(xy 345.3638 -89.281) (xy 344.7796 -89.281) (xy 344.7288 -89.2302) (xy 344.7288 -85.6996) (xy 344.7796 -85.6488)
				(xy 348.2848 -85.6488) (xy 348.3483 -85.7123) (xy 348.3483 -89.281)
			)
		)
	)
	(zone
		(net "GND")
		(layer "B.Cu")
		(hatch none 0.5)
		(connect_pads
			(clearance 0.5)
		)
		(min_thickness 0.25)
		(fill yes
			(thermal_gap 0.5)
			(thermal_bridge_width 0.5)
			(island_removal_mode 0)
		)
		(polygon
			(pts
				(xy 260.647688 -144.312894) (xy 261.582662 -144.312894) (xy 261.726426 -144.456658) (xy 261.726426 -146.028664)
				(xy 261.027672 -146.727418) (xy 261.027672 -146.939) (xy 260.976872 -146.9898) (xy 260.558788 -146.9898)
				(xy 260.431788 -146.8628) (xy 260.431788 -145.905474) (xy 260.647688 -145.689574)
			)
		)
	)
	(zone
		(net "PVDDQ_ABC")
		(layer "B.Cu")
		(hatch none 0.5)
		(connect_pads
			(clearance 0.5)
		)
		(min_thickness 0.25)
		(fill yes
			(thermal_gap 0.5)
			(thermal_bridge_width 0.5)
			(island_removal_mode 0)
		)
		(polygon
			(pts
				(xy 244.4242 -2.0828) (xy 243.5606 -2.9464) (xy 243.5606 -4.2418) (xy 243.7892 -4.4704) (xy 258.191 -4.4704)
				(xy 258.56438 -4.09702) (xy 258.622038 -4.039362) (xy 258.757928 -4.039362) (xy 258.93014 -3.86715)
				(xy 260.151118 -3.86715) (xy 260.21538 -3.802888) (xy 260.21538 -2.71272) (xy 260.172962 -2.670302)
				(xy 259.273294 -2.670302) (xy 259.170678 -2.567686) (xy 259.170678 -2.56667) (xy 258.715256 -2.56667)
				(xy 258.69138 -2.542794) (xy 258.69138 -2.12598) (xy 258.6482 -2.0828)
			)
		)
		(polygon
			(pts
				(xy 253.049532 -3.6322) (xy 252.846332 -3.6322) (xy 252.846332 -3.8354) (xy 253.049532 -3.8354)
			)
		)
		(polygon
			(pts
				(xy 252.7046 -3.6322) (xy 252.5014 -3.6322) (xy 252.5014 -3.8354) (xy 252.7046 -3.8354)
			)
		)
		(polygon
			(pts
				(xy 249.4026 -3.6322) (xy 249.1994 -3.6322) (xy 249.1994 -3.8354) (xy 249.4026 -3.8354)
			)
		)
		(polygon
			(pts
				(xy 253.049532 -2.8702) (xy 252.846332 -2.8702) (xy 252.846332 -3.0734) (xy 253.049532 -3.0734)
			)
		)
		(polygon
			(pts
				(xy 252.7046 -2.8702) (xy 252.5014 -2.8702) (xy 252.5014 -3.0734) (xy 252.7046 -3.0734)
			)
		)
		(polygon
			(pts
				(xy 249.4026 -2.8702) (xy 249.1994 -2.8702) (xy 249.1994 -3.0734) (xy 249.4026 -3.0734)
			)
		)
	)
	(zone
		(net "GND")
		(layer "B.Cu")
		(hatch none 0.5)
		(connect_pads
			(clearance 0.5)
		)
		(min_thickness 0.25)
		(fill yes
			(thermal_gap 0.5)
			(thermal_bridge_width 0.5)
			(island_removal_mode 0)
		)
		(polygon
			(pts
				(xy 459.687676 -11.453876) (xy 457.933298 -13.208) (xy 456.3618 -13.208) (xy 455.8284 -13.7414)
				(xy 454.9521 -14.6177) (xy 454.9521 -16.46936) (xy 455.10069 -16.61795) (xy 456.01255 -16.61795)
				(xy 456.68184 -17.28724) (xy 460.5147 -17.28724) (xy 460.843884 -16.958056) (xy 460.843884 -16.273272)
				(xy 460.843884 -14.793976) (xy 460.89951 -14.73835) (xy 460.900272 -14.73835) (xy 461.143858 -14.494764)
				(xy 462.327752 -14.494764) (xy 462.534 -14.288516) (xy 462.534 -12.9794) (xy 462.21269 -12.65809)
				(xy 462.21269 -11.340338) (xy 462.3054 -11.247628) (xy 462.3054 -10.464292) (xy 462.274412 -10.433304)
				(xy 460.708248 -10.433304) (xy 460.41945 -10.722102) (xy 459.713076 -11.428476)
			)
		)
	)
	(zone
		(net "P12V_STBY")
		(layer "B.Cu")
		(hatch none 0.5)
		(connect_pads
			(clearance 0.5)
		)
		(min_thickness 0.25)
		(fill yes
			(thermal_gap 0.5)
			(thermal_bridge_width 0.5)
			(island_removal_mode 0)
		)
		(polygon
			(pts
				(xy 335.539842 -122.599958) (xy 335.539842 -117.073172) (xy 335.6864 -116.926614) (xy 336.053684 -116.55933)
				(xy 337.965542 -116.55933) (xy 338.174838 -116.350034) (xy 338.174838 -114.767106) (xy 337.809332 -114.4016)
				(xy 335.2038 -114.4016) (xy 329.819 -114.4016) (xy 329.306682 -114.913918) (xy 329.306682 -122.204226)
				(xy 330.374752 -123.272296) (xy 330.374752 -125.940566) (xy 330.646786 -126.2126) (xy 335.153 -126.2126)
				(xy 335.539842 -125.825758) (xy 335.539842 -125.520958)
			)
		)
	)
	(zone
		(net "GND")
		(layer "B.Cu")
		(hatch none 0.5)
		(connect_pads
			(clearance 0.5)
		)
		(min_thickness 0.25)
		(fill yes
			(thermal_gap 0.5)
			(thermal_bridge_width 0.5)
			(island_removal_mode 0)
		)
		(polygon
			(pts
				(xy 265.45032 -69.434964) (xy 265.421618 -69.463666) (xy 265.421618 -69.909182) (xy 265.200384 -70.130416)
				(xy 263.43991 -70.130416) (xy 263.201404 -69.891656) (xy 263.201404 -68.391786) (xy 263.150604 -68.340986)
				(xy 261.516114 -68.340986) (xy 261.382764 -68.474336) (xy 261.382764 -69.856096) (xy 260.921754 -70.317106)
				(xy 258.342892 -70.317106) (xy 258.138422 -70.521576) (xy 257.845306 -70.814692) (xy 257.845306 -72.177402)
				(xy 257.924808 -72.256904) (xy 277.547578 -72.256904) (xy 277.666958 -72.137524) (xy 277.666958 -69.466206)
				(xy 277.342092 -69.14134) (xy 276.290024 -69.14134) (xy 275.9964 -69.434964)
			)
		)
	)
	(zone
		(net "GND")
		(layer "B.Cu")
		(hatch none 0.5)
		(connect_pads
			(clearance 0.5)
		)
		(min_thickness 0.25)
		(fill yes
			(thermal_gap 0.5)
			(thermal_bridge_width 0.5)
			(island_removal_mode 0)
		)
		(polygon
			(pts
				(xy 201.046842 -93.042486) (xy 207.032352 -93.042486) (xy 207.464914 -93.042486) (xy 207.8355 -92.6719)
				(xy 207.8355 -92.239338) (xy 207.8355 -53.0352) (xy 207.4545 -52.6542) (xy 206.2734 -52.6542) (xy 205.359 -51.7398)
				(xy 199.4154 -51.7398) (xy 199.2884 -51.8668) (xy 198.81088 -52.34432) (xy 198.81088 -53.479954)
				(xy 199.10298 -53.772054) (xy 199.10298 -54.41442) (xy 199.10298 -60.71362) (xy 198.813674 -61.002926)
				(xy 198.813674 -61.632338) (xy 199.1614 -61.980064) (xy 199.1614 -62.5602) (xy 199.1614 -68.453)
				(xy 199.158352 -68.456048) (xy 199.158352 -68.576952) (xy 198.807832 -68.927472) (xy 198.807832 -69.777356)
				(xy 199.1614 -70.130924) (xy 199.1614 -70.6374) (xy 199.1614 -71.0692) (xy 199.1614 -76.835) (xy 198.805038 -77.191362)
				(xy 198.805038 -77.87386) (xy 199.097392 -78.166214) (xy 199.097392 -78.880208) (xy 199.097392 -83.685634)
				(xy 199.212708 -83.80095) (xy 199.212708 -85.177884) (xy 199.131682 -85.25891) (xy 199.127364 -85.25891)
				(xy 199.048116 -85.338158) (xy 198.917306 -85.338158) (xy 198.8312 -85.424264) (xy 198.8312 -86.4362)
				(xy 199.1614 -86.7664) (xy 199.1614 -87.0204) (xy 199.1614 -92.9132) (xy 199.290686 -93.042486)
				(xy 199.6694 -93.042486)
			)
		)
	)
	(zone
		(layer "B.Cu")
		(hatch none 0.5)
		(connect_pads
			(clearance 0)
		)
		(min_thickness 0.25)
		(keepout
			(tracks allowed)
			(vias allowed)
			(pads allowed)
			(copperpour allowed)
			(footprints not_allowed)
		)
		(placement
			(enabled no)
			(sheetname "")
		)
		(fill
			(thermal_gap 0.5)
			(thermal_bridge_width 0.5)
			(island_removal_mode 0)
		)
		(polygon
			(pts
				(xy 328.520044 -16.131794) (xy 187.520072 -16.131794) (xy 187.520072 -19.31289) (xy 328.520044 -19.31289)
			)
		)
	)
	(zone
		(layer "B.Cu")
		(hatch none 0.5)
		(connect_pads
			(clearance 0)
		)
		(min_thickness 0.25)
		(keepout
			(tracks allowed)
			(vias allowed)
			(pads allowed)
			(copperpour allowed)
			(footprints allowed)
		)
		(placement
			(enabled no)
			(sheetname "")
		)
		(fill
			(thermal_gap 0.5)
			(thermal_bridge_width 0.5)
			(island_removal_mode 0)
		)
		(polygon
			(pts
				(xy 24.846026 -81.555336) (xy 24.846026 -80.368394) (xy 25.644348 -80.368394) (xy 25.644348 -81.555336)
			)
		)
	)
	(zone
		(layer "B.Cu")
		(hatch none 0.5)
		(connect_pads
			(clearance 0)
		)
		(min_thickness 0.25)
		(keepout
			(tracks not_allowed)
			(vias allowed)
			(pads allowed)
			(copperpour not_allowed)
			(footprints allowed)
		)
		(placement
			(enabled no)
			(sheetname "")
		)
		(fill
			(thermal_gap 0.5)
			(thermal_bridge_width 0.5)
			(island_removal_mode 0)
		)
		(polygon
			(pts
				(arc
					(start 477.800416 -58.996834)
					(mid 474.200474 -55.396892)
					(end 470.600532 -58.996834)
				)
				(arc
					(start 470.600532 -60.59678)
					(mid 474.200474 -64.196722)
					(end 477.800416 -60.59678)
				)
			)
		)
	)
	(zone
		(net "GND")
		(layer "B.Cu")
		(hatch none 0.5)
		(connect_pads
			(clearance 0.5)
		)
		(min_thickness 0.25)
		(fill yes
			(thermal_gap 0.5)
			(thermal_bridge_width 0.5)
			(island_removal_mode 0)
		)
		(polygon
			(pts
				(xy 174.1932 -63.4746) (xy 174.6758 -62.992) (xy 182.0926 -62.992) (xy 182.499 -62.5856) (xy 184.070498 -61.014102)
				(xy 186.206638 -61.014102) (xy 186.94527 -61.752734) (xy 186.994546 -61.80201) (xy 187.100718 -61.908182)
				(xy 187.199778 -62.007242) (xy 189.677802 -62.007242) (xy 189.879986 -61.805058) (xy 189.879986 -60.5917)
				(xy 189.635384 -60.347098) (xy 189.1792 -60.347098) (xy 187.162948 -60.347098) (xy 187.04052 -60.22467)
				(xy 186.7662 -59.95035) (xy 186.7662 -59.69) (xy 186.563 -59.4868) (xy 183.0324 -59.4868) (xy 182.8038 -59.7154)
				(xy 182.8038 -60.198) (xy 181.7878 -61.214) (xy 178.779424 -61.214) (xy 177.47996 -61.214) (xy 176.911 -60.64504)
				(xy 176.911 -58.674) (xy 176.911 -57.277) (xy 177.292 -56.896) (xy 177.292 -55.727092) (xy 177.292 -50.8)
				(xy 177.165 -50.673) (xy 176.76495 -50.673) (xy 175.692308 -49.600358) (xy 174.1678 -49.600358)
				(xy 172.589952 -51.177952) (xy 170.462448 -51.177952) (xy 169.418 -52.2224) (xy 169.418 -54.350158)
				(xy 169.418 -61.9252) (xy 169.418 -62.1284) (xy 169.418 -63.19012) (xy 169.70248 -63.4746) (xy 170.7642 -63.4746)
			)
		)
	)
	(zone
		(net "GND")
		(layer "B.Cu")
		(hatch none 0.5)
		(connect_pads
			(clearance 0.5)
		)
		(min_thickness 0.25)
		(fill yes
			(thermal_gap 0.5)
			(thermal_bridge_width 0.5)
			(island_removal_mode 0)
		)
		(polygon
			(pts
				(xy 342.011 -92.9894) (xy 341.5538 -93.4466) (xy 341.5538 -105.7656) (xy 341.5411 -105.7783) (xy 341.5411 -107.2388)
				(xy 340.836758 -107.943142) (xy 331.832458 -107.943142) (xy 329.765152 -110.010448) (xy 329.765152 -112.683036)
				(xy 330.879958 -113.797842) (xy 337.591654 -113.797842) (xy 337.604608 -113.797842) (xy 337.604862 -113.798096)
				(xy 337.616546 -113.80978) (xy 338.37245 -114.565684) (xy 338.486496 -114.67973) (xy 338.486496 -116.500656)
				(xy 338.359496 -116.627656) (xy 338.178394 -116.808758) (xy 337.905852 -116.808758) (xy 337.591654 -117.122956)
				(xy 337.591654 -124.358654) (xy 337.59775 -124.36475) (xy 337.59775 -125.2474) (xy 337.59775 -125.60935)
				(xy 337.59775 -125.93955) (xy 337.8454 -126.1872) (xy 342.80856 -126.1872) (xy 343.55278 -125.44298)
				(xy 343.55278 -125.255528) (xy 343.55278 -124.41682) (xy 343.55278 -120.40362) (xy 346.8497 -117.1067)
				(xy 346.8497 -115.9383) (xy 347.5482 -115.2398) (xy 347.5482 -113.6523) (xy 347.2307 -113.3348)
				(xy 345.372182 -113.3348) (xy 345.257882 -113.2205) (xy 345.257882 -108.246418) (xy 345.257882 -108.106718)
				(xy 345.910662 -107.453938) (xy 346.050362 -107.453938) (xy 351.116138 -107.453938) (xy 351.4852 -107.823)
				(xy 353.0854 -107.823) (xy 353.3902 -107.5182) (xy 353.3902 -104.271064) (xy 353.2886 -104.169464)
				(xy 345.672156 -104.169464) (xy 345.436444 -103.933752) (xy 345.436444 -103.900986) (xy 345.436444 -102.457758)
				(xy 345.53525 -102.358952) (xy 346.94114 -102.358952) (xy 347.146372 -102.15372) (xy 347.146372 -100.714048)
				(xy 346.9132 -100.480876) (xy 346.9132 -93.599) (xy 346.9132 -93.091) (xy 346.8116 -92.9894) (xy 346.3036 -92.9894)
			)
		)
	)
	(zone
		(net "P1V8_PCH_STBY")
		(layer "B.Cu")
		(hatch none 0.5)
		(connect_pads
			(clearance 0.5)
		)
		(min_thickness 0.25)
		(fill yes
			(thermal_gap 0.5)
			(thermal_bridge_width 0.5)
			(island_removal_mode 0)
		)
		(polygon
			(pts
				(xy 406.53208 -142.279116) (xy 406.53208 -144.01292) (xy 405.848058 -144.696942) (xy 405.848058 -145.218658)
				(xy 405.8412 -145.225516) (xy 405.8412 -148.1963) (xy 405.6126 -148.4249) (xy 404.1902 -148.4249)
				(xy 404.0886 -148.3233) (xy 404.0886 -147.3835) (xy 403.9362 -147.2311) (xy 403.9362 -141.177264)
				(xy 403.963124 -141.15034) (xy 406.35174 -141.15034) (xy 406.53208 -141.33068)
			)
		)
	)
	(zone
		(net "GND")
		(layer "B.Cu")
		(hatch none 0.5)
		(connect_pads
			(clearance 0.5)
		)
		(min_thickness 0.25)
		(fill yes
			(thermal_gap 0.5)
			(thermal_bridge_width 0.5)
			(island_removal_mode 0)
		)
		(polygon
			(pts
				(xy 213.995 -60.325) (xy 213.7664 -60.5536) (xy 213.7664 -61.722) (xy 213.9696 -61.9252) (xy 215.1888 -61.9252)
				(xy 215.5444 -61.5696) (xy 215.5444 -60.5536) (xy 215.3158 -60.325)
			)
		)
		(polygon
			(pts
				(xy 214.9856 -60.94222) (xy 214.7824 -60.94222) (xy 214.7824 -61.34862) (xy 214.9856 -61.34862)
			)
		)
	)
	(zone
		(net "P1V05_PCH_STBY")
		(layer "B.Cu")
		(hatch none 0.5)
		(connect_pads
			(clearance 0.5)
		)
		(min_thickness 0.25)
		(fill yes
			(thermal_gap 0.5)
			(thermal_bridge_width 0.5)
			(island_removal_mode 0)
		)
		(polygon
			(pts
				(xy 372.681246 -92.959682) (xy 372.681246 -94.115382) (xy 371.376194 -94.115382) (xy 371.284246 -94.20733)
				(xy 371.283992 -94.207076) (xy 370.796312 -94.207076) (xy 369.995704 -94.207076) (xy 369.959382 -94.170754)
				(xy 369.959382 -93.721682) (xy 370.500656 -93.180408) (xy 371.64264 -93.180408) (xy 371.979952 -92.843096)
				(xy 372.56466 -92.843096)
			)
		)
	)
	(zone
		(layer "B.Cu")
		(hatch none 0.5)
		(connect_pads
			(clearance 0)
		)
		(min_thickness 0.25)
		(keepout
			(tracks allowed)
			(vias allowed)
			(pads allowed)
			(copperpour allowed)
			(footprints not_allowed)
		)
		(placement
			(enabled no)
			(sheetname "")
		)
		(fill
			(thermal_gap 0.5)
			(thermal_bridge_width 0.5)
			(island_removal_mode 0)
		)
		(polygon
			(pts
				(arc
					(start 151.960072 -93.689932)
					(mid 152.667177 -93.397039)
					(end 152.96007 -92.689934)
				)
				(arc
					(start 152.96007 -85.549994)
					(mid 152.667177 -84.842889)
					(end 151.960072 -84.549996)
				)
				(arc
					(start 146.340068 -84.549996)
					(mid 145.632963 -84.842889)
					(end 145.34007 -85.549994)
				)
				(arc
					(start 145.34007 -92.689934)
					(mid 145.632963 -93.397039)
					(end 146.340068 -93.689932)
				)
			)
		)
	)
	(zone
		(layer "B.Cu")
		(hatch none 0.5)
		(connect_pads
			(clearance 0)
		)
		(min_thickness 0.25)
		(keepout
			(tracks not_allowed)
			(vias allowed)
			(pads allowed)
			(copperpour not_allowed)
			(footprints allowed)
		)
		(placement
			(enabled no)
			(sheetname "")
		)
		(fill
			(thermal_gap 0.5)
			(thermal_bridge_width 0.5)
			(island_removal_mode 0)
		)
		(polygon
			(pts
				(arc
					(start 369.48999 -89.490042)
					(mid 373.080026 -85.900006)
					(end 369.48999 -82.30997)
				)
				(arc
					(start 369.48999 -82.30997)
					(mid 365.899954 -85.900006)
					(end 369.48999 -89.490042)
				)
			)
		)
	)
	(zone
		(net "GND")
		(layer "B.Cu")
		(hatch none 0.5)
		(connect_pads
			(clearance 0.5)
		)
		(min_thickness 0.25)
		(fill yes
			(thermal_gap 0.5)
			(thermal_bridge_width 0.5)
			(island_removal_mode 0)
		)
		(polygon
			(pts
				(xy 187.467494 -134.74954) (xy 187.467494 -134.747) (xy 187.467494 -133.36524) (xy 186.13628 -132.034026)
				(xy 186.13628 -130.55346) (xy 185.88482 -130.302) (xy 184.658 -130.302) (xy 184.531 -130.429) (xy 184.531 -130.444748)
				(xy 184.432702 -130.543046) (xy 184.432702 -133.808216) (xy 184.531 -133.906514) (xy 184.531 -134.874)
				(xy 184.531 -135.0518) (xy 184.658 -135.1788) (xy 185.6486 -135.1788) (xy 185.801 -135.3312) (xy 187.1726 -135.3312)
				(xy 187.467494 -135.036306)
			)
		)
	)
	(zone
		(net "P1V05_PCH_STBY")
		(layer "B.Cu")
		(hatch none 0.5)
		(connect_pads
			(clearance 0.5)
		)
		(min_thickness 0.25)
		(fill yes
			(thermal_gap 0.5)
			(thermal_bridge_width 0.5)
			(island_removal_mode 0)
		)
		(polygon
			(pts
				(xy 404.613872 -113.415826) (xy 403.493986 -114.535712) (xy 401.61464 -114.535712) (xy 401.35556 -114.794792)
				(xy 401.35556 -116.89842) (xy 401.59178 -117.13464) (xy 402.60016 -117.13464) (xy 402.75256 -117.28704)
				(xy 402.75256 -117.888512) (xy 402.77796 -117.913912) (xy 403.282912 -117.913912) (xy 403.403816 -117.793008)
				(xy 403.403816 -117.411246) (xy 403.59584 -117.219222) (xy 405.697436 -117.219222) (xy 405.782018 -117.13464)
				(xy 405.782018 -115.663218) (xy 405.946864 -115.498372) (xy 408.949906 -115.498372) (xy 408.97556 -115.472718)
				(xy 408.97556 -115.241324) (xy 408.97683 -115.2398) (xy 408.97683 -113.54943) (xy 408.843226 -113.415826)
			)
		)
		(polygon
			(pts
				(xy 404.4696 -116.2304) (xy 404.2664 -116.2304) (xy 404.2664 -116.4336) (xy 404.4696 -116.4336)
			)
		)
		(polygon
			(pts
				(xy 404.9776 -116.2304) (xy 404.7744 -116.2304) (xy 404.7744 -116.4336) (xy 404.9776 -116.4336)
			)
		)
	)
	(zone
		(layer "B.Cu")
		(hatch none 0.5)
		(connect_pads
			(clearance 0)
		)
		(min_thickness 0.25)
		(keepout
			(tracks allowed)
			(vias allowed)
			(pads allowed)
			(copperpour allowed)
			(footprints allowed)
		)
		(placement
			(enabled no)
			(sheetname "")
		)
		(fill
			(thermal_gap 0.5)
			(thermal_bridge_width 0.5)
			(island_removal_mode 0)
		)
		(polygon
			(pts
				(xy 317.373 -85.725) (xy 317.373 -84.963) (xy 318.135 -84.963) (xy 318.135 -85.725)
			)
		)
	)
	(zone
		(net "PVPP_ABC")
		(layer "B.Cu")
		(hatch none 0.5)
		(connect_pads
			(clearance 0.5)
		)
		(min_thickness 0.25)
		(fill yes
			(thermal_gap 0.5)
			(thermal_bridge_width 0.5)
			(island_removal_mode 0)
		)
		(polygon
			(pts
				(xy 323.596 3.937) (xy 322.453 2.794) (xy 317.6778 2.794) (xy 317.5 2.6162) (xy 317.5 -3.3782) (xy 316.8142 -4.064)
				(xy 316.8142 -16.0528) (xy 317.0428 -16.2814) (xy 318.3128 -16.2814) (xy 318.389 -16.2052) (xy 318.4652 -16.2052)
				(xy 318.5922 -16.3322) (xy 318.5922 -16.7894) (xy 318.516 -16.8656) (xy 318.516 -17.2466) (xy 318.4144 -17.3482)
				(xy 318.135 -17.3482) (xy 318.0842 -17.399) (xy 318.0842 -18.2118) (xy 317.9572 -18.3388) (xy 317.0936 -18.3388)
				(xy 316.8142 -18.6182) (xy 316.8142 -26.1874) (xy 317.1698 -26.543) (xy 318.516 -26.543) (xy 319.8876 -27.9146)
				(xy 319.8876 -29.356304) (xy 320.04 -29.508704) (xy 323.4436 -29.508704) (xy 323.4944 -29.559504)
				(xy 323.4944 -30.0736) (xy 323.5198 -30.099) (xy 324.0024 -30.099) (xy 324.0532 -30.0482) (xy 324.0532 -29.718)
				(xy 324.262496 -29.508704) (xy 325.515224 -29.508704) (xy 327.12152 -31.115) (xy 334.01 -31.115)
				(xy 334.137 -30.988) (xy 334.137 -23.114) (xy 332.232 -21.209) (xy 329.9714 -21.209) (xy 329.184 -20.4216)
				(xy 329.184 -14.4272) (xy 328.831448 -14.074648) (xy 328.831448 -12.486386) (xy 329.125834 -12.192)
				(xy 330.581 -12.192) (xy 330.835 -11.938) (xy 330.835 -11.43) (xy 330.327 -11.43) (xy 329.692 -10.795)
				(xy 329.692 -8.128) (xy 329.06589 -8.128) (xy 328.676 -7.73811) (xy 328.676 2.921) (xy 327.66 3.937)
			)
		)
		(polygon
			(pts
				(xy 323.04863 -25.736296) (xy 322.147438 -25.736296) (xy 321.983608 -25.900126) (xy 321.983608 -26.674064)
				(xy 320.99123 -26.674064) (xy 320.768218 -26.897076) (xy 320.768218 -27.902916) (xy 320.918332 -28.05303)
				(xy 321.391788 -28.05303) (xy 321.45097 -28.112212) (xy 321.45097 -28.681172) (xy 321.554602 -28.784804)
				(xy 323.475858 -28.784804) (xy 323.621654 -28.639008) (xy 323.621654 -28.174696) (xy 323.671438 -28.124912)
				(xy 324.085712 -28.124912) (xy 324.245224 -27.9654) (xy 324.245224 -26.94686) (xy 323.972428 -26.674064)
				(xy 323.421756 -26.674064) (xy 323.421756 -26.109422)
			)
		)
		(polygon
			(pts
				(xy 319.851532 -18.0594) (xy 319.648332 -18.0594) (xy 319.648332 -18.2626) (xy 319.851532 -18.2626)
			)
		)
		(polygon
			(pts
				(xy 319.089532 -18.0594) (xy 318.886332 -18.0594) (xy 318.886332 -18.2626) (xy 319.089532 -18.2626)
			)
		)
		(polygon
			(pts
				(xy 319.851532 -17.2974) (xy 319.648332 -17.2974) (xy 319.648332 -17.5006) (xy 319.851532 -17.5006)
			)
		)
		(polygon
			(pts
				(xy 319.089532 -17.2974) (xy 318.886332 -17.2974) (xy 318.886332 -17.5006) (xy 319.089532 -17.5006)
			)
		)
		(polygon
			(pts
				(xy 319.851532 -8.4074) (xy 319.648332 -8.4074) (xy 319.648332 -8.6106) (xy 319.851532 -8.6106)
			)
		)
		(polygon
			(pts
				(xy 319.089532 -8.4074) (xy 318.886332 -8.4074) (xy 318.886332 -8.6106) (xy 319.089532 -8.6106)
			)
		)
		(polygon
			(pts
				(xy 319.851532 -7.6454) (xy 319.648332 -7.6454) (xy 319.648332 -7.8486) (xy 319.851532 -7.8486)
			)
		)
		(polygon
			(pts
				(xy 319.089532 -7.6454) (xy 318.886332 -7.6454) (xy 318.886332 -7.8486) (xy 319.089532 -7.8486)
			)
		)
		(polygon
			(pts
				(xy 319.851532 1.4224) (xy 319.648332 1.4224) (xy 319.648332 1.2192) (xy 319.851532 1.2192)
			)
		)
		(polygon
			(pts
				(xy 319.343532 1.4224) (xy 319.140332 1.4224) (xy 319.140332 1.2192) (xy 319.343532 1.2192)
			)
		)
		(polygon
			(pts
				(xy 319.851532 2.1844) (xy 319.648332 2.1844) (xy 319.648332 1.9812) (xy 319.851532 1.9812)
			)
		)
		(polygon
			(pts
				(xy 319.343532 2.1844) (xy 319.140332 2.1844) (xy 319.140332 1.9812) (xy 319.343532 1.9812)
			)
		)
	)
	(zone
		(net "P3V3_STBY_MNG")
		(layer "B.Cu")
		(hatch none 0.5)
		(connect_pads
			(clearance 0.5)
		)
		(min_thickness 0.25)
		(fill yes
			(thermal_gap 0.5)
			(thermal_bridge_width 0.5)
			(island_removal_mode 0)
		)
		(polygon
			(pts
				(xy 480.97567 -27.686762) (xy 480.880166 -27.782266) (xy 480.880166 -28.651708) (xy 481.025708 -28.79725)
				(xy 481.025708 -30.784292) (xy 479.8822 -31.9278) (xy 479.8822 -32.5628) (xy 479.6536 -32.7914)
				(xy 479.6536 -34.285936) (xy 479.664776 -34.275776) (xy 479.664776 -35.371024) (xy 479.425 -35.6108)
				(xy 478.8154 -35.6108) (xy 478.6884 -35.7378) (xy 478.6884 -36.0172) (xy 478.794318 -36.123118)
				(xy 480.652074 -36.123118) (xy 481.076 -35.699192) (xy 481.076 -32.512) (xy 481.584 -32.004) (xy 481.584 -31.5722)
				(xy 482.9302 -30.226) (xy 483.6922 -30.226) (xy 483.842568 -30.075632) (xy 483.842568 -29.212032)
				(xy 484.0986 -28.956) (xy 485.8512 -28.956) (xy 485.902 -28.9052) (xy 485.902 -27.8384) (xy 485.750362 -27.686762)
			)
		)
		(polygon
			(pts
				(xy 480.654106 -35.259518) (xy 480.450906 -35.259518) (xy 480.450906 -35.462718) (xy 480.654106 -35.462718)
			)
		)
		(polygon
			(pts
				(xy 480.654106 -34.497518) (xy 480.450906 -34.497518) (xy 480.450906 -34.700718) (xy 480.654106 -34.700718)
			)
		)
		(polygon
			(pts
				(xy 481.847398 -28.473908) (xy 481.644198 -28.473908) (xy 481.644198 -28.677108) (xy 481.847398 -28.677108)
			)
		)
	)
	(zone
		(net "P3V3_STBY")
		(layer "B.Cu")
		(hatch none 0.5)
		(connect_pads
			(clearance 0.5)
		)
		(min_thickness 0.25)
		(fill yes
			(thermal_gap 0.5)
			(thermal_bridge_width 0.5)
			(island_removal_mode 0)
		)
		(polygon
			(pts
				(xy 398.769332 -73.670668) (xy 397.51 -74.93) (xy 397.51 -75.819) (xy 397.6751 -75.9841) (xy 398.2593 -75.9841)
				(xy 400.0373 -75.9841) (xy 400.3294 -75.692) (xy 400.3294 -75.057) (xy 400.3294 -73.7235) (xy 400.7358 -73.3171)
				(xy 401.193 -73.3171) (xy 401.5359 -73.66) (xy 401.7264 -73.66) (xy 402.9202 -73.66) (xy 403.1234 -73.8632)
				(xy 403.1234 -74.9173) (xy 402.9075 -75.1332) (xy 402.9075 -75.8571) (xy 402.9837 -75.9333) (xy 404.622 -75.9333)
				(xy 405.6888 -75.9333) (xy 405.9047 -75.7174) (xy 405.9047 -72.9996) (xy 405.817324 -72.912224)
				(xy 400.035522 -72.912224) (xy 399.277078 -73.670668)
			)
		)
	)
	(zone
		(layer "B.Cu")
		(hatch none 0.5)
		(connect_pads
			(clearance 0)
		)
		(min_thickness 0.25)
		(keepout
			(tracks not_allowed)
			(vias allowed)
			(pads allowed)
			(copperpour not_allowed)
			(footprints allowed)
		)
		(placement
			(enabled no)
			(sheetname "")
		)
		(fill
			(thermal_gap 0.5)
			(thermal_bridge_width 0.5)
			(island_removal_mode 0)
		)
		(polygon
			(pts
				(arc
					(start 318.000126 -56.449976)
					(mid 319.900046 -54.550056)
					(end 318.000126 -52.649882)
				)
				(arc
					(start 318.000126 -52.649882)
					(mid 316.099952 -54.550056)
					(end 318.000126 -56.449976)
				)
			)
		)
	)
	(zone
		(layer "B.Cu")
		(hatch none 0.5)
		(connect_pads
			(clearance 0)
		)
		(min_thickness 0.25)
		(keepout
			(tracks allowed)
			(vias allowed)
			(pads allowed)
			(copperpour allowed)
			(footprints not_allowed)
		)
		(placement
			(enabled no)
			(sheetname "")
		)
		(fill
			(thermal_gap 0.5)
			(thermal_bridge_width 0.5)
			(island_removal_mode 0)
		)
		(polygon
			(pts
				(arc
					(start 318.000126 -101.089968)
					(mid 320.540126 -98.549968)
					(end 318.000126 -96.009968)
				)
				(arc
					(start 318.000126 -96.009968)
					(mid 315.460126 -98.549968)
					(end 318.000126 -101.089968)
				)
			)
		)
	)
	(zone
		(layer "B.Cu")
		(hatch none 0.5)
		(connect_pads
			(clearance 0)
		)
		(min_thickness 0.25)
		(keepout
			(tracks not_allowed)
			(vias allowed)
			(pads allowed)
			(copperpour not_allowed)
			(footprints allowed)
		)
		(placement
			(enabled no)
			(sheetname "")
		)
		(fill
			(thermal_gap 0.5)
			(thermal_bridge_width 0.5)
			(island_removal_mode 0)
		)
		(polygon
			(pts
				(xy 11.825986 -25.51303) (xy 11.98245 -25.669494)
				(arc
					(start 11.98245 -25.841198)
					(mid 11.9126 -26.365115)
					(end 11.84275 -25.841198)
				)
				(xy 11.84275 -25.727406) (xy 11.768074 -25.65273) (xy 11.52906 -25.65273)
				(arc
					(start 11.52906 -26.098246)
					(mid 11.912473 -26.48204)
					(end 12.29614 -26.0985)
				)
				(arc
					(start 12.29614 -24.8285)
					(mid 11.9126 -24.44496)
					(end 11.52906 -24.8285)
				)
				(xy 11.52906 -25.27173) (xy 11.770614 -25.27173) (xy 11.84275 -25.199594)
				(arc
					(start 11.84275 -25.085802)
					(mid 11.9126 -24.561885)
					(end 11.98245 -25.085802)
				)
				(xy 11.98245 -25.257506) (xy 11.828526 -25.41143) (xy 11.52906 -25.41143) (xy 11.52906 -25.51303)
			)
		)
	)
	(zone
		(net "GND")
		(layer "B.Cu")
		(hatch none 0.5)
		(connect_pads
			(clearance 0.5)
		)
		(min_thickness 0.25)
		(fill yes
			(thermal_gap 0.5)
			(thermal_bridge_width 0.5)
			(island_removal_mode 0)
		)
		(polygon
			(pts
				(xy 341.96909 -27.768042) (xy 339.37702 -27.768042)
				(arc
					(start 337.086448 -25.47747)
					(mid 336.991797 -25.450278)
					(end 336.918554 -25.516078)
				)
				(arc
					(start 336.918554 -25.516078)
					(mid 336.384236 -25.696632)
					(end 336.345276 -25.134062)
				)
				(arc
					(start 336.345276 -25.134062)
					(mid 336.372719 -25.021972)
					(end 336.277712 -24.956516)
				)
				(xy 335.0895 -24.956516) (xy 334.9498 -25.096216) (xy 334.9498 -27.672792) (xy 334.950308 -27.672792)
				(xy 334.950308 -28.943808) (xy 334.9498 -28.943808) (xy 334.9498 -29.704792) (xy 334.950308 -29.704792)
				(xy 334.950308 -30.975808) (xy 334.9498 -30.975808) (xy 334.9498 -31.496) (xy 334.8228 -31.623)
				(xy 331.065632 -31.623)
				(arc
					(start 331.058012 -31.66491)
					(mid 330.6826 -31.978998)
					(end 330.307188 -31.66491)
				)
				(xy 330.299568 -31.623) (xy 326.263 -31.623) (xy 325.755 -32.131) (xy 325.755 -35.941) (xy 326.500744 -36.686744)
				(arc
					(start 328.751946 -36.686744)
					(mid 328.977335 -36.359033)
					(end 329.36561 -36.444682)
				)
				(arc
					(start 329.36561 -36.444682)
					(mid 329.439902 -36.476264)
					(end 329.513692 -36.443666)
				)
				(arc
					(start 329.513692 -36.443666)
					(mid 329.912511 -36.340422)
					(end 330.172568 -36.65982)
				)
				(xy 330.1746 -36.6776) (xy 330.6826 -37.1856) (xy 330.884784 -37.1856) (xy 330.884784 -37.180012)
				(xy 331.393292 -37.180012) (xy 331.393292 -37.1856) (xy 331.773784 -37.1856) (xy 331.773784 -37.180012)
				(xy 332.282292 -37.180012) (xy 332.282292 -37.1856)
				(arc
					(start 332.384654 -37.1856)
					(mid 332.41618 -37.180585)
					(end 332.444598 -37.166042)
				)
				(arc
					(start 333.086202 -37.166042)
					(mid 333.114618 -37.180593)
					(end 333.146146 -37.1856)
				)
				(xy 334.05572 -37.1856) (xy 334.621632 -37.751512) (xy 334.621632 -40.715692) (xy 334.97774 -41.0718)
				(xy 351.0534 -41.0718) (xy 351.4344 -41.4528) (xy 351.4344 -44.8818) (xy 350.9772 -45.339) (xy 348.4118 -45.339)
				(xy 348.4118 -47.9552) (xy 348.5388 -48.0822) (xy 351.12706 -48.0822) (xy 353.5172 -45.69206) (xy 353.5172 -37.8206)
				(xy 352.2726 -36.576) (xy 349.9866 -36.576) (xy 349.733108 -36.322508) (xy 349.630492 -36.322508)
				(xy 349.630492 -33.42259) (xy 349.6818 -33.371536) (xy 349.6818 -33.2105) (xy 350.0501 -32.8422)
				(xy 352.2726 -32.8422) (xy 352.5266 -32.5882) (xy 352.5266 -30.48) (xy 351.8916 -29.845) (xy 351.663508 -29.845)
				(xy 351.663508 -29.845508) (xy 350.392492 -29.845508) (xy 350.392492 -29.845) (xy 350.2914 -29.845)
				(xy 350.0882 -29.6418) (xy 350.0882 -28.83027) (xy 349.860108 -28.602178) (xy 348.845886 -28.602178)
				(xy 348.845632 -28.602432) (xy 347.994732 -28.602432) (xy 346.9767 -27.5844) (xy 346.9767 -26.542238)
				(xy 346.637356 -26.202894) (xy 342.647016 -26.202894) (xy 342.218264 -26.631646) (xy 342.218264 -27.518868)
			)
		)
		(polygon
			(pts
				(xy 335.602326 -39.933118) (xy 335.399126 -39.933118) (xy 335.399126 -40.136318) (xy 335.602326 -40.136318)
			)
		)
		(polygon
			(pts
				(xy 335.602326 -38.653466) (xy 335.399126 -38.653466) (xy 335.399126 -39.145718) (xy 335.602326 -39.145718)
			)
		)
		(polygon
			(pts
				(xy 335.602326 -37.662866) (xy 335.399126 -37.662866) (xy 335.399126 -37.866066) (xy 335.602326 -37.866066)
			)
		)
	)
	(zone
		(layer "B.Cu")
		(hatch none 0.5)
		(connect_pads
			(clearance 0)
		)
		(min_thickness 0.25)
		(keepout
			(tracks not_allowed)
			(vias allowed)
			(pads allowed)
			(copperpour not_allowed)
			(footprints allowed)
		)
		(placement
			(enabled no)
			(sheetname "")
		)
		(fill
			(thermal_gap 0.5)
			(thermal_bridge_width 0.5)
			(island_removal_mode 0)
		)
		(polygon
			(pts
				(arc
					(start 475.80042 -58.996834)
					(mid 474.200474 -57.396888)
					(end 472.600528 -58.996834)
				)
				(arc
					(start 472.600528 -60.59678)
					(mid 474.200474 -62.196726)
					(end 475.80042 -60.59678)
				)
			)
		)
	)
	(zone
		(net "GND")
		(layer "B.Cu")
		(hatch none 0.5)
		(connect_pads
			(clearance 0.5)
		)
		(min_thickness 0.25)
		(fill yes
			(thermal_gap 0.5)
			(thermal_bridge_width 0.5)
			(island_removal_mode 0)
		)
		(polygon
			(pts
				(xy 242.029234 -136.639808) (xy 243.284756 -136.639808) (xy 243.4336 -136.490964) (xy 243.4336 -134.180834)
				(xy 243.219986 -133.96722) (xy 242.055396 -133.96722) (xy 241.848132 -134.174484) (xy 241.848132 -136.458706)
			)
		)
	)
	(zone
		(layer "B.Cu")
		(hatch none 0.5)
		(connect_pads
			(clearance 0)
		)
		(min_thickness 0.25)
		(keepout
			(tracks not_allowed)
			(vias allowed)
			(pads allowed)
			(copperpour not_allowed)
			(footprints allowed)
		)
		(placement
			(enabled no)
			(sheetname "")
		)
		(fill
			(thermal_gap 0.5)
			(thermal_bridge_width 0.5)
			(island_removal_mode 0)
		)
		(polygon
			(pts
				(xy 1.09855 -107.52836) (xy 1.09855 -107.826556) (xy 0.943356 -107.98175)
				(arc
					(start 0.771652 -107.98175)
					(mid 0.247735 -107.9119)
					(end 0.771652 -107.84205)
				)
				(xy 0.885444 -107.84205) (xy 0.95885 -107.768644) (xy 0.95885 -107.52836)
				(arc
					(start 0.514604 -107.52836)
					(mid 0.13081 -107.911773)
					(end 0.51435 -108.29544)
				)
				(arc
					(start 1.78435 -108.29544)
					(mid 2.16789 -107.9119)
					(end 1.78435 -107.52836)
				)
				(xy 1.33985 -107.52836) (xy 1.33985 -107.768644) (xy 1.413256 -107.84205)
				(arc
					(start 1.527048 -107.84205)
					(mid 2.050965 -107.9119)
					(end 1.527048 -107.98175)
				)
				(xy 1.355344 -107.98175) (xy 1.20015 -107.826556) (xy 1.20015 -107.52836)
			)
		)
	)
	(zone
		(net "P12V_STBY")
		(layer "B.Cu")
		(hatch none 0.5)
		(connect_pads
			(clearance 0.5)
		)
		(min_thickness 0.25)
		(fill yes
			(thermal_gap 0.5)
			(thermal_bridge_width 0.5)
			(island_removal_mode 0)
		)
		(polygon
			(pts
				(xy 149.987 -124.079) (xy 153.543 -124.079) (xy 153.95321 -123.66879) (xy 153.95321 -122.28576)
				(xy 154.10053 -122.13844) (xy 154.10053 -120.19153) (xy 154.051 -120.142) (xy 151.257 -120.142)
				(xy 149.987 -121.412)
			)
		)
	)
	(zone
		(layer "B.Cu")
		(hatch none 0.5)
		(connect_pads
			(clearance 0)
		)
		(min_thickness 0.25)
		(keepout
			(tracks allowed)
			(vias allowed)
			(pads allowed)
			(copperpour allowed)
			(footprints allowed)
		)
		(placement
			(enabled no)
			(sheetname "")
		)
		(fill
			(thermal_gap 0.5)
			(thermal_bridge_width 0.5)
			(island_removal_mode 0)
		)
		(polygon
			(pts
				(xy 148.59 -94.361) (xy 148.59 -92.964) (xy 149.352 -92.964) (xy 149.352 -94.361)
			)
		)
	)
	(zone
		(net "GND")
		(layer "B.Cu")
		(hatch none 0.5)
		(connect_pads
			(clearance 0.5)
		)
		(min_thickness 0.25)
		(fill yes
			(thermal_gap 0.5)
			(thermal_bridge_width 0.5)
			(island_removal_mode 0)
		)
		(polygon
			(pts
				(xy 247.0404 -125.0442) (xy 246.761 -125.3236) (xy 246.761 -126.7206) (xy 247.2182 -127.1778) (xy 258.3942 -127.1778)
				(xy 258.8514 -126.7206) (xy 258.8514 -125.6538) (xy 258.2418 -125.0442)
			)
		)
		(polygon
			(pts
				(xy 258.1783 -126.5301) (xy 257.9751 -126.5301) (xy 257.9751 -126.7333) (xy 258.1783 -126.7333)
			)
		)
		(polygon
			(pts
				(xy 258.1783 -125.5395) (xy 257.9751 -125.5395) (xy 257.9751 -125.7427) (xy 258.1783 -125.7427)
			)
		)
	)
	(zone
		(net "GND")
		(layer "B.Cu")
		(hatch none 0.5)
		(connect_pads
			(clearance 0.5)
		)
		(min_thickness 0.25)
		(fill yes
			(thermal_gap 0.5)
			(thermal_bridge_width 0.5)
			(island_removal_mode 0)
		)
		(polygon
			(pts
				(xy 50.4952 -97.0788) (xy 50.4952 -97.3074) (xy 50.3174 -97.4852) (xy 50.0888 -97.4852) (xy 49.022 -97.4852)
				(xy 48.7426 -97.4852) (xy 48.5394 -97.282) (xy 48.5394 -96.012) (xy 48.7426 -95.8088) (xy 50.292 -95.8088)
				(xy 50.4952 -96.012)
			)
		)
	)
	(zone
		(layer "B.Cu")
		(hatch none 0.5)
		(connect_pads
			(clearance 0)
		)
		(min_thickness 0.25)
		(keepout
			(tracks allowed)
			(vias allowed)
			(pads allowed)
			(copperpour allowed)
			(footprints allowed)
		)
		(placement
			(enabled no)
			(sheetname "")
		)
		(fill
			(thermal_gap 0.5)
			(thermal_bridge_width 0.5)
			(island_removal_mode 0)
		)
		(polygon
			(pts
				(xy 310.769 -93.218) (xy 310.769 -92.456) (xy 311.531 -92.456) (xy 311.531 -93.218)
			)
		)
	)
	(zone
		(layer "B.Cu")
		(hatch none 0.5)
		(connect_pads
			(clearance 0)
		)
		(min_thickness 0.25)
		(keepout
			(tracks not_allowed)
			(vias allowed)
			(pads allowed)
			(copperpour not_allowed)
			(footprints allowed)
		)
		(placement
			(enabled no)
			(sheetname "")
		)
		(fill
			(thermal_gap 0.5)
			(thermal_bridge_width 0.5)
			(island_removal_mode 0)
		)
		(polygon
			(pts
				(arc
					(start 338.094828 -69.980048)
					(mid 337.675411 -70.302067)
					(end 337.996022 -69.881496)
				)
				(xy 338.06765 -69.809614) (xy 338.06765 -69.72935)
				(arc
					(start 337.863434 -69.72935)
					(mid 337.479894 -70.11289)
					(end 337.863434 -70.49643)
				)
				(arc
					(start 338.754466 -70.49643)
					(mid 339.13826 -70.113017)
					(end 338.75472 -69.72935)
				)
				(xy 338.469986 -69.72935)
				(arc
					(start 338.622132 -69.881496)
					(mid 338.943297 -70.301467)
					(end 338.523326 -69.980302)
				)
				(xy 338.30895 -69.765926) (xy 338.30895 -69.72935) (xy 338.20735 -69.72935) (xy 338.20735 -69.80809)
				(xy 338.208112 -69.808852) (xy 338.208112 -69.837808) (xy 338.208112 -69.866764) (xy 338.187538 -69.887084)
			)
		)
	)
	(zone
		(layer "B.Cu")
		(hatch none 0.5)
		(connect_pads
			(clearance 0)
		)
		(min_thickness 0.25)
		(keepout
			(tracks not_allowed)
			(vias allowed)
			(pads allowed)
			(copperpour not_allowed)
			(footprints allowed)
		)
		(placement
			(enabled no)
			(sheetname "")
		)
		(fill
			(thermal_gap 0.5)
			(thermal_bridge_width 0.5)
			(island_removal_mode 0)
		)
		(polygon
			(pts
				(arc
					(start 457.308712 -49.927764)
					(mid 457.832629 -49.997614)
					(end 457.308712 -50.067464)
				)
				(xy 457.246736 -50.067464) (xy 457.17333 -50.14087) (xy 457.17333 -50.381154)
				(arc
					(start 457.56576 -50.381154)
					(mid 457.949554 -49.997741)
					(end 457.566014 -49.614074)
				)
				(arc
					(start 456.296014 -49.614074)
					(mid 455.912474 -49.997614)
					(end 456.296014 -50.381154)
				)
				(xy 456.79233 -50.381154) (xy 456.79233 -50.192686) (xy 456.667108 -50.067464)
				(arc
					(start 456.553316 -50.067464)
					(mid 456.029399 -49.997614)
					(end 456.553316 -49.927764)
				)
				(xy 456.72502 -49.927764) (xy 456.93203 -50.134774) (xy 456.93203 -50.381154) (xy 457.03363 -50.381154)
				(xy 457.03363 -50.082958) (xy 457.188824 -49.927764)
			)
		)
	)
	(zone
		(layer "B.Cu")
		(hatch none 0.5)
		(connect_pads
			(clearance 0)
		)
		(min_thickness 0.25)
		(keepout
			(tracks allowed)
			(vias allowed)
			(pads allowed)
			(copperpour allowed)
			(footprints not_allowed)
		)
		(placement
			(enabled no)
			(sheetname "")
		)
		(fill
			(thermal_gap 0.5)
			(thermal_bridge_width 0.5)
			(island_removal_mode 0)
		)
		(polygon
			(pts
				(arc
					(start 4.629912 -46.90999)
					(mid 6.229858 -45.310044)
					(end 4.629912 -43.710098)
				)
				(arc
					(start 4.629912 -43.710098)
					(mid 3.029966 -45.310044)
					(end 4.629912 -46.90999)
				)
			)
		)
	)
	(zone
		(net "PVDDQ_DEF")
		(layer "B.Cu")
		(hatch none 0.5)
		(connect_pads
			(clearance 0.5)
		)
		(min_thickness 0.25)
		(fill yes
			(thermal_gap 0.5)
			(thermal_bridge_width 0.5)
			(island_removal_mode 0)
		)
		(polygon
			(pts
				(xy 265.929364 -134.041896) (xy 265.2268 -134.74446) (xy 265.2268 -135.908034) (xy 265.979148 -136.660382)
				(xy 277.326598 -136.660382) (xy 277.529036 -136.457944) (xy 277.529036 -134.23011) (xy 277.340822 -134.041896)
			)
		)
		(polygon
			(pts
				(xy 276.038564 -135.8011) (xy 275.835364 -135.8011) (xy 275.835364 -136.0043) (xy 276.038564 -136.0043)
			)
		)
		(polygon
			(pts
				(xy 272.518632 -135.8011) (xy 272.315432 -135.8011) (xy 272.315432 -136.0043) (xy 272.518632 -136.0043)
			)
		)
		(polygon
			(pts
				(xy 269.216632 -135.8011) (xy 269.013432 -135.8011) (xy 269.013432 -136.0043) (xy 269.216632 -136.0043)
			)
		)
		(polygon
			(pts
				(xy 276.038564 -134.8105) (xy 275.835364 -134.8105) (xy 275.835364 -135.0137) (xy 276.038564 -135.0137)
			)
		)
		(polygon
			(pts
				(xy 272.518632 -134.8105) (xy 272.315432 -134.8105) (xy 272.315432 -135.0137) (xy 272.518632 -135.0137)
			)
		)
		(polygon
			(pts
				(xy 269.216632 -134.8105) (xy 269.013432 -134.8105) (xy 269.013432 -135.0137) (xy 269.216632 -135.0137)
			)
		)
	)
	(zone
		(net "PVCCMCP_CPU0")
		(layer "B.Cu")
		(hatch none 0.5)
		(connect_pads
			(clearance 0.5)
		)
		(min_thickness 0.25)
		(fill yes
			(thermal_gap 0.5)
			(thermal_bridge_width 0.5)
			(island_removal_mode 0)
		)
		(polygon
			(pts
				(xy 277.6982 -74.676) (xy 277.8506 -74.5236) (xy 277.8506 -73.3298) (xy 277.495 -72.9742) (xy 274.2946 -72.9742)
				(xy 270.9418 -72.9742) (xy 268.9606 -72.9742) (xy 268.9098 -73.025) (xy 268.9098 -74.2442) (xy 269.3416 -74.676)
				(xy 271.018 -74.676) (xy 274.574 -74.676)
			)
		)
	)
	(zone
		(net "VR_FET_SW_P12V_STBY_PVDDQ_KLM")
		(layer "B.Cu")
		(hatch none 0.5)
		(connect_pads
			(clearance 0.5)
		)
		(min_thickness 0.25)
		(fill yes
			(thermal_gap 0.5)
			(thermal_bridge_width 0.5)
			(island_removal_mode 0)
		)
		(polygon
			(pts
				(xy -0.8128 -147.574) (xy -1.27 -148.0312) (xy -1.27 -148.8948) (xy -1.8542 -149.479) (xy -1.8542 -151.2062)
				(xy -1.651 -151.4094) (xy 1.4732 -151.4094) (xy 1.837182 -151.045418) (xy 1.8542 -151.0284) (xy 1.8542 -145.7452)
				(xy 1.7526 -145.6436) (xy 1.0668 -145.6436) (xy 0.8255 -145.8849) (xy 0.8255 -147.4089) (xy 0.6604 -147.574)
			)
		)
	)
	(zone
		(net "PVDDQ_DEF")
		(layer "B.Cu")
		(hatch none 0.5)
		(connect_pads
			(clearance 0.5)
		)
		(min_thickness 0.25)
		(fill yes
			(thermal_gap 0.5)
			(thermal_bridge_width 0.5)
			(island_removal_mode 0)
		)
		(polygon
			(pts
				(xy 272.658078 -138.918188) (xy 272.54962 -139.026646) (xy 272.54962 -139.444222) (xy 272.24228 -139.751562)
				(xy 266.05992 -139.751562) (xy 265.678158 -140.133324) (xy 265.678158 -141.086332) (xy 265.979148 -141.387322)
				(xy 277.326598 -141.387322) (xy 277.529036 -141.184884) (xy 277.529036 -139.118594) (xy 277.32863 -138.918188)
			)
		)
		(polygon
			(pts
				(xy 266.054332 -140.4874) (xy 265.851132 -140.4874) (xy 265.851132 -140.6906) (xy 266.054332 -140.6906)
			)
		)
	)
	(zone
		(layer "B.Cu")
		(hatch none 0.5)
		(connect_pads
			(clearance 0)
		)
		(min_thickness 0.25)
		(keepout
			(tracks not_allowed)
			(vias allowed)
			(pads allowed)
			(copperpour not_allowed)
			(footprints allowed)
		)
		(placement
			(enabled no)
			(sheetname "")
		)
		(fill
			(thermal_gap 0.5)
			(thermal_bridge_width 0.5)
			(island_removal_mode 0)
		)
		(polygon
			(pts
				(arc
					(start 56.999886 -79.090012)
					(mid 59.539886 -76.550012)
					(end 56.999886 -74.010012)
				)
				(arc
					(start 56.999886 -74.010012)
					(mid 54.459886 -76.550012)
					(end 56.999886 -79.090012)
				)
			)
		)
	)
	(zone
		(net "P3V3_STBY")
		(layer "B.Cu")
		(hatch none 0.5)
		(connect_pads
			(clearance 0.5)
		)
		(min_thickness 0.25)
		(fill yes
			(thermal_gap 0.5)
			(thermal_bridge_width 0.5)
			(island_removal_mode 0)
		)
		(polygon
			(pts
				(xy 410.845 -48.46066) (xy 410.77896 -48.39462) (xy 408.52598 -48.39462) (xy 408.178 -48.7426) (xy 408.178 -50.23358)
				(xy 408.38882 -50.4444) (xy 410.5783 -50.4444) (xy 410.845 -50.1777)
			)
		)
	)
	(zone
		(net "P12V_STBY")
		(layer "B.Cu")
		(hatch none 0.5)
		(connect_pads
			(clearance 0.5)
		)
		(min_thickness 0.25)
		(fill yes
			(thermal_gap 0.5)
			(thermal_bridge_width 0.5)
			(island_removal_mode 0)
		)
		(polygon
			(pts
				(xy 358.7496 -35.6616) (xy 359.537 -34.8742) (xy 359.537 -31.44266) (xy 359.321608 -31.227268) (xy 355.558852 -31.227268)
				(xy 355.090984 -30.7594) (xy 353.3394 -30.7594) (xy 352.933 -31.1658) (xy 352.933 -32.639) (xy 352.425 -33.147)
				(xy 350.266 -33.147) (xy 349.885 -33.528) (xy 349.885 -36.068) (xy 353.695 -36.068) (xy 358.3432 -36.068)
			)
		)
	)
	(zone
		(layer "B.Cu")
		(hatch none 0.5)
		(connect_pads
			(clearance 0)
		)
		(min_thickness 0.25)
		(keepout
			(tracks not_allowed)
			(vias allowed)
			(pads allowed)
			(copperpour not_allowed)
			(footprints allowed)
		)
		(placement
			(enabled no)
			(sheetname "")
		)
		(fill
			(thermal_gap 0.5)
			(thermal_bridge_width 0.5)
			(island_removal_mode 0)
		)
		(polygon
			(pts
				(arc
					(start 318.000126 -96.650048)
					(mid 316.100206 -98.549968)
					(end 318.000126 -100.449888)
				)
				(arc
					(start 318.000126 -100.449888)
					(mid 319.900046 -98.549968)
					(end 318.000126 -96.650048)
				)
			)
		)
	)
	(zone
		(net "P12V_STBY")
		(layer "B.Cu")
		(hatch none 0.5)
		(connect_pads
			(clearance 0.5)
		)
		(min_thickness 0.25)
		(fill yes
			(thermal_gap 0.5)
			(thermal_bridge_width 0.5)
			(island_removal_mode 0)
		)
		(polygon
			(pts
				(xy 488.696 -114.046) (xy 488.696 -112.875314) (xy 488.442 -112.621314) (xy 488.442 -112.4712) (xy 488.442 -111.3536)
				(xy 488.442 -110.5408) (xy 488.2896 -110.3884) (xy 486.156 -110.3884) (xy 485.902 -110.6424) (xy 485.902 -111.252)
				(xy 485.902 -111.2774) (xy 485.902 -113.9698) (xy 485.91089 -113.97869) (xy 485.91089 -115.93449)
				(xy 487.4514 -117.475) (xy 487.4514 -118.999) (xy 487.7816 -119.3292) (xy 490.6772 -119.3292) (xy 491.109 -118.8974)
				(xy 491.109 -116.739162) (xy 488.696 -114.326162)
			)
		)
	)
	(zone
		(net "P0V7_GTL2014_2")
		(layer "B.Cu")
		(hatch none 0.5)
		(connect_pads
			(clearance 0.5)
		)
		(min_thickness 0.25)
		(fill yes
			(thermal_gap 0.5)
			(thermal_bridge_width 0.5)
			(island_removal_mode 0)
		)
		(polygon
			(pts
				(xy 439.39968 -14.224) (xy 437.326278 -14.224) (xy 437.2864 -14.184122) (xy 437.2864 -13.8176) (xy 437.3626 -13.7414)
				(xy 439.77306 -13.7414) (xy 440.3725 -13.14196) (xy 441.02528 -13.14196) (xy 441.3504 -12.81684)
				(xy 442.05144 -12.81684) (xy 442.087 -12.8524) (xy 442.087 -14.986) (xy 442.214 -15.113) (xy 442.341 -15.24)
				(xy 442.4934 -15.24) (xy 442.6204 -15.367) (xy 442.6204 -15.9258) (xy 442.4934 -16.0528) (xy 441.8584 -16.0528)
				(xy 441.7568 -15.9512) (xy 441.7568 -15.5448) (xy 441.6806 -15.4686) (xy 441.452 -15.24) (xy 441.325 -15.113)
				(xy 441.1853 -14.9733) (xy 441.1853 -14.6177) (xy 441.1853 -14.4653) (xy 441.0583 -14.3383) (xy 440.4487 -14.3383)
				(xy 440.3344 -14.224)
			)
		)
	)
	(zone
		(layer "B.Cu")
		(hatch none 0.5)
		(connect_pads
			(clearance 0)
		)
		(min_thickness 0.25)
		(keepout
			(tracks allowed)
			(vias allowed)
			(pads allowed)
			(copperpour allowed)
			(footprints not_allowed)
		)
		(placement
			(enabled no)
			(sheetname "")
		)
		(fill
			(thermal_gap 0.5)
			(thermal_bridge_width 0.5)
			(island_removal_mode 0)
		)
		(polygon
			(pts
				(arc
					(start 474.49994 -159.100012)
					(mid 478.499932 -155.10002)
					(end 474.49994 -151.100028)
				)
				(arc
					(start 471.000074 -151.100028)
					(mid 467.000082 -155.10002)
					(end 471.000074 -159.100012)
				)
			)
		)
	)
	(zone
		(layer "B.Cu")
		(hatch none 0.5)
		(connect_pads
			(clearance 0)
		)
		(min_thickness 0.25)
		(keepout
			(tracks not_allowed)
			(vias allowed)
			(pads allowed)
			(copperpour not_allowed)
			(footprints allowed)
		)
		(placement
			(enabled no)
			(sheetname "")
		)
		(fill
			(thermal_gap 0.5)
			(thermal_bridge_width 0.5)
			(island_removal_mode 0)
		)
		(polygon
			(pts
				(arc
					(start 4.629912 -46.90999)
					(mid 6.229858 -45.310044)
					(end 4.629912 -43.710098)
				)
				(arc
					(start 4.629912 -43.710098)
					(mid 3.029966 -45.310044)
					(end 4.629912 -46.90999)
				)
			)
		)
	)
	(zone
		(net "GND")
		(layer "B.Cu")
		(hatch none 0.5)
		(connect_pads
			(clearance 0.5)
		)
		(min_thickness 0.25)
		(fill yes
			(thermal_gap 0.5)
			(thermal_bridge_width 0.5)
			(island_removal_mode 0)
		)
		(polygon
			(pts
				(xy 96.441768 -27.559) (xy 99.794568 -27.559) (xy 99.946968 -27.4066) (xy 99.946968 -26.4414) (xy 98.803968 -25.2984)
				(xy 98.803968 -24.7396) (xy 98.168968 -24.1046) (xy 97.584768 -24.1046) (xy 97.457768 -24.2316)
				(xy 97.457768 -25.1968) (xy 96.416368 -26.2382) (xy 96.416368 -27.5336)
			)
		)
	)
	(zone
		(layer "B.Cu")
		(hatch none 0.5)
		(connect_pads
			(clearance 0)
		)
		(min_thickness 0.25)
		(keepout
			(tracks not_allowed)
			(vias allowed)
			(pads allowed)
			(copperpour not_allowed)
			(footprints allowed)
		)
		(placement
			(enabled no)
			(sheetname "")
		)
		(fill
			(thermal_gap 0.5)
			(thermal_bridge_width 0.5)
			(island_removal_mode 0)
		)
		(polygon
			(pts
				(arc
					(start 471.000074 5.999988)
					(mid 467.000082 1.999996)
					(end 471.000074 -1.999996)
				)
				(arc
					(start 474.49994 -1.999996)
					(mid 478.499932 1.999996)
					(end 474.49994 5.999988)
				)
			)
		)
	)
	(zone
		(net "PVDDQ_GHJ")
		(layer "B.Cu")
		(hatch none 0.5)
		(connect_pads
			(clearance 0.5)
		)
		(min_thickness 0.25)
		(fill yes
			(thermal_gap 0.5)
			(thermal_bridge_width 0.5)
			(island_removal_mode 0)
		)
		(polygon
			(pts
				(xy 100.743512 -21.3106) (xy 100.743512 -22.1488) (xy 101.454712 -22.86) (xy 101.454712 -23.5966)
				(xy 101.618796 -23.760684) (xy 112.381284 -23.760684) (xy 112.850168 -23.2918) (xy 112.850168 -21.5138)
				(xy 112.622584 -21.286216) (xy 100.767896 -21.286216)
			)
		)
	)
	(zone
		(net "AGND_PVPP_DEF")
		(layer "B.Cu")
		(hatch none 0.5)
		(connect_pads
			(clearance 0.5)
		)
		(min_thickness 0.25)
		(fill yes
			(thermal_gap 0.5)
			(thermal_bridge_width 0.5)
			(island_removal_mode 0)
		)
		(polygon
			(pts
				(xy 336.3468 -126.71425) (xy 336.3468 -130.2004) (xy 336.822796 -130.676396) (xy 339.75294 -130.676396)
				(xy 339.772244 -130.657092) (xy 340.585044 -130.657092) (xy 340.59368 -130.648456) (xy 340.8934 -130.34899)
				(xy 340.8934 -130.2512) (xy 340.8934 -129.7178) (xy 340.741 -129.5654) (xy 339.931248 -129.5654)
				(xy 339.657182 -129.839466) (xy 338.426298 -129.839466) (xy 338.071206 -129.484374) (xy 338.071206 -128.326134)
				(xy 338.0994 -128.29794) (xy 338.569046 -127.828294) (xy 342.331294 -127.828294) (xy 343.887044 -129.384044)
				(xy 343.887044 -130.4036) (xy 344.039444 -130.556) (xy 345.3384 -130.556) (xy 345.56446 -130.32994)
				(xy 345.56446 -129.05486) (xy 342.967818 -126.458218) (xy 336.602832 -126.458218)
			)
		)
	)
	(zone
		(layer "B.Cu")
		(hatch none 0.5)
		(connect_pads
			(clearance 0)
		)
		(min_thickness 0.25)
		(keepout
			(tracks not_allowed)
			(vias allowed)
			(pads allowed)
			(copperpour not_allowed)
			(footprints allowed)
		)
		(placement
			(enabled no)
			(sheetname "")
		)
		(fill
			(thermal_gap 0.5)
			(thermal_bridge_width 0.5)
			(island_removal_mode 0)
		)
		(polygon
			(pts
				(arc
					(start 1.928622 -157.04439)
					(mid 1.338226 -156.714333)
					(end 0.671576 -156.59989)
				)
				(arc
					(start 0 -156.59989)
					(mid -1.49987 -155.10002)
					(end 0 -153.599896)
				)
				(arc
					(start 0.671576 -153.599896)
					(mid 1.338203 -153.485602)
					(end 1.928622 -153.15565)
				)
				(arc
					(start 1.928622 -153.15565)
					(mid 5.999742 -155.10002)
					(end 1.928622 -157.04439)
				)
			)
		)
	)
	(zone
		(layer "B.Cu")
		(hatch none 0.5)
		(connect_pads
			(clearance 0)
		)
		(min_thickness 0.25)
		(keepout
			(tracks not_allowed)
			(vias allowed)
			(pads allowed)
			(copperpour not_allowed)
			(footprints allowed)
		)
		(placement
			(enabled no)
			(sheetname "")
		)
		(fill
			(thermal_gap 0.5)
			(thermal_bridge_width 0.5)
			(island_removal_mode 0)
		)
		(polygon
			(pts
				(xy 95.705168 3.0988) (xy 95.705168 3.683) (xy 95.832168 3.683) (xy 95.832168 3.0988)
			)
		)
	)
	(zone
		(net "GND")
		(layer "B.Cu")
		(hatch none 0.5)
		(connect_pads
			(clearance 0.5)
		)
		(min_thickness 0.25)
		(fill yes
			(thermal_gap 0.5)
			(thermal_bridge_width 0.5)
			(island_removal_mode 0)
		)
		(polygon
			(pts
				(xy 469.248744 -7.99592) (xy 469.655144 -7.99592) (xy 469.756744 -7.89432) (xy 469.756744 -4.26212)
				(xy 469.705944 -4.21132) (xy 469.274144 -4.21132) (xy 469.172544 -4.31292) (xy 469.172544 -4.7752)
				(xy 469.17102 -4.776724) (xy 469.17102 -5.144008) (xy 469.006936 -5.308092) (xy 469.006936 -6.441186)
				(xy 468.919306 -6.528816) (xy 468.480902 -6.528816) (xy 468.442548 -6.56717) (xy 468.442548 -7.780528)
				(xy 468.65794 -7.99592)
			)
		)
	)
	(zone
		(net "P12V_PSU")
		(layer "B.Cu")
		(hatch none 0.5)
		(connect_pads
			(clearance 0.5)
		)
		(min_thickness 0.25)
		(fill yes
			(thermal_gap 0.5)
			(thermal_bridge_width 0.5)
			(island_removal_mode 0)
		)
		(polygon
			(pts
				(xy 10.541 -79.837534) (xy 10.541 -76.2254) (xy 10.541 -71.5772) (xy 9.7282 -70.7644) (xy 8.4836 -70.7644)
				(xy 7.9502 -70.231) (xy 7.9502 -67.9958) (xy 9.034272 -66.911728) (xy 9.034272 -65.413128)
				(arc
					(start 7.366 -65.413128)
					(mid 7.316411 -65.410299)
					(end 7.267448 -65.401952)
				)
				(xy 7.26059 -65.400428) (xy 5.536692 -65.400428) (xy 5.536692 -64.535812) (xy 7.26059 -64.535812)
				(arc
					(start 7.267448 -64.534288)
					(mid 7.316412 -64.525951)
					(end 7.366 -64.523112)
				)
				(xy 9.0424 -64.523112) (xy 9.0424 -62.947296) (xy 9.677908 -62.311788) (xy 9.677908 -57.646062)
				(xy 11.646916 -55.677054) (xy 11.788394 -55.677054) (xy 14.144752 -55.677054) (xy 14.225016 -55.59679)
				(xy 14.225016 -51.207416) (xy 13.716 -50.6984) (xy 13.0556 -50.038) (xy 2.7432 -50.038) (xy 2.55397 -49.84877)
				(xy 1.86817 -49.84877) (xy 1.8542 -49.86274) (xy 1.8542 -49.973992) (xy 1.854708 -49.973992) (xy 1.854708 -50.368708)
				(xy 2.2606 -50.7746) (xy 3.048 -51.562) (xy 3.0734 -51.576986) (xy 3.0734 -58.9026) (xy 2.322068 -59.653932)
				(xy 2.322068 -62.299596) (xy 2.5146 -62.492128) (xy 2.5146 -67.3354) (xy 3.5306 -68.3514) (xy 3.5306 -85.587332)
				(xy 4.135374 -86.192106) (xy 9.83234 -86.192106) (xy 11.15822 -86.192106) (xy 13.758926 -83.5914)
				(xy 13.918692 -83.431634) (xy 13.918692 -82.906362) (xy 13.814044 -82.801714) (xy 13.177012 -82.801714)
				(xy 12.898628 -82.52333) (xy 12.898628 -82.189828) (xy 12.1666 -81.4578) (xy 12.161266 -81.4578)
			)
		)
	)
	(zone
		(layer "B.Cu")
		(hatch none 0.5)
		(connect_pads
			(clearance 0)
		)
		(min_thickness 0.25)
		(keepout
			(tracks allowed)
			(vias allowed)
			(pads allowed)
			(copperpour allowed)
			(footprints not_allowed)
		)
		(placement
			(enabled no)
			(sheetname "")
		)
		(fill
			(thermal_gap 0.5)
			(thermal_bridge_width 0.5)
			(island_removal_mode 0)
		)
		(polygon
			(pts
				(arc
					(start -5.999988 -157.599888)
					(mid -4.658434 -155.09995)
					(end -5.999988 -152.599898)
				)
			)
		)
	)
	(zone
		(layer "B.Cu")
		(hatch none 0.5)
		(connect_pads
			(clearance 0)
		)
		(min_thickness 0.25)
		(keepout
			(tracks allowed)
			(vias allowed)
			(pads allowed)
			(copperpour allowed)
			(footprints not_allowed)
		)
		(placement
			(enabled no)
			(sheetname "")
		)
		(fill
			(thermal_gap 0.5)
			(thermal_bridge_width 0.5)
			(island_removal_mode 0)
		)
		(polygon
			(pts
				(arc
					(start 171.309792 5.999988)
					(mid 167.98095 1.778374)
					(end 171.809918 -1.995424)
				)
				(xy 171.809918 -25.733248) (xy 165.159944 -25.733248) (xy 165.159944 5.999988)
			)
		)
	)
	(zone
		(layer "B.Cu")
		(hatch none 0.5)
		(connect_pads
			(clearance 0)
		)
		(min_thickness 0.25)
		(keepout
			(tracks not_allowed)
			(vias allowed)
			(pads allowed)
			(copperpour not_allowed)
			(footprints allowed)
		)
		(placement
			(enabled no)
			(sheetname "")
		)
		(fill
			(thermal_gap 0.5)
			(thermal_bridge_width 0.5)
			(island_removal_mode 0)
		)
		(polygon
			(pts
				(arc
					(start 152.999948 -57.090056)
					(mid 155.539948 -54.550056)
					(end 152.999948 -52.010056)
				)
				(arc
					(start 152.999948 -52.010056)
					(mid 150.459948 -54.550056)
					(end 152.999948 -57.090056)
				)
			)
		)
	)
	(zone
		(net "GND")
		(layer "B.Cu")
		(hatch none 0.5)
		(connect_pads
			(clearance 0.5)
		)
		(min_thickness 0.25)
		(fill yes
			(thermal_gap 0.5)
			(thermal_bridge_width 0.5)
			(island_removal_mode 0)
		)
		(polygon
			(pts
				(xy 471.1446 -13.589) (xy 469.1634 -13.589) (xy 469.011 -13.7414) (xy 469.011 -14.5288) (xy 469.1634 -14.6812)
				(xy 472.9988 -14.6812) (xy 473.075 -14.605) (xy 473.075 -13.843) (xy 472.821 -13.589)
			)
		)
	)
	(zone
		(net "PVDDQ_ABC")
		(layer "B.Cu")
		(hatch none 0.5)
		(connect_pads
			(clearance 0.5)
		)
		(min_thickness 0.25)
		(fill yes
			(thermal_gap 0.5)
			(thermal_bridge_width 0.5)
			(island_removal_mode 0)
		)
		(polygon
			(pts
				(xy 272.6436 0.1778) (xy 277.3172 0.1778) (xy 277.5712 0.4318) (xy 277.5712 2.5908) (xy 277.4696 2.6924)
				(xy 272.5293 2.6924) (xy 272.4785 2.7432) (xy 268.2494 2.7432) (xy 268.1986 2.6924) (xy 266.8778 2.6924)
				(xy 266.7762 2.5908) (xy 266.7762 1.6256) (xy 266.8778 1.524) (xy 266.9794 1.524) (xy 267.335 1.1684)
				(xy 270.0528 1.1684) (xy 270.7132 1.8288) (xy 271.7038 1.8288) (xy 272.3388 1.1938) (xy 272.3388 0.4826)
			)
		)
	)
	(zone
		(layer "B.Cu")
		(hatch none 0.5)
		(connect_pads
			(clearance 0)
		)
		(min_thickness 0.25)
		(keepout
			(tracks allowed)
			(vias allowed)
			(pads allowed)
			(copperpour allowed)
			(footprints not_allowed)
		)
		(placement
			(enabled no)
			(sheetname "")
		)
		(fill
			(thermal_gap 0.5)
			(thermal_bridge_width 0.5)
			(island_removal_mode 0)
		)
		(polygon
			(pts
				(xy 179.23002 -159.104584)
				(arc
					(start 175.50003 -159.100012)
					(mid 177.760669 -158.399936)
					(end 179.23002 -156.544772)
				)
			)
		)
	)
	(zone
		(layer "B.Cu")
		(hatch none 0.5)
		(connect_pads
			(clearance 0)
		)
		(min_thickness 0.25)
		(keepout
			(tracks not_allowed)
			(vias allowed)
			(pads allowed)
			(copperpour not_allowed)
			(footprints allowed)
		)
		(placement
			(enabled no)
			(sheetname "")
		)
		(fill
			(thermal_gap 0.5)
			(thermal_bridge_width 0.5)
			(island_removal_mode 0)
		)
		(polygon
			(pts
				(arc
					(start 3.50012 -159.100012)
					(mid 7.500112 -155.10002)
					(end 3.50012 -151.100028)
				)
				(arc
					(start 0 -151.100028)
					(mid -3.999992 -155.10002)
					(end 0 -159.100012)
				)
			)
		)
	)
	(zone
		(layer "B.Cu")
		(hatch none 0.5)
		(connect_pads
			(clearance 0)
		)
		(min_thickness 0.25)
		(keepout
			(tracks allowed)
			(vias allowed)
			(pads allowed)
			(copperpour allowed)
			(footprints not_allowed)
		)
		(placement
			(enabled no)
			(sheetname "")
		)
		(fill
			(thermal_gap 0.5)
			(thermal_bridge_width 0.5)
			(island_removal_mode 0)
		)
		(polygon
			(pts
				(arc
					(start 33.919922 -108.100114)
					(mid 35.46983 -106.550206)
					(end 33.919922 -105.000044)
				)
				(arc
					(start 33.919922 -105.000044)
					(mid 32.36976 -106.550206)
					(end 33.919922 -108.100114)
				)
			)
		)
	)
	(zone
		(layer "B.Cu")
		(hatch none 0.5)
		(connect_pads
			(clearance 0)
		)
		(min_thickness 0.25)
		(keepout
			(tracks allowed)
			(vias allowed)
			(pads allowed)
			(copperpour allowed)
			(footprints not_allowed)
		)
		(placement
			(enabled no)
			(sheetname "")
		)
		(fill
			(thermal_gap 0.5)
			(thermal_bridge_width 0.5)
			(island_removal_mode 0)
		)
		(polygon
			(pts
				(xy 9.569958 5.999988) (xy 12.07008 5.999988) (xy 12.07008 -25.733248) (xy 9.569958 -25.733248)
			)
		)
	)
	(zone
		(net "P12V_STBY")
		(layer "B.Cu")
		(hatch none 0.5)
		(connect_pads
			(clearance 0.5)
		)
		(min_thickness 0.25)
		(fill yes
			(thermal_gap 0.5)
			(thermal_bridge_width 0.5)
			(island_removal_mode 0)
		)
		(polygon
			(pts
				(xy 20.3708 -66.1924) (xy 20.3708 -58.0898) (xy 20.6248 -57.8358) (xy 22.0218 -57.8358) (xy 22.3774 -57.4802)
				(xy 25.273 -57.4802) (xy 25.4508 -57.658) (xy 25.4508 -60.1726) (xy 24.87295 -60.75045) (xy 24.86025 -60.75045)
				(xy 24.7904 -60.8203) (xy 24.7904 -61.3918) (xy 24.87295 -61.47435) (xy 25.3746 -61.976) (xy 25.3746 -66.2432)
				(xy 24.8666 -66.7512) (xy 20.9296 -66.7512)
			)
		)
	)
	(zone
		(layer "B.Cu")
		(hatch none 0.5)
		(connect_pads
			(clearance 0)
		)
		(min_thickness 0.25)
		(keepout
			(tracks allowed)
			(vias allowed)
			(pads allowed)
			(copperpour allowed)
			(footprints allowed)
		)
		(placement
			(enabled no)
			(sheetname "")
		)
		(fill
			(thermal_gap 0.5)
			(thermal_bridge_width 0.5)
			(island_removal_mode 0)
		)
		(polygon
			(pts
				(xy 338.6328 -90.5002) (xy 343.154 -90.5002) (xy 344.3986 -89.2556) (xy 344.3986 -89.0778) (xy 344.2843 -88.9635)
				(xy 344.2843 -85.2297) (xy 344.1954 -85.1408) (xy 344.1446 -85.1408) (xy 343.281 -84.2772) (xy 343.281 -83.7692)
				(xy 342.9254 -83.4136) (xy 339.6488 -83.4136) (xy 338.8868 -84.1756) (xy 338.8868 -85.852) (xy 338.963 -85.9282)
				(xy 337.9216 -86.9696) (xy 337.3374 -86.9696) (xy 337.3374 -89.2048)
			)
		)
	)
	(zone
		(layer "B.Cu")
		(hatch none 0.5)
		(connect_pads
			(clearance 0)
		)
		(min_thickness 0.25)
		(keepout
			(tracks allowed)
			(vias allowed)
			(pads allowed)
			(copperpour allowed)
			(footprints allowed)
		)
		(placement
			(enabled no)
			(sheetname "")
		)
		(fill
			(thermal_gap 0.5)
			(thermal_bridge_width 0.5)
			(island_removal_mode 0)
		)
		(polygon
			(pts
				(xy 316.357 -93.599) (xy 316.357 -92.837) (xy 317.119 -92.837) (xy 317.119 -93.599)
			)
		)
	)
	(zone
		(layer "B.Cu")
		(hatch none 0.5)
		(connect_pads
			(clearance 0)
		)
		(min_thickness 0.25)
		(keepout
			(tracks allowed)
			(vias allowed)
			(pads allowed)
			(copperpour allowed)
			(footprints allowed)
		)
		(placement
			(enabled no)
			(sheetname "")
		)
		(fill
			(thermal_gap 0.5)
			(thermal_bridge_width 0.5)
			(island_removal_mode 0)
		)
		(polygon
			(pts
				(xy 366.9284 -113.9444) (xy 366.9284 -112.6744) (xy 368.6302 -112.6744) (xy 368.6302 -113.9444)
			)
		)
	)
	(zone
		(layer "B.Cu")
		(hatch none 0.5)
		(connect_pads
			(clearance 0)
		)
		(min_thickness 0.25)
		(keepout
			(tracks allowed)
			(vias allowed)
			(pads allowed)
			(copperpour allowed)
			(footprints not_allowed)
		)
		(placement
			(enabled no)
			(sheetname "")
		)
		(fill
			(thermal_gap 0.5)
			(thermal_bridge_width 0.5)
			(island_removal_mode 0)
		)
		(polygon
			(pts
				(arc
					(start 127 -43.450002)
					(mid 128.89992 -41.550082)
					(end 127 -39.649908)
				)
				(arc
					(start 127 -39.649908)
					(mid 125.099826 -41.550082)
					(end 127 -43.450002)
				)
			)
		)
	)
	(zone
		(net "VCC_D_3V3")
		(layer "B.Cu")
		(hatch none 0.5)
		(connect_pads
			(clearance 0.5)
		)
		(min_thickness 0.25)
		(fill yes
			(thermal_gap 0.5)
			(thermal_bridge_width 0.5)
			(island_removal_mode 0)
		)
		(polygon
			(pts
				(xy 414.616646 -38.744652) (xy 414.489646 -38.871652) (xy 414.489646 -40.2082) (xy 414.247076 -40.45077)
				(xy 414.247076 -42.543476) (xy 413.868616 -42.921682) (xy 413.868616 -44.589446) (xy 414.497012 -45.217842)
				(xy 414.497012 -45.826426) (xy 413.978344 -46.345094) (xy 413.978344 -46.904656) (xy 413.258 -47.625)
				(xy 413.258 -49.022) (xy 413.343344 -49.107344) (xy 414.18256 -49.107344) (xy 414.241488 -49.048416)
				(xy 414.241488 -47.810166) (xy 414.313624 -47.73803) (xy 414.664144 -47.73803) (xy 415.009584 -47.39259)
				(xy 415.009584 -47.016416) (xy 415.2138 -46.8122) (xy 415.2138 -44.50715) (xy 415.213038 -44.507912)
				(xy 415.213038 -42.897044) (xy 415.124646 -42.808652) (xy 415.124646 -40.395652) (xy 415.251646 -40.268652)
				(xy 415.759646 -40.268652) (xy 415.886646 -40.141652) (xy 415.886646 -39.506652) (xy 415.759646 -39.379652)
				(xy 415.124646 -39.379652) (xy 414.997646 -39.252652) (xy 414.997646 -38.871652) (xy 414.870646 -38.744652)
			)
		)
		(polygon
			(pts
				(xy 415.099246 -40.014652) (xy 414.896046 -40.014652) (xy 414.896046 -40.217852) (xy 415.099246 -40.217852)
			)
		)
	)
	(zone
		(layer "B.Cu")
		(hatch none 0.5)
		(connect_pads
			(clearance 0)
		)
		(min_thickness 0.25)
		(keepout
			(tracks allowed)
			(vias allowed)
			(pads allowed)
			(copperpour allowed)
			(footprints not_allowed)
		)
		(placement
			(enabled no)
			(sheetname "")
		)
		(fill
			(thermal_gap 0.5)
			(thermal_bridge_width 0.5)
			(island_removal_mode 0)
		)
		(polygon
			(pts
				(arc
					(start 198.930006 -48.09998)
					(mid 200.479914 -46.550072)
					(end 198.930006 -44.99991)
				)
				(arc
					(start 198.930006 -44.99991)
					(mid 197.379844 -46.550072)
					(end 198.930006 -48.09998)
				)
			)
		)
	)
	(zone
		(net "GND")
		(layer "B.Cu")
		(hatch none 0.5)
		(connect_pads
			(clearance 0.5)
		)
		(min_thickness 0.25)
		(fill yes
			(thermal_gap 0.5)
			(thermal_bridge_width 0.5)
			(island_removal_mode 0)
		)
		(polygon
			(pts
				(xy 280.488898 -146.261836) (xy 278.670512 -146.261836) (xy 278.469852 -146.061176) (xy 278.469852 -143.848074)
				(xy 278.676862 -143.641064) (xy 280.463244 -143.641064) (xy 280.708862 -143.886682) (xy 280.708862 -146.041872)
			)
		)
	)
	(zone
		(net "P1V15_AUX_BMC")
		(layer "B.Cu")
		(hatch none 0.5)
		(connect_pads
			(clearance 0.5)
		)
		(min_thickness 0.25)
		(fill yes
			(thermal_gap 0.5)
			(thermal_bridge_width 0.5)
			(island_removal_mode 0)
		)
		(polygon
			(pts
				(xy 458.1398 -40.259) (xy 459.2574 -40.259) (xy 460.9338 -40.259) (xy 460.9592 -40.2844) (xy 460.9592 -42.5958)
				(xy 460.9592 -42.926) (xy 460.5147 -43.3705) (xy 458.0382 -43.3705) (xy 457.88072 -43.3705) (xy 457.50734 -42.99712)
				(xy 457.50734 -40.71366) (xy 457.962 -40.259)
			)
		)
	)
	(zone
		(net "PVSA_CPU1")
		(layer "B.Cu")
		(hatch none 0.5)
		(connect_pads
			(clearance 0.5)
		)
		(min_thickness 0.25)
		(fill yes
			(thermal_gap 0.5)
			(thermal_bridge_width 0.5)
			(island_removal_mode 0)
		)
		(polygon
			(pts
				(xy 64.909954 -77.810614) (xy 49.875186 -92.845382) (xy 48.471836 -92.845382) (xy 48.471328 -92.84589)
				(xy 43.954954 -92.84589) (xy 43.17238 -93.628464) (xy 43.17238 -101.18598) (xy 44.0182 -102.0318)
				(xy 48.994568 -102.0318) (xy 60.60186 -90.424508) (xy 60.60186 -87.905082) (xy 63.112142 -85.3948)
				(xy 66.672968 -85.3948) (xy 68.034154 -84.033614) (xy 71.411592 -84.033614) (xy 82.7024 -84.040472)
				(xy 81.788 -83.126072) (xy 81.788 -82.8548) (xy 81.9658 -82.677) (xy 82.1944 -82.677) (xy 82.4738 -82.9564)
				(xy 82.8548 -82.9564) (xy 83.2358 -83.3374) (xy 83.6676 -83.3374) (xy 84.1756 -82.8294) (xy 84.7598 -82.8294)
				(xy 85.972904 -84.042504) (xy 89.170256 -84.044536) (xy 89.600786 -84.475066) (xy 93.001592 -84.475066)
				(xy 93.163644 -84.313014) (xy 93.788992 -84.313014) (xy 93.865192 -84.389214) (xy 93.865192 -84.398866)
				(xy 93.941392 -84.475066) (xy 97.719134 -84.475066) (xy 97.776792 -84.417408) (xy 97.776792 -83.1088)
				(xy 97.203768 -83.1088) (xy 96.5708 -82.475832) (xy 96.5708 -81.684368) (xy 96.379792 -81.493614)
				(xy 92.874592 -81.493614) (xy 91.737688 -80.35671) (xy 91.223592 -80.35671) (xy 91.090496 -80.223614)
				(xy 90.213688 -80.223614) (xy 90.080592 -80.35671) (xy 88.156288 -80.35671) (xy 87.896192 -80.096614)
				(xy 86.651592 -80.096614) (xy 86.270592 -79.715614) (xy 86.016592 -79.715614) (xy 85.508592 -79.207614)
				(xy 81.190592 -79.207614) (xy 80.047592 -80.350614) (xy 73.316592 -80.350614) (xy 68.871592 -77.810614)
			)
		)
		(polygon
			(pts
				(xy 49.9364 -98.2726) (xy 49.7332 -98.2726) (xy 49.7332 -98.4758) (xy 49.9364 -98.4758)
			)
		)
		(polygon
			(pts
				(xy 49.4284 -98.2726) (xy 49.2252 -98.2726) (xy 49.2252 -98.4758) (xy 49.4284 -98.4758)
			)
		)
		(polygon
			(pts
				(xy 49.911 -94.0943) (xy 49.7078 -94.0943) (xy 49.7078 -94.2975) (xy 49.911 -94.2975)
			)
		)
		(polygon
			(pts
				(xy 49.149 -94.0943) (xy 48.9458 -94.0943) (xy 48.9458 -94.2975) (xy 49.149 -94.2975)
			)
		)
	)
	(zone
		(layer "B.Cu")
		(hatch none 0.5)
		(connect_pads
			(clearance 0)
		)
		(min_thickness 0.25)
		(keepout
			(tracks not_allowed)
			(vias allowed)
			(pads allowed)
			(copperpour not_allowed)
			(footprints allowed)
		)
		(placement
			(enabled no)
			(sheetname "")
		)
		(fill
			(thermal_gap 0.5)
			(thermal_bridge_width 0.5)
			(island_removal_mode 0)
		)
		(polygon
			(pts
				(arc
					(start 409.963366 -148.845016)
					(mid 409.579826 -148.461476)
					(end 409.196286 -148.845016)
				)
				(arc
					(start 409.196286 -149.860762)
					(mid 409.579699 -150.244556)
					(end 409.963366 -149.861016)
				)
				(xy 409.963366 -149.58314)
				(arc
					(start 409.694126 -149.58314)
					(mid 409.671979 -149.58905)
					(end 409.655772 -149.605238)
				)
				(arc
					(start 409.655772 -149.605238)
					(mid 409.577184 -150.127743)
					(end 409.509976 -149.603714)
				)
				(xy 409.509976 -149.598634)
				(arc
					(start 409.51277 -149.59584)
					(mid 409.563938 -149.497402)
					(end 409.662376 -149.446234)
				)
				(xy 409.66517 -149.44344) (xy 409.963366 -149.44344) (xy 409.963366 -149.34184) (xy 409.66517 -149.34184)
				(arc
					(start 409.662376 -149.339046)
					(mid 409.563938 -149.287878)
					(end 409.51277 -149.18944)
				)
				(xy 409.509976 -149.186646)
				(arc
					(start 409.509976 -149.102318)
					(mid 409.579826 -148.578401)
					(end 409.649676 -149.102318)
				)
				(arc
					(start 409.649676 -149.15769)
					(mid 409.662695 -149.189121)
					(end 409.694126 -149.20214)
				)
				(xy 409.963366 -149.20214)
			)
		)
	)
	(zone
		(layer "B.Cu")
		(hatch none 0.5)
		(connect_pads
			(clearance 0)
		)
		(min_thickness 0.25)
		(keepout
			(tracks not_allowed)
			(vias allowed)
			(pads allowed)
			(copperpour not_allowed)
			(footprints allowed)
		)
		(placement
			(enabled no)
			(sheetname "")
		)
		(fill
			(thermal_gap 0.5)
			(thermal_bridge_width 0.5)
			(island_removal_mode 0)
		)
		(polygon
			(pts
				(arc
					(start 152.999948 -100.449888)
					(mid 154.899868 -98.549968)
					(end 152.999948 -96.650048)
				)
				(arc
					(start 152.999948 -96.650048)
					(mid 151.100028 -98.549968)
					(end 152.999948 -100.449888)
				)
			)
		)
	)
	(zone
		(net "GND")
		(layer "B.Cu")
		(hatch none 0.5)
		(connect_pads
			(clearance 0.5)
		)
		(min_thickness 0.25)
		(fill yes
			(thermal_gap 0.5)
			(thermal_bridge_width 0.5)
			(island_removal_mode 0)
		)
		(polygon
			(pts
				(xy 439.039 -63.119) (xy 438.531 -63.119) (xy 437.96966 -63.119) (xy 437.829198 -63.259462) (xy 437.829198 -65.624456)
				(xy 438.244742 -66.04) (xy 439.674 -66.04) (xy 439.928 -65.786) (xy 439.928 -63.5) (xy 439.547 -63.119)
			)
		)
	)
	(zone
		(net "GND")
		(layer "B.Cu")
		(hatch none 0.5)
		(connect_pads
			(clearance 0.5)
		)
		(min_thickness 0.25)
		(fill yes
			(thermal_gap 0.5)
			(thermal_bridge_width 0.5)
			(island_removal_mode 0)
		)
		(polygon
			(pts
				(xy 403.35454 -106.813096) (xy 402.280628 -107.887008) (xy 402.280628 -108.32846) (xy 401.845526 -108.763562)
				(xy 400.947636 -108.763562) (xy 400.679412 -109.031786) (xy 399.462244 -109.031786) (xy 399.421858 -108.9914)
				(xy 395.0462 -108.9914) (xy 394.5128 -109.5248) (xy 394.5128 -110.5662) (xy 394.701776 -110.755176)
				(xy 394.701776 -110.75924) (xy 395.145768 -111.203232) (xy 399.324068 -111.203232) (xy 399.7579 -110.7694)
				(xy 401.742148 -110.7694) (xy 403.479762 -109.031786) (xy 406.72385 -109.031786) (xy 407.043636 -108.712)
				(xy 407.043636 -106.876088) (xy 406.980644 -106.813096)
			)
		)
		(polygon
			(pts
				(xy 400.6596 -109.8169) (xy 400.4564 -109.8169) (xy 400.4564 -110.0201) (xy 400.6596 -110.0201)
			)
		)
		(polygon
			(pts
				(xy 399.8976 -109.8169) (xy 399.6944 -109.8169) (xy 399.6944 -110.0201) (xy 399.8976 -110.0201)
			)
		)
		(polygon
			(pts
				(xy 401.755356 -109.693456) (xy 401.552156 -109.693456) (xy 401.552156 -109.896656) (xy 401.755356 -109.896656)
			)
		)
		(polygon
			(pts
				(xy 400.993356 -109.693456) (xy 400.790156 -109.693456) (xy 400.790156 -109.896656) (xy 400.993356 -109.896656)
			)
		)
		(polygon
			(pts
				(xy 406.1206 -107.5944) (xy 405.9174 -107.5944) (xy 405.9174 -107.7976) (xy 406.1206 -107.7976)
			)
		)
		(polygon
			(pts
				(xy 405.6888 -107.5944) (xy 405.4856 -107.5944) (xy 405.4856 -107.7976) (xy 405.6888 -107.7976)
			)
		)
		(polygon
			(pts
				(xy 404.9268 -107.5944) (xy 404.7236 -107.5944) (xy 404.7236 -107.7976) (xy 404.9268 -107.7976)
			)
		)
		(polygon
			(pts
				(xy 404.495 -107.5944) (xy 404.2918 -107.5944) (xy 404.2918 -107.7976) (xy 404.495 -107.7976)
			)
		)
	)
	(zone
		(layer "B.Cu")
		(hatch none 0.5)
		(connect_pads
			(clearance 0)
		)
		(min_thickness 0.25)
		(keepout
			(tracks allowed)
			(vias allowed)
			(pads allowed)
			(copperpour allowed)
			(footprints not_allowed)
		)
		(placement
			(enabled no)
			(sheetname "")
		)
		(fill
			(thermal_gap 0.5)
			(thermal_bridge_width 0.5)
			(island_removal_mode 0)
		)
		(polygon
			(pts
				(arc
					(start 110.752382 -85.749892)
					(mid 111.014658 -85.714954)
					(end 111.258604 -85.612478)
				)
				(arc
					(start 117.061234 -82.206592)
					(mid 117.422786 -81.841094)
					(end 117.55501 -81.344262)
				)
				(arc
					(start 117.55501 -71.750682)
					(mid 117.425768 -71.25897)
					(end 117.071394 -70.894448)
				)
				(arc
					(start 111.423196 -67.488562)
					(mid 111.174797 -67.381577)
					(end 110.906814 -67.345052)
				)
				(arc
					(start 99.09302 -67.345052)
					(mid 98.825032 -67.381559)
					(end 98.576638 -67.488562)
				)
				(arc
					(start 92.928694 -70.894448)
					(mid 92.574411 -71.259022)
					(end 92.445078 -71.750682)
				)
				(arc
					(start 92.445078 -81.344262)
					(mid 92.57432 -81.835974)
					(end 92.928694 -82.200496)
				)
				(arc
					(start 98.576638 -85.606382)
					(mid 98.825037 -85.713367)
					(end 99.09302 -85.749892)
				)
			)
		)
	)
	(zone
		(layer "B.Cu")
		(hatch none 0.5)
		(connect_pads
			(clearance 0)
		)
		(min_thickness 0.25)
		(keepout
			(tracks allowed)
			(vias allowed)
			(pads allowed)
			(copperpour allowed)
			(footprints not_allowed)
		)
		(placement
			(enabled no)
			(sheetname "")
		)
		(fill
			(thermal_gap 0.5)
			(thermal_bridge_width 0.5)
			(island_removal_mode 0)
		)
		(polygon
			(pts
				(arc
					(start 152.96007 -60.41009)
					(mid 152.667177 -59.702985)
					(end 151.960072 -59.410092)
				)
				(arc
					(start 146.340068 -59.410092)
					(mid 145.632963 -59.702985)
					(end 145.34007 -60.41009)
				)
				(arc
					(start 145.34007 -67.55003)
					(mid 145.632963 -68.257135)
					(end 146.340068 -68.550028)
				)
				(arc
					(start 151.960072 -68.550028)
					(mid 152.667177 -68.257135)
					(end 152.96007 -67.55003)
				)
			)
		)
	)
	(zone
		(layer "B.Cu")
		(hatch none 0.5)
		(connect_pads
			(clearance 0)
		)
		(min_thickness 0.25)
		(keepout
			(tracks allowed)
			(vias allowed)
			(pads allowed)
			(copperpour allowed)
			(footprints not_allowed)
		)
		(placement
			(enabled no)
			(sheetname "")
		)
		(fill
			(thermal_gap 0.5)
			(thermal_bridge_width 0.5)
			(island_removal_mode 0)
		)
		(polygon
			(pts
				(arc
					(start 80.905096 -90.199972)
					(mid 81.364706 -90.009596)
					(end 81.555082 -89.549986)
				)
				(arc
					(start 81.555082 -85.199982)
					(mid 81.364706 -84.740372)
					(end 80.905096 -84.549996)
				)
				(arc
					(start 79.205074 -84.549996)
					(mid 78.745464 -84.740372)
					(end 78.555088 -85.199982)
				)
				(arc
					(start 78.555088 -89.549986)
					(mid 78.745464 -90.009596)
					(end 79.205074 -90.199972)
				)
			)
		)
	)
	(zone
		(layer "B.Cu")
		(hatch none 0.5)
		(connect_pads
			(clearance 0)
		)
		(min_thickness 0.25)
		(keepout
			(tracks allowed)
			(vias allowed)
			(pads allowed)
			(copperpour allowed)
			(footprints allowed)
		)
		(placement
			(enabled no)
			(sheetname "")
		)
		(fill
			(thermal_gap 0.5)
			(thermal_bridge_width 0.5)
			(island_removal_mode 0)
		)
		(polygon
			(pts
				(xy 149.479 -85.598) (xy 149.479 -84.836) (xy 150.241 -84.836) (xy 150.241 -85.598)
			)
		)
	)
	(zone
		(net "PVDDQ_ABC")
		(layer "B.Cu")
		(hatch none 0.5)
		(connect_pads
			(clearance 0.5)
		)
		(min_thickness 0.25)
		(fill yes
			(thermal_gap 0.5)
			(thermal_bridge_width 0.5)
			(island_removal_mode 0)
		)
		(polygon
			(pts
				(xy 258.1529 -6.7183) (xy 258.1402 -6.731) (xy 244.200934 -6.731) (xy 243.79428 -7.137654) (xy 243.79428 -9.149842)
				(xy 244.169438 -9.525) (xy 258.0132 -9.525) (xy 258.1656 -9.6774) (xy 258.1656 -11.7348) (xy 244.3226 -11.7348)
				(xy 243.5098 -12.5476) (xy 243.5098 -13.7668) (xy 243.9162 -14.1732) (xy 258.1656 -14.1732) (xy 258.1656 -16.2306)
				(xy 258.0132 -16.383) (xy 244.076982 -16.383) (xy 243.745258 -16.714724) (xy 243.745258 -17.151858)
				(xy 243.84 -17.2466) (xy 244.9322 -17.2466) (xy 245.0084 -17.3228) (xy 245.0084 -18.2372) (xy 244.856 -18.3896)
				(xy 243.821458 -18.3896) (xy 243.745258 -18.4658) (xy 243.745258 -18.782284) (xy 244.063774 -19.1008)
				(xy 257.9116 -19.1008) (xy 258.1148 -19.304) (xy 258.1148 -25.654) (xy 258.191 -25.7302) (xy 258.7244 -25.7302)
				(xy 258.7244 -19.3548) (xy 260.1722 -17.907) (xy 260.1722 -16.9164) (xy 260.1214 -16.8656) (xy 259.1816 -16.8656)
				(xy 258.699 -16.383) (xy 258.699 -14.313154) (xy 258.825238 -14.186916) (xy 259.53847 -14.186916)
				(xy 259.797042 -13.928344) (xy 259.797042 -12.471146) (xy 259.671058 -12.345162) (xy 259.055362 -12.345162)
				(xy 258.699 -11.9888) (xy 258.699 -9.6774) (xy 258.826 -9.5504) (xy 259.4356 -9.5504) (xy 260.1468 -8.8392)
				(xy 260.1468 -7.2898) (xy 259.588 -6.731) (xy 259.0546 -6.731) (xy 259.0292 -6.7564) (xy 258.826 -6.7564)
				(xy 258.7879 -6.7183)
			)
		)
		(polygon
			(pts
				(xy 253.049532 -18.1483) (xy 252.846332 -18.1483) (xy 252.846332 -18.3515) (xy 253.049532 -18.3515)
			)
		)
		(polygon
			(pts
				(xy 249.4026 -18.1483) (xy 249.1994 -18.1483) (xy 249.1994 -18.3515) (xy 249.4026 -18.3515)
			)
		)
		(polygon
			(pts
				(xy 246.3038 -18.1483) (xy 246.1006 -18.1483) (xy 246.1006 -18.3515) (xy 246.3038 -18.3515)
			)
		)
		(polygon
			(pts
				(xy 258.9911 -18.0213) (xy 258.7879 -18.0213) (xy 258.7879 -18.2245) (xy 258.9911 -18.2245)
			)
		)
		(polygon
			(pts
				(xy 253.049532 -17.1577) (xy 252.846332 -17.1577) (xy 252.846332 -17.3609) (xy 253.049532 -17.3609)
			)
		)
		(polygon
			(pts
				(xy 246.3038 -17.1577) (xy 246.1006 -17.1577) (xy 246.1006 -17.3609) (xy 246.3038 -17.3609)
			)
		)
		(polygon
			(pts
				(xy 258.9911 -17.0307) (xy 258.7879 -17.0307) (xy 258.7879 -17.2339) (xy 258.9911 -17.2339)
			)
		)
		(polygon
			(pts
				(xy 253.049532 -13.2334) (xy 252.846332 -13.2334) (xy 252.846332 -13.4366) (xy 253.049532 -13.4366)
			)
		)
		(polygon
			(pts
				(xy 252.7046 -13.2334) (xy 252.5014 -13.2334) (xy 252.5014 -13.4366) (xy 252.7046 -13.4366)
			)
		)
		(polygon
			(pts
				(xy 249.4026 -13.2334) (xy 249.1994 -13.2334) (xy 249.1994 -13.4366) (xy 249.4026 -13.4366)
			)
		)
		(polygon
			(pts
				(xy 258.6863 -13.1064) (xy 258.4831 -13.1064) (xy 258.4831 -13.3096) (xy 258.6863 -13.3096)
			)
		)
		(polygon
			(pts
				(xy 253.049532 -12.4714) (xy 252.846332 -12.4714) (xy 252.846332 -12.6746) (xy 253.049532 -12.6746)
			)
		)
		(polygon
			(pts
				(xy 252.7046 -12.4714) (xy 252.5014 -12.4714) (xy 252.5014 -12.6746) (xy 252.7046 -12.6746)
			)
		)
		(polygon
			(pts
				(xy 249.4026 -12.4714) (xy 249.1994 -12.4714) (xy 249.1994 -12.6746) (xy 249.4026 -12.6746)
			)
		)
		(polygon
			(pts
				(xy 258.6863 -12.3444) (xy 258.4831 -12.3444) (xy 258.4831 -12.5476) (xy 258.6863 -12.5476)
			)
		)
		(polygon
			(pts
				(xy 253.049532 -8.5471) (xy 252.846332 -8.5471) (xy 252.846332 -8.7503) (xy 253.049532 -8.7503)
			)
		)
		(polygon
			(pts
				(xy 249.4026 -8.5471) (xy 249.1994 -8.5471) (xy 249.1994 -8.7503) (xy 249.4026 -8.7503)
			)
		)
		(polygon
			(pts
				(xy 246.3038 -8.5471) (xy 246.1006 -8.5471) (xy 246.1006 -8.7503) (xy 246.3038 -8.7503)
			)
		)
		(polygon
			(pts
				(xy 258.9911 -8.4709) (xy 258.7879 -8.4709) (xy 258.7879 -8.6741) (xy 258.9911 -8.6741)
			)
		)
		(polygon
			(pts
				(xy 253.049532 -7.5565) (xy 252.846332 -7.5565) (xy 252.846332 -7.7597) (xy 253.049532 -7.7597)
			)
		)
		(polygon
			(pts
				(xy 246.3038 -7.5565) (xy 246.1006 -7.5565) (xy 246.1006 -7.7597) (xy 246.3038 -7.7597)
			)
		)
		(polygon
			(pts
				(xy 258.9911 -7.4803) (xy 258.7879 -7.4803) (xy 258.7879 -7.6835) (xy 258.9911 -7.6835)
			)
		)
	)
	(zone
		(layer "B.Cu")
		(hatch none 0.5)
		(connect_pads
			(clearance 0)
		)
		(min_thickness 0.25)
		(keepout
			(tracks allowed)
			(vias allowed)
			(pads allowed)
			(copperpour allowed)
			(footprints allowed)
		)
		(placement
			(enabled no)
			(sheetname "")
		)
		(fill
			(thermal_gap 0.5)
			(thermal_bridge_width 0.5)
			(island_removal_mode 0)
		)
		(polygon
			(pts
				(xy 152.273 -91.694) (xy 152.273 -90.932) (xy 153.035 -90.932) (xy 153.035 -91.694)
			)
		)
	)
	(zone
		(net "P1V05_PCH_STBY_VCCA_PLL0")
		(layer "B.Cu")
		(hatch none 0.5)
		(connect_pads
			(clearance 0.5)
		)
		(min_thickness 0.25)
		(fill yes
			(thermal_gap 0.5)
			(thermal_bridge_width 0.5)
			(island_removal_mode 0)
		)
		(polygon
			(pts
				(xy 373.54256 -134.62) (xy 373.08536 -135.0772) (xy 373.08536 -135.67664) (xy 372.582186 -136.179814)
				(xy 371.693186 -136.179814) (xy 371.602 -136.271) (xy 371.602 -136.93902) (xy 371.983762 -137.320782)
				(xy 371.983762 -138.432032) (xy 372.01602 -138.46429) (xy 372.841012 -138.46429) (xy 372.890542 -138.41476)
				(xy 372.890542 -137.570718) (xy 373.424196 -137.037064) (xy 373.424196 -136.20496) (xy 373.771414 -135.857742)
				(xy 375.595134 -135.857742) (xy 375.71553 -135.737346) (xy 375.71553 -134.64413) (xy 375.6914 -134.62)
			)
		)
		(polygon
			(pts
				(xy 372.6815 -136.9822) (xy 372.4783 -136.9822) (xy 372.4783 -137.1854) (xy 372.6815 -137.1854)
			)
		)
	)
	(zone
		(net "GND")
		(layer "B.Cu")
		(hatch none 0.5)
		(connect_pads
			(clearance 0.5)
		)
		(min_thickness 0.25)
		(fill yes
			(thermal_gap 0.5)
			(thermal_bridge_width 0.5)
			(island_removal_mode 0)
		)
		(polygon
			(pts
				(xy 340.7791 -132.2705) (xy 339.7377 -132.2705) (xy 335.3435 -132.2705) (xy 334.5434 -133.0706)
				(xy 334.5434 -133.4008) (xy 334.5434 -135.89) (xy 335.407 -136.7536) (xy 340.3092 -136.7536) (xy 341.0077 -137.4521)
				(xy 343.6493 -137.4521) (xy 343.6493 -137.4394) (xy 350.647 -137.4394) (xy 350.9772 -137.1092) (xy 350.9772 -135.8138)
				(xy 351.2566 -135.5344) (xy 352.2726 -135.5344) (xy 352.3234 -135.4836) (xy 352.3234 -134.5692)
				(xy 352.2472 -134.493) (xy 348.8182 -134.493) (xy 348.5642 -134.239) (xy 347.853 -134.239) (xy 344.062812 -134.239)
				(xy 343.738708 -133.914896) (xy 343.738708 -132.148326) (xy 343.820242 -132.066792) (xy 343.820242 -130.76936)
				(xy 343.502742 -130.45186) (xy 343.502742 -129.770378) (xy 343.43594 -129.703576) (xy 342.015064 -129.703576)
				(xy 341.428324 -129.703576) (xy 341.2109 -129.921) (xy 341.2109 -131.8387)
			)
		)
	)
	(zone
		(net "GND")
		(layer "B.Cu")
		(hatch none 0.5)
		(connect_pads
			(clearance 0.5)
		)
		(min_thickness 0.25)
		(fill yes
			(thermal_gap 0.5)
			(thermal_bridge_width 0.5)
			(island_removal_mode 0)
		)
		(polygon
			(pts
				(xy 16.86814 -55.605172) (xy 16.86814 -53.15712) (xy 16.50492 -52.7939) (xy 15.39748 -52.7939) (xy 14.972284 -53.219096)
				(xy 14.972284 -55.514748) (xy 15.135098 -55.677308) (xy 16.796004 -55.677308)
			)
		)
	)
	(zone
		(net "GND")
		(layer "B.Cu")
		(hatch none 0.5)
		(connect_pads
			(clearance 0.5)
		)
		(min_thickness 0.25)
		(fill yes
			(thermal_gap 0.5)
			(thermal_bridge_width 0.5)
			(island_removal_mode 0)
		)
		(polygon
			(pts
				(xy 113.257584 -18.766028) (xy 113.257584 -16.80083) (xy 113.59134 -16.467074) (xy 114.865658 -16.467074)
				(xy 115.118642 -16.720058) (xy 115.487958 -16.720058) (xy 115.824 -17.0561) (xy 115.824 -17.3482)
				(xy 115.5192 -17.653) (xy 115.208558 -17.653) (xy 115.195858 -17.6403) (xy 115.195858 -18.798286)
				(xy 114.917474 -19.07667) (xy 113.568226 -19.07667)
			)
		)
	)
	(zone
		(layer "B.Cu")
		(hatch none 0.5)
		(connect_pads
			(clearance 0)
		)
		(min_thickness 0.25)
		(keepout
			(tracks allowed)
			(vias allowed)
			(pads allowed)
			(copperpour allowed)
			(footprints not_allowed)
		)
		(placement
			(enabled no)
			(sheetname "")
		)
		(fill
			(thermal_gap 0.5)
			(thermal_bridge_width 0.5)
			(island_removal_mode 0)
		)
		(polygon
			(pts
				(arc
					(start 406.489916 -132.310124)
					(mid 404.899876 -133.900164)
					(end 406.489916 -135.48995)
				)
				(arc
					(start 406.489916 -135.48995)
					(mid 408.079702 -133.900164)
					(end 406.489916 -132.310124)
				)
			)
		)
	)
	(zone
		(layer "B.Cu")
		(hatch none 0.5)
		(connect_pads
			(clearance 0)
		)
		(min_thickness 0.25)
		(keepout
			(tracks not_allowed)
			(vias allowed)
			(pads allowed)
			(copperpour not_allowed)
			(footprints allowed)
		)
		(placement
			(enabled no)
			(sheetname "")
		)
		(fill
			(thermal_gap 0.5)
			(thermal_bridge_width 0.5)
			(island_removal_mode 0)
		)
		(polygon
			(pts
				(xy 345.578176 -78.329536) (xy 346.086176 -78.329536) (xy 346.086176 -77.948536) (xy 345.578176 -77.948536)
			)
		)
	)
	(zone
		(layer "B.Cu")
		(hatch none 0.5)
		(connect_pads
			(clearance 0)
		)
		(min_thickness 0.25)
		(keepout
			(tracks allowed)
			(vias allowed)
			(pads allowed)
			(copperpour allowed)
			(footprints not_allowed)
		)
		(placement
			(enabled no)
			(sheetname "")
		)
		(fill
			(thermal_gap 0.5)
			(thermal_bridge_width 0.5)
			(island_removal_mode 0)
		)
		(polygon
			(pts
				(arc
					(start 291.999924 -39.649908)
					(mid 290.09975 -41.550082)
					(end 291.999924 -43.450002)
				)
				(arc
					(start 291.999924 -43.450002)
					(mid 293.899844 -41.550082)
					(end 291.999924 -39.649908)
				)
			)
		)
	)
	(zone
		(layer "B.Cu")
		(hatch none 0.5)
		(connect_pads
			(clearance 0)
		)
		(min_thickness 0.25)
		(keepout
			(tracks not_allowed)
			(vias allowed)
			(pads allowed)
			(copperpour not_allowed)
			(footprints allowed)
		)
		(placement
			(enabled no)
			(sheetname "")
		)
		(fill
			(thermal_gap 0.5)
			(thermal_bridge_width 0.5)
			(island_removal_mode 0)
		)
		(polygon
			(pts
				(xy 452.793862 -114.333782) (xy 452.949056 -114.488976) (xy 452.949056 -114.787172) (xy 453.050656 -114.787172)
				(xy 453.050656 -114.488976) (xy 453.20585 -114.333782)
				(arc
					(start 453.377554 -114.333782)
					(mid 453.901471 -114.403632)
					(end 453.377554 -114.473482)
				)
				(xy 453.263762 -114.473482) (xy 453.190356 -114.546888) (xy 453.190356 -114.787172)
				(arc
					(start 453.634856 -114.787172)
					(mid 454.018396 -114.403632)
					(end 453.634856 -114.020092)
				)
				(arc
					(start 452.36511 -114.020092)
					(mid 451.981316 -114.403505)
					(end 452.364856 -114.787172)
				)
				(xy 452.809356 -114.787172) (xy 452.809356 -114.546888) (xy 452.73595 -114.473482)
				(arc
					(start 452.622158 -114.473482)
					(mid 452.098241 -114.403632)
					(end 452.622158 -114.333782)
				)
			)
		)
	)
	(zone
		(layer "B.Cu")
		(hatch none 0.5)
		(connect_pads
			(clearance 0)
		)
		(min_thickness 0.25)
		(keepout
			(tracks allowed)
			(vias allowed)
			(pads allowed)
			(copperpour allowed)
			(footprints not_allowed)
		)
		(placement
			(enabled no)
			(sheetname "")
		)
		(fill
			(thermal_gap 0.5)
			(thermal_bridge_width 0.5)
			(island_removal_mode 0)
		)
		(polygon
			(pts
				(xy 187.520072 -127.359918) (xy 185.879994 -127.359918) (xy 185.879994 -159.090106) (xy 187.520072 -159.090106)
			)
		)
	)
	(zone
		(layer "B.Cu")
		(hatch none 0.5)
		(connect_pads
			(clearance 0)
		)
		(min_thickness 0.25)
		(keepout
			(tracks not_allowed)
			(vias allowed)
			(pads allowed)
			(copperpour not_allowed)
			(footprints allowed)
		)
		(placement
			(enabled no)
			(sheetname "")
		)
		(fill
			(thermal_gap 0.5)
			(thermal_bridge_width 0.5)
			(island_removal_mode 0)
		)
		(polygon
			(pts
				(xy 12.93749 -23.74265) (xy 13.120624 -23.925784)
				(arc
					(start 13.120624 -24.063198)
					(mid 13.050774 -24.587115)
					(end 12.980924 -24.063198)
				)
				(xy 12.980924 -23.983696) (xy 12.879578 -23.88235) (xy 12.667234 -23.88235)
				(arc
					(start 12.667234 -24.3205)
					(mid 13.050774 -24.70404)
					(end 13.434314 -24.3205)
				)
				(arc
					(start 13.434314 -23.050754)
					(mid 13.050901 -22.66696)
					(end 12.667234 -23.0505)
				)
				(xy 12.667234 -23.50135) (xy 12.87399 -23.50135) (xy 12.980924 -23.394416)
				(arc
					(start 12.980924 -23.307802)
					(mid 13.050774 -22.783885)
					(end 13.120624 -23.307802)
				)
				(xy 13.120624 -23.452328) (xy 12.931902 -23.64105) (xy 12.667234 -23.64105) (xy 12.667234 -23.74265)
			)
		)
	)
	(zone
		(layer "B.Cu")
		(hatch none 0.5)
		(connect_pads
			(clearance 0)
		)
		(min_thickness 0.25)
		(keepout
			(tracks allowed)
			(vias allowed)
			(pads allowed)
			(copperpour allowed)
			(footprints allowed)
		)
		(placement
			(enabled no)
			(sheetname "")
		)
		(fill
			(thermal_gap 0.5)
			(thermal_bridge_width 0.5)
			(island_removal_mode 0)
		)
		(polygon
			(pts
				(xy 366.9157 -112.3442) (xy 366.9157 -111.0742) (xy 368.6175 -111.0742) (xy 368.6175 -112.3442)
			)
		)
	)
	(zone
		(net "GND")
		(layer "B.Cu")
		(hatch none 0.5)
		(connect_pads
			(clearance 0.5)
		)
		(min_thickness 0.25)
		(fill yes
			(thermal_gap 0.5)
			(thermal_bridge_width 0.5)
			(island_removal_mode 0)
		)
		(polygon
			(pts
				(xy 401.18792 -100.28174) (xy 401.14728 -100.32238) (xy 400.24812 -100.32238) (xy 398.8562 -101.7143)
				(xy 398.8562 -101.95941) (xy 399.030444 -102.133908) (xy 399.070068 -102.173532) (xy 399.476468 -102.173532)
				(xy 399.7706 -101.8794) (xy 404.069296 -101.8794) (xy 405.05761 -102.867714) (xy 408.0002 -102.867714)
				(xy 409.094686 -102.867714) (xy 409.321 -102.6414) (xy 409.321 -101.092) (xy 409.2194 -100.9904)
				(xy 405.53894 -100.9904) (xy 405.36114 -100.8126) (xy 404.83028 -100.28174)
			)
		)
		(polygon
			(pts
				(xy 400.6088 -100.8888) (xy 400.4056 -100.8888) (xy 400.4056 -101.092) (xy 400.6088 -101.092)
			)
		)
		(polygon
			(pts
				(xy 401.0406 -100.8888) (xy 400.8374 -100.8888) (xy 400.8374 -101.092) (xy 401.0406 -101.092)
			)
		)
		(polygon
			(pts
				(xy 401.8026 -100.8888) (xy 401.5994 -100.8888) (xy 401.5994 -101.092) (xy 401.8026 -101.092)
			)
		)
	)
	(zone
		(layer "B.Cu")
		(hatch none 0.5)
		(connect_pads
			(clearance 0)
		)
		(min_thickness 0.25)
		(keepout
			(tracks allowed)
			(vias allowed)
			(pads allowed)
			(copperpour allowed)
			(footprints allowed)
		)
		(placement
			(enabled no)
			(sheetname "")
		)
		(fill
			(thermal_gap 0.5)
			(thermal_bridge_width 0.5)
			(island_removal_mode 0)
		)
		(polygon
			(pts
				(xy 469.138 -132.588) (xy 469.138 -130.81) (xy 470.027 -130.81) (xy 470.027 -132.588)
			)
		)
	)
	(zone
		(layer "B.Cu")
		(hatch none 0.5)
		(connect_pads
			(clearance 0)
		)
		(min_thickness 0.25)
		(keepout
			(tracks allowed)
			(vias allowed)
			(pads allowed)
			(copperpour allowed)
			(footprints not_allowed)
		)
		(placement
			(enabled no)
			(sheetname "")
		)
		(fill
			(thermal_gap 0.5)
			(thermal_bridge_width 0.5)
			(island_removal_mode 0)
		)
		(polygon
			(pts
				(arc
					(start 317.959994 -92.689934)
					(mid 317.667101 -93.397039)
					(end 316.959996 -93.689932)
				)
				(arc
					(start 311.339992 -93.689932)
					(mid 310.632887 -93.397039)
					(end 310.339994 -92.689934)
				)
				(arc
					(start 310.339994 -85.549994)
					(mid 310.632887 -84.842889)
					(end 311.339992 -84.549996)
				)
				(arc
					(start 316.959996 -84.549996)
					(mid 317.667101 -84.842889)
					(end 317.959994 -85.549994)
				)
				(xy 317.959994 -89.019888) (xy 326.749918 -89.019888) (xy 326.749918 -64.079882) (xy 317.959994 -64.079882)
				(arc
					(start 317.959994 -67.55003)
					(mid 317.667101 -68.257135)
					(end 316.959996 -68.550028)
				)
				(arc
					(start 311.339992 -68.550028)
					(mid 310.632887 -68.257135)
					(end 310.339994 -67.55003)
				)
				(arc
					(start 310.339994 -60.41009)
					(mid 310.632887 -59.702985)
					(end 311.339992 -59.410092)
				)
				(arc
					(start 316.959996 -59.410092)
					(mid 317.667101 -59.702985)
					(end 317.959994 -60.41009)
				)
				(xy 317.959994 -63.879984) (xy 326.749918 -63.879984) (xy 326.749918 -33.299908) (xy 319.349882 -33.299908)
				(xy 319.349882 -34.699956) (xy 317.349886 -34.699956) (xy 317.349886 -33.299908) (xy 295.044876 -33.299908)
				(xy 295.044876 -62.900052)
				(arc
					(start 295.794938 -62.900052)
					(mid 296.254548 -63.090428)
					(end 296.444924 -63.550038)
				)
				(arc
					(start 296.444924 -67.900042)
					(mid 296.254548 -68.359652)
					(end 295.794938 -68.550028)
				)
				(arc
					(start 294.094916 -68.550028)
					(mid 293.635306 -68.359652)
					(end 293.44493 -67.900042)
				)
				(arc
					(start 293.44493 -63.550038)
					(mid 293.635306 -63.090428)
					(end 294.094916 -62.900052)
				)
				(xy 294.844978 -62.900052) (xy 294.844978 -33.299908) (xy 245.154958 -33.299908) (xy 245.154958 -62.900052)
				(arc
					(start 245.90502 -62.900052)
					(mid 246.36463 -63.090428)
					(end 246.555006 -63.550038)
				)
				(arc
					(start 246.555006 -67.900042)
					(mid 246.36463 -68.359652)
					(end 245.90502 -68.550028)
				)
				(arc
					(start 244.204998 -68.550028)
					(mid 243.745388 -68.359652)
					(end 243.555012 -67.900042)
				)
				(arc
					(start 243.555012 -63.550038)
					(mid 243.745388 -63.090428)
					(end 244.204998 -62.900052)
				)
				(xy 244.95506 -62.900052) (xy 244.95506 -33.299908) (xy 213.250018 -33.299908) (xy 213.250018 -53.300122)
				(xy 215.000078 -53.300122) (xy 215.000078 -63.879984) (xy 222.039942 -63.879984)
				(arc
					(start 222.039942 -60.41009)
					(mid 222.332835 -59.702985)
					(end 223.03994 -59.410092)
				)
				(arc
					(start 228.659944 -59.410092)
					(mid 229.367049 -59.702985)
					(end 229.659942 -60.41009)
				)
				(arc
					(start 229.659942 -67.55003)
					(mid 229.367049 -68.257135)
					(end 228.659944 -68.550028)
				)
				(arc
					(start 223.03994 -68.550028)
					(mid 222.332835 -68.257135)
					(end 222.039942 -67.55003)
				)
				(xy 222.039942 -64.079882) (xy 215.000078 -64.079882) (xy 215.000078 -89.019888) (xy 222.039942 -89.019888)
				(arc
					(start 222.039942 -85.549994)
					(mid 222.332835 -84.842889)
					(end 223.03994 -84.549996)
				)
				(arc
					(start 228.659944 -84.549996)
					(mid 229.367049 -84.842889)
					(end 229.659942 -85.549994)
				)
				(arc
					(start 229.659942 -92.689934)
					(mid 229.367049 -93.397039)
					(end 228.659944 -93.689932)
				)
				(arc
					(start 223.03994 -93.689932)
					(mid 222.332835 -93.397039)
					(end 222.039942 -92.689934)
				)
				(xy 222.039942 -89.22004) (xy 215.000078 -89.22004) (xy 215.000078 -99.799902) (xy 213.250018 -99.799902)
				(xy 213.250018 -119.800116) (xy 244.95506 -119.800116) (xy 244.95506 -90.199972)
				(arc
					(start 244.204998 -90.199972)
					(mid 243.745388 -90.009596)
					(end 243.555012 -89.549986)
				)
				(arc
					(start 243.555012 -85.199982)
					(mid 243.745388 -84.740372)
					(end 244.204998 -84.549996)
				)
				(arc
					(start 245.90502 -84.549996)
					(mid 246.36463 -84.740372)
					(end 246.555006 -85.199982)
				)
				(arc
					(start 246.555006 -89.549986)
					(mid 246.36463 -90.009596)
					(end 245.90502 -90.199972)
				)
				(xy 245.154958 -90.199972) (xy 245.154958 -119.800116) (xy 269.899892 -119.800116) (xy 269.899892 -85.749892)
				(arc
					(start 264.217404 -85.749892)
					(mid 263.950129 -85.713583)
					(end 263.702292 -85.607144)
				)
				(arc
					(start 257.934968 -82.141822)
					(mid 257.579624 -81.77704)
					(end 257.450082 -81.284572)
				)
				(arc
					(start 257.450082 -71.816214)
					(mid 257.579721 -71.3238)
					(end 257.934968 -70.958964)
				)
				(arc
					(start 263.69645 -67.497198)
					(mid 263.944271 -67.390626)
					(end 264.211562 -67.354196)
				)
				(arc
					(start 275.789644 -67.354958)
					(mid 276.056923 -67.391259)
					(end 276.304756 -67.497706)
				)
				(arc
					(start 282.064968 -70.958964)
					(mid 282.420312 -71.323746)
					(end 282.550108 -71.816214)
				)
				(arc
					(start 282.550108 -81.284572)
					(mid 282.420436 -81.777111)
					(end 282.064968 -82.141822)
				)
				(arc
					(start 276.297644 -85.607144)
					(mid 276.049928 -85.713556)
					(end 275.782786 -85.749892)
				)
				(xy 270.100044 -85.749892) (xy 270.100044 -119.800116) (xy 294.844978 -119.800116) (xy 294.844978 -90.199972)
				(arc
					(start 294.094916 -90.199972)
					(mid 293.635306 -90.009596)
					(end 293.44493 -89.549986)
				)
				(arc
					(start 293.44493 -85.199982)
					(mid 293.635306 -84.740372)
					(end 294.094916 -84.549996)
				)
				(arc
					(start 295.794938 -84.549996)
					(mid 296.254548 -84.740372)
					(end 296.444924 -85.199982)
				)
				(arc
					(start 296.444924 -89.549986)
					(mid 296.254548 -90.009596)
					(end 295.794938 -90.199972)
				)
				(xy 295.044876 -90.199972) (xy 295.044876 -119.800116) (xy 326.749918 -119.800116) (xy 326.749918 -89.22004)
				(xy 317.959994 -89.22004)
			)
		)
	)
	(zone
		(net "GND")
		(layer "B.Cu")
		(hatch none 0.5)
		(connect_pads
			(clearance 0.5)
		)
		(min_thickness 0.25)
		(fill yes
			(thermal_gap 0.5)
			(thermal_bridge_width 0.5)
			(island_removal_mode 0)
		)
		(polygon
			(pts
				(xy 464.933284 -35.902646) (xy 464.845146 -35.990784) (xy 464.845146 -37.027866) (xy 465.196682 -37.379402)
				(xy 466.67547 -37.379402) (xy 467.319614 -36.735258) (xy 467.319614 -36.005262) (xy 467.216998 -35.902646)
			)
		)
		(polygon
			(pts
				(xy 466.601302 -36.715192) (xy 466.398102 -36.715192) (xy 466.398102 -36.918392) (xy 466.601302 -36.918392)
			)
		)
	)
	(zone
		(net "VCC_D_3V3")
		(layer "B.Cu")
		(hatch none 0.5)
		(connect_pads
			(clearance 0.5)
		)
		(min_thickness 0.25)
		(fill yes
			(thermal_gap 0.5)
			(thermal_bridge_width 0.5)
			(island_removal_mode 0)
		)
		(polygon
			(pts
				(xy 417.030662 -39.240206) (xy 417.430966 -39.240206) (xy 417.50742 -39.31666) (xy 418.06622 -39.31666)
				(xy 418.06749 -39.31539) (xy 418.86124 -39.31539) (xy 418.94252 -39.23411) (xy 418.94252 -38.78072)
				(xy 418.86632 -38.70452) (xy 417.582604 -38.70452) (xy 417.478464 -38.60038) (xy 417.478464 -38.494716)
				(xy 417.476432 -38.492938) (xy 417.476432 -37.830252) (xy 417.449508 -37.803328) (xy 416.9918 -37.803328)
				(xy 416.917886 -37.877242) (xy 416.917886 -38.705536) (xy 416.844226 -38.779196) (xy 416.844226 -39.05377)
			)
		)
	)
	(zone
		(net "GND")
		(layer "B.Cu")
		(hatch none 0.5)
		(connect_pads
			(clearance 0.5)
		)
		(min_thickness 0.25)
		(fill yes
			(thermal_gap 0.5)
			(thermal_bridge_width 0.5)
			(island_removal_mode 0)
		)
		(polygon
			(pts
				(xy 213.995 -91.821) (xy 213.7664 -92.0496) (xy 213.7664 -93.218) (xy 214.05342 -93.50502) (xy 215.10498 -93.50502)
				(xy 215.5444 -93.0656) (xy 215.5444 -92.0496) (xy 215.3158 -91.821)
			)
		)
		(polygon
			(pts
				(xy 214.9856 -92.4941) (xy 214.7824 -92.4941) (xy 214.7824 -92.6973) (xy 214.9856 -92.6973)
			)
		)
		(polygon
			(pts
				(xy 214.2236 -92.4941) (xy 214.0204 -92.4941) (xy 214.0204 -92.6973) (xy 214.2236 -92.6973)
			)
		)
	)
	(zone
		(net "PVDDQ_DEF")
		(layer "B.Cu")
		(hatch none 0.5)
		(connect_pads
			(clearance 0.5)
		)
		(min_thickness 0.25)
		(fill yes
			(thermal_gap 0.5)
			(thermal_bridge_width 0.5)
			(island_removal_mode 0)
		)
		(polygon
			(pts
				(xy 272.545302 -148.531834) (xy 272.4404 -148.636736) (xy 272.4404 -148.9456) (xy 272.2626 -149.1234)
				(xy 272.0594 -149.1234) (xy 271.8054 -149.3774) (xy 265.906758 -149.3774) (xy 265.678158 -149.606)
				(xy 265.678158 -150.687532) (xy 265.979148 -150.988522) (xy 277.326598 -150.988522) (xy 277.529036 -150.786084)
				(xy 277.529036 -148.699982) (xy 277.360888 -148.531834)
			)
		)
		(polygon
			(pts
				(xy 272.518632 -150.0886) (xy 272.315432 -150.0886) (xy 272.315432 -150.2918) (xy 272.518632 -150.2918)
			)
		)
		(polygon
			(pts
				(xy 272.518632 -149.3266) (xy 272.315432 -149.3266) (xy 272.315432 -149.5298) (xy 272.518632 -149.5298)
			)
		)
	)
	(zone
		(layer "B.Cu")
		(hatch none 0.5)
		(connect_pads
			(clearance 0)
		)
		(min_thickness 0.25)
		(keepout
			(tracks allowed)
			(vias allowed)
			(pads allowed)
			(copperpour allowed)
			(footprints not_allowed)
		)
		(placement
			(enabled no)
			(sheetname "")
		)
		(fill
			(thermal_gap 0.5)
			(thermal_bridge_width 0.5)
			(island_removal_mode 0)
		)
		(polygon
			(pts
				(arc
					(start 291.999924 -109.650022)
					(mid 290.09975 -111.550196)
					(end 291.999924 -113.450116)
				)
				(arc
					(start 291.999924 -113.450116)
					(mid 293.899844 -111.550196)
					(end 291.999924 -109.650022)
				)
			)
		)
	)
	(zone
		(layer "B.Cu")
		(hatch none 0.5)
		(connect_pads
			(clearance 0)
		)
		(min_thickness 0.25)
		(keepout
			(tracks not_allowed)
			(vias allowed)
			(pads allowed)
			(copperpour not_allowed)
			(footprints allowed)
		)
		(placement
			(enabled no)
			(sheetname "")
		)
		(fill
			(thermal_gap 0.5)
			(thermal_bridge_width 0.5)
			(island_removal_mode 0)
		)
		(polygon
			(pts
				(xy 346.545662 -67.82689) (xy 346.545662 -67.512438) (xy 346.6846 -67.3735)
				(arc
					(start 346.785946 -67.3735)
					(mid 347.309863 -67.44335)
					(end 346.785946 -67.5132)
				)
				(xy 346.742512 -67.5132) (xy 346.685362 -67.57035) (xy 346.685362 -67.82689)
				(arc
					(start 347.043248 -67.82689)
					(mid 347.426788 -67.44335)
					(end 347.043248 -67.05981)
				)
				(arc
					(start 346.152216 -67.05981)
					(mid 345.768676 -67.443223)
					(end 346.151962 -67.82689)
				)
				(xy 346.304362 -67.82689) (xy 346.304362 -67.694556)
				(arc
					(start 346.28455 -67.674744)
					(mid 345.963385 -67.254773)
					(end 346.383356 -67.575938)
				)
				(xy 346.444062 -67.636644) (xy 346.444062 -67.82689)
			)
		)
	)
	(zone
		(net "VR_PVNN_PCH_VDD")
		(layer "B.Cu")
		(hatch none 0.5)
		(connect_pads
			(clearance 0.5)
		)
		(min_thickness 0.25)
		(fill yes
			(thermal_gap 0.5)
			(thermal_bridge_width 0.5)
			(island_removal_mode 0)
		)
		(polygon
			(pts
				(xy 392.3792 -152.3746) (xy 392.8618 -152.3746) (xy 392.9888 -152.5016) (xy 392.9888 -152.9842)
				(xy 393.0142 -153.0096) (xy 393.5222 -153.0096) (xy 393.5476 -152.9842) (xy 393.5476 -150.709122)
				(xy 393.460478 -150.622) (xy 392.7602 -150.622) (xy 392.1252 -151.257) (xy 392.1252 -152.1206)
			)
		)
	)
	(zone
		(layer "B.Cu")
		(hatch none 0.5)
		(connect_pads
			(clearance 0)
		)
		(min_thickness 0.25)
		(keepout
			(tracks allowed)
			(vias allowed)
			(pads allowed)
			(copperpour allowed)
			(footprints not_allowed)
		)
		(placement
			(enabled no)
			(sheetname "")
		)
		(fill
			(thermal_gap 0.5)
			(thermal_bridge_width 0.5)
			(island_removal_mode 0)
		)
		(polygon
			(pts
				(arc
					(start 409.719526 -80.88376)
					(mid 413.719518 -76.883768)
					(end 409.719526 -72.883776)
				)
				(arc
					(start 409.719526 -72.883776)
					(mid 405.719534 -76.883768)
					(end 409.719526 -80.88376)
				)
			)
		)
	)
	(zone
		(layer "B.Cu")
		(hatch none 0.5)
		(connect_pads
			(clearance 0)
		)
		(min_thickness 0.25)
		(keepout
			(tracks not_allowed)
			(vias allowed)
			(pads allowed)
			(copperpour not_allowed)
			(footprints allowed)
		)
		(placement
			(enabled no)
			(sheetname "")
		)
		(fill
			(thermal_gap 0.5)
			(thermal_bridge_width 0.5)
			(island_removal_mode 0)
		)
		(polygon
			(pts
				(arc
					(start 446.947544 -53.621686)
					(mid 446.527573 -53.942851)
					(end 446.848738 -53.52288)
				)
				(xy 447.000884 -53.370734)
				(arc
					(start 446.71615 -53.370734)
					(mid 446.33261 -53.754274)
					(end 446.71615 -54.137814)
				)
				(arc
					(start 447.985896 -54.137814)
					(mid 448.36969 -53.754401)
					(end 447.98615 -53.370734)
				)
				(xy 447.701416 -53.370734)
				(arc
					(start 447.853562 -53.52288)
					(mid 448.174727 -53.942851)
					(end 447.754756 -53.621686)
				)
				(xy 447.503804 -53.370734) (xy 447.198496 -53.370734)
			)
		)
	)
	(zone
		(net "GND")
		(layer "B.Cu")
		(hatch none 0.5)
		(connect_pads
			(clearance 0.5)
		)
		(min_thickness 0.25)
		(fill yes
			(thermal_gap 0.5)
			(thermal_bridge_width 0.5)
			(island_removal_mode 0)
		)
		(polygon
			(pts
				(xy 279.867614 -9.577324) (xy 278.48941 -9.577324) (xy 278.211026 -9.29894) (xy 278.211026 -7.192518)
				(xy 278.544782 -6.858762) (xy 279.8191 -6.858762) (xy 280.1493 -7.188962) (xy 280.543762 -7.188962)
				(xy 280.8224 -7.4676) (xy 280.8224 -7.9502) (xy 280.67 -8.1026) (xy 280.2763 -8.1026) (xy 280.1493 -8.2296)
				(xy 280.1493 -9.295638)
			)
		)
	)
	(zone
		(net "P3V3_STBY_MNG_CPU")
		(layer "B.Cu")
		(hatch none 0.5)
		(connect_pads
			(clearance 0.5)
		)
		(min_thickness 0.25)
		(fill yes
			(thermal_gap 0.5)
			(thermal_bridge_width 0.5)
			(island_removal_mode 0)
		)
		(polygon
			(pts
				(xy 479.353626 -25.84323) (xy 478.817178 -26.379678) (xy 478.817178 -27.916378) (xy 478.8662 -27.9654)
				(xy 480.2886 -27.9654) (xy 480.358958 -27.895042) (xy 480.358958 -27.771598) (xy 480.953572 -27.176984)
				(xy 481.657406 -27.176984) (xy 481.922074 -26.912316) (xy 481.922074 -25.926796) (xy 481.845112 -25.849834)
				(xy 480.484434 -25.849834) (xy 480.47783 -25.84323)
			)
		)
		(polygon
			(pts
				(xy 481.085398 -26.187908) (xy 480.882198 -26.187908) (xy 480.882198 -26.391108) (xy 481.085398 -26.391108)
			)
		)
	)
	(zone
		(layer "B.Cu")
		(hatch none 0.5)
		(connect_pads
			(clearance 0)
		)
		(min_thickness 0.25)
		(keepout
			(tracks not_allowed)
			(vias allowed)
			(pads allowed)
			(copperpour not_allowed)
			(footprints allowed)
		)
		(placement
			(enabled no)
			(sheetname "")
		)
		(fill
			(thermal_gap 0.5)
			(thermal_bridge_width 0.5)
			(island_removal_mode 0)
		)
		(polygon
			(pts
				(arc
					(start 198.930006 -110.10011)
					(mid 202.47991 -106.550206)
					(end 198.930006 -103.000048)
				)
				(arc
					(start 198.930006 -103.000048)
					(mid 195.379848 -106.550206)
					(end 198.930006 -110.10011)
				)
			)
		)
	)
	(zone
		(net "P12V_NVDIMM_ABC")
		(layer "B.Cu")
		(hatch none 0.5)
		(connect_pads
			(clearance 0.5)
		)
		(min_thickness 0.25)
		(fill yes
			(thermal_gap 0.5)
			(thermal_bridge_width 0.5)
			(island_removal_mode 0)
		)
		(polygon
			(pts
				(xy 194.945 -25.273) (xy 194.945 0) (xy 194.945 2.4384) (xy 194.3862 2.9972) (xy 191.2366 2.9972)
				(xy 190.7286 2.4892) (xy 190.7286 -13.0048) (xy 187.5536 -16.1798) (xy 187.5536 -17.7546) (xy 185.020712 -20.287488)
				(xy 185.020712 -22.886162) (xy 185.29935 -23.1648) (xy 189.9666 -23.1648) (xy 191.4906 -24.6888)
				(xy 193.167 -24.6888) (xy 193.9671 -25.4889) (xy 194.7291 -25.4889)
			)
		)
	)
	(zone
		(net "GND")
		(layer "B.Cu")
		(hatch none 0.5)
		(connect_pads
			(clearance 0.5)
		)
		(min_thickness 0.25)
		(fill yes
			(thermal_gap 0.5)
			(thermal_bridge_width 0.5)
			(island_removal_mode 0)
		)
		(polygon
			(pts
				(xy 48.6918 -90.6526) (xy 48.4378 -90.9066) (xy 48.4378 -92.202) (xy 48.6664 -92.4306) (xy 50.2158 -92.4306)
				(xy 50.4698 -92.1766) (xy 50.4698 -90.932) (xy 50.1904 -90.6526)
			)
		)
		(polygon
			(pts
				(xy 49.911 -91.8083) (xy 49.7078 -91.8083) (xy 49.7078 -92.0115) (xy 49.911 -92.0115)
			)
		)
		(polygon
			(pts
				(xy 49.149 -91.8083) (xy 48.9458 -91.8083) (xy 48.9458 -92.0115) (xy 49.149 -92.0115)
			)
		)
	)
	(zone
		(net "GND")
		(layer "B.Cu")
		(hatch none 0.5)
		(connect_pads
			(clearance 0.5)
		)
		(min_thickness 0.25)
		(fill yes
			(thermal_gap 0.5)
			(thermal_bridge_width 0.5)
			(island_removal_mode 0)
		)
		(polygon
			(pts
				(xy 471.17 -22.1742) (xy 471.17 -25.402286) (xy 471.33002 -25.562306) (xy 473.943426 -25.562306)
				(xy 474.790516 -24.715216) (xy 476.521018 -24.715216) (xy 477.87052 -24.715216) (xy 480.491546 -24.715216)
				(xy 480.675188 -24.531828) (xy 480.675188 -19.390868) (xy 480.436936 -19.152616) (xy 474.828616 -19.152616)
				(xy 474.403674 -19.577812) (xy 474.403674 -20.635976) (xy 474.354906 -20.684744) (xy 473.47124 -20.684744)
				(xy 473.34424 -20.557744) (xy 473.34424 -20.476464) (xy 473.349574 -20.47113) (xy 473.349574 -20.032726)
				(xy 473.349574 -19.708114) (xy 473.319602 -19.678142) (xy 472.814904 -19.678142) (xy 472.649296 -19.843496)
				(xy 472.649296 -20.694904)
			)
		)
	)
	(zone
		(layer "B.Cu")
		(hatch none 0.5)
		(connect_pads
			(clearance 0)
		)
		(min_thickness 0.25)
		(keepout
			(tracks not_allowed)
			(vias allowed)
			(pads allowed)
			(copperpour not_allowed)
			(footprints allowed)
		)
		(placement
			(enabled no)
			(sheetname "")
		)
		(fill
			(thermal_gap 0.5)
			(thermal_bridge_width 0.5)
			(island_removal_mode 0)
		)
		(polygon
			(pts
				(xy 347.570806 -60.622434) (xy 347.062806 -60.622434) (xy 347.062806 -61.003434) (xy 347.570806 -61.003434)
			)
		)
	)
	(zone
		(net "GND")
		(layer "B.Cu")
		(hatch none 0.5)
		(connect_pads
			(clearance 0.5)
		)
		(min_thickness 0.25)
		(fill yes
			(thermal_gap 0.5)
			(thermal_bridge_width 0.5)
			(island_removal_mode 0)
		)
		(polygon
			(pts
				(xy 115.52428 -136.648698) (xy 113.705894 -136.648698) (xy 113.505234 -136.448038) (xy 113.505234 -134.234936)
				(xy 113.712244 -134.027926) (xy 115.498626 -134.027926) (xy 115.744244 -134.273544) (xy 115.744244 -136.428734)
			)
		)
	)
	(zone
		(net "PVTT_GHJ")
		(layer "B.Cu")
		(hatch none 0.5)
		(connect_pads
			(clearance 0.5)
		)
		(min_thickness 0.25)
		(fill yes
			(thermal_gap 0.5)
			(thermal_bridge_width 0.5)
			(island_removal_mode 0)
		)
		(polygon
			(pts
				(xy 96.672654 -25.626314) (xy 95.781368 -26.5176) (xy 95.781368 -26.7716) (xy 95.781368 -27.1018)
				(xy 95.781368 -28.46578) (xy 95.781368 -28.881832) (xy 95.6818 -28.9814) (xy 94.107 -28.9814) (xy 94.054168 -28.928568)
				(xy 94.054168 -28.46578) (xy 94.054168 -26.3144) (xy 94.054168 -25.5016) (xy 94.054168 -19.431)
				(xy 94.155768 -19.3294) (xy 94.435168 -19.3294) (xy 94.536768 -19.431) (xy 94.536768 -19.7866) (xy 94.866968 -20.1168)
				(xy 95.273368 -20.1168) (xy 96.416114 -18.974054) (xy 96.54286 -18.847308) (xy 96.54286 -16.45412)
				(xy 96.44634 -16.3576) (xy 94.866968 -16.3576) (xy 94.155768 -16.3576) (xy 93.952568 -16.1544) (xy 93.952568 -14.37894)
				(xy 94.450408 -13.8811) (xy 94.86392 -13.8811) (xy 95.0468 -13.69822) (xy 95.10014 -13.64488) (xy 95.10014 -12.22756)
				(xy 95.0468 -12.17422) (xy 94.40926 -11.53668) (xy 94.1451 -11.53668) (xy 94.13748 -11.5443) (xy 94.102428 -11.5443)
				(xy 93.952568 -11.39444) (xy 93.952568 -10.0584) (xy 94.206568 -9.8044) (xy 94.663768 -9.8044) (xy 95.476568 -8.9916)
				(xy 95.527368 -8.9916) (xy 97.076768 -8.9916) (xy 97.279968 -8.7884) (xy 97.279968 -5.8166) (xy 97.025968 -5.5626)
				(xy 96.467168 -5.5626) (xy 95.552768 -6.477) (xy 94.739968 -6.477) (xy 94.130368 -6.477) (xy 93.952568 -6.2992)
				(xy 93.952568 -4.7752) (xy 94.485968 -4.2418) (xy 96.647 -4.2418) (xy 96.647 -1.397) (xy 96.393 -1.143)
				(xy 95.2754 -1.143) (xy 94.9198 -1.4986) (xy 94.9198 -1.905) (xy 94.742 -2.0828) (xy 94.1578 -2.0828)
				(xy 93.952568 -1.877568) (xy 93.952568 0.0254) (xy 93.600016 0.0254) (xy 93.600016 4.128516) (xy 94.0943 4.6228)
				(xy 96.02216 4.6228) (xy 96.94418 3.70078) (xy 96.94418 3.06578) (xy 96.5708 2.6924) (xy 95.3008 2.6924)
				(xy 95.1484 2.54) (xy 95.1484 0.8636) (xy 95.2754 0.7366) (xy 96.5454 0.7366) (xy 97.64776 -0.36576)
				(xy 97.64776 -19.12112) (xy 96.672654 -20.096226)
			)
		)
	)
	(zone
		(net "P12V_STBY")
		(layer "B.Cu")
		(hatch none 0.5)
		(connect_pads
			(clearance 0.5)
		)
		(min_thickness 0.25)
		(fill yes
			(thermal_gap 0.5)
			(thermal_bridge_width 0.5)
			(island_removal_mode 0)
		)
		(polygon
			(pts
				(xy 177.4952 -97.6884) (xy 177.4952 -100.5205) (xy 177.7365 -100.7618) (xy 177.85588 -100.88118)
				(xy 178.036728 -101.062028) (xy 178.986688 -101.062028) (xy 181.026308 -101.062028) (xy 181.1782 -100.910136)
				(xy 181.1782 -100.67798) (xy 181.1782 -99.9744) (xy 181.1782 -97.4598) (xy 181.1782 -94.488) (xy 181.1528 -94.4626)
				(xy 180.6448 -93.9546) (xy 178.0032 -93.9546) (xy 177.86604 -94.09176) (xy 177.86604 -95.348044)
				(xy 177.4952 -95.718884)
			)
		)
	)
	(zone
		(layer "B.Cu")
		(hatch none 0.5)
		(connect_pads
			(clearance 0)
		)
		(min_thickness 0.25)
		(keepout
			(tracks allowed)
			(vias allowed)
			(pads allowed)
			(copperpour allowed)
			(footprints allowed)
		)
		(placement
			(enabled no)
			(sheetname "")
		)
		(fill
			(thermal_gap 0.5)
			(thermal_bridge_width 0.5)
			(island_removal_mode 0)
		)
		(polygon
			(pts
				(xy 368.8461 -115.5446) (xy 368.8461 -114.2746) (xy 370.5479 -114.2746) (xy 370.5479 -115.5446)
			)
		)
	)
	(zone
		(net "PVDDQ_KLM")
		(layer "B.Cu")
		(hatch none 0.5)
		(connect_pads
			(clearance 0.5)
		)
		(min_thickness 0.25)
		(fill yes
			(thermal_gap 0.5)
			(thermal_bridge_width 0.5)
			(island_removal_mode 0)
		)
		(polygon
			(pts
				(xy 78.838552 -148.570696) (xy 78.735174 -148.674074) (xy 78.735174 -150.834852) (xy 78.865984 -150.965662)
				(xy 88.46947 -150.965662) (xy 88.47709 -150.958042) (xy 93.368876 -150.958042) (xy 93.943678 -150.38324)
				(xy 94.52102 -150.38324) (xy 94.55531 -150.34895) (xy 94.55531 -149.20849) (xy 94.49181 -149.14499)
				(xy 93.810074 -149.14499) (xy 93.603826 -148.938742) (xy 93.603826 -148.570696)
			)
		)
		(polygon
			(pts
				(xy 88.0491 -150.0886) (xy 87.8459 -150.0886) (xy 87.8459 -150.2918) (xy 88.0491 -150.2918)
			)
		)
		(polygon
			(pts
				(xy 87.704168 -150.0886) (xy 87.500968 -150.0886) (xy 87.500968 -150.2918) (xy 87.704168 -150.2918)
			)
		)
		(polygon
			(pts
				(xy 84.402168 -150.0886) (xy 84.198968 -150.0886) (xy 84.198968 -150.2918) (xy 84.402168 -150.2918)
			)
		)
		(polygon
			(pts
				(xy 93.40596 -150.05812) (xy 93.20276 -150.05812) (xy 93.20276 -150.26132) (xy 93.40596 -150.26132)
			)
		)
		(polygon
			(pts
				(xy 88.0491 -149.3266) (xy 87.8459 -149.3266) (xy 87.8459 -149.5298) (xy 88.0491 -149.5298)
			)
		)
		(polygon
			(pts
				(xy 87.704168 -149.3266) (xy 87.500968 -149.3266) (xy 87.500968 -149.5298) (xy 87.704168 -149.5298)
			)
		)
		(polygon
			(pts
				(xy 84.402168 -149.3266) (xy 84.198968 -149.3266) (xy 84.198968 -149.5298) (xy 84.402168 -149.5298)
			)
		)
		(polygon
			(pts
				(xy 93.40596 -149.29612) (xy 93.20276 -149.29612) (xy 93.20276 -149.49932) (xy 93.40596 -149.49932)
			)
		)
	)
	(zone
		(net "GND")
		(layer "B.Cu")
		(hatch none 0.5)
		(connect_pads
			(clearance 0.5)
		)
		(min_thickness 0.25)
		(fill yes
			(thermal_gap 0.5)
			(thermal_bridge_width 0.5)
			(island_removal_mode 0)
		)
		(polygon
			(pts
				(xy 351.6122 -86.9442) (xy 351.663 -86.995) (xy 352.806 -86.995) (xy 352.9457 -86.8553) (xy 352.9457 -85.3694)
				(xy 352.9457 -84.596986) (xy 352.854006 -84.505292) (xy 352.522028 -84.505292) (xy 352.30562 -84.288884)
				(xy 352.30562 -84.147914) (xy 352.206306 -84.0486) (xy 351.7138 -84.0486) (xy 351.6122 -84.1502)
				(xy 351.6122 -84.698078) (xy 351.86747 -84.953348) (xy 351.86747 -86.31301) (xy 351.6122 -86.56828)
			)
		)
	)
	(zone
		(net "P12V_NVDIMM_KLM")
		(layer "B.Cu")
		(hatch none 0.5)
		(connect_pads
			(clearance 0.5)
		)
		(min_thickness 0.25)
		(fill yes
			(thermal_gap 0.5)
			(thermal_bridge_width 0.5)
			(island_removal_mode 0)
		)
		(polygon
			(pts
				(xy 17.19199 -129.73939) (xy 16.891 -129.4384) (xy 13.878306 -129.4384) (xy 13.13307 -130.183636)
				(xy 11.745976 -130.183636) (xy 11.69416 -130.235452) (xy 11.69416 -131.982464) (xy 11.3792 -132.297424)
				(xy 11.3792 -133.7564) (xy 11.7602 -134.1374) (xy 12.065 -134.4422) (xy 16.68526 -134.4422) (xy 16.99514 -134.13232)
				(xy 17.19199 -133.93547)
			)
		)
	)
	(zone
		(net "P1V05_PCH_STBY")
		(layer "B.Cu")
		(hatch none 0.5)
		(connect_pads
			(clearance 0.5)
		)
		(min_thickness 0.25)
		(fill yes
			(thermal_gap 0.5)
			(thermal_bridge_width 0.5)
			(island_removal_mode 0)
		)
		(polygon
			(pts
				(xy 410.1592 -125.1966) (xy 410.0322 -125.3236) (xy 410.0322 -125.6538) (xy 409.861766 -125.824234)
				(xy 408.563064 -125.824234) (xy 408.353768 -126.03353) (xy 408.3558 -126.035562) (xy 408.3558 -129.9718)
				(xy 410.580586 -132.196586) (xy 411.025848 -132.196586) (xy 411.132782 -132.089652) (xy 411.132782 -131.808982)
				(xy 409.194 -129.8702) (xy 409.194 -129.224278) (xy 409.85186 -128.566418) (xy 410.843222 -128.566418)
				(xy 411.29204 -128.1176) (xy 411.29204 -126.55804) (xy 410.7942 -126.0602) (xy 410.718 -125.984)
				(xy 410.718 -125.2347) (xy 410.718 -125.2093) (xy 410.7053 -125.1966) (xy 410.6799 -125.1966)
			)
		)
		(polygon
			(pts
				(xy 408.9019 -126.6571) (xy 408.6987 -126.6571) (xy 408.6987 -126.8603) (xy 408.9019 -126.8603)
			)
		)
		(polygon
			(pts
				(xy 409.8417 -126.6571) (xy 409.6385 -126.6571) (xy 409.6385 -126.8603) (xy 409.8417 -126.8603)
			)
		)
	)
	(zone
		(layer "B.Cu")
		(hatch none 0.5)
		(connect_pads
			(clearance 0)
		)
		(min_thickness 0.25)
		(keepout
			(tracks not_allowed)
			(vias allowed)
			(pads allowed)
			(copperpour not_allowed)
			(footprints allowed)
		)
		(placement
			(enabled no)
			(sheetname "")
		)
		(fill
			(thermal_gap 0.5)
			(thermal_bridge_width 0.5)
			(island_removal_mode 0)
		)
		(polygon
			(pts
				(arc
					(start 421.32377 -139.59586)
					(mid 420.965376 -139.953873)
					(end 421.323516 -140.31214)
				)
				(xy 421.767762 -140.31214)
				(arc
					(start 421.767762 -140.081)
					(mid 421.751023 -140.040589)
					(end 421.710612 -140.02385)
				)
				(arc
					(start 421.580818 -140.02385)
					(mid 421.056901 -139.954)
					(end 421.580818 -139.88415)
				)
				(xy 421.739568 -139.88415)
				(arc
					(start 421.742108 -139.88669)
					(mid 421.849803 -139.941809)
					(end 421.904922 -140.049504)
				)
				(xy 421.907462 -140.052044) (xy 421.907462 -140.31214) (xy 422.009062 -140.31214) (xy 422.009062 -140.052044)
				(arc
					(start 422.011602 -140.049504)
					(mid 422.066721 -139.941809)
					(end 422.174416 -139.88669)
				)
				(xy 422.176956 -139.88415)
				(arc
					(start 422.336214 -139.88415)
					(mid 422.860131 -139.954)
					(end 422.336214 -140.02385)
				)
				(arc
					(start 422.205912 -140.02385)
					(mid 422.165501 -140.040589)
					(end 422.148762 -140.081)
				)
				(xy 422.148762 -140.31214)
				(arc
					(start 422.593516 -140.31214)
					(mid 422.951656 -139.954)
					(end 422.593516 -139.59586)
				)
			)
		)
	)
	(zone
		(layer "B.Cu")
		(hatch none 0.5)
		(connect_pads
			(clearance 0)
		)
		(min_thickness 0.25)
		(keepout
			(tracks not_allowed)
			(vias allowed)
			(pads allowed)
			(copperpour not_allowed)
			(footprints allowed)
		)
		(placement
			(enabled no)
			(sheetname "")
		)
		(fill
			(thermal_gap 0.5)
			(thermal_bridge_width 0.5)
			(island_removal_mode 0)
		)
		(polygon
			(pts
				(arc
					(start 406.489916 -135.48995)
					(mid 408.079702 -133.900164)
					(end 406.489916 -132.310124)
				)
				(arc
					(start 406.489916 -132.310124)
					(mid 404.899876 -133.900164)
					(end 406.489916 -135.48995)
				)
			)
		)
	)
	(zone
		(net "PVDDQ_GHJ")
		(layer "B.Cu")
		(hatch none 0.5)
		(connect_pads
			(clearance 0.5)
		)
		(min_thickness 0.25)
		(fill yes
			(thermal_gap 0.5)
			(thermal_bridge_width 0.5)
			(island_removal_mode 0)
		)
		(polygon
			(pts
				(xy 108.5596 -14.9606) (xy 108.4072 -15.113) (xy 108.4072 -16.3576) (xy 108.3056 -16.4592) (xy 100.835968 -16.4592)
				(xy 100.683568 -16.6116) (xy 100.683568 -18.8722) (xy 100.886768 -19.0754) (xy 112.443768 -19.0754)
				(xy 112.723168 -18.796) (xy 112.723168 -16.8402) (xy 112.342168 -16.4592) (xy 109.1438 -16.4592)
				(xy 109.093 -16.4084) (xy 109.093 -15.0622) (xy 108.9914 -14.9606)
			)
		)
		(polygon
			(pts
				(xy 107.5182 -18.1483) (xy 107.315 -18.1483) (xy 107.315 -18.3515) (xy 107.5182 -18.3515)
			)
		)
		(polygon
			(pts
				(xy 104.2162 -18.1483) (xy 104.013 -18.1483) (xy 104.013 -18.3515) (xy 104.2162 -18.3515)
			)
		)
		(polygon
			(pts
				(xy 101.0539 -18.1483) (xy 100.8507 -18.1483) (xy 100.8507 -18.3515) (xy 101.0539 -18.3515)
			)
		)
		(polygon
			(pts
				(xy 110.657132 -17.1577) (xy 110.453932 -17.1577) (xy 110.453932 -17.3609) (xy 110.657132 -17.3609)
			)
		)
		(polygon
			(pts
				(xy 107.5182 -17.1577) (xy 107.315 -17.1577) (xy 107.315 -17.3609) (xy 107.5182 -17.3609)
			)
		)
		(polygon
			(pts
				(xy 104.2162 -17.1577) (xy 104.013 -17.1577) (xy 104.013 -17.3609) (xy 104.2162 -17.3609)
			)
		)
	)
	(zone
		(layer "B.Cu")
		(hatch none 0.5)
		(connect_pads
			(clearance 0)
		)
		(min_thickness 0.25)
		(keepout
			(tracks not_allowed)
			(vias allowed)
			(pads allowed)
			(copperpour not_allowed)
			(footprints allowed)
		)
		(placement
			(enabled no)
			(sheetname "")
		)
		(fill
			(thermal_gap 0.5)
			(thermal_bridge_width 0.5)
			(island_removal_mode 0)
		)
		(polygon
			(pts
				(arc
					(start 291.999924 -39.649908)
					(mid 290.09975 -41.550082)
					(end 291.999924 -43.450002)
				)
				(arc
					(start 291.999924 -43.450002)
					(mid 293.899844 -41.550082)
					(end 291.999924 -39.649908)
				)
			)
		)
	)
	(zone
		(layer "B.Cu")
		(hatch none 0.5)
		(connect_pads
			(clearance 0)
		)
		(min_thickness 0.25)
		(keepout
			(tracks allowed)
			(vias allowed)
			(pads allowed)
			(copperpour allowed)
			(footprints not_allowed)
		)
		(placement
			(enabled no)
			(sheetname "")
		)
		(fill
			(thermal_gap 0.5)
			(thermal_bridge_width 0.5)
			(island_removal_mode 0)
		)
		(polygon
			(pts
				(arc
					(start 56.999886 -78.449932)
					(mid 58.899806 -76.550012)
					(end 56.999886 -74.650092)
				)
				(arc
					(start 56.999886 -74.650092)
					(mid 55.099966 -76.550012)
					(end 56.999886 -78.449932)
				)
			)
		)
	)
	(zone
		(net "GND")
		(layer "B.Cu")
		(hatch none 0.5)
		(connect_pads
			(clearance 0.5)
		)
		(min_thickness 0.25)
		(fill yes
			(thermal_gap 0.5)
			(thermal_bridge_width 0.5)
			(island_removal_mode 0)
		)
		(polygon
			(pts
				(xy 347.3577 -19.7612) (xy 347.3577 -14.4907) (xy 346.1639 -13.2969) (xy 343.5223 -13.2969)
				(arc
					(start 337.50758 -13.2969)
					(mid 337.24581 -13.469888)
					(end 336.942938 -13.387832)
				)
				(xy 336.907378 -13.358622) (xy 336.169 -14.097) (xy 330.073 -14.097) (xy 329.565 -14.605)
				(arc
					(start 329.565 -18.331688)
					(mid 329.603956 -18.411424)
					(end 329.69073 -18.43024)
				)
				(arc
					(start 329.69073 -18.43024)
					(mid 330.18069 -18.796)
					(end 329.69073 -19.16176)
				)
				(arc
					(start 329.69073 -19.16176)
					(mid 329.603888 -19.18049)
					(end 329.565 -19.260312)
				)
				(xy 329.565 -19.304) (xy 329.946 -19.685)
				(arc
					(start 331.175614 -19.685)
					(mid 331.276647 -19.639959)
					(end 331.38618 -19.624548)
				)
				(arc
					(start 331.38999 -19.624548)
					(mid 331.499509 -19.640006)
					(end 331.600556 -19.685)
				)
				(xy 333.986378 -19.685) (xy 334.002888 -19.668744)
				(arc
					(start 339.030564 -19.668744)
					(mid 339.12041 -19.603714)
					(end 339.097366 -19.495262)
				)
				(xy 338.352892 -18.750788) (xy 338.352892 -18.418048) (xy 338.226908 -18.418048) (xy 338.226908 -18.545048)
				(xy 337.963764 -18.545048) (xy 337.950048 -18.546826)
				(arc
					(start 337.914996 -18.5547)
					(mid 337.880585 -18.55926)
					(end 337.845908 -18.560796)
				)
				(arc
					(start 337.284568 -18.560796)
					(mid 337.132545 -18.530557)
					(end 337.003644 -18.444464)
				)
				(xy 336.882994 -18.324068) (xy 336.779108 -18.220182)
				(arc
					(start 336.779108 -17.979644)
					(mid 336.794362 -17.870836)
					(end 336.838798 -17.770348)
				)
				(arc
					(start 336.838798 -17.770348)
					(mid 336.867944 -17.729349)
					(end 336.902044 -17.69237)
				)
				(arc
					(start 336.902044 -17.69237)
					(mid 336.930801 -17.623033)
					(end 336.904076 -17.552924)
				)
				(arc
					(start 336.904076 -17.552924)
					(mid 336.819729 -17.428248)
					(end 336.787744 -17.281144)
				)
				(arc
					(start 336.787744 -17.281144)
					(mid 336.816376 -17.123366)
					(end 336.905092 -16.989806)
				)
				(arc
					(start 336.905092 -16.989806)
					(mid 336.935148 -16.920815)
					(end 336.90941 -16.850106)
				)
				(arc
					(start 336.90941 -16.850106)
					(mid 336.82905 -16.448739)
					(end 337.15833 -16.205708)
				)
				(arc
					(start 337.15833 -16.205708)
					(mid 337.382478 -16.259875)
					(end 337.534504 -16.433292)
				)
				(arc
					(start 337.534504 -16.433292)
					(mid 337.566383 -16.584128)
					(end 337.536028 -16.735298)
				)
				(arc
					(start 337.536028 -16.735298)
					(mid 337.544819 -16.828065)
					(end 337.625436 -16.874744)
				)
				(arc
					(start 337.845908 -16.874744)
					(mid 337.880585 -16.876283)
					(end 337.914996 -16.88084)
				)
				(xy 337.950556 -16.888714) (xy 337.95716 -16.890492) (xy 338.226908 -16.890492) (xy 338.226908 -17.017492)
				(xy 338.352892 -17.017492) (xy 338.352892 -16.890492) (xy 339.115908 -16.890492) (xy 339.115908 -18.434812)
				(xy 339.278976 -18.59788) (xy 339.342222 -18.534634)
				(arc
					(start 339.323426 -18.501106)
					(mid 339.279585 -18.185489)
					(end 339.463888 -17.925542)
				)
				(arc
					(start 339.463888 -17.925542)
					(mid 339.529081 -17.890643)
					(end 339.59927 -17.867376)
				)
				(arc
					(start 339.59927 -17.867376)
					(mid 340.131128 -18.260168)
					(end 339.654134 -18.718022)
				)
				(arc
					(start 339.654134 -18.718022)
					(mid 339.551986 -18.775376)
					(end 339.571838 -18.890742)
				)
				(arc
					(start 339.829648 -19.148552)
					(mid 339.930776 -19.328974)
					(end 339.922866 -19.535648)
				)
				(arc
					(start 339.922866 -19.535648)
					(mid 339.935746 -19.624698)
					(end 340.014306 -19.668744)
				)
				(xy 341.626952 -19.668744) (xy 341.643462 -19.685) (xy 342.014302 -19.685) (xy 343.101676 -20.772374)
				(arc
					(start 343.13368 -20.757896)
					(mid 343.532741 -20.830259)
					(end 343.605104 -21.22932)
				)
				(xy 343.590626 -21.261324)
				(arc
					(start 344.142568 -21.813266)
					(mid 344.227862 -21.842225)
					(end 344.302588 -21.79193)
				)
				(arc
					(start 344.302588 -21.79193)
					(mid 344.718697 -21.575917)
					(end 345.08694 -21.866098)
				)
				(arc
					(start 345.08694 -21.866098)
					(mid 345.109099 -22.038621)
					(end 345.06154 -22.20595)
				)
				(arc
					(start 345.06154 -22.20595)
					(mid 345.064706 -22.305561)
					(end 345.151456 -22.35454)
				)
				(arc
					(start 345.247722 -22.35454)
					(mid 345.338264 -22.299035)
					(end 345.329764 -22.19325)
				)
				(arc
					(start 345.329764 -22.19325)
					(mid 345.6178 -21.627504)
					(end 345.905836 -22.19325)
				)
				(arc
					(start 345.905836 -22.19325)
					(mid 345.897463 -22.298971)
					(end 345.987878 -22.35454)
				)
				(arc
					(start 347.045534 -22.35454)
					(mid 347.137625 -22.295857)
					(end 347.123258 -22.187662)
				)
				(arc
					(start 347.123258 -22.187662)
					(mid 347.3958 -21.602089)
					(end 347.668342 -22.187662)
				)
				(arc
					(start 347.668342 -22.187662)
					(mid 347.654066 -22.295815)
					(end 347.746066 -22.35454)
				)
				(xy 347.827092 -22.35454)
				(arc
					(start 348.142306 -22.039326)
					(mid 348.17508 -21.757545)
					(end 348.375478 -21.556726)
				)
				(xy 348.375478 -20.183856) (xy 348.156022 -19.9644) (xy 347.5609 -19.9644)
			)
		)
	)
	(zone
		(layer "B.Cu")
		(hatch none 0.5)
		(connect_pads
			(clearance 0)
		)
		(min_thickness 0.25)
		(keepout
			(tracks allowed)
			(vias allowed)
			(pads allowed)
			(copperpour allowed)
			(footprints not_allowed)
		)
		(placement
			(enabled no)
			(sheetname "")
		)
		(fill
			(thermal_gap 0.5)
			(thermal_bridge_width 0.5)
			(island_removal_mode 0)
		)
		(polygon
			(pts
				(xy 336.810096 -127.364998) (xy 336.810096 -159.100012) (xy 330.160122 -159.100012) (xy 330.160122 -127.364998)
			)
		)
	)
	(zone
		(net "P1V05_PCH_STBY")
		(layer "B.Cu")
		(hatch none 0.5)
		(connect_pads
			(clearance 0.5)
		)
		(min_thickness 0.25)
		(fill yes
			(thermal_gap 0.5)
			(thermal_bridge_width 0.5)
			(island_removal_mode 0)
		)
		(polygon
			(pts
				(xy 388.549134 -114.370866) (xy 387.939534 -114.370866) (xy 387.786372 -114.524028) (xy 387.786372 -115.067588)
				(xy 387.7564 -115.09756) (xy 387.683756 -115.170204) (xy 387.683756 -116.22659) (xy 387.392418 -116.517928)
				(xy 387.392418 -117.178582) (xy 387.223 -117.348) (xy 381.762 -117.348) (xy 381 -116.586) (xy 381 -112.522)
				(xy 381.254 -112.268) (xy 382.27 -112.268) (xy 382.905 -112.903) (xy 382.905 -113.792) (xy 383.413 -114.3)
				(xy 385.826 -114.3) (xy 386.461 -114.3) (xy 386.715 -114.046) (xy 386.715 -113.411) (xy 386.715 -113.377218)
				(xy 386.844286 -113.247932) (xy 386.878068 -113.247932) (xy 387.048248 -113.247932) (xy 387.076696 -113.219484)
				(xy 387.076696 -113.049304) (xy 387.21792 -112.90808) (xy 387.27888 -112.90808) (xy 387.50748 -112.90808)
				(xy 387.8326 -113.2332) (xy 388.35838 -113.2332) (xy 388.7978 -112.79378) (xy 389.656828 -112.79378)
				(xy 389.897874 -113.034826) (xy 389.925052 -113.062004) (xy 389.925052 -113.178844) (xy 389.995664 -113.249456)
				(xy 390.251696 -113.249456) (xy 390.317482 -113.18367) (xy 390.317482 -113.042192) (xy 390.45896 -112.900714)
				(xy 390.617456 -112.900714) (xy 390.773412 -113.05667) (xy 390.773412 -113.198148) (xy 390.841738 -113.266474)
				(xy 391.027158 -113.266474) (xy 391.131806 -113.161826) (xy 391.131806 -113.052098) (xy 391.268458 -112.915446)
				(xy 391.62482 -112.915446) (xy 391.93724 -113.227866) (xy 391.98804 -113.227866) (xy 392.24204 -113.481866)
				(xy 392.326114 -113.481866) (xy 392.397488 -113.55324) (xy 392.397488 -114.0968) (xy 391.8712 -114.0968)
				(xy 391.6934 -114.2746) (xy 391.1346 -114.2746) (xy 391.033 -114.3762) (xy 390.8806 -114.3762) (xy 390.7536 -114.2492)
				(xy 390.3472 -114.2492) (xy 389.5344 -114.2492) (xy 389.509 -114.2746) (xy 389.4074 -114.3762) (xy 389.255 -114.3762)
				(xy 389.1534 -114.2746) (xy 388.6454 -114.2746)
			)
		)
	)
	(zone
		(net "PVCCMCP_CPU1")
		(layer "B.Cu")
		(hatch none 0.5)
		(connect_pads
			(clearance 0.5)
		)
		(min_thickness 0.25)
		(fill yes
			(thermal_gap 0.5)
			(thermal_bridge_width 0.5)
			(island_removal_mode 0)
		)
		(polygon
			(pts
				(xy 107.719368 -77.1652) (xy 114.094768 -77.1652) (xy 114.272568 -77.343) (xy 114.272568 -78.0796)
				(xy 114.018568 -78.3336) (xy 112.875568 -78.3336) (xy 112.748568 -78.4606) (xy 112.748568 -78.867)
				(xy 113.002568 -79.121) (xy 114.501168 -79.121) (xy 114.628168 -79.248) (xy 114.628168 -79.9846)
				(xy 114.526568 -80.0862) (xy 107.820968 -80.0862) (xy 104.130856 -80.0862) (xy 103.93807 -79.893414)
				(xy 103.93807 -78.51902) (xy 103.778558 -78.359508) (xy 103.778558 -77.303884) (xy 103.917242 -77.1652)
			)
		)
	)
	(zone
		(layer "B.Cu")
		(hatch none 0.5)
		(connect_pads
			(clearance 0)
		)
		(min_thickness 0.25)
		(keepout
			(tracks allowed)
			(vias allowed)
			(pads allowed)
			(copperpour allowed)
			(footprints allowed)
		)
		(placement
			(enabled no)
			(sheetname "")
		)
		(fill
			(thermal_gap 0.5)
			(thermal_bridge_width 0.5)
			(island_removal_mode 0)
		)
		(polygon
			(pts
				(xy 363.0803 -113.6396) (xy 363.0803 -112.3696) (xy 364.7821 -112.3696) (xy 364.7821 -113.6396)
			)
		)
	)
	(zone
		(net "GND")
		(layer "B.Cu")
		(hatch none 0.5)
		(connect_pads
			(clearance 0.5)
		)
		(min_thickness 0.25)
		(fill yes
			(thermal_gap 0.5)
			(thermal_bridge_width 0.5)
			(island_removal_mode 0)
		)
		(polygon
			(pts
				(xy 367.123472 -14.596872) (xy 367.919 -15.3924) (xy 367.919 -18.3134) (xy 367.538 -18.6944) (xy 364.7948 -18.6944)
				(xy 358.4702 -18.6944) (xy 358.1654 -18.6944) (xy 357.886 -18.6944) (xy 357.5558 -18.6944) (xy 357.0732 -18.2118)
				(xy 357.0732 -13.208) (xy 357.2002 -13.081) (xy 357.5558 -13.081) (xy 359.0036 -13.081) (xy 359.6894 -13.7668)
				(xy 362.937298 -13.7668) (xy 363.76737 -14.596872)
			)
		)
	)
	(zone
		(net "P3V3_STBY")
		(layer "B.Cu")
		(hatch none 0.5)
		(connect_pads
			(clearance 0.5)
		)
		(min_thickness 0.25)
		(fill yes
			(thermal_gap 0.5)
			(thermal_bridge_width 0.5)
			(island_removal_mode 0)
		)
		(polygon
			(pts
				(xy 474.455744 -6.42112) (xy 474.455744 -4.64312) (xy 474.455744 -4.61772) (xy 474.506544 -4.56692)
				(xy 475.116144 -4.56692) (xy 475.192344 -4.64312) (xy 475.192344 -5.969) (xy 475.3864 -6.163056)
				(xy 475.3864 -6.5278) (xy 475.1832 -6.731) (xy 474.5482 -6.731) (xy 474.455744 -6.638544)
			)
		)
	)
	(zone
		(net "GND")
		(layer "B.Cu")
		(hatch none 0.5)
		(connect_pads
			(clearance 0.5)
		)
		(min_thickness 0.25)
		(fill yes
			(thermal_gap 0.5)
			(thermal_bridge_width 0.5)
			(island_removal_mode 0)
		)
		(polygon
			(pts
				(xy 15.7988 -126.111) (xy 16.7005 -127.0127) (xy 16.7005 -128.9177) (xy 17.3482 -129.5654) (xy 17.3482 -133.1976)
				(xy 20.3708 -133.1976) (xy 20.8026 -132.7658) (xy 20.8026 -127.0762) (xy 20.3708 -126.6444) (xy 17.5514 -126.6444)
				(xy 16.8275 -125.9205) (xy 16.8275 -124.6886) (xy 16.5608 -124.4219) (xy 16.299434 -124.160534)
				(xy 13.998448 -124.160534) (xy 13.95857 -124.120656) (xy 13.95857 -123.598686) (xy 13.702538 -123.342654)
				(xy 13.066268 -123.342654) (xy 13.039344 -123.369578) (xy 13.039344 -123.788678) (xy 13.127228 -123.876562)
				(xy 13.334492 -123.876562) (xy 13.526008 -124.068078) (xy 13.526008 -124.611892) (xy 14.040612 -125.126496)
				(xy 14.040612 -125.787912) (xy 14.1732 -125.9205) (xy 14.3637 -126.111)
			)
		)
	)
	(zone
		(net "P1V5_LAN")
		(layer "B.Cu")
		(hatch none 0.5)
		(connect_pads
			(clearance 0.5)
		)
		(min_thickness 0.25)
		(fill yes
			(thermal_gap 0.5)
			(thermal_bridge_width 0.5)
			(island_removal_mode 0)
		)
		(polygon
			(pts
				(xy 476.758 -43.434) (xy 477.139 -43.815) (xy 478.155 -43.815) (xy 478.4344 -43.5356) (xy 478.4344 -42.0878)
				(xy 478.7392 -41.783) (xy 479.18878 -41.783) (xy 479.347784 -41.942004) (xy 480.289616 -41.942004)
				(xy 480.3521 -41.87952) (xy 480.3521 -41.063418) (xy 480.1235 -40.834818) (xy 480.1235 -40.14724)
				(xy 480.22256 -40.04818) (xy 480.22256 -39.18458) (xy 479.9457 -38.90772) (xy 479.9457 -38.38448)
				(xy 479.91014 -38.34892) (xy 479.44278 -38.34892) (xy 479.42754 -38.36416) (xy 479.42754 -38.87216)
				(xy 479.55454 -38.99916) (xy 479.55454 -39.93896) (xy 479.2345 -40.259) (xy 478.85096 -40.259) (xy 478.77476 -40.1828)
				(xy 478.68078 -40.08882) (xy 478.68078 -39.43858) (xy 478.7138 -39.40556) (xy 478.7138 -38.7858)
				(xy 478.4852 -38.5572) (xy 476.885 -38.5572) (xy 476.758 -38.6842) (xy 476.758 -39.3446) (xy 476.758 -40.4876)
			)
		)
	)
	(zone
		(layer "B.Cu")
		(hatch none 0.5)
		(connect_pads
			(clearance 0)
		)
		(min_thickness 0.25)
		(keepout
			(tracks not_allowed)
			(vias allowed)
			(pads allowed)
			(copperpour not_allowed)
			(footprints allowed)
		)
		(placement
			(enabled no)
			(sheetname "")
		)
		(fill
			(thermal_gap 0.5)
			(thermal_bridge_width 0.5)
			(island_removal_mode 0)
		)
		(polygon
			(pts
				(arc
					(start 464.867498 -26.919936)
					(mid 461.267302 -30.520132)
					(end 464.867498 -34.120074)
				)
				(arc
					(start 467.867492 -34.120074)
					(mid 471.467434 -30.520132)
					(end 467.867492 -26.919936)
				)
			)
		)
	)
	(zone
		(layer "B.Cu")
		(hatch none 0.5)
		(connect_pads
			(clearance 0)
		)
		(min_thickness 0.25)
		(keepout
			(tracks not_allowed)
			(vias allowed)
			(pads allowed)
			(copperpour not_allowed)
			(footprints allowed)
		)
		(placement
			(enabled no)
			(sheetname "")
		)
		(fill
			(thermal_gap 0.5)
			(thermal_bridge_width 0.5)
			(island_removal_mode 0)
		)
		(polygon
			(pts
				(arc
					(start 428.10049 -116.196872)
					(mid 431.700432 -119.796814)
					(end 435.300374 -116.196872)
				)
				(arc
					(start 435.300374 -114.596926)
					(mid 431.700432 -110.996984)
					(end 428.10049 -114.596926)
				)
			)
		)
	)
	(zone
		(net "VCC_PA_3V3")
		(layer "B.Cu")
		(hatch none 0.5)
		(connect_pads
			(clearance 0.5)
		)
		(min_thickness 0.25)
		(fill yes
			(thermal_gap 0.5)
			(thermal_bridge_width 0.5)
			(island_removal_mode 0)
		)
		(polygon
			(pts
				(xy 427.3804 -42.5196) (xy 427.3804 -41.7322) (xy 427.3042 -41.656) (xy 426.593 -41.656) (xy 425.958 -41.021)
				(xy 425.8691 -40.9321) (xy 425.8691 -40.7797) (xy 425.5516 -40.4622) (xy 425.40555 -40.31615) (xy 424.23715 -40.31615)
				(xy 423.33545 -40.31615) (xy 422.9481 -39.9288) (xy 422.9481 -39.6367) (xy 422.8084 -39.497) (xy 422.5036 -39.497)
				(xy 422.4401 -39.5605) (xy 422.4401 -40.1066) (xy 422.3258 -40.2209) (xy 422.3258 -41.1988) (xy 422.3512 -41.2242)
				(xy 422.7068 -41.2242) (xy 424.6372 -41.2242) (xy 424.7388 -41.3258) (xy 425.6024 -41.3258) (xy 425.97705 -41.70045)
				(xy 425.97705 -42.22115) (xy 426.4025 -42.6466) (xy 426.4025 -42.7863) (xy 426.72 -43.1038) (xy 426.72 -43.3832)
				(xy 426.8724 -43.5356) (xy 427.609 -43.5356) (xy 427.7106 -43.434) (xy 427.7106 -42.9133) (xy 427.3804 -42.5831)
			)
		)
	)
	(zone
		(net "VR_FET_SW_P12V_STBY_PVDDQ_DEF")
		(layer "B.Cu")
		(hatch none 0.5)
		(connect_pads
			(clearance 0.5)
		)
		(min_thickness 0.25)
		(fill yes
			(thermal_gap 0.5)
			(thermal_bridge_width 0.5)
			(island_removal_mode 0)
		)
		(polygon
			(pts
				(xy 380.6952 -157.153102) (xy 380.6952 -154.57297) (xy 380.688088 -154.566112) (xy 380.688088 -154.221688)
				(xy 380.3142 -153.8478) (xy 375.4882 -153.8478) (xy 375.3358 -154.0002) (xy 375.3358 -154.2796)
				(xy 375.30786 -154.30754) (xy 375.30786 -154.94) (xy 375.3104 -154.94254) (xy 375.3104 -154.94762)
				(xy 375.3104 -155.067) (xy 375.3104 -155.7782) (xy 375.591324 -156.059124) (xy 376.946668 -156.059124)
				(xy 378.412756 -156.059124) (xy 378.898912 -156.54528) (xy 378.898912 -157.323282) (xy 379.112526 -157.536896)
				(xy 379.279404 -157.536896) (xy 380.311406 -157.536896)
			)
		)
	)
	(zone
		(layer "B.Cu")
		(hatch none 0.5)
		(connect_pads
			(clearance 0)
		)
		(min_thickness 0.25)
		(keepout
			(tracks not_allowed)
			(vias allowed)
			(pads allowed)
			(copperpour not_allowed)
			(footprints allowed)
		)
		(placement
			(enabled no)
			(sheetname "")
		)
		(fill
			(thermal_gap 0.5)
			(thermal_bridge_width 0.5)
			(island_removal_mode 0)
		)
		(polygon
			(pts
				(arc
					(start 83.000088 -113.450116)
					(mid 84.900008 -111.550196)
					(end 83.000088 -109.650022)
				)
				(arc
					(start 83.000088 -109.650022)
					(mid 81.099914 -111.550196)
					(end 83.000088 -113.450116)
				)
			)
		)
	)
	(zone
		(layer "B.Cu")
		(hatch none 0.5)
		(connect_pads
			(clearance 0)
		)
		(min_thickness 0.25)
		(keepout
			(tracks not_allowed)
			(vias allowed)
			(pads allowed)
			(copperpour not_allowed)
			(footprints allowed)
		)
		(placement
			(enabled no)
			(sheetname "")
		)
		(fill
			(thermal_gap 0.5)
			(thermal_bridge_width 0.5)
			(island_removal_mode 0)
		)
		(polygon
			(pts
				(xy 449.819522 -114.787172) (xy 449.819522 -114.520218) (xy 450.005958 -114.333782)
				(arc
					(start 450.177662 -114.333782)
					(mid 450.701579 -114.403632)
					(end 450.177662 -114.473482)
				)
				(xy 450.06387 -114.473482) (xy 449.959222 -114.57813) (xy 449.959222 -114.787172)
				(arc
					(start 450.434964 -114.787172)
					(mid 450.818504 -114.403632)
					(end 450.434964 -114.020092)
				)
				(arc
					(start 449.165218 -114.020092)
					(mid 448.781678 -114.403505)
					(end 449.164964 -114.787172)
				)
				(xy 449.578222 -114.787172) (xy 449.578222 -114.546888) (xy 449.504816 -114.473482)
				(arc
					(start 449.422266 -114.473482)
					(mid 448.898349 -114.403632)
					(end 449.422266 -114.333782)
				)
				(xy 449.562728 -114.333782) (xy 449.717922 -114.488976) (xy 449.717922 -114.787172)
			)
		)
	)
	(zone
		(net "P12V_FAN")
		(layer "B.Cu")
		(hatch none 0.5)
		(connect_pads
			(clearance 0.5)
		)
		(min_thickness 0.25)
		(fill yes
			(thermal_gap 0.5)
			(thermal_bridge_width 0.5)
			(island_removal_mode 0)
		)
		(polygon
			(pts
				(xy 3.81 -116.84) (xy 3.81 -114.8842) (xy 3.937 -114.7572) (xy 5.9182 -114.7572) (xy 6.124702 -114.7572)
				(xy 6.8072 -114.7572) (xy 7.3406 -114.7572) (xy 7.57174 -114.98834) (xy 7.57174 -117.3988) (xy 7.24154 -117.729)
				(xy 4.0894 -117.729) (xy 3.81 -117.4496) (xy 3.81 -117.244876)
			)
		)
	)
	(zone
		(net "GND")
		(layer "B.Cu")
		(hatch none 0.5)
		(connect_pads
			(clearance 0.5)
		)
		(min_thickness 0.25)
		(fill yes
			(thermal_gap 0.5)
			(thermal_bridge_width 0.5)
			(island_removal_mode 0)
		)
		(polygon
			(pts
				(xy 401.7264 -140.716) (xy 401.22348 -141.21892) (xy 401.22348 -141.72692) (xy 400.79422 -142.15618)
				(xy 395.58468 -142.15618) (xy 394.208 -143.53286) (xy 394.208 -144.88922) (xy 393.91336 -145.18386)
				(xy 390.138666 -145.18386) (xy 389.887206 -144.9324) (xy 389.887206 -143.979392) (xy 389.5344 -143.626586)
				(xy 382.788414 -143.626586) (xy 382.0414 -144.3736) (xy 382.0414 -152.422098) (xy 381.917194 -152.546304)
				(xy 381.917194 -153.117804) (xy 381.941832 -153.142442) (xy 382.744218 -153.142442) (xy 383.043176 -153.4414)
				(xy 388.7216 -153.4414) (xy 389.676894 -152.486106) (xy 389.676894 -152.237948) (xy 391.454132 -150.46071)
				(xy 392.54811 -150.46071) (xy 393.01166 -149.99716) (xy 394.14704 -149.99716) (xy 395.6304 -148.5138)
				(xy 400.5834 -148.5138) (xy 403.16658 -145.93062) (xy 403.16658 -140.843) (xy 403.03958 -140.716)
			)
		)
		(polygon
			(pts
				(xy 399.664936 -142.966186) (xy 399.461736 -142.966186) (xy 399.461736 -143.169386) (xy 399.664936 -143.169386)
			)
		)
		(polygon
			(pts
				(xy 398.902936 -142.966186) (xy 398.699736 -142.966186) (xy 398.699736 -143.169386) (xy 398.902936 -143.169386)
			)
		)
		(polygon
			(pts
				(xy 400.91868 -142.9639) (xy 400.71548 -142.9639) (xy 400.71548 -143.1671) (xy 400.91868 -143.1671)
			)
		)
		(polygon
			(pts
				(xy 400.15668 -142.9639) (xy 399.95348 -142.9639) (xy 399.95348 -143.1671) (xy 400.15668 -143.1671)
			)
		)
	)
	(zone
		(layer "B.Cu")
		(hatch none 0.5)
		(connect_pads
			(clearance 0)
		)
		(min_thickness 0.25)
		(keepout
			(tracks not_allowed)
			(vias allowed)
			(pads allowed)
			(copperpour not_allowed)
			(footprints allowed)
		)
		(placement
			(enabled no)
			(sheetname "")
		)
		(fill
			(thermal_gap 0.5)
			(thermal_bridge_width 0.5)
			(island_removal_mode 0)
		)
		(polygon
			(pts
				(arc
					(start 294.589962 -41.550336)
					(mid 289.410394 -41.550336)
					(end 294.589962 -41.550336)
				)
			)
		)
	)
	(zone
		(layer "B.Cu")
		(hatch none 0.5)
		(connect_pads
			(clearance 0)
		)
		(min_thickness 0.25)
		(keepout
			(tracks not_allowed)
			(vias allowed)
			(pads allowed)
			(copperpour not_allowed)
			(footprints allowed)
		)
		(placement
			(enabled no)
			(sheetname "")
		)
		(fill
			(thermal_gap 0.5)
			(thermal_bridge_width 0.5)
			(island_removal_mode 0)
		)
		(polygon
			(pts
				(arc
					(start 291.999924 -114.089942)
					(mid 294.539924 -111.549942)
					(end 291.999924 -109.009942)
				)
				(arc
					(start 291.999924 -109.009942)
					(mid 289.459924 -111.549942)
					(end 291.999924 -114.089942)
				)
			)
		)
	)
	(zone
		(layer "B.Cu")
		(hatch none 0.5)
		(connect_pads
			(clearance 0)
		)
		(min_thickness 0.25)
		(keepout
			(tracks not_allowed)
			(vias allowed)
			(pads allowed)
			(copperpour not_allowed)
			(footprints allowed)
		)
		(placement
			(enabled no)
			(sheetname "")
		)
		(fill
			(thermal_gap 0.5)
			(thermal_bridge_width 0.5)
			(island_removal_mode 0)
		)
		(polygon
			(pts
				(xy 12.98575 -34.40303) (xy 13.168376 -34.585656)
				(arc
					(start 13.168376 -34.731198)
					(mid 13.098526 -35.255115)
					(end 13.028676 -34.731198)
				)
				(xy 13.028676 -34.643568) (xy 12.927838 -34.54273) (xy 12.714986 -34.54273)
				(arc
					(start 12.714986 -34.988246)
					(mid 13.098399 -35.37204)
					(end 13.482066 -34.9885)
				)
				(arc
					(start 13.482066 -33.7185)
					(mid 13.098526 -33.33496)
					(end 12.714986 -33.7185)
				)
				(xy 12.714986 -34.16173) (xy 12.90701 -34.16173) (xy 13.028676 -34.040064)
				(arc
					(start 13.028676 -33.975802)
					(mid 13.098526 -33.451885)
					(end 13.168376 -33.975802)
				)
				(xy 13.168376 -34.097976) (xy 12.964922 -34.30143) (xy 12.714986 -34.30143) (xy 12.714986 -34.40303)
			)
		)
	)
	(zone
		(net "P3V3_STBY")
		(layer "B.Cu")
		(hatch none 0.5)
		(connect_pads
			(clearance 0.5)
		)
		(min_thickness 0.25)
		(fill yes
			(thermal_gap 0.5)
			(thermal_bridge_width 0.5)
			(island_removal_mode 0)
		)
		(polygon
			(pts
				(xy 465.006944 -7.53872) (xy 465.006944 -5.86232) (xy 465.006944 -5.089144) (xy 464.759294 -4.841494)
				(xy 464.752436 -4.834636) (xy 464.752436 -4.17322) (xy 464.617816 -4.0386) (xy 463.440526 -4.0386)
				(xy 463.190082 -4.289044) (xy 463.190082 -4.923282) (xy 463.3722 -5.1054) (xy 463.9564 -5.1054)
				(xy 464.232244 -5.381244) (xy 464.232244 -6.810756) (xy 464.185 -6.858) (xy 463.574638 -6.858) (xy 463.46872 -6.963918)
				(xy 463.46872 -7.686294) (xy 463.520028 -7.737602) (xy 464.808062 -7.737602) (xy 464.977226 -7.737602)
				(xy 465.006944 -7.707884)
			)
		)
	)
	(zone
		(layer "B.Cu")
		(hatch none 0.5)
		(connect_pads
			(clearance 0)
		)
		(min_thickness 0.25)
		(keepout
			(tracks not_allowed)
			(vias allowed)
			(pads allowed)
			(copperpour not_allowed)
			(footprints allowed)
		)
		(placement
			(enabled no)
			(sheetname "")
		)
		(fill
			(thermal_gap 0.5)
			(thermal_bridge_width 0.5)
			(island_removal_mode 0)
		)
		(polygon
			(pts
				(xy 446.352168 -114.333782) (xy 446.53073 -114.512344) (xy 446.53073 -114.787172) (xy 446.63233 -114.787172)
				(xy 446.63233 -114.507264) (xy 446.805812 -114.333782)
				(arc
					(start 446.977516 -114.333782)
					(mid 447.501433 -114.403632)
					(end 446.977516 -114.473482)
				)
				(xy 446.863724 -114.473482) (xy 446.77203 -114.565176) (xy 446.77203 -114.787172)
				(arc
					(start 447.234818 -114.787172)
					(mid 447.618358 -114.403632)
					(end 447.234818 -114.020092)
				)
				(arc
					(start 445.965072 -114.020092)
					(mid 445.581532 -114.403505)
					(end 445.964818 -114.787172)
				)
				(xy 446.39103 -114.787172) (xy 446.39103 -114.570256) (xy 446.294256 -114.473482)
				(arc
					(start 446.22212 -114.473482)
					(mid 445.698203 -114.403632)
					(end 446.22212 -114.333782)
				)
			)
		)
	)
	(zone
		(net "GND")
		(layer "B.Cu")
		(hatch none 0.5)
		(connect_pads
			(clearance 0.5)
		)
		(min_thickness 0.25)
		(fill yes
			(thermal_gap 0.5)
			(thermal_bridge_width 0.5)
			(island_removal_mode 0)
		)
		(polygon
			(pts
				(xy 115.364768 -24.2062) (xy 115.263168 -24.3078) (xy 115.263168 -26.035) (xy 115.085368 -26.2128)
				(xy 114.196368 -26.2128) (xy 114.069368 -26.0858) (xy 114.069368 -24.3332) (xy 113.967768 -24.2316)
				(xy 113.637568 -24.2316) (xy 113.612168 -24.257) (xy 113.612168 -25.6032) (xy 112.875568 -26.3398)
				(xy 112.875568 -27.7368) (xy 112.71758 -27.894788) (xy 112.71758 -29.41066) (xy 112.7887 -29.48178)
				(xy 114.28984 -29.48178) (xy 115.796568 -27.975052) (xy 115.796568 -24.4094) (xy 115.593368 -24.2062)
			)
		)
		(polygon
			(pts
				(xy 113.7158 -28.28544) (xy 113.5126 -28.28544) (xy 113.5126 -28.48864) (xy 113.7158 -28.48864)
			)
		)
	)
	(zone
		(layer "B.Cu")
		(hatch none 0.5)
		(connect_pads
			(clearance 0)
		)
		(min_thickness 0.25)
		(keepout
			(tracks allowed)
			(vias allowed)
			(pads allowed)
			(copperpour allowed)
			(footprints not_allowed)
		)
		(placement
			(enabled no)
			(sheetname "")
		)
		(fill
			(thermal_gap 0.5)
			(thermal_bridge_width 0.5)
			(island_removal_mode 0)
		)
		(polygon
			(pts
				(xy 387.330696 -57.33288) (xy 387.330696 -46.00448) (xy 399.421096 -46.00448) (xy 399.421096 -57.33288)
			)
		)
	)
	(zone
		(layer "B.Cu")
		(hatch none 0.5)
		(connect_pads
			(clearance 0)
		)
		(min_thickness 0.25)
		(keepout
			(tracks allowed)
			(vias allowed)
			(pads allowed)
			(copperpour allowed)
			(footprints not_allowed)
		)
		(placement
			(enabled no)
			(sheetname "")
		)
		(fill
			(thermal_gap 0.5)
			(thermal_bridge_width 0.5)
			(island_removal_mode 0)
		)
		(polygon
			(pts
				(arc
					(start 292.902894 -119.800116)
					(mid 296.520162 -125.508518)
					(end 300.137068 -119.800116)
				)
			)
		)
	)
	(zone
		(layer "B.Cu")
		(hatch none 0.5)
		(connect_pads
			(clearance 0)
		)
		(min_thickness 0.25)
		(keepout
			(tracks allowed)
			(vias allowed)
			(pads allowed)
			(copperpour allowed)
			(footprints allowed)
		)
		(placement
			(enabled no)
			(sheetname "")
		)
		(fill
			(thermal_gap 0.5)
			(thermal_bridge_width 0.5)
			(island_removal_mode 0)
		)
		(polygon
			(pts
				(xy 405.638 -126.492) (xy 405.638 -125.476) (xy 407.416 -125.476) (xy 407.416 -126.492)
			)
		)
	)
	(zone
		(net "PVDDQ_ABC")
		(layer "B.Cu")
		(hatch none 0.5)
		(connect_pads
			(clearance 0.5)
		)
		(min_thickness 0.25)
		(fill yes
			(thermal_gap 0.5)
			(thermal_bridge_width 0.5)
			(island_removal_mode 0)
		)
		(polygon
			(pts
				(xy 265.8364 -16.4592) (xy 265.684 -16.6116) (xy 265.684 -18.8722) (xy 265.8872 -19.0754) (xy 277.4442 -19.0754)
				(xy 277.7236 -18.796) (xy 277.7236 -16.8402) (xy 277.3426 -16.4592)
			)
		)
		(polygon
			(pts
				(xy 272.518632 -18.1483) (xy 272.315432 -18.1483) (xy 272.315432 -18.3515) (xy 272.518632 -18.3515)
			)
		)
		(polygon
			(pts
				(xy 269.216632 -18.1483) (xy 269.013432 -18.1483) (xy 269.013432 -18.3515) (xy 269.216632 -18.3515)
			)
		)
		(polygon
			(pts
				(xy 266.054332 -18.1483) (xy 265.851132 -18.1483) (xy 265.851132 -18.3515) (xy 266.054332 -18.3515)
			)
		)
		(polygon
			(pts
				(xy 275.657564 -17.1577) (xy 275.454364 -17.1577) (xy 275.454364 -17.3609) (xy 275.657564 -17.3609)
			)
		)
		(polygon
			(pts
				(xy 272.518632 -17.1577) (xy 272.315432 -17.1577) (xy 272.315432 -17.3609) (xy 272.518632 -17.3609)
			)
		)
		(polygon
			(pts
				(xy 269.216632 -17.1577) (xy 269.013432 -17.1577) (xy 269.013432 -17.3609) (xy 269.216632 -17.3609)
			)
		)
	)
	(zone
		(layer "B.Cu")
		(hatch none 0.5)
		(connect_pads
			(clearance 0)
		)
		(min_thickness 0.25)
		(keepout
			(tracks allowed)
			(vias allowed)
			(pads allowed)
			(copperpour allowed)
			(footprints not_allowed)
		)
		(placement
			(enabled no)
			(sheetname "")
		)
		(fill
			(thermal_gap 0.5)
			(thermal_bridge_width 0.5)
			(island_removal_mode 0)
		)
		(polygon
			(pts
				(arc
					(start 428.10049 -116.196872)
					(mid 431.700432 -119.796814)
					(end 435.300374 -116.196872)
				)
				(arc
					(start 435.300374 -114.596926)
					(mid 431.700432 -110.996984)
					(end 428.10049 -114.596926)
				)
			)
		)
	)
	(zone
		(net "GND")
		(layer "B.Cu")
		(hatch none 0.5)
		(connect_pads
			(clearance 0.5)
		)
		(min_thickness 0.25)
		(fill yes
			(thermal_gap 0.5)
			(thermal_bridge_width 0.5)
			(island_removal_mode 0)
		)
		(polygon
			(pts
				(xy 382.7272 -105.537) (xy 382.7272 -105.1306) (xy 383.1082 -104.7496) (xy 384.1242 -104.7496) (xy 385.151884 -105.777284)
				(xy 385.151884 -105.945686) (xy 385.03606 -106.06151) (xy 384.82651 -106.06151) (xy 384.2512 -105.4862)
				(xy 383.9972 -105.4862) (xy 383.8448 -105.6386) (xy 383.6416 -105.6386) (xy 383.5146 -105.5116)
				(xy 383.1336 -105.5116) (xy 383.0066 -105.6386) (xy 382.8288 -105.6386)
			)
		)
	)
	(zone
		(layer "B.Cu")
		(hatch none 0.5)
		(connect_pads
			(clearance 0)
		)
		(min_thickness 0.25)
		(keepout
			(tracks allowed)
			(vias allowed)
			(pads allowed)
			(copperpour allowed)
			(footprints not_allowed)
		)
		(placement
			(enabled no)
			(sheetname "")
		)
		(fill
			(thermal_gap 0.5)
			(thermal_bridge_width 0.5)
			(island_removal_mode 0)
		)
		(polygon
			(pts
				(arc
					(start 248.000012 -109.009942)
					(mid 245.460012 -111.549942)
					(end 248.000012 -114.089942)
				)
				(arc
					(start 248.000012 -114.089942)
					(mid 250.540012 -111.549942)
					(end 248.000012 -109.009942)
				)
			)
		)
	)
	(zone
		(layer "B.Cu")
		(hatch none 0.5)
		(connect_pads
			(clearance 0)
		)
		(min_thickness 0.25)
		(keepout
			(tracks allowed)
			(vias allowed)
			(pads allowed)
			(copperpour allowed)
			(footprints not_allowed)
		)
		(placement
			(enabled no)
			(sheetname "")
		)
		(fill
			(thermal_gap 0.5)
			(thermal_bridge_width 0.5)
			(island_removal_mode 0)
		)
		(polygon
			(pts
				(xy 339.320124 -127.364998) (xy 336.820002 -127.364998) (xy 336.820002 -159.100012) (xy 339.320124 -159.100012)
			)
		)
	)
	(zone
		(layer "B.Cu")
		(hatch none 0.5)
		(connect_pads
			(clearance 0)
		)
		(min_thickness 0.25)
		(keepout
			(tracks not_allowed)
			(vias allowed)
			(pads allowed)
			(copperpour not_allowed)
			(footprints allowed)
		)
		(placement
			(enabled no)
			(sheetname "")
		)
		(fill
			(thermal_gap 0.5)
			(thermal_bridge_width 0.5)
			(island_removal_mode 0)
		)
		(polygon
			(pts
				(arc
					(start 173.928532 -157.04439)
					(mid 173.338136 -156.714333)
					(end 172.671486 -156.59989)
				)
				(arc
					(start 171.99991 -156.59989)
					(mid 170.50004 -155.10002)
					(end 171.99991 -153.599896)
				)
				(arc
					(start 172.671486 -153.599896)
					(mid 173.338113 -153.485602)
					(end 173.928532 -153.15565)
				)
				(arc
					(start 173.928532 -153.15565)
					(mid 177.999652 -155.10002)
					(end 173.928532 -157.04439)
				)
			)
		)
	)
	(zone
		(net "PVDDQ_KLM")
		(layer "B.Cu")
		(hatch none 0.5)
		(connect_pads
			(clearance 0.5)
		)
		(min_thickness 0.25)
		(fill yes
			(thermal_gap 0.5)
			(thermal_bridge_width 0.5)
			(island_removal_mode 0)
		)
		(polygon
			(pts
				(xy 78.944216 -133.965188) (xy 78.735174 -134.17423) (xy 78.735174 -136.506712) (xy 78.743048 -136.514332)
				(xy 78.743048 -136.617964) (xy 78.917292 -136.792208) (xy 93.259656 -136.792208) (xy 93.989398 -136.062466)
				(xy 94.6531 -136.062466) (xy 94.8055 -135.910066) (xy 94.8055 -134.925562) (xy 94.65818 -134.778242)
				(xy 94.17431 -134.778242) (xy 93.794326 -134.398258) (xy 93.794326 -134.35711) (xy 93.402404 -133.965188)
			)
		)
		(polygon
			(pts
				(xy 88.0491 -135.8011) (xy 87.8459 -135.8011) (xy 87.8459 -136.0043) (xy 88.0491 -136.0043)
			)
		)
		(polygon
			(pts
				(xy 84.402168 -135.8011) (xy 84.198968 -135.8011) (xy 84.198968 -136.0043) (xy 84.402168 -136.0043)
			)
		)
		(polygon
			(pts
				(xy 81.303368 -135.8011) (xy 81.100168 -135.8011) (xy 81.100168 -136.0043) (xy 81.303368 -136.0043)
			)
		)
		(polygon
			(pts
				(xy 93.627448 -135.7249) (xy 93.424248 -135.7249) (xy 93.424248 -135.9281) (xy 93.627448 -135.9281)
			)
		)
		(polygon
			(pts
				(xy 88.0491 -134.8105) (xy 87.8459 -134.8105) (xy 87.8459 -135.0137) (xy 88.0491 -135.0137)
			)
		)
		(polygon
			(pts
				(xy 81.303368 -134.8105) (xy 81.100168 -134.8105) (xy 81.100168 -135.0137) (xy 81.303368 -135.0137)
			)
		)
		(polygon
			(pts
				(xy 93.627448 -134.7343) (xy 93.424248 -134.7343) (xy 93.424248 -134.9375) (xy 93.627448 -134.9375)
			)
		)
	)
	(zone
		(layer "B.Cu")
		(hatch none 0.5)
		(connect_pads
			(clearance 0)
		)
		(min_thickness 0.25)
		(keepout
			(tracks allowed)
			(vias allowed)
			(pads allowed)
			(copperpour allowed)
			(footprints not_allowed)
		)
		(placement
			(enabled no)
			(sheetname "")
		)
		(fill
			(thermal_gap 0.5)
			(thermal_bridge_width 0.5)
			(island_removal_mode 0)
		)
		(polygon
			(pts
				(xy 22.519894 -159.097472) (xy 22.519894 -152.987502) (xy 163.52012 -152.987502) (xy 163.52012 -159.097472)
			)
		)
	)
	(zone
		(layer "B.Cu")
		(hatch none 0.5)
		(connect_pads
			(clearance 0)
		)
		(min_thickness 0.25)
		(keepout
			(tracks not_allowed)
			(vias allowed)
			(pads allowed)
			(copperpour not_allowed)
			(footprints allowed)
		)
		(placement
			(enabled no)
			(sheetname "")
		)
		(fill
			(thermal_gap 0.5)
			(thermal_bridge_width 0.5)
			(island_removal_mode 0)
		)
		(polygon
			(pts
				(xy 453.85355 -123.80468) (xy 453.85355 -124.102876) (xy 453.698356 -124.25807)
				(arc
					(start 453.526652 -124.25807)
					(mid 453.002735 -124.18822)
					(end 453.526652 -124.11837)
				)
				(xy 453.640444 -124.11837) (xy 453.71385 -124.044964) (xy 453.71385 -123.80468)
				(arc
					(start 453.269604 -123.80468)
					(mid 452.88581 -124.188093)
					(end 453.26935 -124.57176)
				)
				(arc
					(start 454.53935 -124.57176)
					(mid 454.92289 -124.18822)
					(end 454.53935 -123.80468)
				)
				(xy 454.09485 -123.80468) (xy 454.09485 -124.044964) (xy 454.168256 -124.11837)
				(arc
					(start 454.282048 -124.11837)
					(mid 454.805965 -124.18822)
					(end 454.282048 -124.25807)
				)
				(xy 454.110344 -124.25807) (xy 453.95515 -124.102876) (xy 453.95515 -123.80468)
			)
		)
	)
	(zone
		(layer "B.Cu")
		(hatch none 0.5)
		(connect_pads
			(clearance 0)
		)
		(min_thickness 0.25)
		(keepout
			(tracks not_allowed)
			(vias allowed)
			(pads allowed)
			(copperpour not_allowed)
			(footprints allowed)
		)
		(placement
			(enabled no)
			(sheetname "")
		)
		(fill
			(thermal_gap 0.5)
			(thermal_bridge_width 0.5)
			(island_removal_mode 0)
		)
		(polygon
			(pts
				(arc
					(start 408.487372 -142.455392)
					(mid 408.203442 -142.90031)
					(end 408.351482 -142.39367)
				)
				(xy 408.6606 -142.084552)
				(arc
					(start 408.66441 -142.084552)
					(mid 408.680206 -142.074592)
					(end 408.696922 -142.066264)
				)
				(xy 408.696922 -141.949424) (xy 408.398726 -141.949424)
				(arc
					(start 408.395932 -141.94663)
					(mid 408.351335 -141.932813)
					(end 408.311604 -141.908276)
				)
				(arc
					(start 408.311604 -141.908276)
					(mid 408.199546 -141.400384)
					(end 408.520392 -141.809724)
				)
				(xy 408.696922 -141.809724)
				(arc
					(start 408.696922 -141.641576)
					(mid 408.313382 -141.258036)
					(end 407.929842 -141.641576)
				)
				(arc
					(start 407.929842 -142.657322)
					(mid 408.313255 -143.041116)
					(end 408.696922 -142.657576)
				)
				(xy 408.696922 -142.245842)
			)
		)
	)
	(zone
		(net "GND")
		(layer "B.Cu")
		(hatch none 0.5)
		(connect_pads
			(clearance 0.5)
		)
		(min_thickness 0.25)
		(fill yes
			(thermal_gap 0.5)
			(thermal_bridge_width 0.5)
			(island_removal_mode 0)
		)
		(polygon
			(pts
				(xy 373.779288 -136.091676) (xy 373.61622 -136.254744) (xy 373.61622 -137.09904) (xy 373.642636 -137.125456)
				(xy 375.77268 -137.125456) (xy 375.993914 -137.34669) (xy 375.993914 -138.162284) (xy 376.120152 -138.288522)
				(xy 376.98553 -138.288522) (xy 377.121674 -138.152378) (xy 377.121674 -136.25195) (xy 377.065794 -136.19607)
				(xy 376.453654 -136.19607) (xy 376.34926 -136.091676)
			)
		)
	)
	(zone
		(net "P3V3_STBY_MNG_RGMII")
		(layer "B.Cu")
		(hatch none 0.5)
		(connect_pads
			(clearance 0.5)
		)
		(min_thickness 0.25)
		(fill yes
			(thermal_gap 0.5)
			(thermal_bridge_width 0.5)
			(island_removal_mode 0)
		)
		(polygon
			(pts
				(xy 474.46946 -28.254452) (xy 473.539058 -29.184854) (xy 473.539058 -31.660084) (xy 473.755974 -31.877)
				(xy 474.472 -31.877) (xy 474.66758 -31.68142) (xy 474.66758 -29.715206) (xy 475.389448 -28.993338)
				(xy 475.389448 -28.39339) (xy 475.25051 -28.254452)
			)
		)
		(polygon
			(pts
				(xy 474.57106 -29.03982) (xy 474.36786 -29.03982) (xy 474.36786 -29.24302) (xy 474.57106 -29.24302)
			)
		)
	)
	(zone
		(net "P12V_STBY")
		(layer "B.Cu")
		(hatch none 0.5)
		(connect_pads
			(clearance 0.5)
		)
		(min_thickness 0.25)
		(fill yes
			(thermal_gap 0.5)
			(thermal_bridge_width 0.5)
			(island_removal_mode 0)
		)
		(polygon
			(pts
				(xy 31.285688 -35.488118) (xy 33.236154 -37.438584) (xy 40.429434 -37.438584) (xy 40.90797 -36.960048)
				(xy 40.90797 -32.258) (xy 40.423084 -31.773114) (xy 30.761686 -31.773114) (xy 30.745684 -31.789116)
				(xy 30.245812 -31.789116) (xy 29.677106 -32.357822) (xy 29.376878 -32.65805) (xy 29.376878 -35.350704)
				(xy 29.514038 -35.487864) (xy 30.145736 -35.487864) (xy 30.145736 -35.488118)
			)
		)
	)
	(zone
		(net "GND")
		(layer "B.Cu")
		(hatch none 0.5)
		(connect_pads
			(clearance 0.5)
		)
		(min_thickness 0.25)
		(fill yes
			(thermal_gap 0.5)
			(thermal_bridge_width 0.5)
			(island_removal_mode 0)
		)
		(polygon
			(pts
				(xy 258.3942 -80.839056) (xy 261.490968 -80.839056) (xy 261.586218 -80.743806) (xy 261.586218 -79.63408)
				(xy 261.586218 -79.388716) (xy 261.586218 -79.214726) (xy 261.471156 -79.099664) (xy 258.149344 -79.099664)
				(xy 258.009898 -78.960472) (xy 257.764026 -78.960472) (xy 257.60299 -79.121508) (xy 257.60299 -80.50276)
				(xy 257.939286 -80.839056)
			)
		)
	)
	(zone
		(layer "B.Cu")
		(hatch none 0.5)
		(connect_pads
			(clearance 0)
		)
		(min_thickness 0.25)
		(keepout
			(tracks not_allowed)
			(vias allowed)
			(pads allowed)
			(copperpour not_allowed)
			(footprints allowed)
		)
		(placement
			(enabled no)
			(sheetname "")
		)
		(fill
			(thermal_gap 0.5)
			(thermal_bridge_width 0.5)
			(island_removal_mode 0)
		)
		(polygon
			(pts
				(arc
					(start 198.930006 -108.100114)
					(mid 200.479914 -106.550206)
					(end 198.930006 -105.000044)
				)
				(arc
					(start 198.930006 -105.000044)
					(mid 197.379844 -106.550206)
					(end 198.930006 -108.100114)
				)
			)
		)
	)
	(zone
		(layer "B.Cu")
		(hatch none 0.5)
		(connect_pads
			(clearance 0)
		)
		(min_thickness 0.25)
		(keepout
			(tracks not_allowed)
			(vias allowed)
			(pads allowed)
			(copperpour not_allowed)
			(footprints allowed)
		)
		(placement
			(enabled no)
			(sheetname "")
		)
		(fill
			(thermal_gap 0.5)
			(thermal_bridge_width 0.5)
			(island_removal_mode 0)
		)
		(polygon
			(pts
				(arc
					(start 494.867692 -26.92019)
					(mid 491.267496 -30.520386)
					(end 494.867692 -34.120328)
				)
				(arc
					(start 497.867686 -34.120328)
					(mid 501.607136 -30.520391)
					(end 497.867686 -26.92019)
				)
			)
		)
	)
	(zone
		(layer "B.Cu")
		(hatch none 0.5)
		(connect_pads
			(clearance 0)
		)
		(min_thickness 0.25)
		(keepout
			(tracks not_allowed)
			(vias allowed)
			(pads allowed)
			(copperpour not_allowed)
			(footprints allowed)
		)
		(placement
			(enabled no)
			(sheetname "")
		)
		(fill
			(thermal_gap 0.5)
			(thermal_bridge_width 0.5)
			(island_removal_mode 0)
		)
		(polygon
			(pts
				(arc
					(start 83.000088 -114.089942)
					(mid 85.540088 -111.549942)
					(end 83.000088 -109.009942)
				)
				(arc
					(start 83.000088 -109.009942)
					(mid 80.460088 -111.549942)
					(end 83.000088 -114.089942)
				)
			)
		)
	)
	(zone
		(net "P3V3")
		(layer "B.Cu")
		(hatch none 0.5)
		(connect_pads
			(clearance 0.5)
		)
		(min_thickness 0.25)
		(fill yes
			(thermal_gap 0.5)
			(thermal_bridge_width 0.5)
			(island_removal_mode 0)
		)
		(polygon
			(pts
				(xy 465.251546 -7.716012) (xy 467.58352 -7.716012) (xy 468.051388 -7.248144) (xy 468.051388 -6.56336)
				(xy 468.17153 -6.443218) (xy 468.17153 -6.44144) (xy 468.776812 -6.44144) (xy 468.902796 -6.315456)
				(xy 468.902796 -5.778754) (xy 468.85352 -5.729478) (xy 467.29904 -5.729478) (xy 466.728048 -5.158486)
				(xy 466.546438 -4.976876) (xy 465.275676 -4.976876) (xy 465.114386 -5.138166) (xy 465.114386 -7.578852)
			)
		)
	)
	(zone
		(net "P3V3_STBY")
		(layer "B.Cu")
		(hatch none 0.5)
		(connect_pads
			(clearance 0.5)
		)
		(min_thickness 0.25)
		(fill yes
			(thermal_gap 0.5)
			(thermal_bridge_width 0.5)
			(island_removal_mode 0)
		)
		(polygon
			(pts
				(xy 491.8964 -35.6362) (xy 494.7412 -35.6362) (xy 494.8428 -35.5346) (xy 494.8428 -34.9504) (xy 494.5634 -34.671)
				(xy 493.5982 -34.671) (xy 493.2426 -35.0266) (xy 492.6076 -35.0266) (xy 492.4298 -34.8488) (xy 491.7948 -34.8488)
				(xy 491.6424 -35.0012) (xy 491.6424 -35.3822)
			)
		)
	)
	(zone
		(layer "B.Cu")
		(hatch none 0.5)
		(connect_pads
			(clearance 0)
		)
		(min_thickness 0.25)
		(keepout
			(tracks allowed)
			(vias allowed)
			(pads allowed)
			(copperpour allowed)
			(footprints not_allowed)
		)
		(placement
			(enabled no)
			(sheetname "")
		)
		(fill
			(thermal_gap 0.5)
			(thermal_bridge_width 0.5)
			(island_removal_mode 0)
		)
		(polygon
			(pts
				(xy 330.160122 -127.359918) (xy 330.160122 -159.090106) (xy 328.520044 -159.090106) (xy 328.520044 -127.359918)
			)
		)
	)
	(zone
		(layer "B.Cu")
		(hatch none 0.5)
		(connect_pads
			(clearance 0)
		)
		(min_thickness 0.25)
		(keepout
			(tracks allowed)
			(vias allowed)
			(pads allowed)
			(copperpour allowed)
			(footprints not_allowed)
		)
		(placement
			(enabled no)
			(sheetname "")
		)
		(fill
			(thermal_gap 0.5)
			(thermal_bridge_width 0.5)
			(island_removal_mode 0)
		)
		(polygon
			(pts
				(arc
					(start 83.000088 -43.450002)
					(mid 84.900008 -41.550082)
					(end 83.000088 -39.649908)
				)
				(arc
					(start 83.000088 -39.649908)
					(mid 81.099914 -41.550082)
					(end 83.000088 -43.450002)
				)
			)
		)
	)
	(zone
		(net "GND")
		(layer "B.Cu")
		(hatch none 0.5)
		(connect_pads
			(clearance 0.5)
		)
		(min_thickness 0.25)
		(fill yes
			(thermal_gap 0.5)
			(thermal_bridge_width 0.5)
			(island_removal_mode 0)
		)
		(polygon
			(pts
				(xy 182.610252 -148.8567) (xy 179.2351 -148.8567) (xy 179.0954 -148.9964) (xy 179.0954 -150.114)
				(xy 179.1462 -150.1648) (xy 180.1622 -150.1648) (xy 180.4924 -149.8346) (xy 181.5084 -149.8346)
				(xy 181.61 -149.9362) (xy 182.51424 -149.9362) (xy 182.64124 -149.8092) (xy 182.64124 -148.887688)
			)
		)
	)
	(zone
		(net "P12V_PUMP")
		(layer "B.Cu")
		(hatch none 0.5)
		(connect_pads
			(clearance 0.5)
		)
		(min_thickness 0.25)
		(fill yes
			(thermal_gap 0.5)
			(thermal_bridge_width 0.5)
			(island_removal_mode 0)
		)
		(polygon
			(pts
				(xy 12.892024 -122.888756) (xy 11.864594 -121.861326) (xy 11.211052 -121.207784) (xy 11.211052 -118.092728)
				(xy 11.504422 -117.799358) (xy 12.157964 -117.799358) (xy 13.502386 -117.799358) (xy 13.833856 -118.130828)
				(xy 13.833856 -120.43156) (xy 15.557246 -122.15495) (xy 15.557246 -123.272042) (xy 15.457424 -123.371864)
				(xy 14.198854 -123.371864) (xy 14.108684 -123.281694) (xy 14.108684 -123.168156) (xy 13.829284 -122.888756)
			)
		)
	)
	(zone
		(layer "B.Cu")
		(hatch none 0.5)
		(connect_pads
			(clearance 0)
		)
		(min_thickness 0.25)
		(keepout
			(tracks allowed)
			(vias allowed)
			(pads allowed)
			(copperpour allowed)
			(footprints not_allowed)
		)
		(placement
			(enabled no)
			(sheetname "")
		)
		(fill
			(thermal_gap 0.5)
			(thermal_bridge_width 0.5)
			(island_removal_mode 0)
		)
		(polygon
			(pts
				(xy 165.159944 5.999988) (xy 165.159944 -25.729946) (xy 163.52012 -25.729946) (xy 163.52012 5.999988)
			)
		)
	)
	(zone
		(layer "B.Cu")
		(hatch none 0.5)
		(connect_pads
			(clearance 0)
		)
		(min_thickness 0.25)
		(keepout
			(tracks allowed)
			(vias allowed)
			(pads allowed)
			(copperpour allowed)
			(footprints not_allowed)
		)
		(placement
			(enabled no)
			(sheetname "")
		)
		(fill
			(thermal_gap 0.5)
			(thermal_bridge_width 0.5)
			(island_removal_mode 0)
		)
		(polygon
			(pts
				(xy 22.519894 -136.966198) (xy 22.519894 -133.785102) (xy 163.52012 -133.785102) (xy 163.52012 -136.966198)
			)
		)
	)
	(zone
		(layer "B.Cu")
		(hatch none 0.5)
		(connect_pads
			(clearance 0)
		)
		(min_thickness 0.25)
		(keepout
			(tracks allowed)
			(vias allowed)
			(pads allowed)
			(copperpour allowed)
			(footprints not_allowed)
		)
		(placement
			(enabled no)
			(sheetname "")
		)
		(fill
			(thermal_gap 0.5)
			(thermal_bridge_width 0.5)
			(island_removal_mode 0)
		)
		(polygon
			(pts
				(arc
					(start 198.930006 -108.100114)
					(mid 200.479914 -106.550206)
					(end 198.930006 -105.000044)
				)
				(arc
					(start 198.930006 -105.000044)
					(mid 197.379844 -106.550206)
					(end 198.930006 -108.100114)
				)
			)
		)
	)
	(zone
		(net "GND")
		(layer "B.Cu")
		(hatch none 0.5)
		(connect_pads
			(clearance 0.5)
		)
		(min_thickness 0.25)
		(fill yes
			(thermal_gap 0.5)
			(thermal_bridge_width 0.5)
			(island_removal_mode 0)
		)
		(polygon
			(pts
				(xy 418.23005 -37.312346) (xy 418.23005 -36.765484) (xy 418.24656 -36.74872) (xy 418.24656 -36.52774)
				(xy 418.4015 -36.3728) (xy 418.978588 -36.3728) (xy 419.064948 -36.28644) (xy 419.064948 -36.068)
				(xy 419.064948 -35.79368) (xy 419.026848 -35.75558) (xy 418.473128 -35.75558) (xy 418.211 -36.017708)
				(xy 417.732464 -36.496244) (xy 417.732464 -37.713158) (xy 417.859718 -37.840412) (xy 417.859718 -38.356794)
				(xy 417.861242 -38.358318) (xy 417.861242 -38.522402) (xy 417.89604 -38.5572) (xy 418.149786 -38.5572)
				(xy 418.929312 -38.5572) (xy 419.030912 -38.4556) (xy 419.030912 -37.95014) (xy 418.987732 -37.90696)
				(xy 418.4396 -37.90696) (xy 418.23005 -37.69741)
			)
		)
	)
	(zone
		(layer "B.Cu")
		(hatch none 0.5)
		(connect_pads
			(clearance 0)
		)
		(min_thickness 0.25)
		(keepout
			(tracks not_allowed)
			(vias allowed)
			(pads allowed)
			(copperpour not_allowed)
			(footprints allowed)
		)
		(placement
			(enabled no)
			(sheetname "")
		)
		(fill
			(thermal_gap 0.5)
			(thermal_bridge_width 0.5)
			(island_removal_mode 0)
		)
		(polygon
			(pts
				(xy 459.41615 -123.75642) (xy 459.415388 -123.75388)
				(arc
					(start 458.971904 -123.75388)
					(mid 458.58811 -124.137293)
					(end 458.97165 -124.52096)
				)
				(arc
					(start 460.24165 -124.52096)
					(mid 460.62519 -124.13742)
					(end 460.24165 -123.75388)
				)
				(xy 459.79715 -123.75388) (xy 459.79715 -123.994164) (xy 459.870556 -124.06757)
				(arc
					(start 459.984348 -124.06757)
					(mid 460.508265 -124.13742)
					(end 459.984348 -124.20727)
				)
				(xy 459.812644 -124.20727) (xy 459.65745 -124.052076) (xy 459.65745 -123.75388) (xy 459.559914 -123.75388)
				(xy 459.55585 -123.761754) (xy 459.55585 -124.052076) (xy 459.400656 -124.20727)
				(arc
					(start 459.228952 -124.20727)
					(mid 458.705035 -124.13742)
					(end 459.228952 -124.06757)
				)
				(xy 459.342744 -124.06757) (xy 459.41615 -123.994164)
			)
		)
	)
	(zone
		(layer "B.Cu")
		(hatch none 0.5)
		(connect_pads
			(clearance 0)
		)
		(min_thickness 0.25)
		(keepout
			(tracks not_allowed)
			(vias allowed)
			(pads allowed)
			(copperpour not_allowed)
			(footprints allowed)
		)
		(placement
			(enabled no)
			(sheetname "")
		)
		(fill
			(thermal_gap 0.5)
			(thermal_bridge_width 0.5)
			(island_removal_mode 0)
		)
		(polygon
			(pts
				(xy 346.173806 -59.733434) (xy 345.665806 -59.733434) (xy 345.665806 -60.114434) (xy 346.173806 -60.114434)
			)
		)
	)
	(zone
		(layer "B.Cu")
		(hatch none 0.5)
		(connect_pads
			(clearance 0)
		)
		(min_thickness 0.25)
		(keepout
			(tracks allowed)
			(vias allowed)
			(pads allowed)
			(copperpour allowed)
			(footprints allowed)
		)
		(placement
			(enabled no)
			(sheetname "")
		)
		(fill
			(thermal_gap 0.5)
			(thermal_bridge_width 0.5)
			(island_removal_mode 0)
		)
		(polygon
			(pts
				(xy 241.803682 -52.233576) (xy 253.12624 -52.233576) (xy 253.143512 -52.250848) (xy 253.143512 -26.286968)
				(xy 253.09195 -26.235406) (xy 237.361984 -29.394658) (xy 237.361984 -50.62347) (xy 238.985298 -52.246784)
				(xy 241.790474 -52.246784)
			)
		)
	)
	(zone
		(net "GND")
		(layer "B.Cu")
		(hatch none 0.5)
		(connect_pads
			(clearance 0.5)
		)
		(min_thickness 0.25)
		(fill yes
			(thermal_gap 0.5)
			(thermal_bridge_width 0.5)
			(island_removal_mode 0)
		)
		(polygon
			(pts
				(xy 445.944752 -27.456384) (xy 444.08217 -27.456384) (xy 443.802262 -27.736292) (xy 443.802262 -28.94076)
				(xy 443.841632 -28.979876) (xy 446.707006 -28.979876) (xy 446.73266 -28.954222) (xy 446.73266 -28.244292)
			)
		)
	)
	(zone
		(layer "B.Cu")
		(hatch none 0.5)
		(connect_pads
			(clearance 0)
		)
		(min_thickness 0.25)
		(keepout
			(tracks allowed)
			(vias allowed)
			(pads allowed)
			(copperpour allowed)
			(footprints not_allowed)
		)
		(placement
			(enabled no)
			(sheetname "")
		)
		(fill
			(thermal_gap 0.5)
			(thermal_bridge_width 0.5)
			(island_removal_mode 0)
		)
		(polygon
			(pts
				(arc
					(start 245.90502 -90.199972)
					(mid 246.36463 -90.009596)
					(end 246.555006 -89.549986)
				)
				(arc
					(start 246.555006 -85.199982)
					(mid 246.36463 -84.740372)
					(end 245.90502 -84.549996)
				)
				(arc
					(start 244.204998 -84.549996)
					(mid 243.745388 -84.740372)
					(end 243.555012 -85.199982)
				)
				(arc
					(start 243.555012 -89.549986)
					(mid 243.745388 -90.009596)
					(end 244.204998 -90.199972)
				)
			)
		)
	)
	(zone
		(net "P3V3_STBY")
		(layer "B.Cu")
		(hatch none 0.5)
		(connect_pads
			(clearance 0.5)
		)
		(min_thickness 0.25)
		(fill yes
			(thermal_gap 0.5)
			(thermal_bridge_width 0.5)
			(island_removal_mode 0)
		)
		(polygon
			(pts
				(xy 412.380684 -113.9444) (xy 412.380684 -103.870252) (xy 411.890718 -103.38054) (xy 405.074374 -103.38054)
				(xy 404.437342 -102.743508) (xy 403.09419 -102.743508) (xy 402.738082 -102.3874) (xy 398.61744 -102.3874)
				(xy 398.255998 -102.748842) (xy 394.090652 -102.748842) (xy 393.62761 -102.2858) (xy 387.0706 -102.2858)
				(xy 386.9944 -102.362) (xy 386.9944 -102.8446) (xy 386.8166 -103.0224) (xy 386.5626 -103.0224) (xy 386.32384 -102.78364)
				(xy 385.75996 -102.78364) (xy 385.668774 -102.6922) (xy 385.653534 -102.6922) (xy 385.6482 -102.686866)
				(xy 382.61544 -102.686866) (xy 382.23444 -103.067866) (xy 382.23444 -104.022398) (xy 382.20396 -104.052878)
				(xy 382.20396 -104.580182) (xy 381.98679 -104.797352) (xy 381.98679 -104.80167) (xy 381.818642 -104.969818)
				(xy 381.818642 -105.153968) (xy 381.878332 -105.213658) (xy 382.419352 -105.213658) (xy 383.028952 -104.604058)
				(xy 383.028952 -104.591866) (xy 383.50444 -104.591866) (xy 383.88544 -104.210866) (xy 387.28396 -104.210866)
				(xy 387.71322 -103.781606) (xy 388.725918 -103.781606) (xy 389.301736 -104.357424) (xy 389.301736 -104.626918)
				(xy 389.411718 -104.7369) (xy 390.3345 -104.7369) (xy 391.186924 -103.884476) (xy 391.492994 -103.884476)
				(xy 391.709148 -104.10063) (xy 391.709148 -104.407462) (xy 391.49147 -104.62514) (xy 391.391902 -104.62514)
				(xy 391.027666 -104.989376) (xy 391.027666 -105.243884) (xy 391.021062 -105.250488) (xy 390.853676 -105.250488)
				(xy 390.7282 -105.375964) (xy 390.7282 -105.543096) (xy 390.858756 -105.673652) (xy 391.109454 -105.673652)
				(xy 392.01344 -104.769666) (xy 392.01344 -104.768396) (xy 392.258042 -104.768396) (xy 392.31951 -104.829864)
				(xy 392.745468 -104.829864) (xy 392.893804 -104.681528) (xy 393.20724 -104.681528) (xy 393.402312 -104.8766)
				(xy 394.0556 -104.8766) (xy 394.309854 -105.130854) (xy 395.887448 -105.130854) (xy 396.799816 -106.043222)
				(xy 398.273524 -106.043222) (xy 398.40281 -105.913936) (xy 399.161 -105.913936) (xy 399.410936 -105.664)
				(xy 400.2532 -105.664) (xy 400.5072 -105.918) (xy 400.5072 -106.990388) (xy 400.890232 -107.37342)
				(xy 401.028408 -107.37342) (xy 401.029932 -107.37469) (xy 401.849336 -107.37469) (xy 402.67763 -106.546396)
				(xy 403.387052 -106.546396) (xy 403.572726 -106.360468) (xy 403.572726 -106.354372) (xy 403.638004 -106.289094)
				(xy 407.078942 -106.289094) (xy 407.414984 -106.625136) (xy 407.414984 -107.966256) (xy 408.373072 -108.924344)
				(xy 408.373072 -112.734598) (xy 409.1178 -113.479326) (xy 409.1178 -115.6716) (xy 409.2956 -115.8494)
				(xy 411.2768 -115.8494) (xy 411.4546 -115.6716) (xy 411.4546 -115.0874) (xy 411.353 -114.9858) (xy 411.353 -114.6048)
				(xy 411.5816 -114.3762) (xy 412.1912 -114.3762) (xy 412.380684 -114.186716)
			)
		)
		(polygon
			(pts
				(xy 406.1206 -105.3084) (xy 405.9174 -105.3084) (xy 405.9174 -105.5116) (xy 406.1206 -105.5116)
			)
		)
		(polygon
			(pts
				(xy 405.6888 -105.3084) (xy 405.4856 -105.3084) (xy 405.4856 -105.5116) (xy 405.6888 -105.5116)
			)
		)
		(polygon
			(pts
				(xy 404.9268 -105.3084) (xy 404.7236 -105.3084) (xy 404.7236 -105.5116) (xy 404.9268 -105.5116)
			)
		)
		(polygon
			(pts
				(xy 404.495 -105.3084) (xy 404.2918 -105.3084) (xy 404.2918 -105.5116) (xy 404.495 -105.5116)
			)
		)
		(polygon
			(pts
				(xy 403.733 -105.3084) (xy 403.5298 -105.3084) (xy 403.5298 -105.5116) (xy 403.733 -105.5116)
			)
		)
		(polygon
			(pts
				(xy 407.8986 -104.1654) (xy 407.6954 -104.1654) (xy 407.6954 -104.3686) (xy 407.8986 -104.3686)
			)
		)
		(polygon
			(pts
				(xy 407.1366 -104.1654) (xy 406.9334 -104.1654) (xy 406.9334 -104.3686) (xy 407.1366 -104.3686)
			)
		)
		(polygon
			(pts
				(xy 401.0406 -103.1748) (xy 400.8374 -103.1748) (xy 400.8374 -103.378) (xy 401.0406 -103.378)
			)
		)
		(polygon
			(pts
				(xy 400.6088 -103.1748) (xy 400.4056 -103.1748) (xy 400.4056 -103.378) (xy 400.6088 -103.378)
			)
		)
		(polygon
			(pts
				(xy 399.8468 -103.1748) (xy 399.6436 -103.1748) (xy 399.6436 -103.378) (xy 399.8468 -103.378)
			)
		)
	)
	(zone
		(layer "B.Cu")
		(hatch none 0.5)
		(connect_pads
			(clearance 0)
		)
		(min_thickness 0.25)
		(keepout
			(tracks allowed)
			(vias allowed)
			(pads allowed)
			(copperpour allowed)
			(footprints allowed)
		)
		(placement
			(enabled no)
			(sheetname "")
		)
		(fill
			(thermal_gap 0.5)
			(thermal_bridge_width 0.5)
			(island_removal_mode 0)
		)
		(polygon
			(pts
				(xy 307.848 -102.235) (xy 307.848 -123.571) (xy 319.278 -123.571) (xy 319.490344 -123.464828) (xy 319.52311 -123.432062)
				(xy 319.52311 -120.617742) (xy 319.806574 -120.334278) (xy 322.715636 -120.334278) (xy 326.263 -115.316)
				(xy 332.359 -109.093) (xy 334.645 -97.79) (xy 334.645 -95.758) (xy 310.26354 -95.758) (xy 310.24068 -95.73514)
				(xy 308.0766 -95.73514) (xy 307.848 -95.96374)
			)
		)
	)
	(zone
		(net "PVDDQ_KLM")
		(layer "B.Cu")
		(hatch none 0.5)
		(connect_pads
			(clearance 0.5)
		)
		(min_thickness 0.25)
		(fill yes
			(thermal_gap 0.5)
			(thermal_bridge_width 0.5)
			(island_removal_mode 0)
		)
		(polygon
			(pts
				(xy 168.454324 -145.393664) (xy 168.063672 -145.784316) (xy 168.063672 -147.616672) (xy 168.6306 -148.1836)
				(xy 171.3484 -148.1836) (xy 171.45 -148.082) (xy 171.45 -147.5994) (xy 171.3738 -147.5232) (xy 169.6466 -147.5232)
				(xy 169.369232 -147.245832) (xy 169.369232 -145.477738) (xy 169.285158 -145.393664)
			)
		)
		(polygon
			(pts
				(xy 168.584626 -146.992848) (xy 168.381426 -146.992848) (xy 168.381426 -147.196048) (xy 168.584626 -147.196048)
			)
		)
		(polygon
			(pts
				(xy 168.584626 -146.230848) (xy 168.381426 -146.230848) (xy 168.381426 -146.434048) (xy 168.584626 -146.434048)
			)
		)
	)
	(zone
		(layer "B.Cu")
		(hatch none 0.5)
		(connect_pads
			(clearance 0)
		)
		(min_thickness 0.25)
		(keepout
			(tracks allowed)
			(vias allowed)
			(pads allowed)
			(copperpour allowed)
			(footprints not_allowed)
		)
		(placement
			(enabled no)
			(sheetname "")
		)
		(fill
			(thermal_gap 0.5)
			(thermal_bridge_width 0.5)
			(island_removal_mode 0)
		)
		(polygon
			(pts
				(arc
					(start 472.928696 -157.04439)
					(mid 472.3383 -156.714333)
					(end 471.67165 -156.59989)
				)
				(arc
					(start 471.000074 -156.59989)
					(mid 469.500204 -155.10002)
					(end 471.000074 -153.599896)
				)
				(arc
					(start 471.67165 -153.599896)
					(mid 472.338277 -153.485602)
					(end 472.928696 -153.15565)
				)
				(arc
					(start 472.928696 -153.15565)
					(mid 476.999816 -155.10002)
					(end 472.928696 -157.04439)
				)
			)
		)
	)
	(zone
		(net "GND")
		(layer "B.Cu")
		(hatch none 0.5)
		(connect_pads
			(clearance 0.5)
		)
		(min_thickness 0.25)
		(fill yes
			(thermal_gap 0.5)
			(thermal_bridge_width 0.5)
			(island_removal_mode 0)
		)
		(polygon
			(pts
				(xy -5.5118 -14.3002) (xy -5.5118 -5.3594) (xy -3.4798 -5.3594) (xy -3.429 -5.4102) (xy -3.429 -14.70914)
				(xy -4.29768 -15.57782) (xy -4.29768 -16.54048) (xy -4.04876 -16.7894) (xy -3.2512 -16.7894) (xy -3.19532 -16.84528)
				(xy -3.19532 -19.4818) (xy -3.4163 -19.70278) (xy -4.95554 -19.70278) (xy -5.5118 -19.14652) (xy -5.5118 -15.55242)
				(xy -5.5118 -15.3162) (xy -5.5118 -14.5542)
			)
		)
	)
	(zone
		(layer "B.Cu")
		(hatch none 0.5)
		(connect_pads
			(clearance 0)
		)
		(min_thickness 0.25)
		(keepout
			(tracks allowed)
			(vias allowed)
			(pads allowed)
			(copperpour allowed)
			(footprints not_allowed)
		)
		(placement
			(enabled no)
			(sheetname "")
		)
		(fill
			(thermal_gap 0.5)
			(thermal_bridge_width 0.5)
			(island_removal_mode 0)
		)
		(polygon
			(pts
				(arc
					(start 465.019898 -26.919936)
					(mid 461.419702 -30.520132)
					(end 465.019898 -34.120074)
				)
				(arc
					(start 468.019892 -34.120074)
					(mid 471.619834 -30.520132)
					(end 468.019892 -26.919936)
				)
			)
		)
	)
	(zone
		(layer "B.Cu")
		(hatch none 0.5)
		(connect_pads
			(clearance 0)
		)
		(min_thickness 0.25)
		(keepout
			(tracks not_allowed)
			(vias allowed)
			(pads allowed)
			(copperpour not_allowed)
			(footprints allowed)
		)
		(placement
			(enabled no)
			(sheetname "")
		)
		(fill
			(thermal_gap 0.5)
			(thermal_bridge_width 0.5)
			(island_removal_mode 0)
		)
		(polygon
			(pts
				(arc
					(start 413.157416 -141.021054)
					(mid 412.774003 -140.63726)
					(end 412.390336 -141.0208)
				)
				(arc
					(start 412.390336 -142.0368)
					(mid 412.773876 -142.42034)
					(end 413.157416 -142.0368)
				)
				(xy 413.157416 -141.7193)
				(arc
					(start 412.888176 -141.7193)
					(mid 412.856745 -141.732319)
					(end 412.843726 -141.76375)
				)
				(arc
					(start 412.843726 -141.779498)
					(mid 412.773876 -142.303415)
					(end 412.704026 -141.779498)
				)
				(xy 412.704026 -141.734794)
				(arc
					(start 412.70682 -141.732)
					(mid 412.757988 -141.633562)
					(end 412.856426 -141.582394)
				)
				(xy 412.85922 -141.5796) (xy 413.157416 -141.5796) (xy 413.157416 -141.478) (xy 412.85922 -141.478)
				(arc
					(start 412.856426 -141.475206)
					(mid 412.7601 -141.426117)
					(end 412.707836 -141.331442)
				)
				(arc
					(start 412.707836 -141.331442)
					(mid 412.764327 -140.703359)
					(end 412.858458 -141.32687)
				)
				(arc
					(start 412.858458 -141.32687)
					(mid 412.872261 -141.335325)
					(end 412.888176 -141.3383)
				)
				(xy 413.157416 -141.3383)
			)
		)
	)
	(zone
		(net "GND")
		(layer "B.Cu")
		(hatch none 0.5)
		(connect_pads
			(clearance 0.5)
		)
		(min_thickness 0.25)
		(fill yes
			(thermal_gap 0.5)
			(thermal_bridge_width 0.5)
			(island_removal_mode 0)
		)
		(polygon
			(pts
				(xy 111.035592 -69.428614) (xy 102.150672 -69.428614) (xy 100.584254 -69.428614) (xy 100.45573 -69.557138)
				(xy 100.45573 -69.874638) (xy 100.117656 -70.212712) (xy 98.521774 -70.212712) (xy 98.141028 -69.831966)
				(xy 98.141028 -68.606162) (xy 97.992946 -68.45808) (xy 96.682306 -68.45808) (xy 96.428814 -68.711572)
				(xy 96.428814 -69.1769) (xy 96.428814 -69.809614) (xy 95.921322 -70.317106) (xy 93.494352 -70.317106)
				(xy 93.13799 -70.673468) (xy 93.13799 -70.714362) (xy 93.136466 -70.715886) (xy 93.133418 -70.715886)
				(xy 93.133418 -72.222614) (xy 108.826554 -72.222614) (xy 108.830364 -72.218804) (xy 112.509554 -72.218804)
				(xy 112.725962 -72.002396) (xy 112.725962 -69.525642) (xy 112.292384 -69.092064) (xy 111.383572 -69.092064)
				(xy 111.035592 -69.440044)
			)
		)
	)
	(zone
		(layer "B.Cu")
		(hatch none 0.5)
		(connect_pads
			(clearance 0)
		)
		(min_thickness 0.25)
		(keepout
			(tracks allowed)
			(vias allowed)
			(pads allowed)
			(copperpour allowed)
			(footprints allowed)
		)
		(placement
			(enabled no)
			(sheetname "")
		)
		(fill
			(thermal_gap 0.5)
			(thermal_bridge_width 0.5)
			(island_removal_mode 0)
		)
		(polygon
			(pts
				(xy 368.935 -117.094) (xy 368.935 -115.824) (xy 370.6368 -115.824) (xy 370.6368 -117.094)
			)
		)
	)
	(zone
		(layer "B.Cu")
		(hatch none 0.5)
		(connect_pads
			(clearance 0)
		)
		(min_thickness 0.25)
		(keepout
			(tracks allowed)
			(vias allowed)
			(pads allowed)
			(copperpour allowed)
			(footprints allowed)
		)
		(placement
			(enabled no)
			(sheetname "")
		)
		(fill
			(thermal_gap 0.5)
			(thermal_bridge_width 0.5)
			(island_removal_mode 0)
		)
		(polygon
			(pts
				(xy 495.176048 -21.789136) (xy 496.917218 -21.789136) (xy 497.058188 -21.648166) (xy 497.058188 -20.404074)
				(xy 496.90909 -20.254976) (xy 495.48288 -20.254976) (xy 495.051588 -20.686268) (xy 495.051588 -21.664676)
			)
		)
	)
	(zone
		(net "PVDDQ_GHJ")
		(layer "B.Cu")
		(hatch none 0.5)
		(connect_pads
			(clearance 0.5)
		)
		(min_thickness 0.25)
		(fill yes
			(thermal_gap 0.5)
			(thermal_bridge_width 0.5)
			(island_removal_mode 0)
		)
		(polygon
			(pts
				(xy 104.468168 -24.2316) (xy 104.214168 -24.4856) (xy 104.214168 -26.1874) (xy 103.909368 -26.4922)
				(xy 101.699568 -26.4922) (xy 101.343968 -26.1366) (xy 100.622862 -26.1366) (xy 100.428806 -26.330656)
				(xy 100.428806 -27.204416) (xy 102.064566 -28.840176) (xy 109.741208 -28.840176) (xy 109.89818 -28.997148)
				(xy 109.89818 -29.00172) (xy 110.46206 -29.5656) (xy 112.00892 -29.5656) (xy 112.2045 -29.37002)
				(xy 112.2045 -28.132532) (xy 112.062768 -27.9908) (xy 112.062768 -26.6192) (xy 112.418368 -26.2636)
				(xy 112.418368 -24.4348) (xy 112.215168 -24.2316) (xy 112.037368 -24.2316) (xy 111.910368 -24.3586)
				(xy 111.910368 -25.8064) (xy 111.757968 -25.9588) (xy 110.818168 -25.9588) (xy 110.691168 -25.8318)
				(xy 110.691168 -24.5364) (xy 110.538768 -24.384) (xy 110.310168 -24.384) (xy 110.233968 -24.4602)
				(xy 110.233968 -25.6794) (xy 109.418882 -26.494486) (xy 106.679746 -26.494486) (xy 106.449368 -26.264108)
				(xy 106.449368 -24.3586) (xy 106.347768 -24.257) (xy 106.119168 -24.257) (xy 105.941368 -24.4348)
				(xy 105.941368 -26.2128) (xy 105.611168 -26.543) (xy 104.925368 -26.543) (xy 104.722168 -26.3398)
				(xy 104.722168 -24.3586) (xy 104.595168 -24.2316)
			)
		)
		(polygon
			(pts
				(xy 111.4298 -28.28544) (xy 111.2266 -28.28544) (xy 111.2266 -28.48864) (xy 111.4298 -28.48864)
			)
		)
	)
	(zone
		(net "P12V_NVDIMM_GHJ")
		(layer "B.Cu")
		(hatch none 0.5)
		(connect_pads
			(clearance 0.5)
		)
		(min_thickness 0.25)
		(fill yes
			(thermal_gap 0.5)
			(thermal_bridge_width 0.5)
			(island_removal_mode 0)
		)
		(polygon
			(pts
				(xy 29.944568 -25.273) (xy 29.944568 0) (xy 29.944568 2.4384) (xy 29.385768 2.9972) (xy 27.7114 2.9972)
				(xy 27.6098 2.8956) (xy 27.6098 1.4859) (xy 27.3431 1.2192) (xy 26.032968 1.2192) (xy 25.728168 0.9144)
				(xy 25.728168 -13.0048) (xy 22.553168 -16.1798) (xy 22.553168 -17.7546) (xy 22.047708 -18.26006)
				(xy 22.047708 -20.1422) (xy 22.875748 -20.97024) (xy 24.71039 -20.97024) (xy 25.57907 -21.83892)
				(xy 25.57907 -21.840444) (xy 25.604978 -21.866352) (xy 25.604978 -26.256996) (xy 26.817828 -27.469846)
				(xy 29.614114 -27.469846) (xy 31.075376 -27.469846) (xy 31.260796 -27.284426) (xy 31.260796 -26.16454)
				(xy 31.186628 -26.090372) (xy 30.215078 -26.090372) (xy 29.944568 -25.819862)
			)
		)
	)
	(zone
		(layer "B.Cu")
		(hatch none 0.5)
		(connect_pads
			(clearance 0)
		)
		(min_thickness 0.25)
		(keepout
			(tracks not_allowed)
			(vias allowed)
			(pads allowed)
			(copperpour not_allowed)
			(footprints allowed)
		)
		(placement
			(enabled no)
			(sheetname "")
		)
		(fill
			(thermal_gap 0.5)
			(thermal_bridge_width 0.5)
			(island_removal_mode 0)
		)
		(polygon
			(pts
				(xy 465.628736 -114.38255) (xy 465.78393 -114.537744) (xy 465.78393 -114.83594) (xy 465.88553 -114.83594)
				(xy 465.88553 -114.537744) (xy 466.040724 -114.38255)
				(arc
					(start 466.212428 -114.38255)
					(mid 466.736345 -114.4524)
					(end 466.212428 -114.52225)
				)
				(xy 466.098636 -114.52225) (xy 466.02523 -114.595656) (xy 466.02523 -114.83594)
				(arc
					(start 466.46973 -114.83594)
					(mid 466.85327 -114.4524)
					(end 466.46973 -114.06886)
				)
				(arc
					(start 465.199984 -114.06886)
					(mid 464.81619 -114.452273)
					(end 465.19973 -114.83594)
				)
				(xy 465.64423 -114.83594) (xy 465.64423 -114.595656) (xy 465.570824 -114.52225)
				(arc
					(start 465.457032 -114.52225)
					(mid 464.933115 -114.4524)
					(end 465.457032 -114.38255)
				)
			)
		)
	)
	(zone
		(net "GND")
		(layer "B.Cu")
		(hatch none 0.5)
		(connect_pads
			(clearance 0.5)
		)
		(min_thickness 0.25)
		(fill yes
			(thermal_gap 0.5)
			(thermal_bridge_width 0.5)
			(island_removal_mode 0)
		)
		(polygon
			(pts
				(xy 187.452 -8.763) (xy 187.452 -8.394446) (xy 187.248546 -8.190992) (xy 185.384948 -8.190992) (xy 184.674764 -8.190992)
				(xy 184.42813 -8.437626) (xy 184.42813 -11.546332) (xy 184.438798 -11.557) (xy 184.914286 -11.557)
				(xy 187.452 -11.557) (xy 187.706 -11.303) (xy 187.706 -9.017)
			)
		)
	)
	(zone
		(layer "B.Cu")
		(hatch none 0.5)
		(connect_pads
			(clearance 0)
		)
		(min_thickness 0.25)
		(keepout
			(tracks not_allowed)
			(vias allowed)
			(pads allowed)
			(copperpour not_allowed)
			(footprints allowed)
		)
		(placement
			(enabled no)
			(sheetname "")
		)
		(fill
			(thermal_gap 0.5)
			(thermal_bridge_width 0.5)
			(island_removal_mode 0)
		)
		(polygon
			(pts
				(xy 387.350762 -29.899356) (xy 387.350762 -30.19298)
				(arc
					(start 387.601714 -30.443932)
					(mid 387.922879 -30.863903)
					(end 387.502908 -30.542738)
				)
				(xy 387.350762 -30.390592)
				(arc
					(start 387.350762 -30.675326)
					(mid 387.734302 -31.058866)
					(end 388.117842 -30.675326)
				)
				(arc
					(start 388.117842 -29.40558)
					(mid 387.734429 -29.02204)
					(end 387.350762 -29.405326)
				)
				(xy 387.350762 -29.701744) (xy 387.454902 -29.597604) (xy 387.454902 -29.58592)
				(arc
					(start 387.465824 -29.574998)
					(mid 387.95528 -29.17731)
					(end 387.571996 -29.678122)
				)
			)
		)
	)
	(zone
		(layer "B.Cu")
		(hatch none 0.5)
		(connect_pads
			(clearance 0)
		)
		(min_thickness 0.25)
		(keepout
			(tracks allowed)
			(vias allowed)
			(pads allowed)
			(copperpour allowed)
			(footprints not_allowed)
		)
		(placement
			(enabled no)
			(sheetname "")
		)
		(fill
			(thermal_gap 0.5)
			(thermal_bridge_width 0.5)
			(island_removal_mode 0)
		)
		(polygon
			(pts
				(arc
					(start 198.930006 -103.000048)
					(mid 195.379848 -106.550206)
					(end 198.930006 -110.10011)
				)
				(arc
					(start 198.930006 -110.10011)
					(mid 202.47991 -106.550206)
					(end 198.930006 -103.000048)
				)
			)
		)
	)
	(zone
		(layer "B.Cu")
		(hatch none 0.5)
		(connect_pads
			(clearance 0)
		)
		(min_thickness 0.25)
		(keepout
			(tracks allowed)
			(vias allowed)
			(pads allowed)
			(copperpour allowed)
			(footprints not_allowed)
		)
		(placement
			(enabled no)
			(sheetname "")
		)
		(fill
			(thermal_gap 0.5)
			(thermal_bridge_width 0.5)
			(island_removal_mode 0)
		)
		(polygon
			(pts
				(arc
					(start 222.039942 -67.55003)
					(mid 222.332835 -68.257135)
					(end 223.03994 -68.550028)
				)
				(arc
					(start 228.659944 -68.550028)
					(mid 229.367049 -68.257135)
					(end 229.659942 -67.55003)
				)
				(arc
					(start 229.659942 -60.41009)
					(mid 229.367049 -59.702985)
					(end 228.659944 -59.410092)
				)
				(arc
					(start 223.03994 -59.410092)
					(mid 222.332835 -59.702985)
					(end 222.039942 -60.41009)
				)
			)
		)
	)
	(zone
		(net "P1V05_PCH_STBY_WM26_PLL")
		(layer "B.Cu")
		(hatch none 0.5)
		(connect_pads
			(clearance 0.5)
		)
		(min_thickness 0.25)
		(fill yes
			(thermal_gap 0.5)
			(thermal_bridge_width 0.5)
			(island_removal_mode 0)
		)
		(polygon
			(pts
				(xy 407.875232 -118.952264) (xy 407.82113 -119.006112) (xy 407.599642 -119.2276) (xy 406.8064 -119.2276)
				(xy 406.348692 -119.685308) (xy 406.348692 -120.166892) (xy 405.765 -120.750584) (xy 405.765 -122.058684)
				(xy 406.083516 -122.3772) (xy 407.2128 -122.3772) (xy 407.3398 -122.2502) (xy 407.3398 -121.318274)
				(xy 407.61412 -121.043954) (xy 408.584146 -121.043954) (xy 408.6606 -120.9675) (xy 408.6606 -120.20804)
				(xy 408.9908 -119.87784) (xy 408.9908 -119.007382) (xy 408.935682 -118.952264)
			)
		)
		(polygon
			(pts
				(xy 408.1526 -119.734584) (xy 407.9494 -119.734584) (xy 407.9494 -119.937784) (xy 408.1526 -119.937784)
			)
		)
		(polygon
			(pts
				(xy 407.7589 -120.0023) (xy 407.5557 -120.0023) (xy 407.5557 -120.2055) (xy 407.7589 -120.2055)
			)
		)
	)
	(zone
		(net "GND")
		(layer "B.Cu")
		(hatch none 0.5)
		(connect_pads
			(clearance 0.5)
		)
		(min_thickness 0.25)
		(fill yes
			(thermal_gap 0.5)
			(thermal_bridge_width 0.5)
			(island_removal_mode 0)
		)
		(polygon
			(pts
				(xy 354.498402 -139.443206) (xy 353.845622 -140.095986) (xy 353.845622 -144.336262) (xy 353.845622 -145.616422)
				(xy 354.769928 -146.540728) (xy 354.77704 -146.540728) (xy 354.890832 -146.65452) (xy 358.833928 -146.65452)
				(xy 358.94772 -146.540728) (xy 361.235498 -146.540728) (xy 362.506768 -145.269458) (xy 365.610902 -145.269458)
				(xy 367.3094 -146.967956) (xy 367.3094 -151.608028) (xy 368.64798 -151.608028) (xy 369.334288 -150.92172)
				(xy 370.818918 -150.92172) (xy 371.31879 -151.421592) (xy 371.31879 -153.242772) (xy 371.884956 -153.808938)
				(xy 373.469662 -153.808938) (xy 373.7864 -153.4922) (xy 375.0183 -153.4922) (xy 375.34469 -153.16581)
				(xy 380.41707 -153.16581) (xy 380.83744 -152.74544) (xy 380.83744 -149.66696) (xy 381.3048 -149.1996)
				(xy 381.3048 -144.431004) (xy 380.649226 -143.77543) (xy 373.44477 -143.77543) (xy 373.443754 -143.776446)
				(xy 373.009414 -143.776446) (xy 372.663466 -144.122394) (xy 367.286794 -144.122394) (xy 366.882172 -143.717772)
				(xy 366.882172 -141.535404) (xy 365.993426 -140.646658) (xy 364.868714 -140.646658) (xy 364.857538 -140.657834)
				(xy 364.09249 -140.657834) (xy 362.877862 -139.443206)
			)
		)
	)
	(zone
		(net "GND")
		(layer "B.Cu")
		(hatch none 0.5)
		(connect_pads
			(clearance 0.5)
		)
		(min_thickness 0.25)
		(fill yes
			(thermal_gap 0.5)
			(thermal_bridge_width 0.5)
			(island_removal_mode 0)
		)
		(polygon
			(pts
				(xy 408.587956 -100.615242) (xy 408.837384 -100.365814) (xy 408.837384 -98.21926) (xy 408.757374 -98.13925)
				(xy 405.769318 -98.13925) (xy 405.68245 -98.226118) (xy 405.68245 -100.493068) (xy 405.804624 -100.615242)
			)
		)
	)
	(zone
		(net "PVPP_DEF")
		(layer "B.Cu")
		(hatch none 0.5)
		(connect_pads
			(clearance 0.5)
		)
		(min_thickness 0.25)
		(fill yes
			(thermal_gap 0.5)
			(thermal_bridge_width 0.5)
			(island_removal_mode 0)
		)
		(polygon
			(pts
				(xy 320.929 -123.19) (xy 319.8876 -124.2314) (xy 319.8876 -125.476) (xy 319.29832 -126.06528) (xy 318.35852 -126.06528)
				(xy 318.29248 -126.13132) (xy 318.29248 -126.52502) (xy 318.11214 -126.70536) (xy 317.56604 -126.70536)
				(xy 317.5 -126.7714) (xy 317.5 -130.6322) (xy 316.8142 -131.318) (xy 316.8142 -133.604) (xy 317.0174 -133.8072)
				(xy 318.0334 -133.8072) (xy 318.5922 -134.366) (xy 318.5922 -134.7216) (xy 318.1858 -135.128) (xy 318.1858 -135.8138)
				(xy 318.0842 -135.9154) (xy 317.373 -135.9154) (xy 316.8142 -136.4742) (xy 316.8142 -143.3068) (xy 317.0428 -143.5354)
				(xy 318.3128 -143.5354) (xy 318.389 -143.4592) (xy 318.4652 -143.4592) (xy 318.5922 -143.5862) (xy 318.5922 -144.0434)
				(xy 318.1731 -144.4625) (xy 318.1731 -145.5039) (xy 318.0842 -145.5928) (xy 317.0936 -145.5928)
				(xy 316.8142 -145.8722) (xy 316.8142 -152.7556) (xy 315.722 -153.8478) (xy 315.722 -157.3276) (xy 316.2808 -157.8864)
				(xy 325.1708 -157.8864) (xy 325.9836 -157.0736) (xy 325.9836 -138.7348) (xy 326.4408 -138.2776)
				(xy 329.057 -138.2776) (xy 330.4286 -136.906) (xy 333.2734 -136.906) (xy 333.7306 -136.4488) (xy 333.7306 -132.842)
				(xy 334.8482 -131.7244) (xy 334.8482 -127.9906) (xy 334.3656 -127.508) (xy 328.67346 -127.508) (xy 325.87438 -124.70892)
				(xy 322.46062 -124.70892) (xy 322.199 -124.4473) (xy 322.199 -123.2916) (xy 322.0974 -123.19)
			)
		)
		(polygon
			(pts
				(xy 319.9511 -155.0924) (xy 319.7479 -155.0924) (xy 319.7479 -155.2956) (xy 319.9511 -155.2956)
			)
		)
		(polygon
			(pts
				(xy 319.9511 -154.3304) (xy 319.7479 -154.3304) (xy 319.7479 -154.5336) (xy 319.9511 -154.5336)
			)
		)
		(polygon
			(pts
				(xy 319.030096 -154.319224) (xy 318.826896 -154.319224) (xy 318.826896 -154.522424) (xy 319.030096 -154.522424)
			)
		)
		(polygon
			(pts
				(xy 319.851532 -145.3134) (xy 319.648332 -145.3134) (xy 319.648332 -145.5166) (xy 319.851532 -145.5166)
			)
		)
		(polygon
			(pts
				(xy 319.851532 -144.5514) (xy 319.648332 -144.5514) (xy 319.648332 -144.7546) (xy 319.851532 -144.7546)
			)
		)
		(polygon
			(pts
				(xy 319.089532 -144.5514) (xy 318.886332 -144.5514) (xy 318.886332 -144.7546) (xy 319.089532 -144.7546)
			)
		)
		(polygon
			(pts
				(xy 322.0974 -144.4498) (xy 320.802 -144.4498) (xy 320.7258 -144.526) (xy 320.7258 -145.3642) (xy 320.8782 -145.5166)
				(xy 322.43014 -145.5166) (xy 322.43014 -144.78254)
			)
		)
		(polygon
			(pts
				(xy 319.851532 -135.6614) (xy 319.648332 -135.6614) (xy 319.648332 -135.8646) (xy 319.851532 -135.8646)
			)
		)
		(polygon
			(pts
				(xy 319.089532 -135.6614) (xy 318.886332 -135.6614) (xy 318.886332 -135.8646) (xy 319.089532 -135.8646)
			)
		)
		(polygon
			(pts
				(xy 319.851532 -134.8994) (xy 319.648332 -134.8994) (xy 319.648332 -135.1026) (xy 319.851532 -135.1026)
			)
		)
		(polygon
			(pts
				(xy 319.089532 -134.8994) (xy 318.886332 -134.8994) (xy 318.886332 -135.1026) (xy 319.089532 -135.1026)
			)
		)
		(polygon
			(pts
				(xy 321.5894 -123.759722) (xy 321.3862 -123.759722) (xy 321.3862 -123.962922) (xy 321.5894 -123.962922)
			)
		)
		(polygon
			(pts
				(xy 321.0814 -123.759722) (xy 320.8782 -123.759722) (xy 320.8782 -123.962922) (xy 321.0814 -123.962922)
			)
		)
	)
	(zone
		(layer "B.Cu")
		(hatch none 0.5)
		(connect_pads
			(clearance 0)
		)
		(min_thickness 0.25)
		(keepout
			(tracks not_allowed)
			(vias allowed)
			(pads allowed)
			(copperpour not_allowed)
			(footprints allowed)
		)
		(placement
			(enabled no)
			(sheetname "")
		)
		(fill
			(thermal_gap 0.5)
			(thermal_bridge_width 0.5)
			(island_removal_mode 0)
		)
		(polygon
			(pts
				(arc
					(start 395.560804 -34.09569)
					(mid 395.524573 -34.045595)
					(end 395.50086 -33.988502)
				)
				(xy 395.50086 -34.155634)
			)
		)
	)
	(zone
		(net "GND")
		(layer "B.Cu")
		(hatch none 0.5)
		(connect_pads
			(clearance 0.5)
		)
		(min_thickness 0.25)
		(fill yes
			(thermal_gap 0.5)
			(thermal_bridge_width 0.5)
			(island_removal_mode 0)
		)
		(polygon
			(pts
				(xy 407.61031 -92.913454) (xy 407.61031 -94.851728) (xy 407.64841 -94.889828) (xy 409.120086 -94.889828)
				(xy 409.155646 -94.854268) (xy 409.155646 -94.47149) (xy 408.624532 -93.940376) (xy 408.624532 -92.967302)
				(xy 408.525218 -92.867988) (xy 407.655776 -92.867988)
			)
		)
	)
	(zone
		(net "PVCCIOMCP_CPU0")
		(layer "B.Cu")
		(hatch none 0.5)
		(connect_pads
			(clearance 0.5)
		)
		(min_thickness 0.25)
		(fill yes
			(thermal_gap 0.5)
			(thermal_bridge_width 0.5)
			(island_removal_mode 0)
		)
		(polygon
			(pts
				(xy 346.59189 -107.861862) (xy 350.901 -107.861862) (xy 351.268538 -108.2294) (xy 353.242118 -108.2294)
				(xy 353.441 -108.428282) (xy 353.441 -110.96498) (xy 352.90506 -111.50092) (xy 351.3201 -111.50092)
				(xy 350.91116 -111.90986) (xy 350.91116 -112.52454) (xy 350.6089 -112.8268) (xy 350.28378 -112.8268)
				(xy 349.97898 -113.1316) (xy 345.7956 -113.1316) (xy 345.6178 -112.9538) (xy 345.6178 -108.1532)
				(xy 345.909138 -107.861862)
			)
		)
	)
	(zone
		(layer "B.Cu")
		(hatch none 0.5)
		(connect_pads
			(clearance 0)
		)
		(min_thickness 0.25)
		(keepout
			(tracks allowed)
			(vias allowed)
			(pads allowed)
			(copperpour allowed)
			(footprints allowed)
		)
		(placement
			(enabled no)
			(sheetname "")
		)
		(fill
			(thermal_gap 0.5)
			(thermal_bridge_width 0.5)
			(island_removal_mode 0)
		)
		(polygon
			(pts
				(xy 183.769 -104.902) (xy 183.769 -124.46) (xy 194.437 -126.746) (xy 207.518 -126.873) (xy 207.518 -107.823)
				(xy 203.962 -108.204)
			)
		)
	)
	(zone
		(layer "B.Cu")
		(hatch none 0.5)
		(connect_pads
			(clearance 0)
		)
		(min_thickness 0.25)
		(keepout
			(tracks allowed)
			(vias allowed)
			(pads allowed)
			(copperpour allowed)
			(footprints not_allowed)
		)
		(placement
			(enabled no)
			(sheetname "")
		)
		(fill
			(thermal_gap 0.5)
			(thermal_bridge_width 0.5)
			(island_removal_mode 0)
		)
		(polygon
			(pts
				(xy 18.720054 -127.359918) (xy 18.720054 -159.090106) (xy 22.519894 -159.090106) (xy 22.519894 -127.359918)
			)
		)
	)
	(zone
		(net "PVCCIN_CPU0")
		(layer "B.Cu")
		(hatch none 0.5)
		(connect_pads
			(clearance 0.5)
		)
		(min_thickness 0.25)
		(fill yes
			(thermal_gap 0.5)
			(thermal_bridge_width 0.5)
			(island_removal_mode 0)
		)
		(polygon
			(pts
				(xy 229.744016 -77.556614) (xy 234.137454 -77.556614) (xy 238.294672 -80.096614) (xy 244.921024 -80.096614)
				(xy 244.921024 -80.071214) (xy 246.038624 -78.953614) (xy 251.155962 -78.953614) (xy 252.072648 -79.8703)
				(xy 253.00432 -79.8703) (xy 253.256034 -80.122014) (xy 254.635762 -80.122014) (xy 255.109726 -79.64805)
				(xy 256.82575 -79.64805) (xy 257.7084 -78.7654) (xy 257.967988 -78.7654) (xy 258.196588 -78.994)
				(xy 261.7216 -78.994) (xy 261.7978 -79.0702) (xy 261.7978 -79.893414) (xy 262.001 -80.096614) (xy 268.750542 -80.096614)
				(xy 268.82725 -80.019906) (xy 268.82725 -78.653132) (xy 268.569694 -78.395576) (xy 268.569694 -77.41158)
				(xy 268.460728 -77.302614) (xy 257.748024 -77.302614) (xy 257.6576 -77.21219) (xy 257.6576 -74.7268)
				(xy 257.7084 -74.676) (xy 268.598396 -74.676) (xy 268.684756 -74.58964) (xy 268.684756 -74.267314)
				(xy 268.51737 -74.099928) (xy 268.51737 -73.155556) (xy 268.346428 -72.984614) (xy 257.837686 -72.984614)
				(xy 257.653536 -72.800464) (xy 257.653536 -70.7263) (xy 258.250436 -70.1294) (xy 260.7056 -70.1294)
				(xy 261.122922 -69.712078) (xy 261.122922 -68.442078) (xy 261.459472 -68.105528) (xy 263.309862 -68.105528)
				(xy 263.534652 -67.880738) (xy 263.534652 -66.944748) (xy 263.8552 -66.6242) (xy 274.20951 -66.6242)
				(xy 274.520914 -66.935604) (xy 274.520914 -68.608702) (xy 274.578826 -68.666614) (xy 276.100032 -68.666614)
				(xy 276.608032 -68.158614) (xy 280.735024 -68.158614) (xy 280.862024 -68.031614) (xy 280.862024 -67.523614)
				(xy 279.719024 -67.015614) (xy 278.068024 -66.126614) (xy 273.877024 -63.586614) (xy 271.967198 -63.586614)
				(xy 271.245584 -62.865) (xy 261.3152 -62.865) (xy 260.339586 -63.840614) (xy 256.06502 -63.840614)
				(xy 249.84202 -70.063614) (xy 236.412024 -70.063614) (xy 236.031024 -69.682614) (xy 231.760014 -69.682614)
				(xy 227.7618 -65.6844) (xy 227.7618 -60.4012) (xy 220.1926 -52.832) (xy 209.1182 -52.832) (xy 208.575402 -53.374798)
				(xy 208.575402 -92.246958) (xy 208.598008 -92.269564) (xy 208.598008 -92.438982) (xy 208.722722 -92.563696)
				(xy 212.896704 -92.563696) (xy 213.8426 -91.6178) (xy 215.6968 -91.6178) (xy 216.1794 -91.1352)
				(xy 216.1794 -91.133676) (xy 229.744016 -77.56906)
			)
		)
		(polygon
			(pts
				(xy 214.9856 -86.7664) (xy 214.7824 -86.7664) (xy 214.7824 -86.9696) (xy 214.9856 -86.9696)
			)
		)
		(polygon
			(pts
				(xy 214.2236 -86.7664) (xy 214.0204 -86.7664) (xy 214.0204 -86.9696) (xy 214.2236 -86.9696)
			)
		)
		(polygon
			(pts
				(xy 214.9856 -78.7527) (xy 214.7824 -78.7527) (xy 214.7824 -78.9559) (xy 214.9856 -78.9559)
			)
		)
		(polygon
			(pts
				(xy 214.2236 -78.7527) (xy 214.0204 -78.7527) (xy 214.0204 -78.9559) (xy 214.2236 -78.9559)
			)
		)
		(polygon
			(pts
				(xy 214.9856 -70.7009) (xy 214.7824 -70.7009) (xy 214.7824 -70.9041) (xy 214.9856 -70.9041)
			)
		)
		(polygon
			(pts
				(xy 214.2236 -70.7009) (xy 214.0204 -70.7009) (xy 214.0204 -70.9041) (xy 214.2236 -70.9041)
			)
		)
	)
	(zone
		(layer "B.Cu")
		(hatch none 0.5)
		(connect_pads
			(clearance 0)
		)
		(min_thickness 0.25)
		(keepout
			(tracks allowed)
			(vias allowed)
			(pads allowed)
			(copperpour allowed)
			(footprints not_allowed)
		)
		(placement
			(enabled no)
			(sheetname "")
		)
		(fill
			(thermal_gap 0.5)
			(thermal_bridge_width 0.5)
			(island_removal_mode 0)
		)
		(polygon
			(pts
				(xy 187.520072 -159.097472) (xy 187.520072 -152.987502) (xy 328.520044 -152.987502) (xy 328.520044 -159.097472)
			)
		)
	)
	(zone
		(net "GND")
		(layer "B.Cu")
		(hatch none 0.5)
		(connect_pads
			(clearance 0.5)
		)
		(min_thickness 0.25)
		(fill yes
			(thermal_gap 0.5)
			(thermal_bridge_width 0.5)
			(island_removal_mode 0)
		)
		(polygon
			(pts
				(xy 77.17409 -19.108928) (xy 78.112366 -19.108928) (xy 78.40472 -18.81632) (xy 78.40472 -17.15008)
				(xy 78.442312 -17.112488) (xy 78.442312 -16.740632) (xy 78.086458 -16.384778) (xy 77.199744 -16.384778)
				(xy 77.112622 -16.384778) (xy 76.2 -17.2974) (xy 76.2 -18.8722) (xy 76.428092 -19.100292) (xy 77.165708 -19.100292)
			)
		)
	)
	(zone
		(layer "B.Cu")
		(hatch none 0.5)
		(connect_pads
			(clearance 0)
		)
		(min_thickness 0.25)
		(keepout
			(tracks allowed)
			(vias allowed)
			(pads allowed)
			(copperpour allowed)
			(footprints not_allowed)
		)
		(placement
			(enabled no)
			(sheetname "")
		)
		(fill
			(thermal_gap 0.5)
			(thermal_bridge_width 0.5)
			(island_removal_mode 0)
		)
		(polygon
			(pts
				(arc
					(start 127 -39.010082)
					(mid 124.46 -41.550082)
					(end 127 -44.090082)
				)
				(arc
					(start 127 -44.090082)
					(mid 129.54 -41.550082)
					(end 127 -39.010082)
				)
			)
		)
	)
	(zone
		(net "GND")
		(layer "B.Cu")
		(hatch none 0.5)
		(connect_pads
			(clearance 0.5)
		)
		(min_thickness 0.25)
		(fill yes
			(thermal_gap 0.5)
			(thermal_bridge_width 0.5)
			(island_removal_mode 0)
		)
		(polygon
			(pts
				(xy 176.276 -16.002) (xy 176.53 -15.748) (xy 179.705 -15.748) (xy 179.959 -15.748) (xy 180.086 -15.621)
				(xy 180.086 -15.367) (xy 180.086 -13.589) (xy 180.213 -13.462) (xy 181.483 -13.462) (xy 181.60873 -13.33627)
				(xy 182.209694 -13.33627) (xy 182.321962 -13.448538) (xy 182.321962 -14.554708) (xy 182.626254 -14.859)
				(xy 184.023 -14.859) (xy 184.785 -15.621) (xy 184.785 -17.1196) (xy 184.3278 -17.5768) (xy 183.896 -18.0086)
				(xy 182.8546 -18.0086) (xy 182.3466 -18.5166) (xy 182.3466 -19.2024) (xy 181.991 -19.558) (xy 176.022 -19.558)
				(xy 175.895 -19.431) (xy 175.895 -18.288) (xy 176.276 -17.907)
			)
		)
	)
	(zone
		(layer "B.Cu")
		(hatch none 0.5)
		(connect_pads
			(clearance 0)
		)
		(min_thickness 0.25)
		(keepout
			(tracks allowed)
			(vias allowed)
			(pads allowed)
			(copperpour allowed)
			(footprints not_allowed)
		)
		(placement
			(enabled no)
			(sheetname "")
		)
		(fill
			(thermal_gap 0.5)
			(thermal_bridge_width 0.5)
			(island_removal_mode 0)
		)
		(polygon
			(pts
				(arc
					(start 495.020092 -26.919936)
					(mid 491.419896 -30.520132)
					(end 495.020092 -34.120074)
				)
				(arc
					(start 498.020086 -34.120074)
					(mid 501.759536 -30.520137)
					(end 498.020086 -26.919936)
				)
			)
		)
	)
	(zone
		(net "P3V3")
		(layer "B.Cu")
		(hatch none 0.5)
		(connect_pads
			(clearance 0.5)
		)
		(min_thickness 0.25)
		(fill yes
			(thermal_gap 0.5)
			(thermal_bridge_width 0.5)
			(island_removal_mode 0)
		)
		(polygon
			(pts
				(xy 390.421368 -26.0858) (xy 390.375902 -26.040334) (xy 390.375902 -21.602954) (xy 390.406636 -21.57222)
				(xy 391.424922 -21.57222) (xy 391.7442 -21.57222) (xy 391.89406 -21.72208) (xy 391.89406 -22.906228)
				(xy 391.846562 -22.953726) (xy 391.846562 -23.620476) (xy 391.925302 -23.699216) (xy 391.925302 -25.396698)
				(xy 391.2362 -26.0858)
			)
		)
	)
	(zone
		(net "PVCCMCP_CPU1")
		(layer "B.Cu")
		(hatch none 0.5)
		(connect_pads
			(clearance 0.5)
		)
		(min_thickness 0.25)
		(fill yes
			(thermal_gap 0.5)
			(thermal_bridge_width 0.5)
			(island_removal_mode 0)
		)
		(polygon
			(pts
				(xy 109.598968 -74.7014) (xy 112.672368 -74.7014) (xy 112.850168 -74.5236) (xy 112.850168 -73.3298)
				(xy 112.494568 -72.9742) (xy 109.294168 -72.9742) (xy 105.941368 -72.9742) (xy 103.960168 -72.9742)
				(xy 103.909368 -73.025) (xy 103.909368 -74.2442) (xy 104.341168 -74.676) (xy 106.017568 -74.676)
				(xy 109.573568 -74.676)
			)
		)
	)
	(zone
		(net "PVDDQ_GHJ")
		(layer "B.Cu")
		(hatch none 0.5)
		(connect_pads
			(clearance 0.5)
		)
		(min_thickness 0.25)
		(fill yes
			(thermal_gap 0.5)
			(thermal_bridge_width 0.5)
			(island_removal_mode 0)
		)
		(polygon
			(pts
				(xy 168.2496 -0.5334) (xy 168.0972 -0.6858) (xy 168.0972 -2.3114) (xy 166.8526 -3.556) (xy 166.8526 -3.9624)
				(xy 165.78834 -5.02666) (xy 165.78834 -5.90042) (xy 166.00932 -6.1214) (xy 166.82466 -6.1214) (xy 166.97706 -5.969)
				(xy 166.97706 -5.60578) (xy 167.24884 -5.334) (xy 169.164 -5.334) (xy 169.469816 -5.028184) (xy 169.469816 -1.067816)
				(xy 168.9354 -0.5334)
			)
		)
		(polygon
			(pts
				(xy 168.6941 -4.9784) (xy 168.4909 -4.9784) (xy 168.4909 -5.1816) (xy 168.6941 -5.1816)
			)
		)
		(polygon
			(pts
				(xy 168.6941 -4.2164) (xy 168.4909 -4.2164) (xy 168.4909 -4.4196) (xy 168.6941 -4.4196)
			)
		)
		(polygon
			(pts
				(xy 168.6941 -3.7338) (xy 168.4909 -3.7338) (xy 168.4909 -3.937) (xy 168.6941 -3.937)
			)
		)
		(polygon
			(pts
				(xy 168.6941 -2.9718) (xy 168.4909 -2.9718) (xy 168.4909 -3.175) (xy 168.6941 -3.175)
			)
		)
	)
	(zone
		(layer "B.Cu")
		(hatch none 0.5)
		(connect_pads
			(clearance 0)
		)
		(min_thickness 0.25)
		(keepout
			(tracks not_allowed)
			(vias allowed)
			(pads allowed)
			(copperpour not_allowed)
			(footprints allowed)
		)
		(placement
			(enabled no)
			(sheetname "")
		)
		(fill
			(thermal_gap 0.5)
			(thermal_bridge_width 0.5)
			(island_removal_mode 0)
		)
		(polygon
			(pts
				(arc
					(start 2.830068 0)
					(mid 0 2.830068)
					(end -2.830068 0)
				)
				(arc
					(start -2.830068 0)
					(mid 0 -2.830068)
					(end 2.830068 0)
				)
			)
		)
	)
	(zone
		(net "GND")
		(layer "B.Cu")
		(hatch none 0.5)
		(connect_pads
			(clearance 0.5)
		)
		(min_thickness 0.25)
		(fill yes
			(thermal_gap 0.5)
			(thermal_bridge_width 0.5)
			(island_removal_mode 0)
		)
		(polygon
			(pts
				(xy -4.1148 -112.649) (xy -3.937 -112.4712) (xy -2.2606 -112.4712) (xy -1.9558 -112.776) (xy -1.9558 -113.905792)
				(xy -1.9558 -114.148616) (xy -1.9558 -114.4524) (xy -2.0574 -114.554) (xy -2.259584 -114.554) (xy -2.335784 -114.6302)
				(xy -2.335784 -115.287806) (xy -2.335784 -115.822984) (xy -2.335784 -115.949984) (xy -2.3876 -116.0018)
				(xy -3.501644 -116.0018) (xy -4.1148 -115.388644)
			)
		)
	)
	(zone
		(net "GND")
		(layer "B.Cu")
		(hatch none 0.5)
		(connect_pads
			(clearance 0.5)
		)
		(min_thickness 0.25)
		(fill yes
			(thermal_gap 0.5)
			(thermal_bridge_width 0.5)
			(island_removal_mode 0)
		)
		(polygon
			(pts
				(xy 355.6 -27.2034) (xy 356.0826 -27.686) (xy 356.0826 -27.7368) (xy 356.0826 -28.1686) (xy 356.2604 -28.3464)
				(xy 358.6226 -28.3464) (xy 358.902 -28.067) (xy 358.902 -25.1714) (xy 358.2416 -24.511) (xy 356.237032 -24.511)
				(xy 354.009452 -22.28342) (xy 353.997768 -22.28342) (xy 353.872038 -22.15769) (xy 352.69424 -22.15769)
				(xy 352.681032 -22.170898) (xy 352.681032 -22.343872) (xy 352.681032 -26.991564) (xy 352.685096 -26.9875)
				(xy 355.3841 -26.9875)
			)
		)
	)
	(zone
		(layer "B.Cu")
		(hatch none 0.5)
		(connect_pads
			(clearance 0)
		)
		(min_thickness 0.25)
		(keepout
			(tracks not_allowed)
			(vias allowed)
			(pads allowed)
			(copperpour not_allowed)
			(footprints allowed)
		)
		(placement
			(enabled no)
			(sheetname "")
		)
		(fill
			(thermal_gap 0.5)
			(thermal_bridge_width 0.5)
			(island_removal_mode 0)
		)
		(polygon
			(pts
				(arc
					(start 407.766266 -153.5303)
					(mid 407.382726 -153.14676)
					(end 406.999186 -153.5303)
				)
				(arc
					(start 406.999186 -154.546046)
					(mid 407.382599 -154.92984)
					(end 407.766266 -154.5463)
				)
				(arc
					(start 407.766266 -154.254708)
					(mid 407.692837 -154.235302)
					(end 407.617168 -154.2288)
				)
				(arc
					(start 407.497026 -154.2288)
					(mid 407.465595 -154.241819)
					(end 407.452576 -154.27325)
				)
				(arc
					(start 407.452576 -154.288998)
					(mid 407.382726 -154.812915)
					(end 407.312876 -154.288998)
				)
				(xy 407.312876 -154.244294)
				(arc
					(start 407.31567 -154.2415)
					(mid 407.366838 -154.143062)
					(end 407.465276 -154.091894)
				)
				(xy 407.46807 -154.0891) (xy 407.766266 -154.0891) (xy 407.766266 -153.9875) (xy 407.46807 -153.9875)
				(arc
					(start 407.465276 -153.984706)
					(mid 407.366838 -153.933538)
					(end 407.31567 -153.8351)
				)
				(xy 407.312876 -153.832306)
				(arc
					(start 407.312876 -153.787602)
					(mid 407.382726 -153.263685)
					(end 407.452576 -153.787602)
				)
				(arc
					(start 407.452576 -153.80335)
					(mid 407.465595 -153.834781)
					(end 407.497026 -153.8478)
				)
				(arc
					(start 407.617168 -153.8478)
					(mid 407.692831 -153.841267)
					(end 407.766266 -153.821892)
				)
			)
		)
	)
	(zone
		(net "P1V05_PCH_STBY")
		(layer "B.Cu")
		(hatch none 0.5)
		(connect_pads
			(clearance 0.5)
		)
		(min_thickness 0.25)
		(fill yes
			(thermal_gap 0.5)
			(thermal_bridge_width 0.5)
			(island_removal_mode 0)
		)
		(polygon
			(pts
				(xy 370.51869 -131.710176) (xy 371.44452 -131.710176) (xy 371.600984 -131.553966) (xy 372.587774 -131.553966)
				(xy 372.67896 -131.46278) (xy 372.67896 -131.14274) (xy 373.30126 -130.52044) (xy 373.30126 -129.16408)
				(xy 373.6721 -128.79324) (xy 374.396 -128.79324) (xy 374.7389 -129.13614) (xy 374.7389 -130.4417)
				(xy 374.8659 -130.5687) (xy 375.59996 -130.5687) (xy 375.98096 -130.9497) (xy 375.98096 -131.771136)
				(xy 376.104912 -131.895088) (xy 377.279662 -131.895088) (xy 377.294648 -131.879848) (xy 377.294648 -132.057648)
				(xy 377.8504 -132.6134) (xy 379.8316 -132.6134) (xy 380.002796 -132.442204) (xy 383.142998 -132.442204)
				(xy 383.669794 -132.969) (xy 384.969004 -132.969) (xy 385.906264 -133.90626) (xy 385.906264 -138.687556)
				(xy 385.50342 -139.0904) (xy 384.3528 -139.0904) (xy 384.048 -139.3952) (xy 384.048 -142.7734) (xy 384.45948 -143.18488)
				(xy 390.106408 -143.18488) (xy 390.41705 -143.495522) (xy 390.41705 -144.66824) (xy 390.56183 -144.81302)
				(xy 393.59078 -144.81302) (xy 393.8778 -144.526) (xy 393.8778 -143.24584) (xy 395.44498 -141.67866)
				(xy 400.68246 -141.67866) (xy 400.82724 -141.53388) (xy 400.82216 -141.5288) (xy 400.82216 -140.74648)
				(xy 396.6337 -136.55802) (xy 395.185646 -136.55802) (xy 391.082022 -132.454396) (xy 387.883908 -132.454396)
				(xy 383.63398 -128.204468) (xy 373.35841 -128.204468) (xy 372.3005 -129.262378) (xy 372.3005 -129.5908)
				(xy 371.267736 -130.623564) (xy 370.535454 -130.623564) (xy 370.38407 -130.774948) (xy 370.38407 -131.575556)
			)
		)
		(polygon
			(pts
				(xy 399.664936 -140.680186) (xy 399.461736 -140.680186) (xy 399.461736 -140.883386) (xy 399.664936 -140.883386)
			)
		)
		(polygon
			(pts
				(xy 398.902936 -140.680186) (xy 398.699736 -140.680186) (xy 398.699736 -140.883386) (xy 398.902936 -140.883386)
			)
		)
		(polygon
			(pts
				(xy 400.15668 -140.6779) (xy 399.95348 -140.6779) (xy 399.95348 -140.8811) (xy 400.15668 -140.8811)
			)
		)
		(polygon
			(pts
				(xy 372.7069 -130.5179) (xy 372.5037 -130.5179) (xy 372.5037 -130.7211) (xy 372.7069 -130.7211)
			)
		)
		(polygon
			(pts
				(xy 371.7671 -130.5179) (xy 371.5639 -130.5179) (xy 371.5639 -130.7211) (xy 371.7671 -130.7211)
			)
		)
	)
	(zone
		(net "P3V3")
		(layer "B.Cu")
		(hatch none 0.5)
		(connect_pads
			(clearance 0.5)
		)
		(min_thickness 0.25)
		(fill yes
			(thermal_gap 0.5)
			(thermal_bridge_width 0.5)
			(island_removal_mode 0)
		)
		(polygon
			(pts
				(xy 390.55167 -40.100504) (xy 390.988804 -40.100504) (xy 391.665206 -40.100504) (xy 391.978388 -39.787322)
				(xy 391.978388 -38.986714) (xy 391.304018 -38.312344) (xy 391.304018 -36.321238) (xy 391.105644 -36.122864)
				(xy 390.652 -36.122864) (xy 390.465056 -36.309808) (xy 390.465056 -40.014144)
			)
		)
	)
	(zone
		(layer "B.Cu")
		(hatch none 0.5)
		(connect_pads
			(clearance 0)
		)
		(min_thickness 0.25)
		(keepout
			(tracks allowed)
			(vias allowed)
			(pads allowed)
			(copperpour allowed)
			(footprints allowed)
		)
		(placement
			(enabled no)
			(sheetname "")
		)
		(fill
			(thermal_gap 0.5)
			(thermal_bridge_width 0.5)
			(island_removal_mode 0)
		)
		(polygon
			(pts
				(xy 310.261 -85.852) (xy 310.261 -85.09) (xy 311.023 -85.09) (xy 311.023 -85.852)
			)
		)
	)
	(zone
		(net "GND")
		(layer "B.Cu")
		(hatch none 0.5)
		(connect_pads
			(clearance 0.5)
		)
		(min_thickness 0.25)
		(fill yes
			(thermal_gap 0.5)
			(thermal_bridge_width 0.5)
			(island_removal_mode 0)
		)
		(polygon
			(pts
				(xy 383.5908 -133.35) (xy 383.54 -133.4008) (xy 383.54 -134.1882) (xy 383.286 -134.4422) (xy 378.9934 -134.4422)
				(xy 378.714 -134.7216) (xy 378.714 -136.271) (xy 379.0188 -136.5758) (xy 385.206494 -136.5758) (xy 385.564126 -136.218168)
				(xy 385.564126 -133.970522) (xy 384.943604 -133.35)
			)
		)
		(polygon
			(pts
				(xy 385.191 -135.5979) (xy 384.9878 -135.5979) (xy 384.9878 -135.8011) (xy 385.191 -135.8011)
			)
		)
		(polygon
			(pts
				(xy 384.429 -135.5979) (xy 384.2258 -135.5979) (xy 384.2258 -135.8011) (xy 384.429 -135.8011)
			)
		)
		(polygon
			(pts
				(xy 383.921 -135.5979) (xy 383.7178 -135.5979) (xy 383.7178 -135.8011) (xy 383.921 -135.8011)
			)
		)
		(polygon
			(pts
				(xy 383.159 -135.5979) (xy 382.9558 -135.5979) (xy 382.9558 -135.8011) (xy 383.159 -135.8011)
			)
		)
		(polygon
			(pts
				(xy 382.5748 -135.5979) (xy 382.3716 -135.5979) (xy 382.3716 -135.8011) (xy 382.5748 -135.8011)
			)
		)
		(polygon
			(pts
				(xy 381.8128 -135.5979) (xy 381.6096 -135.5979) (xy 381.6096 -135.8011) (xy 381.8128 -135.8011)
			)
		)
		(polygon
			(pts
				(xy 381.3302 -135.5979) (xy 381.127 -135.5979) (xy 381.127 -135.8011) (xy 381.3302 -135.8011)
			)
		)
		(polygon
			(pts
				(xy 380.5682 -135.5979) (xy 380.365 -135.5979) (xy 380.365 -135.8011) (xy 380.5682 -135.8011)
			)
		)
	)
	(zone
		(layer "B.Cu")
		(hatch none 0.5)
		(connect_pads
			(clearance 0)
		)
		(min_thickness 0.25)
		(keepout
			(tracks allowed)
			(vias allowed)
			(pads allowed)
			(copperpour allowed)
			(footprints not_allowed)
		)
		(placement
			(enabled no)
			(sheetname "")
		)
		(fill
			(thermal_gap 0.5)
			(thermal_bridge_width 0.5)
			(island_removal_mode 0)
		)
		(polygon
			(pts
				(arc
					(start 360.499914 -159.100012)
					(mid 364.499906 -155.10002)
					(end 360.499914 -151.100028)
				)
				(arc
					(start 357.000048 -151.100028)
					(mid 353.000056 -155.10002)
					(end 357.000048 -159.100012)
				)
			)
		)
	)
	(zone
		(net "P3V3")
		(layer "B.Cu")
		(hatch none 0.5)
		(connect_pads
			(clearance 0.5)
		)
		(min_thickness 0.25)
		(fill yes
			(thermal_gap 0.5)
			(thermal_bridge_width 0.5)
			(island_removal_mode 0)
		)
		(polygon
			(pts
				(xy 176.1998 -80.05064) (xy 176.1998 -78.994) (xy 176.4538 -78.74) (xy 178.308 -78.74) (xy 178.8414 -79.2734)
				(xy 178.8414 -80.8482) (xy 179.1208 -81.1276) (xy 179.8828 -81.1276) (xy 179.9209 -81.1657) (xy 180.7337 -81.1657)
				(xy 181.4068 -81.8388) (xy 181.4068 -83.058) (xy 180.4162 -84.0486) (xy 179.6542 -84.0486) (xy 178.2572 -84.0486)
				(xy 177.544984 -83.336384) (xy 177.544984 -80.582008) (xy 177.43678 -80.473804) (xy 177.168302 -80.205326)
				(xy 176.354486 -80.205326)
			)
		)
	)
	(zone
		(net "VR_FET_SW_P12V_STBY_PVDDQ_DEF")
		(layer "B.Cu")
		(hatch none 0.5)
		(connect_pads
			(clearance 0.5)
		)
		(min_thickness 0.25)
		(fill yes
			(thermal_gap 0.5)
			(thermal_bridge_width 0.5)
			(island_removal_mode 0)
		)
		(polygon
			(pts
				(xy 348.0943 -141.4145) (xy 348.0943 -146.2405) (xy 348.0943 -147.09648) (xy 348.31782 -147.32)
				(xy 348.488 -147.32) (xy 349.25 -147.32) (xy 349.604584 -147.32) (xy 349.644716 -147.360132) (xy 349.644716 -147.834604)
				(xy 350.055942 -148.24583) (xy 350.572578 -148.762466) (xy 350.572578 -149.601936) (xy 350.31045 -149.864064)
				(xy 349.677228 -149.864064) (xy 349.390208 -149.577044) (xy 348.694248 -149.577044) (xy 348.587822 -149.68347)
				(xy 348.55785 -149.68347) (xy 348.08033 -149.68347) (xy 347.98 -149.7838) (xy 347.98 -153.9748)
				(xy 347.98 -154.5082) (xy 348.0816 -154.6098) (xy 348.996 -154.6098) (xy 349.0976 -154.5082) (xy 349.0976 -153.25598)
				(xy 349.2881 -153.06548) (xy 350.88576 -153.06548) (xy 351.30486 -152.64638) (xy 352.8822 -152.64638)
				(xy 355.10978 -150.4188) (xy 355.38918 -150.4188) (xy 362.4834 -150.4188) (xy 365.22914 -153.16454)
				(xy 365.22914 -153.332942) (xy 365.22914 -154.758644) (xy 365.22914 -155.584652) (xy 365.473742 -155.829254)
				(xy 371.56517 -155.829254) (xy 371.636036 -155.758388) (xy 371.636036 -155.330652) (xy 371.64899 -155.317698)
				(xy 371.6782 -155.288488) (xy 371.6782 -155.10764) (xy 371.6782 -153.924) (xy 370.84 -153.0858)
				(xy 370.84 -151.360378) (xy 370.767102 -151.28748) (xy 369.429792 -151.28748) (xy 368.912394 -151.804878)
				(xy 367.112804 -151.804878) (xy 366.960912 -151.652986) (xy 366.960912 -149.714712) (xy 366.960912 -147.352512)
				(xy 366.649 -147.0406) (xy 365.3028 -145.6944) (xy 362.49102 -145.6944) (xy 361.332526 -146.852894)
				(xy 359.0798 -146.852894) (xy 358.930194 -147.0025) (xy 354.7491 -147.0025) (xy 354.599494 -146.852894)
				(xy 353.310444 -145.563844) (xy 353.310444 -144.319244) (xy 353.310444 -142.03299) (xy 353.310444 -140.662406)
				(xy 352.990912 -140.342874) (xy 348.3737 -140.342874) (xy 348.0943 -140.622274)
			)
		)
	)
	(zone
		(net "PVDDQ_GHJ")
		(layer "B.Cu")
		(hatch none 0.5)
		(connect_pads
			(clearance 0.5)
		)
		(min_thickness 0.25)
		(fill yes
			(thermal_gap 0.5)
			(thermal_bridge_width 0.5)
			(island_removal_mode 0)
		)
		(polygon
			(pts
				(xy 93.152468 -6.7183) (xy 93.139768 -6.731) (xy 79.200502 -6.731) (xy 78.793848 -7.137654) (xy 78.793848 -9.149842)
				(xy 79.169006 -9.525) (xy 93.012768 -9.525) (xy 93.165168 -9.6774) (xy 93.165168 -11.7856) (xy 93.114368 -11.7348)
				(xy 79.322168 -11.7348) (xy 78.509368 -12.5476) (xy 78.509368 -13.7668) (xy 78.915768 -14.1732)
				(xy 93.165168 -14.1732) (xy 93.165168 -16.2306) (xy 93.012768 -16.383) (xy 79.07655 -16.383) (xy 78.744826 -16.714724)
				(xy 78.744826 -17.149826) (xy 78.8416 -17.2466) (xy 80.1878 -17.2466) (xy 80.3148 -17.3736) (xy 80.3148 -18.1356)
				(xy 80.01 -18.4404) (xy 79.629 -18.4404) (xy 79.4512 -18.6182) (xy 79.4512 -18.9992) (xy 79.5528 -19.1008)
				(xy 92.975176 -19.1008) (xy 93.19514 -19.320764) (xy 93.19514 -21.193506) (xy 93.114368 -21.274278)
				(xy 93.114368 -21.275294) (xy 93.01734 -21.275294) (xy 92.804996 -21.487638) (xy 91.859862 -21.487638)
				(xy 91.647518 -21.275294) (xy 79.55915 -21.275294) (xy 78.65491 -22.179534) (xy 78.65491 -23.782274)
				(xy 93.114368 -23.782274) (xy 93.114368 -25.7302) (xy 93.723968 -25.7302) (xy 93.723968 -23.652226)
				(xy 93.814392 -23.561802) (xy 93.814392 -21.536914) (xy 93.723968 -21.44649) (xy 93.723968 -19.3548)
				(xy 94.993968 -18.0848) (xy 94.993968 -16.9672) (xy 94.892368 -16.8656) (xy 94.181168 -16.8656)
				(xy 93.698568 -16.383) (xy 93.698568 -14.35354) (xy 94.320868 -13.73124) (xy 94.71406 -13.73124)
				(xy 94.79788 -13.64742) (xy 94.79788 -12.214352) (xy 93.698568 -11.11504) (xy 93.698568 -9.6774)
				(xy 93.825568 -9.5504) (xy 94.435168 -9.5504) (xy 95.146368 -8.8392) (xy 95.146368 -7.2898) (xy 94.587568 -6.731)
				(xy 94.054168 -6.731) (xy 94.028768 -6.7564) (xy 93.825568 -6.7564) (xy 93.787468 -6.7183)
			)
		)
		(polygon
			(pts
				(xy 88.0491 -18.1483) (xy 87.8459 -18.1483) (xy 87.8459 -18.3515) (xy 88.0491 -18.3515)
			)
		)
		(polygon
			(pts
				(xy 84.402168 -18.1483) (xy 84.198968 -18.1483) (xy 84.198968 -18.3515) (xy 84.402168 -18.3515)
			)
		)
		(polygon
			(pts
				(xy 81.303368 -18.1483) (xy 81.100168 -18.1483) (xy 81.100168 -18.3515) (xy 81.303368 -18.3515)
			)
		)
		(polygon
			(pts
				(xy 93.787468 -18.0213) (xy 93.584268 -18.0213) (xy 93.584268 -18.2245) (xy 93.787468 -18.2245)
			)
		)
		(polygon
			(pts
				(xy 88.0491 -17.1577) (xy 87.8459 -17.1577) (xy 87.8459 -17.3609) (xy 88.0491 -17.3609)
			)
		)
		(polygon
			(pts
				(xy 81.303368 -17.1577) (xy 81.100168 -17.1577) (xy 81.100168 -17.3609) (xy 81.303368 -17.3609)
			)
		)
		(polygon
			(pts
				(xy 93.787468 -17.0307) (xy 93.584268 -17.0307) (xy 93.584268 -17.2339) (xy 93.787468 -17.2339)
			)
		)
		(polygon
			(pts
				(xy 88.0491 -13.2334) (xy 87.8459 -13.2334) (xy 87.8459 -13.4366) (xy 88.0491 -13.4366)
			)
		)
		(polygon
			(pts
				(xy 87.704168 -13.2334) (xy 87.500968 -13.2334) (xy 87.500968 -13.4366) (xy 87.704168 -13.4366)
			)
		)
		(polygon
			(pts
				(xy 84.402168 -13.2334) (xy 84.198968 -13.2334) (xy 84.198968 -13.4366) (xy 84.402168 -13.4366)
			)
		)
		(polygon
			(pts
				(xy 93.651832 -13.167868) (xy 93.448632 -13.167868) (xy 93.448632 -13.371068) (xy 93.651832 -13.371068)
			)
		)
		(polygon
			(pts
				(xy 88.0491 -12.4714) (xy 87.8459 -12.4714) (xy 87.8459 -12.6746) (xy 88.0491 -12.6746)
			)
		)
		(polygon
			(pts
				(xy 87.704168 -12.4714) (xy 87.500968 -12.4714) (xy 87.500968 -12.6746) (xy 87.704168 -12.6746)
			)
		)
		(polygon
			(pts
				(xy 84.402168 -12.4714) (xy 84.198968 -12.4714) (xy 84.198968 -12.6746) (xy 84.402168 -12.6746)
			)
		)
		(polygon
			(pts
				(xy 93.651832 -12.405868) (xy 93.448632 -12.405868) (xy 93.448632 -12.609068) (xy 93.651832 -12.609068)
			)
		)
		(polygon
			(pts
				(xy 88.0491 -8.5471) (xy 87.8459 -8.5471) (xy 87.8459 -8.7503) (xy 88.0491 -8.7503)
			)
		)
		(polygon
			(pts
				(xy 84.402168 -8.5471) (xy 84.198968 -8.5471) (xy 84.198968 -8.7503) (xy 84.402168 -8.7503)
			)
		)
		(polygon
			(pts
				(xy 81.303368 -8.5471) (xy 81.100168 -8.5471) (xy 81.100168 -8.7503) (xy 81.303368 -8.7503)
			)
		)
		(polygon
			(pts
				(xy 93.990668 -8.4709) (xy 93.787468 -8.4709) (xy 93.787468 -8.6741) (xy 93.990668 -8.6741)
			)
		)
		(polygon
			(pts
				(xy 88.0491 -7.5565) (xy 87.8459 -7.5565) (xy 87.8459 -7.7597) (xy 88.0491 -7.7597)
			)
		)
		(polygon
			(pts
				(xy 81.303368 -7.5565) (xy 81.100168 -7.5565) (xy 81.100168 -7.7597) (xy 81.303368 -7.7597)
			)
		)
		(polygon
			(pts
				(xy 93.990668 -7.4803) (xy 93.787468 -7.4803) (xy 93.787468 -7.6835) (xy 93.990668 -7.6835)
			)
		)
	)
	(zone
		(net "P3V3_RTC_STBY")
		(layer "B.Cu")
		(hatch none 0.5)
		(connect_pads
			(clearance 0.5)
		)
		(min_thickness 0.25)
		(fill yes
			(thermal_gap 0.5)
			(thermal_bridge_width 0.5)
			(island_removal_mode 0)
		)
		(polygon
			(pts
				(xy 375.031 -104.1908) (xy 380.5936 -104.1908) (xy 380.7714 -104.013) (xy 380.7714 -102.997) (xy 380.2634 -102.489)
				(xy 374.9548 -102.489) (xy 374.7008 -102.743) (xy 374.7008 -103.8606)
			)
		)
	)
	(zone
		(net "GND")
		(layer "B.Cu")
		(hatch none 0.5)
		(connect_pads
			(clearance 0.5)
		)
		(min_thickness 0.25)
		(fill yes
			(thermal_gap 0.5)
			(thermal_bridge_width 0.5)
			(island_removal_mode 0)
		)
		(polygon
			(pts
				(xy 77.028802 -136.639808) (xy 78.284324 -136.639808) (xy 78.433168 -136.490964) (xy 78.433168 -134.180834)
				(xy 78.219554 -133.96722) (xy 77.054964 -133.96722) (xy 76.8477 -134.174484) (xy 76.8477 -136.458706)
			)
		)
	)
	(zone
		(layer "B.Cu")
		(hatch none 0.5)
		(connect_pads
			(clearance 0)
		)
		(min_thickness 0.25)
		(keepout
			(tracks not_allowed)
			(vias allowed)
			(pads allowed)
			(copperpour not_allowed)
			(footprints allowed)
		)
		(placement
			(enabled no)
			(sheetname "")
		)
		(fill
			(thermal_gap 0.5)
			(thermal_bridge_width 0.5)
			(island_removal_mode 0)
		)
		(polygon
			(pts
				(arc
					(start 6.139688 -111.853218)
					(mid 6.209538 -111.329301)
					(end 6.279388 -111.853218)
				)
				(xy 6.279388 -111.96701) (xy 6.352794 -112.040416) (xy 6.593078 -112.040416)
				(arc
					(start 6.593078 -111.59617)
					(mid 6.209665 -111.21263)
					(end 5.825998 -111.595916)
				)
				(arc
					(start 5.825998 -112.865916)
					(mid 6.209538 -113.249456)
					(end 6.593078 -112.865916)
				)
				(xy 6.593078 -112.421416) (xy 6.352794 -112.421416) (xy 6.279388 -112.494822)
				(arc
					(start 6.279388 -112.608614)
					(mid 6.209538 -113.132531)
					(end 6.139688 -112.608614)
				)
				(xy 6.139688 -112.43691) (xy 6.294882 -112.281716) (xy 6.593078 -112.281716) (xy 6.593078 -112.180116)
				(xy 6.294882 -112.180116) (xy 6.139688 -112.024922)
			)
		)
	)
	(zone
		(layer "B.Cu")
		(hatch none 0.5)
		(connect_pads
			(clearance 0)
		)
		(min_thickness 0.25)
		(keepout
			(tracks not_allowed)
			(vias allowed)
			(pads allowed)
			(copperpour not_allowed)
			(footprints allowed)
		)
		(placement
			(enabled no)
			(sheetname "")
		)
		(fill
			(thermal_gap 0.5)
			(thermal_bridge_width 0.5)
			(island_removal_mode 0)
		)
		(polygon
			(pts
				(arc
					(start 409.719526 -74.633836)
					(mid 407.469594 -76.883768)
					(end 409.719526 -79.1337)
				)
				(arc
					(start 409.719526 -79.1337)
					(mid 411.969458 -76.883768)
					(end 409.719526 -74.633836)
				)
			)
		)
	)
	(zone
		(layer "B.Cu")
		(hatch none 0.5)
		(connect_pads
			(clearance 0)
		)
		(min_thickness 0.25)
		(keepout
			(tracks not_allowed)
			(vias allowed)
			(pads allowed)
			(copperpour not_allowed)
			(footprints allowed)
		)
		(placement
			(enabled no)
			(sheetname "")
		)
		(fill
			(thermal_gap 0.5)
			(thermal_bridge_width 0.5)
			(island_removal_mode 0)
		)
		(polygon
			(pts
				(arc
					(start 198.930006 -48.09998)
					(mid 200.479914 -46.550072)
					(end 198.930006 -44.99991)
				)
				(arc
					(start 198.930006 -44.99991)
					(mid 197.379844 -46.550072)
					(end 198.930006 -48.09998)
				)
			)
		)
	)
	(zone
		(layer "B.Cu")
		(hatch none 0.5)
		(connect_pads
			(clearance 0)
		)
		(min_thickness 0.25)
		(keepout
			(tracks not_allowed)
			(vias allowed)
			(pads allowed)
			(copperpour not_allowed)
			(footprints allowed)
		)
		(placement
			(enabled no)
			(sheetname "")
		)
		(fill
			(thermal_gap 0.5)
			(thermal_bridge_width 0.5)
			(island_removal_mode 0)
		)
		(polygon
			(pts
				(arc
					(start 417.036504 -91.567)
					(mid 416.627564 -91.15806)
					(end 416.218624 -91.567)
				)
				(arc
					(start 416.218624 -92.836746)
					(mid 416.626167 -93.245938)
					(end 417.036504 -92.83954)
				)
				(arc
					(start 416.945064 -92.83954)
					(mid 416.627564 -93.15451)
					(end 416.310064 -92.83954)
				)
				(arc
					(start 416.310064 -92.837)
					(mid 416.627564 -92.5195)
					(end 416.945064 -92.837)
				)
				(xy 417.036504 -92.837) (xy 417.036504 -91.56954)
				(arc
					(start 416.945064 -91.56954)
					(mid 416.627564 -91.88451)
					(end 416.310064 -91.56954)
				)
				(arc
					(start 416.310064 -91.567)
					(mid 416.627564 -91.2495)
					(end 416.945064 -91.567)
				)
			)
		)
	)
	(zone
		(layer "B.Cu")
		(hatch none 0.5)
		(connect_pads
			(clearance 0)
		)
		(min_thickness 0.25)
		(keepout
			(tracks allowed)
			(vias allowed)
			(pads allowed)
			(copperpour allowed)
			(footprints allowed)
		)
		(placement
			(enabled no)
			(sheetname "")
		)
		(fill
			(thermal_gap 0.5)
			(thermal_bridge_width 0.5)
			(island_removal_mode 0)
		)
		(polygon
			(pts
				(xy 237.361984 -29.394658) (xy 237.361984 -50.62347) (xy 237.331504 -50.65395) (xy 234.62742 -50.65395)
				(xy 231.19715 -53.808884) (xy 229.033324 -54.152292) (xy 210.933792 -50.717958) (xy 210.952588 -48.018192)
				(xy 210.952588 -25.909016) (xy 226.57816 -29.154628) (xy 237.36427 -29.154628) (xy 237.36427 -29.394658)
			)
		)
	)
	(zone
		(net "FM_USB_P0_EN_R_N")
		(layer "B.Cu")
		(hatch none 0.5)
		(connect_pads
			(clearance 0.5)
		)
		(min_thickness 0.25)
		(fill yes
			(thermal_gap 0.5)
			(thermal_bridge_width 0.5)
			(island_removal_mode 0)
		)
		(polygon
			(pts
				(xy 466.471 -128.6764) (xy 467.868 -130.0734) (xy 469.5698 -130.0734) (xy 470.0016 -129.6416) (xy 470.0016 -126.715012)
				(xy 469.908128 -126.62154) (xy 466.77326 -126.62154) (xy 466.471 -126.9238)
			)
		)
		(polygon
			(pts
				(xy 468.313008 -127.800608) (xy 467.903306 -127.800608) (xy 467.568788 -128.135126) (xy 467.568788 -129.09804)
				(xy 468.22487 -129.754122) (xy 468.682578 -129.754122) (xy 468.911432 -129.525268) (xy 468.911432 -129.237232)
				(xy 469.14816 -129.000504) (xy 469.149938 -129.002282) (xy 469.333834 -129.002282) (xy 469.361012 -128.975104)
				(xy 469.361012 -127.979424) (xy 469.269826 -127.888238) (xy 468.62746 -127.888238) (xy 468.61603 -127.899668)
				(xy 468.412068 -127.899668)
			)
		)
	)
	(zone
		(layer "B.Cu")
		(hatch none 0.5)
		(connect_pads
			(clearance 0)
		)
		(min_thickness 0.25)
		(keepout
			(tracks allowed)
			(vias allowed)
			(pads allowed)
			(copperpour allowed)
			(footprints not_allowed)
		)
		(placement
			(enabled no)
			(sheetname "")
		)
		(fill
			(thermal_gap 0.5)
			(thermal_bridge_width 0.5)
			(island_removal_mode 0)
		)
		(polygon
			(pts
				(xy 165.159944 -127.359918) (xy 165.159944 -159.090106) (xy 163.52012 -159.090106) (xy 163.52012 -127.359918)
			)
		)
	)
	(zone
		(layer "B.Cu")
		(hatch none 0.5)
		(connect_pads
			(clearance 0)
		)
		(min_thickness 0.25)
		(keepout
			(tracks allowed)
			(vias allowed)
			(pads allowed)
			(copperpour allowed)
			(footprints allowed)
		)
		(placement
			(enabled no)
			(sheetname "")
		)
		(fill
			(thermal_gap 0.5)
			(thermal_bridge_width 0.5)
			(island_removal_mode 0)
		)
		(polygon
			(pts
				(xy 313.817 -85.979) (xy 313.817 -85.217) (xy 314.579 -85.217) (xy 314.579 -85.979)
			)
		)
	)
	(zone
		(net "P3V3_STBY")
		(layer "B.Cu")
		(hatch none 0.5)
		(connect_pads
			(clearance 0.5)
		)
		(min_thickness 0.25)
		(fill yes
			(thermal_gap 0.5)
			(thermal_bridge_width 0.5)
			(island_removal_mode 0)
		)
		(polygon
			(pts
				(xy 394.1445 -115.99672) (xy 398.68348 -115.99672) (xy 398.9578 -115.7224) (xy 399.288 -115.7224)
				(xy 399.5166 -115.951) (xy 399.5166 -116.4336) (xy 399.6436 -116.5606) (xy 400.1008 -116.5606) (xy 400.1516 -116.5098)
				(xy 400.1516 -116.078) (xy 400.2786 -115.951) (xy 400.33448 -115.89512) (xy 400.95932 -115.89512)
				(xy 401.0152 -115.83924) (xy 401.0152 -115.28044) (xy 400.94154 -115.20678) (xy 399.5547 -115.20678)
				(xy 399.10766 -114.75974) (xy 399.10766 -114.74958) (xy 398.66062 -114.30254) (xy 392.03376 -114.30254)
				(xy 391.7188 -114.6175) (xy 391.7188 -114.95786) (xy 391.7188 -115.56619) (xy 391.774426 -115.621816)
				(xy 392.318748 -115.621816) (xy 392.436858 -115.503706) (xy 392.436858 -115.143788) (xy 392.523726 -115.05692)
				(xy 393.2047 -115.05692)
			)
		)
	)
	(zone
		(layer "B.Cu")
		(hatch none 0.5)
		(connect_pads
			(clearance 0)
		)
		(min_thickness 0.25)
		(keepout
			(tracks allowed)
			(vias allowed)
			(pads allowed)
			(copperpour allowed)
			(footprints allowed)
		)
		(placement
			(enabled no)
			(sheetname "")
		)
		(fill
			(thermal_gap 0.5)
			(thermal_bridge_width 0.5)
			(island_removal_mode 0)
		)
		(polygon
			(pts
				(xy 314.071 -91.948) (xy 314.071 -91.186) (xy 314.833 -91.186) (xy 314.833 -91.948)
			)
		)
	)
	(zone
		(net "P12V")
		(layer "B.Cu")
		(hatch none 0.5)
		(connect_pads
			(clearance 0.5)
		)
		(min_thickness 0.25)
		(fill yes
			(thermal_gap 0.5)
			(thermal_bridge_width 0.5)
			(island_removal_mode 0)
		)
		(polygon
			(pts
				(xy 474.122242 -7.034022) (xy 474.036644 -7.11962) (xy 471.598244 -7.11962) (xy 471.326972 -7.11962)
				(xy 470.616788 -7.829804) (xy 470.418668 -7.829804) (xy 470.400634 -7.81177) (xy 470.2429 -7.81177)
				(xy 470.163144 -7.732014) (xy 470.163144 -4.23672) (xy 470.213944 -4.18592) (xy 470.721944 -4.18592)
				(xy 471.737944 -5.20192) (xy 473.955364 -5.20192) (xy 474.122242 -5.368798)
			)
		)
	)
	(zone
		(net "PVDDQ_ABC")
		(layer "B.Cu")
		(hatch none 0.5)
		(connect_pads
			(clearance 0.5)
		)
		(min_thickness 0.25)
		(fill yes
			(thermal_gap 0.5)
			(thermal_bridge_width 0.5)
			(island_removal_mode 0)
		)
		(polygon
			(pts
				(xy 272.635726 -11.699748) (xy 270.8275 -13.507974) (xy 270.8275 -13.877798) (xy 271.074134 -14.124432)
				(xy 277.218394 -14.124432) (xy 277.731982 -13.610844) (xy 277.731982 -12.00785) (xy 277.42388 -11.699748)
			)
		)
	)
	(zone
		(layer "B.Cu")
		(hatch none 0.5)
		(connect_pads
			(clearance 0)
		)
		(min_thickness 0.25)
		(keepout
			(tracks not_allowed)
			(vias allowed)
			(pads allowed)
			(copperpour not_allowed)
			(footprints allowed)
		)
		(placement
			(enabled no)
			(sheetname "")
		)
		(fill
			(thermal_gap 0.5)
			(thermal_bridge_width 0.5)
			(island_removal_mode 0)
		)
		(polygon
			(pts
				(arc
					(start 384.672078 -29.782516)
					(mid 384.350913 -29.362545)
					(end 384.770884 -29.68371)
				)
				(xy 384.92303 -29.835856)
				(arc
					(start 384.92303 -29.551376)
					(mid 384.539617 -29.167836)
					(end 384.15595 -29.551122)
				)
				(arc
					(start 384.15595 -30.516322)
					(mid 384.53949 -30.899862)
					(end 384.92303 -30.516322)
				)
				(xy 384.92303 -30.231588)
				(arc
					(start 384.770884 -30.383734)
					(mid 384.350913 -30.704899)
					(end 384.672078 -30.284928)
				)
				(xy 384.872484 -30.084522) (xy 384.92303 -30.084522) (xy 384.92303 -29.982922) (xy 384.872484 -29.982922)
			)
		)
	)
	(zone
		(net "GND")
		(layer "B.Cu")
		(hatch none 0.5)
		(connect_pads
			(clearance 0.5)
		)
		(min_thickness 0.25)
		(fill yes
			(thermal_gap 0.5)
			(thermal_bridge_width 0.5)
			(island_removal_mode 0)
		)
		(polygon
			(pts
				(xy 385.699 -113.932716) (xy 385.429506 -114.20221) (xy 383.488946 -114.20221) (xy 383.050034 -113.763298)
				(xy 383.050034 -113.017554) (xy 383.157476 -112.910112) (xy 383.621788 -112.4458) (xy 383.835148 -112.4458)
				(xy 383.965704 -112.576356) (xy 384.316986 -112.576356) (xy 384.447542 -112.4458) (xy 384.621532 -112.4458)
				(xy 384.782568 -112.606836) (xy 385.094226 -112.606836) (xy 385.255262 -112.4458) (xy 385.4704 -112.4458)
				(xy 385.699 -112.6744)
			)
		)
	)
	(zone
		(layer "B.Cu")
		(hatch none 0.5)
		(connect_pads
			(clearance 0)
		)
		(min_thickness 0.25)
		(keepout
			(tracks not_allowed)
			(vias allowed)
			(pads allowed)
			(copperpour not_allowed)
			(footprints allowed)
		)
		(placement
			(enabled no)
			(sheetname "")
		)
		(fill
			(thermal_gap 0.5)
			(thermal_bridge_width 0.5)
			(island_removal_mode 0)
		)
		(polygon
			(pts
				(arc
					(start 335.194148 -71.680832)
					(mid 334.774177 -72.001997)
					(end 335.095342 -71.582026)
				)
				(xy 335.21777 -71.459598) (xy 335.21777 -71.42988)
				(arc
					(start 334.962754 -71.42988)
					(mid 334.579214 -71.81342)
					(end 334.962754 -72.19696)
				)
				(arc
					(start 335.853786 -72.19696)
					(mid 336.23758 -71.813547)
					(end 335.85404 -71.42988)
				)
				(xy 335.59877 -71.42988) (xy 335.59877 -71.459344)
				(arc
					(start 335.721452 -71.582026)
					(mid 336.042617 -72.001997)
					(end 335.622646 -71.680832)
				)
				(xy 335.45907 -71.517256) (xy 335.45907 -71.42988) (xy 335.35747 -71.42988) (xy 335.35747 -71.51751)
			)
		)
	)
	(zone
		(net "PVDDQ_GHJ")
		(layer "B.Cu")
		(hatch none 0.5)
		(connect_pads
			(clearance 0.5)
		)
		(min_thickness 0.25)
		(fill yes
			(thermal_gap 0.5)
			(thermal_bridge_width 0.5)
			(island_removal_mode 0)
		)
		(polygon
			(pts
				(xy 108.5342 -5.3594) (xy 108.4326 -5.461) (xy 108.4326 -6.7818) (xy 108.3564 -6.858) (xy 100.759768 -6.858)
				(xy 100.607368 -7.0104) (xy 100.607368 -9.3472) (xy 100.835968 -9.5758) (xy 103.251 -9.5758) (xy 103.3272 -9.652)
				(xy 103.3272 -10.7696) (xy 103.4542 -10.8966) (xy 103.8098 -10.8966) (xy 103.9622 -10.7442) (xy 103.9622 -9.7028)
				(xy 104.0892 -9.5758) (xy 111.6838 -9.5758) (xy 111.8108 -9.7028) (xy 111.8108 -10.7696) (xy 111.9378 -10.8966)
				(xy 112.395 -10.8966) (xy 112.519968 -10.771632) (xy 112.519968 -7.1882) (xy 112.189768 -6.858)
				(xy 109.1438 -6.858) (xy 109.0422 -6.7564) (xy 109.0422 -5.4356) (xy 108.966 -5.3594)
			)
		)
		(polygon
			(pts
				(xy 107.5182 -8.5471) (xy 107.315 -8.5471) (xy 107.315 -8.7503) (xy 107.5182 -8.7503)
			)
		)
		(polygon
			(pts
				(xy 104.2162 -8.5471) (xy 104.013 -8.5471) (xy 104.013 -8.7503) (xy 104.2162 -8.7503)
			)
		)
		(polygon
			(pts
				(xy 101.0539 -8.5471) (xy 100.8507 -8.5471) (xy 100.8507 -8.7503) (xy 101.0539 -8.7503)
			)
		)
		(polygon
			(pts
				(xy 110.657132 -7.5565) (xy 110.453932 -7.5565) (xy 110.453932 -7.7597) (xy 110.657132 -7.7597)
			)
		)
		(polygon
			(pts
				(xy 107.5182 -7.5565) (xy 107.315 -7.5565) (xy 107.315 -7.7597) (xy 107.5182 -7.7597)
			)
		)
		(polygon
			(pts
				(xy 104.2162 -7.5565) (xy 104.013 -7.5565) (xy 104.013 -7.7597) (xy 104.2162 -7.7597)
			)
		)
	)
	(zone
		(net "PVDDQ_GHJ")
		(layer "B.Cu")
		(hatch none 0.5)
		(connect_pads
			(clearance 0.5)
		)
		(min_thickness 0.25)
		(fill yes
			(thermal_gap 0.5)
			(thermal_bridge_width 0.5)
			(island_removal_mode 0)
		)
		(polygon
			(pts
				(xy 79.423768 -2.0828) (xy 78.560168 -2.9464) (xy 78.560168 -4.2418) (xy 78.788768 -4.4704) (xy 93.190568 -4.4704)
				(xy 93.191584 -4.469384) (xy 93.981016 -4.469384) (xy 94.4626 -3.9878) (xy 95.0976 -3.9878) (xy 95.2246 -3.8608)
				(xy 95.2246 -2.794) (xy 95.0976 -2.667) (xy 94.2086 -2.667) (xy 93.800168 -2.258568) (xy 93.800168 -2.2352)
				(xy 93.647768 -2.0828)
			)
		)
		(polygon
			(pts
				(xy 88.0491 -3.6322) (xy 87.8459 -3.6322) (xy 87.8459 -3.8354) (xy 88.0491 -3.8354)
			)
		)
		(polygon
			(pts
				(xy 87.704168 -3.6322) (xy 87.500968 -3.6322) (xy 87.500968 -3.8354) (xy 87.704168 -3.8354)
			)
		)
		(polygon
			(pts
				(xy 84.402168 -3.6322) (xy 84.198968 -3.6322) (xy 84.198968 -3.8354) (xy 84.402168 -3.8354)
			)
		)
		(polygon
			(pts
				(xy 93.647768 -3.601212) (xy 93.444568 -3.601212) (xy 93.444568 -3.804412) (xy 93.647768 -3.804412)
			)
		)
		(polygon
			(pts
				(xy 88.0491 -2.8702) (xy 87.8459 -2.8702) (xy 87.8459 -3.0734) (xy 88.0491 -3.0734)
			)
		)
		(polygon
			(pts
				(xy 87.704168 -2.8702) (xy 87.500968 -2.8702) (xy 87.500968 -3.0734) (xy 87.704168 -3.0734)
			)
		)
		(polygon
			(pts
				(xy 84.402168 -2.8702) (xy 84.198968 -2.8702) (xy 84.198968 -3.0734) (xy 84.402168 -3.0734)
			)
		)
		(polygon
			(pts
				(xy 93.647768 -2.839212) (xy 93.444568 -2.839212) (xy 93.444568 -3.042412) (xy 93.647768 -3.042412)
			)
		)
	)
	(zone
		(layer "B.Cu")
		(hatch none 0.5)
		(connect_pads
			(clearance 0)
		)
		(min_thickness 0.25)
		(keepout
			(tracks allowed)
			(vias allowed)
			(pads allowed)
			(copperpour allowed)
			(footprints not_allowed)
		)
		(placement
			(enabled no)
			(sheetname "")
		)
		(fill
			(thermal_gap 0.5)
			(thermal_bridge_width 0.5)
			(island_removal_mode 0)
		)
		(polygon
			(pts
				(arc
					(start 248.000012 -39.649908)
					(mid 246.099838 -41.550082)
					(end 248.000012 -43.450002)
				)
				(arc
					(start 248.000012 -43.450002)
					(mid 249.899932 -41.550082)
					(end 248.000012 -39.649908)
				)
			)
		)
	)
	(zone
		(layer "B.Cu")
		(hatch none 0.5)
		(connect_pads
			(clearance 0)
		)
		(min_thickness 0.25)
		(keepout
			(tracks not_allowed)
			(vias allowed)
			(pads allowed)
			(copperpour not_allowed)
			(footprints allowed)
		)
		(placement
			(enabled no)
			(sheetname "")
		)
		(fill
			(thermal_gap 0.5)
			(thermal_bridge_width 0.5)
			(island_removal_mode 0)
		)
		(polygon
			(pts
				(arc
					(start 343.758266 -67.353942)
					(mid 343.338295 -67.675107)
					(end 343.65946 -67.255136)
				)
				(xy 343.811606 -67.10299)
				(arc
					(start 343.526872 -67.10299)
					(mid 343.143332 -67.48653)
					(end 343.526872 -67.87007)
				)
				(arc
					(start 344.491818 -67.87007)
					(mid 344.875612 -67.486657)
					(end 344.492072 -67.10299)
				)
				(xy 344.207338 -67.10299)
				(arc
					(start 344.359484 -67.255136)
					(mid 344.680649 -67.675107)
					(end 344.260678 -67.353942)
				)
				(xy 344.060272 -67.153536) (xy 344.060272 -67.10299) (xy 343.958672 -67.10299) (xy 343.958672 -67.153536)
			)
		)
	)
	(zone
		(net "PVDDQ_KLM")
		(layer "B.Cu")
		(hatch none 0.5)
		(connect_pads
			(clearance 0.5)
		)
		(min_thickness 0.25)
		(fill yes
			(thermal_gap 0.5)
			(thermal_bridge_width 0.5)
			(island_removal_mode 0)
		)
		(polygon
			(pts
				(xy 102.175818 -86.329266) (xy 100.523802 -86.329266) (xy 100.226876 -86.329266) (xy 99.986592 -86.088982)
				(xy 99.986592 -84.918042) (xy 99.986592 -84.61756) (xy 100.075492 -84.52866) (xy 100.5459 -84.52866)
				(xy 100.558854 -84.541614) (xy 103.161592 -84.541614) (xy 108.679234 -84.541614) (xy 110.485174 -84.541614)
				(xy 110.526068 -84.582508) (xy 110.526068 -85.544152) (xy 110.526068 -85.934296) (xy 110.126526 -86.333838)
				(xy 109.736382 -86.333838) (xy 108.174282 -86.333838) (xy 102.678992 -86.333838) (xy 102.18039 -86.333838)
			)
		)
	)
	(zone
		(layer "B.Cu")
		(hatch none 0.5)
		(connect_pads
			(clearance 0)
		)
		(min_thickness 0.25)
		(keepout
			(tracks allowed)
			(vias allowed)
			(pads allowed)
			(copperpour allowed)
			(footprints not_allowed)
		)
		(placement
			(enabled no)
			(sheetname "")
		)
		(fill
			(thermal_gap 0.5)
			(thermal_bridge_width 0.5)
			(island_removal_mode 0)
		)
		(polygon
			(pts
				(arc
					(start 111.258604 -85.612478)
					(mid 111.014665 -85.714982)
					(end 110.752382 -85.749892)
				)
				(xy 105.10012 -85.749892) (xy 105.10012 -119.800116) (xy 129.845054 -119.800116) (xy 129.845054 -90.199972)
				(arc
					(start 129.094992 -90.199972)
					(mid 128.635382 -90.009596)
					(end 128.445006 -89.549986)
				)
				(arc
					(start 128.445006 -85.199982)
					(mid 128.635382 -84.740372)
					(end 129.094992 -84.549996)
				)
				(arc
					(start 130.795014 -84.549996)
					(mid 131.254624 -84.740372)
					(end 131.445 -85.199982)
				)
				(arc
					(start 131.445 -89.549986)
					(mid 131.254624 -90.009596)
					(end 130.795014 -90.199972)
				)
				(xy 130.044952 -90.199972) (xy 130.044952 -119.800116) (xy 154.850084 -119.800116) (xy 154.850084 -118.800118)
				(xy 156.85008 -118.800118) (xy 156.85008 -119.800116) (xy 161.749994 -119.800116) (xy 161.749994 -89.22004)
				(xy 152.96007 -89.22004)
				(arc
					(start 152.96007 -92.689934)
					(mid 152.667177 -93.397039)
					(end 151.960072 -93.689932)
				)
				(arc
					(start 146.340068 -93.689932)
					(mid 145.632963 -93.397039)
					(end 145.34007 -92.689934)
				)
				(arc
					(start 145.34007 -85.549994)
					(mid 145.632963 -84.842889)
					(end 146.340068 -84.549996)
				)
				(arc
					(start 151.960072 -84.549996)
					(mid 152.667177 -84.842889)
					(end 152.96007 -85.549994)
				)
				(xy 152.96007 -89.019888) (xy 161.749994 -89.019888) (xy 161.749994 -64.079882) (xy 152.96007 -64.079882)
				(arc
					(start 152.96007 -67.55003)
					(mid 152.667177 -68.257135)
					(end 151.960072 -68.550028)
				)
				(arc
					(start 146.340068 -68.550028)
					(mid 145.632963 -68.257135)
					(end 145.34007 -67.55003)
				)
				(arc
					(start 145.34007 -60.41009)
					(mid 145.632963 -59.702985)
					(end 146.340068 -59.410092)
				)
				(arc
					(start 151.960072 -59.410092)
					(mid 152.667177 -59.702985)
					(end 152.96007 -60.41009)
				)
				(xy 152.96007 -63.879984) (xy 161.749994 -63.879984) (xy 161.749994 -33.299908) (xy 130.044952 -33.299908)
				(xy 130.044952 -62.900052)
				(arc
					(start 130.795014 -62.900052)
					(mid 131.254624 -63.090428)
					(end 131.445 -63.550038)
				)
				(arc
					(start 131.445 -67.900042)
					(mid 131.254624 -68.359652)
					(end 130.795014 -68.550028)
				)
				(arc
					(start 129.094992 -68.550028)
					(mid 128.635382 -68.359652)
					(end 128.445006 -67.900042)
				)
				(arc
					(start 128.445006 -63.550038)
					(mid 128.635382 -63.090428)
					(end 129.094992 -62.900052)
				)
				(xy 129.845054 -62.900052) (xy 129.845054 -33.299908) (xy 80.155034 -33.299908) (xy 80.155034 -62.900052)
				(arc
					(start 80.905096 -62.900052)
					(mid 81.364706 -63.090428)
					(end 81.555082 -63.550038)
				)
				(arc
					(start 81.555082 -67.900042)
					(mid 81.364706 -68.359652)
					(end 80.905096 -68.550028)
				)
				(arc
					(start 79.205074 -68.550028)
					(mid 78.745464 -68.359652)
					(end 78.555088 -67.900042)
				)
				(arc
					(start 78.555088 -63.550038)
					(mid 78.745464 -63.090428)
					(end 79.205074 -62.900052)
				)
				(xy 79.954882 -62.900052) (xy 79.954882 -33.299908) (xy 48.250094 -33.299908) (xy 48.250094 -53.300122)
				(xy 49.9999 -53.300122) (xy 49.9999 -63.879984) (xy 57.040018 -63.879984)
				(arc
					(start 57.040018 -60.41009)
					(mid 57.332911 -59.702985)
					(end 58.040016 -59.410092)
				)
				(arc
					(start 63.66002 -59.410092)
					(mid 64.367125 -59.702985)
					(end 64.660018 -60.41009)
				)
				(arc
					(start 64.660018 -67.55003)
					(mid 64.367125 -68.257135)
					(end 63.66002 -68.550028)
				)
				(arc
					(start 58.040016 -68.550028)
					(mid 57.332911 -68.257135)
					(end 57.040018 -67.55003)
				)
				(xy 57.040018 -64.079882) (xy 49.9999 -64.079882) (xy 49.9999 -89.019888) (xy 57.040018 -89.019888)
				(arc
					(start 57.040018 -85.549994)
					(mid 57.332911 -84.842889)
					(end 58.040016 -84.549996)
				)
				(arc
					(start 63.66002 -84.549996)
					(mid 64.367125 -84.842889)
					(end 64.660018 -85.549994)
				)
				(arc
					(start 64.660018 -92.689934)
					(mid 64.367125 -93.397039)
					(end 63.66002 -93.689932)
				)
				(arc
					(start 58.040016 -93.689932)
					(mid 57.332911 -93.397039)
					(end 57.040018 -92.689934)
				)
				(xy 57.040018 -89.22004) (xy 49.9999 -89.22004) (xy 49.9999 -99.799902) (xy 48.250094 -99.799902)
				(xy 48.250094 -119.800116) (xy 79.954882 -119.800116) (xy 79.954882 -90.199972)
				(arc
					(start 79.205074 -90.199972)
					(mid 78.745464 -90.009596)
					(end 78.555088 -89.549986)
				)
				(arc
					(start 78.555088 -85.199982)
					(mid 78.745464 -84.740372)
					(end 79.205074 -84.549996)
				)
				(arc
					(start 80.905096 -84.549996)
					(mid 81.364706 -84.740372)
					(end 81.555082 -85.199982)
				)
				(arc
					(start 81.555082 -89.549986)
					(mid 81.364706 -90.009596)
					(end 80.905096 -90.199972)
				)
				(xy 80.155034 -90.199972) (xy 80.155034 -119.800116) (xy 104.899968 -119.800116) (xy 104.899968 -85.749892)
				(arc
					(start 99.09302 -85.749892)
					(mid 98.825032 -85.713385)
					(end 98.576638 -85.606382)
				)
				(arc
					(start 92.928694 -82.200496)
					(mid 92.574411 -81.835922)
					(end 92.445078 -81.344262)
				)
				(arc
					(start 92.445078 -71.750682)
					(mid 92.57432 -71.25897)
					(end 92.928694 -70.894448)
				)
				(arc
					(start 98.576638 -67.488562)
					(mid 98.825037 -67.381577)
					(end 99.09302 -67.345052)
				)
				(arc
					(start 110.906814 -67.345052)
					(mid 111.174802 -67.381559)
					(end 111.423196 -67.488562)
				)
				(arc
					(start 117.071394 -70.894448)
					(mid 117.425677 -71.259022)
					(end 117.55501 -71.750682)
				)
				(arc
					(start 117.55501 -81.344262)
					(mid 117.422839 -81.841124)
					(end 117.061234 -82.206592)
				)
			)
		)
	)
	(zone
		(layer "B.Cu")
		(hatch none 0.5)
		(connect_pads
			(clearance 0)
		)
		(min_thickness 0.25)
		(keepout
			(tracks not_allowed)
			(vias allowed)
			(pads allowed)
			(copperpour not_allowed)
			(footprints allowed)
		)
		(placement
			(enabled no)
			(sheetname "")
		)
		(fill
			(thermal_gap 0.5)
			(thermal_bridge_width 0.5)
			(island_removal_mode 0)
		)
		(polygon
			(pts
				(xy 346.846398 -89.3064) (xy 347.017848 -89.3064) (xy 347.017848 -89.42324) (xy 346.846398 -89.42324)
			)
		)
	)
	(zone
		(layer "B.Cu")
		(hatch none 0.5)
		(connect_pads
			(clearance 0)
		)
		(min_thickness 0.25)
		(keepout
			(tracks allowed)
			(vias allowed)
			(pads allowed)
			(copperpour allowed)
			(footprints not_allowed)
		)
		(placement
			(enabled no)
			(sheetname "")
		)
		(fill
			(thermal_gap 0.5)
			(thermal_bridge_width 0.5)
			(island_removal_mode 0)
		)
		(polygon
			(pts
				(arc
					(start 152.999948 -96.650048)
					(mid 151.100028 -98.549968)
					(end 152.999948 -100.449888)
				)
				(arc
					(start 152.999948 -100.449888)
					(mid 154.899868 -98.549968)
					(end 152.999948 -96.650048)
				)
			)
		)
	)
	(zone
		(net "GND")
		(layer "B.Cu")
		(hatch none 0.5)
		(connect_pads
			(clearance 0.5)
		)
		(min_thickness 0.25)
		(fill yes
			(thermal_gap 0.5)
			(thermal_bridge_width 0.5)
			(island_removal_mode 0)
		)
		(polygon
			(pts
				(xy 33.814004 -93.655388) (xy 33.814004 -94.176596) (xy 34.0868 -94.449392) (xy 34.0868 -96.650556)
				(xy 34.103056 -96.650556) (xy 34.103056 -97.921572) (xy 34.0868 -97.921572) (xy 34.0868 -98.301556)
				(xy 34.103056 -98.301556) (xy 34.103056 -99.572572) (xy 34.0868 -99.572572) (xy 34.0868 -99.977956)
				(xy 34.103056 -99.977956) (xy 34.103056 -101.248972) (xy 33.904428 -101.248972) (xy 33.7566 -101.3968)
				(xy 33.645856 -101.3968) (xy 33.645856 -101.553772) (xy 33.447228 -101.553772) (xy 33.3502 -101.650546)
				(xy 33.3502 -102.4382) (xy 33.375092 -102.463092) (xy 37.163248 -102.463092) (xy 37.366702 -102.6668)
				(xy 38.70706 -102.6668)
				(arc
					(start 38.70706 -102.616)
					(mid 39.088568 -102.234492)
					(end 39.470076 -102.616)
				)
				(arc
					(start 39.470076 -102.616)
					(mid 39.484955 -102.651921)
					(end 39.520876 -102.6668)
				)
				(xy 41.145968 -102.6668) (xy 42.92092 -100.891848) (xy 42.92092 -93.843348) (xy 42.73296 -93.655388)
			)
		)
	)
	(zone
		(layer "B.Cu")
		(hatch none 0.5)
		(connect_pads
			(clearance 0)
		)
		(min_thickness 0.25)
		(keepout
			(tracks not_allowed)
			(vias allowed)
			(pads allowed)
			(copperpour not_allowed)
			(footprints allowed)
		)
		(placement
			(enabled no)
			(sheetname "")
		)
		(fill
			(thermal_gap 0.5)
			(thermal_bridge_width 0.5)
			(island_removal_mode 0)
		)
		(polygon
			(pts
				(arc
					(start 4.629912 -48.909986)
					(mid 8.229854 -45.310044)
					(end 4.629912 -41.710102)
				)
				(arc
					(start 4.629912 -41.710102)
					(mid 1.02997 -45.310044)
					(end 4.629912 -48.909986)
				)
			)
		)
	)
	(zone
		(layer "B.Cu")
		(hatch none 0.5)
		(connect_pads
			(clearance 0)
		)
		(min_thickness 0.25)
		(keepout
			(tracks allowed)
			(vias allowed)
			(pads allowed)
			(copperpour allowed)
			(footprints allowed)
		)
		(placement
			(enabled no)
			(sheetname "")
		)
		(fill
			(thermal_gap 0.5)
			(thermal_bridge_width 0.5)
			(island_removal_mode 0)
		)
		(polygon
			(pts
				(xy 313.055 -93.472) (xy 313.055 -92.71) (xy 313.817 -92.71) (xy 313.817 -93.472)
			)
		)
	)
	(zone
		(net "P3V3_STBY_MNG_RMII")
		(layer "B.Cu")
		(hatch none 0.5)
		(connect_pads
			(clearance 0.5)
		)
		(min_thickness 0.25)
		(fill yes
			(thermal_gap 0.5)
			(thermal_bridge_width 0.5)
			(island_removal_mode 0)
		)
		(polygon
			(pts
				(xy 473.8878 -33.4264) (xy 473.71 -33.6042) (xy 473.71 -35.2806) (xy 474.1672 -35.7378) (xy 476.8596 -35.7378)
				(xy 477.012 -35.8902) (xy 477.2152 -35.8902) (xy 477.3422 -35.7632) (xy 478.2566 -35.7632) (xy 478.6376 -35.3822)
				(xy 479.0948 -35.3822) (xy 479.171 -35.306) (xy 479.171 -33.909) (xy 479.0948 -33.8328) (xy 476.0468 -33.8328)
				(xy 475.9452 -33.7312) (xy 474.6752 -33.7312) (xy 474.3704 -33.4264)
			)
		)
		(polygon
			(pts
				(xy 478.368106 -35.259518) (xy 478.164906 -35.259518) (xy 478.164906 -35.462718) (xy 478.368106 -35.462718)
			)
		)
		(polygon
			(pts
				(xy 477.6216 -34.2519) (xy 477.4184 -34.2519) (xy 477.4184 -34.4551) (xy 477.6216 -34.4551)
			)
		)
		(polygon
			(pts
				(xy 476.7326 -34.2519) (xy 476.5294 -34.2519) (xy 476.5294 -34.4551) (xy 476.7326 -34.4551)
			)
		)
	)
	(zone
		(net "GND")
		(layer "B.Cu")
		(hatch none 0.5)
		(connect_pads
			(clearance 0.5)
		)
		(min_thickness 0.25)
		(fill yes
			(thermal_gap 0.5)
			(thermal_bridge_width 0.5)
			(island_removal_mode 0)
		)
		(polygon
			(pts
				(xy 412.52648 -30.3022) (xy 412.52648 -26.52014) (xy 412.43504 -26.4287) (xy 412.43504 -24.15794)
				(xy 412.4071 -24.13) (xy 411.93974 -24.13) (xy 411.92196 -24.14778) (xy 411.92196 -25.18156) (xy 411.29712 -25.8064)
				(xy 411.29712 -27.0256) (xy 411.7848 -27.51328) (xy 411.7848 -28.04922) (xy 411.94482 -28.20924)
				(xy 411.94482 -30.11932) (xy 412.21914 -30.39364) (xy 412.43504 -30.39364)
			)
		)
	)
	(zone
		(layer "B.Cu")
		(hatch none 0.5)
		(connect_pads
			(clearance 0)
		)
		(min_thickness 0.25)
		(keepout
			(tracks not_allowed)
			(vias allowed)
			(pads allowed)
			(copperpour not_allowed)
			(footprints allowed)
		)
		(placement
			(enabled no)
			(sheetname "")
		)
		(fill
			(thermal_gap 0.5)
			(thermal_bridge_width 0.5)
			(island_removal_mode 0)
		)
		(polygon
			(pts
				(arc
					(start 127 -114.089942)
					(mid 129.54 -111.549942)
					(end 127 -109.009942)
				)
				(arc
					(start 127 -109.009942)
					(mid 124.46 -111.549942)
					(end 127 -114.089942)
				)
			)
		)
	)
	(zone
		(net "GND")
		(layer "B.Cu")
		(hatch none 0.5)
		(connect_pads
			(clearance 0.5)
		)
		(min_thickness 0.25)
		(fill yes
			(thermal_gap 0.5)
			(thermal_bridge_width 0.5)
			(island_removal_mode 0)
		)
		(polygon
			(pts
				(xy 115.588288 -74.676) (xy 115.358926 -74.905616) (xy 93.107256 -74.905616) (xy 93.001592 -75.01128)
				(xy 93.001592 -76.540614) (xy 115.834414 -76.540614) (xy 116.0526 -76.7588) (xy 116.0526 -79.2226)
				(xy 116.291106 -79.461106) (xy 116.532152 -79.461106) (xy 116.690648 -79.619602) (xy 116.690648 -80.105758)
				(xy 116.880894 -80.296004) (xy 117.652546 -80.296004) (xy 117.768878 -80.179672) (xy 117.768878 -79.39786)
				(xy 117.610128 -79.23911) (xy 116.796312 -79.23911) (xy 116.637816 -79.080614) (xy 116.637816 -79.0448)
				(xy 116.586 -78.992984) (xy 116.586 -74.7014) (xy 116.5606 -74.676)
			)
		)
		(polygon
			(pts
				(xy 115.836192 -75.423014) (xy 115.632992 -75.423014) (xy 115.632992 -75.626214) (xy 115.836192 -75.626214)
			)
		)
		(polygon
			(pts
				(xy 115.074192 -75.423014) (xy 114.870992 -75.423014) (xy 114.870992 -75.626214) (xy 115.074192 -75.626214)
			)
		)
	)
	(zone
		(net "GND")
		(layer "B.Cu")
		(hatch none 0.5)
		(connect_pads
			(clearance 0.5)
		)
		(min_thickness 0.25)
		(fill yes
			(thermal_gap 0.5)
			(thermal_bridge_width 0.5)
			(island_removal_mode 0)
		)
		(polygon
			(pts
				(xy 389.926322 -40.324278) (xy 389.224774 -40.324278) (xy 389.176006 -40.27551) (xy 389.1661 -40.27551)
				(xy 389.1661 -37.508942) (xy 389.327136 -37.347906) (xy 389.950706 -37.347906) (xy 390.0932 -37.4904)
				(xy 390.0932 -40.1574)
			)
		)
	)
	(zone
		(net "GND")
		(layer "B.Cu")
		(hatch none 0.5)
		(connect_pads
			(clearance 0.5)
		)
		(min_thickness 0.25)
		(fill yes
			(thermal_gap 0.5)
			(thermal_bridge_width 0.5)
			(island_removal_mode 0)
		)
		(polygon
			(pts
				(xy 201.659744 -93.570806) (xy 207.45069 -93.570806) (xy 207.742282 -93.862398) (xy 207.742282 -101.073458)
				(xy 207.33004 -101.4857) (xy 205.626716 -101.4857) (xy 205.0034 -102.109016) (xy 204.238606 -102.109016)
				(xy 204.100684 -102.109016) (xy 203.8985 -102.3112) (xy 201.2061 -102.3112) (xy 200.0504 -102.3112)
				(xy 199.4789 -101.7397) (xy 199.263 -101.5238) (xy 199.263 -96.1517) (xy 199.1233 -96.012) (xy 199.1233 -95.9993)
				(xy 198.8312 -95.7072) (xy 198.8312 -95.701612) (xy 198.805038 -95.67545) (xy 198.805038 -93.67774)
				(xy 198.911972 -93.570806) (xy 200.383394 -93.570806) (xy 200.434194 -93.570806)
			)
		)
	)
	(zone
		(net "PVDDQ_DEF")
		(layer "B.Cu")
		(hatch none 0.5)
		(connect_pads
			(clearance 0.5)
		)
		(min_thickness 0.25)
		(fill yes
			(thermal_gap 0.5)
			(thermal_bridge_width 0.5)
			(island_removal_mode 0)
		)
		(polygon
			(pts
				(xy 243.91747 -131.77266) (xy 258.496054 -131.77266) (xy 258.663694 -131.60502) (xy 258.663694 -129.580386)
				(xy 258.510024 -129.426716) (xy 244.559836 -129.426716) (xy 243.764054 -130.222498) (xy 243.764054 -131.619244)
			)
		)
	)
	(zone
		(layer "B.Cu")
		(hatch none 0.5)
		(connect_pads
			(clearance 0)
		)
		(min_thickness 0.25)
		(keepout
			(tracks allowed)
			(vias allowed)
			(pads allowed)
			(copperpour allowed)
			(footprints not_allowed)
		)
		(placement
			(enabled no)
			(sheetname "")
		)
		(fill
			(thermal_gap 0.5)
			(thermal_bridge_width 0.5)
			(island_removal_mode 0)
		)
		(polygon
			(pts
				(arc
					(start 33.919922 -42.999914)
					(mid 30.369764 -46.550072)
					(end 33.919922 -50.099976)
				)
				(arc
					(start 33.919922 -50.099976)
					(mid 37.469826 -46.550072)
					(end 33.919922 -42.999914)
				)
			)
		)
	)
	(zone
		(layer "B.Cu")
		(hatch none 0.5)
		(connect_pads
			(clearance 0)
		)
		(min_thickness 0.25)
		(keepout
			(tracks allowed)
			(vias allowed)
			(pads allowed)
			(copperpour allowed)
			(footprints not_allowed)
		)
		(placement
			(enabled no)
			(sheetname "")
		)
		(fill
			(thermal_gap 0.5)
			(thermal_bridge_width 0.5)
			(island_removal_mode 0)
		)
		(polygon
			(pts
				(arc
					(start 33.919922 -103.000048)
					(mid 30.369764 -106.550206)
					(end 33.919922 -110.10011)
				)
				(arc
					(start 33.919922 -110.10011)
					(mid 37.469826 -106.550206)
					(end 33.919922 -103.000048)
				)
			)
		)
	)
	(zone
		(net "PVDDQ_GHJ")
		(layer "B.Cu")
		(hatch none 0.5)
		(connect_pads
			(clearance 0.5)
		)
		(min_thickness 0.25)
		(fill yes
			(thermal_gap 0.5)
			(thermal_bridge_width 0.5)
			(island_removal_mode 0)
		)
		(polygon
			(pts
				(xy 107.813602 -11.720322) (xy 105.984802 -13.549122) (xy 105.984802 -14.16558) (xy 106.005376 -14.186154)
				(xy 112.313974 -14.186154) (xy 112.498886 -14.001242) (xy 112.498886 -11.925808) (xy 112.2934 -11.720322)
			)
		)
	)
	(zone
		(layer "B.Cu")
		(hatch none 0.5)
		(connect_pads
			(clearance 0)
		)
		(min_thickness 0.25)
		(keepout
			(tracks not_allowed)
			(vias allowed)
			(pads allowed)
			(copperpour not_allowed)
			(footprints allowed)
		)
		(placement
			(enabled no)
			(sheetname "")
		)
		(fill
			(thermal_gap 0.5)
			(thermal_bridge_width 0.5)
			(island_removal_mode 0)
		)
		(polygon
			(pts
				(arc
					(start 450.907912 -49.927764)
					(mid 451.431829 -49.997614)
					(end 450.907912 -50.067464)
				)
				(xy 450.805296 -50.067464) (xy 450.73189 -50.14087) (xy 450.73189 -50.381154)
				(arc
					(start 451.16496 -50.381154)
					(mid 451.548754 -49.997741)
					(end 451.165214 -49.614074)
				)
				(arc
					(start 449.895214 -49.614074)
					(mid 449.511674 -49.997614)
					(end 449.895214 -50.381154)
				)
				(xy 450.35089 -50.381154) (xy 450.35089 -50.152046) (xy 450.266308 -50.067464)
				(arc
					(start 450.152516 -50.067464)
					(mid 449.628599 -49.997614)
					(end 450.152516 -49.927764)
				)
				(xy 450.32422 -49.927764) (xy 450.49059 -50.094134) (xy 450.49059 -50.381154) (xy 450.59219 -50.381154)
				(xy 450.59219 -50.082958) (xy 450.747384 -49.927764)
			)
		)
	)
	(zone
		(layer "B.Cu")
		(hatch none 0.5)
		(connect_pads
			(clearance 0)
		)
		(min_thickness 0.25)
		(keepout
			(tracks allowed)
			(vias allowed)
			(pads allowed)
			(copperpour allowed)
			(footprints allowed)
		)
		(placement
			(enabled no)
			(sheetname "")
		)
		(fill
			(thermal_gap 0.5)
			(thermal_bridge_width 0.5)
			(island_removal_mode 0)
		)
		(polygon
			(pts
				(xy 25.019 -79.756) (xy 25.019 -78.486) (xy 26.162 -78.486) (xy 26.162 -79.756)
			)
		)
	)
	(zone
		(layer "B.Cu")
		(hatch none 0.5)
		(connect_pads
			(clearance 0)
		)
		(min_thickness 0.25)
		(keepout
			(tracks not_allowed)
			(vias allowed)
			(pads allowed)
			(copperpour not_allowed)
			(footprints allowed)
		)
		(placement
			(enabled no)
			(sheetname "")
		)
		(fill
			(thermal_gap 0.5)
			(thermal_bridge_width 0.5)
			(island_removal_mode 0)
		)
		(polygon
			(pts
				(arc
					(start 294.589962 -111.550196)
					(mid 289.410394 -111.550196)
					(end 294.589962 -111.550196)
				)
			)
		)
	)
	(zone
		(net "VR_FET_SW_P12V_STBY_PVDDQ_DEF")
		(layer "B.Cu")
		(hatch none 0.5)
		(connect_pads
			(clearance 0.5)
		)
		(min_thickness 0.25)
		(fill yes
			(thermal_gap 0.5)
			(thermal_bridge_width 0.5)
			(island_removal_mode 0)
		)
		(polygon
			(pts
				(xy 385.735322 -155.617418) (xy 386.169662 -156.051758) (xy 387.849618 -156.051758) (xy 388.07136 -156.2735)
				(xy 388.112 -156.31414) (xy 388.112 -157.621732) (xy 388.275068 -157.7848) (xy 389.74776 -157.7848)
				(xy 389.9916 -157.54096) (xy 389.9916 -153.416) (xy 389.89 -153.3144) (xy 389.4074 -153.3144) (xy 389.001 -153.7208)
				(xy 389.001 -154.051) (xy 388.8232 -154.2288) (xy 384.0861 -154.2288) (xy 384.0099 -154.305) (xy 384.0099 -154.9908)
				(xy 384.12674 -155.10764) (xy 385.4958 -155.10764) (xy 385.735322 -155.347162)
			)
		)
	)
	(zone
		(layer "B.Cu")
		(hatch none 0.5)
		(connect_pads
			(clearance 0)
		)
		(min_thickness 0.25)
		(keepout
			(tracks not_allowed)
			(vias allowed)
			(pads allowed)
			(copperpour not_allowed)
			(footprints allowed)
		)
		(placement
			(enabled no)
			(sheetname "")
		)
		(fill
			(thermal_gap 0.5)
			(thermal_bridge_width 0.5)
			(island_removal_mode 0)
		)
		(polygon
			(pts
				(xy 455.994008 -114.333782) (xy 456.149202 -114.488976) (xy 456.149202 -114.787172) (xy 456.250802 -114.787172)
				(xy 456.250802 -114.488976) (xy 456.405996 -114.333782)
				(arc
					(start 456.5777 -114.333782)
					(mid 457.101617 -114.403632)
					(end 456.5777 -114.473482)
				)
				(xy 456.463908 -114.473482) (xy 456.390502 -114.546888) (xy 456.390502 -114.787172)
				(arc
					(start 456.835002 -114.787172)
					(mid 457.218542 -114.403632)
					(end 456.835002 -114.020092)
				)
				(arc
					(start 455.565256 -114.020092)
					(mid 455.181462 -114.403505)
					(end 455.565002 -114.787172)
				)
				(xy 456.009502 -114.787172) (xy 456.009502 -114.546888) (xy 455.936096 -114.473482)
				(arc
					(start 455.822304 -114.473482)
					(mid 455.298387 -114.403632)
					(end 455.822304 -114.333782)
				)
			)
		)
	)
	(zone
		(layer "B.Cu")
		(hatch none 0.5)
		(connect_pads
			(clearance 0)
		)
		(min_thickness 0.25)
		(keepout
			(tracks not_allowed)
			(vias allowed)
			(pads allowed)
			(copperpour not_allowed)
			(footprints allowed)
		)
		(placement
			(enabled no)
			(sheetname "")
		)
		(fill
			(thermal_gap 0.5)
			(thermal_bridge_width 0.5)
			(island_removal_mode 0)
		)
		(polygon
			(pts
				(xy 448.97675 -123.40463) (xy 448.97675 -123.702826) (xy 448.821556 -123.85802)
				(arc
					(start 448.649852 -123.85802)
					(mid 448.125935 -123.78817)
					(end 448.649852 -123.71832)
				)
				(xy 448.763644 -123.71832) (xy 448.83705 -123.644914) (xy 448.83705 -123.40463)
				(arc
					(start 448.392804 -123.40463)
					(mid 448.00901 -123.788043)
					(end 448.39255 -124.17171)
				)
				(arc
					(start 449.66255 -124.17171)
					(mid 450.04609 -123.78817)
					(end 449.66255 -123.40463)
				)
				(xy 449.21805 -123.40463) (xy 449.21805 -123.644914) (xy 449.291456 -123.71832)
				(arc
					(start 449.405248 -123.71832)
					(mid 449.929165 -123.78817)
					(end 449.405248 -123.85802)
				)
				(xy 449.233544 -123.85802) (xy 449.07835 -123.702826) (xy 449.07835 -123.40463)
			)
		)
	)
	(zone
		(layer "B.Cu")
		(hatch none 0.5)
		(connect_pads
			(clearance 0)
		)
		(min_thickness 0.25)
		(keepout
			(tracks allowed)
			(vias allowed)
			(pads allowed)
			(copperpour allowed)
			(footprints not_allowed)
		)
		(placement
			(enabled no)
			(sheetname "")
		)
		(fill
			(thermal_gap 0.5)
			(thermal_bridge_width 0.5)
			(island_removal_mode 0)
		)
		(polygon
			(pts
				(arc
					(start 318.000126 -96.650048)
					(mid 316.100206 -98.549968)
					(end 318.000126 -100.449888)
				)
				(arc
					(start 318.000126 -100.449888)
					(mid 319.900046 -98.549968)
					(end 318.000126 -96.650048)
				)
			)
		)
	)
	(zone
		(net "VR_FET_SW_P12V_STBY_PVPP_KLM")
		(layer "B.Cu")
		(hatch none 0.5)
		(connect_pads
			(clearance 0.5)
		)
		(min_thickness 0.25)
		(fill yes
			(thermal_gap 0.5)
			(thermal_bridge_width 0.5)
			(island_removal_mode 0)
		)
		(polygon
			(pts
				(xy 177.9143 -136.2075) (xy 181.61 -136.2075) (xy 182.2323 -136.2075) (xy 182.499 -136.4742) (xy 182.499 -136.6774)
				(xy 182.7276 -136.906) (xy 187.1218 -136.906) (xy 187.325 -136.7028) (xy 187.325 -135.509) (xy 187.1218 -135.3058)
				(xy 184.0484 -135.3058) (xy 183.9722 -135.3058) (xy 183.8706 -135.2042) (xy 183.8706 -132.2324)
				(xy 183.8706 -132.111242) (xy 183.712358 -131.953) (xy 182.118 -131.953) (xy 180.467 -131.953) (xy 179.324 -131.953)
				(xy 178.816 -132.461) (xy 178.816 -132.9944) (xy 178.816 -133.1595) (xy 178.816 -134.5565) (xy 178.689 -134.6835)
				(xy 177.8762 -134.6835) (xy 177.8 -134.7597) (xy 177.8 -136.0932)
			)
		)
	)
	(zone
		(layer "B.Cu")
		(hatch none 0.5)
		(connect_pads
			(clearance 0)
		)
		(min_thickness 0.25)
		(keepout
			(tracks not_allowed)
			(vias allowed)
			(pads allowed)
			(copperpour not_allowed)
			(footprints allowed)
		)
		(placement
			(enabled no)
			(sheetname "")
		)
		(fill
			(thermal_gap 0.5)
			(thermal_bridge_width 0.5)
			(island_removal_mode 0)
		)
		(polygon
			(pts
				(arc
					(start 318.000126 -96.009968)
					(mid 315.460126 -98.549968)
					(end 318.000126 -101.089968)
				)
				(arc
					(start 318.000126 -101.089968)
					(mid 320.540126 -98.549968)
					(end 318.000126 -96.009968)
				)
			)
		)
	)
	(zone
		(layer "B.Cu")
		(hatch none 0.5)
		(connect_pads
			(clearance 0)
		)
		(min_thickness 0.25)
		(keepout
			(tracks allowed)
			(vias allowed)
			(pads allowed)
			(copperpour allowed)
			(footprints allowed)
		)
		(placement
			(enabled no)
			(sheetname "")
		)
		(fill
			(thermal_gap 0.5)
			(thermal_bridge_width 0.5)
			(island_removal_mode 0)
		)
		(polygon
			(pts
				(xy 161.798 -98.298) (xy 161.798 -97.536) (xy 162.56 -97.536) (xy 162.56 -98.298)
			)
		)
	)
	(zone
		(net "PVDDQ_KLM")
		(layer "B.Cu")
		(hatch none 0.5)
		(connect_pads
			(clearance 0.5)
		)
		(min_thickness 0.25)
		(fill yes
			(thermal_gap 0.5)
			(thermal_bridge_width 0.5)
			(island_removal_mode 0)
		)
		(polygon
			(pts
				(xy 107.56519 -138.955272) (xy 107.475274 -139.045188) (xy 107.475274 -139.34948) (xy 107.062016 -139.762738)
				(xy 101.181408 -139.762738) (xy 100.677726 -140.26642) (xy 100.677726 -141.086332) (xy 100.978716 -141.387322)
				(xy 112.326166 -141.387322) (xy 112.528604 -141.184884) (xy 112.528604 -139.029694) (xy 112.454182 -138.955272)
			)
		)
	)
	(zone
		(net "GND")
		(layer "B.Cu")
		(hatch none 0.5)
		(connect_pads
			(clearance 0.5)
		)
		(min_thickness 0.25)
		(fill yes
			(thermal_gap 0.5)
			(thermal_bridge_width 0.5)
			(island_removal_mode 0)
		)
		(polygon
			(pts
				(xy 371.467888 -101.899974) (xy 371.404642 -101.96322) (xy 371.40134 -101.96322) (xy 371.08384 -102.280466)
				(xy 371.08384 -105.45064) (xy 371.3988 -105.7656) (xy 374.053608 -105.7656) (xy 374.353328 -105.46588)
				(xy 374.353328 -103.45293) (xy 373.845328 -102.94493) (xy 373.845328 -102.052628) (xy 373.69242 -101.899974)
			)
		)
		(polygon
			(pts
				(xy 372.11 -105.156) (xy 371.9068 -105.156) (xy 371.9068 -105.3592) (xy 372.11 -105.3592)
			)
		)
		(polygon
			(pts
				(xy 372.11 -104.394) (xy 371.9068 -104.394) (xy 371.9068 -104.5972) (xy 372.11 -104.5972)
			)
		)
		(polygon
			(pts
				(xy 372.11 -103.886) (xy 371.9068 -103.886) (xy 371.9068 -104.0892) (xy 372.11 -104.0892)
			)
		)
	)
	(zone
		(layer "B.Cu")
		(hatch none 0.5)
		(connect_pads
			(clearance 0)
		)
		(min_thickness 0.25)
		(keepout
			(tracks allowed)
			(vias allowed)
			(pads allowed)
			(copperpour allowed)
			(footprints not_allowed)
		)
		(placement
			(enabled no)
			(sheetname "")
		)
		(fill
			(thermal_gap 0.5)
			(thermal_bridge_width 0.5)
			(island_removal_mode 0)
		)
		(polygon
			(pts
				(arc
					(start 171.99991 -151.100028)
					(mid 171.904887 -151.101187)
					(end 171.809918 -151.1046)
				)
				(xy 171.809918 -127.364998) (xy 179.23002 -127.364998)
				(arc
					(start 179.23002 -153.655268)
					(mid 177.760683 -151.800083)
					(end 175.50003 -151.100028)
				)
			)
		)
	)
	(zone
		(layer "B.Cu")
		(hatch none 0.5)
		(connect_pads
			(clearance 0)
		)
		(min_thickness 0.25)
		(keepout
			(tracks not_allowed)
			(vias allowed)
			(pads allowed)
			(copperpour not_allowed)
			(footprints allowed)
		)
		(placement
			(enabled no)
			(sheetname "")
		)
		(fill
			(thermal_gap 0.5)
			(thermal_bridge_width 0.5)
			(island_removal_mode 0)
		)
		(polygon
			(pts
				(arc
					(start 341.523066 -67.963542)
					(mid 341.103095 -68.284707)
					(end 341.42426 -67.864736)
				)
				(xy 341.576406 -67.71259)
				(arc
					(start 341.291672 -67.71259)
					(mid 340.908132 -68.09613)
					(end 341.291672 -68.47967)
				)
				(arc
					(start 342.256618 -68.47967)
					(mid 342.640412 -68.096257)
					(end 342.256872 -67.71259)
				)
				(xy 341.972138 -67.71259)
				(arc
					(start 342.124284 -67.864736)
					(mid 342.445449 -68.284707)
					(end 342.025478 -67.963542)
				)
				(xy 341.82812 -67.766184) (xy 341.82812 -67.71259) (xy 341.72652 -67.71259) (xy 341.72652 -67.760088)
			)
		)
	)
	(zone
		(net "GND")
		(layer "B.Cu")
		(hatch none 0.5)
		(connect_pads
			(clearance 0.5)
		)
		(min_thickness 0.25)
		(fill yes
			(thermal_gap 0.5)
			(thermal_bridge_width 0.5)
			(island_removal_mode 0)
		)
		(polygon
			(pts
				(xy 485.6734 -110.5408) (xy 485.5464 -110.4138) (xy 484.3018 -110.4138) (xy 484.1494 -110.5662)
				(xy 484.1494 -112.522) (xy 484.3272 -112.6998) (xy 484.3272 -113.9698) (xy 484.505 -114.1476) (xy 485.4956 -114.1476)
				(xy 485.6734 -113.9698)
			)
		)
	)
	(zone
		(layer "B.Cu")
		(hatch none 0.5)
		(connect_pads
			(clearance 0)
		)
		(min_thickness 0.25)
		(keepout
			(tracks not_allowed)
			(vias allowed)
			(pads allowed)
			(copperpour not_allowed)
			(footprints allowed)
		)
		(placement
			(enabled no)
			(sheetname "")
		)
		(fill
			(thermal_gap 0.5)
			(thermal_bridge_width 0.5)
			(island_removal_mode 0)
		)
		(polygon
			(pts
				(xy 16.611092 -38.090602) (xy 16.611092 -38.388798) (xy 16.455898 -38.543992)
				(arc
					(start 16.284194 -38.543992)
					(mid 15.760277 -38.474142)
					(end 16.284194 -38.404292)
				)
				(xy 16.397986 -38.404292) (xy 16.471392 -38.330886) (xy 16.471392 -38.090602)
				(arc
					(start 16.026892 -38.090602)
					(mid 15.643352 -38.474142)
					(end 16.026892 -38.857682)
				)
				(arc
					(start 17.296638 -38.857682)
					(mid 17.680432 -38.474269)
					(end 17.296892 -38.090602)
				)
				(xy 16.852392 -38.090602) (xy 16.852392 -38.330886) (xy 16.925798 -38.404292)
				(arc
					(start 17.03959 -38.404292)
					(mid 17.563507 -38.474142)
					(end 17.03959 -38.543992)
				)
				(xy 16.867886 -38.543992) (xy 16.712692 -38.388798) (xy 16.712692 -38.090602)
			)
		)
	)
	(zone
		(layer "B.Cu")
		(hatch none 0.5)
		(connect_pads
			(clearance 0)
		)
		(min_thickness 0.25)
		(keepout
			(tracks not_allowed)
			(vias allowed)
			(pads allowed)
			(copperpour not_allowed)
			(footprints allowed)
		)
		(placement
			(enabled no)
			(sheetname "")
		)
		(fill
			(thermal_gap 0.5)
			(thermal_bridge_width 0.5)
			(island_removal_mode 0)
		)
		(polygon
			(pts
				(arc
					(start 426.630592 -9.639808)
					(mid 426.247052 -10.023348)
					(end 426.630592 -10.406888)
				)
				(arc
					(start 427.900338 -10.406888)
					(mid 428.170806 -10.295538)
					(end 428.284132 -10.025888)
				)
				(arc
					(start 428.167292 -10.025888)
					(mid 427.900592 -10.29006)
					(end 427.633892 -10.025888)
				)
				(arc
					(start 426.948092 -10.025888)
					(mid 426.630592 -10.340858)
					(end 426.313092 -10.025888)
				)
				(arc
					(start 426.313092 -10.023348)
					(mid 426.630592 -9.705848)
					(end 426.948092 -10.023348)
				)
				(arc
					(start 427.633892 -10.023348)
					(mid 427.900592 -9.756648)
					(end 428.167292 -10.023348)
				)
				(arc
					(start 428.284132 -10.023348)
					(mid 428.171796 -9.752144)
					(end 427.900592 -9.639808)
				)
			)
		)
	)
	(zone
		(layer "B.Cu")
		(hatch none 0.5)
		(connect_pads
			(clearance 0)
		)
		(min_thickness 0.25)
		(keepout
			(tracks not_allowed)
			(vias allowed)
			(pads allowed)
			(copperpour not_allowed)
			(footprints allowed)
		)
		(placement
			(enabled no)
			(sheetname "")
		)
		(fill
			(thermal_gap 0.5)
			(thermal_bridge_width 0.5)
			(island_removal_mode 0)
		)
		(polygon
			(pts
				(xy 456.7428 -51.848258) (xy 456.2348 -51.848258) (xy 456.2348 -52.229258) (xy 456.7428 -52.229258)
			)
		)
	)
	(zone
		(net "GND")
		(layer "B.Cu")
		(hatch none 0.5)
		(connect_pads
			(clearance 0.5)
		)
		(min_thickness 0.25)
		(fill yes
			(thermal_gap 0.5)
			(thermal_bridge_width 0.5)
			(island_removal_mode 0)
		)
		(polygon
			(pts
				(xy 181.111398 -0.368808) (xy 180.958998 -0.521208) (xy 180.958998 -3.362198) (xy 181.102 -3.5052)
				(xy 182.131208 -3.5052) (xy 183.3118 -2.324608) (xy 186.244992 -2.324608) (xy 186.318398 -2.251202)
				(xy 186.318398 -0.927608) (xy 186.216798 -0.826008) (xy 183.299608 -0.826008) (xy 182.842408 -0.368808)
			)
		)
		(polygon
			(pts
				(xy 182.0799 -2.5146) (xy 181.8767 -2.5146) (xy 181.8767 -2.7178) (xy 182.0799 -2.7178)
			)
		)
		(polygon
			(pts
				(xy 181.3179 -2.5146) (xy 181.1147 -2.5146) (xy 181.1147 -2.7178) (xy 181.3179 -2.7178)
			)
		)
		(polygon
			(pts
				(xy 185.73369 -1.600708) (xy 185.53049 -1.600708) (xy 185.53049 -1.803908) (xy 185.73369 -1.803908)
			)
		)
		(polygon
			(pts
				(xy 184.97169 -1.600708) (xy 184.76849 -1.600708) (xy 184.76849 -1.803908) (xy 184.97169 -1.803908)
			)
		)
		(polygon
			(pts
				(xy 184.15889 -1.600708) (xy 183.95569 -1.600708) (xy 183.95569 -1.803908) (xy 184.15889 -1.803908)
			)
		)
		(polygon
			(pts
				(xy 183.39689 -1.600708) (xy 183.19369 -1.600708) (xy 183.19369 -1.803908) (xy 183.39689 -1.803908)
			)
		)
	)
	(zone
		(net "P12V_STBY")
		(layer "B.Cu")
		(hatch none 0.5)
		(connect_pads
			(clearance 0.5)
		)
		(min_thickness 0.25)
		(fill yes
			(thermal_gap 0.5)
			(thermal_bridge_width 0.5)
			(island_removal_mode 0)
		)
		(polygon
			(pts
				(xy 23.305008 -124.397008) (xy 25.2476 -126.3396) (xy 25.2476 -127.1778) (xy 25.019 -127.4064) (xy 21.7424 -127.4064)
				(xy 20.5232 -126.1872) (xy 17.8054 -126.1872) (xy 17.4498 -126.1872) (xy 17.1196 -125.857) (xy 17.1196 -123.376944)
				(xy 17.308576 -123.187968) (xy 20.142962 -123.187968)
			)
		)
	)
	(zone
		(layer "B.Cu")
		(hatch none 0.5)
		(connect_pads
			(clearance 0)
		)
		(min_thickness 0.25)
		(keepout
			(tracks allowed)
			(vias allowed)
			(pads allowed)
			(copperpour allowed)
			(footprints allowed)
		)
		(placement
			(enabled no)
			(sheetname "")
		)
		(fill
			(thermal_gap 0.5)
			(thermal_bridge_width 0.5)
			(island_removal_mode 0)
		)
		(polygon
			(pts
				(xy 366.903 -110.871) (xy 366.903 -109.601) (xy 368.6048 -109.601) (xy 368.6048 -110.871)
			)
		)
	)
	(zone
		(layer "B.Cu")
		(hatch none 0.5)
		(connect_pads
			(clearance 0)
		)
		(min_thickness 0.25)
		(keepout
			(tracks not_allowed)
			(vias allowed)
			(pads allowed)
			(copperpour not_allowed)
			(footprints allowed)
		)
		(placement
			(enabled no)
			(sheetname "")
		)
		(fill
			(thermal_gap 0.5)
			(thermal_bridge_width 0.5)
			(island_removal_mode 0)
		)
		(polygon
			(pts
				(arc
					(start 444.517526 -49.928272)
					(mid 445.041443 -49.998122)
					(end 444.517526 -50.067972)
				)
				(xy 444.39332 -50.067972) (xy 444.298324 -50.162968) (xy 444.298324 -50.381662)
				(arc
					(start 444.774574 -50.381662)
					(mid 445.158114 -49.998249)
					(end 444.774828 -49.614582)
				)
				(arc
					(start 443.504828 -49.614582)
					(mid 443.121288 -49.998122)
					(end 443.504828 -50.381662)
				)
				(xy 443.917324 -50.381662) (xy 443.917324 -50.141378) (xy 443.843918 -50.067972)
				(arc
					(start 443.76213 -50.067972)
					(mid 443.238213 -49.998122)
					(end 443.76213 -49.928272)
				)
				(xy 443.90183 -49.928272) (xy 444.057024 -50.083466) (xy 444.057024 -50.381662) (xy 444.158624 -50.381662)
				(xy 444.158624 -50.105056) (xy 444.335408 -49.928272)
			)
		)
	)
	(zone
		(layer "B.Cu")
		(hatch none 0.5)
		(connect_pads
			(clearance 0)
		)
		(min_thickness 0.25)
		(keepout
			(tracks allowed)
			(vias allowed)
			(pads allowed)
			(copperpour allowed)
			(footprints allowed)
		)
		(placement
			(enabled no)
			(sheetname "")
		)
		(fill
			(thermal_gap 0.5)
			(thermal_bridge_width 0.5)
			(island_removal_mode 0)
		)
		(polygon
			(pts
				(xy 363.0549 -115.1128) (xy 363.0549 -113.8428) (xy 364.7567 -113.8428) (xy 364.7567 -115.1128)
			)
		)
	)
	(zone
		(layer "B.Cu")
		(hatch none 0.5)
		(connect_pads
			(clearance 0)
		)
		(min_thickness 0.25)
		(keepout
			(tracks allowed)
			(vias allowed)
			(pads allowed)
			(copperpour allowed)
			(footprints not_allowed)
		)
		(placement
			(enabled no)
			(sheetname "")
		)
		(fill
			(thermal_gap 0.5)
			(thermal_bridge_width 0.5)
			(island_removal_mode 0)
		)
		(polygon
			(pts
				(arc
					(start 173.928532 0.055626)
					(mid 173.338136 0.385683)
					(end 172.671486 0.500126)
				)
				(arc
					(start 171.99991 0.500126)
					(mid 170.499786 2.00025)
					(end 171.99991 3.50012)
				)
				(arc
					(start 172.671486 3.50012)
					(mid 173.338113 3.614414)
					(end 173.928532 3.944366)
				)
				(arc
					(start 173.928532 3.944366)
					(mid 177.999652 1.999996)
					(end 173.928532 0.055626)
				)
			)
		)
	)
	(zone
		(net "P3V3_DB1200")
		(layer "B.Cu")
		(hatch none 0.5)
		(connect_pads
			(clearance 0.5)
		)
		(min_thickness 0.25)
		(fill yes
			(thermal_gap 0.5)
			(thermal_bridge_width 0.5)
			(island_removal_mode 0)
		)
		(polygon
			(pts
				(xy 167.5765 -71.1581) (xy 167.54221 -71.19239) (xy 165.70071 -71.19239) (xy 163.99256 -72.90054)
				(xy 163.99256 -74.16546) (xy 164.0459 -74.2188) (xy 160.634934 -74.2188) (xy 160.39973 -74.454004)
				(xy 160.39973 -75.3618) (xy 160.65373 -75.6158) (xy 163.449 -75.6158) (xy 164.1094 -76.2762) (xy 164.1094 -85.471)
				(xy 164.465 -85.8266) (xy 168.0464 -85.8266) (xy 168.6306 -86.4108) (xy 174.4472 -86.4108) (xy 174.869094 -85.988906)
				(xy 174.869094 -80.578706) (xy 175.387 -80.0608) (xy 175.387 -78.867) (xy 175.26 -78.74) (xy 174.752 -78.74)
				(xy 174.498 -78.486) (xy 174.498 -77.5208) (xy 174.8028 -77.216) (xy 174.8028 -75.3999) (xy 175.02378 -75.17892)
				(xy 176.14646 -75.17892) (xy 177.02022 -74.30516) (xy 177.02022 -73.1774) (xy 176.02962 -72.1868)
				(xy 173.41342 -72.1868) (xy 172.38472 -71.1581)
			)
		)
		(polygon
			(pts
				(xy 173.2788 -77.5208) (xy 165.862 -77.5208) (xy 165.227 -78.1558) (xy 165.227 -84.963) (xy 165.5572 -85.2932)
				(xy 168.3258 -85.2932) (xy 168.5036 -85.1154) (xy 171.9834 -85.1154) (xy 172.212 -85.344) (xy 173.101 -85.344)
				(xy 173.609 -84.836) (xy 173.609 -77.851)
			)
		)
		(polygon
			(pts
				(xy 170.0276 -72.9361) (xy 169.8244 -72.9361) (xy 169.8244 -73.1393) (xy 170.0276 -73.1393)
			)
		)
		(polygon
			(pts
				(xy 169.2656 -72.9361) (xy 169.0624 -72.9361) (xy 169.0624 -73.1393) (xy 169.2656 -73.1393)
			)
		)
	)
	(zone
		(layer "B.Cu")
		(hatch none 0.5)
		(connect_pads
			(clearance 0)
		)
		(min_thickness 0.25)
		(keepout
			(tracks not_allowed)
			(vias allowed)
			(pads allowed)
			(copperpour not_allowed)
			(footprints allowed)
		)
		(placement
			(enabled no)
			(sheetname "")
		)
		(fill
			(thermal_gap 0.5)
			(thermal_bridge_width 0.5)
			(island_removal_mode 0)
		)
		(polygon
			(pts
				(arc
					(start 127 -44.090082)
					(mid 129.54 -41.550082)
					(end 127 -39.010082)
				)
				(arc
					(start 127 -39.010082)
					(mid 124.46 -41.550082)
					(end 127 -44.090082)
				)
			)
		)
	)
	(zone
		(net "GND")
		(layer "B.Cu")
		(hatch none 0.5)
		(connect_pads
			(clearance 0.5)
		)
		(min_thickness 0.25)
		(fill yes
			(thermal_gap 0.5)
			(thermal_bridge_width 0.5)
			(island_removal_mode 0)
		)
		(polygon
			(pts
				(xy 115.488466 -146.261836) (xy 113.67008 -146.261836) (xy 113.46942 -146.061176) (xy 113.46942 -143.848074)
				(xy 113.67643 -143.641064) (xy 115.462812 -143.641064) (xy 115.70843 -143.886682) (xy 115.70843 -146.041872)
			)
		)
	)
	(zone
		(layer "B.Cu")
		(hatch none 0.5)
		(connect_pads
			(clearance 0)
		)
		(min_thickness 0.25)
		(keepout
			(tracks not_allowed)
			(vias allowed)
			(pads allowed)
			(copperpour not_allowed)
			(footprints allowed)
		)
		(placement
			(enabled no)
			(sheetname "")
		)
		(fill
			(thermal_gap 0.5)
			(thermal_bridge_width 0.5)
			(island_removal_mode 0)
		)
		(polygon
			(pts
				(arc
					(start 396.01394 -33.988502)
					(mid 395.886339 -34.14906)
					(end 395.68247 -34.171636)
				)
				(xy 395.50086 -34.353246) (xy 395.50086 -34.703004)
				(arc
					(start 395.624812 -34.826956)
					(mid 395.858003 -34.811365)
					(end 396.01394 -34.985452)
				)
			)
		)
	)
	(zone
		(layer "B.Cu")
		(hatch none 0.5)
		(connect_pads
			(clearance 0)
		)
		(min_thickness 0.25)
		(keepout
			(tracks allowed)
			(vias allowed)
			(pads allowed)
			(copperpour allowed)
			(footprints allowed)
		)
		(placement
			(enabled no)
			(sheetname "")
		)
		(fill
			(thermal_gap 0.5)
			(thermal_bridge_width 0.5)
			(island_removal_mode 0)
		)
		(polygon
			(pts
				(xy 475.2086 -10.8204) (xy 477.1898 -10.8204) (xy 477.1898 -12.3952) (xy 475.2086 -12.3952)
			)
		)
	)
	(zone
		(layer "B.Cu")
		(hatch none 0.5)
		(connect_pads
			(clearance 0)
		)
		(min_thickness 0.25)
		(keepout
			(tracks not_allowed)
			(vias allowed)
			(pads allowed)
			(copperpour not_allowed)
			(footprints allowed)
		)
		(placement
			(enabled no)
			(sheetname "")
		)
		(fill
			(thermal_gap 0.5)
			(thermal_bridge_width 0.5)
			(island_removal_mode 0)
		)
		(polygon
			(pts
				(arc
					(start 318.000126 -52.010056)
					(mid 315.460126 -54.550056)
					(end 318.000126 -57.090056)
				)
				(arc
					(start 318.000126 -57.090056)
					(mid 320.540126 -54.550056)
					(end 318.000126 -52.010056)
				)
			)
		)
	)
	(zone
		(layer "B.Cu")
		(hatch none 0.5)
		(connect_pads
			(clearance 0)
		)
		(min_thickness 0.25)
		(keepout
			(tracks allowed)
			(vias allowed)
			(pads allowed)
			(copperpour allowed)
			(footprints not_allowed)
		)
		(placement
			(enabled no)
			(sheetname "")
		)
		(fill
			(thermal_gap 0.5)
			(thermal_bridge_width 0.5)
			(island_removal_mode 0)
		)
		(polygon
			(pts
				(arc
					(start 3.50012 -4.750054)
					(mid 8.250174 0)
					(end 3.50012 4.750054)
				)
				(arc
					(start 0 4.750054)
					(mid -4.750054 0)
					(end 0 -4.750054)
				)
			)
		)
	)
	(zone
		(layers "B.Cu" "In1.Cu" "In2.Cu" "In3.Cu" "In4.Cu" "In5.Cu" "In6.Cu" "In7.Cu"
			"In8.Cu" "In9.Cu" "In10.Cu" "In11.Cu" "In12.Cu"
		)
		(hatch none 0.5)
		(connect_pads
			(clearance 0)
		)
		(min_thickness 0.25)
		(keepout
			(tracks not_allowed)
			(vias allowed)
			(pads allowed)
			(copperpour not_allowed)
			(footprints allowed)
		)
		(placement
			(enabled no)
			(sheetname "")
		)
		(fill yes
			(thermal_gap 0.5)
			(thermal_bridge_width 0.5)
			(island_removal_mode 0)
		)
		(polygon
			(pts
				(arc
					(start 382.77419 -129.32283)
					(mid 382.39319 -129.70383)
					(end 382.77419 -130.08483)
				)
				(arc
					(start 383.43459 -130.08483)
					(mid 383.81559 -129.70383)
					(end 383.43459 -129.32283)
				)
			)
		)
	)
	(zone
		(layers "B.Cu" "In1.Cu" "In2.Cu" "In3.Cu" "In4.Cu" "In5.Cu" "In6.Cu" "In7.Cu"
			"In8.Cu" "In9.Cu" "In10.Cu" "In11.Cu" "In12.Cu"
		)
		(hatch none 0.5)
		(connect_pads
			(clearance 0)
		)
		(min_thickness 0.25)
		(keepout
			(tracks not_allowed)
			(vias allowed)
			(pads allowed)
			(copperpour not_allowed)
			(footprints allowed)
		)
		(placement
			(enabled no)
			(sheetname "")
		)
		(fill yes
			(thermal_gap 0.5)
			(thermal_bridge_width 0.5)
			(island_removal_mode 0)
		)
		(polygon
			(pts
				(arc
					(start 388.112 -127.3302)
					(mid 387.731 -126.9492)
					(end 387.35 -127.3302)
				)
				(arc
					(start 387.35 -127.9652)
					(mid 387.731 -128.3462)
					(end 388.112 -127.9652)
				)
			)
		)
	)
	(zone
		(layers "B.Cu" "In1.Cu" "In2.Cu" "In3.Cu" "In4.Cu" "In5.Cu" "In6.Cu" "In7.Cu"
			"In8.Cu" "In9.Cu" "In10.Cu" "In11.Cu" "In12.Cu"
		)
		(hatch none 0.5)
		(connect_pads
			(clearance 0)
		)
		(min_thickness 0.25)
		(keepout
			(tracks not_allowed)
			(vias allowed)
			(pads allowed)
			(copperpour not_allowed)
			(footprints allowed)
		)
		(placement
			(enabled no)
			(sheetname "")
		)
		(fill yes
			(thermal_gap 0.5)
			(thermal_bridge_width 0.5)
			(island_removal_mode 0)
		)
		(polygon
			(pts
				(arc
					(start 383.191004 -127.390652)
					(mid 382.810004 -127.771652)
					(end 383.191004 -128.152652)
				)
				(arc
					(start 383.826004 -128.152652)
					(mid 384.207004 -127.771652)
					(end 383.826004 -127.390652)
				)
			)
		)
	)
	(zone
		(layers "B.Cu" "In1.Cu" "In2.Cu" "In3.Cu" "In4.Cu" "In5.Cu" "In6.Cu" "In7.Cu"
			"In8.Cu" "In9.Cu" "In10.Cu" "In12.Cu"
		)
		(hatch none 0.5)
		(connect_pads
			(clearance 0)
		)
		(min_thickness 0.25)
		(keepout
			(tracks not_allowed)
			(vias allowed)
			(pads allowed)
			(copperpour not_allowed)
			(footprints allowed)
		)
		(placement
			(enabled no)
			(sheetname "")
		)
		(fill yes
			(thermal_gap 0.5)
			(thermal_bridge_width 0.5)
			(island_removal_mode 0)
		)
		(polygon
			(pts
				(arc
					(start 441.172854 -123.50623)
					(mid 440.78906 -123.889643)
					(end 441.1726 -124.27331)
				)
				(arc
					(start 442.4426 -124.27331)
					(mid 442.712904 -124.16187)
					(end 442.82614 -123.89231)
				)
				(arc
					(start 442.7093 -123.89231)
					(mid 442.4426 -124.156482)
					(end 442.1759 -123.89231)
				)
				(arc
					(start 441.4393 -123.89231)
					(mid 441.1726 -124.156482)
					(end 440.9059 -123.89231)
				)
				(arc
					(start 440.9059 -123.88977)
					(mid 441.1726 -123.62307)
					(end 441.4393 -123.88977)
				)
				(arc
					(start 442.1759 -123.88977)
					(mid 442.4426 -123.62307)
					(end 442.7093 -123.88977)
				)
				(arc
					(start 442.82614 -123.88977)
					(mid 442.713804 -123.618566)
					(end 442.4426 -123.50623)
				)
			)
		)
	)
	(zone
		(layers "B.Cu" "In1.Cu" "In2.Cu" "In3.Cu" "In4.Cu" "In5.Cu" "In6.Cu" "In7.Cu"
			"In8.Cu" "In9.Cu" "In10.Cu" "In12.Cu"
		)
		(hatch none 0.5)
		(connect_pads
			(clearance 0)
		)
		(min_thickness 0.25)
		(keepout
			(tracks not_allowed)
			(vias allowed)
			(pads allowed)
			(copperpour not_allowed)
			(footprints allowed)
		)
		(placement
			(enabled no)
			(sheetname "")
		)
		(fill yes
			(thermal_gap 0.5)
			(thermal_bridge_width 0.5)
			(island_removal_mode 0)
		)
		(polygon
			(pts
				(arc
					(start 463.625692 -120.755918)
					(mid 463.241898 -121.139331)
					(end 463.625438 -121.522998)
				)
				(arc
					(start 464.811618 -121.522998)
					(mid 465.081922 -121.411558)
					(end 465.195158 -121.141998)
				)
				(arc
					(start 465.078318 -121.141998)
					(mid 464.811618 -121.40617)
					(end 464.544918 -121.141998)
				)
				(arc
					(start 463.892138 -121.141998)
					(mid 463.625438 -121.40617)
					(end 463.358738 -121.141998)
				)
				(arc
					(start 463.358738 -121.139458)
					(mid 463.625438 -120.872758)
					(end 463.892138 -121.139458)
				)
				(arc
					(start 464.544918 -121.139458)
					(mid 464.811618 -120.872758)
					(end 465.078318 -121.139458)
				)
				(arc
					(start 465.195158 -121.139458)
					(mid 465.082822 -120.868254)
					(end 464.811618 -120.755918)
				)
			)
		)
	)
	(zone
		(layers "B.Cu" "In1.Cu" "In2.Cu" "In3.Cu" "In4.Cu" "In5.Cu" "In6.Cu" "In7.Cu"
			"In8.Cu" "In9.Cu" "In10.Cu" "In12.Cu"
		)
		(hatch none 0.5)
		(connect_pads
			(clearance 0)
		)
		(min_thickness 0.25)
		(keepout
			(tracks not_allowed)
			(vias allowed)
			(pads allowed)
			(copperpour not_allowed)
			(footprints allowed)
		)
		(placement
			(enabled no)
			(sheetname "")
		)
		(fill yes
			(thermal_gap 0.5)
			(thermal_bridge_width 0.5)
			(island_removal_mode 0)
		)
		(polygon
			(pts
				(arc
					(start 447.472054 -120.43283)
					(mid 447.08826 -120.816243)
					(end 447.4718 -121.19991)
				)
				(arc
					(start 448.7418 -121.19991)
					(mid 449.012104 -121.08847)
					(end 449.12534 -120.81891)
				)
				(arc
					(start 449.0085 -120.81891)
					(mid 448.7418 -121.083082)
					(end 448.4751 -120.81891)
				)
				(arc
					(start 447.7385 -120.81891)
					(mid 447.4718 -121.083082)
					(end 447.2051 -120.81891)
				)
				(arc
					(start 447.2051 -120.81637)
					(mid 447.4718 -120.54967)
					(end 447.7385 -120.81637)
				)
				(arc
					(start 448.4751 -120.81637)
					(mid 448.7418 -120.54967)
					(end 449.0085 -120.81637)
				)
				(arc
					(start 449.12534 -120.81637)
					(mid 449.013004 -120.545166)
					(end 448.7418 -120.43283)
				)
			)
		)
	)
	(zone
		(layers "B.Cu" "In1.Cu" "In2.Cu" "In3.Cu" "In4.Cu" "In5.Cu" "In6.Cu" "In7.Cu"
			"In8.Cu" "In9.Cu" "In10.Cu" "In12.Cu"
		)
		(hatch none 0.5)
		(connect_pads
			(clearance 0)
		)
		(min_thickness 0.25)
		(keepout
			(tracks not_allowed)
			(vias allowed)
			(pads allowed)
			(copperpour not_allowed)
			(footprints allowed)
		)
		(placement
			(enabled no)
			(sheetname "")
		)
		(fill yes
			(thermal_gap 0.5)
			(thermal_bridge_width 0.5)
			(island_removal_mode 0)
		)
		(polygon
			(pts
				(arc
					(start 13.434314 -26.6065)
					(mid 13.050774 -26.22296)
					(end 12.667234 -26.6065)
				)
				(arc
					(start 12.667234 -27.8765)
					(mid 13.049504 -28.260038)
					(end 13.434314 -27.87904)
				)
				(arc
					(start 13.317474 -27.87904)
					(mid 13.050774 -28.143212)
					(end 12.784074 -27.87904)
				)
				(arc
					(start 12.784074 -27.8765)
					(mid 13.050774 -27.6098)
					(end 13.317474 -27.8765)
				)
				(xy 13.434314 -27.8765) (xy 13.434314 -26.60904)
				(arc
					(start 13.317474 -26.60904)
					(mid 13.050774 -26.873212)
					(end 12.784074 -26.60904)
				)
				(arc
					(start 12.784074 -26.6065)
					(mid 13.050774 -26.3398)
					(end 13.317474 -26.6065)
				)
			)
		)
	)
	(zone
		(layers "B.Cu" "In1.Cu" "In2.Cu" "In3.Cu" "In4.Cu" "In5.Cu" "In6.Cu" "In7.Cu"
			"In8.Cu" "In9.Cu" "In10.Cu" "In12.Cu"
		)
		(hatch none 0.5)
		(connect_pads
			(clearance 0)
		)
		(min_thickness 0.25)
		(keepout
			(tracks not_allowed)
			(vias allowed)
			(pads allowed)
			(copperpour not_allowed)
			(footprints allowed)
		)
		(placement
			(enabled no)
			(sheetname "")
		)
		(fill yes
			(thermal_gap 0.5)
			(thermal_bridge_width 0.5)
			(island_removal_mode 0)
		)
		(polygon
			(pts
				(arc
					(start 444.322454 -123.53163)
					(mid 443.93866 -123.915043)
					(end 444.3222 -124.29871)
				)
				(arc
					(start 445.5922 -124.29871)
					(mid 445.862504 -124.18727)
					(end 445.97574 -123.91771)
				)
				(arc
					(start 445.8589 -123.91771)
					(mid 445.5922 -124.181882)
					(end 445.3255 -123.91771)
				)
				(arc
					(start 444.5889 -123.91771)
					(mid 444.3222 -124.181882)
					(end 444.0555 -123.91771)
				)
				(arc
					(start 444.0555 -123.91517)
					(mid 444.3222 -123.64847)
					(end 444.5889 -123.91517)
				)
				(arc
					(start 445.3255 -123.91517)
					(mid 445.5922 -123.64847)
					(end 445.8589 -123.91517)
				)
				(arc
					(start 445.97574 -123.91517)
					(mid 445.863404 -123.643966)
					(end 445.5922 -123.53163)
				)
			)
		)
	)
	(zone
		(layers "B.Cu" "In1.Cu" "In2.Cu" "In3.Cu" "In4.Cu" "In5.Cu" "In6.Cu" "In7.Cu"
			"In8.Cu" "In9.Cu" "In10.Cu" "In12.Cu"
		)
		(hatch none 0.5)
		(connect_pads
			(clearance 0)
		)
		(min_thickness 0.25)
		(keepout
			(tracks not_allowed)
			(vias allowed)
			(pads allowed)
			(copperpour not_allowed)
			(footprints allowed)
		)
		(placement
			(enabled no)
			(sheetname "")
		)
		(fill yes
			(thermal_gap 0.5)
			(thermal_bridge_width 0.5)
			(island_removal_mode 0)
		)
		(polygon
			(pts
				(arc
					(start 454.653904 -121.35866)
					(mid 454.27011 -121.742073)
					(end 454.65365 -122.12574)
				)
				(arc
					(start 455.92365 -122.12574)
					(mid 456.193954 -122.0143)
					(end 456.30719 -121.74474)
				)
				(arc
					(start 456.19035 -121.74474)
					(mid 455.92365 -122.008912)
					(end 455.65695 -121.74474)
				)
				(arc
					(start 454.92035 -121.74474)
					(mid 454.65365 -122.008912)
					(end 454.38695 -121.74474)
				)
				(arc
					(start 454.38695 -121.7422)
					(mid 454.65365 -121.4755)
					(end 454.92035 -121.7422)
				)
				(arc
					(start 455.65695 -121.7422)
					(mid 455.92365 -121.4755)
					(end 456.19035 -121.7422)
				)
				(arc
					(start 456.30719 -121.7422)
					(mid 456.194854 -121.470996)
					(end 455.92365 -121.35866)
				)
			)
		)
	)
	(zone
		(layers "B.Cu" "In1.Cu" "In2.Cu" "In3.Cu" "In4.Cu" "In5.Cu" "In6.Cu" "In7.Cu"
			"In8.Cu" "In9.Cu" "In10.Cu" "In12.Cu"
		)
		(hatch none 0.5)
		(connect_pads
			(clearance 0)
		)
		(min_thickness 0.25)
		(keepout
			(tracks not_allowed)
			(vias allowed)
			(pads allowed)
			(copperpour not_allowed)
			(footprints allowed)
		)
		(placement
			(enabled no)
			(sheetname "")
		)
		(fill yes
			(thermal_gap 0.5)
			(thermal_bridge_width 0.5)
			(island_removal_mode 0)
		)
		(polygon
			(pts
				(arc
					(start 460.343504 -121.10974)
					(mid 459.95971 -121.493153)
					(end 460.34325 -121.87682)
				)
				(arc
					(start 461.61325 -121.87682)
					(mid 461.883554 -121.76538)
					(end 461.99679 -121.49582)
				)
				(arc
					(start 461.87995 -121.49582)
					(mid 461.61325 -121.759992)
					(end 461.34655 -121.49582)
				)
				(arc
					(start 460.60995 -121.49582)
					(mid 460.34325 -121.759992)
					(end 460.07655 -121.49582)
				)
				(arc
					(start 460.07655 -121.49328)
					(mid 460.34325 -121.22658)
					(end 460.60995 -121.49328)
				)
				(arc
					(start 461.34655 -121.49328)
					(mid 461.61325 -121.22658)
					(end 461.87995 -121.49328)
				)
				(arc
					(start 461.99679 -121.49328)
					(mid 461.884454 -121.222076)
					(end 461.61325 -121.10974)
				)
			)
		)
	)
	(zone
		(layers "B.Cu" "In1.Cu" "In2.Cu" "In3.Cu" "In4.Cu" "In5.Cu" "In6.Cu" "In7.Cu"
			"In8.Cu" "In9.Cu" "In10.Cu" "In12.Cu"
		)
		(hatch none 0.5)
		(connect_pads
			(clearance 0)
		)
		(min_thickness 0.25)
		(keepout
			(tracks not_allowed)
			(vias allowed)
			(pads allowed)
			(copperpour not_allowed)
			(footprints allowed)
		)
		(placement
			(enabled no)
			(sheetname "")
		)
		(fill yes
			(thermal_gap 0.5)
			(thermal_bridge_width 0.5)
			(island_removal_mode 0)
		)
		(polygon
			(pts
				(arc
					(start 12.29614 -28.3845)
					(mid 11.9126 -28.00096)
					(end 11.52906 -28.3845)
				)
				(arc
					(start 11.52906 -29.6545)
					(mid 11.91133 -30.038038)
					(end 12.29614 -29.65704)
				)
				(arc
					(start 12.1793 -29.65704)
					(mid 11.9126 -29.921212)
					(end 11.6459 -29.65704)
				)
				(arc
					(start 11.6459 -29.6545)
					(mid 11.9126 -29.3878)
					(end 12.1793 -29.6545)
				)
				(xy 12.29614 -29.6545) (xy 12.29614 -28.38704)
				(arc
					(start 12.1793 -28.38704)
					(mid 11.9126 -28.651212)
					(end 11.6459 -28.38704)
				)
				(arc
					(start 11.6459 -28.3845)
					(mid 11.9126 -28.1178)
					(end 12.1793 -28.3845)
				)
			)
		)
	)
	(zone
		(layers "B.Cu" "In1.Cu" "In2.Cu" "In3.Cu" "In4.Cu" "In5.Cu" "In6.Cu" "In7.Cu"
			"In8.Cu" "In9.Cu" "In10.Cu" "In12.Cu"
		)
		(hatch none 0.5)
		(connect_pads
			(clearance 0)
		)
		(min_thickness 0.25)
		(keepout
			(tracks not_allowed)
			(vias allowed)
			(pads allowed)
			(copperpour not_allowed)
			(footprints allowed)
		)
		(placement
			(enabled no)
			(sheetname "")
		)
		(fill yes
			(thermal_gap 0.5)
			(thermal_bridge_width 0.5)
			(island_removal_mode 0)
		)
		(polygon
			(pts
				(arc
					(start 450.672454 -120.28043)
					(mid 450.28866 -120.663843)
					(end 450.6722 -121.04751)
				)
				(arc
					(start 451.9422 -121.04751)
					(mid 452.212504 -120.93607)
					(end 452.32574 -120.66651)
				)
				(arc
					(start 452.2089 -120.66651)
					(mid 451.9422 -120.930682)
					(end 451.6755 -120.66651)
				)
				(arc
					(start 450.9389 -120.66651)
					(mid 450.6722 -120.930682)
					(end 450.4055 -120.66651)
				)
				(arc
					(start 450.4055 -120.66397)
					(mid 450.6722 -120.39727)
					(end 450.9389 -120.66397)
				)
				(arc
					(start 451.6755 -120.66397)
					(mid 451.9422 -120.39727)
					(end 452.2089 -120.66397)
				)
				(arc
					(start 452.32574 -120.66397)
					(mid 452.213404 -120.392766)
					(end 451.9422 -120.28043)
				)
			)
		)
	)
	(zone
		(layers "B.Cu" "In1.Cu" "In2.Cu" "In3.Cu" "In4.Cu" "In5.Cu" "In6.Cu" "In7.Cu"
			"In8.Cu" "In9.Cu" "In10.Cu" "In12.Cu"
		)
		(hatch none 0.5)
		(connect_pads
			(clearance 0)
		)
		(min_thickness 0.25)
		(keepout
			(tracks not_allowed)
			(vias allowed)
			(pads allowed)
			(copperpour not_allowed)
			(footprints allowed)
		)
		(placement
			(enabled no)
			(sheetname "")
		)
		(fill yes
			(thermal_gap 0.5)
			(thermal_bridge_width 0.5)
			(island_removal_mode 0)
		)
		(polygon
			(pts
				(arc
					(start 12.29614 -35.4965)
					(mid 11.9126 -35.11296)
					(end 11.52906 -35.4965)
				)
				(arc
					(start 11.52906 -36.7665)
					(mid 11.91133 -37.150038)
					(end 12.29614 -36.76904)
				)
				(arc
					(start 12.1793 -36.76904)
					(mid 11.9126 -37.033212)
					(end 11.6459 -36.76904)
				)
				(arc
					(start 11.6459 -36.7665)
					(mid 11.9126 -36.4998)
					(end 12.1793 -36.7665)
				)
				(xy 12.29614 -36.7665) (xy 12.29614 -35.49904)
				(arc
					(start 12.1793 -35.49904)
					(mid 11.9126 -35.763212)
					(end 11.6459 -35.49904)
				)
				(arc
					(start 11.6459 -35.4965)
					(mid 11.9126 -35.2298)
					(end 12.1793 -35.4965)
				)
			)
		)
	)
	(zone
		(layers "B.Cu" "In1.Cu" "In2.Cu" "In3.Cu" "In4.Cu" "In5.Cu" "In6.Cu" "In7.Cu"
			"In8.Cu" "In9.Cu" "In10.Cu" "In12.Cu"
		)
		(hatch none 0.5)
		(connect_pads
			(clearance 0)
		)
		(min_thickness 0.25)
		(keepout
			(tracks not_allowed)
			(vias allowed)
			(pads allowed)
			(copperpour not_allowed)
			(footprints allowed)
		)
		(placement
			(enabled no)
			(sheetname "")
		)
		(fill yes
			(thermal_gap 0.5)
			(thermal_bridge_width 0.5)
			(island_removal_mode 0)
		)
		(polygon
			(pts
				(arc
					(start 388.112 -127.3302)
					(mid 387.731 -126.9492)
					(end 387.35 -127.3302)
				)
				(arc
					(start 387.35 -127.964946)
					(mid 387.729603 -128.346198)
					(end 388.112 -127.96774)
				)
				(arc
					(start 387.9977 -127.96774)
					(mid 387.731 -128.231912)
					(end 387.4643 -127.96774)
				)
				(arc
					(start 387.4643 -127.9652)
					(mid 387.731 -127.6985)
					(end 387.9977 -127.9652)
				)
				(xy 388.112 -127.9652) (xy 388.112 -127.33274)
				(arc
					(start 387.9977 -127.33274)
					(mid 387.731 -127.596912)
					(end 387.4643 -127.33274)
				)
				(arc
					(start 387.4643 -127.3302)
					(mid 387.731 -127.0635)
					(end 387.9977 -127.3302)
				)
			)
		)
	)
	(zone
		(layers "B.Cu" "In1.Cu" "In2.Cu" "In3.Cu" "In4.Cu" "In5.Cu" "In6.Cu" "In7.Cu"
			"In8.Cu" "In9.Cu" "In10.Cu" "In12.Cu"
		)
		(hatch none 0.5)
		(connect_pads
			(clearance 0)
		)
		(min_thickness 0.25)
		(keepout
			(tracks not_allowed)
			(vias allowed)
			(pads allowed)
			(copperpour not_allowed)
			(footprints allowed)
		)
		(placement
			(enabled no)
			(sheetname "")
		)
		(fill yes
			(thermal_gap 0.5)
			(thermal_bridge_width 0.5)
			(island_removal_mode 0)
		)
		(polygon
			(pts
				(arc
					(start 12.29614 -31.9405)
					(mid 11.9126 -31.55696)
					(end 11.52906 -31.9405)
				)
				(arc
					(start 11.52906 -33.2105)
					(mid 11.91133 -33.594038)
					(end 12.29614 -33.21304)
				)
				(arc
					(start 12.1793 -33.21304)
					(mid 11.9126 -33.477212)
					(end 11.6459 -33.21304)
				)
				(arc
					(start 11.6459 -33.2105)
					(mid 11.9126 -32.9438)
					(end 12.1793 -33.2105)
				)
				(xy 12.29614 -33.2105) (xy 12.29614 -31.94304)
				(arc
					(start 12.1793 -31.94304)
					(mid 11.9126 -32.207212)
					(end 11.6459 -31.94304)
				)
				(arc
					(start 11.6459 -31.9405)
					(mid 11.9126 -31.6738)
					(end 12.1793 -31.9405)
				)
			)
		)
	)
	(zone
		(layers "B.Cu" "In1.Cu" "In2.Cu" "In3.Cu" "In4.Cu" "In5.Cu" "In6.Cu" "In7.Cu"
			"In8.Cu" "In9.Cu" "In10.Cu" "In12.Cu"
		)
		(hatch none 0.5)
		(connect_pads
			(clearance 0)
		)
		(min_thickness 0.25)
		(keepout
			(tracks not_allowed)
			(vias allowed)
			(pads allowed)
			(copperpour not_allowed)
			(footprints allowed)
		)
		(placement
			(enabled no)
			(sheetname "")
		)
		(fill yes
			(thermal_gap 0.5)
			(thermal_bridge_width 0.5)
			(island_removal_mode 0)
		)
		(polygon
			(pts
				(arc
					(start 457.587604 -120.00103)
					(mid 457.20381 -120.384443)
					(end 457.58735 -120.76811)
				)
				(arc
					(start 458.85735 -120.76811)
					(mid 459.127654 -120.65667)
					(end 459.24089 -120.38711)
				)
				(arc
					(start 459.12405 -120.38711)
					(mid 458.85735 -120.651282)
					(end 458.59065 -120.38711)
				)
				(arc
					(start 457.85405 -120.38711)
					(mid 457.58735 -120.651282)
					(end 457.32065 -120.38711)
				)
				(arc
					(start 457.32065 -120.38457)
					(mid 457.58735 -120.11787)
					(end 457.85405 -120.38457)
				)
				(arc
					(start 458.59065 -120.38457)
					(mid 458.85735 -120.11787)
					(end 459.12405 -120.38457)
				)
				(arc
					(start 459.24089 -120.38457)
					(mid 459.128554 -120.113366)
					(end 458.85735 -120.00103)
				)
			)
		)
	)
	(zone
		(layers "B.Cu" "In1.Cu" "In2.Cu" "In3.Cu" "In4.Cu" "In5.Cu" "In6.Cu" "In7.Cu"
			"In8.Cu" "In10.Cu" "In11.Cu" "In12.Cu"
		)
		(hatch none 0.5)
		(connect_pads
			(clearance 0)
		)
		(min_thickness 0.25)
		(keepout
			(tracks not_allowed)
			(vias allowed)
			(pads allowed)
			(copperpour not_allowed)
			(footprints allowed)
		)
		(placement
			(enabled no)
			(sheetname "")
		)
		(fill yes
			(thermal_gap 0.5)
			(thermal_bridge_width 0.5)
			(island_removal_mode 0)
		)
		(polygon
			(pts
				(arc
					(start 17.068038 -33.7185)
					(mid 16.684498 -33.33496)
					(end 16.300958 -33.7185)
				)
				(arc
					(start 16.300958 -34.9885)
					(mid 16.683228 -35.372038)
					(end 17.068038 -34.99104)
				)
				(arc
					(start 16.951198 -34.99104)
					(mid 16.684498 -35.255212)
					(end 16.417798 -34.99104)
				)
				(arc
					(start 16.417798 -34.9885)
					(mid 16.684498 -34.7218)
					(end 16.951198 -34.9885)
				)
				(xy 17.068038 -34.9885) (xy 17.068038 -33.72104)
				(arc
					(start 16.951198 -33.72104)
					(mid 16.684498 -33.985212)
					(end 16.417798 -33.72104)
				)
				(arc
					(start 16.417798 -33.7185)
					(mid 16.684498 -33.4518)
					(end 16.951198 -33.7185)
				)
			)
		)
	)
	(zone
		(layers "B.Cu" "In1.Cu" "In2.Cu" "In3.Cu" "In4.Cu" "In5.Cu" "In6.Cu" "In7.Cu"
			"In8.Cu" "In10.Cu" "In11.Cu" "In12.Cu"
		)
		(hatch none 0.5)
		(connect_pads
			(clearance 0)
		)
		(min_thickness 0.25)
		(keepout
			(tracks not_allowed)
			(vias allowed)
			(pads allowed)
			(copperpour not_allowed)
			(footprints allowed)
		)
		(placement
			(enabled no)
			(sheetname "")
		)
		(fill yes
			(thermal_gap 0.5)
			(thermal_bridge_width 0.5)
			(island_removal_mode 0)
		)
		(polygon
			(pts
				(arc
					(start 447.599562 -5.081778)
					(mid 447.485329 -4.818172)
					(end 447.220086 -4.70789)
				)
				(arc
					(start 446.280286 -4.698238)
					(mid 445.892683 -5.077587)
					(end 446.271904 -5.465318)
				)
				(arc
					(start 447.211958 -5.47497)
					(mid 447.488316 -5.361569)
					(end 447.599562 -5.084318)
				)
				(arc
					(start 447.482722 -5.084318)
					(mid 447.216022 -5.358225)
					(end 446.949322 -5.084318)
				)
				(arc
					(start 446.542668 -5.084318)
					(mid 446.275968 -5.34849)
					(end 446.009268 -5.084318)
				)
				(arc
					(start 446.009268 -5.081778)
					(mid 446.275968 -4.815078)
					(end 446.542668 -5.081778)
				)
				(arc
					(start 446.949576 -5.081778)
					(mid 447.216022 -4.824809)
					(end 447.482468 -5.081778)
				)
			)
		)
	)
	(zone
		(layers "B.Cu" "In1.Cu" "In2.Cu" "In3.Cu" "In4.Cu" "In5.Cu" "In6.Cu" "In7.Cu"
			"In8.Cu" "In10.Cu" "In11.Cu" "In12.Cu"
		)
		(hatch none 0.5)
		(connect_pads
			(clearance 0)
		)
		(min_thickness 0.25)
		(keepout
			(tracks not_allowed)
			(vias allowed)
			(pads allowed)
			(copperpour not_allowed)
			(footprints allowed)
		)
		(placement
			(enabled no)
			(sheetname "")
		)
		(fill yes
			(thermal_gap 0.5)
			(thermal_bridge_width 0.5)
			(island_removal_mode 0)
		)
		(polygon
			(pts
				(arc
					(start 15.834614 -31.9405)
					(mid 15.451074 -31.55696)
					(end 15.067534 -31.9405)
				)
				(arc
					(start 15.067534 -33.2105)
					(mid 15.449804 -33.594038)
					(end 15.834614 -33.21304)
				)
				(arc
					(start 15.717774 -33.21304)
					(mid 15.451074 -33.477212)
					(end 15.184374 -33.21304)
				)
				(arc
					(start 15.184374 -33.2105)
					(mid 15.451074 -32.9438)
					(end 15.717774 -33.2105)
				)
				(xy 15.834614 -33.2105) (xy 15.834614 -31.94304)
				(arc
					(start 15.717774 -31.94304)
					(mid 15.451074 -32.207212)
					(end 15.184374 -31.94304)
				)
				(arc
					(start 15.184374 -31.9405)
					(mid 15.451074 -31.6738)
					(end 15.717774 -31.9405)
				)
			)
		)
	)
	(zone
		(layers "B.Cu" "In1.Cu" "In2.Cu" "In3.Cu" "In4.Cu" "In5.Cu" "In6.Cu" "In7.Cu"
			"In8.Cu" "In10.Cu" "In11.Cu" "In12.Cu"
		)
		(hatch none 0.5)
		(connect_pads
			(clearance 0)
		)
		(min_thickness 0.25)
		(keepout
			(tracks not_allowed)
			(vias allowed)
			(pads allowed)
			(copperpour not_allowed)
			(footprints allowed)
		)
		(placement
			(enabled no)
			(sheetname "")
		)
		(fill yes
			(thermal_gap 0.5)
			(thermal_bridge_width 0.5)
			(island_removal_mode 0)
		)
		(polygon
			(pts
				(arc
					(start 395.16685 -106.691176)
					(mid 394.80871 -107.049316)
					(end 395.16685 -107.407456)
				)
				(arc
					(start 396.157196 -107.407456)
					(mid 396.409704 -107.303545)
					(end 396.51559 -107.051856)
				)
				(arc
					(start 396.42415 -107.051856)
					(mid 396.15745 -107.316028)
					(end 395.89075 -107.051856)
				)
				(arc
					(start 395.43355 -107.051856)
					(mid 395.16685 -107.316028)
					(end 394.90015 -107.051856)
				)
				(arc
					(start 394.90015 -107.049316)
					(mid 395.16685 -106.782616)
					(end 395.43355 -107.049316)
				)
				(arc
					(start 395.89075 -107.049316)
					(mid 396.15745 -106.782616)
					(end 396.42415 -107.049316)
				)
				(arc
					(start 396.51559 -107.049316)
					(mid 396.410693 -106.796073)
					(end 396.15745 -106.691176)
				)
			)
		)
	)
	(zone
		(layers "B.Cu" "In1.Cu" "In2.Cu" "In3.Cu" "In4.Cu" "In5.Cu" "In6.Cu" "In7.Cu"
			"In8.Cu" "In10.Cu" "In11.Cu" "In12.Cu"
		)
		(hatch none 0.5)
		(connect_pads
			(clearance 0)
		)
		(min_thickness 0.25)
		(keepout
			(tracks not_allowed)
			(vias allowed)
			(pads allowed)
			(copperpour not_allowed)
			(footprints allowed)
		)
		(placement
			(enabled no)
			(sheetname "")
		)
		(fill yes
			(thermal_gap 0.5)
			(thermal_bridge_width 0.5)
			(island_removal_mode 0)
		)
		(polygon
			(pts
				(arc
					(start 447.893694 -5.715)
					(mid 447.5099 -6.098413)
					(end 447.89344 -6.48208)
				)
				(arc
					(start 448.835526 -6.48208)
					(mid 449.10583 -6.37064)
					(end 449.219066 -6.10108)
				)
				(arc
					(start 449.102226 -6.10108)
					(mid 448.835526 -6.365252)
					(end 448.568826 -6.10108)
				)
				(arc
					(start 448.16014 -6.10108)
					(mid 447.89344 -6.365252)
					(end 447.62674 -6.10108)
				)
				(arc
					(start 447.62674 -6.09854)
					(mid 447.89344 -5.83184)
					(end 448.16014 -6.09854)
				)
				(arc
					(start 448.568826 -6.09854)
					(mid 448.835526 -5.83184)
					(end 449.102226 -6.09854)
				)
				(arc
					(start 449.219066 -6.09854)
					(mid 449.10673 -5.827336)
					(end 448.835526 -5.715)
				)
			)
		)
	)
	(zone
		(layers "B.Cu" "In1.Cu" "In2.Cu" "In3.Cu" "In4.Cu" "In5.Cu" "In6.Cu" "In7.Cu"
			"In8.Cu" "In10.Cu" "In11.Cu" "In12.Cu"
		)
		(hatch none 0.5)
		(connect_pads
			(clearance 0)
		)
		(min_thickness 0.25)
		(keepout
			(tracks not_allowed)
			(vias allowed)
			(pads allowed)
			(copperpour not_allowed)
			(footprints allowed)
		)
		(placement
			(enabled no)
			(sheetname "")
		)
		(fill yes
			(thermal_gap 0.5)
			(thermal_bridge_width 0.5)
			(island_removal_mode 0)
		)
		(polygon
			(pts
				(arc
					(start 420.064184 -91.5924)
					(mid 419.655244 -91.18346)
					(end 419.246304 -91.5924)
				)
				(arc
					(start 419.246304 -92.862146)
					(mid 419.653847 -93.271338)
					(end 420.064184 -92.86494)
				)
				(arc
					(start 419.921944 -92.86494)
					(mid 419.655244 -93.129112)
					(end 419.388544 -92.86494)
				)
				(arc
					(start 419.388544 -92.8624)
					(mid 419.655244 -92.5957)
					(end 419.921944 -92.8624)
				)
				(xy 420.064184 -92.8624) (xy 420.064184 -91.59494)
				(arc
					(start 419.921944 -91.59494)
					(mid 419.655244 -91.859112)
					(end 419.388544 -91.59494)
				)
				(arc
					(start 419.388544 -91.5924)
					(mid 419.655244 -91.3257)
					(end 419.921944 -91.5924)
				)
			)
		)
	)
	(zone
		(layers "B.Cu" "In1.Cu" "In2.Cu" "In3.Cu" "In4.Cu" "In5.Cu" "In6.Cu" "In7.Cu"
			"In8.Cu" "In10.Cu" "In11.Cu" "In12.Cu"
		)
		(hatch none 0.5)
		(connect_pads
			(clearance 0)
		)
		(min_thickness 0.25)
		(keepout
			(tracks not_allowed)
			(vias allowed)
			(pads allowed)
			(copperpour not_allowed)
			(footprints allowed)
		)
		(placement
			(enabled no)
			(sheetname "")
		)
		(fill yes
			(thermal_gap 0.5)
			(thermal_bridge_width 0.5)
			(island_removal_mode 0)
		)
		(polygon
			(pts
				(arc
					(start 430.5808 -2.490978)
					(mid 430.19726 -2.874518)
					(end 430.5808 -3.258058)
				)
				(arc
					(start 431.850546 -3.258058)
					(mid 432.121014 -3.146708)
					(end 432.23434 -2.877058)
				)
				(arc
					(start 432.1175 -2.877058)
					(mid 431.8508 -3.14123)
					(end 431.5841 -2.877058)
				)
				(arc
					(start 430.8475 -2.877058)
					(mid 430.5808 -3.14123)
					(end 430.3141 -2.877058)
				)
				(arc
					(start 430.3141 -2.874518)
					(mid 430.5808 -2.607818)
					(end 430.8475 -2.874518)
				)
				(arc
					(start 431.5841 -2.874518)
					(mid 431.8508 -2.607818)
					(end 432.1175 -2.874518)
				)
				(arc
					(start 432.23434 -2.874518)
					(mid 432.122004 -2.603314)
					(end 431.8508 -2.490978)
				)
			)
		)
	)
	(zone
		(layers "B.Cu" "In1.Cu" "In2.Cu" "In3.Cu" "In4.Cu" "In5.Cu" "In6.Cu" "In7.Cu"
			"In8.Cu" "In10.Cu" "In11.Cu" "In12.Cu"
		)
		(hatch none 0.5)
		(connect_pads
			(clearance 0)
		)
		(min_thickness 0.25)
		(keepout
			(tracks not_allowed)
			(vias allowed)
			(pads allowed)
			(copperpour not_allowed)
			(footprints allowed)
		)
		(placement
			(enabled no)
			(sheetname "")
		)
		(fill yes
			(thermal_gap 0.5)
			(thermal_bridge_width 0.5)
			(island_removal_mode 0)
		)
		(polygon
			(pts
				(arc
					(start 438.755536 -9.64057)
					(mid 438.371996 -10.023983)
					(end 438.755282 -10.40765)
				)
				(arc
					(start 439.720482 -10.40765)
					(mid 439.990786 -10.29621)
					(end 440.104022 -10.02665)
				)
				(arc
					(start 439.987182 -10.02665)
					(mid 439.720482 -10.290822)
					(end 439.453782 -10.02665)
				)
				(arc
					(start 439.021982 -10.02665)
					(mid 438.755282 -10.290822)
					(end 438.488582 -10.02665)
				)
				(arc
					(start 438.488582 -10.02411)
					(mid 438.755282 -9.75741)
					(end 439.021982 -10.02411)
				)
				(arc
					(start 439.453782 -10.02411)
					(mid 439.720482 -9.75741)
					(end 439.987182 -10.02411)
				)
				(arc
					(start 440.104022 -10.02411)
					(mid 439.991686 -9.752906)
					(end 439.720482 -9.64057)
				)
			)
		)
	)
	(zone
		(layers "B.Cu" "In1.Cu" "In2.Cu" "In3.Cu" "In4.Cu" "In5.Cu" "In6.Cu" "In7.Cu"
			"In8.Cu" "In10.Cu" "In11.Cu" "In12.Cu"
		)
		(hatch none 0.5)
		(connect_pads
			(clearance 0)
		)
		(min_thickness 0.25)
		(keepout
			(tracks not_allowed)
			(vias allowed)
			(pads allowed)
			(copperpour not_allowed)
			(footprints allowed)
		)
		(placement
			(enabled no)
			(sheetname "")
		)
		(fill yes
			(thermal_gap 0.5)
			(thermal_bridge_width 0.5)
			(island_removal_mode 0)
		)
		(polygon
			(pts
				(arc
					(start 408.878024 -95.547434)
					(mid 408.469084 -95.138494)
					(end 408.060144 -95.547434)
				)
				(arc
					(start 408.060144 -96.601788)
					(mid 408.467814 -97.010726)
					(end 408.878024 -96.604328)
				)
				(arc
					(start 408.735784 -96.604328)
					(mid 408.469084 -96.8685)
					(end 408.202384 -96.604328)
				)
				(arc
					(start 408.202384 -96.601788)
					(mid 408.469084 -96.335088)
					(end 408.735784 -96.601788)
				)
				(xy 408.878024 -96.601788) (xy 408.878024 -95.549974)
				(arc
					(start 408.735784 -95.549974)
					(mid 408.469084 -95.814146)
					(end 408.202384 -95.549974)
				)
				(arc
					(start 408.202384 -95.547434)
					(mid 408.469084 -95.280734)
					(end 408.735784 -95.547434)
				)
			)
		)
	)
	(zone
		(layers "B.Cu" "In1.Cu" "In2.Cu" "In3.Cu" "In4.Cu" "In5.Cu" "In6.Cu" "In7.Cu"
			"In8.Cu" "In10.Cu" "In11.Cu" "In12.Cu"
		)
		(hatch none 0.5)
		(connect_pads
			(clearance 0)
		)
		(min_thickness 0.25)
		(keepout
			(tracks not_allowed)
			(vias allowed)
			(pads allowed)
			(copperpour not_allowed)
			(footprints allowed)
		)
		(placement
			(enabled no)
			(sheetname "")
		)
		(fill yes
			(thermal_gap 0.5)
			(thermal_bridge_width 0.5)
			(island_removal_mode 0)
		)
		(polygon
			(pts
				(arc
					(start 436.361332 -9.74598)
					(mid 435.977792 -10.12952)
					(end 436.361332 -10.51306)
				)
				(arc
					(start 437.326278 -10.51306)
					(mid 437.596746 -10.40171)
					(end 437.710072 -10.13206)
				)
				(arc
					(start 437.593232 -10.13206)
					(mid 437.326532 -10.396232)
					(end 437.059832 -10.13206)
				)
				(arc
					(start 436.628032 -10.13206)
					(mid 436.361332 -10.396232)
					(end 436.094632 -10.13206)
				)
				(arc
					(start 436.094632 -10.12952)
					(mid 436.361332 -9.86282)
					(end 436.628032 -10.12952)
				)
				(arc
					(start 437.059832 -10.12952)
					(mid 437.326532 -9.86282)
					(end 437.593232 -10.12952)
				)
				(arc
					(start 437.710072 -10.12952)
					(mid 437.597736 -9.858316)
					(end 437.326532 -9.74598)
				)
			)
		)
	)
	(zone
		(layers "B.Cu" "In1.Cu" "In2.Cu" "In3.Cu" "In4.Cu" "In5.Cu" "In6.Cu" "In7.Cu"
			"In8.Cu" "In10.Cu" "In11.Cu" "In12.Cu"
		)
		(hatch none 0.5)
		(connect_pads
			(clearance 0)
		)
		(min_thickness 0.25)
		(keepout
			(tracks not_allowed)
			(vias allowed)
			(pads allowed)
			(copperpour not_allowed)
			(footprints allowed)
		)
		(placement
			(enabled no)
			(sheetname "")
		)
		(fill yes
			(thermal_gap 0.5)
			(thermal_bridge_width 0.5)
			(island_removal_mode 0)
		)
		(polygon
			(pts
				(arc
					(start 446.63487 -7.734808)
					(mid 446.25133 -7.351268)
					(end 445.86779 -7.734808)
				)
				(arc
					(start 445.86779 -8.700008)
					(mid 446.25006 -9.083546)
					(end 446.63487 -8.702548)
				)
				(arc
					(start 446.51803 -8.702548)
					(mid 446.25133 -8.96672)
					(end 445.98463 -8.702548)
				)
				(arc
					(start 445.98463 -8.700008)
					(mid 446.25133 -8.433308)
					(end 446.51803 -8.700008)
				)
				(xy 446.63487 -8.700008) (xy 446.63487 -7.737348)
				(arc
					(start 446.51803 -7.737348)
					(mid 446.25133 -8.00152)
					(end 445.98463 -7.737348)
				)
				(arc
					(start 445.98463 -7.734808)
					(mid 446.25133 -7.468108)
					(end 446.51803 -7.734808)
				)
			)
		)
	)
	(zone
		(layers "B.Cu" "In1.Cu" "In2.Cu" "In3.Cu" "In4.Cu" "In5.Cu" "In6.Cu" "In7.Cu"
			"In8.Cu" "In10.Cu" "In11.Cu" "In12.Cu"
		)
		(hatch none 0.5)
		(connect_pads
			(clearance 0)
		)
		(min_thickness 0.25)
		(keepout
			(tracks not_allowed)
			(vias allowed)
			(pads allowed)
			(copperpour not_allowed)
			(footprints allowed)
		)
		(placement
			(enabled no)
			(sheetname "")
		)
		(fill yes
			(thermal_gap 0.5)
			(thermal_bridge_width 0.5)
			(island_removal_mode 0)
		)
		(polygon
			(pts
				(arc
					(start 16.186404 -22.70506)
					(mid 15.80261 -23.088473)
					(end 16.18615 -23.47214)
				)
				(arc
					(start 17.45615 -23.47214)
					(mid 17.726454 -23.3607)
					(end 17.83969 -23.09114)
				)
				(arc
					(start 17.72285 -23.09114)
					(mid 17.45615 -23.355312)
					(end 17.18945 -23.09114)
				)
				(arc
					(start 16.45285 -23.09114)
					(mid 16.18615 -23.355312)
					(end 15.91945 -23.09114)
				)
				(arc
					(start 15.91945 -23.0886)
					(mid 16.18615 -22.8219)
					(end 16.45285 -23.0886)
				)
				(arc
					(start 17.18945 -23.0886)
					(mid 17.45615 -22.8219)
					(end 17.72285 -23.0886)
				)
				(arc
					(start 17.83969 -23.0886)
					(mid 17.727354 -22.817396)
					(end 17.45615 -22.70506)
				)
			)
		)
	)
	(zone
		(layers "B.Cu" "In1.Cu" "In2.Cu" "In3.Cu" "In4.Cu" "In5.Cu" "In6.Cu" "In7.Cu"
			"In8.Cu" "In10.Cu" "In11.Cu" "In12.Cu"
		)
		(hatch none 0.5)
		(connect_pads
			(clearance 0)
		)
		(min_thickness 0.25)
		(keepout
			(tracks not_allowed)
			(vias allowed)
			(pads allowed)
			(copperpour not_allowed)
			(footprints allowed)
		)
		(placement
			(enabled no)
			(sheetname "")
		)
		(fill yes
			(thermal_gap 0.5)
			(thermal_bridge_width 0.5)
			(island_removal_mode 0)
		)
		(polygon
			(pts
				(arc
					(start 15.80134 -28.3845)
					(mid 15.4178 -28.00096)
					(end 15.03426 -28.3845)
				)
				(arc
					(start 15.03426 -29.6545)
					(mid 15.41653 -30.038038)
					(end 15.80134 -29.65704)
				)
				(arc
					(start 15.6845 -29.65704)
					(mid 15.4178 -29.921212)
					(end 15.1511 -29.65704)
				)
				(arc
					(start 15.1511 -29.6545)
					(mid 15.4178 -29.3878)
					(end 15.6845 -29.6545)
				)
				(xy 15.80134 -29.6545) (xy 15.80134 -28.38704)
				(arc
					(start 15.6845 -28.38704)
					(mid 15.4178 -28.651212)
					(end 15.1511 -28.38704)
				)
				(arc
					(start 15.1511 -28.3845)
					(mid 15.4178 -28.1178)
					(end 15.6845 -28.3845)
				)
			)
		)
	)
	(zone
		(layers "B.Cu" "In1.Cu" "In2.Cu" "In3.Cu" "In4.Cu" "In5.Cu" "In6.Cu" "In7.Cu"
			"In8.Cu" "In10.Cu" "In11.Cu" "In12.Cu"
		)
		(hatch none 0.5)
		(connect_pads
			(clearance 0)
		)
		(min_thickness 0.25)
		(keepout
			(tracks not_allowed)
			(vias allowed)
			(pads allowed)
			(copperpour not_allowed)
			(footprints allowed)
		)
		(placement
			(enabled no)
			(sheetname "")
		)
		(fill yes
			(thermal_gap 0.5)
			(thermal_bridge_width 0.5)
			(island_removal_mode 0)
		)
		(polygon
			(pts
				(arc
					(start 442.760608 -5.508498)
					(mid 442.377068 -5.892038)
					(end 442.760608 -6.275578)
				)
				(arc
					(start 444.030354 -6.275578)
					(mid 444.300822 -6.164228)
					(end 444.414148 -5.894578)
				)
				(arc
					(start 444.297308 -5.894578)
					(mid 444.030608 -6.15875)
					(end 443.763908 -5.894578)
				)
				(arc
					(start 443.027308 -5.894578)
					(mid 442.760608 -6.15875)
					(end 442.493908 -5.894578)
				)
				(arc
					(start 442.493908 -5.892038)
					(mid 442.760608 -5.625338)
					(end 443.027308 -5.892038)
				)
				(arc
					(start 443.763908 -5.892038)
					(mid 444.030608 -5.625338)
					(end 444.297308 -5.892038)
				)
				(arc
					(start 444.414148 -5.892038)
					(mid 444.301812 -5.620834)
					(end 444.030608 -5.508498)
				)
			)
		)
	)
	(zone
		(layers "B.Cu" "In1.Cu" "In2.Cu" "In3.Cu" "In4.Cu" "In5.Cu" "In6.Cu" "In7.Cu"
			"In8.Cu" "In10.Cu" "In11.Cu" "In12.Cu"
		)
		(hatch none 0.5)
		(connect_pads
			(clearance 0)
		)
		(min_thickness 0.25)
		(keepout
			(tracks not_allowed)
			(vias allowed)
			(pads allowed)
			(copperpour not_allowed)
			(footprints allowed)
		)
		(placement
			(enabled no)
			(sheetname "")
		)
		(fill yes
			(thermal_gap 0.5)
			(thermal_bridge_width 0.5)
			(island_removal_mode 0)
		)
		(polygon
			(pts
				(arc
					(start 435.431438 -2.45618)
					(mid 435.047898 -2.83972)
					(end 435.431438 -3.22326)
				)
				(arc
					(start 436.701184 -3.22326)
					(mid 436.971652 -3.11191)
					(end 437.084978 -2.84226)
				)
				(arc
					(start 436.968138 -2.84226)
					(mid 436.701438 -3.106432)
					(end 436.434738 -2.84226)
				)
				(arc
					(start 435.698138 -2.84226)
					(mid 435.431438 -3.106432)
					(end 435.164738 -2.84226)
				)
				(arc
					(start 435.164738 -2.83972)
					(mid 435.431438 -2.57302)
					(end 435.698138 -2.83972)
				)
				(arc
					(start 436.434738 -2.83972)
					(mid 436.701438 -2.57302)
					(end 436.968138 -2.83972)
				)
				(arc
					(start 437.084978 -2.83972)
					(mid 436.972642 -2.568516)
					(end 436.701438 -2.45618)
				)
			)
		)
	)
	(zone
		(layers "B.Cu" "In1.Cu" "In2.Cu" "In3.Cu" "In4.Cu" "In5.Cu" "In6.Cu" "In7.Cu"
			"In8.Cu" "In10.Cu" "In11.Cu" "In12.Cu"
		)
		(hatch none 0.5)
		(connect_pads
			(clearance 0)
		)
		(min_thickness 0.25)
		(keepout
			(tracks not_allowed)
			(vias allowed)
			(pads allowed)
			(copperpour not_allowed)
			(footprints allowed)
		)
		(placement
			(enabled no)
			(sheetname "")
		)
		(fill yes
			(thermal_gap 0.5)
			(thermal_bridge_width 0.5)
			(island_removal_mode 0)
		)
		(polygon
			(pts
				(arc
					(start 455.519536 -63.217552)
					(mid 455.110596 -63.626492)
					(end 455.519536 -64.035432)
				)
				(arc
					(start 456.789282 -64.035432)
					(mid 457.077711 -63.916642)
					(end 457.198476 -63.629032)
				)
				(arc
					(start 457.056236 -63.629032)
					(mid 456.789536 -63.893204)
					(end 456.522836 -63.629032)
				)
				(arc
					(start 455.786236 -63.629032)
					(mid 455.519536 -63.893204)
					(end 455.252836 -63.629032)
				)
				(arc
					(start 455.252836 -63.626492)
					(mid 455.519536 -63.359792)
					(end 455.786236 -63.626492)
				)
				(arc
					(start 456.522836 -63.626492)
					(mid 456.789536 -63.359792)
					(end 457.056236 -63.626492)
				)
				(arc
					(start 457.198476 -63.626492)
					(mid 457.0787 -63.337328)
					(end 456.789536 -63.217552)
				)
			)
		)
	)
	(zone
		(layers "B.Cu" "In1.Cu" "In2.Cu" "In3.Cu" "In4.Cu" "In5.Cu" "In6.Cu" "In7.Cu"
			"In8.Cu" "In10.Cu" "In11.Cu" "In12.Cu"
		)
		(hatch none 0.5)
		(connect_pads
			(clearance 0)
		)
		(min_thickness 0.25)
		(keepout
			(tracks not_allowed)
			(vias allowed)
			(pads allowed)
			(copperpour not_allowed)
			(footprints allowed)
		)
		(placement
			(enabled no)
			(sheetname "")
		)
		(fill yes
			(thermal_gap 0.5)
			(thermal_bridge_width 0.5)
			(island_removal_mode 0)
		)
		(polygon
			(pts
				(arc
					(start 406.523952 -95.591884)
					(mid 406.115012 -95.182944)
					(end 405.706072 -95.591884)
				)
				(arc
					(start 405.706072 -96.607376)
					(mid 406.113742 -97.016314)
					(end 406.523952 -96.609916)
				)
				(arc
					(start 406.381712 -96.609916)
					(mid 406.115012 -96.874088)
					(end 405.848312 -96.609916)
				)
				(arc
					(start 405.848312 -96.607376)
					(mid 406.115012 -96.340676)
					(end 406.381712 -96.607376)
				)
				(xy 406.523952 -96.607376) (xy 406.523952 -95.594424)
				(arc
					(start 406.381712 -95.594424)
					(mid 406.115012 -95.858596)
					(end 405.848312 -95.594424)
				)
				(arc
					(start 405.848312 -95.591884)
					(mid 406.115012 -95.325184)
					(end 406.381712 -95.591884)
				)
			)
		)
	)
	(zone
		(layers "B.Cu" "In1.Cu" "In2.Cu" "In3.Cu" "In4.Cu" "In5.Cu" "In6.Cu" "In7.Cu"
			"In8.Cu" "In10.Cu" "In11.Cu" "In12.Cu"
		)
		(hatch none 0.5)
		(connect_pads
			(clearance 0)
		)
		(min_thickness 0.25)
		(keepout
			(tracks not_allowed)
			(vias allowed)
			(pads allowed)
			(copperpour not_allowed)
			(footprints allowed)
		)
		(placement
			(enabled no)
			(sheetname "")
		)
		(fill yes
			(thermal_gap 0.5)
			(thermal_bridge_width 0.5)
			(island_removal_mode 0)
		)
		(polygon
			(pts
				(arc
					(start 15.834614 -35.4965)
					(mid 15.451074 -35.11296)
					(end 15.067534 -35.4965)
				)
				(arc
					(start 15.067534 -36.7665)
					(mid 15.449804 -37.150038)
					(end 15.834614 -36.76904)
				)
				(arc
					(start 15.717774 -36.76904)
					(mid 15.451074 -37.033212)
					(end 15.184374 -36.76904)
				)
				(arc
					(start 15.184374 -36.7665)
					(mid 15.451074 -36.4998)
					(end 15.717774 -36.7665)
				)
				(xy 15.834614 -36.7665) (xy 15.834614 -35.49904)
				(arc
					(start 15.717774 -35.49904)
					(mid 15.451074 -35.763212)
					(end 15.184374 -35.49904)
				)
				(arc
					(start 15.184374 -35.4965)
					(mid 15.451074 -35.2298)
					(end 15.717774 -35.4965)
				)
			)
		)
	)
	(zone
		(layers "B.Cu" "In1.Cu" "In2.Cu" "In3.Cu" "In4.Cu" "In5.Cu" "In6.Cu" "In7.Cu"
			"In8.Cu" "In10.Cu" "In11.Cu" "In12.Cu"
		)
		(hatch none 0.5)
		(connect_pads
			(clearance 0)
		)
		(min_thickness 0.25)
		(keepout
			(tracks not_allowed)
			(vias allowed)
			(pads allowed)
			(copperpour not_allowed)
			(footprints allowed)
		)
		(placement
			(enabled no)
			(sheetname "")
		)
		(fill yes
			(thermal_gap 0.5)
			(thermal_bridge_width 0.5)
			(island_removal_mode 0)
		)
		(polygon
			(pts
				(arc
					(start 16.99641 -30.15742)
					(mid 16.61287 -29.77388)
					(end 16.22933 -30.15742)
				)
				(arc
					(start 16.22933 -31.427166)
					(mid 16.611473 -31.810958)
					(end 16.99641 -31.42996)
				)
				(arc
					(start 16.87957 -31.42996)
					(mid 16.61287 -31.694132)
					(end 16.34617 -31.42996)
				)
				(arc
					(start 16.34617 -31.42742)
					(mid 16.61287 -31.16072)
					(end 16.87957 -31.42742)
				)
				(xy 16.99641 -31.42742) (xy 16.99641 -30.15996)
				(arc
					(start 16.87957 -30.15996)
					(mid 16.61287 -30.424132)
					(end 16.34617 -30.15996)
				)
				(arc
					(start 16.34617 -30.15742)
					(mid 16.61287 -29.89072)
					(end 16.87957 -30.15742)
				)
			)
		)
	)
	(zone
		(layers "B.Cu" "In1.Cu" "In2.Cu" "In3.Cu" "In4.Cu" "In5.Cu" "In6.Cu" "In7.Cu"
			"In8.Cu" "In10.Cu" "In11.Cu" "In12.Cu"
		)
		(hatch none 0.5)
		(connect_pads
			(clearance 0)
		)
		(min_thickness 0.25)
		(keepout
			(tracks not_allowed)
			(vias allowed)
			(pads allowed)
			(copperpour not_allowed)
			(footprints allowed)
		)
		(placement
			(enabled no)
			(sheetname "")
		)
		(fill yes
			(thermal_gap 0.5)
			(thermal_bridge_width 0.5)
			(island_removal_mode 0)
		)
		(polygon
			(pts
				(arc
					(start 433.011834 -2.476754)
					(mid 432.628294 -2.860294)
					(end 433.011834 -3.243834)
				)
				(arc
					(start 434.28158 -3.243834)
					(mid 434.552048 -3.132484)
					(end 434.665374 -2.862834)
				)
				(arc
					(start 434.548534 -2.862834)
					(mid 434.281834 -3.127006)
					(end 434.015134 -2.862834)
				)
				(arc
					(start 433.278534 -2.862834)
					(mid 433.011834 -3.127006)
					(end 432.745134 -2.862834)
				)
				(arc
					(start 432.745134 -2.860294)
					(mid 433.011834 -2.593594)
					(end 433.278534 -2.860294)
				)
				(arc
					(start 434.015134 -2.860294)
					(mid 434.281834 -2.593594)
					(end 434.548534 -2.860294)
				)
				(arc
					(start 434.665374 -2.860294)
					(mid 434.553038 -2.58909)
					(end 434.281834 -2.476754)
				)
			)
		)
	)
	(zone
		(layers "B.Cu" "In1.Cu" "In2.Cu" "In3.Cu" "In4.Cu" "In5.Cu" "In6.Cu" "In7.Cu"
			"In8.Cu" "In10.Cu" "In11.Cu" "In12.Cu"
		)
		(hatch none 0.5)
		(connect_pads
			(clearance 0)
		)
		(min_thickness 0.25)
		(keepout
			(tracks not_allowed)
			(vias allowed)
			(pads allowed)
			(copperpour not_allowed)
			(footprints allowed)
		)
		(placement
			(enabled no)
			(sheetname "")
		)
		(fill yes
			(thermal_gap 0.5)
			(thermal_bridge_width 0.5)
			(island_removal_mode 0)
		)
		(polygon
			(pts
				(arc
					(start 443.6237 -8.74141)
					(mid 443.24016 -9.12495)
					(end 443.6237 -9.50849)
				)
				(arc
					(start 444.563246 -9.50849)
					(mid 444.833714 -9.39714)
					(end 444.94704 -9.12749)
				)
				(arc
					(start 444.8302 -9.12749)
					(mid 444.5635 -9.391662)
					(end 444.2968 -9.12749)
				)
				(arc
					(start 443.8904 -9.12749)
					(mid 443.6237 -9.391662)
					(end 443.357 -9.12749)
				)
				(arc
					(start 443.357 -9.12495)
					(mid 443.6237 -8.85825)
					(end 443.8904 -9.12495)
				)
				(arc
					(start 444.2968 -9.12495)
					(mid 444.5635 -8.85825)
					(end 444.8302 -9.12495)
				)
				(arc
					(start 444.94704 -9.12495)
					(mid 444.834704 -8.853746)
					(end 444.5635 -8.74141)
				)
			)
		)
	)
	(zone
		(layers "B.Cu" "In1.Cu" "In2.Cu" "In3.Cu" "In4.Cu" "In5.Cu" "In6.Cu" "In7.Cu"
			"In8.Cu" "In10.Cu" "In11.Cu" "In12.Cu"
		)
		(hatch none 0.5)
		(connect_pads
			(clearance 0)
		)
		(min_thickness 0.25)
		(keepout
			(tracks not_allowed)
			(vias allowed)
			(pads allowed)
			(copperpour not_allowed)
			(footprints allowed)
		)
		(placement
			(enabled no)
			(sheetname "")
		)
		(fill yes
			(thermal_gap 0.5)
			(thermal_bridge_width 0.5)
			(island_removal_mode 0)
		)
		(polygon
			(pts
				(arc
					(start 444.883794 -9.508744)
					(mid 444.645262 -9.996095)
					(end 445.13246 -10.234422)
				)
				(xy 445.133222 -10.236962) (xy 445.996822 -9.941052)
				(arc
					(start 445.99606 -9.938512)
					(mid 446.05703 -9.911458)
					(end 446.112392 -9.87425)
				)
				(arc
					(start 445.2747 -9.87425)
					(mid 445.008 -10.138422)
					(end 444.7413 -9.87425)
				)
				(arc
					(start 444.7413 -9.87171)
					(mid 445.008 -9.60501)
					(end 445.2747 -9.87171)
				)
				(arc
					(start 446.115694 -9.87171)
					(mid 446.218027 -9.74052)
					(end 446.25514 -9.57834)
				)
				(arc
					(start 446.1383 -9.57834)
					(mid 445.8716 -9.842512)
					(end 445.6049 -9.57834)
				)
				(arc
					(start 445.6049 -9.5758)
					(mid 445.8716 -9.3091)
					(end 446.1383 -9.5758)
				)
				(arc
					(start 446.25514 -9.5758)
					(mid 446.094489 -9.263673)
					(end 445.74714 -9.213088)
				)
				(xy 445.746378 -9.210548) (xy 444.883032 -9.506458) (xy 444.883032 -9.506712)
			)
		)
	)
	(zone
		(layers "B.Cu" "In1.Cu" "In2.Cu" "In3.Cu" "In4.Cu" "In5.Cu" "In6.Cu" "In7.Cu"
			"In8.Cu" "In10.Cu" "In11.Cu" "In12.Cu"
		)
		(hatch none 0.5)
		(connect_pads
			(clearance 0)
		)
		(min_thickness 0.25)
		(keepout
			(tracks not_allowed)
			(vias allowed)
			(pads allowed)
			(copperpour not_allowed)
			(footprints allowed)
		)
		(placement
			(enabled no)
			(sheetname "")
		)
		(fill yes
			(thermal_gap 0.5)
			(thermal_bridge_width 0.5)
			(island_removal_mode 0)
		)
		(polygon
			(pts
				(arc
					(start 440.224672 -5.283708)
					(mid 439.841132 -5.667248)
					(end 440.224672 -6.050788)
				)
				(arc
					(start 441.494418 -6.050788)
					(mid 441.764886 -5.939438)
					(end 441.878212 -5.669788)
				)
				(arc
					(start 441.761372 -5.669788)
					(mid 441.494672 -5.93396)
					(end 441.227972 -5.669788)
				)
				(arc
					(start 440.491372 -5.669788)
					(mid 440.224672 -5.93396)
					(end 439.957972 -5.669788)
				)
				(arc
					(start 439.957972 -5.667248)
					(mid 440.224672 -5.400548)
					(end 440.491372 -5.667248)
				)
				(arc
					(start 441.227972 -5.667248)
					(mid 441.494672 -5.400548)
					(end 441.761372 -5.667248)
				)
				(arc
					(start 441.878212 -5.667248)
					(mid 441.765876 -5.396044)
					(end 441.494672 -5.283708)
				)
			)
		)
	)
	(zone
		(layers "B.Cu" "In1.Cu" "In2.Cu" "In3.Cu" "In4.Cu" "In5.Cu" "In6.Cu" "In7.Cu"
			"In8.Cu" "In10.Cu" "In11.Cu" "In12.Cu"
		)
		(hatch none 0.5)
		(connect_pads
			(clearance 0)
		)
		(min_thickness 0.25)
		(keepout
			(tracks not_allowed)
			(vias allowed)
			(pads allowed)
			(copperpour not_allowed)
			(footprints allowed)
		)
		(placement
			(enabled no)
			(sheetname "")
		)
		(fill yes
			(thermal_gap 0.5)
			(thermal_bridge_width 0.5)
			(island_removal_mode 0)
		)
		(polygon
			(pts
				(arc
					(start 433.961032 -9.61136)
					(mid 433.577492 -9.9949)
					(end 433.961032 -10.37844)
				)
				(arc
					(start 434.925978 -10.37844)
					(mid 435.196446 -10.26709)
					(end 435.309772 -9.99744)
				)
				(arc
					(start 435.192932 -9.99744)
					(mid 434.926232 -10.261612)
					(end 434.659532 -9.99744)
				)
				(arc
					(start 434.227732 -9.99744)
					(mid 433.961032 -10.261612)
					(end 433.694332 -9.99744)
				)
				(arc
					(start 433.694332 -9.9949)
					(mid 433.961032 -9.7282)
					(end 434.227732 -9.9949)
				)
				(arc
					(start 434.659532 -9.9949)
					(mid 434.926232 -9.7282)
					(end 435.192932 -9.9949)
				)
				(arc
					(start 435.309772 -9.9949)
					(mid 435.197436 -9.723696)
					(end 434.926232 -9.61136)
				)
			)
		)
	)
	(zone
		(layers "B.Cu" "In1.Cu" "In2.Cu" "In3.Cu" "In4.Cu" "In5.Cu" "In6.Cu" "In7.Cu"
			"In8.Cu" "In10.Cu" "In11.Cu" "In12.Cu"
		)
		(hatch none 0.5)
		(connect_pads
			(clearance 0)
		)
		(min_thickness 0.25)
		(keepout
			(tracks not_allowed)
			(vias allowed)
			(pads allowed)
			(copperpour not_allowed)
			(footprints allowed)
		)
		(placement
			(enabled no)
			(sheetname "")
		)
		(fill yes
			(thermal_gap 0.5)
			(thermal_bridge_width 0.5)
			(island_removal_mode 0)
		)
		(polygon
			(pts
				(arc
					(start 431.615342 -9.694926)
					(mid 431.231802 -10.078466)
					(end 431.615342 -10.462006)
				)
				(arc
					(start 432.580288 -10.462006)
					(mid 432.850756 -10.350656)
					(end 432.964082 -10.081006)
				)
				(arc
					(start 432.847242 -10.081006)
					(mid 432.580542 -10.345178)
					(end 432.313842 -10.081006)
				)
				(arc
					(start 431.882042 -10.081006)
					(mid 431.615342 -10.345178)
					(end 431.348642 -10.081006)
				)
				(arc
					(start 431.348642 -10.078466)
					(mid 431.615342 -9.811766)
					(end 431.882042 -10.078466)
				)
				(arc
					(start 432.313842 -10.078466)
					(mid 432.580542 -9.811766)
					(end 432.847242 -10.078466)
				)
				(arc
					(start 432.964082 -10.078466)
					(mid 432.851746 -9.807262)
					(end 432.580542 -9.694926)
				)
			)
		)
	)
	(zone
		(layers "B.Cu" "In1.Cu" "In2.Cu" "In3.Cu" "In4.Cu" "In5.Cu" "In6.Cu" "In7.Cu"
			"In8.Cu" "In10.Cu" "In11.Cu" "In12.Cu"
		)
		(hatch none 0.5)
		(connect_pads
			(clearance 0)
		)
		(min_thickness 0.25)
		(keepout
			(tracks not_allowed)
			(vias allowed)
			(pads allowed)
			(copperpour not_allowed)
			(footprints allowed)
		)
		(placement
			(enabled no)
			(sheetname "")
		)
		(fill yes
			(thermal_gap 0.5)
			(thermal_bridge_width 0.5)
			(island_removal_mode 0)
		)
		(polygon
			(pts
				(arc
					(start 445.910716 -59.969908)
					(mid 445.501776 -60.378848)
					(end 445.910716 -60.787788)
				)
				(arc
					(start 447.180462 -60.787788)
					(mid 447.468891 -60.668998)
					(end 447.589656 -60.381388)
				)
				(arc
					(start 447.447416 -60.381388)
					(mid 447.180716 -60.64556)
					(end 446.914016 -60.381388)
				)
				(arc
					(start 446.177416 -60.381388)
					(mid 445.910716 -60.64556)
					(end 445.644016 -60.381388)
				)
				(arc
					(start 445.644016 -60.378848)
					(mid 445.910716 -60.112148)
					(end 446.177416 -60.378848)
				)
				(arc
					(start 446.914016 -60.378848)
					(mid 447.180716 -60.112148)
					(end 447.447416 -60.378848)
				)
				(arc
					(start 447.589656 -60.378848)
					(mid 447.46988 -60.089684)
					(end 447.180716 -59.969908)
				)
			)
		)
	)
	(zone
		(layers "B.Cu" "In1.Cu" "In2.Cu" "In3.Cu" "In4.Cu" "In5.Cu" "In6.Cu" "In7.Cu"
			"In8.Cu" "In10.Cu" "In11.Cu" "In12.Cu"
		)
		(hatch none 0.5)
		(connect_pads
			(clearance 0)
		)
		(min_thickness 0.25)
		(keepout
			(tracks not_allowed)
			(vias allowed)
			(pads allowed)
			(copperpour not_allowed)
			(footprints allowed)
		)
		(placement
			(enabled no)
			(sheetname "")
		)
		(fill yes
			(thermal_gap 0.5)
			(thermal_bridge_width 0.5)
			(island_removal_mode 0)
		)
		(polygon
			(pts
				(arc
					(start 441.110624 -9.675114)
					(mid 440.738514 -10.069576)
					(end 441.132976 -10.441686)
				)
				(xy 441.132976 -10.444226) (xy 442.122814 -10.41527) (xy 442.123068 -10.415016)
				(arc
					(start 442.123068 -10.41273)
					(mid 442.386068 -10.297512)
					(end 442.495432 -10.031984)
				)
				(arc
					(start 442.378592 -10.031984)
					(mid 442.126396 -10.296013)
					(end 441.84697 -10.06094)
				)
				(arc
					(start 441.3885 -10.06094)
					(mid 441.1218 -10.325112)
					(end 440.8551 -10.06094)
				)
				(arc
					(start 440.8551 -10.0584)
					(mid 441.1218 -9.7917)
					(end 441.3885 -10.0584)
				)
				(xy 441.846716 -10.0584) (xy 441.845192 -10.031984)
				(arc
					(start 441.845192 -10.029444)
					(mid 442.111892 -9.762744)
					(end 442.378592 -10.029444)
				)
				(arc
					(start 442.495432 -10.029444)
					(mid 442.379114 -9.754316)
					(end 442.100716 -9.646158)
				)
				(xy 442.100716 -9.643618) (xy 441.110624 -9.672574)
			)
		)
	)
	(zone
		(layers "B.Cu" "In1.Cu" "In2.Cu" "In3.Cu" "In4.Cu" "In5.Cu" "In6.Cu" "In7.Cu"
			"In8.Cu" "In10.Cu" "In11.Cu" "In12.Cu"
		)
		(hatch none 0.5)
		(connect_pads
			(clearance 0)
		)
		(min_thickness 0.25)
		(keepout
			(tracks not_allowed)
			(vias allowed)
			(pads allowed)
			(copperpour not_allowed)
			(footprints allowed)
		)
		(placement
			(enabled no)
			(sheetname "")
		)
		(fill yes
			(thermal_gap 0.5)
			(thermal_bridge_width 0.5)
			(island_removal_mode 0)
		)
		(polygon
			(pts
				(arc
					(start 437.814212 -2.507234)
					(mid 437.430672 -2.890774)
					(end 437.814212 -3.274314)
				)
				(arc
					(start 439.083958 -3.274314)
					(mid 439.354426 -3.162964)
					(end 439.467752 -2.893314)
				)
				(arc
					(start 439.350912 -2.893314)
					(mid 439.084212 -3.157486)
					(end 438.817512 -2.893314)
				)
				(arc
					(start 438.080912 -2.893314)
					(mid 437.814212 -3.157486)
					(end 437.547512 -2.893314)
				)
				(arc
					(start 437.547512 -2.890774)
					(mid 437.814212 -2.624074)
					(end 438.080912 -2.890774)
				)
				(arc
					(start 438.817512 -2.890774)
					(mid 439.084212 -2.624074)
					(end 439.350912 -2.890774)
				)
				(arc
					(start 439.467752 -2.890774)
					(mid 439.355416 -2.61957)
					(end 439.084212 -2.507234)
				)
			)
		)
	)
	(zone
		(layers "B.Cu" "In1.Cu" "In2.Cu" "In3.Cu" "In4.Cu" "In5.Cu" "In6.Cu" "In7.Cu"
			"In8.Cu" "In10.Cu" "In11.Cu" "In12.Cu"
		)
		(hatch none 0.5)
		(connect_pads
			(clearance 0)
		)
		(min_thickness 0.25)
		(keepout
			(tracks not_allowed)
			(vias allowed)
			(pads allowed)
			(copperpour not_allowed)
			(footprints allowed)
		)
		(placement
			(enabled no)
			(sheetname "")
		)
		(fill yes
			(thermal_gap 0.5)
			(thermal_bridge_width 0.5)
			(island_removal_mode 0)
		)
		(polygon
			(pts
				(arc
					(start 460.319882 -63.217552)
					(mid 459.910688 -63.626365)
					(end 460.319628 -64.035432)
				)
				(arc
					(start 461.589628 -64.035432)
					(mid 461.877893 -63.916553)
					(end 461.998568 -63.629032)
				)
				(arc
					(start 461.856328 -63.629032)
					(mid 461.589628 -63.893204)
					(end 461.322928 -63.629032)
				)
				(arc
					(start 460.586328 -63.629032)
					(mid 460.319628 -63.893204)
					(end 460.052928 -63.629032)
				)
				(arc
					(start 460.052928 -63.626492)
					(mid 460.319628 -63.359792)
					(end 460.586328 -63.626492)
				)
				(arc
					(start 461.322928 -63.626492)
					(mid 461.589628 -63.359792)
					(end 461.856328 -63.626492)
				)
				(arc
					(start 461.998568 -63.626492)
					(mid 461.878792 -63.337328)
					(end 461.589628 -63.217552)
				)
			)
		)
	)
	(zone
		(layers "B.Cu" "In1.Cu" "In2.Cu" "In3.Cu" "In4.Cu" "In5.Cu" "In6.Cu" "In7.Cu"
			"In8.Cu" "In10.Cu" "In11.Cu" "In12.Cu"
		)
		(hatch none 0.5)
		(connect_pads
			(clearance 0)
		)
		(min_thickness 0.25)
		(keepout
			(tracks not_allowed)
			(vias allowed)
			(pads allowed)
			(copperpour not_allowed)
			(footprints allowed)
		)
		(placement
			(enabled no)
			(sheetname "")
		)
		(fill yes
			(thermal_gap 0.5)
			(thermal_bridge_width 0.5)
			(island_removal_mode 0)
		)
		(polygon
			(pts
				(arc
					(start 15.826994 -24.8285)
					(mid 15.443454 -24.44496)
					(end 15.059914 -24.8285)
				)
				(arc
					(start 15.059914 -26.098246)
					(mid 15.442057 -26.482038)
					(end 15.826994 -26.10104)
				)
				(arc
					(start 15.710154 -26.10104)
					(mid 15.443454 -26.365212)
					(end 15.176754 -26.10104)
				)
				(arc
					(start 15.176754 -26.0985)
					(mid 15.443454 -25.8318)
					(end 15.710154 -26.0985)
				)
				(xy 15.826994 -26.0985) (xy 15.826994 -24.83104)
				(arc
					(start 15.710154 -24.83104)
					(mid 15.443454 -25.095212)
					(end 15.176754 -24.83104)
				)
				(arc
					(start 15.176754 -24.8285)
					(mid 15.443454 -24.5618)
					(end 15.710154 -24.8285)
				)
			)
		)
	)
	(zone
		(layers "B.Cu" "In1.Cu" "In2.Cu" "In3.Cu" "In4.Cu" "In5.Cu" "In6.Cu" "In7.Cu"
			"In8.Cu" "In10.Cu" "In11.Cu" "In12.Cu"
		)
		(hatch none 0.5)
		(connect_pads
			(clearance 0)
		)
		(min_thickness 0.25)
		(keepout
			(tracks not_allowed)
			(vias allowed)
			(pads allowed)
			(copperpour not_allowed)
			(footprints allowed)
		)
		(placement
			(enabled no)
			(sheetname "")
		)
		(fill yes
			(thermal_gap 0.5)
			(thermal_bridge_width 0.5)
			(island_removal_mode 0)
		)
		(polygon
			(pts
				(arc
					(start 16.991076 -26.6065)
					(mid 16.607536 -26.22296)
					(end 16.223996 -26.6065)
				)
				(arc
					(start 16.223996 -27.876246)
					(mid 16.606139 -28.260038)
					(end 16.991076 -27.87904)
				)
				(arc
					(start 16.874236 -27.87904)
					(mid 16.607536 -28.143212)
					(end 16.340836 -27.87904)
				)
				(arc
					(start 16.340836 -27.8765)
					(mid 16.607536 -27.6098)
					(end 16.874236 -27.8765)
				)
				(xy 16.991076 -27.8765) (xy 16.991076 -26.60904)
				(arc
					(start 16.874236 -26.60904)
					(mid 16.607536 -26.873212)
					(end 16.340836 -26.60904)
				)
				(arc
					(start 16.340836 -26.6065)
					(mid 16.607536 -26.3398)
					(end 16.874236 -26.6065)
				)
			)
		)
	)
	(zone
		(layers "B.Cu" "In1.Cu" "In2.Cu" "In3.Cu" "In4.Cu" "In5.Cu" "In6.Cu" "In7.Cu"
			"In8.Cu" "In10.Cu" "In11.Cu" "In12.Cu"
		)
		(hatch none 0.5)
		(connect_pads
			(clearance 0)
		)
		(min_thickness 0.25)
		(keepout
			(tracks not_allowed)
			(vias allowed)
			(pads allowed)
			(copperpour not_allowed)
			(footprints allowed)
		)
		(placement
			(enabled no)
			(sheetname "")
		)
		(fill yes
			(thermal_gap 0.5)
			(thermal_bridge_width 0.5)
			(island_removal_mode 0)
		)
		(polygon
			(pts
				(arc
					(start 450.710808 -59.969908)
					(mid 450.301614 -60.378721)
					(end 450.710554 -60.787788)
				)
				(arc
					(start 451.980554 -60.787788)
					(mid 452.268819 -60.668909)
					(end 452.389494 -60.381388)
				)
				(arc
					(start 452.247254 -60.381388)
					(mid 451.980554 -60.64556)
					(end 451.713854 -60.381388)
				)
				(arc
					(start 450.977254 -60.381388)
					(mid 450.710554 -60.64556)
					(end 450.443854 -60.381388)
				)
				(arc
					(start 450.443854 -60.378848)
					(mid 450.710554 -60.112148)
					(end 450.977254 -60.378848)
				)
				(arc
					(start 451.713854 -60.378848)
					(mid 451.980554 -60.112148)
					(end 452.247254 -60.378848)
				)
				(arc
					(start 452.389494 -60.378848)
					(mid 452.269718 -60.089684)
					(end 451.980554 -59.969908)
				)
			)
		)
	)
	(zone
		(layers "B.Cu" "In1.Cu" "In2.Cu" "In3.Cu" "In5.Cu" "In6.Cu" "In7.Cu" "In8.Cu"
			"In9.Cu" "In10.Cu" "In11.Cu" "In12.Cu"
		)
		(hatch none 0.5)
		(connect_pads
			(clearance 0)
		)
		(min_thickness 0.25)
		(keepout
			(tracks not_allowed)
			(vias allowed)
			(pads allowed)
			(copperpour not_allowed)
			(footprints allowed)
		)
		(placement
			(enabled no)
			(sheetname "")
		)
		(fill yes
			(thermal_gap 0.5)
			(thermal_bridge_width 0.5)
			(island_removal_mode 0)
		)
		(polygon
			(pts
				(arc
					(start 361.300268 -2.553462)
					(mid 360.916728 -2.937002)
					(end 361.300268 -3.320542)
				)
				(arc
					(start 362.570014 -3.320542)
					(mid 362.840482 -3.209192)
					(end 362.953808 -2.939542)
				)
				(arc
					(start 362.836968 -2.939542)
					(mid 362.570268 -3.203714)
					(end 362.303568 -2.939542)
				)
				(arc
					(start 361.566968 -2.939542)
					(mid 361.300268 -3.203714)
					(end 361.033568 -2.939542)
				)
				(arc
					(start 361.033568 -2.937002)
					(mid 361.300268 -2.670302)
					(end 361.566968 -2.937002)
				)
				(arc
					(start 362.303568 -2.937002)
					(mid 362.570268 -2.670302)
					(end 362.836968 -2.937002)
				)
				(arc
					(start 362.953808 -2.937002)
					(mid 362.841472 -2.665798)
					(end 362.570268 -2.553462)
				)
			)
		)
	)
	(zone
		(layers "B.Cu" "In1.Cu" "In2.Cu" "In3.Cu" "In5.Cu" "In6.Cu" "In7.Cu" "In8.Cu"
			"In9.Cu" "In10.Cu" "In11.Cu" "In12.Cu"
		)
		(hatch none 0.5)
		(connect_pads
			(clearance 0)
		)
		(min_thickness 0.25)
		(keepout
			(tracks not_allowed)
			(vias allowed)
			(pads allowed)
			(copperpour not_allowed)
			(footprints allowed)
		)
		(placement
			(enabled no)
			(sheetname "")
		)
		(fill yes
			(thermal_gap 0.5)
			(thermal_bridge_width 0.5)
			(island_removal_mode 0)
		)
		(polygon
			(pts
				(arc
					(start 394.753846 -2.742184)
					(mid 394.370052 -3.125597)
					(end 394.753592 -3.509264)
				)
				(arc
					(start 395.769592 -3.509264)
					(mid 396.039896 -3.397824)
					(end 396.153132 -3.128264)
				)
				(arc
					(start 396.036292 -3.128264)
					(mid 395.769592 -3.392436)
					(end 395.502892 -3.128264)
				)
				(arc
					(start 395.020292 -3.128264)
					(mid 394.753592 -3.392436)
					(end 394.486892 -3.128264)
				)
				(arc
					(start 394.486892 -3.125724)
					(mid 394.753592 -2.859024)
					(end 395.020292 -3.125724)
				)
				(arc
					(start 395.502892 -3.125724)
					(mid 395.769592 -2.859024)
					(end 396.036292 -3.125724)
				)
				(arc
					(start 396.153132 -3.125724)
					(mid 396.040796 -2.85452)
					(end 395.769592 -2.742184)
				)
			)
		)
	)
	(zone
		(layers "B.Cu" "In1.Cu" "In2.Cu" "In3.Cu" "In5.Cu" "In6.Cu" "In7.Cu" "In8.Cu"
			"In9.Cu" "In10.Cu" "In11.Cu" "In12.Cu"
		)
		(hatch none 0.5)
		(connect_pads
			(clearance 0)
		)
		(min_thickness 0.25)
		(keepout
			(tracks not_allowed)
			(vias allowed)
			(pads allowed)
			(copperpour not_allowed)
			(footprints allowed)
		)
		(placement
			(enabled no)
			(sheetname "")
		)
		(fill yes
			(thermal_gap 0.5)
			(thermal_bridge_width 0.5)
			(island_removal_mode 0)
		)
		(polygon
			(pts
				(arc
					(start 461.107028 -44.45381)
					(mid 460.723488 -44.83735)
					(end 461.107028 -45.22089)
				)
				(arc
					(start 462.376774 -45.22089)
					(mid 462.647242 -45.10954)
					(end 462.760568 -44.83989)
				)
				(arc
					(start 462.643728 -44.83989)
					(mid 462.377028 -45.104062)
					(end 462.110328 -44.83989)
				)
				(arc
					(start 461.373728 -44.83989)
					(mid 461.107028 -45.104062)
					(end 460.840328 -44.83989)
				)
				(arc
					(start 460.840328 -44.83735)
					(mid 461.107028 -44.57065)
					(end 461.373728 -44.83735)
				)
				(arc
					(start 462.110328 -44.83735)
					(mid 462.377028 -44.57065)
					(end 462.643728 -44.83735)
				)
				(arc
					(start 462.760568 -44.83735)
					(mid 462.648232 -44.566146)
					(end 462.377028 -44.45381)
				)
			)
		)
	)
	(zone
		(layers "B.Cu" "In1.Cu" "In2.Cu" "In3.Cu" "In5.Cu" "In6.Cu" "In7.Cu" "In8.Cu"
			"In9.Cu" "In10.Cu" "In11.Cu" "In12.Cu"
		)
		(hatch none 0.5)
		(connect_pads
			(clearance 0)
		)
		(min_thickness 0.25)
		(keepout
			(tracks not_allowed)
			(vias allowed)
			(pads allowed)
			(copperpour not_allowed)
			(footprints allowed)
		)
		(placement
			(enabled no)
			(sheetname "")
		)
		(fill yes
			(thermal_gap 0.5)
			(thermal_bridge_width 0.5)
			(island_removal_mode 0)
		)
		(polygon
			(pts
				(arc
					(start 363.48035 -1.586484)
					(mid 363.09681 -1.970024)
					(end 363.48035 -2.353564)
				)
				(arc
					(start 364.750096 -2.353564)
					(mid 365.020564 -2.242214)
					(end 365.13389 -1.972564)
				)
				(arc
					(start 365.01705 -1.972564)
					(mid 364.75035 -2.236736)
					(end 364.48365 -1.972564)
				)
				(arc
					(start 363.74705 -1.972564)
					(mid 363.48035 -2.236736)
					(end 363.21365 -1.972564)
				)
				(arc
					(start 363.21365 -1.970024)
					(mid 363.48035 -1.703324)
					(end 363.74705 -1.970024)
				)
				(arc
					(start 364.48365 -1.970024)
					(mid 364.75035 -1.703324)
					(end 365.01705 -1.970024)
				)
				(arc
					(start 365.13389 -1.970024)
					(mid 365.021554 -1.69882)
					(end 364.75035 -1.586484)
				)
			)
		)
	)
	(zone
		(layers "B.Cu" "In1.Cu" "In2.Cu" "In3.Cu" "In5.Cu" "In6.Cu" "In7.Cu" "In8.Cu"
			"In9.Cu" "In10.Cu" "In11.Cu" "In12.Cu"
		)
		(hatch none 0.5)
		(connect_pads
			(clearance 0)
		)
		(min_thickness 0.25)
		(keepout
			(tracks not_allowed)
			(vias allowed)
			(pads allowed)
			(copperpour not_allowed)
			(footprints allowed)
		)
		(placement
			(enabled no)
			(sheetname "")
		)
		(fill yes
			(thermal_gap 0.5)
			(thermal_bridge_width 0.5)
			(island_removal_mode 0)
		)
		(polygon
			(pts
				(arc
					(start 378.14758 -1.371346)
					(mid 377.76404 -1.754886)
					(end 378.14758 -2.138426)
				)
				(arc
					(start 379.417326 -2.138426)
					(mid 379.687794 -2.027076)
					(end 379.80112 -1.757426)
				)
				(arc
					(start 379.68428 -1.757426)
					(mid 379.41758 -2.021598)
					(end 379.15088 -1.757426)
				)
				(arc
					(start 378.41428 -1.757426)
					(mid 378.14758 -2.021598)
					(end 377.88088 -1.757426)
				)
				(arc
					(start 377.88088 -1.754886)
					(mid 378.14758 -1.488186)
					(end 378.41428 -1.754886)
				)
				(arc
					(start 379.15088 -1.754886)
					(mid 379.41758 -1.488186)
					(end 379.68428 -1.754886)
				)
				(arc
					(start 379.80112 -1.754886)
					(mid 379.688784 -1.483682)
					(end 379.41758 -1.371346)
				)
			)
		)
	)
	(zone
		(layers "B.Cu" "In1.Cu" "In2.Cu" "In3.Cu" "In5.Cu" "In6.Cu" "In7.Cu" "In8.Cu"
			"In9.Cu" "In10.Cu" "In11.Cu" "In12.Cu"
		)
		(hatch none 0.5)
		(connect_pads
			(clearance 0)
		)
		(min_thickness 0.25)
		(keepout
			(tracks not_allowed)
			(vias allowed)
			(pads allowed)
			(copperpour not_allowed)
			(footprints allowed)
		)
		(placement
			(enabled no)
			(sheetname "")
		)
		(fill yes
			(thermal_gap 0.5)
			(thermal_bridge_width 0.5)
			(island_removal_mode 0)
		)
		(polygon
			(pts
				(arc
					(start 397.128492 -2.792984)
					(mid 396.744952 -3.176524)
					(end 397.128492 -3.560064)
				)
				(arc
					(start 398.144238 -3.560064)
					(mid 398.414706 -3.448714)
					(end 398.528032 -3.179064)
				)
				(arc
					(start 398.411192 -3.179064)
					(mid 398.144492 -3.443236)
					(end 397.877792 -3.179064)
				)
				(arc
					(start 397.395192 -3.179064)
					(mid 397.128492 -3.443236)
					(end 396.861792 -3.179064)
				)
				(arc
					(start 396.861792 -3.176524)
					(mid 397.128492 -2.909824)
					(end 397.395192 -3.176524)
				)
				(arc
					(start 397.877792 -3.176524)
					(mid 398.144492 -2.909824)
					(end 398.411192 -3.176524)
				)
				(arc
					(start 398.528032 -3.176524)
					(mid 398.415696 -2.90532)
					(end 398.144492 -2.792984)
				)
			)
		)
	)
	(zone
		(layers "B.Cu" "In1.Cu" "In2.Cu" "In3.Cu" "In5.Cu" "In6.Cu" "In7.Cu" "In8.Cu"
			"In9.Cu" "In10.Cu" "In11.Cu" "In12.Cu"
		)
		(hatch none 0.5)
		(connect_pads
			(clearance 0)
		)
		(min_thickness 0.25)
		(keepout
			(tracks not_allowed)
			(vias allowed)
			(pads allowed)
			(copperpour not_allowed)
			(footprints allowed)
		)
		(placement
			(enabled no)
			(sheetname "")
		)
		(fill yes
			(thermal_gap 0.5)
			(thermal_bridge_width 0.5)
			(island_removal_mode 0)
		)
		(polygon
			(pts
				(arc
					(start 349.712788 -23.414228)
					(mid 348.996506 -23.415498)
					(end 349.712788 -23.416768)
				)
				(arc
					(start 349.621348 -23.416768)
					(mid 349.354648 -23.68094)
					(end 349.087948 -23.416768)
				)
				(arc
					(start 349.087948 -23.414228)
					(mid 349.354648 -23.147528)
					(end 349.621348 -23.414228)
				)
			)
		)
	)
	(zone
		(layers "B.Cu" "In1.Cu" "In2.Cu" "In3.Cu" "In5.Cu" "In6.Cu" "In7.Cu" "In8.Cu"
			"In9.Cu" "In10.Cu" "In11.Cu" "In12.Cu"
		)
		(hatch none 0.5)
		(connect_pads
			(clearance 0)
		)
		(min_thickness 0.25)
		(keepout
			(tracks not_allowed)
			(vias allowed)
			(pads allowed)
			(copperpour not_allowed)
			(footprints allowed)
		)
		(placement
			(enabled no)
			(sheetname "")
		)
		(fill yes
			(thermal_gap 0.5)
			(thermal_bridge_width 0.5)
			(island_removal_mode 0)
		)
		(polygon
			(pts
				(arc
					(start 368.297714 -1.036066)
					(mid 367.914174 -1.419606)
					(end 368.297714 -1.803146)
				)
				(arc
					(start 369.56746 -1.803146)
					(mid 369.837928 -1.691796)
					(end 369.951254 -1.422146)
				)
				(arc
					(start 369.834414 -1.422146)
					(mid 369.567714 -1.686318)
					(end 369.301014 -1.422146)
				)
				(arc
					(start 368.564414 -1.422146)
					(mid 368.297714 -1.686318)
					(end 368.031014 -1.422146)
				)
				(arc
					(start 368.031014 -1.419606)
					(mid 368.297714 -1.152906)
					(end 368.564414 -1.419606)
				)
				(arc
					(start 369.301014 -1.419606)
					(mid 369.567714 -1.152906)
					(end 369.834414 -1.419606)
				)
				(arc
					(start 369.951254 -1.419606)
					(mid 369.838918 -1.148402)
					(end 369.567714 -1.036066)
				)
			)
		)
	)
	(zone
		(layers "B.Cu" "In1.Cu" "In2.Cu" "In3.Cu" "In5.Cu" "In6.Cu" "In7.Cu" "In8.Cu"
			"In9.Cu" "In10.Cu" "In11.Cu" "In12.Cu"
		)
		(hatch none 0.5)
		(connect_pads
			(clearance 0)
		)
		(min_thickness 0.25)
		(keepout
			(tracks not_allowed)
			(vias allowed)
			(pads allowed)
			(copperpour not_allowed)
			(footprints allowed)
		)
		(placement
			(enabled no)
			(sheetname "")
		)
		(fill yes
			(thermal_gap 0.5)
			(thermal_bridge_width 0.5)
			(island_removal_mode 0)
		)
		(polygon
			(pts
				(arc
					(start 445.107314 -44.45381)
					(mid 444.723774 -44.837223)
					(end 445.10706 -45.22089)
				)
				(arc
					(start 446.37706 -45.22089)
					(mid 446.647364 -45.10945)
					(end 446.7606 -44.83989)
				)
				(arc
					(start 446.64376 -44.83989)
					(mid 446.37706 -45.104062)
					(end 446.11036 -44.83989)
				)
				(arc
					(start 445.37376 -44.83989)
					(mid 445.10706 -45.104062)
					(end 444.84036 -44.83989)
				)
				(arc
					(start 444.84036 -44.83735)
					(mid 445.10706 -44.57065)
					(end 445.37376 -44.83735)
				)
				(arc
					(start 446.11036 -44.83735)
					(mid 446.37706 -44.57065)
					(end 446.64376 -44.83735)
				)
				(arc
					(start 446.7606 -44.83735)
					(mid 446.648264 -44.566146)
					(end 446.37706 -44.45381)
				)
			)
		)
	)
	(zone
		(layers "B.Cu" "In1.Cu" "In2.Cu" "In3.Cu" "In5.Cu" "In6.Cu" "In7.Cu" "In8.Cu"
			"In9.Cu" "In10.Cu" "In11.Cu" "In12.Cu"
		)
		(hatch none 0.5)
		(connect_pads
			(clearance 0)
		)
		(min_thickness 0.25)
		(keepout
			(tracks not_allowed)
			(vias allowed)
			(pads allowed)
			(copperpour not_allowed)
			(footprints allowed)
		)
		(placement
			(enabled no)
			(sheetname "")
		)
		(fill yes
			(thermal_gap 0.5)
			(thermal_bridge_width 0.5)
			(island_removal_mode 0)
		)
		(polygon
			(pts
				(arc
					(start 366.100614 -2.553462)
					(mid 365.717074 -2.936875)
					(end 366.10036 -3.320542)
				)
				(arc
					(start 367.37036 -3.320542)
					(mid 367.640664 -3.209102)
					(end 367.7539 -2.939542)
				)
				(arc
					(start 367.63706 -2.939542)
					(mid 367.37036 -3.203714)
					(end 367.10366 -2.939542)
				)
				(arc
					(start 366.36706 -2.939542)
					(mid 366.10036 -3.203714)
					(end 365.83366 -2.939542)
				)
				(arc
					(start 365.83366 -2.937002)
					(mid 366.10036 -2.670302)
					(end 366.36706 -2.937002)
				)
				(arc
					(start 367.10366 -2.937002)
					(mid 367.37036 -2.670302)
					(end 367.63706 -2.937002)
				)
				(arc
					(start 367.7539 -2.937002)
					(mid 367.641564 -2.665798)
					(end 367.37036 -2.553462)
				)
			)
		)
	)
	(zone
		(layers "B.Cu" "In1.Cu" "In2.Cu" "In3.Cu" "In5.Cu" "In6.Cu" "In7.Cu" "In8.Cu"
			"In9.Cu" "In10.Cu" "In11.Cu" "In12.Cu"
		)
		(hatch none 0.5)
		(connect_pads
			(clearance 0)
		)
		(min_thickness 0.25)
		(keepout
			(tracks not_allowed)
			(vias allowed)
			(pads allowed)
			(copperpour not_allowed)
			(footprints allowed)
		)
		(placement
			(enabled no)
			(sheetname "")
		)
		(fill yes
			(thermal_gap 0.5)
			(thermal_bridge_width 0.5)
			(island_removal_mode 0)
		)
		(polygon
			(pts
				(arc
					(start 408.897582 -0.99441)
					(mid 408.514042 -1.37795)
					(end 408.897582 -1.76149)
				)
				(arc
					(start 410.167328 -1.76149)
					(mid 410.437796 -1.65014)
					(end 410.551122 -1.38049)
				)
				(arc
					(start 410.434282 -1.38049)
					(mid 410.167582 -1.644662)
					(end 409.900882 -1.38049)
				)
				(arc
					(start 409.164282 -1.38049)
					(mid 408.897582 -1.644662)
					(end 408.630882 -1.38049)
				)
				(arc
					(start 408.630882 -1.37795)
					(mid 408.897582 -1.11125)
					(end 409.164282 -1.37795)
				)
				(arc
					(start 409.900882 -1.37795)
					(mid 410.167582 -1.11125)
					(end 410.434282 -1.37795)
				)
				(arc
					(start 410.551122 -1.37795)
					(mid 410.438786 -1.106746)
					(end 410.167582 -0.99441)
				)
			)
		)
	)
	(zone
		(layers "B.Cu" "In1.Cu" "In2.Cu" "In3.Cu" "In5.Cu" "In6.Cu" "In7.Cu" "In8.Cu"
			"In9.Cu" "In10.Cu" "In11.Cu" "In12.Cu"
		)
		(hatch none 0.5)
		(connect_pads
			(clearance 0)
		)
		(min_thickness 0.25)
		(keepout
			(tracks not_allowed)
			(vias allowed)
			(pads allowed)
			(copperpour not_allowed)
			(footprints allowed)
		)
		(placement
			(enabled no)
			(sheetname "")
		)
		(fill yes
			(thermal_gap 0.5)
			(thermal_bridge_width 0.5)
			(island_removal_mode 0)
		)
		(polygon
			(pts
				(arc
					(start 441.907422 -44.45381)
					(mid 441.523882 -44.837223)
					(end 441.907168 -45.22089)
				)
				(arc
					(start 443.177168 -45.22089)
					(mid 443.447472 -45.10945)
					(end 443.560708 -44.83989)
				)
				(arc
					(start 443.443868 -44.83989)
					(mid 443.177168 -45.104062)
					(end 442.910468 -44.83989)
				)
				(arc
					(start 442.173868 -44.83989)
					(mid 441.907168 -45.104062)
					(end 441.640468 -44.83989)
				)
				(arc
					(start 441.640468 -44.83735)
					(mid 441.907168 -44.57065)
					(end 442.173868 -44.83735)
				)
				(arc
					(start 442.910468 -44.83735)
					(mid 443.177168 -44.57065)
					(end 443.443868 -44.83735)
				)
				(arc
					(start 443.560708 -44.83735)
					(mid 443.448372 -44.566146)
					(end 443.177168 -44.45381)
				)
			)
		)
	)
	(zone
		(layers "B.Cu" "In1.Cu" "In2.Cu" "In3.Cu" "In5.Cu" "In6.Cu" "In7.Cu" "In8.Cu"
			"In9.Cu" "In10.Cu" "In11.Cu" "In12.Cu"
		)
		(hatch none 0.5)
		(connect_pads
			(clearance 0)
		)
		(min_thickness 0.25)
		(keepout
			(tracks not_allowed)
			(vias allowed)
			(pads allowed)
			(copperpour not_allowed)
			(footprints allowed)
		)
		(placement
			(enabled no)
			(sheetname "")
		)
		(fill yes
			(thermal_gap 0.5)
			(thermal_bridge_width 0.5)
			(island_removal_mode 0)
		)
		(polygon
			(pts
				(arc
					(start 404.329392 -2.513584)
					(mid 403.945852 -2.897124)
					(end 404.329392 -3.280664)
				)
				(arc
					(start 405.345138 -3.280664)
					(mid 405.615606 -3.169314)
					(end 405.728932 -2.899664)
				)
				(arc
					(start 405.612092 -2.899664)
					(mid 405.345392 -3.163836)
					(end 405.078692 -2.899664)
				)
				(arc
					(start 404.596092 -2.899664)
					(mid 404.329392 -3.163836)
					(end 404.062692 -2.899664)
				)
				(arc
					(start 404.062692 -2.897124)
					(mid 404.329392 -2.630424)
					(end 404.596092 -2.897124)
				)
				(arc
					(start 405.078692 -2.897124)
					(mid 405.345392 -2.630424)
					(end 405.612092 -2.897124)
				)
				(arc
					(start 405.728932 -2.897124)
					(mid 405.616596 -2.62592)
					(end 405.345392 -2.513584)
				)
			)
		)
	)
	(zone
		(layers "B.Cu" "In1.Cu" "In2.Cu" "In3.Cu" "In5.Cu" "In6.Cu" "In7.Cu" "In8.Cu"
			"In9.Cu" "In10.Cu" "In11.Cu" "In12.Cu"
		)
		(hatch none 0.5)
		(connect_pads
			(clearance 0)
		)
		(min_thickness 0.25)
		(keepout
			(tracks not_allowed)
			(vias allowed)
			(pads allowed)
			(copperpour not_allowed)
			(footprints allowed)
		)
		(placement
			(enabled no)
			(sheetname "")
		)
		(fill yes
			(thermal_gap 0.5)
			(thermal_bridge_width 0.5)
			(island_removal_mode 0)
		)
		(polygon
			(pts
				(arc
					(start 401.827492 -2.50063)
					(mid 401.443952 -2.88417)
					(end 401.827492 -3.26771)
				)
				(arc
					(start 403.097238 -3.26771)
					(mid 403.367706 -3.15636)
					(end 403.481032 -2.88671)
				)
				(arc
					(start 403.364192 -2.88671)
					(mid 403.097492 -3.150882)
					(end 402.830792 -2.88671)
				)
				(arc
					(start 402.094192 -2.88671)
					(mid 401.827492 -3.150882)
					(end 401.560792 -2.88671)
				)
				(arc
					(start 401.560792 -2.88417)
					(mid 401.827492 -2.61747)
					(end 402.094192 -2.88417)
				)
				(arc
					(start 402.830792 -2.88417)
					(mid 403.097492 -2.61747)
					(end 403.364192 -2.88417)
				)
				(arc
					(start 403.481032 -2.88417)
					(mid 403.368696 -2.612966)
					(end 403.097492 -2.50063)
				)
			)
		)
	)
	(zone
		(layers "B.Cu" "In1.Cu" "In2.Cu" "In3.Cu" "In5.Cu" "In6.Cu" "In7.Cu" "In8.Cu"
			"In9.Cu" "In10.Cu" "In11.Cu" "In12.Cu"
		)
		(hatch none 0.5)
		(connect_pads
			(clearance 0)
		)
		(min_thickness 0.25)
		(keepout
			(tracks not_allowed)
			(vias allowed)
			(pads allowed)
			(copperpour not_allowed)
			(footprints allowed)
		)
		(placement
			(enabled no)
			(sheetname "")
		)
		(fill yes
			(thermal_gap 0.5)
			(thermal_bridge_width 0.5)
			(island_removal_mode 0)
		)
		(polygon
			(pts
				(arc
					(start 370.900198 -2.553462)
					(mid 370.516658 -2.937002)
					(end 370.900198 -3.320542)
				)
				(arc
					(start 372.169944 -3.320542)
					(mid 372.440412 -3.209192)
					(end 372.553738 -2.939542)
				)
				(arc
					(start 372.436898 -2.939542)
					(mid 372.170198 -3.203714)
					(end 371.903498 -2.939542)
				)
				(arc
					(start 371.166898 -2.939542)
					(mid 370.900198 -3.203714)
					(end 370.633498 -2.939542)
				)
				(arc
					(start 370.633498 -2.937002)
					(mid 370.900198 -2.670302)
					(end 371.166898 -2.937002)
				)
				(arc
					(start 371.903498 -2.937002)
					(mid 372.170198 -2.670302)
					(end 372.436898 -2.937002)
				)
				(arc
					(start 372.553738 -2.937002)
					(mid 372.441402 -2.665798)
					(end 372.170198 -2.553462)
				)
			)
		)
	)
	(zone
		(layers "B.Cu" "In1.Cu" "In2.Cu" "In3.Cu" "In5.Cu" "In6.Cu" "In7.Cu" "In8.Cu"
			"In9.Cu" "In10.Cu" "In11.Cu" "In12.Cu"
		)
		(hatch none 0.5)
		(connect_pads
			(clearance 0)
		)
		(min_thickness 0.25)
		(keepout
			(tracks not_allowed)
			(vias allowed)
			(pads allowed)
			(copperpour not_allowed)
			(footprints allowed)
		)
		(placement
			(enabled no)
			(sheetname "")
		)
		(fill yes
			(thermal_gap 0.5)
			(thermal_bridge_width 0.5)
			(island_removal_mode 0)
		)
		(polygon
			(pts
				(arc
					(start 406.628092 -2.50063)
					(mid 406.244552 -2.88417)
					(end 406.628092 -3.26771)
				)
				(arc
					(start 407.897838 -3.26771)
					(mid 408.168306 -3.15636)
					(end 408.281632 -2.88671)
				)
				(arc
					(start 408.164792 -2.88671)
					(mid 407.898092 -3.150882)
					(end 407.631392 -2.88671)
				)
				(arc
					(start 406.894792 -2.88671)
					(mid 406.628092 -3.150882)
					(end 406.361392 -2.88671)
				)
				(arc
					(start 406.361392 -2.88417)
					(mid 406.628092 -2.61747)
					(end 406.894792 -2.88417)
				)
				(arc
					(start 407.631392 -2.88417)
					(mid 407.898092 -2.61747)
					(end 408.164792 -2.88417)
				)
				(arc
					(start 408.281632 -2.88417)
					(mid 408.169296 -2.612966)
					(end 407.898092 -2.50063)
				)
			)
		)
	)
	(zone
		(layers "B.Cu" "In1.Cu" "In2.Cu" "In3.Cu" "In5.Cu" "In6.Cu" "In7.Cu" "In8.Cu"
			"In9.Cu" "In10.Cu" "In11.Cu" "In12.Cu"
		)
		(hatch none 0.5)
		(connect_pads
			(clearance 0)
		)
		(min_thickness 0.25)
		(keepout
			(tracks not_allowed)
			(vias allowed)
			(pads allowed)
			(copperpour not_allowed)
			(footprints allowed)
		)
		(placement
			(enabled no)
			(sheetname "")
		)
		(fill yes
			(thermal_gap 0.5)
			(thermal_bridge_width 0.5)
			(island_removal_mode 0)
		)
		(polygon
			(pts
				(arc
					(start 457.907136 -44.45381)
					(mid 457.523596 -44.83735)
					(end 457.907136 -45.22089)
				)
				(arc
					(start 459.176882 -45.22089)
					(mid 459.44735 -45.10954)
					(end 459.560676 -44.83989)
				)
				(arc
					(start 459.443836 -44.83989)
					(mid 459.177136 -45.104062)
					(end 458.910436 -44.83989)
				)
				(arc
					(start 458.173836 -44.83989)
					(mid 457.907136 -45.104062)
					(end 457.640436 -44.83989)
				)
				(arc
					(start 457.640436 -44.83735)
					(mid 457.907136 -44.57065)
					(end 458.173836 -44.83735)
				)
				(arc
					(start 458.910436 -44.83735)
					(mid 459.177136 -44.57065)
					(end 459.443836 -44.83735)
				)
				(arc
					(start 459.560676 -44.83735)
					(mid 459.44834 -44.566146)
					(end 459.177136 -44.45381)
				)
			)
		)
	)
	(zone
		(layers "B.Cu" "In1.Cu" "In2.Cu" "In3.Cu" "In5.Cu" "In6.Cu" "In7.Cu" "In8.Cu"
			"In9.Cu" "In10.Cu" "In11.Cu" "In12.Cu"
		)
		(hatch none 0.5)
		(connect_pads
			(clearance 0)
		)
		(min_thickness 0.25)
		(keepout
			(tracks not_allowed)
			(vias allowed)
			(pads allowed)
			(copperpour not_allowed)
			(footprints allowed)
		)
		(placement
			(enabled no)
			(sheetname "")
		)
		(fill yes
			(thermal_gap 0.5)
			(thermal_bridge_width 0.5)
			(island_removal_mode 0)
		)
		(polygon
			(pts
				(arc
					(start 392.353292 -2.792984)
					(mid 391.969752 -3.176524)
					(end 392.353292 -3.560064)
				)
				(arc
					(start 393.369038 -3.560064)
					(mid 393.639506 -3.448714)
					(end 393.752832 -3.179064)
				)
				(arc
					(start 393.635992 -3.179064)
					(mid 393.369292 -3.443236)
					(end 393.102592 -3.179064)
				)
				(arc
					(start 392.619992 -3.179064)
					(mid 392.353292 -3.443236)
					(end 392.086592 -3.179064)
				)
				(arc
					(start 392.086592 -3.176524)
					(mid 392.353292 -2.909824)
					(end 392.619992 -3.176524)
				)
				(arc
					(start 393.102592 -3.176524)
					(mid 393.369292 -2.909824)
					(end 393.635992 -3.176524)
				)
				(arc
					(start 393.752832 -3.176524)
					(mid 393.640496 -2.90532)
					(end 393.369292 -2.792984)
				)
			)
		)
	)
	(zone
		(layers "B.Cu" "In1.Cu" "In2.Cu" "In3.Cu" "In5.Cu" "In6.Cu" "In7.Cu" "In8.Cu"
			"In9.Cu" "In10.Cu" "In11.Cu" "In12.Cu"
		)
		(hatch none 0.5)
		(connect_pads
			(clearance 0)
		)
		(min_thickness 0.25)
		(keepout
			(tracks not_allowed)
			(vias allowed)
			(pads allowed)
			(copperpour not_allowed)
			(footprints allowed)
		)
		(placement
			(enabled no)
			(sheetname "")
		)
		(fill yes
			(thermal_gap 0.5)
			(thermal_bridge_width 0.5)
			(island_removal_mode 0)
		)
		(polygon
			(pts
				(arc
					(start 448.307206 -44.45381)
					(mid 447.923412 -44.837223)
					(end 448.306952 -45.22089)
				)
				(arc
					(start 449.576952 -45.22089)
					(mid 449.847256 -45.10945)
					(end 449.960492 -44.83989)
				)
				(arc
					(start 449.843652 -44.83989)
					(mid 449.576952 -45.104062)
					(end 449.310252 -44.83989)
				)
				(arc
					(start 448.573652 -44.83989)
					(mid 448.306952 -45.104062)
					(end 448.040252 -44.83989)
				)
				(arc
					(start 448.040252 -44.83735)
					(mid 448.306952 -44.57065)
					(end 448.573652 -44.83735)
				)
				(arc
					(start 449.310252 -44.83735)
					(mid 449.576952 -44.57065)
					(end 449.843652 -44.83735)
				)
				(arc
					(start 449.960492 -44.83735)
					(mid 449.848156 -44.566146)
					(end 449.576952 -44.45381)
				)
			)
		)
	)
	(zone
		(layers "B.Cu" "In1.Cu" "In2.Cu" "In3.Cu" "In5.Cu" "In6.Cu" "In7.Cu" "In8.Cu"
			"In9.Cu" "In10.Cu" "In11.Cu" "In12.Cu"
		)
		(hatch none 0.5)
		(connect_pads
			(clearance 0)
		)
		(min_thickness 0.25)
		(keepout
			(tracks not_allowed)
			(vias allowed)
			(pads allowed)
			(copperpour not_allowed)
			(footprints allowed)
		)
		(placement
			(enabled no)
			(sheetname "")
		)
		(fill yes
			(thermal_gap 0.5)
			(thermal_bridge_width 0.5)
			(island_removal_mode 0)
		)
		(polygon
			(pts
				(arc
					(start 438.707276 -44.45381)
					(mid 438.323736 -44.837223)
					(end 438.707022 -45.22089)
				)
				(arc
					(start 439.977022 -45.22089)
					(mid 440.247326 -45.10945)
					(end 440.360562 -44.83989)
				)
				(arc
					(start 440.243722 -44.83989)
					(mid 439.977022 -45.104062)
					(end 439.710322 -44.83989)
				)
				(arc
					(start 438.973722 -44.83989)
					(mid 438.707022 -45.104062)
					(end 438.440322 -44.83989)
				)
				(arc
					(start 438.440322 -44.83735)
					(mid 438.707022 -44.57065)
					(end 438.973722 -44.83735)
				)
				(arc
					(start 439.710322 -44.83735)
					(mid 439.977022 -44.57065)
					(end 440.243722 -44.83735)
				)
				(arc
					(start 440.360562 -44.83735)
					(mid 440.248226 -44.566146)
					(end 439.977022 -44.45381)
				)
			)
		)
	)
	(zone
		(layers "B.Cu" "In1.Cu" "In2.Cu" "In3.Cu" "In5.Cu" "In6.Cu" "In7.Cu" "In8.Cu"
			"In9.Cu" "In10.Cu" "In11.Cu" "In12.Cu"
		)
		(hatch none 0.5)
		(connect_pads
			(clearance 0)
		)
		(min_thickness 0.25)
		(keepout
			(tracks not_allowed)
			(vias allowed)
			(pads allowed)
			(copperpour not_allowed)
			(footprints allowed)
		)
		(placement
			(enabled no)
			(sheetname "")
		)
		(fill yes
			(thermal_gap 0.5)
			(thermal_bridge_width 0.5)
			(island_removal_mode 0)
		)
		(polygon
			(pts
				(arc
					(start 451.507098 -44.45381)
					(mid 451.123558 -44.83735)
					(end 451.507098 -45.22089)
				)
				(arc
					(start 452.776844 -45.22089)
					(mid 453.047312 -45.10954)
					(end 453.160638 -44.83989)
				)
				(arc
					(start 453.043798 -44.83989)
					(mid 452.777098 -45.104062)
					(end 452.510398 -44.83989)
				)
				(arc
					(start 451.773798 -44.83989)
					(mid 451.507098 -45.104062)
					(end 451.240398 -44.83989)
				)
				(arc
					(start 451.240398 -44.83735)
					(mid 451.507098 -44.57065)
					(end 451.773798 -44.83735)
				)
				(arc
					(start 452.510398 -44.83735)
					(mid 452.777098 -44.57065)
					(end 453.043798 -44.83735)
				)
				(arc
					(start 453.160638 -44.83735)
					(mid 453.048302 -44.566146)
					(end 452.777098 -44.45381)
				)
			)
		)
	)
	(zone
		(layers "B.Cu" "In1.Cu" "In2.Cu" "In3.Cu" "In5.Cu" "In6.Cu" "In7.Cu" "In8.Cu"
			"In9.Cu" "In10.Cu" "In11.Cu" "In12.Cu"
		)
		(hatch none 0.5)
		(connect_pads
			(clearance 0)
		)
		(min_thickness 0.25)
		(keepout
			(tracks not_allowed)
			(vias allowed)
			(pads allowed)
			(copperpour not_allowed)
			(footprints allowed)
		)
		(placement
			(enabled no)
			(sheetname "")
		)
		(fill yes
			(thermal_gap 0.5)
			(thermal_bridge_width 0.5)
			(island_removal_mode 0)
		)
		(polygon
			(pts
				(arc
					(start 454.707244 -44.45381)
					(mid 454.32345 -44.837223)
					(end 454.70699 -45.22089)
				)
				(arc
					(start 455.97699 -45.22089)
					(mid 456.247294 -45.10945)
					(end 456.36053 -44.83989)
				)
				(arc
					(start 456.24369 -44.83989)
					(mid 455.97699 -45.104062)
					(end 455.71029 -44.83989)
				)
				(arc
					(start 454.97369 -44.83989)
					(mid 454.70699 -45.104062)
					(end 454.44029 -44.83989)
				)
				(arc
					(start 454.44029 -44.83735)
					(mid 454.70699 -44.57065)
					(end 454.97369 -44.83735)
				)
				(arc
					(start 455.71029 -44.83735)
					(mid 455.97699 -44.57065)
					(end 456.24369 -44.83735)
				)
				(arc
					(start 456.36053 -44.83735)
					(mid 456.248194 -44.566146)
					(end 455.97699 -44.45381)
				)
			)
		)
	)
	(zone
		(layers "B.Cu" "In1.Cu" "In2.Cu" "In3.Cu" "In5.Cu" "In6.Cu" "In7.Cu" "In8.Cu"
			"In9.Cu" "In10.Cu" "In11.Cu" "In12.Cu"
		)
		(hatch none 0.5)
		(connect_pads
			(clearance 0)
		)
		(min_thickness 0.25)
		(keepout
			(tracks not_allowed)
			(vias allowed)
			(pads allowed)
			(copperpour not_allowed)
			(footprints allowed)
		)
		(placement
			(enabled no)
			(sheetname "")
		)
		(fill yes
			(thermal_gap 0.5)
			(thermal_bridge_width 0.5)
			(island_removal_mode 0)
		)
		(polygon
			(pts
				(arc
					(start 373.224552 -1.036066)
					(mid 372.841012 -1.419606)
					(end 373.224552 -1.803146)
				)
				(arc
					(start 374.494298 -1.803146)
					(mid 374.764766 -1.691796)
					(end 374.878092 -1.422146)
				)
				(arc
					(start 374.761252 -1.422146)
					(mid 374.494552 -1.686318)
					(end 374.227852 -1.422146)
				)
				(arc
					(start 373.491252 -1.422146)
					(mid 373.224552 -1.686318)
					(end 372.957852 -1.422146)
				)
				(arc
					(start 372.957852 -1.419606)
					(mid 373.224552 -1.152906)
					(end 373.491252 -1.419606)
				)
				(arc
					(start 374.227852 -1.419606)
					(mid 374.494552 -1.152906)
					(end 374.761252 -1.419606)
				)
				(arc
					(start 374.878092 -1.419606)
					(mid 374.765756 -1.148402)
					(end 374.494552 -1.036066)
				)
			)
		)
	)
	(zone
		(layers "B.Cu" "In1.Cu" "In2.Cu" "In3.Cu" "In5.Cu" "In6.Cu" "In7.Cu" "In8.Cu"
			"In9.Cu" "In10.Cu" "In11.Cu" "In12.Cu"
		)
		(hatch none 0.5)
		(connect_pads
			(clearance 0)
		)
		(min_thickness 0.25)
		(keepout
			(tracks not_allowed)
			(vias allowed)
			(pads allowed)
			(copperpour not_allowed)
			(footprints allowed)
		)
		(placement
			(enabled no)
			(sheetname "")
		)
		(fill yes
			(thermal_gap 0.5)
			(thermal_bridge_width 0.5)
			(island_removal_mode 0)
		)
		(polygon
			(pts
				(arc
					(start 375.70029 -2.553462)
					(mid 375.31675 -2.937002)
					(end 375.70029 -3.320542)
				)
				(arc
					(start 376.970036 -3.320542)
					(mid 377.240504 -3.209192)
					(end 377.35383 -2.939542)
				)
				(arc
					(start 377.23699 -2.939542)
					(mid 376.97029 -3.203714)
					(end 376.70359 -2.939542)
				)
				(arc
					(start 375.96699 -2.939542)
					(mid 375.70029 -3.203714)
					(end 375.43359 -2.939542)
				)
				(arc
					(start 375.43359 -2.937002)
					(mid 375.70029 -2.670302)
					(end 375.96699 -2.937002)
				)
				(arc
					(start 376.70359 -2.937002)
					(mid 376.97029 -2.670302)
					(end 377.23699 -2.937002)
				)
				(arc
					(start 377.35383 -2.937002)
					(mid 377.241494 -2.665798)
					(end 376.97029 -2.553462)
				)
			)
		)
	)
	(zone
		(layers "B.Cu" "In1.Cu" "In2.Cu" "In3.Cu" "In5.Cu" "In6.Cu" "In7.Cu" "In8.Cu"
			"In9.Cu" "In10.Cu" "In11.Cu" "In12.Cu"
		)
		(hatch none 0.5)
		(connect_pads
			(clearance 0)
		)
		(min_thickness 0.25)
		(keepout
			(tracks not_allowed)
			(vias allowed)
			(pads allowed)
			(copperpour not_allowed)
			(footprints allowed)
		)
		(placement
			(enabled no)
			(sheetname "")
		)
		(fill yes
			(thermal_gap 0.5)
			(thermal_bridge_width 0.5)
			(island_removal_mode 0)
		)
		(polygon
			(pts
				(arc
					(start 399.554192 -2.792984)
					(mid 399.170652 -3.176524)
					(end 399.554192 -3.560064)
				)
				(arc
					(start 400.569938 -3.560064)
					(mid 400.840406 -3.448714)
					(end 400.953732 -3.179064)
				)
				(arc
					(start 400.836892 -3.179064)
					(mid 400.570192 -3.443236)
					(end 400.303492 -3.179064)
				)
				(arc
					(start 399.820892 -3.179064)
					(mid 399.554192 -3.443236)
					(end 399.287492 -3.179064)
				)
				(arc
					(start 399.287492 -3.176524)
					(mid 399.554192 -2.909824)
					(end 399.820892 -3.176524)
				)
				(arc
					(start 400.303492 -3.176524)
					(mid 400.570192 -2.909824)
					(end 400.836892 -3.176524)
				)
				(arc
					(start 400.953732 -3.176524)
					(mid 400.841396 -2.90532)
					(end 400.570192 -2.792984)
				)
			)
		)
	)
	(zone
		(layers "B.Cu" "In1.Cu" "In3.Cu" "In4.Cu" "In5.Cu" "In6.Cu" "In7.Cu" "In8.Cu"
			"In9.Cu" "In10.Cu" "In11.Cu" "In12.Cu"
		)
		(hatch none 0.5)
		(connect_pads
			(clearance 0)
		)
		(min_thickness 0.25)
		(keepout
			(tracks not_allowed)
			(vias allowed)
			(pads allowed)
			(copperpour not_allowed)
			(footprints allowed)
		)
		(placement
			(enabled no)
			(sheetname "")
		)
		(fill yes
			(thermal_gap 0.5)
			(thermal_bridge_width 0.5)
			(island_removal_mode 0)
		)
		(polygon
			(pts
				(arc
					(start 414.629092 -9.741408)
					(mid 414.245552 -10.124948)
					(end 414.629092 -10.508488)
				)
				(arc
					(start 415.898838 -10.508488)
					(mid 416.169306 -10.397138)
					(end 416.282632 -10.127488)
				)
				(arc
					(start 416.165792 -10.127488)
					(mid 415.899092 -10.39166)
					(end 415.632392 -10.127488)
				)
				(arc
					(start 414.895792 -10.127488)
					(mid 414.629092 -10.39166)
					(end 414.362392 -10.127488)
				)
				(arc
					(start 414.362392 -10.124948)
					(mid 414.629092 -9.858248)
					(end 414.895792 -10.124948)
				)
				(arc
					(start 415.632392 -10.124948)
					(mid 415.899092 -9.858248)
					(end 416.165792 -10.124948)
				)
				(arc
					(start 416.282632 -10.124948)
					(mid 416.170296 -9.853744)
					(end 415.899092 -9.741408)
				)
			)
		)
	)
	(zone
		(layers "B.Cu" "In1.Cu" "In3.Cu" "In4.Cu" "In5.Cu" "In6.Cu" "In7.Cu" "In8.Cu"
			"In9.Cu" "In10.Cu" "In11.Cu" "In12.Cu"
		)
		(hatch none 0.5)
		(connect_pads
			(clearance 0)
		)
		(min_thickness 0.25)
		(keepout
			(tracks not_allowed)
			(vias allowed)
			(pads allowed)
			(copperpour not_allowed)
			(footprints allowed)
		)
		(placement
			(enabled no)
			(sheetname "")
		)
		(fill yes
			(thermal_gap 0.5)
			(thermal_bridge_width 0.5)
			(island_removal_mode 0)
		)
		(polygon
			(pts
				(arc
					(start 380.562612 -128.711706)
					(mid 380.181358 -129.092579)
					(end 380.562358 -129.473706)
				)
				(arc
					(start 381.222758 -129.473706)
					(mid 381.491266 -129.36301)
					(end 381.603758 -129.095246)
				)
				(arc
					(start 381.489458 -129.095246)
					(mid 381.222758 -129.359418)
					(end 380.956058 -129.095246)
				)
				(arc
					(start 380.829058 -129.095246)
					(mid 380.562358 -129.359418)
					(end 380.295658 -129.095246)
				)
				(arc
					(start 380.295658 -129.092706)
					(mid 380.562358 -128.826006)
					(end 380.829058 -129.092706)
				)
				(arc
					(start 380.956058 -129.092706)
					(mid 381.222758 -128.826006)
					(end 381.489458 -129.092706)
				)
				(arc
					(start 381.603758 -129.092706)
					(mid 381.492166 -128.823298)
					(end 381.222758 -128.711706)
				)
			)
		)
	)
	(zone
		(layers "B.Cu" "In1.Cu" "In3.Cu" "In4.Cu" "In5.Cu" "In6.Cu" "In7.Cu" "In8.Cu"
			"In9.Cu" "In10.Cu" "In11.Cu" "In12.Cu"
		)
		(hatch none 0.5)
		(connect_pads
			(clearance 0)
		)
		(min_thickness 0.25)
		(keepout
			(tracks not_allowed)
			(vias allowed)
			(pads allowed)
			(copperpour not_allowed)
			(footprints allowed)
		)
		(placement
			(enabled no)
			(sheetname "")
		)
		(fill yes
			(thermal_gap 0.5)
			(thermal_bridge_width 0.5)
			(island_removal_mode 0)
		)
		(polygon
			(pts
				(arc
					(start 413.82315 -10.1346)
					(mid 413.708719 -9.869817)
					(end 413.44215 -9.759696)
				)
				(arc
					(start 412.15183 -9.75106)
					(mid 411.76575 -10.13206)
					(end 412.14675 -10.51814)
				)
				(arc
					(start 413.436816 -10.526776)
					(mid 413.711986 -10.413277)
					(end 413.82315 -10.13714)
				)
				(arc
					(start 413.70631 -10.13714)
					(mid 413.43961 -10.410006)
					(end 413.17291 -10.13714)
				)
				(arc
					(start 412.41599 -10.13714)
					(mid 412.14929 -10.401312)
					(end 411.88259 -10.13714)
				)
				(arc
					(start 411.88259 -10.1346)
					(mid 412.14929 -9.8679)
					(end 412.41599 -10.1346)
				)
				(arc
					(start 413.173164 -10.1346)
					(mid 413.43961 -9.87665)
					(end 413.706056 -10.1346)
				)
			)
		)
	)
	(zone
		(layers "B.Cu" "In1.Cu" "In3.Cu" "In4.Cu" "In5.Cu" "In6.Cu" "In7.Cu" "In8.Cu"
			"In9.Cu" "In10.Cu" "In11.Cu" "In12.Cu"
		)
		(hatch none 0.5)
		(connect_pads
			(clearance 0)
		)
		(min_thickness 0.25)
		(keepout
			(tracks not_allowed)
			(vias allowed)
			(pads allowed)
			(copperpour not_allowed)
			(footprints allowed)
		)
		(placement
			(enabled no)
			(sheetname "")
		)
		(fill yes
			(thermal_gap 0.5)
			(thermal_bridge_width 0.5)
			(island_removal_mode 0)
		)
		(polygon
			(pts
				(arc
					(start 382.881124 -131.23037)
					(mid 382.49987 -131.611243)
					(end 382.88087 -131.99237)
				)
				(arc
					(start 383.54127 -131.99237)
					(mid 383.809778 -131.881674)
					(end 383.92227 -131.61391)
				)
				(arc
					(start 383.80797 -131.61391)
					(mid 383.54127 -131.878082)
					(end 383.27457 -131.61391)
				)
				(arc
					(start 383.14757 -131.61391)
					(mid 382.88087 -131.878082)
					(end 382.61417 -131.61391)
				)
				(arc
					(start 382.61417 -131.61137)
					(mid 382.88087 -131.34467)
					(end 383.14757 -131.61137)
				)
				(arc
					(start 383.27457 -131.61137)
					(mid 383.54127 -131.34467)
					(end 383.80797 -131.61137)
				)
				(arc
					(start 383.92227 -131.61137)
					(mid 383.810678 -131.341962)
					(end 383.54127 -131.23037)
				)
			)
		)
	)
	(zone
		(layers "B.Cu" "In1.Cu" "In3.Cu" "In4.Cu" "In5.Cu" "In6.Cu" "In7.Cu" "In8.Cu"
			"In9.Cu" "In10.Cu" "In11.Cu" "In12.Cu"
		)
		(hatch none 0.5)
		(connect_pads
			(clearance 0)
		)
		(min_thickness 0.25)
		(keepout
			(tracks not_allowed)
			(vias allowed)
			(pads allowed)
			(copperpour not_allowed)
			(footprints allowed)
		)
		(placement
			(enabled no)
			(sheetname "")
		)
		(fill yes
			(thermal_gap 0.5)
			(thermal_bridge_width 0.5)
			(island_removal_mode 0)
		)
		(polygon
			(pts
				(arc
					(start 417.029392 -9.639808)
					(mid 416.645852 -10.023348)
					(end 417.029392 -10.406888)
				)
				(arc
					(start 418.299138 -10.406888)
					(mid 418.569606 -10.295538)
					(end 418.682932 -10.025888)
				)
				(arc
					(start 418.566092 -10.025888)
					(mid 418.299392 -10.29006)
					(end 418.032692 -10.025888)
				)
				(arc
					(start 417.296092 -10.025888)
					(mid 417.029392 -10.29006)
					(end 416.762692 -10.025888)
				)
				(arc
					(start 416.762692 -10.023348)
					(mid 417.029392 -9.756648)
					(end 417.296092 -10.023348)
				)
				(arc
					(start 418.032692 -10.023348)
					(mid 418.299392 -9.756648)
					(end 418.566092 -10.023348)
				)
				(arc
					(start 418.682932 -10.023348)
					(mid 418.570596 -9.752144)
					(end 418.299392 -9.639808)
				)
			)
		)
	)
	(zone
		(layers "B.Cu" "In1.Cu" "In3.Cu" "In4.Cu" "In5.Cu" "In6.Cu" "In7.Cu" "In8.Cu"
			"In9.Cu" "In10.Cu" "In11.Cu" "In12.Cu"
		)
		(hatch none 0.5)
		(connect_pads
			(clearance 0)
		)
		(min_thickness 0.25)
		(keepout
			(tracks not_allowed)
			(vias allowed)
			(pads allowed)
			(copperpour not_allowed)
			(footprints allowed)
		)
		(placement
			(enabled no)
			(sheetname "")
		)
		(fill yes
			(thermal_gap 0.5)
			(thermal_bridge_width 0.5)
			(island_removal_mode 0)
		)
		(polygon
			(pts
				(arc
					(start 380.506224 -130.713988)
					(mid 380.12497 -131.094861)
					(end 380.50597 -131.475988)
				)
				(arc
					(start 381.16637 -131.475988)
					(mid 381.434878 -131.365292)
					(end 381.54737 -131.097528)
				)
				(arc
					(start 381.43307 -131.097528)
					(mid 381.16637 -131.3617)
					(end 380.89967 -131.097528)
				)
				(arc
					(start 380.77267 -131.097528)
					(mid 380.50597 -131.3617)
					(end 380.23927 -131.097528)
				)
				(arc
					(start 380.23927 -131.094988)
					(mid 380.50597 -130.828288)
					(end 380.77267 -131.094988)
				)
				(arc
					(start 380.89967 -131.094988)
					(mid 381.16637 -130.828288)
					(end 381.43307 -131.094988)
				)
				(arc
					(start 381.54737 -131.094988)
					(mid 381.435778 -130.82558)
					(end 381.16637 -130.713988)
				)
			)
		)
	)
	(zone
		(layers "B.Cu" "In1.Cu" "In3.Cu" "In4.Cu" "In5.Cu" "In6.Cu" "In7.Cu" "In8.Cu"
			"In9.Cu" "In10.Cu" "In11.Cu" "In12.Cu"
		)
		(hatch none 0.5)
		(connect_pads
			(clearance 0)
		)
		(min_thickness 0.25)
		(keepout
			(tracks not_allowed)
			(vias allowed)
			(pads allowed)
			(copperpour not_allowed)
			(footprints allowed)
		)
		(placement
			(enabled no)
			(sheetname "")
		)
		(fill yes
			(thermal_gap 0.5)
			(thermal_bridge_width 0.5)
			(island_removal_mode 0)
		)
		(polygon
			(pts
				(arc
					(start 428.230792 -2.34061)
					(mid 427.847252 -2.72415)
					(end 428.230792 -3.10769)
				)
				(arc
					(start 429.500538 -3.10769)
					(mid 429.771006 -2.99634)
					(end 429.884332 -2.72669)
				)
				(arc
					(start 429.767492 -2.72669)
					(mid 429.500792 -2.990862)
					(end 429.234092 -2.72669)
				)
				(arc
					(start 428.497492 -2.72669)
					(mid 428.230792 -2.990862)
					(end 427.964092 -2.72669)
				)
				(arc
					(start 427.964092 -2.72415)
					(mid 428.230792 -2.45745)
					(end 428.497492 -2.72415)
				)
				(arc
					(start 429.234092 -2.72415)
					(mid 429.500792 -2.45745)
					(end 429.767492 -2.72415)
				)
				(arc
					(start 429.884332 -2.72415)
					(mid 429.771996 -2.452946)
					(end 429.500792 -2.34061)
				)
			)
		)
	)
	(zone
		(layers "B.Cu" "In1.Cu" "In3.Cu" "In4.Cu" "In5.Cu" "In6.Cu" "In7.Cu" "In8.Cu"
			"In9.Cu" "In10.Cu" "In11.Cu" "In12.Cu"
		)
		(hatch none 0.5)
		(connect_pads
			(clearance 0)
		)
		(min_thickness 0.25)
		(keepout
			(tracks not_allowed)
			(vias allowed)
			(pads allowed)
			(copperpour not_allowed)
			(footprints allowed)
		)
		(placement
			(enabled no)
			(sheetname "")
		)
		(fill yes
			(thermal_gap 0.5)
			(thermal_bridge_width 0.5)
			(island_removal_mode 0)
		)
		(polygon
			(pts
				(arc
					(start 375.761504 -128.64465)
					(mid 375.38025 -129.025523)
					(end 375.76125 -129.40665)
				)
				(arc
					(start 376.42165 -129.40665)
					(mid 376.690158 -129.295954)
					(end 376.80265 -129.02819)
				)
				(arc
					(start 376.68835 -129.02819)
					(mid 376.42165 -129.292362)
					(end 376.15495 -129.02819)
				)
				(arc
					(start 376.02795 -129.02819)
					(mid 375.76125 -129.292362)
					(end 375.49455 -129.02819)
				)
				(arc
					(start 375.49455 -129.02565)
					(mid 375.76125 -128.75895)
					(end 376.02795 -129.02565)
				)
				(arc
					(start 376.15495 -129.02565)
					(mid 376.42165 -128.75895)
					(end 376.68835 -129.02565)
				)
				(arc
					(start 376.80265 -129.02565)
					(mid 376.691058 -128.756242)
					(end 376.42165 -128.64465)
				)
			)
		)
	)
	(zone
		(layers "B.Cu" "In1.Cu" "In3.Cu" "In4.Cu" "In5.Cu" "In6.Cu" "In7.Cu" "In8.Cu"
			"In9.Cu" "In10.Cu" "In11.Cu" "In12.Cu"
		)
		(hatch none 0.5)
		(connect_pads
			(clearance 0)
		)
		(min_thickness 0.25)
		(keepout
			(tracks not_allowed)
			(vias allowed)
			(pads allowed)
			(copperpour not_allowed)
			(footprints allowed)
		)
		(placement
			(enabled no)
			(sheetname "")
		)
		(fill yes
			(thermal_gap 0.5)
			(thermal_bridge_width 0.5)
			(island_removal_mode 0)
		)
		(polygon
			(pts
				(arc
					(start 413.803592 -1.35001)
					(mid 413.420052 -1.73355)
					(end 413.803592 -2.11709)
				)
				(arc
					(start 415.073338 -2.11709)
					(mid 415.343806 -2.00574)
					(end 415.457132 -1.73609)
				)
				(arc
					(start 415.340292 -1.73609)
					(mid 415.073592 -2.000262)
					(end 414.806892 -1.73609)
				)
				(arc
					(start 414.070292 -1.73609)
					(mid 413.803592 -2.000262)
					(end 413.536892 -1.73609)
				)
				(arc
					(start 413.536892 -1.73355)
					(mid 413.803592 -1.46685)
					(end 414.070292 -1.73355)
				)
				(arc
					(start 414.806892 -1.73355)
					(mid 415.073592 -1.46685)
					(end 415.340292 -1.73355)
				)
				(arc
					(start 415.457132 -1.73355)
					(mid 415.344796 -1.462346)
					(end 415.073592 -1.35001)
				)
			)
		)
	)
	(zone
		(layers "B.Cu" "In1.Cu" "In3.Cu" "In4.Cu" "In5.Cu" "In6.Cu" "In7.Cu" "In8.Cu"
			"In9.Cu" "In10.Cu" "In11.Cu" "In12.Cu"
		)
		(hatch none 0.5)
		(connect_pads
			(clearance 0)
		)
		(min_thickness 0.25)
		(keepout
			(tracks not_allowed)
			(vias allowed)
			(pads allowed)
			(copperpour not_allowed)
			(footprints allowed)
		)
		(placement
			(enabled no)
			(sheetname "")
		)
		(fill yes
			(thermal_gap 0.5)
			(thermal_bridge_width 0.5)
			(island_removal_mode 0)
		)
		(polygon
			(pts
				(arc
					(start 416.27171 -2.43713)
					(mid 415.88817 -2.82067)
					(end 416.27171 -3.20421)
				)
				(arc
					(start 417.541456 -3.20421)
					(mid 417.811924 -3.09286)
					(end 417.92525 -2.82321)
				)
				(arc
					(start 417.80841 -2.82321)
					(mid 417.54171 -3.087382)
					(end 417.27501 -2.82321)
				)
				(arc
					(start 416.53841 -2.82321)
					(mid 416.27171 -3.087382)
					(end 416.00501 -2.82321)
				)
				(arc
					(start 416.00501 -2.82067)
					(mid 416.27171 -2.55397)
					(end 416.53841 -2.82067)
				)
				(arc
					(start 417.27501 -2.82067)
					(mid 417.54171 -2.55397)
					(end 417.80841 -2.82067)
				)
				(arc
					(start 417.92525 -2.82067)
					(mid 417.812914 -2.549466)
					(end 417.54171 -2.43713)
				)
			)
		)
	)
	(zone
		(layers "B.Cu" "In1.Cu" "In3.Cu" "In4.Cu" "In5.Cu" "In6.Cu" "In7.Cu" "In8.Cu"
			"In9.Cu" "In10.Cu" "In11.Cu" "In12.Cu"
		)
		(hatch none 0.5)
		(connect_pads
			(clearance 0)
		)
		(min_thickness 0.25)
		(keepout
			(tracks not_allowed)
			(vias allowed)
			(pads allowed)
			(copperpour not_allowed)
			(footprints allowed)
		)
		(placement
			(enabled no)
			(sheetname "")
		)
		(fill yes
			(thermal_gap 0.5)
			(thermal_bridge_width 0.5)
			(island_removal_mode 0)
		)
		(polygon
			(pts
				(arc
					(start 424.230292 -9.639808)
					(mid 423.846752 -10.023348)
					(end 424.230292 -10.406888)
				)
				(arc
					(start 425.500038 -10.406888)
					(mid 425.770506 -10.295538)
					(end 425.883832 -10.025888)
				)
				(arc
					(start 425.766992 -10.025888)
					(mid 425.500292 -10.29006)
					(end 425.233592 -10.025888)
				)
				(arc
					(start 424.496992 -10.025888)
					(mid 424.230292 -10.29006)
					(end 423.963592 -10.025888)
				)
				(arc
					(start 423.963592 -10.023348)
					(mid 424.230292 -9.756648)
					(end 424.496992 -10.023348)
				)
				(arc
					(start 425.233592 -10.023348)
					(mid 425.500292 -9.756648)
					(end 425.766992 -10.023348)
				)
				(arc
					(start 425.883832 -10.023348)
					(mid 425.771496 -9.752144)
					(end 425.500292 -9.639808)
				)
			)
		)
	)
	(zone
		(layers "B.Cu" "In1.Cu" "In3.Cu" "In4.Cu" "In5.Cu" "In6.Cu" "In7.Cu" "In8.Cu"
			"In9.Cu" "In10.Cu" "In11.Cu" "In12.Cu"
		)
		(hatch none 0.5)
		(connect_pads
			(clearance 0)
		)
		(min_thickness 0.25)
		(keepout
			(tracks not_allowed)
			(vias allowed)
			(pads allowed)
			(copperpour not_allowed)
			(footprints allowed)
		)
		(placement
			(enabled no)
			(sheetname "")
		)
		(fill yes
			(thermal_gap 0.5)
			(thermal_bridge_width 0.5)
			(island_removal_mode 0)
		)
		(polygon
			(pts
				(arc
					(start 419.429692 -9.639808)
					(mid 419.046152 -10.023348)
					(end 419.429692 -10.406888)
				)
				(arc
					(start 420.699438 -10.406888)
					(mid 420.969906 -10.295538)
					(end 421.083232 -10.025888)
				)
				(arc
					(start 420.966392 -10.025888)
					(mid 420.699692 -10.29006)
					(end 420.432992 -10.025888)
				)
				(arc
					(start 419.696392 -10.025888)
					(mid 419.429692 -10.29006)
					(end 419.162992 -10.025888)
				)
				(arc
					(start 419.162992 -10.023348)
					(mid 419.429692 -9.756648)
					(end 419.696392 -10.023348)
				)
				(arc
					(start 420.432992 -10.023348)
					(mid 420.699692 -9.756648)
					(end 420.966392 -10.023348)
				)
				(arc
					(start 421.083232 -10.023348)
					(mid 420.970896 -9.752144)
					(end 420.699692 -9.639808)
				)
			)
		)
	)
	(zone
		(layers "B.Cu" "In1.Cu" "In3.Cu" "In4.Cu" "In5.Cu" "In6.Cu" "In7.Cu" "In8.Cu"
			"In9.Cu" "In10.Cu" "In11.Cu" "In12.Cu"
		)
		(hatch none 0.5)
		(connect_pads
			(clearance 0)
		)
		(min_thickness 0.25)
		(keepout
			(tracks not_allowed)
			(vias allowed)
			(pads allowed)
			(copperpour not_allowed)
			(footprints allowed)
		)
		(placement
			(enabled no)
			(sheetname "")
		)
		(fill yes
			(thermal_gap 0.5)
			(thermal_bridge_width 0.5)
			(island_removal_mode 0)
		)
		(polygon
			(pts
				(arc
					(start 421.829992 -9.639808)
					(mid 421.446452 -10.023348)
					(end 421.829992 -10.406888)
				)
				(arc
					(start 423.099738 -10.406888)
					(mid 423.370206 -10.295538)
					(end 423.483532 -10.025888)
				)
				(arc
					(start 423.366692 -10.025888)
					(mid 423.099992 -10.29006)
					(end 422.833292 -10.025888)
				)
				(arc
					(start 422.096692 -10.025888)
					(mid 421.829992 -10.29006)
					(end 421.563292 -10.025888)
				)
				(arc
					(start 421.563292 -10.023348)
					(mid 421.829992 -9.756648)
					(end 422.096692 -10.023348)
				)
				(arc
					(start 422.833292 -10.023348)
					(mid 423.099992 -9.756648)
					(end 423.366692 -10.023348)
				)
				(arc
					(start 423.483532 -10.023348)
					(mid 423.371196 -9.752144)
					(end 423.099992 -9.639808)
				)
			)
		)
	)
	(zone
		(layers "B.Cu" "In1.Cu" "In3.Cu" "In4.Cu" "In5.Cu" "In6.Cu" "In7.Cu" "In8.Cu"
			"In9.Cu" "In10.Cu" "In11.Cu" "In12.Cu"
		)
		(hatch none 0.5)
		(connect_pads
			(clearance 0)
		)
		(min_thickness 0.25)
		(keepout
			(tracks not_allowed)
			(vias allowed)
			(pads allowed)
			(copperpour not_allowed)
			(footprints allowed)
		)
		(placement
			(enabled no)
			(sheetname "")
		)
		(fill yes
			(thermal_gap 0.5)
			(thermal_bridge_width 0.5)
			(island_removal_mode 0)
		)
		(polygon
			(pts
				(arc
					(start 411.428692 -2.34823)
					(mid 411.045152 -2.73177)
					(end 411.428692 -3.11531)
				)
				(arc
					(start 412.698438 -3.11531)
					(mid 412.968906 -3.00396)
					(end 413.082232 -2.73431)
				)
				(arc
					(start 412.965392 -2.73431)
					(mid 412.698692 -2.998482)
					(end 412.431992 -2.73431)
				)
				(arc
					(start 411.695392 -2.73431)
					(mid 411.428692 -2.998482)
					(end 411.161992 -2.73431)
				)
				(arc
					(start 411.161992 -2.73177)
					(mid 411.428692 -2.46507)
					(end 411.695392 -2.73177)
				)
				(arc
					(start 412.431992 -2.73177)
					(mid 412.698692 -2.46507)
					(end 412.965392 -2.73177)
				)
				(arc
					(start 413.082232 -2.73177)
					(mid 412.969896 -2.460566)
					(end 412.698692 -2.34823)
				)
			)
		)
	)
	(zone
		(layers "B.Cu" "In1.Cu" "In3.Cu" "In4.Cu" "In5.Cu" "In6.Cu" "In7.Cu" "In8.Cu"
			"In9.Cu" "In10.Cu" "In11.Cu" "In12.Cu"
		)
		(hatch none 0.5)
		(connect_pads
			(clearance 0)
		)
		(min_thickness 0.25)
		(keepout
			(tracks not_allowed)
			(vias allowed)
			(pads allowed)
			(copperpour not_allowed)
			(footprints allowed)
		)
		(placement
			(enabled no)
			(sheetname "")
		)
		(fill yes
			(thermal_gap 0.5)
			(thermal_bridge_width 0.5)
			(island_removal_mode 0)
		)
		(polygon
			(pts
				(arc
					(start 377.366276 -128.651)
					(mid 376.985022 -129.031873)
					(end 377.366022 -129.413)
				)
				(arc
					(start 378.026422 -129.413)
					(mid 378.29493 -129.302304)
					(end 378.407422 -129.03454)
				)
				(arc
					(start 378.293122 -129.03454)
					(mid 378.026422 -129.298712)
					(end 377.759722 -129.03454)
				)
				(arc
					(start 377.632722 -129.03454)
					(mid 377.366022 -129.298712)
					(end 377.099322 -129.03454)
				)
				(arc
					(start 377.099322 -129.032)
					(mid 377.366022 -128.7653)
					(end 377.632722 -129.032)
				)
				(arc
					(start 377.759722 -129.032)
					(mid 378.026422 -128.7653)
					(end 378.293122 -129.032)
				)
				(arc
					(start 378.407422 -129.032)
					(mid 378.29583 -128.762592)
					(end 378.026422 -128.651)
				)
			)
		)
	)
	(zone
		(layers "B.Cu" "In1.Cu" "In3.Cu" "In4.Cu" "In5.Cu" "In6.Cu" "In7.Cu" "In8.Cu"
			"In9.Cu" "In10.Cu" "In11.Cu" "In12.Cu"
		)
		(hatch none 0.5)
		(connect_pads
			(clearance 0)
		)
		(min_thickness 0.25)
		(keepout
			(tracks not_allowed)
			(vias allowed)
			(pads allowed)
			(copperpour not_allowed)
			(footprints allowed)
		)
		(placement
			(enabled no)
			(sheetname "")
		)
		(fill yes
			(thermal_gap 0.5)
			(thermal_bridge_width 0.5)
			(island_removal_mode 0)
		)
		(polygon
			(pts
				(arc
					(start 383.191258 -127.390652)
					(mid 382.810004 -127.771525)
					(end 383.191004 -128.152652)
				)
				(arc
					(start 383.826004 -128.152652)
					(mid 384.094512 -128.041956)
					(end 384.207004 -127.774192)
				)
				(arc
					(start 384.092704 -127.774192)
					(mid 383.826004 -128.038364)
					(end 383.559304 -127.774192)
				)
				(arc
					(start 383.457704 -127.774192)
					(mid 383.191004 -128.038364)
					(end 382.924304 -127.774192)
				)
				(arc
					(start 382.924304 -127.771652)
					(mid 383.191004 -127.504952)
					(end 383.457704 -127.771652)
				)
				(arc
					(start 383.559304 -127.771652)
					(mid 383.826004 -127.504952)
					(end 384.092704 -127.771652)
				)
				(arc
					(start 384.207004 -127.771652)
					(mid 384.095412 -127.502244)
					(end 383.826004 -127.390652)
				)
			)
		)
	)
	(zone
		(layers "B.Cu" "In1.Cu" "In3.Cu" "In4.Cu" "In5.Cu" "In6.Cu" "In7.Cu" "In8.Cu"
			"In9.Cu" "In10.Cu" "In11.Cu" "In12.Cu"
		)
		(hatch none 0.5)
		(connect_pads
			(clearance 0)
		)
		(min_thickness 0.25)
		(keepout
			(tracks not_allowed)
			(vias allowed)
			(pads allowed)
			(copperpour not_allowed)
			(footprints allowed)
		)
		(placement
			(enabled no)
			(sheetname "")
		)
		(fill yes
			(thermal_gap 0.5)
			(thermal_bridge_width 0.5)
			(island_removal_mode 0)
		)
		(polygon
			(pts
				(arc
					(start 429.031146 -9.639808)
					(mid 428.647352 -10.023221)
					(end 429.030892 -10.406888)
				)
				(arc
					(start 430.300892 -10.406888)
					(mid 430.571196 -10.295448)
					(end 430.684432 -10.025888)
				)
				(arc
					(start 430.567592 -10.025888)
					(mid 430.300892 -10.29006)
					(end 430.034192 -10.025888)
				)
				(arc
					(start 429.297592 -10.025888)
					(mid 429.030892 -10.29006)
					(end 428.764192 -10.025888)
				)
				(arc
					(start 428.764192 -10.023348)
					(mid 429.030892 -9.756648)
					(end 429.297592 -10.023348)
				)
				(arc
					(start 430.034192 -10.023348)
					(mid 430.300892 -9.756648)
					(end 430.567592 -10.023348)
				)
				(arc
					(start 430.684432 -10.023348)
					(mid 430.572096 -9.752144)
					(end 430.300892 -9.639808)
				)
			)
		)
	)
	(zone
		(layers "B.Cu" "In1.Cu" "In3.Cu" "In4.Cu" "In5.Cu" "In6.Cu" "In7.Cu" "In8.Cu"
			"In9.Cu" "In10.Cu" "In11.Cu" "In12.Cu"
		)
		(hatch none 0.5)
		(connect_pads
			(clearance 0)
		)
		(min_thickness 0.25)
		(keepout
			(tracks not_allowed)
			(vias allowed)
			(pads allowed)
			(copperpour not_allowed)
			(footprints allowed)
		)
		(placement
			(enabled no)
			(sheetname "")
		)
		(fill yes
			(thermal_gap 0.5)
			(thermal_bridge_width 0.5)
			(island_removal_mode 0)
		)
		(polygon
			(pts
				(arc
					(start 418.781992 -1.22301)
					(mid 418.398452 -1.60655)
					(end 418.781992 -1.99009)
				)
				(arc
					(start 420.051738 -1.99009)
					(mid 420.322206 -1.87874)
					(end 420.435532 -1.60909)
				)
				(arc
					(start 420.318692 -1.60909)
					(mid 420.051992 -1.873262)
					(end 419.785292 -1.60909)
				)
				(arc
					(start 419.048692 -1.60909)
					(mid 418.781992 -1.873262)
					(end 418.515292 -1.60909)
				)
				(arc
					(start 418.515292 -1.60655)
					(mid 418.781992 -1.33985)
					(end 419.048692 -1.60655)
				)
				(arc
					(start 419.785292 -1.60655)
					(mid 420.051992 -1.33985)
					(end 420.318692 -1.60655)
				)
				(arc
					(start 420.435532 -1.60655)
					(mid 420.323196 -1.335346)
					(end 420.051992 -1.22301)
				)
			)
		)
	)
	(zone
		(layers "B.Cu" "In1.Cu" "In3.Cu" "In4.Cu" "In5.Cu" "In6.Cu" "In7.Cu" "In8.Cu"
			"In9.Cu" "In10.Cu" "In11.Cu" "In12.Cu"
		)
		(hatch none 0.5)
		(connect_pads
			(clearance 0)
		)
		(min_thickness 0.25)
		(keepout
			(tracks not_allowed)
			(vias allowed)
			(pads allowed)
			(copperpour not_allowed)
			(footprints allowed)
		)
		(placement
			(enabled no)
			(sheetname "")
		)
		(fill yes
			(thermal_gap 0.5)
			(thermal_bridge_width 0.5)
			(island_removal_mode 0)
		)
		(polygon
			(pts
				(arc
					(start 382.774444 -129.32283)
					(mid 382.39319 -129.703703)
					(end 382.77419 -130.08483)
				)
				(arc
					(start 383.43459 -130.08483)
					(mid 383.703098 -129.974134)
					(end 383.81559 -129.70637)
				)
				(arc
					(start 383.70129 -129.70637)
					(mid 383.43459 -129.970542)
					(end 383.16789 -129.70637)
				)
				(arc
					(start 383.04089 -129.70637)
					(mid 382.77419 -129.970542)
					(end 382.50749 -129.70637)
				)
				(arc
					(start 382.50749 -129.70383)
					(mid 382.77419 -129.43713)
					(end 383.04089 -129.70383)
				)
				(arc
					(start 383.16789 -129.70383)
					(mid 383.43459 -129.43713)
					(end 383.70129 -129.70383)
				)
				(arc
					(start 383.81559 -129.70383)
					(mid 383.703998 -129.434422)
					(end 383.43459 -129.32283)
				)
			)
		)
	)
	(zone
		(layers "B.Cu" "In1.Cu" "In3.Cu" "In4.Cu" "In5.Cu" "In6.Cu" "In7.Cu" "In8.Cu"
			"In9.Cu" "In10.Cu" "In11.Cu" "In12.Cu"
		)
		(hatch none 0.5)
		(connect_pads
			(clearance 0)
		)
		(min_thickness 0.25)
		(keepout
			(tracks not_allowed)
			(vias allowed)
			(pads allowed)
			(copperpour not_allowed)
			(footprints allowed)
		)
		(placement
			(enabled no)
			(sheetname "")
		)
		(fill yes
			(thermal_gap 0.5)
			(thermal_bridge_width 0.5)
			(island_removal_mode 0)
		)
		(polygon
			(pts
				(arc
					(start 378.485654 -131.699)
					(mid 378.1044 -132.079873)
					(end 378.4854 -132.461)
				)
				(arc
					(start 379.1458 -132.461)
					(mid 379.414308 -132.350304)
					(end 379.5268 -132.08254)
				)
				(arc
					(start 379.4125 -132.08254)
					(mid 379.1458 -132.346712)
					(end 378.8791 -132.08254)
				)
				(arc
					(start 378.7521 -132.08254)
					(mid 378.4854 -132.346712)
					(end 378.2187 -132.08254)
				)
				(arc
					(start 378.2187 -132.08)
					(mid 378.4854 -131.8133)
					(end 378.7521 -132.08)
				)
				(arc
					(start 378.8791 -132.08)
					(mid 379.1458 -131.8133)
					(end 379.4125 -132.08)
				)
				(arc
					(start 379.5268 -132.08)
					(mid 379.415208 -131.810592)
					(end 379.1458 -131.699)
				)
			)
		)
	)
	(zone
		(layers "B.Cu" "In1.Cu" "In3.Cu" "In4.Cu" "In5.Cu" "In6.Cu" "In7.Cu" "In8.Cu"
			"In9.Cu" "In10.Cu" "In11.Cu" "In12.Cu"
		)
		(hatch none 0.5)
		(connect_pads
			(clearance 0)
		)
		(min_thickness 0.25)
		(keepout
			(tracks not_allowed)
			(vias allowed)
			(pads allowed)
			(copperpour not_allowed)
			(footprints allowed)
		)
		(placement
			(enabled no)
			(sheetname "")
		)
		(fill yes
			(thermal_gap 0.5)
			(thermal_bridge_width 0.5)
			(island_removal_mode 0)
		)
		(polygon
			(pts
				(arc
					(start 422.626282 -2.579116)
					(mid 422.511148 -2.305143)
					(end 422.234868 -2.195576)
				)
				(arc
					(start 420.963852 -2.221992)
					(mid 420.588186 -2.613406)
					(end 420.9796 -2.989072)
				)
				(arc
					(start 422.250362 -2.962656)
					(mid 422.515789 -2.848571)
					(end 422.626282 -2.581656)
				)
				(arc
					(start 422.509442 -2.581656)
					(mid 422.255972 -2.846003)
					(end 421.977566 -2.608072)
				)
				(arc
					(start 421.238426 -2.608072)
					(mid 420.971726 -2.872244)
					(end 420.705026 -2.608072)
				)
				(arc
					(start 420.705026 -2.605532)
					(mid 420.971726 -2.338832)
					(end 421.238426 -2.605532)
				)
				(xy 421.977312 -2.605532) (xy 421.976042 -2.581656)
				(arc
					(start 421.976042 -2.579116)
					(mid 422.242742 -2.312416)
					(end 422.509442 -2.579116)
				)
			)
		)
	)
	(zone
		(layers "B.Cu" "In1.Cu" "In3.Cu" "In4.Cu" "In5.Cu" "In6.Cu" "In7.Cu" "In8.Cu"
			"In9.Cu" "In10.Cu" "In11.Cu" "In12.Cu"
		)
		(hatch none 0.5)
		(connect_pads
			(clearance 0)
		)
		(min_thickness 0.25)
		(keepout
			(tracks not_allowed)
			(vias allowed)
			(pads allowed)
			(copperpour not_allowed)
			(footprints allowed)
		)
		(placement
			(enabled no)
			(sheetname "")
		)
		(fill yes
			(thermal_gap 0.5)
			(thermal_bridge_width 0.5)
			(island_removal_mode 0)
		)
		(polygon
			(pts
				(arc
					(start 423.41292 -1.200404)
					(mid 423.02938 -1.583817)
					(end 423.412666 -1.967484)
				)
				(arc
					(start 424.682666 -1.967484)
					(mid 424.95297 -1.856044)
					(end 425.066206 -1.586484)
				)
				(arc
					(start 424.949366 -1.586484)
					(mid 424.682666 -1.850656)
					(end 424.415966 -1.586484)
				)
				(arc
					(start 423.679366 -1.586484)
					(mid 423.412666 -1.850656)
					(end 423.145966 -1.586484)
				)
				(arc
					(start 423.145966 -1.583944)
					(mid 423.412666 -1.317244)
					(end 423.679366 -1.583944)
				)
				(arc
					(start 424.415966 -1.583944)
					(mid 424.682666 -1.317244)
					(end 424.949366 -1.583944)
				)
				(arc
					(start 425.066206 -1.583944)
					(mid 424.95387 -1.31274)
					(end 424.682666 -1.200404)
				)
			)
		)
	)
	(zone
		(layers "B.Cu" "In1.Cu" "In3.Cu" "In4.Cu" "In5.Cu" "In6.Cu" "In7.Cu" "In8.Cu"
			"In9.Cu" "In10.Cu" "In11.Cu" "In12.Cu"
		)
		(hatch none 0.5)
		(connect_pads
			(clearance 0)
		)
		(min_thickness 0.25)
		(keepout
			(tracks not_allowed)
			(vias allowed)
			(pads allowed)
			(copperpour not_allowed)
			(footprints allowed)
		)
		(placement
			(enabled no)
			(sheetname "")
		)
		(fill yes
			(thermal_gap 0.5)
			(thermal_bridge_width 0.5)
			(island_removal_mode 0)
		)
		(polygon
			(pts
				(arc
					(start 425.812712 -2.507234)
					(mid 425.429172 -2.890774)
					(end 425.812712 -3.274314)
				)
				(arc
					(start 427.082458 -3.274314)
					(mid 427.352926 -3.162964)
					(end 427.466252 -2.893314)
				)
				(arc
					(start 427.349412 -2.893314)
					(mid 427.082712 -3.157486)
					(end 426.816012 -2.893314)
				)
				(arc
					(start 426.079412 -2.893314)
					(mid 425.812712 -3.157486)
					(end 425.546012 -2.893314)
				)
				(arc
					(start 425.546012 -2.890774)
					(mid 425.812712 -2.624074)
					(end 426.079412 -2.890774)
				)
				(arc
					(start 426.816012 -2.890774)
					(mid 427.082712 -2.624074)
					(end 427.349412 -2.890774)
				)
				(arc
					(start 427.466252 -2.890774)
					(mid 427.353916 -2.61957)
					(end 427.082712 -2.507234)
				)
			)
		)
	)
	(zone
		(layers "B.Cu" "In2.Cu" "In4.Cu" "In9.Cu")
		(hatch none 0.5)
		(connect_pads
			(clearance 0)
		)
		(min_thickness 0.25)
		(keepout
			(tracks not_allowed)
			(vias allowed)
			(pads allowed)
			(copperpour not_allowed)
			(footprints allowed)
		)
		(placement
			(enabled no)
			(sheetname "")
		)
		(fill yes
			(thermal_gap 0.5)
			(thermal_bridge_width 0.5)
			(island_removal_mode 0)
		)
		(polygon
			(pts
				(arc
					(start 394.948156 -25.366218)
					(mid 395.141954 -25.622758)
					(end 394.948156 -25.879298)
				)
				(arc
					(start 395.693646 -25.879298)
					(mid 395.499848 -25.622758)
					(end 395.693646 -25.366218)
				)
			)
		)
	)
	(zone
		(layers "B.Cu" "In2.Cu" "In4.Cu" "In9.Cu")
		(hatch none 0.5)
		(connect_pads
			(clearance 0)
		)
		(min_thickness 0.25)
		(keepout
			(tracks not_allowed)
			(vias allowed)
			(pads allowed)
			(copperpour not_allowed)
			(footprints allowed)
		)
		(placement
			(enabled no)
			(sheetname "")
		)
		(fill yes
			(thermal_gap 0.5)
			(thermal_bridge_width 0.5)
			(island_removal_mode 0)
		)
		(polygon
			(pts
				(arc
					(start 396.01394 -31.677356)
					(mid 395.7574 -31.871154)
					(end 395.50086 -31.677356)
				)
				(arc
					(start 395.50086 -32.674306)
					(mid 395.7574 -32.480508)
					(end 396.01394 -32.674306)
				)
			)
		)
	)
	(zone
		(layers "B.Cu" "In2.Cu" "In4.Cu" "In9.Cu" "In11.Cu")
		(hatch none 0.5)
		(connect_pads
			(clearance 0)
		)
		(min_thickness 0.25)
		(keepout
			(tracks not_allowed)
			(vias allowed)
			(pads allowed)
			(copperpour not_allowed)
			(footprints allowed)
		)
		(placement
			(enabled no)
			(sheetname "")
		)
		(fill yes
			(thermal_gap 0.5)
			(thermal_bridge_width 0.5)
			(island_removal_mode 0)
		)
		(polygon
			(pts
				(xy 429.225964 -45.908722) (xy 432.049682 -45.908722) (xy 432.049682 -49.536604) (xy 429.225964 -49.536604)
			)
		)
	)
	(zone
		(layers "B.Cu" "In2.Cu" "In4.Cu" "In11.Cu")
		(hatch none 0.5)
		(connect_pads
			(clearance 0)
		)
		(min_thickness 0.25)
		(keepout
			(tracks not_allowed)
			(vias allowed)
			(pads allowed)
			(copperpour not_allowed)
			(footprints allowed)
		)
		(placement
			(enabled no)
			(sheetname "")
		)
		(fill yes
			(thermal_gap 0.5)
			(thermal_bridge_width 0.5)
			(island_removal_mode 0)
		)
		(polygon
			(pts
				(arc
					(start 394.671804 -105.832656)
					(mid 394.31341 -106.190669)
					(end 394.67155 -106.548936)
				)
				(arc
					(start 395.66215 -106.548936)
					(mid 395.914494 -106.444936)
					(end 396.02029 -106.193336)
				)
				(arc
					(start 395.92885 -106.193336)
					(mid 395.66215 -106.457508)
					(end 395.39545 -106.193336)
				)
				(arc
					(start 394.93825 -106.193336)
					(mid 394.67155 -106.457508)
					(end 394.40485 -106.193336)
				)
				(arc
					(start 394.40485 -106.190796)
					(mid 394.67155 -105.924096)
					(end 394.93825 -106.190796)
				)
				(arc
					(start 395.39545 -106.190796)
					(mid 395.66215 -105.924096)
					(end 395.92885 -106.190796)
				)
				(arc
					(start 396.02029 -106.190796)
					(mid 395.915393 -105.937553)
					(end 395.66215 -105.832656)
				)
			)
		)
	)
	(zone
		(layers "B.Cu" "In2.Cu" "In4.Cu" "In11.Cu")
		(hatch none 0.5)
		(connect_pads
			(clearance 0)
		)
		(min_thickness 0.25)
		(keepout
			(tracks not_allowed)
			(vias allowed)
			(pads allowed)
			(copperpour not_allowed)
			(footprints allowed)
		)
		(placement
			(enabled no)
			(sheetname "")
		)
		(fill yes
			(thermal_gap 0.5)
			(thermal_bridge_width 0.5)
			(island_removal_mode 0)
		)
		(polygon
			(pts
				(arc
					(start 398.138904 -103.257096)
					(mid 397.78051 -103.615109)
					(end 398.13865 -103.973376)
				)
				(arc
					(start 399.12925 -103.973376)
					(mid 399.381594 -103.869376)
					(end 399.48739 -103.617776)
				)
				(arc
					(start 399.39595 -103.617776)
					(mid 399.12925 -103.881948)
					(end 398.86255 -103.617776)
				)
				(arc
					(start 398.40535 -103.617776)
					(mid 398.13865 -103.881948)
					(end 397.87195 -103.617776)
				)
				(arc
					(start 397.87195 -103.615236)
					(mid 398.13865 -103.348536)
					(end 398.40535 -103.615236)
				)
				(arc
					(start 398.86255 -103.615236)
					(mid 399.12925 -103.348536)
					(end 399.39595 -103.615236)
				)
				(arc
					(start 399.48739 -103.615236)
					(mid 399.382493 -103.361993)
					(end 399.12925 -103.257096)
				)
			)
		)
	)
	(zone
		(layers "B.Cu" "In2.Cu" "In4.Cu" "In11.Cu")
		(hatch none 0.5)
		(connect_pads
			(clearance 0)
		)
		(min_thickness 0.25)
		(keepout
			(tracks not_allowed)
			(vias allowed)
			(pads allowed)
			(copperpour not_allowed)
			(footprints allowed)
		)
		(placement
			(enabled no)
			(sheetname "")
		)
		(fill yes
			(thermal_gap 0.5)
			(thermal_bridge_width 0.5)
			(island_removal_mode 0)
		)
		(polygon
			(pts
				(arc
					(start 397.148304 -104.974136)
					(mid 396.78991 -105.332149)
					(end 397.14805 -105.690416)
				)
				(arc
					(start 398.13865 -105.690416)
					(mid 398.390994 -105.586416)
					(end 398.49679 -105.334816)
				)
				(arc
					(start 398.40535 -105.334816)
					(mid 398.13865 -105.598988)
					(end 397.87195 -105.334816)
				)
				(arc
					(start 397.41475 -105.334816)
					(mid 397.14805 -105.598988)
					(end 396.88135 -105.334816)
				)
				(arc
					(start 396.88135 -105.332276)
					(mid 397.14805 -105.065576)
					(end 397.41475 -105.332276)
				)
				(arc
					(start 397.87195 -105.332276)
					(mid 398.13865 -105.065576)
					(end 398.40535 -105.332276)
				)
				(arc
					(start 398.49679 -105.332276)
					(mid 398.391893 -105.079033)
					(end 398.13865 -104.974136)
				)
			)
		)
	)
	(zone
		(layers "B.Cu" "In4.Cu" "In9.Cu" "In11.Cu")
		(hatch none 0.5)
		(connect_pads
			(clearance 0)
		)
		(min_thickness 0.25)
		(keepout
			(tracks not_allowed)
			(vias allowed)
			(pads allowed)
			(copperpour not_allowed)
			(footprints allowed)
		)
		(placement
			(enabled no)
			(sheetname "")
		)
		(fill yes
			(thermal_gap 0.5)
			(thermal_bridge_width 0.5)
			(island_removal_mode 0)
		)
		(polygon
			(pts
				(arc
					(start 454.754742 -2.756408)
					(mid 454.946575 -3.014534)
					(end 454.750678 -3.269488)
				)
				(arc
					(start 455.874882 -3.278632)
					(mid 455.683049 -3.020506)
					(end 455.878946 -2.765552)
				)
			)
		)
	)
	(zone
		(layers "B.Cu" "In4.Cu" "In9.Cu" "In11.Cu")
		(hatch none 0.5)
		(connect_pads
			(clearance 0)
		)
		(min_thickness 0.25)
		(keepout
			(tracks not_allowed)
			(vias allowed)
			(pads allowed)
			(copperpour not_allowed)
			(footprints allowed)
		)
		(placement
			(enabled no)
			(sheetname "")
		)
		(fill yes
			(thermal_gap 0.5)
			(thermal_bridge_width 0.5)
			(island_removal_mode 0)
		)
		(polygon
			(pts
				(arc
					(start 457.136246 -1.98628)
					(mid 457.330044 -2.24282)
					(end 457.136246 -2.49936)
				)
				(arc
					(start 458.26045 -2.49936)
					(mid 458.066652 -2.24282)
					(end 458.26045 -1.98628)
				)
			)
		)
	)
	(zone
		(layers "B.Cu" "In9.Cu")
		(hatch none 0.5)
		(connect_pads
			(clearance 0)
		)
		(min_thickness 0.25)
		(keepout
			(tracks not_allowed)
			(vias allowed)
			(pads allowed)
			(copperpour not_allowed)
			(footprints allowed)
		)
		(placement
			(enabled no)
			(sheetname "")
		)
		(fill yes
			(thermal_gap 0.5)
			(thermal_bridge_width 0.5)
			(island_removal_mode 0)
		)
		(polygon
			(pts
				(arc
					(start 155.589478 -54.55031)
					(mid 150.40991 -54.55031)
					(end 155.589478 -54.55031)
				)
			)
		)
	)
	(zone
		(layers "B.Cu" "In9.Cu")
		(hatch none 0.5)
		(connect_pads
			(clearance 0)
		)
		(min_thickness 0.25)
		(keepout
			(tracks not_allowed)
			(vias allowed)
			(pads allowed)
			(copperpour not_allowed)
			(footprints allowed)
		)
		(placement
			(enabled no)
			(sheetname "")
		)
		(fill yes
			(thermal_gap 0.5)
			(thermal_bridge_width 0.5)
			(island_removal_mode 0)
		)
		(polygon
			(pts
				(arc
					(start 155.589478 -98.550222)
					(mid 150.40991 -98.550222)
					(end 155.589478 -98.550222)
				)
			)
		)
	)
	(zone
		(layer "In1.Cu")
		(hatch none 0.5)
		(connect_pads
			(clearance 0)
		)
		(min_thickness 0.25)
		(keepout
			(tracks not_allowed)
			(vias allowed)
			(pads allowed)
			(copperpour not_allowed)
			(footprints allowed)
		)
		(placement
			(enabled no)
			(sheetname "")
		)
		(fill
			(thermal_gap 0.5)
			(thermal_bridge_width 0.5)
			(island_removal_mode 0)
		)
		(polygon
			(pts
				(xy 44.720002 -141.775942) (xy 44.720002 -143.579342) (xy 45.278802 -143.579342) (xy 45.278802 -141.775942)
			)
		)
	)
	(zone
		(layer "In1.Cu")
		(hatch none 0.5)
		(connect_pads
			(clearance 0)
		)
		(min_thickness 0.25)
		(keepout
			(tracks not_allowed)
			(vias allowed)
			(pads allowed)
			(copperpour not_allowed)
			(footprints allowed)
		)
		(placement
			(enabled no)
			(sheetname "")
		)
		(fill
			(thermal_gap 0.5)
			(thermal_bridge_width 0.5)
			(island_removal_mode 0)
		)
		(polygon
			(pts
				(xy 304.920396 -9.520682) (xy 304.920396 -11.324082) (xy 305.479196 -11.324082) (xy 305.479196 -9.520682)
			)
		)
	)
	(zone
		(layer "In1.Cu")
		(hatch none 0.5)
		(connect_pads
			(clearance 0)
		)
		(min_thickness 0.25)
		(keepout
			(tracks not_allowed)
			(vias allowed)
			(pads allowed)
			(copperpour not_allowed)
			(footprints allowed)
		)
		(placement
			(enabled no)
			(sheetname "")
		)
		(fill
			(thermal_gap 0.5)
			(thermal_bridge_width 0.5)
			(island_removal_mode 0)
		)
		(polygon
			(pts
				(xy 397.776192 -9.774936) (xy 398.284192 -9.774936) (xy 398.284192 -11.171936) (xy 397.776192 -11.171936)
			)
		)
	)
	(zone
		(layer "In1.Cu")
		(hatch none 0.5)
		(connect_pads
			(clearance 0)
		)
		(min_thickness 0.25)
		(keepout
			(tracks not_allowed)
			(vias allowed)
			(pads allowed)
			(copperpour not_allowed)
			(footprints allowed)
		)
		(placement
			(enabled no)
			(sheetname "")
		)
		(fill
			(thermal_gap 0.5)
			(thermal_bridge_width 0.5)
			(island_removal_mode 0)
		)
		(polygon
			(pts
				(xy 137.370058 0.080518) (xy 137.370058 -1.722882) (xy 137.928858 -1.722882) (xy 137.928858 0.080518)
			)
		)
	)
	(zone
		(layer "In1.Cu")
		(hatch none 0.5)
		(connect_pads
			(clearance 0)
		)
		(min_thickness 0.25)
		(keepout
			(tracks not_allowed)
			(vias allowed)
			(pads allowed)
			(copperpour not_allowed)
			(footprints allowed)
		)
		(placement
			(enabled no)
			(sheetname "")
		)
		(fill
			(thermal_gap 0.5)
			(thermal_bridge_width 0.5)
			(island_removal_mode 0)
		)
		(polygon
			(pts
				(xy 213.970362 -9.520682) (xy 213.970362 -11.324082) (xy 214.529162 -11.324082) (xy 214.529162 -9.520682)
			)
		)
	)
	(zone
		(layer "In1.Cu")
		(hatch none 0.5)
		(connect_pads
			(clearance 0)
		)
		(min_thickness 0.25)
		(keepout
			(tracks not_allowed)
			(vias allowed)
			(pads allowed)
			(copperpour not_allowed)
			(footprints allowed)
		)
		(placement
			(enabled no)
			(sheetname "")
		)
		(fill
			(thermal_gap 0.5)
			(thermal_bridge_width 0.5)
			(island_removal_mode 0)
		)
		(polygon
			(pts
				(xy 287.070546 -4.920742) (xy 287.070546 -6.724142) (xy 287.629346 -6.724142) (xy 287.629346 -4.920742)
			)
		)
	)
	(zone
		(layer "In1.Cu")
		(hatch none 0.5)
		(connect_pads
			(clearance 0)
		)
		(min_thickness 0.25)
		(keepout
			(tracks not_allowed)
			(vias allowed)
			(pads allowed)
			(copperpour not_allowed)
			(footprints allowed)
		)
		(placement
			(enabled no)
			(sheetname "")
		)
		(fill
			(thermal_gap 0.5)
			(thermal_bridge_width 0.5)
			(island_removal_mode 0)
		)
		(polygon
			(pts
				(xy 212.270594 -19.121882) (xy 212.270594 -20.925282) (xy 212.829394 -20.925282) (xy 212.829394 -19.121882)
			)
		)
	)
	(zone
		(layer "In1.Cu")
		(hatch none 0.5)
		(connect_pads
			(clearance 0)
		)
		(min_thickness 0.25)
		(keepout
			(tracks not_allowed)
			(vias allowed)
			(pads allowed)
			(copperpour not_allowed)
			(footprints allowed)
		)
		(placement
			(enabled no)
			(sheetname "")
		)
		(fill
			(thermal_gap 0.5)
			(thermal_bridge_width 0.5)
			(island_removal_mode 0)
		)
		(polygon
			(pts
				(xy 202.9206 0.080518) (xy 202.9206 -1.722882) (xy 203.4794 -1.722882) (xy 203.4794 0.080518)
			)
		)
	)
	(zone
		(layer "In1.Cu")
		(hatch none 0.5)
		(connect_pads
			(clearance 0)
		)
		(min_thickness 0.25)
		(keepout
			(tracks not_allowed)
			(vias allowed)
			(pads allowed)
			(copperpour not_allowed)
			(footprints allowed)
		)
		(placement
			(enabled no)
			(sheetname "")
		)
		(fill
			(thermal_gap 0.5)
			(thermal_bridge_width 0.5)
			(island_removal_mode 0)
		)
		(polygon
			(pts
				(xy 74.470006 -4.920742) (xy 74.470006 -6.724142) (xy 75.028806 -6.724142) (xy 75.028806 -4.920742)
			)
		)
	)
	(zone
		(layer "In1.Cu")
		(hatch none 0.5)
		(connect_pads
			(clearance 0)
		)
		(min_thickness 0.25)
		(keepout
			(tracks not_allowed)
			(vias allowed)
			(pads allowed)
			(copperpour not_allowed)
			(footprints allowed)
		)
		(placement
			(enabled no)
			(sheetname "")
		)
		(fill
			(thermal_gap 0.5)
			(thermal_bridge_width 0.5)
			(island_removal_mode 0)
		)
		(polygon
			(pts
				(xy 208.020412 -19.121882) (xy 208.020412 -20.925282) (xy 208.579212 -20.925282) (xy 208.579212 -19.121882)
			)
		)
	)
	(zone
		(layer "In1.Cu")
		(hatch none 0.5)
		(connect_pads
			(clearance 0)
		)
		(min_thickness 0.25)
		(keepout
			(tracks not_allowed)
			(vias allowed)
			(pads allowed)
			(copperpour not_allowed)
			(footprints allowed)
		)
		(placement
			(enabled no)
			(sheetname "")
		)
		(fill
			(thermal_gap 0.5)
			(thermal_bridge_width 0.5)
			(island_removal_mode 0)
		)
		(polygon
			(pts
				(xy 54.069996 -132.174742) (xy 54.069996 -133.978142) (xy 54.628796 -133.978142) (xy 54.628796 -132.174742)
			)
		)
	)
	(zone
		(layer "In1.Cu")
		(hatch none 0.5)
		(connect_pads
			(clearance 0)
		)
		(min_thickness 0.25)
		(keepout
			(tracks not_allowed)
			(vias allowed)
			(pads allowed)
			(copperpour not_allowed)
			(footprints allowed)
		)
		(placement
			(enabled no)
			(sheetname "")
		)
		(fill
			(thermal_gap 0.5)
			(thermal_bridge_width 0.5)
			(island_removal_mode 0)
		)
		(polygon
			(pts
				(xy 452.223378 -3.789172) (xy 453.531478 -3.789172) (xy 453.531478 -4.982972) (xy 452.223378 -4.982972)
			)
		)
	)
	(zone
		(layer "In1.Cu")
		(hatch none 0.5)
		(connect_pads
			(clearance 0)
		)
		(min_thickness 0.25)
		(keepout
			(tracks not_allowed)
			(vias allowed)
			(pads allowed)
			(copperpour not_allowed)
			(footprints allowed)
		)
		(placement
			(enabled no)
			(sheetname "")
		)
		(fill
			(thermal_gap 0.5)
			(thermal_bridge_width 0.5)
			(island_removal_mode 0)
		)
		(polygon
			(pts
				(xy 199.520556 -14.521942) (xy 199.520556 -16.325342) (xy 200.079356 -16.325342) (xy 200.079356 -14.521942)
			)
		)
	)
	(zone
		(layer "In1.Cu")
		(hatch none 0.5)
		(connect_pads
			(clearance 0)
		)
		(min_thickness 0.25)
		(keepout
			(tracks not_allowed)
			(vias allowed)
			(pads allowed)
			(copperpour not_allowed)
			(footprints allowed)
		)
		(placement
			(enabled no)
			(sheetname "")
		)
		(fill
			(thermal_gap 0.5)
			(thermal_bridge_width 0.5)
			(island_removal_mode 0)
		)
		(polygon
			(pts
				(xy 140.770102 4.680458) (xy 140.770102 2.877058) (xy 141.328902 2.877058) (xy 141.328902 4.680458)
			)
		)
	)
	(zone
		(layer "In1.Cu")
		(hatch none 0.5)
		(connect_pads
			(clearance 0)
		)
		(min_thickness 0.25)
		(keepout
			(tracks not_allowed)
			(vias allowed)
			(pads allowed)
			(copperpour not_allowed)
			(footprints allowed)
		)
		(placement
			(enabled no)
			(sheetname "")
		)
		(fill
			(thermal_gap 0.5)
			(thermal_bridge_width 0.5)
			(island_removal_mode 0)
		)
		(polygon
			(pts
				(xy 139.07008 4.680458) (xy 139.07008 2.877058) (xy 139.62888 2.877058) (xy 139.62888 4.680458)
			)
		)
	)
	(zone
		(layer "In1.Cu")
		(hatch none 0.5)
		(connect_pads
			(clearance 0)
		)
		(min_thickness 0.25)
		(keepout
			(tracks not_allowed)
			(vias allowed)
			(pads allowed)
			(copperpour not_allowed)
			(footprints allowed)
		)
		(placement
			(enabled no)
			(sheetname "")
		)
		(fill
			(thermal_gap 0.5)
			(thermal_bridge_width 0.5)
			(island_removal_mode 0)
		)
		(polygon
			(pts
				(xy 321.8815 -116.968016) (xy 324.1675 -116.968016) (xy 324.1675 -117.476016) (xy 321.8815 -117.476016)
			)
		)
	)
	(zone
		(layer "In1.Cu")
		(hatch none 0.5)
		(connect_pads
			(clearance 0)
		)
		(min_thickness 0.25)
		(keepout
			(tracks not_allowed)
			(vias allowed)
			(pads allowed)
			(copperpour not_allowed)
			(footprints allowed)
		)
		(placement
			(enabled no)
			(sheetname "")
		)
		(fill
			(thermal_gap 0.5)
			(thermal_bridge_width 0.5)
			(island_removal_mode 0)
		)
		(polygon
			(pts
				(xy 200.37044 -151.377142) (xy 200.37044 -153.180542) (xy 200.92924 -153.180542) (xy 200.92924 -151.377142)
			)
		)
	)
	(zone
		(layer "In1.Cu")
		(hatch none 0.5)
		(connect_pads
			(clearance 0)
		)
		(min_thickness 0.25)
		(keepout
			(tracks not_allowed)
			(vias allowed)
			(pads allowed)
			(copperpour not_allowed)
			(footprints allowed)
		)
		(placement
			(enabled no)
			(sheetname "")
		)
		(fill
			(thermal_gap 0.5)
			(thermal_bridge_width 0.5)
			(island_removal_mode 0)
		)
		(polygon
			(pts
				(xy 114.419888 -151.377142) (xy 114.419888 -153.180542) (xy 114.978688 -153.180542) (xy 114.978688 -151.377142)
			)
		)
	)
	(zone
		(layer "In1.Cu")
		(hatch none 0.5)
		(connect_pads
			(clearance 0)
		)
		(min_thickness 0.25)
		(keepout
			(tracks not_allowed)
			(vias allowed)
			(pads allowed)
			(copperpour not_allowed)
			(footprints allowed)
		)
		(placement
			(enabled no)
			(sheetname "")
		)
		(fill
			(thermal_gap 0.5)
			(thermal_bridge_width 0.5)
			(island_removal_mode 0)
		)
		(polygon
			(pts
				(xy 272.620486 4.680458) (xy 272.620486 2.877058) (xy 273.179286 2.877058) (xy 273.179286 4.680458)
			)
		)
	)
	(zone
		(layer "In1.Cu")
		(hatch none 0.5)
		(connect_pads
			(clearance 0)
		)
		(min_thickness 0.25)
		(keepout
			(tracks not_allowed)
			(vias allowed)
			(pads allowed)
			(copperpour not_allowed)
			(footprints allowed)
		)
		(placement
			(enabled no)
			(sheetname "")
		)
		(fill
			(thermal_gap 0.5)
			(thermal_bridge_width 0.5)
			(island_removal_mode 0)
		)
		(polygon
			(pts
				(xy 102.519988 -4.920742) (xy 102.519988 -6.724142) (xy 103.078788 -6.724142) (xy 103.078788 -4.920742)
			)
		)
	)
	(zone
		(layer "In1.Cu")
		(hatch none 0.5)
		(connect_pads
			(clearance 0)
		)
		(min_thickness 0.25)
		(keepout
			(tracks not_allowed)
			(vias allowed)
			(pads allowed)
			(copperpour not_allowed)
			(footprints allowed)
		)
		(placement
			(enabled no)
			(sheetname "")
		)
		(fill
			(thermal_gap 0.5)
			(thermal_bridge_width 0.5)
			(island_removal_mode 0)
		)
		(polygon
			(pts
				(xy 61.719968 -136.774682) (xy 61.719968 -138.578082) (xy 62.278768 -138.578082) (xy 62.278768 -136.774682)
			)
		)
	)
	(zone
		(layer "In1.Cu")
		(hatch none 0.5)
		(connect_pads
			(clearance 0)
		)
		(min_thickness 0.25)
		(keepout
			(tracks not_allowed)
			(vias allowed)
			(pads allowed)
			(copperpour not_allowed)
			(footprints allowed)
		)
		(placement
			(enabled no)
			(sheetname "")
		)
		(fill
			(thermal_gap 0.5)
			(thermal_bridge_width 0.5)
			(island_removal_mode 0)
		)
		(polygon
			(pts
				(xy 131.420108 -4.920742) (xy 131.420108 -6.724142) (xy 131.978908 -6.724142) (xy 131.978908 -4.920742)
			)
		)
	)
	(zone
		(layer "In1.Cu")
		(hatch none 0.5)
		(connect_pads
			(clearance 0)
		)
		(min_thickness 0.25)
		(keepout
			(tracks not_allowed)
			(vias allowed)
			(pads allowed)
			(copperpour not_allowed)
			(footprints allowed)
		)
		(placement
			(enabled no)
			(sheetname "")
		)
		(fill
			(thermal_gap 0.5)
			(thermal_bridge_width 0.5)
			(island_removal_mode 0)
		)
		(polygon
			(pts
				(xy 147.569936 -136.774682) (xy 147.569936 -138.578082) (xy 148.128736 -138.578082) (xy 148.128736 -136.774682)
			)
		)
	)
	(zone
		(layer "In1.Cu")
		(hatch none 0.5)
		(connect_pads
			(clearance 0)
		)
		(min_thickness 0.25)
		(keepout
			(tracks not_allowed)
			(vias allowed)
			(pads allowed)
			(copperpour not_allowed)
			(footprints allowed)
		)
		(placement
			(enabled no)
			(sheetname "")
		)
		(fill
			(thermal_gap 0.5)
			(thermal_bridge_width 0.5)
			(island_removal_mode 0)
		)
		(polygon
			(pts
				(xy 308.32044 -136.774682) (xy 308.32044 -138.578082) (xy 308.87924 -138.578082) (xy 308.87924 -136.774682)
			)
		)
	)
	(zone
		(layer "In1.Cu")
		(hatch none 0.5)
		(connect_pads
			(clearance 0)
		)
		(min_thickness 0.25)
		(keepout
			(tracks not_allowed)
			(vias allowed)
			(pads allowed)
			(copperpour not_allowed)
			(footprints allowed)
		)
		(placement
			(enabled no)
			(sheetname "")
		)
		(fill
			(thermal_gap 0.5)
			(thermal_bridge_width 0.5)
			(island_removal_mode 0)
		)
		(polygon
			(pts
				(xy 219.070428 -141.775942) (xy 219.070428 -143.579342) (xy 219.629228 -143.579342) (xy 219.629228 -141.775942)
			)
		)
	)
	(zone
		(layer "In1.Cu")
		(hatch none 0.5)
		(connect_pads
			(clearance 0)
		)
		(min_thickness 0.25)
		(keepout
			(tracks not_allowed)
			(vias allowed)
			(pads allowed)
			(copperpour not_allowed)
			(footprints allowed)
		)
		(placement
			(enabled no)
			(sheetname "")
		)
		(fill
			(thermal_gap 0.5)
			(thermal_bridge_width 0.5)
			(island_removal_mode 0)
		)
		(polygon
			(pts
				(xy 48.96993 -19.121882) (xy 48.96993 -20.925282) (xy 49.52873 -20.925282) (xy 49.52873 -19.121882)
			)
		)
	)
	(zone
		(layer "In1.Cu")
		(hatch none 0.5)
		(connect_pads
			(clearance 0)
		)
		(min_thickness 0.25)
		(keepout
			(tracks not_allowed)
			(vias allowed)
			(pads allowed)
			(copperpour not_allowed)
			(footprints allowed)
		)
		(placement
			(enabled no)
			(sheetname "")
		)
		(fill
			(thermal_gap 0.5)
			(thermal_bridge_width 0.5)
			(island_removal_mode 0)
		)
		(polygon
			(pts
				(xy 293.87038 -136.774682) (xy 293.87038 -138.578082) (xy 294.42918 -138.578082) (xy 294.42918 -136.774682)
			)
		)
	)
	(zone
		(layer "In1.Cu")
		(hatch none 0.5)
		(connect_pads
			(clearance 0)
		)
		(min_thickness 0.25)
		(keepout
			(tracks not_allowed)
			(vias allowed)
			(pads allowed)
			(copperpour not_allowed)
			(footprints allowed)
		)
		(placement
			(enabled no)
			(sheetname "")
		)
		(fill
			(thermal_gap 0.5)
			(thermal_bridge_width 0.5)
			(island_removal_mode 0)
		)
		(polygon
			(pts
				(xy 84.670138 -19.121882) (xy 85.228938 -19.121882) (xy 85.228938 -20.925282) (xy 84.670138 -20.925282)
			)
		)
	)
	(zone
		(layer "In1.Cu")
		(hatch none 0.5)
		(connect_pads
			(clearance 0)
		)
		(min_thickness 0.25)
		(keepout
			(tracks not_allowed)
			(vias allowed)
			(pads allowed)
			(copperpour not_allowed)
			(footprints allowed)
		)
		(placement
			(enabled no)
			(sheetname "")
		)
		(fill
			(thermal_gap 0.5)
			(thermal_bridge_width 0.5)
			(island_removal_mode 0)
		)
		(polygon
			(pts
				(xy 41.319958 -9.520682) (xy 41.319958 -11.324082) (xy 41.878758 -11.324082) (xy 41.878758 -9.520682)
			)
		)
	)
	(zone
		(layer "In1.Cu")
		(hatch none 0.5)
		(connect_pads
			(clearance 0)
		)
		(min_thickness 0.25)
		(keepout
			(tracks not_allowed)
			(vias allowed)
			(pads allowed)
			(copperpour not_allowed)
			(footprints allowed)
		)
		(placement
			(enabled no)
			(sheetname "")
		)
		(fill
			(thermal_gap 0.5)
			(thermal_bridge_width 0.5)
			(island_removal_mode 0)
		)
		(polygon
			(pts
				(xy 110.16996 -9.520682) (xy 110.16996 -11.324082) (xy 110.72876 -11.324082) (xy 110.72876 -9.520682)
			)
		)
	)
	(zone
		(layer "In1.Cu")
		(hatch none 0.5)
		(connect_pads
			(clearance 0)
		)
		(min_thickness 0.25)
		(keepout
			(tracks not_allowed)
			(vias allowed)
			(pads allowed)
			(copperpour not_allowed)
			(footprints allowed)
		)
		(placement
			(enabled no)
			(sheetname "")
		)
		(fill
			(thermal_gap 0.5)
			(thermal_bridge_width 0.5)
			(island_removal_mode 0)
		)
		(polygon
			(pts
				(xy 138.219942 -146.375882) (xy 138.219942 -148.179282) (xy 138.778742 -148.179282) (xy 138.778742 -146.375882)
			)
		)
	)
	(zone
		(layer "In1.Cu")
		(hatch none 0.5)
		(connect_pads
			(clearance 0)
		)
		(min_thickness 0.25)
		(keepout
			(tracks not_allowed)
			(vias allowed)
			(pads allowed)
			(copperpour not_allowed)
			(footprints allowed)
		)
		(placement
			(enabled no)
			(sheetname "")
		)
		(fill
			(thermal_gap 0.5)
			(thermal_bridge_width 0.5)
			(island_removal_mode 0)
		)
		(polygon
			(pts
				(xy 135.670036 -19.121882) (xy 135.670036 -20.925282) (xy 136.228836 -20.925282) (xy 136.228836 -19.121882)
			)
		)
	)
	(zone
		(layer "In1.Cu")
		(hatch none 0.5)
		(connect_pads
			(clearance 0)
		)
		(min_thickness 0.25)
		(keepout
			(tracks not_allowed)
			(vias allowed)
			(pads allowed)
			(copperpour not_allowed)
			(footprints allowed)
		)
		(placement
			(enabled no)
			(sheetname "")
		)
		(fill
			(thermal_gap 0.5)
			(thermal_bridge_width 0.5)
			(island_removal_mode 0)
		)
		(polygon
			(pts
				(xy 282.820364 4.680458) (xy 282.820364 2.877058) (xy 283.379164 2.877058) (xy 283.379164 4.680458)
			)
		)
	)
	(zone
		(layer "In1.Cu")
		(hatch none 0.5)
		(connect_pads
			(clearance 0)
		)
		(min_thickness 0.25)
		(keepout
			(tracks not_allowed)
			(vias allowed)
			(pads allowed)
			(copperpour not_allowed)
			(footprints allowed)
		)
		(placement
			(enabled no)
			(sheetname "")
		)
		(fill
			(thermal_gap 0.5)
			(thermal_bridge_width 0.5)
			(island_removal_mode 0)
		)
		(polygon
			(pts
				(xy 136.51992 -141.775942) (xy 136.51992 -143.579342) (xy 137.07872 -143.579342) (xy 137.07872 -141.775942)
			)
		)
	)
	(zone
		(layer "In1.Cu")
		(hatch none 0.5)
		(connect_pads
			(clearance 0)
		)
		(min_thickness 0.25)
		(keepout
			(tracks not_allowed)
			(vias allowed)
			(pads allowed)
			(copperpour not_allowed)
			(footprints allowed)
		)
		(placement
			(enabled no)
			(sheetname "")
		)
		(fill
			(thermal_gap 0.5)
			(thermal_bridge_width 0.5)
			(island_removal_mode 0)
		)
		(polygon
			(pts
				(xy 209.720434 -9.520682) (xy 209.720434 -11.324082) (xy 210.279234 -11.324082) (xy 210.279234 -9.520682)
			)
		)
	)
	(zone
		(layer "In1.Cu")
		(hatch none 0.5)
		(connect_pads
			(clearance 0)
		)
		(min_thickness 0.25)
		(keepout
			(tracks not_allowed)
			(vias allowed)
			(pads allowed)
			(copperpour not_allowed)
			(footprints allowed)
		)
		(placement
			(enabled no)
			(sheetname "")
		)
		(fill
			(thermal_gap 0.5)
			(thermal_bridge_width 0.5)
			(island_removal_mode 0)
		)
		(polygon
			(pts
				(xy 134.819898 -151.377142) (xy 134.819898 -153.180542) (xy 135.378698 -153.180542) (xy 135.378698 -151.377142)
			)
		)
	)
	(zone
		(layer "In1.Cu")
		(hatch none 0.5)
		(connect_pads
			(clearance 0)
		)
		(min_thickness 0.25)
		(keepout
			(tracks not_allowed)
			(vias allowed)
			(pads allowed)
			(copperpour not_allowed)
			(footprints allowed)
		)
		(placement
			(enabled no)
			(sheetname "")
		)
		(fill
			(thermal_gap 0.5)
			(thermal_bridge_width 0.5)
			(island_removal_mode 0)
		)
		(polygon
			(pts
				(xy 294.720518 -151.377142) (xy 294.720518 -153.180542) (xy 295.279318 -153.180542) (xy 295.279318 -151.377142)
			)
		)
	)
	(zone
		(layer "In1.Cu")
		(hatch none 0.5)
		(connect_pads
			(clearance 0)
		)
		(min_thickness 0.25)
		(keepout
			(tracks not_allowed)
			(vias allowed)
			(pads allowed)
			(copperpour not_allowed)
			(footprints allowed)
		)
		(placement
			(enabled no)
			(sheetname "")
		)
		(fill
			(thermal_gap 0.5)
			(thermal_bridge_width 0.5)
			(island_removal_mode 0)
		)
		(polygon
			(pts
				(xy 275.170392 -136.774682) (xy 275.170392 -138.578082) (xy 275.729192 -138.578082) (xy 275.729192 -136.774682)
			)
		)
	)
	(zone
		(layer "In1.Cu")
		(hatch none 0.5)
		(connect_pads
			(clearance 0)
		)
		(min_thickness 0.25)
		(keepout
			(tracks not_allowed)
			(vias allowed)
			(pads allowed)
			(copperpour not_allowed)
			(footprints allowed)
		)
		(placement
			(enabled no)
			(sheetname "")
		)
		(fill
			(thermal_gap 0.5)
			(thermal_bridge_width 0.5)
			(island_removal_mode 0)
		)
		(polygon
			(pts
				(xy 298.970446 0.080518) (xy 298.970446 -1.722882) (xy 299.529246 -1.722882) (xy 299.529246 0.080518)
			)
		)
	)
	(zone
		(layer "In1.Cu")
		(hatch none 0.5)
		(connect_pads
			(clearance 0)
		)
		(min_thickness 0.25)
		(keepout
			(tracks not_allowed)
			(vias allowed)
			(pads allowed)
			(copperpour not_allowed)
			(footprints allowed)
		)
		(placement
			(enabled no)
			(sheetname "")
		)
		(fill
			(thermal_gap 0.5)
			(thermal_bridge_width 0.5)
			(island_removal_mode 0)
		)
		(polygon
			(pts
				(xy 239.470438 -4.920742) (xy 239.470438 -6.724142) (xy 240.029238 -6.724142) (xy 240.029238 -4.920742)
			)
		)
	)
	(zone
		(layer "In1.Cu")
		(hatch none 0.5)
		(connect_pads
			(clearance 0)
		)
		(min_thickness 0.25)
		(keepout
			(tracks not_allowed)
			(vias allowed)
			(pads allowed)
			(copperpour not_allowed)
			(footprints allowed)
		)
		(placement
			(enabled no)
			(sheetname "")
		)
		(fill
			(thermal_gap 0.5)
			(thermal_bridge_width 0.5)
			(island_removal_mode 0)
		)
		(polygon
			(pts
				(xy 45.57014 -146.375882) (xy 45.57014 -148.179282) (xy 46.12894 -148.179282) (xy 46.12894 -146.375882)
			)
		)
	)
	(zone
		(layer "In1.Cu")
		(hatch none 0.5)
		(connect_pads
			(clearance 0)
		)
		(min_thickness 0.25)
		(keepout
			(tracks not_allowed)
			(vias allowed)
			(pads allowed)
			(copperpour not_allowed)
			(footprints allowed)
		)
		(placement
			(enabled no)
			(sheetname "")
		)
		(fill
			(thermal_gap 0.5)
			(thermal_bridge_width 0.5)
			(island_removal_mode 0)
		)
		(polygon
			(pts
				(xy 132.269992 -155.977082) (xy 132.269992 -157.780482) (xy 132.828792 -157.780482) (xy 132.828792 -155.977082)
			)
		)
	)
	(zone
		(layer "In1.Cu")
		(hatch none 0.5)
		(connect_pads
			(clearance 0)
		)
		(min_thickness 0.25)
		(keepout
			(tracks not_allowed)
			(vias allowed)
			(pads allowed)
			(copperpour not_allowed)
			(footprints allowed)
		)
		(placement
			(enabled no)
			(sheetname "")
		)
		(fill
			(thermal_gap 0.5)
			(thermal_bridge_width 0.5)
			(island_removal_mode 0)
		)
		(polygon
			(pts
				(xy 229.27056 -136.774682) (xy 229.27056 -138.578082) (xy 229.82936 -138.578082) (xy 229.82936 -136.774682)
			)
		)
	)
	(zone
		(layer "In1.Cu")
		(hatch none 0.5)
		(connect_pads
			(clearance 0)
		)
		(min_thickness 0.25)
		(keepout
			(tracks not_allowed)
			(vias allowed)
			(pads allowed)
			(copperpour not_allowed)
			(footprints allowed)
		)
		(placement
			(enabled no)
			(sheetname "")
		)
		(fill
			(thermal_gap 0.5)
			(thermal_bridge_width 0.5)
			(island_removal_mode 0)
		)
		(polygon
			(pts
				(xy 309.170324 -4.920742) (xy 309.170324 -6.724142) (xy 309.729124 -6.724142) (xy 309.729124 -4.920742)
			)
		)
	)
	(zone
		(layer "In1.Cu")
		(hatch none 0.5)
		(connect_pads
			(clearance 0)
		)
		(min_thickness 0.25)
		(keepout
			(tracks not_allowed)
			(vias allowed)
			(pads allowed)
			(copperpour not_allowed)
			(footprints allowed)
		)
		(placement
			(enabled no)
			(sheetname "")
		)
		(fill
			(thermal_gap 0.5)
			(thermal_bridge_width 0.5)
			(island_removal_mode 0)
		)
		(polygon
			(pts
				(xy 216.520522 -14.521942) (xy 216.520522 -16.325342) (xy 217.079322 -16.325342) (xy 217.079322 -14.521942)
			)
		)
	)
	(zone
		(layer "In1.Cu")
		(hatch none 0.5)
		(connect_pads
			(clearance 0)
		)
		(min_thickness 0.25)
		(keepout
			(tracks not_allowed)
			(vias allowed)
			(pads allowed)
			(copperpour not_allowed)
			(footprints allowed)
		)
		(placement
			(enabled no)
			(sheetname "")
		)
		(fill
			(thermal_gap 0.5)
			(thermal_bridge_width 0.5)
			(island_removal_mode 0)
		)
		(polygon
			(pts
				(xy 150.120096 -4.920742) (xy 150.120096 -6.724142) (xy 150.678896 -6.724142) (xy 150.678896 -4.920742)
			)
		)
	)
	(zone
		(layer "In1.Cu")
		(hatch none 0.5)
		(connect_pads
			(clearance 0)
		)
		(min_thickness 0.25)
		(keepout
			(tracks not_allowed)
			(vias allowed)
			(pads allowed)
			(copperpour not_allowed)
			(footprints allowed)
		)
		(placement
			(enabled no)
			(sheetname "")
		)
		(fill
			(thermal_gap 0.5)
			(thermal_bridge_width 0.5)
			(island_removal_mode 0)
		)
		(polygon
			(pts
				(xy 236.920532 -4.920742) (xy 236.920532 -6.724142) (xy 237.479332 -6.724142) (xy 237.479332 -4.920742)
			)
		)
	)
	(zone
		(layer "In1.Cu")
		(hatch none 0.5)
		(connect_pads
			(clearance 0)
		)
		(min_thickness 0.25)
		(keepout
			(tracks not_allowed)
			(vias allowed)
			(pads allowed)
			(copperpour not_allowed)
			(footprints allowed)
		)
		(placement
			(enabled no)
			(sheetname "")
		)
		(fill
			(thermal_gap 0.5)
			(thermal_bridge_width 0.5)
			(island_removal_mode 0)
		)
		(polygon
			(pts
				(xy 140.770102 -151.377142) (xy 140.770102 -153.180542) (xy 141.328902 -153.180542) (xy 141.328902 -151.377142)
			)
		)
	)
	(zone
		(layer "In1.Cu")
		(hatch none 0.5)
		(connect_pads
			(clearance 0)
		)
		(min_thickness 0.25)
		(keepout
			(tracks not_allowed)
			(vias allowed)
			(pads allowed)
			(copperpour not_allowed)
			(footprints allowed)
		)
		(placement
			(enabled no)
			(sheetname "")
		)
		(fill
			(thermal_gap 0.5)
			(thermal_bridge_width 0.5)
			(island_removal_mode 0)
		)
		(polygon
			(pts
				(xy 303.220374 -155.977082) (xy 303.220374 -157.780482) (xy 303.779174 -157.780482) (xy 303.779174 -155.977082)
			)
		)
	)
	(zone
		(layer "In1.Cu")
		(hatch none 0.5)
		(connect_pads
			(clearance 0)
		)
		(min_thickness 0.25)
		(keepout
			(tracks not_allowed)
			(vias allowed)
			(pads allowed)
			(copperpour not_allowed)
			(footprints allowed)
		)
		(placement
			(enabled no)
			(sheetname "")
		)
		(fill
			(thermal_gap 0.5)
			(thermal_bridge_width 0.5)
			(island_removal_mode 0)
		)
		(polygon
			(pts
				(xy 123.769882 -141.775942) (xy 123.769882 -143.579342) (xy 124.328682 -143.579342) (xy 124.328682 -141.775942)
			)
		)
	)
	(zone
		(layer "In1.Cu")
		(hatch none 0.5)
		(connect_pads
			(clearance 0)
		)
		(min_thickness 0.25)
		(keepout
			(tracks not_allowed)
			(vias allowed)
			(pads allowed)
			(copperpour not_allowed)
			(footprints allowed)
		)
		(placement
			(enabled no)
			(sheetname "")
		)
		(fill
			(thermal_gap 0.5)
			(thermal_bridge_width 0.5)
			(island_removal_mode 0)
		)
		(polygon
			(pts
				(xy 294.720518 -14.521942) (xy 294.720518 -16.325342) (xy 295.279318 -16.325342) (xy 295.279318 -14.521942)
			)
		)
	)
	(zone
		(layer "In1.Cu")
		(hatch none 0.5)
		(connect_pads
			(clearance 0)
		)
		(min_thickness 0.25)
		(keepout
			(tracks not_allowed)
			(vias allowed)
			(pads allowed)
			(copperpour not_allowed)
			(footprints allowed)
		)
		(placement
			(enabled no)
			(sheetname "")
		)
		(fill
			(thermal_gap 0.5)
			(thermal_bridge_width 0.5)
			(island_removal_mode 0)
		)
		(polygon
			(pts
				(xy 73.620122 -155.977082) (xy 73.620122 -157.780482) (xy 74.178922 -157.780482) (xy 74.178922 -155.977082)
			)
		)
	)
	(zone
		(layer "In1.Cu")
		(hatch none 0.5)
		(connect_pads
			(clearance 0)
		)
		(min_thickness 0.25)
		(keepout
			(tracks not_allowed)
			(vias allowed)
			(pads allowed)
			(copperpour not_allowed)
			(footprints allowed)
		)
		(placement
			(enabled no)
			(sheetname "")
		)
		(fill
			(thermal_gap 0.5)
			(thermal_bridge_width 0.5)
			(island_removal_mode 0)
		)
		(polygon
			(pts
				(xy 88.920066 -14.521942) (xy 88.920066 -16.325342) (xy 89.478866 -16.325342) (xy 89.478866 -14.521942)
			)
		)
	)
	(zone
		(layer "In1.Cu")
		(hatch none 0.5)
		(connect_pads
			(clearance 0)
		)
		(min_thickness 0.25)
		(keepout
			(tracks not_allowed)
			(vias allowed)
			(pads allowed)
			(copperpour not_allowed)
			(footprints allowed)
		)
		(placement
			(enabled no)
			(sheetname "")
		)
		(fill
			(thermal_gap 0.5)
			(thermal_bridge_width 0.5)
			(island_removal_mode 0)
		)
		(polygon
			(pts
				(xy 301.520352 -14.521942) (xy 301.520352 -16.325342) (xy 302.079152 -16.325342) (xy 302.079152 -14.521942)
			)
		)
	)
	(zone
		(layer "In1.Cu")
		(hatch none 0.5)
		(connect_pads
			(clearance 0)
		)
		(min_thickness 0.25)
		(keepout
			(tracks not_allowed)
			(vias allowed)
			(pads allowed)
			(copperpour not_allowed)
			(footprints allowed)
		)
		(placement
			(enabled no)
			(sheetname "")
		)
		(fill
			(thermal_gap 0.5)
			(thermal_bridge_width 0.5)
			(island_removal_mode 0)
		)
		(polygon
			(pts
				(xy 35.370008 -146.375882) (xy 35.370008 -148.179282) (xy 35.928808 -148.179282) (xy 35.928808 -146.375882)
			)
		)
	)
	(zone
		(layer "In1.Cu")
		(hatch none 0.5)
		(connect_pads
			(clearance 0)
		)
		(min_thickness 0.25)
		(keepout
			(tracks not_allowed)
			(vias allowed)
			(pads allowed)
			(copperpour not_allowed)
			(footprints allowed)
		)
		(placement
			(enabled no)
			(sheetname "")
		)
		(fill
			(thermal_gap 0.5)
			(thermal_bridge_width 0.5)
			(island_removal_mode 0)
		)
		(polygon
			(pts
				(xy 273.47037 -155.977082) (xy 273.47037 -157.780482) (xy 274.02917 -157.780482) (xy 274.02917 -155.977082)
			)
		)
	)
	(zone
		(layer "In1.Cu")
		(hatch none 0.5)
		(connect_pads
			(clearance 0)
		)
		(min_thickness 0.25)
		(keepout
			(tracks not_allowed)
			(vias allowed)
			(pads allowed)
			(copperpour not_allowed)
			(footprints allowed)
		)
		(placement
			(enabled no)
			(sheetname "")
		)
		(fill
			(thermal_gap 0.5)
			(thermal_bridge_width 0.5)
			(island_removal_mode 0)
		)
		(polygon
			(pts
				(xy 231.820466 -4.920742) (xy 231.820466 -6.724142) (xy 232.379266 -6.724142) (xy 232.379266 -4.920742)
			)
		)
	)
	(zone
		(layer "In1.Cu")
		(hatch none 0.5)
		(connect_pads
			(clearance 0)
		)
		(min_thickness 0.25)
		(keepout
			(tracks not_allowed)
			(vias allowed)
			(pads allowed)
			(copperpour not_allowed)
			(footprints allowed)
		)
		(placement
			(enabled no)
			(sheetname "")
		)
		(fill
			(thermal_gap 0.5)
			(thermal_bridge_width 0.5)
			(island_removal_mode 0)
		)
		(polygon
			(pts
				(xy 42.170096 -4.920742) (xy 42.170096 -6.724142) (xy 42.728896 -6.724142) (xy 42.728896 -4.920742)
			)
		)
	)
	(zone
		(layer "In1.Cu")
		(hatch none 0.5)
		(connect_pads
			(clearance 0)
		)
		(min_thickness 0.25)
		(keepout
			(tracks not_allowed)
			(vias allowed)
			(pads allowed)
			(copperpour not_allowed)
			(footprints allowed)
		)
		(placement
			(enabled no)
			(sheetname "")
		)
		(fill
			(thermal_gap 0.5)
			(thermal_bridge_width 0.5)
			(island_removal_mode 0)
		)
		(polygon
			(pts
				(xy 137.370058 4.680458) (xy 137.370058 2.877058) (xy 137.928858 2.877058) (xy 137.928858 4.680458)
			)
		)
	)
	(zone
		(layer "In1.Cu")
		(hatch none 0.5)
		(connect_pads
			(clearance 0)
		)
		(min_thickness 0.25)
		(keepout
			(tracks not_allowed)
			(vias allowed)
			(pads allowed)
			(copperpour not_allowed)
			(footprints allowed)
		)
		(placement
			(enabled no)
			(sheetname "")
		)
		(fill
			(thermal_gap 0.5)
			(thermal_bridge_width 0.5)
			(island_removal_mode 0)
		)
		(polygon
			(pts
				(xy 298.970446 -146.375882) (xy 298.970446 -148.179282) (xy 299.529246 -148.179282) (xy 299.529246 -146.375882)
			)
		)
	)
	(zone
		(layer "In1.Cu")
		(hatch none 0.5)
		(connect_pads
			(clearance 0)
		)
		(min_thickness 0.25)
		(keepout
			(tracks not_allowed)
			(vias allowed)
			(pads allowed)
			(copperpour not_allowed)
			(footprints allowed)
		)
		(placement
			(enabled no)
			(sheetname "")
		)
		(fill
			(thermal_gap 0.5)
			(thermal_bridge_width 0.5)
			(island_removal_mode 0)
		)
		(polygon
			(pts
				(xy 131.420108 -141.775942) (xy 131.420108 -143.579342) (xy 131.978908 -143.579342) (xy 131.978908 -141.775942)
			)
		)
	)
	(zone
		(layer "In1.Cu")
		(hatch none 0.5)
		(connect_pads
			(clearance 0)
		)
		(min_thickness 0.25)
		(keepout
			(tracks not_allowed)
			(vias allowed)
			(pads allowed)
			(copperpour not_allowed)
			(footprints allowed)
		)
		(placement
			(enabled no)
			(sheetname "")
		)
		(fill
			(thermal_gap 0.5)
			(thermal_bridge_width 0.5)
			(island_removal_mode 0)
		)
		(polygon
			(pts
				(xy 145.02003 -155.977082) (xy 145.02003 -157.780482) (xy 145.57883 -157.780482) (xy 145.57883 -155.977082)
			)
		)
	)
	(zone
		(layer "In1.Cu")
		(hatch none 0.5)
		(connect_pads
			(clearance 0)
		)
		(min_thickness 0.25)
		(keepout
			(tracks not_allowed)
			(vias allowed)
			(pads allowed)
			(copperpour not_allowed)
			(footprints allowed)
		)
		(placement
			(enabled no)
			(sheetname "")
		)
		(fill
			(thermal_gap 0.5)
			(thermal_bridge_width 0.5)
			(island_removal_mode 0)
		)
		(polygon
			(pts
				(xy 265.820398 -132.174742) (xy 265.820398 -133.978142) (xy 266.379198 -133.978142) (xy 266.379198 -132.174742)
			)
		)
	)
	(zone
		(layer "In1.Cu")
		(hatch none 0.5)
		(connect_pads
			(clearance 0)
		)
		(min_thickness 0.25)
		(keepout
			(tracks not_allowed)
			(vias allowed)
			(pads allowed)
			(copperpour not_allowed)
			(footprints allowed)
		)
		(placement
			(enabled no)
			(sheetname "")
		)
		(fill
			(thermal_gap 0.5)
			(thermal_bridge_width 0.5)
			(island_removal_mode 0)
		)
		(polygon
			(pts
				(xy 138.219942 -9.520682) (xy 138.219942 -11.324082) (xy 138.778742 -11.324082) (xy 138.778742 -9.520682)
			)
		)
	)
	(zone
		(layer "In1.Cu")
		(hatch none 0.5)
		(connect_pads
			(clearance 0)
		)
		(min_thickness 0.25)
		(keepout
			(tracks not_allowed)
			(vias allowed)
			(pads allowed)
			(copperpour not_allowed)
			(footprints allowed)
		)
		(placement
			(enabled no)
			(sheetname "")
		)
		(fill
			(thermal_gap 0.5)
			(thermal_bridge_width 0.5)
			(island_removal_mode 0)
		)
		(polygon
			(pts
				(xy 309.170324 -151.377142) (xy 309.170324 -153.180542) (xy 309.729124 -153.180542) (xy 309.729124 -151.377142)
			)
		)
	)
	(zone
		(layer "In1.Cu")
		(hatch none 0.5)
		(connect_pads
			(clearance 0)
		)
		(min_thickness 0.25)
		(keepout
			(tracks not_allowed)
			(vias allowed)
			(pads allowed)
			(copperpour not_allowed)
			(footprints allowed)
		)
		(placement
			(enabled no)
			(sheetname "")
		)
		(fill
			(thermal_gap 0.5)
			(thermal_bridge_width 0.5)
			(island_removal_mode 0)
		)
		(polygon
			(pts
				(xy 198.670418 -146.375882) (xy 198.670418 -148.179282) (xy 199.229218 -148.179282) (xy 199.229218 -146.375882)
			)
		)
	)
	(zone
		(layer "In1.Cu")
		(hatch none 0.5)
		(connect_pads
			(clearance 0)
		)
		(min_thickness 0.25)
		(keepout
			(tracks not_allowed)
			(vias allowed)
			(pads allowed)
			(copperpour not_allowed)
			(footprints allowed)
		)
		(placement
			(enabled no)
			(sheetname "")
		)
		(fill
			(thermal_gap 0.5)
			(thermal_bridge_width 0.5)
			(island_removal_mode 0)
		)
		(polygon
			(pts
				(xy 222.470472 -4.920742) (xy 222.470472 -6.724142) (xy 223.029272 -6.724142) (xy 223.029272 -4.920742)
			)
		)
	)
	(zone
		(layer "In1.Cu")
		(hatch none 0.5)
		(connect_pads
			(clearance 0)
		)
		(min_thickness 0.25)
		(keepout
			(tracks not_allowed)
			(vias allowed)
			(pads allowed)
			(copperpour not_allowed)
			(footprints allowed)
		)
		(placement
			(enabled no)
			(sheetname "")
		)
		(fill
			(thermal_gap 0.5)
			(thermal_bridge_width 0.5)
			(island_removal_mode 0)
		)
		(polygon
			(pts
				(xy 445.895984 -60.99937) (xy 447.204084 -60.99937) (xy 447.204084 -63.00597) (xy 445.895984 -63.00597)
			)
		)
	)
	(zone
		(layer "In1.Cu")
		(hatch none 0.5)
		(connect_pads
			(clearance 0)
		)
		(min_thickness 0.25)
		(keepout
			(tracks not_allowed)
			(vias allowed)
			(pads allowed)
			(copperpour not_allowed)
			(footprints allowed)
		)
		(placement
			(enabled no)
			(sheetname "")
		)
		(fill
			(thermal_gap 0.5)
			(thermal_bridge_width 0.5)
			(island_removal_mode 0)
		)
		(polygon
			(pts
				(xy 61.719968 -9.520682) (xy 61.719968 -11.324082) (xy 62.278768 -11.324082) (xy 62.278768 -9.520682)
			)
		)
	)
	(zone
		(layer "In1.Cu")
		(hatch none 0.5)
		(connect_pads
			(clearance 0)
		)
		(min_thickness 0.25)
		(keepout
			(tracks not_allowed)
			(vias allowed)
			(pads allowed)
			(copperpour not_allowed)
			(footprints allowed)
		)
		(placement
			(enabled no)
			(sheetname "")
		)
		(fill
			(thermal_gap 0.5)
			(thermal_bridge_width 0.5)
			(island_removal_mode 0)
		)
		(polygon
			(pts
				(xy 236.070394 0.080518) (xy 236.070394 -1.722882) (xy 236.629194 -1.722882) (xy 236.629194 0.080518)
			)
		)
	)
	(zone
		(layer "In1.Cu")
		(hatch none 0.5)
		(connect_pads
			(clearance 0)
		)
		(min_thickness 0.25)
		(keepout
			(tracks not_allowed)
			(vias allowed)
			(pads allowed)
			(copperpour not_allowed)
			(footprints allowed)
		)
		(placement
			(enabled no)
			(sheetname "")
		)
		(fill
			(thermal_gap 0.5)
			(thermal_bridge_width 0.5)
			(island_removal_mode 0)
		)
		(polygon
			(pts
				(xy 305.770534 -4.920742) (xy 305.770534 -6.724142) (xy 306.329334 -6.724142) (xy 306.329334 -4.920742)
			)
		)
	)
	(zone
		(layer "In1.Cu")
		(hatch none 0.5)
		(connect_pads
			(clearance 0)
		)
		(min_thickness 0.25)
		(keepout
			(tracks not_allowed)
			(vias allowed)
			(pads allowed)
			(copperpour not_allowed)
			(footprints allowed)
		)
		(placement
			(enabled no)
			(sheetname "")
		)
		(fill
			(thermal_gap 0.5)
			(thermal_bridge_width 0.5)
			(island_removal_mode 0)
		)
		(polygon
			(pts
				(xy 292.170358 -14.521942) (xy 292.170358 -16.325342) (xy 292.729158 -16.325342) (xy 292.729158 -14.521942)
			)
		)
	)
	(zone
		(layer "In1.Cu")
		(hatch none 0.5)
		(connect_pads
			(clearance 0)
		)
		(min_thickness 0.25)
		(keepout
			(tracks not_allowed)
			(vias allowed)
			(pads allowed)
			(copperpour not_allowed)
			(footprints allowed)
		)
		(placement
			(enabled no)
			(sheetname "")
		)
		(fill
			(thermal_gap 0.5)
			(thermal_bridge_width 0.5)
			(island_removal_mode 0)
		)
		(polygon
			(pts
				(xy 33.669986 -136.774682) (xy 33.669986 -138.578082) (xy 34.228786 -138.578082) (xy 34.228786 -136.774682)
			)
		)
	)
	(zone
		(layer "In1.Cu")
		(hatch none 0.5)
		(connect_pads
			(clearance 0)
		)
		(min_thickness 0.25)
		(keepout
			(tracks not_allowed)
			(vias allowed)
			(pads allowed)
			(copperpour not_allowed)
			(footprints allowed)
		)
		(placement
			(enabled no)
			(sheetname "")
		)
		(fill
			(thermal_gap 0.5)
			(thermal_bridge_width 0.5)
			(island_removal_mode 0)
		)
		(polygon
			(pts
				(xy 88.920066 -141.775942) (xy 88.920066 -143.579342) (xy 89.478866 -143.579342) (xy 89.478866 -141.775942)
			)
		)
	)
	(zone
		(layer "In1.Cu")
		(hatch none 0.5)
		(connect_pads
			(clearance 0)
		)
		(min_thickness 0.25)
		(keepout
			(tracks not_allowed)
			(vias allowed)
			(pads allowed)
			(copperpour not_allowed)
			(footprints allowed)
		)
		(placement
			(enabled no)
			(sheetname "")
		)
		(fill
			(thermal_gap 0.5)
			(thermal_bridge_width 0.5)
			(island_removal_mode 0)
		)
		(polygon
			(pts
				(xy 150.96998 -9.520682) (xy 150.96998 -11.324082) (xy 151.52878 -11.324082) (xy 151.52878 -9.520682)
			)
		)
	)
	(zone
		(layer "In1.Cu")
		(hatch none 0.5)
		(connect_pads
			(clearance 0)
		)
		(min_thickness 0.25)
		(keepout
			(tracks not_allowed)
			(vias allowed)
			(pads allowed)
			(copperpour not_allowed)
			(footprints allowed)
		)
		(placement
			(enabled no)
			(sheetname "")
		)
		(fill
			(thermal_gap 0.5)
			(thermal_bridge_width 0.5)
			(island_removal_mode 0)
		)
		(polygon
			(pts
				(xy 289.620452 -155.977082) (xy 289.620452 -157.780482) (xy 290.179252 -157.780482) (xy 290.179252 -155.977082)
			)
		)
	)
	(zone
		(layer "In1.Cu")
		(hatch none 0.5)
		(connect_pads
			(clearance 0)
		)
		(min_thickness 0.25)
		(keepout
			(tracks not_allowed)
			(vias allowed)
			(pads allowed)
			(copperpour not_allowed)
			(footprints allowed)
		)
		(placement
			(enabled no)
			(sheetname "")
		)
		(fill
			(thermal_gap 0.5)
			(thermal_bridge_width 0.5)
			(island_removal_mode 0)
		)
		(polygon
			(pts
				(xy 308.32044 -146.375882) (xy 308.32044 -148.179282) (xy 308.87924 -148.179282) (xy 308.87924 -146.375882)
			)
		)
	)
	(zone
		(layer "In1.Cu")
		(hatch none 0.5)
		(connect_pads
			(clearance 0)
		)
		(min_thickness 0.25)
		(keepout
			(tracks not_allowed)
			(vias allowed)
			(pads allowed)
			(copperpour not_allowed)
			(footprints allowed)
		)
		(placement
			(enabled no)
			(sheetname "")
		)
		(fill
			(thermal_gap 0.5)
			(thermal_bridge_width 0.5)
			(island_removal_mode 0)
		)
		(polygon
			(pts
				(xy 122.070114 4.680458) (xy 122.070114 2.877058) (xy 122.628914 2.877058) (xy 122.628914 4.680458)
			)
		)
	)
	(zone
		(layer "In1.Cu")
		(hatch none 0.5)
		(connect_pads
			(clearance 0)
		)
		(min_thickness 0.25)
		(keepout
			(tracks not_allowed)
			(vias allowed)
			(pads allowed)
			(copperpour not_allowed)
			(footprints allowed)
		)
		(placement
			(enabled no)
			(sheetname "")
		)
		(fill
			(thermal_gap 0.5)
			(thermal_bridge_width 0.5)
			(island_removal_mode 0)
		)
		(polygon
			(pts
				(xy 41.319958 -146.375882) (xy 41.319958 -148.179282) (xy 41.878758 -148.179282) (xy 41.878758 -146.375882)
			)
		)
	)
	(zone
		(layer "In1.Cu")
		(hatch none 0.5)
		(connect_pads
			(clearance 0)
		)
		(min_thickness 0.25)
		(keepout
			(tracks not_allowed)
			(vias allowed)
			(pads allowed)
			(copperpour not_allowed)
			(footprints allowed)
		)
		(placement
			(enabled no)
			(sheetname "")
		)
		(fill
			(thermal_gap 0.5)
			(thermal_bridge_width 0.5)
			(island_removal_mode 0)
		)
		(polygon
			(pts
				(xy 304.070512 -14.521942) (xy 304.070512 -16.325342) (xy 304.629312 -16.325342) (xy 304.629312 -14.521942)
			)
		)
	)
	(zone
		(layer "In1.Cu")
		(hatch none 0.5)
		(connect_pads
			(clearance 0)
		)
		(min_thickness 0.25)
		(keepout
			(tracks not_allowed)
			(vias allowed)
			(pads allowed)
			(copperpour not_allowed)
			(footprints allowed)
		)
		(placement
			(enabled no)
			(sheetname "")
		)
		(fill
			(thermal_gap 0.5)
			(thermal_bridge_width 0.5)
			(island_removal_mode 0)
		)
		(polygon
			(pts
				(xy 237.770416 -146.375882) (xy 237.770416 -148.179282) (xy 238.329216 -148.179282) (xy 238.329216 -146.375882)
			)
		)
	)
	(zone
		(layer "In1.Cu")
		(hatch none 0.5)
		(connect_pads
			(clearance 0)
		)
		(min_thickness 0.25)
		(keepout
			(tracks not_allowed)
			(vias allowed)
			(pads allowed)
			(copperpour not_allowed)
			(footprints allowed)
		)
		(placement
			(enabled no)
			(sheetname "")
		)
		(fill
			(thermal_gap 0.5)
			(thermal_bridge_width 0.5)
			(island_removal_mode 0)
		)
		(polygon
			(pts
				(xy 83.82 -141.775942) (xy 83.82 -143.579342) (xy 84.3788 -143.579342) (xy 84.3788 -141.775942)
			)
		)
	)
	(zone
		(layer "In1.Cu")
		(hatch none 0.5)
		(connect_pads
			(clearance 0)
		)
		(min_thickness 0.25)
		(keepout
			(tracks not_allowed)
			(vias allowed)
			(pads allowed)
			(copperpour not_allowed)
			(footprints allowed)
		)
		(placement
			(enabled no)
			(sheetname "")
		)
		(fill
			(thermal_gap 0.5)
			(thermal_bridge_width 0.5)
			(island_removal_mode 0)
		)
		(polygon
			(pts
				(xy 39.619936 -19.121882) (xy 39.619936 -20.925282) (xy 40.178736 -20.925282) (xy 40.178736 -19.121882)
			)
		)
	)
	(zone
		(layer "In1.Cu")
		(hatch none 0.5)
		(connect_pads
			(clearance 0)
		)
		(min_thickness 0.25)
		(keepout
			(tracks not_allowed)
			(vias allowed)
			(pads allowed)
			(copperpour not_allowed)
			(footprints allowed)
		)
		(placement
			(enabled no)
			(sheetname "")
		)
		(fill
			(thermal_gap 0.5)
			(thermal_bridge_width 0.5)
			(island_removal_mode 0)
		)
		(polygon
			(pts
				(xy 463.546952 -115.799362) (xy 464.854798 -115.799362) (xy 464.854798 -118.186962) (xy 463.546952 -118.186962)
			)
		)
	)
	(zone
		(layer "In1.Cu")
		(hatch none 0.5)
		(connect_pads
			(clearance 0)
		)
		(min_thickness 0.25)
		(keepout
			(tracks not_allowed)
			(vias allowed)
			(pads allowed)
			(copperpour not_allowed)
			(footprints allowed)
		)
		(placement
			(enabled no)
			(sheetname "")
		)
		(fill
			(thermal_gap 0.5)
			(thermal_bridge_width 0.5)
			(island_removal_mode 0)
		)
		(polygon
			(pts
				(xy 271.770602 -14.521942) (xy 271.770602 -16.325342) (xy 272.329402 -16.325342) (xy 272.329402 -14.521942)
			)
		)
	)
	(zone
		(layer "In1.Cu")
		(hatch none 0.5)
		(connect_pads
			(clearance 0)
		)
		(min_thickness 0.25)
		(keepout
			(tracks not_allowed)
			(vias allowed)
			(pads allowed)
			(copperpour not_allowed)
			(footprints allowed)
		)
		(placement
			(enabled no)
			(sheetname "")
		)
		(fill
			(thermal_gap 0.5)
			(thermal_bridge_width 0.5)
			(island_removal_mode 0)
		)
		(polygon
			(pts
				(xy 79.570072 4.680458) (xy 79.570072 2.877058) (xy 80.128872 2.877058) (xy 80.128872 4.680458)
			)
		)
	)
	(zone
		(layer "In1.Cu")
		(hatch none 0.5)
		(connect_pads
			(clearance 0)
		)
		(min_thickness 0.25)
		(keepout
			(tracks not_allowed)
			(vias allowed)
			(pads allowed)
			(copperpour not_allowed)
			(footprints allowed)
		)
		(placement
			(enabled no)
			(sheetname "")
		)
		(fill
			(thermal_gap 0.5)
			(thermal_bridge_width 0.5)
			(island_removal_mode 0)
		)
		(polygon
			(pts
				(xy 247.12041 -19.121882) (xy 247.12041 -20.925282) (xy 247.67921 -20.925282) (xy 247.67921 -19.121882)
			)
		)
	)
	(zone
		(layer "In1.Cu")
		(hatch none 0.5)
		(connect_pads
			(clearance 0)
		)
		(min_thickness 0.25)
		(keepout
			(tracks not_allowed)
			(vias allowed)
			(pads allowed)
			(copperpour not_allowed)
			(footprints allowed)
		)
		(placement
			(enabled no)
			(sheetname "")
		)
		(fill
			(thermal_gap 0.5)
			(thermal_bridge_width 0.5)
			(island_removal_mode 0)
		)
		(polygon
			(pts
				(xy 212.270594 -146.375882) (xy 212.270594 -148.179282) (xy 212.829394 -148.179282) (xy 212.829394 -146.375882)
			)
		)
	)
	(zone
		(layer "In1.Cu")
		(hatch none 0.5)
		(connect_pads
			(clearance 0)
		)
		(min_thickness 0.25)
		(keepout
			(tracks not_allowed)
			(vias allowed)
			(pads allowed)
			(copperpour not_allowed)
			(footprints allowed)
		)
		(placement
			(enabled no)
			(sheetname "")
		)
		(fill
			(thermal_gap 0.5)
			(thermal_bridge_width 0.5)
			(island_removal_mode 0)
		)
		(polygon
			(pts
				(xy 208.87055 -14.521942) (xy 208.87055 -16.325342) (xy 209.42935 -16.325342) (xy 209.42935 -14.521942)
			)
		)
	)
	(zone
		(layer "In1.Cu")
		(hatch none 0.5)
		(connect_pads
			(clearance 0)
		)
		(min_thickness 0.25)
		(keepout
			(tracks not_allowed)
			(vias allowed)
			(pads allowed)
			(copperpour not_allowed)
			(footprints allowed)
		)
		(placement
			(enabled no)
			(sheetname "")
		)
		(fill
			(thermal_gap 0.5)
			(thermal_bridge_width 0.5)
			(island_removal_mode 0)
		)
		(polygon
			(pts
				(xy 242.020852 -9.520682) (xy 242.020852 -11.324082) (xy 242.579652 -11.324082) (xy 242.579652 -9.520682)
			)
		)
	)
	(zone
		(layer "In1.Cu")
		(hatch none 0.5)
		(connect_pads
			(clearance 0)
		)
		(min_thickness 0.25)
		(keepout
			(tracks not_allowed)
			(vias allowed)
			(pads allowed)
			(copperpour not_allowed)
			(footprints allowed)
		)
		(placement
			(enabled no)
			(sheetname "")
		)
		(fill
			(thermal_gap 0.5)
			(thermal_bridge_width 0.5)
			(island_removal_mode 0)
		)
		(polygon
			(pts
				(xy 106.77017 -4.920742) (xy 106.77017 -6.724142) (xy 107.32897 -6.724142) (xy 107.32897 -4.920742)
			)
		)
	)
	(zone
		(layer "In1.Cu")
		(hatch none 0.5)
		(connect_pads
			(clearance 0)
		)
		(min_thickness 0.25)
		(keepout
			(tracks not_allowed)
			(vias allowed)
			(pads allowed)
			(copperpour not_allowed)
			(footprints allowed)
		)
		(placement
			(enabled no)
			(sheetname "")
		)
		(fill
			(thermal_gap 0.5)
			(thermal_bridge_width 0.5)
			(island_removal_mode 0)
		)
		(polygon
			(pts
				(xy 100.819966 -4.920742) (xy 100.819966 -6.724142) (xy 101.378766 -6.724142) (xy 101.378766 -4.920742)
			)
		)
	)
	(zone
		(layer "In1.Cu")
		(hatch none 0.5)
		(connect_pads
			(clearance 0)
		)
		(min_thickness 0.25)
		(keepout
			(tracks not_allowed)
			(vias allowed)
			(pads allowed)
			(copperpour not_allowed)
			(footprints allowed)
		)
		(placement
			(enabled no)
			(sheetname "")
		)
		(fill
			(thermal_gap 0.5)
			(thermal_bridge_width 0.5)
			(island_removal_mode 0)
		)
		(polygon
			(pts
				(xy 284.520386 -136.774682) (xy 284.520386 -138.578082) (xy 285.079186 -138.578082) (xy 285.079186 -136.774682)
			)
		)
	)
	(zone
		(layer "In1.Cu")
		(hatch none 0.5)
		(connect_pads
			(clearance 0)
		)
		(min_thickness 0.25)
		(keepout
			(tracks not_allowed)
			(vias allowed)
			(pads allowed)
			(copperpour not_allowed)
			(footprints allowed)
		)
		(placement
			(enabled no)
			(sheetname "")
		)
		(fill
			(thermal_gap 0.5)
			(thermal_bridge_width 0.5)
			(island_removal_mode 0)
		)
		(polygon
			(pts
				(xy 428.220886 -3.789172) (xy 429.528986 -3.789172) (xy 429.528986 -4.982972) (xy 428.220886 -4.982972)
			)
		)
	)
	(zone
		(layer "In1.Cu")
		(hatch none 0.5)
		(connect_pads
			(clearance 0)
		)
		(min_thickness 0.25)
		(keepout
			(tracks not_allowed)
			(vias allowed)
			(pads allowed)
			(copperpour not_allowed)
			(footprints allowed)
		)
		(placement
			(enabled no)
			(sheetname "")
		)
		(fill
			(thermal_gap 0.5)
			(thermal_bridge_width 0.5)
			(island_removal_mode 0)
		)
		(polygon
			(pts
				(xy 239.470438 -14.521942) (xy 239.470438 -16.325342) (xy 240.029238 -16.325342) (xy 240.029238 -14.521942)
			)
		)
	)
	(zone
		(layer "In1.Cu")
		(hatch none 0.5)
		(connect_pads
			(clearance 0)
		)
		(min_thickness 0.25)
		(keepout
			(tracks not_allowed)
			(vias allowed)
			(pads allowed)
			(copperpour not_allowed)
			(footprints allowed)
		)
		(placement
			(enabled no)
			(sheetname "")
		)
		(fill
			(thermal_gap 0.5)
			(thermal_bridge_width 0.5)
			(island_removal_mode 0)
		)
		(polygon
			(pts
				(xy 140.770102 -132.174742) (xy 140.770102 -133.978142) (xy 141.328902 -133.978142) (xy 141.328902 -132.174742)
			)
		)
	)
	(zone
		(layer "In1.Cu")
		(hatch none 0.5)
		(connect_pads
			(clearance 0)
		)
		(min_thickness 0.25)
		(keepout
			(tracks not_allowed)
			(vias allowed)
			(pads allowed)
			(copperpour not_allowed)
			(footprints allowed)
		)
		(placement
			(enabled no)
			(sheetname "")
		)
		(fill
			(thermal_gap 0.5)
			(thermal_bridge_width 0.5)
			(island_removal_mode 0)
		)
		(polygon
			(pts
				(xy 218.220544 -141.775942) (xy 218.220544 -143.579342) (xy 218.779344 -143.579342) (xy 218.779344 -141.775942)
			)
		)
	)
	(zone
		(layer "In1.Cu")
		(hatch none 0.5)
		(connect_pads
			(clearance 0)
		)
		(min_thickness 0.25)
		(keepout
			(tracks not_allowed)
			(vias allowed)
			(pads allowed)
			(copperpour not_allowed)
			(footprints allowed)
		)
		(placement
			(enabled no)
			(sheetname "")
		)
		(fill
			(thermal_gap 0.5)
			(thermal_bridge_width 0.5)
			(island_removal_mode 0)
		)
		(polygon
			(pts
				(xy 195.270374 -146.375882) (xy 195.270374 -148.179282) (xy 195.829174 -148.179282) (xy 195.829174 -146.375882)
			)
		)
	)
	(zone
		(layer "In1.Cu")
		(hatch none 0.5)
		(connect_pads
			(clearance 0)
		)
		(min_thickness 0.25)
		(keepout
			(tracks not_allowed)
			(vias allowed)
			(pads allowed)
			(copperpour not_allowed)
			(footprints allowed)
		)
		(placement
			(enabled no)
			(sheetname "")
		)
		(fill
			(thermal_gap 0.5)
			(thermal_bridge_width 0.5)
			(island_removal_mode 0)
		)
		(polygon
			(pts
				(xy 284.520386 -9.520682) (xy 284.520386 -11.324082) (xy 285.079186 -11.324082) (xy 285.079186 -9.520682)
			)
		)
	)
	(zone
		(layer "In1.Cu")
		(hatch none 0.5)
		(connect_pads
			(clearance 0)
		)
		(min_thickness 0.25)
		(keepout
			(tracks not_allowed)
			(vias allowed)
			(pads allowed)
			(copperpour not_allowed)
			(footprints allowed)
		)
		(placement
			(enabled no)
			(sheetname "")
		)
		(fill
			(thermal_gap 0.5)
			(thermal_bridge_width 0.5)
			(island_removal_mode 0)
		)
		(polygon
			(pts
				(xy 31.12008 4.680458) (xy 31.12008 2.877058) (xy 31.67888 2.877058) (xy 31.67888 4.680458)
			)
		)
	)
	(zone
		(layer "In1.Cu")
		(hatch none 0.5)
		(connect_pads
			(clearance 0)
		)
		(min_thickness 0.25)
		(keepout
			(tracks not_allowed)
			(vias allowed)
			(pads allowed)
			(copperpour not_allowed)
			(footprints allowed)
		)
		(placement
			(enabled no)
			(sheetname "")
		)
		(fill
			(thermal_gap 0.5)
			(thermal_bridge_width 0.5)
			(island_removal_mode 0)
		)
		(polygon
			(pts
				(xy 266.670536 -19.121882) (xy 267.229336 -19.121882) (xy 267.229336 -20.925282) (xy 266.670536 -20.925282)
			)
		)
	)
	(zone
		(layer "In1.Cu")
		(hatch none 0.5)
		(connect_pads
			(clearance 0)
		)
		(min_thickness 0.25)
		(keepout
			(tracks not_allowed)
			(vias allowed)
			(pads allowed)
			(copperpour not_allowed)
			(footprints allowed)
		)
		(placement
			(enabled no)
			(sheetname "")
		)
		(fill
			(thermal_gap 0.5)
			(thermal_bridge_width 0.5)
			(island_removal_mode 0)
		)
		(polygon
			(pts
				(xy 242.020852 0.080518) (xy 242.020852 -1.722882) (xy 242.579652 -1.722882) (xy 242.579652 0.080518)
			)
		)
	)
	(zone
		(layer "In1.Cu")
		(hatch none 0.5)
		(connect_pads
			(clearance 0)
		)
		(min_thickness 0.25)
		(keepout
			(tracks not_allowed)
			(vias allowed)
			(pads allowed)
			(copperpour not_allowed)
			(footprints allowed)
		)
		(placement
			(enabled no)
			(sheetname "")
		)
		(fill
			(thermal_gap 0.5)
			(thermal_bridge_width 0.5)
			(island_removal_mode 0)
		)
		(polygon
			(pts
				(xy 109.320076 -4.920742) (xy 109.320076 -6.724142) (xy 109.878876 -6.724142) (xy 109.878876 -4.920742)
			)
		)
	)
	(zone
		(layer "In1.Cu")
		(hatch none 0.5)
		(connect_pads
			(clearance 0)
		)
		(min_thickness 0.25)
		(keepout
			(tracks not_allowed)
			(vias allowed)
			(pads allowed)
			(copperpour not_allowed)
			(footprints allowed)
		)
		(placement
			(enabled no)
			(sheetname "")
		)
		(fill
			(thermal_gap 0.5)
			(thermal_bridge_width 0.5)
			(island_removal_mode 0)
		)
		(polygon
			(pts
				(xy 218.220544 -14.521942) (xy 218.220544 -16.325342) (xy 218.779344 -16.325342) (xy 218.779344 -14.521942)
			)
		)
	)
	(zone
		(layer "In1.Cu")
		(hatch none 0.5)
		(connect_pads
			(clearance 0)
		)
		(min_thickness 0.25)
		(keepout
			(tracks not_allowed)
			(vias allowed)
			(pads allowed)
			(copperpour not_allowed)
			(footprints allowed)
		)
		(placement
			(enabled no)
			(sheetname "")
		)
		(fill
			(thermal_gap 0.5)
			(thermal_bridge_width 0.5)
			(island_removal_mode 0)
		)
		(polygon
			(pts
				(xy 125.469904 4.680458) (xy 125.469904 2.877058) (xy 126.028704 2.877058) (xy 126.028704 4.680458)
			)
		)
	)
	(zone
		(layer "In1.Cu")
		(hatch none 0.5)
		(connect_pads
			(clearance 0)
		)
		(min_thickness 0.25)
		(keepout
			(tracks not_allowed)
			(vias allowed)
			(pads allowed)
			(copperpour not_allowed)
			(footprints allowed)
		)
		(placement
			(enabled no)
			(sheetname "")
		)
		(fill
			(thermal_gap 0.5)
			(thermal_bridge_width 0.5)
			(island_removal_mode 0)
		)
		(polygon
			(pts
				(xy 78.719934 -155.977082) (xy 78.719934 -157.780482) (xy 79.278734 -157.780482) (xy 79.278734 -155.977082)
			)
		)
	)
	(zone
		(layer "In1.Cu")
		(hatch none 0.5)
		(connect_pads
			(clearance 0)
		)
		(min_thickness 0.25)
		(keepout
			(tracks not_allowed)
			(vias allowed)
			(pads allowed)
			(copperpour not_allowed)
			(footprints allowed)
		)
		(placement
			(enabled no)
			(sheetname "")
		)
		(fill
			(thermal_gap 0.5)
			(thermal_bridge_width 0.5)
			(island_removal_mode 0)
		)
		(polygon
			(pts
				(xy 66.820034 -151.377142) (xy 66.820034 -153.180542) (xy 67.378834 -153.180542) (xy 67.378834 -151.377142)
			)
		)
	)
	(zone
		(layer "In1.Cu")
		(hatch none 0.5)
		(connect_pads
			(clearance 0)
		)
		(min_thickness 0.25)
		(keepout
			(tracks not_allowed)
			(vias allowed)
			(pads allowed)
			(copperpour not_allowed)
			(footprints allowed)
		)
		(placement
			(enabled no)
			(sheetname "")
		)
		(fill
			(thermal_gap 0.5)
			(thermal_bridge_width 0.5)
			(island_removal_mode 0)
		)
		(polygon
			(pts
				(xy 102.519988 -19.121882) (xy 102.519988 -20.925282) (xy 103.078788 -20.925282) (xy 103.078788 -19.121882)
			)
		)
	)
	(zone
		(layer "In1.Cu")
		(hatch none 0.5)
		(connect_pads
			(clearance 0)
		)
		(min_thickness 0.25)
		(keepout
			(tracks not_allowed)
			(vias allowed)
			(pads allowed)
			(copperpour not_allowed)
			(footprints allowed)
		)
		(placement
			(enabled no)
			(sheetname "")
		)
		(fill
			(thermal_gap 0.5)
			(thermal_bridge_width 0.5)
			(island_removal_mode 0)
		)
		(polygon
			(pts
				(xy 40.470074 -4.920742) (xy 40.470074 -6.724142) (xy 41.028874 -6.724142) (xy 41.028874 -4.920742)
			)
		)
	)
	(zone
		(layer "In1.Cu")
		(hatch none 0.5)
		(connect_pads
			(clearance 0)
		)
		(min_thickness 0.25)
		(keepout
			(tracks not_allowed)
			(vias allowed)
			(pads allowed)
			(copperpour not_allowed)
			(footprints allowed)
		)
		(placement
			(enabled no)
			(sheetname "")
		)
		(fill
			(thermal_gap 0.5)
			(thermal_bridge_width 0.5)
			(island_removal_mode 0)
		)
		(polygon
			(pts
				(xy 276.02053 -14.521942) (xy 276.02053 -16.325342) (xy 276.57933 -16.325342) (xy 276.57933 -14.521942)
			)
		)
	)
	(zone
		(layer "In1.Cu")
		(hatch none 0.5)
		(connect_pads
			(clearance 0)
		)
		(min_thickness 0.25)
		(keepout
			(tracks not_allowed)
			(vias allowed)
			(pads allowed)
			(copperpour not_allowed)
			(footprints allowed)
		)
		(placement
			(enabled no)
			(sheetname "")
		)
		(fill
			(thermal_gap 0.5)
			(thermal_bridge_width 0.5)
			(island_removal_mode 0)
		)
		(polygon
			(pts
				(xy 222.470472 -14.521942) (xy 222.470472 -16.325342) (xy 223.029272 -16.325342) (xy 223.029272 -14.521942)
			)
		)
	)
	(zone
		(layer "In1.Cu")
		(hatch none 0.5)
		(connect_pads
			(clearance 0)
		)
		(min_thickness 0.25)
		(keepout
			(tracks not_allowed)
			(vias allowed)
			(pads allowed)
			(copperpour not_allowed)
			(footprints allowed)
		)
		(placement
			(enabled no)
			(sheetname "")
		)
		(fill
			(thermal_gap 0.5)
			(thermal_bridge_width 0.5)
			(island_removal_mode 0)
		)
		(polygon
			(pts
				(xy 247.970548 -9.520682) (xy 247.970548 -11.324082) (xy 248.529348 -11.324082) (xy 248.529348 -9.520682)
			)
		)
	)
	(zone
		(layer "In1.Cu")
		(hatch none 0.5)
		(connect_pads
			(clearance 0)
		)
		(min_thickness 0.25)
		(keepout
			(tracks not_allowed)
			(vias allowed)
			(pads allowed)
			(copperpour not_allowed)
			(footprints allowed)
		)
		(placement
			(enabled no)
			(sheetname "")
		)
		(fill
			(thermal_gap 0.5)
			(thermal_bridge_width 0.5)
			(island_removal_mode 0)
		)
		(polygon
			(pts
				(xy 197.820534 -14.521942) (xy 197.820534 -16.325342) (xy 198.379334 -16.325342) (xy 198.379334 -14.521942)
			)
		)
	)
	(zone
		(layer "In1.Cu")
		(hatch none 0.5)
		(connect_pads
			(clearance 0)
		)
		(min_thickness 0.25)
		(keepout
			(tracks not_allowed)
			(vias allowed)
			(pads allowed)
			(copperpour not_allowed)
			(footprints allowed)
		)
		(placement
			(enabled no)
			(sheetname "")
		)
		(fill
			(thermal_gap 0.5)
			(thermal_bridge_width 0.5)
			(island_removal_mode 0)
		)
		(polygon
			(pts
				(xy 54.069996 -146.375882) (xy 54.069996 -148.179282) (xy 54.628796 -148.179282) (xy 54.628796 -146.375882)
			)
		)
	)
	(zone
		(layer "In1.Cu")
		(hatch none 0.5)
		(connect_pads
			(clearance 0)
		)
		(min_thickness 0.25)
		(keepout
			(tracks not_allowed)
			(vias allowed)
			(pads allowed)
			(copperpour not_allowed)
			(footprints allowed)
		)
		(placement
			(enabled no)
			(sheetname "")
		)
		(fill
			(thermal_gap 0.5)
			(thermal_bridge_width 0.5)
			(island_removal_mode 0)
		)
		(polygon
			(pts
				(xy 203.770484 -132.174742) (xy 203.770484 -133.978142) (xy 204.329284 -133.978142) (xy 204.329284 -132.174742)
			)
		)
	)
	(zone
		(layer "In1.Cu")
		(hatch none 0.5)
		(connect_pads
			(clearance 0)
		)
		(min_thickness 0.25)
		(keepout
			(tracks not_allowed)
			(vias allowed)
			(pads allowed)
			(copperpour not_allowed)
			(footprints allowed)
		)
		(placement
			(enabled no)
			(sheetname "")
		)
		(fill
			(thermal_gap 0.5)
			(thermal_bridge_width 0.5)
			(island_removal_mode 0)
		)
		(polygon
			(pts
				(xy 393.889992 -9.774936) (xy 394.397992 -9.774936) (xy 394.397992 -11.171936) (xy 393.889992 -11.171936)
			)
		)
	)
	(zone
		(layer "In1.Cu")
		(hatch none 0.5)
		(connect_pads
			(clearance 0)
		)
		(min_thickness 0.25)
		(keepout
			(tracks not_allowed)
			(vias allowed)
			(pads allowed)
			(copperpour not_allowed)
			(footprints allowed)
		)
		(placement
			(enabled no)
			(sheetname "")
		)
		(fill
			(thermal_gap 0.5)
			(thermal_bridge_width 0.5)
			(island_removal_mode 0)
		)
		(polygon
			(pts
				(xy 247.12041 -9.520682) (xy 247.12041 -11.324082) (xy 247.67921 -11.324082) (xy 247.67921 -9.520682)
			)
		)
	)
	(zone
		(layer "In1.Cu")
		(hatch none 0.5)
		(connect_pads
			(clearance 0)
		)
		(min_thickness 0.25)
		(keepout
			(tracks not_allowed)
			(vias allowed)
			(pads allowed)
			(copperpour not_allowed)
			(footprints allowed)
		)
		(placement
			(enabled no)
			(sheetname "")
		)
		(fill
			(thermal_gap 0.5)
			(thermal_bridge_width 0.5)
			(island_removal_mode 0)
		)
		(polygon
			(pts
				(xy 223.320356 -19.121882) (xy 223.320356 -20.925282) (xy 223.879156 -20.925282) (xy 223.879156 -19.121882)
			)
		)
	)
	(zone
		(layer "In1.Cu")
		(hatch none 0.5)
		(connect_pads
			(clearance 0)
		)
		(min_thickness 0.25)
		(keepout
			(tracks not_allowed)
			(vias allowed)
			(pads allowed)
			(copperpour not_allowed)
			(footprints allowed)
		)
		(placement
			(enabled no)
			(sheetname "")
		)
		(fill
			(thermal_gap 0.5)
			(thermal_bridge_width 0.5)
			(island_removal_mode 0)
		)
		(polygon
			(pts
				(xy 302.37049 -141.775942) (xy 302.37049 -143.579342) (xy 302.92929 -143.579342) (xy 302.92929 -141.775942)
			)
		)
	)
	(zone
		(layer "In1.Cu")
		(hatch none 0.5)
		(connect_pads
			(clearance 0)
		)
		(min_thickness 0.25)
		(keepout
			(tracks not_allowed)
			(vias allowed)
			(pads allowed)
			(copperpour not_allowed)
			(footprints allowed)
		)
		(placement
			(enabled no)
			(sheetname "")
		)
		(fill
			(thermal_gap 0.5)
			(thermal_bridge_width 0.5)
			(island_removal_mode 0)
		)
		(polygon
			(pts
				(xy 105.070148 -155.977082) (xy 105.070148 -157.780482) (xy 105.628948 -157.780482) (xy 105.628948 -155.977082)
			)
		)
	)
	(zone
		(layer "In1.Cu")
		(hatch none 0.5)
		(connect_pads
			(clearance 0)
		)
		(min_thickness 0.25)
		(keepout
			(tracks not_allowed)
			(vias allowed)
			(pads allowed)
			(copperpour not_allowed)
			(footprints allowed)
		)
		(placement
			(enabled no)
			(sheetname "")
		)
		(fill
			(thermal_gap 0.5)
			(thermal_bridge_width 0.5)
			(island_removal_mode 0)
		)
		(polygon
			(pts
				(xy 213.120478 -151.377142) (xy 213.120478 -153.180542) (xy 213.679278 -153.180542) (xy 213.679278 -151.377142)
			)
		)
	)
	(zone
		(layer "In1.Cu")
		(hatch none 0.5)
		(connect_pads
			(clearance 0)
		)
		(min_thickness 0.25)
		(keepout
			(tracks not_allowed)
			(vias allowed)
			(pads allowed)
			(copperpour not_allowed)
			(footprints allowed)
		)
		(placement
			(enabled no)
			(sheetname "")
		)
		(fill
			(thermal_gap 0.5)
			(thermal_bridge_width 0.5)
			(island_removal_mode 0)
		)
		(polygon
			(pts
				(xy 147.569936 -19.121882) (xy 147.569936 -20.925282) (xy 148.128736 -20.925282) (xy 148.128736 -19.121882)
			)
		)
	)
	(zone
		(layer "In1.Cu")
		(hatch none 0.5)
		(connect_pads
			(clearance 0)
		)
		(min_thickness 0.25)
		(keepout
			(tracks not_allowed)
			(vias allowed)
			(pads allowed)
			(copperpour not_allowed)
			(footprints allowed)
		)
		(placement
			(enabled no)
			(sheetname "")
		)
		(fill
			(thermal_gap 0.5)
			(thermal_bridge_width 0.5)
			(island_removal_mode 0)
		)
		(polygon
			(pts
				(xy 132.269992 0.080518) (xy 132.269992 -1.722882) (xy 132.828792 -1.722882) (xy 132.828792 0.080518)
			)
		)
	)
	(zone
		(layer "In1.Cu")
		(hatch none 0.5)
		(connect_pads
			(clearance 0)
		)
		(min_thickness 0.25)
		(keepout
			(tracks not_allowed)
			(vias allowed)
			(pads allowed)
			(copperpour not_allowed)
			(footprints allowed)
		)
		(placement
			(enabled no)
			(sheetname "")
		)
		(fill
			(thermal_gap 0.5)
			(thermal_bridge_width 0.5)
			(island_removal_mode 0)
		)
		(polygon
			(pts
				(xy 84.670138 -4.920742) (xy 84.670138 -6.724142) (xy 85.228938 -6.724142) (xy 85.228938 -4.920742)
			)
		)
	)
	(zone
		(layer "In1.Cu")
		(hatch none 0.5)
		(connect_pads
			(clearance 0)
		)
		(min_thickness 0.25)
		(keepout
			(tracks not_allowed)
			(vias allowed)
			(pads allowed)
			(copperpour not_allowed)
			(footprints allowed)
		)
		(placement
			(enabled no)
			(sheetname "")
		)
		(fill
			(thermal_gap 0.5)
			(thermal_bridge_width 0.5)
			(island_removal_mode 0)
		)
		(polygon
			(pts
				(xy 204.620368 0.080518) (xy 204.620368 -1.722882) (xy 205.179168 -1.722882) (xy 205.179168 0.080518)
			)
		)
	)
	(zone
		(layer "In1.Cu")
		(hatch none 0.5)
		(connect_pads
			(clearance 0)
		)
		(min_thickness 0.25)
		(keepout
			(tracks not_allowed)
			(vias allowed)
			(pads allowed)
			(copperpour not_allowed)
			(footprints allowed)
		)
		(placement
			(enabled no)
			(sheetname "")
		)
		(fill
			(thermal_gap 0.5)
			(thermal_bridge_width 0.5)
			(island_removal_mode 0)
		)
		(polygon
			(pts
				(xy 217.370406 0.080518) (xy 217.370406 -1.722882) (xy 217.929206 -1.722882) (xy 217.929206 0.080518)
			)
		)
	)
	(zone
		(layer "In1.Cu")
		(hatch none 0.5)
		(connect_pads
			(clearance 0)
		)
		(min_thickness 0.25)
		(keepout
			(tracks not_allowed)
			(vias allowed)
			(pads allowed)
			(copperpour not_allowed)
			(footprints allowed)
		)
		(placement
			(enabled no)
			(sheetname "")
		)
		(fill
			(thermal_gap 0.5)
			(thermal_bridge_width 0.5)
			(island_removal_mode 0)
		)
		(polygon
			(pts
				(xy 92.32011 -9.520682) (xy 92.32011 -11.324082) (xy 92.87891 -11.324082) (xy 92.87891 -9.520682)
			)
		)
	)
	(zone
		(layer "In1.Cu")
		(hatch none 0.5)
		(connect_pads
			(clearance 0)
		)
		(min_thickness 0.25)
		(keepout
			(tracks not_allowed)
			(vias allowed)
			(pads allowed)
			(copperpour not_allowed)
			(footprints allowed)
		)
		(placement
			(enabled no)
			(sheetname "")
		)
		(fill
			(thermal_gap 0.5)
			(thermal_bridge_width 0.5)
			(island_removal_mode 0)
		)
		(polygon
			(pts
				(xy 250.520454 -155.977082) (xy 250.520454 -157.780482) (xy 251.079254 -157.780482) (xy 251.079254 -155.977082)
			)
		)
	)
	(zone
		(layer "In1.Cu")
		(hatch none 0.5)
		(connect_pads
			(clearance 0)
		)
		(min_thickness 0.25)
		(keepout
			(tracks not_allowed)
			(vias allowed)
			(pads allowed)
			(copperpour not_allowed)
			(footprints allowed)
		)
		(placement
			(enabled no)
			(sheetname "")
		)
		(fill
			(thermal_gap 0.5)
			(thermal_bridge_width 0.5)
			(island_removal_mode 0)
		)
		(polygon
			(pts
				(xy 311.720484 -132.174742) (xy 311.720484 -133.978142) (xy 312.279284 -133.978142) (xy 312.279284 -132.174742)
			)
		)
	)
	(zone
		(layer "In1.Cu")
		(hatch none 0.5)
		(connect_pads
			(clearance 0)
		)
		(min_thickness 0.25)
		(keepout
			(tracks not_allowed)
			(vias allowed)
			(pads allowed)
			(copperpour not_allowed)
			(footprints allowed)
		)
		(placement
			(enabled no)
			(sheetname "")
		)
		(fill
			(thermal_gap 0.5)
			(thermal_bridge_width 0.5)
			(island_removal_mode 0)
		)
		(polygon
			(pts
				(xy 288.770314 -141.775942) (xy 288.770314 -143.579342) (xy 289.329114 -143.579342) (xy 289.329114 -141.775942)
			)
		)
	)
	(zone
		(layer "In1.Cu")
		(hatch none 0.5)
		(connect_pads
			(clearance 0)
		)
		(min_thickness 0.25)
		(keepout
			(tracks not_allowed)
			(vias allowed)
			(pads allowed)
			(copperpour not_allowed)
			(footprints allowed)
		)
		(placement
			(enabled no)
			(sheetname "")
		)
		(fill
			(thermal_gap 0.5)
			(thermal_bridge_width 0.5)
			(island_removal_mode 0)
		)
		(polygon
			(pts
				(xy 320.02222 -119.00916) (xy 322.30822 -119.00916) (xy 322.30822 -119.51716) (xy 320.02222 -119.51716)
			)
		)
	)
	(zone
		(layer "In1.Cu")
		(hatch none 0.5)
		(connect_pads
			(clearance 0)
		)
		(min_thickness 0.25)
		(keepout
			(tracks not_allowed)
			(vias allowed)
			(pads allowed)
			(copperpour not_allowed)
			(footprints allowed)
		)
		(placement
			(enabled no)
			(sheetname "")
		)
		(fill
			(thermal_gap 0.5)
			(thermal_bridge_width 0.5)
			(island_removal_mode 0)
		)
		(polygon
			(pts
				(xy 283.670502 -19.121882) (xy 283.670502 -20.925282) (xy 284.229302 -20.925282) (xy 284.229302 -19.121882)
			)
		)
	)
	(zone
		(layer "In1.Cu")
		(hatch none 0.5)
		(connect_pads
			(clearance 0)
		)
		(min_thickness 0.25)
		(keepout
			(tracks not_allowed)
			(vias allowed)
			(pads allowed)
			(copperpour not_allowed)
			(footprints allowed)
		)
		(placement
			(enabled no)
			(sheetname "")
		)
		(fill
			(thermal_gap 0.5)
			(thermal_bridge_width 0.5)
			(island_removal_mode 0)
		)
		(polygon
			(pts
				(xy 315.970412 -9.520682) (xy 315.970412 -11.324082) (xy 316.529212 -11.324082) (xy 316.529212 -9.520682)
			)
		)
	)
	(zone
		(layer "In1.Cu")
		(hatch none 0.5)
		(connect_pads
			(clearance 0)
		)
		(min_thickness 0.25)
		(keepout
			(tracks not_allowed)
			(vias allowed)
			(pads allowed)
			(copperpour not_allowed)
			(footprints allowed)
		)
		(placement
			(enabled no)
			(sheetname "")
		)
		(fill
			(thermal_gap 0.5)
			(thermal_bridge_width 0.5)
			(island_removal_mode 0)
		)
		(polygon
			(pts
				(xy 314.27039 -155.977082) (xy 314.27039 -157.780482) (xy 314.82919 -157.780482) (xy 314.82919 -155.977082)
			)
		)
	)
	(zone
		(layer "In1.Cu")
		(hatch none 0.5)
		(connect_pads
			(clearance 0)
		)
		(min_thickness 0.25)
		(keepout
			(tracks not_allowed)
			(vias allowed)
			(pads allowed)
			(copperpour not_allowed)
			(footprints allowed)
		)
		(placement
			(enabled no)
			(sheetname "")
		)
		(fill
			(thermal_gap 0.5)
			(thermal_bridge_width 0.5)
			(island_removal_mode 0)
		)
		(polygon
			(pts
				(xy 73.620122 -19.121882) (xy 73.620122 -20.925282) (xy 74.178922 -20.925282) (xy 74.178922 -19.121882)
			)
		)
	)
	(zone
		(layer "In1.Cu")
		(hatch none 0.5)
		(connect_pads
			(clearance 0)
		)
		(min_thickness 0.25)
		(keepout
			(tracks not_allowed)
			(vias allowed)
			(pads allowed)
			(copperpour not_allowed)
			(footprints allowed)
		)
		(placement
			(enabled no)
			(sheetname "")
		)
		(fill
			(thermal_gap 0.5)
			(thermal_bridge_width 0.5)
			(island_removal_mode 0)
		)
		(polygon
			(pts
				(xy 36.220146 -146.375882) (xy 36.220146 -148.179282) (xy 36.778946 -148.179282) (xy 36.778946 -146.375882)
			)
		)
	)
	(zone
		(layer "In1.Cu")
		(hatch none 0.5)
		(connect_pads
			(clearance 0)
		)
		(min_thickness 0.25)
		(keepout
			(tracks not_allowed)
			(vias allowed)
			(pads allowed)
			(copperpour not_allowed)
			(footprints allowed)
		)
		(placement
			(enabled no)
			(sheetname "")
		)
		(fill
			(thermal_gap 0.5)
			(thermal_bridge_width 0.5)
			(island_removal_mode 0)
		)
		(polygon
			(pts
				(xy 285.370524 -151.377142) (xy 285.370524 -153.180542) (xy 285.929324 -153.180542) (xy 285.929324 -151.377142)
			)
		)
	)
	(zone
		(layer "In1.Cu")
		(hatch none 0.5)
		(connect_pads
			(clearance 0)
		)
		(min_thickness 0.25)
		(keepout
			(tracks not_allowed)
			(vias allowed)
			(pads allowed)
			(copperpour not_allowed)
			(footprints allowed)
		)
		(placement
			(enabled no)
			(sheetname "")
		)
		(fill
			(thermal_gap 0.5)
			(thermal_bridge_width 0.5)
			(island_removal_mode 0)
		)
		(polygon
			(pts
				(xy 31.12008 -132.174742) (xy 31.12008 -133.978142) (xy 31.67888 -133.978142) (xy 31.67888 -132.174742)
			)
		)
	)
	(zone
		(layer "In1.Cu")
		(hatch none 0.5)
		(connect_pads
			(clearance 0)
		)
		(min_thickness 0.25)
		(keepout
			(tracks not_allowed)
			(vias allowed)
			(pads allowed)
			(copperpour not_allowed)
			(footprints allowed)
		)
		(placement
			(enabled no)
			(sheetname "")
		)
		(fill
			(thermal_gap 0.5)
			(thermal_bridge_width 0.5)
			(island_removal_mode 0)
		)
		(polygon
			(pts
				(xy 267.52042 -19.121882) (xy 267.52042 -20.925282) (xy 268.07922 -20.925282) (xy 268.07922 -19.121882)
			)
		)
	)
	(zone
		(layer "In1.Cu")
		(hatch none 0.5)
		(connect_pads
			(clearance 0)
		)
		(min_thickness 0.25)
		(keepout
			(tracks not_allowed)
			(vias allowed)
			(pads allowed)
			(copperpour not_allowed)
			(footprints allowed)
		)
		(placement
			(enabled no)
			(sheetname "")
		)
		(fill
			(thermal_gap 0.5)
			(thermal_bridge_width 0.5)
			(island_removal_mode 0)
		)
		(polygon
			(pts
				(xy 140.770102 -4.920742) (xy 140.770102 -6.724142) (xy 141.328902 -6.724142) (xy 141.328902 -4.920742)
			)
		)
	)
	(zone
		(layer "In1.Cu")
		(hatch none 0.5)
		(connect_pads
			(clearance 0)
		)
		(min_thickness 0.25)
		(keepout
			(tracks not_allowed)
			(vias allowed)
			(pads allowed)
			(copperpour not_allowed)
			(footprints allowed)
		)
		(placement
			(enabled no)
			(sheetname "")
		)
		(fill
			(thermal_gap 0.5)
			(thermal_bridge_width 0.5)
			(island_removal_mode 0)
		)
		(polygon
			(pts
				(xy 201.220578 -136.774682) (xy 201.220578 -138.578082) (xy 201.779378 -138.578082) (xy 201.779378 -136.774682)
			)
		)
	)
	(zone
		(layer "In1.Cu")
		(hatch none 0.5)
		(connect_pads
			(clearance 0)
		)
		(min_thickness 0.25)
		(keepout
			(tracks not_allowed)
			(vias allowed)
			(pads allowed)
			(copperpour not_allowed)
			(footprints allowed)
		)
		(placement
			(enabled no)
			(sheetname "")
		)
		(fill
			(thermal_gap 0.5)
			(thermal_bridge_width 0.5)
			(island_removal_mode 0)
		)
		(polygon
			(pts
				(xy 252.220476 -155.977082) (xy 252.220476 -157.780482) (xy 252.779276 -157.780482) (xy 252.779276 -155.977082)
			)
		)
	)
	(zone
		(layer "In1.Cu")
		(hatch none 0.5)
		(connect_pads
			(clearance 0)
		)
		(min_thickness 0.25)
		(keepout
			(tracks not_allowed)
			(vias allowed)
			(pads allowed)
			(copperpour not_allowed)
			(footprints allowed)
		)
		(placement
			(enabled no)
			(sheetname "")
		)
		(fill
			(thermal_gap 0.5)
			(thermal_bridge_width 0.5)
			(island_removal_mode 0)
		)
		(polygon
			(pts
				(xy 128.020064 -9.520682) (xy 128.020064 -11.324082) (xy 128.578864 -11.324082) (xy 128.578864 -9.520682)
			)
		)
	)
	(zone
		(layer "In1.Cu")
		(hatch none 0.5)
		(connect_pads
			(clearance 0)
		)
		(min_thickness 0.25)
		(keepout
			(tracks not_allowed)
			(vias allowed)
			(pads allowed)
			(copperpour not_allowed)
			(footprints allowed)
		)
		(placement
			(enabled no)
			(sheetname "")
		)
		(fill
			(thermal_gap 0.5)
			(thermal_bridge_width 0.5)
			(island_removal_mode 0)
		)
		(polygon
			(pts
				(xy 219.070428 -9.520682) (xy 219.070428 -11.324082) (xy 219.629228 -11.324082) (xy 219.629228 -9.520682)
			)
		)
	)
	(zone
		(layer "In1.Cu")
		(hatch none 0.5)
		(connect_pads
			(clearance 0)
		)
		(min_thickness 0.25)
		(keepout
			(tracks not_allowed)
			(vias allowed)
			(pads allowed)
			(copperpour not_allowed)
			(footprints allowed)
		)
		(placement
			(enabled no)
			(sheetname "")
		)
		(fill
			(thermal_gap 0.5)
			(thermal_bridge_width 0.5)
			(island_removal_mode 0)
		)
		(polygon
			(pts
				(xy 280.270458 -155.977082) (xy 280.270458 -157.780482) (xy 280.829258 -157.780482) (xy 280.829258 -155.977082)
			)
		)
	)
	(zone
		(layer "In1.Cu")
		(hatch none 0.5)
		(connect_pads
			(clearance 0)
		)
		(min_thickness 0.25)
		(keepout
			(tracks not_allowed)
			(vias allowed)
			(pads allowed)
			(copperpour not_allowed)
			(footprints allowed)
		)
		(placement
			(enabled no)
			(sheetname "")
		)
		(fill
			(thermal_gap 0.5)
			(thermal_bridge_width 0.5)
			(island_removal_mode 0)
		)
		(polygon
			(pts
				(xy 256.470404 -132.174742) (xy 256.470404 -133.978142) (xy 257.029204 -133.978142) (xy 257.029204 -132.174742)
			)
		)
	)
	(zone
		(layer "In1.Cu")
		(hatch none 0.5)
		(connect_pads
			(clearance 0)
		)
		(min_thickness 0.25)
		(keepout
			(tracks not_allowed)
			(vias allowed)
			(pads allowed)
			(copperpour not_allowed)
			(footprints allowed)
		)
		(placement
			(enabled no)
			(sheetname "")
		)
		(fill
			(thermal_gap 0.5)
			(thermal_bridge_width 0.5)
			(island_removal_mode 0)
		)
		(polygon
			(pts
				(xy 217.370406 -19.121882) (xy 217.370406 -20.925282) (xy 217.929206 -20.925282) (xy 217.929206 -19.121882)
			)
		)
	)
	(zone
		(layer "In1.Cu")
		(hatch none 0.5)
		(connect_pads
			(clearance 0)
		)
		(min_thickness 0.25)
		(keepout
			(tracks not_allowed)
			(vias allowed)
			(pads allowed)
			(copperpour not_allowed)
			(footprints allowed)
		)
		(placement
			(enabled no)
			(sheetname "")
		)
		(fill
			(thermal_gap 0.5)
			(thermal_bridge_width 0.5)
			(island_removal_mode 0)
		)
		(polygon
			(pts
				(xy 107.620054 -14.521942) (xy 107.620054 -16.325342) (xy 108.178854 -16.325342) (xy 108.178854 -14.521942)
			)
		)
	)
	(zone
		(layer "In1.Cu")
		(hatch none 0.5)
		(connect_pads
			(clearance 0)
		)
		(min_thickness 0.25)
		(keepout
			(tracks not_allowed)
			(vias allowed)
			(pads allowed)
			(copperpour not_allowed)
			(footprints allowed)
		)
		(placement
			(enabled no)
			(sheetname "")
		)
		(fill
			(thermal_gap 0.5)
			(thermal_bridge_width 0.5)
			(island_removal_mode 0)
		)
		(polygon
			(pts
				(xy 304.920396 -155.977082) (xy 304.920396 -157.780482) (xy 305.479196 -157.780482) (xy 305.479196 -155.977082)
			)
		)
	)
	(zone
		(layer "In1.Cu")
		(hatch none 0.5)
		(connect_pads
			(clearance 0)
		)
		(min_thickness 0.25)
		(keepout
			(tracks not_allowed)
			(vias allowed)
			(pads allowed)
			(copperpour not_allowed)
			(footprints allowed)
		)
		(placement
			(enabled no)
			(sheetname "")
		)
		(fill
			(thermal_gap 0.5)
			(thermal_bridge_width 0.5)
			(island_removal_mode 0)
		)
		(polygon
			(pts
				(xy 228.420422 -146.375882) (xy 228.420422 -148.179282) (xy 228.979222 -148.179282) (xy 228.979222 -146.375882)
			)
		)
	)
	(zone
		(layer "In1.Cu")
		(hatch none 0.5)
		(connect_pads
			(clearance 0)
		)
		(min_thickness 0.25)
		(keepout
			(tracks not_allowed)
			(vias allowed)
			(pads allowed)
			(copperpour not_allowed)
			(footprints allowed)
		)
		(placement
			(enabled no)
			(sheetname "")
		)
		(fill
			(thermal_gap 0.5)
			(thermal_bridge_width 0.5)
			(island_removal_mode 0)
		)
		(polygon
			(pts
				(xy 50.669952 -155.977082) (xy 50.669952 -157.780482) (xy 51.228752 -157.780482) (xy 51.228752 -155.977082)
			)
		)
	)
	(zone
		(layer "In1.Cu")
		(hatch none 0.5)
		(connect_pads
			(clearance 0)
		)
		(min_thickness 0.25)
		(keepout
			(tracks not_allowed)
			(vias allowed)
			(pads allowed)
			(copperpour not_allowed)
			(footprints allowed)
		)
		(placement
			(enabled no)
			(sheetname "")
		)
		(fill
			(thermal_gap 0.5)
			(thermal_bridge_width 0.5)
			(island_removal_mode 0)
		)
		(polygon
			(pts
				(xy 88.070182 -146.375882) (xy 88.070182 -148.179282) (xy 88.628982 -148.179282) (xy 88.628982 -146.375882)
			)
		)
	)
	(zone
		(layer "In1.Cu")
		(hatch none 0.5)
		(connect_pads
			(clearance 0)
		)
		(min_thickness 0.25)
		(keepout
			(tracks not_allowed)
			(vias allowed)
			(pads allowed)
			(copperpour not_allowed)
			(footprints allowed)
		)
		(placement
			(enabled no)
			(sheetname "")
		)
		(fill
			(thermal_gap 0.5)
			(thermal_bridge_width 0.5)
			(island_removal_mode 0)
		)
		(polygon
			(pts
				(xy 425.820586 -3.789172) (xy 427.128686 -3.789172) (xy 427.128686 -4.982972) (xy 425.820586 -4.982972)
			)
		)
	)
	(zone
		(layer "In1.Cu")
		(hatch none 0.5)
		(connect_pads
			(clearance 0)
		)
		(min_thickness 0.25)
		(keepout
			(tracks not_allowed)
			(vias allowed)
			(pads allowed)
			(copperpour not_allowed)
			(footprints allowed)
		)
		(placement
			(enabled no)
			(sheetname "")
		)
		(fill
			(thermal_gap 0.5)
			(thermal_bridge_width 0.5)
			(island_removal_mode 0)
		)
		(polygon
			(pts
				(xy 270.07058 0.080518) (xy 270.07058 -1.722882) (xy 270.62938 -1.722882) (xy 270.62938 0.080518)
			)
		)
	)
	(zone
		(layer "In1.Cu")
		(hatch none 0.5)
		(connect_pads
			(clearance 0)
		)
		(min_thickness 0.25)
		(keepout
			(tracks not_allowed)
			(vias allowed)
			(pads allowed)
			(copperpour not_allowed)
			(footprints allowed)
		)
		(placement
			(enabled no)
			(sheetname "")
		)
		(fill
			(thermal_gap 0.5)
			(thermal_bridge_width 0.5)
			(island_removal_mode 0)
		)
		(polygon
			(pts
				(xy 409.674822 -10.293858) (xy 410.182822 -10.293858) (xy 410.182822 -11.690858) (xy 409.674822 -11.690858)
			)
		)
	)
	(zone
		(layer "In1.Cu")
		(hatch none 0.5)
		(connect_pads
			(clearance 0)
		)
		(min_thickness 0.25)
		(keepout
			(tracks not_allowed)
			(vias allowed)
			(pads allowed)
			(copperpour not_allowed)
			(footprints allowed)
		)
		(placement
			(enabled no)
			(sheetname "")
		)
		(fill
			(thermal_gap 0.5)
			(thermal_bridge_width 0.5)
			(island_removal_mode 0)
		)
		(polygon
			(pts
				(xy 204.620368 -155.977082) (xy 204.620368 -157.780482) (xy 205.179168 -157.780482) (xy 205.179168 -155.977082)
			)
		)
	)
	(zone
		(layer "In1.Cu")
		(hatch none 0.5)
		(connect_pads
			(clearance 0)
		)
		(min_thickness 0.25)
		(keepout
			(tracks not_allowed)
			(vias allowed)
			(pads allowed)
			(copperpour not_allowed)
			(footprints allowed)
		)
		(placement
			(enabled no)
			(sheetname "")
		)
		(fill
			(thermal_gap 0.5)
			(thermal_bridge_width 0.5)
			(island_removal_mode 0)
		)
		(polygon
			(pts
				(xy 283.670502 0.080518) (xy 283.670502 -1.722882) (xy 284.229302 -1.722882) (xy 284.229302 0.080518)
			)
		)
	)
	(zone
		(layer "In1.Cu")
		(hatch none 0.5)
		(connect_pads
			(clearance 0)
		)
		(min_thickness 0.25)
		(keepout
			(tracks not_allowed)
			(vias allowed)
			(pads allowed)
			(copperpour not_allowed)
			(footprints allowed)
		)
		(placement
			(enabled no)
			(sheetname "")
		)
		(fill
			(thermal_gap 0.5)
			(thermal_bridge_width 0.5)
			(island_removal_mode 0)
		)
		(polygon
			(pts
				(xy 395.325092 -9.825736) (xy 395.833092 -9.825736) (xy 395.833092 -11.222736) (xy 395.325092 -11.222736)
			)
		)
	)
	(zone
		(layer "In1.Cu")
		(hatch none 0.5)
		(connect_pads
			(clearance 0)
		)
		(min_thickness 0.25)
		(keepout
			(tracks not_allowed)
			(vias allowed)
			(pads allowed)
			(copperpour not_allowed)
			(footprints allowed)
		)
		(placement
			(enabled no)
			(sheetname "")
		)
		(fill
			(thermal_gap 0.5)
			(thermal_bridge_width 0.5)
			(island_removal_mode 0)
		)
		(polygon
			(pts
				(xy 271.770602 4.680458) (xy 271.770602 2.877058) (xy 272.329402 2.877058) (xy 272.329402 4.680458)
			)
		)
	)
	(zone
		(layer "In1.Cu")
		(hatch none 0.5)
		(connect_pads
			(clearance 0)
		)
		(min_thickness 0.25)
		(keepout
			(tracks not_allowed)
			(vias allowed)
			(pads allowed)
			(copperpour not_allowed)
			(footprints allowed)
		)
		(placement
			(enabled no)
			(sheetname "")
		)
		(fill
			(thermal_gap 0.5)
			(thermal_bridge_width 0.5)
			(island_removal_mode 0)
		)
		(polygon
			(pts
				(xy 288.770314 -151.377142) (xy 288.770314 -153.180542) (xy 289.329114 -153.180542) (xy 289.329114 -151.377142)
			)
		)
	)
	(zone
		(layer "In1.Cu")
		(hatch none 0.5)
		(connect_pads
			(clearance 0)
		)
		(min_thickness 0.25)
		(keepout
			(tracks not_allowed)
			(vias allowed)
			(pads allowed)
			(copperpour not_allowed)
			(footprints allowed)
		)
		(placement
			(enabled no)
			(sheetname "")
		)
		(fill
			(thermal_gap 0.5)
			(thermal_bridge_width 0.5)
			(island_removal_mode 0)
		)
		(polygon
			(pts
				(xy 47.270162 -136.774682) (xy 47.270162 -138.578082) (xy 47.828962 -138.578082) (xy 47.828962 -136.774682)
			)
		)
	)
	(zone
		(layer "In1.Cu")
		(hatch none 0.5)
		(connect_pads
			(clearance 0)
		)
		(min_thickness 0.25)
		(keepout
			(tracks not_allowed)
			(vias allowed)
			(pads allowed)
			(copperpour not_allowed)
			(footprints allowed)
		)
		(placement
			(enabled no)
			(sheetname "")
		)
		(fill
			(thermal_gap 0.5)
			(thermal_bridge_width 0.5)
			(island_removal_mode 0)
		)
		(polygon
			(pts
				(xy 114.419888 -4.920742) (xy 114.419888 -6.724142) (xy 114.978688 -6.724142) (xy 114.978688 -4.920742)
			)
		)
	)
	(zone
		(layer "In1.Cu")
		(hatch none 0.5)
		(connect_pads
			(clearance 0)
		)
		(min_thickness 0.25)
		(keepout
			(tracks not_allowed)
			(vias allowed)
			(pads allowed)
			(copperpour not_allowed)
			(footprints allowed)
		)
		(placement
			(enabled no)
			(sheetname "")
		)
		(fill
			(thermal_gap 0.5)
			(thermal_bridge_width 0.5)
			(island_removal_mode 0)
		)
		(polygon
			(pts
				(xy 364.346744 -9.773158) (xy 364.854744 -9.773158) (xy 364.854744 -11.170158) (xy 364.346744 -11.170158)
			)
		)
	)
	(zone
		(layer "In1.Cu")
		(hatch none 0.5)
		(connect_pads
			(clearance 0)
		)
		(min_thickness 0.25)
		(keepout
			(tracks not_allowed)
			(vias allowed)
			(pads allowed)
			(copperpour not_allowed)
			(footprints allowed)
		)
		(placement
			(enabled no)
			(sheetname "")
		)
		(fill
			(thermal_gap 0.5)
			(thermal_bridge_width 0.5)
			(island_removal_mode 0)
		)
		(polygon
			(pts
				(xy 13.6398 -36.322) (xy 15.0368 -36.322) (xy 15.0368 -36.83) (xy 13.6398 -36.83)
			)
		)
	)
	(zone
		(layer "In1.Cu")
		(hatch none 0.5)
		(connect_pads
			(clearance 0)
		)
		(min_thickness 0.25)
		(keepout
			(tracks not_allowed)
			(vias allowed)
			(pads allowed)
			(copperpour not_allowed)
			(footprints allowed)
		)
		(placement
			(enabled no)
			(sheetname "")
		)
		(fill
			(thermal_gap 0.5)
			(thermal_bridge_width 0.5)
			(island_removal_mode 0)
		)
		(polygon
			(pts
				(xy 200.37044 4.680458) (xy 200.37044 2.877058) (xy 200.92924 2.877058) (xy 200.92924 4.680458)
			)
		)
	)
	(zone
		(layer "In1.Cu")
		(hatch none 0.5)
		(connect_pads
			(clearance 0)
		)
		(min_thickness 0.25)
		(keepout
			(tracks not_allowed)
			(vias allowed)
			(pads allowed)
			(copperpour not_allowed)
			(footprints allowed)
		)
		(placement
			(enabled no)
			(sheetname "")
		)
		(fill
			(thermal_gap 0.5)
			(thermal_bridge_width 0.5)
			(island_removal_mode 0)
		)
		(polygon
			(pts
				(xy 199.520556 -4.920742) (xy 199.520556 -6.724142) (xy 200.079356 -6.724142) (xy 200.079356 -4.920742)
			)
		)
	)
	(zone
		(layer "In1.Cu")
		(hatch none 0.5)
		(connect_pads
			(clearance 0)
		)
		(min_thickness 0.25)
		(keepout
			(tracks not_allowed)
			(vias allowed)
			(pads allowed)
			(copperpour not_allowed)
			(footprints allowed)
		)
		(placement
			(enabled no)
			(sheetname "")
		)
		(fill
			(thermal_gap 0.5)
			(thermal_bridge_width 0.5)
			(island_removal_mode 0)
		)
		(polygon
			(pts
				(xy 453.947022 -115.799362) (xy 455.254868 -115.799362) (xy 455.254868 -118.186962) (xy 453.947022 -118.186962)
			)
		)
	)
	(zone
		(layer "In1.Cu")
		(hatch none 0.5)
		(connect_pads
			(clearance 0)
		)
		(min_thickness 0.25)
		(keepout
			(tracks not_allowed)
			(vias allowed)
			(pads allowed)
			(copperpour not_allowed)
			(footprints allowed)
		)
		(placement
			(enabled no)
			(sheetname "")
		)
		(fill
			(thermal_gap 0.5)
			(thermal_bridge_width 0.5)
			(island_removal_mode 0)
		)
		(polygon
			(pts
				(xy 382.022604 -31.118556) (xy 383.572004 -31.118556) (xy 383.572004 -31.923228) (xy 382.022604 -31.923228)
			)
		)
	)
	(zone
		(layer "In1.Cu")
		(hatch none 0.5)
		(connect_pads
			(clearance 0)
		)
		(min_thickness 0.25)
		(keepout
			(tracks not_allowed)
			(vias allowed)
			(pads allowed)
			(copperpour not_allowed)
			(footprints allowed)
		)
		(placement
			(enabled no)
			(sheetname "")
		)
		(fill
			(thermal_gap 0.5)
			(thermal_bridge_width 0.5)
			(island_removal_mode 0)
		)
		(polygon
			(pts
				(xy 424.220386 -7.192772) (xy 425.528486 -7.192772) (xy 425.528486 -8.386572) (xy 424.220386 -8.386572)
			)
		)
	)
	(zone
		(layer "In1.Cu")
		(hatch none 0.5)
		(connect_pads
			(clearance 0)
		)
		(min_thickness 0.25)
		(keepout
			(tracks not_allowed)
			(vias allowed)
			(pads allowed)
			(copperpour not_allowed)
			(footprints allowed)
		)
		(placement
			(enabled no)
			(sheetname "")
		)
		(fill
			(thermal_gap 0.5)
			(thermal_bridge_width 0.5)
			(island_removal_mode 0)
		)
		(polygon
			(pts
				(xy 303.220374 -19.121882) (xy 303.220374 -20.925282) (xy 303.779174 -20.925282) (xy 303.779174 -19.121882)
			)
		)
	)
	(zone
		(layer "In1.Cu")
		(hatch none 0.5)
		(connect_pads
			(clearance 0)
		)
		(min_thickness 0.25)
		(keepout
			(tracks not_allowed)
			(vias allowed)
			(pads allowed)
			(copperpour not_allowed)
			(footprints allowed)
		)
		(placement
			(enabled no)
			(sheetname "")
		)
		(fill
			(thermal_gap 0.5)
			(thermal_bridge_width 0.5)
			(island_removal_mode 0)
		)
		(polygon
			(pts
				(xy 58.319924 -19.121882) (xy 58.319924 -20.925282) (xy 58.878724 -20.925282) (xy 58.878724 -19.121882)
			)
		)
	)
	(zone
		(net "GND")
		(layer "In1.Cu")
		(hatch none 0.5)
		(connect_pads
			(clearance 0.5)
		)
		(min_thickness 0.25)
		(fill yes
			(thermal_gap 0.5)
			(thermal_bridge_width 0.5)
			(island_removal_mode 0)
		)
		(polygon
			(pts
				(xy 398.806416 -157.493716) (xy 393.941808 -157.493716) (xy 393.548108 -157.887416) (xy 393.548108 -158.414466)
				(xy 393.775438 -158.641796) (xy 398.130776 -158.641796) (xy 398.623536 -158.149036) (xy 398.948148 -158.149036)
				(xy 398.966182 -158.131002) (xy 398.966182 -157.653482)
			)
		)
	)
	(zone
		(layer "In1.Cu")
		(hatch none 0.5)
		(connect_pads
			(clearance 0)
		)
		(min_thickness 0.25)
		(keepout
			(tracks not_allowed)
			(vias allowed)
			(pads allowed)
			(copperpour not_allowed)
			(footprints allowed)
		)
		(placement
			(enabled no)
			(sheetname "")
		)
		(fill
			(thermal_gap 0.5)
			(thermal_bridge_width 0.5)
			(island_removal_mode 0)
		)
		(polygon
			(pts
				(xy 13.6398 -27.432) (xy 15.0368 -27.432) (xy 15.0368 -27.94) (xy 13.6398 -27.94)
			)
		)
	)
	(zone
		(layer "In1.Cu")
		(hatch none 0.5)
		(connect_pads
			(clearance 0)
		)
		(min_thickness 0.25)
		(keepout
			(tracks not_allowed)
			(vias allowed)
			(pads allowed)
			(copperpour not_allowed)
			(footprints allowed)
		)
		(placement
			(enabled no)
			(sheetname "")
		)
		(fill
			(thermal_gap 0.5)
			(thermal_bridge_width 0.5)
			(island_removal_mode 0)
		)
		(polygon
			(pts
				(xy 82.970116 -136.774682) (xy 82.970116 -138.578082) (xy 83.528916 -138.578082) (xy 83.528916 -136.774682)
			)
		)
	)
	(zone
		(layer "In1.Cu")
		(hatch none 0.5)
		(connect_pads
			(clearance 0)
		)
		(min_thickness 0.25)
		(keepout
			(tracks not_allowed)
			(vias allowed)
			(pads allowed)
			(copperpour not_allowed)
			(footprints allowed)
		)
		(placement
			(enabled no)
			(sheetname "")
		)
		(fill
			(thermal_gap 0.5)
			(thermal_bridge_width 0.5)
			(island_removal_mode 0)
		)
		(polygon
			(pts
				(xy 366.823244 -9.773158) (xy 367.331244 -9.773158) (xy 367.331244 -11.170158) (xy 366.823244 -11.170158)
			)
		)
	)
	(zone
		(layer "In1.Cu")
		(hatch none 0.5)
		(connect_pads
			(clearance 0)
		)
		(min_thickness 0.25)
		(keepout
			(tracks not_allowed)
			(vias allowed)
			(pads allowed)
			(copperpour not_allowed)
			(footprints allowed)
		)
		(placement
			(enabled no)
			(sheetname "")
		)
		(fill
			(thermal_gap 0.5)
			(thermal_bridge_width 0.5)
			(island_removal_mode 0)
		)
		(polygon
			(pts
				(xy 82.119978 4.680458) (xy 82.119978 2.877058) (xy 82.678778 2.877058) (xy 82.678778 4.680458)
			)
		)
	)
	(zone
		(layer "In1.Cu")
		(hatch none 0.5)
		(connect_pads
			(clearance 0)
		)
		(min_thickness 0.25)
		(keepout
			(tracks not_allowed)
			(vias allowed)
			(pads allowed)
			(copperpour not_allowed)
			(footprints allowed)
		)
		(placement
			(enabled no)
			(sheetname "")
		)
		(fill
			(thermal_gap 0.5)
			(thermal_bridge_width 0.5)
			(island_removal_mode 0)
		)
		(polygon
			(pts
				(xy 60.870084 -14.521942) (xy 60.870084 -16.325342) (xy 61.428884 -16.325342) (xy 61.428884 -14.521942)
			)
		)
	)
	(zone
		(layer "In1.Cu")
		(hatch none 0.5)
		(connect_pads
			(clearance 0)
		)
		(min_thickness 0.25)
		(keepout
			(tracks not_allowed)
			(vias allowed)
			(pads allowed)
			(copperpour not_allowed)
			(footprints allowed)
		)
		(placement
			(enabled no)
			(sheetname "")
		)
		(fill
			(thermal_gap 0.5)
			(thermal_bridge_width 0.5)
			(island_removal_mode 0)
		)
		(polygon
			(pts
				(xy 373.231156 -3.792982) (xy 374.539002 -3.792982) (xy 374.539002 -4.986782) (xy 373.231156 -4.986782)
			)
		)
	)
	(zone
		(layer "In1.Cu")
		(hatch none 0.5)
		(connect_pads
			(clearance 0)
		)
		(min_thickness 0.25)
		(keepout
			(tracks not_allowed)
			(vias allowed)
			(pads allowed)
			(copperpour not_allowed)
			(footprints allowed)
		)
		(placement
			(enabled no)
			(sheetname "")
		)
		(fill
			(thermal_gap 0.5)
			(thermal_bridge_width 0.5)
			(island_removal_mode 0)
		)
		(polygon
			(pts
				(xy 231.820466 -151.377142) (xy 231.820466 -153.180542) (xy 232.379266 -153.180542) (xy 232.379266 -151.377142)
			)
		)
	)
	(zone
		(layer "In1.Cu")
		(hatch none 0.5)
		(connect_pads
			(clearance 0)
		)
		(min_thickness 0.25)
		(keepout
			(tracks not_allowed)
			(vias allowed)
			(pads allowed)
			(copperpour not_allowed)
			(footprints allowed)
		)
		(placement
			(enabled no)
			(sheetname "")
		)
		(fill
			(thermal_gap 0.5)
			(thermal_bridge_width 0.5)
			(island_removal_mode 0)
		)
		(polygon
			(pts
				(xy 310.870346 -151.377142) (xy 310.870346 -153.180542) (xy 311.429146 -153.180542) (xy 311.429146 -151.377142)
			)
		)
	)
	(zone
		(layer "In1.Cu")
		(hatch none 0.5)
		(connect_pads
			(clearance 0)
		)
		(min_thickness 0.25)
		(keepout
			(tracks not_allowed)
			(vias allowed)
			(pads allowed)
			(copperpour not_allowed)
			(footprints allowed)
		)
		(placement
			(enabled no)
			(sheetname "")
		)
		(fill
			(thermal_gap 0.5)
			(thermal_bridge_width 0.5)
			(island_removal_mode 0)
		)
		(polygon
			(pts
				(xy 441.887102 -46.478698) (xy 443.194948 -46.478698) (xy 443.194948 -48.485298) (xy 441.887102 -48.485298)
			)
		)
	)
	(zone
		(layer "In1.Cu")
		(hatch none 0.5)
		(connect_pads
			(clearance 0)
		)
		(min_thickness 0.25)
		(keepout
			(tracks not_allowed)
			(vias allowed)
			(pads allowed)
			(copperpour not_allowed)
			(footprints allowed)
		)
		(placement
			(enabled no)
			(sheetname "")
		)
		(fill
			(thermal_gap 0.5)
			(thermal_bridge_width 0.5)
			(island_removal_mode 0)
		)
		(polygon
			(pts
				(xy 44.720002 -155.977082) (xy 44.720002 -157.780482) (xy 45.278802 -157.780482) (xy 45.278802 -155.977082)
			)
		)
	)
	(zone
		(layer "In1.Cu")
		(hatch none 0.5)
		(connect_pads
			(clearance 0)
		)
		(min_thickness 0.25)
		(keepout
			(tracks not_allowed)
			(vias allowed)
			(pads allowed)
			(copperpour not_allowed)
			(footprints allowed)
		)
		(placement
			(enabled no)
			(sheetname "")
		)
		(fill
			(thermal_gap 0.5)
			(thermal_bridge_width 0.5)
			(island_removal_mode 0)
		)
		(polygon
			(pts
				(xy 219.920566 -9.520682) (xy 219.920566 -11.324082) (xy 220.479366 -11.324082) (xy 220.479366 -9.520682)
			)
		)
	)
	(zone
		(layer "In1.Cu")
		(hatch none 0.5)
		(connect_pads
			(clearance 0)
		)
		(min_thickness 0.25)
		(keepout
			(tracks not_allowed)
			(vias allowed)
			(pads allowed)
			(copperpour not_allowed)
			(footprints allowed)
		)
		(placement
			(enabled no)
			(sheetname "")
		)
		(fill
			(thermal_gap 0.5)
			(thermal_bridge_width 0.5)
			(island_removal_mode 0)
		)
		(polygon
			(pts
				(xy 219.070428 -155.977082) (xy 219.070428 -157.780482) (xy 219.629228 -157.780482) (xy 219.629228 -155.977082)
			)
		)
	)
	(zone
		(layer "In1.Cu")
		(hatch none 0.5)
		(connect_pads
			(clearance 0)
		)
		(min_thickness 0.25)
		(keepout
			(tracks not_allowed)
			(vias allowed)
			(pads allowed)
			(copperpour not_allowed)
			(footprints allowed)
		)
		(placement
			(enabled no)
			(sheetname "")
		)
		(fill
			(thermal_gap 0.5)
			(thermal_bridge_width 0.5)
			(island_removal_mode 0)
		)
		(polygon
			(pts
				(xy 37.920168 -155.977082) (xy 37.920168 -157.780482) (xy 38.478968 -157.780482) (xy 38.478968 -155.977082)
			)
		)
	)
	(zone
		(layer "In1.Cu")
		(hatch none 0.5)
		(connect_pads
			(clearance 0)
		)
		(min_thickness 0.25)
		(keepout
			(tracks not_allowed)
			(vias allowed)
			(pads allowed)
			(copperpour not_allowed)
			(footprints allowed)
		)
		(placement
			(enabled no)
			(sheetname "")
		)
		(fill
			(thermal_gap 0.5)
			(thermal_bridge_width 0.5)
			(island_removal_mode 0)
		)
		(polygon
			(pts
				(xy 274.320508 -14.521942) (xy 274.320508 -16.325342) (xy 274.879308 -16.325342) (xy 274.879308 -14.521942)
			)
		)
	)
	(zone
		(layer "In1.Cu")
		(hatch none 0.5)
		(connect_pads
			(clearance 0)
		)
		(min_thickness 0.25)
		(keepout
			(tracks not_allowed)
			(vias allowed)
			(pads allowed)
			(copperpour not_allowed)
			(footprints allowed)
		)
		(placement
			(enabled no)
			(sheetname "")
		)
		(fill
			(thermal_gap 0.5)
			(thermal_bridge_width 0.5)
			(island_removal_mode 0)
		)
		(polygon
			(pts
				(xy 196.120512 4.680458) (xy 196.120512 2.877058) (xy 196.679312 2.877058) (xy 196.679312 4.680458)
			)
		)
	)
	(zone
		(layer "In1.Cu")
		(hatch none 0.5)
		(connect_pads
			(clearance 0)
		)
		(min_thickness 0.25)
		(keepout
			(tracks not_allowed)
			(vias allowed)
			(pads allowed)
			(copperpour not_allowed)
			(footprints allowed)
		)
		(placement
			(enabled no)
			(sheetname "")
		)
		(fill
			(thermal_gap 0.5)
			(thermal_bridge_width 0.5)
			(island_removal_mode 0)
		)
		(polygon
			(pts
				(xy 272.620486 -4.920742) (xy 272.620486 -6.724142) (xy 273.179286 -6.724142) (xy 273.179286 -4.920742)
			)
		)
	)
	(zone
		(layer "In1.Cu")
		(hatch none 0.5)
		(connect_pads
			(clearance 0)
		)
		(min_thickness 0.25)
		(keepout
			(tracks not_allowed)
			(vias allowed)
			(pads allowed)
			(copperpour not_allowed)
			(footprints allowed)
		)
		(placement
			(enabled no)
			(sheetname "")
		)
		(fill
			(thermal_gap 0.5)
			(thermal_bridge_width 0.5)
			(island_removal_mode 0)
		)
		(polygon
			(pts
				(xy 68.520056 -14.521942) (xy 68.520056 -16.325342) (xy 69.078856 -16.325342) (xy 69.078856 -14.521942)
			)
		)
	)
	(zone
		(layer "In1.Cu")
		(hatch none 0.5)
		(connect_pads
			(clearance 0)
		)
		(min_thickness 0.25)
		(keepout
			(tracks not_allowed)
			(vias allowed)
			(pads allowed)
			(copperpour not_allowed)
			(footprints allowed)
		)
		(placement
			(enabled no)
			(sheetname "")
		)
		(fill
			(thermal_gap 0.5)
			(thermal_bridge_width 0.5)
			(island_removal_mode 0)
		)
		(polygon
			(pts
				(xy 239.470438 4.680458) (xy 239.470438 2.877058) (xy 240.029238 2.877058) (xy 240.029238 4.680458)
			)
		)
	)
	(zone
		(layer "In1.Cu")
		(hatch none 0.5)
		(connect_pads
			(clearance 0)
		)
		(min_thickness 0.25)
		(keepout
			(tracks not_allowed)
			(vias allowed)
			(pads allowed)
			(copperpour not_allowed)
			(footprints allowed)
		)
		(placement
			(enabled no)
			(sheetname "")
		)
		(fill
			(thermal_gap 0.5)
			(thermal_bridge_width 0.5)
			(island_removal_mode 0)
		)
		(polygon
			(pts
				(xy 293.87038 -9.520682) (xy 293.87038 -11.324082) (xy 294.42918 -11.324082) (xy 294.42918 -9.520682)
			)
		)
	)
	(zone
		(layer "In1.Cu")
		(hatch none 0.5)
		(connect_pads
			(clearance 0)
		)
		(min_thickness 0.25)
		(keepout
			(tracks not_allowed)
			(vias allowed)
			(pads allowed)
			(copperpour not_allowed)
			(footprints allowed)
		)
		(placement
			(enabled no)
			(sheetname "")
		)
		(fill
			(thermal_gap 0.5)
			(thermal_bridge_width 0.5)
			(island_removal_mode 0)
		)
		(polygon
			(pts
				(xy 70.220078 -132.174742) (xy 70.220078 -133.978142) (xy 70.778878 -133.978142) (xy 70.778878 -132.174742)
			)
		)
	)
	(zone
		(layer "In1.Cu")
		(hatch none 0.5)
		(connect_pads
			(clearance 0)
		)
		(min_thickness 0.25)
		(keepout
			(tracks not_allowed)
			(vias allowed)
			(pads allowed)
			(copperpour not_allowed)
			(footprints allowed)
		)
		(placement
			(enabled no)
			(sheetname "")
		)
		(fill
			(thermal_gap 0.5)
			(thermal_bridge_width 0.5)
			(island_removal_mode 0)
		)
		(polygon
			(pts
				(xy 106.77017 -141.775942) (xy 106.77017 -143.579342) (xy 107.32897 -143.579342) (xy 107.32897 -141.775942)
			)
		)
	)
	(zone
		(layer "In1.Cu")
		(hatch none 0.5)
		(connect_pads
			(clearance 0)
		)
		(min_thickness 0.25)
		(keepout
			(tracks not_allowed)
			(vias allowed)
			(pads allowed)
			(copperpour not_allowed)
			(footprints allowed)
		)
		(placement
			(enabled no)
			(sheetname "")
		)
		(fill
			(thermal_gap 0.5)
			(thermal_bridge_width 0.5)
			(island_removal_mode 0)
		)
		(polygon
			(pts
				(xy 110.16996 -136.774682) (xy 110.16996 -138.578082) (xy 110.72876 -138.578082) (xy 110.72876 -136.774682)
			)
		)
	)
	(zone
		(layer "In1.Cu")
		(hatch none 0.5)
		(connect_pads
			(clearance 0)
		)
		(min_thickness 0.25)
		(keepout
			(tracks not_allowed)
			(vias allowed)
			(pads allowed)
			(copperpour not_allowed)
			(footprints allowed)
		)
		(placement
			(enabled no)
			(sheetname "")
		)
		(fill
			(thermal_gap 0.5)
			(thermal_bridge_width 0.5)
			(island_removal_mode 0)
		)
		(polygon
			(pts
				(xy 44.720002 -19.121882) (xy 44.720002 -20.925282) (xy 45.278802 -20.925282) (xy 45.278802 -19.121882)
			)
		)
	)
	(zone
		(layer "In1.Cu")
		(hatch none 0.5)
		(connect_pads
			(clearance 0)
		)
		(min_thickness 0.25)
		(keepout
			(tracks not_allowed)
			(vias allowed)
			(pads allowed)
			(copperpour not_allowed)
			(footprints allowed)
		)
		(placement
			(enabled no)
			(sheetname "")
		)
		(fill
			(thermal_gap 0.5)
			(thermal_bridge_width 0.5)
			(island_removal_mode 0)
		)
		(polygon
			(pts
				(xy 302.37049 -14.521942) (xy 302.37049 -16.325342) (xy 302.92929 -16.325342) (xy 302.92929 -14.521942)
			)
		)
	)
	(zone
		(layer "In1.Cu")
		(hatch none 0.5)
		(connect_pads
			(clearance 0)
		)
		(min_thickness 0.25)
		(keepout
			(tracks not_allowed)
			(vias allowed)
			(pads allowed)
			(copperpour not_allowed)
			(footprints allowed)
		)
		(placement
			(enabled no)
			(sheetname "")
		)
		(fill
			(thermal_gap 0.5)
			(thermal_bridge_width 0.5)
			(island_removal_mode 0)
		)
		(polygon
			(pts
				(xy 109.320076 -14.521942) (xy 109.320076 -16.325342) (xy 109.878876 -16.325342) (xy 109.878876 -14.521942)
			)
		)
	)
	(zone
		(layer "In1.Cu")
		(hatch none 0.5)
		(connect_pads
			(clearance 0)
		)
		(min_thickness 0.25)
		(keepout
			(tracks not_allowed)
			(vias allowed)
			(pads allowed)
			(copperpour not_allowed)
			(footprints allowed)
		)
		(placement
			(enabled no)
			(sheetname "")
		)
		(fill
			(thermal_gap 0.5)
			(thermal_bridge_width 0.5)
			(island_removal_mode 0)
		)
		(polygon
			(pts
				(xy 44.720002 -132.174742) (xy 44.720002 -133.978142) (xy 45.278802 -133.978142) (xy 45.278802 -132.174742)
			)
		)
	)
	(zone
		(layer "In1.Cu")
		(hatch none 0.5)
		(connect_pads
			(clearance 0)
		)
		(min_thickness 0.25)
		(keepout
			(tracks not_allowed)
			(vias allowed)
			(pads allowed)
			(copperpour not_allowed)
			(footprints allowed)
		)
		(placement
			(enabled no)
			(sheetname "")
		)
		(fill
			(thermal_gap 0.5)
			(thermal_bridge_width 0.5)
			(island_removal_mode 0)
		)
		(polygon
			(pts
				(xy 228.420422 -132.174742) (xy 228.420422 -133.978142) (xy 228.979222 -133.978142) (xy 228.979222 -132.174742)
			)
		)
	)
	(zone
		(layer "In1.Cu")
		(hatch none 0.5)
		(connect_pads
			(clearance 0)
		)
		(min_thickness 0.25)
		(keepout
			(tracks not_allowed)
			(vias allowed)
			(pads allowed)
			(copperpour not_allowed)
			(footprints allowed)
		)
		(placement
			(enabled no)
			(sheetname "")
		)
		(fill
			(thermal_gap 0.5)
			(thermal_bridge_width 0.5)
			(island_removal_mode 0)
		)
		(polygon
			(pts
				(xy 131.420108 4.680458) (xy 131.420108 2.877058) (xy 131.978908 2.877058) (xy 131.978908 4.680458)
			)
		)
	)
	(zone
		(layer "In1.Cu")
		(hatch none 0.5)
		(connect_pads
			(clearance 0)
		)
		(min_thickness 0.25)
		(keepout
			(tracks not_allowed)
			(vias allowed)
			(pads allowed)
			(copperpour not_allowed)
			(footprints allowed)
		)
		(placement
			(enabled no)
			(sheetname "")
		)
		(fill
			(thermal_gap 0.5)
			(thermal_bridge_width 0.5)
			(island_removal_mode 0)
		)
		(polygon
			(pts
				(xy 281.120342 -14.521942) (xy 281.120342 -16.325342) (xy 281.679142 -16.325342) (xy 281.679142 -14.521942)
			)
		)
	)
	(zone
		(layer "In1.Cu")
		(hatch none 0.5)
		(connect_pads
			(clearance 0)
		)
		(min_thickness 0.25)
		(keepout
			(tracks not_allowed)
			(vias allowed)
			(pads allowed)
			(copperpour not_allowed)
			(footprints allowed)
		)
		(placement
			(enabled no)
			(sheetname "")
		)
		(fill
			(thermal_gap 0.5)
			(thermal_bridge_width 0.5)
			(island_removal_mode 0)
		)
		(polygon
			(pts
				(xy 403.465792 -9.774936) (xy 403.973792 -9.774936) (xy 403.973792 -11.171936) (xy 403.465792 -11.171936)
			)
		)
	)
	(zone
		(layer "In1.Cu")
		(hatch none 0.5)
		(connect_pads
			(clearance 0)
		)
		(min_thickness 0.25)
		(keepout
			(tracks not_allowed)
			(vias allowed)
			(pads allowed)
			(copperpour not_allowed)
			(footprints allowed)
		)
		(placement
			(enabled no)
			(sheetname "")
		)
		(fill
			(thermal_gap 0.5)
			(thermal_bridge_width 0.5)
			(island_removal_mode 0)
		)
		(polygon
			(pts
				(xy 275.170392 -146.375882) (xy 275.170392 -148.179282) (xy 275.729192 -148.179282) (xy 275.729192 -146.375882)
			)
		)
	)
	(zone
		(layer "In1.Cu")
		(hatch none 0.5)
		(connect_pads
			(clearance 0)
		)
		(min_thickness 0.25)
		(keepout
			(tracks not_allowed)
			(vias allowed)
			(pads allowed)
			(copperpour not_allowed)
			(footprints allowed)
		)
		(placement
			(enabled no)
			(sheetname "")
		)
		(fill
			(thermal_gap 0.5)
			(thermal_bridge_width 0.5)
			(island_removal_mode 0)
		)
		(polygon
			(pts
				(xy 46.420024 -132.174742) (xy 46.420024 -133.978142) (xy 46.978824 -133.978142) (xy 46.978824 -132.174742)
			)
		)
	)
	(zone
		(layer "In1.Cu")
		(hatch none 0.5)
		(connect_pads
			(clearance 0)
		)
		(min_thickness 0.25)
		(keepout
			(tracks not_allowed)
			(vias allowed)
			(pads allowed)
			(copperpour not_allowed)
			(footprints allowed)
		)
		(placement
			(enabled no)
			(sheetname "")
		)
		(fill
			(thermal_gap 0.5)
			(thermal_bridge_width 0.5)
			(island_removal_mode 0)
		)
		(polygon
			(pts
				(xy 92.32011 0.080518) (xy 92.32011 -1.722882) (xy 92.87891 -1.722882) (xy 92.87891 0.080518)
			)
		)
	)
	(zone
		(layer "In1.Cu")
		(hatch none 0.5)
		(connect_pads
			(clearance 0)
		)
		(min_thickness 0.25)
		(keepout
			(tracks not_allowed)
			(vias allowed)
			(pads allowed)
			(copperpour not_allowed)
			(footprints allowed)
		)
		(placement
			(enabled no)
			(sheetname "")
		)
		(fill
			(thermal_gap 0.5)
			(thermal_bridge_width 0.5)
			(island_removal_mode 0)
		)
		(polygon
			(pts
				(xy 230.120444 -14.521942) (xy 230.120444 -16.325342) (xy 230.679244 -16.325342) (xy 230.679244 -14.521942)
			)
		)
	)
	(zone
		(layer "In1.Cu")
		(hatch none 0.5)
		(connect_pads
			(clearance 0)
		)
		(min_thickness 0.25)
		(keepout
			(tracks not_allowed)
			(vias allowed)
			(pads allowed)
			(copperpour not_allowed)
			(footprints allowed)
		)
		(placement
			(enabled no)
			(sheetname "")
		)
		(fill
			(thermal_gap 0.5)
			(thermal_bridge_width 0.5)
			(island_removal_mode 0)
		)
		(polygon
			(pts
				(xy 133.970014 -136.774682) (xy 133.970014 -138.578082) (xy 134.528814 -138.578082) (xy 134.528814 -136.774682)
			)
		)
	)
	(zone
		(layer "In1.Cu")
		(hatch none 0.5)
		(connect_pads
			(clearance 0)
		)
		(min_thickness 0.25)
		(keepout
			(tracks not_allowed)
			(vias allowed)
			(pads allowed)
			(copperpour not_allowed)
			(footprints allowed)
		)
		(placement
			(enabled no)
			(sheetname "")
		)
		(fill
			(thermal_gap 0.5)
			(thermal_bridge_width 0.5)
			(island_removal_mode 0)
		)
		(polygon
			(pts
				(xy 50.669952 -146.375882) (xy 50.669952 -148.179282) (xy 51.228752 -148.179282) (xy 51.228752 -146.375882)
			)
		)
	)
	(zone
		(layer "In1.Cu")
		(hatch none 0.5)
		(connect_pads
			(clearance 0)
		)
		(min_thickness 0.25)
		(keepout
			(tracks not_allowed)
			(vias allowed)
			(pads allowed)
			(copperpour not_allowed)
			(footprints allowed)
		)
		(placement
			(enabled no)
			(sheetname "")
		)
		(fill
			(thermal_gap 0.5)
			(thermal_bridge_width 0.5)
			(island_removal_mode 0)
		)
		(polygon
			(pts
				(xy 293.87038 -146.375882) (xy 293.87038 -148.179282) (xy 294.42918 -148.179282) (xy 294.42918 -146.375882)
			)
		)
	)
	(zone
		(layer "In1.Cu")
		(hatch none 0.5)
		(connect_pads
			(clearance 0)
		)
		(min_thickness 0.25)
		(keepout
			(tracks not_allowed)
			(vias allowed)
			(pads allowed)
			(copperpour not_allowed)
			(footprints allowed)
		)
		(placement
			(enabled no)
			(sheetname "")
		)
		(fill
			(thermal_gap 0.5)
			(thermal_bridge_width 0.5)
			(island_removal_mode 0)
		)
		(polygon
			(pts
				(xy 150.120096 -14.521942) (xy 150.120096 -16.325342) (xy 150.678896 -16.325342) (xy 150.678896 -14.521942)
			)
		)
	)
	(zone
		(layer "In1.Cu")
		(hatch none 0.5)
		(connect_pads
			(clearance 0)
		)
		(min_thickness 0.25)
		(keepout
			(tracks not_allowed)
			(vias allowed)
			(pads allowed)
			(copperpour not_allowed)
			(footprints allowed)
		)
		(placement
			(enabled no)
			(sheetname "")
		)
		(fill
			(thermal_gap 0.5)
			(thermal_bridge_width 0.5)
			(island_removal_mode 0)
		)
		(polygon
			(pts
				(xy 252.220476 -146.375882) (xy 252.220476 -148.179282) (xy 252.779276 -148.179282) (xy 252.779276 -146.375882)
			)
		)
	)
	(zone
		(layer "In1.Cu")
		(hatch none 0.5)
		(connect_pads
			(clearance 0)
		)
		(min_thickness 0.25)
		(keepout
			(tracks not_allowed)
			(vias allowed)
			(pads allowed)
			(copperpour not_allowed)
			(footprints allowed)
		)
		(placement
			(enabled no)
			(sheetname "")
		)
		(fill
			(thermal_gap 0.5)
			(thermal_bridge_width 0.5)
			(island_removal_mode 0)
		)
		(polygon
			(pts
				(xy 290.470336 -4.920742) (xy 290.470336 -6.724142) (xy 291.029136 -6.724142) (xy 291.029136 -4.920742)
			)
		)
	)
	(zone
		(layer "In1.Cu")
		(hatch none 0.5)
		(connect_pads
			(clearance 0)
		)
		(min_thickness 0.25)
		(keepout
			(tracks not_allowed)
			(vias allowed)
			(pads allowed)
			(copperpour not_allowed)
			(footprints allowed)
		)
		(placement
			(enabled no)
			(sheetname "")
		)
		(fill
			(thermal_gap 0.5)
			(thermal_bridge_width 0.5)
			(island_removal_mode 0)
		)
		(polygon
			(pts
				(xy 34.520124 4.680458) (xy 34.520124 2.877058) (xy 35.078924 2.877058) (xy 35.078924 4.680458)
			)
		)
	)
	(zone
		(layer "In1.Cu")
		(hatch none 0.5)
		(connect_pads
			(clearance 0)
		)
		(min_thickness 0.25)
		(keepout
			(tracks not_allowed)
			(vias allowed)
			(pads allowed)
			(copperpour not_allowed)
			(footprints allowed)
		)
		(placement
			(enabled no)
			(sheetname "")
		)
		(fill
			(thermal_gap 0.5)
			(thermal_bridge_width 0.5)
			(island_removal_mode 0)
		)
		(polygon
			(pts
				(xy 257.320542 -155.977082) (xy 257.320542 -157.780482) (xy 257.879342 -157.780482) (xy 257.879342 -155.977082)
			)
		)
	)
	(zone
		(layer "In1.Cu")
		(hatch none 0.5)
		(connect_pads
			(clearance 0)
		)
		(min_thickness 0.25)
		(keepout
			(tracks not_allowed)
			(vias allowed)
			(pads allowed)
			(copperpour not_allowed)
			(footprints allowed)
		)
		(placement
			(enabled no)
			(sheetname "")
		)
		(fill
			(thermal_gap 0.5)
			(thermal_bridge_width 0.5)
			(island_removal_mode 0)
		)
		(polygon
			(pts
				(xy 248.820432 -4.920742) (xy 248.820432 -6.724142) (xy 249.379232 -6.724142) (xy 249.379232 -4.920742)
			)
		)
	)
	(zone
		(layer "In1.Cu")
		(hatch none 0.5)
		(connect_pads
			(clearance 0)
		)
		(min_thickness 0.25)
		(keepout
			(tracks not_allowed)
			(vias allowed)
			(pads allowed)
			(copperpour not_allowed)
			(footprints allowed)
		)
		(placement
			(enabled no)
			(sheetname "")
		)
		(fill
			(thermal_gap 0.5)
			(thermal_bridge_width 0.5)
			(island_removal_mode 0)
		)
		(polygon
			(pts
				(xy 82.119978 -132.174742) (xy 82.119978 -133.978142) (xy 82.678778 -133.978142) (xy 82.678778 -132.174742)
			)
		)
	)
	(zone
		(layer "In1.Cu")
		(hatch none 0.5)
		(connect_pads
			(clearance 0)
		)
		(min_thickness 0.25)
		(keepout
			(tracks not_allowed)
			(vias allowed)
			(pads allowed)
			(copperpour not_allowed)
			(footprints allowed)
		)
		(placement
			(enabled no)
			(sheetname "")
		)
		(fill
			(thermal_gap 0.5)
			(thermal_bridge_width 0.5)
			(island_removal_mode 0)
		)
		(polygon
			(pts
				(xy 150.120096 -141.775942) (xy 150.120096 -143.579342) (xy 150.678896 -143.579342) (xy 150.678896 -141.775942)
			)
		)
	)
	(zone
		(layer "In1.Cu")
		(hatch none 0.5)
		(connect_pads
			(clearance 0)
		)
		(min_thickness 0.25)
		(keepout
			(tracks not_allowed)
			(vias allowed)
			(pads allowed)
			(copperpour not_allowed)
			(footprints allowed)
		)
		(placement
			(enabled no)
			(sheetname "")
		)
		(fill
			(thermal_gap 0.5)
			(thermal_bridge_width 0.5)
			(island_removal_mode 0)
		)
		(polygon
			(pts
				(xy 449.14693 -111.011716) (xy 450.45503 -111.011716) (xy 450.45503 -113.399316) (xy 449.14693 -113.399316)
			)
		)
	)
	(zone
		(layer "In1.Cu")
		(hatch none 0.5)
		(connect_pads
			(clearance 0)
		)
		(min_thickness 0.25)
		(keepout
			(tracks not_allowed)
			(vias allowed)
			(pads allowed)
			(copperpour not_allowed)
			(footprints allowed)
		)
		(placement
			(enabled no)
			(sheetname "")
		)
		(fill
			(thermal_gap 0.5)
			(thermal_bridge_width 0.5)
			(island_removal_mode 0)
		)
		(polygon
			(pts
				(xy 459.487016 -50.872644) (xy 460.795116 -50.872644) (xy 460.795116 -52.879244) (xy 459.487016 -52.879244)
			)
		)
	)
	(zone
		(layer "In1.Cu")
		(hatch none 0.5)
		(connect_pads
			(clearance 0)
		)
		(min_thickness 0.25)
		(keepout
			(tracks not_allowed)
			(vias allowed)
			(pads allowed)
			(copperpour not_allowed)
			(footprints allowed)
		)
		(placement
			(enabled no)
			(sheetname "")
		)
		(fill
			(thermal_gap 0.5)
			(thermal_bridge_width 0.5)
			(island_removal_mode 0)
		)
		(polygon
			(pts
				(xy 228.420422 -141.775942) (xy 228.420422 -143.579342) (xy 228.979222 -143.579342) (xy 228.979222 -141.775942)
			)
		)
	)
	(zone
		(layer "In1.Cu")
		(hatch none 0.5)
		(connect_pads
			(clearance 0)
		)
		(min_thickness 0.25)
		(keepout
			(tracks not_allowed)
			(vias allowed)
			(pads allowed)
			(copperpour not_allowed)
			(footprints allowed)
		)
		(placement
			(enabled no)
			(sheetname "")
		)
		(fill
			(thermal_gap 0.5)
			(thermal_bridge_width 0.5)
			(island_removal_mode 0)
		)
		(polygon
			(pts
				(xy 67.669918 -136.774682) (xy 67.669918 -138.578082) (xy 68.228718 -138.578082) (xy 68.228718 -136.774682)
			)
		)
	)
	(zone
		(layer "In1.Cu")
		(hatch none 0.5)
		(connect_pads
			(clearance 0)
		)
		(min_thickness 0.25)
		(keepout
			(tracks not_allowed)
			(vias allowed)
			(pads allowed)
			(copperpour not_allowed)
			(footprints allowed)
		)
		(placement
			(enabled no)
			(sheetname "")
		)
		(fill
			(thermal_gap 0.5)
			(thermal_bridge_width 0.5)
			(island_removal_mode 0)
		)
		(polygon
			(pts
				(xy 237.770416 -19.121882) (xy 237.770416 -20.925282) (xy 238.329216 -20.925282) (xy 238.329216 -19.121882)
			)
		)
	)
	(zone
		(layer "In1.Cu")
		(hatch none 0.5)
		(connect_pads
			(clearance 0)
		)
		(min_thickness 0.25)
		(keepout
			(tracks not_allowed)
			(vias allowed)
			(pads allowed)
			(copperpour not_allowed)
			(footprints allowed)
		)
		(placement
			(enabled no)
			(sheetname "")
		)
		(fill
			(thermal_gap 0.5)
			(thermal_bridge_width 0.5)
			(island_removal_mode 0)
		)
		(polygon
			(pts
				(xy 254.770382 -9.520682) (xy 254.770382 -11.324082) (xy 255.329182 -11.324082) (xy 255.329182 -9.520682)
			)
		)
	)
	(zone
		(layer "In1.Cu")
		(hatch none 0.5)
		(connect_pads
			(clearance 0)
		)
		(min_thickness 0.25)
		(keepout
			(tracks not_allowed)
			(vias allowed)
			(pads allowed)
			(copperpour not_allowed)
			(footprints allowed)
		)
		(placement
			(enabled no)
			(sheetname "")
		)
		(fill
			(thermal_gap 0.5)
			(thermal_bridge_width 0.5)
			(island_removal_mode 0)
		)
		(polygon
			(pts
				(xy 220.77045 4.680458) (xy 220.77045 2.877058) (xy 221.32925 2.877058) (xy 221.32925 4.680458)
			)
		)
	)
	(zone
		(layer "In1.Cu")
		(hatch none 0.5)
		(connect_pads
			(clearance 0)
		)
		(min_thickness 0.25)
		(keepout
			(tracks not_allowed)
			(vias allowed)
			(pads allowed)
			(copperpour not_allowed)
			(footprints allowed)
		)
		(placement
			(enabled no)
			(sheetname "")
		)
		(fill
			(thermal_gap 0.5)
			(thermal_bridge_width 0.5)
			(island_removal_mode 0)
		)
		(polygon
			(pts
				(xy 218.220544 -151.377142) (xy 218.220544 -153.180542) (xy 218.779344 -153.180542) (xy 218.779344 -151.377142)
			)
		)
	)
	(zone
		(layer "In1.Cu")
		(hatch none 0.5)
		(connect_pads
			(clearance 0)
		)
		(min_thickness 0.25)
		(keepout
			(tracks not_allowed)
			(vias allowed)
			(pads allowed)
			(copperpour not_allowed)
			(footprints allowed)
		)
		(placement
			(enabled no)
			(sheetname "")
		)
		(fill
			(thermal_gap 0.5)
			(thermal_bridge_width 0.5)
			(island_removal_mode 0)
		)
		(polygon
			(pts
				(xy 41.319958 0.080518) (xy 41.319958 -1.722882) (xy 41.878758 -1.722882) (xy 41.878758 0.080518)
			)
		)
	)
	(zone
		(layer "In1.Cu")
		(hatch none 0.5)
		(connect_pads
			(clearance 0)
		)
		(min_thickness 0.25)
		(keepout
			(tracks not_allowed)
			(vias allowed)
			(pads allowed)
			(copperpour not_allowed)
			(footprints allowed)
		)
		(placement
			(enabled no)
			(sheetname "")
		)
		(fill
			(thermal_gap 0.5)
			(thermal_bridge_width 0.5)
			(island_removal_mode 0)
		)
		(polygon
			(pts
				(xy 148.420074 -4.920742) (xy 148.420074 -6.724142) (xy 148.978874 -6.724142) (xy 148.978874 -4.920742)
			)
		)
	)
	(zone
		(layer "In1.Cu")
		(hatch none 0.5)
		(connect_pads
			(clearance 0)
		)
		(min_thickness 0.25)
		(keepout
			(tracks not_allowed)
			(vias allowed)
			(pads allowed)
			(copperpour not_allowed)
			(footprints allowed)
		)
		(placement
			(enabled no)
			(sheetname "")
		)
		(fill
			(thermal_gap 0.5)
			(thermal_bridge_width 0.5)
			(island_removal_mode 0)
		)
		(polygon
			(pts
				(xy 31.969964 -19.121882) (xy 31.969964 -20.925282) (xy 32.528764 -20.925282) (xy 32.528764 -19.121882)
			)
		)
	)
	(zone
		(layer "In1.Cu")
		(hatch none 0.5)
		(connect_pads
			(clearance 0)
		)
		(min_thickness 0.25)
		(keepout
			(tracks not_allowed)
			(vias allowed)
			(pads allowed)
			(copperpour not_allowed)
			(footprints allowed)
		)
		(placement
			(enabled no)
			(sheetname "")
		)
		(fill
			(thermal_gap 0.5)
			(thermal_bridge_width 0.5)
			(island_removal_mode 0)
		)
		(polygon
			(pts
				(xy 213.970362 -146.375882) (xy 213.970362 -148.179282) (xy 214.529162 -148.179282) (xy 214.529162 -146.375882)
			)
		)
	)
	(zone
		(layer "In1.Cu")
		(hatch none 0.5)
		(connect_pads
			(clearance 0)
		)
		(min_thickness 0.25)
		(keepout
			(tracks not_allowed)
			(vias allowed)
			(pads allowed)
			(copperpour not_allowed)
			(footprints allowed)
		)
		(placement
			(enabled no)
			(sheetname "")
		)
		(fill
			(thermal_gap 0.5)
			(thermal_bridge_width 0.5)
			(island_removal_mode 0)
		)
		(polygon
			(pts
				(xy 224.170494 -4.920742) (xy 224.170494 -6.724142) (xy 224.729294 -6.724142) (xy 224.729294 -4.920742)
			)
		)
	)
	(zone
		(layer "In1.Cu")
		(hatch none 0.5)
		(connect_pads
			(clearance 0)
		)
		(min_thickness 0.25)
		(keepout
			(tracks not_allowed)
			(vias allowed)
			(pads allowed)
			(copperpour not_allowed)
			(footprints allowed)
		)
		(placement
			(enabled no)
			(sheetname "")
		)
		(fill
			(thermal_gap 0.5)
			(thermal_bridge_width 0.5)
			(island_removal_mode 0)
		)
		(polygon
			(pts
				(xy 101.670104 -136.774682) (xy 101.670104 -138.578082) (xy 102.228904 -138.578082) (xy 102.228904 -136.774682)
			)
		)
	)
	(zone
		(net "PVDDQ_GHJ")
		(layer "In1.Cu")
		(hatch none 0.5)
		(connect_pads
			(clearance 0.5)
		)
		(min_thickness 0.25)
		(fill yes
			(thermal_gap 0.5)
			(thermal_bridge_width 0.5)
			(island_removal_mode 0)
		)
		(polygon
			(pts
				(xy 78.310232 4.912868)
				(arc
					(start 78.251558 4.854194)
					(mid 78.229522 4.74341)
					(end 78.32344 4.680712)
				)
				(xy 78.429104 4.680712) (xy 78.429104 2.876804) (xy 77.869796 2.876804)
				(arc
					(start 77.869796 4.227068)
					(mid 77.807077 4.320934)
					(end 77.696314 4.29895)
				)
				(xy 77.662532 4.265168) (xy 77.662532 2.11074)
				(arc
					(start 77.664564 2.103628)
					(mid 77.680617 1.994154)
					(end 77.664564 1.88468)
				)
				(xy 77.662532 1.877568) (xy 77.662532 1.056386)
				(arc
					(start 77.664564 1.049274)
					(mid 77.680617 0.9398)
					(end 77.664564 0.830326)
				)
				(xy 77.662532 0.823214) (xy 77.662532 -2.960624) (xy 77.664818 -2.967736) (xy 77.67066 -2.989834)
				(xy 77.674724 -3.00609) (xy 77.724 -3.047238) (xy 77.77353 -3.00609)
				(arc
					(start 77.77734 -2.989072)
					(mid 77.824624 -2.873591)
					(end 77.906626 -2.779522)
				)
				(arc
					(start 77.906626 -2.779522)
					(mid 77.943588 -2.703463)
					(end 77.910182 -2.625852)
				)
				(arc
					(start 77.910182 -2.625852)
					(mid 78.14945 -2.006164)
					(end 78.388718 -2.625852)
				)
				(arc
					(start 78.388718 -2.625852)
					(mid 78.35548 -2.703459)
					(end 78.392274 -2.779522)
				)
				(arc
					(start 78.392274 -2.779522)
					(mid 78.509188 -2.946903)
					(end 78.523084 -3.150616)
				)
				(arc
					(start 78.523084 -3.150616)
					(mid 78.328672 -3.69493)
					(end 77.874114 -3.337814)
				)
				(arc
					(start 77.874114 -3.337814)
					(mid 77.814204 -3.25575)
					(end 77.778102 -3.160776)
				)
				(xy 77.774038 -3.144012) (xy 77.724762 -3.103118) (xy 77.675232 -3.144266) (xy 77.671422 -3.16103)
				(xy 77.664818 -3.186176) (xy 77.662532 -3.193542) (xy 77.662532 -3.64617)
				(arc
					(start 77.664564 -3.653282)
					(mid 77.680617 -3.762756)
					(end 77.664564 -3.87223)
				)
				(xy 77.662532 -3.879342) (xy 77.662532 -7.49046)
				(arc
					(start 77.664564 -7.497572)
					(mid 77.680617 -7.607046)
					(end 77.664564 -7.71652)
				)
				(xy 77.662532 -7.723632) (xy 77.662532 -8.544814)
				(arc
					(start 77.664564 -8.551926)
					(mid 77.680617 -8.6614)
					(end 77.664564 -8.770874)
				)
				(xy 77.662532 -8.777986) (xy 77.662532 -12.56157)
				(arc
					(start 77.664564 -12.568682)
					(mid 77.680617 -12.678156)
					(end 77.664564 -12.78763)
				)
				(xy 77.662532 -12.794742) (xy 77.662532 -13.24737)
				(arc
					(start 77.664564 -13.254482)
					(mid 77.680617 -13.363956)
					(end 77.664564 -13.47343)
				)
				(xy 77.662532 -13.480542) (xy 77.662532 -17.09166)
				(arc
					(start 77.664564 -17.098772)
					(mid 77.680617 -17.208246)
					(end 77.664564 -17.31772)
				)
				(xy 77.662532 -17.324832) (xy 77.662532 -18.146014)
				(arc
					(start 77.664564 -18.153126)
					(mid 77.680617 -18.2626)
					(end 77.664564 -18.372074)
				)
				(xy 77.662532 -18.379186) (xy 77.662532 -22.16277)
				(arc
					(start 77.664564 -22.169882)
					(mid 77.680617 -22.279356)
					(end 77.664564 -22.38883)
				)
				(xy 77.662532 -22.395942) (xy 77.662532 -22.895052)
				(arc
					(start 77.663548 -22.904704)
					(mid 77.668284 -22.965546)
					(end 77.663294 -23.02637)
				)
				(xy 77.662532 -23.030434) (xy 77.662532 -24.807164) (xy 77.677518 -24.82215) (xy 77.677518 -25.60955)
				(xy 81.417668 -29.3497) (xy 81.417668 -31.2674) (xy 83.932268 -33.782) (xy 83.932268 -34.5567) (xy 85.291168 -35.9156)
				(xy 85.291168 -46.1391) (xy 85.672168 -46.5201) (xy 85.672168 -48.2981) (xy 86.192868 -48.8188)
				(arc
					(start 86.192868 -51.156616)
					(mid 86.173341 -51.241333)
					(end 86.226396 -51.310286)
				)
				(arc
					(start 86.226396 -51.310286)
					(mid 86.405979 -51.729385)
					(end 86.02599 -51.981608)
				)
				(arc
					(start 86.02599 -51.981608)
					(mid 85.947235 -52.006953)
					(end 85.913468 -52.082446)
				)
				(arc
					(start 85.913468 -52.163218)
					(mid 85.947288 -52.238651)
					(end 86.02599 -52.264056)
				)
				(arc
					(start 86.02599 -52.264056)
					(mid 86.421054 -52.618132)
					(end 86.02599 -52.972208)
				)
				(arc
					(start 86.02599 -52.972208)
					(mid 85.947235 -52.997553)
					(end 85.913468 -53.073046)
				)
				(arc
					(start 85.913468 -53.153818)
					(mid 85.947288 -53.229251)
					(end 86.02599 -53.254656)
				)
				(arc
					(start 86.02599 -53.254656)
					(mid 86.421054 -53.608732)
					(end 86.02599 -53.962808)
				)
				(arc
					(start 86.02599 -53.962808)
					(mid 85.947235 -53.988153)
					(end 85.913468 -54.063646)
				)
				(arc
					(start 85.913468 -54.144926)
					(mid 85.947288 -54.220359)
					(end 86.02599 -54.245764)
				)
				(arc
					(start 86.02599 -54.245764)
					(mid 86.421054 -54.59984)
					(end 86.02599 -54.953916)
				)
				(arc
					(start 86.02599 -54.953916)
					(mid 85.947235 -54.979261)
					(end 85.913468 -55.054754)
				)
				(arc
					(start 85.913468 -56.126126)
					(mid 85.947288 -56.201559)
					(end 86.02599 -56.226964)
				)
				(arc
					(start 86.02599 -56.226964)
					(mid 86.421054 -56.58104)
					(end 86.02599 -56.935116)
				)
				(arc
					(start 86.02599 -56.935116)
					(mid 85.947235 -56.960461)
					(end 85.913468 -57.035954)
				)
				(xy 85.913468 -57.8866) (xy 86.383368 -58.3565) (xy 86.383368 -58.402474)
				(arc
					(start 86.38794 -58.412634)
					(mid 86.420897 -58.56224)
					(end 86.38794 -58.711846)
				)
				(xy 86.383368 -58.722006) (xy 86.383368 -59.393074)
				(arc
					(start 86.38794 -59.403234)
					(mid 86.420897 -59.55284)
					(end 86.38794 -59.702446)
				)
				(xy 86.383368 -59.712606) (xy 86.383368 -60.383674)
				(arc
					(start 86.38794 -60.393834)
					(mid 86.420897 -60.54344)
					(end 86.38794 -60.693046)
				)
				(xy 86.383368 -60.703206) (xy 86.383368 -61.374274)
				(arc
					(start 86.38794 -61.384434)
					(mid 86.420897 -61.53404)
					(end 86.38794 -61.683646)
				)
				(xy 86.383368 -61.693806) (xy 86.383368 -62.3189) (xy 86.764114 -62.699646)
				(arc
					(start 86.794848 -62.687454)
					(mid 87.010743 -62.6745)
					(end 87.19439 -62.7888)
				)
				(arc
					(start 87.354156 -62.7888)
					(mid 87.4376 -62.744795)
					(end 87.448898 -62.651132)
				)
				(arc
					(start 87.448898 -62.651132)
					(mid 87.781892 -62.16843)
					(end 88.114886 -62.651132)
				)
				(arc
					(start 88.114886 -62.651132)
					(mid 88.126173 -62.744802)
					(end 88.209628 -62.7888)
				)
				(arc
					(start 88.369394 -62.7888)
					(mid 88.640412 -62.663654)
					(end 88.91143 -62.7888)
				)
				(arc
					(start 89.070942 -62.7888)
					(mid 89.154386 -62.744795)
					(end 89.165684 -62.651132)
				)
				(arc
					(start 89.165684 -62.651132)
					(mid 89.498678 -62.16843)
					(end 89.831672 -62.651132)
				)
				(arc
					(start 89.831672 -62.651132)
					(mid 89.842959 -62.744802)
					(end 89.926414 -62.7888)
				)
				(arc
					(start 90.08618 -62.7888)
					(mid 90.357198 -62.663654)
					(end 90.628216 -62.7888)
				)
				(arc
					(start 90.787982 -62.7888)
					(mid 90.871426 -62.744795)
					(end 90.882724 -62.651132)
				)
				(arc
					(start 90.882724 -62.651132)
					(mid 91.215718 -62.16843)
					(end 91.548712 -62.651132)
				)
				(arc
					(start 91.548712 -62.651132)
					(mid 91.559999 -62.744802)
					(end 91.643454 -62.7888)
				)
				(arc
					(start 91.80322 -62.7888)
					(mid 92.024843 -62.667097)
					(end 92.271342 -62.723268)
				)
				(xy 92.30614 -62.746128) (xy 92.580206 -62.472062)
				(arc
					(start 92.583254 -62.456822)
					(mid 92.865291 -62.175068)
					(end 93.23197 -62.3316)
				)
				(xy 94.219268 -62.3316)
				(arc
					(start 94.529656 -62.021212)
					(mid 94.557668 -61.931731)
					(end 94.500446 -61.857382)
				)
				(arc
					(start 94.500446 -61.857382)
					(mid 94.48723 -61.217136)
					(end 94.999556 -61.60135)
				)
				(arc
					(start 94.999556 -61.60135)
					(mid 95.021073 -61.685174)
					(end 95.099378 -61.722)
				)
				(xy 95.32747 -61.722)
				(arc
					(start 95.3389 -61.715904)
					(mid 95.508318 -61.673017)
					(end 95.677736 -61.715904)
				)
				(xy 95.689166 -61.722) (xy 95.730568 -61.722) (xy 96.027748 -61.42482)
				(arc
					(start 96.031558 -61.414152)
					(mid 96.115059 -61.282261)
					(end 96.24695 -61.19876)
				)
				(xy 96.257618 -61.19495)
				(arc
					(start 96.383094 -61.069474)
					(mid 96.4071 -60.964635)
					(end 96.323404 -60.897008)
				)
				(arc
					(start 96.323404 -60.897008)
					(mid 96.14136 -60.267657)
					(end 96.72193 -60.571126)
				)
				(arc
					(start 96.72193 -60.571126)
					(mid 96.748666 -60.648038)
					(end 96.823276 -60.6806)
				)
				(arc
					(start 97.62744 -60.6806)
					(mid 97.702013 -60.648004)
					(end 97.728786 -60.571126)
				)
				(arc
					(start 97.728786 -60.571126)
					(mid 98.083878 -60.18727)
					(end 98.43897 -60.571126)
				)
				(arc
					(start 98.43897 -60.571126)
					(mid 98.465706 -60.648038)
					(end 98.540316 -60.6806)
				)
				(arc
					(start 99.344226 -60.6806)
					(mid 99.418799 -60.648004)
					(end 99.445572 -60.571126)
				)
				(arc
					(start 99.445572 -60.571126)
					(mid 99.800664 -60.18727)
					(end 100.155756 -60.571126)
				)
				(arc
					(start 100.155756 -60.571126)
					(mid 100.182492 -60.648038)
					(end 100.257102 -60.6806)
				)
				(arc
					(start 101.061266 -60.6806)
					(mid 101.135839 -60.648004)
					(end 101.162612 -60.571126)
				)
				(arc
					(start 101.162612 -60.571126)
					(mid 101.728973 -60.256696)
					(end 101.596444 -60.890658)
				)
				(arc
					(start 101.596444 -60.890658)
					(mid 101.521415 -60.961588)
					(end 101.547168 -61.0616)
				)
				(xy 101.747828 -61.26226)
				(arc
					(start 101.749352 -61.26353)
					(mid 101.770234 -61.282913)
					(end 101.789484 -61.303916)
				)
				(xy 101.915468 -61.4299) (xy 103.693468 -61.4299) (xy 104.815132 -60.308236) (xy 104.815132 -50.105564)
				(xy 105.158032 -49.762664) (xy 105.158032 -41.021) (xy 104.976168 -40.839136) (xy 104.976168 -36.0934)
				(xy 105.20426 -35.865308) (xy 105.20426 -33.781492) (xy 113.782856 -25.202896)
				(arc
					(start 113.782856 -23.138892)
					(mid 113.611698 -22.8346)
					(end 113.782856 -22.530308)
				)
				(arc
					(start 113.782856 -21.98116)
					(mid 113.5909 -21.665184)
					(end 113.782856 -21.349208)
				)
				(xy 113.782856 -19.225006)
				(arc
					(start 113.827306 -19.180556)
					(mid 113.855503 -19.09044)
					(end 113.797334 -19.015964)
				)
				(arc
					(start 113.797334 -19.015964)
					(mid 113.591646 -18.741663)
					(end 113.712752 -18.420842)
				)
				(arc
					(start 113.712752 -18.420842)
					(mid 113.748108 -18.345682)
					(end 113.715546 -18.269204)
				)
				(arc
					(start 113.715546 -18.269204)
					(mid 113.601257 -17.997044)
					(end 113.731548 -17.732248)
				)
				(arc
					(start 113.731548 -17.732248)
					(mid 113.768627 -17.65287)
					(end 113.730278 -17.574006)
				)
				(arc
					(start 113.730278 -17.574006)
					(mid 113.610742 -17.190921)
					(end 113.923826 -16.939768)
				)
				(arc
					(start 113.923826 -16.939768)
					(mid 113.990562 -16.90746)
					(end 114.017552 -16.838422)
				)
				(xy 114.017552 -15.957042) (xy 113.92535 -15.86484) (xy 113.782856 -15.86484)
				(arc
					(start 113.782856 -14.222984)
					(mid 113.657562 -13.940282)
					(end 113.782856 -13.65758)
				)
				(xy 113.782856 -13.28547)
				(arc
					(start 113.75517 -13.271246)
					(mid 113.560845 -12.954)
					(end 113.75517 -12.636754)
				)
				(xy 113.782856 -12.62253) (xy 113.782856 -12.287758)
				(arc
					(start 113.754408 -12.273788)
					(mid 113.541757 -11.93165)
					(end 113.754408 -11.589512)
				)
				(xy 113.782856 -11.575542) (xy 113.782856 -9.526524)
				(arc
					(start 113.741962 -9.518396)
					(mid 113.584179 -9.4475)
					(end 113.473992 -9.31418)
				)
				(arc
					(start 113.473992 -9.31418)
					(mid 113.3867 -9.258046)
					(end 113.295684 -9.30783)
				)
				(arc
					(start 113.295684 -9.30783)
					(mid 113.244641 -9.374149)
					(end 113.179098 -9.426194)
				)
				(xy 113.154714 -9.440926) (xy 113.154714 -9.520428) (xy 113.279428 -9.520428) (xy 113.279428 -11.324336)
				(xy 112.719612 -11.324336) (xy 112.719612 -9.520428) (xy 112.845342 -9.520428) (xy 112.845342 -9.440926)
				(arc
					(start 112.820958 -9.426194)
					(mid 112.762188 -8.885257)
					(end 113.300256 -8.9662)
				)
				(arc
					(start 113.300256 -8.9662)
					(mid 113.389813 -9.018341)
					(end 113.478564 -8.964676)
				)
				(arc
					(start 113.478564 -8.964676)
					(mid 113.579035 -8.844432)
					(end 113.719356 -8.774684)
				)
				(xy 113.75263 -8.75792) (xy 113.782856 -8.744458) (xy 113.782856 -8.45058)
				(arc
					(start 113.74882 -8.438896)
					(mid 113.537715 -8.240382)
					(end 113.544096 -7.950708)
				)
				(arc
					(start 113.544096 -7.950708)
					(mid 113.468871 -7.691636)
					(end 113.58372 -7.447534)
				)
				(arc
					(start 113.58372 -7.447534)
					(mid 113.599221 -7.412668)
					(end 113.586006 -7.376922)
				)
				(arc
					(start 113.586006 -7.376922)
					(mid 113.506304 -7.042366)
					(end 113.746788 -6.796532)
				)
				(xy 113.782856 -6.78561)
				(arc
					(start 113.782856 -4.617974)
					(mid 113.637065 -4.318)
					(end 113.782856 -4.018026)
				)
				(xy 113.782856 -3.82778)
				(arc
					(start 113.74882 -3.816096)
					(mid 113.521491 -3.569598)
					(end 113.599722 -3.24358)
				)
				(arc
					(start 113.599722 -3.24358)
					(mid 113.62505 -3.17088)
					(end 113.592102 -3.10134)
				)
				(arc
					(start 113.592102 -3.10134)
					(mid 113.477963 -2.731502)
					(end 113.745772 -2.452116)
				)
				(xy 113.782856 -2.441702) (xy 113.782856 0.090424) (xy 113.78438 0.091948) (xy 113.78438 1.29794)
				(xy 113.88725 1.40081) (xy 113.88725 1.482598) (xy 113.829592 1.482598)
				(arc
					(start 113.822734 1.48082)
					(mid 113.37155 1.798189)
					(end 113.772696 2.17678)
				)
				(arc
					(start 113.772696 2.17678)
					(mid 113.852803 2.201286)
					(end 113.88725 2.277618)
				)
				(xy 113.88725 4.19862)
				(arc
					(start 113.452656 4.633214)
					(mid 113.342111 4.65505)
					(end 113.279428 4.561332)
				)
				(xy 113.279428 2.876804) (xy 113.171986 2.876804) (xy 113.171986 2.798572)
				(arc
					(start 113.194846 2.783332)
					(mid 112.99952 2.129596)
					(end 112.804194 2.783332)
				)
				(xy 112.827054 2.798572) (xy 112.827054 2.876804) (xy 112.719612 2.876804) (xy 112.719612 4.680712)
				(arc
					(start 113.159794 4.680712)
					(mid 113.25366 4.743431)
					(end 113.231676 4.854194)
				)
				(xy 113.173002 4.912868) (xy 110.937548 4.912868) (xy 110.92688 4.911598)
				(arc
					(start 110.926372 4.911598)
					(mid 110.843568 4.901833)
					(end 110.760764 4.911598)
				)
				(xy 110.754922 4.912868) (xy 107.508548 4.912868) (xy 107.49788 4.911598)
				(arc
					(start 107.497372 4.911598)
					(mid 107.414568 4.901833)
					(end 107.331764 4.911598)
				)
				(xy 107.325922 4.912868) (xy 103.952548 4.912868) (xy 103.94188 4.911598)
				(arc
					(start 103.941372 4.911598)
					(mid 103.858568 4.901833)
					(end 103.775764 4.911598)
				)
				(xy 103.769922 4.912868) (xy 100.142548 4.912868) (xy 100.13188 4.911598)
				(arc
					(start 100.131372 4.911598)
					(mid 100.048568 4.901833)
					(end 99.965764 4.911598)
				)
				(xy 99.959922 4.912868) (xy 83.067144 4.912868)
				(arc
					(start 83.057238 4.90855)
					(mid 82.903568 4.876237)
					(end 82.749898 4.90855)
				)
				(xy 82.739992 4.912868)
			)
		)
	)
	(zone
		(layer "In1.Cu")
		(hatch none 0.5)
		(connect_pads
			(clearance 0)
		)
		(min_thickness 0.25)
		(keepout
			(tracks not_allowed)
			(vias allowed)
			(pads allowed)
			(copperpour not_allowed)
			(footprints allowed)
		)
		(placement
			(enabled no)
			(sheetname "")
		)
		(fill
			(thermal_gap 0.5)
			(thermal_bridge_width 0.5)
			(island_removal_mode 0)
		)
		(polygon
			(pts
				(xy 254.770382 -19.121882) (xy 254.770382 -20.925282) (xy 255.329182 -20.925282) (xy 255.329182 -19.121882)
			)
		)
	)
	(zone
		(layer "In1.Cu")
		(hatch none 0.5)
		(connect_pads
			(clearance 0)
		)
		(min_thickness 0.25)
		(keepout
			(tracks not_allowed)
			(vias allowed)
			(pads allowed)
			(copperpour not_allowed)
			(footprints allowed)
		)
		(placement
			(enabled no)
			(sheetname "")
		)
		(fill
			(thermal_gap 0.5)
			(thermal_bridge_width 0.5)
			(island_removal_mode 0)
		)
		(polygon
			(pts
				(xy 58.319924 -155.977082) (xy 58.319924 -157.780482) (xy 58.878724 -157.780482) (xy 58.878724 -155.977082)
			)
		)
	)
	(zone
		(layer "In1.Cu")
		(hatch none 0.5)
		(connect_pads
			(clearance 0)
		)
		(min_thickness 0.25)
		(keepout
			(tracks not_allowed)
			(vias allowed)
			(pads allowed)
			(copperpour not_allowed)
			(footprints allowed)
		)
		(placement
			(enabled no)
			(sheetname "")
		)
		(fill
			(thermal_gap 0.5)
			(thermal_bridge_width 0.5)
			(island_removal_mode 0)
		)
		(polygon
			(pts
				(xy 150.120096 -132.174742) (xy 150.120096 -133.978142) (xy 150.678896 -133.978142) (xy 150.678896 -132.174742)
			)
		)
	)
	(zone
		(layer "In1.Cu")
		(hatch none 0.5)
		(connect_pads
			(clearance 0)
		)
		(min_thickness 0.25)
		(keepout
			(tracks not_allowed)
			(vias allowed)
			(pads allowed)
			(copperpour not_allowed)
			(footprints allowed)
		)
		(placement
			(enabled no)
			(sheetname "")
		)
		(fill
			(thermal_gap 0.5)
			(thermal_bridge_width 0.5)
			(island_removal_mode 0)
		)
		(polygon
			(pts
				(xy 449.887086 -50.872644) (xy 451.194932 -50.872644) (xy 451.194932 -52.879244) (xy 449.887086 -52.879244)
			)
		)
	)
	(zone
		(layer "In1.Cu")
		(hatch none 0.5)
		(connect_pads
			(clearance 0)
		)
		(min_thickness 0.25)
		(keepout
			(tracks not_allowed)
			(vias allowed)
			(pads allowed)
			(copperpour not_allowed)
			(footprints allowed)
		)
		(placement
			(enabled no)
			(sheetname "")
		)
		(fill
			(thermal_gap 0.5)
			(thermal_bridge_width 0.5)
			(island_removal_mode 0)
		)
		(polygon
			(pts
				(xy 138.219942 0.080518) (xy 138.219942 -1.722882) (xy 138.778742 -1.722882) (xy 138.778742 0.080518)
			)
		)
	)
	(zone
		(layer "In1.Cu")
		(hatch none 0.5)
		(connect_pads
			(clearance 0)
		)
		(min_thickness 0.25)
		(keepout
			(tracks not_allowed)
			(vias allowed)
			(pads allowed)
			(copperpour not_allowed)
			(footprints allowed)
		)
		(placement
			(enabled no)
			(sheetname "")
		)
		(fill
			(thermal_gap 0.5)
			(thermal_bridge_width 0.5)
			(island_removal_mode 0)
		)
		(polygon
			(pts
				(xy 222.470472 -132.174742) (xy 222.470472 -133.978142) (xy 223.029272 -133.978142) (xy 223.029272 -132.174742)
			)
		)
	)
	(zone
		(layer "In1.Cu")
		(hatch none 0.5)
		(connect_pads
			(clearance 0)
		)
		(min_thickness 0.25)
		(keepout
			(tracks not_allowed)
			(vias allowed)
			(pads allowed)
			(copperpour not_allowed)
			(footprints allowed)
		)
		(placement
			(enabled no)
			(sheetname "")
		)
		(fill
			(thermal_gap 0.5)
			(thermal_bridge_width 0.5)
			(island_removal_mode 0)
		)
		(polygon
			(pts
				(xy 112.72012 4.680458) (xy 112.72012 2.877058) (xy 113.27892 2.877058) (xy 113.27892 4.680458)
			)
		)
	)
	(zone
		(layer "In1.Cu")
		(hatch none 0.5)
		(connect_pads
			(clearance 0)
		)
		(min_thickness 0.25)
		(keepout
			(tracks not_allowed)
			(vias allowed)
			(pads allowed)
			(copperpour not_allowed)
			(footprints allowed)
		)
		(placement
			(enabled no)
			(sheetname "")
		)
		(fill
			(thermal_gap 0.5)
			(thermal_bridge_width 0.5)
			(island_removal_mode 0)
		)
		(polygon
			(pts
				(xy 105.070148 -19.121882) (xy 105.070148 -20.925282) (xy 105.628948 -20.925282) (xy 105.628948 -19.121882)
			)
		)
	)
	(zone
		(layer "In1.Cu")
		(hatch none 0.5)
		(connect_pads
			(clearance 0)
		)
		(min_thickness 0.25)
		(keepout
			(tracks not_allowed)
			(vias allowed)
			(pads allowed)
			(copperpour not_allowed)
			(footprints allowed)
		)
		(placement
			(enabled no)
			(sheetname "")
		)
		(fill
			(thermal_gap 0.5)
			(thermal_bridge_width 0.5)
			(island_removal_mode 0)
		)
		(polygon
			(pts
				(xy 115.270026 -155.977082) (xy 115.270026 -157.780482) (xy 115.828826 -157.780482) (xy 115.828826 -155.977082)
			)
		)
	)
	(zone
		(layer "In1.Cu")
		(hatch none 0.5)
		(connect_pads
			(clearance 0)
		)
		(min_thickness 0.25)
		(keepout
			(tracks not_allowed)
			(vias allowed)
			(pads allowed)
			(copperpour not_allowed)
			(footprints allowed)
		)
		(placement
			(enabled no)
			(sheetname "")
		)
		(fill
			(thermal_gap 0.5)
			(thermal_bridge_width 0.5)
			(island_removal_mode 0)
		)
		(polygon
			(pts
				(xy 247.12041 -155.977082) (xy 247.12041 -157.780482) (xy 247.67921 -157.780482) (xy 247.67921 -155.977082)
			)
		)
	)
	(zone
		(layer "In1.Cu")
		(hatch none 0.5)
		(connect_pads
			(clearance 0)
		)
		(min_thickness 0.25)
		(keepout
			(tracks not_allowed)
			(vias allowed)
			(pads allowed)
			(copperpour not_allowed)
			(footprints allowed)
		)
		(placement
			(enabled no)
			(sheetname "")
		)
		(fill
			(thermal_gap 0.5)
			(thermal_bridge_width 0.5)
			(island_removal_mode 0)
		)
		(polygon
			(pts
				(xy 304.070512 4.680458) (xy 304.070512 2.877058) (xy 304.629312 2.877058) (xy 304.629312 4.680458)
			)
		)
	)
	(zone
		(layer "In1.Cu")
		(hatch none 0.5)
		(connect_pads
			(clearance 0)
		)
		(min_thickness 0.25)
		(keepout
			(tracks not_allowed)
			(vias allowed)
			(pads allowed)
			(copperpour not_allowed)
			(footprints allowed)
		)
		(placement
			(enabled no)
			(sheetname "")
		)
		(fill
			(thermal_gap 0.5)
			(thermal_bridge_width 0.5)
			(island_removal_mode 0)
		)
		(polygon
			(pts
				(xy 281.97048 -155.977082) (xy 281.97048 -157.780482) (xy 282.52928 -157.780482) (xy 282.52928 -155.977082)
			)
		)
	)
	(zone
		(layer "In1.Cu")
		(hatch none 0.5)
		(connect_pads
			(clearance 0)
		)
		(min_thickness 0.25)
		(keepout
			(tracks not_allowed)
			(vias allowed)
			(pads allowed)
			(copperpour not_allowed)
			(footprints allowed)
		)
		(placement
			(enabled no)
			(sheetname "")
		)
		(fill
			(thermal_gap 0.5)
			(thermal_bridge_width 0.5)
			(island_removal_mode 0)
		)
		(polygon
			(pts
				(xy 83.82 -132.174742) (xy 83.82 -133.978142) (xy 84.3788 -133.978142) (xy 84.3788 -132.174742)
			)
		)
	)
	(zone
		(net "AGND_HSC")
		(layer "In1.Cu")
		(hatch none 0.5)
		(connect_pads
			(clearance 0.5)
		)
		(min_thickness 0.25)
		(fill yes
			(thermal_gap 0.5)
			(thermal_bridge_width 0.5)
			(island_removal_mode 0)
		)
		(polygon
			(pts
				(xy 23.603458 -86.048342) (xy 24.765 -84.8868) (xy 24.765 -72.5424) (xy 24.765 -69.662802) (xy 23.540974 -68.438776)
				(xy 19.655282 -68.438776) (xy 18.193258 -69.9008) (xy 18.193258 -71.221092) (xy 18.193258 -71.269098)
				(xy 17.656556 -71.8058) (xy 17.60855 -71.8058) (xy 12.945618 -71.8058) (xy 12.814046 -71.937372)
				(xy 12.814046 -72.586596) (xy 12.608306 -72.792336) (xy 12.040616 -72.792336) (xy 11.702034 -73.130918)
				(xy 11.702034 -77.335634) (xy 12.827 -78.4606) (xy 12.827 -84.930996) (xy 13.156438 -85.260434)
				(xy 13.944346 -86.048342)
			)
		)
	)
	(zone
		(layer "In1.Cu")
		(hatch none 0.5)
		(connect_pads
			(clearance 0)
		)
		(min_thickness 0.25)
		(keepout
			(tracks not_allowed)
			(vias allowed)
			(pads allowed)
			(copperpour not_allowed)
			(footprints allowed)
		)
		(placement
			(enabled no)
			(sheetname "")
		)
		(fill
			(thermal_gap 0.5)
			(thermal_bridge_width 0.5)
			(island_removal_mode 0)
		)
		(polygon
			(pts
				(xy 111.020098 -136.774682) (xy 111.020098 -138.578082) (xy 111.578898 -138.578082) (xy 111.578898 -136.774682)
			)
		)
	)
	(zone
		(layer "In1.Cu")
		(hatch none 0.5)
		(connect_pads
			(clearance 0)
		)
		(min_thickness 0.25)
		(keepout
			(tracks not_allowed)
			(vias allowed)
			(pads allowed)
			(copperpour not_allowed)
			(footprints allowed)
		)
		(placement
			(enabled no)
			(sheetname "")
		)
		(fill
			(thermal_gap 0.5)
			(thermal_bridge_width 0.5)
			(island_removal_mode 0)
		)
		(polygon
			(pts
				(xy 63.41999 4.680458) (xy 63.41999 2.877058) (xy 63.97879 2.877058) (xy 63.97879 4.680458)
			)
		)
	)
	(zone
		(layer "In1.Cu")
		(hatch none 0.5)
		(connect_pads
			(clearance 0)
		)
		(min_thickness 0.25)
		(keepout
			(tracks not_allowed)
			(vias allowed)
			(pads allowed)
			(copperpour not_allowed)
			(footprints allowed)
		)
		(placement
			(enabled no)
			(sheetname "")
		)
		(fill
			(thermal_gap 0.5)
			(thermal_bridge_width 0.5)
			(island_removal_mode 0)
		)
		(polygon
			(pts
				(xy 306.620418 -19.121882) (xy 306.620418 -20.925282) (xy 307.179218 -20.925282) (xy 307.179218 -19.121882)
			)
		)
	)
	(zone
		(layer "In1.Cu")
		(hatch none 0.5)
		(connect_pads
			(clearance 0)
		)
		(min_thickness 0.25)
		(keepout
			(tracks not_allowed)
			(vias allowed)
			(pads allowed)
			(copperpour not_allowed)
			(footprints allowed)
		)
		(placement
			(enabled no)
			(sheetname "")
		)
		(fill
			(thermal_gap 0.5)
			(thermal_bridge_width 0.5)
			(island_removal_mode 0)
		)
		(polygon
			(pts
				(xy 55.770018 4.680458) (xy 55.770018 2.877058) (xy 56.328818 2.877058) (xy 56.328818 4.680458)
			)
		)
	)
	(zone
		(layer "In1.Cu")
		(hatch none 0.5)
		(connect_pads
			(clearance 0)
		)
		(min_thickness 0.25)
		(keepout
			(tracks not_allowed)
			(vias allowed)
			(pads allowed)
			(copperpour not_allowed)
			(footprints allowed)
		)
		(placement
			(enabled no)
			(sheetname "")
		)
		(fill
			(thermal_gap 0.5)
			(thermal_bridge_width 0.5)
			(island_removal_mode 0)
		)
		(polygon
			(pts
				(xy 208.87055 -151.377142) (xy 208.87055 -153.180542) (xy 209.42935 -153.180542) (xy 209.42935 -151.377142)
			)
		)
	)
	(zone
		(layer "In1.Cu")
		(hatch none 0.5)
		(connect_pads
			(clearance 0)
		)
		(min_thickness 0.25)
		(keepout
			(tracks not_allowed)
			(vias allowed)
			(pads allowed)
			(copperpour not_allowed)
			(footprints allowed)
		)
		(placement
			(enabled no)
			(sheetname "")
		)
		(fill
			(thermal_gap 0.5)
			(thermal_bridge_width 0.5)
			(island_removal_mode 0)
		)
		(polygon
			(pts
				(xy 226.7204 -19.121882) (xy 226.7204 -20.925282) (xy 227.2792 -20.925282) (xy 227.2792 -19.121882)
			)
		)
	)
	(zone
		(layer "In1.Cu")
		(hatch none 0.5)
		(connect_pads
			(clearance 0)
		)
		(min_thickness 0.25)
		(keepout
			(tracks not_allowed)
			(vias allowed)
			(pads allowed)
			(copperpour not_allowed)
			(footprints allowed)
		)
		(placement
			(enabled no)
			(sheetname "")
		)
		(fill
			(thermal_gap 0.5)
			(thermal_bridge_width 0.5)
			(island_removal_mode 0)
		)
		(polygon
			(pts
				(xy 382.022604 -32.618426) (xy 383.572004 -32.618426) (xy 383.572004 -33.423352) (xy 382.022604 -33.423352)
			)
		)
	)
	(zone
		(layer "In1.Cu")
		(hatch none 0.5)
		(connect_pads
			(clearance 0)
		)
		(min_thickness 0.25)
		(keepout
			(tracks not_allowed)
			(vias allowed)
			(pads allowed)
			(copperpour not_allowed)
			(footprints allowed)
		)
		(placement
			(enabled no)
			(sheetname "")
		)
		(fill
			(thermal_gap 0.5)
			(thermal_bridge_width 0.5)
			(island_removal_mode 0)
		)
		(polygon
			(pts
				(xy 274.320508 -132.174742) (xy 274.320508 -133.978142) (xy 274.879308 -133.978142) (xy 274.879308 -132.174742)
			)
		)
	)
	(zone
		(layer "In1.Cu")
		(hatch none 0.5)
		(connect_pads
			(clearance 0)
		)
		(min_thickness 0.25)
		(keepout
			(tracks not_allowed)
			(vias allowed)
			(pads allowed)
			(copperpour not_allowed)
			(footprints allowed)
		)
		(placement
			(enabled no)
			(sheetname "")
		)
		(fill
			(thermal_gap 0.5)
			(thermal_bridge_width 0.5)
			(island_removal_mode 0)
		)
		(polygon
			(pts
				(xy 247.970548 -19.121882) (xy 248.529348 -19.121882) (xy 248.529348 -20.925282) (xy 247.970548 -20.925282)
			)
		)
	)
	(zone
		(layer "In1.Cu")
		(hatch none 0.5)
		(connect_pads
			(clearance 0)
		)
		(min_thickness 0.25)
		(keepout
			(tracks not_allowed)
			(vias allowed)
			(pads allowed)
			(copperpour not_allowed)
			(footprints allowed)
		)
		(placement
			(enabled no)
			(sheetname "")
		)
		(fill
			(thermal_gap 0.5)
			(thermal_bridge_width 0.5)
			(island_removal_mode 0)
		)
		(polygon
			(pts
				(xy 105.070148 -151.377142) (xy 105.070148 -153.180542) (xy 105.628948 -153.180542) (xy 105.628948 -151.377142)
			)
		)
	)
	(zone
		(layer "In1.Cu")
		(hatch none 0.5)
		(connect_pads
			(clearance 0)
		)
		(min_thickness 0.25)
		(keepout
			(tracks not_allowed)
			(vias allowed)
			(pads allowed)
			(copperpour not_allowed)
			(footprints allowed)
		)
		(placement
			(enabled no)
			(sheetname "")
		)
		(fill
			(thermal_gap 0.5)
			(thermal_bridge_width 0.5)
			(island_removal_mode 0)
		)
		(polygon
			(pts
				(xy 456.287124 -50.872644) (xy 457.59497 -50.872644) (xy 457.59497 -52.879244) (xy 456.287124 -52.879244)
			)
		)
	)
	(zone
		(layer "In1.Cu")
		(hatch none 0.5)
		(connect_pads
			(clearance 0)
		)
		(min_thickness 0.25)
		(keepout
			(tracks not_allowed)
			(vias allowed)
			(pads allowed)
			(copperpour not_allowed)
			(footprints allowed)
		)
		(placement
			(enabled no)
			(sheetname "")
		)
		(fill
			(thermal_gap 0.5)
			(thermal_bridge_width 0.5)
			(island_removal_mode 0)
		)
		(polygon
			(pts
				(xy 105.070148 4.680458) (xy 105.070148 2.877058) (xy 105.628948 2.877058) (xy 105.628948 4.680458)
			)
		)
	)
	(zone
		(layer "In1.Cu")
		(hatch none 0.5)
		(connect_pads
			(clearance 0)
		)
		(min_thickness 0.25)
		(keepout
			(tracks not_allowed)
			(vias allowed)
			(pads allowed)
			(copperpour not_allowed)
			(footprints allowed)
		)
		(placement
			(enabled no)
			(sheetname "")
		)
		(fill
			(thermal_gap 0.5)
			(thermal_bridge_width 0.5)
			(island_removal_mode 0)
		)
		(polygon
			(pts
				(xy 238.620554 -19.121882) (xy 238.620554 -20.925282) (xy 239.179354 -20.925282) (xy 239.179354 -19.121882)
			)
		)
	)
	(zone
		(layer "In1.Cu")
		(hatch none 0.5)
		(connect_pads
			(clearance 0)
		)
		(min_thickness 0.25)
		(keepout
			(tracks not_allowed)
			(vias allowed)
			(pads allowed)
			(copperpour not_allowed)
			(footprints allowed)
		)
		(placement
			(enabled no)
			(sheetname "")
		)
		(fill
			(thermal_gap 0.5)
			(thermal_bridge_width 0.5)
			(island_removal_mode 0)
		)
		(polygon
			(pts
				(xy 244.570504 -14.521942) (xy 244.570504 -16.325342) (xy 245.129304 -16.325342) (xy 245.129304 -14.521942)
			)
		)
	)
	(zone
		(layer "In1.Cu")
		(hatch none 0.5)
		(connect_pads
			(clearance 0)
		)
		(min_thickness 0.25)
		(keepout
			(tracks not_allowed)
			(vias allowed)
			(pads allowed)
			(copperpour not_allowed)
			(footprints allowed)
		)
		(placement
			(enabled no)
			(sheetname "")
		)
		(fill
			(thermal_gap 0.5)
			(thermal_bridge_width 0.5)
			(island_removal_mode 0)
		)
		(polygon
			(pts
				(xy 77.87005 -4.920742) (xy 77.87005 -6.724142) (xy 78.42885 -6.724142) (xy 78.42885 -4.920742)
			)
		)
	)
	(zone
		(layer "In1.Cu")
		(hatch none 0.5)
		(connect_pads
			(clearance 0)
		)
		(min_thickness 0.25)
		(keepout
			(tracks not_allowed)
			(vias allowed)
			(pads allowed)
			(copperpour not_allowed)
			(footprints allowed)
		)
		(placement
			(enabled no)
			(sheetname "")
		)
		(fill
			(thermal_gap 0.5)
			(thermal_bridge_width 0.5)
			(island_removal_mode 0)
		)
		(polygon
			(pts
				(xy 296.42054 4.680458) (xy 296.42054 2.877058) (xy 296.97934 2.877058) (xy 296.97934 4.680458)
			)
		)
	)
	(zone
		(layer "In1.Cu")
		(hatch none 0.5)
		(connect_pads
			(clearance 0)
		)
		(min_thickness 0.25)
		(keepout
			(tracks not_allowed)
			(vias allowed)
			(pads allowed)
			(copperpour not_allowed)
			(footprints allowed)
		)
		(placement
			(enabled no)
			(sheetname "")
		)
		(fill
			(thermal_gap 0.5)
			(thermal_bridge_width 0.5)
			(island_removal_mode 0)
		)
		(polygon
			(pts
				(xy 461.086962 -46.478698) (xy 462.395062 -46.478698) (xy 462.395062 -48.485298) (xy 461.086962 -48.485298)
			)
		)
	)
	(zone
		(layer "In1.Cu")
		(hatch none 0.5)
		(connect_pads
			(clearance 0)
		)
		(min_thickness 0.25)
		(keepout
			(tracks not_allowed)
			(vias allowed)
			(pads allowed)
			(copperpour not_allowed)
			(footprints allowed)
		)
		(placement
			(enabled no)
			(sheetname "")
		)
		(fill
			(thermal_gap 0.5)
			(thermal_bridge_width 0.5)
			(island_removal_mode 0)
		)
		(polygon
			(pts
				(xy 400.176492 -9.774936) (xy 400.684492 -9.774936) (xy 400.684492 -11.171936) (xy 400.176492 -11.171936)
			)
		)
	)
	(zone
		(layer "In1.Cu")
		(hatch none 0.5)
		(connect_pads
			(clearance 0)
		)
		(min_thickness 0.25)
		(keepout
			(tracks not_allowed)
			(vias allowed)
			(pads allowed)
			(copperpour not_allowed)
			(footprints allowed)
		)
		(placement
			(enabled no)
			(sheetname "")
		)
		(fill
			(thermal_gap 0.5)
			(thermal_bridge_width 0.5)
			(island_removal_mode 0)
		)
		(polygon
			(pts
				(xy 89.76995 -132.174742) (xy 89.76995 -133.978142) (xy 90.32875 -133.978142) (xy 90.32875 -132.174742)
			)
		)
	)
	(zone
		(layer "In1.Cu")
		(hatch none 0.5)
		(connect_pads
			(clearance 0)
		)
		(min_thickness 0.25)
		(keepout
			(tracks not_allowed)
			(vias allowed)
			(pads allowed)
			(copperpour not_allowed)
			(footprints allowed)
		)
		(placement
			(enabled no)
			(sheetname "")
		)
		(fill
			(thermal_gap 0.5)
			(thermal_bridge_width 0.5)
			(island_removal_mode 0)
		)
		(polygon
			(pts
				(xy 230.970582 -9.520682) (xy 230.970582 -11.324082) (xy 231.529382 -11.324082) (xy 231.529382 -9.520682)
			)
		)
	)
	(zone
		(layer "In1.Cu")
		(hatch none 0.5)
		(connect_pads
			(clearance 0)
		)
		(min_thickness 0.25)
		(keepout
			(tracks not_allowed)
			(vias allowed)
			(pads allowed)
			(copperpour not_allowed)
			(footprints allowed)
		)
		(placement
			(enabled no)
			(sheetname "")
		)
		(fill
			(thermal_gap 0.5)
			(thermal_bridge_width 0.5)
			(island_removal_mode 0)
		)
		(polygon
			(pts
				(xy 375.631202 -3.792982) (xy 376.939048 -3.792982) (xy 376.939048 -4.986782) (xy 375.631202 -4.986782)
			)
		)
	)
	(zone
		(layer "In1.Cu")
		(hatch none 0.5)
		(connect_pads
			(clearance 0)
		)
		(min_thickness 0.25)
		(keepout
			(tracks not_allowed)
			(vias allowed)
			(pads allowed)
			(copperpour not_allowed)
			(footprints allowed)
		)
		(placement
			(enabled no)
			(sheetname "")
		)
		(fill
			(thermal_gap 0.5)
			(thermal_bridge_width 0.5)
			(island_removal_mode 0)
		)
		(polygon
			(pts
				(xy 228.420422 -136.774682) (xy 228.420422 -138.578082) (xy 228.979222 -138.578082) (xy 228.979222 -136.774682)
			)
		)
	)
	(zone
		(layer "In1.Cu")
		(hatch none 0.5)
		(connect_pads
			(clearance 0)
		)
		(min_thickness 0.25)
		(keepout
			(tracks not_allowed)
			(vias allowed)
			(pads allowed)
			(copperpour not_allowed)
			(footprints allowed)
		)
		(placement
			(enabled no)
			(sheetname "")
		)
		(fill
			(thermal_gap 0.5)
			(thermal_bridge_width 0.5)
			(island_removal_mode 0)
		)
		(polygon
			(pts
				(xy 48.120046 -14.521942) (xy 48.120046 -16.325342) (xy 48.678846 -16.325342) (xy 48.678846 -14.521942)
			)
		)
	)
	(zone
		(layer "In1.Cu")
		(hatch none 0.5)
		(connect_pads
			(clearance 0)
		)
		(min_thickness 0.25)
		(keepout
			(tracks not_allowed)
			(vias allowed)
			(pads allowed)
			(copperpour not_allowed)
			(footprints allowed)
		)
		(placement
			(enabled no)
			(sheetname "")
		)
		(fill
			(thermal_gap 0.5)
			(thermal_bridge_width 0.5)
			(island_removal_mode 0)
		)
		(polygon
			(pts
				(xy 241.170714 -151.377142) (xy 241.170714 -153.180542) (xy 241.729514 -153.180542) (xy 241.729514 -151.377142)
			)
		)
	)
	(zone
		(layer "In1.Cu")
		(hatch none 0.5)
		(connect_pads
			(clearance 0)
		)
		(min_thickness 0.25)
		(keepout
			(tracks not_allowed)
			(vias allowed)
			(pads allowed)
			(copperpour not_allowed)
			(footprints allowed)
		)
		(placement
			(enabled no)
			(sheetname "")
		)
		(fill
			(thermal_gap 0.5)
			(thermal_bridge_width 0.5)
			(island_removal_mode 0)
		)
		(polygon
			(pts
				(xy 338.079588 -117.687598) (xy 340.365588 -117.687598) (xy 340.365588 -118.195598) (xy 338.079588 -118.195598)
			)
		)
	)
	(zone
		(layer "In1.Cu")
		(hatch none 0.5)
		(connect_pads
			(clearance 0)
		)
		(min_thickness 0.25)
		(keepout
			(tracks not_allowed)
			(vias allowed)
			(pads allowed)
			(copperpour not_allowed)
			(footprints allowed)
		)
		(placement
			(enabled no)
			(sheetname "")
		)
		(fill
			(thermal_gap 0.5)
			(thermal_bridge_width 0.5)
			(island_removal_mode 0)
		)
		(polygon
			(pts
				(xy 102.519988 -146.375882) (xy 102.519988 -148.179282) (xy 103.078788 -148.179282) (xy 103.078788 -146.375882)
			)
		)
	)
	(zone
		(layer "In1.Cu")
		(hatch none 0.5)
		(connect_pads
			(clearance 0)
		)
		(min_thickness 0.25)
		(keepout
			(tracks not_allowed)
			(vias allowed)
			(pads allowed)
			(copperpour not_allowed)
			(footprints allowed)
		)
		(placement
			(enabled no)
			(sheetname "")
		)
		(fill
			(thermal_gap 0.5)
			(thermal_bridge_width 0.5)
			(island_removal_mode 0)
		)
		(polygon
			(pts
				(xy 105.070148 -132.174742) (xy 105.070148 -133.978142) (xy 105.628948 -133.978142) (xy 105.628948 -132.174742)
			)
		)
	)
	(zone
		(layer "In1.Cu")
		(hatch none 0.5)
		(connect_pads
			(clearance 0)
		)
		(min_thickness 0.25)
		(keepout
			(tracks not_allowed)
			(vias allowed)
			(pads allowed)
			(copperpour not_allowed)
			(footprints allowed)
		)
		(placement
			(enabled no)
			(sheetname "")
		)
		(fill
			(thermal_gap 0.5)
			(thermal_bridge_width 0.5)
			(island_removal_mode 0)
		)
		(polygon
			(pts
				(xy 306.620418 -136.774682) (xy 306.620418 -138.578082) (xy 307.179218 -138.578082) (xy 307.179218 -136.774682)
			)
		)
	)
	(zone
		(layer "In1.Cu")
		(hatch none 0.5)
		(connect_pads
			(clearance 0)
		)
		(min_thickness 0.25)
		(keepout
			(tracks not_allowed)
			(vias allowed)
			(pads allowed)
			(copperpour not_allowed)
			(footprints allowed)
		)
		(placement
			(enabled no)
			(sheetname "")
		)
		(fill
			(thermal_gap 0.5)
			(thermal_bridge_width 0.5)
			(island_removal_mode 0)
		)
		(polygon
			(pts
				(xy 399.417286 -3.789172) (xy 400.725386 -3.789172) (xy 400.725386 -4.982972) (xy 399.417286 -4.982972)
			)
		)
	)
	(zone
		(layer "In1.Cu")
		(hatch none 0.5)
		(connect_pads
			(clearance 0)
		)
		(min_thickness 0.25)
		(keepout
			(tracks not_allowed)
			(vias allowed)
			(pads allowed)
			(copperpour not_allowed)
			(footprints allowed)
		)
		(placement
			(enabled no)
			(sheetname "")
		)
		(fill
			(thermal_gap 0.5)
			(thermal_bridge_width 0.5)
			(island_removal_mode 0)
		)
		(polygon
			(pts
				(xy 254.770382 4.680458) (xy 254.770382 2.877058) (xy 255.329182 2.877058) (xy 255.329182 4.680458)
			)
		)
	)
	(zone
		(layer "In1.Cu")
		(hatch none 0.5)
		(connect_pads
			(clearance 0)
		)
		(min_thickness 0.25)
		(keepout
			(tracks not_allowed)
			(vias allowed)
			(pads allowed)
			(copperpour not_allowed)
			(footprints allowed)
		)
		(placement
			(enabled no)
			(sheetname "")
		)
		(fill
			(thermal_gap 0.5)
			(thermal_bridge_width 0.5)
			(island_removal_mode 0)
		)
		(polygon
			(pts
				(xy 115.270026 -19.121882) (xy 115.270026 -20.925282) (xy 115.828826 -20.925282) (xy 115.828826 -19.121882)
			)
		)
	)
	(zone
		(layer "In1.Cu")
		(hatch none 0.5)
		(connect_pads
			(clearance 0)
		)
		(min_thickness 0.25)
		(keepout
			(tracks not_allowed)
			(vias allowed)
			(pads allowed)
			(copperpour not_allowed)
			(footprints allowed)
		)
		(placement
			(enabled no)
			(sheetname "")
		)
		(fill
			(thermal_gap 0.5)
			(thermal_bridge_width 0.5)
			(island_removal_mode 0)
		)
		(polygon
			(pts
				(xy 78.719934 -136.774682) (xy 78.719934 -138.578082) (xy 79.278734 -138.578082) (xy 79.278734 -136.774682)
			)
		)
	)
	(zone
		(layer "In1.Cu")
		(hatch none 0.5)
		(connect_pads
			(clearance 0)
		)
		(min_thickness 0.25)
		(keepout
			(tracks not_allowed)
			(vias allowed)
			(pads allowed)
			(copperpour not_allowed)
			(footprints allowed)
		)
		(placement
			(enabled no)
			(sheetname "")
		)
		(fill
			(thermal_gap 0.5)
			(thermal_bridge_width 0.5)
			(island_removal_mode 0)
		)
		(polygon
			(pts
				(xy 60.019946 -136.774682) (xy 60.019946 -138.578082) (xy 60.578746 -138.578082) (xy 60.578746 -136.774682)
			)
		)
	)
	(zone
		(layer "In1.Cu")
		(hatch none 0.5)
		(connect_pads
			(clearance 0)
		)
		(min_thickness 0.25)
		(keepout
			(tracks not_allowed)
			(vias allowed)
			(pads allowed)
			(copperpour not_allowed)
			(footprints allowed)
		)
		(placement
			(enabled no)
			(sheetname "")
		)
		(fill
			(thermal_gap 0.5)
			(thermal_bridge_width 0.5)
			(island_removal_mode 0)
		)
		(polygon
			(pts
				(xy 276.02053 -146.375882) (xy 276.02053 -148.179282) (xy 276.57933 -148.179282) (xy 276.57933 -146.375882)
			)
		)
	)
	(zone
		(layer "In1.Cu")
		(hatch none 0.5)
		(connect_pads
			(clearance 0)
		)
		(min_thickness 0.25)
		(keepout
			(tracks not_allowed)
			(vias allowed)
			(pads allowed)
			(copperpour not_allowed)
			(footprints allowed)
		)
		(placement
			(enabled no)
			(sheetname "")
		)
		(fill
			(thermal_gap 0.5)
			(thermal_bridge_width 0.5)
			(island_removal_mode 0)
		)
		(polygon
			(pts
				(xy 254.770382 -14.521942) (xy 254.770382 -16.325342) (xy 255.329182 -16.325342) (xy 255.329182 -14.521942)
			)
		)
	)
	(zone
		(layer "In1.Cu")
		(hatch none 0.5)
		(connect_pads
			(clearance 0)
		)
		(min_thickness 0.25)
		(keepout
			(tracks not_allowed)
			(vias allowed)
			(pads allowed)
			(copperpour not_allowed)
			(footprints allowed)
		)
		(placement
			(enabled no)
			(sheetname "")
		)
		(fill
			(thermal_gap 0.5)
			(thermal_bridge_width 0.5)
			(island_removal_mode 0)
		)
		(polygon
			(pts
				(xy 311.720484 -19.121882) (xy 311.720484 -20.925282) (xy 312.279284 -20.925282) (xy 312.279284 -19.121882)
			)
		)
	)
	(zone
		(layer "In1.Cu")
		(hatch none 0.5)
		(connect_pads
			(clearance 0)
		)
		(min_thickness 0.25)
		(keepout
			(tracks not_allowed)
			(vias allowed)
			(pads allowed)
			(copperpour not_allowed)
			(footprints allowed)
		)
		(placement
			(enabled no)
			(sheetname "")
		)
		(fill
			(thermal_gap 0.5)
			(thermal_bridge_width 0.5)
			(island_removal_mode 0)
		)
		(polygon
			(pts
				(xy 302.37049 -155.977082) (xy 302.37049 -157.780482) (xy 302.92929 -157.780482) (xy 302.92929 -155.977082)
			)
		)
	)
	(zone
		(layer "In1.Cu")
		(hatch none 0.5)
		(connect_pads
			(clearance 0)
		)
		(min_thickness 0.25)
		(keepout
			(tracks not_allowed)
			(vias allowed)
			(pads allowed)
			(copperpour not_allowed)
			(footprints allowed)
		)
		(placement
			(enabled no)
			(sheetname "")
		)
		(fill
			(thermal_gap 0.5)
			(thermal_bridge_width 0.5)
			(island_removal_mode 0)
		)
		(polygon
			(pts
				(xy 88.920066 4.680458) (xy 88.920066 2.877058) (xy 89.478866 2.877058) (xy 89.478866 4.680458)
			)
		)
	)
	(zone
		(layer "In1.Cu")
		(hatch none 0.5)
		(connect_pads
			(clearance 0)
		)
		(min_thickness 0.25)
		(keepout
			(tracks not_allowed)
			(vias allowed)
			(pads allowed)
			(copperpour not_allowed)
			(footprints allowed)
		)
		(placement
			(enabled no)
			(sheetname "")
		)
		(fill
			(thermal_gap 0.5)
			(thermal_bridge_width 0.5)
			(island_removal_mode 0)
		)
		(polygon
			(pts
				(xy 52.369974 0.080518) (xy 52.369974 -1.722882) (xy 52.928774 -1.722882) (xy 52.928774 0.080518)
			)
		)
	)
	(zone
		(layer "In1.Cu")
		(hatch none 0.5)
		(connect_pads
			(clearance 0)
		)
		(min_thickness 0.25)
		(keepout
			(tracks not_allowed)
			(vias allowed)
			(pads allowed)
			(copperpour not_allowed)
			(footprints allowed)
		)
		(placement
			(enabled no)
			(sheetname "")
		)
		(fill
			(thermal_gap 0.5)
			(thermal_bridge_width 0.5)
			(island_removal_mode 0)
		)
		(polygon
			(pts
				(xy 135.670036 -146.375882) (xy 135.670036 -148.179282) (xy 136.228836 -148.179282) (xy 136.228836 -146.375882)
			)
		)
	)
	(zone
		(layer "In1.Cu")
		(hatch none 0.5)
		(connect_pads
			(clearance 0)
		)
		(min_thickness 0.25)
		(keepout
			(tracks not_allowed)
			(vias allowed)
			(pads allowed)
			(copperpour not_allowed)
			(footprints allowed)
		)
		(placement
			(enabled no)
			(sheetname "")
		)
		(fill
			(thermal_gap 0.5)
			(thermal_bridge_width 0.5)
			(island_removal_mode 0)
		)
		(polygon
			(pts
				(xy 126.320042 -146.375882) (xy 126.320042 -148.179282) (xy 126.878842 -148.179282) (xy 126.878842 -146.375882)
			)
		)
	)
	(zone
		(layer "In1.Cu")
		(hatch none 0.5)
		(connect_pads
			(clearance 0)
		)
		(min_thickness 0.25)
		(keepout
			(tracks not_allowed)
			(vias allowed)
			(pads allowed)
			(copperpour not_allowed)
			(footprints allowed)
		)
		(placement
			(enabled no)
			(sheetname "")
		)
		(fill
			(thermal_gap 0.5)
			(thermal_bridge_width 0.5)
			(island_removal_mode 0)
		)
		(polygon
			(pts
				(xy 71.9201 -14.521942) (xy 71.9201 -16.325342) (xy 72.4789 -16.325342) (xy 72.4789 -14.521942)
			)
		)
	)
	(zone
		(layer "In1.Cu")
		(hatch none 0.5)
		(connect_pads
			(clearance 0)
		)
		(min_thickness 0.25)
		(keepout
			(tracks not_allowed)
			(vias allowed)
			(pads allowed)
			(copperpour not_allowed)
			(footprints allowed)
		)
		(placement
			(enabled no)
			(sheetname "")
		)
		(fill
			(thermal_gap 0.5)
			(thermal_bridge_width 0.5)
			(island_removal_mode 0)
		)
		(polygon
			(pts
				(xy 315.970412 -155.977082) (xy 315.970412 -157.780482) (xy 316.529212 -157.780482) (xy 316.529212 -155.977082)
			)
		)
	)
	(zone
		(layer "In1.Cu")
		(hatch none 0.5)
		(connect_pads
			(clearance 0)
		)
		(min_thickness 0.25)
		(keepout
			(tracks not_allowed)
			(vias allowed)
			(pads allowed)
			(copperpour not_allowed)
			(footprints allowed)
		)
		(placement
			(enabled no)
			(sheetname "")
		)
		(fill
			(thermal_gap 0.5)
			(thermal_bridge_width 0.5)
			(island_removal_mode 0)
		)
		(polygon
			(pts
				(xy 285.370524 -132.174742) (xy 285.370524 -133.978142) (xy 285.929324 -133.978142) (xy 285.929324 -132.174742)
			)
		)
	)
	(zone
		(layer "In1.Cu")
		(hatch none 0.5)
		(connect_pads
			(clearance 0)
		)
		(min_thickness 0.25)
		(keepout
			(tracks not_allowed)
			(vias allowed)
			(pads allowed)
			(copperpour not_allowed)
			(footprints allowed)
		)
		(placement
			(enabled no)
			(sheetname "")
		)
		(fill
			(thermal_gap 0.5)
			(thermal_bridge_width 0.5)
			(island_removal_mode 0)
		)
		(polygon
			(pts
				(xy 301.520352 -141.775942) (xy 301.520352 -143.579342) (xy 302.079152 -143.579342) (xy 302.079152 -141.775942)
			)
		)
	)
	(zone
		(layer "In1.Cu")
		(hatch none 0.5)
		(connect_pads
			(clearance 0)
		)
		(min_thickness 0.25)
		(keepout
			(tracks not_allowed)
			(vias allowed)
			(pads allowed)
			(copperpour not_allowed)
			(footprints allowed)
		)
		(placement
			(enabled no)
			(sheetname "")
		)
		(fill
			(thermal_gap 0.5)
			(thermal_bridge_width 0.5)
			(island_removal_mode 0)
		)
		(polygon
			(pts
				(xy 243.720366 -155.977082) (xy 243.720366 -157.780482) (xy 244.279166 -157.780482) (xy 244.279166 -155.977082)
			)
		)
	)
	(zone
		(layer "In1.Cu")
		(hatch none 0.5)
		(connect_pads
			(clearance 0)
		)
		(min_thickness 0.25)
		(keepout
			(tracks not_allowed)
			(vias allowed)
			(pads allowed)
			(copperpour not_allowed)
			(footprints allowed)
		)
		(placement
			(enabled no)
			(sheetname "")
		)
		(fill
			(thermal_gap 0.5)
			(thermal_bridge_width 0.5)
			(island_removal_mode 0)
		)
		(polygon
			(pts
				(xy 99.970082 -146.375882) (xy 99.970082 -148.179282) (xy 100.528882 -148.179282) (xy 100.528882 -146.375882)
			)
		)
	)
	(zone
		(layer "In1.Cu")
		(hatch none 0.5)
		(connect_pads
			(clearance 0)
		)
		(min_thickness 0.25)
		(keepout
			(tracks not_allowed)
			(vias allowed)
			(pads allowed)
			(copperpour not_allowed)
			(footprints allowed)
		)
		(placement
			(enabled no)
			(sheetname "")
		)
		(fill
			(thermal_gap 0.5)
			(thermal_bridge_width 0.5)
			(island_removal_mode 0)
		)
		(polygon
			(pts
				(xy 455.546968 -111.011716) (xy 456.854814 -111.011716) (xy 456.854814 -113.399316) (xy 455.546968 -113.399316)
			)
		)
	)
	(zone
		(layer "In1.Cu")
		(hatch none 0.5)
		(connect_pads
			(clearance 0)
		)
		(min_thickness 0.25)
		(keepout
			(tracks not_allowed)
			(vias allowed)
			(pads allowed)
			(copperpour not_allowed)
			(footprints allowed)
		)
		(placement
			(enabled no)
			(sheetname "")
		)
		(fill
			(thermal_gap 0.5)
			(thermal_bridge_width 0.5)
			(island_removal_mode 0)
		)
		(polygon
			(pts
				(xy 240.320576 -146.375882) (xy 240.320576 -148.179282) (xy 240.879376 -148.179282) (xy 240.879376 -146.375882)
			)
		)
	)
	(zone
		(layer "In1.Cu")
		(hatch none 0.5)
		(connect_pads
			(clearance 0)
		)
		(min_thickness 0.25)
		(keepout
			(tracks not_allowed)
			(vias allowed)
			(pads allowed)
			(copperpour not_allowed)
			(footprints allowed)
		)
		(placement
			(enabled no)
			(sheetname "")
		)
		(fill
			(thermal_gap 0.5)
			(thermal_bridge_width 0.5)
			(island_removal_mode 0)
		)
		(polygon
			(pts
				(xy 311.720484 -4.920742) (xy 311.720484 -6.724142) (xy 312.279284 -6.724142) (xy 312.279284 -4.920742)
			)
		)
	)
	(zone
		(layer "In1.Cu")
		(hatch none 0.5)
		(connect_pads
			(clearance 0)
		)
		(min_thickness 0.25)
		(keepout
			(tracks not_allowed)
			(vias allowed)
			(pads allowed)
			(copperpour not_allowed)
			(footprints allowed)
		)
		(placement
			(enabled no)
			(sheetname "")
		)
		(fill
			(thermal_gap 0.5)
			(thermal_bridge_width 0.5)
			(island_removal_mode 0)
		)
		(polygon
			(pts
				(xy 110.16996 -19.121882) (xy 110.72876 -19.121882) (xy 110.72876 -20.925282) (xy 110.16996 -20.925282)
			)
		)
	)
	(zone
		(layer "In1.Cu")
		(hatch none 0.5)
		(connect_pads
			(clearance 0)
		)
		(min_thickness 0.25)
		(keepout
			(tracks not_allowed)
			(vias allowed)
			(pads allowed)
			(copperpour not_allowed)
			(footprints allowed)
		)
		(placement
			(enabled no)
			(sheetname "")
		)
		(fill
			(thermal_gap 0.5)
			(thermal_bridge_width 0.5)
			(island_removal_mode 0)
		)
		(polygon
			(pts
				(xy 77.02042 -19.121882) (xy 77.02042 -20.925282) (xy 77.57922 -20.925282) (xy 77.57922 -19.121882)
			)
		)
	)
	(zone
		(layer "In1.Cu")
		(hatch none 0.5)
		(connect_pads
			(clearance 0)
		)
		(min_thickness 0.25)
		(keepout
			(tracks not_allowed)
			(vias allowed)
			(pads allowed)
			(copperpour not_allowed)
			(footprints allowed)
		)
		(placement
			(enabled no)
			(sheetname "")
		)
		(fill
			(thermal_gap 0.5)
			(thermal_bridge_width 0.5)
			(island_removal_mode 0)
		)
		(polygon
			(pts
				(xy 382.022604 -22.118574) (xy 383.572004 -22.118574) (xy 383.572004 -22.923246) (xy 382.022604 -22.923246)
			)
		)
	)
	(zone
		(layer "In1.Cu")
		(hatch none 0.5)
		(connect_pads
			(clearance 0)
		)
		(min_thickness 0.25)
		(keepout
			(tracks not_allowed)
			(vias allowed)
			(pads allowed)
			(copperpour not_allowed)
			(footprints allowed)
		)
		(placement
			(enabled no)
			(sheetname "")
		)
		(fill
			(thermal_gap 0.5)
			(thermal_bridge_width 0.5)
			(island_removal_mode 0)
		)
		(polygon
			(pts
				(xy 238.620554 -9.520682) (xy 238.620554 -11.324082) (xy 239.179354 -11.324082) (xy 239.179354 -9.520682)
			)
		)
	)
	(zone
		(layer "In1.Cu")
		(hatch none 0.5)
		(connect_pads
			(clearance 0)
		)
		(min_thickness 0.25)
		(keepout
			(tracks not_allowed)
			(vias allowed)
			(pads allowed)
			(copperpour not_allowed)
			(footprints allowed)
		)
		(placement
			(enabled no)
			(sheetname "")
		)
		(fill
			(thermal_gap 0.5)
			(thermal_bridge_width 0.5)
			(island_removal_mode 0)
		)
		(polygon
			(pts
				(xy 72.769984 -14.521942) (xy 72.769984 -16.325342) (xy 73.328784 -16.325342) (xy 73.328784 -14.521942)
			)
		)
	)
	(zone
		(layer "In1.Cu")
		(hatch none 0.5)
		(connect_pads
			(clearance 0)
		)
		(min_thickness 0.25)
		(keepout
			(tracks not_allowed)
			(vias allowed)
			(pads allowed)
			(copperpour not_allowed)
			(footprints allowed)
		)
		(placement
			(enabled no)
			(sheetname "")
		)
		(fill
			(thermal_gap 0.5)
			(thermal_bridge_width 0.5)
			(island_removal_mode 0)
		)
		(polygon
			(pts
				(xy 35.370008 -136.774682) (xy 35.370008 -138.578082) (xy 35.928808 -138.578082) (xy 35.928808 -136.774682)
			)
		)
	)
	(zone
		(layer "In1.Cu")
		(hatch none 0.5)
		(connect_pads
			(clearance 0)
		)
		(min_thickness 0.25)
		(keepout
			(tracks not_allowed)
			(vias allowed)
			(pads allowed)
			(copperpour not_allowed)
			(footprints allowed)
		)
		(placement
			(enabled no)
			(sheetname "")
		)
		(fill
			(thermal_gap 0.5)
			(thermal_bridge_width 0.5)
			(island_removal_mode 0)
		)
		(polygon
			(pts
				(xy 293.020496 4.680458) (xy 293.020496 2.877058) (xy 293.579296 2.877058) (xy 293.579296 4.680458)
			)
		)
	)
	(zone
		(layer "In1.Cu")
		(hatch none 0.5)
		(connect_pads
			(clearance 0)
		)
		(min_thickness 0.25)
		(keepout
			(tracks not_allowed)
			(vias allowed)
			(pads allowed)
			(copperpour not_allowed)
			(footprints allowed)
		)
		(placement
			(enabled no)
			(sheetname "")
		)
		(fill
			(thermal_gap 0.5)
			(thermal_bridge_width 0.5)
			(island_removal_mode 0)
		)
		(polygon
			(pts
				(xy 293.020496 -141.775942) (xy 293.020496 -143.579342) (xy 293.579296 -143.579342) (xy 293.579296 -141.775942)
			)
		)
	)
	(zone
		(layer "In1.Cu")
		(hatch none 0.5)
		(connect_pads
			(clearance 0)
		)
		(min_thickness 0.25)
		(keepout
			(tracks not_allowed)
			(vias allowed)
			(pads allowed)
			(copperpour not_allowed)
			(footprints allowed)
		)
		(placement
			(enabled no)
			(sheetname "")
		)
		(fill
			(thermal_gap 0.5)
			(thermal_bridge_width 0.5)
			(island_removal_mode 0)
		)
		(polygon
			(pts
				(xy 100.819966 -132.174742) (xy 100.819966 -133.978142) (xy 101.378766 -133.978142) (xy 101.378766 -132.174742)
			)
		)
	)
	(zone
		(layer "In1.Cu")
		(hatch none 0.5)
		(connect_pads
			(clearance 0)
		)
		(min_thickness 0.25)
		(keepout
			(tracks not_allowed)
			(vias allowed)
			(pads allowed)
			(copperpour not_allowed)
			(footprints allowed)
		)
		(placement
			(enabled no)
			(sheetname "")
		)
		(fill
			(thermal_gap 0.5)
			(thermal_bridge_width 0.5)
			(island_removal_mode 0)
		)
		(polygon
			(pts
				(xy 41.319958 -155.977082) (xy 41.319958 -157.780482) (xy 41.878758 -157.780482) (xy 41.878758 -155.977082)
			)
		)
	)
	(zone
		(layer "In1.Cu")
		(hatch none 0.5)
		(connect_pads
			(clearance 0)
		)
		(min_thickness 0.25)
		(keepout
			(tracks not_allowed)
			(vias allowed)
			(pads allowed)
			(copperpour not_allowed)
			(footprints allowed)
		)
		(placement
			(enabled no)
			(sheetname "")
		)
		(fill
			(thermal_gap 0.5)
			(thermal_bridge_width 0.5)
			(island_removal_mode 0)
		)
		(polygon
			(pts
				(xy 206.32039 -9.520682) (xy 206.32039 -11.324082) (xy 206.87919 -11.324082) (xy 206.87919 -9.520682)
			)
		)
	)
	(zone
		(layer "In1.Cu")
		(hatch none 0.5)
		(connect_pads
			(clearance 0)
		)
		(min_thickness 0.25)
		(keepout
			(tracks not_allowed)
			(vias allowed)
			(pads allowed)
			(copperpour not_allowed)
			(footprints allowed)
		)
		(placement
			(enabled no)
			(sheetname "")
		)
		(fill
			(thermal_gap 0.5)
			(thermal_bridge_width 0.5)
			(island_removal_mode 0)
		)
		(polygon
			(pts
				(xy 224.170494 -14.521942) (xy 224.170494 -16.325342) (xy 224.729294 -16.325342) (xy 224.729294 -14.521942)
			)
		)
	)
	(zone
		(layer "In1.Cu")
		(hatch none 0.5)
		(connect_pads
			(clearance 0)
		)
		(min_thickness 0.25)
		(keepout
			(tracks not_allowed)
			(vias allowed)
			(pads allowed)
			(copperpour not_allowed)
			(footprints allowed)
		)
		(placement
			(enabled no)
			(sheetname "")
		)
		(fill
			(thermal_gap 0.5)
			(thermal_bridge_width 0.5)
			(island_removal_mode 0)
		)
		(polygon
			(pts
				(xy 148.420074 -151.377142) (xy 148.420074 -153.180542) (xy 148.978874 -153.180542) (xy 148.978874 -151.377142)
			)
		)
	)
	(zone
		(layer "In1.Cu")
		(hatch none 0.5)
		(connect_pads
			(clearance 0)
		)
		(min_thickness 0.25)
		(keepout
			(tracks not_allowed)
			(vias allowed)
			(pads allowed)
			(copperpour not_allowed)
			(footprints allowed)
		)
		(placement
			(enabled no)
			(sheetname "")
		)
		(fill
			(thermal_gap 0.5)
			(thermal_bridge_width 0.5)
			(island_removal_mode 0)
		)
		(polygon
			(pts
				(xy 196.120512 -4.920742) (xy 196.120512 -6.724142) (xy 196.679312 -6.724142) (xy 196.679312 -4.920742)
			)
		)
	)
	(zone
		(layer "In1.Cu")
		(hatch none 0.5)
		(connect_pads
			(clearance 0)
		)
		(min_thickness 0.25)
		(keepout
			(tracks not_allowed)
			(vias allowed)
			(pads allowed)
			(copperpour not_allowed)
			(footprints allowed)
		)
		(placement
			(enabled no)
			(sheetname "")
		)
		(fill
			(thermal_gap 0.5)
			(thermal_bridge_width 0.5)
			(island_removal_mode 0)
		)
		(polygon
			(pts
				(xy 336.261202 -121.028968) (xy 338.547202 -121.028968) (xy 338.547202 -121.536968) (xy 336.261202 -121.536968)
			)
		)
	)
	(zone
		(layer "In1.Cu")
		(hatch none 0.5)
		(connect_pads
			(clearance 0)
		)
		(min_thickness 0.25)
		(keepout
			(tracks not_allowed)
			(vias allowed)
			(pads allowed)
			(copperpour not_allowed)
			(footprints allowed)
		)
		(placement
			(enabled no)
			(sheetname "")
		)
		(fill
			(thermal_gap 0.5)
			(thermal_bridge_width 0.5)
			(island_removal_mode 0)
		)
		(polygon
			(pts
				(xy 230.970582 -136.774682) (xy 230.970582 -138.578082) (xy 231.529382 -138.578082) (xy 231.529382 -136.774682)
			)
		)
	)
	(zone
		(layer "In1.Cu")
		(hatch none 0.5)
		(connect_pads
			(clearance 0)
		)
		(min_thickness 0.25)
		(keepout
			(tracks not_allowed)
			(vias allowed)
			(pads allowed)
			(copperpour not_allowed)
			(footprints allowed)
		)
		(placement
			(enabled no)
			(sheetname "")
		)
		(fill
			(thermal_gap 0.5)
			(thermal_bridge_width 0.5)
			(island_removal_mode 0)
		)
		(polygon
			(pts
				(xy 306.620418 -9.520682) (xy 306.620418 -11.324082) (xy 307.179218 -11.324082) (xy 307.179218 -9.520682)
			)
		)
	)
	(zone
		(layer "In1.Cu")
		(hatch none 0.5)
		(connect_pads
			(clearance 0)
		)
		(min_thickness 0.25)
		(keepout
			(tracks not_allowed)
			(vias allowed)
			(pads allowed)
			(copperpour not_allowed)
			(footprints allowed)
		)
		(placement
			(enabled no)
			(sheetname "")
		)
		(fill
			(thermal_gap 0.5)
			(thermal_bridge_width 0.5)
			(island_removal_mode 0)
		)
		(polygon
			(pts
				(xy 65.97015 -155.977082) (xy 65.97015 -157.780482) (xy 66.52895 -157.780482) (xy 66.52895 -155.977082)
			)
		)
	)
	(zone
		(layer "In1.Cu")
		(hatch none 0.5)
		(connect_pads
			(clearance 0)
		)
		(min_thickness 0.25)
		(keepout
			(tracks not_allowed)
			(vias allowed)
			(pads allowed)
			(copperpour not_allowed)
			(footprints allowed)
		)
		(placement
			(enabled no)
			(sheetname "")
		)
		(fill
			(thermal_gap 0.5)
			(thermal_bridge_width 0.5)
			(island_removal_mode 0)
		)
		(polygon
			(pts
				(xy 128.869948 -9.520682) (xy 128.869948 -11.324082) (xy 129.428748 -11.324082) (xy 129.428748 -9.520682)
			)
		)
	)
	(zone
		(layer "In1.Cu")
		(hatch none 0.5)
		(connect_pads
			(clearance 0)
		)
		(min_thickness 0.25)
		(keepout
			(tracks not_allowed)
			(vias allowed)
			(pads allowed)
			(copperpour not_allowed)
			(footprints allowed)
		)
		(placement
			(enabled no)
			(sheetname "")
		)
		(fill
			(thermal_gap 0.5)
			(thermal_bridge_width 0.5)
			(island_removal_mode 0)
		)
		(polygon
			(pts
				(xy 209.720434 -4.920742) (xy 209.720434 -6.724142) (xy 210.279234 -6.724142) (xy 210.279234 -4.920742)
			)
		)
	)
	(zone
		(layer "In1.Cu")
		(hatch none 0.5)
		(connect_pads
			(clearance 0)
		)
		(min_thickness 0.25)
		(keepout
			(tracks not_allowed)
			(vias allowed)
			(pads allowed)
			(copperpour not_allowed)
			(footprints allowed)
		)
		(placement
			(enabled no)
			(sheetname "")
		)
		(fill
			(thermal_gap 0.5)
			(thermal_bridge_width 0.5)
			(island_removal_mode 0)
		)
		(polygon
			(pts
				(xy 408.266392 -9.773666) (xy 408.774392 -9.773666) (xy 408.774392 -11.170666) (xy 408.266392 -11.170666)
			)
		)
	)
	(zone
		(layer "In1.Cu")
		(hatch none 0.5)
		(connect_pads
			(clearance 0)
		)
		(min_thickness 0.25)
		(keepout
			(tracks not_allowed)
			(vias allowed)
			(pads allowed)
			(copperpour not_allowed)
			(footprints allowed)
		)
		(placement
			(enabled no)
			(sheetname "")
		)
		(fill
			(thermal_gap 0.5)
			(thermal_bridge_width 0.5)
			(island_removal_mode 0)
		)
		(polygon
			(pts
				(xy 91.469972 -151.377142) (xy 91.469972 -153.180542) (xy 92.028772 -153.180542) (xy 92.028772 -151.377142)
			)
		)
	)
	(zone
		(layer "In1.Cu")
		(hatch none 0.5)
		(connect_pads
			(clearance 0)
		)
		(min_thickness 0.25)
		(keepout
			(tracks not_allowed)
			(vias allowed)
			(pads allowed)
			(copperpour not_allowed)
			(footprints allowed)
		)
		(placement
			(enabled no)
			(sheetname "")
		)
		(fill
			(thermal_gap 0.5)
			(thermal_bridge_width 0.5)
			(island_removal_mode 0)
		)
		(polygon
			(pts
				(xy 144.169892 -151.377142) (xy 144.169892 -153.180542) (xy 144.728692 -153.180542) (xy 144.728692 -151.377142)
			)
		)
	)
	(zone
		(layer "In1.Cu")
		(hatch none 0.5)
		(connect_pads
			(clearance 0)
		)
		(min_thickness 0.25)
		(keepout
			(tracks not_allowed)
			(vias allowed)
			(pads allowed)
			(copperpour not_allowed)
			(footprints allowed)
		)
		(placement
			(enabled no)
			(sheetname "")
		)
		(fill
			(thermal_gap 0.5)
			(thermal_bridge_width 0.5)
			(island_removal_mode 0)
		)
		(polygon
			(pts
				(xy 301.520352 4.680458) (xy 301.520352 2.877058) (xy 302.079152 2.877058) (xy 302.079152 4.680458)
			)
		)
	)
	(zone
		(layer "In1.Cu")
		(hatch none 0.5)
		(connect_pads
			(clearance 0)
		)
		(min_thickness 0.25)
		(keepout
			(tracks not_allowed)
			(vias allowed)
			(pads allowed)
			(copperpour not_allowed)
			(footprints allowed)
		)
		(placement
			(enabled no)
			(sheetname "")
		)
		(fill
			(thermal_gap 0.5)
			(thermal_bridge_width 0.5)
			(island_removal_mode 0)
		)
		(polygon
			(pts
				(xy 302.37049 -19.121882) (xy 302.37049 -20.925282) (xy 302.92929 -20.925282) (xy 302.92929 -19.121882)
			)
		)
	)
	(zone
		(layer "In1.Cu")
		(hatch none 0.5)
		(connect_pads
			(clearance 0)
		)
		(min_thickness 0.25)
		(keepout
			(tracks not_allowed)
			(vias allowed)
			(pads allowed)
			(copperpour not_allowed)
			(footprints allowed)
		)
		(placement
			(enabled no)
			(sheetname "")
		)
		(fill
			(thermal_gap 0.5)
			(thermal_bridge_width 0.5)
			(island_removal_mode 0)
		)
		(polygon
			(pts
				(xy 286.220408 -19.121882) (xy 286.220408 -20.925282) (xy 286.779208 -20.925282) (xy 286.779208 -19.121882)
			)
		)
	)
	(zone
		(layer "In1.Cu")
		(hatch none 0.5)
		(connect_pads
			(clearance 0)
		)
		(min_thickness 0.25)
		(keepout
			(tracks not_allowed)
			(vias allowed)
			(pads allowed)
			(copperpour not_allowed)
			(footprints allowed)
		)
		(placement
			(enabled no)
			(sheetname "")
		)
		(fill
			(thermal_gap 0.5)
			(thermal_bridge_width 0.5)
			(island_removal_mode 0)
		)
		(polygon
			(pts
				(xy 256.470404 -14.521942) (xy 256.470404 -16.325342) (xy 257.029204 -16.325342) (xy 257.029204 -14.521942)
			)
		)
	)
	(zone
		(layer "In1.Cu")
		(hatch none 0.5)
		(connect_pads
			(clearance 0)
		)
		(min_thickness 0.25)
		(keepout
			(tracks not_allowed)
			(vias allowed)
			(pads allowed)
			(copperpour not_allowed)
			(footprints allowed)
		)
		(placement
			(enabled no)
			(sheetname "")
		)
		(fill
			(thermal_gap 0.5)
			(thermal_bridge_width 0.5)
			(island_removal_mode 0)
		)
		(polygon
			(pts
				(xy 32.820102 -132.174742) (xy 32.820102 -133.978142) (xy 33.378902 -133.978142) (xy 33.378902 -132.174742)
			)
		)
	)
	(zone
		(layer "In1.Cu")
		(hatch none 0.5)
		(connect_pads
			(clearance 0)
		)
		(min_thickness 0.25)
		(keepout
			(tracks not_allowed)
			(vias allowed)
			(pads allowed)
			(copperpour not_allowed)
			(footprints allowed)
		)
		(placement
			(enabled no)
			(sheetname "")
		)
		(fill
			(thermal_gap 0.5)
			(thermal_bridge_width 0.5)
			(island_removal_mode 0)
		)
		(polygon
			(pts
				(xy 203.770484 -14.521942) (xy 203.770484 -16.325342) (xy 204.329284 -16.325342) (xy 204.329284 -14.521942)
			)
		)
	)
	(zone
		(layer "In1.Cu")
		(hatch none 0.5)
		(connect_pads
			(clearance 0)
		)
		(min_thickness 0.25)
		(keepout
			(tracks not_allowed)
			(vias allowed)
			(pads allowed)
			(copperpour not_allowed)
			(footprints allowed)
		)
		(placement
			(enabled no)
			(sheetname "")
		)
		(fill
			(thermal_gap 0.5)
			(thermal_bridge_width 0.5)
			(island_removal_mode 0)
		)
		(polygon
			(pts
				(xy 150.96998 -146.375882) (xy 150.96998 -148.179282) (xy 151.52878 -148.179282) (xy 151.52878 -146.375882)
			)
		)
	)
	(zone
		(layer "In1.Cu")
		(hatch none 0.5)
		(connect_pads
			(clearance 0)
		)
		(min_thickness 0.25)
		(keepout
			(tracks not_allowed)
			(vias allowed)
			(pads allowed)
			(copperpour not_allowed)
			(footprints allowed)
		)
		(placement
			(enabled no)
			(sheetname "")
		)
		(fill
			(thermal_gap 0.5)
			(thermal_bridge_width 0.5)
			(island_removal_mode 0)
		)
		(polygon
			(pts
				(xy 369.223544 -9.773158) (xy 369.731544 -9.773158) (xy 369.731544 -11.170158) (xy 369.223544 -11.170158)
			)
		)
	)
	(zone
		(layer "In1.Cu")
		(hatch none 0.5)
		(connect_pads
			(clearance 0)
		)
		(min_thickness 0.25)
		(keepout
			(tracks not_allowed)
			(vias allowed)
			(pads allowed)
			(copperpour not_allowed)
			(footprints allowed)
		)
		(placement
			(enabled no)
			(sheetname "")
		)
		(fill
			(thermal_gap 0.5)
			(thermal_bridge_width 0.5)
			(island_removal_mode 0)
		)
		(polygon
			(pts
				(xy 141.619986 -155.977082) (xy 141.619986 -157.780482) (xy 142.178786 -157.780482) (xy 142.178786 -155.977082)
			)
		)
	)
	(zone
		(layer "In1.Cu")
		(hatch none 0.5)
		(connect_pads
			(clearance 0)
		)
		(min_thickness 0.25)
		(keepout
			(tracks not_allowed)
			(vias allowed)
			(pads allowed)
			(copperpour not_allowed)
			(footprints allowed)
		)
		(placement
			(enabled no)
			(sheetname "")
		)
		(fill
			(thermal_gap 0.5)
			(thermal_bridge_width 0.5)
			(island_removal_mode 0)
		)
		(polygon
			(pts
				(xy 71.9201 -132.174742) (xy 71.9201 -133.978142) (xy 72.4789 -133.978142) (xy 72.4789 -132.174742)
			)
		)
	)
	(zone
		(layer "In1.Cu")
		(hatch none 0.5)
		(connect_pads
			(clearance 0)
		)
		(min_thickness 0.25)
		(keepout
			(tracks not_allowed)
			(vias allowed)
			(pads allowed)
			(copperpour not_allowed)
			(footprints allowed)
		)
		(placement
			(enabled no)
			(sheetname "")
		)
		(fill
			(thermal_gap 0.5)
			(thermal_bridge_width 0.5)
			(island_removal_mode 0)
		)
		(polygon
			(pts
				(xy 81.270094 -14.521942) (xy 81.270094 -16.325342) (xy 81.828894 -16.325342) (xy 81.828894 -14.521942)
			)
		)
	)
	(zone
		(layer "In1.Cu")
		(hatch none 0.5)
		(connect_pads
			(clearance 0)
		)
		(min_thickness 0.25)
		(keepout
			(tracks not_allowed)
			(vias allowed)
			(pads allowed)
			(copperpour not_allowed)
			(footprints allowed)
		)
		(placement
			(enabled no)
			(sheetname "")
		)
		(fill
			(thermal_gap 0.5)
			(thermal_bridge_width 0.5)
			(island_removal_mode 0)
		)
		(polygon
			(pts
				(xy 250.520454 -146.375882) (xy 250.520454 -148.179282) (xy 251.079254 -148.179282) (xy 251.079254 -146.375882)
			)
		)
	)
	(zone
		(layer "In1.Cu")
		(hatch none 0.5)
		(connect_pads
			(clearance 0)
		)
		(min_thickness 0.25)
		(keepout
			(tracks not_allowed)
			(vias allowed)
			(pads allowed)
			(copperpour not_allowed)
			(footprints allowed)
		)
		(placement
			(enabled no)
			(sheetname "")
		)
		(fill
			(thermal_gap 0.5)
			(thermal_bridge_width 0.5)
			(island_removal_mode 0)
		)
		(polygon
			(pts
				(xy 43.870118 -141.775942) (xy 43.870118 -143.579342) (xy 44.428918 -143.579342) (xy 44.428918 -141.775942)
			)
		)
	)
	(zone
		(layer "In1.Cu")
		(hatch none 0.5)
		(connect_pads
			(clearance 0)
		)
		(min_thickness 0.25)
		(keepout
			(tracks not_allowed)
			(vias allowed)
			(pads allowed)
			(copperpour not_allowed)
			(footprints allowed)
		)
		(placement
			(enabled no)
			(sheetname "")
		)
		(fill
			(thermal_gap 0.5)
			(thermal_bridge_width 0.5)
			(island_removal_mode 0)
		)
		(polygon
			(pts
				(xy 35.370008 0.080518) (xy 35.370008 -1.722882) (xy 35.928808 -1.722882) (xy 35.928808 0.080518)
			)
		)
	)
	(zone
		(layer "In1.Cu")
		(hatch none 0.5)
		(connect_pads
			(clearance 0)
		)
		(min_thickness 0.25)
		(keepout
			(tracks not_allowed)
			(vias allowed)
			(pads allowed)
			(copperpour not_allowed)
			(footprints allowed)
		)
		(placement
			(enabled no)
			(sheetname "")
		)
		(fill
			(thermal_gap 0.5)
			(thermal_bridge_width 0.5)
			(island_removal_mode 0)
		)
		(polygon
			(pts
				(xy 77.02042 0.080518) (xy 77.02042 -1.722882) (xy 77.57922 -1.722882) (xy 77.57922 0.080518)
			)
		)
	)
	(zone
		(layer "In1.Cu")
		(hatch none 0.5)
		(connect_pads
			(clearance 0)
		)
		(min_thickness 0.25)
		(keepout
			(tracks not_allowed)
			(vias allowed)
			(pads allowed)
			(copperpour not_allowed)
			(footprints allowed)
		)
		(placement
			(enabled no)
			(sheetname "")
		)
		(fill
			(thermal_gap 0.5)
			(thermal_bridge_width 0.5)
			(island_removal_mode 0)
		)
		(polygon
			(pts
				(xy 85.520022 -19.121882) (xy 86.078822 -19.121882) (xy 86.078822 -20.925282) (xy 85.520022 -20.925282)
			)
		)
	)
	(zone
		(layer "In1.Cu")
		(hatch none 0.5)
		(connect_pads
			(clearance 0)
		)
		(min_thickness 0.25)
		(keepout
			(tracks not_allowed)
			(vias allowed)
			(pads allowed)
			(copperpour not_allowed)
			(footprints allowed)
		)
		(placement
			(enabled no)
			(sheetname "")
		)
		(fill
			(thermal_gap 0.5)
			(thermal_bridge_width 0.5)
			(island_removal_mode 0)
		)
		(polygon
			(pts
				(xy 241.170714 4.680458) (xy 241.170714 2.877058) (xy 241.729514 2.877058) (xy 241.729514 4.680458)
			)
		)
	)
	(zone
		(layer "In1.Cu")
		(hatch none 0.5)
		(connect_pads
			(clearance 0)
		)
		(min_thickness 0.25)
		(keepout
			(tracks not_allowed)
			(vias allowed)
			(pads allowed)
			(copperpour not_allowed)
			(footprints allowed)
		)
		(placement
			(enabled no)
			(sheetname "")
		)
		(fill
			(thermal_gap 0.5)
			(thermal_bridge_width 0.5)
			(island_removal_mode 0)
		)
		(polygon
			(pts
				(xy 267.52042 -132.174742) (xy 267.52042 -133.978142) (xy 268.07922 -133.978142) (xy 268.07922 -132.174742)
			)
		)
	)
	(zone
		(layer "In1.Cu")
		(hatch none 0.5)
		(connect_pads
			(clearance 0)
		)
		(min_thickness 0.25)
		(keepout
			(tracks not_allowed)
			(vias allowed)
			(pads allowed)
			(copperpour not_allowed)
			(footprints allowed)
		)
		(placement
			(enabled no)
			(sheetname "")
		)
		(fill
			(thermal_gap 0.5)
			(thermal_bridge_width 0.5)
			(island_removal_mode 0)
		)
		(polygon
			(pts
				(xy 297.270424 -136.774682) (xy 297.270424 -138.578082) (xy 297.829224 -138.578082) (xy 297.829224 -136.774682)
			)
		)
	)
	(zone
		(layer "In1.Cu")
		(hatch none 0.5)
		(connect_pads
			(clearance 0)
		)
		(min_thickness 0.25)
		(keepout
			(tracks not_allowed)
			(vias allowed)
			(pads allowed)
			(copperpour not_allowed)
			(footprints allowed)
		)
		(placement
			(enabled no)
			(sheetname "")
		)
		(fill
			(thermal_gap 0.5)
			(thermal_bridge_width 0.5)
			(island_removal_mode 0)
		)
		(polygon
			(pts
				(xy 67.669918 -9.520682) (xy 67.669918 -11.324082) (xy 68.228718 -11.324082) (xy 68.228718 -9.520682)
			)
		)
	)
	(zone
		(layer "In1.Cu")
		(hatch none 0.5)
		(connect_pads
			(clearance 0)
		)
		(min_thickness 0.25)
		(keepout
			(tracks not_allowed)
			(vias allowed)
			(pads allowed)
			(copperpour not_allowed)
			(footprints allowed)
		)
		(placement
			(enabled no)
			(sheetname "")
		)
		(fill
			(thermal_gap 0.5)
			(thermal_bridge_width 0.5)
			(island_removal_mode 0)
		)
		(polygon
			(pts
				(xy 286.220408 -155.977082) (xy 286.220408 -157.780482) (xy 286.779208 -157.780482) (xy 286.779208 -155.977082)
			)
		)
	)
	(zone
		(layer "In1.Cu")
		(hatch none 0.5)
		(connect_pads
			(clearance 0)
		)
		(min_thickness 0.25)
		(keepout
			(tracks not_allowed)
			(vias allowed)
			(pads allowed)
			(copperpour not_allowed)
			(footprints allowed)
		)
		(placement
			(enabled no)
			(sheetname "")
		)
		(fill
			(thermal_gap 0.5)
			(thermal_bridge_width 0.5)
			(island_removal_mode 0)
		)
		(polygon
			(pts
				(xy 219.070428 -136.774682) (xy 219.070428 -138.578082) (xy 219.629228 -138.578082) (xy 219.629228 -136.774682)
			)
		)
	)
	(zone
		(layer "In1.Cu")
		(hatch none 0.5)
		(connect_pads
			(clearance 0)
		)
		(min_thickness 0.25)
		(keepout
			(tracks not_allowed)
			(vias allowed)
			(pads allowed)
			(copperpour not_allowed)
			(footprints allowed)
		)
		(placement
			(enabled no)
			(sheetname "")
		)
		(fill
			(thermal_gap 0.5)
			(thermal_bridge_width 0.5)
			(island_removal_mode 0)
		)
		(polygon
			(pts
				(xy 220.77045 -14.521942) (xy 220.77045 -16.325342) (xy 221.32925 -16.325342) (xy 221.32925 -14.521942)
			)
		)
	)
	(zone
		(layer "In1.Cu")
		(hatch none 0.5)
		(connect_pads
			(clearance 0)
		)
		(min_thickness 0.25)
		(keepout
			(tracks not_allowed)
			(vias allowed)
			(pads allowed)
			(copperpour not_allowed)
			(footprints allowed)
		)
		(placement
			(enabled no)
			(sheetname "")
		)
		(fill
			(thermal_gap 0.5)
			(thermal_bridge_width 0.5)
			(island_removal_mode 0)
		)
		(polygon
			(pts
				(xy 226.7204 0.080518) (xy 226.7204 -1.722882) (xy 227.2792 -1.722882) (xy 227.2792 0.080518)
			)
		)
	)
	(zone
		(layer "In1.Cu")
		(hatch none 0.5)
		(connect_pads
			(clearance 0)
		)
		(min_thickness 0.25)
		(keepout
			(tracks not_allowed)
			(vias allowed)
			(pads allowed)
			(copperpour not_allowed)
			(footprints allowed)
		)
		(placement
			(enabled no)
			(sheetname "")
		)
		(fill
			(thermal_gap 0.5)
			(thermal_bridge_width 0.5)
			(island_removal_mode 0)
		)
		(polygon
			(pts
				(xy 264.970514 -136.774682) (xy 264.970514 -138.578082) (xy 265.529314 -138.578082) (xy 265.529314 -136.774682)
			)
		)
	)
	(zone
		(layer "In1.Cu")
		(hatch none 0.5)
		(connect_pads
			(clearance 0)
		)
		(min_thickness 0.25)
		(keepout
			(tracks not_allowed)
			(vias allowed)
			(pads allowed)
			(copperpour not_allowed)
			(footprints allowed)
		)
		(placement
			(enabled no)
			(sheetname "")
		)
		(fill
			(thermal_gap 0.5)
			(thermal_bridge_width 0.5)
			(island_removal_mode 0)
		)
		(polygon
			(pts
				(xy 256.470404 -141.775942) (xy 256.470404 -143.579342) (xy 257.029204 -143.579342) (xy 257.029204 -141.775942)
			)
		)
	)
	(zone
		(layer "In1.Cu")
		(hatch none 0.5)
		(connect_pads
			(clearance 0)
		)
		(min_thickness 0.25)
		(keepout
			(tracks not_allowed)
			(vias allowed)
			(pads allowed)
			(copperpour not_allowed)
			(footprints allowed)
		)
		(placement
			(enabled no)
			(sheetname "")
		)
		(fill
			(thermal_gap 0.5)
			(thermal_bridge_width 0.5)
			(island_removal_mode 0)
		)
		(polygon
			(pts
				(xy 144.169892 4.680458) (xy 144.169892 2.877058) (xy 144.728692 2.877058) (xy 144.728692 4.680458)
			)
		)
	)
	(zone
		(layer "In1.Cu")
		(hatch none 0.5)
		(connect_pads
			(clearance 0)
		)
		(min_thickness 0.25)
		(keepout
			(tracks not_allowed)
			(vias allowed)
			(pads allowed)
			(copperpour not_allowed)
			(footprints allowed)
		)
		(placement
			(enabled no)
			(sheetname "")
		)
		(fill
			(thermal_gap 0.5)
			(thermal_bridge_width 0.5)
			(island_removal_mode 0)
		)
		(polygon
			(pts
				(xy 143.320008 -136.774682) (xy 143.320008 -138.578082) (xy 143.878808 -138.578082) (xy 143.878808 -136.774682)
			)
		)
	)
	(zone
		(layer "In1.Cu")
		(hatch none 0.5)
		(connect_pads
			(clearance 0)
		)
		(min_thickness 0.25)
		(keepout
			(tracks not_allowed)
			(vias allowed)
			(pads allowed)
			(copperpour not_allowed)
			(footprints allowed)
		)
		(placement
			(enabled no)
			(sheetname "")
		)
		(fill
			(thermal_gap 0.5)
			(thermal_bridge_width 0.5)
			(island_removal_mode 0)
		)
		(polygon
			(pts
				(xy 146.720052 4.680458) (xy 146.720052 2.877058) (xy 147.278852 2.877058) (xy 147.278852 4.680458)
			)
		)
	)
	(zone
		(layer "In1.Cu")
		(hatch none 0.5)
		(connect_pads
			(clearance 0)
		)
		(min_thickness 0.25)
		(keepout
			(tracks not_allowed)
			(vias allowed)
			(pads allowed)
			(copperpour not_allowed)
			(footprints allowed)
		)
		(placement
			(enabled no)
			(sheetname "")
		)
		(fill
			(thermal_gap 0.5)
			(thermal_bridge_width 0.5)
			(island_removal_mode 0)
		)
		(polygon
			(pts
				(xy 407.377392 -9.773666) (xy 407.885392 -9.773666) (xy 407.885392 -11.170666) (xy 407.377392 -11.170666)
			)
		)
	)
	(zone
		(layer "In1.Cu")
		(hatch none 0.5)
		(connect_pads
			(clearance 0)
		)
		(min_thickness 0.25)
		(keepout
			(tracks not_allowed)
			(vias allowed)
			(pads allowed)
			(copperpour not_allowed)
			(footprints allowed)
		)
		(placement
			(enabled no)
			(sheetname "")
		)
		(fill
			(thermal_gap 0.5)
			(thermal_bridge_width 0.5)
			(island_removal_mode 0)
		)
		(polygon
			(pts
				(xy 44.720002 -136.774682) (xy 44.720002 -138.578082) (xy 45.278802 -138.578082) (xy 45.278802 -136.774682)
			)
		)
	)
	(zone
		(layer "In1.Cu")
		(hatch none 0.5)
		(connect_pads
			(clearance 0)
		)
		(min_thickness 0.25)
		(keepout
			(tracks not_allowed)
			(vias allowed)
			(pads allowed)
			(copperpour not_allowed)
			(footprints allowed)
		)
		(placement
			(enabled no)
			(sheetname "")
		)
		(fill
			(thermal_gap 0.5)
			(thermal_bridge_width 0.5)
			(island_removal_mode 0)
		)
		(polygon
			(pts
				(xy 13.6398 -30.099) (xy 15.0368 -30.099) (xy 15.0368 -30.607) (xy 13.6398 -30.607)
			)
		)
	)
	(zone
		(layer "In1.Cu")
		(hatch none 0.5)
		(connect_pads
			(clearance 0)
		)
		(min_thickness 0.25)
		(keepout
			(tracks not_allowed)
			(vias allowed)
			(pads allowed)
			(copperpour not_allowed)
			(footprints allowed)
		)
		(placement
			(enabled no)
			(sheetname "")
		)
		(fill
			(thermal_gap 0.5)
			(thermal_bridge_width 0.5)
			(island_removal_mode 0)
		)
		(polygon
			(pts
				(xy 238.620554 -146.375882) (xy 238.620554 -148.179282) (xy 239.179354 -148.179282) (xy 239.179354 -146.375882)
			)
		)
	)
	(zone
		(layer "In1.Cu")
		(hatch none 0.5)
		(connect_pads
			(clearance 0)
		)
		(min_thickness 0.25)
		(keepout
			(tracks not_allowed)
			(vias allowed)
			(pads allowed)
			(copperpour not_allowed)
			(footprints allowed)
		)
		(placement
			(enabled no)
			(sheetname "")
		)
		(fill
			(thermal_gap 0.5)
			(thermal_bridge_width 0.5)
			(island_removal_mode 0)
		)
		(polygon
			(pts
				(xy 232.67035 -136.774682) (xy 232.67035 -138.578082) (xy 233.22915 -138.578082) (xy 233.22915 -136.774682)
			)
		)
	)
	(zone
		(layer "In1.Cu")
		(hatch none 0.5)
		(connect_pads
			(clearance 0)
		)
		(min_thickness 0.25)
		(keepout
			(tracks not_allowed)
			(vias allowed)
			(pads allowed)
			(copperpour not_allowed)
			(footprints allowed)
		)
		(placement
			(enabled no)
			(sheetname "")
		)
		(fill
			(thermal_gap 0.5)
			(thermal_bridge_width 0.5)
			(island_removal_mode 0)
		)
		(polygon
			(pts
				(xy 312.570368 0.080518) (xy 312.570368 -1.722882) (xy 313.129168 -1.722882) (xy 313.129168 0.080518)
			)
		)
	)
	(zone
		(layer "In1.Cu")
		(hatch none 0.5)
		(connect_pads
			(clearance 0)
		)
		(min_thickness 0.25)
		(keepout
			(tracks not_allowed)
			(vias allowed)
			(pads allowed)
			(copperpour not_allowed)
			(footprints allowed)
		)
		(placement
			(enabled no)
			(sheetname "")
		)
		(fill
			(thermal_gap 0.5)
			(thermal_bridge_width 0.5)
			(island_removal_mode 0)
		)
		(polygon
			(pts
				(xy 133.119876 -141.775942) (xy 133.119876 -143.579342) (xy 133.678676 -143.579342) (xy 133.678676 -141.775942)
			)
		)
	)
	(zone
		(layer "In1.Cu")
		(hatch none 0.5)
		(connect_pads
			(clearance 0)
		)
		(min_thickness 0.25)
		(keepout
			(tracks not_allowed)
			(vias allowed)
			(pads allowed)
			(copperpour not_allowed)
			(footprints allowed)
		)
		(placement
			(enabled no)
			(sheetname "")
		)
		(fill
			(thermal_gap 0.5)
			(thermal_bridge_width 0.5)
			(island_removal_mode 0)
		)
		(polygon
			(pts
				(xy 443.487048 -50.872644) (xy 444.794894 -50.872644) (xy 444.794894 -52.879244) (xy 443.487048 -52.879244)
			)
		)
	)
	(zone
		(layer "In1.Cu")
		(hatch none 0.5)
		(connect_pads
			(clearance 0)
		)
		(min_thickness 0.25)
		(keepout
			(tracks not_allowed)
			(vias allowed)
			(pads allowed)
			(copperpour not_allowed)
			(footprints allowed)
		)
		(placement
			(enabled no)
			(sheetname "")
		)
		(fill
			(thermal_gap 0.5)
			(thermal_bridge_width 0.5)
			(island_removal_mode 0)
		)
		(polygon
			(pts
				(xy 242.870482 4.680458) (xy 242.870482 2.877058) (xy 243.429282 2.877058) (xy 243.429282 4.680458)
			)
		)
	)
	(zone
		(layer "In1.Cu")
		(hatch none 0.5)
		(connect_pads
			(clearance 0)
		)
		(min_thickness 0.25)
		(keepout
			(tracks not_allowed)
			(vias allowed)
			(pads allowed)
			(copperpour not_allowed)
			(footprints allowed)
		)
		(placement
			(enabled no)
			(sheetname "")
		)
		(fill
			(thermal_gap 0.5)
			(thermal_bridge_width 0.5)
			(island_removal_mode 0)
		)
		(polygon
			(pts
				(xy 253.920498 -151.377142) (xy 253.920498 -153.180542) (xy 254.479298 -153.180542) (xy 254.479298 -151.377142)
			)
		)
	)
	(zone
		(layer "In1.Cu")
		(hatch none 0.5)
		(connect_pads
			(clearance 0)
		)
		(min_thickness 0.25)
		(keepout
			(tracks not_allowed)
			(vias allowed)
			(pads allowed)
			(copperpour not_allowed)
			(footprints allowed)
		)
		(placement
			(enabled no)
			(sheetname "")
		)
		(fill
			(thermal_gap 0.5)
			(thermal_bridge_width 0.5)
			(island_removal_mode 0)
		)
		(polygon
			(pts
				(xy 139.07008 -4.920742) (xy 139.07008 -6.724142) (xy 139.62888 -6.724142) (xy 139.62888 -4.920742)
			)
		)
	)
	(zone
		(layer "In1.Cu")
		(hatch none 0.5)
		(connect_pads
			(clearance 0)
		)
		(min_thickness 0.25)
		(keepout
			(tracks not_allowed)
			(vias allowed)
			(pads allowed)
			(copperpour not_allowed)
			(footprints allowed)
		)
		(placement
			(enabled no)
			(sheetname "")
		)
		(fill
			(thermal_gap 0.5)
			(thermal_bridge_width 0.5)
			(island_removal_mode 0)
		)
		(polygon
			(pts
				(xy 118.67007 -9.520682) (xy 118.67007 -11.324082) (xy 119.22887 -11.324082) (xy 119.22887 -9.520682)
			)
		)
	)
	(zone
		(layer "In1.Cu")
		(hatch none 0.5)
		(connect_pads
			(clearance 0)
		)
		(min_thickness 0.25)
		(keepout
			(tracks not_allowed)
			(vias allowed)
			(pads allowed)
			(copperpour not_allowed)
			(footprints allowed)
		)
		(placement
			(enabled no)
			(sheetname "")
		)
		(fill
			(thermal_gap 0.5)
			(thermal_bridge_width 0.5)
			(island_removal_mode 0)
		)
		(polygon
			(pts
				(xy 293.020496 -136.774682) (xy 293.020496 -138.578082) (xy 293.579296 -138.578082) (xy 293.579296 -136.774682)
			)
		)
	)
	(zone
		(layer "In1.Cu")
		(hatch none 0.5)
		(connect_pads
			(clearance 0)
		)
		(min_thickness 0.25)
		(keepout
			(tracks not_allowed)
			(vias allowed)
			(pads allowed)
			(copperpour not_allowed)
			(footprints allowed)
		)
		(placement
			(enabled no)
			(sheetname "")
		)
		(fill
			(thermal_gap 0.5)
			(thermal_bridge_width 0.5)
			(island_removal_mode 0)
		)
		(polygon
			(pts
				(xy 60.870084 -141.775942) (xy 60.870084 -143.579342) (xy 61.428884 -143.579342) (xy 61.428884 -141.775942)
			)
		)
	)
	(zone
		(layer "In1.Cu")
		(hatch none 0.5)
		(connect_pads
			(clearance 0)
		)
		(min_thickness 0.25)
		(keepout
			(tracks not_allowed)
			(vias allowed)
			(pads allowed)
			(copperpour not_allowed)
			(footprints allowed)
		)
		(placement
			(enabled no)
			(sheetname "")
		)
		(fill
			(thermal_gap 0.5)
			(thermal_bridge_width 0.5)
			(island_removal_mode 0)
		)
		(polygon
			(pts
				(xy 134.819898 -4.920742) (xy 134.819898 -6.724142) (xy 135.378698 -6.724142) (xy 135.378698 -4.920742)
			)
		)
	)
	(zone
		(layer "In1.Cu")
		(hatch none 0.5)
		(connect_pads
			(clearance 0)
		)
		(min_thickness 0.25)
		(keepout
			(tracks not_allowed)
			(vias allowed)
			(pads allowed)
			(copperpour not_allowed)
			(footprints allowed)
		)
		(placement
			(enabled no)
			(sheetname "")
		)
		(fill
			(thermal_gap 0.5)
			(thermal_bridge_width 0.5)
			(island_removal_mode 0)
		)
		(polygon
			(pts
				(xy 196.970396 0.080518) (xy 196.970396 -1.722882) (xy 197.529196 -1.722882) (xy 197.529196 0.080518)
			)
		)
	)
	(zone
		(layer "In1.Cu")
		(hatch none 0.5)
		(connect_pads
			(clearance 0)
		)
		(min_thickness 0.25)
		(keepout
			(tracks not_allowed)
			(vias allowed)
			(pads allowed)
			(copperpour not_allowed)
			(footprints allowed)
		)
		(placement
			(enabled no)
			(sheetname "")
		)
		(fill
			(thermal_gap 0.5)
			(thermal_bridge_width 0.5)
			(island_removal_mode 0)
		)
		(polygon
			(pts
				(xy 300.670468 -136.774682) (xy 300.670468 -138.578082) (xy 301.229268 -138.578082) (xy 301.229268 -136.774682)
			)
		)
	)
	(zone
		(layer "In1.Cu")
		(hatch none 0.5)
		(connect_pads
			(clearance 0)
		)
		(min_thickness 0.25)
		(keepout
			(tracks not_allowed)
			(vias allowed)
			(pads allowed)
			(copperpour not_allowed)
			(footprints allowed)
		)
		(placement
			(enabled no)
			(sheetname "")
		)
		(fill
			(thermal_gap 0.5)
			(thermal_bridge_width 0.5)
			(island_removal_mode 0)
		)
		(polygon
			(pts
				(xy 37.07003 -141.775942) (xy 37.07003 -143.579342) (xy 37.62883 -143.579342) (xy 37.62883 -141.775942)
			)
		)
	)
	(zone
		(layer "In1.Cu")
		(hatch none 0.5)
		(connect_pads
			(clearance 0)
		)
		(min_thickness 0.25)
		(keepout
			(tracks not_allowed)
			(vias allowed)
			(pads allowed)
			(copperpour not_allowed)
			(footprints allowed)
		)
		(placement
			(enabled no)
			(sheetname "")
		)
		(fill
			(thermal_gap 0.5)
			(thermal_bridge_width 0.5)
			(island_removal_mode 0)
		)
		(polygon
			(pts
				(xy 112.72012 -132.174742) (xy 112.72012 -133.978142) (xy 113.27892 -133.978142) (xy 113.27892 -132.174742)
			)
		)
	)
	(zone
		(layer "In1.Cu")
		(hatch none 0.5)
		(connect_pads
			(clearance 0)
		)
		(min_thickness 0.25)
		(keepout
			(tracks not_allowed)
			(vias allowed)
			(pads allowed)
			(copperpour not_allowed)
			(footprints allowed)
		)
		(placement
			(enabled no)
			(sheetname "")
		)
		(fill
			(thermal_gap 0.5)
			(thermal_bridge_width 0.5)
			(island_removal_mode 0)
		)
		(polygon
			(pts
				(xy 277.720552 -155.977082) (xy 277.720552 -157.780482) (xy 278.279352 -157.780482) (xy 278.279352 -155.977082)
			)
		)
	)
	(zone
		(layer "In1.Cu")
		(hatch none 0.5)
		(connect_pads
			(clearance 0)
		)
		(min_thickness 0.25)
		(keepout
			(tracks not_allowed)
			(vias allowed)
			(pads allowed)
			(copperpour not_allowed)
			(footprints allowed)
		)
		(placement
			(enabled no)
			(sheetname "")
		)
		(fill
			(thermal_gap 0.5)
			(thermal_bridge_width 0.5)
			(island_removal_mode 0)
		)
		(polygon
			(pts
				(xy 119.519954 -155.977082) (xy 119.519954 -157.780482) (xy 120.078754 -157.780482) (xy 120.078754 -155.977082)
			)
		)
	)
	(zone
		(layer "In1.Cu")
		(hatch none 0.5)
		(connect_pads
			(clearance 0)
		)
		(min_thickness 0.25)
		(keepout
			(tracks not_allowed)
			(vias allowed)
			(pads allowed)
			(copperpour not_allowed)
			(footprints allowed)
		)
		(placement
			(enabled no)
			(sheetname "")
		)
		(fill
			(thermal_gap 0.5)
			(thermal_bridge_width 0.5)
			(island_removal_mode 0)
		)
		(polygon
			(pts
				(xy 242.020852 -136.774682) (xy 242.020852 -138.578082) (xy 242.579652 -138.578082) (xy 242.579652 -136.774682)
			)
		)
	)
	(zone
		(layer "In1.Cu")
		(hatch none 0.5)
		(connect_pads
			(clearance 0)
		)
		(min_thickness 0.25)
		(keepout
			(tracks not_allowed)
			(vias allowed)
			(pads allowed)
			(copperpour not_allowed)
			(footprints allowed)
		)
		(placement
			(enabled no)
			(sheetname "")
		)
		(fill
			(thermal_gap 0.5)
			(thermal_bridge_width 0.5)
			(island_removal_mode 0)
		)
		(polygon
			(pts
				(xy 297.270424 0.080518) (xy 297.270424 -1.722882) (xy 297.829224 -1.722882) (xy 297.829224 0.080518)
			)
		)
	)
	(zone
		(layer "In1.Cu")
		(hatch none 0.5)
		(connect_pads
			(clearance 0)
		)
		(min_thickness 0.25)
		(keepout
			(tracks not_allowed)
			(vias allowed)
			(pads allowed)
			(copperpour not_allowed)
			(footprints allowed)
		)
		(placement
			(enabled no)
			(sheetname "")
		)
		(fill
			(thermal_gap 0.5)
			(thermal_bridge_width 0.5)
			(island_removal_mode 0)
		)
		(polygon
			(pts
				(xy 253.070614 -19.121882) (xy 253.070614 -20.925282) (xy 253.629414 -20.925282) (xy 253.629414 -19.121882)
			)
		)
	)
	(zone
		(layer "In1.Cu")
		(hatch none 0.5)
		(connect_pads
			(clearance 0)
		)
		(min_thickness 0.25)
		(keepout
			(tracks not_allowed)
			(vias allowed)
			(pads allowed)
			(copperpour not_allowed)
			(footprints allowed)
		)
		(placement
			(enabled no)
			(sheetname "")
		)
		(fill
			(thermal_gap 0.5)
			(thermal_bridge_width 0.5)
			(island_removal_mode 0)
		)
		(polygon
			(pts
				(xy 293.87038 -19.121882) (xy 293.87038 -20.925282) (xy 294.42918 -20.925282) (xy 294.42918 -19.121882)
			)
		)
	)
	(zone
		(layer "In1.Cu")
		(hatch none 0.5)
		(connect_pads
			(clearance 0)
		)
		(min_thickness 0.25)
		(keepout
			(tracks not_allowed)
			(vias allowed)
			(pads allowed)
			(copperpour not_allowed)
			(footprints allowed)
		)
		(placement
			(enabled no)
			(sheetname "")
		)
		(fill
			(thermal_gap 0.5)
			(thermal_bridge_width 0.5)
			(island_removal_mode 0)
		)
		(polygon
			(pts
				(xy 139.919964 -155.977082) (xy 139.919964 -157.780482) (xy 140.478764 -157.780482) (xy 140.478764 -155.977082)
			)
		)
	)
	(zone
		(layer "In1.Cu")
		(hatch none 0.5)
		(connect_pads
			(clearance 0)
		)
		(min_thickness 0.25)
		(keepout
			(tracks not_allowed)
			(vias allowed)
			(pads allowed)
			(copperpour not_allowed)
			(footprints allowed)
		)
		(placement
			(enabled no)
			(sheetname "")
		)
		(fill
			(thermal_gap 0.5)
			(thermal_bridge_width 0.5)
			(island_removal_mode 0)
		)
		(polygon
			(pts
				(xy 220.77045 -132.174742) (xy 220.77045 -133.978142) (xy 221.32925 -133.978142) (xy 221.32925 -132.174742)
			)
		)
	)
	(zone
		(layer "In1.Cu")
		(hatch none 0.5)
		(connect_pads
			(clearance 0)
		)
		(min_thickness 0.25)
		(keepout
			(tracks not_allowed)
			(vias allowed)
			(pads allowed)
			(copperpour not_allowed)
			(footprints allowed)
		)
		(placement
			(enabled no)
			(sheetname "")
		)
		(fill
			(thermal_gap 0.5)
			(thermal_bridge_width 0.5)
			(island_removal_mode 0)
		)
		(polygon
			(pts
				(xy 300.670468 0.080518) (xy 300.670468 -1.722882) (xy 301.229268 -1.722882) (xy 301.229268 0.080518)
			)
		)
	)
	(zone
		(layer "In1.Cu")
		(hatch none 0.5)
		(connect_pads
			(clearance 0)
		)
		(min_thickness 0.25)
		(keepout
			(tracks not_allowed)
			(vias allowed)
			(pads allowed)
			(copperpour not_allowed)
			(footprints allowed)
		)
		(placement
			(enabled no)
			(sheetname "")
		)
		(fill
			(thermal_gap 0.5)
			(thermal_bridge_width 0.5)
			(island_removal_mode 0)
		)
		(polygon
			(pts
				(xy 105.070148 -146.375882) (xy 105.070148 -148.179282) (xy 105.628948 -148.179282) (xy 105.628948 -146.375882)
			)
		)
	)
	(zone
		(layer "In1.Cu")
		(hatch none 0.5)
		(connect_pads
			(clearance 0)
		)
		(min_thickness 0.25)
		(keepout
			(tracks not_allowed)
			(vias allowed)
			(pads allowed)
			(copperpour not_allowed)
			(footprints allowed)
		)
		(placement
			(enabled no)
			(sheetname "")
		)
		(fill
			(thermal_gap 0.5)
			(thermal_bridge_width 0.5)
			(island_removal_mode 0)
		)
		(polygon
			(pts
				(xy 247.12041 -146.375882) (xy 247.12041 -148.179282) (xy 247.67921 -148.179282) (xy 247.67921 -146.375882)
			)
		)
	)
	(zone
		(layer "In1.Cu")
		(hatch none 0.5)
		(connect_pads
			(clearance 0)
		)
		(min_thickness 0.25)
		(keepout
			(tracks not_allowed)
			(vias allowed)
			(pads allowed)
			(copperpour not_allowed)
			(footprints allowed)
		)
		(placement
			(enabled no)
			(sheetname "")
		)
		(fill
			(thermal_gap 0.5)
			(thermal_bridge_width 0.5)
			(island_removal_mode 0)
		)
		(polygon
			(pts
				(xy 115.270026 -136.774682) (xy 115.270026 -138.578082) (xy 115.828826 -138.578082) (xy 115.828826 -136.774682)
			)
		)
	)
	(zone
		(layer "In1.Cu")
		(hatch none 0.5)
		(connect_pads
			(clearance 0)
		)
		(min_thickness 0.25)
		(keepout
			(tracks not_allowed)
			(vias allowed)
			(pads allowed)
			(copperpour not_allowed)
			(footprints allowed)
		)
		(placement
			(enabled no)
			(sheetname "")
		)
		(fill
			(thermal_gap 0.5)
			(thermal_bridge_width 0.5)
			(island_removal_mode 0)
		)
		(polygon
			(pts
				(xy 198.670418 -19.121882) (xy 198.670418 -20.925282) (xy 199.229218 -20.925282) (xy 199.229218 -19.121882)
			)
		)
	)
	(zone
		(layer "In1.Cu")
		(hatch none 0.5)
		(connect_pads
			(clearance 0)
		)
		(min_thickness 0.25)
		(keepout
			(tracks not_allowed)
			(vias allowed)
			(pads allowed)
			(copperpour not_allowed)
			(footprints allowed)
		)
		(placement
			(enabled no)
			(sheetname "")
		)
		(fill
			(thermal_gap 0.5)
			(thermal_bridge_width 0.5)
			(island_removal_mode 0)
		)
		(polygon
			(pts
				(xy 237.770416 -132.174742) (xy 237.770416 -133.978142) (xy 238.329216 -133.978142) (xy 238.329216 -132.174742)
			)
		)
	)
	(zone
		(layer "In1.Cu")
		(hatch none 0.5)
		(connect_pads
			(clearance 0)
		)
		(min_thickness 0.25)
		(keepout
			(tracks not_allowed)
			(vias allowed)
			(pads allowed)
			(copperpour not_allowed)
			(footprints allowed)
		)
		(placement
			(enabled no)
			(sheetname "")
		)
		(fill
			(thermal_gap 0.5)
			(thermal_bridge_width 0.5)
			(island_removal_mode 0)
		)
		(polygon
			(pts
				(xy 244.570504 -132.174742) (xy 244.570504 -133.978142) (xy 245.129304 -133.978142) (xy 245.129304 -132.174742)
			)
		)
	)
	(zone
		(layer "In1.Cu")
		(hatch none 0.5)
		(connect_pads
			(clearance 0)
		)
		(min_thickness 0.25)
		(keepout
			(tracks not_allowed)
			(vias allowed)
			(pads allowed)
			(copperpour not_allowed)
			(footprints allowed)
		)
		(placement
			(enabled no)
			(sheetname "")
		)
		(fill
			(thermal_gap 0.5)
			(thermal_bridge_width 0.5)
			(island_removal_mode 0)
		)
		(polygon
			(pts
				(xy 279.42032 -141.775942) (xy 279.42032 -143.579342) (xy 279.97912 -143.579342) (xy 279.97912 -141.775942)
			)
		)
	)
	(zone
		(layer "In1.Cu")
		(hatch none 0.5)
		(connect_pads
			(clearance 0)
		)
		(min_thickness 0.25)
		(keepout
			(tracks not_allowed)
			(vias allowed)
			(pads allowed)
			(copperpour not_allowed)
			(footprints allowed)
		)
		(placement
			(enabled no)
			(sheetname "")
		)
		(fill
			(thermal_gap 0.5)
			(thermal_bridge_width 0.5)
			(island_removal_mode 0)
		)
		(polygon
			(pts
				(xy 102.519988 0.080518) (xy 102.519988 -1.722882) (xy 103.078788 -1.722882) (xy 103.078788 0.080518)
			)
		)
	)
	(zone
		(layer "In1.Cu")
		(hatch none 0.5)
		(connect_pads
			(clearance 0)
		)
		(min_thickness 0.25)
		(keepout
			(tracks not_allowed)
			(vias allowed)
			(pads allowed)
			(copperpour not_allowed)
			(footprints allowed)
		)
		(placement
			(enabled no)
			(sheetname "")
		)
		(fill
			(thermal_gap 0.5)
			(thermal_bridge_width 0.5)
			(island_removal_mode 0)
		)
		(polygon
			(pts
				(xy 111.020098 -146.375882) (xy 111.020098 -148.179282) (xy 111.578898 -148.179282) (xy 111.578898 -146.375882)
			)
		)
	)
	(zone
		(layer "In1.Cu")
		(hatch none 0.5)
		(connect_pads
			(clearance 0)
		)
		(min_thickness 0.25)
		(keepout
			(tracks not_allowed)
			(vias allowed)
			(pads allowed)
			(copperpour not_allowed)
			(footprints allowed)
		)
		(placement
			(enabled no)
			(sheetname "")
		)
		(fill
			(thermal_gap 0.5)
			(thermal_bridge_width 0.5)
			(island_removal_mode 0)
		)
		(polygon
			(pts
				(xy 107.620054 4.680458) (xy 107.620054 2.877058) (xy 108.178854 2.877058) (xy 108.178854 4.680458)
			)
		)
	)
	(zone
		(layer "In1.Cu")
		(hatch none 0.5)
		(connect_pads
			(clearance 0)
		)
		(min_thickness 0.25)
		(keepout
			(tracks not_allowed)
			(vias allowed)
			(pads allowed)
			(copperpour not_allowed)
			(footprints allowed)
		)
		(placement
			(enabled no)
			(sheetname "")
		)
		(fill
			(thermal_gap 0.5)
			(thermal_bridge_width 0.5)
			(island_removal_mode 0)
		)
		(polygon
			(pts
				(xy 129.720086 -14.521942) (xy 129.720086 -16.325342) (xy 130.278886 -16.325342) (xy 130.278886 -14.521942)
			)
		)
	)
	(zone
		(layer "In1.Cu")
		(hatch none 0.5)
		(connect_pads
			(clearance 0)
		)
		(min_thickness 0.25)
		(keepout
			(tracks not_allowed)
			(vias allowed)
			(pads allowed)
			(copperpour not_allowed)
			(footprints allowed)
		)
		(placement
			(enabled no)
			(sheetname "")
		)
		(fill
			(thermal_gap 0.5)
			(thermal_bridge_width 0.5)
			(island_removal_mode 0)
		)
		(polygon
			(pts
				(xy 52.369974 -155.977082) (xy 52.369974 -157.780482) (xy 52.928774 -157.780482) (xy 52.928774 -155.977082)
			)
		)
	)
	(zone
		(layer "In1.Cu")
		(hatch none 0.5)
		(connect_pads
			(clearance 0)
		)
		(min_thickness 0.25)
		(keepout
			(tracks not_allowed)
			(vias allowed)
			(pads allowed)
			(copperpour not_allowed)
			(footprints allowed)
		)
		(placement
			(enabled no)
			(sheetname "")
		)
		(fill
			(thermal_gap 0.5)
			(thermal_bridge_width 0.5)
			(island_removal_mode 0)
		)
		(polygon
			(pts
				(xy 311.720484 -155.977082) (xy 311.720484 -157.780482) (xy 312.279284 -157.780482) (xy 312.279284 -155.977082)
			)
		)
	)
	(zone
		(layer "In1.Cu")
		(hatch none 0.5)
		(connect_pads
			(clearance 0)
		)
		(min_thickness 0.25)
		(keepout
			(tracks not_allowed)
			(vias allowed)
			(pads allowed)
			(copperpour not_allowed)
			(footprints allowed)
		)
		(placement
			(enabled no)
			(sheetname "")
		)
		(fill
			(thermal_gap 0.5)
			(thermal_bridge_width 0.5)
			(island_removal_mode 0)
		)
		(polygon
			(pts
				(xy 114.419888 4.680458) (xy 114.419888 2.877058) (xy 114.978688 2.877058) (xy 114.978688 4.680458)
			)
		)
	)
	(zone
		(layer "In1.Cu")
		(hatch none 0.5)
		(connect_pads
			(clearance 0)
		)
		(min_thickness 0.25)
		(keepout
			(tracks not_allowed)
			(vias allowed)
			(pads allowed)
			(copperpour not_allowed)
			(footprints allowed)
		)
		(placement
			(enabled no)
			(sheetname "")
		)
		(fill
			(thermal_gap 0.5)
			(thermal_bridge_width 0.5)
			(island_removal_mode 0)
		)
		(polygon
			(pts
				(xy 54.069996 -4.920742) (xy 54.069996 -6.724142) (xy 54.628796 -6.724142) (xy 54.628796 -4.920742)
			)
		)
	)
	(zone
		(layer "In1.Cu")
		(hatch none 0.5)
		(connect_pads
			(clearance 0)
		)
		(min_thickness 0.25)
		(keepout
			(tracks not_allowed)
			(vias allowed)
			(pads allowed)
			(copperpour not_allowed)
			(footprints allowed)
		)
		(placement
			(enabled no)
			(sheetname "")
		)
		(fill
			(thermal_gap 0.5)
			(thermal_bridge_width 0.5)
			(island_removal_mode 0)
		)
		(polygon
			(pts
				(xy 251.370592 -151.377142) (xy 251.370592 -153.180542) (xy 251.929392 -153.180542) (xy 251.929392 -151.377142)
			)
		)
	)
	(zone
		(layer "In1.Cu")
		(hatch none 0.5)
		(connect_pads
			(clearance 0)
		)
		(min_thickness 0.25)
		(keepout
			(tracks not_allowed)
			(vias allowed)
			(pads allowed)
			(copperpour not_allowed)
			(footprints allowed)
		)
		(placement
			(enabled no)
			(sheetname "")
		)
		(fill
			(thermal_gap 0.5)
			(thermal_bridge_width 0.5)
			(island_removal_mode 0)
		)
		(polygon
			(pts
				(xy 34.520124 -4.920742) (xy 34.520124 -6.724142) (xy 35.078924 -6.724142) (xy 35.078924 -4.920742)
			)
		)
	)
	(zone
		(layer "In1.Cu")
		(hatch none 0.5)
		(connect_pads
			(clearance 0)
		)
		(min_thickness 0.25)
		(keepout
			(tracks not_allowed)
			(vias allowed)
			(pads allowed)
			(copperpour not_allowed)
			(footprints allowed)
		)
		(placement
			(enabled no)
			(sheetname "")
		)
		(fill
			(thermal_gap 0.5)
			(thermal_bridge_width 0.5)
			(island_removal_mode 0)
		)
		(polygon
			(pts
				(xy 406.618186 -3.789172) (xy 407.926286 -3.789172) (xy 407.926286 -4.982972) (xy 406.618186 -4.982972)
			)
		)
	)
	(zone
		(layer "In1.Cu")
		(hatch none 0.5)
		(connect_pads
			(clearance 0)
		)
		(min_thickness 0.25)
		(keepout
			(tracks not_allowed)
			(vias allowed)
			(pads allowed)
			(copperpour not_allowed)
			(footprints allowed)
		)
		(placement
			(enabled no)
			(sheetname "")
		)
		(fill
			(thermal_gap 0.5)
			(thermal_bridge_width 0.5)
			(island_removal_mode 0)
		)
		(polygon
			(pts
				(xy 128.020064 -151.377142) (xy 128.020064 -153.180542) (xy 128.578864 -153.180542) (xy 128.578864 -151.377142)
			)
		)
	)
	(zone
		(layer "In1.Cu")
		(hatch none 0.5)
		(connect_pads
			(clearance 0)
		)
		(min_thickness 0.25)
		(keepout
			(tracks not_allowed)
			(vias allowed)
			(pads allowed)
			(copperpour not_allowed)
			(footprints allowed)
		)
		(placement
			(enabled no)
			(sheetname "")
		)
		(fill
			(thermal_gap 0.5)
			(thermal_bridge_width 0.5)
			(island_removal_mode 0)
		)
		(polygon
			(pts
				(xy 117.819932 -132.174742) (xy 117.819932 -133.978142) (xy 118.378732 -133.978142) (xy 118.378732 -132.174742)
			)
		)
	)
	(zone
		(layer "In1.Cu")
		(hatch none 0.5)
		(connect_pads
			(clearance 0)
		)
		(min_thickness 0.25)
		(keepout
			(tracks not_allowed)
			(vias allowed)
			(pads allowed)
			(copperpour not_allowed)
			(footprints allowed)
		)
		(placement
			(enabled no)
			(sheetname "")
		)
		(fill
			(thermal_gap 0.5)
			(thermal_bridge_width 0.5)
			(island_removal_mode 0)
		)
		(polygon
			(pts
				(xy 51.52009 4.680458) (xy 51.52009 2.877058) (xy 52.07889 2.877058) (xy 52.07889 4.680458)
			)
		)
	)
	(zone
		(layer "In1.Cu")
		(hatch none 0.5)
		(connect_pads
			(clearance 0)
		)
		(min_thickness 0.25)
		(keepout
			(tracks not_allowed)
			(vias allowed)
			(pads allowed)
			(copperpour not_allowed)
			(footprints allowed)
		)
		(placement
			(enabled no)
			(sheetname "")
		)
		(fill
			(thermal_gap 0.5)
			(thermal_bridge_width 0.5)
			(island_removal_mode 0)
		)
		(polygon
			(pts
				(xy 226.7204 -146.375882) (xy 226.7204 -148.179282) (xy 227.2792 -148.179282) (xy 227.2792 -146.375882)
			)
		)
	)
	(zone
		(layer "In1.Cu")
		(hatch none 0.5)
		(connect_pads
			(clearance 0)
		)
		(min_thickness 0.25)
		(keepout
			(tracks not_allowed)
			(vias allowed)
			(pads allowed)
			(copperpour not_allowed)
			(footprints allowed)
		)
		(placement
			(enabled no)
			(sheetname "")
		)
		(fill
			(thermal_gap 0.5)
			(thermal_bridge_width 0.5)
			(island_removal_mode 0)
		)
		(polygon
			(pts
				(xy 122.919998 -155.977082) (xy 122.919998 -157.780482) (xy 123.478798 -157.780482) (xy 123.478798 -155.977082)
			)
		)
	)
	(zone
		(layer "In1.Cu")
		(hatch none 0.5)
		(connect_pads
			(clearance 0)
		)
		(min_thickness 0.25)
		(keepout
			(tracks not_allowed)
			(vias allowed)
			(pads allowed)
			(copperpour not_allowed)
			(footprints allowed)
		)
		(placement
			(enabled no)
			(sheetname "")
		)
		(fill
			(thermal_gap 0.5)
			(thermal_bridge_width 0.5)
			(island_removal_mode 0)
		)
		(polygon
			(pts
				(xy 230.970582 0.080518) (xy 230.970582 -1.722882) (xy 231.529382 -1.722882) (xy 231.529382 0.080518)
			)
		)
	)
	(zone
		(layer "In1.Cu")
		(hatch none 0.5)
		(connect_pads
			(clearance 0)
		)
		(min_thickness 0.25)
		(keepout
			(tracks not_allowed)
			(vias allowed)
			(pads allowed)
			(copperpour not_allowed)
			(footprints allowed)
		)
		(placement
			(enabled no)
			(sheetname "")
		)
		(fill
			(thermal_gap 0.5)
			(thermal_bridge_width 0.5)
			(island_removal_mode 0)
		)
		(polygon
			(pts
				(xy 276.02053 -141.775942) (xy 276.02053 -143.579342) (xy 276.57933 -143.579342) (xy 276.57933 -141.775942)
			)
		)
	)
	(zone
		(layer "In1.Cu")
		(hatch none 0.5)
		(connect_pads
			(clearance 0)
		)
		(min_thickness 0.25)
		(keepout
			(tracks not_allowed)
			(vias allowed)
			(pads allowed)
			(copperpour not_allowed)
			(footprints allowed)
		)
		(placement
			(enabled no)
			(sheetname "")
		)
		(fill
			(thermal_gap 0.5)
			(thermal_bridge_width 0.5)
			(island_removal_mode 0)
		)
		(polygon
			(pts
				(xy 198.670418 -136.774682) (xy 198.670418 -138.578082) (xy 199.229218 -138.578082) (xy 199.229218 -136.774682)
			)
		)
	)
	(zone
		(layer "In1.Cu")
		(hatch none 0.5)
		(connect_pads
			(clearance 0)
		)
		(min_thickness 0.25)
		(keepout
			(tracks not_allowed)
			(vias allowed)
			(pads allowed)
			(copperpour not_allowed)
			(footprints allowed)
		)
		(placement
			(enabled no)
			(sheetname "")
		)
		(fill
			(thermal_gap 0.5)
			(thermal_bridge_width 0.5)
			(island_removal_mode 0)
		)
		(polygon
			(pts
				(xy 302.37049 -136.774682) (xy 302.37049 -138.578082) (xy 302.92929 -138.578082) (xy 302.92929 -136.774682)
			)
		)
	)
	(zone
		(layer "In1.Cu")
		(hatch none 0.5)
		(connect_pads
			(clearance 0)
		)
		(min_thickness 0.25)
		(keepout
			(tracks not_allowed)
			(vias allowed)
			(pads allowed)
			(copperpour not_allowed)
			(footprints allowed)
		)
		(placement
			(enabled no)
			(sheetname "")
		)
		(fill
			(thermal_gap 0.5)
			(thermal_bridge_width 0.5)
			(island_removal_mode 0)
		)
		(polygon
			(pts
				(xy 35.370008 -4.920742) (xy 35.370008 -6.724142) (xy 35.928808 -6.724142) (xy 35.928808 -4.920742)
			)
		)
	)
	(zone
		(layer "In1.Cu")
		(hatch none 0.5)
		(connect_pads
			(clearance 0)
		)
		(min_thickness 0.25)
		(keepout
			(tracks not_allowed)
			(vias allowed)
			(pads allowed)
			(copperpour not_allowed)
			(footprints allowed)
		)
		(placement
			(enabled no)
			(sheetname "")
		)
		(fill
			(thermal_gap 0.5)
			(thermal_bridge_width 0.5)
			(island_removal_mode 0)
		)
		(polygon
			(pts
				(xy 101.670104 -19.121882) (xy 101.670104 -20.925282) (xy 102.228904 -20.925282) (xy 102.228904 -19.121882)
			)
		)
	)
	(zone
		(layer "In1.Cu")
		(hatch none 0.5)
		(connect_pads
			(clearance 0)
		)
		(min_thickness 0.25)
		(keepout
			(tracks not_allowed)
			(vias allowed)
			(pads allowed)
			(copperpour not_allowed)
			(footprints allowed)
		)
		(placement
			(enabled no)
			(sheetname "")
		)
		(fill
			(thermal_gap 0.5)
			(thermal_bridge_width 0.5)
			(island_removal_mode 0)
		)
		(polygon
			(pts
				(xy 82.119978 0.080518) (xy 82.119978 -1.722882) (xy 82.678778 -1.722882) (xy 82.678778 0.080518)
			)
		)
	)
	(zone
		(layer "In1.Cu")
		(hatch none 0.5)
		(connect_pads
			(clearance 0)
		)
		(min_thickness 0.25)
		(keepout
			(tracks not_allowed)
			(vias allowed)
			(pads allowed)
			(copperpour not_allowed)
			(footprints allowed)
		)
		(placement
			(enabled no)
			(sheetname "")
		)
		(fill
			(thermal_gap 0.5)
			(thermal_bridge_width 0.5)
			(island_removal_mode 0)
		)
		(polygon
			(pts
				(xy 102.519988 -136.774682) (xy 102.519988 -138.578082) (xy 103.078788 -138.578082) (xy 103.078788 -136.774682)
			)
		)
	)
	(zone
		(layer "In1.Cu")
		(hatch none 0.5)
		(connect_pads
			(clearance 0)
		)
		(min_thickness 0.25)
		(keepout
			(tracks not_allowed)
			(vias allowed)
			(pads allowed)
			(copperpour not_allowed)
			(footprints allowed)
		)
		(placement
			(enabled no)
			(sheetname "")
		)
		(fill
			(thermal_gap 0.5)
			(thermal_bridge_width 0.5)
			(island_removal_mode 0)
		)
		(polygon
			(pts
				(xy 267.52042 -155.977082) (xy 267.52042 -157.780482) (xy 268.07922 -157.780482) (xy 268.07922 -155.977082)
			)
		)
	)
	(zone
		(layer "In1.Cu")
		(hatch none 0.5)
		(connect_pads
			(clearance 0)
		)
		(min_thickness 0.25)
		(keepout
			(tracks not_allowed)
			(vias allowed)
			(pads allowed)
			(copperpour not_allowed)
			(footprints allowed)
		)
		(placement
			(enabled no)
			(sheetname "")
		)
		(fill
			(thermal_gap 0.5)
			(thermal_bridge_width 0.5)
			(island_removal_mode 0)
		)
		(polygon
			(pts
				(xy 296.42054 -4.920742) (xy 296.42054 -6.724142) (xy 296.97934 -6.724142) (xy 296.97934 -4.920742)
			)
		)
	)
	(zone
		(layer "In1.Cu")
		(hatch none 0.5)
		(connect_pads
			(clearance 0)
		)
		(min_thickness 0.25)
		(keepout
			(tracks not_allowed)
			(vias allowed)
			(pads allowed)
			(copperpour not_allowed)
			(footprints allowed)
		)
		(placement
			(enabled no)
			(sheetname "")
		)
		(fill
			(thermal_gap 0.5)
			(thermal_bridge_width 0.5)
			(island_removal_mode 0)
		)
		(polygon
			(pts
				(xy 219.070428 -146.375882) (xy 219.070428 -148.179282) (xy 219.629228 -148.179282) (xy 219.629228 -146.375882)
			)
		)
	)
	(zone
		(layer "In1.Cu")
		(hatch none 0.5)
		(connect_pads
			(clearance 0)
		)
		(min_thickness 0.25)
		(keepout
			(tracks not_allowed)
			(vias allowed)
			(pads allowed)
			(copperpour not_allowed)
			(footprints allowed)
		)
		(placement
			(enabled no)
			(sheetname "")
		)
		(fill
			(thermal_gap 0.5)
			(thermal_bridge_width 0.5)
			(island_removal_mode 0)
		)
		(polygon
			(pts
				(xy 299.82033 -141.775942) (xy 299.82033 -143.579342) (xy 300.37913 -143.579342) (xy 300.37913 -141.775942)
			)
		)
	)
	(zone
		(layer "In1.Cu")
		(hatch none 0.5)
		(connect_pads
			(clearance 0)
		)
		(min_thickness 0.25)
		(keepout
			(tracks not_allowed)
			(vias allowed)
			(pads allowed)
			(copperpour not_allowed)
			(footprints allowed)
		)
		(placement
			(enabled no)
			(sheetname "")
		)
		(fill
			(thermal_gap 0.5)
			(thermal_bridge_width 0.5)
			(island_removal_mode 0)
		)
		(polygon
			(pts
				(xy 230.120444 -132.174742) (xy 230.120444 -133.978142) (xy 230.679244 -133.978142) (xy 230.679244 -132.174742)
			)
		)
	)
	(zone
		(layer "In1.Cu")
		(hatch none 0.5)
		(connect_pads
			(clearance 0)
		)
		(min_thickness 0.25)
		(keepout
			(tracks not_allowed)
			(vias allowed)
			(pads allowed)
			(copperpour not_allowed)
			(footprints allowed)
		)
		(placement
			(enabled no)
			(sheetname "")
		)
		(fill
			(thermal_gap 0.5)
			(thermal_bridge_width 0.5)
			(island_removal_mode 0)
		)
		(polygon
			(pts
				(xy 52.369974 -19.121882) (xy 52.369974 -20.925282) (xy 52.928774 -20.925282) (xy 52.928774 -19.121882)
			)
		)
	)
	(zone
		(layer "In1.Cu")
		(hatch none 0.5)
		(connect_pads
			(clearance 0)
		)
		(min_thickness 0.25)
		(keepout
			(tracks not_allowed)
			(vias allowed)
			(pads allowed)
			(copperpour not_allowed)
			(footprints allowed)
		)
		(placement
			(enabled no)
			(sheetname "")
		)
		(fill
			(thermal_gap 0.5)
			(thermal_bridge_width 0.5)
			(island_removal_mode 0)
		)
		(polygon
			(pts
				(xy 128.020064 0.080518) (xy 128.020064 -1.722882) (xy 128.578864 -1.722882) (xy 128.578864 0.080518)
			)
		)
	)
	(zone
		(layer "In1.Cu")
		(hatch none 0.5)
		(connect_pads
			(clearance 0)
		)
		(min_thickness 0.25)
		(keepout
			(tracks not_allowed)
			(vias allowed)
			(pads allowed)
			(copperpour not_allowed)
			(footprints allowed)
		)
		(placement
			(enabled no)
			(sheetname "")
		)
		(fill
			(thermal_gap 0.5)
			(thermal_bridge_width 0.5)
			(island_removal_mode 0)
		)
		(polygon
			(pts
				(xy 82.119978 -14.521942) (xy 82.119978 -16.325342) (xy 82.678778 -16.325342) (xy 82.678778 -14.521942)
			)
		)
	)
	(zone
		(layer "In1.Cu")
		(hatch none 0.5)
		(connect_pads
			(clearance 0)
		)
		(min_thickness 0.25)
		(keepout
			(tracks not_allowed)
			(vias allowed)
			(pads allowed)
			(copperpour not_allowed)
			(footprints allowed)
		)
		(placement
			(enabled no)
			(sheetname "")
		)
		(fill
			(thermal_gap 0.5)
			(thermal_bridge_width 0.5)
			(island_removal_mode 0)
		)
		(polygon
			(pts
				(xy 87.220044 -146.375882) (xy 87.220044 -148.179282) (xy 87.778844 -148.179282) (xy 87.778844 -146.375882)
			)
		)
	)
	(zone
		(layer "In1.Cu")
		(hatch none 0.5)
		(connect_pads
			(clearance 0)
		)
		(min_thickness 0.25)
		(keepout
			(tracks not_allowed)
			(vias allowed)
			(pads allowed)
			(copperpour not_allowed)
			(footprints allowed)
		)
		(placement
			(enabled no)
			(sheetname "")
		)
		(fill
			(thermal_gap 0.5)
			(thermal_bridge_width 0.5)
			(island_removal_mode 0)
		)
		(polygon
			(pts
				(xy 62.570106 -141.775942) (xy 62.570106 -143.579342) (xy 63.128906 -143.579342) (xy 63.128906 -141.775942)
			)
		)
	)
	(zone
		(layer "In1.Cu")
		(hatch none 0.5)
		(connect_pads
			(clearance 0)
		)
		(min_thickness 0.25)
		(keepout
			(tracks not_allowed)
			(vias allowed)
			(pads allowed)
			(copperpour not_allowed)
			(footprints allowed)
		)
		(placement
			(enabled no)
			(sheetname "")
		)
		(fill
			(thermal_gap 0.5)
			(thermal_bridge_width 0.5)
			(island_removal_mode 0)
		)
		(polygon
			(pts
				(xy 465.146898 -111.011716) (xy 466.454998 -111.011716) (xy 466.454998 -113.399316) (xy 465.146898 -113.399316)
			)
		)
	)
	(zone
		(layer "In1.Cu")
		(hatch none 0.5)
		(connect_pads
			(clearance 0)
		)
		(min_thickness 0.25)
		(keepout
			(tracks not_allowed)
			(vias allowed)
			(pads allowed)
			(copperpour not_allowed)
			(footprints allowed)
		)
		(placement
			(enabled no)
			(sheetname "")
		)
		(fill
			(thermal_gap 0.5)
			(thermal_bridge_width 0.5)
			(island_removal_mode 0)
		)
		(polygon
			(pts
				(xy 199.520556 -151.377142) (xy 199.520556 -153.180542) (xy 200.079356 -153.180542) (xy 200.079356 -151.377142)
			)
		)
	)
	(zone
		(layer "In1.Cu")
		(hatch none 0.5)
		(connect_pads
			(clearance 0)
		)
		(min_thickness 0.25)
		(keepout
			(tracks not_allowed)
			(vias allowed)
			(pads allowed)
			(copperpour not_allowed)
			(footprints allowed)
		)
		(placement
			(enabled no)
			(sheetname "")
		)
		(fill
			(thermal_gap 0.5)
			(thermal_bridge_width 0.5)
			(island_removal_mode 0)
		)
		(polygon
			(pts
				(xy 85.520022 -9.520682) (xy 85.520022 -11.324082) (xy 86.078822 -11.324082) (xy 86.078822 -9.520682)
			)
		)
	)
	(zone
		(layer "In1.Cu")
		(hatch none 0.5)
		(connect_pads
			(clearance 0)
		)
		(min_thickness 0.25)
		(keepout
			(tracks not_allowed)
			(vias allowed)
			(pads allowed)
			(copperpour not_allowed)
			(footprints allowed)
		)
		(placement
			(enabled no)
			(sheetname "")
		)
		(fill
			(thermal_gap 0.5)
			(thermal_bridge_width 0.5)
			(island_removal_mode 0)
		)
		(polygon
			(pts
				(xy 209.720434 -141.775942) (xy 209.720434 -143.579342) (xy 210.279234 -143.579342) (xy 210.279234 -141.775942)
			)
		)
	)
	(zone
		(layer "In1.Cu")
		(hatch none 0.5)
		(connect_pads
			(clearance 0)
		)
		(min_thickness 0.25)
		(keepout
			(tracks not_allowed)
			(vias allowed)
			(pads allowed)
			(copperpour not_allowed)
			(footprints allowed)
		)
		(placement
			(enabled no)
			(sheetname "")
		)
		(fill
			(thermal_gap 0.5)
			(thermal_bridge_width 0.5)
			(island_removal_mode 0)
		)
		(polygon
			(pts
				(xy 417.019486 -7.192772) (xy 418.327586 -7.192772) (xy 418.327586 -8.386572) (xy 417.019486 -8.386572)
			)
		)
	)
	(zone
		(layer "In1.Cu")
		(hatch none 0.5)
		(connect_pads
			(clearance 0)
		)
		(min_thickness 0.25)
		(keepout
			(tracks not_allowed)
			(vias allowed)
			(pads allowed)
			(copperpour not_allowed)
			(footprints allowed)
		)
		(placement
			(enabled no)
			(sheetname "")
		)
		(fill
			(thermal_gap 0.5)
			(thermal_bridge_width 0.5)
			(island_removal_mode 0)
		)
		(polygon
			(pts
				(xy 291.320474 0.080518) (xy 291.320474 -1.722882) (xy 291.879274 -1.722882) (xy 291.879274 0.080518)
			)
		)
	)
	(zone
		(layer "In1.Cu")
		(hatch none 0.5)
		(connect_pads
			(clearance 0)
		)
		(min_thickness 0.25)
		(keepout
			(tracks not_allowed)
			(vias allowed)
			(pads allowed)
			(copperpour not_allowed)
			(footprints allowed)
		)
		(placement
			(enabled no)
			(sheetname "")
		)
		(fill
			(thermal_gap 0.5)
			(thermal_bridge_width 0.5)
			(island_removal_mode 0)
		)
		(polygon
			(pts
				(xy 227.570538 4.680458) (xy 227.570538 2.877058) (xy 228.129338 2.877058) (xy 228.129338 4.680458)
			)
		)
	)
	(zone
		(layer "In1.Cu")
		(hatch none 0.5)
		(connect_pads
			(clearance 0)
		)
		(min_thickness 0.25)
		(keepout
			(tracks not_allowed)
			(vias allowed)
			(pads allowed)
			(copperpour not_allowed)
			(footprints allowed)
		)
		(placement
			(enabled no)
			(sheetname "")
		)
		(fill
			(thermal_gap 0.5)
			(thermal_bridge_width 0.5)
			(island_removal_mode 0)
		)
		(polygon
			(pts
				(xy 202.9206 -19.121882) (xy 202.9206 -20.925282) (xy 203.4794 -20.925282) (xy 203.4794 -19.121882)
			)
		)
	)
	(zone
		(layer "In1.Cu")
		(hatch none 0.5)
		(connect_pads
			(clearance 0)
		)
		(min_thickness 0.25)
		(keepout
			(tracks not_allowed)
			(vias allowed)
			(pads allowed)
			(copperpour not_allowed)
			(footprints allowed)
		)
		(placement
			(enabled no)
			(sheetname "")
		)
		(fill
			(thermal_gap 0.5)
			(thermal_bridge_width 0.5)
			(island_removal_mode 0)
		)
		(polygon
			(pts
				(xy 59.170062 -141.775942) (xy 59.170062 -143.579342) (xy 59.728862 -143.579342) (xy 59.728862 -141.775942)
			)
		)
	)
	(zone
		(layer "In1.Cu")
		(hatch none 0.5)
		(connect_pads
			(clearance 0)
		)
		(min_thickness 0.25)
		(keepout
			(tracks not_allowed)
			(vias allowed)
			(pads allowed)
			(copperpour not_allowed)
			(footprints allowed)
		)
		(placement
			(enabled no)
			(sheetname "")
		)
		(fill
			(thermal_gap 0.5)
			(thermal_bridge_width 0.5)
			(island_removal_mode 0)
		)
		(polygon
			(pts
				(xy 147.569936 0.080518) (xy 147.569936 -1.722882) (xy 148.128736 -1.722882) (xy 148.128736 0.080518)
			)
		)
	)
	(zone
		(layer "In1.Cu")
		(hatch none 0.5)
		(connect_pads
			(clearance 0)
		)
		(min_thickness 0.25)
		(keepout
			(tracks not_allowed)
			(vias allowed)
			(pads allowed)
			(copperpour not_allowed)
			(footprints allowed)
		)
		(placement
			(enabled no)
			(sheetname "")
		)
		(fill
			(thermal_gap 0.5)
			(thermal_bridge_width 0.5)
			(island_removal_mode 0)
		)
		(polygon
			(pts
				(xy 136.51992 -151.377142) (xy 136.51992 -153.180542) (xy 137.07872 -153.180542) (xy 137.07872 -151.377142)
			)
		)
	)
	(zone
		(layer "In1.Cu")
		(hatch none 0.5)
		(connect_pads
			(clearance 0)
		)
		(min_thickness 0.25)
		(keepout
			(tracks not_allowed)
			(vias allowed)
			(pads allowed)
			(copperpour not_allowed)
			(footprints allowed)
		)
		(placement
			(enabled no)
			(sheetname "")
		)
		(fill
			(thermal_gap 0.5)
			(thermal_bridge_width 0.5)
			(island_removal_mode 0)
		)
		(polygon
			(pts
				(xy 208.020412 -136.774682) (xy 208.020412 -138.578082) (xy 208.579212 -138.578082) (xy 208.579212 -136.774682)
			)
		)
	)
	(zone
		(layer "In1.Cu")
		(hatch none 0.5)
		(connect_pads
			(clearance 0)
		)
		(min_thickness 0.25)
		(keepout
			(tracks not_allowed)
			(vias allowed)
			(pads allowed)
			(copperpour not_allowed)
			(footprints allowed)
		)
		(placement
			(enabled no)
			(sheetname "")
		)
		(fill
			(thermal_gap 0.5)
			(thermal_bridge_width 0.5)
			(island_removal_mode 0)
		)
		(polygon
			(pts
				(xy 77.02042 -155.977082) (xy 77.02042 -157.780482) (xy 77.57922 -157.780482) (xy 77.57922 -155.977082)
			)
		)
	)
	(zone
		(layer "In1.Cu")
		(hatch none 0.5)
		(connect_pads
			(clearance 0)
		)
		(min_thickness 0.25)
		(keepout
			(tracks not_allowed)
			(vias allowed)
			(pads allowed)
			(copperpour not_allowed)
			(footprints allowed)
		)
		(placement
			(enabled no)
			(sheetname "")
		)
		(fill
			(thermal_gap 0.5)
			(thermal_bridge_width 0.5)
			(island_removal_mode 0)
		)
		(polygon
			(pts
				(xy 71.069962 -155.977082) (xy 71.069962 -157.780482) (xy 71.628762 -157.780482) (xy 71.628762 -155.977082)
			)
		)
	)
	(zone
		(layer "In1.Cu")
		(hatch none 0.5)
		(connect_pads
			(clearance 0)
		)
		(min_thickness 0.25)
		(keepout
			(tracks not_allowed)
			(vias allowed)
			(pads allowed)
			(copperpour not_allowed)
			(footprints allowed)
		)
		(placement
			(enabled no)
			(sheetname "")
		)
		(fill
			(thermal_gap 0.5)
			(thermal_bridge_width 0.5)
			(island_removal_mode 0)
		)
		(polygon
			(pts
				(xy 287.070546 -141.775942) (xy 287.070546 -143.579342) (xy 287.629346 -143.579342) (xy 287.629346 -141.775942)
			)
		)
	)
	(zone
		(layer "In1.Cu")
		(hatch none 0.5)
		(connect_pads
			(clearance 0)
		)
		(min_thickness 0.25)
		(keepout
			(tracks not_allowed)
			(vias allowed)
			(pads allowed)
			(copperpour not_allowed)
			(footprints allowed)
		)
		(placement
			(enabled no)
			(sheetname "")
		)
		(fill
			(thermal_gap 0.5)
			(thermal_bridge_width 0.5)
			(island_removal_mode 0)
		)
		(polygon
			(pts
				(xy 31.969964 -136.774682) (xy 31.969964 -138.578082) (xy 32.528764 -138.578082) (xy 32.528764 -136.774682)
			)
		)
	)
	(zone
		(layer "In1.Cu")
		(hatch none 0.5)
		(connect_pads
			(clearance 0)
		)
		(min_thickness 0.25)
		(keepout
			(tracks not_allowed)
			(vias allowed)
			(pads allowed)
			(copperpour not_allowed)
			(footprints allowed)
		)
		(placement
			(enabled no)
			(sheetname "")
		)
		(fill
			(thermal_gap 0.5)
			(thermal_bridge_width 0.5)
			(island_removal_mode 0)
		)
		(polygon
			(pts
				(xy 371.63121 -7.193026) (xy 372.939056 -7.193026) (xy 372.939056 -8.386826) (xy 371.63121 -8.386826)
			)
		)
	)
	(zone
		(layer "In1.Cu")
		(hatch none 0.5)
		(connect_pads
			(clearance 0)
		)
		(min_thickness 0.25)
		(keepout
			(tracks not_allowed)
			(vias allowed)
			(pads allowed)
			(copperpour not_allowed)
			(footprints allowed)
		)
		(placement
			(enabled no)
			(sheetname "")
		)
		(fill
			(thermal_gap 0.5)
			(thermal_bridge_width 0.5)
			(island_removal_mode 0)
		)
		(polygon
			(pts
				(xy 369.231164 -7.193026) (xy 370.53901 -7.193026) (xy 370.53901 -8.386826) (xy 369.231164 -8.386826)
			)
		)
	)
	(zone
		(layer "In1.Cu")
		(hatch none 0.5)
		(connect_pads
			(clearance 0)
		)
		(min_thickness 0.25)
		(keepout
			(tracks not_allowed)
			(vias allowed)
			(pads allowed)
			(copperpour not_allowed)
			(footprints allowed)
		)
		(placement
			(enabled no)
			(sheetname "")
		)
		(fill
			(thermal_gap 0.5)
			(thermal_bridge_width 0.5)
			(island_removal_mode 0)
		)
		(polygon
			(pts
				(xy 265.820398 -151.377142) (xy 265.820398 -153.180542) (xy 266.379198 -153.180542) (xy 266.379198 -151.377142)
			)
		)
	)
	(zone
		(layer "In1.Cu")
		(hatch none 0.5)
		(connect_pads
			(clearance 0)
		)
		(min_thickness 0.25)
		(keepout
			(tracks not_allowed)
			(vias allowed)
			(pads allowed)
			(copperpour not_allowed)
			(footprints allowed)
		)
		(placement
			(enabled no)
			(sheetname "")
		)
		(fill
			(thermal_gap 0.5)
			(thermal_bridge_width 0.5)
			(island_removal_mode 0)
		)
		(polygon
			(pts
				(xy 247.12041 -14.521942) (xy 247.12041 -16.325342) (xy 247.67921 -16.325342) (xy 247.67921 -14.521942)
			)
		)
	)
	(zone
		(layer "In1.Cu")
		(hatch none 0.5)
		(connect_pads
			(clearance 0)
		)
		(min_thickness 0.25)
		(keepout
			(tracks not_allowed)
			(vias allowed)
			(pads allowed)
			(copperpour not_allowed)
			(footprints allowed)
		)
		(placement
			(enabled no)
			(sheetname "")
		)
		(fill
			(thermal_gap 0.5)
			(thermal_bridge_width 0.5)
			(island_removal_mode 0)
		)
		(polygon
			(pts
				(xy 315.120528 4.680458) (xy 315.120528 2.877058) (xy 315.679328 2.877058) (xy 315.679328 4.680458)
			)
		)
	)
	(zone
		(layer "In1.Cu")
		(hatch none 0.5)
		(connect_pads
			(clearance 0)
		)
		(min_thickness 0.25)
		(keepout
			(tracks not_allowed)
			(vias allowed)
			(pads allowed)
			(copperpour not_allowed)
			(footprints allowed)
		)
		(placement
			(enabled no)
			(sheetname "")
		)
		(fill
			(thermal_gap 0.5)
			(thermal_bridge_width 0.5)
			(island_removal_mode 0)
		)
		(polygon
			(pts
				(xy 143.320008 -19.121882) (xy 143.320008 -20.925282) (xy 143.878808 -20.925282) (xy 143.878808 -19.121882)
			)
		)
	)
	(zone
		(layer "In1.Cu")
		(hatch none 0.5)
		(connect_pads
			(clearance 0)
		)
		(min_thickness 0.25)
		(keepout
			(tracks not_allowed)
			(vias allowed)
			(pads allowed)
			(copperpour not_allowed)
			(footprints allowed)
		)
		(placement
			(enabled no)
			(sheetname "")
		)
		(fill
			(thermal_gap 0.5)
			(thermal_bridge_width 0.5)
			(island_removal_mode 0)
		)
		(polygon
			(pts
				(xy 254.770382 0.080518) (xy 254.770382 -1.722882) (xy 255.329182 -1.722882) (xy 255.329182 0.080518)
			)
		)
	)
	(zone
		(layer "In1.Cu")
		(hatch none 0.5)
		(connect_pads
			(clearance 0)
		)
		(min_thickness 0.25)
		(keepout
			(tracks not_allowed)
			(vias allowed)
			(pads allowed)
			(copperpour not_allowed)
			(footprints allowed)
		)
		(placement
			(enabled no)
			(sheetname "")
		)
		(fill
			(thermal_gap 0.5)
			(thermal_bridge_width 0.5)
			(island_removal_mode 0)
		)
		(polygon
			(pts
				(xy 267.52042 -151.377142) (xy 267.52042 -153.180542) (xy 268.07922 -153.180542) (xy 268.07922 -151.377142)
			)
		)
	)
	(zone
		(layer "In1.Cu")
		(hatch none 0.5)
		(connect_pads
			(clearance 0)
		)
		(min_thickness 0.25)
		(keepout
			(tracks not_allowed)
			(vias allowed)
			(pads allowed)
			(copperpour not_allowed)
			(footprints allowed)
		)
		(placement
			(enabled no)
			(sheetname "")
		)
		(fill
			(thermal_gap 0.5)
			(thermal_bridge_width 0.5)
			(island_removal_mode 0)
		)
		(polygon
			(pts
				(xy 461.947006 -111.011716) (xy 463.254852 -111.011716) (xy 463.254852 -113.399316) (xy 461.947006 -113.399316)
			)
		)
	)
	(zone
		(layer "In1.Cu")
		(hatch none 0.5)
		(connect_pads
			(clearance 0)
		)
		(min_thickness 0.25)
		(keepout
			(tracks not_allowed)
			(vias allowed)
			(pads allowed)
			(copperpour not_allowed)
			(footprints allowed)
		)
		(placement
			(enabled no)
			(sheetname "")
		)
		(fill
			(thermal_gap 0.5)
			(thermal_bridge_width 0.5)
			(island_removal_mode 0)
		)
		(polygon
			(pts
				(xy 431.421286 -7.192772) (xy 432.729386 -7.192772) (xy 432.729386 -8.386572) (xy 431.421286 -8.386572)
			)
		)
	)
	(zone
		(layer "In1.Cu")
		(hatch none 0.5)
		(connect_pads
			(clearance 0)
		)
		(min_thickness 0.25)
		(keepout
			(tracks not_allowed)
			(vias allowed)
			(pads allowed)
			(copperpour not_allowed)
			(footprints allowed)
		)
		(placement
			(enabled no)
			(sheetname "")
		)
		(fill
			(thermal_gap 0.5)
			(thermal_bridge_width 0.5)
			(island_removal_mode 0)
		)
		(polygon
			(pts
				(xy 132.269992 -19.121882) (xy 132.269992 -20.925282) (xy 132.828792 -20.925282) (xy 132.828792 -19.121882)
			)
		)
	)
	(zone
		(layer "In1.Cu")
		(hatch none 0.5)
		(connect_pads
			(clearance 0)
		)
		(min_thickness 0.25)
		(keepout
			(tracks not_allowed)
			(vias allowed)
			(pads allowed)
			(copperpour not_allowed)
			(footprints allowed)
		)
		(placement
			(enabled no)
			(sheetname "")
		)
		(fill
			(thermal_gap 0.5)
			(thermal_bridge_width 0.5)
			(island_removal_mode 0)
		)
		(polygon
			(pts
				(xy 108.469938 -136.774682) (xy 108.469938 -138.578082) (xy 109.028738 -138.578082) (xy 109.028738 -136.774682)
			)
		)
	)
	(zone
		(layer "In1.Cu")
		(hatch none 0.5)
		(connect_pads
			(clearance 0)
		)
		(min_thickness 0.25)
		(keepout
			(tracks not_allowed)
			(vias allowed)
			(pads allowed)
			(copperpour not_allowed)
			(footprints allowed)
		)
		(placement
			(enabled no)
			(sheetname "")
		)
		(fill
			(thermal_gap 0.5)
			(thermal_bridge_width 0.5)
			(island_removal_mode 0)
		)
		(polygon
			(pts
				(xy 119.519954 -19.121882) (xy 119.519954 -20.925282) (xy 120.078754 -20.925282) (xy 120.078754 -19.121882)
			)
		)
	)
	(zone
		(layer "In1.Cu")
		(hatch none 0.5)
		(connect_pads
			(clearance 0)
		)
		(min_thickness 0.25)
		(keepout
			(tracks not_allowed)
			(vias allowed)
			(pads allowed)
			(copperpour not_allowed)
			(footprints allowed)
		)
		(placement
			(enabled no)
			(sheetname "")
		)
		(fill
			(thermal_gap 0.5)
			(thermal_bridge_width 0.5)
			(island_removal_mode 0)
		)
		(polygon
			(pts
				(xy 204.620368 -136.774682) (xy 204.620368 -138.578082) (xy 205.179168 -138.578082) (xy 205.179168 -136.774682)
			)
		)
	)
	(zone
		(layer "In1.Cu")
		(hatch none 0.5)
		(connect_pads
			(clearance 0)
		)
		(min_thickness 0.25)
		(keepout
			(tracks not_allowed)
			(vias allowed)
			(pads allowed)
			(copperpour not_allowed)
			(footprints allowed)
		)
		(placement
			(enabled no)
			(sheetname "")
		)
		(fill
			(thermal_gap 0.5)
			(thermal_bridge_width 0.5)
			(island_removal_mode 0)
		)
		(polygon
			(pts
				(xy 275.170392 -9.520682) (xy 275.170392 -11.324082) (xy 275.729192 -11.324082) (xy 275.729192 -9.520682)
			)
		)
	)
	(zone
		(layer "In1.Cu")
		(hatch none 0.5)
		(connect_pads
			(clearance 0)
		)
		(min_thickness 0.25)
		(keepout
			(tracks not_allowed)
			(vias allowed)
			(pads allowed)
			(copperpour not_allowed)
			(footprints allowed)
		)
		(placement
			(enabled no)
			(sheetname "")
		)
		(fill
			(thermal_gap 0.5)
			(thermal_bridge_width 0.5)
			(island_removal_mode 0)
		)
		(polygon
			(pts
				(xy 31.969964 -155.977082) (xy 31.969964 -157.780482) (xy 32.528764 -157.780482) (xy 32.528764 -155.977082)
			)
		)
	)
	(zone
		(layer "In1.Cu")
		(hatch none 0.5)
		(connect_pads
			(clearance 0)
		)
		(min_thickness 0.25)
		(keepout
			(tracks not_allowed)
			(vias allowed)
			(pads allowed)
			(copperpour not_allowed)
			(footprints allowed)
		)
		(placement
			(enabled no)
			(sheetname "")
		)
		(fill
			(thermal_gap 0.5)
			(thermal_bridge_width 0.5)
			(island_removal_mode 0)
		)
		(polygon
			(pts
				(xy 43.01998 0.080518) (xy 43.01998 -1.722882) (xy 43.57878 -1.722882) (xy 43.57878 0.080518)
			)
		)
	)
	(zone
		(layer "In1.Cu")
		(hatch none 0.5)
		(connect_pads
			(clearance 0)
		)
		(min_thickness 0.25)
		(keepout
			(tracks not_allowed)
			(vias allowed)
			(pads allowed)
			(copperpour not_allowed)
			(footprints allowed)
		)
		(placement
			(enabled no)
			(sheetname "")
		)
		(fill
			(thermal_gap 0.5)
			(thermal_bridge_width 0.5)
			(island_removal_mode 0)
		)
		(polygon
			(pts
				(xy 132.269992 -136.774682) (xy 132.269992 -138.578082) (xy 132.828792 -138.578082) (xy 132.828792 -136.774682)
			)
		)
	)
	(zone
		(layer "In1.Cu")
		(hatch none 0.5)
		(connect_pads
			(clearance 0)
		)
		(min_thickness 0.25)
		(keepout
			(tracks not_allowed)
			(vias allowed)
			(pads allowed)
			(copperpour not_allowed)
			(footprints allowed)
		)
		(placement
			(enabled no)
			(sheetname "")
		)
		(fill
			(thermal_gap 0.5)
			(thermal_bridge_width 0.5)
			(island_removal_mode 0)
		)
		(polygon
			(pts
				(xy 270.07058 -9.520682) (xy 270.07058 -11.324082) (xy 270.62938 -11.324082) (xy 270.62938 -9.520682)
			)
		)
	)
	(zone
		(layer "In1.Cu")
		(hatch none 0.5)
		(connect_pads
			(clearance 0)
		)
		(min_thickness 0.25)
		(keepout
			(tracks not_allowed)
			(vias allowed)
			(pads allowed)
			(copperpour not_allowed)
			(footprints allowed)
		)
		(placement
			(enabled no)
			(sheetname "")
		)
		(fill
			(thermal_gap 0.5)
			(thermal_bridge_width 0.5)
			(island_removal_mode 0)
		)
		(polygon
			(pts
				(xy 246.270526 -151.377142) (xy 246.270526 -153.180542) (xy 246.829326 -153.180542) (xy 246.829326 -151.377142)
			)
		)
	)
	(zone
		(layer "In1.Cu")
		(hatch none 0.5)
		(connect_pads
			(clearance 0)
		)
		(min_thickness 0.25)
		(keepout
			(tracks not_allowed)
			(vias allowed)
			(pads allowed)
			(copperpour not_allowed)
			(footprints allowed)
		)
		(placement
			(enabled no)
			(sheetname "")
		)
		(fill
			(thermal_gap 0.5)
			(thermal_bridge_width 0.5)
			(island_removal_mode 0)
		)
		(polygon
			(pts
				(xy 53.220112 -14.521942) (xy 53.220112 -16.325342) (xy 53.778912 -16.325342) (xy 53.778912 -14.521942)
			)
		)
	)
	(zone
		(layer "In1.Cu")
		(hatch none 0.5)
		(connect_pads
			(clearance 0)
		)
		(min_thickness 0.25)
		(keepout
			(tracks not_allowed)
			(vias allowed)
			(pads allowed)
			(copperpour not_allowed)
			(footprints allowed)
		)
		(placement
			(enabled no)
			(sheetname "")
		)
		(fill
			(thermal_gap 0.5)
			(thermal_bridge_width 0.5)
			(island_removal_mode 0)
		)
		(polygon
			(pts
				(xy 300.670468 -9.520682) (xy 300.670468 -11.324082) (xy 301.229268 -11.324082) (xy 301.229268 -9.520682)
			)
		)
	)
	(zone
		(layer "In1.Cu")
		(hatch none 0.5)
		(connect_pads
			(clearance 0)
		)
		(min_thickness 0.25)
		(keepout
			(tracks not_allowed)
			(vias allowed)
			(pads allowed)
			(copperpour not_allowed)
			(footprints allowed)
		)
		(placement
			(enabled no)
			(sheetname "")
		)
		(fill
			(thermal_gap 0.5)
			(thermal_bridge_width 0.5)
			(island_removal_mode 0)
		)
		(polygon
			(pts
				(xy 240.320576 -9.520682) (xy 240.320576 -11.324082) (xy 240.879376 -11.324082) (xy 240.879376 -9.520682)
			)
		)
	)
	(zone
		(layer "In1.Cu")
		(hatch none 0.5)
		(connect_pads
			(clearance 0)
		)
		(min_thickness 0.25)
		(keepout
			(tracks not_allowed)
			(vias allowed)
			(pads allowed)
			(copperpour not_allowed)
			(footprints allowed)
		)
		(placement
			(enabled no)
			(sheetname "")
		)
		(fill
			(thermal_gap 0.5)
			(thermal_bridge_width 0.5)
			(island_removal_mode 0)
		)
		(polygon
			(pts
				(xy 289.620452 -9.520682) (xy 289.620452 -11.324082) (xy 290.179252 -11.324082) (xy 290.179252 -9.520682)
			)
		)
	)
	(zone
		(layer "In1.Cu")
		(hatch none 0.5)
		(connect_pads
			(clearance 0)
		)
		(min_thickness 0.25)
		(keepout
			(tracks not_allowed)
			(vias allowed)
			(pads allowed)
			(copperpour not_allowed)
			(footprints allowed)
		)
		(placement
			(enabled no)
			(sheetname "")
		)
		(fill
			(thermal_gap 0.5)
			(thermal_bridge_width 0.5)
			(island_removal_mode 0)
		)
		(polygon
			(pts
				(xy 13.6398 -30.988) (xy 15.0368 -30.988) (xy 15.0368 -31.496) (xy 13.6398 -31.496)
			)
		)
	)
	(zone
		(layer "In1.Cu")
		(hatch none 0.5)
		(connect_pads
			(clearance 0)
		)
		(min_thickness 0.25)
		(keepout
			(tracks not_allowed)
			(vias allowed)
			(pads allowed)
			(copperpour not_allowed)
			(footprints allowed)
		)
		(placement
			(enabled no)
			(sheetname "")
		)
		(fill
			(thermal_gap 0.5)
			(thermal_bridge_width 0.5)
			(island_removal_mode 0)
		)
		(polygon
			(pts
				(xy 217.370406 -155.977082) (xy 217.370406 -157.780482) (xy 217.929206 -157.780482) (xy 217.929206 -155.977082)
			)
		)
	)
	(zone
		(layer "In1.Cu")
		(hatch none 0.5)
		(connect_pads
			(clearance 0)
		)
		(min_thickness 0.25)
		(keepout
			(tracks not_allowed)
			(vias allowed)
			(pads allowed)
			(copperpour not_allowed)
			(footprints allowed)
		)
		(placement
			(enabled no)
			(sheetname "")
		)
		(fill
			(thermal_gap 0.5)
			(thermal_bridge_width 0.5)
			(island_removal_mode 0)
		)
		(polygon
			(pts
				(xy 308.32044 0.080518) (xy 308.32044 -1.722882) (xy 308.87924 -1.722882) (xy 308.87924 0.080518)
			)
		)
	)
	(zone
		(layer "In1.Cu")
		(hatch none 0.5)
		(connect_pads
			(clearance 0)
		)
		(min_thickness 0.25)
		(keepout
			(tracks not_allowed)
			(vias allowed)
			(pads allowed)
			(copperpour not_allowed)
			(footprints allowed)
		)
		(placement
			(enabled no)
			(sheetname "")
		)
		(fill
			(thermal_gap 0.5)
			(thermal_bridge_width 0.5)
			(island_removal_mode 0)
		)
		(polygon
			(pts
				(xy 215.670384 -146.375882) (xy 215.670384 -148.179282) (xy 216.229184 -148.179282) (xy 216.229184 -146.375882)
			)
		)
	)
	(zone
		(layer "In1.Cu")
		(hatch none 0.5)
		(connect_pads
			(clearance 0)
		)
		(min_thickness 0.25)
		(keepout
			(tracks not_allowed)
			(vias allowed)
			(pads allowed)
			(copperpour not_allowed)
			(footprints allowed)
		)
		(placement
			(enabled no)
			(sheetname "")
		)
		(fill
			(thermal_gap 0.5)
			(thermal_bridge_width 0.5)
			(island_removal_mode 0)
		)
		(polygon
			(pts
				(xy 270.07058 -132.174742) (xy 270.07058 -133.978142) (xy 270.62938 -133.978142) (xy 270.62938 -132.174742)
			)
		)
	)
	(zone
		(layer "In1.Cu")
		(hatch none 0.5)
		(connect_pads
			(clearance 0)
		)
		(min_thickness 0.25)
		(keepout
			(tracks not_allowed)
			(vias allowed)
			(pads allowed)
			(copperpour not_allowed)
			(footprints allowed)
		)
		(placement
			(enabled no)
			(sheetname "")
		)
		(fill
			(thermal_gap 0.5)
			(thermal_bridge_width 0.5)
			(island_removal_mode 0)
		)
		(polygon
			(pts
				(xy 284.520386 -19.121882) (xy 284.520386 -20.925282) (xy 285.079186 -20.925282) (xy 285.079186 -19.121882)
			)
		)
	)
	(zone
		(layer "In1.Cu")
		(hatch none 0.5)
		(connect_pads
			(clearance 0)
		)
		(min_thickness 0.25)
		(keepout
			(tracks not_allowed)
			(vias allowed)
			(pads allowed)
			(copperpour not_allowed)
			(footprints allowed)
		)
		(placement
			(enabled no)
			(sheetname "")
		)
		(fill
			(thermal_gap 0.5)
			(thermal_bridge_width 0.5)
			(island_removal_mode 0)
		)
		(polygon
			(pts
				(xy 228.420422 -4.920742) (xy 228.420422 -6.724142) (xy 228.979222 -6.724142) (xy 228.979222 -4.920742)
			)
		)
	)
	(zone
		(layer "In1.Cu")
		(hatch none 0.5)
		(connect_pads
			(clearance 0)
		)
		(min_thickness 0.25)
		(keepout
			(tracks not_allowed)
			(vias allowed)
			(pads allowed)
			(copperpour not_allowed)
			(footprints allowed)
		)
		(placement
			(enabled no)
			(sheetname "")
		)
		(fill
			(thermal_gap 0.5)
			(thermal_bridge_width 0.5)
			(island_removal_mode 0)
		)
		(polygon
			(pts
				(xy 222.470472 4.680458) (xy 222.470472 2.877058) (xy 223.029272 2.877058) (xy 223.029272 4.680458)
			)
		)
	)
	(zone
		(layer "In1.Cu")
		(hatch none 0.5)
		(connect_pads
			(clearance 0)
		)
		(min_thickness 0.25)
		(keepout
			(tracks not_allowed)
			(vias allowed)
			(pads allowed)
			(copperpour not_allowed)
			(footprints allowed)
		)
		(placement
			(enabled no)
			(sheetname "")
		)
		(fill
			(thermal_gap 0.5)
			(thermal_bridge_width 0.5)
			(island_removal_mode 0)
		)
		(polygon
			(pts
				(xy 127.169926 4.680458) (xy 127.169926 2.877058) (xy 127.728726 2.877058) (xy 127.728726 4.680458)
			)
		)
	)
	(zone
		(layer "In1.Cu")
		(hatch none 0.5)
		(connect_pads
			(clearance 0)
		)
		(min_thickness 0.25)
		(keepout
			(tracks not_allowed)
			(vias allowed)
			(pads allowed)
			(copperpour not_allowed)
			(footprints allowed)
		)
		(placement
			(enabled no)
			(sheetname "")
		)
		(fill
			(thermal_gap 0.5)
			(thermal_bridge_width 0.5)
			(island_removal_mode 0)
		)
		(polygon
			(pts
				(xy 88.070182 -19.121882) (xy 88.070182 -20.925282) (xy 88.628982 -20.925282) (xy 88.628982 -19.121882)
			)
		)
	)
	(zone
		(layer "In1.Cu")
		(hatch none 0.5)
		(connect_pads
			(clearance 0)
		)
		(min_thickness 0.25)
		(keepout
			(tracks not_allowed)
			(vias allowed)
			(pads allowed)
			(copperpour not_allowed)
			(footprints allowed)
		)
		(placement
			(enabled no)
			(sheetname "")
		)
		(fill
			(thermal_gap 0.5)
			(thermal_bridge_width 0.5)
			(island_removal_mode 0)
		)
		(polygon
			(pts
				(xy 405.866092 -9.774936) (xy 406.374092 -9.774936) (xy 406.374092 -11.171936) (xy 405.866092 -11.171936)
			)
		)
	)
	(zone
		(layer "In1.Cu")
		(hatch none 0.5)
		(connect_pads
			(clearance 0)
		)
		(min_thickness 0.25)
		(keepout
			(tracks not_allowed)
			(vias allowed)
			(pads allowed)
			(copperpour not_allowed)
			(footprints allowed)
		)
		(placement
			(enabled no)
			(sheetname "")
		)
		(fill
			(thermal_gap 0.5)
			(thermal_bridge_width 0.5)
			(island_removal_mode 0)
		)
		(polygon
			(pts
				(xy 60.019946 -155.977082) (xy 60.019946 -157.780482) (xy 60.578746 -157.780482) (xy 60.578746 -155.977082)
			)
		)
	)
	(zone
		(layer "In1.Cu")
		(hatch none 0.5)
		(connect_pads
			(clearance 0)
		)
		(min_thickness 0.25)
		(keepout
			(tracks not_allowed)
			(vias allowed)
			(pads allowed)
			(copperpour not_allowed)
			(footprints allowed)
		)
		(placement
			(enabled no)
			(sheetname "")
		)
		(fill
			(thermal_gap 0.5)
			(thermal_bridge_width 0.5)
			(island_removal_mode 0)
		)
		(polygon
			(pts
				(xy 55.770018 -132.174742) (xy 55.770018 -133.978142) (xy 56.328818 -133.978142) (xy 56.328818 -132.174742)
			)
		)
	)
	(zone
		(layer "In1.Cu")
		(hatch none 0.5)
		(connect_pads
			(clearance 0)
		)
		(min_thickness 0.25)
		(keepout
			(tracks not_allowed)
			(vias allowed)
			(pads allowed)
			(copperpour not_allowed)
			(footprints allowed)
		)
		(placement
			(enabled no)
			(sheetname "")
		)
		(fill
			(thermal_gap 0.5)
			(thermal_bridge_width 0.5)
			(island_removal_mode 0)
		)
		(polygon
			(pts
				(xy 137.370058 -146.375882) (xy 137.370058 -148.179282) (xy 137.928858 -148.179282) (xy 137.928858 -146.375882)
			)
		)
	)
	(zone
		(layer "In1.Cu")
		(hatch none 0.5)
		(connect_pads
			(clearance 0)
		)
		(min_thickness 0.25)
		(keepout
			(tracks not_allowed)
			(vias allowed)
			(pads allowed)
			(copperpour not_allowed)
			(footprints allowed)
		)
		(placement
			(enabled no)
			(sheetname "")
		)
		(fill
			(thermal_gap 0.5)
			(thermal_bridge_width 0.5)
			(island_removal_mode 0)
		)
		(polygon
			(pts
				(xy 247.12041 -4.920742) (xy 247.12041 -6.724142) (xy 247.67921 -6.724142) (xy 247.67921 -4.920742)
			)
		)
	)
	(zone
		(layer "In1.Cu")
		(hatch none 0.5)
		(connect_pads
			(clearance 0)
		)
		(min_thickness 0.25)
		(keepout
			(tracks not_allowed)
			(vias allowed)
			(pads allowed)
			(copperpour not_allowed)
			(footprints allowed)
		)
		(placement
			(enabled no)
			(sheetname "")
		)
		(fill
			(thermal_gap 0.5)
			(thermal_bridge_width 0.5)
			(island_removal_mode 0)
		)
		(polygon
			(pts
				(xy 116.11991 -151.377142) (xy 116.11991 -153.180542) (xy 116.67871 -153.180542) (xy 116.67871 -151.377142)
			)
		)
	)
	(zone
		(layer "In1.Cu")
		(hatch none 0.5)
		(connect_pads
			(clearance 0)
		)
		(min_thickness 0.25)
		(keepout
			(tracks not_allowed)
			(vias allowed)
			(pads allowed)
			(copperpour not_allowed)
			(footprints allowed)
		)
		(placement
			(enabled no)
			(sheetname "")
		)
		(fill
			(thermal_gap 0.5)
			(thermal_bridge_width 0.5)
			(island_removal_mode 0)
		)
		(polygon
			(pts
				(xy 310.870346 -132.174742) (xy 310.870346 -133.978142) (xy 311.429146 -133.978142) (xy 311.429146 -132.174742)
			)
		)
	)
	(zone
		(layer "In1.Cu")
		(hatch none 0.5)
		(connect_pads
			(clearance 0)
		)
		(min_thickness 0.25)
		(keepout
			(tracks not_allowed)
			(vias allowed)
			(pads allowed)
			(copperpour not_allowed)
			(footprints allowed)
		)
		(placement
			(enabled no)
			(sheetname "")
		)
		(fill
			(thermal_gap 0.5)
			(thermal_bridge_width 0.5)
			(island_removal_mode 0)
		)
		(polygon
			(pts
				(xy 103.370126 -141.775942) (xy 103.370126 -143.579342) (xy 103.928926 -143.579342) (xy 103.928926 -141.775942)
			)
		)
	)
	(zone
		(layer "In1.Cu")
		(hatch none 0.5)
		(connect_pads
			(clearance 0)
		)
		(min_thickness 0.25)
		(keepout
			(tracks not_allowed)
			(vias allowed)
			(pads allowed)
			(copperpour not_allowed)
			(footprints allowed)
		)
		(placement
			(enabled no)
			(sheetname "")
		)
		(fill
			(thermal_gap 0.5)
			(thermal_bridge_width 0.5)
			(island_removal_mode 0)
		)
		(polygon
			(pts
				(xy 111.020098 -132.174742) (xy 111.020098 -133.978142) (xy 111.578898 -133.978142) (xy 111.578898 -132.174742)
			)
		)
	)
	(zone
		(layer "In1.Cu")
		(hatch none 0.5)
		(connect_pads
			(clearance 0)
		)
		(min_thickness 0.25)
		(keepout
			(tracks not_allowed)
			(vias allowed)
			(pads allowed)
			(copperpour not_allowed)
			(footprints allowed)
		)
		(placement
			(enabled no)
			(sheetname "")
		)
		(fill
			(thermal_gap 0.5)
			(thermal_bridge_width 0.5)
			(island_removal_mode 0)
		)
		(polygon
			(pts
				(xy 249.67057 4.680458) (xy 249.67057 2.877058) (xy 250.22937 2.877058) (xy 250.22937 4.680458)
			)
		)
	)
	(zone
		(layer "In1.Cu")
		(hatch none 0.5)
		(connect_pads
			(clearance 0)
		)
		(min_thickness 0.25)
		(keepout
			(tracks not_allowed)
			(vias allowed)
			(pads allowed)
			(copperpour not_allowed)
			(footprints allowed)
		)
		(placement
			(enabled no)
			(sheetname "")
		)
		(fill
			(thermal_gap 0.5)
			(thermal_bridge_width 0.5)
			(island_removal_mode 0)
		)
		(polygon
			(pts
				(xy 13.6398 -26.543) (xy 15.0368 -26.543) (xy 15.0368 -27.051) (xy 13.6398 -27.051)
			)
		)
	)
	(zone
		(layer "In1.Cu")
		(hatch none 0.5)
		(connect_pads
			(clearance 0)
		)
		(min_thickness 0.25)
		(keepout
			(tracks not_allowed)
			(vias allowed)
			(pads allowed)
			(copperpour not_allowed)
			(footprints allowed)
		)
		(placement
			(enabled no)
			(sheetname "")
		)
		(fill
			(thermal_gap 0.5)
			(thermal_bridge_width 0.5)
			(island_removal_mode 0)
		)
		(polygon
			(pts
				(xy 34.520124 -141.775942) (xy 34.520124 -143.579342) (xy 35.078924 -143.579342) (xy 35.078924 -141.775942)
			)
		)
	)
	(zone
		(layer "In1.Cu")
		(hatch none 0.5)
		(connect_pads
			(clearance 0)
		)
		(min_thickness 0.25)
		(keepout
			(tracks not_allowed)
			(vias allowed)
			(pads allowed)
			(copperpour not_allowed)
			(footprints allowed)
		)
		(placement
			(enabled no)
			(sheetname "")
		)
		(fill
			(thermal_gap 0.5)
			(thermal_bridge_width 0.5)
			(island_removal_mode 0)
		)
		(polygon
			(pts
				(xy 197.820534 -141.775942) (xy 197.820534 -143.579342) (xy 198.379334 -143.579342) (xy 198.379334 -141.775942)
			)
		)
	)
	(zone
		(layer "In1.Cu")
		(hatch none 0.5)
		(connect_pads
			(clearance 0)
		)
		(min_thickness 0.25)
		(keepout
			(tracks not_allowed)
			(vias allowed)
			(pads allowed)
			(copperpour not_allowed)
			(footprints allowed)
		)
		(placement
			(enabled no)
			(sheetname "")
		)
		(fill
			(thermal_gap 0.5)
			(thermal_bridge_width 0.5)
			(island_removal_mode 0)
		)
		(polygon
			(pts
				(xy 486.1306 -49.9999) (xy 486.6386 -49.9999) (xy 486.6386 -51.3969) (xy 486.1306 -51.3969)
			)
		)
	)
	(zone
		(layer "In1.Cu")
		(hatch none 0.5)
		(connect_pads
			(clearance 0)
		)
		(min_thickness 0.25)
		(keepout
			(tracks not_allowed)
			(vias allowed)
			(pads allowed)
			(copperpour not_allowed)
			(footprints allowed)
		)
		(placement
			(enabled no)
			(sheetname "")
		)
		(fill
			(thermal_gap 0.5)
			(thermal_bridge_width 0.5)
			(island_removal_mode 0)
		)
		(polygon
			(pts
				(xy 84.670138 -141.775942) (xy 84.670138 -143.579342) (xy 85.228938 -143.579342) (xy 85.228938 -141.775942)
			)
		)
	)
	(zone
		(layer "In1.Cu")
		(hatch none 0.5)
		(connect_pads
			(clearance 0)
		)
		(min_thickness 0.25)
		(keepout
			(tracks not_allowed)
			(vias allowed)
			(pads allowed)
			(copperpour not_allowed)
			(footprints allowed)
		)
		(placement
			(enabled no)
			(sheetname "")
		)
		(fill
			(thermal_gap 0.5)
			(thermal_bridge_width 0.5)
			(island_removal_mode 0)
		)
		(polygon
			(pts
				(xy 82.970116 -19.121882) (xy 83.528916 -19.121882) (xy 83.528916 -20.925282) (xy 82.970116 -20.925282)
			)
		)
	)
	(zone
		(layer "In1.Cu")
		(hatch none 0.5)
		(connect_pads
			(clearance 0)
		)
		(min_thickness 0.25)
		(keepout
			(tracks not_allowed)
			(vias allowed)
			(pads allowed)
			(copperpour not_allowed)
			(footprints allowed)
		)
		(placement
			(enabled no)
			(sheetname "")
		)
		(fill
			(thermal_gap 0.5)
			(thermal_bridge_width 0.5)
			(island_removal_mode 0)
		)
		(polygon
			(pts
				(xy 299.82033 -14.521942) (xy 299.82033 -16.325342) (xy 300.37913 -16.325342) (xy 300.37913 -14.521942)
			)
		)
	)
	(zone
		(layer "In1.Cu")
		(hatch none 0.5)
		(connect_pads
			(clearance 0)
		)
		(min_thickness 0.25)
		(keepout
			(tracks not_allowed)
			(vias allowed)
			(pads allowed)
			(copperpour not_allowed)
			(footprints allowed)
		)
		(placement
			(enabled no)
			(sheetname "")
		)
		(fill
			(thermal_gap 0.5)
			(thermal_bridge_width 0.5)
			(island_removal_mode 0)
		)
		(polygon
			(pts
				(xy 290.470336 -141.775942) (xy 290.470336 -143.579342) (xy 291.029136 -143.579342) (xy 291.029136 -141.775942)
			)
		)
	)
	(zone
		(layer "In1.Cu")
		(hatch none 0.5)
		(connect_pads
			(clearance 0)
		)
		(min_thickness 0.25)
		(keepout
			(tracks not_allowed)
			(vias allowed)
			(pads allowed)
			(copperpour not_allowed)
			(footprints allowed)
		)
		(placement
			(enabled no)
			(sheetname "")
		)
		(fill
			(thermal_gap 0.5)
			(thermal_bridge_width 0.5)
			(island_removal_mode 0)
		)
		(polygon
			(pts
				(xy 300.670468 -146.375882) (xy 300.670468 -148.179282) (xy 301.229268 -148.179282) (xy 301.229268 -146.375882)
			)
		)
	)
	(zone
		(layer "In1.Cu")
		(hatch none 0.5)
		(connect_pads
			(clearance 0)
		)
		(min_thickness 0.25)
		(keepout
			(tracks not_allowed)
			(vias allowed)
			(pads allowed)
			(copperpour not_allowed)
			(footprints allowed)
		)
		(placement
			(enabled no)
			(sheetname "")
		)
		(fill
			(thermal_gap 0.5)
			(thermal_bridge_width 0.5)
			(island_removal_mode 0)
		)
		(polygon
			(pts
				(xy 288.770314 -132.174742) (xy 288.770314 -133.978142) (xy 289.329114 -133.978142) (xy 289.329114 -132.174742)
			)
		)
	)
	(zone
		(layer "In1.Cu")
		(hatch none 0.5)
		(connect_pads
			(clearance 0)
		)
		(min_thickness 0.25)
		(keepout
			(tracks not_allowed)
			(vias allowed)
			(pads allowed)
			(copperpour not_allowed)
			(footprints allowed)
		)
		(placement
			(enabled no)
			(sheetname "")
		)
		(fill
			(thermal_gap 0.5)
			(thermal_bridge_width 0.5)
			(island_removal_mode 0)
		)
		(polygon
			(pts
				(xy 48.96993 -146.375882) (xy 48.96993 -148.179282) (xy 49.52873 -148.179282) (xy 49.52873 -146.375882)
			)
		)
	)
	(zone
		(layer "In1.Cu")
		(hatch none 0.5)
		(connect_pads
			(clearance 0)
		)
		(min_thickness 0.25)
		(keepout
			(tracks not_allowed)
			(vias allowed)
			(pads allowed)
			(copperpour not_allowed)
			(footprints allowed)
		)
		(placement
			(enabled no)
			(sheetname "")
		)
		(fill
			(thermal_gap 0.5)
			(thermal_bridge_width 0.5)
			(island_removal_mode 0)
		)
		(polygon
			(pts
				(xy 240.320576 0.080518) (xy 240.320576 -1.722882) (xy 240.879376 -1.722882) (xy 240.879376 0.080518)
			)
		)
	)
	(zone
		(layer "In1.Cu")
		(hatch none 0.5)
		(connect_pads
			(clearance 0)
		)
		(min_thickness 0.25)
		(keepout
			(tracks not_allowed)
			(vias allowed)
			(pads allowed)
			(copperpour not_allowed)
			(footprints allowed)
		)
		(placement
			(enabled no)
			(sheetname "")
		)
		(fill
			(thermal_gap 0.5)
			(thermal_bridge_width 0.5)
			(island_removal_mode 0)
		)
		(polygon
			(pts
				(xy 254.770382 -151.377142) (xy 254.770382 -153.180542) (xy 255.329182 -153.180542) (xy 255.329182 -151.377142)
			)
		)
	)
	(zone
		(layer "In1.Cu")
		(hatch none 0.5)
		(connect_pads
			(clearance 0)
		)
		(min_thickness 0.25)
		(keepout
			(tracks not_allowed)
			(vias allowed)
			(pads allowed)
			(copperpour not_allowed)
			(footprints allowed)
		)
		(placement
			(enabled no)
			(sheetname "")
		)
		(fill
			(thermal_gap 0.5)
			(thermal_bridge_width 0.5)
			(island_removal_mode 0)
		)
		(polygon
			(pts
				(xy 270.07058 -136.774682) (xy 270.07058 -138.578082) (xy 270.62938 -138.578082) (xy 270.62938 -136.774682)
			)
		)
	)
	(zone
		(layer "In1.Cu")
		(hatch none 0.5)
		(connect_pads
			(clearance 0)
		)
		(min_thickness 0.25)
		(keepout
			(tracks not_allowed)
			(vias allowed)
			(pads allowed)
			(copperpour not_allowed)
			(footprints allowed)
		)
		(placement
			(enabled no)
			(sheetname "")
		)
		(fill
			(thermal_gap 0.5)
			(thermal_bridge_width 0.5)
			(island_removal_mode 0)
		)
		(polygon
			(pts
				(xy 265.820398 4.680458) (xy 265.820398 2.877058) (xy 266.379198 2.877058) (xy 266.379198 4.680458)
			)
		)
	)
	(zone
		(layer "In1.Cu")
		(hatch none 0.5)
		(connect_pads
			(clearance 0)
		)
		(min_thickness 0.25)
		(keepout
			(tracks not_allowed)
			(vias allowed)
			(pads allowed)
			(copperpour not_allowed)
			(footprints allowed)
		)
		(placement
			(enabled no)
			(sheetname "")
		)
		(fill
			(thermal_gap 0.5)
			(thermal_bridge_width 0.5)
			(island_removal_mode 0)
		)
		(polygon
			(pts
				(xy 273.47037 -136.774682) (xy 273.47037 -138.578082) (xy 274.02917 -138.578082) (xy 274.02917 -136.774682)
			)
		)
	)
	(zone
		(layer "In1.Cu")
		(hatch none 0.5)
		(connect_pads
			(clearance 0)
		)
		(min_thickness 0.25)
		(keepout
			(tracks not_allowed)
			(vias allowed)
			(pads allowed)
			(copperpour not_allowed)
			(footprints allowed)
		)
		(placement
			(enabled no)
			(sheetname "")
		)
		(fill
			(thermal_gap 0.5)
			(thermal_bridge_width 0.5)
			(island_removal_mode 0)
		)
		(polygon
			(pts
				(xy 126.320042 -136.774682) (xy 126.320042 -138.578082) (xy 126.878842 -138.578082) (xy 126.878842 -136.774682)
			)
		)
	)
	(zone
		(layer "In1.Cu")
		(hatch none 0.5)
		(connect_pads
			(clearance 0)
		)
		(min_thickness 0.25)
		(keepout
			(tracks not_allowed)
			(vias allowed)
			(pads allowed)
			(copperpour not_allowed)
			(footprints allowed)
		)
		(placement
			(enabled no)
			(sheetname "")
		)
		(fill
			(thermal_gap 0.5)
			(thermal_bridge_width 0.5)
			(island_removal_mode 0)
		)
		(polygon
			(pts
				(xy 283.670502 -155.977082) (xy 283.670502 -157.780482) (xy 284.229302 -157.780482) (xy 284.229302 -155.977082)
			)
		)
	)
	(zone
		(layer "In1.Cu")
		(hatch none 0.5)
		(connect_pads
			(clearance 0)
		)
		(min_thickness 0.25)
		(keepout
			(tracks not_allowed)
			(vias allowed)
			(pads allowed)
			(copperpour not_allowed)
			(footprints allowed)
		)
		(placement
			(enabled no)
			(sheetname "")
		)
		(fill
			(thermal_gap 0.5)
			(thermal_bridge_width 0.5)
			(island_removal_mode 0)
		)
		(polygon
			(pts
				(xy 13.6398 -34.544) (xy 15.0368 -34.544) (xy 15.0368 -35.052) (xy 13.6398 -35.052)
			)
		)
	)
	(zone
		(layer "In1.Cu")
		(hatch none 0.5)
		(connect_pads
			(clearance 0)
		)
		(min_thickness 0.25)
		(keepout
			(tracks not_allowed)
			(vias allowed)
			(pads allowed)
			(copperpour not_allowed)
			(footprints allowed)
		)
		(placement
			(enabled no)
			(sheetname "")
		)
		(fill
			(thermal_gap 0.5)
			(thermal_bridge_width 0.5)
			(island_removal_mode 0)
		)
		(polygon
			(pts
				(xy 257.320542 -146.375882) (xy 257.320542 -148.179282) (xy 257.879342 -148.179282) (xy 257.879342 -146.375882)
			)
		)
	)
	(zone
		(layer "In1.Cu")
		(hatch none 0.5)
		(connect_pads
			(clearance 0)
		)
		(min_thickness 0.25)
		(keepout
			(tracks not_allowed)
			(vias allowed)
			(pads allowed)
			(copperpour not_allowed)
			(footprints allowed)
		)
		(placement
			(enabled no)
			(sheetname "")
		)
		(fill
			(thermal_gap 0.5)
			(thermal_bridge_width 0.5)
			(island_removal_mode 0)
		)
		(polygon
			(pts
				(xy 44.720002 -9.520682) (xy 44.720002 -11.324082) (xy 45.278802 -11.324082) (xy 45.278802 -9.520682)
			)
		)
	)
	(zone
		(layer "In1.Cu")
		(hatch none 0.5)
		(connect_pads
			(clearance 0)
		)
		(min_thickness 0.25)
		(keepout
			(tracks not_allowed)
			(vias allowed)
			(pads allowed)
			(copperpour not_allowed)
			(footprints allowed)
		)
		(placement
			(enabled no)
			(sheetname "")
		)
		(fill
			(thermal_gap 0.5)
			(thermal_bridge_width 0.5)
			(island_removal_mode 0)
		)
		(polygon
			(pts
				(xy 81.270094 -132.174742) (xy 81.270094 -133.978142) (xy 81.828894 -133.978142) (xy 81.828894 -132.174742)
			)
		)
	)
	(zone
		(layer "In1.Cu")
		(hatch none 0.5)
		(connect_pads
			(clearance 0)
		)
		(min_thickness 0.25)
		(keepout
			(tracks not_allowed)
			(vias allowed)
			(pads allowed)
			(copperpour not_allowed)
			(footprints allowed)
		)
		(placement
			(enabled no)
			(sheetname "")
		)
		(fill
			(thermal_gap 0.5)
			(thermal_bridge_width 0.5)
			(island_removal_mode 0)
		)
		(polygon
			(pts
				(xy 125.469904 -141.775942) (xy 125.469904 -143.579342) (xy 126.028704 -143.579342) (xy 126.028704 -141.775942)
			)
		)
	)
	(zone
		(layer "In1.Cu")
		(hatch none 0.5)
		(connect_pads
			(clearance 0)
		)
		(min_thickness 0.25)
		(keepout
			(tracks not_allowed)
			(vias allowed)
			(pads allowed)
			(copperpour not_allowed)
			(footprints allowed)
		)
		(placement
			(enabled no)
			(sheetname "")
		)
		(fill
			(thermal_gap 0.5)
			(thermal_bridge_width 0.5)
			(island_removal_mode 0)
		)
		(polygon
			(pts
				(xy 43.870118 -151.377142) (xy 43.870118 -153.180542) (xy 44.428918 -153.180542) (xy 44.428918 -151.377142)
			)
		)
	)
	(zone
		(layer "In1.Cu")
		(hatch none 0.5)
		(connect_pads
			(clearance 0)
		)
		(min_thickness 0.25)
		(keepout
			(tracks not_allowed)
			(vias allowed)
			(pads allowed)
			(copperpour not_allowed)
			(footprints allowed)
		)
		(placement
			(enabled no)
			(sheetname "")
		)
		(fill
			(thermal_gap 0.5)
			(thermal_bridge_width 0.5)
			(island_removal_mode 0)
		)
		(polygon
			(pts
				(xy 197.820534 4.680458) (xy 197.820534 2.877058) (xy 198.379334 2.877058) (xy 198.379334 4.680458)
			)
		)
	)
	(zone
		(layer "In1.Cu")
		(hatch none 0.5)
		(connect_pads
			(clearance 0)
		)
		(min_thickness 0.25)
		(keepout
			(tracks not_allowed)
			(vias allowed)
			(pads allowed)
			(copperpour not_allowed)
			(footprints allowed)
		)
		(placement
			(enabled no)
			(sheetname "")
		)
		(fill
			(thermal_gap 0.5)
			(thermal_bridge_width 0.5)
			(island_removal_mode 0)
		)
		(polygon
			(pts
				(xy 54.920134 -9.520682) (xy 54.920134 -11.324082) (xy 55.478934 -11.324082) (xy 55.478934 -9.520682)
			)
		)
	)
	(zone
		(layer "In1.Cu")
		(hatch none 0.5)
		(connect_pads
			(clearance 0)
		)
		(min_thickness 0.25)
		(keepout
			(tracks not_allowed)
			(vias allowed)
			(pads allowed)
			(copperpour not_allowed)
			(footprints allowed)
		)
		(placement
			(enabled no)
			(sheetname "")
		)
		(fill
			(thermal_gap 0.5)
			(thermal_bridge_width 0.5)
			(island_removal_mode 0)
		)
		(polygon
			(pts
				(xy 32.820102 -141.775942) (xy 32.820102 -143.579342) (xy 33.378902 -143.579342) (xy 33.378902 -141.775942)
			)
		)
	)
	(zone
		(layer "In1.Cu")
		(hatch none 0.5)
		(connect_pads
			(clearance 0)
		)
		(min_thickness 0.25)
		(keepout
			(tracks not_allowed)
			(vias allowed)
			(pads allowed)
			(copperpour not_allowed)
			(footprints allowed)
		)
		(placement
			(enabled no)
			(sheetname "")
		)
		(fill
			(thermal_gap 0.5)
			(thermal_bridge_width 0.5)
			(island_removal_mode 0)
		)
		(polygon
			(pts
				(xy 58.319924 -146.375882) (xy 58.319924 -148.179282) (xy 58.878724 -148.179282) (xy 58.878724 -146.375882)
			)
		)
	)
	(zone
		(layer "In1.Cu")
		(hatch none 0.5)
		(connect_pads
			(clearance 0)
		)
		(min_thickness 0.25)
		(keepout
			(tracks not_allowed)
			(vias allowed)
			(pads allowed)
			(copperpour not_allowed)
			(footprints allowed)
		)
		(placement
			(enabled no)
			(sheetname "")
		)
		(fill
			(thermal_gap 0.5)
			(thermal_bridge_width 0.5)
			(island_removal_mode 0)
		)
		(polygon
			(pts
				(xy 30.269942 -9.520682) (xy 30.269942 -11.324082) (xy 30.828742 -11.324082) (xy 30.828742 -9.520682)
			)
		)
	)
	(zone
		(layer "In1.Cu")
		(hatch none 0.5)
		(connect_pads
			(clearance 0)
		)
		(min_thickness 0.25)
		(keepout
			(tracks not_allowed)
			(vias allowed)
			(pads allowed)
			(copperpour not_allowed)
			(footprints allowed)
		)
		(placement
			(enabled no)
			(sheetname "")
		)
		(fill
			(thermal_gap 0.5)
			(thermal_bridge_width 0.5)
			(island_removal_mode 0)
		)
		(polygon
			(pts
				(xy 85.520022 -19.121882) (xy 85.520022 -20.925282) (xy 86.078822 -20.925282) (xy 86.078822 -19.121882)
			)
		)
	)
	(zone
		(layer "In1.Cu")
		(hatch none 0.5)
		(connect_pads
			(clearance 0)
		)
		(min_thickness 0.25)
		(keepout
			(tracks not_allowed)
			(vias allowed)
			(pads allowed)
			(copperpour not_allowed)
			(footprints allowed)
		)
		(placement
			(enabled no)
			(sheetname "")
		)
		(fill
			(thermal_gap 0.5)
			(thermal_bridge_width 0.5)
			(island_removal_mode 0)
		)
		(polygon
			(pts
				(xy 272.620486 -151.377142) (xy 272.620486 -153.180542) (xy 273.179286 -153.180542) (xy 273.179286 -151.377142)
			)
		)
	)
	(zone
		(layer "In1.Cu")
		(hatch none 0.5)
		(connect_pads
			(clearance 0)
		)
		(min_thickness 0.25)
		(keepout
			(tracks not_allowed)
			(vias allowed)
			(pads allowed)
			(copperpour not_allowed)
			(footprints allowed)
		)
		(placement
			(enabled no)
			(sheetname "")
		)
		(fill
			(thermal_gap 0.5)
			(thermal_bridge_width 0.5)
			(island_removal_mode 0)
		)
		(polygon
			(pts
				(xy 215.670384 -19.121882) (xy 215.670384 -20.925282) (xy 216.229184 -20.925282) (xy 216.229184 -19.121882)
			)
		)
	)
	(zone
		(layer "In1.Cu")
		(hatch none 0.5)
		(connect_pads
			(clearance 0)
		)
		(min_thickness 0.25)
		(keepout
			(tracks not_allowed)
			(vias allowed)
			(pads allowed)
			(copperpour not_allowed)
			(footprints allowed)
		)
		(placement
			(enabled no)
			(sheetname "")
		)
		(fill
			(thermal_gap 0.5)
			(thermal_bridge_width 0.5)
			(island_removal_mode 0)
		)
		(polygon
			(pts
				(xy 123.769882 -132.174742) (xy 123.769882 -133.978142) (xy 124.328682 -133.978142) (xy 124.328682 -132.174742)
			)
		)
	)
	(zone
		(layer "In1.Cu")
		(hatch none 0.5)
		(connect_pads
			(clearance 0)
		)
		(min_thickness 0.25)
		(keepout
			(tracks not_allowed)
			(vias allowed)
			(pads allowed)
			(copperpour not_allowed)
			(footprints allowed)
		)
		(placement
			(enabled no)
			(sheetname "")
		)
		(fill
			(thermal_gap 0.5)
			(thermal_bridge_width 0.5)
			(island_removal_mode 0)
		)
		(polygon
			(pts
				(xy 433.821586 -7.192772) (xy 435.129686 -7.192772) (xy 435.129686 -8.386572) (xy 433.821586 -8.386572)
			)
		)
	)
	(zone
		(layer "In1.Cu")
		(hatch none 0.5)
		(connect_pads
			(clearance 0)
		)
		(min_thickness 0.25)
		(keepout
			(tracks not_allowed)
			(vias allowed)
			(pads allowed)
			(copperpour not_allowed)
			(footprints allowed)
		)
		(placement
			(enabled no)
			(sheetname "")
		)
		(fill
			(thermal_gap 0.5)
			(thermal_bridge_width 0.5)
			(island_removal_mode 0)
		)
		(polygon
			(pts
				(xy 65.120012 -141.775942) (xy 65.120012 -143.579342) (xy 65.678812 -143.579342) (xy 65.678812 -141.775942)
			)
		)
	)
	(zone
		(layer "In1.Cu")
		(hatch none 0.5)
		(connect_pads
			(clearance 0)
		)
		(min_thickness 0.25)
		(keepout
			(tracks not_allowed)
			(vias allowed)
			(pads allowed)
			(copperpour not_allowed)
			(footprints allowed)
		)
		(placement
			(enabled no)
			(sheetname "")
		)
		(fill
			(thermal_gap 0.5)
			(thermal_bridge_width 0.5)
			(island_removal_mode 0)
		)
		(polygon
			(pts
				(xy 287.070546 4.680458) (xy 287.070546 2.877058) (xy 287.629346 2.877058) (xy 287.629346 4.680458)
			)
		)
	)
	(zone
		(layer "In1.Cu")
		(hatch none 0.5)
		(connect_pads
			(clearance 0)
		)
		(min_thickness 0.25)
		(keepout
			(tracks not_allowed)
			(vias allowed)
			(pads allowed)
			(copperpour not_allowed)
			(footprints allowed)
		)
		(placement
			(enabled no)
			(sheetname "")
		)
		(fill
			(thermal_gap 0.5)
			(thermal_bridge_width 0.5)
			(island_removal_mode 0)
		)
		(polygon
			(pts
				(xy 141.619986 0.080518) (xy 141.619986 -1.722882) (xy 142.178786 -1.722882) (xy 142.178786 0.080518)
			)
		)
	)
	(zone
		(layer "In1.Cu")
		(hatch none 0.5)
		(connect_pads
			(clearance 0)
		)
		(min_thickness 0.25)
		(keepout
			(tracks not_allowed)
			(vias allowed)
			(pads allowed)
			(copperpour not_allowed)
			(footprints allowed)
		)
		(placement
			(enabled no)
			(sheetname "")
		)
		(fill
			(thermal_gap 0.5)
			(thermal_bridge_width 0.5)
			(island_removal_mode 0)
		)
		(polygon
			(pts
				(xy 248.820432 -132.174742) (xy 248.820432 -133.978142) (xy 249.379232 -133.978142) (xy 249.379232 -132.174742)
			)
		)
	)
	(zone
		(layer "In1.Cu")
		(hatch none 0.5)
		(connect_pads
			(clearance 0)
		)
		(min_thickness 0.25)
		(keepout
			(tracks not_allowed)
			(vias allowed)
			(pads allowed)
			(copperpour not_allowed)
			(footprints allowed)
		)
		(placement
			(enabled no)
			(sheetname "")
		)
		(fill
			(thermal_gap 0.5)
			(thermal_bridge_width 0.5)
			(island_removal_mode 0)
		)
		(polygon
			(pts
				(xy 143.320008 -146.375882) (xy 143.320008 -148.179282) (xy 143.878808 -148.179282) (xy 143.878808 -146.375882)
			)
		)
	)
	(zone
		(layer "In1.Cu")
		(hatch none 0.5)
		(connect_pads
			(clearance 0)
		)
		(min_thickness 0.25)
		(keepout
			(tracks not_allowed)
			(vias allowed)
			(pads allowed)
			(copperpour not_allowed)
			(footprints allowed)
		)
		(placement
			(enabled no)
			(sheetname "")
		)
		(fill
			(thermal_gap 0.5)
			(thermal_bridge_width 0.5)
			(island_removal_mode 0)
		)
		(polygon
			(pts
				(xy 282.820364 -132.174742) (xy 282.820364 -133.978142) (xy 283.379164 -133.978142) (xy 283.379164 -132.174742)
			)
		)
	)
	(zone
		(layer "In1.Cu")
		(hatch none 0.5)
		(connect_pads
			(clearance 0)
		)
		(min_thickness 0.25)
		(keepout
			(tracks not_allowed)
			(vias allowed)
			(pads allowed)
			(copperpour not_allowed)
			(footprints allowed)
		)
		(placement
			(enabled no)
			(sheetname "")
		)
		(fill
			(thermal_gap 0.5)
			(thermal_bridge_width 0.5)
			(island_removal_mode 0)
		)
		(polygon
			(pts
				(xy 315.120528 -14.521942) (xy 315.120528 -16.325342) (xy 315.679328 -16.325342) (xy 315.679328 -14.521942)
			)
		)
	)
	(zone
		(layer "In1.Cu")
		(hatch none 0.5)
		(connect_pads
			(clearance 0)
		)
		(min_thickness 0.25)
		(keepout
			(tracks not_allowed)
			(vias allowed)
			(pads allowed)
			(copperpour not_allowed)
			(footprints allowed)
		)
		(placement
			(enabled no)
			(sheetname "")
		)
		(fill
			(thermal_gap 0.5)
			(thermal_bridge_width 0.5)
			(island_removal_mode 0)
		)
		(polygon
			(pts
				(xy 89.76995 -141.775942) (xy 89.76995 -143.579342) (xy 90.32875 -143.579342) (xy 90.32875 -141.775942)
			)
		)
	)
	(zone
		(layer "In1.Cu")
		(hatch none 0.5)
		(connect_pads
			(clearance 0)
		)
		(min_thickness 0.25)
		(keepout
			(tracks not_allowed)
			(vias allowed)
			(pads allowed)
			(copperpour not_allowed)
			(footprints allowed)
		)
		(placement
			(enabled no)
			(sheetname "")
		)
		(fill
			(thermal_gap 0.5)
			(thermal_bridge_width 0.5)
			(island_removal_mode 0)
		)
		(polygon
			(pts
				(xy 243.720366 -146.375882) (xy 243.720366 -148.179282) (xy 244.279166 -148.179282) (xy 244.279166 -146.375882)
			)
		)
	)
	(zone
		(layer "In1.Cu")
		(hatch none 0.5)
		(connect_pads
			(clearance 0)
		)
		(min_thickness 0.25)
		(keepout
			(tracks not_allowed)
			(vias allowed)
			(pads allowed)
			(copperpour not_allowed)
			(footprints allowed)
		)
		(placement
			(enabled no)
			(sheetname "")
		)
		(fill
			(thermal_gap 0.5)
			(thermal_bridge_width 0.5)
			(island_removal_mode 0)
		)
		(polygon
			(pts
				(xy 306.620418 0.080518) (xy 306.620418 -1.722882) (xy 307.179218 -1.722882) (xy 307.179218 0.080518)
			)
		)
	)
	(zone
		(layer "In1.Cu")
		(hatch none 0.5)
		(connect_pads
			(clearance 0)
		)
		(min_thickness 0.25)
		(keepout
			(tracks not_allowed)
			(vias allowed)
			(pads allowed)
			(copperpour not_allowed)
			(footprints allowed)
		)
		(placement
			(enabled no)
			(sheetname "")
		)
		(fill
			(thermal_gap 0.5)
			(thermal_bridge_width 0.5)
			(island_removal_mode 0)
		)
		(polygon
			(pts
				(xy 311.720484 -146.375882) (xy 311.720484 -148.179282) (xy 312.279284 -148.179282) (xy 312.279284 -146.375882)
			)
		)
	)
	(zone
		(layer "In1.Cu")
		(hatch none 0.5)
		(connect_pads
			(clearance 0)
		)
		(min_thickness 0.25)
		(keepout
			(tracks not_allowed)
			(vias allowed)
			(pads allowed)
			(copperpour not_allowed)
			(footprints allowed)
		)
		(placement
			(enabled no)
			(sheetname "")
		)
		(fill
			(thermal_gap 0.5)
			(thermal_bridge_width 0.5)
			(island_removal_mode 0)
		)
		(polygon
			(pts
				(xy 267.52042 -9.520682) (xy 267.52042 -11.324082) (xy 268.07922 -11.324082) (xy 268.07922 -9.520682)
			)
		)
	)
	(zone
		(layer "In1.Cu")
		(hatch none 0.5)
		(connect_pads
			(clearance 0)
		)
		(min_thickness 0.25)
		(keepout
			(tracks not_allowed)
			(vias allowed)
			(pads allowed)
			(copperpour not_allowed)
			(footprints allowed)
		)
		(placement
			(enabled no)
			(sheetname "")
		)
		(fill
			(thermal_gap 0.5)
			(thermal_bridge_width 0.5)
			(island_removal_mode 0)
		)
		(polygon
			(pts
				(xy 128.020064 -132.174742) (xy 128.020064 -133.978142) (xy 128.578864 -133.978142) (xy 128.578864 -132.174742)
			)
		)
	)
	(zone
		(layer "In1.Cu")
		(hatch none 0.5)
		(connect_pads
			(clearance 0)
		)
		(min_thickness 0.25)
		(keepout
			(tracks not_allowed)
			(vias allowed)
			(pads allowed)
			(copperpour not_allowed)
			(footprints allowed)
		)
		(placement
			(enabled no)
			(sheetname "")
		)
		(fill
			(thermal_gap 0.5)
			(thermal_bridge_width 0.5)
			(island_removal_mode 0)
		)
		(polygon
			(pts
				(xy 133.119876 -132.174742) (xy 133.119876 -133.978142) (xy 133.678676 -133.978142) (xy 133.678676 -132.174742)
			)
		)
	)
	(zone
		(layer "In1.Cu")
		(hatch none 0.5)
		(connect_pads
			(clearance 0)
		)
		(min_thickness 0.25)
		(keepout
			(tracks not_allowed)
			(vias allowed)
			(pads allowed)
			(copperpour not_allowed)
			(footprints allowed)
		)
		(placement
			(enabled no)
			(sheetname "")
		)
		(fill
			(thermal_gap 0.5)
			(thermal_bridge_width 0.5)
			(island_removal_mode 0)
		)
		(polygon
			(pts
				(xy 75.320144 -155.977082) (xy 75.320144 -157.780482) (xy 75.878944 -157.780482) (xy 75.878944 -155.977082)
			)
		)
	)
	(zone
		(layer "In1.Cu")
		(hatch none 0.5)
		(connect_pads
			(clearance 0)
		)
		(min_thickness 0.25)
		(keepout
			(tracks not_allowed)
			(vias allowed)
			(pads allowed)
			(copperpour not_allowed)
			(footprints allowed)
		)
		(placement
			(enabled no)
			(sheetname "")
		)
		(fill
			(thermal_gap 0.5)
			(thermal_bridge_width 0.5)
			(island_removal_mode 0)
		)
		(polygon
			(pts
				(xy 72.769984 -136.774682) (xy 72.769984 -138.578082) (xy 73.328784 -138.578082) (xy 73.328784 -136.774682)
			)
		)
	)
	(zone
		(layer "In1.Cu")
		(hatch none 0.5)
		(connect_pads
			(clearance 0)
		)
		(min_thickness 0.25)
		(keepout
			(tracks not_allowed)
			(vias allowed)
			(pads allowed)
			(copperpour not_allowed)
			(footprints allowed)
		)
		(placement
			(enabled no)
			(sheetname "")
		)
		(fill
			(thermal_gap 0.5)
			(thermal_bridge_width 0.5)
			(island_removal_mode 0)
		)
		(polygon
			(pts
				(xy 111.020098 0.080518) (xy 111.020098 -1.722882) (xy 111.578898 -1.722882) (xy 111.578898 0.080518)
			)
		)
	)
	(zone
		(layer "In1.Cu")
		(hatch none 0.5)
		(connect_pads
			(clearance 0)
		)
		(min_thickness 0.25)
		(keepout
			(tracks not_allowed)
			(vias allowed)
			(pads allowed)
			(copperpour not_allowed)
			(footprints allowed)
		)
		(placement
			(enabled no)
			(sheetname "")
		)
		(fill
			(thermal_gap 0.5)
			(thermal_bridge_width 0.5)
			(island_removal_mode 0)
		)
		(polygon
			(pts
				(xy 313.420506 4.680458) (xy 313.420506 2.877058) (xy 313.979306 2.877058) (xy 313.979306 4.680458)
			)
		)
	)
	(zone
		(layer "In1.Cu")
		(hatch none 0.5)
		(connect_pads
			(clearance 0)
		)
		(min_thickness 0.25)
		(keepout
			(tracks not_allowed)
			(vias allowed)
			(pads allowed)
			(copperpour not_allowed)
			(footprints allowed)
		)
		(placement
			(enabled no)
			(sheetname "")
		)
		(fill
			(thermal_gap 0.5)
			(thermal_bridge_width 0.5)
			(island_removal_mode 0)
		)
		(polygon
			(pts
				(xy 307.470302 -4.920742) (xy 307.470302 -6.724142) (xy 308.029102 -6.724142) (xy 308.029102 -4.920742)
			)
		)
	)
	(zone
		(layer "In1.Cu")
		(hatch none 0.5)
		(connect_pads
			(clearance 0)
		)
		(min_thickness 0.25)
		(keepout
			(tracks not_allowed)
			(vias allowed)
			(pads allowed)
			(copperpour not_allowed)
			(footprints allowed)
		)
		(placement
			(enabled no)
			(sheetname "")
		)
		(fill
			(thermal_gap 0.5)
			(thermal_bridge_width 0.5)
			(island_removal_mode 0)
		)
		(polygon
			(pts
				(xy 70.220078 4.680458) (xy 70.220078 2.877058) (xy 70.778878 2.877058) (xy 70.778878 4.680458)
			)
		)
	)
	(zone
		(layer "In1.Cu")
		(hatch none 0.5)
		(connect_pads
			(clearance 0)
		)
		(min_thickness 0.25)
		(keepout
			(tracks not_allowed)
			(vias allowed)
			(pads allowed)
			(copperpour not_allowed)
			(footprints allowed)
		)
		(placement
			(enabled no)
			(sheetname "")
		)
		(fill
			(thermal_gap 0.5)
			(thermal_bridge_width 0.5)
			(island_removal_mode 0)
		)
		(polygon
			(pts
				(xy 91.469972 -132.174742) (xy 91.469972 -133.978142) (xy 92.028772 -133.978142) (xy 92.028772 -132.174742)
			)
		)
	)
	(zone
		(layer "In1.Cu")
		(hatch none 0.5)
		(connect_pads
			(clearance 0)
		)
		(min_thickness 0.25)
		(keepout
			(tracks not_allowed)
			(vias allowed)
			(pads allowed)
			(copperpour not_allowed)
			(footprints allowed)
		)
		(placement
			(enabled no)
			(sheetname "")
		)
		(fill
			(thermal_gap 0.5)
			(thermal_bridge_width 0.5)
			(island_removal_mode 0)
		)
		(polygon
			(pts
				(xy 314.27039 -146.375882) (xy 314.27039 -148.179282) (xy 314.82919 -148.179282) (xy 314.82919 -146.375882)
			)
		)
	)
	(zone
		(layer "In1.Cu")
		(hatch none 0.5)
		(connect_pads
			(clearance 0)
		)
		(min_thickness 0.25)
		(keepout
			(tracks not_allowed)
			(vias allowed)
			(pads allowed)
			(copperpour not_allowed)
			(footprints allowed)
		)
		(placement
			(enabled no)
			(sheetname "")
		)
		(fill
			(thermal_gap 0.5)
			(thermal_bridge_width 0.5)
			(island_removal_mode 0)
		)
		(polygon
			(pts
				(xy 292.170358 -151.377142) (xy 292.170358 -153.180542) (xy 292.729158 -153.180542) (xy 292.729158 -151.377142)
			)
		)
	)
	(zone
		(layer "In1.Cu")
		(hatch none 0.5)
		(connect_pads
			(clearance 0)
		)
		(min_thickness 0.25)
		(keepout
			(tracks not_allowed)
			(vias allowed)
			(pads allowed)
			(copperpour not_allowed)
			(footprints allowed)
		)
		(placement
			(enabled no)
			(sheetname "")
		)
		(fill
			(thermal_gap 0.5)
			(thermal_bridge_width 0.5)
			(island_removal_mode 0)
		)
		(polygon
			(pts
				(xy 48.120046 -132.174742) (xy 48.120046 -133.978142) (xy 48.678846 -133.978142) (xy 48.678846 -132.174742)
			)
		)
	)
	(zone
		(layer "In1.Cu")
		(hatch none 0.5)
		(connect_pads
			(clearance 0)
		)
		(min_thickness 0.25)
		(keepout
			(tracks not_allowed)
			(vias allowed)
			(pads allowed)
			(copperpour not_allowed)
			(footprints allowed)
		)
		(placement
			(enabled no)
			(sheetname "")
		)
		(fill
			(thermal_gap 0.5)
			(thermal_bridge_width 0.5)
			(island_removal_mode 0)
		)
		(polygon
			(pts
				(xy 139.919964 -19.121882) (xy 139.919964 -20.925282) (xy 140.478764 -20.925282) (xy 140.478764 -19.121882)
			)
		)
	)
	(zone
		(layer "In1.Cu")
		(hatch none 0.5)
		(connect_pads
			(clearance 0)
		)
		(min_thickness 0.25)
		(keepout
			(tracks not_allowed)
			(vias allowed)
			(pads allowed)
			(copperpour not_allowed)
			(footprints allowed)
		)
		(placement
			(enabled no)
			(sheetname "")
		)
		(fill
			(thermal_gap 0.5)
			(thermal_bridge_width 0.5)
			(island_removal_mode 0)
		)
		(polygon
			(pts
				(xy 287.92043 -155.977082) (xy 287.92043 -157.780482) (xy 288.47923 -157.780482) (xy 288.47923 -155.977082)
			)
		)
	)
	(zone
		(layer "In1.Cu")
		(hatch none 0.5)
		(connect_pads
			(clearance 0)
		)
		(min_thickness 0.25)
		(keepout
			(tracks not_allowed)
			(vias allowed)
			(pads allowed)
			(copperpour not_allowed)
			(footprints allowed)
		)
		(placement
			(enabled no)
			(sheetname "")
		)
		(fill
			(thermal_gap 0.5)
			(thermal_bridge_width 0.5)
			(island_removal_mode 0)
		)
		(polygon
			(pts
				(xy 100.819966 4.680458) (xy 100.819966 2.877058) (xy 101.378766 2.877058) (xy 101.378766 4.680458)
			)
		)
	)
	(zone
		(layer "In1.Cu")
		(hatch none 0.5)
		(connect_pads
			(clearance 0)
		)
		(min_thickness 0.25)
		(keepout
			(tracks not_allowed)
			(vias allowed)
			(pads allowed)
			(copperpour not_allowed)
			(footprints allowed)
		)
		(placement
			(enabled no)
			(sheetname "")
		)
		(fill
			(thermal_gap 0.5)
			(thermal_bridge_width 0.5)
			(island_removal_mode 0)
		)
		(polygon
			(pts
				(xy 446.68694 -50.872644) (xy 447.99504 -50.872644) (xy 447.99504 -52.879244) (xy 446.68694 -52.879244)
			)
		)
	)
	(zone
		(layer "In1.Cu")
		(hatch none 0.5)
		(connect_pads
			(clearance 0)
		)
		(min_thickness 0.25)
		(keepout
			(tracks not_allowed)
			(vias allowed)
			(pads allowed)
			(copperpour not_allowed)
			(footprints allowed)
		)
		(placement
			(enabled no)
			(sheetname "")
		)
		(fill
			(thermal_gap 0.5)
			(thermal_bridge_width 0.5)
			(island_removal_mode 0)
		)
		(polygon
			(pts
				(xy 378.000768 -32.0675) (xy 380.286768 -32.0675) (xy 380.286768 -32.5755) (xy 378.000768 -32.5755)
			)
		)
	)
	(zone
		(layer "In1.Cu")
		(hatch none 0.5)
		(connect_pads
			(clearance 0)
		)
		(min_thickness 0.25)
		(keepout
			(tracks not_allowed)
			(vias allowed)
			(pads allowed)
			(copperpour not_allowed)
			(footprints allowed)
		)
		(placement
			(enabled no)
			(sheetname "")
		)
		(fill
			(thermal_gap 0.5)
			(thermal_bridge_width 0.5)
			(island_removal_mode 0)
		)
		(polygon
			(pts
				(xy 60.870084 -151.377142) (xy 60.870084 -153.180542) (xy 61.428884 -153.180542) (xy 61.428884 -151.377142)
			)
		)
	)
	(zone
		(layer "In1.Cu")
		(hatch none 0.5)
		(connect_pads
			(clearance 0)
		)
		(min_thickness 0.25)
		(keepout
			(tracks not_allowed)
			(vias allowed)
			(pads allowed)
			(copperpour not_allowed)
			(footprints allowed)
		)
		(placement
			(enabled no)
			(sheetname "")
		)
		(fill
			(thermal_gap 0.5)
			(thermal_bridge_width 0.5)
			(island_removal_mode 0)
		)
		(polygon
			(pts
				(xy 74.470006 -132.174742) (xy 74.470006 -133.978142) (xy 75.028806 -133.978142) (xy 75.028806 -132.174742)
			)
		)
	)
	(zone
		(layer "In1.Cu")
		(hatch none 0.5)
		(connect_pads
			(clearance 0)
		)
		(min_thickness 0.25)
		(keepout
			(tracks not_allowed)
			(vias allowed)
			(pads allowed)
			(copperpour not_allowed)
			(footprints allowed)
		)
		(placement
			(enabled no)
			(sheetname "")
		)
		(fill
			(thermal_gap 0.5)
			(thermal_bridge_width 0.5)
			(island_removal_mode 0)
		)
		(polygon
			(pts
				(xy 254.770382 -155.977082) (xy 254.770382 -157.780482) (xy 255.329182 -157.780482) (xy 255.329182 -155.977082)
			)
		)
	)
	(zone
		(layer "In1.Cu")
		(hatch none 0.5)
		(connect_pads
			(clearance 0)
		)
		(min_thickness 0.25)
		(keepout
			(tracks not_allowed)
			(vias allowed)
			(pads allowed)
			(copperpour not_allowed)
			(footprints allowed)
		)
		(placement
			(enabled no)
			(sheetname "")
		)
		(fill
			(thermal_gap 0.5)
			(thermal_bridge_width 0.5)
			(island_removal_mode 0)
		)
		(polygon
			(pts
				(xy 56.620156 -155.977082) (xy 56.620156 -157.780482) (xy 57.178956 -157.780482) (xy 57.178956 -155.977082)
			)
		)
	)
	(zone
		(layer "In1.Cu")
		(hatch none 0.5)
		(connect_pads
			(clearance 0)
		)
		(min_thickness 0.25)
		(keepout
			(tracks not_allowed)
			(vias allowed)
			(pads allowed)
			(copperpour not_allowed)
			(footprints allowed)
		)
		(placement
			(enabled no)
			(sheetname "")
		)
		(fill
			(thermal_gap 0.5)
			(thermal_bridge_width 0.5)
			(island_removal_mode 0)
		)
		(polygon
			(pts
				(xy 279.42032 4.680458) (xy 279.42032 2.877058) (xy 279.97912 2.877058) (xy 279.97912 4.680458)
			)
		)
	)
	(zone
		(layer "In1.Cu")
		(hatch none 0.5)
		(connect_pads
			(clearance 0)
		)
		(min_thickness 0.25)
		(keepout
			(tracks not_allowed)
			(vias allowed)
			(pads allowed)
			(copperpour not_allowed)
			(footprints allowed)
		)
		(placement
			(enabled no)
			(sheetname "")
		)
		(fill
			(thermal_gap 0.5)
			(thermal_bridge_width 0.5)
			(island_removal_mode 0)
		)
		(polygon
			(pts
				(xy 92.32011 -4.920742) (xy 92.32011 -6.724142) (xy 92.87891 -6.724142) (xy 92.87891 -4.920742)
			)
		)
	)
	(zone
		(layer "In1.Cu")
		(hatch none 0.5)
		(connect_pads
			(clearance 0)
		)
		(min_thickness 0.25)
		(keepout
			(tracks not_allowed)
			(vias allowed)
			(pads allowed)
			(copperpour not_allowed)
			(footprints allowed)
		)
		(placement
			(enabled no)
			(sheetname "")
		)
		(fill
			(thermal_gap 0.5)
			(thermal_bridge_width 0.5)
			(island_removal_mode 0)
		)
		(polygon
			(pts
				(xy 249.67057 -141.775942) (xy 249.67057 -143.579342) (xy 250.22937 -143.579342) (xy 250.22937 -141.775942)
			)
		)
	)
	(zone
		(layer "In1.Cu")
		(hatch none 0.5)
		(connect_pads
			(clearance 0)
		)
		(min_thickness 0.25)
		(keepout
			(tracks not_allowed)
			(vias allowed)
			(pads allowed)
			(copperpour not_allowed)
			(footprints allowed)
		)
		(placement
			(enabled no)
			(sheetname "")
		)
		(fill
			(thermal_gap 0.5)
			(thermal_bridge_width 0.5)
			(island_removal_mode 0)
		)
		(polygon
			(pts
				(xy 205.470506 4.680458) (xy 205.470506 2.877058) (xy 206.029306 2.877058) (xy 206.029306 4.680458)
			)
		)
	)
	(zone
		(layer "In1.Cu")
		(hatch none 0.5)
		(connect_pads
			(clearance 0)
		)
		(min_thickness 0.25)
		(keepout
			(tracks not_allowed)
			(vias allowed)
			(pads allowed)
			(copperpour not_allowed)
			(footprints allowed)
		)
		(placement
			(enabled no)
			(sheetname "")
		)
		(fill
			(thermal_gap 0.5)
			(thermal_bridge_width 0.5)
			(island_removal_mode 0)
		)
		(polygon
			(pts
				(xy 412.218886 -7.192772) (xy 413.526986 -7.192772) (xy 413.526986 -8.386572) (xy 412.218886 -8.386572)
			)
		)
	)
	(zone
		(layer "In1.Cu")
		(hatch none 0.5)
		(connect_pads
			(clearance 0)
		)
		(min_thickness 0.25)
		(keepout
			(tracks not_allowed)
			(vias allowed)
			(pads allowed)
			(copperpour not_allowed)
			(footprints allowed)
		)
		(placement
			(enabled no)
			(sheetname "")
		)
		(fill
			(thermal_gap 0.5)
			(thermal_bridge_width 0.5)
			(island_removal_mode 0)
		)
		(polygon
			(pts
				(xy 145.869914 -141.775942) (xy 145.869914 -143.579342) (xy 146.428714 -143.579342) (xy 146.428714 -141.775942)
			)
		)
	)
	(zone
		(layer "In1.Cu")
		(hatch none 0.5)
		(connect_pads
			(clearance 0)
		)
		(min_thickness 0.25)
		(keepout
			(tracks not_allowed)
			(vias allowed)
			(pads allowed)
			(copperpour not_allowed)
			(footprints allowed)
		)
		(placement
			(enabled no)
			(sheetname "")
		)
		(fill
			(thermal_gap 0.5)
			(thermal_bridge_width 0.5)
			(island_removal_mode 0)
		)
		(polygon
			(pts
				(xy 411.418786 -3.789172) (xy 412.726886 -3.789172) (xy 412.726886 -4.982972) (xy 411.418786 -4.982972)
			)
		)
	)
	(zone
		(layer "In1.Cu")
		(hatch none 0.5)
		(connect_pads
			(clearance 0)
		)
		(min_thickness 0.25)
		(keepout
			(tracks not_allowed)
			(vias allowed)
			(pads allowed)
			(copperpour not_allowed)
			(footprints allowed)
		)
		(placement
			(enabled no)
			(sheetname "")
		)
		(fill
			(thermal_gap 0.5)
			(thermal_bridge_width 0.5)
			(island_removal_mode 0)
		)
		(polygon
			(pts
				(xy 72.769984 0.080518) (xy 72.769984 -1.722882) (xy 73.328784 -1.722882) (xy 73.328784 0.080518)
			)
		)
	)
	(zone
		(layer "In1.Cu")
		(hatch none 0.5)
		(connect_pads
			(clearance 0)
		)
		(min_thickness 0.25)
		(keepout
			(tracks not_allowed)
			(vias allowed)
			(pads allowed)
			(copperpour not_allowed)
			(footprints allowed)
		)
		(placement
			(enabled no)
			(sheetname "")
		)
		(fill
			(thermal_gap 0.5)
			(thermal_bridge_width 0.5)
			(island_removal_mode 0)
		)
		(polygon
			(pts
				(xy 39.619936 -9.520682) (xy 39.619936 -11.324082) (xy 40.178736 -11.324082) (xy 40.178736 -9.520682)
			)
		)
	)
	(zone
		(layer "In1.Cu")
		(hatch none 0.5)
		(connect_pads
			(clearance 0)
		)
		(min_thickness 0.25)
		(keepout
			(tracks not_allowed)
			(vias allowed)
			(pads allowed)
			(copperpour not_allowed)
			(footprints allowed)
		)
		(placement
			(enabled no)
			(sheetname "")
		)
		(fill
			(thermal_gap 0.5)
			(thermal_bridge_width 0.5)
			(island_removal_mode 0)
		)
		(polygon
			(pts
				(xy 30.269942 -155.977082) (xy 30.269942 -157.780482) (xy 30.828742 -157.780482) (xy 30.828742 -155.977082)
			)
		)
	)
	(zone
		(layer "In1.Cu")
		(hatch none 0.5)
		(connect_pads
			(clearance 0)
		)
		(min_thickness 0.25)
		(keepout
			(tracks not_allowed)
			(vias allowed)
			(pads allowed)
			(copperpour not_allowed)
			(footprints allowed)
		)
		(placement
			(enabled no)
			(sheetname "")
		)
		(fill
			(thermal_gap 0.5)
			(thermal_bridge_width 0.5)
			(island_removal_mode 0)
		)
		(polygon
			(pts
				(xy 76.170282 -4.920742) (xy 76.170282 -6.724142) (xy 76.729082 -6.724142) (xy 76.729082 -4.920742)
			)
		)
	)
	(zone
		(layer "In1.Cu")
		(hatch none 0.5)
		(connect_pads
			(clearance 0)
		)
		(min_thickness 0.25)
		(keepout
			(tracks not_allowed)
			(vias allowed)
			(pads allowed)
			(copperpour not_allowed)
			(footprints allowed)
		)
		(placement
			(enabled no)
			(sheetname "")
		)
		(fill
			(thermal_gap 0.5)
			(thermal_bridge_width 0.5)
			(island_removal_mode 0)
		)
		(polygon
			(pts
				(xy 414.619186 -7.192772) (xy 415.927286 -7.192772) (xy 415.927286 -8.386572) (xy 414.619186 -8.386572)
			)
		)
	)
	(zone
		(layer "In1.Cu")
		(hatch none 0.5)
		(connect_pads
			(clearance 0)
		)
		(min_thickness 0.25)
		(keepout
			(tracks not_allowed)
			(vias allowed)
			(pads allowed)
			(copperpour not_allowed)
			(footprints allowed)
		)
		(placement
			(enabled no)
			(sheetname "")
		)
		(fill
			(thermal_gap 0.5)
			(thermal_bridge_width 0.5)
			(island_removal_mode 0)
		)
		(polygon
			(pts
				(xy 253.920498 -141.775942) (xy 253.920498 -143.579342) (xy 254.479298 -143.579342) (xy 254.479298 -141.775942)
			)
		)
	)
	(zone
		(layer "In1.Cu")
		(hatch none 0.5)
		(connect_pads
			(clearance 0)
		)
		(min_thickness 0.25)
		(keepout
			(tracks not_allowed)
			(vias allowed)
			(pads allowed)
			(copperpour not_allowed)
			(footprints allowed)
		)
		(placement
			(enabled no)
			(sheetname "")
		)
		(fill
			(thermal_gap 0.5)
			(thermal_bridge_width 0.5)
			(island_removal_mode 0)
		)
		(polygon
			(pts
				(xy 207.170528 -14.521942) (xy 207.170528 -16.325342) (xy 207.729328 -16.325342) (xy 207.729328 -14.521942)
			)
		)
	)
	(zone
		(layer "In1.Cu")
		(hatch none 0.5)
		(connect_pads
			(clearance 0)
		)
		(min_thickness 0.25)
		(keepout
			(tracks not_allowed)
			(vias allowed)
			(pads allowed)
			(copperpour not_allowed)
			(footprints allowed)
		)
		(placement
			(enabled no)
			(sheetname "")
		)
		(fill
			(thermal_gap 0.5)
			(thermal_bridge_width 0.5)
			(island_removal_mode 0)
		)
		(polygon
			(pts
				(xy 82.119978 -9.520682) (xy 82.119978 -11.324082) (xy 82.678778 -11.324082) (xy 82.678778 -9.520682)
			)
		)
	)
	(zone
		(layer "In1.Cu")
		(hatch none 0.5)
		(connect_pads
			(clearance 0)
		)
		(min_thickness 0.25)
		(keepout
			(tracks not_allowed)
			(vias allowed)
			(pads allowed)
			(copperpour not_allowed)
			(footprints allowed)
		)
		(placement
			(enabled no)
			(sheetname "")
		)
		(fill
			(thermal_gap 0.5)
			(thermal_bridge_width 0.5)
			(island_removal_mode 0)
		)
		(polygon
			(pts
				(xy 146.720052 -141.775942) (xy 146.720052 -143.579342) (xy 147.278852 -143.579342) (xy 147.278852 -141.775942)
			)
		)
	)
	(zone
		(layer "In1.Cu")
		(hatch none 0.5)
		(connect_pads
			(clearance 0)
		)
		(min_thickness 0.25)
		(keepout
			(tracks not_allowed)
			(vias allowed)
			(pads allowed)
			(copperpour not_allowed)
			(footprints allowed)
		)
		(placement
			(enabled no)
			(sheetname "")
		)
		(fill
			(thermal_gap 0.5)
			(thermal_bridge_width 0.5)
			(island_removal_mode 0)
		)
		(polygon
			(pts
				(xy 222.470472 -151.377142) (xy 222.470472 -153.180542) (xy 223.029272 -153.180542) (xy 223.029272 -151.377142)
			)
		)
	)
	(zone
		(layer "In1.Cu")
		(hatch none 0.5)
		(connect_pads
			(clearance 0)
		)
		(min_thickness 0.25)
		(keepout
			(tracks not_allowed)
			(vias allowed)
			(pads allowed)
			(copperpour not_allowed)
			(footprints allowed)
		)
		(placement
			(enabled no)
			(sheetname "")
		)
		(fill
			(thermal_gap 0.5)
			(thermal_bridge_width 0.5)
			(island_removal_mode 0)
		)
		(polygon
			(pts
				(xy 268.370558 -14.521942) (xy 268.370558 -16.325342) (xy 268.929358 -16.325342) (xy 268.929358 -14.521942)
			)
		)
	)
	(zone
		(layer "In1.Cu")
		(hatch none 0.5)
		(connect_pads
			(clearance 0)
		)
		(min_thickness 0.25)
		(keepout
			(tracks not_allowed)
			(vias allowed)
			(pads allowed)
			(copperpour not_allowed)
			(footprints allowed)
		)
		(placement
			(enabled no)
			(sheetname "")
		)
		(fill
			(thermal_gap 0.5)
			(thermal_bridge_width 0.5)
			(island_removal_mode 0)
		)
		(polygon
			(pts
				(xy 122.070114 -132.174742) (xy 122.070114 -133.978142) (xy 122.628914 -133.978142) (xy 122.628914 -132.174742)
			)
		)
	)
	(zone
		(layer "In1.Cu")
		(hatch none 0.5)
		(connect_pads
			(clearance 0)
		)
		(min_thickness 0.25)
		(keepout
			(tracks not_allowed)
			(vias allowed)
			(pads allowed)
			(copperpour not_allowed)
			(footprints allowed)
		)
		(placement
			(enabled no)
			(sheetname "")
		)
		(fill
			(thermal_gap 0.5)
			(thermal_bridge_width 0.5)
			(island_removal_mode 0)
		)
		(polygon
			(pts
				(xy 242.870482 -14.521942) (xy 242.870482 -16.325342) (xy 243.429282 -16.325342) (xy 243.429282 -14.521942)
			)
		)
	)
	(zone
		(layer "In1.Cu")
		(hatch none 0.5)
		(connect_pads
			(clearance 0)
		)
		(min_thickness 0.25)
		(keepout
			(tracks not_allowed)
			(vias allowed)
			(pads allowed)
			(copperpour not_allowed)
			(footprints allowed)
		)
		(placement
			(enabled no)
			(sheetname "")
		)
		(fill
			(thermal_gap 0.5)
			(thermal_bridge_width 0.5)
			(island_removal_mode 0)
		)
		(polygon
			(pts
				(xy 82.970116 -9.520682) (xy 82.970116 -11.324082) (xy 83.528916 -11.324082) (xy 83.528916 -9.520682)
			)
		)
	)
	(zone
		(layer "In1.Cu")
		(hatch none 0.5)
		(connect_pads
			(clearance 0)
		)
		(min_thickness 0.25)
		(keepout
			(tracks not_allowed)
			(vias allowed)
			(pads allowed)
			(copperpour not_allowed)
			(footprints allowed)
		)
		(placement
			(enabled no)
			(sheetname "")
		)
		(fill
			(thermal_gap 0.5)
			(thermal_bridge_width 0.5)
			(island_removal_mode 0)
		)
		(polygon
			(pts
				(xy 149.269958 -9.520682) (xy 149.269958 -11.324082) (xy 149.828758 -11.324082) (xy 149.828758 -9.520682)
			)
		)
	)
	(zone
		(layer "In1.Cu")
		(hatch none 0.5)
		(connect_pads
			(clearance 0)
		)
		(min_thickness 0.25)
		(keepout
			(tracks not_allowed)
			(vias allowed)
			(pads allowed)
			(copperpour not_allowed)
			(footprints allowed)
		)
		(placement
			(enabled no)
			(sheetname "")
		)
		(fill
			(thermal_gap 0.5)
			(thermal_bridge_width 0.5)
			(island_removal_mode 0)
		)
		(polygon
			(pts
				(xy 39.619936 -155.977082) (xy 39.619936 -157.780482) (xy 40.178736 -157.780482) (xy 40.178736 -155.977082)
			)
		)
	)
	(zone
		(layer "In1.Cu")
		(hatch none 0.5)
		(connect_pads
			(clearance 0)
		)
		(min_thickness 0.25)
		(keepout
			(tracks not_allowed)
			(vias allowed)
			(pads allowed)
			(copperpour not_allowed)
			(footprints allowed)
		)
		(placement
			(enabled no)
			(sheetname "")
		)
		(fill
			(thermal_gap 0.5)
			(thermal_bridge_width 0.5)
			(island_removal_mode 0)
		)
		(polygon
			(pts
				(xy 288.770314 -4.920742) (xy 288.770314 -6.724142) (xy 289.329114 -6.724142) (xy 289.329114 -4.920742)
			)
		)
	)
	(zone
		(layer "In1.Cu")
		(hatch none 0.5)
		(connect_pads
			(clearance 0)
		)
		(min_thickness 0.25)
		(keepout
			(tracks not_allowed)
			(vias allowed)
			(pads allowed)
			(copperpour not_allowed)
			(footprints allowed)
		)
		(placement
			(enabled no)
			(sheetname "")
		)
		(fill
			(thermal_gap 0.5)
			(thermal_bridge_width 0.5)
			(island_removal_mode 0)
		)
		(polygon
			(pts
				(xy 87.220044 -155.977082) (xy 87.220044 -157.780482) (xy 87.778844 -157.780482) (xy 87.778844 -155.977082)
			)
		)
	)
	(zone
		(layer "In1.Cu")
		(hatch none 0.5)
		(connect_pads
			(clearance 0)
		)
		(min_thickness 0.25)
		(keepout
			(tracks not_allowed)
			(vias allowed)
			(pads allowed)
			(copperpour not_allowed)
			(footprints allowed)
		)
		(placement
			(enabled no)
			(sheetname "")
		)
		(fill
			(thermal_gap 0.5)
			(thermal_bridge_width 0.5)
			(island_removal_mode 0)
		)
		(polygon
			(pts
				(xy 313.420506 -141.775942) (xy 313.420506 -143.579342) (xy 313.979306 -143.579342) (xy 313.979306 -141.775942)
			)
		)
	)
	(zone
		(layer "In1.Cu")
		(hatch none 0.5)
		(connect_pads
			(clearance 0)
		)
		(min_thickness 0.25)
		(keepout
			(tracks not_allowed)
			(vias allowed)
			(pads allowed)
			(copperpour not_allowed)
			(footprints allowed)
		)
		(placement
			(enabled no)
			(sheetname "")
		)
		(fill
			(thermal_gap 0.5)
			(thermal_bridge_width 0.5)
			(island_removal_mode 0)
		)
		(polygon
			(pts
				(xy 139.07008 -141.775942) (xy 139.07008 -143.579342) (xy 139.62888 -143.579342) (xy 139.62888 -141.775942)
			)
		)
	)
	(zone
		(layer "In1.Cu")
		(hatch none 0.5)
		(connect_pads
			(clearance 0)
		)
		(min_thickness 0.25)
		(keepout
			(tracks not_allowed)
			(vias allowed)
			(pads allowed)
			(copperpour not_allowed)
			(footprints allowed)
		)
		(placement
			(enabled no)
			(sheetname "")
		)
		(fill
			(thermal_gap 0.5)
			(thermal_bridge_width 0.5)
			(island_removal_mode 0)
		)
		(polygon
			(pts
				(xy 225.870516 4.680458) (xy 225.870516 2.877058) (xy 226.429316 2.877058) (xy 226.429316 4.680458)
			)
		)
	)
	(zone
		(layer "In1.Cu")
		(hatch none 0.5)
		(connect_pads
			(clearance 0)
		)
		(min_thickness 0.25)
		(keepout
			(tracks not_allowed)
			(vias allowed)
			(pads allowed)
			(copperpour not_allowed)
			(footprints allowed)
		)
		(placement
			(enabled no)
			(sheetname "")
		)
		(fill
			(thermal_gap 0.5)
			(thermal_bridge_width 0.5)
			(island_removal_mode 0)
		)
		(polygon
			(pts
				(xy 376.431048 -7.193026) (xy 377.739148 -7.193026) (xy 377.739148 -8.386826) (xy 376.431048 -8.386826)
			)
		)
	)
	(zone
		(layer "In1.Cu")
		(hatch none 0.5)
		(connect_pads
			(clearance 0)
		)
		(min_thickness 0.25)
		(keepout
			(tracks not_allowed)
			(vias allowed)
			(pads allowed)
			(copperpour not_allowed)
			(footprints allowed)
		)
		(placement
			(enabled no)
			(sheetname "")
		)
		(fill
			(thermal_gap 0.5)
			(thermal_bridge_width 0.5)
			(island_removal_mode 0)
		)
		(polygon
			(pts
				(xy 33.669986 -146.375882) (xy 33.669986 -148.179282) (xy 34.228786 -148.179282) (xy 34.228786 -146.375882)
			)
		)
	)
	(zone
		(layer "In1.Cu")
		(hatch none 0.5)
		(connect_pads
			(clearance 0)
		)
		(min_thickness 0.25)
		(keepout
			(tracks not_allowed)
			(vias allowed)
			(pads allowed)
			(copperpour not_allowed)
			(footprints allowed)
		)
		(placement
			(enabled no)
			(sheetname "")
		)
		(fill
			(thermal_gap 0.5)
			(thermal_bridge_width 0.5)
			(island_removal_mode 0)
		)
		(polygon
			(pts
				(xy 299.82033 -132.174742) (xy 299.82033 -133.978142) (xy 300.37913 -133.978142) (xy 300.37913 -132.174742)
			)
		)
	)
	(zone
		(layer "In1.Cu")
		(hatch none 0.5)
		(connect_pads
			(clearance 0)
		)
		(min_thickness 0.25)
		(keepout
			(tracks not_allowed)
			(vias allowed)
			(pads allowed)
			(copperpour not_allowed)
			(footprints allowed)
		)
		(placement
			(enabled no)
			(sheetname "")
		)
		(fill
			(thermal_gap 0.5)
			(thermal_bridge_width 0.5)
			(island_removal_mode 0)
		)
		(polygon
			(pts
				(xy 37.07003 -4.920742) (xy 37.07003 -6.724142) (xy 37.62883 -6.724142) (xy 37.62883 -4.920742)
			)
		)
	)
	(zone
		(layer "In1.Cu")
		(hatch none 0.5)
		(connect_pads
			(clearance 0)
		)
		(min_thickness 0.25)
		(keepout
			(tracks not_allowed)
			(vias allowed)
			(pads allowed)
			(copperpour not_allowed)
			(footprints allowed)
		)
		(placement
			(enabled no)
			(sheetname "")
		)
		(fill
			(thermal_gap 0.5)
			(thermal_bridge_width 0.5)
			(island_removal_mode 0)
		)
		(polygon
			(pts
				(xy 240.320576 -19.121882) (xy 240.320576 -20.925282) (xy 240.879376 -20.925282) (xy 240.879376 -19.121882)
			)
		)
	)
	(zone
		(layer "In1.Cu")
		(hatch none 0.5)
		(connect_pads
			(clearance 0)
		)
		(min_thickness 0.25)
		(keepout
			(tracks not_allowed)
			(vias allowed)
			(pads allowed)
			(copperpour not_allowed)
			(footprints allowed)
		)
		(placement
			(enabled no)
			(sheetname "")
		)
		(fill
			(thermal_gap 0.5)
			(thermal_bridge_width 0.5)
			(island_removal_mode 0)
		)
		(polygon
			(pts
				(xy 208.87055 4.680458) (xy 208.87055 2.877058) (xy 209.42935 2.877058) (xy 209.42935 4.680458)
			)
		)
	)
	(zone
		(layer "In1.Cu")
		(hatch none 0.5)
		(connect_pads
			(clearance 0)
		)
		(min_thickness 0.25)
		(keepout
			(tracks not_allowed)
			(vias allowed)
			(pads allowed)
			(copperpour not_allowed)
			(footprints allowed)
		)
		(placement
			(enabled no)
			(sheetname "")
		)
		(fill
			(thermal_gap 0.5)
			(thermal_bridge_width 0.5)
			(island_removal_mode 0)
		)
		(polygon
			(pts
				(xy 270.07058 -146.375882) (xy 270.07058 -148.179282) (xy 270.62938 -148.179282) (xy 270.62938 -146.375882)
			)
		)
	)
	(zone
		(layer "In1.Cu")
		(hatch none 0.5)
		(connect_pads
			(clearance 0)
		)
		(min_thickness 0.25)
		(keepout
			(tracks not_allowed)
			(vias allowed)
			(pads allowed)
			(copperpour not_allowed)
			(footprints allowed)
		)
		(placement
			(enabled no)
			(sheetname "")
		)
		(fill
			(thermal_gap 0.5)
			(thermal_bridge_width 0.5)
			(island_removal_mode 0)
		)
		(polygon
			(pts
				(xy 118.67007 -14.521942) (xy 118.67007 -16.325342) (xy 119.22887 -16.325342) (xy 119.22887 -14.521942)
			)
		)
	)
	(zone
		(layer "In1.Cu")
		(hatch none 0.5)
		(connect_pads
			(clearance 0)
		)
		(min_thickness 0.25)
		(keepout
			(tracks not_allowed)
			(vias allowed)
			(pads allowed)
			(copperpour not_allowed)
			(footprints allowed)
		)
		(placement
			(enabled no)
			(sheetname "")
		)
		(fill
			(thermal_gap 0.5)
			(thermal_bridge_width 0.5)
			(island_removal_mode 0)
		)
		(polygon
			(pts
				(xy 268.370558 -151.377142) (xy 268.370558 -153.180542) (xy 268.929358 -153.180542) (xy 268.929358 -151.377142)
			)
		)
	)
	(zone
		(layer "In1.Cu")
		(hatch none 0.5)
		(connect_pads
			(clearance 0)
		)
		(min_thickness 0.25)
		(keepout
			(tracks not_allowed)
			(vias allowed)
			(pads allowed)
			(copperpour not_allowed)
			(footprints allowed)
		)
		(placement
			(enabled no)
			(sheetname "")
		)
		(fill
			(thermal_gap 0.5)
			(thermal_bridge_width 0.5)
			(island_removal_mode 0)
		)
		(polygon
			(pts
				(xy 42.170096 -151.377142) (xy 42.170096 -153.180542) (xy 42.728896 -153.180542) (xy 42.728896 -151.377142)
			)
		)
	)
	(zone
		(layer "In1.Cu")
		(hatch none 0.5)
		(connect_pads
			(clearance 0)
		)
		(min_thickness 0.25)
		(keepout
			(tracks not_allowed)
			(vias allowed)
			(pads allowed)
			(copperpour not_allowed)
			(footprints allowed)
		)
		(placement
			(enabled no)
			(sheetname "")
		)
		(fill
			(thermal_gap 0.5)
			(thermal_bridge_width 0.5)
			(island_removal_mode 0)
		)
		(polygon
			(pts
				(xy 122.919998 -9.520682) (xy 122.919998 -11.324082) (xy 123.478798 -11.324082) (xy 123.478798 -9.520682)
			)
		)
	)
	(zone
		(layer "In1.Cu")
		(hatch none 0.5)
		(connect_pads
			(clearance 0)
		)
		(min_thickness 0.25)
		(keepout
			(tracks not_allowed)
			(vias allowed)
			(pads allowed)
			(copperpour not_allowed)
			(footprints allowed)
		)
		(placement
			(enabled no)
			(sheetname "")
		)
		(fill
			(thermal_gap 0.5)
			(thermal_bridge_width 0.5)
			(island_removal_mode 0)
		)
		(polygon
			(pts
				(xy 30.269942 0.080518) (xy 30.269942 -1.722882) (xy 30.828742 -1.722882) (xy 30.828742 0.080518)
			)
		)
	)
	(zone
		(layer "In1.Cu")
		(hatch none 0.5)
		(connect_pads
			(clearance 0)
		)
		(min_thickness 0.25)
		(keepout
			(tracks not_allowed)
			(vias allowed)
			(pads allowed)
			(copperpour not_allowed)
			(footprints allowed)
		)
		(placement
			(enabled no)
			(sheetname "")
		)
		(fill
			(thermal_gap 0.5)
			(thermal_bridge_width 0.5)
			(island_removal_mode 0)
		)
		(polygon
			(pts
				(xy 437.822086 -3.789172) (xy 439.130186 -3.789172) (xy 439.130186 -4.982972) (xy 437.822086 -4.982972)
			)
		)
	)
	(zone
		(layer "In1.Cu")
		(hatch none 0.5)
		(connect_pads
			(clearance 0)
		)
		(min_thickness 0.25)
		(keepout
			(tracks not_allowed)
			(vias allowed)
			(pads allowed)
			(copperpour not_allowed)
			(footprints allowed)
		)
		(placement
			(enabled no)
			(sheetname "")
		)
		(fill
			(thermal_gap 0.5)
			(thermal_bridge_width 0.5)
			(island_removal_mode 0)
		)
		(polygon
			(pts
				(xy 241.170714 -141.775942) (xy 241.170714 -143.579342) (xy 241.729514 -143.579342) (xy 241.729514 -141.775942)
			)
		)
	)
	(zone
		(layer "In1.Cu")
		(hatch none 0.5)
		(connect_pads
			(clearance 0)
		)
		(min_thickness 0.25)
		(keepout
			(tracks not_allowed)
			(vias allowed)
			(pads allowed)
			(copperpour not_allowed)
			(footprints allowed)
		)
		(placement
			(enabled no)
			(sheetname "")
		)
		(fill
			(thermal_gap 0.5)
			(thermal_bridge_width 0.5)
			(island_removal_mode 0)
		)
		(polygon
			(pts
				(xy 122.919998 -19.121882) (xy 122.919998 -20.925282) (xy 123.478798 -20.925282) (xy 123.478798 -19.121882)
			)
		)
	)
	(zone
		(layer "In1.Cu")
		(hatch none 0.5)
		(connect_pads
			(clearance 0)
		)
		(min_thickness 0.25)
		(keepout
			(tracks not_allowed)
			(vias allowed)
			(pads allowed)
			(copperpour not_allowed)
			(footprints allowed)
		)
		(placement
			(enabled no)
			(sheetname "")
		)
		(fill
			(thermal_gap 0.5)
			(thermal_bridge_width 0.5)
			(island_removal_mode 0)
		)
		(polygon
			(pts
				(xy 42.170096 -14.521942) (xy 42.170096 -16.325342) (xy 42.728896 -16.325342) (xy 42.728896 -14.521942)
			)
		)
	)
	(zone
		(layer "In1.Cu")
		(hatch none 0.5)
		(connect_pads
			(clearance 0)
		)
		(min_thickness 0.25)
		(keepout
			(tracks not_allowed)
			(vias allowed)
			(pads allowed)
			(copperpour not_allowed)
			(footprints allowed)
		)
		(placement
			(enabled no)
			(sheetname "")
		)
		(fill
			(thermal_gap 0.5)
			(thermal_bridge_width 0.5)
			(island_removal_mode 0)
		)
		(polygon
			(pts
				(xy 143.320008 -155.977082) (xy 143.320008 -157.780482) (xy 143.878808 -157.780482) (xy 143.878808 -155.977082)
			)
		)
	)
	(zone
		(layer "In1.Cu")
		(hatch none 0.5)
		(connect_pads
			(clearance 0)
		)
		(min_thickness 0.25)
		(keepout
			(tracks not_allowed)
			(vias allowed)
			(pads allowed)
			(copperpour not_allowed)
			(footprints allowed)
		)
		(placement
			(enabled no)
			(sheetname "")
		)
		(fill
			(thermal_gap 0.5)
			(thermal_bridge_width 0.5)
			(island_removal_mode 0)
		)
		(polygon
			(pts
				(xy 234.370372 0.080518) (xy 234.370372 -1.722882) (xy 234.929172 -1.722882) (xy 234.929172 0.080518)
			)
		)
	)
	(zone
		(layer "In1.Cu")
		(hatch none 0.5)
		(connect_pads
			(clearance 0)
		)
		(min_thickness 0.25)
		(keepout
			(tracks not_allowed)
			(vias allowed)
			(pads allowed)
			(copperpour not_allowed)
			(footprints allowed)
		)
		(placement
			(enabled no)
			(sheetname "")
		)
		(fill
			(thermal_gap 0.5)
			(thermal_bridge_width 0.5)
			(island_removal_mode 0)
		)
		(polygon
			(pts
				(xy 253.920498 -132.174742) (xy 253.920498 -133.978142) (xy 254.479298 -133.978142) (xy 254.479298 -132.174742)
			)
		)
	)
	(zone
		(layer "In1.Cu")
		(hatch none 0.5)
		(connect_pads
			(clearance 0)
		)
		(min_thickness 0.25)
		(keepout
			(tracks not_allowed)
			(vias allowed)
			(pads allowed)
			(copperpour not_allowed)
			(footprints allowed)
		)
		(placement
			(enabled no)
			(sheetname "")
		)
		(fill
			(thermal_gap 0.5)
			(thermal_bridge_width 0.5)
			(island_removal_mode 0)
		)
		(polygon
			(pts
				(xy 125.469904 -14.521942) (xy 125.469904 -16.325342) (xy 126.028704 -16.325342) (xy 126.028704 -14.521942)
			)
		)
	)
	(zone
		(layer "In1.Cu")
		(hatch none 0.5)
		(connect_pads
			(clearance 0)
		)
		(min_thickness 0.25)
		(keepout
			(tracks not_allowed)
			(vias allowed)
			(pads allowed)
			(copperpour not_allowed)
			(footprints allowed)
		)
		(placement
			(enabled no)
			(sheetname "")
		)
		(fill
			(thermal_gap 0.5)
			(thermal_bridge_width 0.5)
			(island_removal_mode 0)
		)
		(polygon
			(pts
				(xy 280.270458 0.080518) (xy 280.270458 -1.722882) (xy 280.829258 -1.722882) (xy 280.829258 0.080518)
			)
		)
	)
	(zone
		(layer "In1.Cu")
		(hatch none 0.5)
		(connect_pads
			(clearance 0)
		)
		(min_thickness 0.25)
		(keepout
			(tracks not_allowed)
			(vias allowed)
			(pads allowed)
			(copperpour not_allowed)
			(footprints allowed)
		)
		(placement
			(enabled no)
			(sheetname "")
		)
		(fill
			(thermal_gap 0.5)
			(thermal_bridge_width 0.5)
			(island_removal_mode 0)
		)
		(polygon
			(pts
				(xy 41.319958 -19.121882) (xy 41.319958 -20.925282) (xy 41.878758 -20.925282) (xy 41.878758 -19.121882)
			)
		)
	)
	(zone
		(layer "In1.Cu")
		(hatch none 0.5)
		(connect_pads
			(clearance 0)
		)
		(min_thickness 0.25)
		(keepout
			(tracks not_allowed)
			(vias allowed)
			(pads allowed)
			(copperpour not_allowed)
			(footprints allowed)
		)
		(placement
			(enabled no)
			(sheetname "")
		)
		(fill
			(thermal_gap 0.5)
			(thermal_bridge_width 0.5)
			(island_removal_mode 0)
		)
		(polygon
			(pts
				(xy 287.92043 -9.520682) (xy 287.92043 -11.324082) (xy 288.47923 -11.324082) (xy 288.47923 -9.520682)
			)
		)
	)
	(zone
		(layer "In1.Cu")
		(hatch none 0.5)
		(connect_pads
			(clearance 0)
		)
		(min_thickness 0.25)
		(keepout
			(tracks not_allowed)
			(vias allowed)
			(pads allowed)
			(copperpour not_allowed)
			(footprints allowed)
		)
		(placement
			(enabled no)
			(sheetname "")
		)
		(fill
			(thermal_gap 0.5)
			(thermal_bridge_width 0.5)
			(island_removal_mode 0)
		)
		(polygon
			(pts
				(xy 237.770416 -14.521942) (xy 237.770416 -16.325342) (xy 238.329216 -16.325342) (xy 238.329216 -14.521942)
			)
		)
	)
	(zone
		(layer "In1.Cu")
		(hatch none 0.5)
		(connect_pads
			(clearance 0)
		)
		(min_thickness 0.25)
		(keepout
			(tracks not_allowed)
			(vias allowed)
			(pads allowed)
			(copperpour not_allowed)
			(footprints allowed)
		)
		(placement
			(enabled no)
			(sheetname "")
		)
		(fill
			(thermal_gap 0.5)
			(thermal_bridge_width 0.5)
			(island_removal_mode 0)
		)
		(polygon
			(pts
				(xy 293.020496 -155.977082) (xy 293.020496 -157.780482) (xy 293.579296 -157.780482) (xy 293.579296 -155.977082)
			)
		)
	)
	(zone
		(layer "In1.Cu")
		(hatch none 0.5)
		(connect_pads
			(clearance 0)
		)
		(min_thickness 0.25)
		(keepout
			(tracks not_allowed)
			(vias allowed)
			(pads allowed)
			(copperpour not_allowed)
			(footprints allowed)
		)
		(placement
			(enabled no)
			(sheetname "")
		)
		(fill
			(thermal_gap 0.5)
			(thermal_bridge_width 0.5)
			(island_removal_mode 0)
		)
		(polygon
			(pts
				(xy 229.27056 0.080518) (xy 229.27056 -1.722882) (xy 229.82936 -1.722882) (xy 229.82936 0.080518)
			)
		)
	)
	(zone
		(layer "In1.Cu")
		(hatch none 0.5)
		(connect_pads
			(clearance 0)
		)
		(min_thickness 0.25)
		(keepout
			(tracks not_allowed)
			(vias allowed)
			(pads allowed)
			(copperpour not_allowed)
			(footprints allowed)
		)
		(placement
			(enabled no)
			(sheetname "")
		)
		(fill
			(thermal_gap 0.5)
			(thermal_bridge_width 0.5)
			(island_removal_mode 0)
		)
		(polygon
			(pts
				(xy 69.36994 0.080518) (xy 69.36994 -1.722882) (xy 69.92874 -1.722882) (xy 69.92874 0.080518)
			)
		)
	)
	(zone
		(layer "In1.Cu")
		(hatch none 0.5)
		(connect_pads
			(clearance 0)
		)
		(min_thickness 0.25)
		(keepout
			(tracks not_allowed)
			(vias allowed)
			(pads allowed)
			(copperpour not_allowed)
			(footprints allowed)
		)
		(placement
			(enabled no)
			(sheetname "")
		)
		(fill
			(thermal_gap 0.5)
			(thermal_bridge_width 0.5)
			(island_removal_mode 0)
		)
		(polygon
			(pts
				(xy 460.296006 -60.99937) (xy 461.604106 -60.99937) (xy 461.604106 -63.00597) (xy 460.296006 -63.00597)
			)
		)
	)
	(zone
		(layer "In1.Cu")
		(hatch none 0.5)
		(connect_pads
			(clearance 0)
		)
		(min_thickness 0.25)
		(keepout
			(tracks not_allowed)
			(vias allowed)
			(pads allowed)
			(copperpour not_allowed)
			(footprints allowed)
		)
		(placement
			(enabled no)
			(sheetname "")
		)
		(fill
			(thermal_gap 0.5)
			(thermal_bridge_width 0.5)
			(island_removal_mode 0)
		)
		(polygon
			(pts
				(xy 247.970548 -136.774682) (xy 247.970548 -138.578082) (xy 248.529348 -138.578082) (xy 248.529348 -136.774682)
			)
		)
	)
	(zone
		(layer "In1.Cu")
		(hatch none 0.5)
		(connect_pads
			(clearance 0)
		)
		(min_thickness 0.25)
		(keepout
			(tracks not_allowed)
			(vias allowed)
			(pads allowed)
			(copperpour not_allowed)
			(footprints allowed)
		)
		(placement
			(enabled no)
			(sheetname "")
		)
		(fill
			(thermal_gap 0.5)
			(thermal_bridge_width 0.5)
			(island_removal_mode 0)
		)
		(polygon
			(pts
				(xy 216.520522 4.680458) (xy 216.520522 2.877058) (xy 217.079322 2.877058) (xy 217.079322 4.680458)
			)
		)
	)
	(zone
		(layer "In1.Cu")
		(hatch none 0.5)
		(connect_pads
			(clearance 0)
		)
		(min_thickness 0.25)
		(keepout
			(tracks not_allowed)
			(vias allowed)
			(pads allowed)
			(copperpour not_allowed)
			(footprints allowed)
		)
		(placement
			(enabled no)
			(sheetname "")
		)
		(fill
			(thermal_gap 0.5)
			(thermal_bridge_width 0.5)
			(island_removal_mode 0)
		)
		(polygon
			(pts
				(xy 13.6398 -33.655) (xy 15.0368 -33.655) (xy 15.0368 -34.163) (xy 13.6398 -34.163)
			)
		)
	)
	(zone
		(layer "In1.Cu")
		(hatch none 0.5)
		(connect_pads
			(clearance 0)
		)
		(min_thickness 0.25)
		(keepout
			(tracks not_allowed)
			(vias allowed)
			(pads allowed)
			(copperpour not_allowed)
			(footprints allowed)
		)
		(placement
			(enabled no)
			(sheetname "")
		)
		(fill
			(thermal_gap 0.5)
			(thermal_bridge_width 0.5)
			(island_removal_mode 0)
		)
		(polygon
			(pts
				(xy 249.67057 -19.121882) (xy 250.22937 -19.121882) (xy 250.22937 -20.925282) (xy 249.67057 -20.925282)
			)
		)
	)
	(zone
		(layer "In1.Cu")
		(hatch none 0.5)
		(connect_pads
			(clearance 0)
		)
		(min_thickness 0.25)
		(keepout
			(tracks not_allowed)
			(vias allowed)
			(pads allowed)
			(copperpour not_allowed)
			(footprints allowed)
		)
		(placement
			(enabled no)
			(sheetname "")
		)
		(fill
			(thermal_gap 0.5)
			(thermal_bridge_width 0.5)
			(island_removal_mode 0)
		)
		(polygon
			(pts
				(xy 202.070462 -14.521942) (xy 202.070462 -16.325342) (xy 202.629262 -16.325342) (xy 202.629262 -14.521942)
			)
		)
	)
	(zone
		(layer "In1.Cu")
		(hatch none 0.5)
		(connect_pads
			(clearance 0)
		)
		(min_thickness 0.25)
		(keepout
			(tracks not_allowed)
			(vias allowed)
			(pads allowed)
			(copperpour not_allowed)
			(footprints allowed)
		)
		(placement
			(enabled no)
			(sheetname "")
		)
		(fill
			(thermal_gap 0.5)
			(thermal_bridge_width 0.5)
			(island_removal_mode 0)
		)
		(polygon
			(pts
				(xy 70.220078 -141.775942) (xy 70.220078 -143.579342) (xy 70.778878 -143.579342) (xy 70.778878 -141.775942)
			)
		)
	)
	(zone
		(layer "In1.Cu")
		(hatch none 0.5)
		(connect_pads
			(clearance 0)
		)
		(min_thickness 0.25)
		(keepout
			(tracks not_allowed)
			(vias allowed)
			(pads allowed)
			(copperpour not_allowed)
			(footprints allowed)
		)
		(placement
			(enabled no)
			(sheetname "")
		)
		(fill
			(thermal_gap 0.5)
			(thermal_bridge_width 0.5)
			(island_removal_mode 0)
		)
		(polygon
			(pts
				(xy 246.270526 -132.174742) (xy 246.270526 -133.978142) (xy 246.829326 -133.978142) (xy 246.829326 -132.174742)
			)
		)
	)
	(zone
		(layer "In1.Cu")
		(hatch none 0.5)
		(connect_pads
			(clearance 0)
		)
		(min_thickness 0.25)
		(keepout
			(tracks not_allowed)
			(vias allowed)
			(pads allowed)
			(copperpour not_allowed)
			(footprints allowed)
		)
		(placement
			(enabled no)
			(sheetname "")
		)
		(fill
			(thermal_gap 0.5)
			(thermal_bridge_width 0.5)
			(island_removal_mode 0)
		)
		(polygon
			(pts
				(xy 146.720052 -136.774682) (xy 146.720052 -138.578082) (xy 147.278852 -138.578082) (xy 147.278852 -136.774682)
			)
		)
	)
	(zone
		(layer "In1.Cu")
		(hatch none 0.5)
		(connect_pads
			(clearance 0)
		)
		(min_thickness 0.25)
		(keepout
			(tracks not_allowed)
			(vias allowed)
			(pads allowed)
			(copperpour not_allowed)
			(footprints allowed)
		)
		(placement
			(enabled no)
			(sheetname "")
		)
		(fill
			(thermal_gap 0.5)
			(thermal_bridge_width 0.5)
			(island_removal_mode 0)
		)
		(polygon
			(pts
				(xy 239.470438 -132.174742) (xy 239.470438 -133.978142) (xy 240.029238 -133.978142) (xy 240.029238 -132.174742)
			)
		)
	)
	(zone
		(layer "In1.Cu")
		(hatch none 0.5)
		(connect_pads
			(clearance 0)
		)
		(min_thickness 0.25)
		(keepout
			(tracks not_allowed)
			(vias allowed)
			(pads allowed)
			(copperpour not_allowed)
			(footprints allowed)
		)
		(placement
			(enabled no)
			(sheetname "")
		)
		(fill
			(thermal_gap 0.5)
			(thermal_bridge_width 0.5)
			(island_removal_mode 0)
		)
		(polygon
			(pts
				(xy 208.020412 -146.375882) (xy 208.020412 -148.179282) (xy 208.579212 -148.179282) (xy 208.579212 -146.375882)
			)
		)
	)
	(zone
		(layer "In1.Cu")
		(hatch none 0.5)
		(connect_pads
			(clearance 0)
		)
		(min_thickness 0.25)
		(keepout
			(tracks not_allowed)
			(vias allowed)
			(pads allowed)
			(copperpour not_allowed)
			(footprints allowed)
		)
		(placement
			(enabled no)
			(sheetname "")
		)
		(fill
			(thermal_gap 0.5)
			(thermal_bridge_width 0.5)
			(island_removal_mode 0)
		)
		(polygon
			(pts
				(xy 116.11991 -141.775942) (xy 116.11991 -143.579342) (xy 116.67871 -143.579342) (xy 116.67871 -141.775942)
			)
		)
	)
	(zone
		(layer "In1.Cu")
		(hatch none 0.5)
		(connect_pads
			(clearance 0)
		)
		(min_thickness 0.25)
		(keepout
			(tracks not_allowed)
			(vias allowed)
			(pads allowed)
			(copperpour not_allowed)
			(footprints allowed)
		)
		(placement
			(enabled no)
			(sheetname "")
		)
		(fill
			(thermal_gap 0.5)
			(thermal_bridge_width 0.5)
			(island_removal_mode 0)
		)
		(polygon
			(pts
				(xy 287.92043 -136.774682) (xy 287.92043 -138.578082) (xy 288.47923 -138.578082) (xy 288.47923 -136.774682)
			)
		)
	)
	(zone
		(layer "In1.Cu")
		(hatch none 0.5)
		(connect_pads
			(clearance 0)
		)
		(min_thickness 0.25)
		(keepout
			(tracks not_allowed)
			(vias allowed)
			(pads allowed)
			(copperpour not_allowed)
			(footprints allowed)
		)
		(placement
			(enabled no)
			(sheetname "")
		)
		(fill
			(thermal_gap 0.5)
			(thermal_bridge_width 0.5)
			(island_removal_mode 0)
		)
		(polygon
			(pts
				(xy 111.020098 -19.121882) (xy 111.578898 -19.121882) (xy 111.578898 -20.925282) (xy 111.020098 -20.925282)
			)
		)
	)
	(zone
		(layer "In1.Cu")
		(hatch none 0.5)
		(connect_pads
			(clearance 0)
		)
		(min_thickness 0.25)
		(keepout
			(tracks not_allowed)
			(vias allowed)
			(pads allowed)
			(copperpour not_allowed)
			(footprints allowed)
		)
		(placement
			(enabled no)
			(sheetname "")
		)
		(fill
			(thermal_gap 0.5)
			(thermal_bridge_width 0.5)
			(island_removal_mode 0)
		)
		(polygon
			(pts
				(xy 121.219976 -136.774682) (xy 121.219976 -138.578082) (xy 121.778776 -138.578082) (xy 121.778776 -136.774682)
			)
		)
	)
	(zone
		(layer "In1.Cu")
		(hatch none 0.5)
		(connect_pads
			(clearance 0)
		)
		(min_thickness 0.25)
		(keepout
			(tracks not_allowed)
			(vias allowed)
			(pads allowed)
			(copperpour not_allowed)
			(footprints allowed)
		)
		(placement
			(enabled no)
			(sheetname "")
		)
		(fill
			(thermal_gap 0.5)
			(thermal_bridge_width 0.5)
			(island_removal_mode 0)
		)
		(polygon
			(pts
				(xy 45.57014 -155.977082) (xy 45.57014 -157.780482) (xy 46.12894 -157.780482) (xy 46.12894 -155.977082)
			)
		)
	)
	(zone
		(layer "In1.Cu")
		(hatch none 0.5)
		(connect_pads
			(clearance 0)
		)
		(min_thickness 0.25)
		(keepout
			(tracks not_allowed)
			(vias allowed)
			(pads allowed)
			(copperpour not_allowed)
			(footprints allowed)
		)
		(placement
			(enabled no)
			(sheetname "")
		)
		(fill
			(thermal_gap 0.5)
			(thermal_bridge_width 0.5)
			(island_removal_mode 0)
		)
		(polygon
			(pts
				(xy 234.370372 -19.121882) (xy 234.370372 -20.925282) (xy 234.929172 -20.925282) (xy 234.929172 -19.121882)
			)
		)
	)
	(zone
		(layer "In1.Cu")
		(hatch none 0.5)
		(connect_pads
			(clearance 0)
		)
		(min_thickness 0.25)
		(keepout
			(tracks not_allowed)
			(vias allowed)
			(pads allowed)
			(copperpour not_allowed)
			(footprints allowed)
		)
		(placement
			(enabled no)
			(sheetname "")
		)
		(fill
			(thermal_gap 0.5)
			(thermal_bridge_width 0.5)
			(island_removal_mode 0)
		)
		(polygon
			(pts
				(xy 63.41999 -14.521942) (xy 63.41999 -16.325342) (xy 63.97879 -16.325342) (xy 63.97879 -14.521942)
			)
		)
	)
	(zone
		(layer "In1.Cu")
		(hatch none 0.5)
		(connect_pads
			(clearance 0)
		)
		(min_thickness 0.25)
		(keepout
			(tracks not_allowed)
			(vias allowed)
			(pads allowed)
			(copperpour not_allowed)
			(footprints allowed)
		)
		(placement
			(enabled no)
			(sheetname "")
		)
		(fill
			(thermal_gap 0.5)
			(thermal_bridge_width 0.5)
			(island_removal_mode 0)
		)
		(polygon
			(pts
				(xy 69.36994 -155.977082) (xy 69.36994 -157.780482) (xy 69.92874 -157.780482) (xy 69.92874 -155.977082)
			)
		)
	)
	(zone
		(layer "In1.Cu")
		(hatch none 0.5)
		(connect_pads
			(clearance 0)
		)
		(min_thickness 0.25)
		(keepout
			(tracks not_allowed)
			(vias allowed)
			(pads allowed)
			(copperpour not_allowed)
			(footprints allowed)
		)
		(placement
			(enabled no)
			(sheetname "")
		)
		(fill
			(thermal_gap 0.5)
			(thermal_bridge_width 0.5)
			(island_removal_mode 0)
		)
		(polygon
			(pts
				(xy 216.520522 -151.377142) (xy 216.520522 -153.180542) (xy 217.079322 -153.180542) (xy 217.079322 -151.377142)
			)
		)
	)
	(zone
		(layer "In1.Cu")
		(hatch none 0.5)
		(connect_pads
			(clearance 0)
		)
		(min_thickness 0.25)
		(keepout
			(tracks not_allowed)
			(vias allowed)
			(pads allowed)
			(copperpour not_allowed)
			(footprints allowed)
		)
		(placement
			(enabled no)
			(sheetname "")
		)
		(fill
			(thermal_gap 0.5)
			(thermal_bridge_width 0.5)
			(island_removal_mode 0)
		)
		(polygon
			(pts
				(xy 362.031026 -7.193026) (xy 363.339126 -7.193026) (xy 363.339126 -8.386826) (xy 362.031026 -8.386826)
			)
		)
	)
	(zone
		(layer "In1.Cu")
		(hatch none 0.5)
		(connect_pads
			(clearance 0)
		)
		(min_thickness 0.25)
		(keepout
			(tracks not_allowed)
			(vias allowed)
			(pads allowed)
			(copperpour not_allowed)
			(footprints allowed)
		)
		(placement
			(enabled no)
			(sheetname "")
		)
		(fill
			(thermal_gap 0.5)
			(thermal_bridge_width 0.5)
			(island_removal_mode 0)
		)
		(polygon
			(pts
				(xy 280.270458 -136.774682) (xy 280.270458 -138.578082) (xy 280.829258 -138.578082) (xy 280.829258 -136.774682)
			)
		)
	)
	(zone
		(layer "In1.Cu")
		(hatch none 0.5)
		(connect_pads
			(clearance 0)
		)
		(min_thickness 0.25)
		(keepout
			(tracks not_allowed)
			(vias allowed)
			(pads allowed)
			(copperpour not_allowed)
			(footprints allowed)
		)
		(placement
			(enabled no)
			(sheetname "")
		)
		(fill
			(thermal_gap 0.5)
			(thermal_bridge_width 0.5)
			(island_removal_mode 0)
		)
		(polygon
			(pts
				(xy 118.67007 4.680458) (xy 118.67007 2.877058) (xy 119.22887 2.877058) (xy 119.22887 4.680458)
			)
		)
	)
	(zone
		(layer "In1.Cu")
		(hatch none 0.5)
		(connect_pads
			(clearance 0)
		)
		(min_thickness 0.25)
		(keepout
			(tracks not_allowed)
			(vias allowed)
			(pads allowed)
			(copperpour not_allowed)
			(footprints allowed)
		)
		(placement
			(enabled no)
			(sheetname "")
		)
		(fill
			(thermal_gap 0.5)
			(thermal_bridge_width 0.5)
			(island_removal_mode 0)
		)
		(polygon
			(pts
				(xy 287.070546 -14.521942) (xy 287.070546 -16.325342) (xy 287.629346 -16.325342) (xy 287.629346 -14.521942)
			)
		)
	)
	(zone
		(layer "In1.Cu")
		(hatch none 0.5)
		(connect_pads
			(clearance 0)
		)
		(min_thickness 0.25)
		(keepout
			(tracks not_allowed)
			(vias allowed)
			(pads allowed)
			(copperpour not_allowed)
			(footprints allowed)
		)
		(placement
			(enabled no)
			(sheetname "")
		)
		(fill
			(thermal_gap 0.5)
			(thermal_bridge_width 0.5)
			(island_removal_mode 0)
		)
		(polygon
			(pts
				(xy 450.623178 -7.192772) (xy 451.931278 -7.192772) (xy 451.931278 -8.386572) (xy 450.623178 -8.386572)
			)
		)
	)
	(zone
		(layer "In1.Cu")
		(hatch none 0.5)
		(connect_pads
			(clearance 0)
		)
		(min_thickness 0.25)
		(keepout
			(tracks not_allowed)
			(vias allowed)
			(pads allowed)
			(copperpour not_allowed)
			(footprints allowed)
		)
		(placement
			(enabled no)
			(sheetname "")
		)
		(fill
			(thermal_gap 0.5)
			(thermal_bridge_width 0.5)
			(island_removal_mode 0)
		)
		(polygon
			(pts
				(xy 253.920498 4.680458) (xy 253.920498 2.877058) (xy 254.479298 2.877058) (xy 254.479298 4.680458)
			)
		)
	)
	(zone
		(layer "In1.Cu")
		(hatch none 0.5)
		(connect_pads
			(clearance 0)
		)
		(min_thickness 0.25)
		(keepout
			(tracks not_allowed)
			(vias allowed)
			(pads allowed)
			(copperpour not_allowed)
			(footprints allowed)
		)
		(placement
			(enabled no)
			(sheetname "")
		)
		(fill
			(thermal_gap 0.5)
			(thermal_bridge_width 0.5)
			(island_removal_mode 0)
		)
		(polygon
			(pts
				(xy 226.7204 -9.520682) (xy 226.7204 -11.324082) (xy 227.2792 -11.324082) (xy 227.2792 -9.520682)
			)
		)
	)
	(zone
		(layer "In1.Cu")
		(hatch none 0.5)
		(connect_pads
			(clearance 0)
		)
		(min_thickness 0.25)
		(keepout
			(tracks not_allowed)
			(vias allowed)
			(pads allowed)
			(copperpour not_allowed)
			(footprints allowed)
		)
		(placement
			(enabled no)
			(sheetname "")
		)
		(fill
			(thermal_gap 0.5)
			(thermal_bridge_width 0.5)
			(island_removal_mode 0)
		)
		(polygon
			(pts
				(xy 253.070614 -155.977082) (xy 253.070614 -157.780482) (xy 253.629414 -157.780482) (xy 253.629414 -155.977082)
			)
		)
	)
	(zone
		(layer "In1.Cu")
		(hatch none 0.5)
		(connect_pads
			(clearance 0)
		)
		(min_thickness 0.25)
		(keepout
			(tracks not_allowed)
			(vias allowed)
			(pads allowed)
			(copperpour not_allowed)
			(footprints allowed)
		)
		(placement
			(enabled no)
			(sheetname "")
		)
		(fill
			(thermal_gap 0.5)
			(thermal_bridge_width 0.5)
			(island_removal_mode 0)
		)
		(polygon
			(pts
				(xy 49.820068 -4.920742) (xy 49.820068 -6.724142) (xy 50.378868 -6.724142) (xy 50.378868 -4.920742)
			)
		)
	)
	(zone
		(layer "In1.Cu")
		(hatch none 0.5)
		(connect_pads
			(clearance 0)
		)
		(min_thickness 0.25)
		(keepout
			(tracks not_allowed)
			(vias allowed)
			(pads allowed)
			(copperpour not_allowed)
			(footprints allowed)
		)
		(placement
			(enabled no)
			(sheetname "")
		)
		(fill
			(thermal_gap 0.5)
			(thermal_bridge_width 0.5)
			(island_removal_mode 0)
		)
		(polygon
			(pts
				(xy 417.6522 -91.5289) (xy 417.6522 -92.9259) (xy 419.0492 -92.9259) (xy 419.0492 -91.5289)
			)
		)
	)
	(zone
		(layer "In1.Cu")
		(hatch none 0.5)
		(connect_pads
			(clearance 0)
		)
		(min_thickness 0.25)
		(keepout
			(tracks not_allowed)
			(vias allowed)
			(pads allowed)
			(copperpour not_allowed)
			(footprints allowed)
		)
		(placement
			(enabled no)
			(sheetname "")
		)
		(fill
			(thermal_gap 0.5)
			(thermal_bridge_width 0.5)
			(island_removal_mode 0)
		)
		(polygon
			(pts
				(xy 256.470404 -155.977082) (xy 256.470404 -157.780482) (xy 257.029204 -157.780482) (xy 257.029204 -155.977082)
			)
		)
	)
	(zone
		(layer "In1.Cu")
		(hatch none 0.5)
		(connect_pads
			(clearance 0)
		)
		(min_thickness 0.25)
		(keepout
			(tracks not_allowed)
			(vias allowed)
			(pads allowed)
			(copperpour not_allowed)
			(footprints allowed)
		)
		(placement
			(enabled no)
			(sheetname "")
		)
		(fill
			(thermal_gap 0.5)
			(thermal_bridge_width 0.5)
			(island_removal_mode 0)
		)
		(polygon
			(pts
				(xy 60.870084 4.680458) (xy 60.870084 2.877058) (xy 61.428884 2.877058) (xy 61.428884 4.680458)
			)
		)
	)
	(zone
		(layer "In1.Cu")
		(hatch none 0.5)
		(connect_pads
			(clearance 0)
		)
		(min_thickness 0.25)
		(keepout
			(tracks not_allowed)
			(vias allowed)
			(pads allowed)
			(copperpour not_allowed)
			(footprints allowed)
		)
		(placement
			(enabled no)
			(sheetname "")
		)
		(fill
			(thermal_gap 0.5)
			(thermal_bridge_width 0.5)
			(island_removal_mode 0)
		)
		(polygon
			(pts
				(xy 51.52009 -132.174742) (xy 51.52009 -133.978142) (xy 52.07889 -133.978142) (xy 52.07889 -132.174742)
			)
		)
	)
	(zone
		(layer "In1.Cu")
		(hatch none 0.5)
		(connect_pads
			(clearance 0)
		)
		(min_thickness 0.25)
		(keepout
			(tracks not_allowed)
			(vias allowed)
			(pads allowed)
			(copperpour not_allowed)
			(footprints allowed)
		)
		(placement
			(enabled no)
			(sheetname "")
		)
		(fill
			(thermal_gap 0.5)
			(thermal_bridge_width 0.5)
			(island_removal_mode 0)
		)
		(polygon
			(pts
				(xy 196.970396 -19.121882) (xy 196.970396 -20.925282) (xy 197.529196 -20.925282) (xy 197.529196 -19.121882)
			)
		)
	)
	(zone
		(layer "In1.Cu")
		(hatch none 0.5)
		(connect_pads
			(clearance 0)
		)
		(min_thickness 0.25)
		(keepout
			(tracks not_allowed)
			(vias allowed)
			(pads allowed)
			(copperpour not_allowed)
			(footprints allowed)
		)
		(placement
			(enabled no)
			(sheetname "")
		)
		(fill
			(thermal_gap 0.5)
			(thermal_bridge_width 0.5)
			(island_removal_mode 0)
		)
		(polygon
			(pts
				(xy 82.119978 -4.920742) (xy 82.119978 -6.724142) (xy 82.678778 -6.724142) (xy 82.678778 -4.920742)
			)
		)
	)
	(zone
		(layer "In1.Cu")
		(hatch none 0.5)
		(connect_pads
			(clearance 0)
		)
		(min_thickness 0.25)
		(keepout
			(tracks not_allowed)
			(vias allowed)
			(pads allowed)
			(copperpour not_allowed)
			(footprints allowed)
		)
		(placement
			(enabled no)
			(sheetname "")
		)
		(fill
			(thermal_gap 0.5)
			(thermal_bridge_width 0.5)
			(island_removal_mode 0)
		)
		(polygon
			(pts
				(xy 247.970548 -146.375882) (xy 247.970548 -148.179282) (xy 248.529348 -148.179282) (xy 248.529348 -146.375882)
			)
		)
	)
	(zone
		(layer "In1.Cu")
		(hatch none 0.5)
		(connect_pads
			(clearance 0)
		)
		(min_thickness 0.25)
		(keepout
			(tracks not_allowed)
			(vias allowed)
			(pads allowed)
			(copperpour not_allowed)
			(footprints allowed)
		)
		(placement
			(enabled no)
			(sheetname "")
		)
		(fill
			(thermal_gap 0.5)
			(thermal_bridge_width 0.5)
			(island_removal_mode 0)
		)
		(polygon
			(pts
				(xy 112.72012 -155.977082) (xy 112.72012 -157.780482) (xy 113.27892 -157.780482) (xy 113.27892 -155.977082)
			)
		)
	)
	(zone
		(layer "In1.Cu")
		(hatch none 0.5)
		(connect_pads
			(clearance 0)
		)
		(min_thickness 0.25)
		(keepout
			(tracks not_allowed)
			(vias allowed)
			(pads allowed)
			(copperpour not_allowed)
			(footprints allowed)
		)
		(placement
			(enabled no)
			(sheetname "")
		)
		(fill
			(thermal_gap 0.5)
			(thermal_bridge_width 0.5)
			(island_removal_mode 0)
		)
		(polygon
			(pts
				(xy 282.820364 -141.775942) (xy 282.820364 -143.579342) (xy 283.379164 -143.579342) (xy 283.379164 -141.775942)
			)
		)
	)
	(zone
		(layer "In1.Cu")
		(hatch none 0.5)
		(connect_pads
			(clearance 0)
		)
		(min_thickness 0.25)
		(keepout
			(tracks not_allowed)
			(vias allowed)
			(pads allowed)
			(copperpour not_allowed)
			(footprints allowed)
		)
		(placement
			(enabled no)
			(sheetname "")
		)
		(fill
			(thermal_gap 0.5)
			(thermal_bridge_width 0.5)
			(island_removal_mode 0)
		)
		(polygon
			(pts
				(xy 146.720052 0.080518) (xy 146.720052 -1.722882) (xy 147.278852 -1.722882) (xy 147.278852 0.080518)
			)
		)
	)
	(zone
		(layer "In1.Cu")
		(hatch none 0.5)
		(connect_pads
			(clearance 0)
		)
		(min_thickness 0.25)
		(keepout
			(tracks not_allowed)
			(vias allowed)
			(pads allowed)
			(copperpour not_allowed)
			(footprints allowed)
		)
		(placement
			(enabled no)
			(sheetname "")
		)
		(fill
			(thermal_gap 0.5)
			(thermal_bridge_width 0.5)
			(island_removal_mode 0)
		)
		(polygon
			(pts
				(xy 237.770416 4.680458) (xy 237.770416 2.877058) (xy 238.329216 2.877058) (xy 238.329216 4.680458)
			)
		)
	)
	(zone
		(layer "In1.Cu")
		(hatch none 0.5)
		(connect_pads
			(clearance 0)
		)
		(min_thickness 0.25)
		(keepout
			(tracks not_allowed)
			(vias allowed)
			(pads allowed)
			(copperpour not_allowed)
			(footprints allowed)
		)
		(placement
			(enabled no)
			(sheetname "")
		)
		(fill
			(thermal_gap 0.5)
			(thermal_bridge_width 0.5)
			(island_removal_mode 0)
		)
		(polygon
			(pts
				(xy 207.170528 -141.775942) (xy 207.170528 -143.579342) (xy 207.729328 -143.579342) (xy 207.729328 -141.775942)
			)
		)
	)
	(zone
		(layer "In1.Cu")
		(hatch none 0.5)
		(connect_pads
			(clearance 0)
		)
		(min_thickness 0.25)
		(keepout
			(tracks not_allowed)
			(vias allowed)
			(pads allowed)
			(copperpour not_allowed)
			(footprints allowed)
		)
		(placement
			(enabled no)
			(sheetname "")
		)
		(fill
			(thermal_gap 0.5)
			(thermal_bridge_width 0.5)
			(island_removal_mode 0)
		)
		(polygon
			(pts
				(xy 122.919998 -136.774682) (xy 122.919998 -138.578082) (xy 123.478798 -138.578082) (xy 123.478798 -136.774682)
			)
		)
	)
	(zone
		(layer "In1.Cu")
		(hatch none 0.5)
		(connect_pads
			(clearance 0)
		)
		(min_thickness 0.25)
		(keepout
			(tracks not_allowed)
			(vias allowed)
			(pads allowed)
			(copperpour not_allowed)
			(footprints allowed)
		)
		(placement
			(enabled no)
			(sheetname "")
		)
		(fill
			(thermal_gap 0.5)
			(thermal_bridge_width 0.5)
			(island_removal_mode 0)
		)
		(polygon
			(pts
				(xy 38.770052 -151.377142) (xy 38.770052 -153.180542) (xy 39.328852 -153.180542) (xy 39.328852 -151.377142)
			)
		)
	)
	(zone
		(layer "In1.Cu")
		(hatch none 0.5)
		(connect_pads
			(clearance 0)
		)
		(min_thickness 0.25)
		(keepout
			(tracks not_allowed)
			(vias allowed)
			(pads allowed)
			(copperpour not_allowed)
			(footprints allowed)
		)
		(placement
			(enabled no)
			(sheetname "")
		)
		(fill
			(thermal_gap 0.5)
			(thermal_bridge_width 0.5)
			(island_removal_mode 0)
		)
		(polygon
			(pts
				(xy 200.37044 -146.375882) (xy 200.37044 -148.179282) (xy 200.92924 -148.179282) (xy 200.92924 -146.375882)
			)
		)
	)
	(zone
		(layer "In1.Cu")
		(hatch none 0.5)
		(connect_pads
			(clearance 0)
		)
		(min_thickness 0.25)
		(keepout
			(tracks not_allowed)
			(vias allowed)
			(pads allowed)
			(copperpour not_allowed)
			(footprints allowed)
		)
		(placement
			(enabled no)
			(sheetname "")
		)
		(fill
			(thermal_gap 0.5)
			(thermal_bridge_width 0.5)
			(island_removal_mode 0)
		)
		(polygon
			(pts
				(xy 63.41999 0.080518) (xy 63.41999 -1.722882) (xy 63.97879 -1.722882) (xy 63.97879 0.080518)
			)
		)
	)
	(zone
		(layer "In1.Cu")
		(hatch none 0.5)
		(connect_pads
			(clearance 0)
		)
		(min_thickness 0.25)
		(keepout
			(tracks not_allowed)
			(vias allowed)
			(pads allowed)
			(copperpour not_allowed)
			(footprints allowed)
		)
		(placement
			(enabled no)
			(sheetname "")
		)
		(fill
			(thermal_gap 0.5)
			(thermal_bridge_width 0.5)
			(island_removal_mode 0)
		)
		(polygon
			(pts
				(xy 143.320008 -9.520682) (xy 143.320008 -11.324082) (xy 143.878808 -11.324082) (xy 143.878808 -9.520682)
			)
		)
	)
	(zone
		(layer "In1.Cu")
		(hatch none 0.5)
		(connect_pads
			(clearance 0)
		)
		(min_thickness 0.25)
		(keepout
			(tracks not_allowed)
			(vias allowed)
			(pads allowed)
			(copperpour not_allowed)
			(footprints allowed)
		)
		(placement
			(enabled no)
			(sheetname "")
		)
		(fill
			(thermal_gap 0.5)
			(thermal_bridge_width 0.5)
			(island_removal_mode 0)
		)
		(polygon
			(pts
				(xy 248.820432 4.680458) (xy 248.820432 2.877058) (xy 249.379232 2.877058) (xy 249.379232 4.680458)
			)
		)
	)
	(zone
		(layer "In1.Cu")
		(hatch none 0.5)
		(connect_pads
			(clearance 0)
		)
		(min_thickness 0.25)
		(keepout
			(tracks not_allowed)
			(vias allowed)
			(pads allowed)
			(copperpour not_allowed)
			(footprints allowed)
		)
		(placement
			(enabled no)
			(sheetname "")
		)
		(fill
			(thermal_gap 0.5)
			(thermal_bridge_width 0.5)
			(island_removal_mode 0)
		)
		(polygon
			(pts
				(xy 100.819966 -151.377142) (xy 100.819966 -153.180542) (xy 101.378766 -153.180542) (xy 101.378766 -151.377142)
			)
		)
	)
	(zone
		(layer "In1.Cu")
		(hatch none 0.5)
		(connect_pads
			(clearance 0)
		)
		(min_thickness 0.25)
		(keepout
			(tracks not_allowed)
			(vias allowed)
			(pads allowed)
			(copperpour not_allowed)
			(footprints allowed)
		)
		(placement
			(enabled no)
			(sheetname "")
		)
		(fill
			(thermal_gap 0.5)
			(thermal_bridge_width 0.5)
			(island_removal_mode 0)
		)
		(polygon
			(pts
				(xy 279.42032 -132.174742) (xy 279.42032 -133.978142) (xy 279.97912 -133.978142) (xy 279.97912 -132.174742)
			)
		)
	)
	(zone
		(layer "In1.Cu")
		(hatch none 0.5)
		(connect_pads
			(clearance 0)
		)
		(min_thickness 0.25)
		(keepout
			(tracks not_allowed)
			(vias allowed)
			(pads allowed)
			(copperpour not_allowed)
			(footprints allowed)
		)
		(placement
			(enabled no)
			(sheetname "")
		)
		(fill
			(thermal_gap 0.5)
			(thermal_bridge_width 0.5)
			(island_removal_mode 0)
		)
		(polygon
			(pts
				(xy 89.76995 -9.520682) (xy 89.76995 -11.324082) (xy 90.32875 -11.324082) (xy 90.32875 -9.520682)
			)
		)
	)
	(zone
		(layer "In1.Cu")
		(hatch none 0.5)
		(connect_pads
			(clearance 0)
		)
		(min_thickness 0.25)
		(keepout
			(tracks not_allowed)
			(vias allowed)
			(pads allowed)
			(copperpour not_allowed)
			(footprints allowed)
		)
		(placement
			(enabled no)
			(sheetname "")
		)
		(fill
			(thermal_gap 0.5)
			(thermal_bridge_width 0.5)
			(island_removal_mode 0)
		)
		(polygon
			(pts
				(xy 233.520488 -132.174742) (xy 233.520488 -133.978142) (xy 234.079288 -133.978142) (xy 234.079288 -132.174742)
			)
		)
	)
	(zone
		(layer "In1.Cu")
		(hatch none 0.5)
		(connect_pads
			(clearance 0)
		)
		(min_thickness 0.25)
		(keepout
			(tracks not_allowed)
			(vias allowed)
			(pads allowed)
			(copperpour not_allowed)
			(footprints allowed)
		)
		(placement
			(enabled no)
			(sheetname "")
		)
		(fill
			(thermal_gap 0.5)
			(thermal_bridge_width 0.5)
			(island_removal_mode 0)
		)
		(polygon
			(pts
				(xy 221.620588 -136.774682) (xy 221.620588 -138.578082) (xy 222.179388 -138.578082) (xy 222.179388 -136.774682)
			)
		)
	)
	(zone
		(layer "In1.Cu")
		(hatch none 0.5)
		(connect_pads
			(clearance 0)
		)
		(min_thickness 0.25)
		(keepout
			(tracks not_allowed)
			(vias allowed)
			(pads allowed)
			(copperpour not_allowed)
			(footprints allowed)
		)
		(placement
			(enabled no)
			(sheetname "")
		)
		(fill
			(thermal_gap 0.5)
			(thermal_bridge_width 0.5)
			(island_removal_mode 0)
		)
		(polygon
			(pts
				(xy 238.620554 -136.774682) (xy 238.620554 -138.578082) (xy 239.179354 -138.578082) (xy 239.179354 -136.774682)
			)
		)
	)
	(zone
		(layer "In1.Cu")
		(hatch none 0.5)
		(connect_pads
			(clearance 0)
		)
		(min_thickness 0.25)
		(keepout
			(tracks not_allowed)
			(vias allowed)
			(pads allowed)
			(copperpour not_allowed)
			(footprints allowed)
		)
		(placement
			(enabled no)
			(sheetname "")
		)
		(fill
			(thermal_gap 0.5)
			(thermal_bridge_width 0.5)
			(island_removal_mode 0)
		)
		(polygon
			(pts
				(xy 73.620122 -9.520682) (xy 73.620122 -11.324082) (xy 74.178922 -11.324082) (xy 74.178922 -9.520682)
			)
		)
	)
	(zone
		(layer "In1.Cu")
		(hatch none 0.5)
		(connect_pads
			(clearance 0)
		)
		(min_thickness 0.25)
		(keepout
			(tracks not_allowed)
			(vias allowed)
			(pads allowed)
			(copperpour not_allowed)
			(footprints allowed)
		)
		(placement
			(enabled no)
			(sheetname "")
		)
		(fill
			(thermal_gap 0.5)
			(thermal_bridge_width 0.5)
			(island_removal_mode 0)
		)
		(polygon
			(pts
				(xy 208.020412 -9.520682) (xy 208.020412 -11.324082) (xy 208.579212 -11.324082) (xy 208.579212 -9.520682)
			)
		)
	)
	(zone
		(layer "In1.Cu")
		(hatch none 0.5)
		(connect_pads
			(clearance 0)
		)
		(min_thickness 0.25)
		(keepout
			(tracks not_allowed)
			(vias allowed)
			(pads allowed)
			(copperpour not_allowed)
			(footprints allowed)
		)
		(placement
			(enabled no)
			(sheetname "")
		)
		(fill
			(thermal_gap 0.5)
			(thermal_bridge_width 0.5)
			(island_removal_mode 0)
		)
		(polygon
			(pts
				(xy 131.420108 -151.377142) (xy 131.420108 -153.180542) (xy 131.978908 -153.180542) (xy 131.978908 -151.377142)
			)
		)
	)
	(zone
		(layer "In1.Cu")
		(hatch none 0.5)
		(connect_pads
			(clearance 0)
		)
		(min_thickness 0.25)
		(keepout
			(tracks not_allowed)
			(vias allowed)
			(pads allowed)
			(copperpour not_allowed)
			(footprints allowed)
		)
		(placement
			(enabled no)
			(sheetname "")
		)
		(fill
			(thermal_gap 0.5)
			(thermal_bridge_width 0.5)
			(island_removal_mode 0)
		)
		(polygon
			(pts
				(xy 61.719968 -155.977082) (xy 61.719968 -157.780482) (xy 62.278768 -157.780482) (xy 62.278768 -155.977082)
			)
		)
	)
	(zone
		(layer "In1.Cu")
		(hatch none 0.5)
		(connect_pads
			(clearance 0)
		)
		(min_thickness 0.25)
		(keepout
			(tracks not_allowed)
			(vias allowed)
			(pads allowed)
			(copperpour not_allowed)
			(footprints allowed)
		)
		(placement
			(enabled no)
			(sheetname "")
		)
		(fill
			(thermal_gap 0.5)
			(thermal_bridge_width 0.5)
			(island_removal_mode 0)
		)
		(polygon
			(pts
				(xy 214.8205 -132.174742) (xy 214.8205 -133.978142) (xy 215.3793 -133.978142) (xy 215.3793 -132.174742)
			)
		)
	)
	(zone
		(layer "In1.Cu")
		(hatch none 0.5)
		(connect_pads
			(clearance 0)
		)
		(min_thickness 0.25)
		(keepout
			(tracks not_allowed)
			(vias allowed)
			(pads allowed)
			(copperpour not_allowed)
			(footprints allowed)
		)
		(placement
			(enabled no)
			(sheetname "")
		)
		(fill
			(thermal_gap 0.5)
			(thermal_bridge_width 0.5)
			(island_removal_mode 0)
		)
		(polygon
			(pts
				(xy 234.370372 -155.977082) (xy 234.370372 -157.780482) (xy 234.929172 -157.780482) (xy 234.929172 -155.977082)
			)
		)
	)
	(zone
		(layer "In1.Cu")
		(hatch none 0.5)
		(connect_pads
			(clearance 0)
		)
		(min_thickness 0.25)
		(keepout
			(tracks not_allowed)
			(vias allowed)
			(pads allowed)
			(copperpour not_allowed)
			(footprints allowed)
		)
		(placement
			(enabled no)
			(sheetname "")
		)
		(fill
			(thermal_gap 0.5)
			(thermal_bridge_width 0.5)
			(island_removal_mode 0)
		)
		(polygon
			(pts
				(xy 429.020986 -7.192772) (xy 430.329086 -7.192772) (xy 430.329086 -8.386572) (xy 429.020986 -8.386572)
			)
		)
	)
	(zone
		(layer "In1.Cu")
		(hatch none 0.5)
		(connect_pads
			(clearance 0)
		)
		(min_thickness 0.25)
		(keepout
			(tracks not_allowed)
			(vias allowed)
			(pads allowed)
			(copperpour not_allowed)
			(footprints allowed)
		)
		(placement
			(enabled no)
			(sheetname "")
		)
		(fill
			(thermal_gap 0.5)
			(thermal_bridge_width 0.5)
			(island_removal_mode 0)
		)
		(polygon
			(pts
				(xy 71.9201 -141.775942) (xy 71.9201 -143.579342) (xy 72.4789 -143.579342) (xy 72.4789 -141.775942)
			)
		)
	)
	(zone
		(layer "In1.Cu")
		(hatch none 0.5)
		(connect_pads
			(clearance 0)
		)
		(min_thickness 0.25)
		(keepout
			(tracks not_allowed)
			(vias allowed)
			(pads allowed)
			(copperpour not_allowed)
			(footprints allowed)
		)
		(placement
			(enabled no)
			(sheetname "")
		)
		(fill
			(thermal_gap 0.5)
			(thermal_bridge_width 0.5)
			(island_removal_mode 0)
		)
		(polygon
			(pts
				(xy 120.370092 4.680458) (xy 120.370092 2.877058) (xy 120.928892 2.877058) (xy 120.928892 4.680458)
			)
		)
	)
	(zone
		(layer "In1.Cu")
		(hatch none 0.5)
		(connect_pads
			(clearance 0)
		)
		(min_thickness 0.25)
		(keepout
			(tracks not_allowed)
			(vias allowed)
			(pads allowed)
			(copperpour not_allowed)
			(footprints allowed)
		)
		(placement
			(enabled no)
			(sheetname "")
		)
		(fill
			(thermal_gap 0.5)
			(thermal_bridge_width 0.5)
			(island_removal_mode 0)
		)
		(polygon
			(pts
				(xy 257.320542 -19.121882) (xy 257.320542 -20.925282) (xy 257.879342 -20.925282) (xy 257.879342 -19.121882)
			)
		)
	)
	(zone
		(layer "In1.Cu")
		(hatch none 0.5)
		(connect_pads
			(clearance 0)
		)
		(min_thickness 0.25)
		(keepout
			(tracks not_allowed)
			(vias allowed)
			(pads allowed)
			(copperpour not_allowed)
			(footprints allowed)
		)
		(placement
			(enabled no)
			(sheetname "")
		)
		(fill
			(thermal_gap 0.5)
			(thermal_bridge_width 0.5)
			(island_removal_mode 0)
		)
		(polygon
			(pts
				(xy 35.370008 -141.775942) (xy 35.370008 -143.579342) (xy 35.928808 -143.579342) (xy 35.928808 -141.775942)
			)
		)
	)
	(zone
		(layer "In1.Cu")
		(hatch none 0.5)
		(connect_pads
			(clearance 0)
		)
		(min_thickness 0.25)
		(keepout
			(tracks not_allowed)
			(vias allowed)
			(pads allowed)
			(copperpour not_allowed)
			(footprints allowed)
		)
		(placement
			(enabled no)
			(sheetname "")
		)
		(fill
			(thermal_gap 0.5)
			(thermal_bridge_width 0.5)
			(island_removal_mode 0)
		)
		(polygon
			(pts
				(xy 88.070182 -136.774682) (xy 88.070182 -138.578082) (xy 88.628982 -138.578082) (xy 88.628982 -136.774682)
			)
		)
	)
	(zone
		(layer "In1.Cu")
		(hatch none 0.5)
		(connect_pads
			(clearance 0)
		)
		(min_thickness 0.25)
		(keepout
			(tracks not_allowed)
			(vias allowed)
			(pads allowed)
			(copperpour not_allowed)
			(footprints allowed)
		)
		(placement
			(enabled no)
			(sheetname "")
		)
		(fill
			(thermal_gap 0.5)
			(thermal_bridge_width 0.5)
			(island_removal_mode 0)
		)
		(polygon
			(pts
				(xy 243.720366 -136.774682) (xy 243.720366 -138.578082) (xy 244.279166 -138.578082) (xy 244.279166 -136.774682)
			)
		)
	)
	(zone
		(layer "In1.Cu")
		(hatch none 0.5)
		(connect_pads
			(clearance 0)
		)
		(min_thickness 0.25)
		(keepout
			(tracks not_allowed)
			(vias allowed)
			(pads allowed)
			(copperpour not_allowed)
			(footprints allowed)
		)
		(placement
			(enabled no)
			(sheetname "")
		)
		(fill
			(thermal_gap 0.5)
			(thermal_bridge_width 0.5)
			(island_removal_mode 0)
		)
		(polygon
			(pts
				(xy 306.620418 -146.375882) (xy 306.620418 -148.179282) (xy 307.179218 -148.179282) (xy 307.179218 -146.375882)
			)
		)
	)
	(zone
		(layer "In1.Cu")
		(hatch none 0.5)
		(connect_pads
			(clearance 0)
		)
		(min_thickness 0.25)
		(keepout
			(tracks not_allowed)
			(vias allowed)
			(pads allowed)
			(copperpour not_allowed)
			(footprints allowed)
		)
		(placement
			(enabled no)
			(sheetname "")
		)
		(fill
			(thermal_gap 0.5)
			(thermal_bridge_width 0.5)
			(island_removal_mode 0)
		)
		(polygon
			(pts
				(xy 273.47037 -19.121882) (xy 273.47037 -20.925282) (xy 274.02917 -20.925282) (xy 274.02917 -19.121882)
			)
		)
	)
	(zone
		(layer "In1.Cu")
		(hatch none 0.5)
		(connect_pads
			(clearance 0)
		)
		(min_thickness 0.25)
		(keepout
			(tracks not_allowed)
			(vias allowed)
			(pads allowed)
			(copperpour not_allowed)
			(footprints allowed)
		)
		(placement
			(enabled no)
			(sheetname "")
		)
		(fill
			(thermal_gap 0.5)
			(thermal_bridge_width 0.5)
			(island_removal_mode 0)
		)
		(polygon
			(pts
				(xy 51.52009 -4.920742) (xy 51.52009 -6.724142) (xy 52.07889 -6.724142) (xy 52.07889 -4.920742)
			)
		)
	)
	(zone
		(layer "In1.Cu")
		(hatch none 0.5)
		(connect_pads
			(clearance 0)
		)
		(min_thickness 0.25)
		(keepout
			(tracks not_allowed)
			(vias allowed)
			(pads allowed)
			(copperpour not_allowed)
			(footprints allowed)
		)
		(placement
			(enabled no)
			(sheetname "")
		)
		(fill
			(thermal_gap 0.5)
			(thermal_bridge_width 0.5)
			(island_removal_mode 0)
		)
		(polygon
			(pts
				(xy 46.420024 -151.377142) (xy 46.420024 -153.180542) (xy 46.978824 -153.180542) (xy 46.978824 -151.377142)
			)
		)
	)
	(zone
		(layer "In1.Cu")
		(hatch none 0.5)
		(connect_pads
			(clearance 0)
		)
		(min_thickness 0.25)
		(keepout
			(tracks not_allowed)
			(vias allowed)
			(pads allowed)
			(copperpour not_allowed)
			(footprints allowed)
		)
		(placement
			(enabled no)
			(sheetname "")
		)
		(fill
			(thermal_gap 0.5)
			(thermal_bridge_width 0.5)
			(island_removal_mode 0)
		)
		(polygon
			(pts
				(xy 225.870516 -132.174742) (xy 225.870516 -133.978142) (xy 226.429316 -133.978142) (xy 226.429316 -132.174742)
			)
		)
	)
	(zone
		(layer "In1.Cu")
		(hatch none 0.5)
		(connect_pads
			(clearance 0)
		)
		(min_thickness 0.25)
		(keepout
			(tracks not_allowed)
			(vias allowed)
			(pads allowed)
			(copperpour not_allowed)
			(footprints allowed)
		)
		(placement
			(enabled no)
			(sheetname "")
		)
		(fill
			(thermal_gap 0.5)
			(thermal_bridge_width 0.5)
			(island_removal_mode 0)
		)
		(polygon
			(pts
				(xy 256.470404 -136.774682) (xy 256.470404 -138.578082) (xy 257.029204 -138.578082) (xy 257.029204 -136.774682)
			)
		)
	)
	(zone
		(layer "In1.Cu")
		(hatch none 0.5)
		(connect_pads
			(clearance 0)
		)
		(min_thickness 0.25)
		(keepout
			(tracks not_allowed)
			(vias allowed)
			(pads allowed)
			(copperpour not_allowed)
			(footprints allowed)
		)
		(placement
			(enabled no)
			(sheetname "")
		)
		(fill
			(thermal_gap 0.5)
			(thermal_bridge_width 0.5)
			(island_removal_mode 0)
		)
		(polygon
			(pts
				(xy 106.77017 4.680458) (xy 106.77017 2.877058) (xy 107.32897 2.877058) (xy 107.32897 4.680458)
			)
		)
	)
	(zone
		(layer "In1.Cu")
		(hatch none 0.5)
		(connect_pads
			(clearance 0)
		)
		(min_thickness 0.25)
		(keepout
			(tracks not_allowed)
			(vias allowed)
			(pads allowed)
			(copperpour not_allowed)
			(footprints allowed)
		)
		(placement
			(enabled no)
			(sheetname "")
		)
		(fill
			(thermal_gap 0.5)
			(thermal_bridge_width 0.5)
			(island_removal_mode 0)
		)
		(polygon
			(pts
				(xy 13.6398 -28.321) (xy 15.0368 -28.321) (xy 15.0368 -28.829) (xy 13.6398 -28.829)
			)
		)
	)
	(zone
		(layer "In1.Cu")
		(hatch none 0.5)
		(connect_pads
			(clearance 0)
		)
		(min_thickness 0.25)
		(keepout
			(tracks not_allowed)
			(vias allowed)
			(pads allowed)
			(copperpour not_allowed)
			(footprints allowed)
		)
		(placement
			(enabled no)
			(sheetname "")
		)
		(fill
			(thermal_gap 0.5)
			(thermal_bridge_width 0.5)
			(island_removal_mode 0)
		)
		(polygon
			(pts
				(xy 303.220374 -136.774682) (xy 303.220374 -138.578082) (xy 303.779174 -138.578082) (xy 303.779174 -136.774682)
			)
		)
	)
	(zone
		(layer "In1.Cu")
		(hatch none 0.5)
		(connect_pads
			(clearance 0)
		)
		(min_thickness 0.25)
		(keepout
			(tracks not_allowed)
			(vias allowed)
			(pads allowed)
			(copperpour not_allowed)
			(footprints allowed)
		)
		(placement
			(enabled no)
			(sheetname "")
		)
		(fill
			(thermal_gap 0.5)
			(thermal_bridge_width 0.5)
			(island_removal_mode 0)
		)
		(polygon
			(pts
				(xy 37.920168 -136.774682) (xy 37.920168 -138.578082) (xy 38.478968 -138.578082) (xy 38.478968 -136.774682)
			)
		)
	)
	(zone
		(layer "In1.Cu")
		(hatch none 0.5)
		(connect_pads
			(clearance 0)
		)
		(min_thickness 0.25)
		(keepout
			(tracks not_allowed)
			(vias allowed)
			(pads allowed)
			(copperpour not_allowed)
			(footprints allowed)
		)
		(placement
			(enabled no)
			(sheetname "")
		)
		(fill
			(thermal_gap 0.5)
			(thermal_bridge_width 0.5)
			(island_removal_mode 0)
		)
		(polygon
			(pts
				(xy 401.817586 -3.789172) (xy 403.125686 -3.789172) (xy 403.125686 -4.982972) (xy 401.817586 -4.982972)
			)
		)
	)
	(zone
		(layer "In1.Cu")
		(hatch none 0.5)
		(connect_pads
			(clearance 0)
		)
		(min_thickness 0.25)
		(keepout
			(tracks not_allowed)
			(vias allowed)
			(pads allowed)
			(copperpour not_allowed)
			(footprints allowed)
		)
		(placement
			(enabled no)
			(sheetname "")
		)
		(fill
			(thermal_gap 0.5)
			(thermal_bridge_width 0.5)
			(island_removal_mode 0)
		)
		(polygon
			(pts
				(xy 127.169926 -14.521942) (xy 127.169926 -16.325342) (xy 127.728726 -16.325342) (xy 127.728726 -14.521942)
			)
		)
	)
	(zone
		(layer "In1.Cu")
		(hatch none 0.5)
		(connect_pads
			(clearance 0)
		)
		(min_thickness 0.25)
		(keepout
			(tracks not_allowed)
			(vias allowed)
			(pads allowed)
			(copperpour not_allowed)
			(footprints allowed)
		)
		(placement
			(enabled no)
			(sheetname "")
		)
		(fill
			(thermal_gap 0.5)
			(thermal_bridge_width 0.5)
			(island_removal_mode 0)
		)
		(polygon
			(pts
				(xy 224.170494 -151.377142) (xy 224.170494 -153.180542) (xy 224.729294 -153.180542) (xy 224.729294 -151.377142)
			)
		)
	)
	(zone
		(layer "In1.Cu")
		(hatch none 0.5)
		(connect_pads
			(clearance 0)
		)
		(min_thickness 0.25)
		(keepout
			(tracks not_allowed)
			(vias allowed)
			(pads allowed)
			(copperpour not_allowed)
			(footprints allowed)
		)
		(placement
			(enabled no)
			(sheetname "")
		)
		(fill
			(thermal_gap 0.5)
			(thermal_bridge_width 0.5)
			(island_removal_mode 0)
		)
		(polygon
			(pts
				(xy 251.370592 4.680458) (xy 251.370592 2.877058) (xy 251.929392 2.877058) (xy 251.929392 4.680458)
			)
		)
	)
	(zone
		(layer "In1.Cu")
		(hatch none 0.5)
		(connect_pads
			(clearance 0)
		)
		(min_thickness 0.25)
		(keepout
			(tracks not_allowed)
			(vias allowed)
			(pads allowed)
			(copperpour not_allowed)
			(footprints allowed)
		)
		(placement
			(enabled no)
			(sheetname "")
		)
		(fill
			(thermal_gap 0.5)
			(thermal_bridge_width 0.5)
			(island_removal_mode 0)
		)
		(polygon
			(pts
				(xy 77.87005 -151.377142) (xy 77.87005 -153.180542) (xy 78.42885 -153.180542) (xy 78.42885 -151.377142)
			)
		)
	)
	(zone
		(layer "In1.Cu")
		(hatch none 0.5)
		(connect_pads
			(clearance 0)
		)
		(min_thickness 0.25)
		(keepout
			(tracks not_allowed)
			(vias allowed)
			(pads allowed)
			(copperpour not_allowed)
			(footprints allowed)
		)
		(placement
			(enabled no)
			(sheetname "")
		)
		(fill
			(thermal_gap 0.5)
			(thermal_bridge_width 0.5)
			(island_removal_mode 0)
		)
		(polygon
			(pts
				(xy 256.470404 -19.121882) (xy 256.470404 -20.925282) (xy 257.029204 -20.925282) (xy 257.029204 -19.121882)
			)
		)
	)
	(zone
		(layer "In1.Cu")
		(hatch none 0.5)
		(connect_pads
			(clearance 0)
		)
		(min_thickness 0.25)
		(keepout
			(tracks not_allowed)
			(vias allowed)
			(pads allowed)
			(copperpour not_allowed)
			(footprints allowed)
		)
		(placement
			(enabled no)
			(sheetname "")
		)
		(fill
			(thermal_gap 0.5)
			(thermal_bridge_width 0.5)
			(island_removal_mode 0)
		)
		(polygon
			(pts
				(xy 305.770534 -141.775942) (xy 305.770534 -143.579342) (xy 306.329334 -143.579342) (xy 306.329334 -141.775942)
			)
		)
	)
	(zone
		(layer "In1.Cu")
		(hatch none 0.5)
		(connect_pads
			(clearance 0)
		)
		(min_thickness 0.25)
		(keepout
			(tracks not_allowed)
			(vias allowed)
			(pads allowed)
			(copperpour not_allowed)
			(footprints allowed)
		)
		(placement
			(enabled no)
			(sheetname "")
		)
		(fill
			(thermal_gap 0.5)
			(thermal_bridge_width 0.5)
			(island_removal_mode 0)
		)
		(polygon
			(pts
				(xy 77.02042 -146.375882) (xy 77.02042 -148.179282) (xy 77.57922 -148.179282) (xy 77.57922 -146.375882)
			)
		)
	)
	(zone
		(layer "In1.Cu")
		(hatch none 0.5)
		(connect_pads
			(clearance 0)
		)
		(min_thickness 0.25)
		(keepout
			(tracks not_allowed)
			(vias allowed)
			(pads allowed)
			(copperpour not_allowed)
			(footprints allowed)
		)
		(placement
			(enabled no)
			(sheetname "")
		)
		(fill
			(thermal_gap 0.5)
			(thermal_bridge_width 0.5)
			(island_removal_mode 0)
		)
		(polygon
			(pts
				(xy 56.620156 -136.774682) (xy 56.620156 -138.578082) (xy 57.178956 -138.578082) (xy 57.178956 -136.774682)
			)
		)
	)
	(zone
		(layer "In1.Cu")
		(hatch none 0.5)
		(connect_pads
			(clearance 0)
		)
		(min_thickness 0.25)
		(keepout
			(tracks not_allowed)
			(vias allowed)
			(pads allowed)
			(copperpour not_allowed)
			(footprints allowed)
		)
		(placement
			(enabled no)
			(sheetname "")
		)
		(fill
			(thermal_gap 0.5)
			(thermal_bridge_width 0.5)
			(island_removal_mode 0)
		)
		(polygon
			(pts
				(xy 264.970514 -146.375882) (xy 264.970514 -148.179282) (xy 265.529314 -148.179282) (xy 265.529314 -146.375882)
			)
		)
	)
	(zone
		(layer "In1.Cu")
		(hatch none 0.5)
		(connect_pads
			(clearance 0)
		)
		(min_thickness 0.25)
		(keepout
			(tracks not_allowed)
			(vias allowed)
			(pads allowed)
			(copperpour not_allowed)
			(footprints allowed)
		)
		(placement
			(enabled no)
			(sheetname "")
		)
		(fill
			(thermal_gap 0.5)
			(thermal_bridge_width 0.5)
			(island_removal_mode 0)
		)
		(polygon
			(pts
				(xy 281.97048 -146.375882) (xy 281.97048 -148.179282) (xy 282.52928 -148.179282) (xy 282.52928 -146.375882)
			)
		)
	)
	(zone
		(layer "In1.Cu")
		(hatch none 0.5)
		(connect_pads
			(clearance 0)
		)
		(min_thickness 0.25)
		(keepout
			(tracks not_allowed)
			(vias allowed)
			(pads allowed)
			(copperpour not_allowed)
			(footprints allowed)
		)
		(placement
			(enabled no)
			(sheetname "")
		)
		(fill
			(thermal_gap 0.5)
			(thermal_bridge_width 0.5)
			(island_removal_mode 0)
		)
		(polygon
			(pts
				(xy 102.519988 -14.521942) (xy 102.519988 -16.325342) (xy 103.078788 -16.325342) (xy 103.078788 -14.521942)
			)
		)
	)
	(zone
		(layer "In1.Cu")
		(hatch none 0.5)
		(connect_pads
			(clearance 0)
		)
		(min_thickness 0.25)
		(keepout
			(tracks not_allowed)
			(vias allowed)
			(pads allowed)
			(copperpour not_allowed)
			(footprints allowed)
		)
		(placement
			(enabled no)
			(sheetname "")
		)
		(fill
			(thermal_gap 0.5)
			(thermal_bridge_width 0.5)
			(island_removal_mode 0)
		)
		(polygon
			(pts
				(xy 57.47004 -132.174742) (xy 57.47004 -133.978142) (xy 58.02884 -133.978142) (xy 58.02884 -132.174742)
			)
		)
	)
	(zone
		(layer "In1.Cu")
		(hatch none 0.5)
		(connect_pads
			(clearance 0)
		)
		(min_thickness 0.25)
		(keepout
			(tracks not_allowed)
			(vias allowed)
			(pads allowed)
			(copperpour not_allowed)
			(footprints allowed)
		)
		(placement
			(enabled no)
			(sheetname "")
		)
		(fill
			(thermal_gap 0.5)
			(thermal_bridge_width 0.5)
			(island_removal_mode 0)
		)
		(polygon
			(pts
				(xy 72.769984 -132.174742) (xy 72.769984 -133.978142) (xy 73.328784 -133.978142) (xy 73.328784 -132.174742)
			)
		)
	)
	(zone
		(layer "In1.Cu")
		(hatch none 0.5)
		(connect_pads
			(clearance 0)
		)
		(min_thickness 0.25)
		(keepout
			(tracks not_allowed)
			(vias allowed)
			(pads allowed)
			(copperpour not_allowed)
			(footprints allowed)
		)
		(placement
			(enabled no)
			(sheetname "")
		)
		(fill
			(thermal_gap 0.5)
			(thermal_bridge_width 0.5)
			(island_removal_mode 0)
		)
		(polygon
			(pts
				(xy 256.470404 0.080518) (xy 256.470404 -1.722882) (xy 257.029204 -1.722882) (xy 257.029204 0.080518)
			)
		)
	)
	(zone
		(layer "In1.Cu")
		(hatch none 0.5)
		(connect_pads
			(clearance 0)
		)
		(min_thickness 0.25)
		(keepout
			(tracks not_allowed)
			(vias allowed)
			(pads allowed)
			(copperpour not_allowed)
			(footprints allowed)
		)
		(placement
			(enabled no)
			(sheetname "")
		)
		(fill
			(thermal_gap 0.5)
			(thermal_bridge_width 0.5)
			(island_removal_mode 0)
		)
		(polygon
			(pts
				(xy 303.220374 -9.520682) (xy 303.220374 -11.324082) (xy 303.779174 -11.324082) (xy 303.779174 -9.520682)
			)
		)
	)
	(zone
		(layer "In1.Cu")
		(hatch none 0.5)
		(connect_pads
			(clearance 0)
		)
		(min_thickness 0.25)
		(keepout
			(tracks not_allowed)
			(vias allowed)
			(pads allowed)
			(copperpour not_allowed)
			(footprints allowed)
		)
		(placement
			(enabled no)
			(sheetname "")
		)
		(fill
			(thermal_gap 0.5)
			(thermal_bridge_width 0.5)
			(island_removal_mode 0)
		)
		(polygon
			(pts
				(xy 378.000768 -33.4645) (xy 380.286768 -33.4645) (xy 380.286768 -33.9725) (xy 378.000768 -33.9725)
			)
		)
	)
	(zone
		(layer "In1.Cu")
		(hatch none 0.5)
		(connect_pads
			(clearance 0)
		)
		(min_thickness 0.25)
		(keepout
			(tracks not_allowed)
			(vias allowed)
			(pads allowed)
			(copperpour not_allowed)
			(footprints allowed)
		)
		(placement
			(enabled no)
			(sheetname "")
		)
		(fill
			(thermal_gap 0.5)
			(thermal_bridge_width 0.5)
			(island_removal_mode 0)
		)
		(polygon
			(pts
				(xy 69.36994 -136.774682) (xy 69.36994 -138.578082) (xy 69.92874 -138.578082) (xy 69.92874 -136.774682)
			)
		)
	)
	(zone
		(layer "In1.Cu")
		(hatch none 0.5)
		(connect_pads
			(clearance 0)
		)
		(min_thickness 0.25)
		(keepout
			(tracks not_allowed)
			(vias allowed)
			(pads allowed)
			(copperpour not_allowed)
			(footprints allowed)
		)
		(placement
			(enabled no)
			(sheetname "")
		)
		(fill
			(thermal_gap 0.5)
			(thermal_bridge_width 0.5)
			(island_removal_mode 0)
		)
		(polygon
			(pts
				(xy 266.670536 -19.121882) (xy 266.670536 -20.925282) (xy 267.229336 -20.925282) (xy 267.229336 -19.121882)
			)
		)
	)
	(zone
		(layer "In1.Cu")
		(hatch none 0.5)
		(connect_pads
			(clearance 0)
		)
		(min_thickness 0.25)
		(keepout
			(tracks not_allowed)
			(vias allowed)
			(pads allowed)
			(copperpour not_allowed)
			(footprints allowed)
		)
		(placement
			(enabled no)
			(sheetname "")
		)
		(fill
			(thermal_gap 0.5)
			(thermal_bridge_width 0.5)
			(island_removal_mode 0)
		)
		(polygon
			(pts
				(xy 267.52042 -146.375882) (xy 267.52042 -148.179282) (xy 268.07922 -148.179282) (xy 268.07922 -146.375882)
			)
		)
	)
	(zone
		(layer "In1.Cu")
		(hatch none 0.5)
		(connect_pads
			(clearance 0)
		)
		(min_thickness 0.25)
		(keepout
			(tracks not_allowed)
			(vias allowed)
			(pads allowed)
			(copperpour not_allowed)
			(footprints allowed)
		)
		(placement
			(enabled no)
			(sheetname "")
		)
		(fill
			(thermal_gap 0.5)
			(thermal_bridge_width 0.5)
			(island_removal_mode 0)
		)
		(polygon
			(pts
				(xy 208.020412 0.080518) (xy 208.020412 -1.722882) (xy 208.579212 -1.722882) (xy 208.579212 0.080518)
			)
		)
	)
	(zone
		(layer "In1.Cu")
		(hatch none 0.5)
		(connect_pads
			(clearance 0)
		)
		(min_thickness 0.25)
		(keepout
			(tracks not_allowed)
			(vias allowed)
			(pads allowed)
			(copperpour not_allowed)
			(footprints allowed)
		)
		(placement
			(enabled no)
			(sheetname "")
		)
		(fill
			(thermal_gap 0.5)
			(thermal_bridge_width 0.5)
			(island_removal_mode 0)
		)
		(polygon
			(pts
				(xy 139.07008 -132.174742) (xy 139.07008 -133.978142) (xy 139.62888 -133.978142) (xy 139.62888 -132.174742)
			)
		)
	)
	(zone
		(layer "In1.Cu")
		(hatch none 0.5)
		(connect_pads
			(clearance 0)
		)
		(min_thickness 0.25)
		(keepout
			(tracks not_allowed)
			(vias allowed)
			(pads allowed)
			(copperpour not_allowed)
			(footprints allowed)
		)
		(placement
			(enabled no)
			(sheetname "")
		)
		(fill
			(thermal_gap 0.5)
			(thermal_bridge_width 0.5)
			(island_removal_mode 0)
		)
		(polygon
			(pts
				(xy 310.870346 4.680458) (xy 310.870346 2.877058) (xy 311.429146 2.877058) (xy 311.429146 4.680458)
			)
		)
	)
	(zone
		(layer "In1.Cu")
		(hatch none 0.5)
		(connect_pads
			(clearance 0)
		)
		(min_thickness 0.25)
		(keepout
			(tracks not_allowed)
			(vias allowed)
			(pads allowed)
			(copperpour not_allowed)
			(footprints allowed)
		)
		(placement
			(enabled no)
			(sheetname "")
		)
		(fill
			(thermal_gap 0.5)
			(thermal_bridge_width 0.5)
			(island_removal_mode 0)
		)
		(polygon
			(pts
				(xy 268.370558 -141.775942) (xy 268.370558 -143.579342) (xy 268.929358 -143.579342) (xy 268.929358 -141.775942)
			)
		)
	)
	(zone
		(layer "In1.Cu")
		(hatch none 0.5)
		(connect_pads
			(clearance 0)
		)
		(min_thickness 0.25)
		(keepout
			(tracks not_allowed)
			(vias allowed)
			(pads allowed)
			(copperpour not_allowed)
			(footprints allowed)
		)
		(placement
			(enabled no)
			(sheetname "")
		)
		(fill
			(thermal_gap 0.5)
			(thermal_bridge_width 0.5)
			(island_removal_mode 0)
		)
		(polygon
			(pts
				(xy 289.620452 -146.375882) (xy 289.620452 -148.179282) (xy 290.179252 -148.179282) (xy 290.179252 -146.375882)
			)
		)
	)
	(zone
		(layer "In1.Cu")
		(hatch none 0.5)
		(connect_pads
			(clearance 0)
		)
		(min_thickness 0.25)
		(keepout
			(tracks not_allowed)
			(vias allowed)
			(pads allowed)
			(copperpour not_allowed)
			(footprints allowed)
		)
		(placement
			(enabled no)
			(sheetname "")
		)
		(fill
			(thermal_gap 0.5)
			(thermal_bridge_width 0.5)
			(island_removal_mode 0)
		)
		(polygon
			(pts
				(xy 200.37044 -141.775942) (xy 200.37044 -143.579342) (xy 200.92924 -143.579342) (xy 200.92924 -141.775942)
			)
		)
	)
	(zone
		(layer "In1.Cu")
		(hatch none 0.5)
		(connect_pads
			(clearance 0)
		)
		(min_thickness 0.25)
		(keepout
			(tracks not_allowed)
			(vias allowed)
			(pads allowed)
			(copperpour not_allowed)
			(footprints allowed)
		)
		(placement
			(enabled no)
			(sheetname "")
		)
		(fill
			(thermal_gap 0.5)
			(thermal_bridge_width 0.5)
			(island_removal_mode 0)
		)
		(polygon
			(pts
				(xy 146.720052 -9.520682) (xy 146.720052 -11.324082) (xy 147.278852 -11.324082) (xy 147.278852 -9.520682)
			)
		)
	)
	(zone
		(layer "In1.Cu")
		(hatch none 0.5)
		(connect_pads
			(clearance 0)
		)
		(min_thickness 0.25)
		(keepout
			(tracks not_allowed)
			(vias allowed)
			(pads allowed)
			(copperpour not_allowed)
			(footprints allowed)
		)
		(placement
			(enabled no)
			(sheetname "")
		)
		(fill
			(thermal_gap 0.5)
			(thermal_bridge_width 0.5)
			(island_removal_mode 0)
		)
		(polygon
			(pts
				(xy 236.920532 -14.521942) (xy 236.920532 -16.325342) (xy 237.479332 -16.325342) (xy 237.479332 -14.521942)
			)
		)
	)
	(zone
		(layer "In1.Cu")
		(hatch none 0.5)
		(connect_pads
			(clearance 0)
		)
		(min_thickness 0.25)
		(keepout
			(tracks not_allowed)
			(vias allowed)
			(pads allowed)
			(copperpour not_allowed)
			(footprints allowed)
		)
		(placement
			(enabled no)
			(sheetname "")
		)
		(fill
			(thermal_gap 0.5)
			(thermal_bridge_width 0.5)
			(island_removal_mode 0)
		)
		(polygon
			(pts
				(xy 66.820034 -141.775942) (xy 66.820034 -143.579342) (xy 67.378834 -143.579342) (xy 67.378834 -141.775942)
			)
		)
	)
	(zone
		(layer "In1.Cu")
		(hatch none 0.5)
		(connect_pads
			(clearance 0)
		)
		(min_thickness 0.25)
		(keepout
			(tracks not_allowed)
			(vias allowed)
			(pads allowed)
			(copperpour not_allowed)
			(footprints allowed)
		)
		(placement
			(enabled no)
			(sheetname "")
		)
		(fill
			(thermal_gap 0.5)
			(thermal_bridge_width 0.5)
			(island_removal_mode 0)
		)
		(polygon
			(pts
				(xy 86.37016 -4.920742) (xy 86.37016 -6.724142) (xy 86.92896 -6.724142) (xy 86.92896 -4.920742)
			)
		)
	)
	(zone
		(layer "In1.Cu")
		(hatch none 0.5)
		(connect_pads
			(clearance 0)
		)
		(min_thickness 0.25)
		(keepout
			(tracks not_allowed)
			(vias allowed)
			(pads allowed)
			(copperpour not_allowed)
			(footprints allowed)
		)
		(placement
			(enabled no)
			(sheetname "")
		)
		(fill
			(thermal_gap 0.5)
			(thermal_bridge_width 0.5)
			(island_removal_mode 0)
		)
		(polygon
			(pts
				(xy 224.170494 -132.174742) (xy 224.170494 -133.978142) (xy 224.729294 -133.978142) (xy 224.729294 -132.174742)
			)
		)
	)
	(zone
		(layer "In1.Cu")
		(hatch none 0.5)
		(connect_pads
			(clearance 0)
		)
		(min_thickness 0.25)
		(keepout
			(tracks not_allowed)
			(vias allowed)
			(pads allowed)
			(copperpour not_allowed)
			(footprints allowed)
		)
		(placement
			(enabled no)
			(sheetname "")
		)
		(fill
			(thermal_gap 0.5)
			(thermal_bridge_width 0.5)
			(island_removal_mode 0)
		)
		(polygon
			(pts
				(xy 141.619986 -9.520682) (xy 141.619986 -11.324082) (xy 142.178786 -11.324082) (xy 142.178786 -9.520682)
			)
		)
	)
	(zone
		(net "AGND_PVPP_GHJ")
		(layer "In1.Cu")
		(hatch none 0.5)
		(connect_pads
			(clearance 0.5)
		)
		(min_thickness 0.25)
		(fill yes
			(thermal_gap 0.5)
			(thermal_bridge_width 0.5)
			(island_removal_mode 0)
		)
		(polygon
			(pts
				(xy 177.94732 -6.4008) (xy 175.390556 -6.4008) (xy 174.831756 -6.9596) (xy 173.053756 -6.9596) (xy 172.2374 -7.775956)
				(xy 172.2374 -8.962644) (xy 172.593 -9.318244)
				(arc
					(start 172.593 -10.38479)
					(mid 172.593624 -10.396292)
					(end 172.59554 -10.40765)
				)
				(xy 172.59554 -10.537952) (xy 172.728382 -10.670794) (xy 178.07178 -10.670794) (xy 178.181 -10.561574)
				(xy 178.181 -10.36828) (xy 178.181 -9.800844) (xy 178.435 -9.546844) (xy 178.435 -8.267446) (xy 178.1556 -8.089646)
				(xy 178.1556 -6.60908) (xy 178.1556 -6.533642) (xy 178.1556 -6.529578) (xy 178.027584 -6.401562)
				(xy 177.948082 -6.401562)
			)
		)
	)
	(zone
		(layer "In1.Cu")
		(hatch none 0.5)
		(connect_pads
			(clearance 0)
		)
		(min_thickness 0.25)
		(keepout
			(tracks not_allowed)
			(vias allowed)
			(pads allowed)
			(copperpour not_allowed)
			(footprints allowed)
		)
		(placement
			(enabled no)
			(sheetname "")
		)
		(fill
			(thermal_gap 0.5)
			(thermal_bridge_width 0.5)
			(island_removal_mode 0)
		)
		(polygon
			(pts
				(xy 257.320542 4.680458) (xy 257.320542 2.877058) (xy 257.879342 2.877058) (xy 257.879342 4.680458)
			)
		)
	)
	(zone
		(layer "In1.Cu")
		(hatch none 0.5)
		(connect_pads
			(clearance 0)
		)
		(min_thickness 0.25)
		(keepout
			(tracks not_allowed)
			(vias allowed)
			(pads allowed)
			(copperpour not_allowed)
			(footprints allowed)
		)
		(placement
			(enabled no)
			(sheetname "")
		)
		(fill
			(thermal_gap 0.5)
			(thermal_bridge_width 0.5)
			(island_removal_mode 0)
		)
		(polygon
			(pts
				(xy 210.570572 -9.520682) (xy 210.570572 -11.324082) (xy 211.129372 -11.324082) (xy 211.129372 -9.520682)
			)
		)
	)
	(zone
		(layer "In1.Cu")
		(hatch none 0.5)
		(connect_pads
			(clearance 0)
		)
		(min_thickness 0.25)
		(keepout
			(tracks not_allowed)
			(vias allowed)
			(pads allowed)
			(copperpour not_allowed)
			(footprints allowed)
		)
		(placement
			(enabled no)
			(sheetname "")
		)
		(fill
			(thermal_gap 0.5)
			(thermal_bridge_width 0.5)
			(island_removal_mode 0)
		)
		(polygon
			(pts
				(xy 65.97015 -136.774682) (xy 65.97015 -138.578082) (xy 66.52895 -138.578082) (xy 66.52895 -136.774682)
			)
		)
	)
	(zone
		(layer "In1.Cu")
		(hatch none 0.5)
		(connect_pads
			(clearance 0)
		)
		(min_thickness 0.25)
		(keepout
			(tracks not_allowed)
			(vias allowed)
			(pads allowed)
			(copperpour not_allowed)
			(footprints allowed)
		)
		(placement
			(enabled no)
			(sheetname "")
		)
		(fill
			(thermal_gap 0.5)
			(thermal_bridge_width 0.5)
			(island_removal_mode 0)
		)
		(polygon
			(pts
				(xy 311.720484 -151.377142) (xy 311.720484 -153.180542) (xy 312.279284 -153.180542) (xy 312.279284 -151.377142)
			)
		)
	)
	(zone
		(layer "In1.Cu")
		(hatch none 0.5)
		(connect_pads
			(clearance 0)
		)
		(min_thickness 0.25)
		(keepout
			(tracks not_allowed)
			(vias allowed)
			(pads allowed)
			(copperpour not_allowed)
			(footprints allowed)
		)
		(placement
			(enabled no)
			(sheetname "")
		)
		(fill
			(thermal_gap 0.5)
			(thermal_bridge_width 0.5)
			(island_removal_mode 0)
		)
		(polygon
			(pts
				(xy 237.770416 -151.377142) (xy 237.770416 -153.180542) (xy 238.329216 -153.180542) (xy 238.329216 -151.377142)
			)
		)
	)
	(zone
		(layer "In1.Cu")
		(hatch none 0.5)
		(connect_pads
			(clearance 0)
		)
		(min_thickness 0.25)
		(keepout
			(tracks not_allowed)
			(vias allowed)
			(pads allowed)
			(copperpour not_allowed)
			(footprints allowed)
		)
		(placement
			(enabled no)
			(sheetname "")
		)
		(fill
			(thermal_gap 0.5)
			(thermal_bridge_width 0.5)
			(island_removal_mode 0)
		)
		(polygon
			(pts
				(xy 374.031002 -7.193026) (xy 375.339102 -7.193026) (xy 375.339102 -8.386826) (xy 374.031002 -8.386826)
			)
		)
	)
	(zone
		(layer "In1.Cu")
		(hatch none 0.5)
		(connect_pads
			(clearance 0)
		)
		(min_thickness 0.25)
		(keepout
			(tracks not_allowed)
			(vias allowed)
			(pads allowed)
			(copperpour not_allowed)
			(footprints allowed)
		)
		(placement
			(enabled no)
			(sheetname "")
		)
		(fill
			(thermal_gap 0.5)
			(thermal_bridge_width 0.5)
			(island_removal_mode 0)
		)
		(polygon
			(pts
				(xy 89.76995 0.080518) (xy 89.76995 -1.722882) (xy 90.32875 -1.722882) (xy 90.32875 0.080518)
			)
		)
	)
	(zone
		(layer "In1.Cu")
		(hatch none 0.5)
		(connect_pads
			(clearance 0)
		)
		(min_thickness 0.25)
		(keepout
			(tracks not_allowed)
			(vias allowed)
			(pads allowed)
			(copperpour not_allowed)
			(footprints allowed)
		)
		(placement
			(enabled no)
			(sheetname "")
		)
		(fill
			(thermal_gap 0.5)
			(thermal_bridge_width 0.5)
			(island_removal_mode 0)
		)
		(polygon
			(pts
				(xy 133.970014 -19.121882) (xy 133.970014 -20.925282) (xy 134.528814 -20.925282) (xy 134.528814 -19.121882)
			)
		)
	)
	(zone
		(layer "In1.Cu")
		(hatch none 0.5)
		(connect_pads
			(clearance 0)
		)
		(min_thickness 0.25)
		(keepout
			(tracks not_allowed)
			(vias allowed)
			(pads allowed)
			(copperpour not_allowed)
			(footprints allowed)
		)
		(placement
			(enabled no)
			(sheetname "")
		)
		(fill
			(thermal_gap 0.5)
			(thermal_bridge_width 0.5)
			(island_removal_mode 0)
		)
		(polygon
			(pts
				(xy 377.2662 -28.978352) (xy 379.5522 -28.978352) (xy 379.5522 -29.486352) (xy 377.2662 -29.486352)
			)
		)
	)
	(zone
		(layer "In1.Cu")
		(hatch none 0.5)
		(connect_pads
			(clearance 0)
		)
		(min_thickness 0.25)
		(keepout
			(tracks not_allowed)
			(vias allowed)
			(pads allowed)
			(copperpour not_allowed)
			(footprints allowed)
		)
		(placement
			(enabled no)
			(sheetname "")
		)
		(fill
			(thermal_gap 0.5)
			(thermal_bridge_width 0.5)
			(island_removal_mode 0)
		)
		(polygon
			(pts
				(xy 295.570402 -146.375882) (xy 295.570402 -148.179282) (xy 296.129202 -148.179282) (xy 296.129202 -146.375882)
			)
		)
	)
	(zone
		(layer "In1.Cu")
		(hatch none 0.5)
		(connect_pads
			(clearance 0)
		)
		(min_thickness 0.25)
		(keepout
			(tracks not_allowed)
			(vias allowed)
			(pads allowed)
			(copperpour not_allowed)
			(footprints allowed)
		)
		(placement
			(enabled no)
			(sheetname "")
		)
		(fill
			(thermal_gap 0.5)
			(thermal_bridge_width 0.5)
			(island_removal_mode 0)
		)
		(polygon
			(pts
				(xy 293.020496 -151.377142) (xy 293.020496 -153.180542) (xy 293.579296 -153.180542) (xy 293.579296 -151.377142)
			)
		)
	)
	(zone
		(layer "In1.Cu")
		(hatch none 0.5)
		(connect_pads
			(clearance 0)
		)
		(min_thickness 0.25)
		(keepout
			(tracks not_allowed)
			(vias allowed)
			(pads allowed)
			(copperpour not_allowed)
			(footprints allowed)
		)
		(placement
			(enabled no)
			(sheetname "")
		)
		(fill
			(thermal_gap 0.5)
			(thermal_bridge_width 0.5)
			(island_removal_mode 0)
		)
		(polygon
			(pts
				(xy 116.970048 -136.774682) (xy 116.970048 -138.578082) (xy 117.528848 -138.578082) (xy 117.528848 -136.774682)
			)
		)
	)
	(zone
		(layer "In1.Cu")
		(hatch none 0.5)
		(connect_pads
			(clearance 0)
		)
		(min_thickness 0.25)
		(keepout
			(tracks not_allowed)
			(vias allowed)
			(pads allowed)
			(copperpour not_allowed)
			(footprints allowed)
		)
		(placement
			(enabled no)
			(sheetname "")
		)
		(fill
			(thermal_gap 0.5)
			(thermal_bridge_width 0.5)
			(island_removal_mode 0)
		)
		(polygon
			(pts
				(xy 67.669918 0.080518) (xy 67.669918 -1.722882) (xy 68.228718 -1.722882) (xy 68.228718 0.080518)
			)
		)
	)
	(zone
		(layer "In1.Cu")
		(hatch none 0.5)
		(connect_pads
			(clearance 0)
		)
		(min_thickness 0.25)
		(keepout
			(tracks not_allowed)
			(vias allowed)
			(pads allowed)
			(copperpour not_allowed)
			(footprints allowed)
		)
		(placement
			(enabled no)
			(sheetname "")
		)
		(fill
			(thermal_gap 0.5)
			(thermal_bridge_width 0.5)
			(island_removal_mode 0)
		)
		(polygon
			(pts
				(xy 38.770052 -132.174742) (xy 38.770052 -133.978142) (xy 39.328852 -133.978142) (xy 39.328852 -132.174742)
			)
		)
	)
	(zone
		(layer "In1.Cu")
		(hatch none 0.5)
		(connect_pads
			(clearance 0)
		)
		(min_thickness 0.25)
		(keepout
			(tracks not_allowed)
			(vias allowed)
			(pads allowed)
			(copperpour not_allowed)
			(footprints allowed)
		)
		(placement
			(enabled no)
			(sheetname "")
		)
		(fill
			(thermal_gap 0.5)
			(thermal_bridge_width 0.5)
			(island_removal_mode 0)
		)
		(polygon
			(pts
				(xy 252.220476 0.080518) (xy 252.220476 -1.722882) (xy 252.779276 -1.722882) (xy 252.779276 0.080518)
			)
		)
	)
	(zone
		(layer "In1.Cu")
		(hatch none 0.5)
		(connect_pads
			(clearance 0)
		)
		(min_thickness 0.25)
		(keepout
			(tracks not_allowed)
			(vias allowed)
			(pads allowed)
			(copperpour not_allowed)
			(footprints allowed)
		)
		(placement
			(enabled no)
			(sheetname "")
		)
		(fill
			(thermal_gap 0.5)
			(thermal_bridge_width 0.5)
			(island_removal_mode 0)
		)
		(polygon
			(pts
				(xy 42.170096 4.680458) (xy 42.170096 2.877058) (xy 42.728896 2.877058) (xy 42.728896 4.680458)
			)
		)
	)
	(zone
		(layer "In1.Cu")
		(hatch none 0.5)
		(connect_pads
			(clearance 0)
		)
		(min_thickness 0.25)
		(keepout
			(tracks not_allowed)
			(vias allowed)
			(pads allowed)
			(copperpour not_allowed)
			(footprints allowed)
		)
		(placement
			(enabled no)
			(sheetname "")
		)
		(fill
			(thermal_gap 0.5)
			(thermal_bridge_width 0.5)
			(island_removal_mode 0)
		)
		(polygon
			(pts
				(xy 249.67057 -4.920742) (xy 249.67057 -6.724142) (xy 250.22937 -6.724142) (xy 250.22937 -4.920742)
			)
		)
	)
	(zone
		(layer "In1.Cu")
		(hatch none 0.5)
		(connect_pads
			(clearance 0)
		)
		(min_thickness 0.25)
		(keepout
			(tracks not_allowed)
			(vias allowed)
			(pads allowed)
			(copperpour not_allowed)
			(footprints allowed)
		)
		(placement
			(enabled no)
			(sheetname "")
		)
		(fill
			(thermal_gap 0.5)
			(thermal_bridge_width 0.5)
			(island_removal_mode 0)
		)
		(polygon
			(pts
				(xy 123.769882 4.680458) (xy 123.769882 2.877058) (xy 124.328682 2.877058) (xy 124.328682 4.680458)
			)
		)
	)
	(zone
		(layer "In1.Cu")
		(hatch none 0.5)
		(connect_pads
			(clearance 0)
		)
		(min_thickness 0.25)
		(keepout
			(tracks not_allowed)
			(vias allowed)
			(pads allowed)
			(copperpour not_allowed)
			(footprints allowed)
		)
		(placement
			(enabled no)
			(sheetname "")
		)
		(fill
			(thermal_gap 0.5)
			(thermal_bridge_width 0.5)
			(island_removal_mode 0)
		)
		(polygon
			(pts
				(xy 310.020462 -146.375882) (xy 310.020462 -148.179282) (xy 310.579262 -148.179282) (xy 310.579262 -146.375882)
			)
		)
	)
	(zone
		(layer "In1.Cu")
		(hatch none 0.5)
		(connect_pads
			(clearance 0)
		)
		(min_thickness 0.25)
		(keepout
			(tracks not_allowed)
			(vias allowed)
			(pads allowed)
			(copperpour not_allowed)
			(footprints allowed)
		)
		(placement
			(enabled no)
			(sheetname "")
		)
		(fill
			(thermal_gap 0.5)
			(thermal_bridge_width 0.5)
			(island_removal_mode 0)
		)
		(polygon
			(pts
				(xy 62.570106 -14.521942) (xy 62.570106 -16.325342) (xy 63.128906 -16.325342) (xy 63.128906 -14.521942)
			)
		)
	)
	(zone
		(layer "In1.Cu")
		(hatch none 0.5)
		(connect_pads
			(clearance 0)
		)
		(min_thickness 0.25)
		(keepout
			(tracks not_allowed)
			(vias allowed)
			(pads allowed)
			(copperpour not_allowed)
			(footprints allowed)
		)
		(placement
			(enabled no)
			(sheetname "")
		)
		(fill
			(thermal_gap 0.5)
			(thermal_bridge_width 0.5)
			(island_removal_mode 0)
		)
		(polygon
			(pts
				(xy 102.519988 -155.977082) (xy 102.519988 -157.780482) (xy 103.078788 -157.780482) (xy 103.078788 -155.977082)
			)
		)
	)
	(zone
		(layer "In1.Cu")
		(hatch none 0.5)
		(connect_pads
			(clearance 0)
		)
		(min_thickness 0.25)
		(keepout
			(tracks not_allowed)
			(vias allowed)
			(pads allowed)
			(copperpour not_allowed)
			(footprints allowed)
		)
		(placement
			(enabled no)
			(sheetname "")
		)
		(fill
			(thermal_gap 0.5)
			(thermal_bridge_width 0.5)
			(island_removal_mode 0)
		)
		(polygon
			(pts
				(xy 438.622186 -7.192772) (xy 439.930286 -7.192772) (xy 439.930286 -8.386572) (xy 438.622186 -8.386572)
			)
		)
	)
	(zone
		(layer "In1.Cu")
		(hatch none 0.5)
		(connect_pads
			(clearance 0)
		)
		(min_thickness 0.25)
		(keepout
			(tracks not_allowed)
			(vias allowed)
			(pads allowed)
			(copperpour not_allowed)
			(footprints allowed)
		)
		(placement
			(enabled no)
			(sheetname "")
		)
		(fill
			(thermal_gap 0.5)
			(thermal_bridge_width 0.5)
			(island_removal_mode 0)
		)
		(polygon
			(pts
				(xy 117.819932 -14.521942) (xy 117.819932 -16.325342) (xy 118.378732 -16.325342) (xy 118.378732 -14.521942)
			)
		)
	)
	(zone
		(layer "In1.Cu")
		(hatch none 0.5)
		(connect_pads
			(clearance 0)
		)
		(min_thickness 0.25)
		(keepout
			(tracks not_allowed)
			(vias allowed)
			(pads allowed)
			(copperpour not_allowed)
			(footprints allowed)
		)
		(placement
			(enabled no)
			(sheetname "")
		)
		(fill
			(thermal_gap 0.5)
			(thermal_bridge_width 0.5)
			(island_removal_mode 0)
		)
		(polygon
			(pts
				(xy 85.520022 -155.977082) (xy 85.520022 -157.780482) (xy 86.078822 -157.780482) (xy 86.078822 -155.977082)
			)
		)
	)
	(zone
		(layer "In1.Cu")
		(hatch none 0.5)
		(connect_pads
			(clearance 0)
		)
		(min_thickness 0.25)
		(keepout
			(tracks not_allowed)
			(vias allowed)
			(pads allowed)
			(copperpour not_allowed)
			(footprints allowed)
		)
		(placement
			(enabled no)
			(sheetname "")
		)
		(fill
			(thermal_gap 0.5)
			(thermal_bridge_width 0.5)
			(island_removal_mode 0)
		)
		(polygon
			(pts
				(xy 291.320474 -146.375882) (xy 291.320474 -148.179282) (xy 291.879274 -148.179282) (xy 291.879274 -146.375882)
			)
		)
	)
	(zone
		(layer "In1.Cu")
		(hatch none 0.5)
		(connect_pads
			(clearance 0)
		)
		(min_thickness 0.25)
		(keepout
			(tracks not_allowed)
			(vias allowed)
			(pads allowed)
			(copperpour not_allowed)
			(footprints allowed)
		)
		(placement
			(enabled no)
			(sheetname "")
		)
		(fill
			(thermal_gap 0.5)
			(thermal_bridge_width 0.5)
			(island_removal_mode 0)
		)
		(polygon
			(pts
				(xy 142.46987 4.680458) (xy 142.46987 2.877058) (xy 143.02867 2.877058) (xy 143.02867 4.680458)
			)
		)
	)
	(zone
		(layer "In1.Cu")
		(hatch none 0.5)
		(connect_pads
			(clearance 0)
		)
		(min_thickness 0.25)
		(keepout
			(tracks not_allowed)
			(vias allowed)
			(pads allowed)
			(copperpour not_allowed)
			(footprints allowed)
		)
		(placement
			(enabled no)
			(sheetname "")
		)
		(fill
			(thermal_gap 0.5)
			(thermal_bridge_width 0.5)
			(island_removal_mode 0)
		)
		(polygon
			(pts
				(xy 249.67057 -14.521942) (xy 249.67057 -16.325342) (xy 250.22937 -16.325342) (xy 250.22937 -14.521942)
			)
		)
	)
	(zone
		(layer "In1.Cu")
		(hatch none 0.5)
		(connect_pads
			(clearance 0)
		)
		(min_thickness 0.25)
		(keepout
			(tracks not_allowed)
			(vias allowed)
			(pads allowed)
			(copperpour not_allowed)
			(footprints allowed)
		)
		(placement
			(enabled no)
			(sheetname "")
		)
		(fill
			(thermal_gap 0.5)
			(thermal_bridge_width 0.5)
			(island_removal_mode 0)
		)
		(polygon
			(pts
				(xy 43.870118 -132.174742) (xy 43.870118 -133.978142) (xy 44.428918 -133.978142) (xy 44.428918 -132.174742)
			)
		)
	)
	(zone
		(layer "In1.Cu")
		(hatch none 0.5)
		(connect_pads
			(clearance 0)
		)
		(min_thickness 0.25)
		(keepout
			(tracks not_allowed)
			(vias allowed)
			(pads allowed)
			(copperpour not_allowed)
			(footprints allowed)
		)
		(placement
			(enabled no)
			(sheetname "")
		)
		(fill
			(thermal_gap 0.5)
			(thermal_bridge_width 0.5)
			(island_removal_mode 0)
		)
		(polygon
			(pts
				(xy 279.42032 -14.521942) (xy 279.42032 -16.325342) (xy 279.97912 -16.325342) (xy 279.97912 -14.521942)
			)
		)
	)
	(zone
		(layer "In1.Cu")
		(hatch none 0.5)
		(connect_pads
			(clearance 0)
		)
		(min_thickness 0.25)
		(keepout
			(tracks not_allowed)
			(vias allowed)
			(pads allowed)
			(copperpour not_allowed)
			(footprints allowed)
		)
		(placement
			(enabled no)
			(sheetname "")
		)
		(fill
			(thermal_gap 0.5)
			(thermal_bridge_width 0.5)
			(island_removal_mode 0)
		)
		(polygon
			(pts
				(xy 78.719934 -19.121882) (xy 78.719934 -20.925282) (xy 79.278734 -20.925282) (xy 79.278734 -19.121882)
			)
		)
	)
	(zone
		(layer "In1.Cu")
		(hatch none 0.5)
		(connect_pads
			(clearance 0)
		)
		(min_thickness 0.25)
		(keepout
			(tracks not_allowed)
			(vias allowed)
			(pads allowed)
			(copperpour not_allowed)
			(footprints allowed)
		)
		(placement
			(enabled no)
			(sheetname "")
		)
		(fill
			(thermal_gap 0.5)
			(thermal_bridge_width 0.5)
			(island_removal_mode 0)
		)
		(polygon
			(pts
				(xy 302.37049 -132.174742) (xy 302.37049 -133.978142) (xy 302.92929 -133.978142) (xy 302.92929 -132.174742)
			)
		)
	)
	(zone
		(layer "In1.Cu")
		(hatch none 0.5)
		(connect_pads
			(clearance 0)
		)
		(min_thickness 0.25)
		(keepout
			(tracks not_allowed)
			(vias allowed)
			(pads allowed)
			(copperpour not_allowed)
			(footprints allowed)
		)
		(placement
			(enabled no)
			(sheetname "")
		)
		(fill
			(thermal_gap 0.5)
			(thermal_bridge_width 0.5)
			(island_removal_mode 0)
		)
		(polygon
			(pts
				(xy 281.97048 -136.774682) (xy 281.97048 -138.578082) (xy 282.52928 -138.578082) (xy 282.52928 -136.774682)
			)
		)
	)
	(zone
		(layer "In1.Cu")
		(hatch none 0.5)
		(connect_pads
			(clearance 0)
		)
		(min_thickness 0.25)
		(keepout
			(tracks not_allowed)
			(vias allowed)
			(pads allowed)
			(copperpour not_allowed)
			(footprints allowed)
		)
		(placement
			(enabled no)
			(sheetname "")
		)
		(fill
			(thermal_gap 0.5)
			(thermal_bridge_width 0.5)
			(island_removal_mode 0)
		)
		(polygon
			(pts
				(xy 229.27056 -155.977082) (xy 229.27056 -157.780482) (xy 229.82936 -157.780482) (xy 229.82936 -155.977082)
			)
		)
	)
	(zone
		(layer "In1.Cu")
		(hatch none 0.5)
		(connect_pads
			(clearance 0)
		)
		(min_thickness 0.25)
		(keepout
			(tracks not_allowed)
			(vias allowed)
			(pads allowed)
			(copperpour not_allowed)
			(footprints allowed)
		)
		(placement
			(enabled no)
			(sheetname "")
		)
		(fill
			(thermal_gap 0.5)
			(thermal_bridge_width 0.5)
			(island_removal_mode 0)
		)
		(polygon
			(pts
				(xy 212.270594 0.080518) (xy 212.270594 -1.722882) (xy 212.829394 -1.722882) (xy 212.829394 0.080518)
			)
		)
	)
	(zone
		(layer "In1.Cu")
		(hatch none 0.5)
		(connect_pads
			(clearance 0)
		)
		(min_thickness 0.25)
		(keepout
			(tracks not_allowed)
			(vias allowed)
			(pads allowed)
			(copperpour not_allowed)
			(footprints allowed)
		)
		(placement
			(enabled no)
			(sheetname "")
		)
		(fill
			(thermal_gap 0.5)
			(thermal_bridge_width 0.5)
			(island_removal_mode 0)
		)
		(polygon
			(pts
				(xy 145.869914 -14.521942) (xy 145.869914 -16.325342) (xy 146.428714 -16.325342) (xy 146.428714 -14.521942)
			)
		)
	)
	(zone
		(layer "In1.Cu")
		(hatch none 0.5)
		(connect_pads
			(clearance 0)
		)
		(min_thickness 0.25)
		(keepout
			(tracks not_allowed)
			(vias allowed)
			(pads allowed)
			(copperpour not_allowed)
			(footprints allowed)
		)
		(placement
			(enabled no)
			(sheetname "")
		)
		(fill
			(thermal_gap 0.5)
			(thermal_bridge_width 0.5)
			(island_removal_mode 0)
		)
		(polygon
			(pts
				(xy 285.370524 -4.920742) (xy 285.370524 -6.724142) (xy 285.929324 -6.724142) (xy 285.929324 -4.920742)
			)
		)
	)
	(zone
		(layer "In1.Cu")
		(hatch none 0.5)
		(connect_pads
			(clearance 0)
		)
		(min_thickness 0.25)
		(keepout
			(tracks not_allowed)
			(vias allowed)
			(pads allowed)
			(copperpour not_allowed)
			(footprints allowed)
		)
		(placement
			(enabled no)
			(sheetname "")
		)
		(fill
			(thermal_gap 0.5)
			(thermal_bridge_width 0.5)
			(island_removal_mode 0)
		)
		(polygon
			(pts
				(xy 409.018486 -3.789172) (xy 410.326586 -3.789172) (xy 410.326586 -4.982972) (xy 409.018486 -4.982972)
			)
		)
	)
	(zone
		(layer "In1.Cu")
		(hatch none 0.5)
		(connect_pads
			(clearance 0)
		)
		(min_thickness 0.25)
		(keepout
			(tracks not_allowed)
			(vias allowed)
			(pads allowed)
			(copperpour not_allowed)
			(footprints allowed)
		)
		(placement
			(enabled no)
			(sheetname "")
		)
		(fill
			(thermal_gap 0.5)
			(thermal_bridge_width 0.5)
			(island_removal_mode 0)
		)
		(polygon
			(pts
				(xy 227.570538 -151.377142) (xy 227.570538 -153.180542) (xy 228.129338 -153.180542) (xy 228.129338 -151.377142)
			)
		)
	)
	(zone
		(layer "In1.Cu")
		(hatch none 0.5)
		(connect_pads
			(clearance 0)
		)
		(min_thickness 0.25)
		(keepout
			(tracks not_allowed)
			(vias allowed)
			(pads allowed)
			(copperpour not_allowed)
			(footprints allowed)
		)
		(placement
			(enabled no)
			(sheetname "")
		)
		(fill
			(thermal_gap 0.5)
			(thermal_bridge_width 0.5)
			(island_removal_mode 0)
		)
		(polygon
			(pts
				(xy 54.069996 -136.774682) (xy 54.069996 -138.578082) (xy 54.628796 -138.578082) (xy 54.628796 -136.774682)
			)
		)
	)
	(zone
		(layer "In1.Cu")
		(hatch none 0.5)
		(connect_pads
			(clearance 0)
		)
		(min_thickness 0.25)
		(keepout
			(tracks not_allowed)
			(vias allowed)
			(pads allowed)
			(copperpour not_allowed)
			(footprints allowed)
		)
		(placement
			(enabled no)
			(sheetname "")
		)
		(fill
			(thermal_gap 0.5)
			(thermal_bridge_width 0.5)
			(island_removal_mode 0)
		)
		(polygon
			(pts
				(xy 13.6398 -32.766) (xy 15.0368 -32.766) (xy 15.0368 -33.274) (xy 13.6398 -33.274)
			)
		)
	)
	(zone
		(layer "In1.Cu")
		(hatch none 0.5)
		(connect_pads
			(clearance 0)
		)
		(min_thickness 0.25)
		(keepout
			(tracks not_allowed)
			(vias allowed)
			(pads allowed)
			(copperpour not_allowed)
			(footprints allowed)
		)
		(placement
			(enabled no)
			(sheetname "")
		)
		(fill
			(thermal_gap 0.5)
			(thermal_bridge_width 0.5)
			(island_removal_mode 0)
		)
		(polygon
			(pts
				(xy 299.82033 4.680458) (xy 299.82033 2.877058) (xy 300.37913 2.877058) (xy 300.37913 4.680458)
			)
		)
	)
	(zone
		(layer "In1.Cu")
		(hatch none 0.5)
		(connect_pads
			(clearance 0)
		)
		(min_thickness 0.25)
		(keepout
			(tracks not_allowed)
			(vias allowed)
			(pads allowed)
			(copperpour not_allowed)
			(footprints allowed)
		)
		(placement
			(enabled no)
			(sheetname "")
		)
		(fill
			(thermal_gap 0.5)
			(thermal_bridge_width 0.5)
			(island_removal_mode 0)
		)
		(polygon
			(pts
				(xy 396.214092 -9.825736) (xy 396.722092 -9.825736) (xy 396.722092 -11.222736) (xy 396.214092 -11.222736)
			)
		)
	)
	(zone
		(layer "In1.Cu")
		(hatch none 0.5)
		(connect_pads
			(clearance 0)
		)
		(min_thickness 0.25)
		(keepout
			(tracks not_allowed)
			(vias allowed)
			(pads allowed)
			(copperpour not_allowed)
			(footprints allowed)
		)
		(placement
			(enabled no)
			(sheetname "")
		)
		(fill
			(thermal_gap 0.5)
			(thermal_bridge_width 0.5)
			(island_removal_mode 0)
		)
		(polygon
			(pts
				(xy 137.370058 -136.774682) (xy 137.370058 -138.578082) (xy 137.928858 -138.578082) (xy 137.928858 -136.774682)
			)
		)
	)
	(zone
		(layer "In1.Cu")
		(hatch none 0.5)
		(connect_pads
			(clearance 0)
		)
		(min_thickness 0.25)
		(keepout
			(tracks not_allowed)
			(vias allowed)
			(pads allowed)
			(copperpour not_allowed)
			(footprints allowed)
		)
		(placement
			(enabled no)
			(sheetname "")
		)
		(fill
			(thermal_gap 0.5)
			(thermal_bridge_width 0.5)
			(island_removal_mode 0)
		)
		(polygon
			(pts
				(xy 77.87005 4.680458) (xy 77.87005 2.877058) (xy 78.42885 2.877058) (xy 78.42885 4.680458)
			)
		)
	)
	(zone
		(layer "In1.Cu")
		(hatch none 0.5)
		(connect_pads
			(clearance 0)
		)
		(min_thickness 0.25)
		(keepout
			(tracks not_allowed)
			(vias allowed)
			(pads allowed)
			(copperpour not_allowed)
			(footprints allowed)
		)
		(placement
			(enabled no)
			(sheetname "")
		)
		(fill
			(thermal_gap 0.5)
			(thermal_bridge_width 0.5)
			(island_removal_mode 0)
		)
		(polygon
			(pts
				(xy 293.020496 -9.520682) (xy 293.020496 -11.324082) (xy 293.579296 -11.324082) (xy 293.579296 -9.520682)
			)
		)
	)
	(zone
		(layer "In1.Cu")
		(hatch none 0.5)
		(connect_pads
			(clearance 0)
		)
		(min_thickness 0.25)
		(keepout
			(tracks not_allowed)
			(vias allowed)
			(pads allowed)
			(copperpour not_allowed)
			(footprints allowed)
		)
		(placement
			(enabled no)
			(sheetname "")
		)
		(fill
			(thermal_gap 0.5)
			(thermal_bridge_width 0.5)
			(island_removal_mode 0)
		)
		(polygon
			(pts
				(xy 83.82 -151.377142) (xy 83.82 -153.180542) (xy 84.3788 -153.180542) (xy 84.3788 -151.377142)
			)
		)
	)
	(zone
		(layer "In1.Cu")
		(hatch none 0.5)
		(connect_pads
			(clearance 0)
		)
		(min_thickness 0.25)
		(keepout
			(tracks not_allowed)
			(vias allowed)
			(pads allowed)
			(copperpour not_allowed)
			(footprints allowed)
		)
		(placement
			(enabled no)
			(sheetname "")
		)
		(fill
			(thermal_gap 0.5)
			(thermal_bridge_width 0.5)
			(island_removal_mode 0)
		)
		(polygon
			(pts
				(xy 81.270094 4.680458) (xy 81.270094 2.877058) (xy 81.828894 2.877058) (xy 81.828894 4.680458)
			)
		)
	)
	(zone
		(layer "In1.Cu")
		(hatch none 0.5)
		(connect_pads
			(clearance 0)
		)
		(min_thickness 0.25)
		(keepout
			(tracks not_allowed)
			(vias allowed)
			(pads allowed)
			(copperpour not_allowed)
			(footprints allowed)
		)
		(placement
			(enabled no)
			(sheetname "")
		)
		(fill
			(thermal_gap 0.5)
			(thermal_bridge_width 0.5)
			(island_removal_mode 0)
		)
		(polygon
			(pts
				(xy 105.070148 -136.774682) (xy 105.070148 -138.578082) (xy 105.628948 -138.578082) (xy 105.628948 -136.774682)
			)
		)
	)
	(zone
		(layer "In1.Cu")
		(hatch none 0.5)
		(connect_pads
			(clearance 0)
		)
		(min_thickness 0.25)
		(keepout
			(tracks not_allowed)
			(vias allowed)
			(pads allowed)
			(copperpour not_allowed)
			(footprints allowed)
		)
		(placement
			(enabled no)
			(sheetname "")
		)
		(fill
			(thermal_gap 0.5)
			(thermal_bridge_width 0.5)
			(island_removal_mode 0)
		)
		(polygon
			(pts
				(xy 203.770484 -141.775942) (xy 203.770484 -143.579342) (xy 204.329284 -143.579342) (xy 204.329284 -141.775942)
			)
		)
	)
	(zone
		(layer "In1.Cu")
		(hatch none 0.5)
		(connect_pads
			(clearance 0)
		)
		(min_thickness 0.25)
		(keepout
			(tracks not_allowed)
			(vias allowed)
			(pads allowed)
			(copperpour not_allowed)
			(footprints allowed)
		)
		(placement
			(enabled no)
			(sheetname "")
		)
		(fill
			(thermal_gap 0.5)
			(thermal_bridge_width 0.5)
			(island_removal_mode 0)
		)
		(polygon
			(pts
				(xy 30.269942 -146.375882) (xy 30.269942 -148.179282) (xy 30.828742 -148.179282) (xy 30.828742 -146.375882)
			)
		)
	)
	(zone
		(layer "In1.Cu")
		(hatch none 0.5)
		(connect_pads
			(clearance 0)
		)
		(min_thickness 0.25)
		(keepout
			(tracks not_allowed)
			(vias allowed)
			(pads allowed)
			(copperpour not_allowed)
			(footprints allowed)
		)
		(placement
			(enabled no)
			(sheetname "")
		)
		(fill
			(thermal_gap 0.5)
			(thermal_bridge_width 0.5)
			(island_removal_mode 0)
		)
		(polygon
			(pts
				(xy 111.020098 -9.520682) (xy 111.020098 -11.324082) (xy 111.578898 -11.324082) (xy 111.578898 -9.520682)
			)
		)
	)
	(zone
		(layer "In1.Cu")
		(hatch none 0.5)
		(connect_pads
			(clearance 0)
		)
		(min_thickness 0.25)
		(keepout
			(tracks not_allowed)
			(vias allowed)
			(pads allowed)
			(copperpour not_allowed)
			(footprints allowed)
		)
		(placement
			(enabled no)
			(sheetname "")
		)
		(fill
			(thermal_gap 0.5)
			(thermal_bridge_width 0.5)
			(island_removal_mode 0)
		)
		(polygon
			(pts
				(xy 297.270424 -155.977082) (xy 297.270424 -157.780482) (xy 297.829224 -157.780482) (xy 297.829224 -155.977082)
			)
		)
	)
	(zone
		(layer "In1.Cu")
		(hatch none 0.5)
		(connect_pads
			(clearance 0)
		)
		(min_thickness 0.25)
		(keepout
			(tracks not_allowed)
			(vias allowed)
			(pads allowed)
			(copperpour not_allowed)
			(footprints allowed)
		)
		(placement
			(enabled no)
			(sheetname "")
		)
		(fill
			(thermal_gap 0.5)
			(thermal_bridge_width 0.5)
			(island_removal_mode 0)
		)
		(polygon
			(pts
				(xy 232.67035 0.080518) (xy 232.67035 -1.722882) (xy 233.22915 -1.722882) (xy 233.22915 0.080518)
			)
		)
	)
	(zone
		(layer "In1.Cu")
		(hatch none 0.5)
		(connect_pads
			(clearance 0)
		)
		(min_thickness 0.25)
		(keepout
			(tracks not_allowed)
			(vias allowed)
			(pads allowed)
			(copperpour not_allowed)
			(footprints allowed)
		)
		(placement
			(enabled no)
			(sheetname "")
		)
		(fill
			(thermal_gap 0.5)
			(thermal_bridge_width 0.5)
			(island_removal_mode 0)
		)
		(polygon
			(pts
				(xy 219.920566 0.080518) (xy 219.920566 -1.722882) (xy 220.479366 -1.722882) (xy 220.479366 0.080518)
			)
		)
	)
	(zone
		(layer "In1.Cu")
		(hatch none 0.5)
		(connect_pads
			(clearance 0)
		)
		(min_thickness 0.25)
		(keepout
			(tracks not_allowed)
			(vias allowed)
			(pads allowed)
			(copperpour not_allowed)
			(footprints allowed)
		)
		(placement
			(enabled no)
			(sheetname "")
		)
		(fill
			(thermal_gap 0.5)
			(thermal_bridge_width 0.5)
			(island_removal_mode 0)
		)
		(polygon
			(pts
				(xy 78.719934 0.080518) (xy 78.719934 -1.722882) (xy 79.278734 -1.722882) (xy 79.278734 0.080518)
			)
		)
	)
	(zone
		(layer "In1.Cu")
		(hatch none 0.5)
		(connect_pads
			(clearance 0)
		)
		(min_thickness 0.25)
		(keepout
			(tracks not_allowed)
			(vias allowed)
			(pads allowed)
			(copperpour not_allowed)
			(footprints allowed)
		)
		(placement
			(enabled no)
			(sheetname "")
		)
		(fill
			(thermal_gap 0.5)
			(thermal_bridge_width 0.5)
			(island_removal_mode 0)
		)
		(polygon
			(pts
				(xy 202.070462 -141.775942) (xy 202.070462 -143.579342) (xy 202.629262 -143.579342) (xy 202.629262 -141.775942)
			)
		)
	)
	(zone
		(layer "In1.Cu")
		(hatch none 0.5)
		(connect_pads
			(clearance 0)
		)
		(min_thickness 0.25)
		(keepout
			(tracks not_allowed)
			(vias allowed)
			(pads allowed)
			(copperpour not_allowed)
			(footprints allowed)
		)
		(placement
			(enabled no)
			(sheetname "")
		)
		(fill
			(thermal_gap 0.5)
			(thermal_bridge_width 0.5)
			(island_removal_mode 0)
		)
		(polygon
			(pts
				(xy 105.070148 -141.775942) (xy 105.070148 -143.579342) (xy 105.628948 -143.579342) (xy 105.628948 -141.775942)
			)
		)
	)
	(zone
		(layer "In1.Cu")
		(hatch none 0.5)
		(connect_pads
			(clearance 0)
		)
		(min_thickness 0.25)
		(keepout
			(tracks not_allowed)
			(vias allowed)
			(pads allowed)
			(copperpour not_allowed)
			(footprints allowed)
		)
		(placement
			(enabled no)
			(sheetname "")
		)
		(fill
			(thermal_gap 0.5)
			(thermal_bridge_width 0.5)
			(island_removal_mode 0)
		)
		(polygon
			(pts
				(xy 221.620588 -9.520682) (xy 221.620588 -11.324082) (xy 222.179388 -11.324082) (xy 222.179388 -9.520682)
			)
		)
	)
	(zone
		(layer "In1.Cu")
		(hatch none 0.5)
		(connect_pads
			(clearance 0)
		)
		(min_thickness 0.25)
		(keepout
			(tracks not_allowed)
			(vias allowed)
			(pads allowed)
			(copperpour not_allowed)
			(footprints allowed)
		)
		(placement
			(enabled no)
			(sheetname "")
		)
		(fill
			(thermal_gap 0.5)
			(thermal_bridge_width 0.5)
			(island_removal_mode 0)
		)
		(polygon
			(pts
				(xy 31.969964 0.080518) (xy 31.969964 -1.722882) (xy 32.528764 -1.722882) (xy 32.528764 0.080518)
			)
		)
	)
	(zone
		(layer "In1.Cu")
		(hatch none 0.5)
		(connect_pads
			(clearance 0)
		)
		(min_thickness 0.25)
		(keepout
			(tracks not_allowed)
			(vias allowed)
			(pads allowed)
			(copperpour not_allowed)
			(footprints allowed)
		)
		(placement
			(enabled no)
			(sheetname "")
		)
		(fill
			(thermal_gap 0.5)
			(thermal_bridge_width 0.5)
			(island_removal_mode 0)
		)
		(polygon
			(pts
				(xy 101.670104 -146.375882) (xy 101.670104 -148.179282) (xy 102.228904 -148.179282) (xy 102.228904 -146.375882)
			)
		)
	)
	(zone
		(layer "In1.Cu")
		(hatch none 0.5)
		(connect_pads
			(clearance 0)
		)
		(min_thickness 0.25)
		(keepout
			(tracks not_allowed)
			(vias allowed)
			(pads allowed)
			(copperpour not_allowed)
			(footprints allowed)
		)
		(placement
			(enabled no)
			(sheetname "")
		)
		(fill
			(thermal_gap 0.5)
			(thermal_bridge_width 0.5)
			(island_removal_mode 0)
		)
		(polygon
			(pts
				(xy 36.220146 -19.121882) (xy 36.220146 -20.925282) (xy 36.778946 -20.925282) (xy 36.778946 -19.121882)
			)
		)
	)
	(zone
		(layer "In1.Cu")
		(hatch none 0.5)
		(connect_pads
			(clearance 0)
		)
		(min_thickness 0.25)
		(keepout
			(tracks not_allowed)
			(vias allowed)
			(pads allowed)
			(copperpour not_allowed)
			(footprints allowed)
		)
		(placement
			(enabled no)
			(sheetname "")
		)
		(fill
			(thermal_gap 0.5)
			(thermal_bridge_width 0.5)
			(island_removal_mode 0)
		)
		(polygon
			(pts
				(xy 143.320008 0.080518) (xy 143.320008 -1.722882) (xy 143.878808 -1.722882) (xy 143.878808 0.080518)
			)
		)
	)
	(zone
		(layer "In1.Cu")
		(hatch none 0.5)
		(connect_pads
			(clearance 0)
		)
		(min_thickness 0.25)
		(keepout
			(tracks not_allowed)
			(vias allowed)
			(pads allowed)
			(copperpour not_allowed)
			(footprints allowed)
		)
		(placement
			(enabled no)
			(sheetname "")
		)
		(fill
			(thermal_gap 0.5)
			(thermal_bridge_width 0.5)
			(island_removal_mode 0)
		)
		(polygon
			(pts
				(xy 63.41999 -132.174742) (xy 63.41999 -133.978142) (xy 63.97879 -133.978142) (xy 63.97879 -132.174742)
			)
		)
	)
	(zone
		(layer "In1.Cu")
		(hatch none 0.5)
		(connect_pads
			(clearance 0)
		)
		(min_thickness 0.25)
		(keepout
			(tracks not_allowed)
			(vias allowed)
			(pads allowed)
			(copperpour not_allowed)
			(footprints allowed)
		)
		(placement
			(enabled no)
			(sheetname "")
		)
		(fill
			(thermal_gap 0.5)
			(thermal_bridge_width 0.5)
			(island_removal_mode 0)
		)
		(polygon
			(pts
				(xy 313.420506 -14.521942) (xy 313.420506 -16.325342) (xy 313.979306 -16.325342) (xy 313.979306 -14.521942)
			)
		)
	)
	(zone
		(layer "In1.Cu")
		(hatch none 0.5)
		(connect_pads
			(clearance 0)
		)
		(min_thickness 0.25)
		(keepout
			(tracks not_allowed)
			(vias allowed)
			(pads allowed)
			(copperpour not_allowed)
			(footprints allowed)
		)
		(placement
			(enabled no)
			(sheetname "")
		)
		(fill
			(thermal_gap 0.5)
			(thermal_bridge_width 0.5)
			(island_removal_mode 0)
		)
		(polygon
			(pts
				(xy 73.620122 0.080518) (xy 73.620122 -1.722882) (xy 74.178922 -1.722882) (xy 74.178922 0.080518)
			)
		)
	)
	(zone
		(layer "In1.Cu")
		(hatch none 0.5)
		(connect_pads
			(clearance 0)
		)
		(min_thickness 0.25)
		(keepout
			(tracks not_allowed)
			(vias allowed)
			(pads allowed)
			(copperpour not_allowed)
			(footprints allowed)
		)
		(placement
			(enabled no)
			(sheetname "")
		)
		(fill
			(thermal_gap 0.5)
			(thermal_bridge_width 0.5)
			(island_removal_mode 0)
		)
		(polygon
			(pts
				(xy 106.77017 -132.174742) (xy 106.77017 -133.978142) (xy 107.32897 -133.978142) (xy 107.32897 -132.174742)
			)
		)
	)
	(zone
		(layer "In1.Cu")
		(hatch none 0.5)
		(connect_pads
			(clearance 0)
		)
		(min_thickness 0.25)
		(keepout
			(tracks not_allowed)
			(vias allowed)
			(pads allowed)
			(copperpour not_allowed)
			(footprints allowed)
		)
		(placement
			(enabled no)
			(sheetname "")
		)
		(fill
			(thermal_gap 0.5)
			(thermal_bridge_width 0.5)
			(island_removal_mode 0)
		)
		(polygon
			(pts
				(xy 35.370008 -151.377142) (xy 35.370008 -153.180542) (xy 35.928808 -153.180542) (xy 35.928808 -151.377142)
			)
		)
	)
	(zone
		(layer "In1.Cu")
		(hatch none 0.5)
		(connect_pads
			(clearance 0)
		)
		(min_thickness 0.25)
		(keepout
			(tracks not_allowed)
			(vias allowed)
			(pads allowed)
			(copperpour not_allowed)
			(footprints allowed)
		)
		(placement
			(enabled no)
			(sheetname "")
		)
		(fill
			(thermal_gap 0.5)
			(thermal_bridge_width 0.5)
			(island_removal_mode 0)
		)
		(polygon
			(pts
				(xy 77.87005 -141.775942) (xy 77.87005 -143.579342) (xy 78.42885 -143.579342) (xy 78.42885 -141.775942)
			)
		)
	)
	(zone
		(layer "In1.Cu")
		(hatch none 0.5)
		(connect_pads
			(clearance 0)
		)
		(min_thickness 0.25)
		(keepout
			(tracks not_allowed)
			(vias allowed)
			(pads allowed)
			(copperpour not_allowed)
			(footprints allowed)
		)
		(placement
			(enabled no)
			(sheetname "")
		)
		(fill
			(thermal_gap 0.5)
			(thermal_bridge_width 0.5)
			(island_removal_mode 0)
		)
		(polygon
			(pts
				(xy 296.42054 -151.377142) (xy 296.42054 -153.180542) (xy 296.97934 -153.180542) (xy 296.97934 -151.377142)
			)
		)
	)
	(zone
		(layer "In1.Cu")
		(hatch none 0.5)
		(connect_pads
			(clearance 0)
		)
		(min_thickness 0.25)
		(keepout
			(tracks not_allowed)
			(vias allowed)
			(pads allowed)
			(copperpour not_allowed)
			(footprints allowed)
		)
		(placement
			(enabled no)
			(sheetname "")
		)
		(fill
			(thermal_gap 0.5)
			(thermal_bridge_width 0.5)
			(island_removal_mode 0)
		)
		(polygon
			(pts
				(xy 83.82 -14.521942) (xy 83.82 -16.325342) (xy 84.3788 -16.325342) (xy 84.3788 -14.521942)
			)
		)
	)
	(zone
		(layer "In1.Cu")
		(hatch none 0.5)
		(connect_pads
			(clearance 0)
		)
		(min_thickness 0.25)
		(keepout
			(tracks not_allowed)
			(vias allowed)
			(pads allowed)
			(copperpour not_allowed)
			(footprints allowed)
		)
		(placement
			(enabled no)
			(sheetname "")
		)
		(fill
			(thermal_gap 0.5)
			(thermal_bridge_width 0.5)
			(island_removal_mode 0)
		)
		(polygon
			(pts
				(xy 214.8205 -141.775942) (xy 214.8205 -143.579342) (xy 215.3793 -143.579342) (xy 215.3793 -141.775942)
			)
		)
	)
	(zone
		(layer "In1.Cu")
		(hatch none 0.5)
		(connect_pads
			(clearance 0)
		)
		(min_thickness 0.25)
		(keepout
			(tracks not_allowed)
			(vias allowed)
			(pads allowed)
			(copperpour not_allowed)
			(footprints allowed)
		)
		(placement
			(enabled no)
			(sheetname "")
		)
		(fill
			(thermal_gap 0.5)
			(thermal_bridge_width 0.5)
			(island_removal_mode 0)
		)
		(polygon
			(pts
				(xy 87.220044 -132.174742) (xy 87.220044 -133.978142) (xy 87.778844 -133.978142) (xy 87.778844 -132.174742)
			)
		)
	)
	(zone
		(layer "In1.Cu")
		(hatch none 0.5)
		(connect_pads
			(clearance 0)
		)
		(min_thickness 0.25)
		(keepout
			(tracks not_allowed)
			(vias allowed)
			(pads allowed)
			(copperpour not_allowed)
			(footprints allowed)
		)
		(placement
			(enabled no)
			(sheetname "")
		)
		(fill
			(thermal_gap 0.5)
			(thermal_bridge_width 0.5)
			(island_removal_mode 0)
		)
		(polygon
			(pts
				(xy 111.020098 -19.121882) (xy 111.020098 -20.925282) (xy 111.578898 -20.925282) (xy 111.578898 -19.121882)
			)
		)
	)
	(zone
		(layer "In1.Cu")
		(hatch none 0.5)
		(connect_pads
			(clearance 0)
		)
		(min_thickness 0.25)
		(keepout
			(tracks not_allowed)
			(vias allowed)
			(pads allowed)
			(copperpour not_allowed)
			(footprints allowed)
		)
		(placement
			(enabled no)
			(sheetname "")
		)
		(fill
			(thermal_gap 0.5)
			(thermal_bridge_width 0.5)
			(island_removal_mode 0)
		)
		(polygon
			(pts
				(xy 78.719934 -9.520682) (xy 78.719934 -11.324082) (xy 79.278734 -11.324082) (xy 79.278734 -9.520682)
			)
		)
	)
	(zone
		(layer "In1.Cu")
		(hatch none 0.5)
		(connect_pads
			(clearance 0)
		)
		(min_thickness 0.25)
		(keepout
			(tracks not_allowed)
			(vias allowed)
			(pads allowed)
			(copperpour not_allowed)
			(footprints allowed)
		)
		(placement
			(enabled no)
			(sheetname "")
		)
		(fill
			(thermal_gap 0.5)
			(thermal_bridge_width 0.5)
			(island_removal_mode 0)
		)
		(polygon
			(pts
				(xy 228.420422 -155.977082) (xy 228.420422 -157.780482) (xy 228.979222 -157.780482) (xy 228.979222 -155.977082)
			)
		)
	)
	(zone
		(layer "In1.Cu")
		(hatch none 0.5)
		(connect_pads
			(clearance 0)
		)
		(min_thickness 0.25)
		(keepout
			(tracks not_allowed)
			(vias allowed)
			(pads allowed)
			(copperpour not_allowed)
			(footprints allowed)
		)
		(placement
			(enabled no)
			(sheetname "")
		)
		(fill
			(thermal_gap 0.5)
			(thermal_bridge_width 0.5)
			(island_removal_mode 0)
		)
		(polygon
			(pts
				(xy 71.069962 -136.774682) (xy 71.069962 -138.578082) (xy 71.628762 -138.578082) (xy 71.628762 -136.774682)
			)
		)
	)
	(zone
		(layer "In1.Cu")
		(hatch none 0.5)
		(connect_pads
			(clearance 0)
		)
		(min_thickness 0.25)
		(keepout
			(tracks not_allowed)
			(vias allowed)
			(pads allowed)
			(copperpour not_allowed)
			(footprints allowed)
		)
		(placement
			(enabled no)
			(sheetname "")
		)
		(fill
			(thermal_gap 0.5)
			(thermal_bridge_width 0.5)
			(island_removal_mode 0)
		)
		(polygon
			(pts
				(xy 108.469938 -146.375882) (xy 108.469938 -148.179282) (xy 109.028738 -148.179282) (xy 109.028738 -146.375882)
			)
		)
	)
	(zone
		(layer "In1.Cu")
		(hatch none 0.5)
		(connect_pads
			(clearance 0)
		)
		(min_thickness 0.25)
		(keepout
			(tracks not_allowed)
			(vias allowed)
			(pads allowed)
			(copperpour not_allowed)
			(footprints allowed)
		)
		(placement
			(enabled no)
			(sheetname "")
		)
		(fill
			(thermal_gap 0.5)
			(thermal_bridge_width 0.5)
			(island_removal_mode 0)
		)
		(polygon
			(pts
				(xy 233.520488 -14.521942) (xy 233.520488 -16.325342) (xy 234.079288 -16.325342) (xy 234.079288 -14.521942)
			)
		)
	)
	(zone
		(layer "In1.Cu")
		(hatch none 0.5)
		(connect_pads
			(clearance 0)
		)
		(min_thickness 0.25)
		(keepout
			(tracks not_allowed)
			(vias allowed)
			(pads allowed)
			(copperpour not_allowed)
			(footprints allowed)
		)
		(placement
			(enabled no)
			(sheetname "")
		)
		(fill
			(thermal_gap 0.5)
			(thermal_bridge_width 0.5)
			(island_removal_mode 0)
		)
		(polygon
			(pts
				(xy 87.220044 -14.521942) (xy 87.220044 -16.325342) (xy 87.778844 -16.325342) (xy 87.778844 -14.521942)
			)
		)
	)
	(zone
		(layer "In1.Cu")
		(hatch none 0.5)
		(connect_pads
			(clearance 0)
		)
		(min_thickness 0.25)
		(keepout
			(tracks not_allowed)
			(vias allowed)
			(pads allowed)
			(copperpour not_allowed)
			(footprints allowed)
		)
		(placement
			(enabled no)
			(sheetname "")
		)
		(fill
			(thermal_gap 0.5)
			(thermal_bridge_width 0.5)
			(island_removal_mode 0)
		)
		(polygon
			(pts
				(xy 298.120308 -14.521942) (xy 298.120308 -16.325342) (xy 298.679108 -16.325342) (xy 298.679108 -14.521942)
			)
		)
	)
	(zone
		(layer "In1.Cu")
		(hatch none 0.5)
		(connect_pads
			(clearance 0)
		)
		(min_thickness 0.25)
		(keepout
			(tracks not_allowed)
			(vias allowed)
			(pads allowed)
			(copperpour not_allowed)
			(footprints allowed)
		)
		(placement
			(enabled no)
			(sheetname "")
		)
		(fill
			(thermal_gap 0.5)
			(thermal_bridge_width 0.5)
			(island_removal_mode 0)
		)
		(polygon
			(pts
				(xy 292.170358 -132.174742) (xy 292.170358 -133.978142) (xy 292.729158 -133.978142) (xy 292.729158 -132.174742)
			)
		)
	)
	(zone
		(layer "In1.Cu")
		(hatch none 0.5)
		(connect_pads
			(clearance 0)
		)
		(min_thickness 0.25)
		(keepout
			(tracks not_allowed)
			(vias allowed)
			(pads allowed)
			(copperpour not_allowed)
			(footprints allowed)
		)
		(placement
			(enabled no)
			(sheetname "")
		)
		(fill
			(thermal_gap 0.5)
			(thermal_bridge_width 0.5)
			(island_removal_mode 0)
		)
		(polygon
			(pts
				(xy 118.67007 -151.377142) (xy 118.67007 -153.180542) (xy 119.22887 -153.180542) (xy 119.22887 -151.377142)
			)
		)
	)
	(zone
		(layer "In1.Cu")
		(hatch none 0.5)
		(connect_pads
			(clearance 0)
		)
		(min_thickness 0.25)
		(keepout
			(tracks not_allowed)
			(vias allowed)
			(pads allowed)
			(copperpour not_allowed)
			(footprints allowed)
		)
		(placement
			(enabled no)
			(sheetname "")
		)
		(fill
			(thermal_gap 0.5)
			(thermal_bridge_width 0.5)
			(island_removal_mode 0)
		)
		(polygon
			(pts
				(xy 370.112544 -9.773158) (xy 370.620544 -9.773158) (xy 370.620544 -11.170158) (xy 370.112544 -11.170158)
			)
		)
	)
	(zone
		(layer "In1.Cu")
		(hatch none 0.5)
		(connect_pads
			(clearance 0)
		)
		(min_thickness 0.25)
		(keepout
			(tracks not_allowed)
			(vias allowed)
			(pads allowed)
			(copperpour not_allowed)
			(footprints allowed)
		)
		(placement
			(enabled no)
			(sheetname "")
		)
		(fill
			(thermal_gap 0.5)
			(thermal_bridge_width 0.5)
			(island_removal_mode 0)
		)
		(polygon
			(pts
				(xy 393.000992 -9.774936) (xy 393.508992 -9.774936) (xy 393.508992 -11.171936) (xy 393.000992 -11.171936)
			)
		)
	)
	(zone
		(layer "In1.Cu")
		(hatch none 0.5)
		(connect_pads
			(clearance 0)
		)
		(min_thickness 0.25)
		(keepout
			(tracks not_allowed)
			(vias allowed)
			(pads allowed)
			(copperpour not_allowed)
			(footprints allowed)
		)
		(placement
			(enabled no)
			(sheetname "")
		)
		(fill
			(thermal_gap 0.5)
			(thermal_bridge_width 0.5)
			(island_removal_mode 0)
		)
		(polygon
			(pts
				(xy 308.32044 -155.977082) (xy 308.32044 -157.780482) (xy 308.87924 -157.780482) (xy 308.87924 -155.977082)
			)
		)
	)
	(zone
		(layer "In1.Cu")
		(hatch none 0.5)
		(connect_pads
			(clearance 0)
		)
		(min_thickness 0.25)
		(keepout
			(tracks not_allowed)
			(vias allowed)
			(pads allowed)
			(copperpour not_allowed)
			(footprints allowed)
		)
		(placement
			(enabled no)
			(sheetname "")
		)
		(fill
			(thermal_gap 0.5)
			(thermal_bridge_width 0.5)
			(island_removal_mode 0)
		)
		(polygon
			(pts
				(xy 315.970412 0.080518) (xy 315.970412 -1.722882) (xy 316.529212 -1.722882) (xy 316.529212 0.080518)
			)
		)
	)
	(zone
		(layer "In1.Cu")
		(hatch none 0.5)
		(connect_pads
			(clearance 0)
		)
		(min_thickness 0.25)
		(keepout
			(tracks not_allowed)
			(vias allowed)
			(pads allowed)
			(copperpour not_allowed)
			(footprints allowed)
		)
		(placement
			(enabled no)
			(sheetname "")
		)
		(fill
			(thermal_gap 0.5)
			(thermal_bridge_width 0.5)
			(island_removal_mode 0)
		)
		(polygon
			(pts
				(xy 304.070512 -151.377142) (xy 304.070512 -153.180542) (xy 304.629312 -153.180542) (xy 304.629312 -151.377142)
			)
		)
	)
	(zone
		(layer "In1.Cu")
		(hatch none 0.5)
		(connect_pads
			(clearance 0)
		)
		(min_thickness 0.25)
		(keepout
			(tracks not_allowed)
			(vias allowed)
			(pads allowed)
			(copperpour not_allowed)
			(footprints allowed)
		)
		(placement
			(enabled no)
			(sheetname "")
		)
		(fill
			(thermal_gap 0.5)
			(thermal_bridge_width 0.5)
			(island_removal_mode 0)
		)
		(polygon
			(pts
				(xy 92.32011 4.680458) (xy 92.32011 2.877058) (xy 92.87891 2.877058) (xy 92.87891 4.680458)
			)
		)
	)
	(zone
		(layer "In1.Cu")
		(hatch none 0.5)
		(connect_pads
			(clearance 0)
		)
		(min_thickness 0.25)
		(keepout
			(tracks not_allowed)
			(vias allowed)
			(pads allowed)
			(copperpour not_allowed)
			(footprints allowed)
		)
		(placement
			(enabled no)
			(sheetname "")
		)
		(fill
			(thermal_gap 0.5)
			(thermal_bridge_width 0.5)
			(island_removal_mode 0)
		)
		(polygon
			(pts
				(xy 266.670536 -155.977082) (xy 266.670536 -157.780482) (xy 267.229336 -157.780482) (xy 267.229336 -155.977082)
			)
		)
	)
	(zone
		(layer "In1.Cu")
		(hatch none 0.5)
		(connect_pads
			(clearance 0)
		)
		(min_thickness 0.25)
		(keepout
			(tracks not_allowed)
			(vias allowed)
			(pads allowed)
			(copperpour not_allowed)
			(footprints allowed)
		)
		(placement
			(enabled no)
			(sheetname "")
		)
		(fill
			(thermal_gap 0.5)
			(thermal_bridge_width 0.5)
			(island_removal_mode 0)
		)
		(polygon
			(pts
				(xy 133.970014 0.080518) (xy 133.970014 -1.722882) (xy 134.528814 -1.722882) (xy 134.528814 0.080518)
			)
		)
	)
	(zone
		(layer "In1.Cu")
		(hatch none 0.5)
		(connect_pads
			(clearance 0)
		)
		(min_thickness 0.25)
		(keepout
			(tracks not_allowed)
			(vias allowed)
			(pads allowed)
			(copperpour not_allowed)
			(footprints allowed)
		)
		(placement
			(enabled no)
			(sheetname "")
		)
		(fill
			(thermal_gap 0.5)
			(thermal_bridge_width 0.5)
			(island_removal_mode 0)
		)
		(polygon
			(pts
				(xy 256.470404 4.680458) (xy 256.470404 2.877058) (xy 257.029204 2.877058) (xy 257.029204 4.680458)
			)
		)
	)
	(zone
		(layer "In1.Cu")
		(hatch none 0.5)
		(connect_pads
			(clearance 0)
		)
		(min_thickness 0.25)
		(keepout
			(tracks not_allowed)
			(vias allowed)
			(pads allowed)
			(copperpour not_allowed)
			(footprints allowed)
		)
		(placement
			(enabled no)
			(sheetname "")
		)
		(fill
			(thermal_gap 0.5)
			(thermal_bridge_width 0.5)
			(island_removal_mode 0)
		)
		(polygon
			(pts
				(xy 336.286602 -119.784368) (xy 338.572602 -119.784368) (xy 338.572602 -120.292368) (xy 336.286602 -120.292368)
			)
		)
	)
	(zone
		(layer "In1.Cu")
		(hatch none 0.5)
		(connect_pads
			(clearance 0)
		)
		(min_thickness 0.25)
		(keepout
			(tracks not_allowed)
			(vias allowed)
			(pads allowed)
			(copperpour not_allowed)
			(footprints allowed)
		)
		(placement
			(enabled no)
			(sheetname "")
		)
		(fill
			(thermal_gap 0.5)
			(thermal_bridge_width 0.5)
			(island_removal_mode 0)
		)
		(polygon
			(pts
				(xy 81.270094 -141.775942) (xy 81.270094 -143.579342) (xy 81.828894 -143.579342) (xy 81.828894 -141.775942)
			)
		)
	)
	(zone
		(layer "In1.Cu")
		(hatch none 0.5)
		(connect_pads
			(clearance 0)
		)
		(min_thickness 0.25)
		(keepout
			(tracks not_allowed)
			(vias allowed)
			(pads allowed)
			(copperpour not_allowed)
			(footprints allowed)
		)
		(placement
			(enabled no)
			(sheetname "")
		)
		(fill
			(thermal_gap 0.5)
			(thermal_bridge_width 0.5)
			(island_removal_mode 0)
		)
		(polygon
			(pts
				(xy 128.869948 -19.121882) (xy 128.869948 -20.925282) (xy 129.428748 -20.925282) (xy 129.428748 -19.121882)
			)
		)
	)
	(zone
		(layer "In1.Cu")
		(hatch none 0.5)
		(connect_pads
			(clearance 0)
		)
		(min_thickness 0.25)
		(keepout
			(tracks not_allowed)
			(vias allowed)
			(pads allowed)
			(copperpour not_allowed)
			(footprints allowed)
		)
		(placement
			(enabled no)
			(sheetname "")
		)
		(fill
			(thermal_gap 0.5)
			(thermal_bridge_width 0.5)
			(island_removal_mode 0)
		)
		(polygon
			(pts
				(xy 218.220544 -132.174742) (xy 218.220544 -133.978142) (xy 218.779344 -133.978142) (xy 218.779344 -132.174742)
			)
		)
	)
	(zone
		(layer "In1.Cu")
		(hatch none 0.5)
		(connect_pads
			(clearance 0)
		)
		(min_thickness 0.25)
		(keepout
			(tracks not_allowed)
			(vias allowed)
			(pads allowed)
			(copperpour not_allowed)
			(footprints allowed)
		)
		(placement
			(enabled no)
			(sheetname "")
		)
		(fill
			(thermal_gap 0.5)
			(thermal_bridge_width 0.5)
			(island_removal_mode 0)
		)
		(polygon
			(pts
				(xy 76.170282 -132.174742) (xy 76.170282 -133.978142) (xy 76.729082 -133.978142) (xy 76.729082 -132.174742)
			)
		)
	)
	(zone
		(layer "In1.Cu")
		(hatch none 0.5)
		(connect_pads
			(clearance 0)
		)
		(min_thickness 0.25)
		(keepout
			(tracks not_allowed)
			(vias allowed)
			(pads allowed)
			(copperpour not_allowed)
			(footprints allowed)
		)
		(placement
			(enabled no)
			(sheetname "")
		)
		(fill
			(thermal_gap 0.5)
			(thermal_bridge_width 0.5)
			(island_removal_mode 0)
		)
		(polygon
			(pts
				(xy 394.616686 -3.789172) (xy 395.924786 -3.789172) (xy 395.924786 -4.982972) (xy 394.616686 -4.982972)
			)
		)
	)
	(zone
		(layer "In1.Cu")
		(hatch none 0.5)
		(connect_pads
			(clearance 0)
		)
		(min_thickness 0.25)
		(keepout
			(tracks not_allowed)
			(vias allowed)
			(pads allowed)
			(copperpour not_allowed)
			(footprints allowed)
		)
		(placement
			(enabled no)
			(sheetname "")
		)
		(fill
			(thermal_gap 0.5)
			(thermal_bridge_width 0.5)
			(island_removal_mode 0)
		)
		(polygon
			(pts
				(xy 59.170062 -151.377142) (xy 59.170062 -153.180542) (xy 59.728862 -153.180542) (xy 59.728862 -151.377142)
			)
		)
	)
	(zone
		(layer "In1.Cu")
		(hatch none 0.5)
		(connect_pads
			(clearance 0)
		)
		(min_thickness 0.25)
		(keepout
			(tracks not_allowed)
			(vias allowed)
			(pads allowed)
			(copperpour not_allowed)
			(footprints allowed)
		)
		(placement
			(enabled no)
			(sheetname "")
		)
		(fill
			(thermal_gap 0.5)
			(thermal_bridge_width 0.5)
			(island_removal_mode 0)
		)
		(polygon
			(pts
				(xy 242.870482 -141.775942) (xy 242.870482 -143.579342) (xy 243.429282 -143.579342) (xy 243.429282 -141.775942)
			)
		)
	)
	(zone
		(layer "In1.Cu")
		(hatch none 0.5)
		(connect_pads
			(clearance 0)
		)
		(min_thickness 0.25)
		(keepout
			(tracks not_allowed)
			(vias allowed)
			(pads allowed)
			(copperpour not_allowed)
			(footprints allowed)
		)
		(placement
			(enabled no)
			(sheetname "")
		)
		(fill
			(thermal_gap 0.5)
			(thermal_bridge_width 0.5)
			(island_removal_mode 0)
		)
		(polygon
			(pts
				(xy 82.970116 -155.977082) (xy 82.970116 -157.780482) (xy 83.528916 -157.780482) (xy 83.528916 -155.977082)
			)
		)
	)
	(zone
		(layer "In1.Cu")
		(hatch none 0.5)
		(connect_pads
			(clearance 0)
		)
		(min_thickness 0.25)
		(keepout
			(tracks not_allowed)
			(vias allowed)
			(pads allowed)
			(copperpour not_allowed)
			(footprints allowed)
		)
		(placement
			(enabled no)
			(sheetname "")
		)
		(fill
			(thermal_gap 0.5)
			(thermal_bridge_width 0.5)
			(island_removal_mode 0)
		)
		(polygon
			(pts
				(xy 291.320474 -19.121882) (xy 291.320474 -20.925282) (xy 291.879274 -20.925282) (xy 291.879274 -19.121882)
			)
		)
	)
	(zone
		(layer "In1.Cu")
		(hatch none 0.5)
		(connect_pads
			(clearance 0)
		)
		(min_thickness 0.25)
		(keepout
			(tracks not_allowed)
			(vias allowed)
			(pads allowed)
			(copperpour not_allowed)
			(footprints allowed)
		)
		(placement
			(enabled no)
			(sheetname "")
		)
		(fill
			(thermal_gap 0.5)
			(thermal_bridge_width 0.5)
			(island_removal_mode 0)
		)
		(polygon
			(pts
				(xy 55.770018 -14.521942) (xy 55.770018 -16.325342) (xy 56.328818 -16.325342) (xy 56.328818 -14.521942)
			)
		)
	)
	(zone
		(layer "In1.Cu")
		(hatch none 0.5)
		(connect_pads
			(clearance 0)
		)
		(min_thickness 0.25)
		(keepout
			(tracks not_allowed)
			(vias allowed)
			(pads allowed)
			(copperpour not_allowed)
			(footprints allowed)
		)
		(placement
			(enabled no)
			(sheetname "")
		)
		(fill
			(thermal_gap 0.5)
			(thermal_bridge_width 0.5)
			(island_removal_mode 0)
		)
		(polygon
			(pts
				(xy 309.170324 -132.174742) (xy 309.170324 -133.978142) (xy 309.729124 -133.978142) (xy 309.729124 -132.174742)
			)
		)
	)
	(zone
		(layer "In1.Cu")
		(hatch none 0.5)
		(connect_pads
			(clearance 0)
		)
		(min_thickness 0.25)
		(keepout
			(tracks not_allowed)
			(vias allowed)
			(pads allowed)
			(copperpour not_allowed)
			(footprints allowed)
		)
		(placement
			(enabled no)
			(sheetname "")
		)
		(fill
			(thermal_gap 0.5)
			(thermal_bridge_width 0.5)
			(island_removal_mode 0)
		)
		(polygon
			(pts
				(xy 293.020496 -146.375882) (xy 293.020496 -148.179282) (xy 293.579296 -148.179282) (xy 293.579296 -146.375882)
			)
		)
	)
	(zone
		(layer "In1.Cu")
		(hatch none 0.5)
		(connect_pads
			(clearance 0)
		)
		(min_thickness 0.25)
		(keepout
			(tracks not_allowed)
			(vias allowed)
			(pads allowed)
			(copperpour not_allowed)
			(footprints allowed)
		)
		(placement
			(enabled no)
			(sheetname "")
		)
		(fill
			(thermal_gap 0.5)
			(thermal_bridge_width 0.5)
			(island_removal_mode 0)
		)
		(polygon
			(pts
				(xy 239.470438 -151.377142) (xy 239.470438 -153.180542) (xy 240.029238 -153.180542) (xy 240.029238 -151.377142)
			)
		)
	)
	(zone
		(layer "In1.Cu")
		(hatch none 0.5)
		(connect_pads
			(clearance 0)
		)
		(min_thickness 0.25)
		(keepout
			(tracks not_allowed)
			(vias allowed)
			(pads allowed)
			(copperpour not_allowed)
			(footprints allowed)
		)
		(placement
			(enabled no)
			(sheetname "")
		)
		(fill
			(thermal_gap 0.5)
			(thermal_bridge_width 0.5)
			(island_removal_mode 0)
		)
		(polygon
			(pts
				(xy 13.6398 -22.987) (xy 15.0368 -22.987) (xy 15.0368 -23.495) (xy 13.6398 -23.495)
			)
		)
	)
	(zone
		(layer "In1.Cu")
		(hatch none 0.5)
		(connect_pads
			(clearance 0)
		)
		(min_thickness 0.25)
		(keepout
			(tracks not_allowed)
			(vias allowed)
			(pads allowed)
			(copperpour not_allowed)
			(footprints allowed)
		)
		(placement
			(enabled no)
			(sheetname "")
		)
		(fill
			(thermal_gap 0.5)
			(thermal_bridge_width 0.5)
			(island_removal_mode 0)
		)
		(polygon
			(pts
				(xy 364.431072 -7.193026) (xy 365.739172 -7.193026) (xy 365.739172 -8.386826) (xy 364.431072 -8.386826)
			)
		)
	)
	(zone
		(layer "In1.Cu")
		(hatch none 0.5)
		(connect_pads
			(clearance 0)
		)
		(min_thickness 0.25)
		(keepout
			(tracks not_allowed)
			(vias allowed)
			(pads allowed)
			(copperpour not_allowed)
			(footprints allowed)
		)
		(placement
			(enabled no)
			(sheetname "")
		)
		(fill
			(thermal_gap 0.5)
			(thermal_bridge_width 0.5)
			(island_removal_mode 0)
		)
		(polygon
			(pts
				(xy 207.170528 -4.920742) (xy 207.170528 -6.724142) (xy 207.729328 -6.724142) (xy 207.729328 -4.920742)
			)
		)
	)
	(zone
		(layer "In1.Cu")
		(hatch none 0.5)
		(connect_pads
			(clearance 0)
		)
		(min_thickness 0.25)
		(keepout
			(tracks not_allowed)
			(vias allowed)
			(pads allowed)
			(copperpour not_allowed)
			(footprints allowed)
		)
		(placement
			(enabled no)
			(sheetname "")
		)
		(fill
			(thermal_gap 0.5)
			(thermal_bridge_width 0.5)
			(island_removal_mode 0)
		)
		(polygon
			(pts
				(xy 309.170324 -141.775942) (xy 309.170324 -143.579342) (xy 309.729124 -143.579342) (xy 309.729124 -141.775942)
			)
		)
	)
	(zone
		(layer "In1.Cu")
		(hatch none 0.5)
		(connect_pads
			(clearance 0)
		)
		(min_thickness 0.25)
		(keepout
			(tracks not_allowed)
			(vias allowed)
			(pads allowed)
			(copperpour not_allowed)
			(footprints allowed)
		)
		(placement
			(enabled no)
			(sheetname "")
		)
		(fill
			(thermal_gap 0.5)
			(thermal_bridge_width 0.5)
			(island_removal_mode 0)
		)
		(polygon
			(pts
				(xy 73.620122 -146.375882) (xy 73.620122 -148.179282) (xy 74.178922 -148.179282) (xy 74.178922 -146.375882)
			)
		)
	)
	(zone
		(layer "In1.Cu")
		(hatch none 0.5)
		(connect_pads
			(clearance 0)
		)
		(min_thickness 0.25)
		(keepout
			(tracks not_allowed)
			(vias allowed)
			(pads allowed)
			(copperpour not_allowed)
			(footprints allowed)
		)
		(placement
			(enabled no)
			(sheetname "")
		)
		(fill
			(thermal_gap 0.5)
			(thermal_bridge_width 0.5)
			(island_removal_mode 0)
		)
		(polygon
			(pts
				(xy 196.120512 -151.377142) (xy 196.120512 -153.180542) (xy 196.679312 -153.180542) (xy 196.679312 -151.377142)
			)
		)
	)
	(zone
		(layer "In1.Cu")
		(hatch none 0.5)
		(connect_pads
			(clearance 0)
		)
		(min_thickness 0.25)
		(keepout
			(tracks not_allowed)
			(vias allowed)
			(pads allowed)
			(copperpour not_allowed)
			(footprints allowed)
		)
		(placement
			(enabled no)
			(sheetname "")
		)
		(fill
			(thermal_gap 0.5)
			(thermal_bridge_width 0.5)
			(island_removal_mode 0)
		)
		(polygon
			(pts
				(xy 13.6398 -25.654) (xy 15.0368 -25.654) (xy 15.0368 -26.162) (xy 13.6398 -26.162)
			)
		)
	)
	(zone
		(layer "In1.Cu")
		(hatch none 0.5)
		(connect_pads
			(clearance 0)
		)
		(min_thickness 0.25)
		(keepout
			(tracks not_allowed)
			(vias allowed)
			(pads allowed)
			(copperpour not_allowed)
			(footprints allowed)
		)
		(placement
			(enabled no)
			(sheetname "")
		)
		(fill
			(thermal_gap 0.5)
			(thermal_bridge_width 0.5)
			(island_removal_mode 0)
		)
		(polygon
			(pts
				(xy 84.670138 -19.121882) (xy 84.670138 -20.925282) (xy 85.228938 -20.925282) (xy 85.228938 -19.121882)
			)
		)
	)
	(zone
		(layer "In1.Cu")
		(hatch none 0.5)
		(connect_pads
			(clearance 0)
		)
		(min_thickness 0.25)
		(keepout
			(tracks not_allowed)
			(vias allowed)
			(pads allowed)
			(copperpour not_allowed)
			(footprints allowed)
		)
		(placement
			(enabled no)
			(sheetname "")
		)
		(fill
			(thermal_gap 0.5)
			(thermal_bridge_width 0.5)
			(island_removal_mode 0)
		)
		(polygon
			(pts
				(xy 31.12008 -4.920742) (xy 31.12008 -6.724142) (xy 31.67888 -6.724142) (xy 31.67888 -4.920742)
			)
		)
	)
	(zone
		(layer "In1.Cu")
		(hatch none 0.5)
		(connect_pads
			(clearance 0)
		)
		(min_thickness 0.25)
		(keepout
			(tracks not_allowed)
			(vias allowed)
			(pads allowed)
			(copperpour not_allowed)
			(footprints allowed)
		)
		(placement
			(enabled no)
			(sheetname "")
		)
		(fill
			(thermal_gap 0.5)
			(thermal_bridge_width 0.5)
			(island_removal_mode 0)
		)
		(polygon
			(pts
				(xy 421.019986 -3.789172) (xy 422.328086 -3.789172) (xy 422.328086 -4.982972) (xy 421.019986 -4.982972)
			)
		)
	)
	(zone
		(layer "In1.Cu")
		(hatch none 0.5)
		(connect_pads
			(clearance 0)
		)
		(min_thickness 0.25)
		(keepout
			(tracks not_allowed)
			(vias allowed)
			(pads allowed)
			(copperpour not_allowed)
			(footprints allowed)
		)
		(placement
			(enabled no)
			(sheetname "")
		)
		(fill
			(thermal_gap 0.5)
			(thermal_bridge_width 0.5)
			(island_removal_mode 0)
		)
		(polygon
			(pts
				(xy 195.270374 -19.121882) (xy 195.270374 -20.925282) (xy 195.829174 -20.925282) (xy 195.829174 -19.121882)
			)
		)
	)
	(zone
		(layer "In1.Cu")
		(hatch none 0.5)
		(connect_pads
			(clearance 0)
		)
		(min_thickness 0.25)
		(keepout
			(tracks not_allowed)
			(vias allowed)
			(pads allowed)
			(copperpour not_allowed)
			(footprints allowed)
		)
		(placement
			(enabled no)
			(sheetname "")
		)
		(fill
			(thermal_gap 0.5)
			(thermal_bridge_width 0.5)
			(island_removal_mode 0)
		)
		(polygon
			(pts
				(xy 120.370092 -14.521942) (xy 120.370092 -16.325342) (xy 120.928892 -16.325342) (xy 120.928892 -14.521942)
			)
		)
	)
	(zone
		(layer "In1.Cu")
		(hatch none 0.5)
		(connect_pads
			(clearance 0)
		)
		(min_thickness 0.25)
		(keepout
			(tracks not_allowed)
			(vias allowed)
			(pads allowed)
			(copperpour not_allowed)
			(footprints allowed)
		)
		(placement
			(enabled no)
			(sheetname "")
		)
		(fill
			(thermal_gap 0.5)
			(thermal_bridge_width 0.5)
			(island_removal_mode 0)
		)
		(polygon
			(pts
				(xy 40.470074 -132.174742) (xy 40.470074 -133.978142) (xy 41.028874 -133.978142) (xy 41.028874 -132.174742)
			)
		)
	)
	(zone
		(layer "In1.Cu")
		(hatch none 0.5)
		(connect_pads
			(clearance 0)
		)
		(min_thickness 0.25)
		(keepout
			(tracks not_allowed)
			(vias allowed)
			(pads allowed)
			(copperpour not_allowed)
			(footprints allowed)
		)
		(placement
			(enabled no)
			(sheetname "")
		)
		(fill
			(thermal_gap 0.5)
			(thermal_bridge_width 0.5)
			(island_removal_mode 0)
		)
		(polygon
			(pts
				(xy 288.770314 4.680458) (xy 288.770314 2.877058) (xy 289.329114 2.877058) (xy 289.329114 4.680458)
			)
		)
	)
	(zone
		(layer "In1.Cu")
		(hatch none 0.5)
		(connect_pads
			(clearance 0)
		)
		(min_thickness 0.25)
		(keepout
			(tracks not_allowed)
			(vias allowed)
			(pads allowed)
			(copperpour not_allowed)
			(footprints allowed)
		)
		(placement
			(enabled no)
			(sheetname "")
		)
		(fill
			(thermal_gap 0.5)
			(thermal_bridge_width 0.5)
			(island_removal_mode 0)
		)
		(polygon
			(pts
				(xy 305.770534 -151.377142) (xy 305.770534 -153.180542) (xy 306.329334 -153.180542) (xy 306.329334 -151.377142)
			)
		)
	)
	(zone
		(layer "In1.Cu")
		(hatch none 0.5)
		(connect_pads
			(clearance 0)
		)
		(min_thickness 0.25)
		(keepout
			(tracks not_allowed)
			(vias allowed)
			(pads allowed)
			(copperpour not_allowed)
			(footprints allowed)
		)
		(placement
			(enabled no)
			(sheetname "")
		)
		(fill
			(thermal_gap 0.5)
			(thermal_bridge_width 0.5)
			(island_removal_mode 0)
		)
		(polygon
			(pts
				(xy 56.620156 -146.375882) (xy 56.620156 -148.179282) (xy 57.178956 -148.179282) (xy 57.178956 -146.375882)
			)
		)
	)
	(zone
		(layer "In1.Cu")
		(hatch none 0.5)
		(connect_pads
			(clearance 0)
		)
		(min_thickness 0.25)
		(keepout
			(tracks not_allowed)
			(vias allowed)
			(pads allowed)
			(copperpour not_allowed)
			(footprints allowed)
		)
		(placement
			(enabled no)
			(sheetname "")
		)
		(fill
			(thermal_gap 0.5)
			(thermal_bridge_width 0.5)
			(island_removal_mode 0)
		)
		(polygon
			(pts
				(xy 311.720484 4.680458) (xy 311.720484 2.877058) (xy 312.279284 2.877058) (xy 312.279284 4.680458)
			)
		)
	)
	(zone
		(layer "In1.Cu")
		(hatch none 0.5)
		(connect_pads
			(clearance 0)
		)
		(min_thickness 0.25)
		(keepout
			(tracks not_allowed)
			(vias allowed)
			(pads allowed)
			(copperpour not_allowed)
			(footprints allowed)
		)
		(placement
			(enabled no)
			(sheetname "")
		)
		(fill
			(thermal_gap 0.5)
			(thermal_bridge_width 0.5)
			(island_removal_mode 0)
		)
		(polygon
			(pts
				(xy 310.020462 0.080518) (xy 310.020462 -1.722882) (xy 310.579262 -1.722882) (xy 310.579262 0.080518)
			)
		)
	)
	(zone
		(layer "In1.Cu")
		(hatch none 0.5)
		(connect_pads
			(clearance 0)
		)
		(min_thickness 0.25)
		(keepout
			(tracks not_allowed)
			(vias allowed)
			(pads allowed)
			(copperpour not_allowed)
			(footprints allowed)
		)
		(placement
			(enabled no)
			(sheetname "")
		)
		(fill
			(thermal_gap 0.5)
			(thermal_bridge_width 0.5)
			(island_removal_mode 0)
		)
		(polygon
			(pts
				(xy 91.469972 4.680458) (xy 91.469972 2.877058) (xy 92.028772 2.877058) (xy 92.028772 4.680458)
			)
		)
	)
	(zone
		(layer "In1.Cu")
		(hatch none 0.5)
		(connect_pads
			(clearance 0)
		)
		(min_thickness 0.25)
		(keepout
			(tracks not_allowed)
			(vias allowed)
			(pads allowed)
			(copperpour not_allowed)
			(footprints allowed)
		)
		(placement
			(enabled no)
			(sheetname "")
		)
		(fill
			(thermal_gap 0.5)
			(thermal_bridge_width 0.5)
			(island_removal_mode 0)
		)
		(polygon
			(pts
				(xy 203.770484 4.680458) (xy 203.770484 2.877058) (xy 204.329284 2.877058) (xy 204.329284 4.680458)
			)
		)
	)
	(zone
		(layer "In1.Cu")
		(hatch none 0.5)
		(connect_pads
			(clearance 0)
		)
		(min_thickness 0.25)
		(keepout
			(tracks not_allowed)
			(vias allowed)
			(pads allowed)
			(copperpour not_allowed)
			(footprints allowed)
		)
		(placement
			(enabled no)
			(sheetname "")
		)
		(fill
			(thermal_gap 0.5)
			(thermal_bridge_width 0.5)
			(island_removal_mode 0)
		)
		(polygon
			(pts
				(xy 235.22051 -14.521942) (xy 235.22051 -16.325342) (xy 235.77931 -16.325342) (xy 235.77931 -14.521942)
			)
		)
	)
	(zone
		(layer "In1.Cu")
		(hatch none 0.5)
		(connect_pads
			(clearance 0)
		)
		(min_thickness 0.25)
		(keepout
			(tracks not_allowed)
			(vias allowed)
			(pads allowed)
			(copperpour not_allowed)
			(footprints allowed)
		)
		(placement
			(enabled no)
			(sheetname "")
		)
		(fill
			(thermal_gap 0.5)
			(thermal_bridge_width 0.5)
			(island_removal_mode 0)
		)
		(polygon
			(pts
				(xy 201.220578 -155.977082) (xy 201.220578 -157.780482) (xy 201.779378 -157.780482) (xy 201.779378 -155.977082)
			)
		)
	)
	(zone
		(layer "In1.Cu")
		(hatch none 0.5)
		(connect_pads
			(clearance 0)
		)
		(min_thickness 0.25)
		(keepout
			(tracks not_allowed)
			(vias allowed)
			(pads allowed)
			(copperpour not_allowed)
			(footprints allowed)
		)
		(placement
			(enabled no)
			(sheetname "")
		)
		(fill
			(thermal_gap 0.5)
			(thermal_bridge_width 0.5)
			(island_removal_mode 0)
		)
		(polygon
			(pts
				(xy 294.720518 -132.174742) (xy 294.720518 -133.978142) (xy 295.279318 -133.978142) (xy 295.279318 -132.174742)
			)
		)
	)
	(zone
		(layer "In1.Cu")
		(hatch none 0.5)
		(connect_pads
			(clearance 0)
		)
		(min_thickness 0.25)
		(keepout
			(tracks not_allowed)
			(vias allowed)
			(pads allowed)
			(copperpour not_allowed)
			(footprints allowed)
		)
		(placement
			(enabled no)
			(sheetname "")
		)
		(fill
			(thermal_gap 0.5)
			(thermal_bridge_width 0.5)
			(island_removal_mode 0)
		)
		(polygon
			(pts
				(xy 208.87055 -132.174742) (xy 208.87055 -133.978142) (xy 209.42935 -133.978142) (xy 209.42935 -132.174742)
			)
		)
	)
	(zone
		(layer "In1.Cu")
		(hatch none 0.5)
		(connect_pads
			(clearance 0)
		)
		(min_thickness 0.25)
		(keepout
			(tracks not_allowed)
			(vias allowed)
			(pads allowed)
			(copperpour not_allowed)
			(footprints allowed)
		)
		(placement
			(enabled no)
			(sheetname "")
		)
		(fill
			(thermal_gap 0.5)
			(thermal_bridge_width 0.5)
			(island_removal_mode 0)
		)
		(polygon
			(pts
				(xy 211.420456 -14.521942) (xy 211.420456 -16.325342) (xy 211.979256 -16.325342) (xy 211.979256 -14.521942)
			)
		)
	)
	(zone
		(layer "In1.Cu")
		(hatch none 0.5)
		(connect_pads
			(clearance 0)
		)
		(min_thickness 0.25)
		(keepout
			(tracks not_allowed)
			(vias allowed)
			(pads allowed)
			(copperpour not_allowed)
			(footprints allowed)
		)
		(placement
			(enabled no)
			(sheetname "")
		)
		(fill
			(thermal_gap 0.5)
			(thermal_bridge_width 0.5)
			(island_removal_mode 0)
		)
		(polygon
			(pts
				(xy 292.170358 -141.775942) (xy 292.170358 -143.579342) (xy 292.729158 -143.579342) (xy 292.729158 -141.775942)
			)
		)
	)
	(zone
		(layer "In1.Cu")
		(hatch none 0.5)
		(connect_pads
			(clearance 0)
		)
		(min_thickness 0.25)
		(keepout
			(tracks not_allowed)
			(vias allowed)
			(pads allowed)
			(copperpour not_allowed)
			(footprints allowed)
		)
		(placement
			(enabled no)
			(sheetname "")
		)
		(fill
			(thermal_gap 0.5)
			(thermal_bridge_width 0.5)
			(island_removal_mode 0)
		)
		(polygon
			(pts
				(xy 231.820466 4.680458) (xy 231.820466 2.877058) (xy 232.379266 2.877058) (xy 232.379266 4.680458)
			)
		)
	)
	(zone
		(layer "In1.Cu")
		(hatch none 0.5)
		(connect_pads
			(clearance 0)
		)
		(min_thickness 0.25)
		(keepout
			(tracks not_allowed)
			(vias allowed)
			(pads allowed)
			(copperpour not_allowed)
			(footprints allowed)
		)
		(placement
			(enabled no)
			(sheetname "")
		)
		(fill
			(thermal_gap 0.5)
			(thermal_bridge_width 0.5)
			(island_removal_mode 0)
		)
		(polygon
			(pts
				(xy 253.070614 -9.520682) (xy 253.070614 -11.324082) (xy 253.629414 -11.324082) (xy 253.629414 -9.520682)
			)
		)
	)
	(zone
		(layer "In1.Cu")
		(hatch none 0.5)
		(connect_pads
			(clearance 0)
		)
		(min_thickness 0.25)
		(keepout
			(tracks not_allowed)
			(vias allowed)
			(pads allowed)
			(copperpour not_allowed)
			(footprints allowed)
		)
		(placement
			(enabled no)
			(sheetname "")
		)
		(fill
			(thermal_gap 0.5)
			(thermal_bridge_width 0.5)
			(island_removal_mode 0)
		)
		(polygon
			(pts
				(xy 202.070462 -132.174742) (xy 202.070462 -133.978142) (xy 202.629262 -133.978142) (xy 202.629262 -132.174742)
			)
		)
	)
	(zone
		(layer "In1.Cu")
		(hatch none 0.5)
		(connect_pads
			(clearance 0)
		)
		(min_thickness 0.25)
		(keepout
			(tracks not_allowed)
			(vias allowed)
			(pads allowed)
			(copperpour not_allowed)
			(footprints allowed)
		)
		(placement
			(enabled no)
			(sheetname "")
		)
		(fill
			(thermal_gap 0.5)
			(thermal_bridge_width 0.5)
			(island_removal_mode 0)
		)
		(polygon
			(pts
				(xy 362.022644 -9.773158) (xy 362.530644 -9.773158) (xy 362.530644 -11.170158) (xy 362.022644 -11.170158)
			)
		)
	)
	(zone
		(layer "In1.Cu")
		(hatch none 0.5)
		(connect_pads
			(clearance 0)
		)
		(min_thickness 0.25)
		(keepout
			(tracks not_allowed)
			(vias allowed)
			(pads allowed)
			(copperpour not_allowed)
			(footprints allowed)
		)
		(placement
			(enabled no)
			(sheetname "")
		)
		(fill
			(thermal_gap 0.5)
			(thermal_bridge_width 0.5)
			(island_removal_mode 0)
		)
		(polygon
			(pts
				(xy 118.67007 0.080518) (xy 118.67007 -1.722882) (xy 119.22887 -1.722882) (xy 119.22887 0.080518)
			)
		)
	)
	(zone
		(layer "In1.Cu")
		(hatch none 0.5)
		(connect_pads
			(clearance 0)
		)
		(min_thickness 0.25)
		(keepout
			(tracks not_allowed)
			(vias allowed)
			(pads allowed)
			(copperpour not_allowed)
			(footprints allowed)
		)
		(placement
			(enabled no)
			(sheetname "")
		)
		(fill
			(thermal_gap 0.5)
			(thermal_bridge_width 0.5)
			(island_removal_mode 0)
		)
		(polygon
			(pts
				(xy 65.120012 4.680458) (xy 65.120012 2.877058) (xy 65.678812 2.877058) (xy 65.678812 4.680458)
			)
		)
	)
	(zone
		(layer "In1.Cu")
		(hatch none 0.5)
		(connect_pads
			(clearance 0)
		)
		(min_thickness 0.25)
		(keepout
			(tracks not_allowed)
			(vias allowed)
			(pads allowed)
			(copperpour not_allowed)
			(footprints allowed)
		)
		(placement
			(enabled no)
			(sheetname "")
		)
		(fill
			(thermal_gap 0.5)
			(thermal_bridge_width 0.5)
			(island_removal_mode 0)
		)
		(polygon
			(pts
				(xy 196.120512 -14.521942) (xy 196.120512 -16.325342) (xy 196.679312 -16.325342) (xy 196.679312 -14.521942)
			)
		)
	)
	(zone
		(layer "In1.Cu")
		(hatch none 0.5)
		(connect_pads
			(clearance 0)
		)
		(min_thickness 0.25)
		(keepout
			(tracks not_allowed)
			(vias allowed)
			(pads allowed)
			(copperpour not_allowed)
			(footprints allowed)
		)
		(placement
			(enabled no)
			(sheetname "")
		)
		(fill
			(thermal_gap 0.5)
			(thermal_bridge_width 0.5)
			(island_removal_mode 0)
		)
		(polygon
			(pts
				(xy 291.320474 -155.977082) (xy 291.320474 -157.780482) (xy 291.879274 -157.780482) (xy 291.879274 -155.977082)
			)
		)
	)
	(zone
		(layer "In1.Cu")
		(hatch none 0.5)
		(connect_pads
			(clearance 0)
		)
		(min_thickness 0.25)
		(keepout
			(tracks not_allowed)
			(vias allowed)
			(pads allowed)
			(copperpour not_allowed)
			(footprints allowed)
		)
		(placement
			(enabled no)
			(sheetname "")
		)
		(fill
			(thermal_gap 0.5)
			(thermal_bridge_width 0.5)
			(island_removal_mode 0)
		)
		(polygon
			(pts
				(xy 236.070394 -136.774682) (xy 236.070394 -138.578082) (xy 236.629194 -138.578082) (xy 236.629194 -136.774682)
			)
		)
	)
	(zone
		(layer "In1.Cu")
		(hatch none 0.5)
		(connect_pads
			(clearance 0)
		)
		(min_thickness 0.25)
		(keepout
			(tracks not_allowed)
			(vias allowed)
			(pads allowed)
			(copperpour not_allowed)
			(footprints allowed)
		)
		(placement
			(enabled no)
			(sheetname "")
		)
		(fill
			(thermal_gap 0.5)
			(thermal_bridge_width 0.5)
			(island_removal_mode 0)
		)
		(polygon
			(pts
				(xy 423.420286 -3.789172) (xy 424.728386 -3.789172) (xy 424.728386 -4.982972) (xy 423.420286 -4.982972)
			)
		)
	)
	(zone
		(layer "In1.Cu")
		(hatch none 0.5)
		(connect_pads
			(clearance 0)
		)
		(min_thickness 0.25)
		(keepout
			(tracks not_allowed)
			(vias allowed)
			(pads allowed)
			(copperpour not_allowed)
			(footprints allowed)
		)
		(placement
			(enabled no)
			(sheetname "")
		)
		(fill
			(thermal_gap 0.5)
			(thermal_bridge_width 0.5)
			(island_removal_mode 0)
		)
		(polygon
			(pts
				(xy 129.720086 -4.920742) (xy 129.720086 -6.724142) (xy 130.278886 -6.724142) (xy 130.278886 -4.920742)
			)
		)
	)
	(zone
		(layer "In1.Cu")
		(hatch none 0.5)
		(connect_pads
			(clearance 0)
		)
		(min_thickness 0.25)
		(keepout
			(tracks not_allowed)
			(vias allowed)
			(pads allowed)
			(copperpour not_allowed)
			(footprints allowed)
		)
		(placement
			(enabled no)
			(sheetname "")
		)
		(fill
			(thermal_gap 0.5)
			(thermal_bridge_width 0.5)
			(island_removal_mode 0)
		)
		(polygon
			(pts
				(xy 133.970014 -146.375882) (xy 133.970014 -148.179282) (xy 134.528814 -148.179282) (xy 134.528814 -146.375882)
			)
		)
	)
	(zone
		(layer "In1.Cu")
		(hatch none 0.5)
		(connect_pads
			(clearance 0)
		)
		(min_thickness 0.25)
		(keepout
			(tracks not_allowed)
			(vias allowed)
			(pads allowed)
			(copperpour not_allowed)
			(footprints allowed)
		)
		(placement
			(enabled no)
			(sheetname "")
		)
		(fill
			(thermal_gap 0.5)
			(thermal_bridge_width 0.5)
			(island_removal_mode 0)
		)
		(polygon
			(pts
				(xy 290.470336 4.680458) (xy 290.470336 2.877058) (xy 291.029136 2.877058) (xy 291.029136 4.680458)
			)
		)
	)
	(zone
		(layer "In1.Cu")
		(hatch none 0.5)
		(connect_pads
			(clearance 0)
		)
		(min_thickness 0.25)
		(keepout
			(tracks not_allowed)
			(vias allowed)
			(pads allowed)
			(copperpour not_allowed)
			(footprints allowed)
		)
		(placement
			(enabled no)
			(sheetname "")
		)
		(fill
			(thermal_gap 0.5)
			(thermal_bridge_width 0.5)
			(island_removal_mode 0)
		)
		(polygon
			(pts
				(xy 315.970412 -136.774682) (xy 315.970412 -138.578082) (xy 316.529212 -138.578082) (xy 316.529212 -136.774682)
			)
		)
	)
	(zone
		(layer "In1.Cu")
		(hatch none 0.5)
		(connect_pads
			(clearance 0)
		)
		(min_thickness 0.25)
		(keepout
			(tracks not_allowed)
			(vias allowed)
			(pads allowed)
			(copperpour not_allowed)
			(footprints allowed)
		)
		(placement
			(enabled no)
			(sheetname "")
		)
		(fill
			(thermal_gap 0.5)
			(thermal_bridge_width 0.5)
			(island_removal_mode 0)
		)
		(polygon
			(pts
				(xy 58.319924 -136.774682) (xy 58.319924 -138.578082) (xy 58.878724 -138.578082) (xy 58.878724 -136.774682)
			)
		)
	)
	(zone
		(layer "In1.Cu")
		(hatch none 0.5)
		(connect_pads
			(clearance 0)
		)
		(min_thickness 0.25)
		(keepout
			(tracks not_allowed)
			(vias allowed)
			(pads allowed)
			(copperpour not_allowed)
			(footprints allowed)
		)
		(placement
			(enabled no)
			(sheetname "")
		)
		(fill
			(thermal_gap 0.5)
			(thermal_bridge_width 0.5)
			(island_removal_mode 0)
		)
		(polygon
			(pts
				(xy 31.12008 -151.377142) (xy 31.12008 -153.180542) (xy 31.67888 -153.180542) (xy 31.67888 -151.377142)
			)
		)
	)
	(zone
		(layer "In1.Cu")
		(hatch none 0.5)
		(connect_pads
			(clearance 0)
		)
		(min_thickness 0.25)
		(keepout
			(tracks not_allowed)
			(vias allowed)
			(pads allowed)
			(copperpour not_allowed)
			(footprints allowed)
		)
		(placement
			(enabled no)
			(sheetname "")
		)
		(fill
			(thermal_gap 0.5)
			(thermal_bridge_width 0.5)
			(island_removal_mode 0)
		)
		(polygon
			(pts
				(xy 252.220476 -9.520682) (xy 252.220476 -11.324082) (xy 252.779276 -11.324082) (xy 252.779276 -9.520682)
			)
		)
	)
	(zone
		(layer "In1.Cu")
		(hatch none 0.5)
		(connect_pads
			(clearance 0)
		)
		(min_thickness 0.25)
		(keepout
			(tracks not_allowed)
			(vias allowed)
			(pads allowed)
			(copperpour not_allowed)
			(footprints allowed)
		)
		(placement
			(enabled no)
			(sheetname "")
		)
		(fill
			(thermal_gap 0.5)
			(thermal_bridge_width 0.5)
			(island_removal_mode 0)
		)
		(polygon
			(pts
				(xy 13.6398 -23.876) (xy 15.0368 -23.876) (xy 15.0368 -24.384) (xy 13.6398 -24.384)
			)
		)
	)
	(zone
		(layer "In1.Cu")
		(hatch none 0.5)
		(connect_pads
			(clearance 0)
		)
		(min_thickness 0.25)
		(keepout
			(tracks not_allowed)
			(vias allowed)
			(pads allowed)
			(copperpour not_allowed)
			(footprints allowed)
		)
		(placement
			(enabled no)
			(sheetname "")
		)
		(fill
			(thermal_gap 0.5)
			(thermal_bridge_width 0.5)
			(island_removal_mode 0)
		)
		(polygon
			(pts
				(xy 139.07008 -14.521942) (xy 139.07008 -16.325342) (xy 139.62888 -16.325342) (xy 139.62888 -14.521942)
			)
		)
	)
	(zone
		(layer "In1.Cu")
		(hatch none 0.5)
		(connect_pads
			(clearance 0)
		)
		(min_thickness 0.25)
		(keepout
			(tracks not_allowed)
			(vias allowed)
			(pads allowed)
			(copperpour not_allowed)
			(footprints allowed)
		)
		(placement
			(enabled no)
			(sheetname "")
		)
		(fill
			(thermal_gap 0.5)
			(thermal_bridge_width 0.5)
			(island_removal_mode 0)
		)
		(polygon
			(pts
				(xy 200.37044 0.080518) (xy 200.37044 -1.722882) (xy 200.92924 -1.722882) (xy 200.92924 0.080518)
			)
		)
	)
	(zone
		(layer "In1.Cu")
		(hatch none 0.5)
		(connect_pads
			(clearance 0)
		)
		(min_thickness 0.25)
		(keepout
			(tracks not_allowed)
			(vias allowed)
			(pads allowed)
			(copperpour not_allowed)
			(footprints allowed)
		)
		(placement
			(enabled no)
			(sheetname "")
		)
		(fill
			(thermal_gap 0.5)
			(thermal_bridge_width 0.5)
			(island_removal_mode 0)
		)
		(polygon
			(pts
				(xy 311.720484 0.080518) (xy 311.720484 -1.722882) (xy 312.279284 -1.722882) (xy 312.279284 0.080518)
			)
		)
	)
	(zone
		(layer "In1.Cu")
		(hatch none 0.5)
		(connect_pads
			(clearance 0)
		)
		(min_thickness 0.25)
		(keepout
			(tracks not_allowed)
			(vias allowed)
			(pads allowed)
			(copperpour not_allowed)
			(footprints allowed)
		)
		(placement
			(enabled no)
			(sheetname "")
		)
		(fill
			(thermal_gap 0.5)
			(thermal_bridge_width 0.5)
			(island_removal_mode 0)
		)
		(polygon
			(pts
				(xy 55.770018 -4.920742) (xy 55.770018 -6.724142) (xy 56.328818 -6.724142) (xy 56.328818 -4.920742)
			)
		)
	)
	(zone
		(layer "In1.Cu")
		(hatch none 0.5)
		(connect_pads
			(clearance 0)
		)
		(min_thickness 0.25)
		(keepout
			(tracks not_allowed)
			(vias allowed)
			(pads allowed)
			(copperpour not_allowed)
			(footprints allowed)
		)
		(placement
			(enabled no)
			(sheetname "")
		)
		(fill
			(thermal_gap 0.5)
			(thermal_bridge_width 0.5)
			(island_removal_mode 0)
		)
		(polygon
			(pts
				(xy 116.11991 4.680458) (xy 116.11991 2.877058) (xy 116.67871 2.877058) (xy 116.67871 4.680458)
			)
		)
	)
	(zone
		(layer "In1.Cu")
		(hatch none 0.5)
		(connect_pads
			(clearance 0)
		)
		(min_thickness 0.25)
		(keepout
			(tracks not_allowed)
			(vias allowed)
			(pads allowed)
			(copperpour not_allowed)
			(footprints allowed)
		)
		(placement
			(enabled no)
			(sheetname "")
		)
		(fill
			(thermal_gap 0.5)
			(thermal_bridge_width 0.5)
			(island_removal_mode 0)
		)
		(polygon
			(pts
				(xy 237.770416 -9.520682) (xy 237.770416 -11.324082) (xy 238.329216 -11.324082) (xy 238.329216 -9.520682)
			)
		)
	)
	(zone
		(layer "In1.Cu")
		(hatch none 0.5)
		(connect_pads
			(clearance 0)
		)
		(min_thickness 0.25)
		(keepout
			(tracks not_allowed)
			(vias allowed)
			(pads allowed)
			(copperpour not_allowed)
			(footprints allowed)
		)
		(placement
			(enabled no)
			(sheetname "")
		)
		(fill
			(thermal_gap 0.5)
			(thermal_bridge_width 0.5)
			(island_removal_mode 0)
		)
		(polygon
			(pts
				(xy 229.27056 -9.520682) (xy 229.27056 -11.324082) (xy 229.82936 -11.324082) (xy 229.82936 -9.520682)
			)
		)
	)
	(zone
		(layer "In1.Cu")
		(hatch none 0.5)
		(connect_pads
			(clearance 0)
		)
		(min_thickness 0.25)
		(keepout
			(tracks not_allowed)
			(vias allowed)
			(pads allowed)
			(copperpour not_allowed)
			(footprints allowed)
		)
		(placement
			(enabled no)
			(sheetname "")
		)
		(fill
			(thermal_gap 0.5)
			(thermal_bridge_width 0.5)
			(island_removal_mode 0)
		)
		(polygon
			(pts
				(xy 368.431064 -3.792982) (xy 369.739164 -3.792982) (xy 369.739164 -4.986782) (xy 368.431064 -4.986782)
			)
		)
	)
	(zone
		(layer "In1.Cu")
		(hatch none 0.5)
		(connect_pads
			(clearance 0)
		)
		(min_thickness 0.25)
		(keepout
			(tracks not_allowed)
			(vias allowed)
			(pads allowed)
			(copperpour not_allowed)
			(footprints allowed)
		)
		(placement
			(enabled no)
			(sheetname "")
		)
		(fill
			(thermal_gap 0.5)
			(thermal_bridge_width 0.5)
			(island_removal_mode 0)
		)
		(polygon
			(pts
				(xy 142.46987 -4.920742) (xy 142.46987 -6.724142) (xy 143.02867 -6.724142) (xy 143.02867 -4.920742)
			)
		)
	)
	(zone
		(layer "In1.Cu")
		(hatch none 0.5)
		(connect_pads
			(clearance 0)
		)
		(min_thickness 0.25)
		(keepout
			(tracks not_allowed)
			(vias allowed)
			(pads allowed)
			(copperpour not_allowed)
			(footprints allowed)
		)
		(placement
			(enabled no)
			(sheetname "")
		)
		(fill
			(thermal_gap 0.5)
			(thermal_bridge_width 0.5)
			(island_removal_mode 0)
		)
		(polygon
			(pts
				(xy 88.070182 0.080518) (xy 88.070182 -1.722882) (xy 88.628982 -1.722882) (xy 88.628982 0.080518)
			)
		)
	)
	(zone
		(layer "In1.Cu")
		(hatch none 0.5)
		(connect_pads
			(clearance 0)
		)
		(min_thickness 0.25)
		(keepout
			(tracks not_allowed)
			(vias allowed)
			(pads allowed)
			(copperpour not_allowed)
			(footprints allowed)
		)
		(placement
			(enabled no)
			(sheetname "")
		)
		(fill
			(thermal_gap 0.5)
			(thermal_bridge_width 0.5)
			(island_removal_mode 0)
		)
		(polygon
			(pts
				(xy 209.720434 4.680458) (xy 209.720434 2.877058) (xy 210.279234 2.877058) (xy 210.279234 4.680458)
			)
		)
	)
	(zone
		(layer "In1.Cu")
		(hatch none 0.5)
		(connect_pads
			(clearance 0)
		)
		(min_thickness 0.25)
		(keepout
			(tracks not_allowed)
			(vias allowed)
			(pads allowed)
			(copperpour not_allowed)
			(footprints allowed)
		)
		(placement
			(enabled no)
			(sheetname "")
		)
		(fill
			(thermal_gap 0.5)
			(thermal_bridge_width 0.5)
			(island_removal_mode 0)
		)
		(polygon
			(pts
				(xy 219.070428 -132.174742) (xy 219.070428 -133.978142) (xy 219.629228 -133.978142) (xy 219.629228 -132.174742)
			)
		)
	)
	(zone
		(layer "In1.Cu")
		(hatch none 0.5)
		(connect_pads
			(clearance 0)
		)
		(min_thickness 0.25)
		(keepout
			(tracks not_allowed)
			(vias allowed)
			(pads allowed)
			(copperpour not_allowed)
			(footprints allowed)
		)
		(placement
			(enabled no)
			(sheetname "")
		)
		(fill
			(thermal_gap 0.5)
			(thermal_bridge_width 0.5)
			(island_removal_mode 0)
		)
		(polygon
			(pts
				(xy 217.370406 -9.520682) (xy 217.370406 -11.324082) (xy 217.929206 -11.324082) (xy 217.929206 -9.520682)
			)
		)
	)
	(zone
		(layer "In1.Cu")
		(hatch none 0.5)
		(connect_pads
			(clearance 0)
		)
		(min_thickness 0.25)
		(keepout
			(tracks not_allowed)
			(vias allowed)
			(pads allowed)
			(copperpour not_allowed)
			(footprints allowed)
		)
		(placement
			(enabled no)
			(sheetname "")
		)
		(fill
			(thermal_gap 0.5)
			(thermal_bridge_width 0.5)
			(island_removal_mode 0)
		)
		(polygon
			(pts
				(xy 277.720552 -19.121882) (xy 277.720552 -20.925282) (xy 278.279352 -20.925282) (xy 278.279352 -19.121882)
			)
		)
	)
	(zone
		(layer "In1.Cu")
		(hatch none 0.5)
		(connect_pads
			(clearance 0)
		)
		(min_thickness 0.25)
		(keepout
			(tracks not_allowed)
			(vias allowed)
			(pads allowed)
			(copperpour not_allowed)
			(footprints allowed)
		)
		(placement
			(enabled no)
			(sheetname "")
		)
		(fill
			(thermal_gap 0.5)
			(thermal_bridge_width 0.5)
			(island_removal_mode 0)
		)
		(polygon
			(pts
				(xy 436.221886 -7.192772) (xy 437.529986 -7.192772) (xy 437.529986 -8.386572) (xy 436.221886 -8.386572)
			)
		)
	)
	(zone
		(layer "In1.Cu")
		(hatch none 0.5)
		(connect_pads
			(clearance 0)
		)
		(min_thickness 0.25)
		(keepout
			(tracks not_allowed)
			(vias allowed)
			(pads allowed)
			(copperpour not_allowed)
			(footprints allowed)
		)
		(placement
			(enabled no)
			(sheetname "")
		)
		(fill
			(thermal_gap 0.5)
			(thermal_bridge_width 0.5)
			(island_removal_mode 0)
		)
		(polygon
			(pts
				(xy 287.92043 -146.375882) (xy 287.92043 -148.179282) (xy 288.47923 -148.179282) (xy 288.47923 -146.375882)
			)
		)
	)
	(zone
		(layer "In1.Cu")
		(hatch none 0.5)
		(connect_pads
			(clearance 0)
		)
		(min_thickness 0.25)
		(keepout
			(tracks not_allowed)
			(vias allowed)
			(pads allowed)
			(copperpour not_allowed)
			(footprints allowed)
		)
		(placement
			(enabled no)
			(sheetname "")
		)
		(fill
			(thermal_gap 0.5)
			(thermal_bridge_width 0.5)
			(island_removal_mode 0)
		)
		(polygon
			(pts
				(xy 286.220408 -146.375882) (xy 286.220408 -148.179282) (xy 286.779208 -148.179282) (xy 286.779208 -146.375882)
			)
		)
	)
	(zone
		(layer "In1.Cu")
		(hatch none 0.5)
		(connect_pads
			(clearance 0)
		)
		(min_thickness 0.25)
		(keepout
			(tracks not_allowed)
			(vias allowed)
			(pads allowed)
			(copperpour not_allowed)
			(footprints allowed)
		)
		(placement
			(enabled no)
			(sheetname "")
		)
		(fill
			(thermal_gap 0.5)
			(thermal_bridge_width 0.5)
			(island_removal_mode 0)
		)
		(polygon
			(pts
				(xy 236.920532 -141.775942) (xy 236.920532 -143.579342) (xy 237.479332 -143.579342) (xy 237.479332 -141.775942)
			)
		)
	)
	(zone
		(layer "In1.Cu")
		(hatch none 0.5)
		(connect_pads
			(clearance 0)
		)
		(min_thickness 0.25)
		(keepout
			(tracks not_allowed)
			(vias allowed)
			(pads allowed)
			(copperpour not_allowed)
			(footprints allowed)
		)
		(placement
			(enabled no)
			(sheetname "")
		)
		(fill
			(thermal_gap 0.5)
			(thermal_bridge_width 0.5)
			(island_removal_mode 0)
		)
		(polygon
			(pts
				(xy 48.96993 -9.520682) (xy 48.96993 -11.324082) (xy 49.52873 -11.324082) (xy 49.52873 -9.520682)
			)
		)
	)
	(zone
		(layer "In1.Cu")
		(hatch none 0.5)
		(connect_pads
			(clearance 0)
		)
		(min_thickness 0.25)
		(keepout
			(tracks not_allowed)
			(vias allowed)
			(pads allowed)
			(copperpour not_allowed)
			(footprints allowed)
		)
		(placement
			(enabled no)
			(sheetname "")
		)
		(fill
			(thermal_gap 0.5)
			(thermal_bridge_width 0.5)
			(island_removal_mode 0)
		)
		(polygon
			(pts
				(xy 457.146914 -115.799362) (xy 458.455014 -115.799362) (xy 458.455014 -118.186962) (xy 457.146914 -118.186962)
			)
		)
	)
	(zone
		(layer "In1.Cu")
		(hatch none 0.5)
		(connect_pads
			(clearance 0)
		)
		(min_thickness 0.25)
		(keepout
			(tracks not_allowed)
			(vias allowed)
			(pads allowed)
			(copperpour not_allowed)
			(footprints allowed)
		)
		(placement
			(enabled no)
			(sheetname "")
		)
		(fill
			(thermal_gap 0.5)
			(thermal_bridge_width 0.5)
			(island_removal_mode 0)
		)
		(polygon
			(pts
				(xy 137.370058 -14.521942) (xy 137.370058 -16.325342) (xy 137.928858 -16.325342) (xy 137.928858 -14.521942)
			)
		)
	)
	(zone
		(layer "In1.Cu")
		(hatch none 0.5)
		(connect_pads
			(clearance 0)
		)
		(min_thickness 0.25)
		(keepout
			(tracks not_allowed)
			(vias allowed)
			(pads allowed)
			(copperpour not_allowed)
			(footprints allowed)
		)
		(placement
			(enabled no)
			(sheetname "")
		)
		(fill
			(thermal_gap 0.5)
			(thermal_bridge_width 0.5)
			(island_removal_mode 0)
		)
		(polygon
			(pts
				(xy 118.67007 -146.375882) (xy 118.67007 -148.179282) (xy 119.22887 -148.179282) (xy 119.22887 -146.375882)
			)
		)
	)
	(zone
		(layer "In1.Cu")
		(hatch none 0.5)
		(connect_pads
			(clearance 0)
		)
		(min_thickness 0.25)
		(keepout
			(tracks not_allowed)
			(vias allowed)
			(pads allowed)
			(copperpour not_allowed)
			(footprints allowed)
		)
		(placement
			(enabled no)
			(sheetname "")
		)
		(fill
			(thermal_gap 0.5)
			(thermal_bridge_width 0.5)
			(island_removal_mode 0)
		)
		(polygon
			(pts
				(xy 242.870482 -151.377142) (xy 242.870482 -153.180542) (xy 243.429282 -153.180542) (xy 243.429282 -151.377142)
			)
		)
	)
	(zone
		(layer "In1.Cu")
		(hatch none 0.5)
		(connect_pads
			(clearance 0)
		)
		(min_thickness 0.25)
		(keepout
			(tracks not_allowed)
			(vias allowed)
			(pads allowed)
			(copperpour not_allowed)
			(footprints allowed)
		)
		(placement
			(enabled no)
			(sheetname "")
		)
		(fill
			(thermal_gap 0.5)
			(thermal_bridge_width 0.5)
			(island_removal_mode 0)
		)
		(polygon
			(pts
				(xy 223.320356 -155.977082) (xy 223.320356 -157.780482) (xy 223.879156 -157.780482) (xy 223.879156 -155.977082)
			)
		)
	)
	(zone
		(layer "In1.Cu")
		(hatch none 0.5)
		(connect_pads
			(clearance 0)
		)
		(min_thickness 0.25)
		(keepout
			(tracks not_allowed)
			(vias allowed)
			(pads allowed)
			(copperpour not_allowed)
			(footprints allowed)
		)
		(placement
			(enabled no)
			(sheetname "")
		)
		(fill
			(thermal_gap 0.5)
			(thermal_bridge_width 0.5)
			(island_removal_mode 0)
		)
		(polygon
			(pts
				(xy 402.576792 -9.774936) (xy 403.084792 -9.774936) (xy 403.084792 -11.171936) (xy 402.576792 -11.171936)
			)
		)
	)
	(zone
		(layer "In1.Cu")
		(hatch none 0.5)
		(connect_pads
			(clearance 0)
		)
		(min_thickness 0.25)
		(keepout
			(tracks not_allowed)
			(vias allowed)
			(pads allowed)
			(copperpour not_allowed)
			(footprints allowed)
		)
		(placement
			(enabled no)
			(sheetname "")
		)
		(fill
			(thermal_gap 0.5)
			(thermal_bridge_width 0.5)
			(island_removal_mode 0)
		)
		(polygon
			(pts
				(xy 34.520124 -151.377142) (xy 34.520124 -153.180542) (xy 35.078924 -153.180542) (xy 35.078924 -151.377142)
			)
		)
	)
	(zone
		(layer "In1.Cu")
		(hatch none 0.5)
		(connect_pads
			(clearance 0)
		)
		(min_thickness 0.25)
		(keepout
			(tracks not_allowed)
			(vias allowed)
			(pads allowed)
			(copperpour not_allowed)
			(footprints allowed)
		)
		(placement
			(enabled no)
			(sheetname "")
		)
		(fill
			(thermal_gap 0.5)
			(thermal_bridge_width 0.5)
			(island_removal_mode 0)
		)
		(polygon
			(pts
				(xy 131.420108 -132.174742) (xy 131.420108 -133.978142) (xy 131.978908 -133.978142) (xy 131.978908 -132.174742)
			)
		)
	)
	(zone
		(layer "In1.Cu")
		(hatch none 0.5)
		(connect_pads
			(clearance 0)
		)
		(min_thickness 0.25)
		(keepout
			(tracks not_allowed)
			(vias allowed)
			(pads allowed)
			(copperpour not_allowed)
			(footprints allowed)
		)
		(placement
			(enabled no)
			(sheetname "")
		)
		(fill
			(thermal_gap 0.5)
			(thermal_bridge_width 0.5)
			(island_removal_mode 0)
		)
		(polygon
			(pts
				(xy 266.670536 -146.375882) (xy 266.670536 -148.179282) (xy 267.229336 -148.179282) (xy 267.229336 -146.375882)
			)
		)
	)
	(zone
		(layer "In1.Cu")
		(hatch none 0.5)
		(connect_pads
			(clearance 0)
		)
		(min_thickness 0.25)
		(keepout
			(tracks not_allowed)
			(vias allowed)
			(pads allowed)
			(copperpour not_allowed)
			(footprints allowed)
		)
		(placement
			(enabled no)
			(sheetname "")
		)
		(fill
			(thermal_gap 0.5)
			(thermal_bridge_width 0.5)
			(island_removal_mode 0)
		)
		(polygon
			(pts
				(xy 233.520488 4.680458) (xy 233.520488 2.877058) (xy 234.079288 2.877058) (xy 234.079288 4.680458)
			)
		)
	)
	(zone
		(layer "In1.Cu")
		(hatch none 0.5)
		(connect_pads
			(clearance 0)
		)
		(min_thickness 0.25)
		(keepout
			(tracks not_allowed)
			(vias allowed)
			(pads allowed)
			(copperpour not_allowed)
			(footprints allowed)
		)
		(placement
			(enabled no)
			(sheetname "")
		)
		(fill
			(thermal_gap 0.5)
			(thermal_bridge_width 0.5)
			(island_removal_mode 0)
		)
		(polygon
			(pts
				(xy 49.820068 -132.174742) (xy 49.820068 -133.978142) (xy 50.378868 -133.978142) (xy 50.378868 -132.174742)
			)
		)
	)
	(zone
		(layer "In1.Cu")
		(hatch none 0.5)
		(connect_pads
			(clearance 0)
		)
		(min_thickness 0.25)
		(keepout
			(tracks not_allowed)
			(vias allowed)
			(pads allowed)
			(copperpour not_allowed)
			(footprints allowed)
		)
		(placement
			(enabled no)
			(sheetname "")
		)
		(fill
			(thermal_gap 0.5)
			(thermal_bridge_width 0.5)
			(island_removal_mode 0)
		)
		(polygon
			(pts
				(xy 121.219976 -9.520682) (xy 121.219976 -11.324082) (xy 121.778776 -11.324082) (xy 121.778776 -9.520682)
			)
		)
	)
	(zone
		(layer "In1.Cu")
		(hatch none 0.5)
		(connect_pads
			(clearance 0)
		)
		(min_thickness 0.25)
		(keepout
			(tracks not_allowed)
			(vias allowed)
			(pads allowed)
			(copperpour not_allowed)
			(footprints allowed)
		)
		(placement
			(enabled no)
			(sheetname "")
		)
		(fill
			(thermal_gap 0.5)
			(thermal_bridge_width 0.5)
			(island_removal_mode 0)
		)
		(polygon
			(pts
				(xy 225.870516 -4.920742) (xy 225.870516 -6.724142) (xy 226.429316 -6.724142) (xy 226.429316 -4.920742)
			)
		)
	)
	(zone
		(layer "In1.Cu")
		(hatch none 0.5)
		(connect_pads
			(clearance 0)
		)
		(min_thickness 0.25)
		(keepout
			(tracks not_allowed)
			(vias allowed)
			(pads allowed)
			(copperpour not_allowed)
			(footprints allowed)
		)
		(placement
			(enabled no)
			(sheetname "")
		)
		(fill
			(thermal_gap 0.5)
			(thermal_bridge_width 0.5)
			(island_removal_mode 0)
		)
		(polygon
			(pts
				(xy 242.020852 -19.121882) (xy 242.020852 -20.925282) (xy 242.579652 -20.925282) (xy 242.579652 -19.121882)
			)
		)
	)
	(zone
		(layer "In1.Cu")
		(hatch none 0.5)
		(connect_pads
			(clearance 0)
		)
		(min_thickness 0.25)
		(keepout
			(tracks not_allowed)
			(vias allowed)
			(pads allowed)
			(copperpour not_allowed)
			(footprints allowed)
		)
		(placement
			(enabled no)
			(sheetname "")
		)
		(fill
			(thermal_gap 0.5)
			(thermal_bridge_width 0.5)
			(island_removal_mode 0)
		)
		(polygon
			(pts
				(xy 119.519954 -136.774682) (xy 119.519954 -138.578082) (xy 120.078754 -138.578082) (xy 120.078754 -136.774682)
			)
		)
	)
	(zone
		(layer "In1.Cu")
		(hatch none 0.5)
		(connect_pads
			(clearance 0)
		)
		(min_thickness 0.25)
		(keepout
			(tracks not_allowed)
			(vias allowed)
			(pads allowed)
			(copperpour not_allowed)
			(footprints allowed)
		)
		(placement
			(enabled no)
			(sheetname "")
		)
		(fill
			(thermal_gap 0.5)
			(thermal_bridge_width 0.5)
			(island_removal_mode 0)
		)
		(polygon
			(pts
				(xy 222.470472 -141.775942) (xy 222.470472 -143.579342) (xy 223.029272 -143.579342) (xy 223.029272 -141.775942)
			)
		)
	)
	(zone
		(layer "In1.Cu")
		(hatch none 0.5)
		(connect_pads
			(clearance 0)
		)
		(min_thickness 0.25)
		(keepout
			(tracks not_allowed)
			(vias allowed)
			(pads allowed)
			(copperpour not_allowed)
			(footprints allowed)
		)
		(placement
			(enabled no)
			(sheetname "")
		)
		(fill
			(thermal_gap 0.5)
			(thermal_bridge_width 0.5)
			(island_removal_mode 0)
		)
		(polygon
			(pts
				(xy 297.270424 -146.375882) (xy 297.270424 -148.179282) (xy 297.829224 -148.179282) (xy 297.829224 -146.375882)
			)
		)
	)
	(zone
		(layer "In1.Cu")
		(hatch none 0.5)
		(connect_pads
			(clearance 0)
		)
		(min_thickness 0.25)
		(keepout
			(tracks not_allowed)
			(vias allowed)
			(pads allowed)
			(copperpour not_allowed)
			(footprints allowed)
		)
		(placement
			(enabled no)
			(sheetname "")
		)
		(fill
			(thermal_gap 0.5)
			(thermal_bridge_width 0.5)
			(island_removal_mode 0)
		)
		(polygon
			(pts
				(xy 252.220476 -4.920742) (xy 252.220476 -6.724142) (xy 252.779276 -6.724142) (xy 252.779276 -4.920742)
			)
		)
	)
	(zone
		(layer "In1.Cu")
		(hatch none 0.5)
		(connect_pads
			(clearance 0)
		)
		(min_thickness 0.25)
		(keepout
			(tracks not_allowed)
			(vias allowed)
			(pads allowed)
			(copperpour not_allowed)
			(footprints allowed)
		)
		(placement
			(enabled no)
			(sheetname "")
		)
		(fill
			(thermal_gap 0.5)
			(thermal_bridge_width 0.5)
			(island_removal_mode 0)
		)
		(polygon
			(pts
				(xy 81.270094 -151.377142) (xy 81.270094 -153.180542) (xy 81.828894 -153.180542) (xy 81.828894 -151.377142)
			)
		)
	)
	(zone
		(layer "In1.Cu")
		(hatch none 0.5)
		(connect_pads
			(clearance 0)
		)
		(min_thickness 0.25)
		(keepout
			(tracks not_allowed)
			(vias allowed)
			(pads allowed)
			(copperpour not_allowed)
			(footprints allowed)
		)
		(placement
			(enabled no)
			(sheetname "")
		)
		(fill
			(thermal_gap 0.5)
			(thermal_bridge_width 0.5)
			(island_removal_mode 0)
		)
		(polygon
			(pts
				(xy 31.12008 -141.775942) (xy 31.12008 -143.579342) (xy 31.67888 -143.579342) (xy 31.67888 -141.775942)
			)
		)
	)
	(zone
		(layer "In1.Cu")
		(hatch none 0.5)
		(connect_pads
			(clearance 0)
		)
		(min_thickness 0.25)
		(keepout
			(tracks not_allowed)
			(vias allowed)
			(pads allowed)
			(copperpour not_allowed)
			(footprints allowed)
		)
		(placement
			(enabled no)
			(sheetname "")
		)
		(fill
			(thermal_gap 0.5)
			(thermal_bridge_width 0.5)
			(island_removal_mode 0)
		)
		(polygon
			(pts
				(xy 65.97015 -19.121882) (xy 65.97015 -20.925282) (xy 66.52895 -20.925282) (xy 66.52895 -19.121882)
			)
		)
	)
	(zone
		(layer "In1.Cu")
		(hatch none 0.5)
		(connect_pads
			(clearance 0)
		)
		(min_thickness 0.25)
		(keepout
			(tracks not_allowed)
			(vias allowed)
			(pads allowed)
			(copperpour not_allowed)
			(footprints allowed)
		)
		(placement
			(enabled no)
			(sheetname "")
		)
		(fill
			(thermal_gap 0.5)
			(thermal_bridge_width 0.5)
			(island_removal_mode 0)
		)
		(polygon
			(pts
				(xy 64.270128 -146.375882) (xy 64.270128 -148.179282) (xy 64.828928 -148.179282) (xy 64.828928 -146.375882)
			)
		)
	)
	(zone
		(layer "In1.Cu")
		(hatch none 0.5)
		(connect_pads
			(clearance 0)
		)
		(min_thickness 0.25)
		(keepout
			(tracks not_allowed)
			(vias allowed)
			(pads allowed)
			(copperpour not_allowed)
			(footprints allowed)
		)
		(placement
			(enabled no)
			(sheetname "")
		)
		(fill
			(thermal_gap 0.5)
			(thermal_bridge_width 0.5)
			(island_removal_mode 0)
		)
		(polygon
			(pts
				(xy 295.570402 0.080518) (xy 295.570402 -1.722882) (xy 296.129202 -1.722882) (xy 296.129202 0.080518)
			)
		)
	)
	(zone
		(layer "In1.Cu")
		(hatch none 0.5)
		(connect_pads
			(clearance 0)
		)
		(min_thickness 0.25)
		(keepout
			(tracks not_allowed)
			(vias allowed)
			(pads allowed)
			(copperpour not_allowed)
			(footprints allowed)
		)
		(placement
			(enabled no)
			(sheetname "")
		)
		(fill
			(thermal_gap 0.5)
			(thermal_bridge_width 0.5)
			(island_removal_mode 0)
		)
		(polygon
			(pts
				(xy 66.820034 -132.174742) (xy 66.820034 -133.978142) (xy 67.378834 -133.978142) (xy 67.378834 -132.174742)
			)
		)
	)
	(zone
		(layer "In1.Cu")
		(hatch none 0.5)
		(connect_pads
			(clearance 0)
		)
		(min_thickness 0.25)
		(keepout
			(tracks not_allowed)
			(vias allowed)
			(pads allowed)
			(copperpour not_allowed)
			(footprints allowed)
		)
		(placement
			(enabled no)
			(sheetname "")
		)
		(fill
			(thermal_gap 0.5)
			(thermal_bridge_width 0.5)
			(island_removal_mode 0)
		)
		(polygon
			(pts
				(xy 102.519988 -19.121882) (xy 103.078788 -19.121882) (xy 103.078788 -20.925282) (xy 102.519988 -20.925282)
			)
		)
	)
	(zone
		(layer "In1.Cu")
		(hatch none 0.5)
		(connect_pads
			(clearance 0)
		)
		(min_thickness 0.25)
		(keepout
			(tracks not_allowed)
			(vias allowed)
			(pads allowed)
			(copperpour not_allowed)
			(footprints allowed)
		)
		(placement
			(enabled no)
			(sheetname "")
		)
		(fill
			(thermal_gap 0.5)
			(thermal_bridge_width 0.5)
			(island_removal_mode 0)
		)
		(polygon
			(pts
				(xy 274.320508 4.680458) (xy 274.320508 2.877058) (xy 274.879308 2.877058) (xy 274.879308 4.680458)
			)
		)
	)
	(zone
		(layer "In1.Cu")
		(hatch none 0.5)
		(connect_pads
			(clearance 0)
		)
		(min_thickness 0.25)
		(keepout
			(tracks not_allowed)
			(vias allowed)
			(pads allowed)
			(copperpour not_allowed)
			(footprints allowed)
		)
		(placement
			(enabled no)
			(sheetname "")
		)
		(fill
			(thermal_gap 0.5)
			(thermal_bridge_width 0.5)
			(island_removal_mode 0)
		)
		(polygon
			(pts
				(xy 54.069996 4.680458) (xy 54.069996 2.877058) (xy 54.628796 2.877058) (xy 54.628796 4.680458)
			)
		)
	)
	(zone
		(layer "In1.Cu")
		(hatch none 0.5)
		(connect_pads
			(clearance 0)
		)
		(min_thickness 0.25)
		(keepout
			(tracks not_allowed)
			(vias allowed)
			(pads allowed)
			(copperpour not_allowed)
			(footprints allowed)
		)
		(placement
			(enabled no)
			(sheetname "")
		)
		(fill
			(thermal_gap 0.5)
			(thermal_bridge_width 0.5)
			(island_removal_mode 0)
		)
		(polygon
			(pts
				(xy 82.119978 -19.121882) (xy 82.678778 -19.121882) (xy 82.678778 -20.925282) (xy 82.119978 -20.925282)
			)
		)
	)
	(zone
		(layer "In1.Cu")
		(hatch none 0.5)
		(connect_pads
			(clearance 0)
		)
		(min_thickness 0.25)
		(keepout
			(tracks not_allowed)
			(vias allowed)
			(pads allowed)
			(copperpour not_allowed)
			(footprints allowed)
		)
		(placement
			(enabled no)
			(sheetname "")
		)
		(fill
			(thermal_gap 0.5)
			(thermal_bridge_width 0.5)
			(island_removal_mode 0)
		)
		(polygon
			(pts
				(xy 128.020064 -4.920742) (xy 128.020064 -6.724142) (xy 128.578864 -6.724142) (xy 128.578864 -4.920742)
			)
		)
	)
	(zone
		(layer "In1.Cu")
		(hatch none 0.5)
		(connect_pads
			(clearance 0)
		)
		(min_thickness 0.25)
		(keepout
			(tracks not_allowed)
			(vias allowed)
			(pads allowed)
			(copperpour not_allowed)
			(footprints allowed)
		)
		(placement
			(enabled no)
			(sheetname "")
		)
		(fill
			(thermal_gap 0.5)
			(thermal_bridge_width 0.5)
			(island_removal_mode 0)
		)
		(polygon
			(pts
				(xy 221.620588 -155.977082) (xy 221.620588 -157.780482) (xy 222.179388 -157.780482) (xy 222.179388 -155.977082)
			)
		)
	)
	(zone
		(layer "In1.Cu")
		(hatch none 0.5)
		(connect_pads
			(clearance 0)
		)
		(min_thickness 0.25)
		(keepout
			(tracks not_allowed)
			(vias allowed)
			(pads allowed)
			(copperpour not_allowed)
			(footprints allowed)
		)
		(placement
			(enabled no)
			(sheetname "")
		)
		(fill
			(thermal_gap 0.5)
			(thermal_bridge_width 0.5)
			(island_removal_mode 0)
		)
		(polygon
			(pts
				(xy 122.070114 -141.775942) (xy 122.070114 -143.579342) (xy 122.628914 -143.579342) (xy 122.628914 -141.775942)
			)
		)
	)
	(zone
		(layer "In1.Cu")
		(hatch none 0.5)
		(connect_pads
			(clearance 0)
		)
		(min_thickness 0.25)
		(keepout
			(tracks not_allowed)
			(vias allowed)
			(pads allowed)
			(copperpour not_allowed)
			(footprints allowed)
		)
		(placement
			(enabled no)
			(sheetname "")
		)
		(fill
			(thermal_gap 0.5)
			(thermal_bridge_width 0.5)
			(island_removal_mode 0)
		)
		(polygon
			(pts
				(xy 121.219976 -19.121882) (xy 121.219976 -20.925282) (xy 121.778776 -20.925282) (xy 121.778776 -19.121882)
			)
		)
	)
	(zone
		(layer "In1.Cu")
		(hatch none 0.5)
		(connect_pads
			(clearance 0)
		)
		(min_thickness 0.25)
		(keepout
			(tracks not_allowed)
			(vias allowed)
			(pads allowed)
			(copperpour not_allowed)
			(footprints allowed)
		)
		(placement
			(enabled no)
			(sheetname "")
		)
		(fill
			(thermal_gap 0.5)
			(thermal_bridge_width 0.5)
			(island_removal_mode 0)
		)
		(polygon
			(pts
				(xy 274.320508 -151.377142) (xy 274.320508 -153.180542) (xy 274.879308 -153.180542) (xy 274.879308 -151.377142)
			)
		)
	)
	(zone
		(layer "In1.Cu")
		(hatch none 0.5)
		(connect_pads
			(clearance 0)
		)
		(min_thickness 0.25)
		(keepout
			(tracks not_allowed)
			(vias allowed)
			(pads allowed)
			(copperpour not_allowed)
			(footprints allowed)
		)
		(placement
			(enabled no)
			(sheetname "")
		)
		(fill
			(thermal_gap 0.5)
			(thermal_bridge_width 0.5)
			(island_removal_mode 0)
		)
		(polygon
			(pts
				(xy 92.32011 -155.977082) (xy 92.32011 -157.780482) (xy 92.87891 -157.780482) (xy 92.87891 -155.977082)
			)
		)
	)
	(zone
		(layer "In1.Cu")
		(hatch none 0.5)
		(connect_pads
			(clearance 0)
		)
		(min_thickness 0.25)
		(keepout
			(tracks not_allowed)
			(vias allowed)
			(pads allowed)
			(copperpour not_allowed)
			(footprints allowed)
		)
		(placement
			(enabled no)
			(sheetname "")
		)
		(fill
			(thermal_gap 0.5)
			(thermal_bridge_width 0.5)
			(island_removal_mode 0)
		)
		(polygon
			(pts
				(xy 435.421786 -3.789172) (xy 436.729886 -3.789172) (xy 436.729886 -4.982972) (xy 435.421786 -4.982972)
			)
		)
	)
	(zone
		(layer "In1.Cu")
		(hatch none 0.5)
		(connect_pads
			(clearance 0)
		)
		(min_thickness 0.25)
		(keepout
			(tracks not_allowed)
			(vias allowed)
			(pads allowed)
			(copperpour not_allowed)
			(footprints allowed)
		)
		(placement
			(enabled no)
			(sheetname "")
		)
		(fill
			(thermal_gap 0.5)
			(thermal_bridge_width 0.5)
			(island_removal_mode 0)
		)
		(polygon
			(pts
				(xy 303.220374 -146.375882) (xy 303.220374 -148.179282) (xy 303.779174 -148.179282) (xy 303.779174 -146.375882)
			)
		)
	)
	(zone
		(layer "In1.Cu")
		(hatch none 0.5)
		(connect_pads
			(clearance 0)
		)
		(min_thickness 0.25)
		(keepout
			(tracks not_allowed)
			(vias allowed)
			(pads allowed)
			(copperpour not_allowed)
			(footprints allowed)
		)
		(placement
			(enabled no)
			(sheetname "")
		)
		(fill
			(thermal_gap 0.5)
			(thermal_bridge_width 0.5)
			(island_removal_mode 0)
		)
		(polygon
			(pts
				(xy 277.720552 -4.920742) (xy 277.720552 -6.724142) (xy 278.279352 -6.724142) (xy 278.279352 -4.920742)
			)
		)
	)
	(zone
		(layer "In1.Cu")
		(hatch none 0.5)
		(connect_pads
			(clearance 0)
		)
		(min_thickness 0.25)
		(keepout
			(tracks not_allowed)
			(vias allowed)
			(pads allowed)
			(copperpour not_allowed)
			(footprints allowed)
		)
		(placement
			(enabled no)
			(sheetname "")
		)
		(fill
			(thermal_gap 0.5)
			(thermal_bridge_width 0.5)
			(island_removal_mode 0)
		)
		(polygon
			(pts
				(xy 33.669986 -19.121882) (xy 33.669986 -20.925282) (xy 34.228786 -20.925282) (xy 34.228786 -19.121882)
			)
		)
	)
	(zone
		(layer "In1.Cu")
		(hatch none 0.5)
		(connect_pads
			(clearance 0)
		)
		(min_thickness 0.25)
		(keepout
			(tracks not_allowed)
			(vias allowed)
			(pads allowed)
			(copperpour not_allowed)
			(footprints allowed)
		)
		(placement
			(enabled no)
			(sheetname "")
		)
		(fill
			(thermal_gap 0.5)
			(thermal_bridge_width 0.5)
			(island_removal_mode 0)
		)
		(polygon
			(pts
				(xy 135.670036 -9.520682) (xy 135.670036 -11.324082) (xy 136.228836 -11.324082) (xy 136.228836 -9.520682)
			)
		)
	)
	(zone
		(layer "In1.Cu")
		(hatch none 0.5)
		(connect_pads
			(clearance 0)
		)
		(min_thickness 0.25)
		(keepout
			(tracks not_allowed)
			(vias allowed)
			(pads allowed)
			(copperpour not_allowed)
			(footprints allowed)
		)
		(placement
			(enabled no)
			(sheetname "")
		)
		(fill
			(thermal_gap 0.5)
			(thermal_bridge_width 0.5)
			(island_removal_mode 0)
		)
		(polygon
			(pts
				(xy 302.37049 4.680458) (xy 302.37049 2.877058) (xy 302.92929 2.877058) (xy 302.92929 4.680458)
			)
		)
	)
	(zone
		(layer "In1.Cu")
		(hatch none 0.5)
		(connect_pads
			(clearance 0)
		)
		(min_thickness 0.25)
		(keepout
			(tracks not_allowed)
			(vias allowed)
			(pads allowed)
			(copperpour not_allowed)
			(footprints allowed)
		)
		(placement
			(enabled no)
			(sheetname "")
		)
		(fill
			(thermal_gap 0.5)
			(thermal_bridge_width 0.5)
			(island_removal_mode 0)
		)
		(polygon
			(pts
				(xy 442.746892 -111.011716) (xy 444.054992 -111.011716) (xy 444.054992 -113.399316) (xy 442.746892 -113.399316)
			)
		)
	)
	(zone
		(layer "In1.Cu")
		(hatch none 0.5)
		(connect_pads
			(clearance 0)
		)
		(min_thickness 0.25)
		(keepout
			(tracks not_allowed)
			(vias allowed)
			(pads allowed)
			(copperpour not_allowed)
			(footprints allowed)
		)
		(placement
			(enabled no)
			(sheetname "")
		)
		(fill
			(thermal_gap 0.5)
			(thermal_bridge_width 0.5)
			(island_removal_mode 0)
		)
		(polygon
			(pts
				(xy 247.12041 0.080518) (xy 247.12041 -1.722882) (xy 247.67921 -1.722882) (xy 247.67921 0.080518)
			)
		)
	)
	(zone
		(layer "In1.Cu")
		(hatch none 0.5)
		(connect_pads
			(clearance 0)
		)
		(min_thickness 0.25)
		(keepout
			(tracks not_allowed)
			(vias allowed)
			(pads allowed)
			(copperpour not_allowed)
			(footprints allowed)
		)
		(placement
			(enabled no)
			(sheetname "")
		)
		(fill
			(thermal_gap 0.5)
			(thermal_bridge_width 0.5)
			(island_removal_mode 0)
		)
		(polygon
			(pts
				(xy 304.070512 -4.920742) (xy 304.070512 -6.724142) (xy 304.629312 -6.724142) (xy 304.629312 -4.920742)
			)
		)
	)
	(zone
		(layer "In1.Cu")
		(hatch none 0.5)
		(connect_pads
			(clearance 0)
		)
		(min_thickness 0.25)
		(keepout
			(tracks not_allowed)
			(vias allowed)
			(pads allowed)
			(copperpour not_allowed)
			(footprints allowed)
		)
		(placement
			(enabled no)
			(sheetname "")
		)
		(fill
			(thermal_gap 0.5)
			(thermal_bridge_width 0.5)
			(island_removal_mode 0)
		)
		(polygon
			(pts
				(xy 48.96993 -136.774682) (xy 48.96993 -138.578082) (xy 49.52873 -138.578082) (xy 49.52873 -136.774682)
			)
		)
	)
	(zone
		(layer "In1.Cu")
		(hatch none 0.5)
		(connect_pads
			(clearance 0)
		)
		(min_thickness 0.25)
		(keepout
			(tracks not_allowed)
			(vias allowed)
			(pads allowed)
			(copperpour not_allowed)
			(footprints allowed)
		)
		(placement
			(enabled no)
			(sheetname "")
		)
		(fill
			(thermal_gap 0.5)
			(thermal_bridge_width 0.5)
			(island_removal_mode 0)
		)
		(polygon
			(pts
				(xy 252.220476 4.680458) (xy 252.220476 2.877058) (xy 252.779276 2.877058) (xy 252.779276 4.680458)
			)
		)
	)
	(zone
		(layer "In1.Cu")
		(hatch none 0.5)
		(connect_pads
			(clearance 0)
		)
		(min_thickness 0.25)
		(keepout
			(tracks not_allowed)
			(vias allowed)
			(pads allowed)
			(copperpour not_allowed)
			(footprints allowed)
		)
		(placement
			(enabled no)
			(sheetname "")
		)
		(fill
			(thermal_gap 0.5)
			(thermal_bridge_width 0.5)
			(island_removal_mode 0)
		)
		(polygon
			(pts
				(xy 268.370558 4.680458) (xy 268.370558 2.877058) (xy 268.929358 2.877058) (xy 268.929358 4.680458)
			)
		)
	)
	(zone
		(layer "In1.Cu")
		(hatch none 0.5)
		(connect_pads
			(clearance 0)
		)
		(min_thickness 0.25)
		(keepout
			(tracks not_allowed)
			(vias allowed)
			(pads allowed)
			(copperpour not_allowed)
			(footprints allowed)
		)
		(placement
			(enabled no)
			(sheetname "")
		)
		(fill
			(thermal_gap 0.5)
			(thermal_bridge_width 0.5)
			(island_removal_mode 0)
		)
		(polygon
			(pts
				(xy 292.170358 -4.920742) (xy 292.170358 -6.724142) (xy 292.729158 -6.724142) (xy 292.729158 -4.920742)
			)
		)
	)
	(zone
		(layer "In1.Cu")
		(hatch none 0.5)
		(connect_pads
			(clearance 0)
		)
		(min_thickness 0.25)
		(keepout
			(tracks not_allowed)
			(vias allowed)
			(pads allowed)
			(copperpour not_allowed)
			(footprints allowed)
		)
		(placement
			(enabled no)
			(sheetname "")
		)
		(fill
			(thermal_gap 0.5)
			(thermal_bridge_width 0.5)
			(island_removal_mode 0)
		)
		(polygon
			(pts
				(xy 84.670138 -9.520682) (xy 84.670138 -11.324082) (xy 85.228938 -11.324082) (xy 85.228938 -9.520682)
			)
		)
	)
	(zone
		(layer "In1.Cu")
		(hatch none 0.5)
		(connect_pads
			(clearance 0)
		)
		(min_thickness 0.25)
		(keepout
			(tracks not_allowed)
			(vias allowed)
			(pads allowed)
			(copperpour not_allowed)
			(footprints allowed)
		)
		(placement
			(enabled no)
			(sheetname "")
		)
		(fill
			(thermal_gap 0.5)
			(thermal_bridge_width 0.5)
			(island_removal_mode 0)
		)
		(polygon
			(pts
				(xy 197.820534 -151.377142) (xy 197.820534 -153.180542) (xy 198.379334 -153.180542) (xy 198.379334 -151.377142)
			)
		)
	)
	(zone
		(layer "In1.Cu")
		(hatch none 0.5)
		(connect_pads
			(clearance 0)
		)
		(min_thickness 0.25)
		(keepout
			(tracks not_allowed)
			(vias allowed)
			(pads allowed)
			(copperpour not_allowed)
			(footprints allowed)
		)
		(placement
			(enabled no)
			(sheetname "")
		)
		(fill
			(thermal_gap 0.5)
			(thermal_bridge_width 0.5)
			(island_removal_mode 0)
		)
		(polygon
			(pts
				(xy 128.020064 -19.121882) (xy 128.020064 -20.925282) (xy 128.578864 -20.925282) (xy 128.578864 -19.121882)
			)
		)
	)
	(zone
		(layer "In1.Cu")
		(hatch none 0.5)
		(connect_pads
			(clearance 0)
		)
		(min_thickness 0.25)
		(keepout
			(tracks not_allowed)
			(vias allowed)
			(pads allowed)
			(copperpour not_allowed)
			(footprints allowed)
		)
		(placement
			(enabled no)
			(sheetname "")
		)
		(fill
			(thermal_gap 0.5)
			(thermal_bridge_width 0.5)
			(island_removal_mode 0)
		)
		(polygon
			(pts
				(xy 141.619986 -136.774682) (xy 141.619986 -138.578082) (xy 142.178786 -138.578082) (xy 142.178786 -136.774682)
			)
		)
	)
	(zone
		(layer "In1.Cu")
		(hatch none 0.5)
		(connect_pads
			(clearance 0)
		)
		(min_thickness 0.25)
		(keepout
			(tracks not_allowed)
			(vias allowed)
			(pads allowed)
			(copperpour not_allowed)
			(footprints allowed)
		)
		(placement
			(enabled no)
			(sheetname "")
		)
		(fill
			(thermal_gap 0.5)
			(thermal_bridge_width 0.5)
			(island_removal_mode 0)
		)
		(polygon
			(pts
				(xy 56.620156 -19.121882) (xy 56.620156 -20.925282) (xy 57.178956 -20.925282) (xy 57.178956 -19.121882)
			)
		)
	)
	(zone
		(layer "In1.Cu")
		(hatch none 0.5)
		(connect_pads
			(clearance 0)
		)
		(min_thickness 0.25)
		(keepout
			(tracks not_allowed)
			(vias allowed)
			(pads allowed)
			(copperpour not_allowed)
			(footprints allowed)
		)
		(placement
			(enabled no)
			(sheetname "")
		)
		(fill
			(thermal_gap 0.5)
			(thermal_bridge_width 0.5)
			(island_removal_mode 0)
		)
		(polygon
			(pts
				(xy 91.469972 -155.977082) (xy 91.469972 -157.780482) (xy 92.028772 -157.780482) (xy 92.028772 -155.977082)
			)
		)
	)
	(zone
		(layer "In1.Cu")
		(hatch none 0.5)
		(connect_pads
			(clearance 0)
		)
		(min_thickness 0.25)
		(keepout
			(tracks not_allowed)
			(vias allowed)
			(pads allowed)
			(copperpour not_allowed)
			(footprints allowed)
		)
		(placement
			(enabled no)
			(sheetname "")
		)
		(fill
			(thermal_gap 0.5)
			(thermal_bridge_width 0.5)
			(island_removal_mode 0)
		)
		(polygon
			(pts
				(xy 198.670418 -155.977082) (xy 198.670418 -157.780482) (xy 199.229218 -157.780482) (xy 199.229218 -155.977082)
			)
		)
	)
	(zone
		(layer "In1.Cu")
		(hatch none 0.5)
		(connect_pads
			(clearance 0)
		)
		(min_thickness 0.25)
		(keepout
			(tracks not_allowed)
			(vias allowed)
			(pads allowed)
			(copperpour not_allowed)
			(footprints allowed)
		)
		(placement
			(enabled no)
			(sheetname "")
		)
		(fill
			(thermal_gap 0.5)
			(thermal_bridge_width 0.5)
			(island_removal_mode 0)
		)
		(polygon
			(pts
				(xy 210.570572 -136.774682) (xy 210.570572 -138.578082) (xy 211.129372 -138.578082) (xy 211.129372 -136.774682)
			)
		)
	)
	(zone
		(layer "In1.Cu")
		(hatch none 0.5)
		(connect_pads
			(clearance 0)
		)
		(min_thickness 0.25)
		(keepout
			(tracks not_allowed)
			(vias allowed)
			(pads allowed)
			(copperpour not_allowed)
			(footprints allowed)
		)
		(placement
			(enabled no)
			(sheetname "")
		)
		(fill
			(thermal_gap 0.5)
			(thermal_bridge_width 0.5)
			(island_removal_mode 0)
		)
		(polygon
			(pts
				(xy 150.96998 -136.774682) (xy 150.96998 -138.578082) (xy 151.52878 -138.578082) (xy 151.52878 -136.774682)
			)
		)
	)
	(zone
		(layer "In1.Cu")
		(hatch none 0.5)
		(connect_pads
			(clearance 0)
		)
		(min_thickness 0.25)
		(keepout
			(tracks not_allowed)
			(vias allowed)
			(pads allowed)
			(copperpour not_allowed)
			(footprints allowed)
		)
		(placement
			(enabled no)
			(sheetname "")
		)
		(fill
			(thermal_gap 0.5)
			(thermal_bridge_width 0.5)
			(island_removal_mode 0)
		)
		(polygon
			(pts
				(xy 198.670418 0.080518) (xy 198.670418 -1.722882) (xy 199.229218 -1.722882) (xy 199.229218 0.080518)
			)
		)
	)
	(zone
		(layer "In1.Cu")
		(hatch none 0.5)
		(connect_pads
			(clearance 0)
		)
		(min_thickness 0.25)
		(keepout
			(tracks not_allowed)
			(vias allowed)
			(pads allowed)
			(copperpour not_allowed)
			(footprints allowed)
		)
		(placement
			(enabled no)
			(sheetname "")
		)
		(fill
			(thermal_gap 0.5)
			(thermal_bridge_width 0.5)
			(island_removal_mode 0)
		)
		(polygon
			(pts
				(xy 125.469904 -151.377142) (xy 125.469904 -153.180542) (xy 126.028704 -153.180542) (xy 126.028704 -151.377142)
			)
		)
	)
	(zone
		(layer "In1.Cu")
		(hatch none 0.5)
		(connect_pads
			(clearance 0)
		)
		(min_thickness 0.25)
		(keepout
			(tracks not_allowed)
			(vias allowed)
			(pads allowed)
			(copperpour not_allowed)
			(footprints allowed)
		)
		(placement
			(enabled no)
			(sheetname "")
		)
		(fill
			(thermal_gap 0.5)
			(thermal_bridge_width 0.5)
			(island_removal_mode 0)
		)
		(polygon
			(pts
				(xy 47.270162 -146.375882) (xy 47.270162 -148.179282) (xy 47.828962 -148.179282) (xy 47.828962 -146.375882)
			)
		)
	)
	(zone
		(layer "In1.Cu")
		(hatch none 0.5)
		(connect_pads
			(clearance 0)
		)
		(min_thickness 0.25)
		(keepout
			(tracks not_allowed)
			(vias allowed)
			(pads allowed)
			(copperpour not_allowed)
			(footprints allowed)
		)
		(placement
			(enabled no)
			(sheetname "")
		)
		(fill
			(thermal_gap 0.5)
			(thermal_bridge_width 0.5)
			(island_removal_mode 0)
		)
		(polygon
			(pts
				(xy 55.770018 -141.775942) (xy 55.770018 -143.579342) (xy 56.328818 -143.579342) (xy 56.328818 -141.775942)
			)
		)
	)
	(zone
		(layer "In1.Cu")
		(hatch none 0.5)
		(connect_pads
			(clearance 0)
		)
		(min_thickness 0.25)
		(keepout
			(tracks not_allowed)
			(vias allowed)
			(pads allowed)
			(copperpour not_allowed)
			(footprints allowed)
		)
		(placement
			(enabled no)
			(sheetname "")
		)
		(fill
			(thermal_gap 0.5)
			(thermal_bridge_width 0.5)
			(island_removal_mode 0)
		)
		(polygon
			(pts
				(xy 36.220146 0.080518) (xy 36.220146 -1.722882) (xy 36.778946 -1.722882) (xy 36.778946 0.080518)
			)
		)
	)
	(zone
		(layer "In1.Cu")
		(hatch none 0.5)
		(connect_pads
			(clearance 0)
		)
		(min_thickness 0.25)
		(keepout
			(tracks not_allowed)
			(vias allowed)
			(pads allowed)
			(copperpour not_allowed)
			(footprints allowed)
		)
		(placement
			(enabled no)
			(sheetname "")
		)
		(fill
			(thermal_gap 0.5)
			(thermal_bridge_width 0.5)
			(island_removal_mode 0)
		)
		(polygon
			(pts
				(xy 234.370372 -9.520682) (xy 234.370372 -11.324082) (xy 234.929172 -11.324082) (xy 234.929172 -9.520682)
			)
		)
	)
	(zone
		(layer "In1.Cu")
		(hatch none 0.5)
		(connect_pads
			(clearance 0)
		)
		(min_thickness 0.25)
		(keepout
			(tracks not_allowed)
			(vias allowed)
			(pads allowed)
			(copperpour not_allowed)
			(footprints allowed)
		)
		(placement
			(enabled no)
			(sheetname "")
		)
		(fill
			(thermal_gap 0.5)
			(thermal_bridge_width 0.5)
			(island_removal_mode 0)
		)
		(polygon
			(pts
				(xy 144.169892 -141.775942) (xy 144.169892 -143.579342) (xy 144.728692 -143.579342) (xy 144.728692 -141.775942)
			)
		)
	)
	(zone
		(layer "In1.Cu")
		(hatch none 0.5)
		(connect_pads
			(clearance 0)
		)
		(min_thickness 0.25)
		(keepout
			(tracks not_allowed)
			(vias allowed)
			(pads allowed)
			(copperpour not_allowed)
			(footprints allowed)
		)
		(placement
			(enabled no)
			(sheetname "")
		)
		(fill
			(thermal_gap 0.5)
			(thermal_bridge_width 0.5)
			(island_removal_mode 0)
		)
		(polygon
			(pts
				(xy 139.919964 -9.520682) (xy 139.919964 -11.324082) (xy 140.478764 -11.324082) (xy 140.478764 -9.520682)
			)
		)
	)
	(zone
		(layer "In1.Cu")
		(hatch none 0.5)
		(connect_pads
			(clearance 0)
		)
		(min_thickness 0.25)
		(keepout
			(tracks not_allowed)
			(vias allowed)
			(pads allowed)
			(copperpour not_allowed)
			(footprints allowed)
		)
		(placement
			(enabled no)
			(sheetname "")
		)
		(fill
			(thermal_gap 0.5)
			(thermal_bridge_width 0.5)
			(island_removal_mode 0)
		)
		(polygon
			(pts
				(xy 295.570402 -155.977082) (xy 295.570402 -157.780482) (xy 296.129202 -157.780482) (xy 296.129202 -155.977082)
			)
		)
	)
	(zone
		(layer "In1.Cu")
		(hatch none 0.5)
		(connect_pads
			(clearance 0)
		)
		(min_thickness 0.25)
		(keepout
			(tracks not_allowed)
			(vias allowed)
			(pads allowed)
			(copperpour not_allowed)
			(footprints allowed)
		)
		(placement
			(enabled no)
			(sheetname "")
		)
		(fill
			(thermal_gap 0.5)
			(thermal_bridge_width 0.5)
			(island_removal_mode 0)
		)
		(polygon
			(pts
				(xy 59.170062 4.680458) (xy 59.170062 2.877058) (xy 59.728862 2.877058) (xy 59.728862 4.680458)
			)
		)
	)
	(zone
		(layer "In1.Cu")
		(hatch none 0.5)
		(connect_pads
			(clearance 0)
		)
		(min_thickness 0.25)
		(keepout
			(tracks not_allowed)
			(vias allowed)
			(pads allowed)
			(copperpour not_allowed)
			(footprints allowed)
		)
		(placement
			(enabled no)
			(sheetname "")
		)
		(fill
			(thermal_gap 0.5)
			(thermal_bridge_width 0.5)
			(island_removal_mode 0)
		)
		(polygon
			(pts
				(xy 118.67007 -155.977082) (xy 118.67007 -157.780482) (xy 119.22887 -157.780482) (xy 119.22887 -155.977082)
			)
		)
	)
	(zone
		(layer "In1.Cu")
		(hatch none 0.5)
		(connect_pads
			(clearance 0)
		)
		(min_thickness 0.25)
		(keepout
			(tracks not_allowed)
			(vias allowed)
			(pads allowed)
			(copperpour not_allowed)
			(footprints allowed)
		)
		(placement
			(enabled no)
			(sheetname "")
		)
		(fill
			(thermal_gap 0.5)
			(thermal_bridge_width 0.5)
			(island_removal_mode 0)
		)
		(polygon
			(pts
				(xy 62.570106 -151.377142) (xy 62.570106 -153.180542) (xy 63.128906 -153.180542) (xy 63.128906 -151.377142)
			)
		)
	)
	(zone
		(layer "In1.Cu")
		(hatch none 0.5)
		(connect_pads
			(clearance 0)
		)
		(min_thickness 0.25)
		(keepout
			(tracks not_allowed)
			(vias allowed)
			(pads allowed)
			(copperpour not_allowed)
			(footprints allowed)
		)
		(placement
			(enabled no)
			(sheetname "")
		)
		(fill
			(thermal_gap 0.5)
			(thermal_bridge_width 0.5)
			(island_removal_mode 0)
		)
		(polygon
			(pts
				(xy 297.270424 -19.121882) (xy 297.270424 -20.925282) (xy 297.829224 -20.925282) (xy 297.829224 -19.121882)
			)
		)
	)
	(zone
		(layer "In1.Cu")
		(hatch none 0.5)
		(connect_pads
			(clearance 0)
		)
		(min_thickness 0.25)
		(keepout
			(tracks not_allowed)
			(vias allowed)
			(pads allowed)
			(copperpour not_allowed)
			(footprints allowed)
		)
		(placement
			(enabled no)
			(sheetname "")
		)
		(fill
			(thermal_gap 0.5)
			(thermal_bridge_width 0.5)
			(island_removal_mode 0)
		)
		(polygon
			(pts
				(xy 297.270424 -9.520682) (xy 297.270424 -11.324082) (xy 297.829224 -11.324082) (xy 297.829224 -9.520682)
			)
		)
	)
	(zone
		(layer "In1.Cu")
		(hatch none 0.5)
		(connect_pads
			(clearance 0)
		)
		(min_thickness 0.25)
		(keepout
			(tracks not_allowed)
			(vias allowed)
			(pads allowed)
			(copperpour not_allowed)
			(footprints allowed)
		)
		(placement
			(enabled no)
			(sheetname "")
		)
		(fill
			(thermal_gap 0.5)
			(thermal_bridge_width 0.5)
			(island_removal_mode 0)
		)
		(polygon
			(pts
				(xy 271.770602 -141.775942) (xy 271.770602 -143.579342) (xy 272.329402 -143.579342) (xy 272.329402 -141.775942)
			)
		)
	)
	(zone
		(layer "In1.Cu")
		(hatch none 0.5)
		(connect_pads
			(clearance 0)
		)
		(min_thickness 0.25)
		(keepout
			(tracks not_allowed)
			(vias allowed)
			(pads allowed)
			(copperpour not_allowed)
			(footprints allowed)
		)
		(placement
			(enabled no)
			(sheetname "")
		)
		(fill
			(thermal_gap 0.5)
			(thermal_bridge_width 0.5)
			(island_removal_mode 0)
		)
		(polygon
			(pts
				(xy 379.561344 -9.798558) (xy 380.069344 -9.798558) (xy 380.069344 -11.195558) (xy 379.561344 -11.195558)
			)
		)
	)
	(zone
		(layer "In1.Cu")
		(hatch none 0.5)
		(connect_pads
			(clearance 0)
		)
		(min_thickness 0.25)
		(keepout
			(tracks not_allowed)
			(vias allowed)
			(pads allowed)
			(copperpour not_allowed)
			(footprints allowed)
		)
		(placement
			(enabled no)
			(sheetname "")
		)
		(fill
			(thermal_gap 0.5)
			(thermal_bridge_width 0.5)
			(island_removal_mode 0)
		)
		(polygon
			(pts
				(xy 251.370592 -132.174742) (xy 251.370592 -133.978142) (xy 251.929392 -133.978142) (xy 251.929392 -132.174742)
			)
		)
	)
	(zone
		(layer "In1.Cu")
		(hatch none 0.5)
		(connect_pads
			(clearance 0)
		)
		(min_thickness 0.25)
		(keepout
			(tracks not_allowed)
			(vias allowed)
			(pads allowed)
			(copperpour not_allowed)
			(footprints allowed)
		)
		(placement
			(enabled no)
			(sheetname "")
		)
		(fill
			(thermal_gap 0.5)
			(thermal_bridge_width 0.5)
			(island_removal_mode 0)
		)
		(polygon
			(pts
				(xy 43.01998 -146.375882) (xy 43.01998 -148.179282) (xy 43.57878 -148.179282) (xy 43.57878 -146.375882)
			)
		)
	)
	(zone
		(layer "In1.Cu")
		(hatch none 0.5)
		(connect_pads
			(clearance 0)
		)
		(min_thickness 0.25)
		(keepout
			(tracks not_allowed)
			(vias allowed)
			(pads allowed)
			(copperpour not_allowed)
			(footprints allowed)
		)
		(placement
			(enabled no)
			(sheetname "")
		)
		(fill
			(thermal_gap 0.5)
			(thermal_bridge_width 0.5)
			(island_removal_mode 0)
		)
		(polygon
			(pts
				(xy 220.77045 -4.920742) (xy 220.77045 -6.724142) (xy 221.32925 -6.724142) (xy 221.32925 -4.920742)
			)
		)
	)
	(zone
		(layer "In1.Cu")
		(hatch none 0.5)
		(connect_pads
			(clearance 0)
		)
		(min_thickness 0.25)
		(keepout
			(tracks not_allowed)
			(vias allowed)
			(pads allowed)
			(copperpour not_allowed)
			(footprints allowed)
		)
		(placement
			(enabled no)
			(sheetname "")
		)
		(fill
			(thermal_gap 0.5)
			(thermal_bridge_width 0.5)
			(island_removal_mode 0)
		)
		(polygon
			(pts
				(xy 112.72012 -9.520682) (xy 112.72012 -11.324082) (xy 113.27892 -11.324082) (xy 113.27892 -9.520682)
			)
		)
	)
	(zone
		(layer "In1.Cu")
		(hatch none 0.5)
		(connect_pads
			(clearance 0)
		)
		(min_thickness 0.25)
		(keepout
			(tracks not_allowed)
			(vias allowed)
			(pads allowed)
			(copperpour not_allowed)
			(footprints allowed)
		)
		(placement
			(enabled no)
			(sheetname "")
		)
		(fill
			(thermal_gap 0.5)
			(thermal_bridge_width 0.5)
			(island_removal_mode 0)
		)
		(polygon
			(pts
				(xy 218.220544 -4.920742) (xy 218.220544 -6.724142) (xy 218.779344 -6.724142) (xy 218.779344 -4.920742)
			)
		)
	)
	(zone
		(layer "In1.Cu")
		(hatch none 0.5)
		(connect_pads
			(clearance 0)
		)
		(min_thickness 0.25)
		(keepout
			(tracks not_allowed)
			(vias allowed)
			(pads allowed)
			(copperpour not_allowed)
			(footprints allowed)
		)
		(placement
			(enabled no)
			(sheetname "")
		)
		(fill
			(thermal_gap 0.5)
			(thermal_bridge_width 0.5)
			(island_removal_mode 0)
		)
		(polygon
			(pts
				(xy 485.2416 -49.9999) (xy 485.7496 -49.9999) (xy 485.7496 -51.3969) (xy 485.2416 -51.3969)
			)
		)
	)
	(zone
		(layer "In1.Cu")
		(hatch none 0.5)
		(connect_pads
			(clearance 0)
		)
		(min_thickness 0.25)
		(keepout
			(tracks not_allowed)
			(vias allowed)
			(pads allowed)
			(copperpour not_allowed)
			(footprints allowed)
		)
		(placement
			(enabled no)
			(sheetname "")
		)
		(fill
			(thermal_gap 0.5)
			(thermal_bridge_width 0.5)
			(island_removal_mode 0)
		)
		(polygon
			(pts
				(xy 122.070114 -4.920742) (xy 122.070114 -6.724142) (xy 122.628914 -6.724142) (xy 122.628914 -4.920742)
			)
		)
	)
	(zone
		(layer "In1.Cu")
		(hatch none 0.5)
		(connect_pads
			(clearance 0)
		)
		(min_thickness 0.25)
		(keepout
			(tracks not_allowed)
			(vias allowed)
			(pads allowed)
			(copperpour not_allowed)
			(footprints allowed)
		)
		(placement
			(enabled no)
			(sheetname "")
		)
		(fill
			(thermal_gap 0.5)
			(thermal_bridge_width 0.5)
			(island_removal_mode 0)
		)
		(polygon
			(pts
				(xy 130.56997 0.080518) (xy 130.56997 -1.722882) (xy 131.12877 -1.722882) (xy 131.12877 0.080518)
			)
		)
	)
	(zone
		(layer "In1.Cu")
		(hatch none 0.5)
		(connect_pads
			(clearance 0)
		)
		(min_thickness 0.25)
		(keepout
			(tracks not_allowed)
			(vias allowed)
			(pads allowed)
			(copperpour not_allowed)
			(footprints allowed)
		)
		(placement
			(enabled no)
			(sheetname "")
		)
		(fill
			(thermal_gap 0.5)
			(thermal_bridge_width 0.5)
			(island_removal_mode 0)
		)
		(polygon
			(pts
				(xy 276.02053 -19.121882) (xy 276.02053 -20.925282) (xy 276.57933 -20.925282) (xy 276.57933 -19.121882)
			)
		)
	)
	(zone
		(layer "In1.Cu")
		(hatch none 0.5)
		(connect_pads
			(clearance 0)
		)
		(min_thickness 0.25)
		(keepout
			(tracks not_allowed)
			(vias allowed)
			(pads allowed)
			(copperpour not_allowed)
			(footprints allowed)
		)
		(placement
			(enabled no)
			(sheetname "")
		)
		(fill
			(thermal_gap 0.5)
			(thermal_bridge_width 0.5)
			(island_removal_mode 0)
		)
		(polygon
			(pts
				(xy 48.120046 -4.920742) (xy 48.120046 -6.724142) (xy 48.678846 -6.724142) (xy 48.678846 -4.920742)
			)
		)
	)
	(zone
		(layer "In1.Cu")
		(hatch none 0.5)
		(connect_pads
			(clearance 0)
		)
		(min_thickness 0.25)
		(keepout
			(tracks not_allowed)
			(vias allowed)
			(pads allowed)
			(copperpour not_allowed)
			(footprints allowed)
		)
		(placement
			(enabled no)
			(sheetname "")
		)
		(fill
			(thermal_gap 0.5)
			(thermal_bridge_width 0.5)
			(island_removal_mode 0)
		)
		(polygon
			(pts
				(xy 198.670418 -9.520682) (xy 198.670418 -11.324082) (xy 199.229218 -11.324082) (xy 199.229218 -9.520682)
			)
		)
	)
	(zone
		(layer "In1.Cu")
		(hatch none 0.5)
		(connect_pads
			(clearance 0)
		)
		(min_thickness 0.25)
		(keepout
			(tracks not_allowed)
			(vias allowed)
			(pads allowed)
			(copperpour not_allowed)
			(footprints allowed)
		)
		(placement
			(enabled no)
			(sheetname "")
		)
		(fill
			(thermal_gap 0.5)
			(thermal_bridge_width 0.5)
			(island_removal_mode 0)
		)
		(polygon
			(pts
				(xy 82.970116 -146.375882) (xy 82.970116 -148.179282) (xy 83.528916 -148.179282) (xy 83.528916 -146.375882)
			)
		)
	)
	(zone
		(layer "In1.Cu")
		(hatch none 0.5)
		(connect_pads
			(clearance 0)
		)
		(min_thickness 0.25)
		(keepout
			(tracks not_allowed)
			(vias allowed)
			(pads allowed)
			(copperpour not_allowed)
			(footprints allowed)
		)
		(placement
			(enabled no)
			(sheetname "")
		)
		(fill
			(thermal_gap 0.5)
			(thermal_bridge_width 0.5)
			(island_removal_mode 0)
		)
		(polygon
			(pts
				(xy 53.220112 -141.775942) (xy 53.220112 -143.579342) (xy 53.778912 -143.579342) (xy 53.778912 -141.775942)
			)
		)
	)
	(zone
		(layer "In1.Cu")
		(hatch none 0.5)
		(connect_pads
			(clearance 0)
		)
		(min_thickness 0.25)
		(keepout
			(tracks not_allowed)
			(vias allowed)
			(pads allowed)
			(copperpour not_allowed)
			(footprints allowed)
		)
		(placement
			(enabled no)
			(sheetname "")
		)
		(fill
			(thermal_gap 0.5)
			(thermal_bridge_width 0.5)
			(island_removal_mode 0)
		)
		(polygon
			(pts
				(xy 286.220408 -9.520682) (xy 286.220408 -11.324082) (xy 286.779208 -11.324082) (xy 286.779208 -9.520682)
			)
		)
	)
	(zone
		(layer "In1.Cu")
		(hatch none 0.5)
		(connect_pads
			(clearance 0)
		)
		(min_thickness 0.25)
		(keepout
			(tracks not_allowed)
			(vias allowed)
			(pads allowed)
			(copperpour not_allowed)
			(footprints allowed)
		)
		(placement
			(enabled no)
			(sheetname "")
		)
		(fill
			(thermal_gap 0.5)
			(thermal_bridge_width 0.5)
			(island_removal_mode 0)
		)
		(polygon
			(pts
				(xy 206.32039 -136.774682) (xy 206.32039 -138.578082) (xy 206.87919 -138.578082) (xy 206.87919 -136.774682)
			)
		)
	)
	(zone
		(layer "In1.Cu")
		(hatch none 0.5)
		(connect_pads
			(clearance 0)
		)
		(min_thickness 0.25)
		(keepout
			(tracks not_allowed)
			(vias allowed)
			(pads allowed)
			(copperpour not_allowed)
			(footprints allowed)
		)
		(placement
			(enabled no)
			(sheetname "")
		)
		(fill
			(thermal_gap 0.5)
			(thermal_bridge_width 0.5)
			(island_removal_mode 0)
		)
		(polygon
			(pts
				(xy 39.619936 -136.774682) (xy 39.619936 -138.578082) (xy 40.178736 -138.578082) (xy 40.178736 -136.774682)
			)
		)
	)
	(zone
		(layer "In1.Cu")
		(hatch none 0.5)
		(connect_pads
			(clearance 0)
		)
		(min_thickness 0.25)
		(keepout
			(tracks not_allowed)
			(vias allowed)
			(pads allowed)
			(copperpour not_allowed)
			(footprints allowed)
		)
		(placement
			(enabled no)
			(sheetname "")
		)
		(fill
			(thermal_gap 0.5)
			(thermal_bridge_width 0.5)
			(island_removal_mode 0)
		)
		(polygon
			(pts
				(xy 111.020098 4.680458) (xy 111.020098 2.877058) (xy 111.578898 2.877058) (xy 111.578898 4.680458)
			)
		)
	)
	(zone
		(layer "In1.Cu")
		(hatch none 0.5)
		(connect_pads
			(clearance 0)
		)
		(min_thickness 0.25)
		(keepout
			(tracks not_allowed)
			(vias allowed)
			(pads allowed)
			(copperpour not_allowed)
			(footprints allowed)
		)
		(placement
			(enabled no)
			(sheetname "")
		)
		(fill
			(thermal_gap 0.5)
			(thermal_bridge_width 0.5)
			(island_removal_mode 0)
		)
		(polygon
			(pts
				(xy 310.020462 -9.520682) (xy 310.020462 -11.324082) (xy 310.579262 -11.324082) (xy 310.579262 -9.520682)
			)
		)
	)
	(zone
		(layer "In1.Cu")
		(hatch none 0.5)
		(connect_pads
			(clearance 0)
		)
		(min_thickness 0.25)
		(keepout
			(tracks not_allowed)
			(vias allowed)
			(pads allowed)
			(copperpour not_allowed)
			(footprints allowed)
		)
		(placement
			(enabled no)
			(sheetname "")
		)
		(fill
			(thermal_gap 0.5)
			(thermal_bridge_width 0.5)
			(island_removal_mode 0)
		)
		(polygon
			(pts
				(xy 195.270374 -9.520682) (xy 195.270374 -11.324082) (xy 195.829174 -11.324082) (xy 195.829174 -9.520682)
			)
		)
	)
	(zone
		(layer "In1.Cu")
		(hatch none 0.5)
		(connect_pads
			(clearance 0)
		)
		(min_thickness 0.25)
		(keepout
			(tracks not_allowed)
			(vias allowed)
			(pads allowed)
			(copperpour not_allowed)
			(footprints allowed)
		)
		(placement
			(enabled no)
			(sheetname "")
		)
		(fill
			(thermal_gap 0.5)
			(thermal_bridge_width 0.5)
			(island_removal_mode 0)
		)
		(polygon
			(pts
				(xy 313.420506 -4.920742) (xy 313.420506 -6.724142) (xy 313.979306 -6.724142) (xy 313.979306 -4.920742)
			)
		)
	)
	(zone
		(layer "In1.Cu")
		(hatch none 0.5)
		(connect_pads
			(clearance 0)
		)
		(min_thickness 0.25)
		(keepout
			(tracks not_allowed)
			(vias allowed)
			(pads allowed)
			(copperpour not_allowed)
			(footprints allowed)
		)
		(placement
			(enabled no)
			(sheetname "")
		)
		(fill
			(thermal_gap 0.5)
			(thermal_bridge_width 0.5)
			(island_removal_mode 0)
		)
		(polygon
			(pts
				(xy 85.520022 0.080518) (xy 85.520022 -1.722882) (xy 86.078822 -1.722882) (xy 86.078822 0.080518)
			)
		)
	)
	(zone
		(layer "In1.Cu")
		(hatch none 0.5)
		(connect_pads
			(clearance 0)
		)
		(min_thickness 0.25)
		(keepout
			(tracks not_allowed)
			(vias allowed)
			(pads allowed)
			(copperpour not_allowed)
			(footprints allowed)
		)
		(placement
			(enabled no)
			(sheetname "")
		)
		(fill
			(thermal_gap 0.5)
			(thermal_bridge_width 0.5)
			(island_removal_mode 0)
		)
		(polygon
			(pts
				(xy 296.42054 -141.775942) (xy 296.42054 -143.579342) (xy 296.97934 -143.579342) (xy 296.97934 -141.775942)
			)
		)
	)
	(zone
		(layer "In1.Cu")
		(hatch none 0.5)
		(connect_pads
			(clearance 0)
		)
		(min_thickness 0.25)
		(keepout
			(tracks not_allowed)
			(vias allowed)
			(pads allowed)
			(copperpour not_allowed)
			(footprints allowed)
		)
		(placement
			(enabled no)
			(sheetname "")
		)
		(fill
			(thermal_gap 0.5)
			(thermal_bridge_width 0.5)
			(island_removal_mode 0)
		)
		(polygon
			(pts
				(xy 448.286886 -46.478698) (xy 449.594986 -46.478698) (xy 449.594986 -48.485298) (xy 448.286886 -48.485298)
			)
		)
	)
	(zone
		(layer "In1.Cu")
		(hatch none 0.5)
		(connect_pads
			(clearance 0)
		)
		(min_thickness 0.25)
		(keepout
			(tracks not_allowed)
			(vias allowed)
			(pads allowed)
			(copperpour not_allowed)
			(footprints allowed)
		)
		(placement
			(enabled no)
			(sheetname "")
		)
		(fill
			(thermal_gap 0.5)
			(thermal_bridge_width 0.5)
			(island_removal_mode 0)
		)
		(polygon
			(pts
				(xy 304.070512 -141.775942) (xy 304.070512 -143.579342) (xy 304.629312 -143.579342) (xy 304.629312 -141.775942)
			)
		)
	)
	(zone
		(layer "In1.Cu")
		(hatch none 0.5)
		(connect_pads
			(clearance 0)
		)
		(min_thickness 0.25)
		(keepout
			(tracks not_allowed)
			(vias allowed)
			(pads allowed)
			(copperpour not_allowed)
			(footprints allowed)
		)
		(placement
			(enabled no)
			(sheetname "")
		)
		(fill
			(thermal_gap 0.5)
			(thermal_bridge_width 0.5)
			(island_removal_mode 0)
		)
		(polygon
			(pts
				(xy 367.712244 -9.773158) (xy 368.220244 -9.773158) (xy 368.220244 -11.170158) (xy 367.712244 -11.170158)
			)
		)
	)
	(zone
		(layer "In1.Cu")
		(hatch none 0.5)
		(connect_pads
			(clearance 0)
		)
		(min_thickness 0.25)
		(keepout
			(tracks not_allowed)
			(vias allowed)
			(pads allowed)
			(copperpour not_allowed)
			(footprints allowed)
		)
		(placement
			(enabled no)
			(sheetname "")
		)
		(fill
			(thermal_gap 0.5)
			(thermal_bridge_width 0.5)
			(island_removal_mode 0)
		)
		(polygon
			(pts
				(xy 128.020064 -136.774682) (xy 128.020064 -138.578082) (xy 128.578864 -138.578082) (xy 128.578864 -136.774682)
			)
		)
	)
	(zone
		(layer "In1.Cu")
		(hatch none 0.5)
		(connect_pads
			(clearance 0)
		)
		(min_thickness 0.25)
		(keepout
			(tracks not_allowed)
			(vias allowed)
			(pads allowed)
			(copperpour not_allowed)
			(footprints allowed)
		)
		(placement
			(enabled no)
			(sheetname "")
		)
		(fill
			(thermal_gap 0.5)
			(thermal_bridge_width 0.5)
			(island_removal_mode 0)
		)
		(polygon
			(pts
				(xy 83.82 4.680458) (xy 83.82 2.877058) (xy 84.3788 2.877058) (xy 84.3788 4.680458)
			)
		)
	)
	(zone
		(layer "In1.Cu")
		(hatch none 0.5)
		(connect_pads
			(clearance 0)
		)
		(min_thickness 0.25)
		(keepout
			(tracks not_allowed)
			(vias allowed)
			(pads allowed)
			(copperpour not_allowed)
			(footprints allowed)
		)
		(placement
			(enabled no)
			(sheetname "")
		)
		(fill
			(thermal_gap 0.5)
			(thermal_bridge_width 0.5)
			(island_removal_mode 0)
		)
		(polygon
			(pts
				(xy 50.669952 -19.121882) (xy 50.669952 -20.925282) (xy 51.228752 -20.925282) (xy 51.228752 -19.121882)
			)
		)
	)
	(zone
		(layer "In1.Cu")
		(hatch none 0.5)
		(connect_pads
			(clearance 0)
		)
		(min_thickness 0.25)
		(keepout
			(tracks not_allowed)
			(vias allowed)
			(pads allowed)
			(copperpour not_allowed)
			(footprints allowed)
		)
		(placement
			(enabled no)
			(sheetname "")
		)
		(fill
			(thermal_gap 0.5)
			(thermal_bridge_width 0.5)
			(island_removal_mode 0)
		)
		(polygon
			(pts
				(xy 74.470006 -151.377142) (xy 74.470006 -153.180542) (xy 75.028806 -153.180542) (xy 75.028806 -151.377142)
			)
		)
	)
	(zone
		(layer "In1.Cu")
		(hatch none 0.5)
		(connect_pads
			(clearance 0)
		)
		(min_thickness 0.25)
		(keepout
			(tracks not_allowed)
			(vias allowed)
			(pads allowed)
			(copperpour not_allowed)
			(footprints allowed)
		)
		(placement
			(enabled no)
			(sheetname "")
		)
		(fill
			(thermal_gap 0.5)
			(thermal_bridge_width 0.5)
			(island_removal_mode 0)
		)
		(polygon
			(pts
				(xy 257.320542 -141.775942) (xy 257.320542 -143.579342) (xy 257.879342 -143.579342) (xy 257.879342 -141.775942)
			)
		)
	)
	(zone
		(layer "In1.Cu")
		(hatch none 0.5)
		(connect_pads
			(clearance 0)
		)
		(min_thickness 0.25)
		(keepout
			(tracks not_allowed)
			(vias allowed)
			(pads allowed)
			(copperpour not_allowed)
			(footprints allowed)
		)
		(placement
			(enabled no)
			(sheetname "")
		)
		(fill
			(thermal_gap 0.5)
			(thermal_bridge_width 0.5)
			(island_removal_mode 0)
		)
		(polygon
			(pts
				(xy 401.065492 -9.774936) (xy 401.573492 -9.774936) (xy 401.573492 -11.171936) (xy 401.065492 -11.171936)
			)
		)
	)
	(zone
		(layer "In1.Cu")
		(hatch none 0.5)
		(connect_pads
			(clearance 0)
		)
		(min_thickness 0.25)
		(keepout
			(tracks not_allowed)
			(vias allowed)
			(pads allowed)
			(copperpour not_allowed)
			(footprints allowed)
		)
		(placement
			(enabled no)
			(sheetname "")
		)
		(fill
			(thermal_gap 0.5)
			(thermal_bridge_width 0.5)
			(island_removal_mode 0)
		)
		(polygon
			(pts
				(xy 440.222386 -3.789172) (xy 441.530486 -3.789172) (xy 441.530486 -4.982972) (xy 440.222386 -4.982972)
			)
		)
	)
	(zone
		(layer "In1.Cu")
		(hatch none 0.5)
		(connect_pads
			(clearance 0)
		)
		(min_thickness 0.25)
		(keepout
			(tracks not_allowed)
			(vias allowed)
			(pads allowed)
			(copperpour not_allowed)
			(footprints allowed)
		)
		(placement
			(enabled no)
			(sheetname "")
		)
		(fill
			(thermal_gap 0.5)
			(thermal_bridge_width 0.5)
			(island_removal_mode 0)
		)
		(polygon
			(pts
				(xy 286.220408 -136.774682) (xy 286.220408 -138.578082) (xy 286.779208 -138.578082) (xy 286.779208 -136.774682)
			)
		)
	)
	(zone
		(layer "In1.Cu")
		(hatch none 0.5)
		(connect_pads
			(clearance 0)
		)
		(min_thickness 0.25)
		(keepout
			(tracks not_allowed)
			(vias allowed)
			(pads allowed)
			(copperpour not_allowed)
			(footprints allowed)
		)
		(placement
			(enabled no)
			(sheetname "")
		)
		(fill
			(thermal_gap 0.5)
			(thermal_bridge_width 0.5)
			(island_removal_mode 0)
		)
		(polygon
			(pts
				(xy 264.970514 -19.121882) (xy 264.970514 -20.925282) (xy 265.529314 -20.925282) (xy 265.529314 -19.121882)
			)
		)
	)
	(zone
		(layer "In1.Cu")
		(hatch none 0.5)
		(connect_pads
			(clearance 0)
		)
		(min_thickness 0.25)
		(keepout
			(tracks not_allowed)
			(vias allowed)
			(pads allowed)
			(copperpour not_allowed)
			(footprints allowed)
		)
		(placement
			(enabled no)
			(sheetname "")
		)
		(fill
			(thermal_gap 0.5)
			(thermal_bridge_width 0.5)
			(island_removal_mode 0)
		)
		(polygon
			(pts
				(xy 91.469972 0.080518) (xy 91.469972 -1.722882) (xy 92.028772 -1.722882) (xy 92.028772 0.080518)
			)
		)
	)
	(zone
		(layer "In1.Cu")
		(hatch none 0.5)
		(connect_pads
			(clearance 0)
		)
		(min_thickness 0.25)
		(keepout
			(tracks not_allowed)
			(vias allowed)
			(pads allowed)
			(copperpour not_allowed)
			(footprints allowed)
		)
		(placement
			(enabled no)
			(sheetname "")
		)
		(fill
			(thermal_gap 0.5)
			(thermal_bridge_width 0.5)
			(island_removal_mode 0)
		)
		(polygon
			(pts
				(xy 89.76995 -14.521942) (xy 89.76995 -16.325342) (xy 90.32875 -16.325342) (xy 90.32875 -14.521942)
			)
		)
	)
	(zone
		(layer "In1.Cu")
		(hatch none 0.5)
		(connect_pads
			(clearance 0)
		)
		(min_thickness 0.25)
		(keepout
			(tracks not_allowed)
			(vias allowed)
			(pads allowed)
			(copperpour not_allowed)
			(footprints allowed)
		)
		(placement
			(enabled no)
			(sheetname "")
		)
		(fill
			(thermal_gap 0.5)
			(thermal_bridge_width 0.5)
			(island_removal_mode 0)
		)
		(polygon
			(pts
				(xy 47.270162 -9.520682) (xy 47.270162 -11.324082) (xy 47.828962 -11.324082) (xy 47.828962 -9.520682)
			)
		)
	)
	(zone
		(layer "In1.Cu")
		(hatch none 0.5)
		(connect_pads
			(clearance 0)
		)
		(min_thickness 0.25)
		(keepout
			(tracks not_allowed)
			(vias allowed)
			(pads allowed)
			(copperpour not_allowed)
			(footprints allowed)
		)
		(placement
			(enabled no)
			(sheetname "")
		)
		(fill
			(thermal_gap 0.5)
			(thermal_bridge_width 0.5)
			(island_removal_mode 0)
		)
		(polygon
			(pts
				(xy 200.37044 -155.977082) (xy 200.37044 -157.780482) (xy 200.92924 -157.780482) (xy 200.92924 -155.977082)
			)
		)
	)
	(zone
		(layer "In1.Cu")
		(hatch none 0.5)
		(connect_pads
			(clearance 0)
		)
		(min_thickness 0.25)
		(keepout
			(tracks not_allowed)
			(vias allowed)
			(pads allowed)
			(copperpour not_allowed)
			(footprints allowed)
		)
		(placement
			(enabled no)
			(sheetname "")
		)
		(fill
			(thermal_gap 0.5)
			(thermal_bridge_width 0.5)
			(island_removal_mode 0)
		)
		(polygon
			(pts
				(xy 210.570572 -155.977082) (xy 210.570572 -157.780482) (xy 211.129372 -157.780482) (xy 211.129372 -155.977082)
			)
		)
	)
	(zone
		(layer "In1.Cu")
		(hatch none 0.5)
		(connect_pads
			(clearance 0)
		)
		(min_thickness 0.25)
		(keepout
			(tracks not_allowed)
			(vias allowed)
			(pads allowed)
			(copperpour not_allowed)
			(footprints allowed)
		)
		(placement
			(enabled no)
			(sheetname "")
		)
		(fill
			(thermal_gap 0.5)
			(thermal_bridge_width 0.5)
			(island_removal_mode 0)
		)
		(polygon
			(pts
				(xy 101.670104 -19.121882) (xy 102.228904 -19.121882) (xy 102.228904 -20.925282) (xy 101.670104 -20.925282)
			)
		)
	)
	(zone
		(layer "In1.Cu")
		(hatch none 0.5)
		(connect_pads
			(clearance 0)
		)
		(min_thickness 0.25)
		(keepout
			(tracks not_allowed)
			(vias allowed)
			(pads allowed)
			(copperpour not_allowed)
			(footprints allowed)
		)
		(placement
			(enabled no)
			(sheetname "")
		)
		(fill
			(thermal_gap 0.5)
			(thermal_bridge_width 0.5)
			(island_removal_mode 0)
		)
		(polygon
			(pts
				(xy 40.470074 -14.521942) (xy 40.470074 -16.325342) (xy 41.028874 -16.325342) (xy 41.028874 -14.521942)
			)
		)
	)
	(zone
		(layer "In1.Cu")
		(hatch none 0.5)
		(connect_pads
			(clearance 0)
		)
		(min_thickness 0.25)
		(keepout
			(tracks not_allowed)
			(vias allowed)
			(pads allowed)
			(copperpour not_allowed)
			(footprints allowed)
		)
		(placement
			(enabled no)
			(sheetname "")
		)
		(fill
			(thermal_gap 0.5)
			(thermal_bridge_width 0.5)
			(island_removal_mode 0)
		)
		(polygon
			(pts
				(xy 215.670384 -136.774682) (xy 215.670384 -138.578082) (xy 216.229184 -138.578082) (xy 216.229184 -136.774682)
			)
		)
	)
	(zone
		(layer "In1.Cu")
		(hatch none 0.5)
		(connect_pads
			(clearance 0)
		)
		(min_thickness 0.25)
		(keepout
			(tracks not_allowed)
			(vias allowed)
			(pads allowed)
			(copperpour not_allowed)
			(footprints allowed)
		)
		(placement
			(enabled no)
			(sheetname "")
		)
		(fill
			(thermal_gap 0.5)
			(thermal_bridge_width 0.5)
			(island_removal_mode 0)
		)
		(polygon
			(pts
				(xy 243.720366 0.080518) (xy 243.720366 -1.722882) (xy 244.279166 -1.722882) (xy 244.279166 0.080518)
			)
		)
	)
	(zone
		(layer "In1.Cu")
		(hatch none 0.5)
		(connect_pads
			(clearance 0)
		)
		(min_thickness 0.25)
		(keepout
			(tracks not_allowed)
			(vias allowed)
			(pads allowed)
			(copperpour not_allowed)
			(footprints allowed)
		)
		(placement
			(enabled no)
			(sheetname "")
		)
		(fill
			(thermal_gap 0.5)
			(thermal_bridge_width 0.5)
			(island_removal_mode 0)
		)
		(polygon
			(pts
				(xy 445.946784 -111.011716) (xy 447.254884 -111.011716) (xy 447.254884 -113.399316) (xy 445.946784 -113.399316)
			)
		)
	)
	(zone
		(layer "In1.Cu")
		(hatch none 0.5)
		(connect_pads
			(clearance 0)
		)
		(min_thickness 0.25)
		(keepout
			(tracks not_allowed)
			(vias allowed)
			(pads allowed)
			(copperpour not_allowed)
			(footprints allowed)
		)
		(placement
			(enabled no)
			(sheetname "")
		)
		(fill
			(thermal_gap 0.5)
			(thermal_bridge_width 0.5)
			(island_removal_mode 0)
		)
		(polygon
			(pts
				(xy 305.770534 4.680458) (xy 305.770534 2.877058) (xy 306.329334 2.877058) (xy 306.329334 4.680458)
			)
		)
	)
	(zone
		(layer "In1.Cu")
		(hatch none 0.5)
		(connect_pads
			(clearance 0)
		)
		(min_thickness 0.25)
		(keepout
			(tracks not_allowed)
			(vias allowed)
			(pads allowed)
			(copperpour not_allowed)
			(footprints allowed)
		)
		(placement
			(enabled no)
			(sheetname "")
		)
		(fill
			(thermal_gap 0.5)
			(thermal_bridge_width 0.5)
			(island_removal_mode 0)
		)
		(polygon
			(pts
				(xy 145.869914 4.680458) (xy 145.869914 2.877058) (xy 146.428714 2.877058) (xy 146.428714 4.680458)
			)
		)
	)
	(zone
		(layer "In1.Cu")
		(hatch none 0.5)
		(connect_pads
			(clearance 0)
		)
		(min_thickness 0.25)
		(keepout
			(tracks not_allowed)
			(vias allowed)
			(pads allowed)
			(copperpour not_allowed)
			(footprints allowed)
		)
		(placement
			(enabled no)
			(sheetname "")
		)
		(fill
			(thermal_gap 0.5)
			(thermal_bridge_width 0.5)
			(island_removal_mode 0)
		)
		(polygon
			(pts
				(xy 302.37049 0.080518) (xy 302.37049 -1.722882) (xy 302.92929 -1.722882) (xy 302.92929 0.080518)
			)
		)
	)
	(zone
		(layer "In1.Cu")
		(hatch none 0.5)
		(connect_pads
			(clearance 0)
		)
		(min_thickness 0.25)
		(keepout
			(tracks not_allowed)
			(vias allowed)
			(pads allowed)
			(copperpour not_allowed)
			(footprints allowed)
		)
		(placement
			(enabled no)
			(sheetname "")
		)
		(fill
			(thermal_gap 0.5)
			(thermal_bridge_width 0.5)
			(island_removal_mode 0)
		)
		(polygon
			(pts
				(xy 219.070428 -151.377142) (xy 219.070428 -153.180542) (xy 219.629228 -153.180542) (xy 219.629228 -151.377142)
			)
		)
	)
	(zone
		(layer "In1.Cu")
		(hatch none 0.5)
		(connect_pads
			(clearance 0)
		)
		(min_thickness 0.25)
		(keepout
			(tracks not_allowed)
			(vias allowed)
			(pads allowed)
			(copperpour not_allowed)
			(footprints allowed)
		)
		(placement
			(enabled no)
			(sheetname "")
		)
		(fill
			(thermal_gap 0.5)
			(thermal_bridge_width 0.5)
			(island_removal_mode 0)
		)
		(polygon
			(pts
				(xy 34.520124 -14.521942) (xy 34.520124 -16.325342) (xy 35.078924 -16.325342) (xy 35.078924 -14.521942)
			)
		)
	)
	(zone
		(layer "In1.Cu")
		(hatch none 0.5)
		(connect_pads
			(clearance 0)
		)
		(min_thickness 0.25)
		(keepout
			(tracks not_allowed)
			(vias allowed)
			(pads allowed)
			(copperpour not_allowed)
			(footprints allowed)
		)
		(placement
			(enabled no)
			(sheetname "")
		)
		(fill
			(thermal_gap 0.5)
			(thermal_bridge_width 0.5)
			(island_removal_mode 0)
		)
		(polygon
			(pts
				(xy 443.422786 -7.192772) (xy 444.730886 -7.192772) (xy 444.730886 -8.386572) (xy 443.422786 -8.386572)
			)
		)
	)
	(zone
		(layer "In1.Cu")
		(hatch none 0.5)
		(connect_pads
			(clearance 0)
		)
		(min_thickness 0.25)
		(keepout
			(tracks not_allowed)
			(vias allowed)
			(pads allowed)
			(copperpour not_allowed)
			(footprints allowed)
		)
		(placement
			(enabled no)
			(sheetname "")
		)
		(fill
			(thermal_gap 0.5)
			(thermal_bridge_width 0.5)
			(island_removal_mode 0)
		)
		(polygon
			(pts
				(xy 32.820102 4.680458) (xy 32.820102 2.877058) (xy 33.378902 2.877058) (xy 33.378902 4.680458)
			)
		)
	)
	(zone
		(layer "In1.Cu")
		(hatch none 0.5)
		(connect_pads
			(clearance 0)
		)
		(min_thickness 0.25)
		(keepout
			(tracks not_allowed)
			(vias allowed)
			(pads allowed)
			(copperpour not_allowed)
			(footprints allowed)
		)
		(placement
			(enabled no)
			(sheetname "")
		)
		(fill
			(thermal_gap 0.5)
			(thermal_bridge_width 0.5)
			(island_removal_mode 0)
		)
		(polygon
			(pts
				(xy 91.469972 -19.121882) (xy 91.469972 -20.925282) (xy 92.028772 -20.925282) (xy 92.028772 -19.121882)
			)
		)
	)
	(zone
		(layer "In1.Cu")
		(hatch none 0.5)
		(connect_pads
			(clearance 0)
		)
		(min_thickness 0.25)
		(keepout
			(tracks not_allowed)
			(vias allowed)
			(pads allowed)
			(copperpour not_allowed)
			(footprints allowed)
		)
		(placement
			(enabled no)
			(sheetname "")
		)
		(fill
			(thermal_gap 0.5)
			(thermal_bridge_width 0.5)
			(island_removal_mode 0)
		)
		(polygon
			(pts
				(xy 217.370406 -146.375882) (xy 217.370406 -148.179282) (xy 217.929206 -148.179282) (xy 217.929206 -146.375882)
			)
		)
	)
	(zone
		(layer "In1.Cu")
		(hatch none 0.5)
		(connect_pads
			(clearance 0)
		)
		(min_thickness 0.25)
		(keepout
			(tracks not_allowed)
			(vias allowed)
			(pads allowed)
			(copperpour not_allowed)
			(footprints allowed)
		)
		(placement
			(enabled no)
			(sheetname "")
		)
		(fill
			(thermal_gap 0.5)
			(thermal_bridge_width 0.5)
			(island_removal_mode 0)
		)
		(polygon
			(pts
				(xy 315.120528 -132.174742) (xy 315.120528 -133.978142) (xy 315.679328 -133.978142) (xy 315.679328 -132.174742)
			)
		)
	)
	(zone
		(layer "In1.Cu")
		(hatch none 0.5)
		(connect_pads
			(clearance 0)
		)
		(min_thickness 0.25)
		(keepout
			(tracks not_allowed)
			(vias allowed)
			(pads allowed)
			(copperpour not_allowed)
			(footprints allowed)
		)
		(placement
			(enabled no)
			(sheetname "")
		)
		(fill
			(thermal_gap 0.5)
			(thermal_bridge_width 0.5)
			(island_removal_mode 0)
		)
		(polygon
			(pts
				(xy 107.620054 -151.377142) (xy 107.620054 -153.180542) (xy 108.178854 -153.180542) (xy 108.178854 -151.377142)
			)
		)
	)
	(zone
		(layer "In1.Cu")
		(hatch none 0.5)
		(connect_pads
			(clearance 0)
		)
		(min_thickness 0.25)
		(keepout
			(tracks not_allowed)
			(vias allowed)
			(pads allowed)
			(copperpour not_allowed)
			(footprints allowed)
		)
		(placement
			(enabled no)
			(sheetname "")
		)
		(fill
			(thermal_gap 0.5)
			(thermal_bridge_width 0.5)
			(island_removal_mode 0)
		)
		(polygon
			(pts
				(xy 46.420024 -4.920742) (xy 46.420024 -6.724142) (xy 46.978824 -6.724142) (xy 46.978824 -4.920742)
			)
		)
	)
	(zone
		(layer "In1.Cu")
		(hatch none 0.5)
		(connect_pads
			(clearance 0)
		)
		(min_thickness 0.25)
		(keepout
			(tracks not_allowed)
			(vias allowed)
			(pads allowed)
			(copperpour not_allowed)
			(footprints allowed)
		)
		(placement
			(enabled no)
			(sheetname "")
		)
		(fill
			(thermal_gap 0.5)
			(thermal_bridge_width 0.5)
			(island_removal_mode 0)
		)
		(polygon
			(pts
				(xy 92.32011 -151.377142) (xy 92.32011 -153.180542) (xy 92.87891 -153.180542) (xy 92.87891 -151.377142)
			)
		)
	)
	(zone
		(layer "In1.Cu")
		(hatch none 0.5)
		(connect_pads
			(clearance 0)
		)
		(min_thickness 0.25)
		(keepout
			(tracks not_allowed)
			(vias allowed)
			(pads allowed)
			(copperpour not_allowed)
			(footprints allowed)
		)
		(placement
			(enabled no)
			(sheetname "")
		)
		(fill
			(thermal_gap 0.5)
			(thermal_bridge_width 0.5)
			(island_removal_mode 0)
		)
		(polygon
			(pts
				(xy 133.119876 -151.377142) (xy 133.119876 -153.180542) (xy 133.678676 -153.180542) (xy 133.678676 -151.377142)
			)
		)
	)
	(zone
		(layer "In1.Cu")
		(hatch none 0.5)
		(connect_pads
			(clearance 0)
		)
		(min_thickness 0.25)
		(keepout
			(tracks not_allowed)
			(vias allowed)
			(pads allowed)
			(copperpour not_allowed)
			(footprints allowed)
		)
		(placement
			(enabled no)
			(sheetname "")
		)
		(fill
			(thermal_gap 0.5)
			(thermal_bridge_width 0.5)
			(island_removal_mode 0)
		)
		(polygon
			(pts
				(xy 59.170062 -4.920742) (xy 59.170062 -6.724142) (xy 59.728862 -6.724142) (xy 59.728862 -4.920742)
			)
		)
	)
	(zone
		(layer "In1.Cu")
		(hatch none 0.5)
		(connect_pads
			(clearance 0)
		)
		(min_thickness 0.25)
		(keepout
			(tracks not_allowed)
			(vias allowed)
			(pads allowed)
			(copperpour not_allowed)
			(footprints allowed)
		)
		(placement
			(enabled no)
			(sheetname "")
		)
		(fill
			(thermal_gap 0.5)
			(thermal_bridge_width 0.5)
			(island_removal_mode 0)
		)
		(polygon
			(pts
				(xy 53.220112 -4.920742) (xy 53.220112 -6.724142) (xy 53.778912 -6.724142) (xy 53.778912 -4.920742)
			)
		)
	)
	(zone
		(layer "In1.Cu")
		(hatch none 0.5)
		(connect_pads
			(clearance 0)
		)
		(min_thickness 0.25)
		(keepout
			(tracks not_allowed)
			(vias allowed)
			(pads allowed)
			(copperpour not_allowed)
			(footprints allowed)
		)
		(placement
			(enabled no)
			(sheetname "")
		)
		(fill
			(thermal_gap 0.5)
			(thermal_bridge_width 0.5)
			(island_removal_mode 0)
		)
		(polygon
			(pts
				(xy 247.12041 -141.775942) (xy 247.12041 -143.579342) (xy 247.67921 -143.579342) (xy 247.67921 -141.775942)
			)
		)
	)
	(zone
		(layer "In1.Cu")
		(hatch none 0.5)
		(connect_pads
			(clearance 0)
		)
		(min_thickness 0.25)
		(keepout
			(tracks not_allowed)
			(vias allowed)
			(pads allowed)
			(copperpour not_allowed)
			(footprints allowed)
		)
		(placement
			(enabled no)
			(sheetname "")
		)
		(fill
			(thermal_gap 0.5)
			(thermal_bridge_width 0.5)
			(island_removal_mode 0)
		)
		(polygon
			(pts
				(xy 249.67057 -9.520682) (xy 249.67057 -11.324082) (xy 250.22937 -11.324082) (xy 250.22937 -9.520682)
			)
		)
	)
	(zone
		(layer "In1.Cu")
		(hatch none 0.5)
		(connect_pads
			(clearance 0)
		)
		(min_thickness 0.25)
		(keepout
			(tracks not_allowed)
			(vias allowed)
			(pads allowed)
			(copperpour not_allowed)
			(footprints allowed)
		)
		(placement
			(enabled no)
			(sheetname "")
		)
		(fill
			(thermal_gap 0.5)
			(thermal_bridge_width 0.5)
			(island_removal_mode 0)
		)
		(polygon
			(pts
				(xy 377.2662 -30.375352) (xy 379.5522 -30.375352) (xy 379.5522 -30.883352) (xy 377.2662 -30.883352)
			)
		)
	)
	(zone
		(layer "In1.Cu")
		(hatch none 0.5)
		(connect_pads
			(clearance 0)
		)
		(min_thickness 0.25)
		(keepout
			(tracks not_allowed)
			(vias allowed)
			(pads allowed)
			(copperpour not_allowed)
			(footprints allowed)
		)
		(placement
			(enabled no)
			(sheetname "")
		)
		(fill
			(thermal_gap 0.5)
			(thermal_bridge_width 0.5)
			(island_removal_mode 0)
		)
		(polygon
			(pts
				(xy 116.970048 -19.121882) (xy 116.970048 -20.925282) (xy 117.528848 -20.925282) (xy 117.528848 -19.121882)
			)
		)
	)
	(zone
		(layer "In1.Cu")
		(hatch none 0.5)
		(connect_pads
			(clearance 0)
		)
		(min_thickness 0.25)
		(keepout
			(tracks not_allowed)
			(vias allowed)
			(pads allowed)
			(copperpour not_allowed)
			(footprints allowed)
		)
		(placement
			(enabled no)
			(sheetname "")
		)
		(fill
			(thermal_gap 0.5)
			(thermal_bridge_width 0.5)
			(island_removal_mode 0)
		)
		(polygon
			(pts
				(xy 376.424444 -9.773158) (xy 376.932444 -9.773158) (xy 376.932444 -11.170158) (xy 376.424444 -11.170158)
			)
		)
	)
	(zone
		(layer "In1.Cu")
		(hatch none 0.5)
		(connect_pads
			(clearance 0)
		)
		(min_thickness 0.25)
		(keepout
			(tracks not_allowed)
			(vias allowed)
			(pads allowed)
			(copperpour not_allowed)
			(footprints allowed)
		)
		(placement
			(enabled no)
			(sheetname "")
		)
		(fill
			(thermal_gap 0.5)
			(thermal_bridge_width 0.5)
			(island_removal_mode 0)
		)
		(polygon
			(pts
				(xy 126.320042 -9.520682) (xy 126.320042 -11.324082) (xy 126.878842 -11.324082) (xy 126.878842 -9.520682)
			)
		)
	)
	(zone
		(layer "In1.Cu")
		(hatch none 0.5)
		(connect_pads
			(clearance 0)
		)
		(min_thickness 0.25)
		(keepout
			(tracks not_allowed)
			(vias allowed)
			(pads allowed)
			(copperpour not_allowed)
			(footprints allowed)
		)
		(placement
			(enabled no)
			(sheetname "")
		)
		(fill
			(thermal_gap 0.5)
			(thermal_bridge_width 0.5)
			(island_removal_mode 0)
		)
		(polygon
			(pts
				(xy 65.120012 -132.174742) (xy 65.120012 -133.978142) (xy 65.678812 -133.978142) (xy 65.678812 -132.174742)
			)
		)
	)
	(zone
		(layer "In1.Cu")
		(hatch none 0.5)
		(connect_pads
			(clearance 0)
		)
		(min_thickness 0.25)
		(keepout
			(tracks not_allowed)
			(vias allowed)
			(pads allowed)
			(copperpour not_allowed)
			(footprints allowed)
		)
		(placement
			(enabled no)
			(sheetname "")
		)
		(fill
			(thermal_gap 0.5)
			(thermal_bridge_width 0.5)
			(island_removal_mode 0)
		)
		(polygon
			(pts
				(xy 72.769984 4.680458) (xy 72.769984 2.877058) (xy 73.328784 2.877058) (xy 73.328784 4.680458)
			)
		)
	)
	(zone
		(layer "In1.Cu")
		(hatch none 0.5)
		(connect_pads
			(clearance 0)
		)
		(min_thickness 0.25)
		(keepout
			(tracks not_allowed)
			(vias allowed)
			(pads allowed)
			(copperpour not_allowed)
			(footprints allowed)
		)
		(placement
			(enabled no)
			(sheetname "")
		)
		(fill
			(thermal_gap 0.5)
			(thermal_bridge_width 0.5)
			(island_removal_mode 0)
		)
		(polygon
			(pts
				(xy 281.97048 -19.121882) (xy 281.97048 -20.925282) (xy 282.52928 -20.925282) (xy 282.52928 -19.121882)
			)
		)
	)
	(zone
		(layer "In1.Cu")
		(hatch none 0.5)
		(connect_pads
			(clearance 0)
		)
		(min_thickness 0.25)
		(keepout
			(tracks not_allowed)
			(vias allowed)
			(pads allowed)
			(copperpour not_allowed)
			(footprints allowed)
		)
		(placement
			(enabled no)
			(sheetname "")
		)
		(fill
			(thermal_gap 0.5)
			(thermal_bridge_width 0.5)
			(island_removal_mode 0)
		)
		(polygon
			(pts
				(xy 219.920566 -155.977082) (xy 219.920566 -157.780482) (xy 220.479366 -157.780482) (xy 220.479366 -155.977082)
			)
		)
	)
	(zone
		(layer "In1.Cu")
		(hatch none 0.5)
		(connect_pads
			(clearance 0)
		)
		(min_thickness 0.25)
		(keepout
			(tracks not_allowed)
			(vias allowed)
			(pads allowed)
			(copperpour not_allowed)
			(footprints allowed)
		)
		(placement
			(enabled no)
			(sheetname "")
		)
		(fill
			(thermal_gap 0.5)
			(thermal_bridge_width 0.5)
			(island_removal_mode 0)
		)
		(polygon
			(pts
				(xy 87.220044 0.080518) (xy 87.220044 -1.722882) (xy 87.778844 -1.722882) (xy 87.778844 0.080518)
			)
		)
	)
	(zone
		(layer "In1.Cu")
		(hatch none 0.5)
		(connect_pads
			(clearance 0)
		)
		(min_thickness 0.25)
		(keepout
			(tracks not_allowed)
			(vias allowed)
			(pads allowed)
			(copperpour not_allowed)
			(footprints allowed)
		)
		(placement
			(enabled no)
			(sheetname "")
		)
		(fill
			(thermal_gap 0.5)
			(thermal_bridge_width 0.5)
			(island_removal_mode 0)
		)
		(polygon
			(pts
				(xy 228.420422 -9.520682) (xy 228.420422 -11.324082) (xy 228.979222 -11.324082) (xy 228.979222 -9.520682)
			)
		)
	)
	(zone
		(layer "In1.Cu")
		(hatch none 0.5)
		(connect_pads
			(clearance 0)
		)
		(min_thickness 0.25)
		(keepout
			(tracks not_allowed)
			(vias allowed)
			(pads allowed)
			(copperpour not_allowed)
			(footprints allowed)
		)
		(placement
			(enabled no)
			(sheetname "")
		)
		(fill
			(thermal_gap 0.5)
			(thermal_bridge_width 0.5)
			(island_removal_mode 0)
		)
		(polygon
			(pts
				(xy 220.77045 -141.775942) (xy 220.77045 -143.579342) (xy 221.32925 -143.579342) (xy 221.32925 -141.775942)
			)
		)
	)
	(zone
		(layer "In1.Cu")
		(hatch none 0.5)
		(connect_pads
			(clearance 0)
		)
		(min_thickness 0.25)
		(keepout
			(tracks not_allowed)
			(vias allowed)
			(pads allowed)
			(copperpour not_allowed)
			(footprints allowed)
		)
		(placement
			(enabled no)
			(sheetname "")
		)
		(fill
			(thermal_gap 0.5)
			(thermal_bridge_width 0.5)
			(island_removal_mode 0)
		)
		(polygon
			(pts
				(xy 370.83111 -3.792982) (xy 372.13921 -3.792982) (xy 372.13921 -4.986782) (xy 370.83111 -4.986782)
			)
		)
	)
	(zone
		(layer "In1.Cu")
		(hatch none 0.5)
		(connect_pads
			(clearance 0)
		)
		(min_thickness 0.25)
		(keepout
			(tracks not_allowed)
			(vias allowed)
			(pads allowed)
			(copperpour not_allowed)
			(footprints allowed)
		)
		(placement
			(enabled no)
			(sheetname "")
		)
		(fill
			(thermal_gap 0.5)
			(thermal_bridge_width 0.5)
			(island_removal_mode 0)
		)
		(polygon
			(pts
				(xy 246.270526 -4.920742) (xy 246.270526 -6.724142) (xy 246.829326 -6.724142) (xy 246.829326 -4.920742)
			)
		)
	)
	(zone
		(layer "In1.Cu")
		(hatch none 0.5)
		(connect_pads
			(clearance 0)
		)
		(min_thickness 0.25)
		(keepout
			(tracks not_allowed)
			(vias allowed)
			(pads allowed)
			(copperpour not_allowed)
			(footprints allowed)
		)
		(placement
			(enabled no)
			(sheetname "")
		)
		(fill
			(thermal_gap 0.5)
			(thermal_bridge_width 0.5)
			(island_removal_mode 0)
		)
		(polygon
			(pts
				(xy 247.12041 -136.774682) (xy 247.12041 -138.578082) (xy 247.67921 -138.578082) (xy 247.67921 -136.774682)
			)
		)
	)
	(zone
		(layer "In1.Cu")
		(hatch none 0.5)
		(connect_pads
			(clearance 0)
		)
		(min_thickness 0.25)
		(keepout
			(tracks not_allowed)
			(vias allowed)
			(pads allowed)
			(copperpour not_allowed)
			(footprints allowed)
		)
		(placement
			(enabled no)
			(sheetname "")
		)
		(fill
			(thermal_gap 0.5)
			(thermal_bridge_width 0.5)
			(island_removal_mode 0)
		)
		(polygon
			(pts
				(xy 146.720052 -14.521942) (xy 146.720052 -16.325342) (xy 147.278852 -16.325342) (xy 147.278852 -14.521942)
			)
		)
	)
	(zone
		(layer "In1.Cu")
		(hatch none 0.5)
		(connect_pads
			(clearance 0)
		)
		(min_thickness 0.25)
		(keepout
			(tracks not_allowed)
			(vias allowed)
			(pads allowed)
			(copperpour not_allowed)
			(footprints allowed)
		)
		(placement
			(enabled no)
			(sheetname "")
		)
		(fill
			(thermal_gap 0.5)
			(thermal_bridge_width 0.5)
			(island_removal_mode 0)
		)
		(polygon
			(pts
				(xy 310.020462 -136.774682) (xy 310.020462 -138.578082) (xy 310.579262 -138.578082) (xy 310.579262 -136.774682)
			)
		)
	)
	(zone
		(layer "In1.Cu")
		(hatch none 0.5)
		(connect_pads
			(clearance 0)
		)
		(min_thickness 0.25)
		(keepout
			(tracks not_allowed)
			(vias allowed)
			(pads allowed)
			(copperpour not_allowed)
			(footprints allowed)
		)
		(placement
			(enabled no)
			(sheetname "")
		)
		(fill
			(thermal_gap 0.5)
			(thermal_bridge_width 0.5)
			(island_removal_mode 0)
		)
		(polygon
			(pts
				(xy 283.670502 -151.377142) (xy 283.670502 -153.180542) (xy 284.229302 -153.180542) (xy 284.229302 -151.377142)
			)
		)
	)
	(zone
		(layer "In1.Cu")
		(hatch none 0.5)
		(connect_pads
			(clearance 0)
		)
		(min_thickness 0.25)
		(keepout
			(tracks not_allowed)
			(vias allowed)
			(pads allowed)
			(copperpour not_allowed)
			(footprints allowed)
		)
		(placement
			(enabled no)
			(sheetname "")
		)
		(fill
			(thermal_gap 0.5)
			(thermal_bridge_width 0.5)
			(island_removal_mode 0)
		)
		(polygon
			(pts
				(xy 58.319924 -9.520682) (xy 58.319924 -11.324082) (xy 58.878724 -11.324082) (xy 58.878724 -9.520682)
			)
		)
	)
	(zone
		(layer "In1.Cu")
		(hatch none 0.5)
		(connect_pads
			(clearance 0)
		)
		(min_thickness 0.25)
		(keepout
			(tracks not_allowed)
			(vias allowed)
			(pads allowed)
			(copperpour not_allowed)
			(footprints allowed)
		)
		(placement
			(enabled no)
			(sheetname "")
		)
		(fill
			(thermal_gap 0.5)
			(thermal_bridge_width 0.5)
			(island_removal_mode 0)
		)
		(polygon
			(pts
				(xy 256.470404 -9.520682) (xy 256.470404 -11.324082) (xy 257.029204 -11.324082) (xy 257.029204 -9.520682)
			)
		)
	)
	(zone
		(layer "In1.Cu")
		(hatch none 0.5)
		(connect_pads
			(clearance 0)
		)
		(min_thickness 0.25)
		(keepout
			(tracks not_allowed)
			(vias allowed)
			(pads allowed)
			(copperpour not_allowed)
			(footprints allowed)
		)
		(placement
			(enabled no)
			(sheetname "")
		)
		(fill
			(thermal_gap 0.5)
			(thermal_bridge_width 0.5)
			(island_removal_mode 0)
		)
		(polygon
			(pts
				(xy 256.470404 -151.377142) (xy 256.470404 -153.180542) (xy 257.029204 -153.180542) (xy 257.029204 -151.377142)
			)
		)
	)
	(zone
		(layer "In1.Cu")
		(hatch none 0.5)
		(connect_pads
			(clearance 0)
		)
		(min_thickness 0.25)
		(keepout
			(tracks not_allowed)
			(vias allowed)
			(pads allowed)
			(copperpour not_allowed)
			(footprints allowed)
		)
		(placement
			(enabled no)
			(sheetname "")
		)
		(fill
			(thermal_gap 0.5)
			(thermal_bridge_width 0.5)
			(island_removal_mode 0)
		)
		(polygon
			(pts
				(xy 214.8205 -4.920742) (xy 214.8205 -6.724142) (xy 215.3793 -6.724142) (xy 215.3793 -4.920742)
			)
		)
	)
	(zone
		(layer "In1.Cu")
		(hatch none 0.5)
		(connect_pads
			(clearance 0)
		)
		(min_thickness 0.25)
		(keepout
			(tracks not_allowed)
			(vias allowed)
			(pads allowed)
			(copperpour not_allowed)
			(footprints allowed)
		)
		(placement
			(enabled no)
			(sheetname "")
		)
		(fill
			(thermal_gap 0.5)
			(thermal_bridge_width 0.5)
			(island_removal_mode 0)
		)
		(polygon
			(pts
				(xy 290.470336 -132.174742) (xy 290.470336 -133.978142) (xy 291.029136 -133.978142) (xy 291.029136 -132.174742)
			)
		)
	)
	(zone
		(layer "In1.Cu")
		(hatch none 0.5)
		(connect_pads
			(clearance 0)
		)
		(min_thickness 0.25)
		(keepout
			(tracks not_allowed)
			(vias allowed)
			(pads allowed)
			(copperpour not_allowed)
			(footprints allowed)
		)
		(placement
			(enabled no)
			(sheetname "")
		)
		(fill
			(thermal_gap 0.5)
			(thermal_bridge_width 0.5)
			(island_removal_mode 0)
		)
		(polygon
			(pts
				(xy 130.56997 -19.121882) (xy 130.56997 -20.925282) (xy 131.12877 -20.925282) (xy 131.12877 -19.121882)
			)
		)
	)
	(zone
		(layer "In1.Cu")
		(hatch none 0.5)
		(connect_pads
			(clearance 0)
		)
		(min_thickness 0.25)
		(keepout
			(tracks not_allowed)
			(vias allowed)
			(pads allowed)
			(copperpour not_allowed)
			(footprints allowed)
		)
		(placement
			(enabled no)
			(sheetname "")
		)
		(fill
			(thermal_gap 0.5)
			(thermal_bridge_width 0.5)
			(island_removal_mode 0)
		)
		(polygon
			(pts
				(xy 307.470302 4.680458) (xy 307.470302 2.877058) (xy 308.029102 2.877058) (xy 308.029102 4.680458)
			)
		)
	)
	(zone
		(layer "In1.Cu")
		(hatch none 0.5)
		(connect_pads
			(clearance 0)
		)
		(min_thickness 0.25)
		(keepout
			(tracks not_allowed)
			(vias allowed)
			(pads allowed)
			(copperpour not_allowed)
			(footprints allowed)
		)
		(placement
			(enabled no)
			(sheetname "")
		)
		(fill
			(thermal_gap 0.5)
			(thermal_bridge_width 0.5)
			(island_removal_mode 0)
		)
		(polygon
			(pts
				(xy 457.88707 -46.478698) (xy 459.194916 -46.478698) (xy 459.194916 -48.485298) (xy 457.88707 -48.485298)
			)
		)
	)
	(zone
		(layer "In1.Cu")
		(hatch none 0.5)
		(connect_pads
			(clearance 0)
		)
		(min_thickness 0.25)
		(keepout
			(tracks not_allowed)
			(vias allowed)
			(pads allowed)
			(copperpour not_allowed)
			(footprints allowed)
		)
		(placement
			(enabled no)
			(sheetname "")
		)
		(fill
			(thermal_gap 0.5)
			(thermal_bridge_width 0.5)
			(island_removal_mode 0)
		)
		(polygon
			(pts
				(xy 275.170392 0.080518) (xy 275.170392 -1.722882) (xy 275.729192 -1.722882) (xy 275.729192 0.080518)
			)
		)
	)
	(zone
		(layer "In1.Cu")
		(hatch none 0.5)
		(connect_pads
			(clearance 0)
		)
		(min_thickness 0.25)
		(keepout
			(tracks not_allowed)
			(vias allowed)
			(pads allowed)
			(copperpour not_allowed)
			(footprints allowed)
		)
		(placement
			(enabled no)
			(sheetname "")
		)
		(fill
			(thermal_gap 0.5)
			(thermal_bridge_width 0.5)
			(island_removal_mode 0)
		)
		(polygon
			(pts
				(xy 129.720086 -151.377142) (xy 129.720086 -153.180542) (xy 130.278886 -153.180542) (xy 130.278886 -151.377142)
			)
		)
	)
	(zone
		(layer "In1.Cu")
		(hatch none 0.5)
		(connect_pads
			(clearance 0)
		)
		(min_thickness 0.25)
		(keepout
			(tracks not_allowed)
			(vias allowed)
			(pads allowed)
			(copperpour not_allowed)
			(footprints allowed)
		)
		(placement
			(enabled no)
			(sheetname "")
		)
		(fill
			(thermal_gap 0.5)
			(thermal_bridge_width 0.5)
			(island_removal_mode 0)
		)
		(polygon
			(pts
				(xy 75.320144 -136.774682) (xy 75.320144 -138.578082) (xy 75.878944 -138.578082) (xy 75.878944 -136.774682)
			)
		)
	)
	(zone
		(layer "In1.Cu")
		(hatch none 0.5)
		(connect_pads
			(clearance 0)
		)
		(min_thickness 0.25)
		(keepout
			(tracks not_allowed)
			(vias allowed)
			(pads allowed)
			(copperpour not_allowed)
			(footprints allowed)
		)
		(placement
			(enabled no)
			(sheetname "")
		)
		(fill
			(thermal_gap 0.5)
			(thermal_bridge_width 0.5)
			(island_removal_mode 0)
		)
		(polygon
			(pts
				(xy 319.4685 -124.333) (xy 321.7545 -124.333) (xy 321.7545 -124.841) (xy 319.4685 -124.841)
			)
		)
	)
	(zone
		(layer "In1.Cu")
		(hatch none 0.5)
		(connect_pads
			(clearance 0)
		)
		(min_thickness 0.25)
		(keepout
			(tracks not_allowed)
			(vias allowed)
			(pads allowed)
			(copperpour not_allowed)
			(footprints allowed)
		)
		(placement
			(enabled no)
			(sheetname "")
		)
		(fill
			(thermal_gap 0.5)
			(thermal_bridge_width 0.5)
			(island_removal_mode 0)
		)
		(polygon
			(pts
				(xy 57.47004 -14.521942) (xy 57.47004 -16.325342) (xy 58.02884 -16.325342) (xy 58.02884 -14.521942)
			)
		)
	)
	(zone
		(layer "In1.Cu")
		(hatch none 0.5)
		(connect_pads
			(clearance 0)
		)
		(min_thickness 0.25)
		(keepout
			(tracks not_allowed)
			(vias allowed)
			(pads allowed)
			(copperpour not_allowed)
			(footprints allowed)
		)
		(placement
			(enabled no)
			(sheetname "")
		)
		(fill
			(thermal_gap 0.5)
			(thermal_bridge_width 0.5)
			(island_removal_mode 0)
		)
		(polygon
			(pts
				(xy 139.919964 -136.774682) (xy 139.919964 -138.578082) (xy 140.478764 -138.578082) (xy 140.478764 -136.774682)
			)
		)
	)
	(zone
		(layer "In1.Cu")
		(hatch none 0.5)
		(connect_pads
			(clearance 0)
		)
		(min_thickness 0.25)
		(keepout
			(tracks not_allowed)
			(vias allowed)
			(pads allowed)
			(copperpour not_allowed)
			(footprints allowed)
		)
		(placement
			(enabled no)
			(sheetname "")
		)
		(fill
			(thermal_gap 0.5)
			(thermal_bridge_width 0.5)
			(island_removal_mode 0)
		)
		(polygon
			(pts
				(xy 276.02053 -4.920742) (xy 276.02053 -6.724142) (xy 276.57933 -6.724142) (xy 276.57933 -4.920742)
			)
		)
	)
	(zone
		(layer "In1.Cu")
		(hatch none 0.5)
		(connect_pads
			(clearance 0)
		)
		(min_thickness 0.25)
		(keepout
			(tracks not_allowed)
			(vias allowed)
			(pads allowed)
			(copperpour not_allowed)
			(footprints allowed)
		)
		(placement
			(enabled no)
			(sheetname "")
		)
		(fill
			(thermal_gap 0.5)
			(thermal_bridge_width 0.5)
			(island_removal_mode 0)
		)
		(polygon
			(pts
				(xy 59.170062 -132.174742) (xy 59.170062 -133.978142) (xy 59.728862 -133.978142) (xy 59.728862 -132.174742)
			)
		)
	)
	(zone
		(layer "In1.Cu")
		(hatch none 0.5)
		(connect_pads
			(clearance 0)
		)
		(min_thickness 0.25)
		(keepout
			(tracks not_allowed)
			(vias allowed)
			(pads allowed)
			(copperpour not_allowed)
			(footprints allowed)
		)
		(placement
			(enabled no)
			(sheetname "")
		)
		(fill
			(thermal_gap 0.5)
			(thermal_bridge_width 0.5)
			(island_removal_mode 0)
		)
		(polygon
			(pts
				(xy 88.920066 -132.174742) (xy 88.920066 -133.978142) (xy 89.478866 -133.978142) (xy 89.478866 -132.174742)
			)
		)
	)
	(zone
		(layer "In1.Cu")
		(hatch none 0.5)
		(connect_pads
			(clearance 0)
		)
		(min_thickness 0.25)
		(keepout
			(tracks not_allowed)
			(vias allowed)
			(pads allowed)
			(copperpour not_allowed)
			(footprints allowed)
		)
		(placement
			(enabled no)
			(sheetname "")
		)
		(fill
			(thermal_gap 0.5)
			(thermal_bridge_width 0.5)
			(island_removal_mode 0)
		)
		(polygon
			(pts
				(xy 293.020496 -132.174742) (xy 293.020496 -133.978142) (xy 293.579296 -133.978142) (xy 293.579296 -132.174742)
			)
		)
	)
	(zone
		(layer "In1.Cu")
		(hatch none 0.5)
		(connect_pads
			(clearance 0)
		)
		(min_thickness 0.25)
		(keepout
			(tracks not_allowed)
			(vias allowed)
			(pads allowed)
			(copperpour not_allowed)
			(footprints allowed)
		)
		(placement
			(enabled no)
			(sheetname "")
		)
		(fill
			(thermal_gap 0.5)
			(thermal_bridge_width 0.5)
			(island_removal_mode 0)
		)
		(polygon
			(pts
				(xy 296.42054 -14.521942) (xy 296.42054 -16.325342) (xy 296.97934 -16.325342) (xy 296.97934 -14.521942)
			)
		)
	)
	(zone
		(layer "In1.Cu")
		(hatch none 0.5)
		(connect_pads
			(clearance 0)
		)
		(min_thickness 0.25)
		(keepout
			(tracks not_allowed)
			(vias allowed)
			(pads allowed)
			(copperpour not_allowed)
			(footprints allowed)
		)
		(placement
			(enabled no)
			(sheetname "")
		)
		(fill
			(thermal_gap 0.5)
			(thermal_bridge_width 0.5)
			(island_removal_mode 0)
		)
		(polygon
			(pts
				(xy 241.170714 -14.521942) (xy 241.170714 -16.325342) (xy 241.729514 -16.325342) (xy 241.729514 -14.521942)
			)
		)
	)
	(zone
		(layer "In1.Cu")
		(hatch none 0.5)
		(connect_pads
			(clearance 0)
		)
		(min_thickness 0.25)
		(keepout
			(tracks not_allowed)
			(vias allowed)
			(pads allowed)
			(copperpour not_allowed)
			(footprints allowed)
		)
		(placement
			(enabled no)
			(sheetname "")
		)
		(fill
			(thermal_gap 0.5)
			(thermal_bridge_width 0.5)
			(island_removal_mode 0)
		)
		(polygon
			(pts
				(xy 84.670138 -146.375882) (xy 84.670138 -148.179282) (xy 85.228938 -148.179282) (xy 85.228938 -146.375882)
			)
		)
	)
	(zone
		(layer "In1.Cu")
		(hatch none 0.5)
		(connect_pads
			(clearance 0)
		)
		(min_thickness 0.25)
		(keepout
			(tracks not_allowed)
			(vias allowed)
			(pads allowed)
			(copperpour not_allowed)
			(footprints allowed)
		)
		(placement
			(enabled no)
			(sheetname "")
		)
		(fill
			(thermal_gap 0.5)
			(thermal_bridge_width 0.5)
			(island_removal_mode 0)
		)
		(polygon
			(pts
				(xy 120.370092 -141.775942) (xy 120.370092 -143.579342) (xy 120.928892 -143.579342) (xy 120.928892 -141.775942)
			)
		)
	)
	(zone
		(layer "In1.Cu")
		(hatch none 0.5)
		(connect_pads
			(clearance 0)
		)
		(min_thickness 0.25)
		(keepout
			(tracks not_allowed)
			(vias allowed)
			(pads allowed)
			(copperpour not_allowed)
			(footprints allowed)
		)
		(placement
			(enabled no)
			(sheetname "")
		)
		(fill
			(thermal_gap 0.5)
			(thermal_bridge_width 0.5)
			(island_removal_mode 0)
		)
		(polygon
			(pts
				(xy 64.270128 0.080518) (xy 64.270128 -1.722882) (xy 64.828928 -1.722882) (xy 64.828928 0.080518)
			)
		)
	)
	(zone
		(layer "In1.Cu")
		(hatch none 0.5)
		(connect_pads
			(clearance 0)
		)
		(min_thickness 0.25)
		(keepout
			(tracks not_allowed)
			(vias allowed)
			(pads allowed)
			(copperpour not_allowed)
			(footprints allowed)
		)
		(placement
			(enabled no)
			(sheetname "")
		)
		(fill
			(thermal_gap 0.5)
			(thermal_bridge_width 0.5)
			(island_removal_mode 0)
		)
		(polygon
			(pts
				(xy 298.970446 -9.520682) (xy 298.970446 -11.324082) (xy 299.529246 -11.324082) (xy 299.529246 -9.520682)
			)
		)
	)
	(zone
		(layer "In1.Cu")
		(hatch none 0.5)
		(connect_pads
			(clearance 0)
		)
		(min_thickness 0.25)
		(keepout
			(tracks not_allowed)
			(vias allowed)
			(pads allowed)
			(copperpour not_allowed)
			(footprints allowed)
		)
		(placement
			(enabled no)
			(sheetname "")
		)
		(fill
			(thermal_gap 0.5)
			(thermal_bridge_width 0.5)
			(island_removal_mode 0)
		)
		(polygon
			(pts
				(xy 249.67057 -151.377142) (xy 249.67057 -153.180542) (xy 250.22937 -153.180542) (xy 250.22937 -151.377142)
			)
		)
	)
	(zone
		(layer "In1.Cu")
		(hatch none 0.5)
		(connect_pads
			(clearance 0)
		)
		(min_thickness 0.25)
		(keepout
			(tracks not_allowed)
			(vias allowed)
			(pads allowed)
			(copperpour not_allowed)
			(footprints allowed)
		)
		(placement
			(enabled no)
			(sheetname "")
		)
		(fill
			(thermal_gap 0.5)
			(thermal_bridge_width 0.5)
			(island_removal_mode 0)
		)
		(polygon
			(pts
				(xy 220.77045 -151.377142) (xy 220.77045 -153.180542) (xy 221.32925 -153.180542) (xy 221.32925 -151.377142)
			)
		)
	)
	(zone
		(layer "In1.Cu")
		(hatch none 0.5)
		(connect_pads
			(clearance 0)
		)
		(min_thickness 0.25)
		(keepout
			(tracks not_allowed)
			(vias allowed)
			(pads allowed)
			(copperpour not_allowed)
			(footprints allowed)
		)
		(placement
			(enabled no)
			(sheetname "")
		)
		(fill
			(thermal_gap 0.5)
			(thermal_bridge_width 0.5)
			(island_removal_mode 0)
		)
		(polygon
			(pts
				(xy 64.270128 -155.977082) (xy 64.270128 -157.780482) (xy 64.828928 -157.780482) (xy 64.828928 -155.977082)
			)
		)
	)
	(zone
		(layer "In1.Cu")
		(hatch none 0.5)
		(connect_pads
			(clearance 0)
		)
		(min_thickness 0.25)
		(keepout
			(tracks not_allowed)
			(vias allowed)
			(pads allowed)
			(copperpour not_allowed)
			(footprints allowed)
		)
		(placement
			(enabled no)
			(sheetname "")
		)
		(fill
			(thermal_gap 0.5)
			(thermal_bridge_width 0.5)
			(island_removal_mode 0)
		)
		(polygon
			(pts
				(xy 242.020852 -155.977082) (xy 242.020852 -157.780482) (xy 242.579652 -157.780482) (xy 242.579652 -155.977082)
			)
		)
	)
	(zone
		(layer "In1.Cu")
		(hatch none 0.5)
		(connect_pads
			(clearance 0)
		)
		(min_thickness 0.25)
		(keepout
			(tracks not_allowed)
			(vias allowed)
			(pads allowed)
			(copperpour not_allowed)
			(footprints allowed)
		)
		(placement
			(enabled no)
			(sheetname "")
		)
		(fill
			(thermal_gap 0.5)
			(thermal_bridge_width 0.5)
			(island_removal_mode 0)
		)
		(polygon
			(pts
				(xy 13.6398 -31.877) (xy 15.0368 -31.877) (xy 15.0368 -32.385) (xy 13.6398 -32.385)
			)
		)
	)
	(zone
		(layer "In1.Cu")
		(hatch none 0.5)
		(connect_pads
			(clearance 0)
		)
		(min_thickness 0.25)
		(keepout
			(tracks not_allowed)
			(vias allowed)
			(pads allowed)
			(copperpour not_allowed)
			(footprints allowed)
		)
		(placement
			(enabled no)
			(sheetname "")
		)
		(fill
			(thermal_gap 0.5)
			(thermal_bridge_width 0.5)
			(island_removal_mode 0)
		)
		(polygon
			(pts
				(xy 116.11991 -14.521942) (xy 116.11991 -16.325342) (xy 116.67871 -16.325342) (xy 116.67871 -14.521942)
			)
		)
	)
	(zone
		(layer "In1.Cu")
		(hatch none 0.5)
		(connect_pads
			(clearance 0)
		)
		(min_thickness 0.25)
		(keepout
			(tracks not_allowed)
			(vias allowed)
			(pads allowed)
			(copperpour not_allowed)
			(footprints allowed)
		)
		(placement
			(enabled no)
			(sheetname "")
		)
		(fill
			(thermal_gap 0.5)
			(thermal_bridge_width 0.5)
			(island_removal_mode 0)
		)
		(polygon
			(pts
				(xy 206.32039 -19.121882) (xy 206.32039 -20.925282) (xy 206.87919 -20.925282) (xy 206.87919 -19.121882)
			)
		)
	)
	(zone
		(layer "In1.Cu")
		(hatch none 0.5)
		(connect_pads
			(clearance 0)
		)
		(min_thickness 0.25)
		(keepout
			(tracks not_allowed)
			(vias allowed)
			(pads allowed)
			(copperpour not_allowed)
			(footprints allowed)
		)
		(placement
			(enabled no)
			(sheetname "")
		)
		(fill
			(thermal_gap 0.5)
			(thermal_bridge_width 0.5)
			(island_removal_mode 0)
		)
		(polygon
			(pts
				(xy 48.96993 0.080518) (xy 48.96993 -1.722882) (xy 49.52873 -1.722882) (xy 49.52873 0.080518)
			)
		)
	)
	(zone
		(layer "In1.Cu")
		(hatch none 0.5)
		(connect_pads
			(clearance 0)
		)
		(min_thickness 0.25)
		(keepout
			(tracks not_allowed)
			(vias allowed)
			(pads allowed)
			(copperpour not_allowed)
			(footprints allowed)
		)
		(placement
			(enabled no)
			(sheetname "")
		)
		(fill
			(thermal_gap 0.5)
			(thermal_bridge_width 0.5)
			(island_removal_mode 0)
		)
		(polygon
			(pts
				(xy 102.519988 -9.520682) (xy 102.519988 -11.324082) (xy 103.078788 -11.324082) (xy 103.078788 -9.520682)
			)
		)
	)
	(zone
		(layer "In1.Cu")
		(hatch none 0.5)
		(connect_pads
			(clearance 0)
		)
		(min_thickness 0.25)
		(keepout
			(tracks not_allowed)
			(vias allowed)
			(pads allowed)
			(copperpour not_allowed)
			(footprints allowed)
		)
		(placement
			(enabled no)
			(sheetname "")
		)
		(fill
			(thermal_gap 0.5)
			(thermal_bridge_width 0.5)
			(island_removal_mode 0)
		)
		(polygon
			(pts
				(xy 234.370372 -136.774682) (xy 234.370372 -138.578082) (xy 234.929172 -138.578082) (xy 234.929172 -136.774682)
			)
		)
	)
	(zone
		(layer "In1.Cu")
		(hatch none 0.5)
		(connect_pads
			(clearance 0)
		)
		(min_thickness 0.25)
		(keepout
			(tracks not_allowed)
			(vias allowed)
			(pads allowed)
			(copperpour not_allowed)
			(footprints allowed)
		)
		(placement
			(enabled no)
			(sheetname "")
		)
		(fill
			(thermal_gap 0.5)
			(thermal_bridge_width 0.5)
			(island_removal_mode 0)
		)
		(polygon
			(pts
				(xy 52.369974 -146.375882) (xy 52.369974 -148.179282) (xy 52.928774 -148.179282) (xy 52.928774 -146.375882)
			)
		)
	)
	(zone
		(layer "In1.Cu")
		(hatch none 0.5)
		(connect_pads
			(clearance 0)
		)
		(min_thickness 0.25)
		(keepout
			(tracks not_allowed)
			(vias allowed)
			(pads allowed)
			(copperpour not_allowed)
			(footprints allowed)
		)
		(placement
			(enabled no)
			(sheetname "")
		)
		(fill
			(thermal_gap 0.5)
			(thermal_bridge_width 0.5)
			(island_removal_mode 0)
		)
		(polygon
			(pts
				(xy 77.02042 -9.520682) (xy 77.02042 -11.324082) (xy 77.57922 -11.324082) (xy 77.57922 -9.520682)
			)
		)
	)
	(zone
		(layer "In1.Cu")
		(hatch none 0.5)
		(connect_pads
			(clearance 0)
		)
		(min_thickness 0.25)
		(keepout
			(tracks not_allowed)
			(vias allowed)
			(pads allowed)
			(copperpour not_allowed)
			(footprints allowed)
		)
		(placement
			(enabled no)
			(sheetname "")
		)
		(fill
			(thermal_gap 0.5)
			(thermal_bridge_width 0.5)
			(island_removal_mode 0)
		)
		(polygon
			(pts
				(xy 54.920134 0.080518) (xy 54.920134 -1.722882) (xy 55.478934 -1.722882) (xy 55.478934 0.080518)
			)
		)
	)
	(zone
		(layer "In1.Cu")
		(hatch none 0.5)
		(connect_pads
			(clearance 0)
		)
		(min_thickness 0.25)
		(keepout
			(tracks not_allowed)
			(vias allowed)
			(pads allowed)
			(copperpour not_allowed)
			(footprints allowed)
		)
		(placement
			(enabled no)
			(sheetname "")
		)
		(fill
			(thermal_gap 0.5)
			(thermal_bridge_width 0.5)
			(island_removal_mode 0)
		)
		(polygon
			(pts
				(xy 232.67035 -9.520682) (xy 232.67035 -11.324082) (xy 233.22915 -11.324082) (xy 233.22915 -9.520682)
			)
		)
	)
	(zone
		(layer "In1.Cu")
		(hatch none 0.5)
		(connect_pads
			(clearance 0)
		)
		(min_thickness 0.25)
		(keepout
			(tracks not_allowed)
			(vias allowed)
			(pads allowed)
			(copperpour not_allowed)
			(footprints allowed)
		)
		(placement
			(enabled no)
			(sheetname "")
		)
		(fill
			(thermal_gap 0.5)
			(thermal_bridge_width 0.5)
			(island_removal_mode 0)
		)
		(polygon
			(pts
				(xy 371.623844 -9.773158) (xy 372.131844 -9.773158) (xy 372.131844 -11.170158) (xy 371.623844 -11.170158)
			)
		)
	)
	(zone
		(layer "In1.Cu")
		(hatch none 0.5)
		(connect_pads
			(clearance 0)
		)
		(min_thickness 0.25)
		(keepout
			(tracks not_allowed)
			(vias allowed)
			(pads allowed)
			(copperpour not_allowed)
			(footprints allowed)
		)
		(placement
			(enabled no)
			(sheetname "")
		)
		(fill
			(thermal_gap 0.5)
			(thermal_bridge_width 0.5)
			(island_removal_mode 0)
		)
		(polygon
			(pts
				(xy 112.72012 -14.521942) (xy 112.72012 -16.325342) (xy 113.27892 -16.325342) (xy 113.27892 -14.521942)
			)
		)
	)
	(zone
		(layer "In1.Cu")
		(hatch none 0.5)
		(connect_pads
			(clearance 0)
		)
		(min_thickness 0.25)
		(keepout
			(tracks not_allowed)
			(vias allowed)
			(pads allowed)
			(copperpour not_allowed)
			(footprints allowed)
		)
		(placement
			(enabled no)
			(sheetname "")
		)
		(fill
			(thermal_gap 0.5)
			(thermal_bridge_width 0.5)
			(island_removal_mode 0)
		)
		(polygon
			(pts
				(xy 72.769984 -155.977082) (xy 72.769984 -157.780482) (xy 73.328784 -157.780482) (xy 73.328784 -155.977082)
			)
		)
	)
	(zone
		(layer "In1.Cu")
		(hatch none 0.5)
		(connect_pads
			(clearance 0)
		)
		(min_thickness 0.25)
		(keepout
			(tracks not_allowed)
			(vias allowed)
			(pads allowed)
			(copperpour not_allowed)
			(footprints allowed)
		)
		(placement
			(enabled no)
			(sheetname "")
		)
		(fill
			(thermal_gap 0.5)
			(thermal_bridge_width 0.5)
			(island_removal_mode 0)
		)
		(polygon
			(pts
				(xy 107.620054 -141.775942) (xy 107.620054 -143.579342) (xy 108.178854 -143.579342) (xy 108.178854 -141.775942)
			)
		)
	)
	(zone
		(layer "In1.Cu")
		(hatch none 0.5)
		(connect_pads
			(clearance 0)
		)
		(min_thickness 0.25)
		(keepout
			(tracks not_allowed)
			(vias allowed)
			(pads allowed)
			(copperpour not_allowed)
			(footprints allowed)
		)
		(placement
			(enabled no)
			(sheetname "")
		)
		(fill
			(thermal_gap 0.5)
			(thermal_bridge_width 0.5)
			(island_removal_mode 0)
		)
		(polygon
			(pts
				(xy 63.41999 -146.375882) (xy 63.41999 -148.179282) (xy 63.97879 -148.179282) (xy 63.97879 -146.375882)
			)
		)
	)
	(zone
		(layer "In1.Cu")
		(hatch none 0.5)
		(connect_pads
			(clearance 0)
		)
		(min_thickness 0.25)
		(keepout
			(tracks not_allowed)
			(vias allowed)
			(pads allowed)
			(copperpour not_allowed)
			(footprints allowed)
		)
		(placement
			(enabled no)
			(sheetname "")
		)
		(fill
			(thermal_gap 0.5)
			(thermal_bridge_width 0.5)
			(island_removal_mode 0)
		)
		(polygon
			(pts
				(xy 267.52042 -136.774682) (xy 267.52042 -138.578082) (xy 268.07922 -138.578082) (xy 268.07922 -136.774682)
			)
		)
	)
	(zone
		(layer "In1.Cu")
		(hatch none 0.5)
		(connect_pads
			(clearance 0)
		)
		(min_thickness 0.25)
		(keepout
			(tracks not_allowed)
			(vias allowed)
			(pads allowed)
			(copperpour not_allowed)
			(footprints allowed)
		)
		(placement
			(enabled no)
			(sheetname "")
		)
		(fill
			(thermal_gap 0.5)
			(thermal_bridge_width 0.5)
			(island_removal_mode 0)
		)
		(polygon
			(pts
				(xy 116.970048 -9.520682) (xy 116.970048 -11.324082) (xy 117.528848 -11.324082) (xy 117.528848 -9.520682)
			)
		)
	)
	(zone
		(layer "In1.Cu")
		(hatch none 0.5)
		(connect_pads
			(clearance 0)
		)
		(min_thickness 0.25)
		(keepout
			(tracks not_allowed)
			(vias allowed)
			(pads allowed)
			(copperpour not_allowed)
			(footprints allowed)
		)
		(placement
			(enabled no)
			(sheetname "")
		)
		(fill
			(thermal_gap 0.5)
			(thermal_bridge_width 0.5)
			(island_removal_mode 0)
		)
		(polygon
			(pts
				(xy 71.9201 -4.920742) (xy 71.9201 -6.724142) (xy 72.4789 -6.724142) (xy 72.4789 -4.920742)
			)
		)
	)
	(zone
		(layer "In1.Cu")
		(hatch none 0.5)
		(connect_pads
			(clearance 0)
		)
		(min_thickness 0.25)
		(keepout
			(tracks not_allowed)
			(vias allowed)
			(pads allowed)
			(copperpour not_allowed)
			(footprints allowed)
		)
		(placement
			(enabled no)
			(sheetname "")
		)
		(fill
			(thermal_gap 0.5)
			(thermal_bridge_width 0.5)
			(island_removal_mode 0)
		)
		(polygon
			(pts
				(xy 211.420456 -132.174742) (xy 211.420456 -133.978142) (xy 211.979256 -133.978142) (xy 211.979256 -132.174742)
			)
		)
	)
	(zone
		(layer "In1.Cu")
		(hatch none 0.5)
		(connect_pads
			(clearance 0)
		)
		(min_thickness 0.25)
		(keepout
			(tracks not_allowed)
			(vias allowed)
			(pads allowed)
			(copperpour not_allowed)
			(footprints allowed)
		)
		(placement
			(enabled no)
			(sheetname "")
		)
		(fill
			(thermal_gap 0.5)
			(thermal_bridge_width 0.5)
			(island_removal_mode 0)
		)
		(polygon
			(pts
				(xy 150.96998 -19.121882) (xy 150.96998 -20.925282) (xy 151.52878 -20.925282) (xy 151.52878 -19.121882)
			)
		)
	)
	(zone
		(layer "In1.Cu")
		(hatch none 0.5)
		(connect_pads
			(clearance 0)
		)
		(min_thickness 0.25)
		(keepout
			(tracks not_allowed)
			(vias allowed)
			(pads allowed)
			(copperpour not_allowed)
			(footprints allowed)
		)
		(placement
			(enabled no)
			(sheetname "")
		)
		(fill
			(thermal_gap 0.5)
			(thermal_bridge_width 0.5)
			(island_removal_mode 0)
		)
		(polygon
			(pts
				(xy 85.520022 -136.774682) (xy 85.520022 -138.578082) (xy 86.078822 -138.578082) (xy 86.078822 -136.774682)
			)
		)
	)
	(zone
		(layer "In1.Cu")
		(hatch none 0.5)
		(connect_pads
			(clearance 0)
		)
		(min_thickness 0.25)
		(keepout
			(tracks not_allowed)
			(vias allowed)
			(pads allowed)
			(copperpour not_allowed)
			(footprints allowed)
		)
		(placement
			(enabled no)
			(sheetname "")
		)
		(fill
			(thermal_gap 0.5)
			(thermal_bridge_width 0.5)
			(island_removal_mode 0)
		)
		(polygon
			(pts
				(xy 393.016486 -7.192772) (xy 394.324586 -7.192772) (xy 394.324586 -8.386572) (xy 393.016486 -8.386572)
			)
		)
	)
	(zone
		(layer "In1.Cu")
		(hatch none 0.5)
		(connect_pads
			(clearance 0)
		)
		(min_thickness 0.25)
		(keepout
			(tracks not_allowed)
			(vias allowed)
			(pads allowed)
			(copperpour not_allowed)
			(footprints allowed)
		)
		(placement
			(enabled no)
			(sheetname "")
		)
		(fill
			(thermal_gap 0.5)
			(thermal_bridge_width 0.5)
			(island_removal_mode 0)
		)
		(polygon
			(pts
				(xy 89.76995 4.680458) (xy 89.76995 2.877058) (xy 90.32875 2.877058) (xy 90.32875 4.680458)
			)
		)
	)
	(zone
		(layer "In1.Cu")
		(hatch none 0.5)
		(connect_pads
			(clearance 0)
		)
		(min_thickness 0.25)
		(keepout
			(tracks not_allowed)
			(vias allowed)
			(pads allowed)
			(copperpour not_allowed)
			(footprints allowed)
		)
		(placement
			(enabled no)
			(sheetname "")
		)
		(fill
			(thermal_gap 0.5)
			(thermal_bridge_width 0.5)
			(island_removal_mode 0)
		)
		(polygon
			(pts
				(xy 304.920396 -136.774682) (xy 304.920396 -138.578082) (xy 305.479196 -138.578082) (xy 305.479196 -136.774682)
			)
		)
	)
	(zone
		(layer "In1.Cu")
		(hatch none 0.5)
		(connect_pads
			(clearance 0)
		)
		(min_thickness 0.25)
		(keepout
			(tracks not_allowed)
			(vias allowed)
			(pads allowed)
			(copperpour not_allowed)
			(footprints allowed)
		)
		(placement
			(enabled no)
			(sheetname "")
		)
		(fill
			(thermal_gap 0.5)
			(thermal_bridge_width 0.5)
			(island_removal_mode 0)
		)
		(polygon
			(pts
				(xy 207.170528 -151.377142) (xy 207.170528 -153.180542) (xy 207.729328 -153.180542) (xy 207.729328 -151.377142)
			)
		)
	)
	(zone
		(layer "In1.Cu")
		(hatch none 0.5)
		(connect_pads
			(clearance 0)
		)
		(min_thickness 0.25)
		(keepout
			(tracks not_allowed)
			(vias allowed)
			(pads allowed)
			(copperpour not_allowed)
			(footprints allowed)
		)
		(placement
			(enabled no)
			(sheetname "")
		)
		(fill
			(thermal_gap 0.5)
			(thermal_bridge_width 0.5)
			(island_removal_mode 0)
		)
		(polygon
			(pts
				(xy 203.770484 -151.377142) (xy 203.770484 -153.180542) (xy 204.329284 -153.180542) (xy 204.329284 -151.377142)
			)
		)
	)
	(zone
		(layer "In1.Cu")
		(hatch none 0.5)
		(connect_pads
			(clearance 0)
		)
		(min_thickness 0.25)
		(keepout
			(tracks not_allowed)
			(vias allowed)
			(pads allowed)
			(copperpour not_allowed)
			(footprints allowed)
		)
		(placement
			(enabled no)
			(sheetname "")
		)
		(fill
			(thermal_gap 0.5)
			(thermal_bridge_width 0.5)
			(island_removal_mode 0)
		)
		(polygon
			(pts
				(xy 416.219386 -3.789172) (xy 417.527486 -3.789172) (xy 417.527486 -4.982972) (xy 416.219386 -4.982972)
			)
		)
	)
	(zone
		(layer "In1.Cu")
		(hatch none 0.5)
		(connect_pads
			(clearance 0)
		)
		(min_thickness 0.25)
		(keepout
			(tracks not_allowed)
			(vias allowed)
			(pads allowed)
			(copperpour not_allowed)
			(footprints allowed)
		)
		(placement
			(enabled no)
			(sheetname "")
		)
		(fill
			(thermal_gap 0.5)
			(thermal_bridge_width 0.5)
			(island_removal_mode 0)
		)
		(polygon
			(pts
				(xy 306.620418 -155.977082) (xy 306.620418 -157.780482) (xy 307.179218 -157.780482) (xy 307.179218 -155.977082)
			)
		)
	)
	(zone
		(layer "In1.Cu")
		(hatch none 0.5)
		(connect_pads
			(clearance 0)
		)
		(min_thickness 0.25)
		(keepout
			(tracks not_allowed)
			(vias allowed)
			(pads allowed)
			(copperpour not_allowed)
			(footprints allowed)
		)
		(placement
			(enabled no)
			(sheetname "")
		)
		(fill
			(thermal_gap 0.5)
			(thermal_bridge_width 0.5)
			(island_removal_mode 0)
		)
		(polygon
			(pts
				(xy 146.720052 -132.174742) (xy 146.720052 -133.978142) (xy 147.278852 -133.978142) (xy 147.278852 -132.174742)
			)
		)
	)
	(zone
		(layer "In1.Cu")
		(hatch none 0.5)
		(connect_pads
			(clearance 0)
		)
		(min_thickness 0.25)
		(keepout
			(tracks not_allowed)
			(vias allowed)
			(pads allowed)
			(copperpour not_allowed)
			(footprints allowed)
		)
		(placement
			(enabled no)
			(sheetname "")
		)
		(fill
			(thermal_gap 0.5)
			(thermal_bridge_width 0.5)
			(island_removal_mode 0)
		)
		(polygon
			(pts
				(xy 382.022604 -26.618438) (xy 383.572004 -26.618438) (xy 383.572004 -27.423364) (xy 382.022604 -27.423364)
			)
		)
	)
	(zone
		(layer "In1.Cu")
		(hatch none 0.5)
		(connect_pads
			(clearance 0)
		)
		(min_thickness 0.25)
		(keepout
			(tracks not_allowed)
			(vias allowed)
			(pads allowed)
			(copperpour not_allowed)
			(footprints allowed)
		)
		(placement
			(enabled no)
			(sheetname "")
		)
		(fill
			(thermal_gap 0.5)
			(thermal_bridge_width 0.5)
			(island_removal_mode 0)
		)
		(polygon
			(pts
				(xy 300.670468 -19.121882) (xy 300.670468 -20.925282) (xy 301.229268 -20.925282) (xy 301.229268 -19.121882)
			)
		)
	)
	(zone
		(layer "In1.Cu")
		(hatch none 0.5)
		(connect_pads
			(clearance 0)
		)
		(min_thickness 0.25)
		(keepout
			(tracks not_allowed)
			(vias allowed)
			(pads allowed)
			(copperpour not_allowed)
			(footprints allowed)
		)
		(placement
			(enabled no)
			(sheetname "")
		)
		(fill
			(thermal_gap 0.5)
			(thermal_bridge_width 0.5)
			(island_removal_mode 0)
		)
		(polygon
			(pts
				(xy 267.52042 -4.920742) (xy 267.52042 -6.724142) (xy 268.07922 -6.724142) (xy 268.07922 -4.920742)
			)
		)
	)
	(zone
		(layer "In1.Cu")
		(hatch none 0.5)
		(connect_pads
			(clearance 0)
		)
		(min_thickness 0.25)
		(keepout
			(tracks not_allowed)
			(vias allowed)
			(pads allowed)
			(copperpour not_allowed)
			(footprints allowed)
		)
		(placement
			(enabled no)
			(sheetname "")
		)
		(fill
			(thermal_gap 0.5)
			(thermal_bridge_width 0.5)
			(island_removal_mode 0)
		)
		(polygon
			(pts
				(xy 235.22051 4.680458) (xy 235.22051 2.877058) (xy 235.77931 2.877058) (xy 235.77931 4.680458)
			)
		)
	)
	(zone
		(layer "In1.Cu")
		(hatch none 0.5)
		(connect_pads
			(clearance 0)
		)
		(min_thickness 0.25)
		(keepout
			(tracks not_allowed)
			(vias allowed)
			(pads allowed)
			(copperpour not_allowed)
			(footprints allowed)
		)
		(placement
			(enabled no)
			(sheetname "")
		)
		(fill
			(thermal_gap 0.5)
			(thermal_bridge_width 0.5)
			(island_removal_mode 0)
		)
		(polygon
			(pts
				(xy 282.820364 -4.920742) (xy 282.820364 -6.724142) (xy 283.379164 -6.724142) (xy 283.379164 -4.920742)
			)
		)
	)
	(zone
		(layer "In1.Cu")
		(hatch none 0.5)
		(connect_pads
			(clearance 0)
		)
		(min_thickness 0.25)
		(keepout
			(tracks not_allowed)
			(vias allowed)
			(pads allowed)
			(copperpour not_allowed)
			(footprints allowed)
		)
		(placement
			(enabled no)
			(sheetname "")
		)
		(fill
			(thermal_gap 0.5)
			(thermal_bridge_width 0.5)
			(island_removal_mode 0)
		)
		(polygon
			(pts
				(xy 240.320576 -136.774682) (xy 240.320576 -138.578082) (xy 240.879376 -138.578082) (xy 240.879376 -136.774682)
			)
		)
	)
	(zone
		(layer "In1.Cu")
		(hatch none 0.5)
		(connect_pads
			(clearance 0)
		)
		(min_thickness 0.25)
		(keepout
			(tracks not_allowed)
			(vias allowed)
			(pads allowed)
			(copperpour not_allowed)
			(footprints allowed)
		)
		(placement
			(enabled no)
			(sheetname "")
		)
		(fill
			(thermal_gap 0.5)
			(thermal_bridge_width 0.5)
			(island_removal_mode 0)
		)
		(polygon
			(pts
				(xy 250.520454 -9.520682) (xy 250.520454 -11.324082) (xy 251.079254 -11.324082) (xy 251.079254 -9.520682)
			)
		)
	)
	(zone
		(layer "In1.Cu")
		(hatch none 0.5)
		(connect_pads
			(clearance 0)
		)
		(min_thickness 0.25)
		(keepout
			(tracks not_allowed)
			(vias allowed)
			(pads allowed)
			(copperpour not_allowed)
			(footprints allowed)
		)
		(placement
			(enabled no)
			(sheetname "")
		)
		(fill
			(thermal_gap 0.5)
			(thermal_bridge_width 0.5)
			(island_removal_mode 0)
		)
		(polygon
			(pts
				(xy 69.36994 -146.375882) (xy 69.36994 -148.179282) (xy 69.92874 -148.179282) (xy 69.92874 -146.375882)
			)
		)
	)
	(zone
		(layer "In1.Cu")
		(hatch none 0.5)
		(connect_pads
			(clearance 0)
		)
		(min_thickness 0.25)
		(keepout
			(tracks not_allowed)
			(vias allowed)
			(pads allowed)
			(copperpour not_allowed)
			(footprints allowed)
		)
		(placement
			(enabled no)
			(sheetname "")
		)
		(fill
			(thermal_gap 0.5)
			(thermal_bridge_width 0.5)
			(island_removal_mode 0)
		)
		(polygon
			(pts
				(xy 149.269958 -19.121882) (xy 149.269958 -20.925282) (xy 149.828758 -20.925282) (xy 149.828758 -19.121882)
			)
		)
	)
	(zone
		(layer "In1.Cu")
		(hatch none 0.5)
		(connect_pads
			(clearance 0)
		)
		(min_thickness 0.25)
		(keepout
			(tracks not_allowed)
			(vias allowed)
			(pads allowed)
			(copperpour not_allowed)
			(footprints allowed)
		)
		(placement
			(enabled no)
			(sheetname "")
		)
		(fill
			(thermal_gap 0.5)
			(thermal_bridge_width 0.5)
			(island_removal_mode 0)
		)
		(polygon
			(pts
				(xy 118.67007 -19.121882) (xy 118.67007 -20.925282) (xy 119.22887 -20.925282) (xy 119.22887 -19.121882)
			)
		)
	)
	(zone
		(layer "In1.Cu")
		(hatch none 0.5)
		(connect_pads
			(clearance 0)
		)
		(min_thickness 0.25)
		(keepout
			(tracks not_allowed)
			(vias allowed)
			(pads allowed)
			(copperpour not_allowed)
			(footprints allowed)
		)
		(placement
			(enabled no)
			(sheetname "")
		)
		(fill
			(thermal_gap 0.5)
			(thermal_bridge_width 0.5)
			(island_removal_mode 0)
		)
		(polygon
			(pts
				(xy 92.32011 -146.375882) (xy 92.32011 -148.179282) (xy 92.87891 -148.179282) (xy 92.87891 -146.375882)
			)
		)
	)
	(zone
		(layer "In1.Cu")
		(hatch none 0.5)
		(connect_pads
			(clearance 0)
		)
		(min_thickness 0.25)
		(keepout
			(tracks not_allowed)
			(vias allowed)
			(pads allowed)
			(copperpour not_allowed)
			(footprints allowed)
		)
		(placement
			(enabled no)
			(sheetname "")
		)
		(fill
			(thermal_gap 0.5)
			(thermal_bridge_width 0.5)
			(island_removal_mode 0)
		)
		(polygon
			(pts
				(xy 86.37016 -132.174742) (xy 86.37016 -133.978142) (xy 86.92896 -133.978142) (xy 86.92896 -132.174742)
			)
		)
	)
	(zone
		(layer "In1.Cu")
		(hatch none 0.5)
		(connect_pads
			(clearance 0)
		)
		(min_thickness 0.25)
		(keepout
			(tracks not_allowed)
			(vias allowed)
			(pads allowed)
			(copperpour not_allowed)
			(footprints allowed)
		)
		(placement
			(enabled no)
			(sheetname "")
		)
		(fill
			(thermal_gap 0.5)
			(thermal_bridge_width 0.5)
			(island_removal_mode 0)
		)
		(polygon
			(pts
				(xy 321.8815 -118.161816) (xy 324.1675 -118.161816) (xy 324.1675 -118.669816) (xy 321.8815 -118.669816)
			)
		)
	)
	(zone
		(layer "In1.Cu")
		(hatch none 0.5)
		(connect_pads
			(clearance 0)
		)
		(min_thickness 0.25)
		(keepout
			(tracks not_allowed)
			(vias allowed)
			(pads allowed)
			(copperpour not_allowed)
			(footprints allowed)
		)
		(placement
			(enabled no)
			(sheetname "")
		)
		(fill
			(thermal_gap 0.5)
			(thermal_bridge_width 0.5)
			(island_removal_mode 0)
		)
		(polygon
			(pts
				(xy 88.920066 -4.920742) (xy 88.920066 -6.724142) (xy 89.478866 -6.724142) (xy 89.478866 -4.920742)
			)
		)
	)
	(zone
		(layer "In1.Cu")
		(hatch none 0.5)
		(connect_pads
			(clearance 0)
		)
		(min_thickness 0.25)
		(keepout
			(tracks not_allowed)
			(vias allowed)
			(pads allowed)
			(copperpour not_allowed)
			(footprints allowed)
		)
		(placement
			(enabled no)
			(sheetname "")
		)
		(fill
			(thermal_gap 0.5)
			(thermal_bridge_width 0.5)
			(island_removal_mode 0)
		)
		(polygon
			(pts
				(xy 247.12041 -19.121882) (xy 247.67921 -19.121882) (xy 247.67921 -20.925282) (xy 247.12041 -20.925282)
			)
		)
	)
	(zone
		(layer "In1.Cu")
		(hatch none 0.5)
		(connect_pads
			(clearance 0)
		)
		(min_thickness 0.25)
		(keepout
			(tracks not_allowed)
			(vias allowed)
			(pads allowed)
			(copperpour not_allowed)
			(footprints allowed)
		)
		(placement
			(enabled no)
			(sheetname "")
		)
		(fill
			(thermal_gap 0.5)
			(thermal_bridge_width 0.5)
			(island_removal_mode 0)
		)
		(polygon
			(pts
				(xy 275.170392 -19.121882) (xy 275.170392 -20.925282) (xy 275.729192 -20.925282) (xy 275.729192 -19.121882)
			)
		)
	)
	(zone
		(layer "In1.Cu")
		(hatch none 0.5)
		(connect_pads
			(clearance 0)
		)
		(min_thickness 0.25)
		(keepout
			(tracks not_allowed)
			(vias allowed)
			(pads allowed)
			(copperpour not_allowed)
			(footprints allowed)
		)
		(placement
			(enabled no)
			(sheetname "")
		)
		(fill
			(thermal_gap 0.5)
			(thermal_bridge_width 0.5)
			(island_removal_mode 0)
		)
		(polygon
			(pts
				(xy 101.670104 -9.520682) (xy 101.670104 -11.324082) (xy 102.228904 -11.324082) (xy 102.228904 -9.520682)
			)
		)
	)
	(zone
		(layer "In1.Cu")
		(hatch none 0.5)
		(connect_pads
			(clearance 0)
		)
		(min_thickness 0.25)
		(keepout
			(tracks not_allowed)
			(vias allowed)
			(pads allowed)
			(copperpour not_allowed)
			(footprints allowed)
		)
		(placement
			(enabled no)
			(sheetname "")
		)
		(fill
			(thermal_gap 0.5)
			(thermal_bridge_width 0.5)
			(island_removal_mode 0)
		)
		(polygon
			(pts
				(xy 109.320076 -151.377142) (xy 109.320076 -153.180542) (xy 109.878876 -153.180542) (xy 109.878876 -151.377142)
			)
		)
	)
	(zone
		(layer "In1.Cu")
		(hatch none 0.5)
		(connect_pads
			(clearance 0)
		)
		(min_thickness 0.25)
		(keepout
			(tracks not_allowed)
			(vias allowed)
			(pads allowed)
			(copperpour not_allowed)
			(footprints allowed)
		)
		(placement
			(enabled no)
			(sheetname "")
		)
		(fill
			(thermal_gap 0.5)
			(thermal_bridge_width 0.5)
			(island_removal_mode 0)
		)
		(polygon
			(pts
				(xy 406.60828 -95.398082) (xy 406.60828 -96.795082) (xy 408.00528 -96.795082) (xy 408.00528 -95.398082)
			)
		)
	)
	(zone
		(layer "In1.Cu")
		(hatch none 0.5)
		(connect_pads
			(clearance 0)
		)
		(min_thickness 0.25)
		(keepout
			(tracks not_allowed)
			(vias allowed)
			(pads allowed)
			(copperpour not_allowed)
			(footprints allowed)
		)
		(placement
			(enabled no)
			(sheetname "")
		)
		(fill
			(thermal_gap 0.5)
			(thermal_bridge_width 0.5)
			(island_removal_mode 0)
		)
		(polygon
			(pts
				(xy 205.470506 -151.377142) (xy 205.470506 -153.180542) (xy 206.029306 -153.180542) (xy 206.029306 -151.377142)
			)
		)
	)
	(zone
		(layer "In1.Cu")
		(hatch none 0.5)
		(connect_pads
			(clearance 0)
		)
		(min_thickness 0.25)
		(keepout
			(tracks not_allowed)
			(vias allowed)
			(pads allowed)
			(copperpour not_allowed)
			(footprints allowed)
		)
		(placement
			(enabled no)
			(sheetname "")
		)
		(fill
			(thermal_gap 0.5)
			(thermal_bridge_width 0.5)
			(island_removal_mode 0)
		)
		(polygon
			(pts
				(xy 72.769984 -9.520682) (xy 72.769984 -11.324082) (xy 73.328784 -11.324082) (xy 73.328784 -9.520682)
			)
		)
	)
	(zone
		(layer "In1.Cu")
		(hatch none 0.5)
		(connect_pads
			(clearance 0)
		)
		(min_thickness 0.25)
		(keepout
			(tracks not_allowed)
			(vias allowed)
			(pads allowed)
			(copperpour not_allowed)
			(footprints allowed)
		)
		(placement
			(enabled no)
			(sheetname "")
		)
		(fill
			(thermal_gap 0.5)
			(thermal_bridge_width 0.5)
			(island_removal_mode 0)
		)
		(polygon
			(pts
				(xy 118.67007 -141.775942) (xy 118.67007 -143.579342) (xy 119.22887 -143.579342) (xy 119.22887 -141.775942)
			)
		)
	)
	(zone
		(layer "In1.Cu")
		(hatch none 0.5)
		(connect_pads
			(clearance 0)
		)
		(min_thickness 0.25)
		(keepout
			(tracks not_allowed)
			(vias allowed)
			(pads allowed)
			(copperpour not_allowed)
			(footprints allowed)
		)
		(placement
			(enabled no)
			(sheetname "")
		)
		(fill
			(thermal_gap 0.5)
			(thermal_bridge_width 0.5)
			(island_removal_mode 0)
		)
		(polygon
			(pts
				(xy 150.96998 0.080518) (xy 150.96998 -1.722882) (xy 151.52878 -1.722882) (xy 151.52878 0.080518)
			)
		)
	)
	(zone
		(layer "In1.Cu")
		(hatch none 0.5)
		(connect_pads
			(clearance 0)
		)
		(min_thickness 0.25)
		(keepout
			(tracks not_allowed)
			(vias allowed)
			(pads allowed)
			(copperpour not_allowed)
			(footprints allowed)
		)
		(placement
			(enabled no)
			(sheetname "")
		)
		(fill
			(thermal_gap 0.5)
			(thermal_bridge_width 0.5)
			(island_removal_mode 0)
		)
		(polygon
			(pts
				(xy 301.520352 -4.920742) (xy 301.520352 -6.724142) (xy 302.079152 -6.724142) (xy 302.079152 -4.920742)
			)
		)
	)
	(zone
		(layer "In1.Cu")
		(hatch none 0.5)
		(connect_pads
			(clearance 0)
		)
		(min_thickness 0.25)
		(keepout
			(tracks not_allowed)
			(vias allowed)
			(pads allowed)
			(copperpour not_allowed)
			(footprints allowed)
		)
		(placement
			(enabled no)
			(sheetname "")
		)
		(fill
			(thermal_gap 0.5)
			(thermal_bridge_width 0.5)
			(island_removal_mode 0)
		)
		(polygon
			(pts
				(xy 223.320356 -136.774682) (xy 223.320356 -138.578082) (xy 223.879156 -138.578082) (xy 223.879156 -136.774682)
			)
		)
	)
	(zone
		(layer "In1.Cu")
		(hatch none 0.5)
		(connect_pads
			(clearance 0)
		)
		(min_thickness 0.25)
		(keepout
			(tracks not_allowed)
			(vias allowed)
			(pads allowed)
			(copperpour not_allowed)
			(footprints allowed)
		)
		(placement
			(enabled no)
			(sheetname "")
		)
		(fill
			(thermal_gap 0.5)
			(thermal_bridge_width 0.5)
			(island_removal_mode 0)
		)
		(polygon
			(pts
				(xy 103.370126 4.680458) (xy 103.370126 2.877058) (xy 103.928926 2.877058) (xy 103.928926 4.680458)
			)
		)
	)
	(zone
		(layer "In1.Cu")
		(hatch none 0.5)
		(connect_pads
			(clearance 0)
		)
		(min_thickness 0.25)
		(keepout
			(tracks not_allowed)
			(vias allowed)
			(pads allowed)
			(copperpour not_allowed)
			(footprints allowed)
		)
		(placement
			(enabled no)
			(sheetname "")
		)
		(fill
			(thermal_gap 0.5)
			(thermal_bridge_width 0.5)
			(island_removal_mode 0)
		)
		(polygon
			(pts
				(xy 293.020496 -14.521942) (xy 293.020496 -16.325342) (xy 293.579296 -16.325342) (xy 293.579296 -14.521942)
			)
		)
	)
	(zone
		(layer "In1.Cu")
		(hatch none 0.5)
		(connect_pads
			(clearance 0)
		)
		(min_thickness 0.25)
		(keepout
			(tracks not_allowed)
			(vias allowed)
			(pads allowed)
			(copperpour not_allowed)
			(footprints allowed)
		)
		(placement
			(enabled no)
			(sheetname "")
		)
		(fill
			(thermal_gap 0.5)
			(thermal_bridge_width 0.5)
			(island_removal_mode 0)
		)
		(polygon
			(pts
				(xy 84.670138 -132.174742) (xy 84.670138 -133.978142) (xy 85.228938 -133.978142) (xy 85.228938 -132.174742)
			)
		)
	)
	(zone
		(layer "In1.Cu")
		(hatch none 0.5)
		(connect_pads
			(clearance 0)
		)
		(min_thickness 0.25)
		(keepout
			(tracks not_allowed)
			(vias allowed)
			(pads allowed)
			(copperpour not_allowed)
			(footprints allowed)
		)
		(placement
			(enabled no)
			(sheetname "")
		)
		(fill
			(thermal_gap 0.5)
			(thermal_bridge_width 0.5)
			(island_removal_mode 0)
		)
		(polygon
			(pts
				(xy 40.470074 -141.775942) (xy 40.470074 -143.579342) (xy 41.028874 -143.579342) (xy 41.028874 -141.775942)
			)
		)
	)
	(zone
		(layer "In1.Cu")
		(hatch none 0.5)
		(connect_pads
			(clearance 0)
		)
		(min_thickness 0.25)
		(keepout
			(tracks not_allowed)
			(vias allowed)
			(pads allowed)
			(copperpour not_allowed)
			(footprints allowed)
		)
		(placement
			(enabled no)
			(sheetname "")
		)
		(fill
			(thermal_gap 0.5)
			(thermal_bridge_width 0.5)
			(island_removal_mode 0)
		)
		(polygon
			(pts
				(xy 287.92043 -19.121882) (xy 287.92043 -20.925282) (xy 288.47923 -20.925282) (xy 288.47923 -19.121882)
			)
		)
	)
	(zone
		(layer "In1.Cu")
		(hatch none 0.5)
		(connect_pads
			(clearance 0)
		)
		(min_thickness 0.25)
		(keepout
			(tracks not_allowed)
			(vias allowed)
			(pads allowed)
			(copperpour not_allowed)
			(footprints allowed)
		)
		(placement
			(enabled no)
			(sheetname "")
		)
		(fill
			(thermal_gap 0.5)
			(thermal_bridge_width 0.5)
			(island_removal_mode 0)
		)
		(polygon
			(pts
				(xy 34.520124 -132.174742) (xy 34.520124 -133.978142) (xy 35.078924 -133.978142) (xy 35.078924 -132.174742)
			)
		)
	)
	(zone
		(layer "In1.Cu")
		(hatch none 0.5)
		(connect_pads
			(clearance 0)
		)
		(min_thickness 0.25)
		(keepout
			(tracks not_allowed)
			(vias allowed)
			(pads allowed)
			(copperpour not_allowed)
			(footprints allowed)
		)
		(placement
			(enabled no)
			(sheetname "")
		)
		(fill
			(thermal_gap 0.5)
			(thermal_bridge_width 0.5)
			(island_removal_mode 0)
		)
		(polygon
			(pts
				(xy 268.370558 -132.174742) (xy 268.370558 -133.978142) (xy 268.929358 -133.978142) (xy 268.929358 -132.174742)
			)
		)
	)
	(zone
		(layer "In1.Cu")
		(hatch none 0.5)
		(connect_pads
			(clearance 0)
		)
		(min_thickness 0.25)
		(keepout
			(tracks not_allowed)
			(vias allowed)
			(pads allowed)
			(copperpour not_allowed)
			(footprints allowed)
		)
		(placement
			(enabled no)
			(sheetname "")
		)
		(fill
			(thermal_gap 0.5)
			(thermal_bridge_width 0.5)
			(island_removal_mode 0)
		)
		(polygon
			(pts
				(xy 76.170282 -151.377142) (xy 76.170282 -153.180542) (xy 76.729082 -153.180542) (xy 76.729082 -151.377142)
			)
		)
	)
	(zone
		(layer "In1.Cu")
		(hatch none 0.5)
		(connect_pads
			(clearance 0)
		)
		(min_thickness 0.25)
		(keepout
			(tracks not_allowed)
			(vias allowed)
			(pads allowed)
			(copperpour not_allowed)
			(footprints allowed)
		)
		(placement
			(enabled no)
			(sheetname "")
		)
		(fill
			(thermal_gap 0.5)
			(thermal_bridge_width 0.5)
			(island_removal_mode 0)
		)
		(polygon
			(pts
				(xy 204.620368 -9.520682) (xy 204.620368 -11.324082) (xy 205.179168 -11.324082) (xy 205.179168 -9.520682)
			)
		)
	)
	(zone
		(layer "In1.Cu")
		(hatch none 0.5)
		(connect_pads
			(clearance 0)
		)
		(min_thickness 0.25)
		(keepout
			(tracks not_allowed)
			(vias allowed)
			(pads allowed)
			(copperpour not_allowed)
			(footprints allowed)
		)
		(placement
			(enabled no)
			(sheetname "")
		)
		(fill
			(thermal_gap 0.5)
			(thermal_bridge_width 0.5)
			(island_removal_mode 0)
		)
		(polygon
			(pts
				(xy 257.320542 -136.774682) (xy 257.320542 -138.578082) (xy 257.879342 -138.578082) (xy 257.879342 -136.774682)
			)
		)
	)
	(zone
		(layer "In1.Cu")
		(hatch none 0.5)
		(connect_pads
			(clearance 0)
		)
		(min_thickness 0.25)
		(keepout
			(tracks not_allowed)
			(vias allowed)
			(pads allowed)
			(copperpour not_allowed)
			(footprints allowed)
		)
		(placement
			(enabled no)
			(sheetname "")
		)
		(fill
			(thermal_gap 0.5)
			(thermal_bridge_width 0.5)
			(island_removal_mode 0)
		)
		(polygon
			(pts
				(xy 106.77017 -151.377142) (xy 106.77017 -153.180542) (xy 107.32897 -153.180542) (xy 107.32897 -151.377142)
			)
		)
	)
	(zone
		(layer "In1.Cu")
		(hatch none 0.5)
		(connect_pads
			(clearance 0)
		)
		(min_thickness 0.25)
		(keepout
			(tracks not_allowed)
			(vias allowed)
			(pads allowed)
			(copperpour not_allowed)
			(footprints allowed)
		)
		(placement
			(enabled no)
			(sheetname "")
		)
		(fill
			(thermal_gap 0.5)
			(thermal_bridge_width 0.5)
			(island_removal_mode 0)
		)
		(polygon
			(pts
				(xy 298.120308 4.680458) (xy 298.120308 2.877058) (xy 298.679108 2.877058) (xy 298.679108 4.680458)
			)
		)
	)
	(zone
		(layer "In1.Cu")
		(hatch none 0.5)
		(connect_pads
			(clearance 0)
		)
		(min_thickness 0.25)
		(keepout
			(tracks not_allowed)
			(vias allowed)
			(pads allowed)
			(copperpour not_allowed)
			(footprints allowed)
		)
		(placement
			(enabled no)
			(sheetname "")
		)
		(fill
			(thermal_gap 0.5)
			(thermal_bridge_width 0.5)
			(island_removal_mode 0)
		)
		(polygon
			(pts
				(xy 283.670502 -9.520682) (xy 283.670502 -11.324082) (xy 284.229302 -11.324082) (xy 284.229302 -9.520682)
			)
		)
	)
	(zone
		(layer "In1.Cu")
		(hatch none 0.5)
		(connect_pads
			(clearance 0)
		)
		(min_thickness 0.25)
		(keepout
			(tracks not_allowed)
			(vias allowed)
			(pads allowed)
			(copperpour not_allowed)
			(footprints allowed)
		)
		(placement
			(enabled no)
			(sheetname "")
		)
		(fill
			(thermal_gap 0.5)
			(thermal_bridge_width 0.5)
			(island_removal_mode 0)
		)
		(polygon
			(pts
				(xy 100.819966 -14.521942) (xy 100.819966 -16.325342) (xy 101.378766 -16.325342) (xy 101.378766 -14.521942)
			)
		)
	)
	(zone
		(layer "In1.Cu")
		(hatch none 0.5)
		(connect_pads
			(clearance 0)
		)
		(min_thickness 0.25)
		(keepout
			(tracks not_allowed)
			(vias allowed)
			(pads allowed)
			(copperpour not_allowed)
			(footprints allowed)
		)
		(placement
			(enabled no)
			(sheetname "")
		)
		(fill
			(thermal_gap 0.5)
			(thermal_bridge_width 0.5)
			(island_removal_mode 0)
		)
		(polygon
			(pts
				(xy 215.670384 0.080518) (xy 215.670384 -1.722882) (xy 216.229184 -1.722882) (xy 216.229184 0.080518)
			)
		)
	)
	(zone
		(layer "In1.Cu")
		(hatch none 0.5)
		(connect_pads
			(clearance 0)
		)
		(min_thickness 0.25)
		(keepout
			(tracks not_allowed)
			(vias allowed)
			(pads allowed)
			(copperpour not_allowed)
			(footprints allowed)
		)
		(placement
			(enabled no)
			(sheetname "")
		)
		(fill
			(thermal_gap 0.5)
			(thermal_bridge_width 0.5)
			(island_removal_mode 0)
		)
		(polygon
			(pts
				(xy 294.720518 4.680458) (xy 294.720518 2.877058) (xy 295.279318 2.877058) (xy 295.279318 4.680458)
			)
		)
	)
	(zone
		(layer "In1.Cu")
		(hatch none 0.5)
		(connect_pads
			(clearance 0)
		)
		(min_thickness 0.25)
		(keepout
			(tracks not_allowed)
			(vias allowed)
			(pads allowed)
			(copperpour not_allowed)
			(footprints allowed)
		)
		(placement
			(enabled no)
			(sheetname "")
		)
		(fill
			(thermal_gap 0.5)
			(thermal_bridge_width 0.5)
			(island_removal_mode 0)
		)
		(polygon
			(pts
				(xy 69.36994 -19.121882) (xy 69.36994 -20.925282) (xy 69.92874 -20.925282) (xy 69.92874 -19.121882)
			)
		)
	)
	(zone
		(layer "In1.Cu")
		(hatch none 0.5)
		(connect_pads
			(clearance 0)
		)
		(min_thickness 0.25)
		(keepout
			(tracks not_allowed)
			(vias allowed)
			(pads allowed)
			(copperpour not_allowed)
			(footprints allowed)
		)
		(placement
			(enabled no)
			(sheetname "")
		)
		(fill
			(thermal_gap 0.5)
			(thermal_bridge_width 0.5)
			(island_removal_mode 0)
		)
		(polygon
			(pts
				(xy 118.67007 -4.920742) (xy 118.67007 -6.724142) (xy 119.22887 -6.724142) (xy 119.22887 -4.920742)
			)
		)
	)
	(zone
		(layer "In1.Cu")
		(hatch none 0.5)
		(connect_pads
			(clearance 0)
		)
		(min_thickness 0.25)
		(keepout
			(tracks not_allowed)
			(vias allowed)
			(pads allowed)
			(copperpour not_allowed)
			(footprints allowed)
		)
		(placement
			(enabled no)
			(sheetname "")
		)
		(fill
			(thermal_gap 0.5)
			(thermal_bridge_width 0.5)
			(island_removal_mode 0)
		)
		(polygon
			(pts
				(xy 402.617686 -7.192772) (xy 403.925786 -7.192772) (xy 403.925786 -8.386572) (xy 402.617686 -8.386572)
			)
		)
	)
	(zone
		(layer "In1.Cu")
		(hatch none 0.5)
		(connect_pads
			(clearance 0)
		)
		(min_thickness 0.25)
		(keepout
			(tracks not_allowed)
			(vias allowed)
			(pads allowed)
			(copperpour not_allowed)
			(footprints allowed)
		)
		(placement
			(enabled no)
			(sheetname "")
		)
		(fill
			(thermal_gap 0.5)
			(thermal_bridge_width 0.5)
			(island_removal_mode 0)
		)
		(polygon
			(pts
				(xy 57.47004 4.680458) (xy 57.47004 2.877058) (xy 58.02884 2.877058) (xy 58.02884 4.680458)
			)
		)
	)
	(zone
		(layer "In1.Cu")
		(hatch none 0.5)
		(connect_pads
			(clearance 0)
		)
		(min_thickness 0.25)
		(keepout
			(tracks not_allowed)
			(vias allowed)
			(pads allowed)
			(copperpour not_allowed)
			(footprints allowed)
		)
		(placement
			(enabled no)
			(sheetname "")
		)
		(fill
			(thermal_gap 0.5)
			(thermal_bridge_width 0.5)
			(island_removal_mode 0)
		)
		(polygon
			(pts
				(xy 92.32011 -14.521942) (xy 92.32011 -16.325342) (xy 92.87891 -16.325342) (xy 92.87891 -14.521942)
			)
		)
	)
	(zone
		(layer "In1.Cu")
		(hatch none 0.5)
		(connect_pads
			(clearance 0)
		)
		(min_thickness 0.25)
		(keepout
			(tracks not_allowed)
			(vias allowed)
			(pads allowed)
			(copperpour not_allowed)
			(footprints allowed)
		)
		(placement
			(enabled no)
			(sheetname "")
		)
		(fill
			(thermal_gap 0.5)
			(thermal_bridge_width 0.5)
			(island_removal_mode 0)
		)
		(polygon
			(pts
				(xy 128.020064 -155.977082) (xy 128.020064 -157.780482) (xy 128.578864 -157.780482) (xy 128.578864 -155.977082)
			)
		)
	)
	(zone
		(layer "In1.Cu")
		(hatch none 0.5)
		(connect_pads
			(clearance 0)
		)
		(min_thickness 0.25)
		(keepout
			(tracks not_allowed)
			(vias allowed)
			(pads allowed)
			(copperpour not_allowed)
			(footprints allowed)
		)
		(placement
			(enabled no)
			(sheetname "")
		)
		(fill
			(thermal_gap 0.5)
			(thermal_bridge_width 0.5)
			(island_removal_mode 0)
		)
		(polygon
			(pts
				(xy 40.470074 -151.377142) (xy 40.470074 -153.180542) (xy 41.028874 -153.180542) (xy 41.028874 -151.377142)
			)
		)
	)
	(zone
		(layer "In1.Cu")
		(hatch none 0.5)
		(connect_pads
			(clearance 0)
		)
		(min_thickness 0.25)
		(keepout
			(tracks not_allowed)
			(vias allowed)
			(pads allowed)
			(copperpour not_allowed)
			(footprints allowed)
		)
		(placement
			(enabled no)
			(sheetname "")
		)
		(fill
			(thermal_gap 0.5)
			(thermal_bridge_width 0.5)
			(island_removal_mode 0)
		)
		(polygon
			(pts
				(xy 108.469938 -19.121882) (xy 108.469938 -20.925282) (xy 109.028738 -20.925282) (xy 109.028738 -19.121882)
			)
		)
	)
	(zone
		(layer "In1.Cu")
		(hatch none 0.5)
		(connect_pads
			(clearance 0)
		)
		(min_thickness 0.25)
		(keepout
			(tracks not_allowed)
			(vias allowed)
			(pads allowed)
			(copperpour not_allowed)
			(footprints allowed)
		)
		(placement
			(enabled no)
			(sheetname "")
		)
		(fill
			(thermal_gap 0.5)
			(thermal_bridge_width 0.5)
			(island_removal_mode 0)
		)
		(polygon
			(pts
				(xy 71.069962 -19.121882) (xy 71.069962 -20.925282) (xy 71.628762 -20.925282) (xy 71.628762 -19.121882)
			)
		)
	)
	(zone
		(layer "In1.Cu")
		(hatch none 0.5)
		(connect_pads
			(clearance 0)
		)
		(min_thickness 0.25)
		(keepout
			(tracks not_allowed)
			(vias allowed)
			(pads allowed)
			(copperpour not_allowed)
			(footprints allowed)
		)
		(placement
			(enabled no)
			(sheetname "")
		)
		(fill
			(thermal_gap 0.5)
			(thermal_bridge_width 0.5)
			(island_removal_mode 0)
		)
		(polygon
			(pts
				(xy 211.420456 -4.920742) (xy 211.420456 -6.724142) (xy 211.979256 -6.724142) (xy 211.979256 -4.920742)
			)
		)
	)
	(zone
		(layer "In1.Cu")
		(hatch none 0.5)
		(connect_pads
			(clearance 0)
		)
		(min_thickness 0.25)
		(keepout
			(tracks not_allowed)
			(vias allowed)
			(pads allowed)
			(copperpour not_allowed)
			(footprints allowed)
		)
		(placement
			(enabled no)
			(sheetname "")
		)
		(fill
			(thermal_gap 0.5)
			(thermal_bridge_width 0.5)
			(island_removal_mode 0)
		)
		(polygon
			(pts
				(xy 298.120308 -151.377142) (xy 298.120308 -153.180542) (xy 298.679108 -153.180542) (xy 298.679108 -151.377142)
			)
		)
	)
	(zone
		(layer "In1.Cu")
		(hatch none 0.5)
		(connect_pads
			(clearance 0)
		)
		(min_thickness 0.25)
		(keepout
			(tracks not_allowed)
			(vias allowed)
			(pads allowed)
			(copperpour not_allowed)
			(footprints allowed)
		)
		(placement
			(enabled no)
			(sheetname "")
		)
		(fill
			(thermal_gap 0.5)
			(thermal_bridge_width 0.5)
			(island_removal_mode 0)
		)
		(polygon
			(pts
				(xy 150.120096 -151.377142) (xy 150.120096 -153.180542) (xy 150.678896 -153.180542) (xy 150.678896 -151.377142)
			)
		)
	)
	(zone
		(layer "In1.Cu")
		(hatch none 0.5)
		(connect_pads
			(clearance 0)
		)
		(min_thickness 0.25)
		(keepout
			(tracks not_allowed)
			(vias allowed)
			(pads allowed)
			(copperpour not_allowed)
			(footprints allowed)
		)
		(placement
			(enabled no)
			(sheetname "")
		)
		(fill
			(thermal_gap 0.5)
			(thermal_bridge_width 0.5)
			(island_removal_mode 0)
		)
		(polygon
			(pts
				(xy 105.070148 0.080518) (xy 105.070148 -1.722882) (xy 105.628948 -1.722882) (xy 105.628948 0.080518)
			)
		)
	)
	(zone
		(layer "In1.Cu")
		(hatch none 0.5)
		(connect_pads
			(clearance 0)
		)
		(min_thickness 0.25)
		(keepout
			(tracks not_allowed)
			(vias allowed)
			(pads allowed)
			(copperpour not_allowed)
			(footprints allowed)
		)
		(placement
			(enabled no)
			(sheetname "")
		)
		(fill
			(thermal_gap 0.5)
			(thermal_bridge_width 0.5)
			(island_removal_mode 0)
		)
		(polygon
			(pts
				(xy 237.770416 -141.775942) (xy 237.770416 -143.579342) (xy 238.329216 -143.579342) (xy 238.329216 -141.775942)
			)
		)
	)
	(zone
		(layer "In1.Cu")
		(hatch none 0.5)
		(connect_pads
			(clearance 0)
		)
		(min_thickness 0.25)
		(keepout
			(tracks not_allowed)
			(vias allowed)
			(pads allowed)
			(copperpour not_allowed)
			(footprints allowed)
		)
		(placement
			(enabled no)
			(sheetname "")
		)
		(fill
			(thermal_gap 0.5)
			(thermal_bridge_width 0.5)
			(island_removal_mode 0)
		)
		(polygon
			(pts
				(xy 304.920396 -19.121882) (xy 304.920396 -20.925282) (xy 305.479196 -20.925282) (xy 305.479196 -19.121882)
			)
		)
	)
	(zone
		(layer "In1.Cu")
		(hatch none 0.5)
		(connect_pads
			(clearance 0)
		)
		(min_thickness 0.25)
		(keepout
			(tracks not_allowed)
			(vias allowed)
			(pads allowed)
			(copperpour not_allowed)
			(footprints allowed)
		)
		(placement
			(enabled no)
			(sheetname "")
		)
		(fill
			(thermal_gap 0.5)
			(thermal_bridge_width 0.5)
			(island_removal_mode 0)
		)
		(polygon
			(pts
				(xy 282.820364 -151.377142) (xy 282.820364 -153.180542) (xy 283.379164 -153.180542) (xy 283.379164 -151.377142)
			)
		)
	)
	(zone
		(layer "In1.Cu")
		(hatch none 0.5)
		(connect_pads
			(clearance 0)
		)
		(min_thickness 0.25)
		(keepout
			(tracks not_allowed)
			(vias allowed)
			(pads allowed)
			(copperpour not_allowed)
			(footprints allowed)
		)
		(placement
			(enabled no)
			(sheetname "")
		)
		(fill
			(thermal_gap 0.5)
			(thermal_bridge_width 0.5)
			(island_removal_mode 0)
		)
		(polygon
			(pts
				(xy 86.37016 -141.775942) (xy 86.37016 -143.579342) (xy 86.92896 -143.579342) (xy 86.92896 -141.775942)
			)
		)
	)
	(zone
		(layer "In1.Cu")
		(hatch none 0.5)
		(connect_pads
			(clearance 0)
		)
		(min_thickness 0.25)
		(keepout
			(tracks not_allowed)
			(vias allowed)
			(pads allowed)
			(copperpour not_allowed)
			(footprints allowed)
		)
		(placement
			(enabled no)
			(sheetname "")
		)
		(fill
			(thermal_gap 0.5)
			(thermal_bridge_width 0.5)
			(island_removal_mode 0)
		)
		(polygon
			(pts
				(xy 74.470006 4.680458) (xy 74.470006 2.877058) (xy 75.028806 2.877058) (xy 75.028806 4.680458)
			)
		)
	)
	(zone
		(layer "In1.Cu")
		(hatch none 0.5)
		(connect_pads
			(clearance 0)
		)
		(min_thickness 0.25)
		(keepout
			(tracks not_allowed)
			(vias allowed)
			(pads allowed)
			(copperpour not_allowed)
			(footprints allowed)
		)
		(placement
			(enabled no)
			(sheetname "")
		)
		(fill
			(thermal_gap 0.5)
			(thermal_bridge_width 0.5)
			(island_removal_mode 0)
		)
		(polygon
			(pts
				(xy 294.720518 -4.920742) (xy 294.720518 -6.724142) (xy 295.279318 -6.724142) (xy 295.279318 -4.920742)
			)
		)
	)
	(zone
		(layer "In1.Cu")
		(hatch none 0.5)
		(connect_pads
			(clearance 0)
		)
		(min_thickness 0.25)
		(keepout
			(tracks not_allowed)
			(vias allowed)
			(pads allowed)
			(copperpour not_allowed)
			(footprints allowed)
		)
		(placement
			(enabled no)
			(sheetname "")
		)
		(fill
			(thermal_gap 0.5)
			(thermal_bridge_width 0.5)
			(island_removal_mode 0)
		)
		(polygon
			(pts
				(xy 451.487032 -46.478698) (xy 452.795132 -46.478698) (xy 452.795132 -48.485298) (xy 451.487032 -48.485298)
			)
		)
	)
	(zone
		(layer "In1.Cu")
		(hatch none 0.5)
		(connect_pads
			(clearance 0)
		)
		(min_thickness 0.25)
		(keepout
			(tracks not_allowed)
			(vias allowed)
			(pads allowed)
			(copperpour not_allowed)
			(footprints allowed)
		)
		(placement
			(enabled no)
			(sheetname "")
		)
		(fill
			(thermal_gap 0.5)
			(thermal_bridge_width 0.5)
			(island_removal_mode 0)
		)
		(polygon
			(pts
				(xy 137.370058 -9.520682) (xy 137.370058 -11.324082) (xy 137.928858 -11.324082) (xy 137.928858 -9.520682)
			)
		)
	)
	(zone
		(layer "In1.Cu")
		(hatch none 0.5)
		(connect_pads
			(clearance 0)
		)
		(min_thickness 0.25)
		(keepout
			(tracks not_allowed)
			(vias allowed)
			(pads allowed)
			(copperpour not_allowed)
			(footprints allowed)
		)
		(placement
			(enabled no)
			(sheetname "")
		)
		(fill
			(thermal_gap 0.5)
			(thermal_bridge_width 0.5)
			(island_removal_mode 0)
		)
		(polygon
			(pts
				(xy 293.020496 -4.920742) (xy 293.020496 -6.724142) (xy 293.579296 -6.724142) (xy 293.579296 -4.920742)
			)
		)
	)
	(zone
		(layer "In1.Cu")
		(hatch none 0.5)
		(connect_pads
			(clearance 0)
		)
		(min_thickness 0.25)
		(keepout
			(tracks not_allowed)
			(vias allowed)
			(pads allowed)
			(copperpour not_allowed)
			(footprints allowed)
		)
		(placement
			(enabled no)
			(sheetname "")
		)
		(fill
			(thermal_gap 0.5)
			(thermal_bridge_width 0.5)
			(island_removal_mode 0)
		)
		(polygon
			(pts
				(xy 312.570368 -146.375882) (xy 312.570368 -148.179282) (xy 313.129168 -148.179282) (xy 313.129168 -146.375882)
			)
		)
	)
	(zone
		(layer "In1.Cu")
		(hatch none 0.5)
		(connect_pads
			(clearance 0)
		)
		(min_thickness 0.25)
		(keepout
			(tracks not_allowed)
			(vias allowed)
			(pads allowed)
			(copperpour not_allowed)
			(footprints allowed)
		)
		(placement
			(enabled no)
			(sheetname "")
		)
		(fill
			(thermal_gap 0.5)
			(thermal_bridge_width 0.5)
			(island_removal_mode 0)
		)
		(polygon
			(pts
				(xy 277.720552 0.080518) (xy 277.720552 -1.722882) (xy 278.279352 -1.722882) (xy 278.279352 0.080518)
			)
		)
	)
	(zone
		(layer "In1.Cu")
		(hatch none 0.5)
		(connect_pads
			(clearance 0)
		)
		(min_thickness 0.25)
		(keepout
			(tracks not_allowed)
			(vias allowed)
			(pads allowed)
			(copperpour not_allowed)
			(footprints allowed)
		)
		(placement
			(enabled no)
			(sheetname "")
		)
		(fill
			(thermal_gap 0.5)
			(thermal_bridge_width 0.5)
			(island_removal_mode 0)
		)
		(polygon
			(pts
				(xy 454.686924 -46.478698) (xy 455.995024 -46.478698) (xy 455.995024 -48.485298) (xy 454.686924 -48.485298)
			)
		)
	)
	(zone
		(layer "In1.Cu")
		(hatch none 0.5)
		(connect_pads
			(clearance 0)
		)
		(min_thickness 0.25)
		(keepout
			(tracks not_allowed)
			(vias allowed)
			(pads allowed)
			(copperpour not_allowed)
			(footprints allowed)
		)
		(placement
			(enabled no)
			(sheetname "")
		)
		(fill
			(thermal_gap 0.5)
			(thermal_bridge_width 0.5)
			(island_removal_mode 0)
		)
		(polygon
			(pts
				(xy 44.720002 -151.377142) (xy 44.720002 -153.180542) (xy 45.278802 -153.180542) (xy 45.278802 -151.377142)
			)
		)
	)
	(zone
		(layer "In1.Cu")
		(hatch none 0.5)
		(connect_pads
			(clearance 0)
		)
		(min_thickness 0.25)
		(keepout
			(tracks not_allowed)
			(vias allowed)
			(pads allowed)
			(copperpour not_allowed)
			(footprints allowed)
		)
		(placement
			(enabled no)
			(sheetname "")
		)
		(fill
			(thermal_gap 0.5)
			(thermal_bridge_width 0.5)
			(island_removal_mode 0)
		)
		(polygon
			(pts
				(xy 148.420074 -141.775942) (xy 148.420074 -143.579342) (xy 148.978874 -143.579342) (xy 148.978874 -141.775942)
			)
		)
	)
	(zone
		(layer "In1.Cu")
		(hatch none 0.5)
		(connect_pads
			(clearance 0)
		)
		(min_thickness 0.25)
		(keepout
			(tracks not_allowed)
			(vias allowed)
			(pads allowed)
			(copperpour not_allowed)
			(footprints allowed)
		)
		(placement
			(enabled no)
			(sheetname "")
		)
		(fill
			(thermal_gap 0.5)
			(thermal_bridge_width 0.5)
			(island_removal_mode 0)
		)
		(polygon
			(pts
				(xy 70.220078 -151.377142) (xy 70.220078 -153.180542) (xy 70.778878 -153.180542) (xy 70.778878 -151.377142)
			)
		)
	)
	(zone
		(layer "In1.Cu")
		(hatch none 0.5)
		(connect_pads
			(clearance 0)
		)
		(min_thickness 0.25)
		(keepout
			(tracks not_allowed)
			(vias allowed)
			(pads allowed)
			(copperpour not_allowed)
			(footprints allowed)
		)
		(placement
			(enabled no)
			(sheetname "")
		)
		(fill
			(thermal_gap 0.5)
			(thermal_bridge_width 0.5)
			(island_removal_mode 0)
		)
		(polygon
			(pts
				(xy 63.41999 -141.775942) (xy 63.41999 -143.579342) (xy 63.97879 -143.579342) (xy 63.97879 -141.775942)
			)
		)
	)
	(zone
		(layer "In1.Cu")
		(hatch none 0.5)
		(connect_pads
			(clearance 0)
		)
		(min_thickness 0.25)
		(keepout
			(tracks not_allowed)
			(vias allowed)
			(pads allowed)
			(copperpour not_allowed)
			(footprints allowed)
		)
		(placement
			(enabled no)
			(sheetname "")
		)
		(fill
			(thermal_gap 0.5)
			(thermal_bridge_width 0.5)
			(island_removal_mode 0)
		)
		(polygon
			(pts
				(xy 37.920168 -9.520682) (xy 37.920168 -11.324082) (xy 38.478968 -11.324082) (xy 38.478968 -9.520682)
			)
		)
	)
	(zone
		(layer "In1.Cu")
		(hatch none 0.5)
		(connect_pads
			(clearance 0)
		)
		(min_thickness 0.25)
		(keepout
			(tracks not_allowed)
			(vias allowed)
			(pads allowed)
			(copperpour not_allowed)
			(footprints allowed)
		)
		(placement
			(enabled no)
			(sheetname "")
		)
		(fill
			(thermal_gap 0.5)
			(thermal_bridge_width 0.5)
			(island_removal_mode 0)
		)
		(polygon
			(pts
				(xy 257.320542 -9.520682) (xy 257.320542 -11.324082) (xy 257.879342 -11.324082) (xy 257.879342 -9.520682)
			)
		)
	)
	(zone
		(layer "In1.Cu")
		(hatch none 0.5)
		(connect_pads
			(clearance 0)
		)
		(min_thickness 0.25)
		(keepout
			(tracks not_allowed)
			(vias allowed)
			(pads allowed)
			(copperpour not_allowed)
			(footprints allowed)
		)
		(placement
			(enabled no)
			(sheetname "")
		)
		(fill
			(thermal_gap 0.5)
			(thermal_bridge_width 0.5)
			(island_removal_mode 0)
		)
		(polygon
			(pts
				(xy 89.76995 -146.375882) (xy 89.76995 -148.179282) (xy 90.32875 -148.179282) (xy 90.32875 -146.375882)
			)
		)
	)
	(zone
		(layer "In1.Cu")
		(hatch none 0.5)
		(connect_pads
			(clearance 0)
		)
		(min_thickness 0.25)
		(keepout
			(tracks not_allowed)
			(vias allowed)
			(pads allowed)
			(copperpour not_allowed)
			(footprints allowed)
		)
		(placement
			(enabled no)
			(sheetname "")
		)
		(fill
			(thermal_gap 0.5)
			(thermal_bridge_width 0.5)
			(island_removal_mode 0)
		)
		(polygon
			(pts
				(xy 382.022604 -25.118568) (xy 383.572004 -25.118568) (xy 383.572004 -25.92324) (xy 382.022604 -25.92324)
			)
		)
	)
	(zone
		(layer "In1.Cu")
		(hatch none 0.5)
		(connect_pads
			(clearance 0)
		)
		(min_thickness 0.25)
		(keepout
			(tracks not_allowed)
			(vias allowed)
			(pads allowed)
			(copperpour not_allowed)
			(footprints allowed)
		)
		(placement
			(enabled no)
			(sheetname "")
		)
		(fill
			(thermal_gap 0.5)
			(thermal_bridge_width 0.5)
			(island_removal_mode 0)
		)
		(polygon
			(pts
				(xy 84.670138 -155.977082) (xy 84.670138 -157.780482) (xy 85.228938 -157.780482) (xy 85.228938 -155.977082)
			)
		)
	)
	(zone
		(layer "In1.Cu")
		(hatch none 0.5)
		(connect_pads
			(clearance 0)
		)
		(min_thickness 0.25)
		(keepout
			(tracks not_allowed)
			(vias allowed)
			(pads allowed)
			(copperpour not_allowed)
			(footprints allowed)
		)
		(placement
			(enabled no)
			(sheetname "")
		)
		(fill
			(thermal_gap 0.5)
			(thermal_bridge_width 0.5)
			(island_removal_mode 0)
		)
		(polygon
			(pts
				(xy 282.820364 -14.521942) (xy 282.820364 -16.325342) (xy 283.379164 -16.325342) (xy 283.379164 -14.521942)
			)
		)
	)
	(zone
		(layer "In1.Cu")
		(hatch none 0.5)
		(connect_pads
			(clearance 0)
		)
		(min_thickness 0.25)
		(keepout
			(tracks not_allowed)
			(vias allowed)
			(pads allowed)
			(copperpour not_allowed)
			(footprints allowed)
		)
		(placement
			(enabled no)
			(sheetname "")
		)
		(fill
			(thermal_gap 0.5)
			(thermal_bridge_width 0.5)
			(island_removal_mode 0)
		)
		(polygon
			(pts
				(xy 397.817086 -7.192772) (xy 399.125186 -7.192772) (xy 399.125186 -8.386572) (xy 397.817086 -8.386572)
			)
		)
	)
	(zone
		(layer "In1.Cu")
		(hatch none 0.5)
		(connect_pads
			(clearance 0)
		)
		(min_thickness 0.25)
		(keepout
			(tracks not_allowed)
			(vias allowed)
			(pads allowed)
			(copperpour not_allowed)
			(footprints allowed)
		)
		(placement
			(enabled no)
			(sheetname "")
		)
		(fill
			(thermal_gap 0.5)
			(thermal_bridge_width 0.5)
			(island_removal_mode 0)
		)
		(polygon
			(pts
				(xy 33.669986 -155.977082) (xy 33.669986 -157.780482) (xy 34.228786 -157.780482) (xy 34.228786 -155.977082)
			)
		)
	)
	(zone
		(layer "In1.Cu")
		(hatch none 0.5)
		(connect_pads
			(clearance 0)
		)
		(min_thickness 0.25)
		(keepout
			(tracks not_allowed)
			(vias allowed)
			(pads allowed)
			(copperpour not_allowed)
			(footprints allowed)
		)
		(placement
			(enabled no)
			(sheetname "")
		)
		(fill
			(thermal_gap 0.5)
			(thermal_bridge_width 0.5)
			(island_removal_mode 0)
		)
		(polygon
			(pts
				(xy 250.520454 0.080518) (xy 250.520454 -1.722882) (xy 251.079254 -1.722882) (xy 251.079254 0.080518)
			)
		)
	)
	(zone
		(layer "In1.Cu")
		(hatch none 0.5)
		(connect_pads
			(clearance 0)
		)
		(min_thickness 0.25)
		(keepout
			(tracks not_allowed)
			(vias allowed)
			(pads allowed)
			(copperpour not_allowed)
			(footprints allowed)
		)
		(placement
			(enabled no)
			(sheetname "")
		)
		(fill
			(thermal_gap 0.5)
			(thermal_bridge_width 0.5)
			(island_removal_mode 0)
		)
		(polygon
			(pts
				(xy 277.720552 -141.775942) (xy 277.720552 -143.579342) (xy 278.279352 -143.579342) (xy 278.279352 -141.775942)
			)
		)
	)
	(zone
		(layer "In1.Cu")
		(hatch none 0.5)
		(connect_pads
			(clearance 0)
		)
		(min_thickness 0.25)
		(keepout
			(tracks not_allowed)
			(vias allowed)
			(pads allowed)
			(copperpour not_allowed)
			(footprints allowed)
		)
		(placement
			(enabled no)
			(sheetname "")
		)
		(fill
			(thermal_gap 0.5)
			(thermal_bridge_width 0.5)
			(island_removal_mode 0)
		)
		(polygon
			(pts
				(xy 382.022604 -23.618444) (xy 383.572004 -23.618444) (xy 383.572004 -24.42337) (xy 382.022604 -24.42337)
			)
		)
	)
	(zone
		(layer "In1.Cu")
		(hatch none 0.5)
		(connect_pads
			(clearance 0)
		)
		(min_thickness 0.25)
		(keepout
			(tracks not_allowed)
			(vias allowed)
			(pads allowed)
			(copperpour not_allowed)
			(footprints allowed)
		)
		(placement
			(enabled no)
			(sheetname "")
		)
		(fill
			(thermal_gap 0.5)
			(thermal_bridge_width 0.5)
			(island_removal_mode 0)
		)
		(polygon
			(pts
				(xy 453.086978 -50.872644) (xy 454.395078 -50.872644) (xy 454.395078 -52.879244) (xy 453.086978 -52.879244)
			)
		)
	)
	(zone
		(layer "In1.Cu")
		(hatch none 0.5)
		(connect_pads
			(clearance 0)
		)
		(min_thickness 0.25)
		(keepout
			(tracks not_allowed)
			(vias allowed)
			(pads allowed)
			(copperpour not_allowed)
			(footprints allowed)
		)
		(placement
			(enabled no)
			(sheetname "")
		)
		(fill
			(thermal_gap 0.5)
			(thermal_bridge_width 0.5)
			(island_removal_mode 0)
		)
		(polygon
			(pts
				(xy 92.32011 -141.775942) (xy 92.32011 -143.579342) (xy 92.87891 -143.579342) (xy 92.87891 -141.775942)
			)
		)
	)
	(zone
		(layer "In1.Cu")
		(hatch none 0.5)
		(connect_pads
			(clearance 0)
		)
		(min_thickness 0.25)
		(keepout
			(tracks not_allowed)
			(vias allowed)
			(pads allowed)
			(copperpour not_allowed)
			(footprints allowed)
		)
		(placement
			(enabled no)
			(sheetname "")
		)
		(fill
			(thermal_gap 0.5)
			(thermal_bridge_width 0.5)
			(island_removal_mode 0)
		)
		(polygon
			(pts
				(xy 137.370058 -4.920742) (xy 137.370058 -6.724142) (xy 137.928858 -6.724142) (xy 137.928858 -4.920742)
			)
		)
	)
	(zone
		(layer "In1.Cu")
		(hatch none 0.5)
		(connect_pads
			(clearance 0)
		)
		(min_thickness 0.25)
		(keepout
			(tracks not_allowed)
			(vias allowed)
			(pads allowed)
			(copperpour not_allowed)
			(footprints allowed)
		)
		(placement
			(enabled no)
			(sheetname "")
		)
		(fill
			(thermal_gap 0.5)
			(thermal_bridge_width 0.5)
			(island_removal_mode 0)
		)
		(polygon
			(pts
				(xy 133.970014 -9.520682) (xy 133.970014 -11.324082) (xy 134.528814 -11.324082) (xy 134.528814 -9.520682)
			)
		)
	)
	(zone
		(layer "In1.Cu")
		(hatch none 0.5)
		(connect_pads
			(clearance 0)
		)
		(min_thickness 0.25)
		(keepout
			(tracks not_allowed)
			(vias allowed)
			(pads allowed)
			(copperpour not_allowed)
			(footprints allowed)
		)
		(placement
			(enabled no)
			(sheetname "")
		)
		(fill
			(thermal_gap 0.5)
			(thermal_bridge_width 0.5)
			(island_removal_mode 0)
		)
		(polygon
			(pts
				(xy 116.970048 -155.977082) (xy 116.970048 -157.780482) (xy 117.528848 -157.780482) (xy 117.528848 -155.977082)
			)
		)
	)
	(zone
		(layer "In1.Cu")
		(hatch none 0.5)
		(connect_pads
			(clearance 0)
		)
		(min_thickness 0.25)
		(keepout
			(tracks not_allowed)
			(vias allowed)
			(pads allowed)
			(copperpour not_allowed)
			(footprints allowed)
		)
		(placement
			(enabled no)
			(sheetname "")
		)
		(fill
			(thermal_gap 0.5)
			(thermal_bridge_width 0.5)
			(island_removal_mode 0)
		)
		(polygon
			(pts
				(xy 232.67035 -19.121882) (xy 232.67035 -20.925282) (xy 233.22915 -20.925282) (xy 233.22915 -19.121882)
			)
		)
	)
	(zone
		(layer "In1.Cu")
		(hatch none 0.5)
		(connect_pads
			(clearance 0)
		)
		(min_thickness 0.25)
		(keepout
			(tracks not_allowed)
			(vias allowed)
			(pads allowed)
			(copperpour not_allowed)
			(footprints allowed)
		)
		(placement
			(enabled no)
			(sheetname "")
		)
		(fill
			(thermal_gap 0.5)
			(thermal_bridge_width 0.5)
			(island_removal_mode 0)
		)
		(polygon
			(pts
				(xy 75.320144 0.080518) (xy 75.320144 -1.722882) (xy 75.878944 -1.722882) (xy 75.878944 0.080518)
			)
		)
	)
	(zone
		(layer "In1.Cu")
		(hatch none 0.5)
		(connect_pads
			(clearance 0)
		)
		(min_thickness 0.25)
		(keepout
			(tracks not_allowed)
			(vias allowed)
			(pads allowed)
			(copperpour not_allowed)
			(footprints allowed)
		)
		(placement
			(enabled no)
			(sheetname "")
		)
		(fill
			(thermal_gap 0.5)
			(thermal_bridge_width 0.5)
			(island_removal_mode 0)
		)
		(polygon
			(pts
				(xy 227.570538 -141.775942) (xy 227.570538 -143.579342) (xy 228.129338 -143.579342) (xy 228.129338 -141.775942)
			)
		)
	)
	(zone
		(layer "In1.Cu")
		(hatch none 0.5)
		(connect_pads
			(clearance 0)
		)
		(min_thickness 0.25)
		(keepout
			(tracks not_allowed)
			(vias allowed)
			(pads allowed)
			(copperpour not_allowed)
			(footprints allowed)
		)
		(placement
			(enabled no)
			(sheetname "")
		)
		(fill
			(thermal_gap 0.5)
			(thermal_bridge_width 0.5)
			(island_removal_mode 0)
		)
		(polygon
			(pts
				(xy 281.120342 -132.174742) (xy 281.120342 -133.978142) (xy 281.679142 -133.978142) (xy 281.679142 -132.174742)
			)
		)
	)
	(zone
		(layer "In1.Cu")
		(hatch none 0.5)
		(connect_pads
			(clearance 0)
		)
		(min_thickness 0.25)
		(keepout
			(tracks not_allowed)
			(vias allowed)
			(pads allowed)
			(copperpour not_allowed)
			(footprints allowed)
		)
		(placement
			(enabled no)
			(sheetname "")
		)
		(fill
			(thermal_gap 0.5)
			(thermal_bridge_width 0.5)
			(island_removal_mode 0)
		)
		(polygon
			(pts
				(xy 237.770416 -136.774682) (xy 237.770416 -138.578082) (xy 238.329216 -138.578082) (xy 238.329216 -136.774682)
			)
		)
	)
	(zone
		(layer "In1.Cu")
		(hatch none 0.5)
		(connect_pads
			(clearance 0)
		)
		(min_thickness 0.25)
		(keepout
			(tracks not_allowed)
			(vias allowed)
			(pads allowed)
			(copperpour not_allowed)
			(footprints allowed)
		)
		(placement
			(enabled no)
			(sheetname "")
		)
		(fill
			(thermal_gap 0.5)
			(thermal_bridge_width 0.5)
			(island_removal_mode 0)
		)
		(polygon
			(pts
				(xy 33.669986 -9.520682) (xy 33.669986 -11.324082) (xy 34.228786 -11.324082) (xy 34.228786 -9.520682)
			)
		)
	)
	(zone
		(layer "In1.Cu")
		(hatch none 0.5)
		(connect_pads
			(clearance 0)
		)
		(min_thickness 0.25)
		(keepout
			(tracks not_allowed)
			(vias allowed)
			(pads allowed)
			(copperpour not_allowed)
			(footprints allowed)
		)
		(placement
			(enabled no)
			(sheetname "")
		)
		(fill
			(thermal_gap 0.5)
			(thermal_bridge_width 0.5)
			(island_removal_mode 0)
		)
		(polygon
			(pts
				(xy 54.069996 -155.977082) (xy 54.069996 -157.780482) (xy 54.628796 -157.780482) (xy 54.628796 -155.977082)
			)
		)
	)
	(zone
		(net "GND")
		(layer "In1.Cu")
		(hatch none 0.5)
		(connect_pads
			(clearance 0.5)
		)
		(min_thickness 0.25)
		(fill yes
			(thermal_gap 0.5)
			(thermal_bridge_width 0.5)
			(island_removal_mode 0)
		)
		(polygon
			(pts
				(xy 483.851966 5.542534) (xy 483.851204 5.541772)
				(arc
					(start 280.680668 5.541772)
					(mid 280.597613 5.498329)
					(end 280.585418 5.405374)
				)
				(arc
					(start 280.585418 5.405374)
					(mid 280.2509 4.92707)
					(end 279.916382 5.405374)
				)
				(arc
					(start 279.916382 5.405374)
					(mid 279.904224 5.498355)
					(end 279.821132 5.541772)
				)
				(arc
					(start 279.499568 5.541772)
					(mid 279.416513 5.498329)
					(end 279.404318 5.405374)
				)
				(arc
					(start 279.404318 5.405374)
					(mid 279.0698 4.92707)
					(end 278.735282 5.405374)
				)
				(arc
					(start 278.735282 5.405374)
					(mid 278.723124 5.498355)
					(end 278.640032 5.541772)
				)
				(arc
					(start 278.565102 5.541772)
					(mid 278.477096 5.490498)
					(end 278.477726 5.38861)
				)
				(arc
					(start 278.477726 5.38861)
					(mid 278.516674 5.121485)
					(end 278.357076 4.903724)
				)
				(arc
					(start 278.357076 4.83743)
					(mid 278.370803 4.8027)
					(end 278.404574 4.786884)
				)
				(arc
					(start 278.404574 4.786884)
					(mid 278.528133 4.756098)
					(end 278.63292 4.68376)
				)
				(xy 278.981916 4.335018) (xy 278.981916 2.135632) (xy 278.805386 1.959356)
				(arc
					(start 278.715216 1.950212)
					(mid 278.600788 1.823846)
					(end 278.714962 1.697228)
				)
				(xy 278.804624 1.68783) (xy 278.943308 1.5494) (xy 278.943308 -0.054102) (xy 279.037796 -0.14859)
				(arc
					(start 279.037796 -2.516886)
					(mid 279.205987 -2.8194)
					(end 279.037796 -3.121914)
				)
				(xy 279.037796 -4.141724)
				(arc
					(start 278.940514 -4.217924)
					(mid 278.891818 -4.318)
					(end 278.940514 -4.418076)
				)
				(xy 279.037796 -4.494276) (xy 279.037796 -25.308306) (xy 270.4592 -33.886902) (xy 270.4592 -35.970718)
				(xy 270.231108 -36.19881) (xy 270.231108 -40.733726) (xy 270.412972 -40.91559) (xy 270.412972 -49.799494)
				(xy 270.016224 -50.195988) (xy 270.016224 -60.51677) (xy 269.768828 -60.764166) (xy 269.768828 -61.64199)
				(xy 269.13586 -62.275212)
				(arc
					(start 268.815312 -62.275212)
					(mid 268.557756 -62.385335)
					(end 268.3002 -62.275212)
				)
				(arc
					(start 266.951206 -62.275212)
					(mid 266.868573 -62.317699)
					(end 266.855194 -62.409578)
				)
				(arc
					(start 266.855194 -62.409578)
					(mid 266.518136 -62.880796)
					(end 266.181078 -62.409578)
				)
				(arc
					(start 266.181078 -62.409578)
					(mid 266.167577 -62.317787)
					(end 266.085066 -62.275212)
				)
				(arc
					(start 265.917172 -62.275212)
					(mid 265.659616 -62.385335)
					(end 265.40206 -62.275212)
				)
				(arc
					(start 265.234166 -62.275212)
					(mid 265.151533 -62.317699)
					(end 265.138154 -62.409578)
				)
				(arc
					(start 265.138154 -62.409578)
					(mid 264.801096 -62.880796)
					(end 264.464038 -62.409578)
				)
				(arc
					(start 264.464038 -62.409578)
					(mid 264.450537 -62.317787)
					(end 264.368026 -62.275212)
				)
				(arc
					(start 264.200386 -62.275212)
					(mid 263.94283 -62.385335)
					(end 263.685274 -62.275212)
				)
				(arc
					(start 263.51738 -62.275212)
					(mid 263.434747 -62.317699)
					(end 263.421368 -62.409578)
				)
				(arc
					(start 263.421368 -62.409578)
					(mid 263.08431 -62.880796)
					(end 262.747252 -62.409578)
				)
				(arc
					(start 262.747252 -62.409578)
					(mid 262.733751 -62.317787)
					(end 262.65124 -62.275212)
				)
				(arc
					(start 262.483346 -62.275212)
					(mid 262.22579 -62.385335)
					(end 261.968234 -62.275212)
				)
				(arc
					(start 261.80034 -62.275212)
					(mid 261.717707 -62.317699)
					(end 261.704328 -62.409578)
				)
				(arc
					(start 261.704328 -62.409578)
					(mid 261.431845 -62.874893)
					(end 261.011416 -62.53734)
				)
				(arc
					(start 261.011416 -62.53734)
					(mid 260.946957 -62.446505)
					(end 260.837934 -62.469268)
				)
				(xy 260.627622 -62.67958)
				(arc
					(start 259.970778 -62.67958)
					(mid 259.65023 -62.88067)
					(end 259.329682 -62.67958)
				)
				(arc
					(start 259.182362 -62.67958)
					(mid 259.093715 -62.731539)
					(end 259.095748 -62.834266)
				)
				(arc
					(start 259.095748 -62.834266)
					(mid 258.79171 -63.375804)
					(end 258.487672 -62.834266)
				)
				(arc
					(start 258.487672 -62.834266)
					(mid 258.489695 -62.731545)
					(end 258.401058 -62.67958)
				)
				(arc
					(start 258.253738 -62.67958)
					(mid 257.941707 -62.880568)
					(end 257.620262 -62.69482)
				)
				(xy 257.552698 -62.69482) (xy 257.39217 -62.855094)
				(arc
					(start 257.40487 -62.886336)
					(mid 257.174385 -63.361903)
					(end 256.724658 -63.08471)
				)
				(xy 256.716784 -63.043308) (xy 252.28169 -63.043308)
				(arc
					(start 252.273816 -63.08471)
					(mid 251.839349 -63.365524)
					(end 251.58319 -62.916054)
				)
				(xy 251.59208 -62.886844) (xy 251.129292 -62.42431)
				(arc
					(start 251.129292 -59.01817)
					(mid 251.10235 -58.949513)
					(end 251.036074 -58.917078)
				)
				(arc
					(start 251.036074 -58.917078)
					(mid 250.709246 -58.56224)
					(end 251.036074 -58.207402)
				)
				(arc
					(start 251.036074 -58.207402)
					(mid 251.102418 -58.175029)
					(end 251.129292 -58.10631)
				)
				(xy 251.129292 -57.97931) (xy 250.47829 -57.328308) (xy 250.44019 -57.328308) (xy 250.164092 -57.05221)
				(xy 250.164092 -56.44134)
				(arc
					(start 250.124976 -56.432196)
					(mid 249.850538 -56.085486)
					(end 250.124976 -55.738776)
				)
				(xy 250.164092 -55.729632) (xy 250.164092 -54.45379) (xy 250.595892 -54.02199) (xy 250.595892 -51.10099)
				(xy 250.975368 -50.721514) (xy 250.975368 -48.856646) (xy 250.3932 -48.274478) (xy 250.3932 -45.917612)
				(xy 250.23572 -45.759878)
				(arc
					(start 250.23572 -42.61993)
					(mid 250.157463 -42.521048)
					(end 250.043188 -42.574464)
				)
				(arc
					(start 250.043188 -42.574464)
					(mid 245.714902 -41.550082)
					(end 250.043188 -40.5257)
				)
				(arc
					(start 250.043188 -40.5257)
					(mid 250.157354 -40.579209)
					(end 250.23572 -40.480488)
				)
				(xy 250.23572 -36.219384) (xy 248.678192 -34.66211) (xy 248.678192 -33.88741) (xy 246.163592 -31.37281)
				(xy 246.163592 -29.45511) (xy 242.423696 -25.71496) (xy 242.423696 -24.92756) (xy 242.408456 -24.912574)
				(xy 242.408456 -23.006812)
				(arc
					(start 242.413028 -22.983444)
					(mid 242.414348 -22.965156)
					(end 242.413028 -22.946868)
				)
				(xy 242.408456 -22.9235)
				(arc
					(start 242.408456 -22.73681)
					(mid 242.378067 -22.664596)
					(end 242.305332 -22.635464)
				)
				(arc
					(start 242.305332 -22.635464)
					(mid 241.943592 -22.279356)
					(end 242.305332 -21.923248)
				)
				(arc
					(start 242.305332 -21.923248)
					(mid 242.378075 -21.894124)
					(end 242.408456 -21.821902)
				)
				(xy 242.408456 -20.925536) (xy 242.020344 -20.925536) (xy 242.020344 -19.121628) (xy 242.408456 -19.121628)
				(arc
					(start 242.408456 -18.720054)
					(mid 242.378067 -18.64784)
					(end 242.305332 -18.618708)
				)
				(arc
					(start 242.305332 -18.618708)
					(mid 241.943592 -18.2626)
					(end 242.305332 -17.906492)
				)
				(arc
					(start 242.305332 -17.906492)
					(mid 242.378075 -17.877368)
					(end 242.408456 -17.805146)
				)
				(xy 242.408456 -17.289526) (xy 242.420902 -17.246346)
				(arc
					(start 242.42141 -17.244822)
					(mid 242.426789 -17.208246)
					(end 242.42141 -17.17167)
				)
				(xy 242.420902 -17.170146) (xy 242.408456 -17.126966) (xy 242.408456 -13.445236) (xy 242.420902 -13.402056)
				(arc
					(start 242.42141 -13.400532)
					(mid 242.426789 -13.363956)
					(end 242.42141 -13.32738)
				)
				(xy 242.420902 -13.325856) (xy 242.408456 -13.282676) (xy 242.408456 -13.137388)
				(arc
					(start 242.305332 -13.034264)
					(mid 241.943592 -12.678156)
					(end 242.305332 -12.322048)
				)
				(arc
					(start 242.305332 -12.322048)
					(mid 242.378075 -12.292924)
					(end 242.408456 -12.220702)
				)
				(xy 242.408456 -11.324336) (xy 242.020344 -11.324336) (xy 242.020344 -9.520428) (xy 242.408456 -9.520428)
				(arc
					(start 242.408456 -9.118854)
					(mid 242.378067 -9.04664)
					(end 242.305332 -9.017508)
				)
				(arc
					(start 242.305332 -9.017508)
					(mid 241.943592 -8.6614)
					(end 242.305332 -8.305292)
				)
				(arc
					(start 242.305332 -8.305292)
					(mid 242.378075 -8.276168)
					(end 242.408456 -8.203946)
				)
				(xy 242.408456 -7.688326) (xy 242.420902 -7.645146)
				(arc
					(start 242.42141 -7.643622)
					(mid 242.426789 -7.607046)
					(end 242.42141 -7.57047)
				)
				(xy 242.420902 -7.568946) (xy 242.408456 -7.525766) (xy 242.408456 -3.844036) (xy 242.420902 -3.800856)
				(arc
					(start 242.42141 -3.799332)
					(mid 242.426789 -3.762756)
					(end 242.42141 -3.72618)
				)
				(xy 242.420902 -3.724656) (xy 242.408456 -3.681476)
				(arc
					(start 242.408456 -3.53441)
					(mid 242.378067 -3.462196)
					(end 242.305332 -3.433064)
				)
				(arc
					(start 242.305332 -3.433064)
					(mid 241.943592 -3.076956)
					(end 242.305332 -2.720848)
				)
				(arc
					(start 242.305332 -2.720848)
					(mid 242.378075 -2.691724)
					(end 242.408456 -2.619502)
				)
				(xy 242.408456 -1.723136) (xy 242.020344 -1.723136) (xy 242.020344 0.080772) (xy 242.408456 0.080772)
				(arc
					(start 242.408456 0.482346)
					(mid 242.378067 0.55456)
					(end 242.305332 0.583692)
				)
				(arc
					(start 242.305332 0.583692)
					(mid 241.943592 0.9398)
					(end 242.305332 1.295908)
				)
				(arc
					(start 242.305332 1.295908)
					(mid 242.378075 1.325032)
					(end 242.408456 1.397254)
				)
				(xy 242.408456 1.912874) (xy 242.420902 1.956054)
				(arc
					(start 242.42141 1.957578)
					(mid 242.426789 1.994154)
					(end 242.42141 2.03073)
				)
				(xy 242.420902 2.032254) (xy 242.408456 2.075434) (xy 242.408456 4.370578) (xy 243.245386 5.207508)
				(xy 267.058394 5.207508)
				(arc
					(start 267.072618 5.234686)
					(mid 267.38834 5.426007)
					(end 267.704062 5.234686)
				)
				(xy 267.718286 5.207508)
				(arc
					(start 267.803376 5.207508)
					(mid 268.12748 5.415905)
					(end 268.451584 5.207508)
				)
				(xy 277.812246 5.207508)
				(arc
					(start 277.817834 5.251958)
					(mid 277.834189 5.322684)
					(end 277.86457 5.38861)
				)
				(arc
					(start 277.86457 5.38861)
					(mid 277.865265 5.490535)
					(end 277.777194 5.541772)
				)
				(arc
					(start 167.243252 5.541772)
					(mid 167.157489 5.494645)
					(end 167.151304 5.396992)
				)
				(arc
					(start 167.151304 5.396992)
					(mid 166.828978 4.889502)
					(end 166.506652 5.396992)
				)
				(arc
					(start 166.506652 5.396992)
					(mid 166.500451 5.494636)
					(end 166.414704 5.541772)
				)
				(xy 115.669568 5.541772) (xy 114.810032 5.541772) (xy 114.751358 5.541772) (xy 113.971832 5.541772)
				(arc
					(start -3.675126 5.541772)
					(mid -4.995044 4.995044)
					(end -5.541772 3.675126)
				)
				(arc
					(start -5.541772 -156.77515)
					(mid -4.995044 -158.095068)
					(end -3.675126 -158.641796)
				)
				(xy 112.6109 -158.641796) (xy 112.6109 -158.210504) (xy 112.573054 -158.172658) (xy 78.524862 -158.172658)
				(arc
					(start 77.752956 -157.401006)
					(mid 77.642529 -157.379121)
					(end 77.579728 -157.472634)
				)
				(xy 77.579728 -157.780736) (xy 77.019912 -157.780736) (xy 77.019912 -155.976828) (xy 77.596492 -155.976828)
				(arc
					(start 77.596492 -155.531566)
					(mid 77.549365 -155.445803)
					(end 77.451712 -155.439618)
				)
				(arc
					(start 77.451712 -155.439618)
					(mid 76.943233 -155.1178)
					(end 77.451712 -154.795982)
				)
				(arc
					(start 77.451712 -154.795982)
					(mid 77.549356 -154.789781)
					(end 77.596492 -154.704034)
				)
				(arc
					(start 77.596492 -149.947122)
					(mid 77.549365 -149.861359)
					(end 77.451712 -149.855174)
				)
				(arc
					(start 77.451712 -149.855174)
					(mid 76.943233 -149.533356)
					(end 77.451712 -149.211538)
				)
				(arc
					(start 77.451712 -149.211538)
					(mid 77.549356 -149.205337)
					(end 77.596492 -149.11959)
				)
				(xy 77.596492 -148.179536) (xy 77.019912 -148.179536) (xy 77.019912 -146.375628) (xy 77.596492 -146.375628)
				(arc
					(start 77.596492 -145.930366)
					(mid 77.549365 -145.844603)
					(end 77.451712 -145.838418)
				)
				(arc
					(start 77.451712 -145.838418)
					(mid 76.943233 -145.5166)
					(end 77.451712 -145.194782)
				)
				(arc
					(start 77.451712 -145.194782)
					(mid 77.549356 -145.188581)
					(end 77.596492 -145.102834)
				)
				(arc
					(start 77.596492 -140.345922)
					(mid 77.549365 -140.260159)
					(end 77.451712 -140.253974)
				)
				(arc
					(start 77.451712 -140.253974)
					(mid 76.943233 -139.932156)
					(end 77.451712 -139.610338)
				)
				(arc
					(start 77.451712 -139.610338)
					(mid 77.549356 -139.604137)
					(end 77.596492 -139.51839)
				)
				(xy 77.596492 -138.578336) (xy 77.019912 -138.578336) (xy 77.019912 -136.774428) (xy 77.596492 -136.774428)
				(arc
					(start 77.596492 -136.329166)
					(mid 77.549365 -136.243403)
					(end 77.451712 -136.237218)
				)
				(arc
					(start 77.451712 -136.237218)
					(mid 76.943233 -135.9154)
					(end 77.451712 -135.593582)
				)
				(arc
					(start 77.451712 -135.593582)
					(mid 77.549356 -135.587381)
					(end 77.596492 -135.501634)
				)
				(arc
					(start 77.596492 -130.744722)
					(mid 77.549365 -130.658959)
					(end 77.451712 -130.652774)
				)
				(arc
					(start 77.451712 -130.652774)
					(mid 76.943233 -130.330956)
					(end 77.451712 -130.009138)
				)
				(arc
					(start 77.451712 -130.009138)
					(mid 77.549356 -130.002937)
					(end 77.596492 -129.91719)
				)
				(xy 77.596492 -129.692146) (xy 78.235048 -129.05359) (xy 78.235048 -126.715774) (xy 81.143348 -123.807474)
				(xy 81.143348 -117.53088) (xy 85.600032 -113.074196) (xy 85.600032 -105.528618) (xy 85.983572 -105.145332)
				(xy 85.983572 -97.544128)
				(arc
					(start 85.949028 -97.532444)
					(mid 85.713169 -97.251954)
					(end 85.849714 -96.911922)
				)
				(arc
					(start 85.849714 -96.911922)
					(mid 85.889713 -96.837827)
					(end 85.860128 -96.759014)
				)
				(xy 85.46846 -96.3676)
				(arc
					(start 85.46846 -96.137984)
					(mid 85.424755 -96.054493)
					(end 85.3313 -96.042988)
				)
				(arc
					(start 85.3313 -96.042988)
					(mid 84.850185 -95.709486)
					(end 85.3313 -95.375984)
				)
				(arc
					(start 85.3313 -95.375984)
					(mid 85.42466 -95.364342)
					(end 85.46846 -95.280988)
				)
				(arc
					(start 85.46846 -94.157038)
					(mid 85.424755 -94.073547)
					(end 85.3313 -94.062042)
				)
				(arc
					(start 85.3313 -94.062042)
					(mid 84.850185 -93.72854)
					(end 85.3313 -93.395038)
				)
				(arc
					(start 85.3313 -93.395038)
					(mid 85.42466 -93.383396)
					(end 85.46846 -93.300042)
				)
				(arc
					(start 85.46846 -93.166184)
					(mid 85.424755 -93.082693)
					(end 85.3313 -93.071188)
				)
				(arc
					(start 85.3313 -93.071188)
					(mid 84.850185 -92.737686)
					(end 85.3313 -92.404184)
				)
				(arc
					(start 85.3313 -92.404184)
					(mid 85.42466 -92.392542)
					(end 85.46846 -92.309188)
				)
				(xy 85.46846 -92.284804) (xy 86.36762 -91.385898) (xy 86.36762 -89.787984) (xy 86.67496 -89.48039)
				(xy 86.67496 -89.13749) (xy 86.729316 -89.083388)
				(arc
					(start 86.690708 -89.04478)
					(mid 86.656938 -88.53858)
					(end 87.163402 -88.512142)
				)
				(arc
					(start 87.163402 -88.512142)
					(mid 87.234153 -88.538588)
					(end 87.30361 -88.50884)
				)
				(xy 87.437468 -88.374982)
				(arc
					(start 87.432388 -88.348566)
					(mid 87.746432 -87.92589)
					(end 88.138 -88.277954)
				)
				(arc
					(start 88.138 -88.277954)
					(mid 88.168026 -88.349305)
					(end 88.2396 -88.378792)
				)
				(arc
					(start 89.04097 -88.378792)
					(mid 89.112542 -88.349303)
					(end 89.14257 -88.277954)
				)
				(arc
					(start 89.14257 -88.277954)
					(mid 89.498678 -87.924125)
					(end 89.854786 -88.277954)
				)
				(arc
					(start 89.854786 -88.277954)
					(mid 89.884812 -88.349305)
					(end 89.956386 -88.378792)
				)
				(arc
					(start 90.75801 -88.378792)
					(mid 90.829582 -88.349303)
					(end 90.85961 -88.277954)
				)
				(arc
					(start 90.85961 -88.277954)
					(mid 91.215718 -87.924125)
					(end 91.571826 -88.277954)
				)
				(arc
					(start 91.571826 -88.277954)
					(mid 91.601852 -88.349305)
					(end 91.673426 -88.378792)
				)
				(arc
					(start 92.47505 -88.378792)
					(mid 92.546622 -88.349303)
					(end 92.57665 -88.277954)
				)
				(arc
					(start 92.57665 -88.277954)
					(mid 92.932758 -87.924125)
					(end 93.288866 -88.277954)
				)
				(arc
					(start 93.288866 -88.277954)
					(mid 93.316759 -88.347376)
					(end 93.384624 -88.378792)
				)
				(arc
					(start 93.500194 -88.494362)
					(mid 93.533405 -88.509056)
					(end 93.568012 -88.497918)
				)
				(arc
					(start 93.568012 -88.497918)
					(mid 93.933832 -88.449005)
					(end 94.146624 -88.750648)
				)
				(xy 94.149926 -88.797892) (xy 95.14967 -88.797892)
				(arc
					(start 95.152972 -88.750648)
					(mid 95.651836 -88.449279)
					(end 95.766382 -89.02065)
				)
				(arc
					(start 95.885 -89.139268)
					(mid 95.973278 -89.167712)
					(end 96.047814 -89.112598)
				)
				(arc
					(start 96.047814 -89.112598)
					(mid 96.717785 -89.210402)
					(end 96.119188 -89.526618)
				)
				(arc
					(start 96.119188 -89.526618)
					(mid 96.008992 -89.506064)
					(end 95.946976 -89.599516)
				)
				(xy 95.946976 -89.89949)
				(arc
					(start 96.0501 -90.002868)
					(mid 96.085538 -90.017879)
					(end 96.12122 -90.00363)
				)
				(arc
					(start 96.12122 -90.00363)
					(mid 96.618378 -90.0099)
					(end 96.624648 -90.507058)
				)
				(xy 96.590358 -90.543126) (xy 96.763078 -90.715592) (xy 96.86925 -90.715592)
				(arc
					(start 96.878394 -90.676476)
					(mid 97.225358 -90.400416)
					(end 97.572322 -90.676476)
				)
				(xy 97.581466 -90.715592)
				(arc
					(start 97.792286 -90.715592)
					(mid 97.887662 -90.648307)
					(end 97.856802 -90.53576)
				)
				(arc
					(start 97.856802 -90.53576)
					(mid 98.083878 -89.905329)
					(end 98.310954 -90.53576)
				)
				(arc
					(start 98.310954 -90.53576)
					(mid 98.280127 -90.648295)
					(end 98.37547 -90.715592)
				)
				(xy 98.58629 -90.715592)
				(arc
					(start 98.595434 -90.676476)
					(mid 98.942398 -90.400416)
					(end 99.289362 -90.676476)
				)
				(xy 99.298506 -90.715592)
				(arc
					(start 99.509072 -90.715592)
					(mid 99.604448 -90.648307)
					(end 99.573588 -90.53576)
				)
				(arc
					(start 99.573588 -90.53576)
					(mid 99.800664 -89.905329)
					(end 100.02774 -90.53576)
				)
				(arc
					(start 100.02774 -90.53576)
					(mid 99.996913 -90.648295)
					(end 100.092256 -90.715592)
				)
				(xy 100.303076 -90.715592)
				(arc
					(start 100.31222 -90.676476)
					(mid 100.63584 -90.401182)
					(end 100.992686 -90.631772)
				)
				(xy 101.005132 -90.664792)
				(arc
					(start 101.173788 -90.664792)
					(mid 101.266092 -90.605092)
					(end 101.249988 -90.49639)
				)
				(arc
					(start 101.249988 -90.49639)
					(mid 101.353891 -89.945151)
					(end 101.863906 -90.178382)
				)
				(arc
					(start 101.863906 -90.178382)
					(mid 101.93509 -90.252523)
					(end 102.034594 -90.226642)
				)
				(arc
					(start 102.066598 -90.194638)
					(mid 102.152562 -90.127113)
					(end 102.127558 -90.020648)
				)
				(arc
					(start 102.127558 -90.020648)
					(mid 102.376224 -89.409883)
					(end 102.62489 -90.020648)
				)
				(arc
					(start 102.62489 -90.020648)
					(mid 102.601834 -90.13158)
					(end 102.695756 -90.194892)
				)
				(xy 102.79761 -90.194892) (xy 103.541576 -90.938858) (xy 103.541576 -97.743518)
				(arc
					(start 103.91013 -98.112326)
					(mid 104.00529 -98.1394)
					(end 104.078278 -98.072702)
				)
				(arc
					(start 104.078278 -98.072702)
					(mid 104.675618 -97.942602)
					(end 104.507538 -98.53041)
				)
				(arc
					(start 104.507538 -98.53041)
					(mid 104.44153 -98.586007)
					(end 104.442006 -98.672396)
				)
				(arc
					(start 104.442006 -98.672396)
					(mid 104.468129 -98.747268)
					(end 104.477058 -98.826066)
				)
				(arc
					(start 104.477058 -98.826066)
					(mid 104.667627 -98.925057)
					(end 104.766618 -99.115626)
				)
				(arc
					(start 104.766618 -99.115626)
					(mid 104.902373 -99.142727)
					(end 105.01757 -99.219512)
				)
				(xy 105.97642 -100.178362) (xy 105.97642 -103.61549) (xy 106.640376 -104.279446) (xy 106.640376 -111.972598)
				(xy 106.247184 -112.365536) (xy 106.247184 -119.366538) (xy 112.42548 -125.544834) (xy 112.42548 -126.85141)
				(xy 114.143028 -128.568704) (xy 114.143028 -130.395218) (xy 113.888012 -130.64998) (xy 113.888012 -131.663948)
				(xy 114.143028 -131.91871) (xy 114.143028 -134.424928) (xy 113.763552 -134.80415) (xy 113.763552 -149.095714)
				(arc
					(start 113.803176 -149.104858)
					(mid 114.080668 -149.452076)
					(end 113.803176 -149.799294)
				)
				(xy 113.763552 -149.808438) (xy 113.763552 -153.915364) (xy 113.592356 -154.086814) (xy 113.592356 -154.41168)
				(xy 113.763552 -154.58313) (xy 113.763552 -155.258262)
				(arc
					(start 113.804192 -155.266644)
					(mid 114.088586 -155.615386)
					(end 113.804192 -155.964128)
				)
				(xy 113.763552 -155.97251) (xy 113.763552 -157.8356) (xy 113.890552 -157.9626) (xy 114.2492 -157.9626)
				(xy 114.4778 -158.1912) (xy 114.4778 -158.5849) (xy 114.534696 -158.641796)
				(arc
					(start 185.770012 -158.641796)
					(mid 185.86314 -158.580813)
					(end 185.844434 -158.471108)
				)
				(arc
					(start 185.844434 -158.471108)
					(mid 186.1058 -157.873234)
					(end 186.367166 -158.471108)
				)
				(arc
					(start 186.367166 -158.471108)
					(mid 186.348509 -158.580792)
					(end 186.441588 -158.641796)
				)
				(arc
					(start 393.779248 -158.641796)
					(mid 393.868339 -158.589036)
					(end 393.864846 -158.485586)
				)
				(arc
					(start 393.864846 -158.485586)
					(mid 393.984546 -157.987522)
					(end 394.478256 -158.124652)
				)
				(arc
					(start 394.478256 -158.124652)
					(mid 394.557615 -158.177363)
					(end 394.645642 -158.141162)
				)
				(arc
					(start 394.645642 -158.141162)
					(mid 394.921541 -158.012996)
					(end 395.195806 -158.144718)
				)
				(arc
					(start 395.195806 -158.144718)
					(mid 395.2748 -158.182381)
					(end 395.353794 -158.144718)
				)
				(arc
					(start 395.353794 -158.144718)
					(mid 395.615465 -158.013205)
					(end 395.887194 -158.122366)
				)
				(arc
					(start 395.887194 -158.122366)
					(mid 395.9606 -158.153687)
					(end 396.034006 -158.122366)
				)
				(arc
					(start 396.034006 -158.122366)
					(mid 396.48419 -158.070049)
					(end 396.621 -158.502096)
				)
				(arc
					(start 396.621 -158.502096)
					(mid 396.63096 -158.597025)
					(end 396.715234 -158.641796)
				)
				(arc
					(start 396.788132 -158.641796)
					(mid 396.832578 -158.615134)
					(end 396.83055 -158.56331)
				)
				(arc
					(start 396.83055 -158.56331)
					(mid 397.094515 -158.014543)
					(end 397.4592 -158.502096)
				)
				(arc
					(start 397.4592 -158.502096)
					(mid 397.46916 -158.597025)
					(end 397.553434 -158.641796)
				)
				(xy 425.379134 -158.641796) (xy 427.700186 -158.641796) (xy 437.211724 -158.641796) (xy 449.98005 -158.641796)
				(xy 492.591344 -158.641796) (xy 497.269262 -158.641796)
				(arc
					(start 499.674896 -158.641796)
					(mid 500.994994 -158.094994)
					(end 501.541796 -156.774896)
				)
				(arc
					(start 501.541796 -112.203992)
					(mid 500.995068 -110.884074)
					(end 499.67515 -110.337346)
				)
				(arc
					(start 488.267756 -110.337346)
					(mid 488.18139 -110.385435)
					(end 488.176824 -110.484158)
				)
				(arc
					(start 488.176824 -110.484158)
					(mid 488.03596 -110.950744)
					(end 487.561382 -110.839758)
				)
				(arc
					(start 487.561382 -110.839758)
					(mid 487.4768 -110.794491)
					(end 487.392218 -110.839758)
				)
				(arc
					(start 487.392218 -110.839758)
					(mid 487.0958 -110.998509)
					(end 486.799382 -110.839758)
				)
				(arc
					(start 486.799382 -110.839758)
					(mid 486.7148 -110.794491)
					(end 486.630218 -110.839758)
				)
				(arc
					(start 486.630218 -110.839758)
					(mid 486.155642 -110.95074)
					(end 486.014776 -110.484158)
				)
				(arc
					(start 486.014776 -110.484158)
					(mid 486.025261 -110.433717)
					(end 486.009696 -110.38459)
				)
				(xy 427.63059 -110.38459) (xy 426.7454 -109.4994) (xy 426.7454 -68.2244) (xy 427.549056 -67.420744)
				(xy 428.1932 -67.420744) (xy 429.980344 -67.420744)
				(arc
					(start 478.267014 -67.420744)
					(mid 478.784816 -67.206264)
					(end 478.999296 -66.688462)
				)
				(xy 478.999296 -63.087504) (xy 479.206052 -62.880748) (xy 479.8695 -62.2173) (xy 480.6188 -62.2173)
				(xy 480.62261 -62.22111) (xy 480.64801 -62.220856)
				(arc
					(start 499.674896 -62.220856)
					(mid 500.994994 -61.674054)
					(end 501.541796 -60.353956)
				)
				(xy 501.541796 -17.677892) (xy 501.542558 -17.677892)
				(arc
					(start 501.542558 -16.999966)
					(mid 501.541789 -16.971351)
					(end 501.53951 -16.942816)
				)
				(xy 501.53951 -14.96949) (xy 501.0404 -14.47038) (xy 483.9589 -14.47038) (xy 483.39248 -13.90396)
				(arc
					(start 483.39248 0.500126)
					(mid 483.416529 0.713383)
					(end 483.487476 0.915924)
				)
				(xy 483.362 1.0414) (xy 483.362 2.8702) (xy 483.9716 3.4798) (xy 501.0404 3.4798) (xy 501.523 3.9624)
				(xy 501.523 5.0038) (xy 500.98706 5.53974) (xy 487.75874 5.53974) (xy 487.7562 5.542534)
			)
		)
		(polygon
			(pts
				(xy 19.11985 -55.668926) (xy 13.038836 -55.668926) (xy 13.034772 -55.67299) (xy 11.402314 -55.67299)
				(xy 11.21791 -55.488586) (xy 10.897362 -55.809134) (xy 10.897362 -68.494402) (xy 11.265916 -68.862956)
				(xy 18.954242 -68.862956) (xy 20.08759 -67.729608) (xy 20.08759 -56.636666)
			)
		)
		(polygon
			(pts
				(arc
					(start 483.391972 -13.360908)
					(mid 483.337595 -13.280843)
					(end 483.240842 -13.282676)
				)
				(arc
					(start 483.240842 -13.282676)
					(mid 482.878878 -13.387375)
					(end 482.50856 -13.317728)
				)
				(arc
					(start 482.50856 -13.317728)
					(mid 482.403723 -13.331158)
					(end 482.36759 -13.430504)
				)
				(arc
					(start 482.36759 -13.430504)
					(mid 482.383385 -13.590016)
					(end 482.36759 -13.749528)
				)
				(arc
					(start 482.36759 -13.749528)
					(mid 482.403701 -13.848901)
					(end 482.50856 -13.862304)
				)
				(arc
					(start 482.50856 -13.862304)
					(mid 482.87888 -13.792621)
					(end 483.240842 -13.897356)
				)
				(arc
					(start 483.240842 -13.897356)
					(mid 483.337582 -13.899163)
					(end 483.391972 -13.819124)
				)
			)
		)
		(polygon
			(pts
				(arc
					(start 483.391972 -11.388852)
					(mid 483.338904 -11.309477)
					(end 483.243382 -11.309096)
				)
				(arc
					(start 483.243382 -11.309096)
					(mid 482.908897 -11.40638)
					(end 482.56317 -11.363706)
				)
				(arc
					(start 482.56317 -11.363706)
					(mid 482.467253 -11.380574)
					(end 482.429566 -11.470386)
				)
				(arc
					(start 482.429566 -11.470386)
					(mid 482.43382 -11.58555)
					(end 482.422708 -11.700256)
				)
				(arc
					(start 482.422708 -11.700256)
					(mid 482.458247 -11.795014)
					(end 482.55809 -11.812016)
				)
				(arc
					(start 482.55809 -11.812016)
					(mid 482.905572 -11.764346)
					(end 483.240842 -11.867388)
				)
				(arc
					(start 483.240842 -11.867388)
					(mid 483.337582 -11.869195)
					(end 483.391972 -11.789156)
				)
			)
		)
		(polygon
			(pts
				(arc
					(start 483.391972 -9.388856)
					(mid 483.338904 -9.309481)
					(end 483.243382 -9.3091)
				)
				(arc
					(start 483.243382 -9.3091)
					(mid 482.908897 -9.406384)
					(end 482.56317 -9.36371)
				)
				(arc
					(start 482.56317 -9.36371)
					(mid 482.467253 -9.380578)
					(end 482.429566 -9.47039)
				)
				(arc
					(start 482.429566 -9.47039)
					(mid 482.43382 -9.585554)
					(end 482.422708 -9.70026)
				)
				(arc
					(start 482.422708 -9.70026)
					(mid 482.458247 -9.795018)
					(end 482.55809 -9.81202)
				)
				(arc
					(start 482.55809 -9.81202)
					(mid 482.905572 -9.76435)
					(end 483.240842 -9.867392)
				)
				(arc
					(start 483.240842 -9.867392)
					(mid 483.337582 -9.869199)
					(end 483.391972 -9.78916)
				)
			)
		)
		(polygon
			(pts
				(arc
					(start 483.391972 -7.300976)
					(mid 483.337595 -7.220911)
					(end 483.240842 -7.222744)
				)
				(arc
					(start 483.240842 -7.222744)
					(mid 482.878878 -7.327443)
					(end 482.50856 -7.257796)
				)
				(arc
					(start 482.50856 -7.257796)
					(mid 482.403723 -7.271226)
					(end 482.36759 -7.370572)
				)
				(arc
					(start 482.36759 -7.370572)
					(mid 482.383385 -7.530084)
					(end 482.36759 -7.689596)
				)
				(arc
					(start 482.36759 -7.689596)
					(mid 482.403701 -7.788969)
					(end 482.50856 -7.802372)
				)
				(arc
					(start 482.50856 -7.802372)
					(mid 482.87888 -7.732689)
					(end 483.240842 -7.837424)
				)
				(arc
					(start 483.240842 -7.837424)
					(mid 483.337582 -7.839231)
					(end 483.391972 -7.759192)
				)
			)
		)
		(polygon
			(pts
				(arc
					(start 483.391972 -5.241036)
					(mid 483.337595 -5.160971)
					(end 483.240842 -5.162804)
				)
				(arc
					(start 483.240842 -5.162804)
					(mid 482.878878 -5.267503)
					(end 482.50856 -5.197856)
				)
				(arc
					(start 482.50856 -5.197856)
					(mid 482.403723 -5.211286)
					(end 482.36759 -5.310632)
				)
				(arc
					(start 482.36759 -5.310632)
					(mid 482.383385 -5.470144)
					(end 482.36759 -5.629656)
				)
				(arc
					(start 482.36759 -5.629656)
					(mid 482.403701 -5.729029)
					(end 482.50856 -5.742432)
				)
				(arc
					(start 482.50856 -5.742432)
					(mid 482.87888 -5.672749)
					(end 483.240842 -5.777484)
				)
				(arc
					(start 483.240842 -5.777484)
					(mid 483.337582 -5.779291)
					(end 483.391972 -5.699252)
				)
			)
		)
		(polygon
			(pts
				(arc
					(start 483.391972 -3.211068)
					(mid 483.337595 -3.131003)
					(end 483.240842 -3.132836)
				)
				(arc
					(start 483.240842 -3.132836)
					(mid 482.878878 -3.237535)
					(end 482.50856 -3.167888)
				)
				(arc
					(start 482.50856 -3.167888)
					(mid 482.403723 -3.181318)
					(end 482.36759 -3.280664)
				)
				(arc
					(start 482.36759 -3.280664)
					(mid 482.383385 -3.440176)
					(end 482.36759 -3.599688)
				)
				(arc
					(start 482.36759 -3.599688)
					(mid 482.403701 -3.699061)
					(end 482.50856 -3.712464)
				)
				(arc
					(start 482.50856 -3.712464)
					(mid 482.87888 -3.642781)
					(end 483.240842 -3.747516)
				)
				(arc
					(start 483.240842 -3.747516)
					(mid 483.337582 -3.749323)
					(end 483.391972 -3.669284)
				)
			)
		)
		(polygon
			(pts
				(arc
					(start 483.391972 -1.1811)
					(mid 483.337595 -1.101035)
					(end 483.240842 -1.102868)
				)
				(arc
					(start 483.240842 -1.102868)
					(mid 482.878878 -1.207567)
					(end 482.50856 -1.13792)
				)
				(arc
					(start 482.50856 -1.13792)
					(mid 482.403723 -1.15135)
					(end 482.36759 -1.250696)
				)
				(arc
					(start 482.36759 -1.250696)
					(mid 482.383385 -1.410208)
					(end 482.36759 -1.56972)
				)
				(arc
					(start 482.36759 -1.56972)
					(mid 482.403701 -1.669093)
					(end 482.50856 -1.682496)
				)
				(arc
					(start 482.50856 -1.682496)
					(mid 482.87888 -1.612813)
					(end 483.240842 -1.717548)
				)
				(arc
					(start 483.240842 -1.717548)
					(mid 483.337582 -1.719355)
					(end 483.391972 -1.639316)
				)
			)
		)
		(polygon
			(pts
				(arc
					(start 483.446836 0.819404)
					(mid 483.406802 0.927079)
					(end 483.291896 0.928624)
				)
				(arc
					(start 483.291896 0.928624)
					(mid 482.908809 0.794446)
					(end 482.50856 0.862076)
				)
				(arc
					(start 482.50856 0.862076)
					(mid 482.403723 0.848646)
					(end 482.36759 0.7493)
				)
				(arc
					(start 482.36759 0.7493)
					(mid 482.383385 0.589788)
					(end 482.36759 0.430276)
				)
				(arc
					(start 482.36759 0.430276)
					(mid 482.403701 0.330903)
					(end 482.50856 0.3175)
				)
				(arc
					(start 482.50856 0.3175)
					(mid 482.87888 0.387183)
					(end 483.240842 0.282448)
				)
				(arc
					(start 483.240842 0.282448)
					(mid 483.337582 0.280641)
					(end 483.391972 0.36068)
				)
				(arc
					(start 483.391972 0.500126)
					(mid 483.40581 0.662101)
					(end 483.446836 0.819404)
				)
			)
		)
	)
	(zone
		(layer "In1.Cu")
		(hatch none 0.5)
		(connect_pads
			(clearance 0)
		)
		(min_thickness 0.25)
		(keepout
			(tracks not_allowed)
			(vias allowed)
			(pads allowed)
			(copperpour not_allowed)
			(footprints allowed)
		)
		(placement
			(enabled no)
			(sheetname "")
		)
		(fill
			(thermal_gap 0.5)
			(thermal_bridge_width 0.5)
			(island_removal_mode 0)
		)
		(polygon
			(pts
				(xy 229.27056 -19.121882) (xy 229.27056 -20.925282) (xy 229.82936 -20.925282) (xy 229.82936 -19.121882)
			)
		)
	)
	(zone
		(layer "In1.Cu")
		(hatch none 0.5)
		(connect_pads
			(clearance 0)
		)
		(min_thickness 0.25)
		(keepout
			(tracks not_allowed)
			(vias allowed)
			(pads allowed)
			(copperpour not_allowed)
			(footprints allowed)
		)
		(placement
			(enabled no)
			(sheetname "")
		)
		(fill
			(thermal_gap 0.5)
			(thermal_bridge_width 0.5)
			(island_removal_mode 0)
		)
		(polygon
			(pts
				(xy 75.320144 -19.121882) (xy 75.320144 -20.925282) (xy 75.878944 -20.925282) (xy 75.878944 -19.121882)
			)
		)
	)
	(zone
		(layer "In1.Cu")
		(hatch none 0.5)
		(connect_pads
			(clearance 0)
		)
		(min_thickness 0.25)
		(keepout
			(tracks not_allowed)
			(vias allowed)
			(pads allowed)
			(copperpour not_allowed)
			(footprints allowed)
		)
		(placement
			(enabled no)
			(sheetname "")
		)
		(fill
			(thermal_gap 0.5)
			(thermal_bridge_width 0.5)
			(island_removal_mode 0)
		)
		(polygon
			(pts
				(xy 211.420456 -141.775942) (xy 211.420456 -143.579342) (xy 211.979256 -143.579342) (xy 211.979256 -141.775942)
			)
		)
	)
	(zone
		(layer "In1.Cu")
		(hatch none 0.5)
		(connect_pads
			(clearance 0)
		)
		(min_thickness 0.25)
		(keepout
			(tracks not_allowed)
			(vias allowed)
			(pads allowed)
			(copperpour not_allowed)
			(footprints allowed)
		)
		(placement
			(enabled no)
			(sheetname "")
		)
		(fill
			(thermal_gap 0.5)
			(thermal_bridge_width 0.5)
			(island_removal_mode 0)
		)
		(polygon
			(pts
				(xy 301.520352 -132.174742) (xy 301.520352 -133.978142) (xy 302.079152 -133.978142) (xy 302.079152 -132.174742)
			)
		)
	)
	(zone
		(layer "In1.Cu")
		(hatch none 0.5)
		(connect_pads
			(clearance 0)
		)
		(min_thickness 0.25)
		(keepout
			(tracks not_allowed)
			(vias allowed)
			(pads allowed)
			(copperpour not_allowed)
			(footprints allowed)
		)
		(placement
			(enabled no)
			(sheetname "")
		)
		(fill
			(thermal_gap 0.5)
			(thermal_bridge_width 0.5)
			(island_removal_mode 0)
		)
		(polygon
			(pts
				(xy 60.019946 -19.121882) (xy 60.019946 -20.925282) (xy 60.578746 -20.925282) (xy 60.578746 -19.121882)
			)
		)
	)
	(zone
		(layer "In1.Cu")
		(hatch none 0.5)
		(connect_pads
			(clearance 0)
		)
		(min_thickness 0.25)
		(keepout
			(tracks not_allowed)
			(vias allowed)
			(pads allowed)
			(copperpour not_allowed)
			(footprints allowed)
		)
		(placement
			(enabled no)
			(sheetname "")
		)
		(fill
			(thermal_gap 0.5)
			(thermal_bridge_width 0.5)
			(island_removal_mode 0)
		)
		(polygon
			(pts
				(xy 279.42032 -151.377142) (xy 279.42032 -153.180542) (xy 279.97912 -153.180542) (xy 279.97912 -151.377142)
			)
		)
	)
	(zone
		(layer "In1.Cu")
		(hatch none 0.5)
		(connect_pads
			(clearance 0)
		)
		(min_thickness 0.25)
		(keepout
			(tracks not_allowed)
			(vias allowed)
			(pads allowed)
			(copperpour not_allowed)
			(footprints allowed)
		)
		(placement
			(enabled no)
			(sheetname "")
		)
		(fill
			(thermal_gap 0.5)
			(thermal_bridge_width 0.5)
			(island_removal_mode 0)
		)
		(polygon
			(pts
				(xy 82.119978 -141.775942) (xy 82.119978 -143.579342) (xy 82.678778 -143.579342) (xy 82.678778 -141.775942)
			)
		)
	)
	(zone
		(layer "In1.Cu")
		(hatch none 0.5)
		(connect_pads
			(clearance 0)
		)
		(min_thickness 0.25)
		(keepout
			(tracks not_allowed)
			(vias allowed)
			(pads allowed)
			(copperpour not_allowed)
			(footprints allowed)
		)
		(placement
			(enabled no)
			(sheetname "")
		)
		(fill
			(thermal_gap 0.5)
			(thermal_bridge_width 0.5)
			(island_removal_mode 0)
		)
		(polygon
			(pts
				(xy 137.370058 -19.121882) (xy 137.370058 -20.925282) (xy 137.928858 -20.925282) (xy 137.928858 -19.121882)
			)
		)
	)
	(zone
		(layer "In1.Cu")
		(hatch none 0.5)
		(connect_pads
			(clearance 0)
		)
		(min_thickness 0.25)
		(keepout
			(tracks not_allowed)
			(vias allowed)
			(pads allowed)
			(copperpour not_allowed)
			(footprints allowed)
		)
		(placement
			(enabled no)
			(sheetname "")
		)
		(fill
			(thermal_gap 0.5)
			(thermal_bridge_width 0.5)
			(island_removal_mode 0)
		)
		(polygon
			(pts
				(xy 207.170528 -132.174742) (xy 207.170528 -133.978142) (xy 207.729328 -133.978142) (xy 207.729328 -132.174742)
			)
		)
	)
	(zone
		(layer "In1.Cu")
		(hatch none 0.5)
		(connect_pads
			(clearance 0)
		)
		(min_thickness 0.25)
		(keepout
			(tracks not_allowed)
			(vias allowed)
			(pads allowed)
			(copperpour not_allowed)
			(footprints allowed)
		)
		(placement
			(enabled no)
			(sheetname "")
		)
		(fill
			(thermal_gap 0.5)
			(thermal_bridge_width 0.5)
			(island_removal_mode 0)
		)
		(polygon
			(pts
				(xy 88.070182 -9.520682) (xy 88.070182 -11.324082) (xy 88.628982 -11.324082) (xy 88.628982 -9.520682)
			)
		)
	)
	(zone
		(layer "In1.Cu")
		(hatch none 0.5)
		(connect_pads
			(clearance 0)
		)
		(min_thickness 0.25)
		(keepout
			(tracks not_allowed)
			(vias allowed)
			(pads allowed)
			(copperpour not_allowed)
			(footprints allowed)
		)
		(placement
			(enabled no)
			(sheetname "")
		)
		(fill
			(thermal_gap 0.5)
			(thermal_bridge_width 0.5)
			(island_removal_mode 0)
		)
		(polygon
			(pts
				(xy 44.720002 -146.375882) (xy 44.720002 -148.179282) (xy 45.278802 -148.179282) (xy 45.278802 -146.375882)
			)
		)
	)
	(zone
		(layer "In1.Cu")
		(hatch none 0.5)
		(connect_pads
			(clearance 0)
		)
		(min_thickness 0.25)
		(keepout
			(tracks not_allowed)
			(vias allowed)
			(pads allowed)
			(copperpour not_allowed)
			(footprints allowed)
		)
		(placement
			(enabled no)
			(sheetname "")
		)
		(fill
			(thermal_gap 0.5)
			(thermal_bridge_width 0.5)
			(island_removal_mode 0)
		)
		(polygon
			(pts
				(xy 219.070428 0.080518) (xy 219.070428 -1.722882) (xy 219.629228 -1.722882) (xy 219.629228 0.080518)
			)
		)
	)
	(zone
		(layer "In1.Cu")
		(hatch none 0.5)
		(connect_pads
			(clearance 0)
		)
		(min_thickness 0.25)
		(keepout
			(tracks not_allowed)
			(vias allowed)
			(pads allowed)
			(copperpour not_allowed)
			(footprints allowed)
		)
		(placement
			(enabled no)
			(sheetname "")
		)
		(fill
			(thermal_gap 0.5)
			(thermal_bridge_width 0.5)
			(island_removal_mode 0)
		)
		(polygon
			(pts
				(xy 130.56997 -155.977082) (xy 130.56997 -157.780482) (xy 131.12877 -157.780482) (xy 131.12877 -155.977082)
			)
		)
	)
	(zone
		(layer "In1.Cu")
		(hatch none 0.5)
		(connect_pads
			(clearance 0)
		)
		(min_thickness 0.25)
		(keepout
			(tracks not_allowed)
			(vias allowed)
			(pads allowed)
			(copperpour not_allowed)
			(footprints allowed)
		)
		(placement
			(enabled no)
			(sheetname "")
		)
		(fill
			(thermal_gap 0.5)
			(thermal_bridge_width 0.5)
			(island_removal_mode 0)
		)
		(polygon
			(pts
				(xy 54.920134 -146.375882) (xy 54.920134 -148.179282) (xy 55.478934 -148.179282) (xy 55.478934 -146.375882)
			)
		)
	)
	(zone
		(layer "In1.Cu")
		(hatch none 0.5)
		(connect_pads
			(clearance 0)
		)
		(min_thickness 0.25)
		(keepout
			(tracks not_allowed)
			(vias allowed)
			(pads allowed)
			(copperpour not_allowed)
			(footprints allowed)
		)
		(placement
			(enabled no)
			(sheetname "")
		)
		(fill
			(thermal_gap 0.5)
			(thermal_bridge_width 0.5)
			(island_removal_mode 0)
		)
		(polygon
			(pts
				(xy 200.37044 -9.520682) (xy 200.37044 -11.324082) (xy 200.92924 -11.324082) (xy 200.92924 -9.520682)
			)
		)
	)
	(zone
		(layer "In1.Cu")
		(hatch none 0.5)
		(connect_pads
			(clearance 0)
		)
		(min_thickness 0.25)
		(keepout
			(tracks not_allowed)
			(vias allowed)
			(pads allowed)
			(copperpour not_allowed)
			(footprints allowed)
		)
		(placement
			(enabled no)
			(sheetname "")
		)
		(fill
			(thermal_gap 0.5)
			(thermal_bridge_width 0.5)
			(island_removal_mode 0)
		)
		(polygon
			(pts
				(xy 323.4055 -123.571) (xy 325.6915 -123.571) (xy 325.6915 -124.079) (xy 323.4055 -124.079)
			)
		)
	)
	(zone
		(layer "In1.Cu")
		(hatch none 0.5)
		(connect_pads
			(clearance 0)
		)
		(min_thickness 0.25)
		(keepout
			(tracks not_allowed)
			(vias allowed)
			(pads allowed)
			(copperpour not_allowed)
			(footprints allowed)
		)
		(placement
			(enabled no)
			(sheetname "")
		)
		(fill
			(thermal_gap 0.5)
			(thermal_bridge_width 0.5)
			(island_removal_mode 0)
		)
		(polygon
			(pts
				(xy 236.070394 -155.977082) (xy 236.070394 -157.780482) (xy 236.629194 -157.780482) (xy 236.629194 -155.977082)
			)
		)
	)
	(zone
		(layer "In1.Cu")
		(hatch none 0.5)
		(connect_pads
			(clearance 0)
		)
		(min_thickness 0.25)
		(keepout
			(tracks not_allowed)
			(vias allowed)
			(pads allowed)
			(copperpour not_allowed)
			(footprints allowed)
		)
		(placement
			(enabled no)
			(sheetname "")
		)
		(fill
			(thermal_gap 0.5)
			(thermal_bridge_width 0.5)
			(island_removal_mode 0)
		)
		(polygon
			(pts
				(xy 241.170714 -4.920742) (xy 241.170714 -6.724142) (xy 241.729514 -6.724142) (xy 241.729514 -4.920742)
			)
		)
	)
	(zone
		(layer "In1.Cu")
		(hatch none 0.5)
		(connect_pads
			(clearance 0)
		)
		(min_thickness 0.25)
		(keepout
			(tracks not_allowed)
			(vias allowed)
			(pads allowed)
			(copperpour not_allowed)
			(footprints allowed)
		)
		(placement
			(enabled no)
			(sheetname "")
		)
		(fill
			(thermal_gap 0.5)
			(thermal_bridge_width 0.5)
			(island_removal_mode 0)
		)
		(polygon
			(pts
				(xy 283.670502 -141.775942) (xy 283.670502 -143.579342) (xy 284.229302 -143.579342) (xy 284.229302 -141.775942)
			)
		)
	)
	(zone
		(layer "In1.Cu")
		(hatch none 0.5)
		(connect_pads
			(clearance 0)
		)
		(min_thickness 0.25)
		(keepout
			(tracks not_allowed)
			(vias allowed)
			(pads allowed)
			(copperpour not_allowed)
			(footprints allowed)
		)
		(placement
			(enabled no)
			(sheetname "")
		)
		(fill
			(thermal_gap 0.5)
			(thermal_bridge_width 0.5)
			(island_removal_mode 0)
		)
		(polygon
			(pts
				(xy 217.370406 -136.774682) (xy 217.370406 -138.578082) (xy 217.929206 -138.578082) (xy 217.929206 -136.774682)
			)
		)
	)
	(zone
		(layer "In1.Cu")
		(hatch none 0.5)
		(connect_pads
			(clearance 0)
		)
		(min_thickness 0.25)
		(keepout
			(tracks not_allowed)
			(vias allowed)
			(pads allowed)
			(copperpour not_allowed)
			(footprints allowed)
		)
		(placement
			(enabled no)
			(sheetname "")
		)
		(fill
			(thermal_gap 0.5)
			(thermal_bridge_width 0.5)
			(island_removal_mode 0)
		)
		(polygon
			(pts
				(xy 256.470404 -146.375882) (xy 256.470404 -148.179282) (xy 257.029204 -148.179282) (xy 257.029204 -146.375882)
			)
		)
	)
	(zone
		(layer "In1.Cu")
		(hatch none 0.5)
		(connect_pads
			(clearance 0)
		)
		(min_thickness 0.25)
		(keepout
			(tracks not_allowed)
			(vias allowed)
			(pads allowed)
			(copperpour not_allowed)
			(footprints allowed)
		)
		(placement
			(enabled no)
			(sheetname "")
		)
		(fill
			(thermal_gap 0.5)
			(thermal_bridge_width 0.5)
			(island_removal_mode 0)
		)
		(polygon
			(pts
				(xy 105.070148 -4.920742) (xy 105.070148 -6.724142) (xy 105.628948 -6.724142) (xy 105.628948 -4.920742)
			)
		)
	)
	(zone
		(layer "In1.Cu")
		(hatch none 0.5)
		(connect_pads
			(clearance 0)
		)
		(min_thickness 0.25)
		(keepout
			(tracks not_allowed)
			(vias allowed)
			(pads allowed)
			(copperpour not_allowed)
			(footprints allowed)
		)
		(placement
			(enabled no)
			(sheetname "")
		)
		(fill
			(thermal_gap 0.5)
			(thermal_bridge_width 0.5)
			(island_removal_mode 0)
		)
		(polygon
			(pts
				(xy 127.169926 -4.920742) (xy 127.169926 -6.724142) (xy 127.728726 -6.724142) (xy 127.728726 -4.920742)
			)
		)
	)
	(zone
		(layer "In1.Cu")
		(hatch none 0.5)
		(connect_pads
			(clearance 0)
		)
		(min_thickness 0.25)
		(keepout
			(tracks not_allowed)
			(vias allowed)
			(pads allowed)
			(copperpour not_allowed)
			(footprints allowed)
		)
		(placement
			(enabled no)
			(sheetname "")
		)
		(fill
			(thermal_gap 0.5)
			(thermal_bridge_width 0.5)
			(island_removal_mode 0)
		)
		(polygon
			(pts
				(xy 225.020378 -19.121882) (xy 225.020378 -20.925282) (xy 225.579178 -20.925282) (xy 225.579178 -19.121882)
			)
		)
	)
	(zone
		(layer "In1.Cu")
		(hatch none 0.5)
		(connect_pads
			(clearance 0)
		)
		(min_thickness 0.25)
		(keepout
			(tracks not_allowed)
			(vias allowed)
			(pads allowed)
			(copperpour not_allowed)
			(footprints allowed)
		)
		(placement
			(enabled no)
			(sheetname "")
		)
		(fill
			(thermal_gap 0.5)
			(thermal_bridge_width 0.5)
			(island_removal_mode 0)
		)
		(polygon
			(pts
				(xy 37.920168 0.080518) (xy 37.920168 -1.722882) (xy 38.478968 -1.722882) (xy 38.478968 0.080518)
			)
		)
	)
	(zone
		(layer "In1.Cu")
		(hatch none 0.5)
		(connect_pads
			(clearance 0)
		)
		(min_thickness 0.25)
		(keepout
			(tracks not_allowed)
			(vias allowed)
			(pads allowed)
			(copperpour not_allowed)
			(footprints allowed)
		)
		(placement
			(enabled no)
			(sheetname "")
		)
		(fill
			(thermal_gap 0.5)
			(thermal_bridge_width 0.5)
			(island_removal_mode 0)
		)
		(polygon
			(pts
				(xy 270.07058 -155.977082) (xy 270.07058 -157.780482) (xy 270.62938 -157.780482) (xy 270.62938 -155.977082)
			)
		)
	)
	(zone
		(layer "In1.Cu")
		(hatch none 0.5)
		(connect_pads
			(clearance 0)
		)
		(min_thickness 0.25)
		(keepout
			(tracks not_allowed)
			(vias allowed)
			(pads allowed)
			(copperpour not_allowed)
			(footprints allowed)
		)
		(placement
			(enabled no)
			(sheetname "")
		)
		(fill
			(thermal_gap 0.5)
			(thermal_bridge_width 0.5)
			(island_removal_mode 0)
		)
		(polygon
			(pts
				(xy 246.270526 -14.521942) (xy 246.270526 -16.325342) (xy 246.829326 -16.325342) (xy 246.829326 -14.521942)
			)
		)
	)
	(zone
		(layer "In1.Cu")
		(hatch none 0.5)
		(connect_pads
			(clearance 0)
		)
		(min_thickness 0.25)
		(keepout
			(tracks not_allowed)
			(vias allowed)
			(pads allowed)
			(copperpour not_allowed)
			(footprints allowed)
		)
		(placement
			(enabled no)
			(sheetname "")
		)
		(fill
			(thermal_gap 0.5)
			(thermal_bridge_width 0.5)
			(island_removal_mode 0)
		)
		(polygon
			(pts
				(xy 76.170282 -141.775942) (xy 76.170282 -143.579342) (xy 76.729082 -143.579342) (xy 76.729082 -141.775942)
			)
		)
	)
	(zone
		(layer "In1.Cu")
		(hatch none 0.5)
		(connect_pads
			(clearance 0)
		)
		(min_thickness 0.25)
		(keepout
			(tracks not_allowed)
			(vias allowed)
			(pads allowed)
			(copperpour not_allowed)
			(footprints allowed)
		)
		(placement
			(enabled no)
			(sheetname "")
		)
		(fill
			(thermal_gap 0.5)
			(thermal_bridge_width 0.5)
			(island_removal_mode 0)
		)
		(polygon
			(pts
				(xy 298.970446 -155.977082) (xy 298.970446 -157.780482) (xy 299.529246 -157.780482) (xy 299.529246 -155.977082)
			)
		)
	)
	(zone
		(layer "In1.Cu")
		(hatch none 0.5)
		(connect_pads
			(clearance 0)
		)
		(min_thickness 0.25)
		(keepout
			(tracks not_allowed)
			(vias allowed)
			(pads allowed)
			(copperpour not_allowed)
			(footprints allowed)
		)
		(placement
			(enabled no)
			(sheetname "")
		)
		(fill
			(thermal_gap 0.5)
			(thermal_bridge_width 0.5)
			(island_removal_mode 0)
		)
		(polygon
			(pts
				(xy 200.37044 -132.174742) (xy 200.37044 -133.978142) (xy 200.92924 -133.978142) (xy 200.92924 -132.174742)
			)
		)
	)
	(zone
		(net "AGND_PVPP_ABC")
		(layer "In1.Cu")
		(hatch none 0.5)
		(connect_pads
			(clearance 0.5)
		)
		(min_thickness 0.25)
		(fill yes
			(thermal_gap 0.5)
			(thermal_bridge_width 0.5)
			(island_removal_mode 0)
		)
		(polygon
			(pts
				(xy 340.338156 -21.59) (xy 340.233 -21.695156) (xy 340.233 -22.119844) (xy 340.338156 -22.225) (xy 340.592156 -22.225)
				(xy 340.995 -22.627844) (xy 340.995 -23.346156) (xy 340.719156 -23.622) (xy 338.365846 -23.622)
				(xy 337.730846 -23.114) (xy 337.625944 -23.114) (xy 337.625944 -23.190708)
				(arc
					(start 337.647026 -23.205948)
					(mid 337.49047 -23.847387)
					(end 337.15706 -23.277576)
				)
				(arc
					(start 337.15706 -23.277576)
					(mid 337.167705 -23.170728)
					(end 337.076542 -23.114)
				)
				(xy 336.55 -23.114) (xy 336.55 -24.151844) (xy 337.036156 -24.638) (xy 340.084156 -24.638) (xy 340.614 -25.167844)
				(xy 340.614 -25.675844) (xy 340.846156 -25.908)
				(arc
					(start 341.325454 -25.908)
					(mid 341.40839 -25.865087)
					(end 341.421212 -25.772618)
				)
				(arc
					(start 341.421212 -25.772618)
					(mid 341.757 -25.297877)
					(end 342.092788 -25.772618)
				)
				(arc
					(start 342.092788 -25.772618)
					(mid 342.105657 -25.865054)
					(end 342.188546 -25.908)
				)
				(xy 342.70696 -25.908) (xy 345.207844 -25.908) (xy 345.426792 -25.689052) (xy 346.075 -25.040844)
				(xy 346.075 -23.727156) (xy 345.948 -23.600156) (xy 345.948 -21.949156) (xy 345.715844 -21.717)
				(xy 345.44 -21.717) (xy 345.44 -22.330156) (xy 345.164156 -22.606) (xy 343.175844 -22.606) (xy 342.540844 -21.971)
				(xy 341.270844 -21.971) (xy 340.889844 -21.59)
			)
		)
	)
	(zone
		(layer "In1.Cu")
		(hatch none 0.5)
		(connect_pads
			(clearance 0)
		)
		(min_thickness 0.25)
		(keepout
			(tracks not_allowed)
			(vias allowed)
			(pads allowed)
			(copperpour not_allowed)
			(footprints allowed)
		)
		(placement
			(enabled no)
			(sheetname "")
		)
		(fill
			(thermal_gap 0.5)
			(thermal_bridge_width 0.5)
			(island_removal_mode 0)
		)
		(polygon
			(pts
				(xy 311.720484 -141.775942) (xy 311.720484 -143.579342) (xy 312.279284 -143.579342) (xy 312.279284 -141.775942)
			)
		)
	)
	(zone
		(layer "In1.Cu")
		(hatch none 0.5)
		(connect_pads
			(clearance 0)
		)
		(min_thickness 0.25)
		(keepout
			(tracks not_allowed)
			(vias allowed)
			(pads allowed)
			(copperpour not_allowed)
			(footprints allowed)
		)
		(placement
			(enabled no)
			(sheetname "")
		)
		(fill
			(thermal_gap 0.5)
			(thermal_bridge_width 0.5)
			(island_removal_mode 0)
		)
		(polygon
			(pts
				(xy 120.370092 -151.377142) (xy 120.370092 -153.180542) (xy 120.928892 -153.180542) (xy 120.928892 -151.377142)
			)
		)
	)
	(zone
		(layer "In1.Cu")
		(hatch none 0.5)
		(connect_pads
			(clearance 0)
		)
		(min_thickness 0.25)
		(keepout
			(tracks not_allowed)
			(vias allowed)
			(pads allowed)
			(copperpour not_allowed)
			(footprints allowed)
		)
		(placement
			(enabled no)
			(sheetname "")
		)
		(fill
			(thermal_gap 0.5)
			(thermal_bridge_width 0.5)
			(island_removal_mode 0)
		)
		(polygon
			(pts
				(xy 125.469904 -4.920742) (xy 125.469904 -6.724142) (xy 126.028704 -6.724142) (xy 126.028704 -4.920742)
			)
		)
	)
	(zone
		(layer "In1.Cu")
		(hatch none 0.5)
		(connect_pads
			(clearance 0)
		)
		(min_thickness 0.25)
		(keepout
			(tracks not_allowed)
			(vias allowed)
			(pads allowed)
			(copperpour not_allowed)
			(footprints allowed)
		)
		(placement
			(enabled no)
			(sheetname "")
		)
		(fill
			(thermal_gap 0.5)
			(thermal_bridge_width 0.5)
			(island_removal_mode 0)
		)
		(polygon
			(pts
				(xy 92.32011 -19.121882) (xy 92.32011 -20.925282) (xy 92.87891 -20.925282) (xy 92.87891 -19.121882)
			)
		)
	)
	(zone
		(layer "In1.Cu")
		(hatch none 0.5)
		(connect_pads
			(clearance 0)
		)
		(min_thickness 0.25)
		(keepout
			(tracks not_allowed)
			(vias allowed)
			(pads allowed)
			(copperpour not_allowed)
			(footprints allowed)
		)
		(placement
			(enabled no)
			(sheetname "")
		)
		(fill
			(thermal_gap 0.5)
			(thermal_bridge_width 0.5)
			(island_removal_mode 0)
		)
		(polygon
			(pts
				(xy 225.020378 -146.375882) (xy 225.020378 -148.179282) (xy 225.579178 -148.179282) (xy 225.579178 -146.375882)
			)
		)
	)
	(zone
		(layer "In1.Cu")
		(hatch none 0.5)
		(connect_pads
			(clearance 0)
		)
		(min_thickness 0.25)
		(keepout
			(tracks not_allowed)
			(vias allowed)
			(pads allowed)
			(copperpour not_allowed)
			(footprints allowed)
		)
		(placement
			(enabled no)
			(sheetname "")
		)
		(fill
			(thermal_gap 0.5)
			(thermal_bridge_width 0.5)
			(island_removal_mode 0)
		)
		(polygon
			(pts
				(xy 377.313444 -9.773158) (xy 377.821444 -9.773158) (xy 377.821444 -11.170158) (xy 377.313444 -11.170158)
			)
		)
	)
	(zone
		(layer "In1.Cu")
		(hatch none 0.5)
		(connect_pads
			(clearance 0)
		)
		(min_thickness 0.25)
		(keepout
			(tracks not_allowed)
			(vias allowed)
			(pads allowed)
			(copperpour not_allowed)
			(footprints allowed)
		)
		(placement
			(enabled no)
			(sheetname "")
		)
		(fill
			(thermal_gap 0.5)
			(thermal_bridge_width 0.5)
			(island_removal_mode 0)
		)
		(polygon
			(pts
				(xy 108.469938 -155.977082) (xy 108.469938 -157.780482) (xy 109.028738 -157.780482) (xy 109.028738 -155.977082)
			)
		)
	)
	(zone
		(layer "In1.Cu")
		(hatch none 0.5)
		(connect_pads
			(clearance 0)
		)
		(min_thickness 0.25)
		(keepout
			(tracks not_allowed)
			(vias allowed)
			(pads allowed)
			(copperpour not_allowed)
			(footprints allowed)
		)
		(placement
			(enabled no)
			(sheetname "")
		)
		(fill
			(thermal_gap 0.5)
			(thermal_bridge_width 0.5)
			(island_removal_mode 0)
		)
		(polygon
			(pts
				(xy 54.920134 -136.774682) (xy 54.920134 -138.578082) (xy 55.478934 -138.578082) (xy 55.478934 -136.774682)
			)
		)
	)
	(zone
		(layer "In1.Cu")
		(hatch none 0.5)
		(connect_pads
			(clearance 0)
		)
		(min_thickness 0.25)
		(keepout
			(tracks not_allowed)
			(vias allowed)
			(pads allowed)
			(copperpour not_allowed)
			(footprints allowed)
		)
		(placement
			(enabled no)
			(sheetname "")
		)
		(fill
			(thermal_gap 0.5)
			(thermal_bridge_width 0.5)
			(island_removal_mode 0)
		)
		(polygon
			(pts
				(xy 319.4685 -123.063) (xy 321.7545 -123.063) (xy 321.7545 -123.571) (xy 319.4685 -123.571)
			)
		)
	)
	(zone
		(layer "In1.Cu")
		(hatch none 0.5)
		(connect_pads
			(clearance 0)
		)
		(min_thickness 0.25)
		(keepout
			(tracks not_allowed)
			(vias allowed)
			(pads allowed)
			(copperpour not_allowed)
			(footprints allowed)
		)
		(placement
			(enabled no)
			(sheetname "")
		)
		(fill
			(thermal_gap 0.5)
			(thermal_bridge_width 0.5)
			(island_removal_mode 0)
		)
		(polygon
			(pts
				(xy 109.320076 -132.174742) (xy 109.320076 -133.978142) (xy 109.878876 -133.978142) (xy 109.878876 -132.174742)
			)
		)
	)
	(zone
		(layer "In1.Cu")
		(hatch none 0.5)
		(connect_pads
			(clearance 0)
		)
		(min_thickness 0.25)
		(keepout
			(tracks not_allowed)
			(vias allowed)
			(pads allowed)
			(copperpour not_allowed)
			(footprints allowed)
		)
		(placement
			(enabled no)
			(sheetname "")
		)
		(fill
			(thermal_gap 0.5)
			(thermal_bridge_width 0.5)
			(island_removal_mode 0)
		)
		(polygon
			(pts
				(xy 144.169892 -14.521942) (xy 144.169892 -16.325342) (xy 144.728692 -16.325342) (xy 144.728692 -14.521942)
			)
		)
	)
	(zone
		(layer "In1.Cu")
		(hatch none 0.5)
		(connect_pads
			(clearance 0)
		)
		(min_thickness 0.25)
		(keepout
			(tracks not_allowed)
			(vias allowed)
			(pads allowed)
			(copperpour not_allowed)
			(footprints allowed)
		)
		(placement
			(enabled no)
			(sheetname "")
		)
		(fill
			(thermal_gap 0.5)
			(thermal_bridge_width 0.5)
			(island_removal_mode 0)
		)
		(polygon
			(pts
				(xy 283.670502 -14.521942) (xy 283.670502 -16.325342) (xy 284.229302 -16.325342) (xy 284.229302 -14.521942)
			)
		)
	)
	(zone
		(layer "In1.Cu")
		(hatch none 0.5)
		(connect_pads
			(clearance 0)
		)
		(min_thickness 0.25)
		(keepout
			(tracks not_allowed)
			(vias allowed)
			(pads allowed)
			(copperpour not_allowed)
			(footprints allowed)
		)
		(placement
			(enabled no)
			(sheetname "")
		)
		(fill
			(thermal_gap 0.5)
			(thermal_bridge_width 0.5)
			(island_removal_mode 0)
		)
		(polygon
			(pts
				(xy 13.6398 -29.21) (xy 15.0368 -29.21) (xy 15.0368 -29.718) (xy 13.6398 -29.718)
			)
		)
	)
	(zone
		(layer "In1.Cu")
		(hatch none 0.5)
		(connect_pads
			(clearance 0)
		)
		(min_thickness 0.25)
		(keepout
			(tracks not_allowed)
			(vias allowed)
			(pads allowed)
			(copperpour not_allowed)
			(footprints allowed)
		)
		(placement
			(enabled no)
			(sheetname "")
		)
		(fill
			(thermal_gap 0.5)
			(thermal_bridge_width 0.5)
			(island_removal_mode 0)
		)
		(polygon
			(pts
				(xy 248.820432 -141.775942) (xy 248.820432 -143.579342) (xy 249.379232 -143.579342) (xy 249.379232 -141.775942)
			)
		)
	)
	(zone
		(layer "In1.Cu")
		(hatch none 0.5)
		(connect_pads
			(clearance 0)
		)
		(min_thickness 0.25)
		(keepout
			(tracks not_allowed)
			(vias allowed)
			(pads allowed)
			(copperpour not_allowed)
			(footprints allowed)
		)
		(placement
			(enabled no)
			(sheetname "")
		)
		(fill
			(thermal_gap 0.5)
			(thermal_bridge_width 0.5)
			(island_removal_mode 0)
		)
		(polygon
			(pts
				(xy 201.220578 -19.121882) (xy 201.220578 -20.925282) (xy 201.779378 -20.925282) (xy 201.779378 -19.121882)
			)
		)
	)
	(zone
		(layer "In1.Cu")
		(hatch none 0.5)
		(connect_pads
			(clearance 0)
		)
		(min_thickness 0.25)
		(keepout
			(tracks not_allowed)
			(vias allowed)
			(pads allowed)
			(copperpour not_allowed)
			(footprints allowed)
		)
		(placement
			(enabled no)
			(sheetname "")
		)
		(fill
			(thermal_gap 0.5)
			(thermal_bridge_width 0.5)
			(island_removal_mode 0)
		)
		(polygon
			(pts
				(xy 147.569936 -9.520682) (xy 147.569936 -11.324082) (xy 148.128736 -11.324082) (xy 148.128736 -9.520682)
			)
		)
	)
	(zone
		(layer "In1.Cu")
		(hatch none 0.5)
		(connect_pads
			(clearance 0)
		)
		(min_thickness 0.25)
		(keepout
			(tracks not_allowed)
			(vias allowed)
			(pads allowed)
			(copperpour not_allowed)
			(footprints allowed)
		)
		(placement
			(enabled no)
			(sheetname "")
		)
		(fill
			(thermal_gap 0.5)
			(thermal_bridge_width 0.5)
			(island_removal_mode 0)
		)
		(polygon
			(pts
				(xy 279.42032 -4.920742) (xy 279.42032 -6.724142) (xy 279.97912 -6.724142) (xy 279.97912 -4.920742)
			)
		)
	)
	(zone
		(layer "In1.Cu")
		(hatch none 0.5)
		(connect_pads
			(clearance 0)
		)
		(min_thickness 0.25)
		(keepout
			(tracks not_allowed)
			(vias allowed)
			(pads allowed)
			(copperpour not_allowed)
			(footprints allowed)
		)
		(placement
			(enabled no)
			(sheetname "")
		)
		(fill
			(thermal_gap 0.5)
			(thermal_bridge_width 0.5)
			(island_removal_mode 0)
		)
		(polygon
			(pts
				(xy 224.170494 4.680458) (xy 224.170494 2.877058) (xy 224.729294 2.877058) (xy 224.729294 4.680458)
			)
		)
	)
	(zone
		(layer "In1.Cu")
		(hatch none 0.5)
		(connect_pads
			(clearance 0)
		)
		(min_thickness 0.25)
		(keepout
			(tracks not_allowed)
			(vias allowed)
			(pads allowed)
			(copperpour not_allowed)
			(footprints allowed)
		)
		(placement
			(enabled no)
			(sheetname "")
		)
		(fill
			(thermal_gap 0.5)
			(thermal_bridge_width 0.5)
			(island_removal_mode 0)
		)
		(polygon
			(pts
				(xy 209.720434 -132.174742) (xy 209.720434 -133.978142) (xy 210.279234 -133.978142) (xy 210.279234 -132.174742)
			)
		)
	)
	(zone
		(layer "In1.Cu")
		(hatch none 0.5)
		(connect_pads
			(clearance 0)
		)
		(min_thickness 0.25)
		(keepout
			(tracks not_allowed)
			(vias allowed)
			(pads allowed)
			(copperpour not_allowed)
			(footprints allowed)
		)
		(placement
			(enabled no)
			(sheetname "")
		)
		(fill
			(thermal_gap 0.5)
			(thermal_bridge_width 0.5)
			(island_removal_mode 0)
		)
		(polygon
			(pts
				(xy 264.970514 -9.520682) (xy 264.970514 -11.324082) (xy 265.529314 -11.324082) (xy 265.529314 -9.520682)
			)
		)
	)
	(zone
		(layer "In1.Cu")
		(hatch none 0.5)
		(connect_pads
			(clearance 0)
		)
		(min_thickness 0.25)
		(keepout
			(tracks not_allowed)
			(vias allowed)
			(pads allowed)
			(copperpour not_allowed)
			(footprints allowed)
		)
		(placement
			(enabled no)
			(sheetname "")
		)
		(fill
			(thermal_gap 0.5)
			(thermal_bridge_width 0.5)
			(island_removal_mode 0)
		)
		(polygon
			(pts
				(xy 225.020378 -136.774682) (xy 225.020378 -138.578082) (xy 225.579178 -138.578082) (xy 225.579178 -136.774682)
			)
		)
	)
	(zone
		(layer "In1.Cu")
		(hatch none 0.5)
		(connect_pads
			(clearance 0)
		)
		(min_thickness 0.25)
		(keepout
			(tracks not_allowed)
			(vias allowed)
			(pads allowed)
			(copperpour not_allowed)
			(footprints allowed)
		)
		(placement
			(enabled no)
			(sheetname "")
		)
		(fill
			(thermal_gap 0.5)
			(thermal_bridge_width 0.5)
			(island_removal_mode 0)
		)
		(polygon
			(pts
				(xy 137.370058 -141.775942) (xy 137.370058 -143.579342) (xy 137.928858 -143.579342) (xy 137.928858 -141.775942)
			)
		)
	)
	(zone
		(layer "In1.Cu")
		(hatch none 0.5)
		(connect_pads
			(clearance 0)
		)
		(min_thickness 0.25)
		(keepout
			(tracks not_allowed)
			(vias allowed)
			(pads allowed)
			(copperpour not_allowed)
			(footprints allowed)
		)
		(placement
			(enabled no)
			(sheetname "")
		)
		(fill
			(thermal_gap 0.5)
			(thermal_bridge_width 0.5)
			(island_removal_mode 0)
		)
		(polygon
			(pts
				(xy 84.670138 -14.521942) (xy 84.670138 -16.325342) (xy 85.228938 -16.325342) (xy 85.228938 -14.521942)
			)
		)
	)
	(zone
		(layer "In1.Cu")
		(hatch none 0.5)
		(connect_pads
			(clearance 0)
		)
		(min_thickness 0.25)
		(keepout
			(tracks not_allowed)
			(vias allowed)
			(pads allowed)
			(copperpour not_allowed)
			(footprints allowed)
		)
		(placement
			(enabled no)
			(sheetname "")
		)
		(fill
			(thermal_gap 0.5)
			(thermal_bridge_width 0.5)
			(island_removal_mode 0)
		)
		(polygon
			(pts
				(xy 312.570368 -9.520682) (xy 312.570368 -11.324082) (xy 313.129168 -11.324082) (xy 313.129168 -9.520682)
			)
		)
	)
	(zone
		(layer "In1.Cu")
		(hatch none 0.5)
		(connect_pads
			(clearance 0)
		)
		(min_thickness 0.25)
		(keepout
			(tracks not_allowed)
			(vias allowed)
			(pads allowed)
			(copperpour not_allowed)
			(footprints allowed)
		)
		(placement
			(enabled no)
			(sheetname "")
		)
		(fill
			(thermal_gap 0.5)
			(thermal_bridge_width 0.5)
			(island_removal_mode 0)
		)
		(polygon
			(pts
				(xy 277.720552 -9.520682) (xy 277.720552 -11.324082) (xy 278.279352 -11.324082) (xy 278.279352 -9.520682)
			)
		)
	)
	(zone
		(layer "In1.Cu")
		(hatch none 0.5)
		(connect_pads
			(clearance 0)
		)
		(min_thickness 0.25)
		(keepout
			(tracks not_allowed)
			(vias allowed)
			(pads allowed)
			(copperpour not_allowed)
			(footprints allowed)
		)
		(placement
			(enabled no)
			(sheetname "")
		)
		(fill
			(thermal_gap 0.5)
			(thermal_bridge_width 0.5)
			(island_removal_mode 0)
		)
		(polygon
			(pts
				(xy 209.720434 -155.977082) (xy 209.720434 -157.780482) (xy 210.279234 -157.780482) (xy 210.279234 -155.977082)
			)
		)
	)
	(zone
		(layer "In1.Cu")
		(hatch none 0.5)
		(connect_pads
			(clearance 0)
		)
		(min_thickness 0.25)
		(keepout
			(tracks not_allowed)
			(vias allowed)
			(pads allowed)
			(copperpour not_allowed)
			(footprints allowed)
		)
		(placement
			(enabled no)
			(sheetname "")
		)
		(fill
			(thermal_gap 0.5)
			(thermal_bridge_width 0.5)
			(island_removal_mode 0)
		)
		(polygon
			(pts
				(xy 438.686956 -46.478698) (xy 439.995056 -46.478698) (xy 439.995056 -48.485298) (xy 438.686956 -48.485298)
			)
		)
	)
	(zone
		(layer "In1.Cu")
		(hatch none 0.5)
		(connect_pads
			(clearance 0)
		)
		(min_thickness 0.25)
		(keepout
			(tracks not_allowed)
			(vias allowed)
			(pads allowed)
			(copperpour not_allowed)
			(footprints allowed)
		)
		(placement
			(enabled no)
			(sheetname "")
		)
		(fill
			(thermal_gap 0.5)
			(thermal_bridge_width 0.5)
			(island_removal_mode 0)
		)
		(polygon
			(pts
				(xy 228.420422 -14.521942) (xy 228.420422 -16.325342) (xy 228.979222 -16.325342) (xy 228.979222 -14.521942)
			)
		)
	)
	(zone
		(layer "In1.Cu")
		(hatch none 0.5)
		(connect_pads
			(clearance 0)
		)
		(min_thickness 0.25)
		(keepout
			(tracks not_allowed)
			(vias allowed)
			(pads allowed)
			(copperpour not_allowed)
			(footprints allowed)
		)
		(placement
			(enabled no)
			(sheetname "")
		)
		(fill
			(thermal_gap 0.5)
			(thermal_bridge_width 0.5)
			(island_removal_mode 0)
		)
		(polygon
			(pts
				(xy 36.220146 -9.520682) (xy 36.220146 -11.324082) (xy 36.778946 -11.324082) (xy 36.778946 -9.520682)
			)
		)
	)
	(zone
		(layer "In1.Cu")
		(hatch none 0.5)
		(connect_pads
			(clearance 0)
		)
		(min_thickness 0.25)
		(keepout
			(tracks not_allowed)
			(vias allowed)
			(pads allowed)
			(copperpour not_allowed)
			(footprints allowed)
		)
		(placement
			(enabled no)
			(sheetname "")
		)
		(fill
			(thermal_gap 0.5)
			(thermal_bridge_width 0.5)
			(island_removal_mode 0)
		)
		(polygon
			(pts
				(xy 70.220078 -4.920742) (xy 70.220078 -6.724142) (xy 70.778878 -6.724142) (xy 70.778878 -4.920742)
			)
		)
	)
	(zone
		(layer "In1.Cu")
		(hatch none 0.5)
		(connect_pads
			(clearance 0)
		)
		(min_thickness 0.25)
		(keepout
			(tracks not_allowed)
			(vias allowed)
			(pads allowed)
			(copperpour not_allowed)
			(footprints allowed)
		)
		(placement
			(enabled no)
			(sheetname "")
		)
		(fill
			(thermal_gap 0.5)
			(thermal_bridge_width 0.5)
			(island_removal_mode 0)
		)
		(polygon
			(pts
				(xy 254.770382 -132.174742) (xy 254.770382 -133.978142) (xy 255.329182 -133.978142) (xy 255.329182 -132.174742)
			)
		)
	)
	(zone
		(layer "In1.Cu")
		(hatch none 0.5)
		(connect_pads
			(clearance 0)
		)
		(min_thickness 0.25)
		(keepout
			(tracks not_allowed)
			(vias allowed)
			(pads allowed)
			(copperpour not_allowed)
			(footprints allowed)
		)
		(placement
			(enabled no)
			(sheetname "")
		)
		(fill
			(thermal_gap 0.5)
			(thermal_bridge_width 0.5)
			(island_removal_mode 0)
		)
		(polygon
			(pts
				(xy 31.12008 -14.521942) (xy 31.12008 -16.325342) (xy 31.67888 -16.325342) (xy 31.67888 -14.521942)
			)
		)
	)
	(zone
		(layer "In1.Cu")
		(hatch none 0.5)
		(connect_pads
			(clearance 0)
		)
		(min_thickness 0.25)
		(keepout
			(tracks not_allowed)
			(vias allowed)
			(pads allowed)
			(copperpour not_allowed)
			(footprints allowed)
		)
		(placement
			(enabled no)
			(sheetname "")
		)
		(fill
			(thermal_gap 0.5)
			(thermal_bridge_width 0.5)
			(island_removal_mode 0)
		)
		(polygon
			(pts
				(xy 129.720086 -141.775942) (xy 129.720086 -143.579342) (xy 130.278886 -143.579342) (xy 130.278886 -141.775942)
			)
		)
	)
	(zone
		(layer "In1.Cu")
		(hatch none 0.5)
		(connect_pads
			(clearance 0)
		)
		(min_thickness 0.25)
		(keepout
			(tracks not_allowed)
			(vias allowed)
			(pads allowed)
			(copperpour not_allowed)
			(footprints allowed)
		)
		(placement
			(enabled no)
			(sheetname "")
		)
		(fill
			(thermal_gap 0.5)
			(thermal_bridge_width 0.5)
			(island_removal_mode 0)
		)
		(polygon
			(pts
				(xy 82.119978 -155.977082) (xy 82.119978 -157.780482) (xy 82.678778 -157.780482) (xy 82.678778 -155.977082)
			)
		)
	)
	(zone
		(layer "In1.Cu")
		(hatch none 0.5)
		(connect_pads
			(clearance 0)
		)
		(min_thickness 0.25)
		(keepout
			(tracks not_allowed)
			(vias allowed)
			(pads allowed)
			(copperpour not_allowed)
			(footprints allowed)
		)
		(placement
			(enabled no)
			(sheetname "")
		)
		(fill
			(thermal_gap 0.5)
			(thermal_bridge_width 0.5)
			(island_removal_mode 0)
		)
		(polygon
			(pts
				(xy 281.120342 -141.775942) (xy 281.120342 -143.579342) (xy 281.679142 -143.579342) (xy 281.679142 -141.775942)
			)
		)
	)
	(zone
		(layer "In1.Cu")
		(hatch none 0.5)
		(connect_pads
			(clearance 0)
		)
		(min_thickness 0.25)
		(keepout
			(tracks not_allowed)
			(vias allowed)
			(pads allowed)
			(copperpour not_allowed)
			(footprints allowed)
		)
		(placement
			(enabled no)
			(sheetname "")
		)
		(fill
			(thermal_gap 0.5)
			(thermal_bridge_width 0.5)
			(island_removal_mode 0)
		)
		(polygon
			(pts
				(xy 202.9206 -9.520682) (xy 202.9206 -11.324082) (xy 203.4794 -11.324082) (xy 203.4794 -9.520682)
			)
		)
	)
	(zone
		(layer "In1.Cu")
		(hatch none 0.5)
		(connect_pads
			(clearance 0)
		)
		(min_thickness 0.25)
		(keepout
			(tracks not_allowed)
			(vias allowed)
			(pads allowed)
			(copperpour not_allowed)
			(footprints allowed)
		)
		(placement
			(enabled no)
			(sheetname "")
		)
		(fill
			(thermal_gap 0.5)
			(thermal_bridge_width 0.5)
			(island_removal_mode 0)
		)
		(polygon
			(pts
				(xy 323.4055 -121.412) (xy 325.6915 -121.412) (xy 325.6915 -121.92) (xy 323.4055 -121.92)
			)
		)
	)
	(zone
		(layer "In1.Cu")
		(hatch none 0.5)
		(connect_pads
			(clearance 0)
		)
		(min_thickness 0.25)
		(keepout
			(tracks not_allowed)
			(vias allowed)
			(pads allowed)
			(copperpour not_allowed)
			(footprints allowed)
		)
		(placement
			(enabled no)
			(sheetname "")
		)
		(fill
			(thermal_gap 0.5)
			(thermal_bridge_width 0.5)
			(island_removal_mode 0)
		)
		(polygon
			(pts
				(xy 142.46987 -14.521942) (xy 142.46987 -16.325342) (xy 143.02867 -16.325342) (xy 143.02867 -14.521942)
			)
		)
	)
	(zone
		(layer "In1.Cu")
		(hatch none 0.5)
		(connect_pads
			(clearance 0)
		)
		(min_thickness 0.25)
		(keepout
			(tracks not_allowed)
			(vias allowed)
			(pads allowed)
			(copperpour not_allowed)
			(footprints allowed)
		)
		(placement
			(enabled no)
			(sheetname "")
		)
		(fill
			(thermal_gap 0.5)
			(thermal_bridge_width 0.5)
			(island_removal_mode 0)
		)
		(polygon
			(pts
				(xy 126.320042 -19.121882) (xy 126.320042 -20.925282) (xy 126.878842 -20.925282) (xy 126.878842 -19.121882)
			)
		)
	)
	(zone
		(layer "In1.Cu")
		(hatch none 0.5)
		(connect_pads
			(clearance 0)
		)
		(min_thickness 0.25)
		(keepout
			(tracks not_allowed)
			(vias allowed)
			(pads allowed)
			(copperpour not_allowed)
			(footprints allowed)
		)
		(placement
			(enabled no)
			(sheetname "")
		)
		(fill
			(thermal_gap 0.5)
			(thermal_bridge_width 0.5)
			(island_removal_mode 0)
		)
		(polygon
			(pts
				(xy 302.37049 -9.520682) (xy 302.37049 -11.324082) (xy 302.92929 -11.324082) (xy 302.92929 -9.520682)
			)
		)
	)
	(zone
		(layer "In1.Cu")
		(hatch none 0.5)
		(connect_pads
			(clearance 0)
		)
		(min_thickness 0.25)
		(keepout
			(tracks not_allowed)
			(vias allowed)
			(pads allowed)
			(copperpour not_allowed)
			(footprints allowed)
		)
		(placement
			(enabled no)
			(sheetname "")
		)
		(fill
			(thermal_gap 0.5)
			(thermal_bridge_width 0.5)
			(island_removal_mode 0)
		)
		(polygon
			(pts
				(xy 43.870118 -4.920742) (xy 43.870118 -6.724142) (xy 44.428918 -6.724142) (xy 44.428918 -4.920742)
			)
		)
	)
	(zone
		(layer "In1.Cu")
		(hatch none 0.5)
		(connect_pads
			(clearance 0)
		)
		(min_thickness 0.25)
		(keepout
			(tracks not_allowed)
			(vias allowed)
			(pads allowed)
			(copperpour not_allowed)
			(footprints allowed)
		)
		(placement
			(enabled no)
			(sheetname "")
		)
		(fill
			(thermal_gap 0.5)
			(thermal_bridge_width 0.5)
			(island_removal_mode 0)
		)
		(polygon
			(pts
				(xy 225.020378 0.080518) (xy 225.020378 -1.722882) (xy 225.579178 -1.722882) (xy 225.579178 0.080518)
			)
		)
	)
	(zone
		(layer "In1.Cu")
		(hatch none 0.5)
		(connect_pads
			(clearance 0)
		)
		(min_thickness 0.25)
		(keepout
			(tracks not_allowed)
			(vias allowed)
			(pads allowed)
			(copperpour not_allowed)
			(footprints allowed)
		)
		(placement
			(enabled no)
			(sheetname "")
		)
		(fill
			(thermal_gap 0.5)
			(thermal_bridge_width 0.5)
			(island_removal_mode 0)
		)
		(polygon
			(pts
				(xy 45.57014 0.080518) (xy 45.57014 -1.722882) (xy 46.12894 -1.722882) (xy 46.12894 0.080518)
			)
		)
	)
	(zone
		(layer "In1.Cu")
		(hatch none 0.5)
		(connect_pads
			(clearance 0)
		)
		(min_thickness 0.25)
		(keepout
			(tracks not_allowed)
			(vias allowed)
			(pads allowed)
			(copperpour not_allowed)
			(footprints allowed)
		)
		(placement
			(enabled no)
			(sheetname "")
		)
		(fill
			(thermal_gap 0.5)
			(thermal_bridge_width 0.5)
			(island_removal_mode 0)
		)
		(polygon
			(pts
				(xy 145.02003 0.080518) (xy 145.02003 -1.722882) (xy 145.57883 -1.722882) (xy 145.57883 0.080518)
			)
		)
	)
	(zone
		(layer "In1.Cu")
		(hatch none 0.5)
		(connect_pads
			(clearance 0)
		)
		(min_thickness 0.25)
		(keepout
			(tracks not_allowed)
			(vias allowed)
			(pads allowed)
			(copperpour not_allowed)
			(footprints allowed)
		)
		(placement
			(enabled no)
			(sheetname "")
		)
		(fill
			(thermal_gap 0.5)
			(thermal_bridge_width 0.5)
			(island_removal_mode 0)
		)
		(polygon
			(pts
				(xy 63.41999 -136.774682) (xy 63.41999 -138.578082) (xy 63.97879 -138.578082) (xy 63.97879 -136.774682)
			)
		)
	)
	(zone
		(layer "In1.Cu")
		(hatch none 0.5)
		(connect_pads
			(clearance 0)
		)
		(min_thickness 0.25)
		(keepout
			(tracks not_allowed)
			(vias allowed)
			(pads allowed)
			(copperpour not_allowed)
			(footprints allowed)
		)
		(placement
			(enabled no)
			(sheetname "")
		)
		(fill
			(thermal_gap 0.5)
			(thermal_bridge_width 0.5)
			(island_removal_mode 0)
		)
		(polygon
			(pts
				(xy 264.970514 0.080518) (xy 264.970514 -1.722882) (xy 265.529314 -1.722882) (xy 265.529314 0.080518)
			)
		)
	)
	(zone
		(layer "In1.Cu")
		(hatch none 0.5)
		(connect_pads
			(clearance 0)
		)
		(min_thickness 0.25)
		(keepout
			(tracks not_allowed)
			(vias allowed)
			(pads allowed)
			(copperpour not_allowed)
			(footprints allowed)
		)
		(placement
			(enabled no)
			(sheetname "")
		)
		(fill
			(thermal_gap 0.5)
			(thermal_bridge_width 0.5)
			(island_removal_mode 0)
		)
		(polygon
			(pts
				(xy 313.420506 -132.174742) (xy 313.420506 -133.978142) (xy 313.979306 -133.978142) (xy 313.979306 -132.174742)
			)
		)
	)
	(zone
		(layer "In1.Cu")
		(hatch none 0.5)
		(connect_pads
			(clearance 0)
		)
		(min_thickness 0.25)
		(keepout
			(tracks not_allowed)
			(vias allowed)
			(pads allowed)
			(copperpour not_allowed)
			(footprints allowed)
		)
		(placement
			(enabled no)
			(sheetname "")
		)
		(fill
			(thermal_gap 0.5)
			(thermal_bridge_width 0.5)
			(island_removal_mode 0)
		)
		(polygon
			(pts
				(xy 270.07058 -19.121882) (xy 270.07058 -20.925282) (xy 270.62938 -20.925282) (xy 270.62938 -19.121882)
			)
		)
	)
	(zone
		(layer "In1.Cu")
		(hatch none 0.5)
		(connect_pads
			(clearance 0)
		)
		(min_thickness 0.25)
		(keepout
			(tracks not_allowed)
			(vias allowed)
			(pads allowed)
			(copperpour not_allowed)
			(footprints allowed)
		)
		(placement
			(enabled no)
			(sheetname "")
		)
		(fill
			(thermal_gap 0.5)
			(thermal_bridge_width 0.5)
			(island_removal_mode 0)
		)
		(polygon
			(pts
				(xy 203.770484 -4.920742) (xy 203.770484 -6.724142) (xy 204.329284 -6.724142) (xy 204.329284 -4.920742)
			)
		)
	)
	(zone
		(layer "In1.Cu")
		(hatch none 0.5)
		(connect_pads
			(clearance 0)
		)
		(min_thickness 0.25)
		(keepout
			(tracks not_allowed)
			(vias allowed)
			(pads allowed)
			(copperpour not_allowed)
			(footprints allowed)
		)
		(placement
			(enabled no)
			(sheetname "")
		)
		(fill
			(thermal_gap 0.5)
			(thermal_bridge_width 0.5)
			(island_removal_mode 0)
		)
		(polygon
			(pts
				(xy 85.520022 -146.375882) (xy 85.520022 -148.179282) (xy 86.078822 -148.179282) (xy 86.078822 -146.375882)
			)
		)
	)
	(zone
		(layer "In1.Cu")
		(hatch none 0.5)
		(connect_pads
			(clearance 0)
		)
		(min_thickness 0.25)
		(keepout
			(tracks not_allowed)
			(vias allowed)
			(pads allowed)
			(copperpour not_allowed)
			(footprints allowed)
		)
		(placement
			(enabled no)
			(sheetname "")
		)
		(fill
			(thermal_gap 0.5)
			(thermal_bridge_width 0.5)
			(island_removal_mode 0)
		)
		(polygon
			(pts
				(xy 236.920532 4.680458) (xy 236.920532 2.877058) (xy 237.479332 2.877058) (xy 237.479332 4.680458)
			)
		)
	)
	(zone
		(layer "In1.Cu")
		(hatch none 0.5)
		(connect_pads
			(clearance 0)
		)
		(min_thickness 0.25)
		(keepout
			(tracks not_allowed)
			(vias allowed)
			(pads allowed)
			(copperpour not_allowed)
			(footprints allowed)
		)
		(placement
			(enabled no)
			(sheetname "")
		)
		(fill
			(thermal_gap 0.5)
			(thermal_bridge_width 0.5)
			(island_removal_mode 0)
		)
		(polygon
			(pts
				(xy 105.070148 -14.521942) (xy 105.070148 -16.325342) (xy 105.628948 -16.325342) (xy 105.628948 -14.521942)
			)
		)
	)
	(zone
		(layer "In1.Cu")
		(hatch none 0.5)
		(connect_pads
			(clearance 0)
		)
		(min_thickness 0.25)
		(keepout
			(tracks not_allowed)
			(vias allowed)
			(pads allowed)
			(copperpour not_allowed)
			(footprints allowed)
		)
		(placement
			(enabled no)
			(sheetname "")
		)
		(fill
			(thermal_gap 0.5)
			(thermal_bridge_width 0.5)
			(island_removal_mode 0)
		)
		(polygon
			(pts
				(xy 68.520056 4.680458) (xy 68.520056 2.877058) (xy 69.078856 2.877058) (xy 69.078856 4.680458)
			)
		)
	)
	(zone
		(layer "In1.Cu")
		(hatch none 0.5)
		(connect_pads
			(clearance 0)
		)
		(min_thickness 0.25)
		(keepout
			(tracks not_allowed)
			(vias allowed)
			(pads allowed)
			(copperpour not_allowed)
			(footprints allowed)
		)
		(placement
			(enabled no)
			(sheetname "")
		)
		(fill
			(thermal_gap 0.5)
			(thermal_bridge_width 0.5)
			(island_removal_mode 0)
		)
		(polygon
			(pts
				(xy 87.220044 -9.520682) (xy 87.220044 -11.324082) (xy 87.778844 -11.324082) (xy 87.778844 -9.520682)
			)
		)
	)
	(zone
		(layer "In1.Cu")
		(hatch none 0.5)
		(connect_pads
			(clearance 0)
		)
		(min_thickness 0.25)
		(keepout
			(tracks not_allowed)
			(vias allowed)
			(pads allowed)
			(copperpour not_allowed)
			(footprints allowed)
		)
		(placement
			(enabled no)
			(sheetname "")
		)
		(fill
			(thermal_gap 0.5)
			(thermal_bridge_width 0.5)
			(island_removal_mode 0)
		)
		(polygon
			(pts
				(xy 138.219942 -155.977082) (xy 138.219942 -157.780482) (xy 138.778742 -157.780482) (xy 138.778742 -155.977082)
			)
		)
	)
	(zone
		(layer "In1.Cu")
		(hatch none 0.5)
		(connect_pads
			(clearance 0)
		)
		(min_thickness 0.25)
		(keepout
			(tracks not_allowed)
			(vias allowed)
			(pads allowed)
			(copperpour not_allowed)
			(footprints allowed)
		)
		(placement
			(enabled no)
			(sheetname "")
		)
		(fill
			(thermal_gap 0.5)
			(thermal_bridge_width 0.5)
			(island_removal_mode 0)
		)
		(polygon
			(pts
				(xy 213.120478 -132.174742) (xy 213.120478 -133.978142) (xy 213.679278 -133.978142) (xy 213.679278 -132.174742)
			)
		)
	)
	(zone
		(layer "In1.Cu")
		(hatch none 0.5)
		(connect_pads
			(clearance 0)
		)
		(min_thickness 0.25)
		(keepout
			(tracks not_allowed)
			(vias allowed)
			(pads allowed)
			(copperpour not_allowed)
			(footprints allowed)
		)
		(placement
			(enabled no)
			(sheetname "")
		)
		(fill
			(thermal_gap 0.5)
			(thermal_bridge_width 0.5)
			(island_removal_mode 0)
		)
		(polygon
			(pts
				(xy 89.76995 -136.774682) (xy 89.76995 -138.578082) (xy 90.32875 -138.578082) (xy 90.32875 -136.774682)
			)
		)
	)
	(zone
		(layer "In1.Cu")
		(hatch none 0.5)
		(connect_pads
			(clearance 0)
		)
		(min_thickness 0.25)
		(keepout
			(tracks not_allowed)
			(vias allowed)
			(pads allowed)
			(copperpour not_allowed)
			(footprints allowed)
		)
		(placement
			(enabled no)
			(sheetname "")
		)
		(fill
			(thermal_gap 0.5)
			(thermal_bridge_width 0.5)
			(island_removal_mode 0)
		)
		(polygon
			(pts
				(xy 114.419888 -132.174742) (xy 114.419888 -133.978142) (xy 114.978688 -133.978142) (xy 114.978688 -132.174742)
			)
		)
	)
	(zone
		(layer "In1.Cu")
		(hatch none 0.5)
		(connect_pads
			(clearance 0)
		)
		(min_thickness 0.25)
		(keepout
			(tracks not_allowed)
			(vias allowed)
			(pads allowed)
			(copperpour not_allowed)
			(footprints allowed)
		)
		(placement
			(enabled no)
			(sheetname "")
		)
		(fill
			(thermal_gap 0.5)
			(thermal_bridge_width 0.5)
			(island_removal_mode 0)
		)
		(polygon
			(pts
				(xy 133.119876 -14.521942) (xy 133.119876 -16.325342) (xy 133.678676 -16.325342) (xy 133.678676 -14.521942)
			)
		)
	)
	(zone
		(layer "In1.Cu")
		(hatch none 0.5)
		(connect_pads
			(clearance 0)
		)
		(min_thickness 0.25)
		(keepout
			(tracks not_allowed)
			(vias allowed)
			(pads allowed)
			(copperpour not_allowed)
			(footprints allowed)
		)
		(placement
			(enabled no)
			(sheetname "")
		)
		(fill
			(thermal_gap 0.5)
			(thermal_bridge_width 0.5)
			(island_removal_mode 0)
		)
		(polygon
			(pts
				(xy 266.670536 -136.774682) (xy 266.670536 -138.578082) (xy 267.229336 -138.578082) (xy 267.229336 -136.774682)
			)
		)
	)
	(zone
		(layer "In1.Cu")
		(hatch none 0.5)
		(connect_pads
			(clearance 0)
		)
		(min_thickness 0.25)
		(keepout
			(tracks not_allowed)
			(vias allowed)
			(pads allowed)
			(copperpour not_allowed)
			(footprints allowed)
		)
		(placement
			(enabled no)
			(sheetname "")
		)
		(fill
			(thermal_gap 0.5)
			(thermal_bridge_width 0.5)
			(island_removal_mode 0)
		)
		(polygon
			(pts
				(xy 250.520454 -19.121882) (xy 251.079254 -19.121882) (xy 251.079254 -20.925282) (xy 250.520454 -20.925282)
			)
		)
	)
	(zone
		(layer "In1.Cu")
		(hatch none 0.5)
		(connect_pads
			(clearance 0)
		)
		(min_thickness 0.25)
		(keepout
			(tracks not_allowed)
			(vias allowed)
			(pads allowed)
			(copperpour not_allowed)
			(footprints allowed)
		)
		(placement
			(enabled no)
			(sheetname "")
		)
		(fill
			(thermal_gap 0.5)
			(thermal_bridge_width 0.5)
			(island_removal_mode 0)
		)
		(polygon
			(pts
				(xy 235.22051 -4.920742) (xy 235.22051 -6.724142) (xy 235.77931 -6.724142) (xy 235.77931 -4.920742)
			)
		)
	)
	(zone
		(layer "In1.Cu")
		(hatch none 0.5)
		(connect_pads
			(clearance 0)
		)
		(min_thickness 0.25)
		(keepout
			(tracks not_allowed)
			(vias allowed)
			(pads allowed)
			(copperpour not_allowed)
			(footprints allowed)
		)
		(placement
			(enabled no)
			(sheetname "")
		)
		(fill
			(thermal_gap 0.5)
			(thermal_bridge_width 0.5)
			(island_removal_mode 0)
		)
		(polygon
			(pts
				(xy 244.570504 4.680458) (xy 244.570504 2.877058) (xy 245.129304 2.877058) (xy 245.129304 4.680458)
			)
		)
	)
	(zone
		(layer "In1.Cu")
		(hatch none 0.5)
		(connect_pads
			(clearance 0)
		)
		(min_thickness 0.25)
		(keepout
			(tracks not_allowed)
			(vias allowed)
			(pads allowed)
			(copperpour not_allowed)
			(footprints allowed)
		)
		(placement
			(enabled no)
			(sheetname "")
		)
		(fill
			(thermal_gap 0.5)
			(thermal_bridge_width 0.5)
			(island_removal_mode 0)
		)
		(polygon
			(pts
				(xy 252.220476 -132.174742) (xy 252.220476 -133.978142) (xy 252.779276 -133.978142) (xy 252.779276 -132.174742)
			)
		)
	)
	(zone
		(layer "In1.Cu")
		(hatch none 0.5)
		(connect_pads
			(clearance 0)
		)
		(min_thickness 0.25)
		(keepout
			(tracks not_allowed)
			(vias allowed)
			(pads allowed)
			(copperpour not_allowed)
			(footprints allowed)
		)
		(placement
			(enabled no)
			(sheetname "")
		)
		(fill
			(thermal_gap 0.5)
			(thermal_bridge_width 0.5)
			(island_removal_mode 0)
		)
		(polygon
			(pts
				(xy 48.120046 4.680458) (xy 48.120046 2.877058) (xy 48.678846 2.877058) (xy 48.678846 4.680458)
			)
		)
	)
	(zone
		(layer "In1.Cu")
		(hatch none 0.5)
		(connect_pads
			(clearance 0)
		)
		(min_thickness 0.25)
		(keepout
			(tracks not_allowed)
			(vias allowed)
			(pads allowed)
			(copperpour not_allowed)
			(footprints allowed)
		)
		(placement
			(enabled no)
			(sheetname "")
		)
		(fill
			(thermal_gap 0.5)
			(thermal_bridge_width 0.5)
			(island_removal_mode 0)
		)
		(polygon
			(pts
				(xy 236.070394 -19.121882) (xy 236.070394 -20.925282) (xy 236.629194 -20.925282) (xy 236.629194 -19.121882)
			)
		)
	)
	(zone
		(layer "In1.Cu")
		(hatch none 0.5)
		(connect_pads
			(clearance 0)
		)
		(min_thickness 0.25)
		(keepout
			(tracks not_allowed)
			(vias allowed)
			(pads allowed)
			(copperpour not_allowed)
			(footprints allowed)
		)
		(placement
			(enabled no)
			(sheetname "")
		)
		(fill
			(thermal_gap 0.5)
			(thermal_bridge_width 0.5)
			(island_removal_mode 0)
		)
		(polygon
			(pts
				(xy 71.069962 -9.520682) (xy 71.069962 -11.324082) (xy 71.628762 -11.324082) (xy 71.628762 -9.520682)
			)
		)
	)
	(zone
		(layer "In1.Cu")
		(hatch none 0.5)
		(connect_pads
			(clearance 0)
		)
		(min_thickness 0.25)
		(keepout
			(tracks not_allowed)
			(vias allowed)
			(pads allowed)
			(copperpour not_allowed)
			(footprints allowed)
		)
		(placement
			(enabled no)
			(sheetname "")
		)
		(fill
			(thermal_gap 0.5)
			(thermal_bridge_width 0.5)
			(island_removal_mode 0)
		)
		(polygon
			(pts
				(xy 213.120478 -4.920742) (xy 213.120478 -6.724142) (xy 213.679278 -6.724142) (xy 213.679278 -4.920742)
			)
		)
	)
	(zone
		(layer "In1.Cu")
		(hatch none 0.5)
		(connect_pads
			(clearance 0)
		)
		(min_thickness 0.25)
		(keepout
			(tracks not_allowed)
			(vias allowed)
			(pads allowed)
			(copperpour not_allowed)
			(footprints allowed)
		)
		(placement
			(enabled no)
			(sheetname "")
		)
		(fill
			(thermal_gap 0.5)
			(thermal_bridge_width 0.5)
			(island_removal_mode 0)
		)
		(polygon
			(pts
				(xy 136.51992 -4.920742) (xy 136.51992 -6.724142) (xy 137.07872 -6.724142) (xy 137.07872 -4.920742)
			)
		)
	)
	(zone
		(layer "In1.Cu")
		(hatch none 0.5)
		(connect_pads
			(clearance 0)
		)
		(min_thickness 0.25)
		(keepout
			(tracks not_allowed)
			(vias allowed)
			(pads allowed)
			(copperpour not_allowed)
			(footprints allowed)
		)
		(placement
			(enabled no)
			(sheetname "")
		)
		(fill
			(thermal_gap 0.5)
			(thermal_bridge_width 0.5)
			(island_removal_mode 0)
		)
		(polygon
			(pts
				(xy 382.022604 -29.618432) (xy 383.572004 -29.618432) (xy 383.572004 -30.423358) (xy 382.022604 -30.423358)
			)
		)
	)
	(zone
		(layer "In1.Cu")
		(hatch none 0.5)
		(connect_pads
			(clearance 0)
		)
		(min_thickness 0.25)
		(keepout
			(tracks not_allowed)
			(vias allowed)
			(pads allowed)
			(copperpour not_allowed)
			(footprints allowed)
		)
		(placement
			(enabled no)
			(sheetname "")
		)
		(fill
			(thermal_gap 0.5)
			(thermal_bridge_width 0.5)
			(island_removal_mode 0)
		)
		(polygon
			(pts
				(xy 61.719968 -19.121882) (xy 61.719968 -20.925282) (xy 62.278768 -20.925282) (xy 62.278768 -19.121882)
			)
		)
	)
	(zone
		(layer "In1.Cu")
		(hatch none 0.5)
		(connect_pads
			(clearance 0)
		)
		(min_thickness 0.25)
		(keepout
			(tracks not_allowed)
			(vias allowed)
			(pads allowed)
			(copperpour not_allowed)
			(footprints allowed)
		)
		(placement
			(enabled no)
			(sheetname "")
		)
		(fill
			(thermal_gap 0.5)
			(thermal_bridge_width 0.5)
			(island_removal_mode 0)
		)
		(polygon
			(pts
				(xy 228.420422 4.680458) (xy 228.420422 2.877058) (xy 228.979222 2.877058) (xy 228.979222 4.680458)
			)
		)
	)
	(zone
		(layer "In1.Cu")
		(hatch none 0.5)
		(connect_pads
			(clearance 0)
		)
		(min_thickness 0.25)
		(keepout
			(tracks not_allowed)
			(vias allowed)
			(pads allowed)
			(copperpour not_allowed)
			(footprints allowed)
		)
		(placement
			(enabled no)
			(sheetname "")
		)
		(fill
			(thermal_gap 0.5)
			(thermal_bridge_width 0.5)
			(island_removal_mode 0)
		)
		(polygon
			(pts
				(xy 283.670502 -146.375882) (xy 283.670502 -148.179282) (xy 284.229302 -148.179282) (xy 284.229302 -146.375882)
			)
		)
	)
	(zone
		(layer "In1.Cu")
		(hatch none 0.5)
		(connect_pads
			(clearance 0)
		)
		(min_thickness 0.25)
		(keepout
			(tracks not_allowed)
			(vias allowed)
			(pads allowed)
			(copperpour not_allowed)
			(footprints allowed)
		)
		(placement
			(enabled no)
			(sheetname "")
		)
		(fill
			(thermal_gap 0.5)
			(thermal_bridge_width 0.5)
			(island_removal_mode 0)
		)
		(polygon
			(pts
				(xy 252.220476 -14.521942) (xy 252.220476 -16.325342) (xy 252.779276 -16.325342) (xy 252.779276 -14.521942)
			)
		)
	)
	(zone
		(layer "In1.Cu")
		(hatch none 0.5)
		(connect_pads
			(clearance 0)
		)
		(min_thickness 0.25)
		(keepout
			(tracks not_allowed)
			(vias allowed)
			(pads allowed)
			(copperpour not_allowed)
			(footprints allowed)
		)
		(placement
			(enabled no)
			(sheetname "")
		)
		(fill
			(thermal_gap 0.5)
			(thermal_bridge_width 0.5)
			(island_removal_mode 0)
		)
		(polygon
			(pts
				(xy 114.419888 -14.521942) (xy 114.419888 -16.325342) (xy 114.978688 -16.325342) (xy 114.978688 -14.521942)
			)
		)
	)
	(zone
		(layer "In1.Cu")
		(hatch none 0.5)
		(connect_pads
			(clearance 0)
		)
		(min_thickness 0.25)
		(keepout
			(tracks not_allowed)
			(vias allowed)
			(pads allowed)
			(copperpour not_allowed)
			(footprints allowed)
		)
		(placement
			(enabled no)
			(sheetname "")
		)
		(fill
			(thermal_gap 0.5)
			(thermal_bridge_width 0.5)
			(island_removal_mode 0)
		)
		(polygon
			(pts
				(xy 223.320356 0.080518) (xy 223.320356 -1.722882) (xy 223.879156 -1.722882) (xy 223.879156 0.080518)
			)
		)
	)
	(zone
		(layer "In1.Cu")
		(hatch none 0.5)
		(connect_pads
			(clearance 0)
		)
		(min_thickness 0.25)
		(keepout
			(tracks not_allowed)
			(vias allowed)
			(pads allowed)
			(copperpour not_allowed)
			(footprints allowed)
		)
		(placement
			(enabled no)
			(sheetname "")
		)
		(fill
			(thermal_gap 0.5)
			(thermal_bridge_width 0.5)
			(island_removal_mode 0)
		)
		(polygon
			(pts
				(xy 274.320508 -141.775942) (xy 274.320508 -143.579342) (xy 274.879308 -143.579342) (xy 274.879308 -141.775942)
			)
		)
	)
	(zone
		(layer "In1.Cu")
		(hatch none 0.5)
		(connect_pads
			(clearance 0)
		)
		(min_thickness 0.25)
		(keepout
			(tracks not_allowed)
			(vias allowed)
			(pads allowed)
			(copperpour not_allowed)
			(footprints allowed)
		)
		(placement
			(enabled no)
			(sheetname "")
		)
		(fill
			(thermal_gap 0.5)
			(thermal_bridge_width 0.5)
			(island_removal_mode 0)
		)
		(polygon
			(pts
				(xy 270.07058 4.680458) (xy 270.07058 2.877058) (xy 270.62938 2.877058) (xy 270.62938 4.680458)
			)
		)
	)
	(zone
		(layer "In1.Cu")
		(hatch none 0.5)
		(connect_pads
			(clearance 0)
		)
		(min_thickness 0.25)
		(keepout
			(tracks not_allowed)
			(vias allowed)
			(pads allowed)
			(copperpour not_allowed)
			(footprints allowed)
		)
		(placement
			(enabled no)
			(sheetname "")
		)
		(fill
			(thermal_gap 0.5)
			(thermal_bridge_width 0.5)
			(island_removal_mode 0)
		)
		(polygon
			(pts
				(xy 72.769984 -141.775942) (xy 72.769984 -143.579342) (xy 73.328784 -143.579342) (xy 73.328784 -141.775942)
			)
		)
	)
	(zone
		(layer "In1.Cu")
		(hatch none 0.5)
		(connect_pads
			(clearance 0)
		)
		(min_thickness 0.25)
		(keepout
			(tracks not_allowed)
			(vias allowed)
			(pads allowed)
			(copperpour not_allowed)
			(footprints allowed)
		)
		(placement
			(enabled no)
			(sheetname "")
		)
		(fill
			(thermal_gap 0.5)
			(thermal_bridge_width 0.5)
			(island_removal_mode 0)
		)
		(polygon
			(pts
				(xy 310.870346 -141.775942) (xy 310.870346 -143.579342) (xy 311.429146 -143.579342) (xy 311.429146 -141.775942)
			)
		)
	)
	(zone
		(layer "In1.Cu")
		(hatch none 0.5)
		(connect_pads
			(clearance 0)
		)
		(min_thickness 0.25)
		(keepout
			(tracks not_allowed)
			(vias allowed)
			(pads allowed)
			(copperpour not_allowed)
			(footprints allowed)
		)
		(placement
			(enabled no)
			(sheetname "")
		)
		(fill
			(thermal_gap 0.5)
			(thermal_bridge_width 0.5)
			(island_removal_mode 0)
		)
		(polygon
			(pts
				(xy 56.620156 -9.520682) (xy 56.620156 -11.324082) (xy 57.178956 -11.324082) (xy 57.178956 -9.520682)
			)
		)
	)
	(zone
		(layer "In1.Cu")
		(hatch none 0.5)
		(connect_pads
			(clearance 0)
		)
		(min_thickness 0.25)
		(keepout
			(tracks not_allowed)
			(vias allowed)
			(pads allowed)
			(copperpour not_allowed)
			(footprints allowed)
		)
		(placement
			(enabled no)
			(sheetname "")
		)
		(fill
			(thermal_gap 0.5)
			(thermal_bridge_width 0.5)
			(island_removal_mode 0)
		)
		(polygon
			(pts
				(xy 53.220112 -151.377142) (xy 53.220112 -153.180542) (xy 53.778912 -153.180542) (xy 53.778912 -151.377142)
			)
		)
	)
	(zone
		(layer "In1.Cu")
		(hatch none 0.5)
		(connect_pads
			(clearance 0)
		)
		(min_thickness 0.25)
		(keepout
			(tracks not_allowed)
			(vias allowed)
			(pads allowed)
			(copperpour not_allowed)
			(footprints allowed)
		)
		(placement
			(enabled no)
			(sheetname "")
		)
		(fill
			(thermal_gap 0.5)
			(thermal_bridge_width 0.5)
			(island_removal_mode 0)
		)
		(polygon
			(pts
				(xy 67.669918 -19.121882) (xy 67.669918 -20.925282) (xy 68.228718 -20.925282) (xy 68.228718 -19.121882)
			)
		)
	)
	(zone
		(layer "In1.Cu")
		(hatch none 0.5)
		(connect_pads
			(clearance 0)
		)
		(min_thickness 0.25)
		(keepout
			(tracks not_allowed)
			(vias allowed)
			(pads allowed)
			(copperpour not_allowed)
			(footprints allowed)
		)
		(placement
			(enabled no)
			(sheetname "")
		)
		(fill
			(thermal_gap 0.5)
			(thermal_bridge_width 0.5)
			(island_removal_mode 0)
		)
		(polygon
			(pts
				(xy 63.41999 -155.977082) (xy 63.41999 -157.780482) (xy 63.97879 -157.780482) (xy 63.97879 -155.977082)
			)
		)
	)
	(zone
		(layer "In1.Cu")
		(hatch none 0.5)
		(connect_pads
			(clearance 0)
		)
		(min_thickness 0.25)
		(keepout
			(tracks not_allowed)
			(vias allowed)
			(pads allowed)
			(copperpour not_allowed)
			(footprints allowed)
		)
		(placement
			(enabled no)
			(sheetname "")
		)
		(fill
			(thermal_gap 0.5)
			(thermal_bridge_width 0.5)
			(island_removal_mode 0)
		)
		(polygon
			(pts
				(xy 112.72012 0.080518) (xy 112.72012 -1.722882) (xy 113.27892 -1.722882) (xy 113.27892 0.080518)
			)
		)
	)
	(zone
		(layer "In1.Cu")
		(hatch none 0.5)
		(connect_pads
			(clearance 0)
		)
		(min_thickness 0.25)
		(keepout
			(tracks not_allowed)
			(vias allowed)
			(pads allowed)
			(copperpour not_allowed)
			(footprints allowed)
		)
		(placement
			(enabled no)
			(sheetname "")
		)
		(fill
			(thermal_gap 0.5)
			(thermal_bridge_width 0.5)
			(island_removal_mode 0)
		)
		(polygon
			(pts
				(xy 230.970582 -155.977082) (xy 230.970582 -157.780482) (xy 231.529382 -157.780482) (xy 231.529382 -155.977082)
			)
		)
	)
	(zone
		(layer "In1.Cu")
		(hatch none 0.5)
		(connect_pads
			(clearance 0)
		)
		(min_thickness 0.25)
		(keepout
			(tracks not_allowed)
			(vias allowed)
			(pads allowed)
			(copperpour not_allowed)
			(footprints allowed)
		)
		(placement
			(enabled no)
			(sheetname "")
		)
		(fill
			(thermal_gap 0.5)
			(thermal_bridge_width 0.5)
			(island_removal_mode 0)
		)
		(polygon
			(pts
				(xy 31.969964 -9.520682) (xy 31.969964 -11.324082) (xy 32.528764 -11.324082) (xy 32.528764 -9.520682)
			)
		)
	)
	(zone
		(layer "In1.Cu")
		(hatch none 0.5)
		(connect_pads
			(clearance 0)
		)
		(min_thickness 0.25)
		(keepout
			(tracks not_allowed)
			(vias allowed)
			(pads allowed)
			(copperpour not_allowed)
			(footprints allowed)
		)
		(placement
			(enabled no)
			(sheetname "")
		)
		(fill
			(thermal_gap 0.5)
			(thermal_bridge_width 0.5)
			(island_removal_mode 0)
		)
		(polygon
			(pts
				(xy 225.020378 -155.977082) (xy 225.020378 -157.780482) (xy 225.579178 -157.780482) (xy 225.579178 -155.977082)
			)
		)
	)
	(zone
		(layer "In1.Cu")
		(hatch none 0.5)
		(connect_pads
			(clearance 0)
		)
		(min_thickness 0.25)
		(keepout
			(tracks not_allowed)
			(vias allowed)
			(pads allowed)
			(copperpour not_allowed)
			(footprints allowed)
		)
		(placement
			(enabled no)
			(sheetname "")
		)
		(fill
			(thermal_gap 0.5)
			(thermal_bridge_width 0.5)
			(island_removal_mode 0)
		)
		(polygon
			(pts
				(xy 213.120478 4.680458) (xy 213.120478 2.877058) (xy 213.679278 2.877058) (xy 213.679278 4.680458)
			)
		)
	)
	(zone
		(layer "In1.Cu")
		(hatch none 0.5)
		(connect_pads
			(clearance 0)
		)
		(min_thickness 0.25)
		(keepout
			(tracks not_allowed)
			(vias allowed)
			(pads allowed)
			(copperpour not_allowed)
			(footprints allowed)
		)
		(placement
			(enabled no)
			(sheetname "")
		)
		(fill
			(thermal_gap 0.5)
			(thermal_bridge_width 0.5)
			(island_removal_mode 0)
		)
		(polygon
			(pts
				(xy 100.819966 -141.775942) (xy 100.819966 -143.579342) (xy 101.378766 -143.579342) (xy 101.378766 -141.775942)
			)
		)
	)
	(zone
		(layer "In1.Cu")
		(hatch none 0.5)
		(connect_pads
			(clearance 0)
		)
		(min_thickness 0.25)
		(keepout
			(tracks not_allowed)
			(vias allowed)
			(pads allowed)
			(copperpour not_allowed)
			(footprints allowed)
		)
		(placement
			(enabled no)
			(sheetname "")
		)
		(fill
			(thermal_gap 0.5)
			(thermal_bridge_width 0.5)
			(island_removal_mode 0)
		)
		(polygon
			(pts
				(xy 51.52009 -151.377142) (xy 51.52009 -153.180542) (xy 52.07889 -153.180542) (xy 52.07889 -151.377142)
			)
		)
	)
	(zone
		(layer "In1.Cu")
		(hatch none 0.5)
		(connect_pads
			(clearance 0)
		)
		(min_thickness 0.25)
		(keepout
			(tracks not_allowed)
			(vias allowed)
			(pads allowed)
			(copperpour not_allowed)
			(footprints allowed)
		)
		(placement
			(enabled no)
			(sheetname "")
		)
		(fill
			(thermal_gap 0.5)
			(thermal_bridge_width 0.5)
			(island_removal_mode 0)
		)
		(polygon
			(pts
				(xy 236.070394 -146.375882) (xy 236.070394 -148.179282) (xy 236.629194 -148.179282) (xy 236.629194 -146.375882)
			)
		)
	)
	(zone
		(layer "In1.Cu")
		(hatch none 0.5)
		(connect_pads
			(clearance 0)
		)
		(min_thickness 0.25)
		(keepout
			(tracks not_allowed)
			(vias allowed)
			(pads allowed)
			(copperpour not_allowed)
			(footprints allowed)
		)
		(placement
			(enabled no)
			(sheetname "")
		)
		(fill
			(thermal_gap 0.5)
			(thermal_bridge_width 0.5)
			(island_removal_mode 0)
		)
		(polygon
			(pts
				(xy 247.12041 4.680458) (xy 247.12041 2.877058) (xy 247.67921 2.877058) (xy 247.67921 4.680458)
			)
		)
	)
	(zone
		(layer "In1.Cu")
		(hatch none 0.5)
		(connect_pads
			(clearance 0)
		)
		(min_thickness 0.25)
		(keepout
			(tracks not_allowed)
			(vias allowed)
			(pads allowed)
			(copperpour not_allowed)
			(footprints allowed)
		)
		(placement
			(enabled no)
			(sheetname "")
		)
		(fill
			(thermal_gap 0.5)
			(thermal_bridge_width 0.5)
			(island_removal_mode 0)
		)
		(polygon
			(pts
				(xy 102.519988 -141.775942) (xy 102.519988 -143.579342) (xy 103.078788 -143.579342) (xy 103.078788 -141.775942)
			)
		)
	)
	(zone
		(layer "In1.Cu")
		(hatch none 0.5)
		(connect_pads
			(clearance 0)
		)
		(min_thickness 0.25)
		(keepout
			(tracks not_allowed)
			(vias allowed)
			(pads allowed)
			(copperpour not_allowed)
			(footprints allowed)
		)
		(placement
			(enabled no)
			(sheetname "")
		)
		(fill
			(thermal_gap 0.5)
			(thermal_bridge_width 0.5)
			(island_removal_mode 0)
		)
		(polygon
			(pts
				(xy 43.01998 -155.977082) (xy 43.01998 -157.780482) (xy 43.57878 -157.780482) (xy 43.57878 -155.977082)
			)
		)
	)
	(zone
		(layer "In1.Cu")
		(hatch none 0.5)
		(connect_pads
			(clearance 0)
		)
		(min_thickness 0.25)
		(keepout
			(tracks not_allowed)
			(vias allowed)
			(pads allowed)
			(copperpour not_allowed)
			(footprints allowed)
		)
		(placement
			(enabled no)
			(sheetname "")
		)
		(fill
			(thermal_gap 0.5)
			(thermal_bridge_width 0.5)
			(island_removal_mode 0)
		)
		(polygon
			(pts
				(xy 433.021486 -3.789172) (xy 434.329586 -3.789172) (xy 434.329586 -4.982972) (xy 433.021486 -4.982972)
			)
		)
	)
	(zone
		(layer "In1.Cu")
		(hatch none 0.5)
		(connect_pads
			(clearance 0)
		)
		(min_thickness 0.25)
		(keepout
			(tracks not_allowed)
			(vias allowed)
			(pads allowed)
			(copperpour not_allowed)
			(footprints allowed)
		)
		(placement
			(enabled no)
			(sheetname "")
		)
		(fill
			(thermal_gap 0.5)
			(thermal_bridge_width 0.5)
			(island_removal_mode 0)
		)
		(polygon
			(pts
				(xy 57.47004 -4.920742) (xy 57.47004 -6.724142) (xy 58.02884 -6.724142) (xy 58.02884 -4.920742)
			)
		)
	)
	(zone
		(layer "In1.Cu")
		(hatch none 0.5)
		(connect_pads
			(clearance 0)
		)
		(min_thickness 0.25)
		(keepout
			(tracks not_allowed)
			(vias allowed)
			(pads allowed)
			(copperpour not_allowed)
			(footprints allowed)
		)
		(placement
			(enabled no)
			(sheetname "")
		)
		(fill
			(thermal_gap 0.5)
			(thermal_bridge_width 0.5)
			(island_removal_mode 0)
		)
		(polygon
			(pts
				(xy 71.069962 -146.375882) (xy 71.069962 -148.179282) (xy 71.628762 -148.179282) (xy 71.628762 -146.375882)
			)
		)
	)
	(zone
		(layer "In1.Cu")
		(hatch none 0.5)
		(connect_pads
			(clearance 0)
		)
		(min_thickness 0.25)
		(keepout
			(tracks not_allowed)
			(vias allowed)
			(pads allowed)
			(copperpour not_allowed)
			(footprints allowed)
		)
		(placement
			(enabled no)
			(sheetname "")
		)
		(fill
			(thermal_gap 0.5)
			(thermal_bridge_width 0.5)
			(island_removal_mode 0)
		)
		(polygon
			(pts
				(xy 253.920498 -14.521942) (xy 253.920498 -16.325342) (xy 254.479298 -16.325342) (xy 254.479298 -14.521942)
			)
		)
	)
	(zone
		(layer "In1.Cu")
		(hatch none 0.5)
		(connect_pads
			(clearance 0)
		)
		(min_thickness 0.25)
		(keepout
			(tracks not_allowed)
			(vias allowed)
			(pads allowed)
			(copperpour not_allowed)
			(footprints allowed)
		)
		(placement
			(enabled no)
			(sheetname "")
		)
		(fill
			(thermal_gap 0.5)
			(thermal_bridge_width 0.5)
			(island_removal_mode 0)
		)
		(polygon
			(pts
				(xy 462.686908 -50.872644) (xy 463.995008 -50.872644) (xy 463.995008 -52.879244) (xy 462.686908 -52.879244)
			)
		)
	)
	(zone
		(layer "In1.Cu")
		(hatch none 0.5)
		(connect_pads
			(clearance 0)
		)
		(min_thickness 0.25)
		(keepout
			(tracks not_allowed)
			(vias allowed)
			(pads allowed)
			(copperpour not_allowed)
			(footprints allowed)
		)
		(placement
			(enabled no)
			(sheetname "")
		)
		(fill
			(thermal_gap 0.5)
			(thermal_bridge_width 0.5)
			(island_removal_mode 0)
		)
		(polygon
			(pts
				(xy 392.216386 -3.789172) (xy 393.524486 -3.789172) (xy 393.524486 -4.982972) (xy 392.216386 -4.982972)
			)
		)
	)
	(zone
		(layer "In1.Cu")
		(hatch none 0.5)
		(connect_pads
			(clearance 0)
		)
		(min_thickness 0.25)
		(keepout
			(tracks not_allowed)
			(vias allowed)
			(pads allowed)
			(copperpour not_allowed)
			(footprints allowed)
		)
		(placement
			(enabled no)
			(sheetname "")
		)
		(fill
			(thermal_gap 0.5)
			(thermal_bridge_width 0.5)
			(island_removal_mode 0)
		)
		(polygon
			(pts
				(xy 404.977092 -9.774936) (xy 405.485092 -9.774936) (xy 405.485092 -11.171936) (xy 404.977092 -11.171936)
			)
		)
	)
	(zone
		(layer "In1.Cu")
		(hatch none 0.5)
		(connect_pads
			(clearance 0)
		)
		(min_thickness 0.25)
		(keepout
			(tracks not_allowed)
			(vias allowed)
			(pads allowed)
			(copperpour not_allowed)
			(footprints allowed)
		)
		(placement
			(enabled no)
			(sheetname "")
		)
		(fill
			(thermal_gap 0.5)
			(thermal_bridge_width 0.5)
			(island_removal_mode 0)
		)
		(polygon
			(pts
				(xy 150.96998 -155.977082) (xy 150.96998 -157.780482) (xy 151.52878 -157.780482) (xy 151.52878 -155.977082)
			)
		)
	)
	(zone
		(layer "In1.Cu")
		(hatch none 0.5)
		(connect_pads
			(clearance 0)
		)
		(min_thickness 0.25)
		(keepout
			(tracks not_allowed)
			(vias allowed)
			(pads allowed)
			(copperpour not_allowed)
			(footprints allowed)
		)
		(placement
			(enabled no)
			(sheetname "")
		)
		(fill
			(thermal_gap 0.5)
			(thermal_bridge_width 0.5)
			(island_removal_mode 0)
		)
		(polygon
			(pts
				(xy 79.570072 -151.377142) (xy 79.570072 -153.180542) (xy 80.128872 -153.180542) (xy 80.128872 -151.377142)
			)
		)
	)
	(zone
		(layer "In1.Cu")
		(hatch none 0.5)
		(connect_pads
			(clearance 0)
		)
		(min_thickness 0.25)
		(keepout
			(tracks not_allowed)
			(vias allowed)
			(pads allowed)
			(copperpour not_allowed)
			(footprints allowed)
		)
		(placement
			(enabled no)
			(sheetname "")
		)
		(fill
			(thermal_gap 0.5)
			(thermal_bridge_width 0.5)
			(island_removal_mode 0)
		)
		(polygon
			(pts
				(xy 63.41999 -4.920742) (xy 63.41999 -6.724142) (xy 63.97879 -6.724142) (xy 63.97879 -4.920742)
			)
		)
	)
	(zone
		(layer "In1.Cu")
		(hatch none 0.5)
		(connect_pads
			(clearance 0)
		)
		(min_thickness 0.25)
		(keepout
			(tracks not_allowed)
			(vias allowed)
			(pads allowed)
			(copperpour not_allowed)
			(footprints allowed)
		)
		(placement
			(enabled no)
			(sheetname "")
		)
		(fill
			(thermal_gap 0.5)
			(thermal_bridge_width 0.5)
			(island_removal_mode 0)
		)
		(polygon
			(pts
				(xy 110.16996 -146.375882) (xy 110.16996 -148.179282) (xy 110.72876 -148.179282) (xy 110.72876 -146.375882)
			)
		)
	)
	(zone
		(layer "In1.Cu")
		(hatch none 0.5)
		(connect_pads
			(clearance 0)
		)
		(min_thickness 0.25)
		(keepout
			(tracks not_allowed)
			(vias allowed)
			(pads allowed)
			(copperpour not_allowed)
			(footprints allowed)
		)
		(placement
			(enabled no)
			(sheetname "")
		)
		(fill
			(thermal_gap 0.5)
			(thermal_bridge_width 0.5)
			(island_removal_mode 0)
		)
		(polygon
			(pts
				(xy 117.819932 -4.920742) (xy 117.819932 -6.724142) (xy 118.378732 -6.724142) (xy 118.378732 -4.920742)
			)
		)
	)
	(zone
		(layer "In1.Cu")
		(hatch none 0.5)
		(connect_pads
			(clearance 0)
		)
		(min_thickness 0.25)
		(keepout
			(tracks not_allowed)
			(vias allowed)
			(pads allowed)
			(copperpour not_allowed)
			(footprints allowed)
		)
		(placement
			(enabled no)
			(sheetname "")
		)
		(fill
			(thermal_gap 0.5)
			(thermal_bridge_width 0.5)
			(island_removal_mode 0)
		)
		(polygon
			(pts
				(xy 285.370524 4.680458) (xy 285.370524 2.877058) (xy 285.929324 2.877058) (xy 285.929324 4.680458)
			)
		)
	)
	(zone
		(layer "In1.Cu")
		(hatch none 0.5)
		(connect_pads
			(clearance 0)
		)
		(min_thickness 0.25)
		(keepout
			(tracks not_allowed)
			(vias allowed)
			(pads allowed)
			(copperpour not_allowed)
			(footprints allowed)
		)
		(placement
			(enabled no)
			(sheetname "")
		)
		(fill
			(thermal_gap 0.5)
			(thermal_bridge_width 0.5)
			(island_removal_mode 0)
		)
		(polygon
			(pts
				(xy 298.970446 -136.774682) (xy 298.970446 -138.578082) (xy 299.529246 -138.578082) (xy 299.529246 -136.774682)
			)
		)
	)
	(zone
		(layer "In1.Cu")
		(hatch none 0.5)
		(connect_pads
			(clearance 0)
		)
		(min_thickness 0.25)
		(keepout
			(tracks not_allowed)
			(vias allowed)
			(pads allowed)
			(copperpour not_allowed)
			(footprints allowed)
		)
		(placement
			(enabled no)
			(sheetname "")
		)
		(fill
			(thermal_gap 0.5)
			(thermal_bridge_width 0.5)
			(island_removal_mode 0)
		)
		(polygon
			(pts
				(xy 102.519988 4.680458) (xy 102.519988 2.877058) (xy 103.078788 2.877058) (xy 103.078788 4.680458)
			)
		)
	)
	(zone
		(layer "In1.Cu")
		(hatch none 0.5)
		(connect_pads
			(clearance 0)
		)
		(min_thickness 0.25)
		(keepout
			(tracks not_allowed)
			(vias allowed)
			(pads allowed)
			(copperpour not_allowed)
			(footprints allowed)
		)
		(placement
			(enabled no)
			(sheetname "")
		)
		(fill
			(thermal_gap 0.5)
			(thermal_bridge_width 0.5)
			(island_removal_mode 0)
		)
		(polygon
			(pts
				(xy 53.220112 -132.174742) (xy 53.220112 -133.978142) (xy 53.778912 -133.978142) (xy 53.778912 -132.174742)
			)
		)
	)
	(zone
		(layer "In1.Cu")
		(hatch none 0.5)
		(connect_pads
			(clearance 0)
		)
		(min_thickness 0.25)
		(keepout
			(tracks not_allowed)
			(vias allowed)
			(pads allowed)
			(copperpour not_allowed)
			(footprints allowed)
		)
		(placement
			(enabled no)
			(sheetname "")
		)
		(fill
			(thermal_gap 0.5)
			(thermal_bridge_width 0.5)
			(island_removal_mode 0)
		)
		(polygon
			(pts
				(xy 44.720002 -4.920742) (xy 44.720002 -6.724142) (xy 45.278802 -6.724142) (xy 45.278802 -4.920742)
			)
		)
	)
	(zone
		(layer "In1.Cu")
		(hatch none 0.5)
		(connect_pads
			(clearance 0)
		)
		(min_thickness 0.25)
		(keepout
			(tracks not_allowed)
			(vias allowed)
			(pads allowed)
			(copperpour not_allowed)
			(footprints allowed)
		)
		(placement
			(enabled no)
			(sheetname "")
		)
		(fill
			(thermal_gap 0.5)
			(thermal_bridge_width 0.5)
			(island_removal_mode 0)
		)
		(polygon
			(pts
				(xy 79.570072 -14.521942) (xy 79.570072 -16.325342) (xy 80.128872 -16.325342) (xy 80.128872 -14.521942)
			)
		)
	)
	(zone
		(layer "In1.Cu")
		(hatch none 0.5)
		(connect_pads
			(clearance 0)
		)
		(min_thickness 0.25)
		(keepout
			(tracks not_allowed)
			(vias allowed)
			(pads allowed)
			(copperpour not_allowed)
			(footprints allowed)
		)
		(placement
			(enabled no)
			(sheetname "")
		)
		(fill
			(thermal_gap 0.5)
			(thermal_bridge_width 0.5)
			(island_removal_mode 0)
		)
		(polygon
			(pts
				(xy 378.831094 -7.193026) (xy 380.139194 -7.193026) (xy 380.139194 -8.386826) (xy 378.831094 -8.386826)
			)
		)
	)
	(zone
		(layer "In1.Cu")
		(hatch none 0.5)
		(connect_pads
			(clearance 0)
		)
		(min_thickness 0.25)
		(keepout
			(tracks not_allowed)
			(vias allowed)
			(pads allowed)
			(copperpour not_allowed)
			(footprints allowed)
		)
		(placement
			(enabled no)
			(sheetname "")
		)
		(fill
			(thermal_gap 0.5)
			(thermal_bridge_width 0.5)
			(island_removal_mode 0)
		)
		(polygon
			(pts
				(xy 82.119978 -146.375882) (xy 82.119978 -148.179282) (xy 82.678778 -148.179282) (xy 82.678778 -146.375882)
			)
		)
	)
	(zone
		(layer "In1.Cu")
		(hatch none 0.5)
		(connect_pads
			(clearance 0)
		)
		(min_thickness 0.25)
		(keepout
			(tracks not_allowed)
			(vias allowed)
			(pads allowed)
			(copperpour not_allowed)
			(footprints allowed)
		)
		(placement
			(enabled no)
			(sheetname "")
		)
		(fill
			(thermal_gap 0.5)
			(thermal_bridge_width 0.5)
			(island_removal_mode 0)
		)
		(polygon
			(pts
				(xy 400.217386 -7.192772) (xy 401.525486 -7.192772) (xy 401.525486 -8.386572) (xy 400.217386 -8.386572)
			)
		)
	)
	(zone
		(layer "In1.Cu")
		(hatch none 0.5)
		(connect_pads
			(clearance 0)
		)
		(min_thickness 0.25)
		(keepout
			(tracks not_allowed)
			(vias allowed)
			(pads allowed)
			(copperpour not_allowed)
			(footprints allowed)
		)
		(placement
			(enabled no)
			(sheetname "")
		)
		(fill
			(thermal_gap 0.5)
			(thermal_bridge_width 0.5)
			(island_removal_mode 0)
		)
		(polygon
			(pts
				(xy 65.120012 -4.920742) (xy 65.120012 -6.724142) (xy 65.678812 -6.724142) (xy 65.678812 -4.920742)
			)
		)
	)
	(zone
		(layer "In1.Cu")
		(hatch none 0.5)
		(connect_pads
			(clearance 0)
		)
		(min_thickness 0.25)
		(keepout
			(tracks not_allowed)
			(vias allowed)
			(pads allowed)
			(copperpour not_allowed)
			(footprints allowed)
		)
		(placement
			(enabled no)
			(sheetname "")
		)
		(fill
			(thermal_gap 0.5)
			(thermal_bridge_width 0.5)
			(island_removal_mode 0)
		)
		(polygon
			(pts
				(xy 268.370558 -4.920742) (xy 268.370558 -6.724142) (xy 268.929358 -6.724142) (xy 268.929358 -4.920742)
			)
		)
	)
	(zone
		(layer "In1.Cu")
		(hatch none 0.5)
		(connect_pads
			(clearance 0)
		)
		(min_thickness 0.25)
		(keepout
			(tracks not_allowed)
			(vias allowed)
			(pads allowed)
			(copperpour not_allowed)
			(footprints allowed)
		)
		(placement
			(enabled no)
			(sheetname "")
		)
		(fill
			(thermal_gap 0.5)
			(thermal_bridge_width 0.5)
			(island_removal_mode 0)
		)
		(polygon
			(pts
				(xy 251.370592 -14.521942) (xy 251.370592 -16.325342) (xy 251.929392 -16.325342) (xy 251.929392 -14.521942)
			)
		)
	)
	(zone
		(layer "In1.Cu")
		(hatch none 0.5)
		(connect_pads
			(clearance 0)
		)
		(min_thickness 0.25)
		(keepout
			(tracks not_allowed)
			(vias allowed)
			(pads allowed)
			(copperpour not_allowed)
			(footprints allowed)
		)
		(placement
			(enabled no)
			(sheetname "")
		)
		(fill
			(thermal_gap 0.5)
			(thermal_bridge_width 0.5)
			(island_removal_mode 0)
		)
		(polygon
			(pts
				(xy 201.220578 0.080518) (xy 201.220578 -1.722882) (xy 201.779378 -1.722882) (xy 201.779378 0.080518)
			)
		)
	)
	(zone
		(layer "In1.Cu")
		(hatch none 0.5)
		(connect_pads
			(clearance 0)
		)
		(min_thickness 0.25)
		(keepout
			(tracks not_allowed)
			(vias allowed)
			(pads allowed)
			(copperpour not_allowed)
			(footprints allowed)
		)
		(placement
			(enabled no)
			(sheetname "")
		)
		(fill
			(thermal_gap 0.5)
			(thermal_bridge_width 0.5)
			(island_removal_mode 0)
		)
		(polygon
			(pts
				(xy 37.07003 -132.174742) (xy 37.07003 -133.978142) (xy 37.62883 -133.978142) (xy 37.62883 -132.174742)
			)
		)
	)
	(zone
		(layer "In1.Cu")
		(hatch none 0.5)
		(connect_pads
			(clearance 0)
		)
		(min_thickness 0.25)
		(keepout
			(tracks not_allowed)
			(vias allowed)
			(pads allowed)
			(copperpour not_allowed)
			(footprints allowed)
		)
		(placement
			(enabled no)
			(sheetname "")
		)
		(fill
			(thermal_gap 0.5)
			(thermal_bridge_width 0.5)
			(island_removal_mode 0)
		)
		(polygon
			(pts
				(xy 126.320042 0.080518) (xy 126.320042 -1.722882) (xy 126.878842 -1.722882) (xy 126.878842 0.080518)
			)
		)
	)
	(zone
		(layer "In1.Cu")
		(hatch none 0.5)
		(connect_pads
			(clearance 0)
		)
		(min_thickness 0.25)
		(keepout
			(tracks not_allowed)
			(vias allowed)
			(pads allowed)
			(copperpour not_allowed)
			(footprints allowed)
		)
		(placement
			(enabled no)
			(sheetname "")
		)
		(fill
			(thermal_gap 0.5)
			(thermal_bridge_width 0.5)
			(island_removal_mode 0)
		)
		(polygon
			(pts
				(xy 419.419786 -7.192772) (xy 420.727886 -7.192772) (xy 420.727886 -8.386572) (xy 419.419786 -8.386572)
			)
		)
	)
	(zone
		(layer "In1.Cu")
		(hatch none 0.5)
		(connect_pads
			(clearance 0)
		)
		(min_thickness 0.25)
		(keepout
			(tracks not_allowed)
			(vias allowed)
			(pads allowed)
			(copperpour not_allowed)
			(footprints allowed)
		)
		(placement
			(enabled no)
			(sheetname "")
		)
		(fill
			(thermal_gap 0.5)
			(thermal_bridge_width 0.5)
			(island_removal_mode 0)
		)
		(polygon
			(pts
				(xy 257.320542 -132.174742) (xy 257.320542 -133.978142) (xy 257.879342 -133.978142) (xy 257.879342 -132.174742)
			)
		)
	)
	(zone
		(layer "In1.Cu")
		(hatch none 0.5)
		(connect_pads
			(clearance 0)
		)
		(min_thickness 0.25)
		(keepout
			(tracks not_allowed)
			(vias allowed)
			(pads allowed)
			(copperpour not_allowed)
			(footprints allowed)
		)
		(placement
			(enabled no)
			(sheetname "")
		)
		(fill
			(thermal_gap 0.5)
			(thermal_bridge_width 0.5)
			(island_removal_mode 0)
		)
		(polygon
			(pts
				(xy 49.820068 -151.377142) (xy 49.820068 -153.180542) (xy 50.378868 -153.180542) (xy 50.378868 -151.377142)
			)
		)
	)
	(zone
		(layer "In1.Cu")
		(hatch none 0.5)
		(connect_pads
			(clearance 0)
		)
		(min_thickness 0.25)
		(keepout
			(tracks not_allowed)
			(vias allowed)
			(pads allowed)
			(copperpour not_allowed)
			(footprints allowed)
		)
		(placement
			(enabled no)
			(sheetname "")
		)
		(fill
			(thermal_gap 0.5)
			(thermal_bridge_width 0.5)
			(island_removal_mode 0)
		)
		(polygon
			(pts
				(xy 87.220044 -19.121882) (xy 87.220044 -20.925282) (xy 87.778844 -20.925282) (xy 87.778844 -19.121882)
			)
		)
	)
	(zone
		(layer "In1.Cu")
		(hatch none 0.5)
		(connect_pads
			(clearance 0)
		)
		(min_thickness 0.25)
		(keepout
			(tracks not_allowed)
			(vias allowed)
			(pads allowed)
			(copperpour not_allowed)
			(footprints allowed)
		)
		(placement
			(enabled no)
			(sheetname "")
		)
		(fill
			(thermal_gap 0.5)
			(thermal_bridge_width 0.5)
			(island_removal_mode 0)
		)
		(polygon
			(pts
				(xy 247.970548 -155.977082) (xy 247.970548 -157.780482) (xy 248.529348 -157.780482) (xy 248.529348 -155.977082)
			)
		)
	)
	(zone
		(layer "In1.Cu")
		(hatch none 0.5)
		(connect_pads
			(clearance 0)
		)
		(min_thickness 0.25)
		(keepout
			(tracks not_allowed)
			(vias allowed)
			(pads allowed)
			(copperpour not_allowed)
			(footprints allowed)
		)
		(placement
			(enabled no)
			(sheetname "")
		)
		(fill
			(thermal_gap 0.5)
			(thermal_bridge_width 0.5)
			(island_removal_mode 0)
		)
		(polygon
			(pts
				(xy 63.41999 -19.121882) (xy 63.41999 -20.925282) (xy 63.97879 -20.925282) (xy 63.97879 -19.121882)
			)
		)
	)
	(zone
		(layer "In1.Cu")
		(hatch none 0.5)
		(connect_pads
			(clearance 0)
		)
		(min_thickness 0.25)
		(keepout
			(tracks not_allowed)
			(vias allowed)
			(pads allowed)
			(copperpour not_allowed)
			(footprints allowed)
		)
		(placement
			(enabled no)
			(sheetname "")
		)
		(fill
			(thermal_gap 0.5)
			(thermal_bridge_width 0.5)
			(island_removal_mode 0)
		)
		(polygon
			(pts
				(xy 102.519988 -151.377142) (xy 102.519988 -153.180542) (xy 103.078788 -153.180542) (xy 103.078788 -151.377142)
			)
		)
	)
	(zone
		(layer "In1.Cu")
		(hatch none 0.5)
		(connect_pads
			(clearance 0)
		)
		(min_thickness 0.25)
		(keepout
			(tracks not_allowed)
			(vias allowed)
			(pads allowed)
			(copperpour not_allowed)
			(footprints allowed)
		)
		(placement
			(enabled no)
			(sheetname "")
		)
		(fill
			(thermal_gap 0.5)
			(thermal_bridge_width 0.5)
			(island_removal_mode 0)
		)
		(polygon
			(pts
				(xy 281.120342 4.680458) (xy 281.120342 2.877058) (xy 281.679142 2.877058) (xy 281.679142 4.680458)
			)
		)
	)
	(zone
		(layer "In1.Cu")
		(hatch none 0.5)
		(connect_pads
			(clearance 0)
		)
		(min_thickness 0.25)
		(keepout
			(tracks not_allowed)
			(vias allowed)
			(pads allowed)
			(copperpour not_allowed)
			(footprints allowed)
		)
		(placement
			(enabled no)
			(sheetname "")
		)
		(fill
			(thermal_gap 0.5)
			(thermal_bridge_width 0.5)
			(island_removal_mode 0)
		)
		(polygon
			(pts
				(xy 130.56997 -136.774682) (xy 130.56997 -138.578082) (xy 131.12877 -138.578082) (xy 131.12877 -136.774682)
			)
		)
	)
	(zone
		(layer "In1.Cu")
		(hatch none 0.5)
		(connect_pads
			(clearance 0)
		)
		(min_thickness 0.25)
		(keepout
			(tracks not_allowed)
			(vias allowed)
			(pads allowed)
			(copperpour not_allowed)
			(footprints allowed)
		)
		(placement
			(enabled no)
			(sheetname "")
		)
		(fill
			(thermal_gap 0.5)
			(thermal_bridge_width 0.5)
			(island_removal_mode 0)
		)
		(polygon
			(pts
				(xy 202.070462 -151.377142) (xy 202.070462 -153.180542) (xy 202.629262 -153.180542) (xy 202.629262 -151.377142)
			)
		)
	)
	(zone
		(layer "In1.Cu")
		(hatch none 0.5)
		(connect_pads
			(clearance 0)
		)
		(min_thickness 0.25)
		(keepout
			(tracks not_allowed)
			(vias allowed)
			(pads allowed)
			(copperpour not_allowed)
			(footprints allowed)
		)
		(placement
			(enabled no)
			(sheetname "")
		)
		(fill
			(thermal_gap 0.5)
			(thermal_bridge_width 0.5)
			(island_removal_mode 0)
		)
		(polygon
			(pts
				(xy 211.420456 -151.377142) (xy 211.420456 -153.180542) (xy 211.979256 -153.180542) (xy 211.979256 -151.377142)
			)
		)
	)
	(zone
		(layer "In1.Cu")
		(hatch none 0.5)
		(connect_pads
			(clearance 0)
		)
		(min_thickness 0.25)
		(keepout
			(tracks not_allowed)
			(vias allowed)
			(pads allowed)
			(copperpour not_allowed)
			(footprints allowed)
		)
		(placement
			(enabled no)
			(sheetname "")
		)
		(fill
			(thermal_gap 0.5)
			(thermal_bridge_width 0.5)
			(island_removal_mode 0)
		)
		(polygon
			(pts
				(xy 271.770602 -4.920742) (xy 271.770602 -6.724142) (xy 272.329402 -6.724142) (xy 272.329402 -4.920742)
			)
		)
	)
	(zone
		(layer "In1.Cu")
		(hatch none 0.5)
		(connect_pads
			(clearance 0)
		)
		(min_thickness 0.25)
		(keepout
			(tracks not_allowed)
			(vias allowed)
			(pads allowed)
			(copperpour not_allowed)
			(footprints allowed)
		)
		(placement
			(enabled no)
			(sheetname "")
		)
		(fill
			(thermal_gap 0.5)
			(thermal_bridge_width 0.5)
			(island_removal_mode 0)
		)
		(polygon
			(pts
				(xy 298.970446 -19.121882) (xy 298.970446 -20.925282) (xy 299.529246 -20.925282) (xy 299.529246 -19.121882)
			)
		)
	)
	(zone
		(layer "In1.Cu")
		(hatch none 0.5)
		(connect_pads
			(clearance 0)
		)
		(min_thickness 0.25)
		(keepout
			(tracks not_allowed)
			(vias allowed)
			(pads allowed)
			(copperpour not_allowed)
			(footprints allowed)
		)
		(placement
			(enabled no)
			(sheetname "")
		)
		(fill
			(thermal_gap 0.5)
			(thermal_bridge_width 0.5)
			(island_removal_mode 0)
		)
		(polygon
			(pts
				(xy 221.620588 0.080518) (xy 221.620588 -1.722882) (xy 222.179388 -1.722882) (xy 222.179388 0.080518)
			)
		)
	)
	(zone
		(layer "In1.Cu")
		(hatch none 0.5)
		(connect_pads
			(clearance 0)
		)
		(min_thickness 0.25)
		(keepout
			(tracks not_allowed)
			(vias allowed)
			(pads allowed)
			(copperpour not_allowed)
			(footprints allowed)
		)
		(placement
			(enabled no)
			(sheetname "")
		)
		(fill
			(thermal_gap 0.5)
			(thermal_bridge_width 0.5)
			(island_removal_mode 0)
		)
		(polygon
			(pts
				(xy 267.52042 -141.775942) (xy 267.52042 -143.579342) (xy 268.07922 -143.579342) (xy 268.07922 -141.775942)
			)
		)
	)
	(zone
		(layer "In1.Cu")
		(hatch none 0.5)
		(connect_pads
			(clearance 0)
		)
		(min_thickness 0.25)
		(keepout
			(tracks not_allowed)
			(vias allowed)
			(pads allowed)
			(copperpour not_allowed)
			(footprints allowed)
		)
		(placement
			(enabled no)
			(sheetname "")
		)
		(fill
			(thermal_gap 0.5)
			(thermal_bridge_width 0.5)
			(island_removal_mode 0)
		)
		(polygon
			(pts
				(xy 243.720366 -19.121882) (xy 243.720366 -20.925282) (xy 244.279166 -20.925282) (xy 244.279166 -19.121882)
			)
		)
	)
	(zone
		(layer "In1.Cu")
		(hatch none 0.5)
		(connect_pads
			(clearance 0)
		)
		(min_thickness 0.25)
		(keepout
			(tracks not_allowed)
			(vias allowed)
			(pads allowed)
			(copperpour not_allowed)
			(footprints allowed)
		)
		(placement
			(enabled no)
			(sheetname "")
		)
		(fill
			(thermal_gap 0.5)
			(thermal_bridge_width 0.5)
			(island_removal_mode 0)
		)
		(polygon
			(pts
				(xy 72.769984 -146.375882) (xy 72.769984 -148.179282) (xy 73.328784 -148.179282) (xy 73.328784 -146.375882)
			)
		)
	)
	(zone
		(layer "In1.Cu")
		(hatch none 0.5)
		(connect_pads
			(clearance 0)
		)
		(min_thickness 0.25)
		(keepout
			(tracks not_allowed)
			(vias allowed)
			(pads allowed)
			(copperpour not_allowed)
			(footprints allowed)
		)
		(placement
			(enabled no)
			(sheetname "")
		)
		(fill
			(thermal_gap 0.5)
			(thermal_bridge_width 0.5)
			(island_removal_mode 0)
		)
		(polygon
			(pts
				(xy 213.970362 -19.121882) (xy 213.970362 -20.925282) (xy 214.529162 -20.925282) (xy 214.529162 -19.121882)
			)
		)
	)
	(zone
		(layer "In1.Cu")
		(hatch none 0.5)
		(connect_pads
			(clearance 0)
		)
		(min_thickness 0.25)
		(keepout
			(tracks not_allowed)
			(vias allowed)
			(pads allowed)
			(copperpour not_allowed)
			(footprints allowed)
		)
		(placement
			(enabled no)
			(sheetname "")
		)
		(fill
			(thermal_gap 0.5)
			(thermal_bridge_width 0.5)
			(island_removal_mode 0)
		)
		(polygon
			(pts
				(xy 314.27039 0.080518) (xy 314.27039 -1.722882) (xy 314.82919 -1.722882) (xy 314.82919 0.080518)
			)
		)
	)
	(zone
		(layer "In1.Cu")
		(hatch none 0.5)
		(connect_pads
			(clearance 0)
		)
		(min_thickness 0.25)
		(keepout
			(tracks not_allowed)
			(vias allowed)
			(pads allowed)
			(copperpour not_allowed)
			(footprints allowed)
		)
		(placement
			(enabled no)
			(sheetname "")
		)
		(fill
			(thermal_gap 0.5)
			(thermal_bridge_width 0.5)
			(island_removal_mode 0)
		)
		(polygon
			(pts
				(xy 91.469972 -14.521942) (xy 91.469972 -16.325342) (xy 92.028772 -16.325342) (xy 92.028772 -14.521942)
			)
		)
	)
	(zone
		(layer "In1.Cu")
		(hatch none 0.5)
		(connect_pads
			(clearance 0)
		)
		(min_thickness 0.25)
		(keepout
			(tracks not_allowed)
			(vias allowed)
			(pads allowed)
			(copperpour not_allowed)
			(footprints allowed)
		)
		(placement
			(enabled no)
			(sheetname "")
		)
		(fill
			(thermal_gap 0.5)
			(thermal_bridge_width 0.5)
			(island_removal_mode 0)
		)
		(polygon
			(pts
				(xy 219.070428 -19.121882) (xy 219.070428 -20.925282) (xy 219.629228 -20.925282) (xy 219.629228 -19.121882)
			)
		)
	)
	(zone
		(layer "In1.Cu")
		(hatch none 0.5)
		(connect_pads
			(clearance 0)
		)
		(min_thickness 0.25)
		(keepout
			(tracks not_allowed)
			(vias allowed)
			(pads allowed)
			(copperpour not_allowed)
			(footprints allowed)
		)
		(placement
			(enabled no)
			(sheetname "")
		)
		(fill
			(thermal_gap 0.5)
			(thermal_bridge_width 0.5)
			(island_removal_mode 0)
		)
		(polygon
			(pts
				(xy 103.370126 -14.521942) (xy 103.370126 -16.325342) (xy 103.928926 -16.325342) (xy 103.928926 -14.521942)
			)
		)
	)
	(zone
		(layer "In1.Cu")
		(hatch none 0.5)
		(connect_pads
			(clearance 0)
		)
		(min_thickness 0.25)
		(keepout
			(tracks not_allowed)
			(vias allowed)
			(pads allowed)
			(copperpour not_allowed)
			(footprints allowed)
		)
		(placement
			(enabled no)
			(sheetname "")
		)
		(fill
			(thermal_gap 0.5)
			(thermal_bridge_width 0.5)
			(island_removal_mode 0)
		)
		(polygon
			(pts
				(xy 265.820398 -141.775942) (xy 265.820398 -143.579342) (xy 266.379198 -143.579342) (xy 266.379198 -141.775942)
			)
		)
	)
	(zone
		(layer "In1.Cu")
		(hatch none 0.5)
		(connect_pads
			(clearance 0)
		)
		(min_thickness 0.25)
		(keepout
			(tracks not_allowed)
			(vias allowed)
			(pads allowed)
			(copperpour not_allowed)
			(footprints allowed)
		)
		(placement
			(enabled no)
			(sheetname "")
		)
		(fill
			(thermal_gap 0.5)
			(thermal_bridge_width 0.5)
			(island_removal_mode 0)
		)
		(polygon
			(pts
				(xy 147.569936 -146.375882) (xy 147.569936 -148.179282) (xy 148.128736 -148.179282) (xy 148.128736 -146.375882)
			)
		)
	)
	(zone
		(layer "In1.Cu")
		(hatch none 0.5)
		(connect_pads
			(clearance 0)
		)
		(min_thickness 0.25)
		(keepout
			(tracks not_allowed)
			(vias allowed)
			(pads allowed)
			(copperpour not_allowed)
			(footprints allowed)
		)
		(placement
			(enabled no)
			(sheetname "")
		)
		(fill
			(thermal_gap 0.5)
			(thermal_bridge_width 0.5)
			(island_removal_mode 0)
		)
		(polygon
			(pts
				(xy 294.720518 -141.775942) (xy 294.720518 -143.579342) (xy 295.279318 -143.579342) (xy 295.279318 -141.775942)
			)
		)
	)
	(zone
		(layer "In1.Cu")
		(hatch none 0.5)
		(connect_pads
			(clearance 0)
		)
		(min_thickness 0.25)
		(keepout
			(tracks not_allowed)
			(vias allowed)
			(pads allowed)
			(copperpour not_allowed)
			(footprints allowed)
		)
		(placement
			(enabled no)
			(sheetname "")
		)
		(fill
			(thermal_gap 0.5)
			(thermal_bridge_width 0.5)
			(island_removal_mode 0)
		)
		(polygon
			(pts
				(xy 13.6398 -35.433) (xy 15.0368 -35.433) (xy 15.0368 -35.941) (xy 13.6398 -35.941)
			)
		)
	)
	(zone
		(layer "In1.Cu")
		(hatch none 0.5)
		(connect_pads
			(clearance 0)
		)
		(min_thickness 0.25)
		(keepout
			(tracks not_allowed)
			(vias allowed)
			(pads allowed)
			(copperpour not_allowed)
			(footprints allowed)
		)
		(placement
			(enabled no)
			(sheetname "")
		)
		(fill
			(thermal_gap 0.5)
			(thermal_bridge_width 0.5)
			(island_removal_mode 0)
		)
		(polygon
			(pts
				(xy 242.870482 -132.174742) (xy 242.870482 -133.978142) (xy 243.429282 -133.978142) (xy 243.429282 -132.174742)
			)
		)
	)
	(zone
		(layer "In1.Cu")
		(hatch none 0.5)
		(connect_pads
			(clearance 0)
		)
		(min_thickness 0.25)
		(keepout
			(tracks not_allowed)
			(vias allowed)
			(pads allowed)
			(copperpour not_allowed)
			(footprints allowed)
		)
		(placement
			(enabled no)
			(sheetname "")
		)
		(fill
			(thermal_gap 0.5)
			(thermal_bridge_width 0.5)
			(island_removal_mode 0)
		)
		(polygon
			(pts
				(xy 202.9206 -155.977082) (xy 202.9206 -157.780482) (xy 203.4794 -157.780482) (xy 203.4794 -155.977082)
			)
		)
	)
	(zone
		(layer "In1.Cu")
		(hatch none 0.5)
		(connect_pads
			(clearance 0)
		)
		(min_thickness 0.25)
		(keepout
			(tracks not_allowed)
			(vias allowed)
			(pads allowed)
			(copperpour not_allowed)
			(footprints allowed)
		)
		(placement
			(enabled no)
			(sheetname "")
		)
		(fill
			(thermal_gap 0.5)
			(thermal_bridge_width 0.5)
			(island_removal_mode 0)
		)
		(polygon
			(pts
				(xy 124.62002 -146.375882) (xy 124.62002 -148.179282) (xy 125.17882 -148.179282) (xy 125.17882 -146.375882)
			)
		)
	)
	(zone
		(layer "In1.Cu")
		(hatch none 0.5)
		(connect_pads
			(clearance 0)
		)
		(min_thickness 0.25)
		(keepout
			(tracks not_allowed)
			(vias allowed)
			(pads allowed)
			(copperpour not_allowed)
			(footprints allowed)
		)
		(placement
			(enabled no)
			(sheetname "")
		)
		(fill
			(thermal_gap 0.5)
			(thermal_bridge_width 0.5)
			(island_removal_mode 0)
		)
		(polygon
			(pts
				(xy 291.320474 -9.520682) (xy 291.320474 -11.324082) (xy 291.879274 -11.324082) (xy 291.879274 -9.520682)
			)
		)
	)
	(zone
		(layer "In1.Cu")
		(hatch none 0.5)
		(connect_pads
			(clearance 0)
		)
		(min_thickness 0.25)
		(keepout
			(tracks not_allowed)
			(vias allowed)
			(pads allowed)
			(copperpour not_allowed)
			(footprints allowed)
		)
		(placement
			(enabled no)
			(sheetname "")
		)
		(fill
			(thermal_gap 0.5)
			(thermal_bridge_width 0.5)
			(island_removal_mode 0)
		)
		(polygon
			(pts
				(xy 112.72012 -151.377142) (xy 112.72012 -153.180542) (xy 113.27892 -153.180542) (xy 113.27892 -151.377142)
			)
		)
	)
	(zone
		(layer "In1.Cu")
		(hatch none 0.5)
		(connect_pads
			(clearance 0)
		)
		(min_thickness 0.25)
		(keepout
			(tracks not_allowed)
			(vias allowed)
			(pads allowed)
			(copperpour not_allowed)
			(footprints allowed)
		)
		(placement
			(enabled no)
			(sheetname "")
		)
		(fill
			(thermal_gap 0.5)
			(thermal_bridge_width 0.5)
			(island_removal_mode 0)
		)
		(polygon
			(pts
				(xy 72.769984 -151.377142) (xy 72.769984 -153.180542) (xy 73.328784 -153.180542) (xy 73.328784 -151.377142)
			)
		)
	)
	(zone
		(layer "In1.Cu")
		(hatch none 0.5)
		(connect_pads
			(clearance 0)
		)
		(min_thickness 0.25)
		(keepout
			(tracks not_allowed)
			(vias allowed)
			(pads allowed)
			(copperpour not_allowed)
			(footprints allowed)
		)
		(placement
			(enabled no)
			(sheetname "")
		)
		(fill
			(thermal_gap 0.5)
			(thermal_bridge_width 0.5)
			(island_removal_mode 0)
		)
		(polygon
			(pts
				(xy 92.32011 -132.174742) (xy 92.32011 -133.978142) (xy 92.87891 -133.978142) (xy 92.87891 -132.174742)
			)
		)
	)
	(zone
		(layer "In1.Cu")
		(hatch none 0.5)
		(connect_pads
			(clearance 0)
		)
		(min_thickness 0.25)
		(keepout
			(tracks not_allowed)
			(vias allowed)
			(pads allowed)
			(copperpour not_allowed)
			(footprints allowed)
		)
		(placement
			(enabled no)
			(sheetname "")
		)
		(fill
			(thermal_gap 0.5)
			(thermal_bridge_width 0.5)
			(island_removal_mode 0)
		)
		(polygon
			(pts
				(xy 254.770382 -146.375882) (xy 254.770382 -148.179282) (xy 255.329182 -148.179282) (xy 255.329182 -146.375882)
			)
		)
	)
	(zone
		(layer "In1.Cu")
		(hatch none 0.5)
		(connect_pads
			(clearance 0)
		)
		(min_thickness 0.25)
		(keepout
			(tracks not_allowed)
			(vias allowed)
			(pads allowed)
			(copperpour not_allowed)
			(footprints allowed)
		)
		(placement
			(enabled no)
			(sheetname "")
		)
		(fill
			(thermal_gap 0.5)
			(thermal_bridge_width 0.5)
			(island_removal_mode 0)
		)
		(polygon
			(pts
				(xy 312.570368 -19.121882) (xy 312.570368 -20.925282) (xy 313.129168 -20.925282) (xy 313.129168 -19.121882)
			)
		)
	)
	(zone
		(layer "In1.Cu")
		(hatch none 0.5)
		(connect_pads
			(clearance 0)
		)
		(min_thickness 0.25)
		(keepout
			(tracks not_allowed)
			(vias allowed)
			(pads allowed)
			(copperpour not_allowed)
			(footprints allowed)
		)
		(placement
			(enabled no)
			(sheetname "")
		)
		(fill
			(thermal_gap 0.5)
			(thermal_bridge_width 0.5)
			(island_removal_mode 0)
		)
		(polygon
			(pts
				(xy 276.02053 -136.774682) (xy 276.02053 -138.578082) (xy 276.57933 -138.578082) (xy 276.57933 -136.774682)
			)
		)
	)
	(zone
		(layer "In1.Cu")
		(hatch none 0.5)
		(connect_pads
			(clearance 0)
		)
		(min_thickness 0.25)
		(keepout
			(tracks not_allowed)
			(vias allowed)
			(pads allowed)
			(copperpour not_allowed)
			(footprints allowed)
		)
		(placement
			(enabled no)
			(sheetname "")
		)
		(fill
			(thermal_gap 0.5)
			(thermal_bridge_width 0.5)
			(island_removal_mode 0)
		)
		(polygon
			(pts
				(xy 235.22051 -151.377142) (xy 235.22051 -153.180542) (xy 235.77931 -153.180542) (xy 235.77931 -151.377142)
			)
		)
	)
	(zone
		(layer "In1.Cu")
		(hatch none 0.5)
		(connect_pads
			(clearance 0)
		)
		(min_thickness 0.25)
		(keepout
			(tracks not_allowed)
			(vias allowed)
			(pads allowed)
			(copperpour not_allowed)
			(footprints allowed)
		)
		(placement
			(enabled no)
			(sheetname "")
		)
		(fill
			(thermal_gap 0.5)
			(thermal_bridge_width 0.5)
			(island_removal_mode 0)
		)
		(polygon
			(pts
				(xy 230.120444 -4.920742) (xy 230.120444 -6.724142) (xy 230.679244 -6.724142) (xy 230.679244 -4.920742)
			)
		)
	)
	(zone
		(layer "In1.Cu")
		(hatch none 0.5)
		(connect_pads
			(clearance 0)
		)
		(min_thickness 0.25)
		(keepout
			(tracks not_allowed)
			(vias allowed)
			(pads allowed)
			(copperpour not_allowed)
			(footprints allowed)
		)
		(placement
			(enabled no)
			(sheetname "")
		)
		(fill
			(thermal_gap 0.5)
			(thermal_bridge_width 0.5)
			(island_removal_mode 0)
		)
		(polygon
			(pts
				(xy 102.519988 -132.174742) (xy 102.519988 -133.978142) (xy 103.078788 -133.978142) (xy 103.078788 -132.174742)
			)
		)
	)
	(zone
		(layer "In1.Cu")
		(hatch none 0.5)
		(connect_pads
			(clearance 0)
		)
		(min_thickness 0.25)
		(keepout
			(tracks not_allowed)
			(vias allowed)
			(pads allowed)
			(copperpour not_allowed)
			(footprints allowed)
		)
		(placement
			(enabled no)
			(sheetname "")
		)
		(fill
			(thermal_gap 0.5)
			(thermal_bridge_width 0.5)
			(island_removal_mode 0)
		)
		(polygon
			(pts
				(xy 272.620486 -132.174742) (xy 272.620486 -133.978142) (xy 273.179286 -133.978142) (xy 273.179286 -132.174742)
			)
		)
	)
	(zone
		(layer "In1.Cu")
		(hatch none 0.5)
		(connect_pads
			(clearance 0)
		)
		(min_thickness 0.25)
		(keepout
			(tracks not_allowed)
			(vias allowed)
			(pads allowed)
			(copperpour not_allowed)
			(footprints allowed)
		)
		(placement
			(enabled no)
			(sheetname "")
		)
		(fill
			(thermal_gap 0.5)
			(thermal_bridge_width 0.5)
			(island_removal_mode 0)
		)
		(polygon
			(pts
				(xy 365.235744 -9.773158) (xy 365.743744 -9.773158) (xy 365.743744 -11.170158) (xy 365.235744 -11.170158)
			)
		)
	)
	(zone
		(layer "In1.Cu")
		(hatch none 0.5)
		(connect_pads
			(clearance 0)
		)
		(min_thickness 0.25)
		(keepout
			(tracks not_allowed)
			(vias allowed)
			(pads allowed)
			(copperpour not_allowed)
			(footprints allowed)
		)
		(placement
			(enabled no)
			(sheetname "")
		)
		(fill
			(thermal_gap 0.5)
			(thermal_bridge_width 0.5)
			(island_removal_mode 0)
		)
		(polygon
			(pts
				(xy 276.02053 4.680458) (xy 276.02053 2.877058) (xy 276.57933 2.877058) (xy 276.57933 4.680458)
			)
		)
	)
	(zone
		(layer "In1.Cu")
		(hatch none 0.5)
		(connect_pads
			(clearance 0)
		)
		(min_thickness 0.25)
		(keepout
			(tracks not_allowed)
			(vias allowed)
			(pads allowed)
			(copperpour not_allowed)
			(footprints allowed)
		)
		(placement
			(enabled no)
			(sheetname "")
		)
		(fill
			(thermal_gap 0.5)
			(thermal_bridge_width 0.5)
			(island_removal_mode 0)
		)
		(polygon
			(pts
				(xy 280.270458 -9.520682) (xy 280.270458 -11.324082) (xy 280.829258 -11.324082) (xy 280.829258 -9.520682)
			)
		)
	)
	(zone
		(layer "In1.Cu")
		(hatch none 0.5)
		(connect_pads
			(clearance 0)
		)
		(min_thickness 0.25)
		(keepout
			(tracks not_allowed)
			(vias allowed)
			(pads allowed)
			(copperpour not_allowed)
			(footprints allowed)
		)
		(placement
			(enabled no)
			(sheetname "")
		)
		(fill
			(thermal_gap 0.5)
			(thermal_bridge_width 0.5)
			(island_removal_mode 0)
		)
		(polygon
			(pts
				(xy 237.770416 -155.977082) (xy 237.770416 -157.780482) (xy 238.329216 -157.780482) (xy 238.329216 -155.977082)
			)
		)
	)
	(zone
		(layer "In1.Cu")
		(hatch none 0.5)
		(connect_pads
			(clearance 0)
		)
		(min_thickness 0.25)
		(keepout
			(tracks not_allowed)
			(vias allowed)
			(pads allowed)
			(copperpour not_allowed)
			(footprints allowed)
		)
		(placement
			(enabled no)
			(sheetname "")
		)
		(fill
			(thermal_gap 0.5)
			(thermal_bridge_width 0.5)
			(island_removal_mode 0)
		)
		(polygon
			(pts
				(xy 63.41999 -151.377142) (xy 63.41999 -153.180542) (xy 63.97879 -153.180542) (xy 63.97879 -151.377142)
			)
		)
	)
	(zone
		(layer "In1.Cu")
		(hatch none 0.5)
		(connect_pads
			(clearance 0)
		)
		(min_thickness 0.25)
		(keepout
			(tracks not_allowed)
			(vias allowed)
			(pads allowed)
			(copperpour not_allowed)
			(footprints allowed)
		)
		(placement
			(enabled no)
			(sheetname "")
		)
		(fill
			(thermal_gap 0.5)
			(thermal_bridge_width 0.5)
			(island_removal_mode 0)
		)
		(polygon
			(pts
				(xy 276.02053 -151.377142) (xy 276.02053 -153.180542) (xy 276.57933 -153.180542) (xy 276.57933 -151.377142)
			)
		)
	)
	(zone
		(layer "In1.Cu")
		(hatch none 0.5)
		(connect_pads
			(clearance 0)
		)
		(min_thickness 0.25)
		(keepout
			(tracks not_allowed)
			(vias allowed)
			(pads allowed)
			(copperpour not_allowed)
			(footprints allowed)
		)
		(placement
			(enabled no)
			(sheetname "")
		)
		(fill
			(thermal_gap 0.5)
			(thermal_bridge_width 0.5)
			(island_removal_mode 0)
		)
		(polygon
			(pts
				(xy 196.970396 -146.375882) (xy 196.970396 -148.179282) (xy 197.529196 -148.179282) (xy 197.529196 -146.375882)
			)
		)
	)
	(zone
		(layer "In1.Cu")
		(hatch none 0.5)
		(connect_pads
			(clearance 0)
		)
		(min_thickness 0.25)
		(keepout
			(tracks not_allowed)
			(vias allowed)
			(pads allowed)
			(copperpour not_allowed)
			(footprints allowed)
		)
		(placement
			(enabled no)
			(sheetname "")
		)
		(fill
			(thermal_gap 0.5)
			(thermal_bridge_width 0.5)
			(island_removal_mode 0)
		)
		(polygon
			(pts
				(xy 71.9201 -151.377142) (xy 71.9201 -153.180542) (xy 72.4789 -153.180542) (xy 72.4789 -151.377142)
			)
		)
	)
	(zone
		(layer "In1.Cu")
		(hatch none 0.5)
		(connect_pads
			(clearance 0)
		)
		(min_thickness 0.25)
		(keepout
			(tracks not_allowed)
			(vias allowed)
			(pads allowed)
			(copperpour not_allowed)
			(footprints allowed)
		)
		(placement
			(enabled no)
			(sheetname "")
		)
		(fill
			(thermal_gap 0.5)
			(thermal_bridge_width 0.5)
			(island_removal_mode 0)
		)
		(polygon
			(pts
				(xy 32.820102 -4.920742) (xy 32.820102 -6.724142) (xy 33.378902 -6.724142) (xy 33.378902 -4.920742)
			)
		)
	)
	(zone
		(layer "In1.Cu")
		(hatch none 0.5)
		(connect_pads
			(clearance 0)
		)
		(min_thickness 0.25)
		(keepout
			(tracks not_allowed)
			(vias allowed)
			(pads allowed)
			(copperpour not_allowed)
			(footprints allowed)
		)
		(placement
			(enabled no)
			(sheetname "")
		)
		(fill
			(thermal_gap 0.5)
			(thermal_bridge_width 0.5)
			(island_removal_mode 0)
		)
		(polygon
			(pts
				(xy 280.270458 -146.375882) (xy 280.270458 -148.179282) (xy 280.829258 -148.179282) (xy 280.829258 -146.375882)
			)
		)
	)
	(zone
		(layer "In1.Cu")
		(hatch none 0.5)
		(connect_pads
			(clearance 0)
		)
		(min_thickness 0.25)
		(keepout
			(tracks not_allowed)
			(vias allowed)
			(pads allowed)
			(copperpour not_allowed)
			(footprints allowed)
		)
		(placement
			(enabled no)
			(sheetname "")
		)
		(fill
			(thermal_gap 0.5)
			(thermal_bridge_width 0.5)
			(island_removal_mode 0)
		)
		(polygon
			(pts
				(xy 247.12041 -151.377142) (xy 247.12041 -153.180542) (xy 247.67921 -153.180542) (xy 247.67921 -151.377142)
			)
		)
	)
	(zone
		(layer "In1.Cu")
		(hatch none 0.5)
		(connect_pads
			(clearance 0)
		)
		(min_thickness 0.25)
		(keepout
			(tracks not_allowed)
			(vias allowed)
			(pads allowed)
			(copperpour not_allowed)
			(footprints allowed)
		)
		(placement
			(enabled no)
			(sheetname "")
		)
		(fill
			(thermal_gap 0.5)
			(thermal_bridge_width 0.5)
			(island_removal_mode 0)
		)
		(polygon
			(pts
				(xy 128.020064 -14.521942) (xy 128.020064 -16.325342) (xy 128.578864 -16.325342) (xy 128.578864 -14.521942)
			)
		)
	)
	(zone
		(layer "In1.Cu")
		(hatch none 0.5)
		(connect_pads
			(clearance 0)
		)
		(min_thickness 0.25)
		(keepout
			(tracks not_allowed)
			(vias allowed)
			(pads allowed)
			(copperpour not_allowed)
			(footprints allowed)
		)
		(placement
			(enabled no)
			(sheetname "")
		)
		(fill
			(thermal_gap 0.5)
			(thermal_bridge_width 0.5)
			(island_removal_mode 0)
		)
		(polygon
			(pts
				(xy 293.020496 0.080518) (xy 293.020496 -1.722882) (xy 293.579296 -1.722882) (xy 293.579296 0.080518)
			)
		)
	)
	(zone
		(layer "In1.Cu")
		(hatch none 0.5)
		(connect_pads
			(clearance 0)
		)
		(min_thickness 0.25)
		(keepout
			(tracks not_allowed)
			(vias allowed)
			(pads allowed)
			(copperpour not_allowed)
			(footprints allowed)
		)
		(placement
			(enabled no)
			(sheetname "")
		)
		(fill
			(thermal_gap 0.5)
			(thermal_bridge_width 0.5)
			(island_removal_mode 0)
		)
		(polygon
			(pts
				(xy 233.520488 -141.775942) (xy 233.520488 -143.579342) (xy 234.079288 -143.579342) (xy 234.079288 -141.775942)
			)
		)
	)
	(zone
		(layer "In1.Cu")
		(hatch none 0.5)
		(connect_pads
			(clearance 0)
		)
		(min_thickness 0.25)
		(keepout
			(tracks not_allowed)
			(vias allowed)
			(pads allowed)
			(copperpour not_allowed)
			(footprints allowed)
		)
		(placement
			(enabled no)
			(sheetname "")
		)
		(fill
			(thermal_gap 0.5)
			(thermal_bridge_width 0.5)
			(island_removal_mode 0)
		)
		(polygon
			(pts
				(xy 125.469904 -132.174742) (xy 125.469904 -133.978142) (xy 126.028704 -133.978142) (xy 126.028704 -132.174742)
			)
		)
	)
	(zone
		(layer "In1.Cu")
		(hatch none 0.5)
		(connect_pads
			(clearance 0)
		)
		(min_thickness 0.25)
		(keepout
			(tracks not_allowed)
			(vias allowed)
			(pads allowed)
			(copperpour not_allowed)
			(footprints allowed)
		)
		(placement
			(enabled no)
			(sheetname "")
		)
		(fill
			(thermal_gap 0.5)
			(thermal_bridge_width 0.5)
			(island_removal_mode 0)
		)
		(polygon
			(pts
				(xy 277.720552 -14.521942) (xy 277.720552 -16.325342) (xy 278.279352 -16.325342) (xy 278.279352 -14.521942)
			)
		)
	)
	(zone
		(layer "In1.Cu")
		(hatch none 0.5)
		(connect_pads
			(clearance 0)
		)
		(min_thickness 0.25)
		(keepout
			(tracks not_allowed)
			(vias allowed)
			(pads allowed)
			(copperpour not_allowed)
			(footprints allowed)
		)
		(placement
			(enabled no)
			(sheetname "")
		)
		(fill
			(thermal_gap 0.5)
			(thermal_bridge_width 0.5)
			(island_removal_mode 0)
		)
		(polygon
			(pts
				(xy 202.070462 4.680458) (xy 202.070462 2.877058) (xy 202.629262 2.877058) (xy 202.629262 4.680458)
			)
		)
	)
	(zone
		(layer "In1.Cu")
		(hatch none 0.5)
		(connect_pads
			(clearance 0)
		)
		(min_thickness 0.25)
		(keepout
			(tracks not_allowed)
			(vias allowed)
			(pads allowed)
			(copperpour not_allowed)
			(footprints allowed)
		)
		(placement
			(enabled no)
			(sheetname "")
		)
		(fill
			(thermal_gap 0.5)
			(thermal_bridge_width 0.5)
			(island_removal_mode 0)
		)
		(polygon
			(pts
				(xy 136.51992 4.680458) (xy 136.51992 2.877058) (xy 137.07872 2.877058) (xy 137.07872 4.680458)
			)
		)
	)
	(zone
		(layer "In1.Cu")
		(hatch none 0.5)
		(connect_pads
			(clearance 0)
		)
		(min_thickness 0.25)
		(keepout
			(tracks not_allowed)
			(vias allowed)
			(pads allowed)
			(copperpour not_allowed)
			(footprints allowed)
		)
		(placement
			(enabled no)
			(sheetname "")
		)
		(fill
			(thermal_gap 0.5)
			(thermal_bridge_width 0.5)
			(island_removal_mode 0)
		)
		(polygon
			(pts
				(xy 243.720366 -9.520682) (xy 243.720366 -11.324082) (xy 244.279166 -11.324082) (xy 244.279166 -9.520682)
			)
		)
	)
	(zone
		(layer "In1.Cu")
		(hatch none 0.5)
		(connect_pads
			(clearance 0)
		)
		(min_thickness 0.25)
		(keepout
			(tracks not_allowed)
			(vias allowed)
			(pads allowed)
			(copperpour not_allowed)
			(footprints allowed)
		)
		(placement
			(enabled no)
			(sheetname "")
		)
		(fill
			(thermal_gap 0.5)
			(thermal_bridge_width 0.5)
			(island_removal_mode 0)
		)
		(polygon
			(pts
				(xy 257.320542 -4.920742) (xy 257.320542 -6.724142) (xy 257.879342 -6.724142) (xy 257.879342 -4.920742)
			)
		)
	)
	(zone
		(layer "In1.Cu")
		(hatch none 0.5)
		(connect_pads
			(clearance 0)
		)
		(min_thickness 0.25)
		(keepout
			(tracks not_allowed)
			(vias allowed)
			(pads allowed)
			(copperpour not_allowed)
			(footprints allowed)
		)
		(placement
			(enabled no)
			(sheetname "")
		)
		(fill
			(thermal_gap 0.5)
			(thermal_bridge_width 0.5)
			(island_removal_mode 0)
		)
		(polygon
			(pts
				(xy 199.520556 -132.174742) (xy 199.520556 -133.978142) (xy 200.079356 -133.978142) (xy 200.079356 -132.174742)
			)
		)
	)
	(zone
		(layer "In1.Cu")
		(hatch none 0.5)
		(connect_pads
			(clearance 0)
		)
		(min_thickness 0.25)
		(keepout
			(tracks not_allowed)
			(vias allowed)
			(pads allowed)
			(copperpour not_allowed)
			(footprints allowed)
		)
		(placement
			(enabled no)
			(sheetname "")
		)
		(fill
			(thermal_gap 0.5)
			(thermal_bridge_width 0.5)
			(island_removal_mode 0)
		)
		(polygon
			(pts
				(xy 128.869948 -136.774682) (xy 128.869948 -138.578082) (xy 129.428748 -138.578082) (xy 129.428748 -136.774682)
			)
		)
	)
	(zone
		(layer "In1.Cu")
		(hatch none 0.5)
		(connect_pads
			(clearance 0)
		)
		(min_thickness 0.25)
		(keepout
			(tracks not_allowed)
			(vias allowed)
			(pads allowed)
			(copperpour not_allowed)
			(footprints allowed)
		)
		(placement
			(enabled no)
			(sheetname "")
		)
		(fill
			(thermal_gap 0.5)
			(thermal_bridge_width 0.5)
			(island_removal_mode 0)
		)
		(polygon
			(pts
				(xy 65.97015 0.080518) (xy 65.97015 -1.722882) (xy 66.52895 -1.722882) (xy 66.52895 0.080518)
			)
		)
	)
	(zone
		(layer "In1.Cu")
		(hatch none 0.5)
		(connect_pads
			(clearance 0)
		)
		(min_thickness 0.25)
		(keepout
			(tracks not_allowed)
			(vias allowed)
			(pads allowed)
			(copperpour not_allowed)
			(footprints allowed)
		)
		(placement
			(enabled no)
			(sheetname "")
		)
		(fill
			(thermal_gap 0.5)
			(thermal_bridge_width 0.5)
			(island_removal_mode 0)
		)
		(polygon
			(pts
				(xy 135.670036 0.080518) (xy 135.670036 -1.722882) (xy 136.228836 -1.722882) (xy 136.228836 0.080518)
			)
		)
	)
	(zone
		(layer "In1.Cu")
		(hatch none 0.5)
		(connect_pads
			(clearance 0)
		)
		(min_thickness 0.25)
		(keepout
			(tracks not_allowed)
			(vias allowed)
			(pads allowed)
			(copperpour not_allowed)
			(footprints allowed)
		)
		(placement
			(enabled no)
			(sheetname "")
		)
		(fill
			(thermal_gap 0.5)
			(thermal_bridge_width 0.5)
			(island_removal_mode 0)
		)
		(polygon
			(pts
				(xy 116.970048 0.080518) (xy 116.970048 -1.722882) (xy 117.528848 -1.722882) (xy 117.528848 0.080518)
			)
		)
	)
	(zone
		(layer "In1.Cu")
		(hatch none 0.5)
		(connect_pads
			(clearance 0)
		)
		(min_thickness 0.25)
		(keepout
			(tracks not_allowed)
			(vias allowed)
			(pads allowed)
			(copperpour not_allowed)
			(footprints allowed)
		)
		(placement
			(enabled no)
			(sheetname "")
		)
		(fill
			(thermal_gap 0.5)
			(thermal_bridge_width 0.5)
			(island_removal_mode 0)
		)
		(polygon
			(pts
				(xy 48.120046 -141.775942) (xy 48.120046 -143.579342) (xy 48.678846 -143.579342) (xy 48.678846 -141.775942)
			)
		)
	)
	(zone
		(layer "In1.Cu")
		(hatch none 0.5)
		(connect_pads
			(clearance 0)
		)
		(min_thickness 0.25)
		(keepout
			(tracks not_allowed)
			(vias allowed)
			(pads allowed)
			(copperpour not_allowed)
			(footprints allowed)
		)
		(placement
			(enabled no)
			(sheetname "")
		)
		(fill
			(thermal_gap 0.5)
			(thermal_bridge_width 0.5)
			(island_removal_mode 0)
		)
		(polygon
			(pts
				(xy 87.220044 4.680458) (xy 87.220044 2.877058) (xy 87.778844 2.877058) (xy 87.778844 4.680458)
			)
		)
	)
	(zone
		(layer "In1.Cu")
		(hatch none 0.5)
		(connect_pads
			(clearance 0)
		)
		(min_thickness 0.25)
		(keepout
			(tracks not_allowed)
			(vias allowed)
			(pads allowed)
			(copperpour not_allowed)
			(footprints allowed)
		)
		(placement
			(enabled no)
			(sheetname "")
		)
		(fill
			(thermal_gap 0.5)
			(thermal_bridge_width 0.5)
			(island_removal_mode 0)
		)
		(polygon
			(pts
				(xy 33.669986 0.080518) (xy 33.669986 -1.722882) (xy 34.228786 -1.722882) (xy 34.228786 0.080518)
			)
		)
	)
	(zone
		(layer "In1.Cu")
		(hatch none 0.5)
		(connect_pads
			(clearance 0)
		)
		(min_thickness 0.25)
		(keepout
			(tracks not_allowed)
			(vias allowed)
			(pads allowed)
			(copperpour not_allowed)
			(footprints allowed)
		)
		(placement
			(enabled no)
			(sheetname "")
		)
		(fill
			(thermal_gap 0.5)
			(thermal_bridge_width 0.5)
			(island_removal_mode 0)
		)
		(polygon
			(pts
				(xy 127.169926 -132.174742) (xy 127.169926 -133.978142) (xy 127.728726 -133.978142) (xy 127.728726 -132.174742)
			)
		)
	)
	(zone
		(layer "In1.Cu")
		(hatch none 0.5)
		(connect_pads
			(clearance 0)
		)
		(min_thickness 0.25)
		(keepout
			(tracks not_allowed)
			(vias allowed)
			(pads allowed)
			(copperpour not_allowed)
			(footprints allowed)
		)
		(placement
			(enabled no)
			(sheetname "")
		)
		(fill
			(thermal_gap 0.5)
			(thermal_bridge_width 0.5)
			(island_removal_mode 0)
		)
		(polygon
			(pts
				(xy 121.219976 0.080518) (xy 121.219976 -1.722882) (xy 121.778776 -1.722882) (xy 121.778776 0.080518)
			)
		)
	)
	(zone
		(layer "In1.Cu")
		(hatch none 0.5)
		(connect_pads
			(clearance 0)
		)
		(min_thickness 0.25)
		(keepout
			(tracks not_allowed)
			(vias allowed)
			(pads allowed)
			(copperpour not_allowed)
			(footprints allowed)
		)
		(placement
			(enabled no)
			(sheetname "")
		)
		(fill
			(thermal_gap 0.5)
			(thermal_bridge_width 0.5)
			(island_removal_mode 0)
		)
		(polygon
			(pts
				(xy 37.07003 -151.377142) (xy 37.07003 -153.180542) (xy 37.62883 -153.180542) (xy 37.62883 -151.377142)
			)
		)
	)
	(zone
		(layer "In1.Cu")
		(hatch none 0.5)
		(connect_pads
			(clearance 0)
		)
		(min_thickness 0.25)
		(keepout
			(tracks not_allowed)
			(vias allowed)
			(pads allowed)
			(copperpour not_allowed)
			(footprints allowed)
		)
		(placement
			(enabled no)
			(sheetname "")
		)
		(fill
			(thermal_gap 0.5)
			(thermal_bridge_width 0.5)
			(island_removal_mode 0)
		)
		(polygon
			(pts
				(xy 149.269958 0.080518) (xy 149.269958 -1.722882) (xy 149.828758 -1.722882) (xy 149.828758 0.080518)
			)
		)
	)
	(zone
		(layer "In1.Cu")
		(hatch none 0.5)
		(connect_pads
			(clearance 0)
		)
		(min_thickness 0.25)
		(keepout
			(tracks not_allowed)
			(vias allowed)
			(pads allowed)
			(copperpour not_allowed)
			(footprints allowed)
		)
		(placement
			(enabled no)
			(sheetname "")
		)
		(fill
			(thermal_gap 0.5)
			(thermal_bridge_width 0.5)
			(island_removal_mode 0)
		)
		(polygon
			(pts
				(xy 307.470302 -132.174742) (xy 307.470302 -133.978142) (xy 308.029102 -133.978142) (xy 308.029102 -132.174742)
			)
		)
	)
	(zone
		(layer "In1.Cu")
		(hatch none 0.5)
		(connect_pads
			(clearance 0)
		)
		(min_thickness 0.25)
		(keepout
			(tracks not_allowed)
			(vias allowed)
			(pads allowed)
			(copperpour not_allowed)
			(footprints allowed)
		)
		(placement
			(enabled no)
			(sheetname "")
		)
		(fill
			(thermal_gap 0.5)
			(thermal_bridge_width 0.5)
			(island_removal_mode 0)
		)
		(polygon
			(pts
				(xy 270.07058 -151.377142) (xy 270.07058 -153.180542) (xy 270.62938 -153.180542) (xy 270.62938 -151.377142)
			)
		)
	)
	(zone
		(layer "In1.Cu")
		(hatch none 0.5)
		(connect_pads
			(clearance 0)
		)
		(min_thickness 0.25)
		(keepout
			(tracks not_allowed)
			(vias allowed)
			(pads allowed)
			(copperpour not_allowed)
			(footprints allowed)
		)
		(placement
			(enabled no)
			(sheetname "")
		)
		(fill
			(thermal_gap 0.5)
			(thermal_bridge_width 0.5)
			(island_removal_mode 0)
		)
		(polygon
			(pts
				(xy 320.02222 -120.27916) (xy 322.30822 -120.27916) (xy 322.30822 -120.78716) (xy 320.02222 -120.78716)
			)
		)
	)
	(zone
		(layer "In1.Cu")
		(hatch none 0.5)
		(connect_pads
			(clearance 0)
		)
		(min_thickness 0.25)
		(keepout
			(tracks not_allowed)
			(vias allowed)
			(pads allowed)
			(copperpour not_allowed)
			(footprints allowed)
		)
		(placement
			(enabled no)
			(sheetname "")
		)
		(fill
			(thermal_gap 0.5)
			(thermal_bridge_width 0.5)
			(island_removal_mode 0)
		)
		(polygon
			(pts
				(xy 47.270162 0.080518) (xy 47.270162 -1.722882) (xy 47.828962 -1.722882) (xy 47.828962 0.080518)
			)
		)
	)
	(zone
		(layer "In1.Cu")
		(hatch none 0.5)
		(connect_pads
			(clearance 0)
		)
		(min_thickness 0.25)
		(keepout
			(tracks not_allowed)
			(vias allowed)
			(pads allowed)
			(copperpour not_allowed)
			(footprints allowed)
		)
		(placement
			(enabled no)
			(sheetname "")
		)
		(fill
			(thermal_gap 0.5)
			(thermal_bridge_width 0.5)
			(island_removal_mode 0)
		)
		(polygon
			(pts
				(xy 197.820534 -4.920742) (xy 197.820534 -6.724142) (xy 198.379334 -6.724142) (xy 198.379334 -4.920742)
			)
		)
	)
	(zone
		(layer "In1.Cu")
		(hatch none 0.5)
		(connect_pads
			(clearance 0)
		)
		(min_thickness 0.25)
		(keepout
			(tracks not_allowed)
			(vias allowed)
			(pads allowed)
			(copperpour not_allowed)
			(footprints allowed)
		)
		(placement
			(enabled no)
			(sheetname "")
		)
		(fill
			(thermal_gap 0.5)
			(thermal_bridge_width 0.5)
			(island_removal_mode 0)
		)
		(polygon
			(pts
				(xy 265.820398 -4.920742) (xy 265.820398 -6.724142) (xy 266.379198 -6.724142) (xy 266.379198 -4.920742)
			)
		)
	)
	(zone
		(layer "In1.Cu")
		(hatch none 0.5)
		(connect_pads
			(clearance 0)
		)
		(min_thickness 0.25)
		(keepout
			(tracks not_allowed)
			(vias allowed)
			(pads allowed)
			(copperpour not_allowed)
			(footprints allowed)
		)
		(placement
			(enabled no)
			(sheetname "")
		)
		(fill
			(thermal_gap 0.5)
			(thermal_bridge_width 0.5)
			(island_removal_mode 0)
		)
		(polygon
			(pts
				(xy 293.87038 -155.977082) (xy 293.87038 -157.780482) (xy 294.42918 -157.780482) (xy 294.42918 -155.977082)
			)
		)
	)
	(zone
		(layer "In1.Cu")
		(hatch none 0.5)
		(connect_pads
			(clearance 0)
		)
		(min_thickness 0.25)
		(keepout
			(tracks not_allowed)
			(vias allowed)
			(pads allowed)
			(copperpour not_allowed)
			(footprints allowed)
		)
		(placement
			(enabled no)
			(sheetname "")
		)
		(fill
			(thermal_gap 0.5)
			(thermal_bridge_width 0.5)
			(island_removal_mode 0)
		)
		(polygon
			(pts
				(xy 445.086994 -46.478698) (xy 446.395094 -46.478698) (xy 446.395094 -48.485298) (xy 445.086994 -48.485298)
			)
		)
	)
	(zone
		(layer "In1.Cu")
		(hatch none 0.5)
		(connect_pads
			(clearance 0)
		)
		(min_thickness 0.25)
		(keepout
			(tracks not_allowed)
			(vias allowed)
			(pads allowed)
			(copperpour not_allowed)
			(footprints allowed)
		)
		(placement
			(enabled no)
			(sheetname "")
		)
		(fill
			(thermal_gap 0.5)
			(thermal_bridge_width 0.5)
			(island_removal_mode 0)
		)
		(polygon
			(pts
				(xy 137.370058 -155.977082) (xy 137.370058 -157.780482) (xy 137.928858 -157.780482) (xy 137.928858 -155.977082)
			)
		)
	)
	(zone
		(layer "In1.Cu")
		(hatch none 0.5)
		(connect_pads
			(clearance 0)
		)
		(min_thickness 0.25)
		(keepout
			(tracks not_allowed)
			(vias allowed)
			(pads allowed)
			(copperpour not_allowed)
			(footprints allowed)
		)
		(placement
			(enabled no)
			(sheetname "")
		)
		(fill
			(thermal_gap 0.5)
			(thermal_bridge_width 0.5)
			(island_removal_mode 0)
		)
		(polygon
			(pts
				(xy 146.720052 -151.377142) (xy 146.720052 -153.180542) (xy 147.278852 -153.180542) (xy 147.278852 -151.377142)
			)
		)
	)
	(zone
		(layer "In1.Cu")
		(hatch none 0.5)
		(connect_pads
			(clearance 0)
		)
		(min_thickness 0.25)
		(keepout
			(tracks not_allowed)
			(vias allowed)
			(pads allowed)
			(copperpour not_allowed)
			(footprints allowed)
		)
		(placement
			(enabled no)
			(sheetname "")
		)
		(fill
			(thermal_gap 0.5)
			(thermal_bridge_width 0.5)
			(island_removal_mode 0)
		)
		(polygon
			(pts
				(xy 37.07003 -14.521942) (xy 37.07003 -16.325342) (xy 37.62883 -16.325342) (xy 37.62883 -14.521942)
			)
		)
	)
	(zone
		(layer "In1.Cu")
		(hatch none 0.5)
		(connect_pads
			(clearance 0)
		)
		(min_thickness 0.25)
		(keepout
			(tracks not_allowed)
			(vias allowed)
			(pads allowed)
			(copperpour not_allowed)
			(footprints allowed)
		)
		(placement
			(enabled no)
			(sheetname "")
		)
		(fill
			(thermal_gap 0.5)
			(thermal_bridge_width 0.5)
			(island_removal_mode 0)
		)
		(polygon
			(pts
				(xy 38.770052 4.680458) (xy 38.770052 2.877058) (xy 39.328852 2.877058) (xy 39.328852 4.680458)
			)
		)
	)
	(zone
		(layer "In1.Cu")
		(hatch none 0.5)
		(connect_pads
			(clearance 0)
		)
		(min_thickness 0.25)
		(keepout
			(tracks not_allowed)
			(vias allowed)
			(pads allowed)
			(copperpour not_allowed)
			(footprints allowed)
		)
		(placement
			(enabled no)
			(sheetname "")
		)
		(fill
			(thermal_gap 0.5)
			(thermal_bridge_width 0.5)
			(island_removal_mode 0)
		)
		(polygon
			(pts
				(xy 215.670384 -9.520682) (xy 215.670384 -11.324082) (xy 216.229184 -11.324082) (xy 216.229184 -9.520682)
			)
		)
	)
	(zone
		(layer "In1.Cu")
		(hatch none 0.5)
		(connect_pads
			(clearance 0)
		)
		(min_thickness 0.25)
		(keepout
			(tracks not_allowed)
			(vias allowed)
			(pads allowed)
			(copperpour not_allowed)
			(footprints allowed)
		)
		(placement
			(enabled no)
			(sheetname "")
		)
		(fill
			(thermal_gap 0.5)
			(thermal_bridge_width 0.5)
			(island_removal_mode 0)
		)
		(polygon
			(pts
				(xy 45.57014 -9.520682) (xy 45.57014 -11.324082) (xy 46.12894 -11.324082) (xy 46.12894 -9.520682)
			)
		)
	)
	(zone
		(layer "In1.Cu")
		(hatch none 0.5)
		(connect_pads
			(clearance 0)
		)
		(min_thickness 0.25)
		(keepout
			(tracks not_allowed)
			(vias allowed)
			(pads allowed)
			(copperpour not_allowed)
			(footprints allowed)
		)
		(placement
			(enabled no)
			(sheetname "")
		)
		(fill
			(thermal_gap 0.5)
			(thermal_bridge_width 0.5)
			(island_removal_mode 0)
		)
		(polygon
			(pts
				(xy 441.146946 -115.799362) (xy 442.454792 -115.799362) (xy 442.454792 -118.186962) (xy 441.146946 -118.186962)
			)
		)
	)
	(zone
		(layer "In1.Cu")
		(hatch none 0.5)
		(connect_pads
			(clearance 0)
		)
		(min_thickness 0.25)
		(keepout
			(tracks not_allowed)
			(vias allowed)
			(pads allowed)
			(copperpour not_allowed)
			(footprints allowed)
		)
		(placement
			(enabled no)
			(sheetname "")
		)
		(fill
			(thermal_gap 0.5)
			(thermal_bridge_width 0.5)
			(island_removal_mode 0)
		)
		(polygon
			(pts
				(xy 82.970116 -19.121882) (xy 82.970116 -20.925282) (xy 83.528916 -20.925282) (xy 83.528916 -19.121882)
			)
		)
	)
	(zone
		(layer "In1.Cu")
		(hatch none 0.5)
		(connect_pads
			(clearance 0)
		)
		(min_thickness 0.25)
		(keepout
			(tracks not_allowed)
			(vias allowed)
			(pads allowed)
			(copperpour not_allowed)
			(footprints allowed)
		)
		(placement
			(enabled no)
			(sheetname "")
		)
		(fill
			(thermal_gap 0.5)
			(thermal_bridge_width 0.5)
			(island_removal_mode 0)
		)
		(polygon
			(pts
				(xy 223.320356 -146.375882) (xy 223.320356 -148.179282) (xy 223.879156 -148.179282) (xy 223.879156 -146.375882)
			)
		)
	)
	(zone
		(layer "In1.Cu")
		(hatch none 0.5)
		(connect_pads
			(clearance 0)
		)
		(min_thickness 0.25)
		(keepout
			(tracks not_allowed)
			(vias allowed)
			(pads allowed)
			(copperpour not_allowed)
			(footprints allowed)
		)
		(placement
			(enabled no)
			(sheetname "")
		)
		(fill
			(thermal_gap 0.5)
			(thermal_bridge_width 0.5)
			(island_removal_mode 0)
		)
		(polygon
			(pts
				(xy 145.02003 -19.121882) (xy 145.02003 -20.925282) (xy 145.57883 -20.925282) (xy 145.57883 -19.121882)
			)
		)
	)
	(zone
		(net "PVDDQ_DEF")
		(layer "In1.Cu")
		(hatch none 0.5)
		(connect_pads
			(clearance 0.5)
		)
		(min_thickness 0.25)
		(fill yes
			(thermal_gap 0.5)
			(thermal_bridge_width 0.5)
			(island_removal_mode 0)
		)
		(polygon
			(pts
				(xy 252.5395 -88.6333) (xy 252.246384 -88.926416)
				(arc
					(start 252.242574 -88.933782)
					(mid 252.175533 -89.027015)
					(end 252.0823 -89.094056)
				)
				(xy 252.074934 -89.097866) (xy 251.9299 -89.2429) (xy 251.9299 -89.5858) (xy 251.43206 -90.08364)
				(xy 251.43206 -90.480388) (xy 251.1552 -90.757248) (xy 251.1552 -90.905584)
				(arc
					(start 251.188474 -90.917776)
					(mid 251.421526 -91.25204)
					(end 251.188474 -91.586304)
				)
				(xy 251.1552 -91.598496) (xy 251.1552 -91.896184)
				(arc
					(start 251.188474 -91.908376)
					(mid 251.421526 -92.24264)
					(end 251.188474 -92.576904)
				)
				(xy 251.1552 -92.589096) (xy 251.1552 -93.87713)
				(arc
					(start 251.188474 -93.889322)
					(mid 251.420366 -94.25231)
					(end 251.133102 -94.57309)
				)
				(xy 251.117862 -94.576138) (xy 250.952 -94.742) (xy 250.952 -94.863158) (xy 251.00661 -94.863158)
				(arc
					(start 251.010674 -94.86265)
					(mid 251.420555 -95.191612)
					(end 251.05614 -95.570548)
				)
				(arc
					(start 251.05614 -95.570548)
					(mid 250.98273 -95.599302)
					(end 250.952 -95.671894)
				)
				(arc
					(start 250.952 -95.747586)
					(mid 250.982752 -95.820155)
					(end 251.05614 -95.848932)
				)
				(arc
					(start 251.05614 -95.848932)
					(mid 251.421509 -96.20504)
					(end 251.05614 -96.561148)
				)
				(arc
					(start 251.05614 -96.561148)
					(mid 250.98273 -96.589902)
					(end 250.952 -96.662494)
				)
				(xy 250.952 -96.7613) (xy 251.2314 -97.0407) (xy 251.2314 -97.409) (xy 251.3584 -97.536) (xy 251.3584 -99.9998)
				(xy 251.1806 -100.1776) (xy 251.171964 -100.1776) (xy 251.171964 -101.327204) (xy 251.116084 -101.383084)
				(xy 251.116084 -105.372916) (xy 250.854972 -105.634028) (xy 250.854972 -107.188) (xy 250.317 -107.725972)
				(xy 250.317 -113.665) (xy 246.623586 -117.358414) (xy 246.623586 -123.687586) (xy 243.489988 -126.821184)
				(xy 243.489988 -129.159) (xy 242.824 -129.824988)
				(arc
					(start 242.824 -129.953512)
					(mid 242.89057 -130.048882)
					(end 243.00307 -130.019298)
				)
				(arc
					(start 243.00307 -130.019298)
					(mid 243.630686 -130.249676)
					(end 243.00307 -130.480054)
				)
				(arc
					(start 243.00307 -130.480054)
					(mid 242.890558 -130.450438)
					(end 242.824 -130.54584)
				)
				(arc
					(start 242.824 -131.187444)
					(mid 242.874278 -131.275129)
					(end 242.975384 -131.27609)
				)
				(arc
					(start 242.975384 -131.27609)
					(mid 243.505958 -131.586478)
					(end 242.975384 -131.896866)
				)
				(arc
					(start 242.975384 -131.896866)
					(mid 242.874243 -131.897768)
					(end 242.824 -131.985512)
				)
				(xy 242.824 -132.174488) (xy 243.429536 -132.174488)
				(arc
					(start 243.429536 -134.020814)
					(mid 243.372535 -134.662606)
					(end 242.99926 -134.1374)
				)
				(arc
					(start 242.99926 -134.1374)
					(mid 243.008098 -134.038338)
					(end 242.92814 -133.979158)
				)
				(xy 242.86337 -133.979158) (xy 242.809522 -134.033006) (xy 242.809522 -134.107428) (xy 242.809522 -141.76121)
				(xy 242.824 -141.775688) (xy 243.429536 -141.775688) (xy 243.429536 -143.579596) (xy 243.404644 -143.579596)
				(xy 243.404644 -143.656812)
				(arc
					(start 243.426234 -143.672052)
					(mid 243.494839 -144.168668)
					(end 242.994688 -144.204436)
				)
				(arc
					(start 242.994688 -144.204436)
					(mid 242.885004 -144.185779)
					(end 242.824 -144.278858)
				)
				(arc
					(start 242.824 -144.667224)
					(mid 242.884075 -144.759951)
					(end 242.993164 -144.742916)
				)
				(arc
					(start 242.993164 -144.742916)
					(mid 243.586587 -145.0086)
					(end 242.993164 -145.274284)
				)
				(arc
					(start 242.993164 -145.274284)
					(mid 242.900499 -145.251728)
					(end 242.830096 -145.31594)
				)
				(xy 242.829588 -145.316702) (xy 242.813078 -145.346674) (xy 242.813078 -149.070314)
				(arc
					(start 242.82527 -149.082506)
					(mid 242.886763 -149.160009)
					(end 242.985036 -149.148292)
				)
				(arc
					(start 242.985036 -149.148292)
					(mid 243.468665 -149.20984)
					(end 243.437664 -149.696424)
				)
				(arc
					(start 243.437664 -149.696424)
					(mid 243.405752 -149.772047)
					(end 243.440204 -149.846538)
				)
				(arc
					(start 243.440204 -149.846538)
					(mid 243.56079 -150.130442)
					(end 243.41455 -150.402036)
				)
				(arc
					(start 243.41455 -150.402036)
					(mid 243.373042 -150.474612)
					(end 243.400072 -150.553674)
				)
				(arc
					(start 243.400072 -150.553674)
					(mid 243.418597 -151.002672)
					(end 242.976908 -151.08555)
				)
				(arc
					(start 242.976908 -151.08555)
					(mid 242.875095 -151.085085)
					(end 242.824 -151.17318)
				)
				(xy 242.824 -151.376888) (xy 243.429536 -151.376888) (xy 243.429536 -153.180796) (xy 242.855242 -153.180796)
				(xy 242.791488 -153.24455) (xy 242.791488 -157.079188) (xy 242.824 -157.1117) (xy 243.66855 -157.95625)
				(arc
					(start 266.251182 -157.95625)
					(mid 266.385222 -157.827901)
					(end 266.565634 -157.784546)
				)
				(arc
					(start 266.565634 -157.784546)
					(mid 266.639302 -157.755796)
					(end 266.670028 -157.682946)
				)
				(arc
					(start 266.670028 -155.874466)
					(mid 266.685003 -155.340037)
					(end 267.219684 -155.34513)
				)
				(arc
					(start 267.219684 -155.34513)
					(mid 267.331526 -155.607765)
					(end 267.229844 -155.874466)
				)
				(xy 267.229844 -157.780736)
				(arc
					(start 266.9286 -157.780736)
					(mid 266.842535 -157.837158)
					(end 266.84986 -157.93974)
				)
				(arc
					(start 266.84986 -157.93974)
					(mid 266.887803 -158.011932)
					(end 266.90828 -158.09087)
				)
				(xy 266.90828 -158.091124) (xy 266.91463 -158.134812) (xy 269.625826 -158.134812)
				(arc
					(start 269.632176 -158.091124)
					(mid 269.746424 -157.875953)
					(end 269.972282 -157.784546)
				)
				(arc
					(start 269.972282 -157.784546)
					(mid 270.041611 -157.75357)
					(end 270.070072 -157.6832)
				)
				(arc
					(start 270.070072 -155.874466)
					(mid 270.349367 -155.233313)
					(end 270.629888 -155.873958)
				)
				(xy 270.629888 -157.780736)
				(arc
					(start 270.3576 -157.780736)
					(mid 270.271535 -157.837158)
					(end 270.27886 -157.93974)
				)
				(arc
					(start 270.27886 -157.93974)
					(mid 270.316803 -158.011932)
					(end 270.33728 -158.09087)
				)
				(xy 270.33728 -158.091124) (xy 270.34363 -158.134812) (xy 273.181826 -158.134812) (xy 273.188176 -158.091124)
				(arc
					(start 273.188176 -158.09087)
					(mid 273.269225 -157.910112)
					(end 273.434302 -157.800548)
				)
				(xy 273.470116 -157.789372) (xy 273.470116 -155.976828) (xy 273.470116 -155.874974)
				(arc
					(start 273.458178 -155.86075)
					(mid 273.74977 -155.233461)
					(end 274.041362 -155.86075)
				)
				(xy 274.029424 -155.874974) (xy 274.029424 -155.976828) (xy 274.029424 -157.780736)
				(arc
					(start 273.9136 -157.780736)
					(mid 273.827535 -157.837158)
					(end 273.83486 -157.93974)
				)
				(arc
					(start 273.83486 -157.93974)
					(mid 273.872803 -158.011932)
					(end 273.89328 -158.09087)
				)
				(xy 273.89328 -158.091124) (xy 273.89963 -158.134812) (xy 277.886668 -158.134812)
				(arc
					(start 277.894288 -158.093156)
					(mid 277.917953 -158.013573)
					(end 277.958296 -157.94101)
				)
				(arc
					(start 277.958296 -157.94101)
					(mid 277.965537 -157.835567)
					(end 277.875238 -157.780736)
				)
				(xy 277.720044 -157.780736) (xy 277.720044 -155.976828) (xy 278.27986 -155.976828) (xy 278.27986 -157.777688)
				(arc
					(start 278.323294 -157.783784)
					(mid 278.368464 -157.793038)
					(end 278.412194 -157.80766)
				)
				(xy 278.443182 -157.820106) (xy 278.888952 -157.374336)
				(arc
					(start 278.888952 -156.095192)
					(mid 278.854944 -156.019591)
					(end 278.775922 -155.994354)
				)
				(arc
					(start 278.775922 -155.994354)
					(mid 278.351605 -155.615386)
					(end 278.775922 -155.236418)
				)
				(arc
					(start 278.775922 -155.236418)
					(mid 278.855034 -155.211283)
					(end 278.888952 -155.13558)
				)
				(arc
					(start 278.888952 -154.713178)
					(mid 278.854556 -154.636979)
					(end 278.774652 -154.61234)
				)
				(arc
					(start 278.774652 -154.61234)
					(mid 278.346011 -154.23388)
					(end 278.774652 -153.85542)
				)
				(arc
					(start 278.774652 -153.85542)
					(mid 278.854579 -153.830807)
					(end 278.888952 -153.754582)
				)
				(xy 278.888952 -150.463758)
				(arc
					(start 278.853392 -150.452328)
					(mid 278.620476 -150.245338)
					(end 278.619458 -149.93366)
				)
				(arc
					(start 278.619458 -149.93366)
					(mid 278.621483 -149.856268)
					(end 278.568404 -149.799802)
				)
				(arc
					(start 278.568404 -149.799802)
					(mid 278.358349 -149.347938)
					(end 278.774398 -149.07387)
				)
				(arc
					(start 278.774398 -149.07387)
					(mid 278.854505 -149.049364)
					(end 278.888952 -148.973032)
				)
				(arc
					(start 278.888952 -146.493992)
					(mid 278.854944 -146.418391)
					(end 278.775922 -146.393154)
				)
				(arc
					(start 278.775922 -146.393154)
					(mid 278.573232 -146.360502)
					(end 278.416766 -146.227546)
				)
				(arc
					(start 278.416766 -146.227546)
					(mid 278.339393 -146.183147)
					(end 278.256746 -146.216878)
				)
				(arc
					(start 278.256746 -146.216878)
					(mid 278.220526 -146.251997)
					(end 278.17953 -146.281394)
				)
				(xy 278.155146 -146.296126) (xy 278.155146 -146.375628) (xy 278.27986 -146.375628) (xy 278.27986 -148.179536)
				(xy 277.720044 -148.179536) (xy 277.720044 -146.375628) (xy 277.845774 -146.375628) (xy 277.845774 -146.296126)
				(arc
					(start 277.82139 -146.281394)
					(mid 277.744708 -145.758987)
					(end 278.27224 -145.778474)
				)
				(arc
					(start 278.27224 -145.778474)
					(mid 278.352401 -145.818105)
					(end 278.432768 -145.778982)
				)
				(arc
					(start 278.432768 -145.778982)
					(mid 278.585626 -145.662419)
					(end 278.775922 -145.635218)
				)
				(arc
					(start 278.775922 -145.635218)
					(mid 278.855034 -145.610083)
					(end 278.888952 -145.53438)
				)
				(arc
					(start 278.888952 -145.111978)
					(mid 278.854556 -145.035779)
					(end 278.774652 -145.01114)
				)
				(arc
					(start 278.774652 -145.01114)
					(mid 278.347661 -144.668128)
					(end 278.703786 -144.251934)
				)
				(arc
					(start 278.703786 -144.251934)
					(mid 278.781752 -144.227238)
					(end 278.863298 -144.220946)
				)
				(arc
					(start 278.863298 -144.220946)
					(mid 278.882359 -144.189526)
					(end 278.888952 -144.153382)
				)
				(xy 278.888952 -140.862558)
				(arc
					(start 278.853392 -140.851128)
					(mid 278.620476 -140.644138)
					(end 278.619458 -140.33246)
				)
				(arc
					(start 278.619458 -140.33246)
					(mid 278.621483 -140.255068)
					(end 278.568404 -140.198602)
				)
				(arc
					(start 278.568404 -140.198602)
					(mid 278.344535 -139.828203)
					(end 278.610822 -139.487148)
				)
				(arc
					(start 278.610822 -139.487148)
					(mid 278.710628 -139.373559)
					(end 278.848566 -139.311634)
				)
				(xy 278.888952 -139.303252)
				(arc
					(start 278.888952 -136.892792)
					(mid 278.854944 -136.817191)
					(end 278.775922 -136.791954)
				)
				(arc
					(start 278.775922 -136.791954)
					(mid 278.573232 -136.759302)
					(end 278.416766 -136.626346)
				)
				(arc
					(start 278.416766 -136.626346)
					(mid 278.339393 -136.581947)
					(end 278.256746 -136.615678)
				)
				(arc
					(start 278.256746 -136.615678)
					(mid 278.220526 -136.650797)
					(end 278.17953 -136.680194)
				)
				(xy 278.155146 -136.694926) (xy 278.155146 -136.774428) (xy 278.27986 -136.774428) (xy 278.27986 -138.578336)
				(xy 277.720044 -138.578336) (xy 277.720044 -136.774428) (xy 277.845774 -136.774428) (xy 277.845774 -136.694926)
				(arc
					(start 277.82139 -136.680194)
					(mid 277.744708 -136.157787)
					(end 278.27224 -136.177274)
				)
				(arc
					(start 278.27224 -136.177274)
					(mid 278.352401 -136.216905)
					(end 278.432768 -136.177782)
				)
				(arc
					(start 278.432768 -136.177782)
					(mid 278.552456 -136.077035)
					(end 278.702516 -136.032748)
				)
				(arc
					(start 278.702516 -136.032748)
					(mid 278.734494 -136.013505)
					(end 278.768302 -135.997696)
				)
				(arc
					(start 278.768302 -135.997696)
					(mid 278.799915 -135.952752)
					(end 278.772112 -135.90524)
				)
				(arc
					(start 278.772112 -135.90524)
					(mid 278.598399 -135.710041)
					(end 278.604726 -135.448802)
				)
				(arc
					(start 278.604726 -135.448802)
					(mid 278.605047 -135.409952)
					(end 278.577802 -135.382254)
				)
				(arc
					(start 278.577802 -135.382254)
					(mid 278.347853 -134.994573)
					(end 278.64816 -134.658354)
				)
				(arc
					(start 278.64816 -134.658354)
					(mid 278.739163 -134.594226)
					(end 278.845518 -134.561326)
				)
				(xy 278.888952 -134.554976) (xy 278.888952 -131.261358)
				(arc
					(start 278.853392 -131.249928)
					(mid 278.620476 -131.042938)
					(end 278.619458 -130.73126)
				)
				(arc
					(start 278.619458 -130.73126)
					(mid 278.621483 -130.653868)
					(end 278.568404 -130.597402)
				)
				(arc
					(start 278.568404 -130.597402)
					(mid 278.358349 -130.145538)
					(end 278.774398 -129.87147)
				)
				(arc
					(start 278.774398 -129.87147)
					(mid 278.854505 -129.846964)
					(end 278.888952 -129.770632)
				)
				(xy 278.888952 -128.674114) (xy 277.341584 -127.126746) (xy 277.177246 -126.962408) (xy 277.177246 -125.6919)
				(xy 271.3863 -119.900954) (xy 271.3863 -116.4844) (xy 271.0942 -116.1923) (xy 271.0942 -111.6965)
				(xy 271.3863 -111.4044) (xy 271.3863 -104.3305) (xy 271.2212 -104.1654) (xy 271.166844 -104.1654)
				(xy 270.722344 -103.7209) (xy 270.722344 -100.283772)
				(arc
					(start 269.83817 -99.399598)
					(mid 269.762049 -99.370102)
					(end 269.688818 -99.406202)
				)
				(arc
					(start 269.688818 -99.406202)
					(mid 269.164397 -99.428719)
					(end 269.186914 -98.904298)
				)
				(arc
					(start 269.186914 -98.904298)
					(mid 269.223036 -98.831068)
					(end 269.193518 -98.754946)
				)
				(xy 268.2875 -97.848928) (xy 268.2875 -91.2241) (xy 267.5509 -90.4875) (xy 267.3223 -90.4875) (xy 266.790678 -91.019122)
				(arc
					(start 266.814046 -91.053666)
					(mid 266.551213 -91.606752)
					(end 266.19073 -91.111832)
				)
				(arc
					(start 266.19073 -91.111832)
					(mid 266.182286 -91.0159)
					(end 266.097512 -90.9701)
				)
				(arc
					(start 265.944604 -90.9701)
					(mid 265.659616 -91.112645)
					(end 265.374628 -90.9701)
				)
				(arc
					(start 265.22172 -90.9701)
					(mid 265.136854 -91.01584)
					(end 265.128502 -91.111832)
				)
				(arc
					(start 265.128502 -91.111832)
					(mid 264.801096 -91.608204)
					(end 264.47369 -91.111832)
				)
				(arc
					(start 264.47369 -91.111832)
					(mid 264.465246 -91.0159)
					(end 264.380472 -90.9701)
				)
				(arc
					(start 264.227818 -90.9701)
					(mid 263.94283 -91.112645)
					(end 263.657842 -90.9701)
				)
				(arc
					(start 263.504934 -90.9701)
					(mid 263.420068 -91.01584)
					(end 263.411716 -91.111832)
				)
				(arc
					(start 263.411716 -91.111832)
					(mid 263.08431 -91.608204)
					(end 262.756904 -91.111832)
				)
				(arc
					(start 262.756904 -91.111832)
					(mid 262.74846 -91.0159)
					(end 262.663686 -90.9701)
				)
				(arc
					(start 262.510778 -90.9701)
					(mid 262.22579 -91.112645)
					(end 261.940802 -90.9701)
				)
				(arc
					(start 261.787894 -90.9701)
					(mid 261.703028 -91.01584)
					(end 261.694676 -91.111832)
				)
				(arc
					(start 261.694676 -91.111832)
					(mid 261.180273 -91.555165)
					(end 261.34568 -90.896694)
				)
				(arc
					(start 261.34568 -90.896694)
					(mid 261.434509 -90.831367)
					(end 261.411466 -90.723466)
				)
				(xy 261.299198 -90.611198)
				(arc
					(start 261.285228 -90.607896)
					(mid 261.115514 -90.513196)
					(end 261.020814 -90.343482)
				)
				(xy 261.017512 -90.329512) (xy 260.6929 -90.0049) (xy 260.6929 -89.3064) (xy 260.518402 -89.131902)
				(arc
					(start 260.498082 -89.13114)
					(mid 260.385084 -89.109217)
					(end 260.284976 -89.0524)
				)
				(arc
					(start 260.092698 -89.0524)
					(mid 260.012396 -89.092085)
					(end 259.994654 -89.179908)
				)
				(arc
					(start 259.994654 -89.179908)
					(mid 259.65023 -89.627065)
					(end 259.305806 -89.179908)
				)
				(arc
					(start 259.305806 -89.179908)
					(mid 259.288107 -89.092052)
					(end 259.207762 -89.0524)
				)
				(arc
					(start 259.015484 -89.0524)
					(mid 258.652647 -89.103201)
					(end 258.437126 -88.807036)
				)
				(xy 258.435348 -88.788748) (xy 258.2799 -88.6333) (xy 257.979672 -88.6333)
				(arc
					(start 257.976624 -88.633554)
					(mid 257.93319 -88.636214)
					(end 257.889756 -88.633554)
				)
				(xy 257.886708 -88.6333)
				(arc
					(start 257.5306 -88.6333)
					(mid 257.455677 -88.666277)
					(end 257.429508 -88.74379)
				)
				(arc
					(start 257.429508 -88.74379)
					(mid 257.07467 -89.131519)
					(end 256.719832 -88.74379)
				)
				(arc
					(start 256.719832 -88.74379)
					(mid 256.693576 -88.666356)
					(end 256.61874 -88.6333)
				)
				(xy 256.262632 -88.6333)
				(arc
					(start 256.259584 -88.633554)
					(mid 256.21615 -88.636214)
					(end 256.172716 -88.633554)
				)
				(xy 256.169668 -88.6333)
				(arc
					(start 255.81356 -88.6333)
					(mid 255.738637 -88.666277)
					(end 255.712468 -88.74379)
				)
				(arc
					(start 255.712468 -88.74379)
					(mid 255.35763 -89.131519)
					(end 255.002792 -88.74379)
				)
				(arc
					(start 255.002792 -88.74379)
					(mid 254.976536 -88.666356)
					(end 254.9017 -88.6333)
				)
				(xy 254.545592 -88.6333)
				(arc
					(start 254.542544 -88.633554)
					(mid 254.49911 -88.636214)
					(end 254.455676 -88.633554)
				)
				(xy 254.452628 -88.6333)
				(arc
					(start 254.096774 -88.6333)
					(mid 254.021851 -88.666277)
					(end 253.995682 -88.74379)
				)
				(arc
					(start 253.995682 -88.74379)
					(mid 253.640844 -89.131519)
					(end 253.286006 -88.74379)
				)
				(arc
					(start 253.286006 -88.74379)
					(mid 253.25975 -88.666356)
					(end 253.184914 -88.6333)
				)
				(xy 252.828806 -88.6333)
				(arc
					(start 252.825758 -88.633554)
					(mid 252.782324 -88.636214)
					(end 252.73889 -88.633554)
				)
				(xy 252.735842 -88.6333)
			)
		)
	)
	(zone
		(layer "In1.Cu")
		(hatch none 0.5)
		(connect_pads
			(clearance 0)
		)
		(min_thickness 0.25)
		(keepout
			(tracks not_allowed)
			(vias allowed)
			(pads allowed)
			(copperpour not_allowed)
			(footprints allowed)
		)
		(placement
			(enabled no)
			(sheetname "")
		)
		(fill
			(thermal_gap 0.5)
			(thermal_bridge_width 0.5)
			(island_removal_mode 0)
		)
		(polygon
			(pts
				(xy 142.46987 -151.377142) (xy 142.46987 -153.180542) (xy 143.02867 -153.180542) (xy 143.02867 -151.377142)
			)
		)
	)
	(zone
		(layer "In1.Cu")
		(hatch none 0.5)
		(connect_pads
			(clearance 0)
		)
		(min_thickness 0.25)
		(keepout
			(tracks not_allowed)
			(vias allowed)
			(pads allowed)
			(copperpour not_allowed)
			(footprints allowed)
		)
		(placement
			(enabled no)
			(sheetname "")
		)
		(fill
			(thermal_gap 0.5)
			(thermal_bridge_width 0.5)
			(island_removal_mode 0)
		)
		(polygon
			(pts
				(xy 460.346806 -115.799362) (xy 461.654906 -115.799362) (xy 461.654906 -118.186962) (xy 460.346806 -118.186962)
			)
		)
	)
	(zone
		(layer "In1.Cu")
		(hatch none 0.5)
		(connect_pads
			(clearance 0)
		)
		(min_thickness 0.25)
		(keepout
			(tracks not_allowed)
			(vias allowed)
			(pads allowed)
			(copperpour not_allowed)
			(footprints allowed)
		)
		(placement
			(enabled no)
			(sheetname "")
		)
		(fill
			(thermal_gap 0.5)
			(thermal_bridge_width 0.5)
			(island_removal_mode 0)
		)
		(polygon
			(pts
				(xy 71.9201 4.680458) (xy 71.9201 2.877058) (xy 72.4789 2.877058) (xy 72.4789 4.680458)
			)
		)
	)
	(zone
		(layer "In1.Cu")
		(hatch none 0.5)
		(connect_pads
			(clearance 0)
		)
		(min_thickness 0.25)
		(keepout
			(tracks not_allowed)
			(vias allowed)
			(pads allowed)
			(copperpour not_allowed)
			(footprints allowed)
		)
		(placement
			(enabled no)
			(sheetname "")
		)
		(fill
			(thermal_gap 0.5)
			(thermal_bridge_width 0.5)
			(island_removal_mode 0)
		)
		(polygon
			(pts
				(xy 230.970582 -146.375882) (xy 230.970582 -148.179282) (xy 231.529382 -148.179282) (xy 231.529382 -146.375882)
			)
		)
	)
	(zone
		(layer "In1.Cu")
		(hatch none 0.5)
		(connect_pads
			(clearance 0)
		)
		(min_thickness 0.25)
		(keepout
			(tracks not_allowed)
			(vias allowed)
			(pads allowed)
			(copperpour not_allowed)
			(footprints allowed)
		)
		(placement
			(enabled no)
			(sheetname "")
		)
		(fill
			(thermal_gap 0.5)
			(thermal_bridge_width 0.5)
			(island_removal_mode 0)
		)
		(polygon
			(pts
				(xy 214.8205 4.680458) (xy 214.8205 2.877058) (xy 215.3793 2.877058) (xy 215.3793 4.680458)
			)
		)
	)
	(zone
		(layer "In1.Cu")
		(hatch none 0.5)
		(connect_pads
			(clearance 0)
		)
		(min_thickness 0.25)
		(keepout
			(tracks not_allowed)
			(vias allowed)
			(pads allowed)
			(copperpour not_allowed)
			(footprints allowed)
		)
		(placement
			(enabled no)
			(sheetname "")
		)
		(fill
			(thermal_gap 0.5)
			(thermal_bridge_width 0.5)
			(island_removal_mode 0)
		)
		(polygon
			(pts
				(xy 244.570504 -4.920742) (xy 244.570504 -6.724142) (xy 245.129304 -6.724142) (xy 245.129304 -4.920742)
			)
		)
	)
	(zone
		(layer "In1.Cu")
		(hatch none 0.5)
		(connect_pads
			(clearance 0)
		)
		(min_thickness 0.25)
		(keepout
			(tracks not_allowed)
			(vias allowed)
			(pads allowed)
			(copperpour not_allowed)
			(footprints allowed)
		)
		(placement
			(enabled no)
			(sheetname "")
		)
		(fill
			(thermal_gap 0.5)
			(thermal_bridge_width 0.5)
			(island_removal_mode 0)
		)
		(polygon
			(pts
				(xy 231.820466 -132.174742) (xy 231.820466 -133.978142) (xy 232.379266 -133.978142) (xy 232.379266 -132.174742)
			)
		)
	)
	(zone
		(layer "In1.Cu")
		(hatch none 0.5)
		(connect_pads
			(clearance 0)
		)
		(min_thickness 0.25)
		(keepout
			(tracks not_allowed)
			(vias allowed)
			(pads allowed)
			(copperpour not_allowed)
			(footprints allowed)
		)
		(placement
			(enabled no)
			(sheetname "")
		)
		(fill
			(thermal_gap 0.5)
			(thermal_bridge_width 0.5)
			(island_removal_mode 0)
		)
		(polygon
			(pts
				(xy 119.519954 -146.375882) (xy 119.519954 -148.179282) (xy 120.078754 -148.179282) (xy 120.078754 -146.375882)
			)
		)
	)
	(zone
		(layer "In1.Cu")
		(hatch none 0.5)
		(connect_pads
			(clearance 0)
		)
		(min_thickness 0.25)
		(keepout
			(tracks not_allowed)
			(vias allowed)
			(pads allowed)
			(copperpour not_allowed)
			(footprints allowed)
		)
		(placement
			(enabled no)
			(sheetname "")
		)
		(fill
			(thermal_gap 0.5)
			(thermal_bridge_width 0.5)
			(island_removal_mode 0)
		)
		(polygon
			(pts
				(xy 65.97015 -146.375882) (xy 65.97015 -148.179282) (xy 66.52895 -148.179282) (xy 66.52895 -146.375882)
			)
		)
	)
	(zone
		(layer "In1.Cu")
		(hatch none 0.5)
		(connect_pads
			(clearance 0)
		)
		(min_thickness 0.25)
		(keepout
			(tracks not_allowed)
			(vias allowed)
			(pads allowed)
			(copperpour not_allowed)
			(footprints allowed)
		)
		(placement
			(enabled no)
			(sheetname "")
		)
		(fill
			(thermal_gap 0.5)
			(thermal_bridge_width 0.5)
			(island_removal_mode 0)
		)
		(polygon
			(pts
				(xy 54.920134 -155.977082) (xy 54.920134 -157.780482) (xy 55.478934 -157.780482) (xy 55.478934 -155.977082)
			)
		)
	)
	(zone
		(layer "In1.Cu")
		(hatch none 0.5)
		(connect_pads
			(clearance 0)
		)
		(min_thickness 0.25)
		(keepout
			(tracks not_allowed)
			(vias allowed)
			(pads allowed)
			(copperpour not_allowed)
			(footprints allowed)
		)
		(placement
			(enabled no)
			(sheetname "")
		)
		(fill
			(thermal_gap 0.5)
			(thermal_bridge_width 0.5)
			(island_removal_mode 0)
		)
		(polygon
			(pts
				(xy 124.62002 -136.774682) (xy 124.62002 -138.578082) (xy 125.17882 -138.578082) (xy 125.17882 -136.774682)
			)
		)
	)
	(zone
		(layer "In1.Cu")
		(hatch none 0.5)
		(connect_pads
			(clearance 0)
		)
		(min_thickness 0.25)
		(keepout
			(tracks not_allowed)
			(vias allowed)
			(pads allowed)
			(copperpour not_allowed)
			(footprints allowed)
		)
		(placement
			(enabled no)
			(sheetname "")
		)
		(fill
			(thermal_gap 0.5)
			(thermal_bridge_width 0.5)
			(island_removal_mode 0)
		)
		(polygon
			(pts
				(xy 248.820432 -151.377142) (xy 248.820432 -153.180542) (xy 249.379232 -153.180542) (xy 249.379232 -151.377142)
			)
		)
	)
	(zone
		(layer "In1.Cu")
		(hatch none 0.5)
		(connect_pads
			(clearance 0)
		)
		(min_thickness 0.25)
		(keepout
			(tracks not_allowed)
			(vias allowed)
			(pads allowed)
			(copperpour not_allowed)
			(footprints allowed)
		)
		(placement
			(enabled no)
			(sheetname "")
		)
		(fill
			(thermal_gap 0.5)
			(thermal_bridge_width 0.5)
			(island_removal_mode 0)
		)
		(polygon
			(pts
				(xy 86.37016 -151.377142) (xy 86.37016 -153.180542) (xy 86.92896 -153.180542) (xy 86.92896 -151.377142)
			)
		)
	)
	(zone
		(layer "In1.Cu")
		(hatch none 0.5)
		(connect_pads
			(clearance 0)
		)
		(min_thickness 0.25)
		(keepout
			(tracks not_allowed)
			(vias allowed)
			(pads allowed)
			(copperpour not_allowed)
			(footprints allowed)
		)
		(placement
			(enabled no)
			(sheetname "")
		)
		(fill
			(thermal_gap 0.5)
			(thermal_bridge_width 0.5)
			(island_removal_mode 0)
		)
		(polygon
			(pts
				(xy 301.520352 -151.377142) (xy 301.520352 -153.180542) (xy 302.079152 -153.180542) (xy 302.079152 -151.377142)
			)
		)
	)
	(zone
		(layer "In1.Cu")
		(hatch none 0.5)
		(connect_pads
			(clearance 0)
		)
		(min_thickness 0.25)
		(keepout
			(tracks not_allowed)
			(vias allowed)
			(pads allowed)
			(copperpour not_allowed)
			(footprints allowed)
		)
		(placement
			(enabled no)
			(sheetname "")
		)
		(fill
			(thermal_gap 0.5)
			(thermal_bridge_width 0.5)
			(island_removal_mode 0)
		)
		(polygon
			(pts
				(xy 99.970082 0.080518) (xy 99.970082 -1.722882) (xy 100.528882 -1.722882) (xy 100.528882 0.080518)
			)
		)
	)
	(zone
		(layer "In1.Cu")
		(hatch none 0.5)
		(connect_pads
			(clearance 0)
		)
		(min_thickness 0.25)
		(keepout
			(tracks not_allowed)
			(vias allowed)
			(pads allowed)
			(copperpour not_allowed)
			(footprints allowed)
		)
		(placement
			(enabled no)
			(sheetname "")
		)
		(fill
			(thermal_gap 0.5)
			(thermal_bridge_width 0.5)
			(island_removal_mode 0)
		)
		(polygon
			(pts
				(xy 209.720434 -136.774682) (xy 209.720434 -138.578082) (xy 210.279234 -138.578082) (xy 210.279234 -136.774682)
			)
		)
	)
	(zone
		(layer "In1.Cu")
		(hatch none 0.5)
		(connect_pads
			(clearance 0)
		)
		(min_thickness 0.25)
		(keepout
			(tracks not_allowed)
			(vias allowed)
			(pads allowed)
			(copperpour not_allowed)
			(footprints allowed)
		)
		(placement
			(enabled no)
			(sheetname "")
		)
		(fill
			(thermal_gap 0.5)
			(thermal_bridge_width 0.5)
			(island_removal_mode 0)
		)
		(polygon
			(pts
				(xy 37.920168 -19.121882) (xy 37.920168 -20.925282) (xy 38.478968 -20.925282) (xy 38.478968 -19.121882)
			)
		)
	)
	(zone
		(layer "In1.Cu")
		(hatch none 0.5)
		(connect_pads
			(clearance 0)
		)
		(min_thickness 0.25)
		(keepout
			(tracks not_allowed)
			(vias allowed)
			(pads allowed)
			(copperpour not_allowed)
			(footprints allowed)
		)
		(placement
			(enabled no)
			(sheetname "")
		)
		(fill
			(thermal_gap 0.5)
			(thermal_bridge_width 0.5)
			(island_removal_mode 0)
		)
		(polygon
			(pts
				(xy 238.620554 -155.977082) (xy 238.620554 -157.780482) (xy 239.179354 -157.780482) (xy 239.179354 -155.977082)
			)
		)
	)
	(zone
		(layer "In1.Cu")
		(hatch none 0.5)
		(connect_pads
			(clearance 0)
		)
		(min_thickness 0.25)
		(keepout
			(tracks not_allowed)
			(vias allowed)
			(pads allowed)
			(copperpour not_allowed)
			(footprints allowed)
		)
		(placement
			(enabled no)
			(sheetname "")
		)
		(fill
			(thermal_gap 0.5)
			(thermal_bridge_width 0.5)
			(island_removal_mode 0)
		)
		(polygon
			(pts
				(xy 101.670104 0.080518) (xy 101.670104 -1.722882) (xy 102.228904 -1.722882) (xy 102.228904 0.080518)
			)
		)
	)
	(zone
		(layer "In1.Cu")
		(hatch none 0.5)
		(connect_pads
			(clearance 0)
		)
		(min_thickness 0.25)
		(keepout
			(tracks not_allowed)
			(vias allowed)
			(pads allowed)
			(copperpour not_allowed)
			(footprints allowed)
		)
		(placement
			(enabled no)
			(sheetname "")
		)
		(fill
			(thermal_gap 0.5)
			(thermal_bridge_width 0.5)
			(island_removal_mode 0)
		)
		(polygon
			(pts
				(xy 363.631226 -3.792982) (xy 364.939072 -3.792982) (xy 364.939072 -4.986782) (xy 363.631226 -4.986782)
			)
		)
	)
	(zone
		(layer "In1.Cu")
		(hatch none 0.5)
		(connect_pads
			(clearance 0)
		)
		(min_thickness 0.25)
		(keepout
			(tracks not_allowed)
			(vias allowed)
			(pads allowed)
			(copperpour not_allowed)
			(footprints allowed)
		)
		(placement
			(enabled no)
			(sheetname "")
		)
		(fill
			(thermal_gap 0.5)
			(thermal_bridge_width 0.5)
			(island_removal_mode 0)
		)
		(polygon
			(pts
				(xy 232.67035 -146.375882) (xy 232.67035 -148.179282) (xy 233.22915 -148.179282) (xy 233.22915 -146.375882)
			)
		)
	)
	(zone
		(layer "In1.Cu")
		(hatch none 0.5)
		(connect_pads
			(clearance 0)
		)
		(min_thickness 0.25)
		(keepout
			(tracks not_allowed)
			(vias allowed)
			(pads allowed)
			(copperpour not_allowed)
			(footprints allowed)
		)
		(placement
			(enabled no)
			(sheetname "")
		)
		(fill
			(thermal_gap 0.5)
			(thermal_bridge_width 0.5)
			(island_removal_mode 0)
		)
		(polygon
			(pts
				(xy 226.7204 -136.774682) (xy 226.7204 -138.578082) (xy 227.2792 -138.578082) (xy 227.2792 -136.774682)
			)
		)
	)
	(zone
		(layer "In1.Cu")
		(hatch none 0.5)
		(connect_pads
			(clearance 0)
		)
		(min_thickness 0.25)
		(keepout
			(tracks not_allowed)
			(vias allowed)
			(pads allowed)
			(copperpour not_allowed)
			(footprints allowed)
		)
		(placement
			(enabled no)
			(sheetname "")
		)
		(fill
			(thermal_gap 0.5)
			(thermal_bridge_width 0.5)
			(island_removal_mode 0)
		)
		(polygon
			(pts
				(xy 89.76995 -155.977082) (xy 89.76995 -157.780482) (xy 90.32875 -157.780482) (xy 90.32875 -155.977082)
			)
		)
	)
	(zone
		(layer "In1.Cu")
		(hatch none 0.5)
		(connect_pads
			(clearance 0)
		)
		(min_thickness 0.25)
		(keepout
			(tracks not_allowed)
			(vias allowed)
			(pads allowed)
			(copperpour not_allowed)
			(footprints allowed)
		)
		(placement
			(enabled no)
			(sheetname "")
		)
		(fill
			(thermal_gap 0.5)
			(thermal_bridge_width 0.5)
			(island_removal_mode 0)
		)
		(polygon
			(pts
				(xy 121.219976 -155.977082) (xy 121.219976 -157.780482) (xy 121.778776 -157.780482) (xy 121.778776 -155.977082)
			)
		)
	)
	(zone
		(layer "In1.Cu")
		(hatch none 0.5)
		(connect_pads
			(clearance 0)
		)
		(min_thickness 0.25)
		(keepout
			(tracks not_allowed)
			(vias allowed)
			(pads allowed)
			(copperpour not_allowed)
			(footprints allowed)
		)
		(placement
			(enabled no)
			(sheetname "")
		)
		(fill
			(thermal_gap 0.5)
			(thermal_bridge_width 0.5)
			(island_removal_mode 0)
		)
		(polygon
			(pts
				(xy 404.217886 -3.789172) (xy 405.525986 -3.789172) (xy 405.525986 -4.982972) (xy 404.217886 -4.982972)
			)
		)
	)
	(zone
		(layer "In1.Cu")
		(hatch none 0.5)
		(connect_pads
			(clearance 0)
		)
		(min_thickness 0.25)
		(keepout
			(tracks not_allowed)
			(vias allowed)
			(pads allowed)
			(copperpour not_allowed)
			(footprints allowed)
		)
		(placement
			(enabled no)
			(sheetname "")
		)
		(fill
			(thermal_gap 0.5)
			(thermal_bridge_width 0.5)
			(island_removal_mode 0)
		)
		(polygon
			(pts
				(xy 241.170714 -132.174742) (xy 241.170714 -133.978142) (xy 241.729514 -133.978142) (xy 241.729514 -132.174742)
			)
		)
	)
	(zone
		(layer "In1.Cu")
		(hatch none 0.5)
		(connect_pads
			(clearance 0)
		)
		(min_thickness 0.25)
		(keepout
			(tracks not_allowed)
			(vias allowed)
			(pads allowed)
			(copperpour not_allowed)
			(footprints allowed)
		)
		(placement
			(enabled no)
			(sheetname "")
		)
		(fill
			(thermal_gap 0.5)
			(thermal_bridge_width 0.5)
			(island_removal_mode 0)
		)
		(polygon
			(pts
				(xy 205.470506 -4.920742) (xy 205.470506 -6.724142) (xy 206.029306 -6.724142) (xy 206.029306 -4.920742)
			)
		)
	)
	(zone
		(layer "In1.Cu")
		(hatch none 0.5)
		(connect_pads
			(clearance 0)
		)
		(min_thickness 0.25)
		(keepout
			(tracks not_allowed)
			(vias allowed)
			(pads allowed)
			(copperpour not_allowed)
			(footprints allowed)
		)
		(placement
			(enabled no)
			(sheetname "")
		)
		(fill
			(thermal_gap 0.5)
			(thermal_bridge_width 0.5)
			(island_removal_mode 0)
		)
		(polygon
			(pts
				(xy 66.820034 4.680458) (xy 66.820034 2.877058) (xy 67.378834 2.877058) (xy 67.378834 4.680458)
			)
		)
	)
	(zone
		(layer "In1.Cu")
		(hatch none 0.5)
		(connect_pads
			(clearance 0)
		)
		(min_thickness 0.25)
		(keepout
			(tracks not_allowed)
			(vias allowed)
			(pads allowed)
			(copperpour not_allowed)
			(footprints allowed)
		)
		(placement
			(enabled no)
			(sheetname "")
		)
		(fill
			(thermal_gap 0.5)
			(thermal_bridge_width 0.5)
			(island_removal_mode 0)
		)
		(polygon
			(pts
				(xy 216.520522 -4.920742) (xy 216.520522 -6.724142) (xy 217.079322 -6.724142) (xy 217.079322 -4.920742)
			)
		)
	)
	(zone
		(layer "In1.Cu")
		(hatch none 0.5)
		(connect_pads
			(clearance 0)
		)
		(min_thickness 0.25)
		(keepout
			(tracks not_allowed)
			(vias allowed)
			(pads allowed)
			(copperpour not_allowed)
			(footprints allowed)
		)
		(placement
			(enabled no)
			(sheetname "")
		)
		(fill
			(thermal_gap 0.5)
			(thermal_bridge_width 0.5)
			(island_removal_mode 0)
		)
		(polygon
			(pts
				(xy 121.219976 -146.375882) (xy 121.219976 -148.179282) (xy 121.778776 -148.179282) (xy 121.778776 -146.375882)
			)
		)
	)
	(zone
		(layer "In1.Cu")
		(hatch none 0.5)
		(connect_pads
			(clearance 0)
		)
		(min_thickness 0.25)
		(keepout
			(tracks not_allowed)
			(vias allowed)
			(pads allowed)
			(copperpour not_allowed)
			(footprints allowed)
		)
		(placement
			(enabled no)
			(sheetname "")
		)
		(fill
			(thermal_gap 0.5)
			(thermal_bridge_width 0.5)
			(island_removal_mode 0)
		)
		(polygon
			(pts
				(xy 133.970014 -155.977082) (xy 133.970014 -157.780482) (xy 134.528814 -157.780482) (xy 134.528814 -155.977082)
			)
		)
	)
	(zone
		(layer "In1.Cu")
		(hatch none 0.5)
		(connect_pads
			(clearance 0)
		)
		(min_thickness 0.25)
		(keepout
			(tracks not_allowed)
			(vias allowed)
			(pads allowed)
			(copperpour not_allowed)
			(footprints allowed)
		)
		(placement
			(enabled no)
			(sheetname "")
		)
		(fill
			(thermal_gap 0.5)
			(thermal_bridge_width 0.5)
			(island_removal_mode 0)
		)
		(polygon
			(pts
				(xy 407.418286 -7.192772) (xy 408.726386 -7.192772) (xy 408.726386 -8.386572) (xy 407.418286 -8.386572)
			)
		)
	)
	(zone
		(layer "In1.Cu")
		(hatch none 0.5)
		(connect_pads
			(clearance 0)
		)
		(min_thickness 0.25)
		(keepout
			(tracks not_allowed)
			(vias allowed)
			(pads allowed)
			(copperpour not_allowed)
			(footprints allowed)
		)
		(placement
			(enabled no)
			(sheetname "")
		)
		(fill
			(thermal_gap 0.5)
			(thermal_bridge_width 0.5)
			(island_removal_mode 0)
		)
		(polygon
			(pts
				(xy 135.670036 -155.977082) (xy 135.670036 -157.780482) (xy 136.228836 -157.780482) (xy 136.228836 -155.977082)
			)
		)
	)
	(zone
		(layer "In1.Cu")
		(hatch none 0.5)
		(connect_pads
			(clearance 0)
		)
		(min_thickness 0.25)
		(keepout
			(tracks not_allowed)
			(vias allowed)
			(pads allowed)
			(copperpour not_allowed)
			(footprints allowed)
		)
		(placement
			(enabled no)
			(sheetname "")
		)
		(fill
			(thermal_gap 0.5)
			(thermal_bridge_width 0.5)
			(island_removal_mode 0)
		)
		(polygon
			(pts
				(xy 128.869948 0.080518) (xy 128.869948 -1.722882) (xy 129.428748 -1.722882) (xy 129.428748 0.080518)
			)
		)
	)
	(zone
		(layer "In1.Cu")
		(hatch none 0.5)
		(connect_pads
			(clearance 0)
		)
		(min_thickness 0.25)
		(keepout
			(tracks not_allowed)
			(vias allowed)
			(pads allowed)
			(copperpour not_allowed)
			(footprints allowed)
		)
		(placement
			(enabled no)
			(sheetname "")
		)
		(fill
			(thermal_gap 0.5)
			(thermal_bridge_width 0.5)
			(island_removal_mode 0)
		)
		(polygon
			(pts
				(xy 276.02053 -155.977082) (xy 276.02053 -157.780482) (xy 276.57933 -157.780482) (xy 276.57933 -155.977082)
			)
		)
	)
	(zone
		(layer "In1.Cu")
		(hatch none 0.5)
		(connect_pads
			(clearance 0)
		)
		(min_thickness 0.25)
		(keepout
			(tracks not_allowed)
			(vias allowed)
			(pads allowed)
			(copperpour not_allowed)
			(footprints allowed)
		)
		(placement
			(enabled no)
			(sheetname "")
		)
		(fill
			(thermal_gap 0.5)
			(thermal_bridge_width 0.5)
			(island_removal_mode 0)
		)
		(polygon
			(pts
				(xy 219.920566 -136.774682) (xy 219.920566 -138.578082) (xy 220.479366 -138.578082) (xy 220.479366 -136.774682)
			)
		)
	)
	(zone
		(layer "In1.Cu")
		(hatch none 0.5)
		(connect_pads
			(clearance 0)
		)
		(min_thickness 0.25)
		(keepout
			(tracks not_allowed)
			(vias allowed)
			(pads allowed)
			(copperpour not_allowed)
			(footprints allowed)
		)
		(placement
			(enabled no)
			(sheetname "")
		)
		(fill
			(thermal_gap 0.5)
			(thermal_bridge_width 0.5)
			(island_removal_mode 0)
		)
		(polygon
			(pts
				(xy 142.46987 -132.174742) (xy 142.46987 -133.978142) (xy 143.02867 -133.978142) (xy 143.02867 -132.174742)
			)
		)
	)
	(zone
		(layer "In1.Cu")
		(hatch none 0.5)
		(connect_pads
			(clearance 0)
		)
		(min_thickness 0.25)
		(keepout
			(tracks not_allowed)
			(vias allowed)
			(pads allowed)
			(copperpour not_allowed)
			(footprints allowed)
		)
		(placement
			(enabled no)
			(sheetname "")
		)
		(fill
			(thermal_gap 0.5)
			(thermal_bridge_width 0.5)
			(island_removal_mode 0)
		)
		(polygon
			(pts
				(xy 302.37049 -151.377142) (xy 302.37049 -153.180542) (xy 302.92929 -153.180542) (xy 302.92929 -151.377142)
			)
		)
	)
	(zone
		(layer "In1.Cu")
		(hatch none 0.5)
		(connect_pads
			(clearance 0)
		)
		(min_thickness 0.25)
		(keepout
			(tracks not_allowed)
			(vias allowed)
			(pads allowed)
			(copperpour not_allowed)
			(footprints allowed)
		)
		(placement
			(enabled no)
			(sheetname "")
		)
		(fill
			(thermal_gap 0.5)
			(thermal_bridge_width 0.5)
			(island_removal_mode 0)
		)
		(polygon
			(pts
				(xy 105.070148 -9.520682) (xy 105.070148 -11.324082) (xy 105.628948 -11.324082) (xy 105.628948 -9.520682)
			)
		)
	)
	(zone
		(layer "In1.Cu")
		(hatch none 0.5)
		(connect_pads
			(clearance 0)
		)
		(min_thickness 0.25)
		(keepout
			(tracks not_allowed)
			(vias allowed)
			(pads allowed)
			(copperpour not_allowed)
			(footprints allowed)
		)
		(placement
			(enabled no)
			(sheetname "")
		)
		(fill
			(thermal_gap 0.5)
			(thermal_bridge_width 0.5)
			(island_removal_mode 0)
		)
		(polygon
			(pts
				(xy 150.120096 4.680458) (xy 150.120096 2.877058) (xy 150.678896 2.877058) (xy 150.678896 4.680458)
			)
		)
	)
	(zone
		(layer "In1.Cu")
		(hatch none 0.5)
		(connect_pads
			(clearance 0)
		)
		(min_thickness 0.25)
		(keepout
			(tracks not_allowed)
			(vias allowed)
			(pads allowed)
			(copperpour not_allowed)
			(footprints allowed)
		)
		(placement
			(enabled no)
			(sheetname "")
		)
		(fill
			(thermal_gap 0.5)
			(thermal_bridge_width 0.5)
			(island_removal_mode 0)
		)
		(polygon
			(pts
				(xy 249.67057 0.080518) (xy 249.67057 -1.722882) (xy 250.22937 -1.722882) (xy 250.22937 0.080518)
			)
		)
	)
	(zone
		(layer "In1.Cu")
		(hatch none 0.5)
		(connect_pads
			(clearance 0)
		)
		(min_thickness 0.25)
		(keepout
			(tracks not_allowed)
			(vias allowed)
			(pads allowed)
			(copperpour not_allowed)
			(footprints allowed)
		)
		(placement
			(enabled no)
			(sheetname "")
		)
		(fill
			(thermal_gap 0.5)
			(thermal_bridge_width 0.5)
			(island_removal_mode 0)
		)
		(polygon
			(pts
				(xy 43.870118 4.680458) (xy 43.870118 2.877058) (xy 44.428918 2.877058) (xy 44.428918 4.680458)
			)
		)
	)
	(zone
		(layer "In1.Cu")
		(hatch none 0.5)
		(connect_pads
			(clearance 0)
		)
		(min_thickness 0.25)
		(keepout
			(tracks not_allowed)
			(vias allowed)
			(pads allowed)
			(copperpour not_allowed)
			(footprints allowed)
		)
		(placement
			(enabled no)
			(sheetname "")
		)
		(fill
			(thermal_gap 0.5)
			(thermal_bridge_width 0.5)
			(island_removal_mode 0)
		)
		(polygon
			(pts
				(xy 44.720002 0.080518) (xy 44.720002 -1.722882) (xy 45.278802 -1.722882) (xy 45.278802 0.080518)
			)
		)
	)
	(zone
		(layer "In1.Cu")
		(hatch none 0.5)
		(connect_pads
			(clearance 0)
		)
		(min_thickness 0.25)
		(keepout
			(tracks not_allowed)
			(vias allowed)
			(pads allowed)
			(copperpour not_allowed)
			(footprints allowed)
		)
		(placement
			(enabled no)
			(sheetname "")
		)
		(fill
			(thermal_gap 0.5)
			(thermal_bridge_width 0.5)
			(island_removal_mode 0)
		)
		(polygon
			(pts
				(xy 232.67035 -155.977082) (xy 232.67035 -157.780482) (xy 233.22915 -157.780482) (xy 233.22915 -155.977082)
			)
		)
	)
	(zone
		(layer "In1.Cu")
		(hatch none 0.5)
		(connect_pads
			(clearance 0)
		)
		(min_thickness 0.25)
		(keepout
			(tracks not_allowed)
			(vias allowed)
			(pads allowed)
			(copperpour not_allowed)
			(footprints allowed)
		)
		(placement
			(enabled no)
			(sheetname "")
		)
		(fill
			(thermal_gap 0.5)
			(thermal_bridge_width 0.5)
			(island_removal_mode 0)
		)
		(polygon
			(pts
				(xy 117.819932 4.680458) (xy 117.819932 2.877058) (xy 118.378732 2.877058) (xy 118.378732 4.680458)
			)
		)
	)
	(zone
		(layer "In1.Cu")
		(hatch none 0.5)
		(connect_pads
			(clearance 0)
		)
		(min_thickness 0.25)
		(keepout
			(tracks not_allowed)
			(vias allowed)
			(pads allowed)
			(copperpour not_allowed)
			(footprints allowed)
		)
		(placement
			(enabled no)
			(sheetname "")
		)
		(fill
			(thermal_gap 0.5)
			(thermal_bridge_width 0.5)
			(island_removal_mode 0)
		)
		(polygon
			(pts
				(xy 267.52042 -14.521942) (xy 267.52042 -16.325342) (xy 268.07922 -16.325342) (xy 268.07922 -14.521942)
			)
		)
	)
	(zone
		(layer "In1.Cu")
		(hatch none 0.5)
		(connect_pads
			(clearance 0)
		)
		(min_thickness 0.25)
		(keepout
			(tracks not_allowed)
			(vias allowed)
			(pads allowed)
			(copperpour not_allowed)
			(footprints allowed)
		)
		(placement
			(enabled no)
			(sheetname "")
		)
		(fill
			(thermal_gap 0.5)
			(thermal_bridge_width 0.5)
			(island_removal_mode 0)
		)
		(polygon
			(pts
				(xy 314.27039 -19.121882) (xy 314.27039 -20.925282) (xy 314.82919 -20.925282) (xy 314.82919 -19.121882)
			)
		)
	)
	(zone
		(layer "In1.Cu")
		(hatch none 0.5)
		(connect_pads
			(clearance 0)
		)
		(min_thickness 0.25)
		(keepout
			(tracks not_allowed)
			(vias allowed)
			(pads allowed)
			(copperpour not_allowed)
			(footprints allowed)
		)
		(placement
			(enabled no)
			(sheetname "")
		)
		(fill
			(thermal_gap 0.5)
			(thermal_bridge_width 0.5)
			(island_removal_mode 0)
		)
		(polygon
			(pts
				(xy 250.520454 -19.121882) (xy 250.520454 -20.925282) (xy 251.079254 -20.925282) (xy 251.079254 -19.121882)
			)
		)
	)
	(zone
		(layer "In1.Cu")
		(hatch none 0.5)
		(connect_pads
			(clearance 0)
		)
		(min_thickness 0.25)
		(keepout
			(tracks not_allowed)
			(vias allowed)
			(pads allowed)
			(copperpour not_allowed)
			(footprints allowed)
		)
		(placement
			(enabled no)
			(sheetname "")
		)
		(fill
			(thermal_gap 0.5)
			(thermal_bridge_width 0.5)
			(island_removal_mode 0)
		)
		(polygon
			(pts
				(xy 109.320076 4.680458) (xy 109.320076 2.877058) (xy 109.878876 2.877058) (xy 109.878876 4.680458)
			)
		)
	)
	(zone
		(layer "In1.Cu")
		(hatch none 0.5)
		(connect_pads
			(clearance 0)
		)
		(min_thickness 0.25)
		(keepout
			(tracks not_allowed)
			(vias allowed)
			(pads allowed)
			(copperpour not_allowed)
			(footprints allowed)
		)
		(placement
			(enabled no)
			(sheetname "")
		)
		(fill
			(thermal_gap 0.5)
			(thermal_bridge_width 0.5)
			(island_removal_mode 0)
		)
		(polygon
			(pts
				(xy 374.913144 -9.773158) (xy 375.421144 -9.773158) (xy 375.421144 -11.170158) (xy 374.913144 -11.170158)
			)
		)
	)
	(zone
		(layer "In1.Cu")
		(hatch none 0.5)
		(connect_pads
			(clearance 0)
		)
		(min_thickness 0.25)
		(keepout
			(tracks not_allowed)
			(vias allowed)
			(pads allowed)
			(copperpour not_allowed)
			(footprints allowed)
		)
		(placement
			(enabled no)
			(sheetname "")
		)
		(fill
			(thermal_gap 0.5)
			(thermal_bridge_width 0.5)
			(island_removal_mode 0)
		)
		(polygon
			(pts
				(xy 111.020098 -151.377142) (xy 111.020098 -153.180542) (xy 111.578898 -153.180542) (xy 111.578898 -151.377142)
			)
		)
	)
	(zone
		(layer "In1.Cu")
		(hatch none 0.5)
		(connect_pads
			(clearance 0)
		)
		(min_thickness 0.25)
		(keepout
			(tracks not_allowed)
			(vias allowed)
			(pads allowed)
			(copperpour not_allowed)
			(footprints allowed)
		)
		(placement
			(enabled no)
			(sheetname "")
		)
		(fill
			(thermal_gap 0.5)
			(thermal_bridge_width 0.5)
			(island_removal_mode 0)
		)
		(polygon
			(pts
				(xy 43.870118 -14.521942) (xy 43.870118 -16.325342) (xy 44.428918 -16.325342) (xy 44.428918 -14.521942)
			)
		)
	)
	(zone
		(layer "In1.Cu")
		(hatch none 0.5)
		(connect_pads
			(clearance 0)
		)
		(min_thickness 0.25)
		(keepout
			(tracks not_allowed)
			(vias allowed)
			(pads allowed)
			(copperpour not_allowed)
			(footprints allowed)
		)
		(placement
			(enabled no)
			(sheetname "")
		)
		(fill
			(thermal_gap 0.5)
			(thermal_bridge_width 0.5)
			(island_removal_mode 0)
		)
		(polygon
			(pts
				(xy 112.72012 -19.121882) (xy 112.72012 -20.925282) (xy 113.27892 -20.925282) (xy 113.27892 -19.121882)
			)
		)
	)
	(zone
		(layer "In1.Cu")
		(hatch none 0.5)
		(connect_pads
			(clearance 0)
		)
		(min_thickness 0.25)
		(keepout
			(tracks not_allowed)
			(vias allowed)
			(pads allowed)
			(copperpour not_allowed)
			(footprints allowed)
		)
		(placement
			(enabled no)
			(sheetname "")
		)
		(fill
			(thermal_gap 0.5)
			(thermal_bridge_width 0.5)
			(island_removal_mode 0)
		)
		(polygon
			(pts
				(xy 246.270526 4.680458) (xy 246.270526 2.877058) (xy 246.829326 2.877058) (xy 246.829326 4.680458)
			)
		)
	)
	(zone
		(layer "In1.Cu")
		(hatch none 0.5)
		(connect_pads
			(clearance 0)
		)
		(min_thickness 0.25)
		(keepout
			(tracks not_allowed)
			(vias allowed)
			(pads allowed)
			(copperpour not_allowed)
			(footprints allowed)
		)
		(placement
			(enabled no)
			(sheetname "")
		)
		(fill
			(thermal_gap 0.5)
			(thermal_bridge_width 0.5)
			(island_removal_mode 0)
		)
		(polygon
			(pts
				(xy 38.770052 -141.775942) (xy 38.770052 -143.579342) (xy 39.328852 -143.579342) (xy 39.328852 -141.775942)
			)
		)
	)
	(zone
		(layer "In1.Cu")
		(hatch none 0.5)
		(connect_pads
			(clearance 0)
		)
		(min_thickness 0.25)
		(keepout
			(tracks not_allowed)
			(vias allowed)
			(pads allowed)
			(copperpour not_allowed)
			(footprints allowed)
		)
		(placement
			(enabled no)
			(sheetname "")
		)
		(fill
			(thermal_gap 0.5)
			(thermal_bridge_width 0.5)
			(island_removal_mode 0)
		)
		(polygon
			(pts
				(xy 59.170062 -14.521942) (xy 59.170062 -16.325342) (xy 59.728862 -16.325342) (xy 59.728862 -14.521942)
			)
		)
	)
	(zone
		(layer "In1.Cu")
		(hatch none 0.5)
		(connect_pads
			(clearance 0)
		)
		(min_thickness 0.25)
		(keepout
			(tracks not_allowed)
			(vias allowed)
			(pads allowed)
			(copperpour not_allowed)
			(footprints allowed)
		)
		(placement
			(enabled no)
			(sheetname "")
		)
		(fill
			(thermal_gap 0.5)
			(thermal_bridge_width 0.5)
			(island_removal_mode 0)
		)
		(polygon
			(pts
				(xy 52.369974 -136.774682) (xy 52.369974 -138.578082) (xy 52.928774 -138.578082) (xy 52.928774 -136.774682)
			)
		)
	)
	(zone
		(layer "In1.Cu")
		(hatch none 0.5)
		(connect_pads
			(clearance 0)
		)
		(min_thickness 0.25)
		(keepout
			(tracks not_allowed)
			(vias allowed)
			(pads allowed)
			(copperpour not_allowed)
			(footprints allowed)
		)
		(placement
			(enabled no)
			(sheetname "")
		)
		(fill
			(thermal_gap 0.5)
			(thermal_bridge_width 0.5)
			(island_removal_mode 0)
		)
		(polygon
			(pts
				(xy 216.520522 -141.775942) (xy 216.520522 -143.579342) (xy 217.079322 -143.579342) (xy 217.079322 -141.775942)
			)
		)
	)
	(zone
		(net "AGND_PVPP_DEF")
		(layer "In1.Cu")
		(hatch none 0.5)
		(connect_pads
			(clearance 0.5)
		)
		(min_thickness 0.25)
		(fill yes
			(thermal_gap 0.5)
			(thermal_bridge_width 0.5)
			(island_removal_mode 0)
		)
		(polygon
			(pts
				(xy 337.82 -126.8222) (xy 337.82 -128.502156) (xy 337.82 -129.057146) (xy 337.82 -129.516886) (xy 338.579714 -130.2766)
				(xy 339.677756 -130.2766) (xy 341.03056 -130.2766) (xy 341.516208 -129.790952) (xy 344.321892 -129.790952)
				(xy 344.932 -129.180844) (xy 344.932 -128.502156) (xy 344.551 -128.121156) (xy 344.551 -126.767844)
				(xy 344.351356 -126.5682) (xy 342.2904 -126.5682) (xy 341.7824 -127.0762) (xy 340.614 -127.0762)
				(xy 340.106 -126.5682) (xy 338.074 -126.5682)
			)
		)
	)
	(zone
		(layer "In1.Cu")
		(hatch none 0.5)
		(connect_pads
			(clearance 0)
		)
		(min_thickness 0.25)
		(keepout
			(tracks not_allowed)
			(vias allowed)
			(pads allowed)
			(copperpour not_allowed)
			(footprints allowed)
		)
		(placement
			(enabled no)
			(sheetname "")
		)
		(fill
			(thermal_gap 0.5)
			(thermal_bridge_width 0.5)
			(island_removal_mode 0)
		)
		(polygon
			(pts
				(xy 123.769882 -14.521942) (xy 123.769882 -16.325342) (xy 124.328682 -16.325342) (xy 124.328682 -14.521942)
			)
		)
	)
	(zone
		(layer "In1.Cu")
		(hatch none 0.5)
		(connect_pads
			(clearance 0)
		)
		(min_thickness 0.25)
		(keepout
			(tracks not_allowed)
			(vias allowed)
			(pads allowed)
			(copperpour not_allowed)
			(footprints allowed)
		)
		(placement
			(enabled no)
			(sheetname "")
		)
		(fill
			(thermal_gap 0.5)
			(thermal_bridge_width 0.5)
			(island_removal_mode 0)
		)
		(polygon
			(pts
				(xy 450.746876 -115.799362) (xy 452.054976 -115.799362) (xy 452.054976 -118.186962) (xy 450.746876 -118.186962)
			)
		)
	)
	(zone
		(layer "In1.Cu")
		(hatch none 0.5)
		(connect_pads
			(clearance 0)
		)
		(min_thickness 0.25)
		(keepout
			(tracks not_allowed)
			(vias allowed)
			(pads allowed)
			(copperpour not_allowed)
			(footprints allowed)
		)
		(placement
			(enabled no)
			(sheetname "")
		)
		(fill
			(thermal_gap 0.5)
			(thermal_bridge_width 0.5)
			(island_removal_mode 0)
		)
		(polygon
			(pts
				(xy 314.27039 -136.774682) (xy 314.27039 -138.578082) (xy 314.82919 -138.578082) (xy 314.82919 -136.774682)
			)
		)
	)
	(zone
		(layer "In1.Cu")
		(hatch none 0.5)
		(connect_pads
			(clearance 0)
		)
		(min_thickness 0.25)
		(keepout
			(tracks not_allowed)
			(vias allowed)
			(pads allowed)
			(copperpour not_allowed)
			(footprints allowed)
		)
		(placement
			(enabled no)
			(sheetname "")
		)
		(fill
			(thermal_gap 0.5)
			(thermal_bridge_width 0.5)
			(island_removal_mode 0)
		)
		(polygon
			(pts
				(xy 35.370008 -132.174742) (xy 35.370008 -133.978142) (xy 35.928808 -133.978142) (xy 35.928808 -132.174742)
			)
		)
	)
	(zone
		(layer "In1.Cu")
		(hatch none 0.5)
		(connect_pads
			(clearance 0)
		)
		(min_thickness 0.25)
		(keepout
			(tracks not_allowed)
			(vias allowed)
			(pads allowed)
			(copperpour not_allowed)
			(footprints allowed)
		)
		(placement
			(enabled no)
			(sheetname "")
		)
		(fill
			(thermal_gap 0.5)
			(thermal_bridge_width 0.5)
			(island_removal_mode 0)
		)
		(polygon
			(pts
				(xy 289.620452 -136.774682) (xy 289.620452 -138.578082) (xy 290.179252 -138.578082) (xy 290.179252 -136.774682)
			)
		)
	)
	(zone
		(layer "In1.Cu")
		(hatch none 0.5)
		(connect_pads
			(clearance 0)
		)
		(min_thickness 0.25)
		(keepout
			(tracks not_allowed)
			(vias allowed)
			(pads allowed)
			(copperpour not_allowed)
			(footprints allowed)
		)
		(placement
			(enabled no)
			(sheetname "")
		)
		(fill
			(thermal_gap 0.5)
			(thermal_bridge_width 0.5)
			(island_removal_mode 0)
		)
		(polygon
			(pts
				(xy 249.67057 -136.774682) (xy 249.67057 -138.578082) (xy 250.22937 -138.578082) (xy 250.22937 -136.774682)
			)
		)
	)
	(zone
		(layer "In1.Cu")
		(hatch none 0.5)
		(connect_pads
			(clearance 0)
		)
		(min_thickness 0.25)
		(keepout
			(tracks not_allowed)
			(vias allowed)
			(pads allowed)
			(copperpour not_allowed)
			(footprints allowed)
		)
		(placement
			(enabled no)
			(sheetname "")
		)
		(fill
			(thermal_gap 0.5)
			(thermal_bridge_width 0.5)
			(island_removal_mode 0)
		)
		(polygon
			(pts
				(xy 228.420422 -19.121882) (xy 228.420422 -20.925282) (xy 228.979222 -20.925282) (xy 228.979222 -19.121882)
			)
		)
	)
	(zone
		(layer "In1.Cu")
		(hatch none 0.5)
		(connect_pads
			(clearance 0)
		)
		(min_thickness 0.25)
		(keepout
			(tracks not_allowed)
			(vias allowed)
			(pads allowed)
			(copperpour not_allowed)
			(footprints allowed)
		)
		(placement
			(enabled no)
			(sheetname "")
		)
		(fill
			(thermal_gap 0.5)
			(thermal_bridge_width 0.5)
			(island_removal_mode 0)
		)
		(polygon
			(pts
				(xy 117.819932 -151.377142) (xy 117.819932 -153.180542) (xy 118.378732 -153.180542) (xy 118.378732 -151.377142)
			)
		)
	)
	(zone
		(layer "In1.Cu")
		(hatch none 0.5)
		(connect_pads
			(clearance 0)
		)
		(min_thickness 0.25)
		(keepout
			(tracks not_allowed)
			(vias allowed)
			(pads allowed)
			(copperpour not_allowed)
			(footprints allowed)
		)
		(placement
			(enabled no)
			(sheetname "")
		)
		(fill
			(thermal_gap 0.5)
			(thermal_bridge_width 0.5)
			(island_removal_mode 0)
		)
		(polygon
			(pts
				(xy 120.370092 -4.920742) (xy 120.370092 -6.724142) (xy 120.928892 -6.724142) (xy 120.928892 -4.920742)
			)
		)
	)
	(zone
		(layer "In1.Cu")
		(hatch none 0.5)
		(connect_pads
			(clearance 0)
		)
		(min_thickness 0.25)
		(keepout
			(tracks not_allowed)
			(vias allowed)
			(pads allowed)
			(copperpour not_allowed)
			(footprints allowed)
		)
		(placement
			(enabled no)
			(sheetname "")
		)
		(fill
			(thermal_gap 0.5)
			(thermal_bridge_width 0.5)
			(island_removal_mode 0)
		)
		(polygon
			(pts
				(xy 214.8205 -14.521942) (xy 214.8205 -16.325342) (xy 215.3793 -16.325342) (xy 215.3793 -14.521942)
			)
		)
	)
	(zone
		(layer "In1.Cu")
		(hatch none 0.5)
		(connect_pads
			(clearance 0)
		)
		(min_thickness 0.25)
		(keepout
			(tracks not_allowed)
			(vias allowed)
			(pads allowed)
			(copperpour not_allowed)
			(footprints allowed)
		)
		(placement
			(enabled no)
			(sheetname "")
		)
		(fill
			(thermal_gap 0.5)
			(thermal_bridge_width 0.5)
			(island_removal_mode 0)
		)
		(polygon
			(pts
				(xy 290.470336 -14.521942) (xy 290.470336 -16.325342) (xy 291.029136 -16.325342) (xy 291.029136 -14.521942)
			)
		)
	)
	(zone
		(layer "In1.Cu")
		(hatch none 0.5)
		(connect_pads
			(clearance 0)
		)
		(min_thickness 0.25)
		(keepout
			(tracks not_allowed)
			(vias allowed)
			(pads allowed)
			(copperpour not_allowed)
			(footprints allowed)
		)
		(placement
			(enabled no)
			(sheetname "")
		)
		(fill
			(thermal_gap 0.5)
			(thermal_bridge_width 0.5)
			(island_removal_mode 0)
		)
		(polygon
			(pts
				(xy 226.7204 -155.977082) (xy 226.7204 -157.780482) (xy 227.2792 -157.780482) (xy 227.2792 -155.977082)
			)
		)
	)
	(zone
		(layer "In1.Cu")
		(hatch none 0.5)
		(connect_pads
			(clearance 0)
		)
		(min_thickness 0.25)
		(keepout
			(tracks not_allowed)
			(vias allowed)
			(pads allowed)
			(copperpour not_allowed)
			(footprints allowed)
		)
		(placement
			(enabled no)
			(sheetname "")
		)
		(fill
			(thermal_gap 0.5)
			(thermal_bridge_width 0.5)
			(island_removal_mode 0)
		)
		(polygon
			(pts
				(xy 378.030994 -3.792982) (xy 379.339094 -3.792982) (xy 379.339094 -4.986782) (xy 378.030994 -4.986782)
			)
		)
	)
	(zone
		(layer "In1.Cu")
		(hatch none 0.5)
		(connect_pads
			(clearance 0)
		)
		(min_thickness 0.25)
		(keepout
			(tracks not_allowed)
			(vias allowed)
			(pads allowed)
			(copperpour not_allowed)
			(footprints allowed)
		)
		(placement
			(enabled no)
			(sheetname "")
		)
		(fill
			(thermal_gap 0.5)
			(thermal_bridge_width 0.5)
			(island_removal_mode 0)
		)
		(polygon
			(pts
				(xy 199.520556 -141.775942) (xy 199.520556 -143.579342) (xy 200.079356 -143.579342) (xy 200.079356 -141.775942)
			)
		)
	)
	(zone
		(layer "In1.Cu")
		(hatch none 0.5)
		(connect_pads
			(clearance 0)
		)
		(min_thickness 0.25)
		(keepout
			(tracks not_allowed)
			(vias allowed)
			(pads allowed)
			(copperpour not_allowed)
			(footprints allowed)
		)
		(placement
			(enabled no)
			(sheetname "")
		)
		(fill
			(thermal_gap 0.5)
			(thermal_bridge_width 0.5)
			(island_removal_mode 0)
		)
		(polygon
			(pts
				(xy 49.820068 4.680458) (xy 49.820068 2.877058) (xy 50.378868 2.877058) (xy 50.378868 4.680458)
			)
		)
	)
	(zone
		(layer "In1.Cu")
		(hatch none 0.5)
		(connect_pads
			(clearance 0)
		)
		(min_thickness 0.25)
		(keepout
			(tracks not_allowed)
			(vias allowed)
			(pads allowed)
			(copperpour not_allowed)
			(footprints allowed)
		)
		(placement
			(enabled no)
			(sheetname "")
		)
		(fill
			(thermal_gap 0.5)
			(thermal_bridge_width 0.5)
			(island_removal_mode 0)
		)
		(polygon
			(pts
				(xy 307.470302 -151.377142) (xy 307.470302 -153.180542) (xy 308.029102 -153.180542) (xy 308.029102 -151.377142)
			)
		)
	)
	(zone
		(layer "In1.Cu")
		(hatch none 0.5)
		(connect_pads
			(clearance 0)
		)
		(min_thickness 0.25)
		(keepout
			(tracks not_allowed)
			(vias allowed)
			(pads allowed)
			(copperpour not_allowed)
			(footprints allowed)
		)
		(placement
			(enabled no)
			(sheetname "")
		)
		(fill
			(thermal_gap 0.5)
			(thermal_bridge_width 0.5)
			(island_removal_mode 0)
		)
		(polygon
			(pts
				(xy 99.970082 -9.520682) (xy 99.970082 -11.324082) (xy 100.528882 -11.324082) (xy 100.528882 -9.520682)
			)
		)
	)
	(zone
		(layer "In1.Cu")
		(hatch none 0.5)
		(connect_pads
			(clearance 0)
		)
		(min_thickness 0.25)
		(keepout
			(tracks not_allowed)
			(vias allowed)
			(pads allowed)
			(copperpour not_allowed)
			(footprints allowed)
		)
		(placement
			(enabled no)
			(sheetname "")
		)
		(fill
			(thermal_gap 0.5)
			(thermal_bridge_width 0.5)
			(island_removal_mode 0)
		)
		(polygon
			(pts
				(xy 114.419888 -141.775942) (xy 114.419888 -143.579342) (xy 114.978688 -143.579342) (xy 114.978688 -141.775942)
			)
		)
	)
	(zone
		(layer "In1.Cu")
		(hatch none 0.5)
		(connect_pads
			(clearance 0)
		)
		(min_thickness 0.25)
		(keepout
			(tracks not_allowed)
			(vias allowed)
			(pads allowed)
			(copperpour not_allowed)
			(footprints allowed)
		)
		(placement
			(enabled no)
			(sheetname "")
		)
		(fill
			(thermal_gap 0.5)
			(thermal_bridge_width 0.5)
			(island_removal_mode 0)
		)
		(polygon
			(pts
				(xy 310.870346 -4.920742) (xy 310.870346 -6.724142) (xy 311.429146 -6.724142) (xy 311.429146 -4.920742)
			)
		)
	)
	(zone
		(layer "In1.Cu")
		(hatch none 0.5)
		(connect_pads
			(clearance 0)
		)
		(min_thickness 0.25)
		(keepout
			(tracks not_allowed)
			(vias allowed)
			(pads allowed)
			(copperpour not_allowed)
			(footprints allowed)
		)
		(placement
			(enabled no)
			(sheetname "")
		)
		(fill
			(thermal_gap 0.5)
			(thermal_bridge_width 0.5)
			(island_removal_mode 0)
		)
		(polygon
			(pts
				(xy 247.12041 -132.174742) (xy 247.12041 -133.978142) (xy 247.67921 -133.978142) (xy 247.67921 -132.174742)
			)
		)
	)
	(zone
		(layer "In1.Cu")
		(hatch none 0.5)
		(connect_pads
			(clearance 0)
		)
		(min_thickness 0.25)
		(keepout
			(tracks not_allowed)
			(vias allowed)
			(pads allowed)
			(copperpour not_allowed)
			(footprints allowed)
		)
		(placement
			(enabled no)
			(sheetname "")
		)
		(fill
			(thermal_gap 0.5)
			(thermal_bridge_width 0.5)
			(island_removal_mode 0)
		)
		(polygon
			(pts
				(xy 276.02053 -19.121882) (xy 276.57933 -19.121882) (xy 276.57933 -20.925282) (xy 276.02053 -20.925282)
			)
		)
	)
	(zone
		(layer "In1.Cu")
		(hatch none 0.5)
		(connect_pads
			(clearance 0)
		)
		(min_thickness 0.25)
		(keepout
			(tracks not_allowed)
			(vias allowed)
			(pads allowed)
			(copperpour not_allowed)
			(footprints allowed)
		)
		(placement
			(enabled no)
			(sheetname "")
		)
		(fill
			(thermal_gap 0.5)
			(thermal_bridge_width 0.5)
			(island_removal_mode 0)
		)
		(polygon
			(pts
				(xy 140.770102 -141.775942) (xy 140.770102 -143.579342) (xy 141.328902 -143.579342) (xy 141.328902 -141.775942)
			)
		)
	)
	(zone
		(layer "In1.Cu")
		(hatch none 0.5)
		(connect_pads
			(clearance 0)
		)
		(min_thickness 0.25)
		(keepout
			(tracks not_allowed)
			(vias allowed)
			(pads allowed)
			(copperpour not_allowed)
			(footprints allowed)
		)
		(placement
			(enabled no)
			(sheetname "")
		)
		(fill
			(thermal_gap 0.5)
			(thermal_bridge_width 0.5)
			(island_removal_mode 0)
		)
		(polygon
			(pts
				(xy 124.62002 -155.977082) (xy 124.62002 -157.780482) (xy 125.17882 -157.780482) (xy 125.17882 -155.977082)
			)
		)
	)
	(zone
		(layer "In1.Cu")
		(hatch none 0.5)
		(connect_pads
			(clearance 0)
		)
		(min_thickness 0.25)
		(keepout
			(tracks not_allowed)
			(vias allowed)
			(pads allowed)
			(copperpour not_allowed)
			(footprints allowed)
		)
		(placement
			(enabled no)
			(sheetname "")
		)
		(fill
			(thermal_gap 0.5)
			(thermal_bridge_width 0.5)
			(island_removal_mode 0)
		)
		(polygon
			(pts
				(xy 281.97048 0.080518) (xy 281.97048 -1.722882) (xy 282.52928 -1.722882) (xy 282.52928 0.080518)
			)
		)
	)
	(zone
		(layer "In1.Cu")
		(hatch none 0.5)
		(connect_pads
			(clearance 0)
		)
		(min_thickness 0.25)
		(keepout
			(tracks not_allowed)
			(vias allowed)
			(pads allowed)
			(copperpour not_allowed)
			(footprints allowed)
		)
		(placement
			(enabled no)
			(sheetname "")
		)
		(fill
			(thermal_gap 0.5)
			(thermal_bridge_width 0.5)
			(island_removal_mode 0)
		)
		(polygon
			(pts
				(xy 118.67007 -132.174742) (xy 118.67007 -133.978142) (xy 119.22887 -133.978142) (xy 119.22887 -132.174742)
			)
		)
	)
	(zone
		(layer "In1.Cu")
		(hatch none 0.5)
		(connect_pads
			(clearance 0)
		)
		(min_thickness 0.25)
		(keepout
			(tracks not_allowed)
			(vias allowed)
			(pads allowed)
			(copperpour not_allowed)
			(footprints allowed)
		)
		(placement
			(enabled no)
			(sheetname "")
		)
		(fill
			(thermal_gap 0.5)
			(thermal_bridge_width 0.5)
			(island_removal_mode 0)
		)
		(polygon
			(pts
				(xy 54.069996 -9.520682) (xy 54.069996 -11.324082) (xy 54.628796 -11.324082) (xy 54.628796 -9.520682)
			)
		)
	)
	(zone
		(layer "In1.Cu")
		(hatch none 0.5)
		(connect_pads
			(clearance 0)
		)
		(min_thickness 0.25)
		(keepout
			(tracks not_allowed)
			(vias allowed)
			(pads allowed)
			(copperpour not_allowed)
			(footprints allowed)
		)
		(placement
			(enabled no)
			(sheetname "")
		)
		(fill
			(thermal_gap 0.5)
			(thermal_bridge_width 0.5)
			(island_removal_mode 0)
		)
		(polygon
			(pts
				(xy 452.346822 -111.011716) (xy 453.654922 -111.011716) (xy 453.654922 -113.399316) (xy 452.346822 -113.399316)
			)
		)
	)
	(zone
		(layer "In1.Cu")
		(hatch none 0.5)
		(connect_pads
			(clearance 0)
		)
		(min_thickness 0.25)
		(keepout
			(tracks not_allowed)
			(vias allowed)
			(pads allowed)
			(copperpour not_allowed)
			(footprints allowed)
		)
		(placement
			(enabled no)
			(sheetname "")
		)
		(fill
			(thermal_gap 0.5)
			(thermal_bridge_width 0.5)
			(island_removal_mode 0)
		)
		(polygon
			(pts
				(xy 43.01998 -136.774682) (xy 43.01998 -138.578082) (xy 43.57878 -138.578082) (xy 43.57878 -136.774682)
			)
		)
	)
	(zone
		(layer "In1.Cu")
		(hatch none 0.5)
		(connect_pads
			(clearance 0)
		)
		(min_thickness 0.25)
		(keepout
			(tracks not_allowed)
			(vias allowed)
			(pads allowed)
			(copperpour not_allowed)
			(footprints allowed)
		)
		(placement
			(enabled no)
			(sheetname "")
		)
		(fill
			(thermal_gap 0.5)
			(thermal_bridge_width 0.5)
			(island_removal_mode 0)
		)
		(polygon
			(pts
				(xy 109.320076 -141.775942) (xy 109.320076 -143.579342) (xy 109.878876 -143.579342) (xy 109.878876 -141.775942)
			)
		)
	)
	(zone
		(layer "In1.Cu")
		(hatch none 0.5)
		(connect_pads
			(clearance 0)
		)
		(min_thickness 0.25)
		(keepout
			(tracks not_allowed)
			(vias allowed)
			(pads allowed)
			(copperpour not_allowed)
			(footprints allowed)
		)
		(placement
			(enabled no)
			(sheetname "")
		)
		(fill
			(thermal_gap 0.5)
			(thermal_bridge_width 0.5)
			(island_removal_mode 0)
		)
		(polygon
			(pts
				(xy 453.023478 -7.192772) (xy 454.331578 -7.192772) (xy 454.331578 -8.386572) (xy 453.023478 -8.386572)
			)
		)
	)
	(zone
		(layer "In1.Cu")
		(hatch none 0.5)
		(connect_pads
			(clearance 0)
		)
		(min_thickness 0.25)
		(keepout
			(tracks not_allowed)
			(vias allowed)
			(pads allowed)
			(copperpour not_allowed)
			(footprints allowed)
		)
		(placement
			(enabled no)
			(sheetname "")
		)
		(fill
			(thermal_gap 0.5)
			(thermal_bridge_width 0.5)
			(island_removal_mode 0)
		)
		(polygon
			(pts
				(xy 128.020064 -146.375882) (xy 128.020064 -148.179282) (xy 128.578864 -148.179282) (xy 128.578864 -146.375882)
			)
		)
	)
	(zone
		(layer "In1.Cu")
		(hatch none 0.5)
		(connect_pads
			(clearance 0)
		)
		(min_thickness 0.25)
		(keepout
			(tracks not_allowed)
			(vias allowed)
			(pads allowed)
			(copperpour not_allowed)
			(footprints allowed)
		)
		(placement
			(enabled no)
			(sheetname "")
		)
		(fill
			(thermal_gap 0.5)
			(thermal_bridge_width 0.5)
			(island_removal_mode 0)
		)
		(polygon
			(pts
				(xy 74.470006 -141.775942) (xy 74.470006 -143.579342) (xy 75.028806 -143.579342) (xy 75.028806 -141.775942)
			)
		)
	)
	(zone
		(layer "In1.Cu")
		(hatch none 0.5)
		(connect_pads
			(clearance 0)
		)
		(min_thickness 0.25)
		(keepout
			(tracks not_allowed)
			(vias allowed)
			(pads allowed)
			(copperpour not_allowed)
			(footprints allowed)
		)
		(placement
			(enabled no)
			(sheetname "")
		)
		(fill
			(thermal_gap 0.5)
			(thermal_bridge_width 0.5)
			(island_removal_mode 0)
		)
		(polygon
			(pts
				(xy 204.620368 -146.375882) (xy 204.620368 -148.179282) (xy 205.179168 -148.179282) (xy 205.179168 -146.375882)
			)
		)
	)
	(zone
		(layer "In1.Cu")
		(hatch none 0.5)
		(connect_pads
			(clearance 0)
		)
		(min_thickness 0.25)
		(keepout
			(tracks not_allowed)
			(vias allowed)
			(pads allowed)
			(copperpour not_allowed)
			(footprints allowed)
		)
		(placement
			(enabled no)
			(sheetname "")
		)
		(fill
			(thermal_gap 0.5)
			(thermal_bridge_width 0.5)
			(island_removal_mode 0)
		)
		(polygon
			(pts
				(xy 223.320356 -9.520682) (xy 223.320356 -11.324082) (xy 223.879156 -11.324082) (xy 223.879156 -9.520682)
			)
		)
	)
	(zone
		(layer "In1.Cu")
		(hatch none 0.5)
		(connect_pads
			(clearance 0)
		)
		(min_thickness 0.25)
		(keepout
			(tracks not_allowed)
			(vias allowed)
			(pads allowed)
			(copperpour not_allowed)
			(footprints allowed)
		)
		(placement
			(enabled no)
			(sheetname "")
		)
		(fill
			(thermal_gap 0.5)
			(thermal_bridge_width 0.5)
			(island_removal_mode 0)
		)
		(polygon
			(pts
				(xy 288.770314 -14.521942) (xy 288.770314 -16.325342) (xy 289.329114 -16.325342) (xy 289.329114 -14.521942)
			)
		)
	)
	(zone
		(net "PVDDQ_ABC")
		(layer "In1.Cu")
		(hatch none 0.5)
		(connect_pads
			(clearance 0.5)
		)
		(min_thickness 0.25)
		(fill yes
			(thermal_gap 0.5)
			(thermal_bridge_width 0.5)
			(island_removal_mode 0)
		)
		(polygon
			(pts
				(xy 243.350796 4.953)
				(arc
					(start 243.25199 4.854194)
					(mid 243.229954 4.74341)
					(end 243.323872 4.680712)
				)
				(xy 243.429536 4.680712) (xy 243.429536 2.876804) (xy 242.870228 2.876804)
				(arc
					(start 242.870228 4.227068)
					(mid 242.807509 4.320934)
					(end 242.696746 4.29895)
				)
				(xy 242.662964 4.265168) (xy 242.662964 2.11074)
				(arc
					(start 242.664996 2.103628)
					(mid 242.681049 1.994154)
					(end 242.664996 1.88468)
				)
				(xy 242.662964 1.877568) (xy 242.662964 1.056386)
				(arc
					(start 242.664996 1.049274)
					(mid 242.681049 0.9398)
					(end 242.664996 0.830326)
				)
				(xy 242.662964 0.823214) (xy 242.662964 -3.64617)
				(arc
					(start 242.664996 -3.653282)
					(mid 242.681049 -3.762756)
					(end 242.664996 -3.87223)
				)
				(xy 242.662964 -3.879342) (xy 242.662964 -7.49046)
				(arc
					(start 242.664996 -7.497572)
					(mid 242.681049 -7.607046)
					(end 242.664996 -7.71652)
				)
				(xy 242.662964 -7.723632) (xy 242.662964 -8.544814)
				(arc
					(start 242.664996 -8.551926)
					(mid 242.681049 -8.6614)
					(end 242.664996 -8.770874)
				)
				(xy 242.662964 -8.777986) (xy 242.662964 -12.56157)
				(arc
					(start 242.664996 -12.568682)
					(mid 242.681049 -12.678156)
					(end 242.664996 -12.78763)
				)
				(xy 242.662964 -12.794742) (xy 242.662964 -13.24737)
				(arc
					(start 242.664996 -13.254482)
					(mid 242.681049 -13.363956)
					(end 242.664996 -13.47343)
				)
				(xy 242.662964 -13.480542) (xy 242.662964 -17.09166)
				(arc
					(start 242.664996 -17.098772)
					(mid 242.681049 -17.208246)
					(end 242.664996 -17.31772)
				)
				(xy 242.662964 -17.324832) (xy 242.662964 -18.146014)
				(arc
					(start 242.664996 -18.153126)
					(mid 242.681049 -18.2626)
					(end 242.664996 -18.372074)
				)
				(xy 242.662964 -18.379186) (xy 242.662964 -22.16277)
				(arc
					(start 242.664996 -22.169882)
					(mid 242.681049 -22.279356)
					(end 242.664996 -22.38883)
				)
				(xy 242.662964 -22.395942)
				(arc
					(start 242.662964 -22.89937)
					(mid 242.668677 -22.965156)
					(end 242.662964 -23.030942)
				)
				(xy 242.662964 -24.807164) (xy 242.67795 -24.82215) (xy 242.67795 -25.60955) (xy 246.4181 -29.3497)
				(xy 246.4181 -31.2674) (xy 248.9327 -33.782) (xy 248.9327 -34.5567) (xy 250.489974 -36.113974) (xy 250.489974 -45.654468)
				(xy 250.647708 -45.812202) (xy 250.647708 -48.169068) (xy 251.229876 -48.751236) (xy 251.229876 -50.847498)
				(xy 251.156216 -50.921158) (xy 251.135642 -50.921158) (xy 250.8504 -51.2064) (xy 250.8504 -51.305968)
				(xy 250.911868 -51.305968)
				(arc
					(start 250.921774 -51.30165)
					(mid 251.42016 -51.598251)
					(end 250.977146 -51.972464)
				)
				(arc
					(start 250.977146 -51.972464)
					(mid 250.889601 -51.990697)
					(end 250.8504 -52.071016)
				)
				(arc
					(start 250.8504 -52.174648)
					(mid 250.889668 -52.254881)
					(end 250.977146 -52.2732)
				)
				(arc
					(start 250.977146 -52.2732)
					(mid 251.421299 -52.618132)
					(end 250.977146 -52.963064)
				)
				(arc
					(start 250.977146 -52.963064)
					(mid 250.889601 -52.981297)
					(end 250.8504 -53.061616)
				)
				(arc
					(start 250.8504 -53.165248)
					(mid 250.889668 -53.245481)
					(end 250.977146 -53.2638)
				)
				(arc
					(start 250.977146 -53.2638)
					(mid 251.421299 -53.608732)
					(end 250.977146 -53.953664)
				)
				(arc
					(start 250.977146 -53.953664)
					(mid 250.889601 -53.971897)
					(end 250.8504 -54.052216)
				)
				(xy 250.8504 -54.1274) (xy 250.4186 -54.5592)
				(arc
					(start 250.4186 -54.808628)
					(mid 250.562879 -55.094886)
					(end 250.4186 -55.381144)
				)
				(arc
					(start 250.4186 -55.799228)
					(mid 250.562879 -56.085486)
					(end 250.4186 -56.371744)
				)
				(arc
					(start 250.4186 -56.789828)
					(mid 250.515028 -56.897784)
					(end 250.560586 -57.035192)
				)
				(xy 250.562618 -57.052718) (xy 251.3838 -57.8739) (xy 251.3838 -58.402474)
				(arc
					(start 251.388372 -58.412634)
					(mid 251.421329 -58.56224)
					(end 251.388372 -58.711846)
				)
				(xy 251.3838 -58.722006) (xy 251.3838 -59.393074)
				(arc
					(start 251.388372 -59.403234)
					(mid 251.421329 -59.55284)
					(end 251.388372 -59.702446)
				)
				(xy 251.3838 -59.712606) (xy 251.3838 -60.383674)
				(arc
					(start 251.388372 -60.393834)
					(mid 251.421329 -60.54344)
					(end 251.388372 -60.693046)
				)
				(xy 251.3838 -60.703206) (xy 251.3838 -61.374274)
				(arc
					(start 251.388372 -61.384434)
					(mid 251.421329 -61.53404)
					(end 251.388372 -61.683646)
				)
				(xy 251.3838 -61.693806) (xy 251.3838 -62.3189) (xy 251.764546 -62.699646)
				(arc
					(start 251.79528 -62.687454)
					(mid 252.011175 -62.6745)
					(end 252.194822 -62.7888)
				)
				(arc
					(start 252.354588 -62.7888)
					(mid 252.438032 -62.744795)
					(end 252.44933 -62.651132)
				)
				(arc
					(start 252.44933 -62.651132)
					(mid 252.782324 -62.16843)
					(end 253.115318 -62.651132)
				)
				(arc
					(start 253.115318 -62.651132)
					(mid 253.126605 -62.744802)
					(end 253.21006 -62.7888)
				)
				(arc
					(start 253.369826 -62.7888)
					(mid 253.640844 -62.663654)
					(end 253.911862 -62.7888)
				)
				(arc
					(start 254.071374 -62.7888)
					(mid 254.154818 -62.744795)
					(end 254.166116 -62.651132)
				)
				(arc
					(start 254.166116 -62.651132)
					(mid 254.49911 -62.16843)
					(end 254.832104 -62.651132)
				)
				(arc
					(start 254.832104 -62.651132)
					(mid 254.843391 -62.744802)
					(end 254.926846 -62.7888)
				)
				(arc
					(start 255.086612 -62.7888)
					(mid 255.35763 -62.663654)
					(end 255.628648 -62.7888)
				)
				(arc
					(start 255.788414 -62.7888)
					(mid 255.871858 -62.744795)
					(end 255.883156 -62.651132)
				)
				(arc
					(start 255.883156 -62.651132)
					(mid 256.21615 -62.16843)
					(end 256.549144 -62.651132)
				)
				(arc
					(start 256.549144 -62.651132)
					(mid 256.560431 -62.744802)
					(end 256.643886 -62.7888)
				)
				(arc
					(start 256.803652 -62.7888)
					(mid 256.971938 -62.678797)
					(end 257.172968 -62.677548)
				)
				(xy 257.201924 -62.685676) (xy 257.447288 -62.440312) (xy 257.585464 -62.440312)
				(arc
					(start 257.597402 -62.406276)
					(mid 257.926278 -62.168668)
					(end 258.264152 -62.393322)
				)
				(xy 258.276852 -62.425326) (xy 259.306568 -62.425326)
				(arc
					(start 259.319268 -62.393322)
					(mid 259.65023 -62.168578)
					(end 259.981192 -62.393322)
				)
				(xy 259.993892 -62.425326)
				(arc
					(start 260.158484 -62.425326)
					(mid 260.250575 -62.366643)
					(end 260.236208 -62.258448)
				)
				(arc
					(start 260.236208 -62.258448)
					(mid 260.36259 -61.704243)
					(end 260.861048 -61.97727)
				)
				(xy 260.867398 -62.020704) (xy 261.867142 -62.020704)
				(arc
					(start 261.873492 -61.97727)
					(mid 262.22579 -61.672998)
					(end 262.578088 -61.97727)
				)
				(xy 262.584438 -62.020704) (xy 263.584182 -62.020704)
				(arc
					(start 263.590532 -61.97727)
					(mid 263.94283 -61.672998)
					(end 264.295128 -61.97727)
				)
				(xy 264.301478 -62.020704) (xy 265.300968 -62.020704)
				(arc
					(start 265.307318 -61.97727)
					(mid 265.659616 -61.672998)
					(end 266.011914 -61.97727)
				)
				(xy 266.018264 -62.020704) (xy 268.199108 -62.020704)
				(arc
					(start 268.205458 -61.97727)
					(mid 268.557756 -61.672998)
					(end 268.910054 -61.97727)
				)
				(xy 268.916404 -62.020704) (xy 269.03045 -62.020704) (xy 269.514574 -61.53658) (xy 269.514574 -60.658756)
				(xy 269.76197 -60.41136) (xy 269.76197 -50.090578) (xy 270.158464 -49.694084) (xy 270.158464 -41.021)
				(xy 269.9766 -40.839136) (xy 269.9766 -36.0934) (xy 270.204692 -35.865308) (xy 270.204692 -33.781492)
				(xy 278.783288 -25.202896)
				(arc
					(start 278.783288 -23.138892)
					(mid 278.61213 -22.8346)
					(end 278.783288 -22.530308)
				)
				(arc
					(start 278.783288 -21.98116)
					(mid 278.591332 -21.665184)
					(end 278.783288 -21.349208)
				)
				(arc
					(start 278.783288 -19.009106)
					(mid 278.590959 -18.73373)
					(end 278.713184 -18.420842)
				)
				(arc
					(start 278.713184 -18.420842)
					(mid 278.74854 -18.345682)
					(end 278.715978 -18.269204)
				)
				(arc
					(start 278.715978 -18.269204)
					(mid 278.603967 -17.966014)
					(end 278.783288 -17.697196)
				)
				(arc
					(start 278.783288 -17.60855)
					(mid 278.595655 -17.29486)
					(end 278.783288 -16.98117)
				)
				(arc
					(start 278.783288 -14.187424)
					(mid 278.683538 -13.940282)
					(end 278.783288 -13.69314)
				)
				(xy 278.783288 -13.28547)
				(arc
					(start 278.755602 -13.271246)
					(mid 278.561277 -12.954)
					(end 278.755602 -12.636754)
				)
				(xy 278.783288 -12.62253) (xy 278.783288 -12.260326)
				(arc
					(start 278.756364 -12.245848)
					(mid 278.567747 -11.93165)
					(end 278.756364 -11.617452)
				)
				(xy 278.783288 -11.602974) (xy 278.783288 -9.42213)
				(arc
					(start 278.753062 -9.408668)
					(mid 278.54156 -9.083294)
					(end 278.753062 -8.75792)
				)
				(xy 278.783288 -8.744458) (xy 278.783288 -8.45058)
				(arc
					(start 278.749252 -8.438896)
					(mid 278.510418 -8.1026)
					(end 278.749252 -7.766304)
				)
				(xy 278.783288 -7.75462) (xy 278.783288 -7.48919)
				(arc
					(start 278.74722 -7.478268)
					(mid 278.493857 -7.1374)
					(end 278.74722 -6.796532)
				)
				(xy 278.783288 -6.78561)
				(arc
					(start 278.783288 -4.617974)
					(mid 278.637497 -4.318)
					(end 278.783288 -4.018026)
				)
				(xy 278.783288 -3.82778)
				(arc
					(start 278.749252 -3.816096)
					(mid 278.521923 -3.569598)
					(end 278.600154 -3.24358)
				)
				(arc
					(start 278.600154 -3.24358)
					(mid 278.625482 -3.17088)
					(end 278.592534 -3.10134)
				)
				(arc
					(start 278.592534 -3.10134)
					(mid 278.478395 -2.731502)
					(end 278.746204 -2.452116)
				)
				(xy 278.783288 -2.441702) (xy 278.783288 -0.254) (xy 278.6888 -0.159512) (xy 278.6888 1.44399)
				(arc
					(start 278.688546 1.444244)
					(mid 278.346708 1.816032)
					(end 278.673306 2.201164)
				)
				(xy 278.69007 2.203704) (xy 278.727408 2.241042) (xy 278.727408 4.229608)
				(arc
					(start 278.453088 4.503674)
					(mid 278.342543 4.52551)
					(end 278.27986 4.431792)
				)
				(xy 278.27986 2.876804) (xy 278.215852 2.876804) (xy 278.215852 2.801112)
				(arc
					(start 278.23541 2.785872)
					(mid 277.999952 2.104098)
					(end 277.764494 2.785872)
				)
				(xy 277.784052 2.801112) (xy 277.784052 2.876804) (xy 277.720044 2.876804) (xy 277.720044 4.680712)
				(arc
					(start 278.035766 4.680712)
					(mid 278.07195 4.68933)
					(end 278.102568 4.71043)
				)
				(xy 278.102568 4.854194)
				(arc
					(start 278.097742 4.85902)
					(mid 278.003162 4.893481)
					(end 277.921974 4.953)
				)
				(xy 276.189948 4.953)
				(arc
					(start 276.177756 4.91998)
					(mid 276.159443 4.878911)
					(end 276.1361 4.840478)
				)
				(arc
					(start 276.1361 4.840478)
					(mid 276.129317 4.735333)
					(end 276.219412 4.680712)
				)
				(xy 276.579584 4.680712) (xy 276.579584 2.876804) (xy 276.472396 2.876804) (xy 276.472396 2.798572)
				(arc
					(start 276.495256 2.783332)
					(mid 276.29993 2.129596)
					(end 276.104604 2.783332)
				)
				(xy 276.127464 2.798572) (xy 276.127464 2.876804) (xy 276.020276 2.876804)
				(arc
					(start 276.020276 4.592828)
					(mid 275.984332 4.670364)
					(end 275.901912 4.693158)
				)
				(arc
					(start 275.901912 4.693158)
					(mid 275.665484 4.736406)
					(end 275.510244 4.91998)
				)
				(xy 275.498052 4.953) (xy 272.758916 4.953)
				(arc
					(start 272.746216 4.920996)
					(mid 272.726985 4.880256)
					(end 272.702782 4.842256)
				)
				(arc
					(start 272.702782 4.842256)
					(mid 272.694334 4.736145)
					(end 272.785078 4.680712)
				)
				(xy 273.17954 4.680712) (xy 273.17954 2.876804) (xy 273.072352 2.876804) (xy 273.072352 2.798572)
				(arc
					(start 273.095212 2.783332)
					(mid 272.899886 2.129596)
					(end 272.70456 2.783332)
				)
				(xy 272.72742 2.798572) (xy 272.72742 2.876804) (xy 272.620232 2.876804)
				(arc
					(start 272.620232 4.606036)
					(mid 272.581687 4.685448)
					(end 272.495518 4.704842)
				)
				(arc
					(start 272.495518 4.704842)
					(mid 272.461823 4.698761)
					(end 272.4277 4.695952)
				)
				(arc
					(start 272.4277 4.695952)
					(mid 272.358124 4.66497)
					(end 272.329656 4.594352)
				)
				(xy 272.329656 2.876804) (xy 271.770348 2.876804) (xy 271.770348 4.680712)
				(arc
					(start 272.044922 4.680712)
					(mid 272.135476 4.736241)
					(end 272.127218 4.842256)
				)
				(arc
					(start 272.127218 4.842256)
					(mid 272.102995 4.880244)
					(end 272.083784 4.920996)
				)
				(xy 272.071084 4.953) (xy 269.362428 4.953)
				(arc
					(start 269.349728 4.920996)
					(mid 269.222721 4.760982)
					(end 269.028672 4.697222)
				)
				(arc
					(start 269.028672 4.697222)
					(mid 268.958455 4.666583)
					(end 268.929612 4.595622)
				)
				(xy 268.929612 2.876804) (xy 268.370304 2.876804)
				(arc
					(start 268.370304 4.624324)
					(mid 268.328371 4.706558)
					(end 268.237208 4.720844)
				)
				(arc
					(start 268.237208 4.720844)
					(mid 268.184275 4.708116)
					(end 268.13002 4.703572)
				)
				(arc
					(start 268.13002 4.703572)
					(mid 268.094263 4.688604)
					(end 268.079474 4.652772)
				)
				(xy 268.079474 2.876804) (xy 268.011402 2.876804) (xy 268.011402 2.802382)
				(arc
					(start 268.029436 2.787142)
					(mid 267.79982 2.158674)
					(end 267.570204 2.787142)
				)
				(xy 267.588238 2.802382) (xy 267.588238 2.876804) (xy 267.519912 2.876804)
				(arc
					(start 267.519912 4.613148)
					(mid 267.487779 4.687289)
					(end 267.411708 4.714494)
				)
				(arc
					(start 267.411708 4.714494)
					(mid 267.205235 4.764407)
					(end 267.063982 4.923028)
				)
				(xy 267.050266 4.953)
			)
		)
	)
	(zone
		(layer "In1.Cu")
		(hatch none 0.5)
		(connect_pads
			(clearance 0)
		)
		(min_thickness 0.25)
		(keepout
			(tracks not_allowed)
			(vias allowed)
			(pads allowed)
			(copperpour not_allowed)
			(footprints allowed)
		)
		(placement
			(enabled no)
			(sheetname "")
		)
		(fill
			(thermal_gap 0.5)
			(thermal_bridge_width 0.5)
			(island_removal_mode 0)
		)
		(polygon
			(pts
				(xy 82.119978 -136.774682) (xy 82.119978 -138.578082) (xy 82.678778 -138.578082) (xy 82.678778 -136.774682)
			)
		)
	)
	(zone
		(layer "In1.Cu")
		(hatch none 0.5)
		(connect_pads
			(clearance 0)
		)
		(min_thickness 0.25)
		(keepout
			(tracks not_allowed)
			(vias allowed)
			(pads allowed)
			(copperpour not_allowed)
			(footprints allowed)
		)
		(placement
			(enabled no)
			(sheetname "")
		)
		(fill
			(thermal_gap 0.5)
			(thermal_bridge_width 0.5)
			(island_removal_mode 0)
		)
		(polygon
			(pts
				(xy 53.220112 4.680458) (xy 53.220112 2.877058) (xy 53.778912 2.877058) (xy 53.778912 4.680458)
			)
		)
	)
	(zone
		(layer "In1.Cu")
		(hatch none 0.5)
		(connect_pads
			(clearance 0)
		)
		(min_thickness 0.25)
		(keepout
			(tracks not_allowed)
			(vias allowed)
			(pads allowed)
			(copperpour not_allowed)
			(footprints allowed)
		)
		(placement
			(enabled no)
			(sheetname "")
		)
		(fill
			(thermal_gap 0.5)
			(thermal_bridge_width 0.5)
			(island_removal_mode 0)
		)
		(polygon
			(pts
				(xy 128.020064 4.680458) (xy 128.020064 2.877058) (xy 128.578864 2.877058) (xy 128.578864 4.680458)
			)
		)
	)
	(zone
		(layer "In1.Cu")
		(hatch none 0.5)
		(connect_pads
			(clearance 0)
		)
		(min_thickness 0.25)
		(keepout
			(tracks not_allowed)
			(vias allowed)
			(pads allowed)
			(copperpour not_allowed)
			(footprints allowed)
		)
		(placement
			(enabled no)
			(sheetname "")
		)
		(fill
			(thermal_gap 0.5)
			(thermal_bridge_width 0.5)
			(island_removal_mode 0)
		)
		(polygon
			(pts
				(xy 68.520056 -132.174742) (xy 68.520056 -133.978142) (xy 69.078856 -133.978142) (xy 69.078856 -132.174742)
			)
		)
	)
	(zone
		(layer "In1.Cu")
		(hatch none 0.5)
		(connect_pads
			(clearance 0)
		)
		(min_thickness 0.25)
		(keepout
			(tracks not_allowed)
			(vias allowed)
			(pads allowed)
			(copperpour not_allowed)
			(footprints allowed)
		)
		(placement
			(enabled no)
			(sheetname "")
		)
		(fill
			(thermal_gap 0.5)
			(thermal_bridge_width 0.5)
			(island_removal_mode 0)
		)
		(polygon
			(pts
				(xy 146.720052 -155.977082) (xy 146.720052 -157.780482) (xy 147.278852 -157.780482) (xy 147.278852 -155.977082)
			)
		)
	)
	(zone
		(layer "In1.Cu")
		(hatch none 0.5)
		(connect_pads
			(clearance 0)
		)
		(min_thickness 0.25)
		(keepout
			(tracks not_allowed)
			(vias allowed)
			(pads allowed)
			(copperpour not_allowed)
			(footprints allowed)
		)
		(placement
			(enabled no)
			(sheetname "")
		)
		(fill
			(thermal_gap 0.5)
			(thermal_bridge_width 0.5)
			(island_removal_mode 0)
		)
		(polygon
			(pts
				(xy 309.170324 -14.521942) (xy 309.170324 -16.325342) (xy 309.729124 -16.325342) (xy 309.729124 -14.521942)
			)
		)
	)
	(zone
		(layer "In1.Cu")
		(hatch none 0.5)
		(connect_pads
			(clearance 0)
		)
		(min_thickness 0.25)
		(keepout
			(tracks not_allowed)
			(vias allowed)
			(pads allowed)
			(copperpour not_allowed)
			(footprints allowed)
		)
		(placement
			(enabled no)
			(sheetname "")
		)
		(fill
			(thermal_gap 0.5)
			(thermal_bridge_width 0.5)
			(island_removal_mode 0)
		)
		(polygon
			(pts
				(xy 195.270374 -136.774682) (xy 195.270374 -138.578082) (xy 195.829174 -138.578082) (xy 195.829174 -136.774682)
			)
		)
	)
	(zone
		(layer "In1.Cu")
		(hatch none 0.5)
		(connect_pads
			(clearance 0)
		)
		(min_thickness 0.25)
		(keepout
			(tracks not_allowed)
			(vias allowed)
			(pads allowed)
			(copperpour not_allowed)
			(footprints allowed)
		)
		(placement
			(enabled no)
			(sheetname "")
		)
		(fill
			(thermal_gap 0.5)
			(thermal_bridge_width 0.5)
			(island_removal_mode 0)
		)
		(polygon
			(pts
				(xy 32.820102 -151.377142) (xy 32.820102 -153.180542) (xy 33.378902 -153.180542) (xy 33.378902 -151.377142)
			)
		)
	)
	(zone
		(layer "In1.Cu")
		(hatch none 0.5)
		(connect_pads
			(clearance 0)
		)
		(min_thickness 0.25)
		(keepout
			(tracks not_allowed)
			(vias allowed)
			(pads allowed)
			(copperpour not_allowed)
			(footprints allowed)
		)
		(placement
			(enabled no)
			(sheetname "")
		)
		(fill
			(thermal_gap 0.5)
			(thermal_bridge_width 0.5)
			(island_removal_mode 0)
		)
		(polygon
			(pts
				(xy 205.470506 -141.775942) (xy 205.470506 -143.579342) (xy 206.029306 -143.579342) (xy 206.029306 -141.775942)
			)
		)
	)
	(zone
		(layer "In1.Cu")
		(hatch none 0.5)
		(connect_pads
			(clearance 0)
		)
		(min_thickness 0.25)
		(keepout
			(tracks not_allowed)
			(vias allowed)
			(pads allowed)
			(copperpour not_allowed)
			(footprints allowed)
		)
		(placement
			(enabled no)
			(sheetname "")
		)
		(fill
			(thermal_gap 0.5)
			(thermal_bridge_width 0.5)
			(island_removal_mode 0)
		)
		(polygon
			(pts
				(xy 277.720552 -136.774682) (xy 277.720552 -138.578082) (xy 278.279352 -138.578082) (xy 278.279352 -136.774682)
			)
		)
	)
	(zone
		(layer "In1.Cu")
		(hatch none 0.5)
		(connect_pads
			(clearance 0)
		)
		(min_thickness 0.25)
		(keepout
			(tracks not_allowed)
			(vias allowed)
			(pads allowed)
			(copperpour not_allowed)
			(footprints allowed)
		)
		(placement
			(enabled no)
			(sheetname "")
		)
		(fill
			(thermal_gap 0.5)
			(thermal_bridge_width 0.5)
			(island_removal_mode 0)
		)
		(polygon
			(pts
				(xy 230.120444 4.680458) (xy 230.120444 2.877058) (xy 230.679244 2.877058) (xy 230.679244 4.680458)
			)
		)
	)
	(zone
		(layer "In1.Cu")
		(hatch none 0.5)
		(connect_pads
			(clearance 0)
		)
		(min_thickness 0.25)
		(keepout
			(tracks not_allowed)
			(vias allowed)
			(pads allowed)
			(copperpour not_allowed)
			(footprints allowed)
		)
		(placement
			(enabled no)
			(sheetname "")
		)
		(fill
			(thermal_gap 0.5)
			(thermal_bridge_width 0.5)
			(island_removal_mode 0)
		)
		(polygon
			(pts
				(xy 310.020462 -155.977082) (xy 310.020462 -157.780482) (xy 310.579262 -157.780482) (xy 310.579262 -155.977082)
			)
		)
	)
	(zone
		(layer "In1.Cu")
		(hatch none 0.5)
		(connect_pads
			(clearance 0)
		)
		(min_thickness 0.25)
		(keepout
			(tracks not_allowed)
			(vias allowed)
			(pads allowed)
			(copperpour not_allowed)
			(footprints allowed)
		)
		(placement
			(enabled no)
			(sheetname "")
		)
		(fill
			(thermal_gap 0.5)
			(thermal_bridge_width 0.5)
			(island_removal_mode 0)
		)
		(polygon
			(pts
				(xy 99.970082 -136.774682) (xy 99.970082 -138.578082) (xy 100.528882 -138.578082) (xy 100.528882 -136.774682)
			)
		)
	)
	(zone
		(layer "In1.Cu")
		(hatch none 0.5)
		(connect_pads
			(clearance 0)
		)
		(min_thickness 0.25)
		(keepout
			(tracks not_allowed)
			(vias allowed)
			(pads allowed)
			(copperpour not_allowed)
			(footprints allowed)
		)
		(placement
			(enabled no)
			(sheetname "")
		)
		(fill
			(thermal_gap 0.5)
			(thermal_bridge_width 0.5)
			(island_removal_mode 0)
		)
		(polygon
			(pts
				(xy 273.47037 -146.375882) (xy 273.47037 -148.179282) (xy 274.02917 -148.179282) (xy 274.02917 -146.375882)
			)
		)
	)
	(zone
		(layer "In1.Cu")
		(hatch none 0.5)
		(connect_pads
			(clearance 0)
		)
		(min_thickness 0.25)
		(keepout
			(tracks not_allowed)
			(vias allowed)
			(pads allowed)
			(copperpour not_allowed)
			(footprints allowed)
		)
		(placement
			(enabled no)
			(sheetname "")
		)
		(fill
			(thermal_gap 0.5)
			(thermal_bridge_width 0.5)
			(island_removal_mode 0)
		)
		(polygon
			(pts
				(xy 38.770052 -14.521942) (xy 38.770052 -16.325342) (xy 39.328852 -16.325342) (xy 39.328852 -14.521942)
			)
		)
	)
	(zone
		(layer "In1.Cu")
		(hatch none 0.5)
		(connect_pads
			(clearance 0)
		)
		(min_thickness 0.25)
		(keepout
			(tracks not_allowed)
			(vias allowed)
			(pads allowed)
			(copperpour not_allowed)
			(footprints allowed)
		)
		(placement
			(enabled no)
			(sheetname "")
		)
		(fill
			(thermal_gap 0.5)
			(thermal_bridge_width 0.5)
			(island_removal_mode 0)
		)
		(polygon
			(pts
				(xy 122.919998 0.080518) (xy 122.919998 -1.722882) (xy 123.478798 -1.722882) (xy 123.478798 0.080518)
			)
		)
	)
	(zone
		(layer "In1.Cu")
		(hatch none 0.5)
		(connect_pads
			(clearance 0)
		)
		(min_thickness 0.25)
		(keepout
			(tracks not_allowed)
			(vias allowed)
			(pads allowed)
			(copperpour not_allowed)
			(footprints allowed)
		)
		(placement
			(enabled no)
			(sheetname "")
		)
		(fill
			(thermal_gap 0.5)
			(thermal_bridge_width 0.5)
			(island_removal_mode 0)
		)
		(polygon
			(pts
				(xy 250.520454 -136.774682) (xy 250.520454 -138.578082) (xy 251.079254 -138.578082) (xy 251.079254 -136.774682)
			)
		)
	)
	(zone
		(layer "In1.Cu")
		(hatch none 0.5)
		(connect_pads
			(clearance 0)
		)
		(min_thickness 0.25)
		(keepout
			(tracks not_allowed)
			(vias allowed)
			(pads allowed)
			(copperpour not_allowed)
			(footprints allowed)
		)
		(placement
			(enabled no)
			(sheetname "")
		)
		(fill
			(thermal_gap 0.5)
			(thermal_bridge_width 0.5)
			(island_removal_mode 0)
		)
		(polygon
			(pts
				(xy 212.270594 -136.774682) (xy 212.270594 -138.578082) (xy 212.829394 -138.578082) (xy 212.829394 -136.774682)
			)
		)
	)
	(zone
		(layer "In1.Cu")
		(hatch none 0.5)
		(connect_pads
			(clearance 0)
		)
		(min_thickness 0.25)
		(keepout
			(tracks not_allowed)
			(vias allowed)
			(pads allowed)
			(copperpour not_allowed)
			(footprints allowed)
		)
		(placement
			(enabled no)
			(sheetname "")
		)
		(fill
			(thermal_gap 0.5)
			(thermal_bridge_width 0.5)
			(island_removal_mode 0)
		)
		(polygon
			(pts
				(xy 147.569936 -155.977082) (xy 147.569936 -157.780482) (xy 148.128736 -157.780482) (xy 148.128736 -155.977082)
			)
		)
	)
	(zone
		(layer "In1.Cu")
		(hatch none 0.5)
		(connect_pads
			(clearance 0)
		)
		(min_thickness 0.25)
		(keepout
			(tracks not_allowed)
			(vias allowed)
			(pads allowed)
			(copperpour not_allowed)
			(footprints allowed)
		)
		(placement
			(enabled no)
			(sheetname "")
		)
		(fill
			(thermal_gap 0.5)
			(thermal_bridge_width 0.5)
			(island_removal_mode 0)
		)
		(polygon
			(pts
				(xy 89.76995 -19.121882) (xy 89.76995 -20.925282) (xy 90.32875 -20.925282) (xy 90.32875 -19.121882)
			)
		)
	)
	(zone
		(layer "In1.Cu")
		(hatch none 0.5)
		(connect_pads
			(clearance 0)
		)
		(min_thickness 0.25)
		(keepout
			(tracks not_allowed)
			(vias allowed)
			(pads allowed)
			(copperpour not_allowed)
			(footprints allowed)
		)
		(placement
			(enabled no)
			(sheetname "")
		)
		(fill
			(thermal_gap 0.5)
			(thermal_bridge_width 0.5)
			(island_removal_mode 0)
		)
		(polygon
			(pts
				(xy 44.720002 -14.521942) (xy 44.720002 -16.325342) (xy 45.278802 -16.325342) (xy 45.278802 -14.521942)
			)
		)
	)
	(zone
		(layer "In1.Cu")
		(hatch none 0.5)
		(connect_pads
			(clearance 0)
		)
		(min_thickness 0.25)
		(keepout
			(tracks not_allowed)
			(vias allowed)
			(pads allowed)
			(copperpour not_allowed)
			(footprints allowed)
		)
		(placement
			(enabled no)
			(sheetname "")
		)
		(fill
			(thermal_gap 0.5)
			(thermal_bridge_width 0.5)
			(island_removal_mode 0)
		)
		(polygon
			(pts
				(xy 308.32044 -9.520682) (xy 308.32044 -11.324082) (xy 308.87924 -11.324082) (xy 308.87924 -9.520682)
			)
		)
	)
	(zone
		(layer "In1.Cu")
		(hatch none 0.5)
		(connect_pads
			(clearance 0)
		)
		(min_thickness 0.25)
		(keepout
			(tracks not_allowed)
			(vias allowed)
			(pads allowed)
			(copperpour not_allowed)
			(footprints allowed)
		)
		(placement
			(enabled no)
			(sheetname "")
		)
		(fill
			(thermal_gap 0.5)
			(thermal_bridge_width 0.5)
			(island_removal_mode 0)
		)
		(polygon
			(pts
				(xy 64.270128 -19.121882) (xy 64.270128 -20.925282) (xy 64.828928 -20.925282) (xy 64.828928 -19.121882)
			)
		)
	)
	(zone
		(layer "In1.Cu")
		(hatch none 0.5)
		(connect_pads
			(clearance 0)
		)
		(min_thickness 0.25)
		(keepout
			(tracks not_allowed)
			(vias allowed)
			(pads allowed)
			(copperpour not_allowed)
			(footprints allowed)
		)
		(placement
			(enabled no)
			(sheetname "")
		)
		(fill
			(thermal_gap 0.5)
			(thermal_bridge_width 0.5)
			(island_removal_mode 0)
		)
		(polygon
			(pts
				(xy 267.52042 4.680458) (xy 267.52042 2.877058) (xy 268.07922 2.877058) (xy 268.07922 4.680458)
			)
		)
	)
	(zone
		(layer "In1.Cu")
		(hatch none 0.5)
		(connect_pads
			(clearance 0)
		)
		(min_thickness 0.25)
		(keepout
			(tracks not_allowed)
			(vias allowed)
			(pads allowed)
			(copperpour not_allowed)
			(footprints allowed)
		)
		(placement
			(enabled no)
			(sheetname "")
		)
		(fill
			(thermal_gap 0.5)
			(thermal_bridge_width 0.5)
			(island_removal_mode 0)
		)
		(polygon
			(pts
				(xy 57.47004 -151.377142) (xy 57.47004 -153.180542) (xy 58.02884 -153.180542) (xy 58.02884 -151.377142)
			)
		)
	)
	(zone
		(net "AGND_PVPP_KLM")
		(layer "In1.Cu")
		(hatch none 0.5)
		(connect_pads
			(clearance 0.5)
		)
		(min_thickness 0.25)
		(fill yes
			(thermal_gap 0.5)
			(thermal_bridge_width 0.5)
			(island_removal_mode 0)
		)
		(polygon
			(pts
				(xy 171.5262 -129.872994) (xy 171.5262 -131.550156) (xy 171.224956 -131.8514) (xy 170.793156 -131.8514)
				(xy 170.688 -131.956556) (xy 170.688 -132.482844) (xy 170.689016 -132.48386) (xy 170.689016 -132.601462)
				(xy 170.92041 -132.832856) (xy 173.070012 -132.832856) (xy 173.355 -133.117844) (xy 173.355 -134.006844)
				(xy 173.587156 -134.239) (xy 174.25924 -134.239) (xy 174.260256 -134.237984) (xy 177.69713 -134.237984)
				(xy 178.308 -133.627114) (xy 178.308 -133.26872) (xy 178.308 -132.185156) (xy 178.1556 -132.032756)
				(xy 178.1556 -129.797556) (xy 178.101244 -129.7432) (xy 172.462444 -129.7432) (xy 172.233844 -129.5146)
				(xy 171.872402 -129.5146) (xy 171.66463 -129.5146) (xy 171.5262 -129.65303)
			)
		)
	)
	(zone
		(layer "In1.Cu")
		(hatch none 0.5)
		(connect_pads
			(clearance 0)
		)
		(min_thickness 0.25)
		(keepout
			(tracks not_allowed)
			(vias allowed)
			(pads allowed)
			(copperpour not_allowed)
			(footprints allowed)
		)
		(placement
			(enabled no)
			(sheetname "")
		)
		(fill
			(thermal_gap 0.5)
			(thermal_bridge_width 0.5)
			(island_removal_mode 0)
		)
		(polygon
			(pts
				(xy 144.169892 -4.920742) (xy 144.169892 -6.724142) (xy 144.728692 -6.724142) (xy 144.728692 -4.920742)
			)
		)
	)
	(zone
		(layer "In1.Cu")
		(hatch none 0.5)
		(connect_pads
			(clearance 0)
		)
		(min_thickness 0.25)
		(keepout
			(tracks not_allowed)
			(vias allowed)
			(pads allowed)
			(copperpour not_allowed)
			(footprints allowed)
		)
		(placement
			(enabled no)
			(sheetname "")
		)
		(fill
			(thermal_gap 0.5)
			(thermal_bridge_width 0.5)
			(island_removal_mode 0)
		)
		(polygon
			(pts
				(xy 110.16996 -155.977082) (xy 110.16996 -157.780482) (xy 110.72876 -157.780482) (xy 110.72876 -155.977082)
			)
		)
	)
	(zone
		(layer "In1.Cu")
		(hatch none 0.5)
		(connect_pads
			(clearance 0)
		)
		(min_thickness 0.25)
		(keepout
			(tracks not_allowed)
			(vias allowed)
			(pads allowed)
			(copperpour not_allowed)
			(footprints allowed)
		)
		(placement
			(enabled no)
			(sheetname "")
		)
		(fill
			(thermal_gap 0.5)
			(thermal_bridge_width 0.5)
			(island_removal_mode 0)
		)
		(polygon
			(pts
				(xy 361.23118 -3.792982) (xy 362.539026 -3.792982) (xy 362.539026 -4.986782) (xy 361.23118 -4.986782)
			)
		)
	)
	(zone
		(layer "In1.Cu")
		(hatch none 0.5)
		(connect_pads
			(clearance 0)
		)
		(min_thickness 0.25)
		(keepout
			(tracks not_allowed)
			(vias allowed)
			(pads allowed)
			(copperpour not_allowed)
			(footprints allowed)
		)
		(placement
			(enabled no)
			(sheetname "")
		)
		(fill
			(thermal_gap 0.5)
			(thermal_bridge_width 0.5)
			(island_removal_mode 0)
		)
		(polygon
			(pts
				(xy 285.370524 -14.521942) (xy 285.370524 -16.325342) (xy 285.929324 -16.325342) (xy 285.929324 -14.521942)
			)
		)
	)
	(zone
		(layer "In1.Cu")
		(hatch none 0.5)
		(connect_pads
			(clearance 0)
		)
		(min_thickness 0.25)
		(keepout
			(tracks not_allowed)
			(vias allowed)
			(pads allowed)
			(copperpour not_allowed)
			(footprints allowed)
		)
		(placement
			(enabled no)
			(sheetname "")
		)
		(fill
			(thermal_gap 0.5)
			(thermal_bridge_width 0.5)
			(island_removal_mode 0)
		)
		(polygon
			(pts
				(xy 91.469972 -9.520682) (xy 91.469972 -11.324082) (xy 92.028772 -11.324082) (xy 92.028772 -9.520682)
			)
		)
	)
	(zone
		(layer "In1.Cu")
		(hatch none 0.5)
		(connect_pads
			(clearance 0)
		)
		(min_thickness 0.25)
		(keepout
			(tracks not_allowed)
			(vias allowed)
			(pads allowed)
			(copperpour not_allowed)
			(footprints allowed)
		)
		(placement
			(enabled no)
			(sheetname "")
		)
		(fill
			(thermal_gap 0.5)
			(thermal_bridge_width 0.5)
			(island_removal_mode 0)
		)
		(polygon
			(pts
				(xy 237.770416 -4.920742) (xy 237.770416 -6.724142) (xy 238.329216 -6.724142) (xy 238.329216 -4.920742)
			)
		)
	)
	(zone
		(layer "In1.Cu")
		(hatch none 0.5)
		(connect_pads
			(clearance 0)
		)
		(min_thickness 0.25)
		(keepout
			(tracks not_allowed)
			(vias allowed)
			(pads allowed)
			(copperpour not_allowed)
			(footprints allowed)
		)
		(placement
			(enabled no)
			(sheetname "")
		)
		(fill
			(thermal_gap 0.5)
			(thermal_bridge_width 0.5)
			(island_removal_mode 0)
		)
		(polygon
			(pts
				(xy 230.970582 -19.121882) (xy 230.970582 -20.925282) (xy 231.529382 -20.925282) (xy 231.529382 -19.121882)
			)
		)
	)
	(zone
		(layer "In1.Cu")
		(hatch none 0.5)
		(connect_pads
			(clearance 0)
		)
		(min_thickness 0.25)
		(keepout
			(tracks not_allowed)
			(vias allowed)
			(pads allowed)
			(copperpour not_allowed)
			(footprints allowed)
		)
		(placement
			(enabled no)
			(sheetname "")
		)
		(fill
			(thermal_gap 0.5)
			(thermal_bridge_width 0.5)
			(island_removal_mode 0)
		)
		(polygon
			(pts
				(xy 46.420024 -14.521942) (xy 46.420024 -16.325342) (xy 46.978824 -16.325342) (xy 46.978824 -14.521942)
			)
		)
	)
	(zone
		(layer "In1.Cu")
		(hatch none 0.5)
		(connect_pads
			(clearance 0)
		)
		(min_thickness 0.25)
		(keepout
			(tracks not_allowed)
			(vias allowed)
			(pads allowed)
			(copperpour not_allowed)
			(footprints allowed)
		)
		(placement
			(enabled no)
			(sheetname "")
		)
		(fill
			(thermal_gap 0.5)
			(thermal_bridge_width 0.5)
			(island_removal_mode 0)
		)
		(polygon
			(pts
				(xy 54.069996 -141.775942) (xy 54.069996 -143.579342) (xy 54.628796 -143.579342) (xy 54.628796 -141.775942)
			)
		)
	)
	(zone
		(layer "In1.Cu")
		(hatch none 0.5)
		(connect_pads
			(clearance 0)
		)
		(min_thickness 0.25)
		(keepout
			(tracks not_allowed)
			(vias allowed)
			(pads allowed)
			(copperpour not_allowed)
			(footprints allowed)
		)
		(placement
			(enabled no)
			(sheetname "")
		)
		(fill
			(thermal_gap 0.5)
			(thermal_bridge_width 0.5)
			(island_removal_mode 0)
		)
		(polygon
			(pts
				(xy 76.170282 -14.521942) (xy 76.170282 -16.325342) (xy 76.729082 -16.325342) (xy 76.729082 -14.521942)
			)
		)
	)
	(zone
		(layer "In1.Cu")
		(hatch none 0.5)
		(connect_pads
			(clearance 0)
		)
		(min_thickness 0.25)
		(keepout
			(tracks not_allowed)
			(vias allowed)
			(pads allowed)
			(copperpour not_allowed)
			(footprints allowed)
		)
		(placement
			(enabled no)
			(sheetname "")
		)
		(fill
			(thermal_gap 0.5)
			(thermal_bridge_width 0.5)
			(island_removal_mode 0)
		)
		(polygon
			(pts
				(xy 62.570106 -4.920742) (xy 62.570106 -6.724142) (xy 63.128906 -6.724142) (xy 63.128906 -4.920742)
			)
		)
	)
	(zone
		(layer "In1.Cu")
		(hatch none 0.5)
		(connect_pads
			(clearance 0)
		)
		(min_thickness 0.25)
		(keepout
			(tracks not_allowed)
			(vias allowed)
			(pads allowed)
			(copperpour not_allowed)
			(footprints allowed)
		)
		(placement
			(enabled no)
			(sheetname "")
		)
		(fill
			(thermal_gap 0.5)
			(thermal_bridge_width 0.5)
			(island_removal_mode 0)
		)
		(polygon
			(pts
				(xy 225.870516 -151.377142) (xy 225.870516 -153.180542) (xy 226.429316 -153.180542) (xy 226.429316 -151.377142)
			)
		)
	)
	(zone
		(layer "In1.Cu")
		(hatch none 0.5)
		(connect_pads
			(clearance 0)
		)
		(min_thickness 0.25)
		(keepout
			(tracks not_allowed)
			(vias allowed)
			(pads allowed)
			(copperpour not_allowed)
			(footprints allowed)
		)
		(placement
			(enabled no)
			(sheetname "")
		)
		(fill
			(thermal_gap 0.5)
			(thermal_bridge_width 0.5)
			(island_removal_mode 0)
		)
		(polygon
			(pts
				(xy 212.270594 -9.520682) (xy 212.270594 -11.324082) (xy 212.829394 -11.324082) (xy 212.829394 -9.520682)
			)
		)
	)
	(zone
		(layer "In1.Cu")
		(hatch none 0.5)
		(connect_pads
			(clearance 0)
		)
		(min_thickness 0.25)
		(keepout
			(tracks not_allowed)
			(vias allowed)
			(pads allowed)
			(copperpour not_allowed)
			(footprints allowed)
		)
		(placement
			(enabled no)
			(sheetname "")
		)
		(fill
			(thermal_gap 0.5)
			(thermal_bridge_width 0.5)
			(island_removal_mode 0)
		)
		(polygon
			(pts
				(xy 209.720434 -14.521942) (xy 209.720434 -16.325342) (xy 210.279234 -16.325342) (xy 210.279234 -14.521942)
			)
		)
	)
	(zone
		(layer "In1.Cu")
		(hatch none 0.5)
		(connect_pads
			(clearance 0)
		)
		(min_thickness 0.25)
		(keepout
			(tracks not_allowed)
			(vias allowed)
			(pads allowed)
			(copperpour not_allowed)
			(footprints allowed)
		)
		(placement
			(enabled no)
			(sheetname "")
		)
		(fill
			(thermal_gap 0.5)
			(thermal_bridge_width 0.5)
			(island_removal_mode 0)
		)
		(polygon
			(pts
				(xy 206.32039 0.080518) (xy 206.32039 -1.722882) (xy 206.87919 -1.722882) (xy 206.87919 0.080518)
			)
		)
	)
	(zone
		(layer "In1.Cu")
		(hatch none 0.5)
		(connect_pads
			(clearance 0)
		)
		(min_thickness 0.25)
		(keepout
			(tracks not_allowed)
			(vias allowed)
			(pads allowed)
			(copperpour not_allowed)
			(footprints allowed)
		)
		(placement
			(enabled no)
			(sheetname "")
		)
		(fill
			(thermal_gap 0.5)
			(thermal_bridge_width 0.5)
			(island_removal_mode 0)
		)
		(polygon
			(pts
				(xy 115.270026 -9.520682) (xy 115.270026 -11.324082) (xy 115.828826 -11.324082) (xy 115.828826 -9.520682)
			)
		)
	)
	(zone
		(layer "In1.Cu")
		(hatch none 0.5)
		(connect_pads
			(clearance 0)
		)
		(min_thickness 0.25)
		(keepout
			(tracks not_allowed)
			(vias allowed)
			(pads allowed)
			(copperpour not_allowed)
			(footprints allowed)
		)
		(placement
			(enabled no)
			(sheetname "")
		)
		(fill
			(thermal_gap 0.5)
			(thermal_bridge_width 0.5)
			(island_removal_mode 0)
		)
		(polygon
			(pts
				(xy 60.870084 -132.174742) (xy 60.870084 -133.978142) (xy 61.428884 -133.978142) (xy 61.428884 -132.174742)
			)
		)
	)
	(zone
		(layer "In1.Cu")
		(hatch none 0.5)
		(connect_pads
			(clearance 0)
		)
		(min_thickness 0.25)
		(keepout
			(tracks not_allowed)
			(vias allowed)
			(pads allowed)
			(copperpour not_allowed)
			(footprints allowed)
		)
		(placement
			(enabled no)
			(sheetname "")
		)
		(fill
			(thermal_gap 0.5)
			(thermal_bridge_width 0.5)
			(island_removal_mode 0)
		)
		(polygon
			(pts
				(xy 126.320042 -155.977082) (xy 126.320042 -157.780482) (xy 126.878842 -157.780482) (xy 126.878842 -155.977082)
			)
		)
	)
	(zone
		(layer "In1.Cu")
		(hatch none 0.5)
		(connect_pads
			(clearance 0)
		)
		(min_thickness 0.25)
		(keepout
			(tracks not_allowed)
			(vias allowed)
			(pads allowed)
			(copperpour not_allowed)
			(footprints allowed)
		)
		(placement
			(enabled no)
			(sheetname "")
		)
		(fill
			(thermal_gap 0.5)
			(thermal_bridge_width 0.5)
			(island_removal_mode 0)
		)
		(polygon
			(pts
				(xy 61.719968 -146.375882) (xy 61.719968 -148.179282) (xy 62.278768 -148.179282) (xy 62.278768 -146.375882)
			)
		)
	)
	(zone
		(layer "In1.Cu")
		(hatch none 0.5)
		(connect_pads
			(clearance 0)
		)
		(min_thickness 0.25)
		(keepout
			(tracks not_allowed)
			(vias allowed)
			(pads allowed)
			(copperpour not_allowed)
			(footprints allowed)
		)
		(placement
			(enabled no)
			(sheetname "")
		)
		(fill
			(thermal_gap 0.5)
			(thermal_bridge_width 0.5)
			(island_removal_mode 0)
		)
		(polygon
			(pts
				(xy 216.520522 -132.174742) (xy 216.520522 -133.978142) (xy 217.079322 -133.978142) (xy 217.079322 -132.174742)
			)
		)
	)
	(zone
		(layer "In1.Cu")
		(hatch none 0.5)
		(connect_pads
			(clearance 0)
		)
		(min_thickness 0.25)
		(keepout
			(tracks not_allowed)
			(vias allowed)
			(pads allowed)
			(copperpour not_allowed)
			(footprints allowed)
		)
		(placement
			(enabled no)
			(sheetname "")
		)
		(fill
			(thermal_gap 0.5)
			(thermal_bridge_width 0.5)
			(island_removal_mode 0)
		)
		(polygon
			(pts
				(xy 77.87005 -132.174742) (xy 77.87005 -133.978142) (xy 78.42885 -133.978142) (xy 78.42885 -132.174742)
			)
		)
	)
	(zone
		(layer "In1.Cu")
		(hatch none 0.5)
		(connect_pads
			(clearance 0)
		)
		(min_thickness 0.25)
		(keepout
			(tracks not_allowed)
			(vias allowed)
			(pads allowed)
			(copperpour not_allowed)
			(footprints allowed)
		)
		(placement
			(enabled no)
			(sheetname "")
		)
		(fill
			(thermal_gap 0.5)
			(thermal_bridge_width 0.5)
			(island_removal_mode 0)
		)
		(polygon
			(pts
				(xy 307.470302 -141.775942) (xy 307.470302 -143.579342) (xy 308.029102 -143.579342) (xy 308.029102 -141.775942)
			)
		)
	)
	(zone
		(layer "In1.Cu")
		(hatch none 0.5)
		(connect_pads
			(clearance 0)
		)
		(min_thickness 0.25)
		(keepout
			(tracks not_allowed)
			(vias allowed)
			(pads allowed)
			(copperpour not_allowed)
			(footprints allowed)
		)
		(placement
			(enabled no)
			(sheetname "")
		)
		(fill
			(thermal_gap 0.5)
			(thermal_bridge_width 0.5)
			(island_removal_mode 0)
		)
		(polygon
			(pts
				(xy 251.370592 -141.775942) (xy 251.370592 -143.579342) (xy 251.929392 -143.579342) (xy 251.929392 -141.775942)
			)
		)
	)
	(zone
		(layer "In1.Cu")
		(hatch none 0.5)
		(connect_pads
			(clearance 0)
		)
		(min_thickness 0.25)
		(keepout
			(tracks not_allowed)
			(vias allowed)
			(pads allowed)
			(copperpour not_allowed)
			(footprints allowed)
		)
		(placement
			(enabled no)
			(sheetname "")
		)
		(fill
			(thermal_gap 0.5)
			(thermal_bridge_width 0.5)
			(island_removal_mode 0)
		)
		(polygon
			(pts
				(xy 89.76995 -151.377142) (xy 89.76995 -153.180542) (xy 90.32875 -153.180542) (xy 90.32875 -151.377142)
			)
		)
	)
	(zone
		(layer "In1.Cu")
		(hatch none 0.5)
		(connect_pads
			(clearance 0)
		)
		(min_thickness 0.25)
		(keepout
			(tracks not_allowed)
			(vias allowed)
			(pads allowed)
			(copperpour not_allowed)
			(footprints allowed)
		)
		(placement
			(enabled no)
			(sheetname "")
		)
		(fill
			(thermal_gap 0.5)
			(thermal_bridge_width 0.5)
			(island_removal_mode 0)
		)
		(polygon
			(pts
				(xy 207.170528 4.680458) (xy 207.170528 2.877058) (xy 207.729328 2.877058) (xy 207.729328 4.680458)
			)
		)
	)
	(zone
		(layer "In1.Cu")
		(hatch none 0.5)
		(connect_pads
			(clearance 0)
		)
		(min_thickness 0.25)
		(keepout
			(tracks not_allowed)
			(vias allowed)
			(pads allowed)
			(copperpour not_allowed)
			(footprints allowed)
		)
		(placement
			(enabled no)
			(sheetname "")
		)
		(fill
			(thermal_gap 0.5)
			(thermal_bridge_width 0.5)
			(island_removal_mode 0)
		)
		(polygon
			(pts
				(xy 315.120528 -151.377142) (xy 315.120528 -153.180542) (xy 315.679328 -153.180542) (xy 315.679328 -151.377142)
			)
		)
	)
	(zone
		(layer "In1.Cu")
		(hatch none 0.5)
		(connect_pads
			(clearance 0)
		)
		(min_thickness 0.25)
		(keepout
			(tracks not_allowed)
			(vias allowed)
			(pads allowed)
			(copperpour not_allowed)
			(footprints allowed)
		)
		(placement
			(enabled no)
			(sheetname "")
		)
		(fill
			(thermal_gap 0.5)
			(thermal_bridge_width 0.5)
			(island_removal_mode 0)
		)
		(polygon
			(pts
				(xy 49.820068 -141.775942) (xy 49.820068 -143.579342) (xy 50.378868 -143.579342) (xy 50.378868 -141.775942)
			)
		)
	)
	(zone
		(layer "In1.Cu")
		(hatch none 0.5)
		(connect_pads
			(clearance 0)
		)
		(min_thickness 0.25)
		(keepout
			(tracks not_allowed)
			(vias allowed)
			(pads allowed)
			(copperpour not_allowed)
			(footprints allowed)
		)
		(placement
			(enabled no)
			(sheetname "")
		)
		(fill
			(thermal_gap 0.5)
			(thermal_bridge_width 0.5)
			(island_removal_mode 0)
		)
		(polygon
			(pts
				(xy 208.87055 -4.920742) (xy 208.87055 -6.724142) (xy 209.42935 -6.724142) (xy 209.42935 -4.920742)
			)
		)
	)
	(zone
		(layer "In1.Cu")
		(hatch none 0.5)
		(connect_pads
			(clearance 0)
		)
		(min_thickness 0.25)
		(keepout
			(tracks not_allowed)
			(vias allowed)
			(pads allowed)
			(copperpour not_allowed)
			(footprints allowed)
		)
		(placement
			(enabled no)
			(sheetname "")
		)
		(fill
			(thermal_gap 0.5)
			(thermal_bridge_width 0.5)
			(island_removal_mode 0)
		)
		(polygon
			(pts
				(xy 78.719934 -146.375882) (xy 78.719934 -148.179282) (xy 79.278734 -148.179282) (xy 79.278734 -146.375882)
			)
		)
	)
	(zone
		(layer "In1.Cu")
		(hatch none 0.5)
		(connect_pads
			(clearance 0)
		)
		(min_thickness 0.25)
		(keepout
			(tracks not_allowed)
			(vias allowed)
			(pads allowed)
			(copperpour not_allowed)
			(footprints allowed)
		)
		(placement
			(enabled no)
			(sheetname "")
		)
		(fill
			(thermal_gap 0.5)
			(thermal_bridge_width 0.5)
			(island_removal_mode 0)
		)
		(polygon
			(pts
				(xy 254.770382 -141.775942) (xy 254.770382 -143.579342) (xy 255.329182 -143.579342) (xy 255.329182 -141.775942)
			)
		)
	)
	(zone
		(layer "In1.Cu")
		(hatch none 0.5)
		(connect_pads
			(clearance 0)
		)
		(min_thickness 0.25)
		(keepout
			(tracks not_allowed)
			(vias allowed)
			(pads allowed)
			(copperpour not_allowed)
			(footprints allowed)
		)
		(placement
			(enabled no)
			(sheetname "")
		)
		(fill
			(thermal_gap 0.5)
			(thermal_bridge_width 0.5)
			(island_removal_mode 0)
		)
		(polygon
			(pts
				(xy 112.72012 -141.775942) (xy 112.72012 -143.579342) (xy 113.27892 -143.579342) (xy 113.27892 -141.775942)
			)
		)
	)
	(zone
		(layer "In1.Cu")
		(hatch none 0.5)
		(connect_pads
			(clearance 0)
		)
		(min_thickness 0.25)
		(keepout
			(tracks not_allowed)
			(vias allowed)
			(pads allowed)
			(copperpour not_allowed)
			(footprints allowed)
		)
		(placement
			(enabled no)
			(sheetname "")
		)
		(fill
			(thermal_gap 0.5)
			(thermal_bridge_width 0.5)
			(island_removal_mode 0)
		)
		(polygon
			(pts
				(xy 270.07058 -141.775942) (xy 270.07058 -143.579342) (xy 270.62938 -143.579342) (xy 270.62938 -141.775942)
			)
		)
	)
	(zone
		(layer "In1.Cu")
		(hatch none 0.5)
		(connect_pads
			(clearance 0)
		)
		(min_thickness 0.25)
		(keepout
			(tracks not_allowed)
			(vias allowed)
			(pads allowed)
			(copperpour not_allowed)
			(footprints allowed)
		)
		(placement
			(enabled no)
			(sheetname "")
		)
		(fill
			(thermal_gap 0.5)
			(thermal_bridge_width 0.5)
			(island_removal_mode 0)
		)
		(polygon
			(pts
				(xy 205.470506 -14.521942) (xy 205.470506 -16.325342) (xy 206.029306 -16.325342) (xy 206.029306 -14.521942)
			)
		)
	)
	(zone
		(layer "In1.Cu")
		(hatch none 0.5)
		(connect_pads
			(clearance 0)
		)
		(min_thickness 0.25)
		(keepout
			(tracks not_allowed)
			(vias allowed)
			(pads allowed)
			(copperpour not_allowed)
			(footprints allowed)
		)
		(placement
			(enabled no)
			(sheetname "")
		)
		(fill
			(thermal_gap 0.5)
			(thermal_bridge_width 0.5)
			(island_removal_mode 0)
		)
		(polygon
			(pts
				(xy 200.37044 -136.774682) (xy 200.37044 -138.578082) (xy 200.92924 -138.578082) (xy 200.92924 -136.774682)
			)
		)
	)
	(zone
		(layer "In1.Cu")
		(hatch none 0.5)
		(connect_pads
			(clearance 0)
		)
		(min_thickness 0.25)
		(keepout
			(tracks not_allowed)
			(vias allowed)
			(pads allowed)
			(copperpour not_allowed)
			(footprints allowed)
		)
		(placement
			(enabled no)
			(sheetname "")
		)
		(fill
			(thermal_gap 0.5)
			(thermal_bridge_width 0.5)
			(island_removal_mode 0)
		)
		(polygon
			(pts
				(xy 99.970082 -155.977082) (xy 99.970082 -157.780482) (xy 100.528882 -157.780482) (xy 100.528882 -155.977082)
			)
		)
	)
	(zone
		(layer "In1.Cu")
		(hatch none 0.5)
		(connect_pads
			(clearance 0)
		)
		(min_thickness 0.25)
		(keepout
			(tracks not_allowed)
			(vias allowed)
			(pads allowed)
			(copperpour not_allowed)
			(footprints allowed)
		)
		(placement
			(enabled no)
			(sheetname "")
		)
		(fill
			(thermal_gap 0.5)
			(thermal_bridge_width 0.5)
			(island_removal_mode 0)
		)
		(polygon
			(pts
				(xy 200.37044 -14.521942) (xy 200.37044 -16.325342) (xy 200.92924 -16.325342) (xy 200.92924 -14.521942)
			)
		)
	)
	(zone
		(layer "In1.Cu")
		(hatch none 0.5)
		(connect_pads
			(clearance 0)
		)
		(min_thickness 0.25)
		(keepout
			(tracks not_allowed)
			(vias allowed)
			(pads allowed)
			(copperpour not_allowed)
			(footprints allowed)
		)
		(placement
			(enabled no)
			(sheetname "")
		)
		(fill
			(thermal_gap 0.5)
			(thermal_bridge_width 0.5)
			(island_removal_mode 0)
		)
		(polygon
			(pts
				(xy 231.820466 -14.521942) (xy 231.820466 -16.325342) (xy 232.379266 -16.325342) (xy 232.379266 -14.521942)
			)
		)
	)
	(zone
		(layer "In1.Cu")
		(hatch none 0.5)
		(connect_pads
			(clearance 0)
		)
		(min_thickness 0.25)
		(keepout
			(tracks not_allowed)
			(vias allowed)
			(pads allowed)
			(copperpour not_allowed)
			(footprints allowed)
		)
		(placement
			(enabled no)
			(sheetname "")
		)
		(fill
			(thermal_gap 0.5)
			(thermal_bridge_width 0.5)
			(island_removal_mode 0)
		)
		(polygon
			(pts
				(xy 295.570402 -9.520682) (xy 295.570402 -11.324082) (xy 296.129202 -11.324082) (xy 296.129202 -9.520682)
			)
		)
	)
	(zone
		(layer "In1.Cu")
		(hatch none 0.5)
		(connect_pads
			(clearance 0)
		)
		(min_thickness 0.25)
		(keepout
			(tracks not_allowed)
			(vias allowed)
			(pads allowed)
			(copperpour not_allowed)
			(footprints allowed)
		)
		(placement
			(enabled no)
			(sheetname "")
		)
		(fill
			(thermal_gap 0.5)
			(thermal_bridge_width 0.5)
			(island_removal_mode 0)
		)
		(polygon
			(pts
				(xy 84.670138 -151.377142) (xy 84.670138 -153.180542) (xy 85.228938 -153.180542) (xy 85.228938 -151.377142)
			)
		)
	)
	(zone
		(layer "In1.Cu")
		(hatch none 0.5)
		(connect_pads
			(clearance 0)
		)
		(min_thickness 0.25)
		(keepout
			(tracks not_allowed)
			(vias allowed)
			(pads allowed)
			(copperpour not_allowed)
			(footprints allowed)
		)
		(placement
			(enabled no)
			(sheetname "")
		)
		(fill
			(thermal_gap 0.5)
			(thermal_bridge_width 0.5)
			(island_removal_mode 0)
		)
		(polygon
			(pts
				(xy 130.56997 -9.520682) (xy 130.56997 -11.324082) (xy 131.12877 -11.324082) (xy 131.12877 -9.520682)
			)
		)
	)
	(zone
		(layer "In1.Cu")
		(hatch none 0.5)
		(connect_pads
			(clearance 0)
		)
		(min_thickness 0.25)
		(keepout
			(tracks not_allowed)
			(vias allowed)
			(pads allowed)
			(copperpour not_allowed)
			(footprints allowed)
		)
		(placement
			(enabled no)
			(sheetname "")
		)
		(fill
			(thermal_gap 0.5)
			(thermal_bridge_width 0.5)
			(island_removal_mode 0)
		)
		(polygon
			(pts
				(xy 91.469972 -4.920742) (xy 91.469972 -6.724142) (xy 92.028772 -6.724142) (xy 92.028772 -4.920742)
			)
		)
	)
	(zone
		(layer "In1.Cu")
		(hatch none 0.5)
		(connect_pads
			(clearance 0)
		)
		(min_thickness 0.25)
		(keepout
			(tracks not_allowed)
			(vias allowed)
			(pads allowed)
			(copperpour not_allowed)
			(footprints allowed)
		)
		(placement
			(enabled no)
			(sheetname "")
		)
		(fill
			(thermal_gap 0.5)
			(thermal_bridge_width 0.5)
			(island_removal_mode 0)
		)
		(polygon
			(pts
				(xy 103.370126 -4.920742) (xy 103.370126 -6.724142) (xy 103.928926 -6.724142) (xy 103.928926 -4.920742)
			)
		)
	)
	(zone
		(layer "In1.Cu")
		(hatch none 0.5)
		(connect_pads
			(clearance 0)
		)
		(min_thickness 0.25)
		(keepout
			(tracks not_allowed)
			(vias allowed)
			(pads allowed)
			(copperpour not_allowed)
			(footprints allowed)
		)
		(placement
			(enabled no)
			(sheetname "")
		)
		(fill
			(thermal_gap 0.5)
			(thermal_bridge_width 0.5)
			(island_removal_mode 0)
		)
		(polygon
			(pts
				(xy 117.819932 -141.775942) (xy 117.819932 -143.579342) (xy 118.378732 -143.579342) (xy 118.378732 -141.775942)
			)
		)
	)
	(zone
		(layer "In1.Cu")
		(hatch none 0.5)
		(connect_pads
			(clearance 0)
		)
		(min_thickness 0.25)
		(keepout
			(tracks not_allowed)
			(vias allowed)
			(pads allowed)
			(copperpour not_allowed)
			(footprints allowed)
		)
		(placement
			(enabled no)
			(sheetname "")
		)
		(fill
			(thermal_gap 0.5)
			(thermal_bridge_width 0.5)
			(island_removal_mode 0)
		)
		(polygon
			(pts
				(xy 276.02053 -9.520682) (xy 276.02053 -11.324082) (xy 276.57933 -11.324082) (xy 276.57933 -9.520682)
			)
		)
	)
	(zone
		(layer "In1.Cu")
		(hatch none 0.5)
		(connect_pads
			(clearance 0)
		)
		(min_thickness 0.25)
		(keepout
			(tracks not_allowed)
			(vias allowed)
			(pads allowed)
			(copperpour not_allowed)
			(footprints allowed)
		)
		(placement
			(enabled no)
			(sheetname "")
		)
		(fill
			(thermal_gap 0.5)
			(thermal_bridge_width 0.5)
			(island_removal_mode 0)
		)
		(polygon
			(pts
				(xy 38.770052 -4.920742) (xy 38.770052 -6.724142) (xy 39.328852 -6.724142) (xy 39.328852 -4.920742)
			)
		)
	)
	(zone
		(layer "In1.Cu")
		(hatch none 0.5)
		(connect_pads
			(clearance 0)
		)
		(min_thickness 0.25)
		(keepout
			(tracks not_allowed)
			(vias allowed)
			(pads allowed)
			(copperpour not_allowed)
			(footprints allowed)
		)
		(placement
			(enabled no)
			(sheetname "")
		)
		(fill
			(thermal_gap 0.5)
			(thermal_bridge_width 0.5)
			(island_removal_mode 0)
		)
		(polygon
			(pts
				(xy 290.470336 -151.377142) (xy 290.470336 -153.180542) (xy 291.029136 -153.180542) (xy 291.029136 -151.377142)
			)
		)
	)
	(zone
		(layer "In1.Cu")
		(hatch none 0.5)
		(connect_pads
			(clearance 0)
		)
		(min_thickness 0.25)
		(keepout
			(tracks not_allowed)
			(vias allowed)
			(pads allowed)
			(copperpour not_allowed)
			(footprints allowed)
		)
		(placement
			(enabled no)
			(sheetname "")
		)
		(fill
			(thermal_gap 0.5)
			(thermal_bridge_width 0.5)
			(island_removal_mode 0)
		)
		(polygon
			(pts
				(xy 284.520386 0.080518) (xy 284.520386 -1.722882) (xy 285.079186 -1.722882) (xy 285.079186 0.080518)
			)
		)
	)
	(zone
		(layer "In1.Cu")
		(hatch none 0.5)
		(connect_pads
			(clearance 0)
		)
		(min_thickness 0.25)
		(keepout
			(tracks not_allowed)
			(vias allowed)
			(pads allowed)
			(copperpour not_allowed)
			(footprints allowed)
		)
		(placement
			(enabled no)
			(sheetname "")
		)
		(fill
			(thermal_gap 0.5)
			(thermal_bridge_width 0.5)
			(island_removal_mode 0)
		)
		(polygon
			(pts
				(xy 277.720552 4.680458) (xy 277.720552 2.877058) (xy 278.279352 2.877058) (xy 278.279352 4.680458)
			)
		)
	)
	(zone
		(layer "In1.Cu")
		(hatch none 0.5)
		(connect_pads
			(clearance 0)
		)
		(min_thickness 0.25)
		(keepout
			(tracks not_allowed)
			(vias allowed)
			(pads allowed)
			(copperpour not_allowed)
			(footprints allowed)
		)
		(placement
			(enabled no)
			(sheetname "")
		)
		(fill
			(thermal_gap 0.5)
			(thermal_bridge_width 0.5)
			(island_removal_mode 0)
		)
		(polygon
			(pts
				(xy 409.818586 -7.192772) (xy 411.126686 -7.192772) (xy 411.126686 -8.386572) (xy 409.818586 -8.386572)
			)
		)
	)
	(zone
		(layer "In1.Cu")
		(hatch none 0.5)
		(connect_pads
			(clearance 0)
		)
		(min_thickness 0.25)
		(keepout
			(tracks not_allowed)
			(vias allowed)
			(pads allowed)
			(copperpour not_allowed)
			(footprints allowed)
		)
		(placement
			(enabled no)
			(sheetname "")
		)
		(fill
			(thermal_gap 0.5)
			(thermal_bridge_width 0.5)
			(island_removal_mode 0)
		)
		(polygon
			(pts
				(xy 308.32044 -19.121882) (xy 308.32044 -20.925282) (xy 308.87924 -20.925282) (xy 308.87924 -19.121882)
			)
		)
	)
	(zone
		(layer "In1.Cu")
		(hatch none 0.5)
		(connect_pads
			(clearance 0)
		)
		(min_thickness 0.25)
		(keepout
			(tracks not_allowed)
			(vias allowed)
			(pads allowed)
			(copperpour not_allowed)
			(footprints allowed)
		)
		(placement
			(enabled no)
			(sheetname "")
		)
		(fill
			(thermal_gap 0.5)
			(thermal_bridge_width 0.5)
			(island_removal_mode 0)
		)
		(polygon
			(pts
				(xy 64.270128 -136.774682) (xy 64.270128 -138.578082) (xy 64.828928 -138.578082) (xy 64.828928 -136.774682)
			)
		)
	)
	(zone
		(layer "In1.Cu")
		(hatch none 0.5)
		(connect_pads
			(clearance 0)
		)
		(min_thickness 0.25)
		(keepout
			(tracks not_allowed)
			(vias allowed)
			(pads allowed)
			(copperpour not_allowed)
			(footprints allowed)
		)
		(placement
			(enabled no)
			(sheetname "")
		)
		(fill
			(thermal_gap 0.5)
			(thermal_bridge_width 0.5)
			(island_removal_mode 0)
		)
		(polygon
			(pts
				(xy 81.270094 -4.920742) (xy 81.270094 -6.724142) (xy 81.828894 -6.724142) (xy 81.828894 -4.920742)
			)
		)
	)
	(zone
		(layer "In1.Cu")
		(hatch none 0.5)
		(connect_pads
			(clearance 0)
		)
		(min_thickness 0.25)
		(keepout
			(tracks not_allowed)
			(vias allowed)
			(pads allowed)
			(copperpour not_allowed)
			(footprints allowed)
		)
		(placement
			(enabled no)
			(sheetname "")
		)
		(fill
			(thermal_gap 0.5)
			(thermal_bridge_width 0.5)
			(island_removal_mode 0)
		)
		(polygon
			(pts
				(xy 115.270026 -146.375882) (xy 115.270026 -148.179282) (xy 115.828826 -148.179282) (xy 115.828826 -146.375882)
			)
		)
	)
	(zone
		(layer "In1.Cu")
		(hatch none 0.5)
		(connect_pads
			(clearance 0)
		)
		(min_thickness 0.25)
		(keepout
			(tracks not_allowed)
			(vias allowed)
			(pads allowed)
			(copperpour not_allowed)
			(footprints allowed)
		)
		(placement
			(enabled no)
			(sheetname "")
		)
		(fill
			(thermal_gap 0.5)
			(thermal_bridge_width 0.5)
			(island_removal_mode 0)
		)
		(polygon
			(pts
				(xy 66.820034 -14.521942) (xy 66.820034 -16.325342) (xy 67.378834 -16.325342) (xy 67.378834 -14.521942)
			)
		)
	)
	(zone
		(layer "In1.Cu")
		(hatch none 0.5)
		(connect_pads
			(clearance 0)
		)
		(min_thickness 0.25)
		(keepout
			(tracks not_allowed)
			(vias allowed)
			(pads allowed)
			(copperpour not_allowed)
			(footprints allowed)
		)
		(placement
			(enabled no)
			(sheetname "")
		)
		(fill
			(thermal_gap 0.5)
			(thermal_bridge_width 0.5)
			(island_removal_mode 0)
		)
		(polygon
			(pts
				(xy 84.670138 -136.774682) (xy 84.670138 -138.578082) (xy 85.228938 -138.578082) (xy 85.228938 -136.774682)
			)
		)
	)
	(zone
		(layer "In1.Cu")
		(hatch none 0.5)
		(connect_pads
			(clearance 0)
		)
		(min_thickness 0.25)
		(keepout
			(tracks not_allowed)
			(vias allowed)
			(pads allowed)
			(copperpour not_allowed)
			(footprints allowed)
		)
		(placement
			(enabled no)
			(sheetname "")
		)
		(fill
			(thermal_gap 0.5)
			(thermal_bridge_width 0.5)
			(island_removal_mode 0)
		)
		(polygon
			(pts
				(xy 277.720552 -132.174742) (xy 277.720552 -133.978142) (xy 278.279352 -133.978142) (xy 278.279352 -132.174742)
			)
		)
	)
	(zone
		(layer "In1.Cu")
		(hatch none 0.5)
		(connect_pads
			(clearance 0)
		)
		(min_thickness 0.25)
		(keepout
			(tracks not_allowed)
			(vias allowed)
			(pads allowed)
			(copperpour not_allowed)
			(footprints allowed)
		)
		(placement
			(enabled no)
			(sheetname "")
		)
		(fill
			(thermal_gap 0.5)
			(thermal_bridge_width 0.5)
			(island_removal_mode 0)
		)
		(polygon
			(pts
				(xy 13.6398 -24.765) (xy 15.0368 -24.765) (xy 15.0368 -25.273) (xy 13.6398 -25.273)
			)
		)
	)
	(zone
		(layer "In1.Cu")
		(hatch none 0.5)
		(connect_pads
			(clearance 0)
		)
		(min_thickness 0.25)
		(keepout
			(tracks not_allowed)
			(vias allowed)
			(pads allowed)
			(copperpour not_allowed)
			(footprints allowed)
		)
		(placement
			(enabled no)
			(sheetname "")
		)
		(fill
			(thermal_gap 0.5)
			(thermal_bridge_width 0.5)
			(island_removal_mode 0)
		)
		(polygon
			(pts
				(xy 213.970362 -136.774682) (xy 213.970362 -138.578082) (xy 214.529162 -138.578082) (xy 214.529162 -136.774682)
			)
		)
	)
	(zone
		(layer "In1.Cu")
		(hatch none 0.5)
		(connect_pads
			(clearance 0)
		)
		(min_thickness 0.25)
		(keepout
			(tracks not_allowed)
			(vias allowed)
			(pads allowed)
			(copperpour not_allowed)
			(footprints allowed)
		)
		(placement
			(enabled no)
			(sheetname "")
		)
		(fill
			(thermal_gap 0.5)
			(thermal_bridge_width 0.5)
			(island_removal_mode 0)
		)
		(polygon
			(pts
				(xy 138.219942 -136.774682) (xy 138.219942 -138.578082) (xy 138.778742 -138.578082) (xy 138.778742 -136.774682)
			)
		)
	)
	(zone
		(layer "In1.Cu")
		(hatch none 0.5)
		(connect_pads
			(clearance 0)
		)
		(min_thickness 0.25)
		(keepout
			(tracks not_allowed)
			(vias allowed)
			(pads allowed)
			(copperpour not_allowed)
			(footprints allowed)
		)
		(placement
			(enabled no)
			(sheetname "")
		)
		(fill
			(thermal_gap 0.5)
			(thermal_bridge_width 0.5)
			(island_removal_mode 0)
		)
		(polygon
			(pts
				(xy 307.470302 -14.521942) (xy 307.470302 -16.325342) (xy 308.029102 -16.325342) (xy 308.029102 -14.521942)
			)
		)
	)
	(zone
		(layer "In1.Cu")
		(hatch none 0.5)
		(connect_pads
			(clearance 0)
		)
		(min_thickness 0.25)
		(keepout
			(tracks not_allowed)
			(vias allowed)
			(pads allowed)
			(copperpour not_allowed)
			(footprints allowed)
		)
		(placement
			(enabled no)
			(sheetname "")
		)
		(fill
			(thermal_gap 0.5)
			(thermal_bridge_width 0.5)
			(island_removal_mode 0)
		)
		(polygon
			(pts
				(xy 305.770534 -132.174742) (xy 305.770534 -133.978142) (xy 306.329334 -133.978142) (xy 306.329334 -132.174742)
			)
		)
	)
	(zone
		(layer "In1.Cu")
		(hatch none 0.5)
		(connect_pads
			(clearance 0)
		)
		(min_thickness 0.25)
		(keepout
			(tracks not_allowed)
			(vias allowed)
			(pads allowed)
			(copperpour not_allowed)
			(footprints allowed)
		)
		(placement
			(enabled no)
			(sheetname "")
		)
		(fill
			(thermal_gap 0.5)
			(thermal_bridge_width 0.5)
			(island_removal_mode 0)
		)
		(polygon
			(pts
				(xy 69.36994 -9.520682) (xy 69.36994 -11.324082) (xy 69.92874 -11.324082) (xy 69.92874 -9.520682)
			)
		)
	)
	(zone
		(layer "In1.Cu")
		(hatch none 0.5)
		(connect_pads
			(clearance 0)
		)
		(min_thickness 0.25)
		(keepout
			(tracks not_allowed)
			(vias allowed)
			(pads allowed)
			(copperpour not_allowed)
			(footprints allowed)
		)
		(placement
			(enabled no)
			(sheetname "")
		)
		(fill
			(thermal_gap 0.5)
			(thermal_bridge_width 0.5)
			(island_removal_mode 0)
		)
		(polygon
			(pts
				(xy 134.819898 -132.174742) (xy 134.819898 -133.978142) (xy 135.378698 -133.978142) (xy 135.378698 -132.174742)
			)
		)
	)
	(zone
		(layer "In1.Cu")
		(hatch none 0.5)
		(connect_pads
			(clearance 0)
		)
		(min_thickness 0.25)
		(keepout
			(tracks not_allowed)
			(vias allowed)
			(pads allowed)
			(copperpour not_allowed)
			(footprints allowed)
		)
		(placement
			(enabled no)
			(sheetname "")
		)
		(fill
			(thermal_gap 0.5)
			(thermal_bridge_width 0.5)
			(island_removal_mode 0)
		)
		(polygon
			(pts
				(xy 219.070428 4.680458) (xy 219.070428 2.877058) (xy 219.629228 2.877058) (xy 219.629228 4.680458)
			)
		)
	)
	(zone
		(layer "In1.Cu")
		(hatch none 0.5)
		(connect_pads
			(clearance 0)
		)
		(min_thickness 0.25)
		(keepout
			(tracks not_allowed)
			(vias allowed)
			(pads allowed)
			(copperpour not_allowed)
			(footprints allowed)
		)
		(placement
			(enabled no)
			(sheetname "")
		)
		(fill
			(thermal_gap 0.5)
			(thermal_bridge_width 0.5)
			(island_removal_mode 0)
		)
		(polygon
			(pts
				(xy 270.07058 -14.521942) (xy 270.07058 -16.325342) (xy 270.62938 -16.325342) (xy 270.62938 -14.521942)
			)
		)
	)
	(zone
		(layer "In1.Cu")
		(hatch none 0.5)
		(connect_pads
			(clearance 0)
		)
		(min_thickness 0.25)
		(keepout
			(tracks not_allowed)
			(vias allowed)
			(pads allowed)
			(copperpour not_allowed)
			(footprints allowed)
		)
		(placement
			(enabled no)
			(sheetname "")
		)
		(fill
			(thermal_gap 0.5)
			(thermal_bridge_width 0.5)
			(island_removal_mode 0)
		)
		(polygon
			(pts
				(xy 127.169926 -141.775942) (xy 127.169926 -143.579342) (xy 127.728726 -143.579342) (xy 127.728726 -141.775942)
			)
		)
	)
	(zone
		(layer "In1.Cu")
		(hatch none 0.5)
		(connect_pads
			(clearance 0)
		)
		(min_thickness 0.25)
		(keepout
			(tracks not_allowed)
			(vias allowed)
			(pads allowed)
			(copperpour not_allowed)
			(footprints allowed)
		)
		(placement
			(enabled no)
			(sheetname "")
		)
		(fill
			(thermal_gap 0.5)
			(thermal_bridge_width 0.5)
			(island_removal_mode 0)
		)
		(polygon
			(pts
				(xy 214.8205 -151.377142) (xy 214.8205 -153.180542) (xy 215.3793 -153.180542) (xy 215.3793 -151.377142)
			)
		)
	)
	(zone
		(layer "In1.Cu")
		(hatch none 0.5)
		(connect_pads
			(clearance 0)
		)
		(min_thickness 0.25)
		(keepout
			(tracks not_allowed)
			(vias allowed)
			(pads allowed)
			(copperpour not_allowed)
			(footprints allowed)
		)
		(placement
			(enabled no)
			(sheetname "")
		)
		(fill
			(thermal_gap 0.5)
			(thermal_bridge_width 0.5)
			(island_removal_mode 0)
		)
		(polygon
			(pts
				(xy 141.619986 -19.121882) (xy 141.619986 -20.925282) (xy 142.178786 -20.925282) (xy 142.178786 -19.121882)
			)
		)
	)
	(zone
		(layer "In1.Cu")
		(hatch none 0.5)
		(connect_pads
			(clearance 0)
		)
		(min_thickness 0.25)
		(keepout
			(tracks not_allowed)
			(vias allowed)
			(pads allowed)
			(copperpour not_allowed)
			(footprints allowed)
		)
		(placement
			(enabled no)
			(sheetname "")
		)
		(fill
			(thermal_gap 0.5)
			(thermal_bridge_width 0.5)
			(island_removal_mode 0)
		)
		(polygon
			(pts
				(xy 35.370008 -155.977082) (xy 35.370008 -157.780482) (xy 35.928808 -157.780482) (xy 35.928808 -155.977082)
			)
		)
	)
	(zone
		(layer "In1.Cu")
		(hatch none 0.5)
		(connect_pads
			(clearance 0)
		)
		(min_thickness 0.25)
		(keepout
			(tracks not_allowed)
			(vias allowed)
			(pads allowed)
			(copperpour not_allowed)
			(footprints allowed)
		)
		(placement
			(enabled no)
			(sheetname "")
		)
		(fill
			(thermal_gap 0.5)
			(thermal_bridge_width 0.5)
			(island_removal_mode 0)
		)
		(polygon
			(pts
				(xy 47.270162 -19.121882) (xy 47.270162 -20.925282) (xy 47.828962 -20.925282) (xy 47.828962 -19.121882)
			)
		)
	)
	(zone
		(layer "In1.Cu")
		(hatch none 0.5)
		(connect_pads
			(clearance 0)
		)
		(min_thickness 0.25)
		(keepout
			(tracks not_allowed)
			(vias allowed)
			(pads allowed)
			(copperpour not_allowed)
			(footprints allowed)
		)
		(placement
			(enabled no)
			(sheetname "")
		)
		(fill
			(thermal_gap 0.5)
			(thermal_bridge_width 0.5)
			(island_removal_mode 0)
		)
		(polygon
			(pts
				(xy 77.87005 -14.521942) (xy 77.87005 -16.325342) (xy 78.42885 -16.325342) (xy 78.42885 -14.521942)
			)
		)
	)
	(zone
		(layer "In1.Cu")
		(hatch none 0.5)
		(connect_pads
			(clearance 0)
		)
		(min_thickness 0.25)
		(keepout
			(tracks not_allowed)
			(vias allowed)
			(pads allowed)
			(copperpour not_allowed)
			(footprints allowed)
		)
		(placement
			(enabled no)
			(sheetname "")
		)
		(fill
			(thermal_gap 0.5)
			(thermal_bridge_width 0.5)
			(island_removal_mode 0)
		)
		(polygon
			(pts
				(xy 71.069962 0.080518) (xy 71.069962 -1.722882) (xy 71.628762 -1.722882) (xy 71.628762 0.080518)
			)
		)
	)
	(zone
		(layer "In1.Cu")
		(hatch none 0.5)
		(connect_pads
			(clearance 0)
		)
		(min_thickness 0.25)
		(keepout
			(tracks not_allowed)
			(vias allowed)
			(pads allowed)
			(copperpour not_allowed)
			(footprints allowed)
		)
		(placement
			(enabled no)
			(sheetname "")
		)
		(fill
			(thermal_gap 0.5)
			(thermal_bridge_width 0.5)
			(island_removal_mode 0)
		)
		(polygon
			(pts
				(xy 43.01998 -9.520682) (xy 43.01998 -11.324082) (xy 43.57878 -11.324082) (xy 43.57878 -9.520682)
			)
		)
	)
	(zone
		(layer "In1.Cu")
		(hatch none 0.5)
		(connect_pads
			(clearance 0)
		)
		(min_thickness 0.25)
		(keepout
			(tracks not_allowed)
			(vias allowed)
			(pads allowed)
			(copperpour not_allowed)
			(footprints allowed)
		)
		(placement
			(enabled no)
			(sheetname "")
		)
		(fill
			(thermal_gap 0.5)
			(thermal_bridge_width 0.5)
			(island_removal_mode 0)
		)
		(polygon
			(pts
				(xy 299.82033 -151.377142) (xy 299.82033 -153.180542) (xy 300.37913 -153.180542) (xy 300.37913 -151.377142)
			)
		)
	)
	(zone
		(layer "In1.Cu")
		(hatch none 0.5)
		(connect_pads
			(clearance 0)
		)
		(min_thickness 0.25)
		(keepout
			(tracks not_allowed)
			(vias allowed)
			(pads allowed)
			(copperpour not_allowed)
			(footprints allowed)
		)
		(placement
			(enabled no)
			(sheetname "")
		)
		(fill
			(thermal_gap 0.5)
			(thermal_bridge_width 0.5)
			(island_removal_mode 0)
		)
		(polygon
			(pts
				(xy 249.67057 -155.977082) (xy 249.67057 -157.780482) (xy 250.22937 -157.780482) (xy 250.22937 -155.977082)
			)
		)
	)
	(zone
		(layer "In1.Cu")
		(hatch none 0.5)
		(connect_pads
			(clearance 0)
		)
		(min_thickness 0.25)
		(keepout
			(tracks not_allowed)
			(vias allowed)
			(pads allowed)
			(copperpour not_allowed)
			(footprints allowed)
		)
		(placement
			(enabled no)
			(sheetname "")
		)
		(fill
			(thermal_gap 0.5)
			(thermal_bridge_width 0.5)
			(island_removal_mode 0)
		)
		(polygon
			(pts
				(xy 64.270128 -9.520682) (xy 64.270128 -11.324082) (xy 64.828928 -11.324082) (xy 64.828928 -9.520682)
			)
		)
	)
	(zone
		(layer "In1.Cu")
		(hatch none 0.5)
		(connect_pads
			(clearance 0)
		)
		(min_thickness 0.25)
		(keepout
			(tracks not_allowed)
			(vias allowed)
			(pads allowed)
			(copperpour not_allowed)
			(footprints allowed)
		)
		(placement
			(enabled no)
			(sheetname "")
		)
		(fill
			(thermal_gap 0.5)
			(thermal_bridge_width 0.5)
			(island_removal_mode 0)
		)
		(polygon
			(pts
				(xy 75.320144 -9.520682) (xy 75.320144 -11.324082) (xy 75.878944 -11.324082) (xy 75.878944 -9.520682)
			)
		)
	)
	(zone
		(layer "In1.Cu")
		(hatch none 0.5)
		(connect_pads
			(clearance 0)
		)
		(min_thickness 0.25)
		(keepout
			(tracks not_allowed)
			(vias allowed)
			(pads allowed)
			(copperpour not_allowed)
			(footprints allowed)
		)
		(placement
			(enabled no)
			(sheetname "")
		)
		(fill
			(thermal_gap 0.5)
			(thermal_bridge_width 0.5)
			(island_removal_mode 0)
		)
		(polygon
			(pts
				(xy 99.970082 -19.121882) (xy 99.970082 -20.925282) (xy 100.528882 -20.925282) (xy 100.528882 -19.121882)
			)
		)
	)
	(zone
		(layer "In1.Cu")
		(hatch none 0.5)
		(connect_pads
			(clearance 0)
		)
		(min_thickness 0.25)
		(keepout
			(tracks not_allowed)
			(vias allowed)
			(pads allowed)
			(copperpour not_allowed)
			(footprints allowed)
		)
		(placement
			(enabled no)
			(sheetname "")
		)
		(fill
			(thermal_gap 0.5)
			(thermal_bridge_width 0.5)
			(island_removal_mode 0)
		)
		(polygon
			(pts
				(xy 79.570072 -141.775942) (xy 79.570072 -143.579342) (xy 80.128872 -143.579342) (xy 80.128872 -141.775942)
			)
		)
	)
	(zone
		(layer "In1.Cu")
		(hatch none 0.5)
		(connect_pads
			(clearance 0)
		)
		(min_thickness 0.25)
		(keepout
			(tracks not_allowed)
			(vias allowed)
			(pads allowed)
			(copperpour not_allowed)
			(footprints allowed)
		)
		(placement
			(enabled no)
			(sheetname "")
		)
		(fill
			(thermal_gap 0.5)
			(thermal_bridge_width 0.5)
			(island_removal_mode 0)
		)
		(polygon
			(pts
				(xy 63.41999 -9.520682) (xy 63.41999 -11.324082) (xy 63.97879 -11.324082) (xy 63.97879 -9.520682)
			)
		)
	)
	(zone
		(layer "In1.Cu")
		(hatch none 0.5)
		(connect_pads
			(clearance 0)
		)
		(min_thickness 0.25)
		(keepout
			(tracks not_allowed)
			(vias allowed)
			(pads allowed)
			(copperpour not_allowed)
			(footprints allowed)
		)
		(placement
			(enabled no)
			(sheetname "")
		)
		(fill
			(thermal_gap 0.5)
			(thermal_bridge_width 0.5)
			(island_removal_mode 0)
		)
		(polygon
			(pts
				(xy 91.469972 -141.775942) (xy 91.469972 -143.579342) (xy 92.028772 -143.579342) (xy 92.028772 -141.775942)
			)
		)
	)
	(zone
		(layer "In1.Cu")
		(hatch none 0.5)
		(connect_pads
			(clearance 0)
		)
		(min_thickness 0.25)
		(keepout
			(tracks not_allowed)
			(vias allowed)
			(pads allowed)
			(copperpour not_allowed)
			(footprints allowed)
		)
		(placement
			(enabled no)
			(sheetname "")
		)
		(fill
			(thermal_gap 0.5)
			(thermal_bridge_width 0.5)
			(island_removal_mode 0)
		)
		(polygon
			(pts
				(xy 119.519954 0.080518) (xy 119.519954 -1.722882) (xy 120.078754 -1.722882) (xy 120.078754 0.080518)
			)
		)
	)
	(zone
		(layer "In1.Cu")
		(hatch none 0.5)
		(connect_pads
			(clearance 0)
		)
		(min_thickness 0.25)
		(keepout
			(tracks not_allowed)
			(vias allowed)
			(pads allowed)
			(copperpour not_allowed)
			(footprints allowed)
		)
		(placement
			(enabled no)
			(sheetname "")
		)
		(fill
			(thermal_gap 0.5)
			(thermal_bridge_width 0.5)
			(island_removal_mode 0)
		)
		(polygon
			(pts
				(xy 110.16996 0.080518) (xy 110.16996 -1.722882) (xy 110.72876 -1.722882) (xy 110.72876 0.080518)
			)
		)
	)
	(zone
		(layer "In1.Cu")
		(hatch none 0.5)
		(connect_pads
			(clearance 0)
		)
		(min_thickness 0.25)
		(keepout
			(tracks not_allowed)
			(vias allowed)
			(pads allowed)
			(copperpour not_allowed)
			(footprints allowed)
		)
		(placement
			(enabled no)
			(sheetname "")
		)
		(fill
			(thermal_gap 0.5)
			(thermal_bridge_width 0.5)
			(island_removal_mode 0)
		)
		(polygon
			(pts
				(xy 244.570504 -141.775942) (xy 244.570504 -143.579342) (xy 245.129304 -143.579342) (xy 245.129304 -141.775942)
			)
		)
	)
	(zone
		(layer "In1.Cu")
		(hatch none 0.5)
		(connect_pads
			(clearance 0)
		)
		(min_thickness 0.25)
		(keepout
			(tracks not_allowed)
			(vias allowed)
			(pads allowed)
			(copperpour not_allowed)
			(footprints allowed)
		)
		(placement
			(enabled no)
			(sheetname "")
		)
		(fill
			(thermal_gap 0.5)
			(thermal_bridge_width 0.5)
			(island_removal_mode 0)
		)
		(polygon
			(pts
				(xy 52.369974 -9.520682) (xy 52.369974 -11.324082) (xy 52.928774 -11.324082) (xy 52.928774 -9.520682)
			)
		)
	)
	(zone
		(layer "In1.Cu")
		(hatch none 0.5)
		(connect_pads
			(clearance 0)
		)
		(min_thickness 0.25)
		(keepout
			(tracks not_allowed)
			(vias allowed)
			(pads allowed)
			(copperpour not_allowed)
			(footprints allowed)
		)
		(placement
			(enabled no)
			(sheetname "")
		)
		(fill
			(thermal_gap 0.5)
			(thermal_bridge_width 0.5)
			(island_removal_mode 0)
		)
		(polygon
			(pts
				(xy 46.420024 -141.775942) (xy 46.420024 -143.579342) (xy 46.978824 -143.579342) (xy 46.978824 -141.775942)
			)
		)
	)
	(zone
		(layer "In1.Cu")
		(hatch none 0.5)
		(connect_pads
			(clearance 0)
		)
		(min_thickness 0.25)
		(keepout
			(tracks not_allowed)
			(vias allowed)
			(pads allowed)
			(copperpour not_allowed)
			(footprints allowed)
		)
		(placement
			(enabled no)
			(sheetname "")
		)
		(fill
			(thermal_gap 0.5)
			(thermal_bridge_width 0.5)
			(island_removal_mode 0)
		)
		(polygon
			(pts
				(xy 219.920566 -146.375882) (xy 219.920566 -148.179282) (xy 220.479366 -148.179282) (xy 220.479366 -146.375882)
			)
		)
	)
	(zone
		(layer "In1.Cu")
		(hatch none 0.5)
		(connect_pads
			(clearance 0)
		)
		(min_thickness 0.25)
		(keepout
			(tracks not_allowed)
			(vias allowed)
			(pads allowed)
			(copperpour not_allowed)
			(footprints allowed)
		)
		(placement
			(enabled no)
			(sheetname "")
		)
		(fill
			(thermal_gap 0.5)
			(thermal_bridge_width 0.5)
			(island_removal_mode 0)
		)
		(polygon
			(pts
				(xy 40.470074 4.680458) (xy 40.470074 2.877058) (xy 41.028874 2.877058) (xy 41.028874 4.680458)
			)
		)
	)
	(zone
		(layer "In1.Cu")
		(hatch none 0.5)
		(connect_pads
			(clearance 0)
		)
		(min_thickness 0.25)
		(keepout
			(tracks not_allowed)
			(vias allowed)
			(pads allowed)
			(copperpour not_allowed)
			(footprints allowed)
		)
		(placement
			(enabled no)
			(sheetname "")
		)
		(fill
			(thermal_gap 0.5)
			(thermal_bridge_width 0.5)
			(island_removal_mode 0)
		)
		(polygon
			(pts
				(xy 70.220078 -14.521942) (xy 70.220078 -16.325342) (xy 70.778878 -16.325342) (xy 70.778878 -14.521942)
			)
		)
	)
	(zone
		(layer "In1.Cu")
		(hatch none 0.5)
		(connect_pads
			(clearance 0)
		)
		(min_thickness 0.25)
		(keepout
			(tracks not_allowed)
			(vias allowed)
			(pads allowed)
			(copperpour not_allowed)
			(footprints allowed)
		)
		(placement
			(enabled no)
			(sheetname "")
		)
		(fill
			(thermal_gap 0.5)
			(thermal_bridge_width 0.5)
			(island_removal_mode 0)
		)
		(polygon
			(pts
				(xy 254.770382 -4.920742) (xy 254.770382 -6.724142) (xy 255.329182 -6.724142) (xy 255.329182 -4.920742)
			)
		)
	)
	(zone
		(layer "In1.Cu")
		(hatch none 0.5)
		(connect_pads
			(clearance 0)
		)
		(min_thickness 0.25)
		(keepout
			(tracks not_allowed)
			(vias allowed)
			(pads allowed)
			(copperpour not_allowed)
			(footprints allowed)
		)
		(placement
			(enabled no)
			(sheetname "")
		)
		(fill
			(thermal_gap 0.5)
			(thermal_bridge_width 0.5)
			(island_removal_mode 0)
		)
		(polygon
			(pts
				(xy 42.170096 -141.775942) (xy 42.170096 -143.579342) (xy 42.728896 -143.579342) (xy 42.728896 -141.775942)
			)
		)
	)
	(zone
		(layer "In1.Cu")
		(hatch none 0.5)
		(connect_pads
			(clearance 0)
		)
		(min_thickness 0.25)
		(keepout
			(tracks not_allowed)
			(vias allowed)
			(pads allowed)
			(copperpour not_allowed)
			(footprints allowed)
		)
		(placement
			(enabled no)
			(sheetname "")
		)
		(fill
			(thermal_gap 0.5)
			(thermal_bridge_width 0.5)
			(island_removal_mode 0)
		)
		(polygon
			(pts
				(xy 215.670384 -155.977082) (xy 215.670384 -157.780482) (xy 216.229184 -157.780482) (xy 216.229184 -155.977082)
			)
		)
	)
	(zone
		(layer "In1.Cu")
		(hatch none 0.5)
		(connect_pads
			(clearance 0)
		)
		(min_thickness 0.25)
		(keepout
			(tracks not_allowed)
			(vias allowed)
			(pads allowed)
			(copperpour not_allowed)
			(footprints allowed)
		)
		(placement
			(enabled no)
			(sheetname "")
		)
		(fill
			(thermal_gap 0.5)
			(thermal_bridge_width 0.5)
			(island_removal_mode 0)
		)
		(polygon
			(pts
				(xy 295.570402 -136.774682) (xy 295.570402 -138.578082) (xy 296.129202 -138.578082) (xy 296.129202 -136.774682)
			)
		)
	)
	(zone
		(layer "In1.Cu")
		(hatch none 0.5)
		(connect_pads
			(clearance 0)
		)
		(min_thickness 0.25)
		(keepout
			(tracks not_allowed)
			(vias allowed)
			(pads allowed)
			(copperpour not_allowed)
			(footprints allowed)
		)
		(placement
			(enabled no)
			(sheetname "")
		)
		(fill
			(thermal_gap 0.5)
			(thermal_bridge_width 0.5)
			(island_removal_mode 0)
		)
		(polygon
			(pts
				(xy 84.670138 0.080518) (xy 84.670138 -1.722882) (xy 85.228938 -1.722882) (xy 85.228938 0.080518)
			)
		)
	)
	(zone
		(layer "In1.Cu")
		(hatch none 0.5)
		(connect_pads
			(clearance 0)
		)
		(min_thickness 0.25)
		(keepout
			(tracks not_allowed)
			(vias allowed)
			(pads allowed)
			(copperpour not_allowed)
			(footprints allowed)
		)
		(placement
			(enabled no)
			(sheetname "")
		)
		(fill
			(thermal_gap 0.5)
			(thermal_bridge_width 0.5)
			(island_removal_mode 0)
		)
		(polygon
			(pts
				(xy 142.46987 -141.775942) (xy 142.46987 -143.579342) (xy 143.02867 -143.579342) (xy 143.02867 -141.775942)
			)
		)
	)
	(zone
		(layer "In1.Cu")
		(hatch none 0.5)
		(connect_pads
			(clearance 0)
		)
		(min_thickness 0.25)
		(keepout
			(tracks not_allowed)
			(vias allowed)
			(pads allowed)
			(copperpour not_allowed)
			(footprints allowed)
		)
		(placement
			(enabled no)
			(sheetname "")
		)
		(fill
			(thermal_gap 0.5)
			(thermal_bridge_width 0.5)
			(island_removal_mode 0)
		)
		(polygon
			(pts
				(xy 140.770102 -14.521942) (xy 140.770102 -16.325342) (xy 141.328902 -16.325342) (xy 141.328902 -14.521942)
			)
		)
	)
	(zone
		(layer "In1.Cu")
		(hatch none 0.5)
		(connect_pads
			(clearance 0)
		)
		(min_thickness 0.25)
		(keepout
			(tracks not_allowed)
			(vias allowed)
			(pads allowed)
			(copperpour not_allowed)
			(footprints allowed)
		)
		(placement
			(enabled no)
			(sheetname "")
		)
		(fill
			(thermal_gap 0.5)
			(thermal_bridge_width 0.5)
			(island_removal_mode 0)
		)
		(polygon
			(pts
				(xy 132.269992 -146.375882) (xy 132.269992 -148.179282) (xy 132.828792 -148.179282) (xy 132.828792 -146.375882)
			)
		)
	)
	(zone
		(layer "In1.Cu")
		(hatch none 0.5)
		(connect_pads
			(clearance 0)
		)
		(min_thickness 0.25)
		(keepout
			(tracks not_allowed)
			(vias allowed)
			(pads allowed)
			(copperpour not_allowed)
			(footprints allowed)
		)
		(placement
			(enabled no)
			(sheetname "")
		)
		(fill
			(thermal_gap 0.5)
			(thermal_bridge_width 0.5)
			(island_removal_mode 0)
		)
		(polygon
			(pts
				(xy 209.720434 -146.375882) (xy 209.720434 -148.179282) (xy 210.279234 -148.179282) (xy 210.279234 -146.375882)
			)
		)
	)
	(zone
		(layer "In1.Cu")
		(hatch none 0.5)
		(connect_pads
			(clearance 0)
		)
		(min_thickness 0.25)
		(keepout
			(tracks not_allowed)
			(vias allowed)
			(pads allowed)
			(copperpour not_allowed)
			(footprints allowed)
		)
		(placement
			(enabled no)
			(sheetname "")
		)
		(fill
			(thermal_gap 0.5)
			(thermal_bridge_width 0.5)
			(island_removal_mode 0)
		)
		(polygon
			(pts
				(xy 146.720052 -146.375882) (xy 146.720052 -148.179282) (xy 147.278852 -148.179282) (xy 147.278852 -146.375882)
			)
		)
	)
	(zone
		(layer "In1.Cu")
		(hatch none 0.5)
		(connect_pads
			(clearance 0)
		)
		(min_thickness 0.25)
		(keepout
			(tracks not_allowed)
			(vias allowed)
			(pads allowed)
			(copperpour not_allowed)
			(footprints allowed)
		)
		(placement
			(enabled no)
			(sheetname "")
		)
		(fill
			(thermal_gap 0.5)
			(thermal_bridge_width 0.5)
			(island_removal_mode 0)
		)
		(polygon
			(pts
				(xy 204.620368 -19.121882) (xy 204.620368 -20.925282) (xy 205.179168 -20.925282) (xy 205.179168 -19.121882)
			)
		)
	)
	(zone
		(layer "In1.Cu")
		(hatch none 0.5)
		(connect_pads
			(clearance 0)
		)
		(min_thickness 0.25)
		(keepout
			(tracks not_allowed)
			(vias allowed)
			(pads allowed)
			(copperpour not_allowed)
			(footprints allowed)
		)
		(placement
			(enabled no)
			(sheetname "")
		)
		(fill
			(thermal_gap 0.5)
			(thermal_bridge_width 0.5)
			(island_removal_mode 0)
		)
		(polygon
			(pts
				(xy 196.970396 -136.774682) (xy 196.970396 -138.578082) (xy 197.529196 -138.578082) (xy 197.529196 -136.774682)
			)
		)
	)
	(zone
		(layer "In1.Cu")
		(hatch none 0.5)
		(connect_pads
			(clearance 0)
		)
		(min_thickness 0.25)
		(keepout
			(tracks not_allowed)
			(vias allowed)
			(pads allowed)
			(copperpour not_allowed)
			(footprints allowed)
		)
		(placement
			(enabled no)
			(sheetname "")
		)
		(fill
			(thermal_gap 0.5)
			(thermal_bridge_width 0.5)
			(island_removal_mode 0)
		)
		(polygon
			(pts
				(xy 127.169926 -151.377142) (xy 127.169926 -153.180542) (xy 127.728726 -153.180542) (xy 127.728726 -151.377142)
			)
		)
	)
	(zone
		(layer "In1.Cu")
		(hatch none 0.5)
		(connect_pads
			(clearance 0)
		)
		(min_thickness 0.25)
		(keepout
			(tracks not_allowed)
			(vias allowed)
			(pads allowed)
			(copperpour not_allowed)
			(footprints allowed)
		)
		(placement
			(enabled no)
			(sheetname "")
		)
		(fill
			(thermal_gap 0.5)
			(thermal_bridge_width 0.5)
			(island_removal_mode 0)
		)
		(polygon
			(pts
				(xy 199.520556 4.680458) (xy 199.520556 2.877058) (xy 200.079356 2.877058) (xy 200.079356 4.680458)
			)
		)
	)
	(zone
		(layer "In1.Cu")
		(hatch none 0.5)
		(connect_pads
			(clearance 0)
		)
		(min_thickness 0.25)
		(keepout
			(tracks not_allowed)
			(vias allowed)
			(pads allowed)
			(copperpour not_allowed)
			(footprints allowed)
		)
		(placement
			(enabled no)
			(sheetname "")
		)
		(fill
			(thermal_gap 0.5)
			(thermal_bridge_width 0.5)
			(island_removal_mode 0)
		)
		(polygon
			(pts
				(xy 206.32039 -146.375882) (xy 206.32039 -148.179282) (xy 206.87919 -148.179282) (xy 206.87919 -146.375882)
			)
		)
	)
	(zone
		(layer "In1.Cu")
		(hatch none 0.5)
		(connect_pads
			(clearance 0)
		)
		(min_thickness 0.25)
		(keepout
			(tracks not_allowed)
			(vias allowed)
			(pads allowed)
			(copperpour not_allowed)
			(footprints allowed)
		)
		(placement
			(enabled no)
			(sheetname "")
		)
		(fill
			(thermal_gap 0.5)
			(thermal_bridge_width 0.5)
			(island_removal_mode 0)
		)
		(polygon
			(pts
				(xy 280.270458 -19.121882) (xy 280.270458 -20.925282) (xy 280.829258 -20.925282) (xy 280.829258 -19.121882)
			)
		)
	)
	(zone
		(layer "In1.Cu")
		(hatch none 0.5)
		(connect_pads
			(clearance 0)
		)
		(min_thickness 0.25)
		(keepout
			(tracks not_allowed)
			(vias allowed)
			(pads allowed)
			(copperpour not_allowed)
			(footprints allowed)
		)
		(placement
			(enabled no)
			(sheetname "")
		)
		(fill
			(thermal_gap 0.5)
			(thermal_bridge_width 0.5)
			(island_removal_mode 0)
		)
		(polygon
			(pts
				(xy 311.720484 -136.774682) (xy 311.720484 -138.578082) (xy 312.279284 -138.578082) (xy 312.279284 -136.774682)
			)
		)
	)
	(zone
		(layer "In1.Cu")
		(hatch none 0.5)
		(connect_pads
			(clearance 0)
		)
		(min_thickness 0.25)
		(keepout
			(tracks not_allowed)
			(vias allowed)
			(pads allowed)
			(copperpour not_allowed)
			(footprints allowed)
		)
		(placement
			(enabled no)
			(sheetname "")
		)
		(fill
			(thermal_gap 0.5)
			(thermal_bridge_width 0.5)
			(island_removal_mode 0)
		)
		(polygon
			(pts
				(xy 82.119978 -19.121882) (xy 82.119978 -20.925282) (xy 82.678778 -20.925282) (xy 82.678778 -19.121882)
			)
		)
	)
	(zone
		(layer "In1.Cu")
		(hatch none 0.5)
		(connect_pads
			(clearance 0)
		)
		(min_thickness 0.25)
		(keepout
			(tracks not_allowed)
			(vias allowed)
			(pads allowed)
			(copperpour not_allowed)
			(footprints allowed)
		)
		(placement
			(enabled no)
			(sheetname "")
		)
		(fill
			(thermal_gap 0.5)
			(thermal_bridge_width 0.5)
			(island_removal_mode 0)
		)
		(polygon
			(pts
				(xy 219.070428 -4.920742) (xy 219.070428 -6.724142) (xy 219.629228 -6.724142) (xy 219.629228 -4.920742)
			)
		)
	)
	(zone
		(layer "In1.Cu")
		(hatch none 0.5)
		(connect_pads
			(clearance 0)
		)
		(min_thickness 0.25)
		(keepout
			(tracks not_allowed)
			(vias allowed)
			(pads allowed)
			(copperpour not_allowed)
			(footprints allowed)
		)
		(placement
			(enabled no)
			(sheetname "")
		)
		(fill
			(thermal_gap 0.5)
			(thermal_bridge_width 0.5)
			(island_removal_mode 0)
		)
		(polygon
			(pts
				(xy 139.919964 -146.375882) (xy 139.919964 -148.179282) (xy 140.478764 -148.179282) (xy 140.478764 -146.375882)
			)
		)
	)
	(zone
		(net "PVDDQ_KLM")
		(layer "In1.Cu")
		(hatch none 0.5)
		(connect_pads
			(clearance 0.5)
		)
		(min_thickness 0.25)
		(fill yes
			(thermal_gap 0.5)
			(thermal_bridge_width 0.5)
			(island_removal_mode 0)
		)
		(polygon
			(pts
				(xy 87.539068 -88.6333) (xy 87.245952 -88.926416)
				(arc
					(start 87.242142 -88.933782)
					(mid 87.175101 -89.027015)
					(end 87.081868 -89.094056)
				)
				(xy 87.074502 -89.097866) (xy 86.929468 -89.2429) (xy 86.929468 -89.5858) (xy 86.621874 -89.893394)
				(arc
					(start 86.621874 -90.344752)
					(mid 86.669578 -90.430878)
					(end 86.767924 -90.436192)
				)
				(arc
					(start 86.767924 -90.436192)
					(mid 87.279395 -90.756486)
					(end 86.767924 -91.07678)
				)
				(arc
					(start 86.767924 -91.07678)
					(mid 86.66954 -91.082033)
					(end 86.621874 -91.16822)
				)
				(arc
					(start 86.621874 -91.335352)
					(mid 86.669578 -91.421478)
					(end 86.767924 -91.426792)
				)
				(arc
					(start 86.767924 -91.426792)
					(mid 87.233496 -91.921945)
					(end 86.568788 -91.779852)
				)
				(arc
					(start 86.568788 -91.779852)
					(mid 86.502161 -91.693751)
					(end 86.395814 -91.717368)
				)
				(arc
					(start 86.290404 -91.822778)
					(mid 86.260707 -91.898616)
					(end 86.296246 -91.971876)
				)
				(arc
					(start 86.296246 -91.971876)
					(mid 86.352653 -92.452465)
					(end 85.877908 -92.545662)
				)
				(arc
					(start 85.877908 -92.545662)
					(mid 85.774963 -92.54347)
					(end 85.722968 -92.632276)
				)
				(arc
					(start 85.722968 -93.83395)
					(mid 85.775022 -93.92265)
					(end 85.877908 -93.920564)
				)
				(arc
					(start 85.877908 -93.920564)
					(mid 86.4209 -94.223586)
					(end 85.877908 -94.526608)
				)
				(arc
					(start 85.877908 -94.526608)
					(mid 85.774963 -94.524416)
					(end 85.722968 -94.613222)
				)
				(arc
					(start 85.722968 -94.824804)
					(mid 85.775022 -94.913504)
					(end 85.877908 -94.911418)
				)
				(arc
					(start 85.877908 -94.911418)
					(mid 86.4209 -95.21444)
					(end 85.877908 -95.517462)
				)
				(arc
					(start 85.877908 -95.517462)
					(mid 85.774963 -95.51527)
					(end 85.722968 -95.604076)
				)
				(arc
					(start 85.722968 -95.815404)
					(mid 85.775022 -95.904104)
					(end 85.877908 -95.902018)
				)
				(arc
					(start 85.877908 -95.902018)
					(mid 86.382876 -96.044942)
					(end 86.196932 -96.535748)
				)
				(arc
					(start 86.196932 -96.535748)
					(mid 86.134947 -96.609609)
					(end 86.162642 -96.701864)
				)
				(xy 86.237826 -96.777048) (xy 86.237826 -105.250742) (xy 85.85454 -105.634028) (xy 85.85454 -113.179606)
				(xy 81.397856 -117.63629) (xy 81.397856 -123.912884) (xy 78.489556 -126.821184) (xy 78.489556 -129.159)
				(xy 77.851 -129.797556)
				(arc
					(start 77.851 -129.924048)
					(mid 77.91347 -130.017811)
					(end 78.023974 -129.996184)
				)
				(arc
					(start 78.023974 -129.996184)
					(mid 78.630329 -130.249676)
					(end 78.023974 -130.503168)
				)
				(arc
					(start 78.023974 -130.503168)
					(mid 77.913517 -130.481654)
					(end 77.851 -130.575304)
				)
				(arc
					(start 77.851 -131.17322)
					(mid 77.898367 -131.259134)
					(end 77.996288 -131.264914)
				)
				(arc
					(start 77.996288 -131.264914)
					(mid 78.505627 -131.586478)
					(end 77.996288 -131.908042)
				)
				(arc
					(start 77.996288 -131.908042)
					(mid 77.898383 -131.913847)
					(end 77.851 -131.999736)
				)
				(xy 77.851 -132.174488) (xy 78.429104 -132.174488)
				(arc
					(start 78.429104 -134.020814)
					(mid 78.558068 -134.535755)
					(end 78.027784 -134.561834)
				)
				(arc
					(start 78.027784 -134.561834)
					(mid 77.915974 -134.535399)
					(end 77.851 -134.63016)
				)
				(arc
					(start 77.851 -135.043418)
					(mid 77.907482 -135.13445)
					(end 78.014068 -135.12419)
				)
				(arc
					(start 78.014068 -135.12419)
					(mid 78.586087 -135.4074)
					(end 78.014068 -135.69061)
				)
				(arc
					(start 78.014068 -135.69061)
					(mid 77.907526 -135.680438)
					(end 77.851 -135.771382)
				)
				(arc
					(start 77.851 -135.97382)
					(mid 77.898367 -136.059734)
					(end 77.996288 -136.065514)
				)
				(arc
					(start 77.996288 -136.065514)
					(mid 78.505627 -136.387078)
					(end 77.996288 -136.708642)
				)
				(arc
					(start 77.996288 -136.708642)
					(mid 77.898383 -136.714447)
					(end 77.851 -136.800336)
				)
				(arc
					(start 77.851 -138.829542)
					(mid 77.898367 -138.915456)
					(end 77.996288 -138.921236)
				)
				(arc
					(start 77.996288 -138.921236)
					(mid 78.505627 -139.2428)
					(end 77.996288 -139.564364)
				)
				(arc
					(start 77.996288 -139.564364)
					(mid 77.898383 -139.570169)
					(end 77.851 -139.656058)
				)
				(arc
					(start 77.851 -139.866624)
					(mid 77.911075 -139.959351)
					(end 78.020164 -139.942316)
				)
				(arc
					(start 78.020164 -139.942316)
					(mid 78.613587 -140.208)
					(end 78.020164 -140.473684)
				)
				(arc
					(start 78.020164 -140.473684)
					(mid 77.911132 -140.456777)
					(end 77.851 -140.549376)
				)
				(arc
					(start 77.851 -140.788644)
					(mid 77.898992 -140.87495)
					(end 77.997558 -140.879576)
				)
				(arc
					(start 77.997558 -140.879576)
					(mid 78.492958 -141.187678)
					(end 77.997558 -141.49578)
				)
				(arc
					(start 77.997558 -141.49578)
					(mid 77.899077 -141.500543)
					(end 77.851 -141.586712)
				)
				(xy 77.851 -141.775688) (xy 78.429104 -141.775688) (xy 78.429104 -143.579596) (xy 78.404212 -143.579596)
				(xy 78.404212 -143.656812)
				(arc
					(start 78.425802 -143.672052)
					(mid 78.502921 -144.15772)
					(end 78.015338 -144.22247)
				)
				(arc
					(start 78.015338 -144.22247)
					(mid 77.908267 -144.210948)
					(end 77.851 -144.302226)
				)
				(arc
					(start 77.851 -144.644618)
					(mid 77.907482 -144.73565)
					(end 78.014068 -144.72539)
				)
				(arc
					(start 78.014068 -144.72539)
					(mid 78.586087 -145.0086)
					(end 78.014068 -145.29181)
				)
				(arc
					(start 78.014068 -145.29181)
					(mid 77.907526 -145.281638)
					(end 77.851 -145.372582)
				)
				(arc
					(start 77.851 -145.57502)
					(mid 77.898367 -145.660934)
					(end 77.996288 -145.666714)
				)
				(arc
					(start 77.996288 -145.666714)
					(mid 78.505627 -145.988278)
					(end 77.996288 -146.309842)
				)
				(arc
					(start 77.996288 -146.309842)
					(mid 77.898383 -146.315647)
					(end 77.851 -146.401536)
				)
				(arc
					(start 77.851 -149.047708)
					(mid 77.903112 -149.136441)
					(end 78.00594 -149.134068)
				)
				(arc
					(start 78.00594 -149.134068)
					(mid 78.475959 -149.220128)
					(end 78.437232 -149.696424)
				)
				(arc
					(start 78.437232 -149.696424)
					(mid 78.40532 -149.772047)
					(end 78.439772 -149.846538)
				)
				(arc
					(start 78.439772 -149.846538)
					(mid 78.560358 -150.130442)
					(end 78.414118 -150.402036)
				)
				(arc
					(start 78.414118 -150.402036)
					(mid 78.37261 -150.474612)
					(end 78.39964 -150.553674)
				)
				(arc
					(start 78.39964 -150.553674)
					(mid 78.425465 -150.993161)
					(end 77.997558 -151.09698)
				)
				(arc
					(start 77.997558 -151.09698)
					(mid 77.899077 -151.101743)
					(end 77.851 -151.187912)
				)
				(xy 77.851 -151.376888) (xy 78.429104 -151.376888) (xy 78.429104 -153.180796) (xy 77.851 -153.180796)
				(arc
					(start 77.851 -153.905966)
					(mid 77.913139 -153.99959)
					(end 78.023466 -153.97861)
				)
				(arc
					(start 78.023466 -153.97861)
					(mid 78.628068 -154.23388)
					(end 78.023466 -154.48915)
				)
				(arc
					(start 78.023466 -154.48915)
					(mid 77.913183 -154.468277)
					(end 77.851 -154.561794)
				)
				(arc
					(start 77.851 -154.933142)
					(mid 77.898367 -155.019056)
					(end 77.996288 -155.024836)
				)
				(arc
					(start 77.996288 -155.024836)
					(mid 78.505627 -155.3464)
					(end 77.996288 -155.667964)
				)
				(arc
					(start 77.996288 -155.667964)
					(mid 77.898383 -155.673769)
					(end 77.851 -155.759658)
				)
				(xy 77.851 -157.139132) (xy 78.668118 -157.95625) (xy 113.35766 -157.95625) (xy 113.509298 -157.804612)
				(arc
					(start 113.509298 -155.892754)
					(mid 113.376501 -155.615386)
					(end 113.509298 -155.338018)
				)
				(xy 113.509298 -154.68854) (xy 113.337848 -154.51709) (xy 113.337848 -153.981404) (xy 113.509298 -153.809954)
				(arc
					(start 113.509298 -149.73554)
					(mid 113.368677 -149.452076)
					(end 113.509298 -149.168612)
				)
				(xy 113.509298 -144.682718)
				(arc
					(start 113.507266 -144.675606)
					(mid 113.493285 -144.5768)
					(end 113.507266 -144.477994)
				)
				(xy 113.509298 -144.470882) (xy 113.509298 -134.69874) (xy 113.88852 -134.319518) (xy 113.88852 -132.02412)
				(xy 113.633758 -131.769358) (xy 113.633758 -131.009898)
				(arc
					(start 113.630964 -131.002024)
					(mid 113.611605 -130.8862)
					(end 113.630964 -130.770376)
				)
				(xy 113.633758 -130.762502) (xy 113.633758 -130.595878)
				(arc
					(start 113.600738 -130.583432)
					(mid 113.37939 -130.16293)
					(end 113.773204 -129.89687)
				)
				(arc
					(start 113.773204 -129.89687)
					(mid 113.853677 -129.872764)
					(end 113.88852 -129.796286)
				)
				(xy 113.88852 -128.674114) (xy 112.171226 -126.95682) (xy 112.171226 -125.650244) (xy 105.99293 -119.471948)
				(xy 105.99293 -112.260126) (xy 106.385868 -111.867188) (xy 106.385868 -104.384856) (xy 105.721912 -103.7209)
				(xy 105.721912 -100.283772)
				(arc
					(start 104.837738 -99.399598)
					(mid 104.761617 -99.370102)
					(end 104.688386 -99.406202)
				)
				(arc
					(start 104.688386 -99.406202)
					(mid 104.163965 -99.428719)
					(end 104.186482 -98.904298)
				)
				(arc
					(start 104.186482 -98.904298)
					(mid 104.222604 -98.831068)
					(end 104.193086 -98.754946)
				)
				(xy 103.287068 -97.848928) (xy 103.287068 -91.044268) (xy 102.6922 -90.4494) (xy 102.1715 -90.4494)
				(arc
					(start 101.766878 -90.854022)
					(mid 101.737104 -90.926263)
					(end 101.767386 -90.998294)
				)
				(arc
					(start 101.767386 -90.998294)
					(mid 101.564569 -91.604931)
					(end 101.210364 -91.072208)
				)
				(arc
					(start 101.210364 -91.072208)
					(mid 101.210829 -90.970395)
					(end 101.122734 -90.9193)
				)
				(arc
					(start 100.975922 -90.9193)
					(mid 100.689136 -91.111358)
					(end 100.374196 -90.9701)
				)
				(arc
					(start 100.221288 -90.9701)
					(mid 100.136422 -91.01584)
					(end 100.12807 -91.111832)
				)
				(arc
					(start 100.12807 -91.111832)
					(mid 99.800664 -91.608204)
					(end 99.473258 -91.111832)
				)
				(arc
					(start 99.473258 -91.111832)
					(mid 99.464814 -91.0159)
					(end 99.38004 -90.9701)
				)
				(arc
					(start 99.227386 -90.9701)
					(mid 98.942398 -91.112645)
					(end 98.65741 -90.9701)
				)
				(arc
					(start 98.504502 -90.9701)
					(mid 98.419636 -91.01584)
					(end 98.411284 -91.111832)
				)
				(arc
					(start 98.411284 -91.111832)
					(mid 98.083878 -91.608204)
					(end 97.756472 -91.111832)
				)
				(arc
					(start 97.756472 -91.111832)
					(mid 97.748028 -91.0159)
					(end 97.663254 -90.9701)
				)
				(arc
					(start 97.510346 -90.9701)
					(mid 97.225358 -91.112645)
					(end 96.94037 -90.9701)
				)
				(arc
					(start 96.787462 -90.9701)
					(mid 96.702596 -91.01584)
					(end 96.694244 -91.111832)
				)
				(arc
					(start 96.694244 -91.111832)
					(mid 96.179841 -91.555165)
					(end 96.345248 -90.896694)
				)
				(arc
					(start 96.345248 -90.896694)
					(mid 96.434077 -90.831367)
					(end 96.411034 -90.723466)
				)
				(xy 96.298766 -90.611198)
				(arc
					(start 96.284796 -90.607896)
					(mid 96.115082 -90.513196)
					(end 96.020382 -90.343482)
				)
				(xy 96.01708 -90.329512) (xy 95.692468 -90.0049) (xy 95.692468 -89.3064) (xy 95.51797 -89.131902)
				(arc
					(start 95.49765 -89.13114)
					(mid 95.384652 -89.109217)
					(end 95.284544 -89.0524)
				)
				(arc
					(start 95.092266 -89.0524)
					(mid 95.011964 -89.092085)
					(end 94.994222 -89.179908)
				)
				(arc
					(start 94.994222 -89.179908)
					(mid 94.649798 -89.627065)
					(end 94.305374 -89.179908)
				)
				(arc
					(start 94.305374 -89.179908)
					(mid 94.287675 -89.092052)
					(end 94.20733 -89.0524)
				)
				(arc
					(start 94.015052 -89.0524)
					(mid 93.652215 -89.103201)
					(end 93.436694 -88.807036)
				)
				(xy 93.434916 -88.788748) (xy 93.279468 -88.6333) (xy 92.97924 -88.6333)
				(arc
					(start 92.976192 -88.633554)
					(mid 92.932758 -88.636214)
					(end 92.889324 -88.633554)
				)
				(xy 92.886276 -88.6333)
				(arc
					(start 92.530168 -88.6333)
					(mid 92.455245 -88.666277)
					(end 92.429076 -88.74379)
				)
				(arc
					(start 92.429076 -88.74379)
					(mid 92.074238 -89.131519)
					(end 91.7194 -88.74379)
				)
				(arc
					(start 91.7194 -88.74379)
					(mid 91.693144 -88.666356)
					(end 91.618308 -88.6333)
				)
				(xy 91.2622 -88.6333)
				(arc
					(start 91.259152 -88.633554)
					(mid 91.215718 -88.636214)
					(end 91.172284 -88.633554)
				)
				(xy 91.169236 -88.6333)
				(arc
					(start 90.813128 -88.6333)
					(mid 90.738205 -88.666277)
					(end 90.712036 -88.74379)
				)
				(arc
					(start 90.712036 -88.74379)
					(mid 90.357198 -89.131243)
					(end 90.00236 -88.74379)
				)
				(arc
					(start 90.00236 -88.74379)
					(mid 89.976104 -88.666356)
					(end 89.901268 -88.6333)
				)
				(xy 89.54516 -88.6333)
				(arc
					(start 89.542112 -88.633554)
					(mid 89.498678 -88.636214)
					(end 89.455244 -88.633554)
				)
				(xy 89.452196 -88.6333)
				(arc
					(start 89.096342 -88.6333)
					(mid 89.021419 -88.666277)
					(end 88.99525 -88.74379)
				)
				(arc
					(start 88.99525 -88.74379)
					(mid 88.640412 -89.131243)
					(end 88.285574 -88.74379)
				)
				(arc
					(start 88.285574 -88.74379)
					(mid 88.259318 -88.666356)
					(end 88.184482 -88.6333)
				)
				(xy 87.828374 -88.6333)
				(arc
					(start 87.825326 -88.633554)
					(mid 87.781892 -88.636214)
					(end 87.738458 -88.633554)
				)
				(xy 87.73541 -88.6333)
			)
		)
	)
	(zone
		(layer "In1.Cu")
		(hatch none 0.5)
		(connect_pads
			(clearance 0)
		)
		(min_thickness 0.25)
		(keepout
			(tracks not_allowed)
			(vias allowed)
			(pads allowed)
			(copperpour not_allowed)
			(footprints allowed)
		)
		(placement
			(enabled no)
			(sheetname "")
		)
		(fill
			(thermal_gap 0.5)
			(thermal_bridge_width 0.5)
			(island_removal_mode 0)
		)
		(polygon
			(pts
				(xy 277.720552 -146.375882) (xy 277.720552 -148.179282) (xy 278.279352 -148.179282) (xy 278.279352 -146.375882)
			)
		)
	)
	(zone
		(layer "In1.Cu")
		(hatch none 0.5)
		(connect_pads
			(clearance 0)
		)
		(min_thickness 0.25)
		(keepout
			(tracks not_allowed)
			(vias allowed)
			(pads allowed)
			(copperpour not_allowed)
			(footprints allowed)
		)
		(placement
			(enabled no)
			(sheetname "")
		)
		(fill
			(thermal_gap 0.5)
			(thermal_bridge_width 0.5)
			(island_removal_mode 0)
		)
		(polygon
			(pts
				(xy 209.720434 0.080518) (xy 209.720434 -1.722882) (xy 210.279234 -1.722882) (xy 210.279234 0.080518)
			)
		)
	)
	(zone
		(layer "In1.Cu")
		(hatch none 0.5)
		(connect_pads
			(clearance 0)
		)
		(min_thickness 0.25)
		(keepout
			(tracks not_allowed)
			(vias allowed)
			(pads allowed)
			(copperpour not_allowed)
			(footprints allowed)
		)
		(placement
			(enabled no)
			(sheetname "")
		)
		(fill
			(thermal_gap 0.5)
			(thermal_bridge_width 0.5)
			(island_removal_mode 0)
		)
		(polygon
			(pts
				(xy 86.37016 -14.521942) (xy 86.37016 -16.325342) (xy 86.92896 -16.325342) (xy 86.92896 -14.521942)
			)
		)
	)
	(zone
		(layer "In1.Cu")
		(hatch none 0.5)
		(connect_pads
			(clearance 0)
		)
		(min_thickness 0.25)
		(keepout
			(tracks not_allowed)
			(vias allowed)
			(pads allowed)
			(copperpour not_allowed)
			(footprints allowed)
		)
		(placement
			(enabled no)
			(sheetname "")
		)
		(fill
			(thermal_gap 0.5)
			(thermal_bridge_width 0.5)
			(island_removal_mode 0)
		)
		(polygon
			(pts
				(xy 149.269958 -146.375882) (xy 149.269958 -148.179282) (xy 149.828758 -148.179282) (xy 149.828758 -146.375882)
			)
		)
	)
	(zone
		(layer "In1.Cu")
		(hatch none 0.5)
		(connect_pads
			(clearance 0)
		)
		(min_thickness 0.25)
		(keepout
			(tracks not_allowed)
			(vias allowed)
			(pads allowed)
			(copperpour not_allowed)
			(footprints allowed)
		)
		(placement
			(enabled no)
			(sheetname "")
		)
		(fill
			(thermal_gap 0.5)
			(thermal_bridge_width 0.5)
			(island_removal_mode 0)
		)
		(polygon
			(pts
				(xy 118.67007 -136.774682) (xy 118.67007 -138.578082) (xy 119.22887 -138.578082) (xy 119.22887 -136.774682)
			)
		)
	)
	(zone
		(layer "In1.Cu")
		(hatch none 0.5)
		(connect_pads
			(clearance 0)
		)
		(min_thickness 0.25)
		(keepout
			(tracks not_allowed)
			(vias allowed)
			(pads allowed)
			(copperpour not_allowed)
			(footprints allowed)
		)
		(placement
			(enabled no)
			(sheetname "")
		)
		(fill
			(thermal_gap 0.5)
			(thermal_bridge_width 0.5)
			(island_removal_mode 0)
		)
		(polygon
			(pts
				(xy 257.320542 -14.521942) (xy 257.320542 -16.325342) (xy 257.879342 -16.325342) (xy 257.879342 -14.521942)
			)
		)
	)
	(zone
		(layer "In1.Cu")
		(hatch none 0.5)
		(connect_pads
			(clearance 0)
		)
		(min_thickness 0.25)
		(keepout
			(tracks not_allowed)
			(vias allowed)
			(pads allowed)
			(copperpour not_allowed)
			(footprints allowed)
		)
		(placement
			(enabled no)
			(sheetname "")
		)
		(fill
			(thermal_gap 0.5)
			(thermal_bridge_width 0.5)
			(island_removal_mode 0)
		)
		(polygon
			(pts
				(xy 58.319924 0.080518) (xy 58.319924 -1.722882) (xy 58.878724 -1.722882) (xy 58.878724 0.080518)
			)
		)
	)
	(zone
		(layer "In1.Cu")
		(hatch none 0.5)
		(connect_pads
			(clearance 0)
		)
		(min_thickness 0.25)
		(keepout
			(tracks not_allowed)
			(vias allowed)
			(pads allowed)
			(copperpour not_allowed)
			(footprints allowed)
		)
		(placement
			(enabled no)
			(sheetname "")
		)
		(fill
			(thermal_gap 0.5)
			(thermal_bridge_width 0.5)
			(island_removal_mode 0)
		)
		(polygon
			(pts
				(xy 219.920566 -19.121882) (xy 219.920566 -20.925282) (xy 220.479366 -20.925282) (xy 220.479366 -19.121882)
			)
		)
	)
	(zone
		(layer "In1.Cu")
		(hatch none 0.5)
		(connect_pads
			(clearance 0)
		)
		(min_thickness 0.25)
		(keepout
			(tracks not_allowed)
			(vias allowed)
			(pads allowed)
			(copperpour not_allowed)
			(footprints allowed)
		)
		(placement
			(enabled no)
			(sheetname "")
		)
		(fill
			(thermal_gap 0.5)
			(thermal_bridge_width 0.5)
			(island_removal_mode 0)
		)
		(polygon
			(pts
				(xy 242.870482 -4.920742) (xy 242.870482 -6.724142) (xy 243.429282 -6.724142) (xy 243.429282 -4.920742)
			)
		)
	)
	(zone
		(layer "In1.Cu")
		(hatch none 0.5)
		(connect_pads
			(clearance 0)
		)
		(min_thickness 0.25)
		(keepout
			(tracks not_allowed)
			(vias allowed)
			(pads allowed)
			(copperpour not_allowed)
			(footprints allowed)
		)
		(placement
			(enabled no)
			(sheetname "")
		)
		(fill
			(thermal_gap 0.5)
			(thermal_bridge_width 0.5)
			(island_removal_mode 0)
		)
		(polygon
			(pts
				(xy 149.269958 -155.977082) (xy 149.269958 -157.780482) (xy 149.828758 -157.780482) (xy 149.828758 -155.977082)
			)
		)
	)
	(zone
		(layer "In1.Cu")
		(hatch none 0.5)
		(connect_pads
			(clearance 0)
		)
		(min_thickness 0.25)
		(keepout
			(tracks not_allowed)
			(vias allowed)
			(pads allowed)
			(copperpour not_allowed)
			(footprints allowed)
		)
		(placement
			(enabled no)
			(sheetname "")
		)
		(fill
			(thermal_gap 0.5)
			(thermal_bridge_width 0.5)
			(island_removal_mode 0)
		)
		(polygon
			(pts
				(xy 230.120444 -141.775942) (xy 230.120444 -143.579342) (xy 230.679244 -143.579342) (xy 230.679244 -141.775942)
			)
		)
	)
	(zone
		(layer "In1.Cu")
		(hatch none 0.5)
		(connect_pads
			(clearance 0)
		)
		(min_thickness 0.25)
		(keepout
			(tracks not_allowed)
			(vias allowed)
			(pads allowed)
			(copperpour not_allowed)
			(footprints allowed)
		)
		(placement
			(enabled no)
			(sheetname "")
		)
		(fill
			(thermal_gap 0.5)
			(thermal_bridge_width 0.5)
			(island_removal_mode 0)
		)
		(polygon
			(pts
				(xy 119.519954 -9.520682) (xy 119.519954 -11.324082) (xy 120.078754 -11.324082) (xy 120.078754 -9.520682)
			)
		)
	)
	(zone
		(layer "In1.Cu")
		(hatch none 0.5)
		(connect_pads
			(clearance 0)
		)
		(min_thickness 0.25)
		(keepout
			(tracks not_allowed)
			(vias allowed)
			(pads allowed)
			(copperpour not_allowed)
			(footprints allowed)
		)
		(placement
			(enabled no)
			(sheetname "")
		)
		(fill
			(thermal_gap 0.5)
			(thermal_bridge_width 0.5)
			(island_removal_mode 0)
		)
		(polygon
			(pts
				(xy 77.02042 -136.774682) (xy 77.02042 -138.578082) (xy 77.57922 -138.578082) (xy 77.57922 -136.774682)
			)
		)
	)
	(zone
		(layer "In1.Cu")
		(hatch none 0.5)
		(connect_pads
			(clearance 0)
		)
		(min_thickness 0.25)
		(keepout
			(tracks not_allowed)
			(vias allowed)
			(pads allowed)
			(copperpour not_allowed)
			(footprints allowed)
		)
		(placement
			(enabled no)
			(sheetname "")
		)
		(fill
			(thermal_gap 0.5)
			(thermal_bridge_width 0.5)
			(island_removal_mode 0)
		)
		(polygon
			(pts
				(xy 298.120308 -141.775942) (xy 298.120308 -143.579342) (xy 298.679108 -143.579342) (xy 298.679108 -141.775942)
			)
		)
	)
	(zone
		(layer "In1.Cu")
		(hatch none 0.5)
		(connect_pads
			(clearance 0)
		)
		(min_thickness 0.25)
		(keepout
			(tracks not_allowed)
			(vias allowed)
			(pads allowed)
			(copperpour not_allowed)
			(footprints allowed)
		)
		(placement
			(enabled no)
			(sheetname "")
		)
		(fill
			(thermal_gap 0.5)
			(thermal_bridge_width 0.5)
			(island_removal_mode 0)
		)
		(polygon
			(pts
				(xy 314.27039 -9.520682) (xy 314.27039 -11.324082) (xy 314.82919 -11.324082) (xy 314.82919 -9.520682)
			)
		)
	)
	(zone
		(layer "In1.Cu")
		(hatch none 0.5)
		(connect_pads
			(clearance 0)
		)
		(min_thickness 0.25)
		(keepout
			(tracks not_allowed)
			(vias allowed)
			(pads allowed)
			(copperpour not_allowed)
			(footprints allowed)
		)
		(placement
			(enabled no)
			(sheetname "")
		)
		(fill
			(thermal_gap 0.5)
			(thermal_bridge_width 0.5)
			(island_removal_mode 0)
		)
		(polygon
			(pts
				(xy 106.77017 -14.521942) (xy 106.77017 -16.325342) (xy 107.32897 -16.325342) (xy 107.32897 -14.521942)
			)
		)
	)
	(zone
		(layer "In1.Cu")
		(hatch none 0.5)
		(connect_pads
			(clearance 0)
		)
		(min_thickness 0.25)
		(keepout
			(tracks not_allowed)
			(vias allowed)
			(pads allowed)
			(copperpour not_allowed)
			(footprints allowed)
		)
		(placement
			(enabled no)
			(sheetname "")
		)
		(fill
			(thermal_gap 0.5)
			(thermal_bridge_width 0.5)
			(island_removal_mode 0)
		)
		(polygon
			(pts
				(xy 45.57014 -19.121882) (xy 45.57014 -20.925282) (xy 46.12894 -20.925282) (xy 46.12894 -19.121882)
			)
		)
	)
	(zone
		(layer "In1.Cu")
		(hatch none 0.5)
		(connect_pads
			(clearance 0)
		)
		(min_thickness 0.25)
		(keepout
			(tracks not_allowed)
			(vias allowed)
			(pads allowed)
			(copperpour not_allowed)
			(footprints allowed)
		)
		(placement
			(enabled no)
			(sheetname "")
		)
		(fill
			(thermal_gap 0.5)
			(thermal_bridge_width 0.5)
			(island_removal_mode 0)
		)
		(polygon
			(pts
				(xy 248.820432 -14.521942) (xy 248.820432 -16.325342) (xy 249.379232 -16.325342) (xy 249.379232 -14.521942)
			)
		)
	)
	(zone
		(layer "In1.Cu")
		(hatch none 0.5)
		(connect_pads
			(clearance 0)
		)
		(min_thickness 0.25)
		(keepout
			(tracks not_allowed)
			(vias allowed)
			(pads allowed)
			(copperpour not_allowed)
			(footprints allowed)
		)
		(placement
			(enabled no)
			(sheetname "")
		)
		(fill
			(thermal_gap 0.5)
			(thermal_bridge_width 0.5)
			(island_removal_mode 0)
		)
		(polygon
			(pts
				(xy 366.831118 -7.193026) (xy 368.139218 -7.193026) (xy 368.139218 -8.386826) (xy 366.831118 -8.386826)
			)
		)
	)
	(zone
		(layer "In1.Cu")
		(hatch none 0.5)
		(connect_pads
			(clearance 0)
		)
		(min_thickness 0.25)
		(keepout
			(tracks not_allowed)
			(vias allowed)
			(pads allowed)
			(copperpour not_allowed)
			(footprints allowed)
		)
		(placement
			(enabled no)
			(sheetname "")
		)
		(fill
			(thermal_gap 0.5)
			(thermal_bridge_width 0.5)
			(island_removal_mode 0)
		)
		(polygon
			(pts
				(xy 249.67057 -19.121882) (xy 249.67057 -20.925282) (xy 250.22937 -20.925282) (xy 250.22937 -19.121882)
			)
		)
	)
	(zone
		(layer "In1.Cu")
		(hatch none 0.5)
		(connect_pads
			(clearance 0)
		)
		(min_thickness 0.25)
		(keepout
			(tracks not_allowed)
			(vias allowed)
			(pads allowed)
			(copperpour not_allowed)
			(footprints allowed)
		)
		(placement
			(enabled no)
			(sheetname "")
		)
		(fill
			(thermal_gap 0.5)
			(thermal_bridge_width 0.5)
			(island_removal_mode 0)
		)
		(polygon
			(pts
				(xy 42.170096 -132.174742) (xy 42.170096 -133.978142) (xy 42.728896 -133.978142) (xy 42.728896 -132.174742)
			)
		)
	)
	(zone
		(layer "In1.Cu")
		(hatch none 0.5)
		(connect_pads
			(clearance 0)
		)
		(min_thickness 0.25)
		(keepout
			(tracks not_allowed)
			(vias allowed)
			(pads allowed)
			(copperpour not_allowed)
			(footprints allowed)
		)
		(placement
			(enabled no)
			(sheetname "")
		)
		(fill
			(thermal_gap 0.5)
			(thermal_bridge_width 0.5)
			(island_removal_mode 0)
		)
		(polygon
			(pts
				(xy 112.72012 -146.375882) (xy 112.72012 -148.179282) (xy 113.27892 -148.179282) (xy 113.27892 -146.375882)
			)
		)
	)
	(zone
		(layer "In1.Cu")
		(hatch none 0.5)
		(connect_pads
			(clearance 0)
		)
		(min_thickness 0.25)
		(keepout
			(tracks not_allowed)
			(vias allowed)
			(pads allowed)
			(copperpour not_allowed)
			(footprints allowed)
		)
		(placement
			(enabled no)
			(sheetname "")
		)
		(fill
			(thermal_gap 0.5)
			(thermal_bridge_width 0.5)
			(island_removal_mode 0)
		)
		(polygon
			(pts
				(xy 66.820034 -4.920742) (xy 66.820034 -6.724142) (xy 67.378834 -6.724142) (xy 67.378834 -4.920742)
			)
		)
	)
	(zone
		(layer "In1.Cu")
		(hatch none 0.5)
		(connect_pads
			(clearance 0)
		)
		(min_thickness 0.25)
		(keepout
			(tracks not_allowed)
			(vias allowed)
			(pads allowed)
			(copperpour not_allowed)
			(footprints allowed)
		)
		(placement
			(enabled no)
			(sheetname "")
		)
		(fill
			(thermal_gap 0.5)
			(thermal_bridge_width 0.5)
			(island_removal_mode 0)
		)
		(polygon
			(pts
				(xy 274.320508 -4.920742) (xy 274.320508 -6.724142) (xy 274.879308 -6.724142) (xy 274.879308 -4.920742)
			)
		)
	)
	(zone
		(layer "In1.Cu")
		(hatch none 0.5)
		(connect_pads
			(clearance 0)
		)
		(min_thickness 0.25)
		(keepout
			(tracks not_allowed)
			(vias allowed)
			(pads allowed)
			(copperpour not_allowed)
			(footprints allowed)
		)
		(placement
			(enabled no)
			(sheetname "")
		)
		(fill
			(thermal_gap 0.5)
			(thermal_bridge_width 0.5)
			(island_removal_mode 0)
		)
		(polygon
			(pts
				(xy 50.669952 0.080518) (xy 50.669952 -1.722882) (xy 51.228752 -1.722882) (xy 51.228752 0.080518)
			)
		)
	)
	(zone
		(layer "In1.Cu")
		(hatch none 0.5)
		(connect_pads
			(clearance 0)
		)
		(min_thickness 0.25)
		(keepout
			(tracks not_allowed)
			(vias allowed)
			(pads allowed)
			(copperpour not_allowed)
			(footprints allowed)
		)
		(placement
			(enabled no)
			(sheetname "")
		)
		(fill
			(thermal_gap 0.5)
			(thermal_bridge_width 0.5)
			(island_removal_mode 0)
		)
		(polygon
			(pts
				(xy 68.520056 -4.920742) (xy 68.520056 -6.724142) (xy 69.078856 -6.724142) (xy 69.078856 -4.920742)
			)
		)
	)
	(zone
		(layer "In1.Cu")
		(hatch none 0.5)
		(connect_pads
			(clearance 0)
		)
		(min_thickness 0.25)
		(keepout
			(tracks not_allowed)
			(vias allowed)
			(pads allowed)
			(copperpour not_allowed)
			(footprints allowed)
		)
		(placement
			(enabled no)
			(sheetname "")
		)
		(fill
			(thermal_gap 0.5)
			(thermal_bridge_width 0.5)
			(island_removal_mode 0)
		)
		(polygon
			(pts
				(xy 304.070512 -132.174742) (xy 304.070512 -133.978142) (xy 304.629312 -133.978142) (xy 304.629312 -132.174742)
			)
		)
	)
	(zone
		(layer "In1.Cu")
		(hatch none 0.5)
		(connect_pads
			(clearance 0)
		)
		(min_thickness 0.25)
		(keepout
			(tracks not_allowed)
			(vias allowed)
			(pads allowed)
			(copperpour not_allowed)
			(footprints allowed)
		)
		(placement
			(enabled no)
			(sheetname "")
		)
		(fill
			(thermal_gap 0.5)
			(thermal_bridge_width 0.5)
			(island_removal_mode 0)
		)
		(polygon
			(pts
				(xy 61.719968 0.080518) (xy 61.719968 -1.722882) (xy 62.278768 -1.722882) (xy 62.278768 0.080518)
			)
		)
	)
	(zone
		(layer "In1.Cu")
		(hatch none 0.5)
		(connect_pads
			(clearance 0)
		)
		(min_thickness 0.25)
		(keepout
			(tracks not_allowed)
			(vias allowed)
			(pads allowed)
			(copperpour not_allowed)
			(footprints allowed)
		)
		(placement
			(enabled no)
			(sheetname "")
		)
		(fill
			(thermal_gap 0.5)
			(thermal_bridge_width 0.5)
			(island_removal_mode 0)
		)
		(polygon
			(pts
				(xy 128.020064 -141.775942) (xy 128.020064 -143.579342) (xy 128.578864 -143.579342) (xy 128.578864 -141.775942)
			)
		)
	)
	(zone
		(layer "In1.Cu")
		(hatch none 0.5)
		(connect_pads
			(clearance 0)
		)
		(min_thickness 0.25)
		(keepout
			(tracks not_allowed)
			(vias allowed)
			(pads allowed)
			(copperpour not_allowed)
			(footprints allowed)
		)
		(placement
			(enabled no)
			(sheetname "")
		)
		(fill
			(thermal_gap 0.5)
			(thermal_bridge_width 0.5)
			(island_removal_mode 0)
		)
		(polygon
			(pts
				(xy 237.770416 0.080518) (xy 237.770416 -1.722882) (xy 238.329216 -1.722882) (xy 238.329216 0.080518)
			)
		)
	)
	(zone
		(layer "In1.Cu")
		(hatch none 0.5)
		(connect_pads
			(clearance 0)
		)
		(min_thickness 0.25)
		(keepout
			(tracks not_allowed)
			(vias allowed)
			(pads allowed)
			(copperpour not_allowed)
			(footprints allowed)
		)
		(placement
			(enabled no)
			(sheetname "")
		)
		(fill
			(thermal_gap 0.5)
			(thermal_bridge_width 0.5)
			(island_removal_mode 0)
		)
		(polygon
			(pts
				(xy 144.169892 -132.174742) (xy 144.169892 -133.978142) (xy 144.728692 -133.978142) (xy 144.728692 -132.174742)
			)
		)
	)
	(zone
		(layer "In1.Cu")
		(hatch none 0.5)
		(connect_pads
			(clearance 0)
		)
		(min_thickness 0.25)
		(keepout
			(tracks not_allowed)
			(vias allowed)
			(pads allowed)
			(copperpour not_allowed)
			(footprints allowed)
		)
		(placement
			(enabled no)
			(sheetname "")
		)
		(fill
			(thermal_gap 0.5)
			(thermal_bridge_width 0.5)
			(island_removal_mode 0)
		)
		(polygon
			(pts
				(xy 67.669918 -146.375882) (xy 67.669918 -148.179282) (xy 68.228718 -148.179282) (xy 68.228718 -146.375882)
			)
		)
	)
	(zone
		(layer "In1.Cu")
		(hatch none 0.5)
		(connect_pads
			(clearance 0)
		)
		(min_thickness 0.25)
		(keepout
			(tracks not_allowed)
			(vias allowed)
			(pads allowed)
			(copperpour not_allowed)
			(footprints allowed)
		)
		(placement
			(enabled no)
			(sheetname "")
		)
		(fill
			(thermal_gap 0.5)
			(thermal_bridge_width 0.5)
			(island_removal_mode 0)
		)
		(polygon
			(pts
				(xy 283.670502 4.680458) (xy 283.670502 2.877058) (xy 284.229302 2.877058) (xy 284.229302 4.680458)
			)
		)
	)
	(zone
		(layer "In1.Cu")
		(hatch none 0.5)
		(connect_pads
			(clearance 0)
		)
		(min_thickness 0.25)
		(keepout
			(tracks not_allowed)
			(vias allowed)
			(pads allowed)
			(copperpour not_allowed)
			(footprints allowed)
		)
		(placement
			(enabled no)
			(sheetname "")
		)
		(fill
			(thermal_gap 0.5)
			(thermal_bridge_width 0.5)
			(island_removal_mode 0)
		)
		(polygon
			(pts
				(xy 298.120308 -4.920742) (xy 298.120308 -6.724142) (xy 298.679108 -6.724142) (xy 298.679108 -4.920742)
			)
		)
	)
	(zone
		(layer "In1.Cu")
		(hatch none 0.5)
		(connect_pads
			(clearance 0)
		)
		(min_thickness 0.25)
		(keepout
			(tracks not_allowed)
			(vias allowed)
			(pads allowed)
			(copperpour not_allowed)
			(footprints allowed)
		)
		(placement
			(enabled no)
			(sheetname "")
		)
		(fill
			(thermal_gap 0.5)
			(thermal_bridge_width 0.5)
			(island_removal_mode 0)
		)
		(polygon
			(pts
				(xy 134.819898 -14.521942) (xy 134.819898 -16.325342) (xy 135.378698 -16.325342) (xy 135.378698 -14.521942)
			)
		)
	)
	(zone
		(layer "In1.Cu")
		(hatch none 0.5)
		(connect_pads
			(clearance 0)
		)
		(min_thickness 0.25)
		(keepout
			(tracks not_allowed)
			(vias allowed)
			(pads allowed)
			(copperpour not_allowed)
			(footprints allowed)
		)
		(placement
			(enabled no)
			(sheetname "")
		)
		(fill
			(thermal_gap 0.5)
			(thermal_bridge_width 0.5)
			(island_removal_mode 0)
		)
		(polygon
			(pts
				(xy 225.870516 -14.521942) (xy 225.870516 -16.325342) (xy 226.429316 -16.325342) (xy 226.429316 -14.521942)
			)
		)
	)
	(zone
		(layer "In1.Cu")
		(hatch none 0.5)
		(connect_pads
			(clearance 0)
		)
		(min_thickness 0.25)
		(keepout
			(tracks not_allowed)
			(vias allowed)
			(pads allowed)
			(copperpour not_allowed)
			(footprints allowed)
		)
		(placement
			(enabled no)
			(sheetname "")
		)
		(fill
			(thermal_gap 0.5)
			(thermal_bridge_width 0.5)
			(island_removal_mode 0)
		)
		(polygon
			(pts
				(xy 247.970548 0.080518) (xy 247.970548 -1.722882) (xy 248.529348 -1.722882) (xy 248.529348 0.080518)
			)
		)
	)
	(zone
		(layer "In1.Cu")
		(hatch none 0.5)
		(connect_pads
			(clearance 0)
		)
		(min_thickness 0.25)
		(keepout
			(tracks not_allowed)
			(vias allowed)
			(pads allowed)
			(copperpour not_allowed)
			(footprints allowed)
		)
		(placement
			(enabled no)
			(sheetname "")
		)
		(fill
			(thermal_gap 0.5)
			(thermal_bridge_width 0.5)
			(island_removal_mode 0)
		)
		(polygon
			(pts
				(xy 331.745844 -117.10162) (xy 334.031844 -117.10162) (xy 334.031844 -117.60962) (xy 331.745844 -117.60962)
			)
		)
	)
	(zone
		(layer "In1.Cu")
		(hatch none 0.5)
		(connect_pads
			(clearance 0)
		)
		(min_thickness 0.25)
		(keepout
			(tracks not_allowed)
			(vias allowed)
			(pads allowed)
			(copperpour not_allowed)
			(footprints allowed)
		)
		(placement
			(enabled no)
			(sheetname "")
		)
		(fill
			(thermal_gap 0.5)
			(thermal_bridge_width 0.5)
			(island_removal_mode 0)
		)
		(polygon
			(pts
				(xy 304.920396 -146.375882) (xy 304.920396 -148.179282) (xy 305.479196 -148.179282) (xy 305.479196 -146.375882)
			)
		)
	)
	(zone
		(layer "In1.Cu")
		(hatch none 0.5)
		(connect_pads
			(clearance 0)
		)
		(min_thickness 0.25)
		(keepout
			(tracks not_allowed)
			(vias allowed)
			(pads allowed)
			(copperpour not_allowed)
			(footprints allowed)
		)
		(placement
			(enabled no)
			(sheetname "")
		)
		(fill
			(thermal_gap 0.5)
			(thermal_bridge_width 0.5)
			(island_removal_mode 0)
		)
		(polygon
			(pts
				(xy 284.520386 -155.977082) (xy 284.520386 -157.780482) (xy 285.079186 -157.780482) (xy 285.079186 -155.977082)
			)
		)
	)
	(zone
		(layer "In1.Cu")
		(hatch none 0.5)
		(connect_pads
			(clearance 0)
		)
		(min_thickness 0.25)
		(keepout
			(tracks not_allowed)
			(vias allowed)
			(pads allowed)
			(copperpour not_allowed)
			(footprints allowed)
		)
		(placement
			(enabled no)
			(sheetname "")
		)
		(fill
			(thermal_gap 0.5)
			(thermal_bridge_width 0.5)
			(island_removal_mode 0)
		)
		(polygon
			(pts
				(xy 83.82 -4.920742) (xy 83.82 -6.724142) (xy 84.3788 -6.724142) (xy 84.3788 -4.920742)
			)
		)
	)
	(zone
		(layer "In1.Cu")
		(hatch none 0.5)
		(connect_pads
			(clearance 0)
		)
		(min_thickness 0.25)
		(keepout
			(tracks not_allowed)
			(vias allowed)
			(pads allowed)
			(copperpour not_allowed)
			(footprints allowed)
		)
		(placement
			(enabled no)
			(sheetname "")
		)
		(fill
			(thermal_gap 0.5)
			(thermal_bridge_width 0.5)
			(island_removal_mode 0)
		)
		(polygon
			(pts
				(xy 67.669918 -155.977082) (xy 67.669918 -157.780482) (xy 68.228718 -157.780482) (xy 68.228718 -155.977082)
			)
		)
	)
	(zone
		(layer "In1.Cu")
		(hatch none 0.5)
		(connect_pads
			(clearance 0)
		)
		(min_thickness 0.25)
		(keepout
			(tracks not_allowed)
			(vias allowed)
			(pads allowed)
			(copperpour not_allowed)
			(footprints allowed)
		)
		(placement
			(enabled no)
			(sheetname "")
		)
		(fill
			(thermal_gap 0.5)
			(thermal_bridge_width 0.5)
			(island_removal_mode 0)
		)
		(polygon
			(pts
				(xy 397.016986 -3.789172) (xy 398.325086 -3.789172) (xy 398.325086 -4.982972) (xy 397.016986 -4.982972)
			)
		)
	)
	(zone
		(layer "In1.Cu")
		(hatch none 0.5)
		(connect_pads
			(clearance 0)
		)
		(min_thickness 0.25)
		(keepout
			(tracks not_allowed)
			(vias allowed)
			(pads allowed)
			(copperpour not_allowed)
			(footprints allowed)
		)
		(placement
			(enabled no)
			(sheetname "")
		)
		(fill
			(thermal_gap 0.5)
			(thermal_bridge_width 0.5)
			(island_removal_mode 0)
		)
		(polygon
			(pts
				(xy 41.319958 -136.774682) (xy 41.319958 -138.578082) (xy 41.878758 -138.578082) (xy 41.878758 -136.774682)
			)
		)
	)
	(zone
		(layer "In1.Cu")
		(hatch none 0.5)
		(connect_pads
			(clearance 0)
		)
		(min_thickness 0.25)
		(keepout
			(tracks not_allowed)
			(vias allowed)
			(pads allowed)
			(copperpour not_allowed)
			(footprints allowed)
		)
		(placement
			(enabled no)
			(sheetname "")
		)
		(fill
			(thermal_gap 0.5)
			(thermal_bridge_width 0.5)
			(island_removal_mode 0)
		)
		(polygon
			(pts
				(xy 219.070428 -14.521942) (xy 219.070428 -16.325342) (xy 219.629228 -16.325342) (xy 219.629228 -14.521942)
			)
		)
	)
	(zone
		(layer "In1.Cu")
		(hatch none 0.5)
		(connect_pads
			(clearance 0)
		)
		(min_thickness 0.25)
		(keepout
			(tracks not_allowed)
			(vias allowed)
			(pads allowed)
			(copperpour not_allowed)
			(footprints allowed)
		)
		(placement
			(enabled no)
			(sheetname "")
		)
		(fill
			(thermal_gap 0.5)
			(thermal_bridge_width 0.5)
			(island_removal_mode 0)
		)
		(polygon
			(pts
				(xy 196.970396 -155.977082) (xy 196.970396 -157.780482) (xy 197.529196 -157.780482) (xy 197.529196 -155.977082)
			)
		)
	)
	(zone
		(layer "In1.Cu")
		(hatch none 0.5)
		(connect_pads
			(clearance 0)
		)
		(min_thickness 0.25)
		(keepout
			(tracks not_allowed)
			(vias allowed)
			(pads allowed)
			(copperpour not_allowed)
			(footprints allowed)
		)
		(placement
			(enabled no)
			(sheetname "")
		)
		(fill
			(thermal_gap 0.5)
			(thermal_bridge_width 0.5)
			(island_removal_mode 0)
		)
		(polygon
			(pts
				(xy 73.620122 -136.774682) (xy 73.620122 -138.578082) (xy 74.178922 -138.578082) (xy 74.178922 -136.774682)
			)
		)
	)
	(zone
		(layer "In1.Cu")
		(hatch none 0.5)
		(connect_pads
			(clearance 0)
		)
		(min_thickness 0.25)
		(keepout
			(tracks not_allowed)
			(vias allowed)
			(pads allowed)
			(copperpour not_allowed)
			(footprints allowed)
		)
		(placement
			(enabled no)
			(sheetname "")
		)
		(fill
			(thermal_gap 0.5)
			(thermal_bridge_width 0.5)
			(island_removal_mode 0)
		)
		(polygon
			(pts
				(xy 312.570368 -136.774682) (xy 312.570368 -138.578082) (xy 313.129168 -138.578082) (xy 313.129168 -136.774682)
			)
		)
	)
	(zone
		(layer "In1.Cu")
		(hatch none 0.5)
		(connect_pads
			(clearance 0)
		)
		(min_thickness 0.25)
		(keepout
			(tracks not_allowed)
			(vias allowed)
			(pads allowed)
			(copperpour not_allowed)
			(footprints allowed)
		)
		(placement
			(enabled no)
			(sheetname "")
		)
		(fill
			(thermal_gap 0.5)
			(thermal_bridge_width 0.5)
			(island_removal_mode 0)
		)
		(polygon
			(pts
				(xy 88.920066 -151.377142) (xy 88.920066 -153.180542) (xy 89.478866 -153.180542) (xy 89.478866 -151.377142)
			)
		)
	)
	(zone
		(layer "In1.Cu")
		(hatch none 0.5)
		(connect_pads
			(clearance 0)
		)
		(min_thickness 0.25)
		(keepout
			(tracks not_allowed)
			(vias allowed)
			(pads allowed)
			(copperpour not_allowed)
			(footprints allowed)
		)
		(placement
			(enabled no)
			(sheetname "")
		)
		(fill
			(thermal_gap 0.5)
			(thermal_bridge_width 0.5)
			(island_removal_mode 0)
		)
		(polygon
			(pts
				(xy 221.620588 -19.121882) (xy 221.620588 -20.925282) (xy 222.179388 -20.925282) (xy 222.179388 -19.121882)
			)
		)
	)
	(zone
		(layer "In1.Cu")
		(hatch none 0.5)
		(connect_pads
			(clearance 0)
		)
		(min_thickness 0.25)
		(keepout
			(tracks not_allowed)
			(vias allowed)
			(pads allowed)
			(copperpour not_allowed)
			(footprints allowed)
		)
		(placement
			(enabled no)
			(sheetname "")
		)
		(fill
			(thermal_gap 0.5)
			(thermal_bridge_width 0.5)
			(island_removal_mode 0)
		)
		(polygon
			(pts
				(xy 246.270526 -141.775942) (xy 246.270526 -143.579342) (xy 246.829326 -143.579342) (xy 246.829326 -141.775942)
			)
		)
	)
	(zone
		(layer "In1.Cu")
		(hatch none 0.5)
		(connect_pads
			(clearance 0)
		)
		(min_thickness 0.25)
		(keepout
			(tracks not_allowed)
			(vias allowed)
			(pads allowed)
			(copperpour not_allowed)
			(footprints allowed)
		)
		(placement
			(enabled no)
			(sheetname "")
		)
		(fill
			(thermal_gap 0.5)
			(thermal_bridge_width 0.5)
			(island_removal_mode 0)
		)
		(polygon
			(pts
				(xy 287.92043 0.080518) (xy 287.92043 -1.722882) (xy 288.47923 -1.722882) (xy 288.47923 0.080518)
			)
		)
	)
	(zone
		(layer "In1.Cu")
		(hatch none 0.5)
		(connect_pads
			(clearance 0)
		)
		(min_thickness 0.25)
		(keepout
			(tracks not_allowed)
			(vias allowed)
			(pads allowed)
			(copperpour not_allowed)
			(footprints allowed)
		)
		(placement
			(enabled no)
			(sheetname "")
		)
		(fill
			(thermal_gap 0.5)
			(thermal_bridge_width 0.5)
			(island_removal_mode 0)
		)
		(polygon
			(pts
				(xy 75.320144 -146.375882) (xy 75.320144 -148.179282) (xy 75.878944 -148.179282) (xy 75.878944 -146.375882)
			)
		)
	)
	(zone
		(layer "In1.Cu")
		(hatch none 0.5)
		(connect_pads
			(clearance 0)
		)
		(min_thickness 0.25)
		(keepout
			(tracks not_allowed)
			(vias allowed)
			(pads allowed)
			(copperpour not_allowed)
			(footprints allowed)
		)
		(placement
			(enabled no)
			(sheetname "")
		)
		(fill
			(thermal_gap 0.5)
			(thermal_bridge_width 0.5)
			(island_removal_mode 0)
		)
		(polygon
			(pts
				(xy 44.720002 4.680458) (xy 44.720002 2.877058) (xy 45.278802 2.877058) (xy 45.278802 4.680458)
			)
		)
	)
	(zone
		(layer "In1.Cu")
		(hatch none 0.5)
		(connect_pads
			(clearance 0)
		)
		(min_thickness 0.25)
		(keepout
			(tracks not_allowed)
			(vias allowed)
			(pads allowed)
			(copperpour not_allowed)
			(footprints allowed)
		)
		(placement
			(enabled no)
			(sheetname "")
		)
		(fill
			(thermal_gap 0.5)
			(thermal_bridge_width 0.5)
			(island_removal_mode 0)
		)
		(polygon
			(pts
				(xy 122.070114 -14.521942) (xy 122.070114 -16.325342) (xy 122.628914 -16.325342) (xy 122.628914 -14.521942)
			)
		)
	)
	(zone
		(layer "In1.Cu")
		(hatch none 0.5)
		(connect_pads
			(clearance 0)
		)
		(min_thickness 0.25)
		(keepout
			(tracks not_allowed)
			(vias allowed)
			(pads allowed)
			(copperpour not_allowed)
			(footprints allowed)
		)
		(placement
			(enabled no)
			(sheetname "")
		)
		(fill
			(thermal_gap 0.5)
			(thermal_bridge_width 0.5)
			(island_removal_mode 0)
		)
		(polygon
			(pts
				(xy 281.120342 -151.377142) (xy 281.120342 -153.180542) (xy 281.679142 -153.180542) (xy 281.679142 -151.377142)
			)
		)
	)
	(zone
		(layer "In1.Cu")
		(hatch none 0.5)
		(connect_pads
			(clearance 0)
		)
		(min_thickness 0.25)
		(keepout
			(tracks not_allowed)
			(vias allowed)
			(pads allowed)
			(copperpour not_allowed)
			(footprints allowed)
		)
		(placement
			(enabled no)
			(sheetname "")
		)
		(fill
			(thermal_gap 0.5)
			(thermal_bridge_width 0.5)
			(island_removal_mode 0)
		)
		(polygon
			(pts
				(xy 418.619686 -3.789172) (xy 419.927786 -3.789172) (xy 419.927786 -4.982972) (xy 418.619686 -4.982972)
			)
		)
	)
	(zone
		(layer "In1.Cu")
		(hatch none 0.5)
		(connect_pads
			(clearance 0)
		)
		(min_thickness 0.25)
		(keepout
			(tracks not_allowed)
			(vias allowed)
			(pads allowed)
			(copperpour not_allowed)
			(footprints allowed)
		)
		(placement
			(enabled no)
			(sheetname "")
		)
		(fill
			(thermal_gap 0.5)
			(thermal_bridge_width 0.5)
			(island_removal_mode 0)
		)
		(polygon
			(pts
				(xy 37.07003 4.680458) (xy 37.07003 2.877058) (xy 37.62883 2.877058) (xy 37.62883 4.680458)
			)
		)
	)
	(zone
		(layer "In1.Cu")
		(hatch none 0.5)
		(connect_pads
			(clearance 0)
		)
		(min_thickness 0.25)
		(keepout
			(tracks not_allowed)
			(vias allowed)
			(pads allowed)
			(copperpour not_allowed)
			(footprints allowed)
		)
		(placement
			(enabled no)
			(sheetname "")
		)
		(fill
			(thermal_gap 0.5)
			(thermal_bridge_width 0.5)
			(island_removal_mode 0)
		)
		(polygon
			(pts
				(xy 149.269958 -136.774682) (xy 149.269958 -138.578082) (xy 149.828758 -138.578082) (xy 149.828758 -136.774682)
			)
		)
	)
	(zone
		(layer "In1.Cu")
		(hatch none 0.5)
		(connect_pads
			(clearance 0)
		)
		(min_thickness 0.25)
		(keepout
			(tracks not_allowed)
			(vias allowed)
			(pads allowed)
			(copperpour not_allowed)
			(footprints allowed)
		)
		(placement
			(enabled no)
			(sheetname "")
		)
		(fill
			(thermal_gap 0.5)
			(thermal_bridge_width 0.5)
			(island_removal_mode 0)
		)
		(polygon
			(pts
				(xy 32.820102 -14.521942) (xy 32.820102 -16.325342) (xy 33.378902 -16.325342) (xy 33.378902 -14.521942)
			)
		)
	)
	(zone
		(layer "In1.Cu")
		(hatch none 0.5)
		(connect_pads
			(clearance 0)
		)
		(min_thickness 0.25)
		(keepout
			(tracks not_allowed)
			(vias allowed)
			(pads allowed)
			(copperpour not_allowed)
			(footprints allowed)
		)
		(placement
			(enabled no)
			(sheetname "")
		)
		(fill
			(thermal_gap 0.5)
			(thermal_bridge_width 0.5)
			(island_removal_mode 0)
		)
		(polygon
			(pts
				(xy 124.62002 -9.520682) (xy 124.62002 -11.324082) (xy 125.17882 -11.324082) (xy 125.17882 -9.520682)
			)
		)
	)
	(zone
		(layer "In1.Cu")
		(hatch none 0.5)
		(connect_pads
			(clearance 0)
		)
		(min_thickness 0.25)
		(keepout
			(tracks not_allowed)
			(vias allowed)
			(pads allowed)
			(copperpour not_allowed)
			(footprints allowed)
		)
		(placement
			(enabled no)
			(sheetname "")
		)
		(fill
			(thermal_gap 0.5)
			(thermal_bridge_width 0.5)
			(island_removal_mode 0)
		)
		(polygon
			(pts
				(xy 249.67057 -146.375882) (xy 249.67057 -148.179282) (xy 250.22937 -148.179282) (xy 250.22937 -146.375882)
			)
		)
	)
	(zone
		(layer "In1.Cu")
		(hatch none 0.5)
		(connect_pads
			(clearance 0)
		)
		(min_thickness 0.25)
		(keepout
			(tracks not_allowed)
			(vias allowed)
			(pads allowed)
			(copperpour not_allowed)
			(footprints allowed)
		)
		(placement
			(enabled no)
			(sheetname "")
		)
		(fill
			(thermal_gap 0.5)
			(thermal_bridge_width 0.5)
			(island_removal_mode 0)
		)
		(polygon
			(pts
				(xy 148.420074 -14.521942) (xy 148.420074 -16.325342) (xy 148.978874 -16.325342) (xy 148.978874 -14.521942)
			)
		)
	)
	(zone
		(layer "In1.Cu")
		(hatch none 0.5)
		(connect_pads
			(clearance 0)
		)
		(min_thickness 0.25)
		(keepout
			(tracks not_allowed)
			(vias allowed)
			(pads allowed)
			(copperpour not_allowed)
			(footprints allowed)
		)
		(placement
			(enabled no)
			(sheetname "")
		)
		(fill
			(thermal_gap 0.5)
			(thermal_bridge_width 0.5)
			(island_removal_mode 0)
		)
		(polygon
			(pts
				(xy 195.270374 -155.977082) (xy 195.270374 -157.780482) (xy 195.829174 -157.780482) (xy 195.829174 -155.977082)
			)
		)
	)
	(zone
		(layer "In1.Cu")
		(hatch none 0.5)
		(connect_pads
			(clearance 0)
		)
		(min_thickness 0.25)
		(keepout
			(tracks not_allowed)
			(vias allowed)
			(pads allowed)
			(copperpour not_allowed)
			(footprints allowed)
		)
		(placement
			(enabled no)
			(sheetname "")
		)
		(fill
			(thermal_gap 0.5)
			(thermal_bridge_width 0.5)
			(island_removal_mode 0)
		)
		(polygon
			(pts
				(xy 72.769984 -19.121882) (xy 72.769984 -20.925282) (xy 73.328784 -20.925282) (xy 73.328784 -19.121882)
			)
		)
	)
	(zone
		(layer "In1.Cu")
		(hatch none 0.5)
		(connect_pads
			(clearance 0)
		)
		(min_thickness 0.25)
		(keepout
			(tracks not_allowed)
			(vias allowed)
			(pads allowed)
			(copperpour not_allowed)
			(footprints allowed)
		)
		(placement
			(enabled no)
			(sheetname "")
		)
		(fill
			(thermal_gap 0.5)
			(thermal_bridge_width 0.5)
			(island_removal_mode 0)
		)
		(polygon
			(pts
				(xy 218.220544 4.680458) (xy 218.220544 2.877058) (xy 218.779344 2.877058) (xy 218.779344 4.680458)
			)
		)
	)
	(zone
		(layer "In1.Cu")
		(hatch none 0.5)
		(connect_pads
			(clearance 0)
		)
		(min_thickness 0.25)
		(keepout
			(tracks not_allowed)
			(vias allowed)
			(pads allowed)
			(copperpour not_allowed)
			(footprints allowed)
		)
		(placement
			(enabled no)
			(sheetname "")
		)
		(fill
			(thermal_gap 0.5)
			(thermal_bridge_width 0.5)
			(island_removal_mode 0)
		)
		(polygon
			(pts
				(xy 289.620452 -19.121882) (xy 289.620452 -20.925282) (xy 290.179252 -20.925282) (xy 290.179252 -19.121882)
			)
		)
	)
	(zone
		(layer "In1.Cu")
		(hatch none 0.5)
		(connect_pads
			(clearance 0)
		)
		(min_thickness 0.25)
		(keepout
			(tracks not_allowed)
			(vias allowed)
			(pads allowed)
			(copperpour not_allowed)
			(footprints allowed)
		)
		(placement
			(enabled no)
			(sheetname "")
		)
		(fill
			(thermal_gap 0.5)
			(thermal_bridge_width 0.5)
			(island_removal_mode 0)
		)
		(polygon
			(pts
				(xy 312.570368 -155.977082) (xy 312.570368 -157.780482) (xy 313.129168 -157.780482) (xy 313.129168 -155.977082)
			)
		)
	)
	(zone
		(layer "In1.Cu")
		(hatch none 0.5)
		(connect_pads
			(clearance 0)
		)
		(min_thickness 0.25)
		(keepout
			(tracks not_allowed)
			(vias allowed)
			(pads allowed)
			(copperpour not_allowed)
			(footprints allowed)
		)
		(placement
			(enabled no)
			(sheetname "")
		)
		(fill
			(thermal_gap 0.5)
			(thermal_bridge_width 0.5)
			(island_removal_mode 0)
		)
		(polygon
			(pts
				(xy 79.570072 -4.920742) (xy 79.570072 -6.724142) (xy 80.128872 -6.724142) (xy 80.128872 -4.920742)
			)
		)
	)
	(zone
		(layer "In1.Cu")
		(hatch none 0.5)
		(connect_pads
			(clearance 0)
		)
		(min_thickness 0.25)
		(keepout
			(tracks not_allowed)
			(vias allowed)
			(pads allowed)
			(copperpour not_allowed)
			(footprints allowed)
		)
		(placement
			(enabled no)
			(sheetname "")
		)
		(fill
			(thermal_gap 0.5)
			(thermal_bridge_width 0.5)
			(island_removal_mode 0)
		)
		(polygon
			(pts
				(xy 82.970116 0.080518) (xy 82.970116 -1.722882) (xy 83.528916 -1.722882) (xy 83.528916 0.080518)
			)
		)
	)
	(zone
		(layer "In1.Cu")
		(hatch none 0.5)
		(connect_pads
			(clearance 0)
		)
		(min_thickness 0.25)
		(keepout
			(tracks not_allowed)
			(vias allowed)
			(pads allowed)
			(copperpour not_allowed)
			(footprints allowed)
		)
		(placement
			(enabled no)
			(sheetname "")
		)
		(fill
			(thermal_gap 0.5)
			(thermal_bridge_width 0.5)
			(island_removal_mode 0)
		)
		(polygon
			(pts
				(xy 202.070462 -4.920742) (xy 202.070462 -6.724142) (xy 202.629262 -6.724142) (xy 202.629262 -4.920742)
			)
		)
	)
	(zone
		(layer "In1.Cu")
		(hatch none 0.5)
		(connect_pads
			(clearance 0)
		)
		(min_thickness 0.25)
		(keepout
			(tracks not_allowed)
			(vias allowed)
			(pads allowed)
			(copperpour not_allowed)
			(footprints allowed)
		)
		(placement
			(enabled no)
			(sheetname "")
		)
		(fill
			(thermal_gap 0.5)
			(thermal_bridge_width 0.5)
			(island_removal_mode 0)
		)
		(polygon
			(pts
				(xy 197.820534 -132.174742) (xy 197.820534 -133.978142) (xy 198.379334 -133.978142) (xy 198.379334 -132.174742)
			)
		)
	)
	(zone
		(layer "In1.Cu")
		(hatch none 0.5)
		(connect_pads
			(clearance 0)
		)
		(min_thickness 0.25)
		(keepout
			(tracks not_allowed)
			(vias allowed)
			(pads allowed)
			(copperpour not_allowed)
			(footprints allowed)
		)
		(placement
			(enabled no)
			(sheetname "")
		)
		(fill
			(thermal_gap 0.5)
			(thermal_bridge_width 0.5)
			(island_removal_mode 0)
		)
		(polygon
			(pts
				(xy 92.32011 -136.774682) (xy 92.32011 -138.578082) (xy 92.87891 -138.578082) (xy 92.87891 -136.774682)
			)
		)
	)
	(zone
		(layer "In1.Cu")
		(hatch none 0.5)
		(connect_pads
			(clearance 0)
		)
		(min_thickness 0.25)
		(keepout
			(tracks not_allowed)
			(vias allowed)
			(pads allowed)
			(copperpour not_allowed)
			(footprints allowed)
		)
		(placement
			(enabled no)
			(sheetname "")
		)
		(fill
			(thermal_gap 0.5)
			(thermal_bridge_width 0.5)
			(island_removal_mode 0)
		)
		(polygon
			(pts
				(xy 82.119978 -151.377142) (xy 82.119978 -153.180542) (xy 82.678778 -153.180542) (xy 82.678778 -151.377142)
			)
		)
	)
	(zone
		(layer "In1.Cu")
		(hatch none 0.5)
		(connect_pads
			(clearance 0)
		)
		(min_thickness 0.25)
		(keepout
			(tracks not_allowed)
			(vias allowed)
			(pads allowed)
			(copperpour not_allowed)
			(footprints allowed)
		)
		(placement
			(enabled no)
			(sheetname "")
		)
		(fill
			(thermal_gap 0.5)
			(thermal_bridge_width 0.5)
			(island_removal_mode 0)
		)
		(polygon
			(pts
				(xy 108.469938 -9.520682) (xy 108.469938 -11.324082) (xy 109.028738 -11.324082) (xy 109.028738 -9.520682)
			)
		)
	)
	(zone
		(layer "In1.Cu")
		(hatch none 0.5)
		(connect_pads
			(clearance 0)
		)
		(min_thickness 0.25)
		(keepout
			(tracks not_allowed)
			(vias allowed)
			(pads allowed)
			(copperpour not_allowed)
			(footprints allowed)
		)
		(placement
			(enabled no)
			(sheetname "")
		)
		(fill
			(thermal_gap 0.5)
			(thermal_bridge_width 0.5)
			(island_removal_mode 0)
		)
		(polygon
			(pts
				(xy 135.670036 -136.774682) (xy 135.670036 -138.578082) (xy 136.228836 -138.578082) (xy 136.228836 -136.774682)
			)
		)
	)
	(zone
		(layer "In1.Cu")
		(hatch none 0.5)
		(connect_pads
			(clearance 0)
		)
		(min_thickness 0.25)
		(keepout
			(tracks not_allowed)
			(vias allowed)
			(pads allowed)
			(copperpour not_allowed)
			(footprints allowed)
		)
		(placement
			(enabled no)
			(sheetname "")
		)
		(fill
			(thermal_gap 0.5)
			(thermal_bridge_width 0.5)
			(island_removal_mode 0)
		)
		(polygon
			(pts
				(xy 87.220044 -151.377142) (xy 87.220044 -153.180542) (xy 87.778844 -153.180542) (xy 87.778844 -151.377142)
			)
		)
	)
	(zone
		(layer "In1.Cu")
		(hatch none 0.5)
		(connect_pads
			(clearance 0)
		)
		(min_thickness 0.25)
		(keepout
			(tracks not_allowed)
			(vias allowed)
			(pads allowed)
			(copperpour not_allowed)
			(footprints allowed)
		)
		(placement
			(enabled no)
			(sheetname "")
		)
		(fill
			(thermal_gap 0.5)
			(thermal_bridge_width 0.5)
			(island_removal_mode 0)
		)
		(polygon
			(pts
				(xy 267.52042 0.080518) (xy 267.52042 -1.722882) (xy 268.07922 -1.722882) (xy 268.07922 0.080518)
			)
		)
	)
	(zone
		(layer "In1.Cu")
		(hatch none 0.5)
		(connect_pads
			(clearance 0)
		)
		(min_thickness 0.25)
		(keepout
			(tracks not_allowed)
			(vias allowed)
			(pads allowed)
			(copperpour not_allowed)
			(footprints allowed)
		)
		(placement
			(enabled no)
			(sheetname "")
		)
		(fill
			(thermal_gap 0.5)
			(thermal_bridge_width 0.5)
			(island_removal_mode 0)
		)
		(polygon
			(pts
				(xy 55.770018 -151.377142) (xy 55.770018 -153.180542) (xy 56.328818 -153.180542) (xy 56.328818 -151.377142)
			)
		)
	)
	(zone
		(layer "In1.Cu")
		(hatch none 0.5)
		(connect_pads
			(clearance 0)
		)
		(min_thickness 0.25)
		(keepout
			(tracks not_allowed)
			(vias allowed)
			(pads allowed)
			(copperpour not_allowed)
			(footprints allowed)
		)
		(placement
			(enabled no)
			(sheetname "")
		)
		(fill
			(thermal_gap 0.5)
			(thermal_bridge_width 0.5)
			(island_removal_mode 0)
		)
		(polygon
			(pts
				(xy 300.670468 -155.977082) (xy 300.670468 -157.780482) (xy 301.229268 -157.780482) (xy 301.229268 -155.977082)
			)
		)
	)
	(zone
		(layer "In1.Cu")
		(hatch none 0.5)
		(connect_pads
			(clearance 0)
		)
		(min_thickness 0.25)
		(keepout
			(tracks not_allowed)
			(vias allowed)
			(pads allowed)
			(copperpour not_allowed)
			(footprints allowed)
		)
		(placement
			(enabled no)
			(sheetname "")
		)
		(fill
			(thermal_gap 0.5)
			(thermal_bridge_width 0.5)
			(island_removal_mode 0)
		)
		(polygon
			(pts
				(xy 103.370126 -151.377142) (xy 103.370126 -153.180542) (xy 103.928926 -153.180542) (xy 103.928926 -151.377142)
			)
		)
	)
	(zone
		(layer "In1.Cu")
		(hatch none 0.5)
		(connect_pads
			(clearance 0)
		)
		(min_thickness 0.25)
		(keepout
			(tracks not_allowed)
			(vias allowed)
			(pads allowed)
			(copperpour not_allowed)
			(footprints allowed)
		)
		(placement
			(enabled no)
			(sheetname "")
		)
		(fill
			(thermal_gap 0.5)
			(thermal_bridge_width 0.5)
			(island_removal_mode 0)
		)
		(polygon
			(pts
				(xy 257.320542 -151.377142) (xy 257.320542 -153.180542) (xy 257.879342 -153.180542) (xy 257.879342 -151.377142)
			)
		)
	)
	(zone
		(layer "In1.Cu")
		(hatch none 0.5)
		(connect_pads
			(clearance 0)
		)
		(min_thickness 0.25)
		(keepout
			(tracks not_allowed)
			(vias allowed)
			(pads allowed)
			(copperpour not_allowed)
			(footprints allowed)
		)
		(placement
			(enabled no)
			(sheetname "")
		)
		(fill
			(thermal_gap 0.5)
			(thermal_bridge_width 0.5)
			(island_removal_mode 0)
		)
		(polygon
			(pts
				(xy 132.269992 -9.520682) (xy 132.269992 -11.324082) (xy 132.828792 -11.324082) (xy 132.828792 -9.520682)
			)
		)
	)
	(zone
		(layer "In1.Cu")
		(hatch none 0.5)
		(connect_pads
			(clearance 0)
		)
		(min_thickness 0.25)
		(keepout
			(tracks not_allowed)
			(vias allowed)
			(pads allowed)
			(copperpour not_allowed)
			(footprints allowed)
		)
		(placement
			(enabled no)
			(sheetname "")
		)
		(fill
			(thermal_gap 0.5)
			(thermal_bridge_width 0.5)
			(island_removal_mode 0)
		)
		(polygon
			(pts
				(xy 31.969964 -146.375882) (xy 31.969964 -148.179282) (xy 32.528764 -148.179282) (xy 32.528764 -146.375882)
			)
		)
	)
	(zone
		(layer "In1.Cu")
		(hatch none 0.5)
		(connect_pads
			(clearance 0)
		)
		(min_thickness 0.25)
		(keepout
			(tracks not_allowed)
			(vias allowed)
			(pads allowed)
			(copperpour not_allowed)
			(footprints allowed)
		)
		(placement
			(enabled no)
			(sheetname "")
		)
		(fill
			(thermal_gap 0.5)
			(thermal_bridge_width 0.5)
			(island_removal_mode 0)
		)
		(polygon
			(pts
				(xy 202.9206 -146.375882) (xy 202.9206 -148.179282) (xy 203.4794 -148.179282) (xy 203.4794 -146.375882)
			)
		)
	)
	(zone
		(layer "In1.Cu")
		(hatch none 0.5)
		(connect_pads
			(clearance 0)
		)
		(min_thickness 0.25)
		(keepout
			(tracks not_allowed)
			(vias allowed)
			(pads allowed)
			(copperpour not_allowed)
			(footprints allowed)
		)
		(placement
			(enabled no)
			(sheetname "")
		)
		(fill
			(thermal_gap 0.5)
			(thermal_bridge_width 0.5)
			(island_removal_mode 0)
		)
		(polygon
			(pts
				(xy 221.620588 -146.375882) (xy 221.620588 -148.179282) (xy 222.179388 -148.179282) (xy 222.179388 -146.375882)
			)
		)
	)
	(zone
		(layer "In1.Cu")
		(hatch none 0.5)
		(connect_pads
			(clearance 0)
		)
		(min_thickness 0.25)
		(keepout
			(tracks not_allowed)
			(vias allowed)
			(pads allowed)
			(copperpour not_allowed)
			(footprints allowed)
		)
		(placement
			(enabled no)
			(sheetname "")
		)
		(fill
			(thermal_gap 0.5)
			(thermal_bridge_width 0.5)
			(island_removal_mode 0)
		)
		(polygon
			(pts
				(xy 374.024144 -9.773158) (xy 374.532144 -9.773158) (xy 374.532144 -11.170158) (xy 374.024144 -11.170158)
			)
		)
	)
	(zone
		(layer "In1.Cu")
		(hatch none 0.5)
		(connect_pads
			(clearance 0)
		)
		(min_thickness 0.25)
		(keepout
			(tracks not_allowed)
			(vias allowed)
			(pads allowed)
			(copperpour not_allowed)
			(footprints allowed)
		)
		(placement
			(enabled no)
			(sheetname "")
		)
		(fill
			(thermal_gap 0.5)
			(thermal_bridge_width 0.5)
			(island_removal_mode 0)
		)
		(polygon
			(pts
				(xy 60.019946 -146.375882) (xy 60.019946 -148.179282) (xy 60.578746 -148.179282) (xy 60.578746 -146.375882)
			)
		)
	)
	(zone
		(layer "In1.Cu")
		(hatch none 0.5)
		(connect_pads
			(clearance 0)
		)
		(min_thickness 0.25)
		(keepout
			(tracks not_allowed)
			(vias allowed)
			(pads allowed)
			(copperpour not_allowed)
			(footprints allowed)
		)
		(placement
			(enabled no)
			(sheetname "")
		)
		(fill
			(thermal_gap 0.5)
			(thermal_bridge_width 0.5)
			(island_removal_mode 0)
		)
		(polygon
			(pts
				(xy 276.02053 0.080518) (xy 276.02053 -1.722882) (xy 276.57933 -1.722882) (xy 276.57933 0.080518)
			)
		)
	)
	(zone
		(layer "In1.Cu")
		(hatch none 0.5)
		(connect_pads
			(clearance 0)
		)
		(min_thickness 0.25)
		(keepout
			(tracks not_allowed)
			(vias allowed)
			(pads allowed)
			(copperpour not_allowed)
			(footprints allowed)
		)
		(placement
			(enabled no)
			(sheetname "")
		)
		(fill
			(thermal_gap 0.5)
			(thermal_bridge_width 0.5)
			(island_removal_mode 0)
		)
		(polygon
			(pts
				(xy 35.370008 -19.121882) (xy 35.370008 -20.925282) (xy 35.928808 -20.925282) (xy 35.928808 -19.121882)
			)
		)
	)
	(zone
		(layer "In1.Cu")
		(hatch none 0.5)
		(connect_pads
			(clearance 0)
		)
		(min_thickness 0.25)
		(keepout
			(tracks not_allowed)
			(vias allowed)
			(pads allowed)
			(copperpour not_allowed)
			(footprints allowed)
		)
		(placement
			(enabled no)
			(sheetname "")
		)
		(fill
			(thermal_gap 0.5)
			(thermal_bridge_width 0.5)
			(island_removal_mode 0)
		)
		(polygon
			(pts
				(xy 39.619936 -146.375882) (xy 39.619936 -148.179282) (xy 40.178736 -148.179282) (xy 40.178736 -146.375882)
			)
		)
	)
	(zone
		(layer "In1.Cu")
		(hatch none 0.5)
		(connect_pads
			(clearance 0)
		)
		(min_thickness 0.25)
		(keepout
			(tracks not_allowed)
			(vias allowed)
			(pads allowed)
			(copperpour not_allowed)
			(footprints allowed)
		)
		(placement
			(enabled no)
			(sheetname "")
		)
		(fill
			(thermal_gap 0.5)
			(thermal_bridge_width 0.5)
			(island_removal_mode 0)
		)
		(polygon
			(pts
				(xy 37.920168 -146.375882) (xy 37.920168 -148.179282) (xy 38.478968 -148.179282) (xy 38.478968 -146.375882)
			)
		)
	)
	(zone
		(layer "In1.Cu")
		(hatch none 0.5)
		(connect_pads
			(clearance 0)
		)
		(min_thickness 0.25)
		(keepout
			(tracks not_allowed)
			(vias allowed)
			(pads allowed)
			(copperpour not_allowed)
			(footprints allowed)
		)
		(placement
			(enabled no)
			(sheetname "")
		)
		(fill
			(thermal_gap 0.5)
			(thermal_bridge_width 0.5)
			(island_removal_mode 0)
		)
		(polygon
			(pts
				(xy 235.22051 -132.174742) (xy 235.22051 -133.978142) (xy 235.77931 -133.978142) (xy 235.77931 -132.174742)
			)
		)
	)
	(zone
		(layer "In1.Cu")
		(hatch none 0.5)
		(connect_pads
			(clearance 0)
		)
		(min_thickness 0.25)
		(keepout
			(tracks not_allowed)
			(vias allowed)
			(pads allowed)
			(copperpour not_allowed)
			(footprints allowed)
		)
		(placement
			(enabled no)
			(sheetname "")
		)
		(fill
			(thermal_gap 0.5)
			(thermal_bridge_width 0.5)
			(island_removal_mode 0)
		)
		(polygon
			(pts
				(xy 323.4055 -120.142) (xy 325.6915 -120.142) (xy 325.6915 -120.65) (xy 323.4055 -120.65)
			)
		)
	)
	(zone
		(layer "In1.Cu")
		(hatch none 0.5)
		(connect_pads
			(clearance 0)
		)
		(min_thickness 0.25)
		(keepout
			(tracks not_allowed)
			(vias allowed)
			(pads allowed)
			(copperpour not_allowed)
			(footprints allowed)
		)
		(placement
			(enabled no)
			(sheetname "")
		)
		(fill
			(thermal_gap 0.5)
			(thermal_bridge_width 0.5)
			(island_removal_mode 0)
		)
		(polygon
			(pts
				(xy 252.220476 -19.121882) (xy 252.220476 -20.925282) (xy 252.779276 -20.925282) (xy 252.779276 -19.121882)
			)
		)
	)
	(zone
		(layer "In1.Cu")
		(hatch none 0.5)
		(connect_pads
			(clearance 0)
		)
		(min_thickness 0.25)
		(keepout
			(tracks not_allowed)
			(vias allowed)
			(pads allowed)
			(copperpour not_allowed)
			(footprints allowed)
		)
		(placement
			(enabled no)
			(sheetname "")
		)
		(fill
			(thermal_gap 0.5)
			(thermal_bridge_width 0.5)
			(island_removal_mode 0)
		)
		(polygon
			(pts
				(xy 238.620554 0.080518) (xy 238.620554 -1.722882) (xy 239.179354 -1.722882) (xy 239.179354 0.080518)
			)
		)
	)
	(zone
		(layer "In1.Cu")
		(hatch none 0.5)
		(connect_pads
			(clearance 0)
		)
		(min_thickness 0.25)
		(keepout
			(tracks not_allowed)
			(vias allowed)
			(pads allowed)
			(copperpour not_allowed)
			(footprints allowed)
		)
		(placement
			(enabled no)
			(sheetname "")
		)
		(fill
			(thermal_gap 0.5)
			(thermal_bridge_width 0.5)
			(island_removal_mode 0)
		)
		(polygon
			(pts
				(xy 145.869914 -132.174742) (xy 145.869914 -133.978142) (xy 146.428714 -133.978142) (xy 146.428714 -132.174742)
			)
		)
	)
	(zone
		(layer "In1.Cu")
		(hatch none 0.5)
		(connect_pads
			(clearance 0)
		)
		(min_thickness 0.25)
		(keepout
			(tracks not_allowed)
			(vias allowed)
			(pads allowed)
			(copperpour not_allowed)
			(footprints allowed)
		)
		(placement
			(enabled no)
			(sheetname "")
		)
		(fill
			(thermal_gap 0.5)
			(thermal_bridge_width 0.5)
			(island_removal_mode 0)
		)
		(polygon
			(pts
				(xy 275.170392 -19.121882) (xy 275.729192 -19.121882) (xy 275.729192 -20.925282) (xy 275.170392 -20.925282)
			)
		)
	)
	(zone
		(layer "In1.Cu")
		(hatch none 0.5)
		(connect_pads
			(clearance 0)
		)
		(min_thickness 0.25)
		(keepout
			(tracks not_allowed)
			(vias allowed)
			(pads allowed)
			(copperpour not_allowed)
			(footprints allowed)
		)
		(placement
			(enabled no)
			(sheetname "")
		)
		(fill
			(thermal_gap 0.5)
			(thermal_bridge_width 0.5)
			(island_removal_mode 0)
		)
		(polygon
			(pts
				(xy 136.51992 -132.174742) (xy 136.51992 -133.978142) (xy 137.07872 -133.978142) (xy 137.07872 -132.174742)
			)
		)
	)
	(zone
		(layer "In1.Cu")
		(hatch none 0.5)
		(connect_pads
			(clearance 0)
		)
		(min_thickness 0.25)
		(keepout
			(tracks not_allowed)
			(vias allowed)
			(pads allowed)
			(copperpour not_allowed)
			(footprints allowed)
		)
		(placement
			(enabled no)
			(sheetname "")
		)
		(fill
			(thermal_gap 0.5)
			(thermal_bridge_width 0.5)
			(island_removal_mode 0)
		)
		(polygon
			(pts
				(xy 86.37016 4.680458) (xy 86.37016 2.877058) (xy 86.92896 2.877058) (xy 86.92896 4.680458)
			)
		)
	)
	(zone
		(layer "In1.Cu")
		(hatch none 0.5)
		(connect_pads
			(clearance 0)
		)
		(min_thickness 0.25)
		(keepout
			(tracks not_allowed)
			(vias allowed)
			(pads allowed)
			(copperpour not_allowed)
			(footprints allowed)
		)
		(placement
			(enabled no)
			(sheetname "")
		)
		(fill
			(thermal_gap 0.5)
			(thermal_bridge_width 0.5)
			(island_removal_mode 0)
		)
		(polygon
			(pts
				(xy 233.520488 -4.920742) (xy 233.520488 -6.724142) (xy 234.079288 -6.724142) (xy 234.079288 -4.920742)
			)
		)
	)
	(zone
		(layer "In1.Cu")
		(hatch none 0.5)
		(connect_pads
			(clearance 0)
		)
		(min_thickness 0.25)
		(keepout
			(tracks not_allowed)
			(vias allowed)
			(pads allowed)
			(copperpour not_allowed)
			(footprints allowed)
		)
		(placement
			(enabled no)
			(sheetname "")
		)
		(fill
			(thermal_gap 0.5)
			(thermal_bridge_width 0.5)
			(island_removal_mode 0)
		)
		(polygon
			(pts
				(xy 313.420506 -151.377142) (xy 313.420506 -153.180542) (xy 313.979306 -153.180542) (xy 313.979306 -151.377142)
			)
		)
	)
	(zone
		(layer "In1.Cu")
		(hatch none 0.5)
		(connect_pads
			(clearance 0)
		)
		(min_thickness 0.25)
		(keepout
			(tracks not_allowed)
			(vias allowed)
			(pads allowed)
			(copperpour not_allowed)
			(footprints allowed)
		)
		(placement
			(enabled no)
			(sheetname "")
		)
		(fill
			(thermal_gap 0.5)
			(thermal_bridge_width 0.5)
			(island_removal_mode 0)
		)
		(polygon
			(pts
				(xy 210.570572 -19.121882) (xy 210.570572 -20.925282) (xy 211.129372 -20.925282) (xy 211.129372 -19.121882)
			)
		)
	)
	(zone
		(layer "In1.Cu")
		(hatch none 0.5)
		(connect_pads
			(clearance 0)
		)
		(min_thickness 0.25)
		(keepout
			(tracks not_allowed)
			(vias allowed)
			(pads allowed)
			(copperpour not_allowed)
			(footprints allowed)
		)
		(placement
			(enabled no)
			(sheetname "")
		)
		(fill
			(thermal_gap 0.5)
			(thermal_bridge_width 0.5)
			(island_removal_mode 0)
		)
		(polygon
			(pts
				(xy 145.02003 -146.375882) (xy 145.02003 -148.179282) (xy 145.57883 -148.179282) (xy 145.57883 -146.375882)
			)
		)
	)
	(zone
		(layer "In1.Cu")
		(hatch none 0.5)
		(connect_pads
			(clearance 0)
		)
		(min_thickness 0.25)
		(keepout
			(tracks not_allowed)
			(vias allowed)
			(pads allowed)
			(copperpour not_allowed)
			(footprints allowed)
		)
		(placement
			(enabled no)
			(sheetname "")
		)
		(fill
			(thermal_gap 0.5)
			(thermal_bridge_width 0.5)
			(island_removal_mode 0)
		)
		(polygon
			(pts
				(xy 284.520386 -146.375882) (xy 284.520386 -148.179282) (xy 285.079186 -148.179282) (xy 285.079186 -146.375882)
			)
		)
	)
	(zone
		(layer "In1.Cu")
		(hatch none 0.5)
		(connect_pads
			(clearance 0)
		)
		(min_thickness 0.25)
		(keepout
			(tracks not_allowed)
			(vias allowed)
			(pads allowed)
			(copperpour not_allowed)
			(footprints allowed)
		)
		(placement
			(enabled no)
			(sheetname "")
		)
		(fill
			(thermal_gap 0.5)
			(thermal_bridge_width 0.5)
			(island_removal_mode 0)
		)
		(polygon
			(pts
				(xy 35.370008 -9.520682) (xy 35.370008 -11.324082) (xy 35.928808 -11.324082) (xy 35.928808 -9.520682)
			)
		)
	)
	(zone
		(layer "In1.Cu")
		(hatch none 0.5)
		(connect_pads
			(clearance 0)
		)
		(min_thickness 0.25)
		(keepout
			(tracks not_allowed)
			(vias allowed)
			(pads allowed)
			(copperpour not_allowed)
			(footprints allowed)
		)
		(placement
			(enabled no)
			(sheetname "")
		)
		(fill
			(thermal_gap 0.5)
			(thermal_bridge_width 0.5)
			(island_removal_mode 0)
		)
		(polygon
			(pts
				(xy 410.563822 -10.293858) (xy 411.071822 -10.293858) (xy 411.071822 -11.690858) (xy 410.563822 -11.690858)
			)
		)
	)
	(zone
		(layer "In1.Cu")
		(hatch none 0.5)
		(connect_pads
			(clearance 0)
		)
		(min_thickness 0.25)
		(keepout
			(tracks not_allowed)
			(vias allowed)
			(pads allowed)
			(copperpour not_allowed)
			(footprints allowed)
		)
		(placement
			(enabled no)
			(sheetname "")
		)
		(fill
			(thermal_gap 0.5)
			(thermal_bridge_width 0.5)
			(island_removal_mode 0)
		)
		(polygon
			(pts
				(xy 372.512844 -9.773158) (xy 373.020844 -9.773158) (xy 373.020844 -11.170158) (xy 372.512844 -11.170158)
			)
		)
	)
	(zone
		(layer "In1.Cu")
		(hatch none 0.5)
		(connect_pads
			(clearance 0)
		)
		(min_thickness 0.25)
		(keepout
			(tracks not_allowed)
			(vias allowed)
			(pads allowed)
			(copperpour not_allowed)
			(footprints allowed)
		)
		(placement
			(enabled no)
			(sheetname "")
		)
		(fill
			(thermal_gap 0.5)
			(thermal_bridge_width 0.5)
			(island_removal_mode 0)
		)
		(polygon
			(pts
				(xy 200.37044 -4.920742) (xy 200.37044 -6.724142) (xy 200.92924 -6.724142) (xy 200.92924 -4.920742)
			)
		)
	)
	(zone
		(layer "In1.Cu")
		(hatch none 0.5)
		(connect_pads
			(clearance 0)
		)
		(min_thickness 0.25)
		(keepout
			(tracks not_allowed)
			(vias allowed)
			(pads allowed)
			(copperpour not_allowed)
			(footprints allowed)
		)
		(placement
			(enabled no)
			(sheetname "")
		)
		(fill
			(thermal_gap 0.5)
			(thermal_bridge_width 0.5)
			(island_removal_mode 0)
		)
		(polygon
			(pts
				(xy 210.570572 0.080518) (xy 210.570572 -1.722882) (xy 211.129372 -1.722882) (xy 211.129372 0.080518)
			)
		)
	)
	(zone
		(layer "In1.Cu")
		(hatch none 0.5)
		(connect_pads
			(clearance 0)
		)
		(min_thickness 0.25)
		(keepout
			(tracks not_allowed)
			(vias allowed)
			(pads allowed)
			(copperpour not_allowed)
			(footprints allowed)
		)
		(placement
			(enabled no)
			(sheetname "")
		)
		(fill
			(thermal_gap 0.5)
			(thermal_bridge_width 0.5)
			(island_removal_mode 0)
		)
		(polygon
			(pts
				(xy 43.01998 -19.121882) (xy 43.01998 -20.925282) (xy 43.57878 -20.925282) (xy 43.57878 -19.121882)
			)
		)
	)
	(zone
		(layer "In1.Cu")
		(hatch none 0.5)
		(connect_pads
			(clearance 0)
		)
		(min_thickness 0.25)
		(keepout
			(tracks not_allowed)
			(vias allowed)
			(pads allowed)
			(copperpour not_allowed)
			(footprints allowed)
		)
		(placement
			(enabled no)
			(sheetname "")
		)
		(fill
			(thermal_gap 0.5)
			(thermal_bridge_width 0.5)
			(island_removal_mode 0)
		)
		(polygon
			(pts
				(xy 213.970362 -155.977082) (xy 213.970362 -157.780482) (xy 214.529162 -157.780482) (xy 214.529162 -155.977082)
			)
		)
	)
	(zone
		(layer "In1.Cu")
		(hatch none 0.5)
		(connect_pads
			(clearance 0)
		)
		(min_thickness 0.25)
		(keepout
			(tracks not_allowed)
			(vias allowed)
			(pads allowed)
			(copperpour not_allowed)
			(footprints allowed)
		)
		(placement
			(enabled no)
			(sheetname "")
		)
		(fill
			(thermal_gap 0.5)
			(thermal_bridge_width 0.5)
			(island_removal_mode 0)
		)
		(polygon
			(pts
				(xy 89.76995 -4.920742) (xy 89.76995 -6.724142) (xy 90.32875 -6.724142) (xy 90.32875 -4.920742)
			)
		)
	)
	(zone
		(layer "In1.Cu")
		(hatch none 0.5)
		(connect_pads
			(clearance 0)
		)
		(min_thickness 0.25)
		(keepout
			(tracks not_allowed)
			(vias allowed)
			(pads allowed)
			(copperpour not_allowed)
			(footprints allowed)
		)
		(placement
			(enabled no)
			(sheetname "")
		)
		(fill
			(thermal_gap 0.5)
			(thermal_bridge_width 0.5)
			(island_removal_mode 0)
		)
		(polygon
			(pts
				(xy 286.220408 0.080518) (xy 286.220408 -1.722882) (xy 286.779208 -1.722882) (xy 286.779208 0.080518)
			)
		)
	)
	(zone
		(layer "In1.Cu")
		(hatch none 0.5)
		(connect_pads
			(clearance 0)
		)
		(min_thickness 0.25)
		(keepout
			(tracks not_allowed)
			(vias allowed)
			(pads allowed)
			(copperpour not_allowed)
			(footprints allowed)
		)
		(placement
			(enabled no)
			(sheetname "")
		)
		(fill
			(thermal_gap 0.5)
			(thermal_bridge_width 0.5)
			(island_removal_mode 0)
		)
		(polygon
			(pts
				(xy 205.470506 -132.174742) (xy 205.470506 -133.978142) (xy 206.029306 -133.978142) (xy 206.029306 -132.174742)
			)
		)
	)
	(zone
		(layer "In1.Cu")
		(hatch none 0.5)
		(connect_pads
			(clearance 0)
		)
		(min_thickness 0.25)
		(keepout
			(tracks not_allowed)
			(vias allowed)
			(pads allowed)
			(copperpour not_allowed)
			(footprints allowed)
		)
		(placement
			(enabled no)
			(sheetname "")
		)
		(fill
			(thermal_gap 0.5)
			(thermal_bridge_width 0.5)
			(island_removal_mode 0)
		)
		(polygon
			(pts
				(xy 283.670502 -4.920742) (xy 283.670502 -6.724142) (xy 284.229302 -6.724142) (xy 284.229302 -4.920742)
			)
		)
	)
	(zone
		(layer "In1.Cu")
		(hatch none 0.5)
		(connect_pads
			(clearance 0)
		)
		(min_thickness 0.25)
		(keepout
			(tracks not_allowed)
			(vias allowed)
			(pads allowed)
			(copperpour not_allowed)
			(footprints allowed)
		)
		(placement
			(enabled no)
			(sheetname "")
		)
		(fill
			(thermal_gap 0.5)
			(thermal_bridge_width 0.5)
			(island_removal_mode 0)
		)
		(polygon
			(pts
				(xy 123.769882 -151.377142) (xy 123.769882 -153.180542) (xy 124.328682 -153.180542) (xy 124.328682 -151.377142)
			)
		)
	)
	(zone
		(layer "In1.Cu")
		(hatch none 0.5)
		(connect_pads
			(clearance 0)
		)
		(min_thickness 0.25)
		(keepout
			(tracks not_allowed)
			(vias allowed)
			(pads allowed)
			(copperpour not_allowed)
			(footprints allowed)
		)
		(placement
			(enabled no)
			(sheetname "")
		)
		(fill
			(thermal_gap 0.5)
			(thermal_bridge_width 0.5)
			(island_removal_mode 0)
		)
		(polygon
			(pts
				(xy 211.420456 4.680458) (xy 211.420456 2.877058) (xy 211.979256 2.877058) (xy 211.979256 4.680458)
			)
		)
	)
	(zone
		(layer "In1.Cu")
		(hatch none 0.5)
		(connect_pads
			(clearance 0)
		)
		(min_thickness 0.25)
		(keepout
			(tracks not_allowed)
			(vias allowed)
			(pads allowed)
			(copperpour not_allowed)
			(footprints allowed)
		)
		(placement
			(enabled no)
			(sheetname "")
		)
		(fill
			(thermal_gap 0.5)
			(thermal_bridge_width 0.5)
			(island_removal_mode 0)
		)
		(polygon
			(pts
				(xy 60.019946 0.080518) (xy 60.019946 -1.722882) (xy 60.578746 -1.722882) (xy 60.578746 0.080518)
			)
		)
	)
	(zone
		(layer "In1.Cu")
		(hatch none 0.5)
		(connect_pads
			(clearance 0)
		)
		(min_thickness 0.25)
		(keepout
			(tracks not_allowed)
			(vias allowed)
			(pads allowed)
			(copperpour not_allowed)
			(footprints allowed)
		)
		(placement
			(enabled no)
			(sheetname "")
		)
		(fill
			(thermal_gap 0.5)
			(thermal_bridge_width 0.5)
			(island_removal_mode 0)
		)
		(polygon
			(pts
				(xy 251.370592 -4.920742) (xy 251.370592 -6.724142) (xy 251.929392 -6.724142) (xy 251.929392 -4.920742)
			)
		)
	)
	(zone
		(layer "In1.Cu")
		(hatch none 0.5)
		(connect_pads
			(clearance 0)
		)
		(min_thickness 0.25)
		(keepout
			(tracks not_allowed)
			(vias allowed)
			(pads allowed)
			(copperpour not_allowed)
			(footprints allowed)
		)
		(placement
			(enabled no)
			(sheetname "")
		)
		(fill
			(thermal_gap 0.5)
			(thermal_bridge_width 0.5)
			(island_removal_mode 0)
		)
		(polygon
			(pts
				(xy 315.970412 -146.375882) (xy 315.970412 -148.179282) (xy 316.529212 -148.179282) (xy 316.529212 -146.375882)
			)
		)
	)
	(zone
		(layer "In1.Cu")
		(hatch none 0.5)
		(connect_pads
			(clearance 0)
		)
		(min_thickness 0.25)
		(keepout
			(tracks not_allowed)
			(vias allowed)
			(pads allowed)
			(copperpour not_allowed)
			(footprints allowed)
		)
		(placement
			(enabled no)
			(sheetname "")
		)
		(fill
			(thermal_gap 0.5)
			(thermal_bridge_width 0.5)
			(island_removal_mode 0)
		)
		(polygon
			(pts
				(xy 395.416786 -7.192772) (xy 396.724886 -7.192772) (xy 396.724886 -8.386572) (xy 395.416786 -8.386572)
			)
		)
	)
	(zone
		(layer "In1.Cu")
		(hatch none 0.5)
		(connect_pads
			(clearance 0)
		)
		(min_thickness 0.25)
		(keepout
			(tracks not_allowed)
			(vias allowed)
			(pads allowed)
			(copperpour not_allowed)
			(footprints allowed)
		)
		(placement
			(enabled no)
			(sheetname "")
		)
		(fill
			(thermal_gap 0.5)
			(thermal_bridge_width 0.5)
			(island_removal_mode 0)
		)
		(polygon
			(pts
				(xy 302.37049 -146.375882) (xy 302.37049 -148.179282) (xy 302.92929 -148.179282) (xy 302.92929 -146.375882)
			)
		)
	)
	(zone
		(layer "In1.Cu")
		(hatch none 0.5)
		(connect_pads
			(clearance 0)
		)
		(min_thickness 0.25)
		(keepout
			(tracks not_allowed)
			(vias allowed)
			(pads allowed)
			(copperpour not_allowed)
			(footprints allowed)
		)
		(placement
			(enabled no)
			(sheetname "")
		)
		(fill
			(thermal_gap 0.5)
			(thermal_bridge_width 0.5)
			(island_removal_mode 0)
		)
		(polygon
			(pts
				(xy 111.020098 -155.977082) (xy 111.020098 -157.780482) (xy 111.578898 -157.780482) (xy 111.578898 -155.977082)
			)
		)
	)
	(zone
		(layer "In1.Cu")
		(hatch none 0.5)
		(connect_pads
			(clearance 0)
		)
		(min_thickness 0.25)
		(keepout
			(tracks not_allowed)
			(vias allowed)
			(pads allowed)
			(copperpour not_allowed)
			(footprints allowed)
		)
		(placement
			(enabled no)
			(sheetname "")
		)
		(fill
			(thermal_gap 0.5)
			(thermal_bridge_width 0.5)
			(island_removal_mode 0)
		)
		(polygon
			(pts
				(xy 145.02003 -9.520682) (xy 145.02003 -11.324082) (xy 145.57883 -11.324082) (xy 145.57883 -9.520682)
			)
		)
	)
	(zone
		(layer "In1.Cu")
		(hatch none 0.5)
		(connect_pads
			(clearance 0)
		)
		(min_thickness 0.25)
		(keepout
			(tracks not_allowed)
			(vias allowed)
			(pads allowed)
			(copperpour not_allowed)
			(footprints allowed)
		)
		(placement
			(enabled no)
			(sheetname "")
		)
		(fill
			(thermal_gap 0.5)
			(thermal_bridge_width 0.5)
			(island_removal_mode 0)
		)
		(polygon
			(pts
				(xy 229.27056 -146.375882) (xy 229.27056 -148.179282) (xy 229.82936 -148.179282) (xy 229.82936 -146.375882)
			)
		)
	)
	(zone
		(layer "In1.Cu")
		(hatch none 0.5)
		(connect_pads
			(clearance 0)
		)
		(min_thickness 0.25)
		(keepout
			(tracks not_allowed)
			(vias allowed)
			(pads allowed)
			(copperpour not_allowed)
			(footprints allowed)
		)
		(placement
			(enabled no)
			(sheetname "")
		)
		(fill
			(thermal_gap 0.5)
			(thermal_bridge_width 0.5)
			(island_removal_mode 0)
		)
		(polygon
			(pts
				(xy 236.920532 -132.174742) (xy 236.920532 -133.978142) (xy 237.479332 -133.978142) (xy 237.479332 -132.174742)
			)
		)
	)
	(zone
		(layer "In1.Cu")
		(hatch none 0.5)
		(connect_pads
			(clearance 0)
		)
		(min_thickness 0.25)
		(keepout
			(tracks not_allowed)
			(vias allowed)
			(pads allowed)
			(copperpour not_allowed)
			(footprints allowed)
		)
		(placement
			(enabled no)
			(sheetname "")
		)
		(fill
			(thermal_gap 0.5)
			(thermal_bridge_width 0.5)
			(island_removal_mode 0)
		)
		(polygon
			(pts
				(xy 129.720086 4.680458) (xy 129.720086 2.877058) (xy 130.278886 2.877058) (xy 130.278886 4.680458)
			)
		)
	)
	(zone
		(layer "In1.Cu")
		(hatch none 0.5)
		(connect_pads
			(clearance 0)
		)
		(min_thickness 0.25)
		(keepout
			(tracks not_allowed)
			(vias allowed)
			(pads allowed)
			(copperpour not_allowed)
			(footprints allowed)
		)
		(placement
			(enabled no)
			(sheetname "")
		)
		(fill
			(thermal_gap 0.5)
			(thermal_bridge_width 0.5)
			(island_removal_mode 0)
		)
		(polygon
			(pts
				(xy 292.170358 4.680458) (xy 292.170358 2.877058) (xy 292.729158 2.877058) (xy 292.729158 4.680458)
			)
		)
	)
	(zone
		(layer "In1.Cu")
		(hatch none 0.5)
		(connect_pads
			(clearance 0)
		)
		(min_thickness 0.25)
		(keepout
			(tracks not_allowed)
			(vias allowed)
			(pads allowed)
			(copperpour not_allowed)
			(footprints allowed)
		)
		(placement
			(enabled no)
			(sheetname "")
		)
		(fill
			(thermal_gap 0.5)
			(thermal_bridge_width 0.5)
			(island_removal_mode 0)
		)
		(polygon
			(pts
				(xy 234.370372 -146.375882) (xy 234.370372 -148.179282) (xy 234.929172 -148.179282) (xy 234.929172 -146.375882)
			)
		)
	)
	(zone
		(layer "In1.Cu")
		(hatch none 0.5)
		(connect_pads
			(clearance 0)
		)
		(min_thickness 0.25)
		(keepout
			(tracks not_allowed)
			(vias allowed)
			(pads allowed)
			(copperpour not_allowed)
			(footprints allowed)
		)
		(placement
			(enabled no)
			(sheetname "")
		)
		(fill
			(thermal_gap 0.5)
			(thermal_bridge_width 0.5)
			(island_removal_mode 0)
		)
		(polygon
			(pts
				(xy 141.619986 -146.375882) (xy 141.619986 -148.179282) (xy 142.178786 -148.179282) (xy 142.178786 -146.375882)
			)
		)
	)
	(zone
		(layer "In1.Cu")
		(hatch none 0.5)
		(connect_pads
			(clearance 0)
		)
		(min_thickness 0.25)
		(keepout
			(tracks not_allowed)
			(vias allowed)
			(pads allowed)
			(copperpour not_allowed)
			(footprints allowed)
		)
		(placement
			(enabled no)
			(sheetname "")
		)
		(fill
			(thermal_gap 0.5)
			(thermal_bridge_width 0.5)
			(island_removal_mode 0)
		)
		(polygon
			(pts
				(xy 54.069996 -151.377142) (xy 54.069996 -153.180542) (xy 54.628796 -153.180542) (xy 54.628796 -151.377142)
			)
		)
	)
	(zone
		(layer "In1.Cu")
		(hatch none 0.5)
		(connect_pads
			(clearance 0)
		)
		(min_thickness 0.25)
		(keepout
			(tracks not_allowed)
			(vias allowed)
			(pads allowed)
			(copperpour not_allowed)
			(footprints allowed)
		)
		(placement
			(enabled no)
			(sheetname "")
		)
		(fill
			(thermal_gap 0.5)
			(thermal_bridge_width 0.5)
			(island_removal_mode 0)
		)
		(polygon
			(pts
				(xy 281.97048 -9.520682) (xy 281.97048 -11.324082) (xy 282.52928 -11.324082) (xy 282.52928 -9.520682)
			)
		)
	)
	(zone
		(layer "In1.Cu")
		(hatch none 0.5)
		(connect_pads
			(clearance 0)
		)
		(min_thickness 0.25)
		(keepout
			(tracks not_allowed)
			(vias allowed)
			(pads allowed)
			(copperpour not_allowed)
			(footprints allowed)
		)
		(placement
			(enabled no)
			(sheetname "")
		)
		(fill
			(thermal_gap 0.5)
			(thermal_bridge_width 0.5)
			(island_removal_mode 0)
		)
		(polygon
			(pts
				(xy 315.120528 -4.920742) (xy 315.120528 -6.724142) (xy 315.679328 -6.724142) (xy 315.679328 -4.920742)
			)
		)
	)
	(zone
		(layer "In1.Cu")
		(hatch none 0.5)
		(connect_pads
			(clearance 0)
		)
		(min_thickness 0.25)
		(keepout
			(tracks not_allowed)
			(vias allowed)
			(pads allowed)
			(copperpour not_allowed)
			(footprints allowed)
		)
		(placement
			(enabled no)
			(sheetname "")
		)
		(fill
			(thermal_gap 0.5)
			(thermal_bridge_width 0.5)
			(island_removal_mode 0)
		)
		(polygon
			(pts
				(xy 196.970396 -9.520682) (xy 196.970396 -11.324082) (xy 197.529196 -11.324082) (xy 197.529196 -9.520682)
			)
		)
	)
	(zone
		(layer "In1.Cu")
		(hatch none 0.5)
		(connect_pads
			(clearance 0)
		)
		(min_thickness 0.25)
		(keepout
			(tracks not_allowed)
			(vias allowed)
			(pads allowed)
			(copperpour not_allowed)
			(footprints allowed)
		)
		(placement
			(enabled no)
			(sheetname "")
		)
		(fill
			(thermal_gap 0.5)
			(thermal_bridge_width 0.5)
			(island_removal_mode 0)
		)
		(polygon
			(pts
				(xy 116.970048 -146.375882) (xy 116.970048 -148.179282) (xy 117.528848 -148.179282) (xy 117.528848 -146.375882)
			)
		)
	)
	(zone
		(layer "In1.Cu")
		(hatch none 0.5)
		(connect_pads
			(clearance 0)
		)
		(min_thickness 0.25)
		(keepout
			(tracks not_allowed)
			(vias allowed)
			(pads allowed)
			(copperpour not_allowed)
			(footprints allowed)
		)
		(placement
			(enabled no)
			(sheetname "")
		)
		(fill
			(thermal_gap 0.5)
			(thermal_bridge_width 0.5)
			(island_removal_mode 0)
		)
		(polygon
			(pts
				(xy 212.270594 -155.977082) (xy 212.270594 -157.780482) (xy 212.829394 -157.780482) (xy 212.829394 -155.977082)
			)
		)
	)
	(zone
		(layer "In1.Cu")
		(hatch none 0.5)
		(connect_pads
			(clearance 0)
		)
		(min_thickness 0.25)
		(keepout
			(tracks not_allowed)
			(vias allowed)
			(pads allowed)
			(copperpour not_allowed)
			(footprints allowed)
		)
		(placement
			(enabled no)
			(sheetname "")
		)
		(fill
			(thermal_gap 0.5)
			(thermal_bridge_width 0.5)
			(island_removal_mode 0)
		)
		(polygon
			(pts
				(xy 305.770534 -14.521942) (xy 305.770534 -16.325342) (xy 306.329334 -16.325342) (xy 306.329334 -14.521942)
			)
		)
	)
	(zone
		(layer "In1.Cu")
		(hatch none 0.5)
		(connect_pads
			(clearance 0)
		)
		(min_thickness 0.25)
		(keepout
			(tracks not_allowed)
			(vias allowed)
			(pads allowed)
			(copperpour not_allowed)
			(footprints allowed)
		)
		(placement
			(enabled no)
			(sheetname "")
		)
		(fill
			(thermal_gap 0.5)
			(thermal_bridge_width 0.5)
			(island_removal_mode 0)
		)
		(polygon
			(pts
				(xy 265.820398 -14.521942) (xy 265.820398 -16.325342) (xy 266.379198 -16.325342) (xy 266.379198 -14.521942)
			)
		)
	)
	(zone
		(layer "In1.Cu")
		(hatch none 0.5)
		(connect_pads
			(clearance 0)
		)
		(min_thickness 0.25)
		(keepout
			(tracks not_allowed)
			(vias allowed)
			(pads allowed)
			(copperpour not_allowed)
			(footprints allowed)
		)
		(placement
			(enabled no)
			(sheetname "")
		)
		(fill
			(thermal_gap 0.5)
			(thermal_bridge_width 0.5)
			(island_removal_mode 0)
		)
		(polygon
			(pts
				(xy 315.970412 -19.121882) (xy 315.970412 -20.925282) (xy 316.529212 -20.925282) (xy 316.529212 -19.121882)
			)
		)
	)
	(zone
		(layer "In1.Cu")
		(hatch none 0.5)
		(connect_pads
			(clearance 0)
		)
		(min_thickness 0.25)
		(keepout
			(tracks not_allowed)
			(vias allowed)
			(pads allowed)
			(copperpour not_allowed)
			(footprints allowed)
		)
		(placement
			(enabled no)
			(sheetname "")
		)
		(fill
			(thermal_gap 0.5)
			(thermal_bridge_width 0.5)
			(island_removal_mode 0)
		)
		(polygon
			(pts
				(xy 304.920396 0.080518) (xy 304.920396 -1.722882) (xy 305.479196 -1.722882) (xy 305.479196 0.080518)
			)
		)
	)
	(zone
		(layer "In1.Cu")
		(hatch none 0.5)
		(connect_pads
			(clearance 0)
		)
		(min_thickness 0.25)
		(keepout
			(tracks not_allowed)
			(vias allowed)
			(pads allowed)
			(copperpour not_allowed)
			(footprints allowed)
		)
		(placement
			(enabled no)
			(sheetname "")
		)
		(fill
			(thermal_gap 0.5)
			(thermal_bridge_width 0.5)
			(island_removal_mode 0)
		)
		(polygon
			(pts
				(xy 146.720052 -4.920742) (xy 146.720052 -6.724142) (xy 147.278852 -6.724142) (xy 147.278852 -4.920742)
			)
		)
	)
	(zone
		(layer "In1.Cu")
		(hatch none 0.5)
		(connect_pads
			(clearance 0)
		)
		(min_thickness 0.25)
		(keepout
			(tracks not_allowed)
			(vias allowed)
			(pads allowed)
			(copperpour not_allowed)
			(footprints allowed)
		)
		(placement
			(enabled no)
			(sheetname "")
		)
		(fill
			(thermal_gap 0.5)
			(thermal_bridge_width 0.5)
			(island_removal_mode 0)
		)
		(polygon
			(pts
				(xy 378.672344 -9.798558) (xy 379.180344 -9.798558) (xy 379.180344 -11.195558) (xy 378.672344 -11.195558)
			)
		)
	)
	(zone
		(layer "In1.Cu")
		(hatch none 0.5)
		(connect_pads
			(clearance 0)
		)
		(min_thickness 0.25)
		(keepout
			(tracks not_allowed)
			(vias allowed)
			(pads allowed)
			(copperpour not_allowed)
			(footprints allowed)
		)
		(placement
			(enabled no)
			(sheetname "")
		)
		(fill
			(thermal_gap 0.5)
			(thermal_bridge_width 0.5)
			(island_removal_mode 0)
		)
		(polygon
			(pts
				(xy 209.720434 -151.377142) (xy 209.720434 -153.180542) (xy 210.279234 -153.180542) (xy 210.279234 -151.377142)
			)
		)
	)
	(zone
		(layer "In1.Cu")
		(hatch none 0.5)
		(connect_pads
			(clearance 0)
		)
		(min_thickness 0.25)
		(keepout
			(tracks not_allowed)
			(vias allowed)
			(pads allowed)
			(copperpour not_allowed)
			(footprints allowed)
		)
		(placement
			(enabled no)
			(sheetname "")
		)
		(fill
			(thermal_gap 0.5)
			(thermal_bridge_width 0.5)
			(island_removal_mode 0)
		)
		(polygon
			(pts
				(xy 271.770602 -132.174742) (xy 271.770602 -133.978142) (xy 272.329402 -133.978142) (xy 272.329402 -132.174742)
			)
		)
	)
	(zone
		(layer "In1.Cu")
		(hatch none 0.5)
		(connect_pads
			(clearance 0)
		)
		(min_thickness 0.25)
		(keepout
			(tracks not_allowed)
			(vias allowed)
			(pads allowed)
			(copperpour not_allowed)
			(footprints allowed)
		)
		(placement
			(enabled no)
			(sheetname "")
		)
		(fill
			(thermal_gap 0.5)
			(thermal_bridge_width 0.5)
			(island_removal_mode 0)
		)
		(polygon
			(pts
				(xy 230.120444 -151.377142) (xy 230.120444 -153.180542) (xy 230.679244 -153.180542) (xy 230.679244 -151.377142)
			)
		)
	)
	(zone
		(layer "In1.Cu")
		(hatch none 0.5)
		(connect_pads
			(clearance 0)
		)
		(min_thickness 0.25)
		(keepout
			(tracks not_allowed)
			(vias allowed)
			(pads allowed)
			(copperpour not_allowed)
			(footprints allowed)
		)
		(placement
			(enabled no)
			(sheetname "")
		)
		(fill
			(thermal_gap 0.5)
			(thermal_bridge_width 0.5)
			(island_removal_mode 0)
		)
		(polygon
			(pts
				(xy 296.42054 -132.174742) (xy 296.42054 -133.978142) (xy 296.97934 -133.978142) (xy 296.97934 -132.174742)
			)
		)
	)
	(zone
		(layer "In1.Cu")
		(hatch none 0.5)
		(connect_pads
			(clearance 0)
		)
		(min_thickness 0.25)
		(keepout
			(tracks not_allowed)
			(vias allowed)
			(pads allowed)
			(copperpour not_allowed)
			(footprints allowed)
		)
		(placement
			(enabled no)
			(sheetname "")
		)
		(fill
			(thermal_gap 0.5)
			(thermal_bridge_width 0.5)
			(island_removal_mode 0)
		)
		(polygon
			(pts
				(xy 111.020098 -141.775942) (xy 111.020098 -143.579342) (xy 111.578898 -143.579342) (xy 111.578898 -141.775942)
			)
		)
	)
	(zone
		(layer "In1.Cu")
		(hatch none 0.5)
		(connect_pads
			(clearance 0)
		)
		(min_thickness 0.25)
		(keepout
			(tracks not_allowed)
			(vias allowed)
			(pads allowed)
			(copperpour not_allowed)
			(footprints allowed)
		)
		(placement
			(enabled no)
			(sheetname "")
		)
		(fill
			(thermal_gap 0.5)
			(thermal_bridge_width 0.5)
			(island_removal_mode 0)
		)
		(polygon
			(pts
				(xy 148.420074 4.680458) (xy 148.420074 2.877058) (xy 148.978874 2.877058) (xy 148.978874 4.680458)
			)
		)
	)
	(zone
		(layer "In1.Cu")
		(hatch none 0.5)
		(connect_pads
			(clearance 0)
		)
		(min_thickness 0.25)
		(keepout
			(tracks not_allowed)
			(vias allowed)
			(pads allowed)
			(copperpour not_allowed)
			(footprints allowed)
		)
		(placement
			(enabled no)
			(sheetname "")
		)
		(fill
			(thermal_gap 0.5)
			(thermal_bridge_width 0.5)
			(island_removal_mode 0)
		)
		(polygon
			(pts
				(xy 57.47004 -141.775942) (xy 57.47004 -143.579342) (xy 58.02884 -143.579342) (xy 58.02884 -141.775942)
			)
		)
	)
	(zone
		(layer "In1.Cu")
		(hatch none 0.5)
		(connect_pads
			(clearance 0)
		)
		(min_thickness 0.25)
		(keepout
			(tracks not_allowed)
			(vias allowed)
			(pads allowed)
			(copperpour not_allowed)
			(footprints allowed)
		)
		(placement
			(enabled no)
			(sheetname "")
		)
		(fill
			(thermal_gap 0.5)
			(thermal_bridge_width 0.5)
			(island_removal_mode 0)
		)
		(polygon
			(pts
				(xy 273.47037 0.080518) (xy 273.47037 -1.722882) (xy 274.02917 -1.722882) (xy 274.02917 0.080518)
			)
		)
	)
	(zone
		(layer "In1.Cu")
		(hatch none 0.5)
		(connect_pads
			(clearance 0)
		)
		(min_thickness 0.25)
		(keepout
			(tracks not_allowed)
			(vias allowed)
			(pads allowed)
			(copperpour not_allowed)
			(footprints allowed)
		)
		(placement
			(enabled no)
			(sheetname "")
		)
		(fill
			(thermal_gap 0.5)
			(thermal_bridge_width 0.5)
			(island_removal_mode 0)
		)
		(polygon
			(pts
				(xy 88.070182 -155.977082) (xy 88.070182 -157.780482) (xy 88.628982 -157.780482) (xy 88.628982 -155.977082)
			)
		)
	)
	(zone
		(layer "In1.Cu")
		(hatch none 0.5)
		(connect_pads
			(clearance 0)
		)
		(min_thickness 0.25)
		(keepout
			(tracks not_allowed)
			(vias allowed)
			(pads allowed)
			(copperpour not_allowed)
			(footprints allowed)
		)
		(placement
			(enabled no)
			(sheetname "")
		)
		(fill
			(thermal_gap 0.5)
			(thermal_bridge_width 0.5)
			(island_removal_mode 0)
		)
		(polygon
			(pts
				(xy 362.911644 -9.773158) (xy 363.419644 -9.773158) (xy 363.419644 -11.170158) (xy 362.911644 -11.170158)
			)
		)
	)
	(zone
		(layer "In1.Cu")
		(hatch none 0.5)
		(connect_pads
			(clearance 0)
		)
		(min_thickness 0.25)
		(keepout
			(tracks not_allowed)
			(vias allowed)
			(pads allowed)
			(copperpour not_allowed)
			(footprints allowed)
		)
		(placement
			(enabled no)
			(sheetname "")
		)
		(fill
			(thermal_gap 0.5)
			(thermal_bridge_width 0.5)
			(island_removal_mode 0)
		)
		(polygon
			(pts
				(xy 447.546984 -115.799362) (xy 448.85483 -115.799362) (xy 448.85483 -118.186962) (xy 447.546984 -118.186962)
			)
		)
	)
	(zone
		(layer "In1.Cu")
		(hatch none 0.5)
		(connect_pads
			(clearance 0)
		)
		(min_thickness 0.25)
		(keepout
			(tracks not_allowed)
			(vias allowed)
			(pads allowed)
			(copperpour not_allowed)
			(footprints allowed)
		)
		(placement
			(enabled no)
			(sheetname "")
		)
		(fill
			(thermal_gap 0.5)
			(thermal_bridge_width 0.5)
			(island_removal_mode 0)
		)
		(polygon
			(pts
				(xy 213.120478 -141.775942) (xy 213.120478 -143.579342) (xy 213.679278 -143.579342) (xy 213.679278 -141.775942)
			)
		)
	)
	(zone
		(layer "In1.Cu")
		(hatch none 0.5)
		(connect_pads
			(clearance 0)
		)
		(min_thickness 0.25)
		(keepout
			(tracks not_allowed)
			(vias allowed)
			(pads allowed)
			(copperpour not_allowed)
			(footprints allowed)
		)
		(placement
			(enabled no)
			(sheetname "")
		)
		(fill
			(thermal_gap 0.5)
			(thermal_bridge_width 0.5)
			(island_removal_mode 0)
		)
		(polygon
			(pts
				(xy 111.020098 -4.920742) (xy 111.020098 -6.724142) (xy 111.578898 -6.724142) (xy 111.578898 -4.920742)
			)
		)
	)
	(zone
		(layer "In1.Cu")
		(hatch none 0.5)
		(connect_pads
			(clearance 0)
		)
		(min_thickness 0.25)
		(keepout
			(tracks not_allowed)
			(vias allowed)
			(pads allowed)
			(copperpour not_allowed)
			(footprints allowed)
		)
		(placement
			(enabled no)
			(sheetname "")
		)
		(fill
			(thermal_gap 0.5)
			(thermal_bridge_width 0.5)
			(island_removal_mode 0)
		)
		(polygon
			(pts
				(xy 382.022604 -28.118562) (xy 383.572004 -28.118562) (xy 383.572004 -28.923234) (xy 382.022604 -28.923234)
			)
		)
	)
	(zone
		(layer "In1.Cu")
		(hatch none 0.5)
		(connect_pads
			(clearance 0)
		)
		(min_thickness 0.25)
		(keepout
			(tracks not_allowed)
			(vias allowed)
			(pads allowed)
			(copperpour not_allowed)
			(footprints allowed)
		)
		(placement
			(enabled no)
			(sheetname "")
		)
		(fill
			(thermal_gap 0.5)
			(thermal_bridge_width 0.5)
			(island_removal_mode 0)
		)
		(polygon
			(pts
				(xy 112.72012 -136.774682) (xy 112.72012 -138.578082) (xy 113.27892 -138.578082) (xy 113.27892 -136.774682)
			)
		)
	)
	(zone
		(layer "In1.Cu")
		(hatch none 0.5)
		(connect_pads
			(clearance 0)
		)
		(min_thickness 0.25)
		(keepout
			(tracks not_allowed)
			(vias allowed)
			(pads allowed)
			(copperpour not_allowed)
			(footprints allowed)
		)
		(placement
			(enabled no)
			(sheetname "")
		)
		(fill
			(thermal_gap 0.5)
			(thermal_bridge_width 0.5)
			(island_removal_mode 0)
		)
		(polygon
			(pts
				(xy 227.570538 -14.521942) (xy 227.570538 -16.325342) (xy 228.129338 -16.325342) (xy 228.129338 -14.521942)
			)
		)
	)
	(zone
		(layer "In1.Cu")
		(hatch none 0.5)
		(connect_pads
			(clearance 0)
		)
		(min_thickness 0.25)
		(keepout
			(tracks not_allowed)
			(vias allowed)
			(pads allowed)
			(copperpour not_allowed)
			(footprints allowed)
		)
		(placement
			(enabled no)
			(sheetname "")
		)
		(fill
			(thermal_gap 0.5)
			(thermal_bridge_width 0.5)
			(island_removal_mode 0)
		)
		(polygon
			(pts
				(xy 91.469972 -136.774682) (xy 91.469972 -138.578082) (xy 92.028772 -138.578082) (xy 92.028772 -136.774682)
			)
		)
	)
	(zone
		(layer "In1.Cu")
		(hatch none 0.5)
		(connect_pads
			(clearance 0)
		)
		(min_thickness 0.25)
		(keepout
			(tracks not_allowed)
			(vias allowed)
			(pads allowed)
			(copperpour not_allowed)
			(footprints allowed)
		)
		(placement
			(enabled no)
			(sheetname "")
		)
		(fill
			(thermal_gap 0.5)
			(thermal_bridge_width 0.5)
			(island_removal_mode 0)
		)
		(polygon
			(pts
				(xy 450.696076 -60.99937) (xy 452.003922 -60.99937) (xy 452.003922 -63.00597) (xy 450.696076 -63.00597)
			)
		)
	)
	(zone
		(layer "In1.Cu")
		(hatch none 0.5)
		(connect_pads
			(clearance 0)
		)
		(min_thickness 0.25)
		(keepout
			(tracks not_allowed)
			(vias allowed)
			(pads allowed)
			(copperpour not_allowed)
			(footprints allowed)
		)
		(placement
			(enabled no)
			(sheetname "")
		)
		(fill
			(thermal_gap 0.5)
			(thermal_bridge_width 0.5)
			(island_removal_mode 0)
		)
		(polygon
			(pts
				(xy 421.820086 -7.192772) (xy 423.128186 -7.192772) (xy 423.128186 -8.386572) (xy 421.820086 -8.386572)
			)
		)
	)
	(zone
		(layer "In1.Cu")
		(hatch none 0.5)
		(connect_pads
			(clearance 0)
		)
		(min_thickness 0.25)
		(keepout
			(tracks not_allowed)
			(vias allowed)
			(pads allowed)
			(copperpour not_allowed)
			(footprints allowed)
		)
		(placement
			(enabled no)
			(sheetname "")
		)
		(fill
			(thermal_gap 0.5)
			(thermal_bridge_width 0.5)
			(island_removal_mode 0)
		)
		(polygon
			(pts
				(xy 115.270026 0.080518) (xy 115.270026 -1.722882) (xy 115.828826 -1.722882) (xy 115.828826 0.080518)
			)
		)
	)
	(zone
		(layer "In1.Cu")
		(hatch none 0.5)
		(connect_pads
			(clearance 0)
		)
		(min_thickness 0.25)
		(keepout
			(tracks not_allowed)
			(vias allowed)
			(pads allowed)
			(copperpour not_allowed)
			(footprints allowed)
		)
		(placement
			(enabled no)
			(sheetname "")
		)
		(fill
			(thermal_gap 0.5)
			(thermal_bridge_width 0.5)
			(island_removal_mode 0)
		)
		(polygon
			(pts
				(xy 116.11991 -4.920742) (xy 116.11991 -6.724142) (xy 116.67871 -6.724142) (xy 116.67871 -4.920742)
			)
		)
	)
	(zone
		(layer "In1.Cu")
		(hatch none 0.5)
		(connect_pads
			(clearance 0)
		)
		(min_thickness 0.25)
		(keepout
			(tracks not_allowed)
			(vias allowed)
			(pads allowed)
			(copperpour not_allowed)
			(footprints allowed)
		)
		(placement
			(enabled no)
			(sheetname "")
		)
		(fill
			(thermal_gap 0.5)
			(thermal_bridge_width 0.5)
			(island_removal_mode 0)
		)
		(polygon
			(pts
				(xy 45.57014 -136.774682) (xy 45.57014 -138.578082) (xy 46.12894 -138.578082) (xy 46.12894 -136.774682)
			)
		)
	)
	(zone
		(layer "In1.Cu")
		(hatch none 0.5)
		(connect_pads
			(clearance 0)
		)
		(min_thickness 0.25)
		(keepout
			(tracks not_allowed)
			(vias allowed)
			(pads allowed)
			(copperpour not_allowed)
			(footprints allowed)
		)
		(placement
			(enabled no)
			(sheetname "")
		)
		(fill
			(thermal_gap 0.5)
			(thermal_bridge_width 0.5)
			(island_removal_mode 0)
		)
		(polygon
			(pts
				(xy 271.770602 -151.377142) (xy 271.770602 -153.180542) (xy 272.329402 -153.180542) (xy 272.329402 -151.377142)
			)
		)
	)
	(zone
		(layer "In1.Cu")
		(hatch none 0.5)
		(connect_pads
			(clearance 0)
		)
		(min_thickness 0.25)
		(keepout
			(tracks not_allowed)
			(vias allowed)
			(pads allowed)
			(copperpour not_allowed)
			(footprints allowed)
		)
		(placement
			(enabled no)
			(sheetname "")
		)
		(fill
			(thermal_gap 0.5)
			(thermal_bridge_width 0.5)
			(island_removal_mode 0)
		)
		(polygon
			(pts
				(xy 455.496168 -60.99937) (xy 456.804014 -60.99937) (xy 456.804014 -63.00597) (xy 455.496168 -63.00597)
			)
		)
	)
	(zone
		(layer "In1.Cu")
		(hatch none 0.5)
		(connect_pads
			(clearance 0)
		)
		(min_thickness 0.25)
		(keepout
			(tracks not_allowed)
			(vias allowed)
			(pads allowed)
			(copperpour not_allowed)
			(footprints allowed)
		)
		(placement
			(enabled no)
			(sheetname "")
		)
		(fill
			(thermal_gap 0.5)
			(thermal_bridge_width 0.5)
			(island_removal_mode 0)
		)
		(polygon
			(pts
				(xy 253.070614 -136.774682) (xy 253.070614 -138.578082) (xy 253.629414 -138.578082) (xy 253.629414 -136.774682)
			)
		)
	)
	(zone
		(layer "In1.Cu")
		(hatch none 0.5)
		(connect_pads
			(clearance 0)
		)
		(min_thickness 0.25)
		(keepout
			(tracks not_allowed)
			(vias allowed)
			(pads allowed)
			(copperpour not_allowed)
			(footprints allowed)
		)
		(placement
			(enabled no)
			(sheetname "")
		)
		(fill
			(thermal_gap 0.5)
			(thermal_bridge_width 0.5)
			(island_removal_mode 0)
		)
		(polygon
			(pts
				(xy 276.02053 -132.174742) (xy 276.02053 -133.978142) (xy 276.57933 -133.978142) (xy 276.57933 -132.174742)
			)
		)
	)
	(zone
		(layer "In1.Cu")
		(hatch none 0.5)
		(connect_pads
			(clearance 0)
		)
		(min_thickness 0.25)
		(keepout
			(tracks not_allowed)
			(vias allowed)
			(pads allowed)
			(copperpour not_allowed)
			(footprints allowed)
		)
		(placement
			(enabled no)
			(sheetname "")
		)
		(fill
			(thermal_gap 0.5)
			(thermal_bridge_width 0.5)
			(island_removal_mode 0)
		)
		(polygon
			(pts
				(xy 249.67057 -132.174742) (xy 249.67057 -133.978142) (xy 250.22937 -133.978142) (xy 250.22937 -132.174742)
			)
		)
	)
	(zone
		(layer "In1.Cu")
		(hatch none 0.5)
		(connect_pads
			(clearance 0)
		)
		(min_thickness 0.25)
		(keepout
			(tracks not_allowed)
			(vias allowed)
			(pads allowed)
			(copperpour not_allowed)
			(footprints allowed)
		)
		(placement
			(enabled no)
			(sheetname "")
		)
		(fill
			(thermal_gap 0.5)
			(thermal_bridge_width 0.5)
			(island_removal_mode 0)
		)
		(polygon
			(pts
				(xy 302.37049 -4.920742) (xy 302.37049 -6.724142) (xy 302.92929 -6.724142) (xy 302.92929 -4.920742)
			)
		)
	)
	(zone
		(layer "In1.Cu")
		(hatch none 0.5)
		(connect_pads
			(clearance 0)
		)
		(min_thickness 0.25)
		(keepout
			(tracks not_allowed)
			(vias allowed)
			(pads allowed)
			(copperpour not_allowed)
			(footprints allowed)
		)
		(placement
			(enabled no)
			(sheetname "")
		)
		(fill
			(thermal_gap 0.5)
			(thermal_bridge_width 0.5)
			(island_removal_mode 0)
		)
		(polygon
			(pts
				(xy 51.52009 -14.521942) (xy 51.52009 -16.325342) (xy 52.07889 -16.325342) (xy 52.07889 -14.521942)
			)
		)
	)
	(zone
		(layer "In1.Cu")
		(hatch none 0.5)
		(connect_pads
			(clearance 0)
		)
		(min_thickness 0.25)
		(keepout
			(tracks not_allowed)
			(vias allowed)
			(pads allowed)
			(copperpour not_allowed)
			(footprints allowed)
		)
		(placement
			(enabled no)
			(sheetname "")
		)
		(fill
			(thermal_gap 0.5)
			(thermal_bridge_width 0.5)
			(island_removal_mode 0)
		)
		(polygon
			(pts
				(xy 253.920498 -4.920742) (xy 253.920498 -6.724142) (xy 254.479298 -6.724142) (xy 254.479298 -4.920742)
			)
		)
	)
	(zone
		(layer "In1.Cu")
		(hatch none 0.5)
		(connect_pads
			(clearance 0)
		)
		(min_thickness 0.25)
		(keepout
			(tracks not_allowed)
			(vias allowed)
			(pads allowed)
			(copperpour not_allowed)
			(footprints allowed)
		)
		(placement
			(enabled no)
			(sheetname "")
		)
		(fill
			(thermal_gap 0.5)
			(thermal_bridge_width 0.5)
			(island_removal_mode 0)
		)
		(polygon
			(pts
				(xy 272.620486 -14.521942) (xy 272.620486 -16.325342) (xy 273.179286 -16.325342) (xy 273.179286 -14.521942)
			)
		)
	)
	(zone
		(layer "In1.Cu")
		(hatch none 0.5)
		(connect_pads
			(clearance 0)
		)
		(min_thickness 0.25)
		(keepout
			(tracks not_allowed)
			(vias allowed)
			(pads allowed)
			(copperpour not_allowed)
			(footprints allowed)
		)
		(placement
			(enabled no)
			(sheetname "")
		)
		(fill
			(thermal_gap 0.5)
			(thermal_bridge_width 0.5)
			(island_removal_mode 0)
		)
		(polygon
			(pts
				(xy 338.079588 -118.957598) (xy 340.365588 -118.957598) (xy 340.365588 -119.465598) (xy 338.079588 -119.465598)
			)
		)
	)
	(zone
		(layer "In1.Cu")
		(hatch none 0.5)
		(connect_pads
			(clearance 0)
		)
		(min_thickness 0.25)
		(keepout
			(tracks not_allowed)
			(vias allowed)
			(pads allowed)
			(copperpour not_allowed)
			(footprints allowed)
		)
		(placement
			(enabled no)
			(sheetname "")
		)
		(fill
			(thermal_gap 0.5)
			(thermal_bridge_width 0.5)
			(island_removal_mode 0)
		)
		(polygon
			(pts
				(xy 458.74686 -111.011716) (xy 460.05496 -111.011716) (xy 460.05496 -113.399316) (xy 458.74686 -113.399316)
			)
		)
	)
	(zone
		(layer "In1.Cu")
		(hatch none 0.5)
		(connect_pads
			(clearance 0)
		)
		(min_thickness 0.25)
		(keepout
			(tracks not_allowed)
			(vias allowed)
			(pads allowed)
			(copperpour not_allowed)
			(footprints allowed)
		)
		(placement
			(enabled no)
			(sheetname "")
		)
		(fill
			(thermal_gap 0.5)
			(thermal_bridge_width 0.5)
			(island_removal_mode 0)
		)
		(polygon
			(pts
				(xy 133.119876 -4.920742) (xy 133.119876 -6.724142) (xy 133.678676 -6.724142) (xy 133.678676 -4.920742)
			)
		)
	)
	(zone
		(layer "In1.Cu")
		(hatch none 0.5)
		(connect_pads
			(clearance 0)
		)
		(min_thickness 0.25)
		(keepout
			(tracks not_allowed)
			(vias allowed)
			(pads allowed)
			(copperpour not_allowed)
			(footprints allowed)
		)
		(placement
			(enabled no)
			(sheetname "")
		)
		(fill
			(thermal_gap 0.5)
			(thermal_bridge_width 0.5)
			(island_removal_mode 0)
		)
		(polygon
			(pts
				(xy 139.919964 0.080518) (xy 139.919964 -1.722882) (xy 140.478764 -1.722882) (xy 140.478764 0.080518)
			)
		)
	)
	(zone
		(layer "In1.Cu")
		(hatch none 0.5)
		(connect_pads
			(clearance 0)
		)
		(min_thickness 0.25)
		(keepout
			(tracks not_allowed)
			(vias allowed)
			(pads allowed)
			(copperpour not_allowed)
			(footprints allowed)
		)
		(placement
			(enabled no)
			(sheetname "")
		)
		(fill
			(thermal_gap 0.5)
			(thermal_bridge_width 0.5)
			(island_removal_mode 0)
		)
		(polygon
			(pts
				(xy 252.220476 -141.775942) (xy 252.220476 -143.579342) (xy 252.779276 -143.579342) (xy 252.779276 -141.775942)
			)
		)
	)
	(zone
		(layer "In1.Cu")
		(hatch none 0.5)
		(connect_pads
			(clearance 0)
		)
		(min_thickness 0.25)
		(keepout
			(tracks not_allowed)
			(vias allowed)
			(pads allowed)
			(copperpour not_allowed)
			(footprints allowed)
		)
		(placement
			(enabled no)
			(sheetname "")
		)
		(fill
			(thermal_gap 0.5)
			(thermal_bridge_width 0.5)
			(island_removal_mode 0)
		)
		(polygon
			(pts
				(xy 49.820068 -14.521942) (xy 49.820068 -16.325342) (xy 50.378868 -16.325342) (xy 50.378868 -14.521942)
			)
		)
	)
	(zone
		(layer "In1.Cu")
		(hatch none 0.5)
		(connect_pads
			(clearance 0)
		)
		(min_thickness 0.25)
		(keepout
			(tracks not_allowed)
			(vias allowed)
			(pads allowed)
			(copperpour not_allowed)
			(footprints allowed)
		)
		(placement
			(enabled no)
			(sheetname "")
		)
		(fill
			(thermal_gap 0.5)
			(thermal_bridge_width 0.5)
			(island_removal_mode 0)
		)
		(polygon
			(pts
				(xy 266.670536 0.080518) (xy 266.670536 -1.722882) (xy 267.229336 -1.722882) (xy 267.229336 0.080518)
			)
		)
	)
	(zone
		(layer "In1.Cu")
		(hatch none 0.5)
		(connect_pads
			(clearance 0)
		)
		(min_thickness 0.25)
		(keepout
			(tracks not_allowed)
			(vias allowed)
			(pads allowed)
			(copperpour not_allowed)
			(footprints allowed)
		)
		(placement
			(enabled no)
			(sheetname "")
		)
		(fill
			(thermal_gap 0.5)
			(thermal_bridge_width 0.5)
			(island_removal_mode 0)
		)
		(polygon
			(pts
				(xy 36.220146 -136.774682) (xy 36.220146 -138.578082) (xy 36.778946 -138.578082) (xy 36.778946 -136.774682)
			)
		)
	)
	(zone
		(layer "In1.Cu")
		(hatch none 0.5)
		(connect_pads
			(clearance 0)
		)
		(min_thickness 0.25)
		(keepout
			(tracks not_allowed)
			(vias allowed)
			(pads allowed)
			(copperpour not_allowed)
			(footprints allowed)
		)
		(placement
			(enabled no)
			(sheetname "")
		)
		(fill
			(thermal_gap 0.5)
			(thermal_bridge_width 0.5)
			(island_removal_mode 0)
		)
		(polygon
			(pts
				(xy 120.370092 -132.174742) (xy 120.370092 -133.978142) (xy 120.928892 -133.978142) (xy 120.928892 -132.174742)
			)
		)
	)
	(zone
		(layer "In1.Cu")
		(hatch none 0.5)
		(connect_pads
			(clearance 0)
		)
		(min_thickness 0.25)
		(keepout
			(tracks not_allowed)
			(vias allowed)
			(pads allowed)
			(copperpour not_allowed)
			(footprints allowed)
		)
		(placement
			(enabled no)
			(sheetname "")
		)
		(fill
			(thermal_gap 0.5)
			(thermal_bridge_width 0.5)
			(island_removal_mode 0)
		)
		(polygon
			(pts
				(xy 107.620054 -4.920742) (xy 107.620054 -6.724142) (xy 108.178854 -6.724142) (xy 108.178854 -4.920742)
			)
		)
	)
	(zone
		(layer "In1.Cu")
		(hatch none 0.5)
		(connect_pads
			(clearance 0)
		)
		(min_thickness 0.25)
		(keepout
			(tracks not_allowed)
			(vias allowed)
			(pads allowed)
			(copperpour not_allowed)
			(footprints allowed)
		)
		(placement
			(enabled no)
			(sheetname "")
		)
		(fill
			(thermal_gap 0.5)
			(thermal_bridge_width 0.5)
			(island_removal_mode 0)
		)
		(polygon
			(pts
				(xy 133.119876 4.680458) (xy 133.119876 2.877058) (xy 133.678676 2.877058) (xy 133.678676 4.680458)
			)
		)
	)
	(zone
		(layer "In1.Cu")
		(hatch none 0.5)
		(connect_pads
			(clearance 0)
		)
		(min_thickness 0.25)
		(keepout
			(tracks not_allowed)
			(vias allowed)
			(pads allowed)
			(copperpour not_allowed)
			(footprints allowed)
		)
		(placement
			(enabled no)
			(sheetname "")
		)
		(fill
			(thermal_gap 0.5)
			(thermal_bridge_width 0.5)
			(island_removal_mode 0)
		)
		(polygon
			(pts
				(xy 68.520056 -141.775942) (xy 68.520056 -143.579342) (xy 69.078856 -143.579342) (xy 69.078856 -141.775942)
			)
		)
	)
	(zone
		(layer "In1.Cu")
		(hatch none 0.5)
		(connect_pads
			(clearance 0)
		)
		(min_thickness 0.25)
		(keepout
			(tracks not_allowed)
			(vias allowed)
			(pads allowed)
			(copperpour not_allowed)
			(footprints allowed)
		)
		(placement
			(enabled no)
			(sheetname "")
		)
		(fill
			(thermal_gap 0.5)
			(thermal_bridge_width 0.5)
			(island_removal_mode 0)
		)
		(polygon
			(pts
				(xy 224.170494 -141.775942) (xy 224.170494 -143.579342) (xy 224.729294 -143.579342) (xy 224.729294 -141.775942)
			)
		)
	)
	(zone
		(layer "In1.Cu")
		(hatch none 0.5)
		(connect_pads
			(clearance 0)
		)
		(min_thickness 0.25)
		(keepout
			(tracks not_allowed)
			(vias allowed)
			(pads allowed)
			(copperpour not_allowed)
			(footprints allowed)
		)
		(placement
			(enabled no)
			(sheetname "")
		)
		(fill
			(thermal_gap 0.5)
			(thermal_bridge_width 0.5)
			(island_removal_mode 0)
		)
		(polygon
			(pts
				(xy 30.269942 -19.121882) (xy 30.269942 -20.925282) (xy 30.828742 -20.925282) (xy 30.828742 -19.121882)
			)
		)
	)
	(zone
		(layer "In1.Cu")
		(hatch none 0.5)
		(connect_pads
			(clearance 0)
		)
		(min_thickness 0.25)
		(keepout
			(tracks not_allowed)
			(vias allowed)
			(pads allowed)
			(copperpour not_allowed)
			(footprints allowed)
		)
		(placement
			(enabled no)
			(sheetname "")
		)
		(fill
			(thermal_gap 0.5)
			(thermal_bridge_width 0.5)
			(island_removal_mode 0)
		)
		(polygon
			(pts
				(xy 449.823078 -3.789172) (xy 451.131178 -3.789172) (xy 451.131178 -4.982972) (xy 449.823078 -4.982972)
			)
		)
	)
	(zone
		(layer "In1.Cu")
		(hatch none 0.5)
		(connect_pads
			(clearance 0)
		)
		(min_thickness 0.25)
		(keepout
			(tracks not_allowed)
			(vias allowed)
			(pads allowed)
			(copperpour not_allowed)
			(footprints allowed)
		)
		(placement
			(enabled no)
			(sheetname "")
		)
		(fill
			(thermal_gap 0.5)
			(thermal_bridge_width 0.5)
			(island_removal_mode 0)
		)
		(polygon
			(pts
				(xy 228.420422 -151.377142) (xy 228.420422 -153.180542) (xy 228.979222 -153.180542) (xy 228.979222 -151.377142)
			)
		)
	)
	(zone
		(layer "In1.Cu")
		(hatch none 0.5)
		(connect_pads
			(clearance 0)
		)
		(min_thickness 0.25)
		(keepout
			(tracks not_allowed)
			(vias allowed)
			(pads allowed)
			(copperpour not_allowed)
			(footprints allowed)
		)
		(placement
			(enabled no)
			(sheetname "")
		)
		(fill
			(thermal_gap 0.5)
			(thermal_bridge_width 0.5)
			(island_removal_mode 0)
		)
		(polygon
			(pts
				(xy 309.170324 4.680458) (xy 309.170324 2.877058) (xy 309.729124 2.877058) (xy 309.729124 4.680458)
			)
		)
	)
	(zone
		(layer "In1.Cu")
		(hatch none 0.5)
		(connect_pads
			(clearance 0)
		)
		(min_thickness 0.25)
		(keepout
			(tracks not_allowed)
			(vias allowed)
			(pads allowed)
			(copperpour not_allowed)
			(footprints allowed)
		)
		(placement
			(enabled no)
			(sheetname "")
		)
		(fill
			(thermal_gap 0.5)
			(thermal_bridge_width 0.5)
			(island_removal_mode 0)
		)
		(polygon
			(pts
				(xy 273.47037 -9.520682) (xy 273.47037 -11.324082) (xy 274.02917 -11.324082) (xy 274.02917 -9.520682)
			)
		)
	)
	(zone
		(layer "In1.Cu")
		(hatch none 0.5)
		(connect_pads
			(clearance 0)
		)
		(min_thickness 0.25)
		(keepout
			(tracks not_allowed)
			(vias allowed)
			(pads allowed)
			(copperpour not_allowed)
			(footprints allowed)
		)
		(placement
			(enabled no)
			(sheetname "")
		)
		(fill
			(thermal_gap 0.5)
			(thermal_bridge_width 0.5)
			(island_removal_mode 0)
		)
		(polygon
			(pts
				(xy 122.919998 -146.375882) (xy 122.919998 -148.179282) (xy 123.478798 -148.179282) (xy 123.478798 -146.375882)
			)
		)
	)
	(zone
		(layer "In1.Cu")
		(hatch none 0.5)
		(connect_pads
			(clearance 0)
		)
		(min_thickness 0.25)
		(keepout
			(tracks not_allowed)
			(vias allowed)
			(pads allowed)
			(copperpour not_allowed)
			(footprints allowed)
		)
		(placement
			(enabled no)
			(sheetname "")
		)
		(fill
			(thermal_gap 0.5)
			(thermal_bridge_width 0.5)
			(island_removal_mode 0)
		)
		(polygon
			(pts
				(xy 137.370058 -132.174742) (xy 137.370058 -133.978142) (xy 137.928858 -133.978142) (xy 137.928858 -132.174742)
			)
		)
	)
	(zone
		(layer "In1.Cu")
		(hatch none 0.5)
		(connect_pads
			(clearance 0)
		)
		(min_thickness 0.25)
		(keepout
			(tracks not_allowed)
			(vias allowed)
			(pads allowed)
			(copperpour not_allowed)
			(footprints allowed)
		)
		(placement
			(enabled no)
			(sheetname "")
		)
		(fill
			(thermal_gap 0.5)
			(thermal_bridge_width 0.5)
			(island_removal_mode 0)
		)
		(polygon
			(pts
				(xy 298.120308 -132.174742) (xy 298.120308 -133.978142) (xy 298.679108 -133.978142) (xy 298.679108 -132.174742)
			)
		)
	)
	(zone
		(layer "In1.Cu")
		(hatch none 0.5)
		(connect_pads
			(clearance 0)
		)
		(min_thickness 0.25)
		(keepout
			(tracks not_allowed)
			(vias allowed)
			(pads allowed)
			(copperpour not_allowed)
			(footprints allowed)
		)
		(placement
			(enabled no)
			(sheetname "")
		)
		(fill
			(thermal_gap 0.5)
			(thermal_bridge_width 0.5)
			(island_removal_mode 0)
		)
		(polygon
			(pts
				(xy 257.320542 0.080518) (xy 257.320542 -1.722882) (xy 257.879342 -1.722882) (xy 257.879342 0.080518)
			)
		)
	)
	(zone
		(layer "In1.Cu")
		(hatch none 0.5)
		(connect_pads
			(clearance 0)
		)
		(min_thickness 0.25)
		(keepout
			(tracks not_allowed)
			(vias allowed)
			(pads allowed)
			(copperpour not_allowed)
			(footprints allowed)
		)
		(placement
			(enabled no)
			(sheetname "")
		)
		(fill
			(thermal_gap 0.5)
			(thermal_bridge_width 0.5)
			(island_removal_mode 0)
		)
		(polygon
			(pts
				(xy 254.770382 -136.774682) (xy 254.770382 -138.578082) (xy 255.329182 -138.578082) (xy 255.329182 -136.774682)
			)
		)
	)
	(zone
		(layer "In1.Cu")
		(hatch none 0.5)
		(connect_pads
			(clearance 0)
		)
		(min_thickness 0.25)
		(keepout
			(tracks not_allowed)
			(vias allowed)
			(pads allowed)
			(copperpour not_allowed)
			(footprints allowed)
		)
		(placement
			(enabled no)
			(sheetname "")
		)
		(fill
			(thermal_gap 0.5)
			(thermal_bridge_width 0.5)
			(island_removal_mode 0)
		)
		(polygon
			(pts
				(xy 272.620486 -141.775942) (xy 272.620486 -143.579342) (xy 273.179286 -143.579342) (xy 273.179286 -141.775942)
			)
		)
	)
	(zone
		(layer "In1.Cu")
		(hatch none 0.5)
		(connect_pads
			(clearance 0)
		)
		(min_thickness 0.25)
		(keepout
			(tracks not_allowed)
			(vias allowed)
			(pads allowed)
			(copperpour not_allowed)
			(footprints allowed)
		)
		(placement
			(enabled no)
			(sheetname "")
		)
		(fill
			(thermal_gap 0.5)
			(thermal_bridge_width 0.5)
			(island_removal_mode 0)
		)
		(polygon
			(pts
				(xy 145.869914 -4.920742) (xy 145.869914 -6.724142) (xy 146.428714 -6.724142) (xy 146.428714 -4.920742)
			)
		)
	)
	(zone
		(layer "In1.Cu")
		(hatch none 0.5)
		(connect_pads
			(clearance 0)
		)
		(min_thickness 0.25)
		(keepout
			(tracks not_allowed)
			(vias allowed)
			(pads allowed)
			(copperpour not_allowed)
			(footprints allowed)
		)
		(placement
			(enabled no)
			(sheetname "")
		)
		(fill
			(thermal_gap 0.5)
			(thermal_bridge_width 0.5)
			(island_removal_mode 0)
		)
		(polygon
			(pts
				(xy 116.11991 -132.174742) (xy 116.11991 -133.978142) (xy 116.67871 -133.978142) (xy 116.67871 -132.174742)
			)
		)
	)
	(zone
		(layer "In1.Cu")
		(hatch none 0.5)
		(connect_pads
			(clearance 0)
		)
		(min_thickness 0.25)
		(keepout
			(tracks not_allowed)
			(vias allowed)
			(pads allowed)
			(copperpour not_allowed)
			(footprints allowed)
		)
		(placement
			(enabled no)
			(sheetname "")
		)
		(fill
			(thermal_gap 0.5)
			(thermal_bridge_width 0.5)
			(island_removal_mode 0)
		)
		(polygon
			(pts
				(xy 405.017986 -7.192772) (xy 406.326086 -7.192772) (xy 406.326086 -8.386572) (xy 405.017986 -8.386572)
			)
		)
	)
	(zone
		(layer "In1.Cu")
		(hatch none 0.5)
		(connect_pads
			(clearance 0)
		)
		(min_thickness 0.25)
		(keepout
			(tracks not_allowed)
			(vias allowed)
			(pads allowed)
			(copperpour not_allowed)
			(footprints allowed)
		)
		(placement
			(enabled no)
			(sheetname "")
		)
		(fill
			(thermal_gap 0.5)
			(thermal_bridge_width 0.5)
			(island_removal_mode 0)
		)
		(polygon
			(pts
				(xy 266.670536 -9.520682) (xy 266.670536 -11.324082) (xy 267.229336 -11.324082) (xy 267.229336 -9.520682)
			)
		)
	)
	(zone
		(layer "In1.Cu")
		(hatch none 0.5)
		(connect_pads
			(clearance 0)
		)
		(min_thickness 0.25)
		(keepout
			(tracks not_allowed)
			(vias allowed)
			(pads allowed)
			(copperpour not_allowed)
			(footprints allowed)
		)
		(placement
			(enabled no)
			(sheetname "")
		)
		(fill
			(thermal_gap 0.5)
			(thermal_bridge_width 0.5)
			(island_removal_mode 0)
		)
		(polygon
			(pts
				(xy 323.4055 -122.301) (xy 325.6915 -122.301) (xy 325.6915 -122.809) (xy 323.4055 -122.809)
			)
		)
	)
	(zone
		(net "P12V_PSU")
		(layer "In1.Cu")
		(hatch none 0.5)
		(connect_pads
			(clearance 0.5)
		)
		(min_thickness 0.25)
		(fill yes
			(thermal_gap 0.5)
			(thermal_bridge_width 0.5)
			(island_removal_mode 0)
		)
		(polygon
			(pts
				(xy 3.5306 -68.714874) (xy 3.5306 -85.585046) (xy 4.076954 -86.1314) (xy 9.8298 -86.1314) (xy 10.0584 -85.9028)
				(xy 10.0584 -58.3692) (xy 10.0584 -50.546762) (xy 9.5504 -50.038762) (xy 9.459722 -50.038762) (xy 3.361182 -50.038762)
				(xy 3.0734 -50.326544) (xy 3.0734 -58.9534) (xy 2.286 -59.7408) (xy 2.286 -59.89447) (xy 1.778762 -60.401708)
				(xy 1.729486 -60.401708) (xy 1.729486 -66.91376)
			)
		)
	)
	(zone
		(layer "In1.Cu")
		(hatch none 0.5)
		(connect_pads
			(clearance 0)
		)
		(min_thickness 0.25)
		(keepout
			(tracks not_allowed)
			(vias allowed)
			(pads allowed)
			(copperpour not_allowed)
			(footprints allowed)
		)
		(placement
			(enabled no)
			(sheetname "")
		)
		(fill
			(thermal_gap 0.5)
			(thermal_bridge_width 0.5)
			(island_removal_mode 0)
		)
		(polygon
			(pts
				(xy 440.286902 -50.872644) (xy 441.595002 -50.872644) (xy 441.595002 -52.879244) (xy 440.286902 -52.879244)
			)
		)
	)
	(zone
		(layer "In1.Cu")
		(hatch none 0.5)
		(connect_pads
			(clearance 0)
		)
		(min_thickness 0.25)
		(keepout
			(tracks not_allowed)
			(vias allowed)
			(pads allowed)
			(copperpour not_allowed)
			(footprints allowed)
		)
		(placement
			(enabled no)
			(sheetname "")
		)
		(fill
			(thermal_gap 0.5)
			(thermal_bridge_width 0.5)
			(island_removal_mode 0)
		)
		(polygon
			(pts
				(xy 84.670138 4.680458) (xy 84.670138 2.877058) (xy 85.228938 2.877058) (xy 85.228938 4.680458)
			)
		)
	)
	(zone
		(layer "In1.Cu")
		(hatch none 0.5)
		(connect_pads
			(clearance 0)
		)
		(min_thickness 0.25)
		(keepout
			(tracks not_allowed)
			(vias allowed)
			(pads allowed)
			(copperpour not_allowed)
			(footprints allowed)
		)
		(placement
			(enabled no)
			(sheetname "")
		)
		(fill
			(thermal_gap 0.5)
			(thermal_bridge_width 0.5)
			(island_removal_mode 0)
		)
		(polygon
			(pts
				(xy 131.420108 -14.521942) (xy 131.420108 -16.325342) (xy 131.978908 -16.325342) (xy 131.978908 -14.521942)
			)
		)
	)
	(zone
		(layer "In1.Cu")
		(hatch none 0.5)
		(connect_pads
			(clearance 0)
		)
		(min_thickness 0.25)
		(keepout
			(tracks not_allowed)
			(vias allowed)
			(pads allowed)
			(copperpour not_allowed)
			(footprints allowed)
		)
		(placement
			(enabled no)
			(sheetname "")
		)
		(fill
			(thermal_gap 0.5)
			(thermal_bridge_width 0.5)
			(island_removal_mode 0)
		)
		(polygon
			(pts
				(xy 128.869948 -146.375882) (xy 128.869948 -148.179282) (xy 129.428748 -148.179282) (xy 129.428748 -146.375882)
			)
		)
	)
	(zone
		(layer "In1.Cu")
		(hatch none 0.5)
		(connect_pads
			(clearance 0)
		)
		(min_thickness 0.25)
		(keepout
			(tracks not_allowed)
			(vias allowed)
			(pads allowed)
			(copperpour not_allowed)
			(footprints allowed)
		)
		(placement
			(enabled no)
			(sheetname "")
		)
		(fill
			(thermal_gap 0.5)
			(thermal_bridge_width 0.5)
			(island_removal_mode 0)
		)
		(polygon
			(pts
				(xy 103.370126 -132.174742) (xy 103.370126 -133.978142) (xy 103.928926 -133.978142) (xy 103.928926 -132.174742)
			)
		)
	)
	(zone
		(layer "In1.Cu")
		(hatch none 0.5)
		(connect_pads
			(clearance 0)
		)
		(min_thickness 0.25)
		(keepout
			(tracks not_allowed)
			(vias allowed)
			(pads allowed)
			(copperpour not_allowed)
			(footprints allowed)
		)
		(placement
			(enabled no)
			(sheetname "")
		)
		(fill
			(thermal_gap 0.5)
			(thermal_bridge_width 0.5)
			(island_removal_mode 0)
		)
		(polygon
			(pts
				(xy 426.620686 -7.192772) (xy 427.928786 -7.192772) (xy 427.928786 -8.386572) (xy 426.620686 -8.386572)
			)
		)
	)
	(zone
		(layer "In1.Cu")
		(hatch none 0.5)
		(connect_pads
			(clearance 0)
		)
		(min_thickness 0.25)
		(keepout
			(tracks not_allowed)
			(vias allowed)
			(pads allowed)
			(copperpour not_allowed)
			(footprints allowed)
		)
		(placement
			(enabled no)
			(sheetname "")
		)
		(fill
			(thermal_gap 0.5)
			(thermal_bridge_width 0.5)
			(island_removal_mode 0)
		)
		(polygon
			(pts
				(xy 299.82033 -4.920742) (xy 299.82033 -6.724142) (xy 300.37913 -6.724142) (xy 300.37913 -4.920742)
			)
		)
	)
	(zone
		(layer "In1.Cu")
		(hatch none 0.5)
		(connect_pads
			(clearance 0)
		)
		(min_thickness 0.25)
		(keepout
			(tracks not_allowed)
			(vias allowed)
			(pads allowed)
			(copperpour not_allowed)
			(footprints allowed)
		)
		(placement
			(enabled no)
			(sheetname "")
		)
		(fill
			(thermal_gap 0.5)
			(thermal_bridge_width 0.5)
			(island_removal_mode 0)
		)
		(polygon
			(pts
				(xy 331.75702 -118.2624) (xy 334.04302 -118.2624) (xy 334.04302 -118.7704) (xy 331.75702 -118.7704)
			)
		)
	)
	(zone
		(layer "In1.Cu")
		(hatch none 0.5)
		(connect_pads
			(clearance 0)
		)
		(min_thickness 0.25)
		(keepout
			(tracks not_allowed)
			(vias allowed)
			(pads allowed)
			(copperpour not_allowed)
			(footprints allowed)
		)
		(placement
			(enabled no)
			(sheetname "")
		)
		(fill
			(thermal_gap 0.5)
			(thermal_bridge_width 0.5)
			(island_removal_mode 0)
		)
		(polygon
			(pts
				(xy 35.370008 4.680458) (xy 35.370008 2.877058) (xy 35.928808 2.877058) (xy 35.928808 4.680458)
			)
		)
	)
	(zone
		(layer "In1.Cu")
		(hatch none 0.5)
		(connect_pads
			(clearance 0)
		)
		(min_thickness 0.25)
		(keepout
			(tracks not_allowed)
			(vias allowed)
			(pads allowed)
			(copperpour not_allowed)
			(footprints allowed)
		)
		(placement
			(enabled no)
			(sheetname "")
		)
		(fill
			(thermal_gap 0.5)
			(thermal_bridge_width 0.5)
			(island_removal_mode 0)
		)
		(polygon
			(pts
				(xy 311.720484 -9.520682) (xy 311.720484 -11.324082) (xy 312.279284 -11.324082) (xy 312.279284 -9.520682)
			)
		)
	)
	(zone
		(layer "In1.Cu")
		(hatch none 0.5)
		(connect_pads
			(clearance 0)
		)
		(min_thickness 0.25)
		(keepout
			(tracks not_allowed)
			(vias allowed)
			(pads allowed)
			(copperpour not_allowed)
			(footprints allowed)
		)
		(placement
			(enabled no)
			(sheetname "")
		)
		(fill
			(thermal_gap 0.5)
			(thermal_bridge_width 0.5)
			(island_removal_mode 0)
		)
		(polygon
			(pts
				(xy 206.32039 -155.977082) (xy 206.32039 -157.780482) (xy 206.87919 -157.780482) (xy 206.87919 -155.977082)
			)
		)
	)
	(zone
		(layer "In1.Cu")
		(hatch none 0.5)
		(connect_pads
			(clearance 0)
		)
		(min_thickness 0.25)
		(keepout
			(tracks not_allowed)
			(vias allowed)
			(pads allowed)
			(copperpour not_allowed)
			(footprints allowed)
		)
		(placement
			(enabled no)
			(sheetname "")
		)
		(fill
			(thermal_gap 0.5)
			(thermal_bridge_width 0.5)
			(island_removal_mode 0)
		)
		(polygon
			(pts
				(xy 208.020412 -155.977082) (xy 208.020412 -157.780482) (xy 208.579212 -157.780482) (xy 208.579212 -155.977082)
			)
		)
	)
	(zone
		(layer "In1.Cu")
		(hatch none 0.5)
		(connect_pads
			(clearance 0)
		)
		(min_thickness 0.25)
		(keepout
			(tracks not_allowed)
			(vias allowed)
			(pads allowed)
			(copperpour not_allowed)
			(footprints allowed)
		)
		(placement
			(enabled no)
			(sheetname "")
		)
		(fill
			(thermal_gap 0.5)
			(thermal_bridge_width 0.5)
			(island_removal_mode 0)
		)
		(polygon
			(pts
				(xy 264.970514 -155.977082) (xy 264.970514 -157.780482) (xy 265.529314 -157.780482) (xy 265.529314 -155.977082)
			)
		)
	)
	(zone
		(layer "In1.Cu")
		(hatch none 0.5)
		(connect_pads
			(clearance 0)
		)
		(min_thickness 0.25)
		(keepout
			(tracks not_allowed)
			(vias allowed)
			(pads allowed)
			(copperpour not_allowed)
			(footprints allowed)
		)
		(placement
			(enabled no)
			(sheetname "")
		)
		(fill
			(thermal_gap 0.5)
			(thermal_bridge_width 0.5)
			(island_removal_mode 0)
		)
		(polygon
			(pts
				(xy 48.96993 -155.977082) (xy 48.96993 -157.780482) (xy 49.52873 -157.780482) (xy 49.52873 -155.977082)
			)
		)
	)
	(zone
		(layer "In1.Cu")
		(hatch none 0.5)
		(connect_pads
			(clearance 0)
		)
		(min_thickness 0.25)
		(keepout
			(tracks not_allowed)
			(vias allowed)
			(pads allowed)
			(copperpour not_allowed)
			(footprints allowed)
		)
		(placement
			(enabled no)
			(sheetname "")
		)
		(fill
			(thermal_gap 0.5)
			(thermal_bridge_width 0.5)
			(island_removal_mode 0)
		)
		(polygon
			(pts
				(xy 277.720552 -151.377142) (xy 277.720552 -153.180542) (xy 278.279352 -153.180542) (xy 278.279352 -151.377142)
			)
		)
	)
	(zone
		(layer "In1.Cu")
		(hatch none 0.5)
		(connect_pads
			(clearance 0)
		)
		(min_thickness 0.25)
		(keepout
			(tracks not_allowed)
			(vias allowed)
			(pads allowed)
			(copperpour not_allowed)
			(footprints allowed)
		)
		(placement
			(enabled no)
			(sheetname "")
		)
		(fill
			(thermal_gap 0.5)
			(thermal_bridge_width 0.5)
			(island_removal_mode 0)
		)
		(polygon
			(pts
				(xy 87.220044 -4.920742) (xy 87.220044 -6.724142) (xy 87.778844 -6.724142) (xy 87.778844 -4.920742)
			)
		)
	)
	(zone
		(layer "In1.Cu")
		(hatch none 0.5)
		(connect_pads
			(clearance 0)
		)
		(min_thickness 0.25)
		(keepout
			(tracks not_allowed)
			(vias allowed)
			(pads allowed)
			(copperpour not_allowed)
			(footprints allowed)
		)
		(placement
			(enabled no)
			(sheetname "")
		)
		(fill
			(thermal_gap 0.5)
			(thermal_bridge_width 0.5)
			(island_removal_mode 0)
		)
		(polygon
			(pts
				(xy 235.22051 -141.775942) (xy 235.22051 -143.579342) (xy 235.77931 -143.579342) (xy 235.77931 -141.775942)
			)
		)
	)
	(zone
		(layer "In1.Cu")
		(hatch none 0.5)
		(connect_pads
			(clearance 0)
		)
		(min_thickness 0.25)
		(keepout
			(tracks not_allowed)
			(vias allowed)
			(pads allowed)
			(copperpour not_allowed)
			(footprints allowed)
		)
		(placement
			(enabled no)
			(sheetname "")
		)
		(fill
			(thermal_gap 0.5)
			(thermal_bridge_width 0.5)
			(island_removal_mode 0)
		)
		(polygon
			(pts
				(xy 200.37044 -19.121882) (xy 200.37044 -20.925282) (xy 200.92924 -20.925282) (xy 200.92924 -19.121882)
			)
		)
	)
	(zone
		(layer "In1.Cu")
		(hatch none 0.5)
		(connect_pads
			(clearance 0)
		)
		(min_thickness 0.25)
		(keepout
			(tracks not_allowed)
			(vias allowed)
			(pads allowed)
			(copperpour not_allowed)
			(footprints allowed)
		)
		(placement
			(enabled no)
			(sheetname "")
		)
		(fill
			(thermal_gap 0.5)
			(thermal_bridge_width 0.5)
			(island_removal_mode 0)
		)
		(polygon
			(pts
				(xy 138.219942 -19.121882) (xy 138.219942 -20.925282) (xy 138.778742 -20.925282) (xy 138.778742 -19.121882)
			)
		)
	)
	(zone
		(layer "In1.Cu")
		(hatch none 0.5)
		(connect_pads
			(clearance 0)
		)
		(min_thickness 0.25)
		(keepout
			(tracks not_allowed)
			(vias allowed)
			(pads allowed)
			(copperpour not_allowed)
			(footprints allowed)
		)
		(placement
			(enabled no)
			(sheetname "")
		)
		(fill
			(thermal_gap 0.5)
			(thermal_bridge_width 0.5)
			(island_removal_mode 0)
		)
		(polygon
			(pts
				(xy 124.62002 -19.121882) (xy 124.62002 -20.925282) (xy 125.17882 -20.925282) (xy 125.17882 -19.121882)
			)
		)
	)
	(zone
		(layer "In1.Cu")
		(hatch none 0.5)
		(connect_pads
			(clearance 0)
		)
		(min_thickness 0.25)
		(keepout
			(tracks not_allowed)
			(vias allowed)
			(pads allowed)
			(copperpour not_allowed)
			(footprints allowed)
		)
		(placement
			(enabled no)
			(sheetname "")
		)
		(fill
			(thermal_gap 0.5)
			(thermal_bridge_width 0.5)
			(island_removal_mode 0)
		)
		(polygon
			(pts
				(xy 145.869914 -151.377142) (xy 145.869914 -153.180542) (xy 146.428714 -153.180542) (xy 146.428714 -151.377142)
			)
		)
	)
	(zone
		(layer "In1.Cu")
		(hatch none 0.5)
		(connect_pads
			(clearance 0)
		)
		(min_thickness 0.25)
		(keepout
			(tracks not_allowed)
			(vias allowed)
			(pads allowed)
			(copperpour not_allowed)
			(footprints allowed)
		)
		(placement
			(enabled no)
			(sheetname "")
		)
		(fill
			(thermal_gap 0.5)
			(thermal_bridge_width 0.5)
			(island_removal_mode 0)
		)
		(polygon
			(pts
				(xy 201.220578 -146.375882) (xy 201.220578 -148.179282) (xy 201.779378 -148.179282) (xy 201.779378 -146.375882)
			)
		)
	)
	(zone
		(layer "In1.Cu")
		(hatch none 0.5)
		(connect_pads
			(clearance 0)
		)
		(min_thickness 0.25)
		(keepout
			(tracks not_allowed)
			(vias allowed)
			(pads allowed)
			(copperpour not_allowed)
			(footprints allowed)
		)
		(placement
			(enabled no)
			(sheetname "")
		)
		(fill
			(thermal_gap 0.5)
			(thermal_bridge_width 0.5)
			(island_removal_mode 0)
		)
		(polygon
			(pts
				(xy 87.220044 -141.775942) (xy 87.220044 -143.579342) (xy 87.778844 -143.579342) (xy 87.778844 -141.775942)
			)
		)
	)
	(zone
		(layer "In1.Cu")
		(hatch none 0.5)
		(connect_pads
			(clearance 0)
		)
		(min_thickness 0.25)
		(keepout
			(tracks not_allowed)
			(vias allowed)
			(pads allowed)
			(copperpour not_allowed)
			(footprints allowed)
		)
		(placement
			(enabled no)
			(sheetname "")
		)
		(fill
			(thermal_gap 0.5)
			(thermal_bridge_width 0.5)
			(island_removal_mode 0)
		)
		(polygon
			(pts
				(xy 54.069996 -19.121882) (xy 54.069996 -20.925282) (xy 54.628796 -20.925282) (xy 54.628796 -19.121882)
			)
		)
	)
	(zone
		(layer "In1.Cu")
		(hatch none 0.5)
		(connect_pads
			(clearance 0)
		)
		(min_thickness 0.25)
		(keepout
			(tracks not_allowed)
			(vias allowed)
			(pads allowed)
			(copperpour not_allowed)
			(footprints allowed)
		)
		(placement
			(enabled no)
			(sheetname "")
		)
		(fill
			(thermal_gap 0.5)
			(thermal_bridge_width 0.5)
			(island_removal_mode 0)
		)
		(polygon
			(pts
				(xy 76.170282 4.680458) (xy 76.170282 2.877058) (xy 76.729082 2.877058) (xy 76.729082 4.680458)
			)
		)
	)
	(zone
		(layer "In1.Cu")
		(hatch none 0.5)
		(connect_pads
			(clearance 0)
		)
		(min_thickness 0.25)
		(keepout
			(tracks not_allowed)
			(vias allowed)
			(pads allowed)
			(copperpour not_allowed)
			(footprints allowed)
		)
		(placement
			(enabled no)
			(sheetname "")
		)
		(fill
			(thermal_gap 0.5)
			(thermal_bridge_width 0.5)
			(island_removal_mode 0)
		)
		(polygon
			(pts
				(xy 128.869948 -155.977082) (xy 128.869948 -157.780482) (xy 129.428748 -157.780482) (xy 129.428748 -155.977082)
			)
		)
	)
	(zone
		(layer "In1.Cu")
		(hatch none 0.5)
		(connect_pads
			(clearance 0)
		)
		(min_thickness 0.25)
		(keepout
			(tracks not_allowed)
			(vias allowed)
			(pads allowed)
			(copperpour not_allowed)
			(footprints allowed)
		)
		(placement
			(enabled no)
			(sheetname "")
		)
		(fill
			(thermal_gap 0.5)
			(thermal_bridge_width 0.5)
			(island_removal_mode 0)
		)
		(polygon
			(pts
				(xy 444.346838 -115.799362) (xy 445.654938 -115.799362) (xy 445.654938 -118.186962) (xy 444.346838 -118.186962)
			)
		)
	)
	(zone
		(layer "In1.Cu")
		(hatch none 0.5)
		(connect_pads
			(clearance 0)
		)
		(min_thickness 0.25)
		(keepout
			(tracks not_allowed)
			(vias allowed)
			(pads allowed)
			(copperpour not_allowed)
			(footprints allowed)
		)
		(placement
			(enabled no)
			(sheetname "")
		)
		(fill
			(thermal_gap 0.5)
			(thermal_bridge_width 0.5)
			(island_removal_mode 0)
		)
		(polygon
			(pts
				(xy 39.619936 0.080518) (xy 39.619936 -1.722882) (xy 40.178736 -1.722882) (xy 40.178736 0.080518)
			)
		)
	)
	(zone
		(layer "In1.Cu")
		(hatch none 0.5)
		(connect_pads
			(clearance 0)
		)
		(min_thickness 0.25)
		(keepout
			(tracks not_allowed)
			(vias allowed)
			(pads allowed)
			(copperpour not_allowed)
			(footprints allowed)
		)
		(placement
			(enabled no)
			(sheetname "")
		)
		(fill
			(thermal_gap 0.5)
			(thermal_bridge_width 0.5)
			(island_removal_mode 0)
		)
		(polygon
			(pts
				(xy 148.420074 -132.174742) (xy 148.420074 -133.978142) (xy 148.978874 -133.978142) (xy 148.978874 -132.174742)
			)
		)
	)
	(zone
		(layer "In1.Cu")
		(hatch none 0.5)
		(connect_pads
			(clearance 0)
		)
		(min_thickness 0.25)
		(keepout
			(tracks not_allowed)
			(vias allowed)
			(pads allowed)
			(copperpour not_allowed)
			(footprints allowed)
		)
		(placement
			(enabled no)
			(sheetname "")
		)
		(fill
			(thermal_gap 0.5)
			(thermal_bridge_width 0.5)
			(island_removal_mode 0)
		)
		(polygon
			(pts
				(xy 136.51992 -14.521942) (xy 136.51992 -16.325342) (xy 137.07872 -16.325342) (xy 137.07872 -14.521942)
			)
		)
	)
	(zone
		(layer "In1.Cu")
		(hatch none 0.5)
		(connect_pads
			(clearance 0)
		)
		(min_thickness 0.25)
		(keepout
			(tracks not_allowed)
			(vias allowed)
			(pads allowed)
			(copperpour not_allowed)
			(footprints allowed)
		)
		(placement
			(enabled no)
			(sheetname "")
		)
		(fill
			(thermal_gap 0.5)
			(thermal_bridge_width 0.5)
			(island_removal_mode 0)
		)
		(polygon
			(pts
				(xy 65.120012 -14.521942) (xy 65.120012 -16.325342) (xy 65.678812 -16.325342) (xy 65.678812 -14.521942)
			)
		)
	)
	(zone
		(layer "In1.Cu")
		(hatch none 0.5)
		(connect_pads
			(clearance 0)
		)
		(min_thickness 0.25)
		(keepout
			(tracks not_allowed)
			(vias allowed)
			(pads allowed)
			(copperpour not_allowed)
			(footprints allowed)
		)
		(placement
			(enabled no)
			(sheetname "")
		)
		(fill
			(thermal_gap 0.5)
			(thermal_bridge_width 0.5)
			(island_removal_mode 0)
		)
		(polygon
			(pts
				(xy 134.819898 4.680458) (xy 134.819898 2.877058) (xy 135.378698 2.877058) (xy 135.378698 4.680458)
			)
		)
	)
	(zone
		(layer "In1.Cu")
		(hatch none 0.5)
		(connect_pads
			(clearance 0)
		)
		(min_thickness 0.25)
		(keepout
			(tracks not_allowed)
			(vias allowed)
			(pads allowed)
			(copperpour not_allowed)
			(footprints allowed)
		)
		(placement
			(enabled no)
			(sheetname "")
		)
		(fill
			(thermal_gap 0.5)
			(thermal_bridge_width 0.5)
			(island_removal_mode 0)
		)
		(polygon
			(pts
				(xy 62.570106 -132.174742) (xy 62.570106 -133.978142) (xy 63.128906 -133.978142) (xy 63.128906 -132.174742)
			)
		)
	)
	(zone
		(layer "In1.Cu")
		(hatch none 0.5)
		(connect_pads
			(clearance 0)
		)
		(min_thickness 0.25)
		(keepout
			(tracks not_allowed)
			(vias allowed)
			(pads allowed)
			(copperpour not_allowed)
			(footprints allowed)
		)
		(placement
			(enabled no)
			(sheetname "")
		)
		(fill
			(thermal_gap 0.5)
			(thermal_bridge_width 0.5)
			(island_removal_mode 0)
		)
		(polygon
			(pts
				(xy 48.120046 -151.377142) (xy 48.120046 -153.180542) (xy 48.678846 -153.180542) (xy 48.678846 -151.377142)
			)
		)
	)
	(zone
		(layer "In1.Cu")
		(hatch none 0.5)
		(connect_pads
			(clearance 0)
		)
		(min_thickness 0.25)
		(keepout
			(tracks not_allowed)
			(vias allowed)
			(pads allowed)
			(copperpour not_allowed)
			(footprints allowed)
		)
		(placement
			(enabled no)
			(sheetname "")
		)
		(fill
			(thermal_gap 0.5)
			(thermal_bridge_width 0.5)
			(island_removal_mode 0)
		)
		(polygon
			(pts
				(xy 227.570538 -4.920742) (xy 227.570538 -6.724142) (xy 228.129338 -6.724142) (xy 228.129338 -4.920742)
			)
		)
	)
	(zone
		(layer "In1.Cu")
		(hatch none 0.5)
		(connect_pads
			(clearance 0)
		)
		(min_thickness 0.25)
		(keepout
			(tracks not_allowed)
			(vias allowed)
			(pads allowed)
			(copperpour not_allowed)
			(footprints allowed)
		)
		(placement
			(enabled no)
			(sheetname "")
		)
		(fill
			(thermal_gap 0.5)
			(thermal_bridge_width 0.5)
			(island_removal_mode 0)
		)
		(polygon
			(pts
				(xy 228.420422 0.080518) (xy 228.420422 -1.722882) (xy 228.979222 -1.722882) (xy 228.979222 0.080518)
			)
		)
	)
	(zone
		(layer "In1.Cu")
		(hatch none 0.5)
		(connect_pads
			(clearance 0)
		)
		(min_thickness 0.25)
		(keepout
			(tracks not_allowed)
			(vias allowed)
			(pads allowed)
			(copperpour not_allowed)
			(footprints allowed)
		)
		(placement
			(enabled no)
			(sheetname "")
		)
		(fill
			(thermal_gap 0.5)
			(thermal_bridge_width 0.5)
			(island_removal_mode 0)
		)
		(polygon
			(pts
				(xy 196.120512 -141.775942) (xy 196.120512 -143.579342) (xy 196.679312 -143.579342) (xy 196.679312 -141.775942)
			)
		)
	)
	(zone
		(layer "In1.Cu")
		(hatch none 0.5)
		(connect_pads
			(clearance 0)
		)
		(min_thickness 0.25)
		(keepout
			(tracks not_allowed)
			(vias allowed)
			(pads allowed)
			(copperpour not_allowed)
			(footprints allowed)
		)
		(placement
			(enabled no)
			(sheetname "")
		)
		(fill
			(thermal_gap 0.5)
			(thermal_bridge_width 0.5)
			(island_removal_mode 0)
		)
		(polygon
			(pts
				(xy 442.622686 -3.789172) (xy 443.930786 -3.789172) (xy 443.930786 -4.982972) (xy 442.622686 -4.982972)
			)
		)
	)
	(zone
		(layer "In1.Cu")
		(hatch none 0.5)
		(connect_pads
			(clearance 0)
		)
		(min_thickness 0.25)
		(keepout
			(tracks not_allowed)
			(vias allowed)
			(pads allowed)
			(copperpour not_allowed)
			(footprints allowed)
		)
		(placement
			(enabled no)
			(sheetname "")
		)
		(fill
			(thermal_gap 0.5)
			(thermal_bridge_width 0.5)
			(island_removal_mode 0)
		)
		(polygon
			(pts
				(xy 139.07008 -151.377142) (xy 139.07008 -153.180542) (xy 139.62888 -153.180542) (xy 139.62888 -151.377142)
			)
		)
	)
	(zone
		(layer "In1.Cu")
		(hatch none 0.5)
		(connect_pads
			(clearance 0)
		)
		(min_thickness 0.25)
		(keepout
			(tracks not_allowed)
			(vias allowed)
			(pads allowed)
			(copperpour not_allowed)
			(footprints allowed)
		)
		(placement
			(enabled no)
			(sheetname "")
		)
		(fill
			(thermal_gap 0.5)
			(thermal_bridge_width 0.5)
			(island_removal_mode 0)
		)
		(polygon
			(pts
				(xy 253.070614 -146.375882) (xy 253.070614 -148.179282) (xy 253.629414 -148.179282) (xy 253.629414 -146.375882)
			)
		)
	)
	(zone
		(layer "In1.Cu")
		(hatch none 0.5)
		(connect_pads
			(clearance 0)
		)
		(min_thickness 0.25)
		(keepout
			(tracks not_allowed)
			(vias allowed)
			(pads allowed)
			(copperpour not_allowed)
			(footprints allowed)
		)
		(placement
			(enabled no)
			(sheetname "")
		)
		(fill
			(thermal_gap 0.5)
			(thermal_bridge_width 0.5)
			(island_removal_mode 0)
		)
		(polygon
			(pts
				(xy 209.720434 -19.121882) (xy 209.720434 -20.925282) (xy 210.279234 -20.925282) (xy 210.279234 -19.121882)
			)
		)
	)
	(zone
		(layer "In1.Cu")
		(hatch none 0.5)
		(connect_pads
			(clearance 0)
		)
		(min_thickness 0.25)
		(keepout
			(tracks not_allowed)
			(vias allowed)
			(pads allowed)
			(copperpour not_allowed)
			(footprints allowed)
		)
		(placement
			(enabled no)
			(sheetname "")
		)
		(fill
			(thermal_gap 0.5)
			(thermal_bridge_width 0.5)
			(island_removal_mode 0)
		)
		(polygon
			(pts
				(xy 315.120528 -141.775942) (xy 315.120528 -143.579342) (xy 315.679328 -143.579342) (xy 315.679328 -141.775942)
			)
		)
	)
	(zone
		(layer "In1.Cu")
		(hatch none 0.5)
		(connect_pads
			(clearance 0)
		)
		(min_thickness 0.25)
		(keepout
			(tracks not_allowed)
			(vias allowed)
			(pads allowed)
			(copperpour not_allowed)
			(footprints allowed)
		)
		(placement
			(enabled no)
			(sheetname "")
		)
		(fill
			(thermal_gap 0.5)
			(thermal_bridge_width 0.5)
			(island_removal_mode 0)
		)
		(polygon
			(pts
				(xy 244.570504 -151.377142) (xy 244.570504 -153.180542) (xy 245.129304 -153.180542) (xy 245.129304 -151.377142)
			)
		)
	)
	(zone
		(layer "In1.Cu")
		(hatch none 0.5)
		(connect_pads
			(clearance 0)
		)
		(min_thickness 0.25)
		(keepout
			(tracks not_allowed)
			(vias allowed)
			(pads allowed)
			(copperpour not_allowed)
			(footprints allowed)
		)
		(placement
			(enabled no)
			(sheetname "")
		)
		(fill
			(thermal_gap 0.5)
			(thermal_bridge_width 0.5)
			(island_removal_mode 0)
		)
		(polygon
			(pts
				(xy 54.920134 -19.121882) (xy 54.920134 -20.925282) (xy 55.478934 -20.925282) (xy 55.478934 -19.121882)
			)
		)
	)
	(zone
		(layer "In1.Cu")
		(hatch none 0.5)
		(connect_pads
			(clearance 0)
		)
		(min_thickness 0.25)
		(keepout
			(tracks not_allowed)
			(vias allowed)
			(pads allowed)
			(copperpour not_allowed)
			(footprints allowed)
		)
		(placement
			(enabled no)
			(sheetname "")
		)
		(fill
			(thermal_gap 0.5)
			(thermal_bridge_width 0.5)
			(island_removal_mode 0)
		)
		(polygon
			(pts
				(xy 108.469938 0.080518) (xy 108.469938 -1.722882) (xy 109.028738 -1.722882) (xy 109.028738 0.080518)
			)
		)
	)
	(zone
		(layer "In1.Cu")
		(hatch none 0.5)
		(connect_pads
			(clearance 0)
		)
		(min_thickness 0.25)
		(keepout
			(tracks not_allowed)
			(vias allowed)
			(pads allowed)
			(copperpour not_allowed)
			(footprints allowed)
		)
		(placement
			(enabled no)
			(sheetname "")
		)
		(fill
			(thermal_gap 0.5)
			(thermal_bridge_width 0.5)
			(island_removal_mode 0)
		)
		(polygon
			(pts
				(xy 50.669952 -136.774682) (xy 50.669952 -138.578082) (xy 51.228752 -138.578082) (xy 51.228752 -136.774682)
			)
		)
	)
	(zone
		(layer "In1.Cu")
		(hatch none 0.5)
		(connect_pads
			(clearance 0)
		)
		(min_thickness 0.25)
		(keepout
			(tracks not_allowed)
			(vias allowed)
			(pads allowed)
			(copperpour not_allowed)
			(footprints allowed)
		)
		(placement
			(enabled no)
			(sheetname "")
		)
		(fill
			(thermal_gap 0.5)
			(thermal_bridge_width 0.5)
			(island_removal_mode 0)
		)
		(polygon
			(pts
				(xy 51.52009 -141.775942) (xy 51.52009 -143.579342) (xy 52.07889 -143.579342) (xy 52.07889 -141.775942)
			)
		)
	)
	(zone
		(layer "In1.Cu")
		(hatch none 0.5)
		(connect_pads
			(clearance 0)
		)
		(min_thickness 0.25)
		(keepout
			(tracks not_allowed)
			(vias allowed)
			(pads allowed)
			(copperpour not_allowed)
			(footprints allowed)
		)
		(placement
			(enabled no)
			(sheetname "")
		)
		(fill
			(thermal_gap 0.5)
			(thermal_bridge_width 0.5)
			(island_removal_mode 0)
		)
		(polygon
			(pts
				(xy 275.170392 -155.977082) (xy 275.170392 -157.780482) (xy 275.729192 -157.780482) (xy 275.729192 -155.977082)
			)
		)
	)
	(zone
		(layer "In1.Cu")
		(hatch none 0.5)
		(connect_pads
			(clearance 0)
		)
		(min_thickness 0.25)
		(keepout
			(tracks not_allowed)
			(vias allowed)
			(pads allowed)
			(copperpour not_allowed)
			(footprints allowed)
		)
		(placement
			(enabled no)
			(sheetname "")
		)
		(fill
			(thermal_gap 0.5)
			(thermal_bridge_width 0.5)
			(island_removal_mode 0)
		)
		(polygon
			(pts
				(xy 208.87055 -141.775942) (xy 208.87055 -143.579342) (xy 209.42935 -143.579342) (xy 209.42935 -141.775942)
			)
		)
	)
	(zone
		(layer "In1.Cu")
		(hatch none 0.5)
		(connect_pads
			(clearance 0)
		)
		(min_thickness 0.25)
		(keepout
			(tracks not_allowed)
			(vias allowed)
			(pads allowed)
			(copperpour not_allowed)
			(footprints allowed)
		)
		(placement
			(enabled no)
			(sheetname "")
		)
		(fill
			(thermal_gap 0.5)
			(thermal_bridge_width 0.5)
			(island_removal_mode 0)
		)
		(polygon
			(pts
				(xy 202.9206 -136.774682) (xy 202.9206 -138.578082) (xy 203.4794 -138.578082) (xy 203.4794 -136.774682)
			)
		)
	)
	(zone
		(layer "In1.Cu")
		(hatch none 0.5)
		(connect_pads
			(clearance 0)
		)
		(min_thickness 0.25)
		(keepout
			(tracks not_allowed)
			(vias allowed)
			(pads allowed)
			(copperpour not_allowed)
			(footprints allowed)
		)
		(placement
			(enabled no)
			(sheetname "")
		)
		(fill
			(thermal_gap 0.5)
			(thermal_bridge_width 0.5)
			(island_removal_mode 0)
		)
		(polygon
			(pts
				(xy 287.070546 -132.174742) (xy 287.070546 -133.978142) (xy 287.629346 -133.978142) (xy 287.629346 -132.174742)
			)
		)
	)
	(zone
		(layer "In1.Cu")
		(hatch none 0.5)
		(connect_pads
			(clearance 0)
		)
		(min_thickness 0.25)
		(keepout
			(tracks not_allowed)
			(vias allowed)
			(pads allowed)
			(copperpour not_allowed)
			(footprints allowed)
		)
		(placement
			(enabled no)
			(sheetname "")
		)
		(fill
			(thermal_gap 0.5)
			(thermal_bridge_width 0.5)
			(island_removal_mode 0)
		)
		(polygon
			(pts
				(xy 236.920532 -151.377142) (xy 236.920532 -153.180542) (xy 237.479332 -153.180542) (xy 237.479332 -151.377142)
			)
		)
	)
	(zone
		(layer "In1.Cu")
		(hatch none 0.5)
		(connect_pads
			(clearance 0)
		)
		(min_thickness 0.25)
		(keepout
			(tracks not_allowed)
			(vias allowed)
			(pads allowed)
			(copperpour not_allowed)
			(footprints allowed)
		)
		(placement
			(enabled no)
			(sheetname "")
		)
		(fill
			(thermal_gap 0.5)
			(thermal_bridge_width 0.5)
			(island_removal_mode 0)
		)
		(polygon
			(pts
				(xy 35.370008 -14.521942) (xy 35.370008 -16.325342) (xy 35.928808 -16.325342) (xy 35.928808 -14.521942)
			)
		)
	)
	(zone
		(layer "In1.Cu")
		(hatch none 0.5)
		(connect_pads
			(clearance 0)
		)
		(min_thickness 0.25)
		(keepout
			(tracks not_allowed)
			(vias allowed)
			(pads allowed)
			(copperpour not_allowed)
			(footprints allowed)
		)
		(placement
			(enabled no)
			(sheetname "")
		)
		(fill
			(thermal_gap 0.5)
			(thermal_bridge_width 0.5)
			(island_removal_mode 0)
		)
		(polygon
			(pts
				(xy 74.470006 -14.521942) (xy 74.470006 -16.325342) (xy 75.028806 -16.325342) (xy 75.028806 -14.521942)
			)
		)
	)
	(zone
		(layer "In1.Cu")
		(hatch none 0.5)
		(connect_pads
			(clearance 0)
		)
		(min_thickness 0.25)
		(keepout
			(tracks not_allowed)
			(vias allowed)
			(pads allowed)
			(copperpour not_allowed)
			(footprints allowed)
		)
		(placement
			(enabled no)
			(sheetname "")
		)
		(fill
			(thermal_gap 0.5)
			(thermal_bridge_width 0.5)
			(island_removal_mode 0)
		)
		(polygon
			(pts
				(xy 101.670104 -155.977082) (xy 101.670104 -157.780482) (xy 102.228904 -157.780482) (xy 102.228904 -155.977082)
			)
		)
	)
	(zone
		(layer "In1.Cu")
		(hatch none 0.5)
		(connect_pads
			(clearance 0)
		)
		(min_thickness 0.25)
		(keepout
			(tracks not_allowed)
			(vias allowed)
			(pads allowed)
			(copperpour not_allowed)
			(footprints allowed)
		)
		(placement
			(enabled no)
			(sheetname "")
		)
		(fill
			(thermal_gap 0.5)
			(thermal_bridge_width 0.5)
			(island_removal_mode 0)
		)
		(polygon
			(pts
				(xy 54.069996 -14.521942) (xy 54.069996 -16.325342) (xy 54.628796 -16.325342) (xy 54.628796 -14.521942)
			)
		)
	)
	(zone
		(layer "In1.Cu")
		(hatch none 0.5)
		(connect_pads
			(clearance 0)
		)
		(min_thickness 0.25)
		(keepout
			(tracks not_allowed)
			(vias allowed)
			(pads allowed)
			(copperpour not_allowed)
			(footprints allowed)
		)
		(placement
			(enabled no)
			(sheetname "")
		)
		(fill
			(thermal_gap 0.5)
			(thermal_bridge_width 0.5)
			(island_removal_mode 0)
		)
		(polygon
			(pts
				(xy 267.52042 -19.121882) (xy 268.07922 -19.121882) (xy 268.07922 -20.925282) (xy 267.52042 -20.925282)
			)
		)
	)
	(zone
		(layer "In1.Cu")
		(hatch none 0.5)
		(connect_pads
			(clearance 0)
		)
		(min_thickness 0.25)
		(keepout
			(tracks not_allowed)
			(vias allowed)
			(pads allowed)
			(copperpour not_allowed)
			(footprints allowed)
		)
		(placement
			(enabled no)
			(sheetname "")
		)
		(fill
			(thermal_gap 0.5)
			(thermal_bridge_width 0.5)
			(island_removal_mode 0)
		)
		(polygon
			(pts
				(xy 281.120342 -4.920742) (xy 281.120342 -6.724142) (xy 281.679142 -6.724142) (xy 281.679142 -4.920742)
			)
		)
	)
	(zone
		(layer "In1.Cu")
		(hatch none 0.5)
		(connect_pads
			(clearance 0)
		)
		(min_thickness 0.25)
		(keepout
			(tracks not_allowed)
			(vias allowed)
			(pads allowed)
			(copperpour not_allowed)
			(footprints allowed)
		)
		(placement
			(enabled no)
			(sheetname "")
		)
		(fill
			(thermal_gap 0.5)
			(thermal_bridge_width 0.5)
			(island_removal_mode 0)
		)
		(polygon
			(pts
				(xy 430.621186 -3.789172) (xy 431.929286 -3.789172) (xy 431.929286 -4.982972) (xy 430.621186 -4.982972)
			)
		)
	)
	(zone
		(layer "In1.Cu")
		(hatch none 0.5)
		(connect_pads
			(clearance 0)
		)
		(min_thickness 0.25)
		(keepout
			(tracks not_allowed)
			(vias allowed)
			(pads allowed)
			(copperpour not_allowed)
			(footprints allowed)
		)
		(placement
			(enabled no)
			(sheetname "")
		)
		(fill
			(thermal_gap 0.5)
			(thermal_bridge_width 0.5)
			(island_removal_mode 0)
		)
		(polygon
			(pts
				(xy 123.769882 -4.920742) (xy 123.769882 -6.724142) (xy 124.328682 -6.724142) (xy 124.328682 -4.920742)
			)
		)
	)
	(zone
		(layer "In1.Cu")
		(hatch none 0.5)
		(connect_pads
			(clearance 0)
		)
		(min_thickness 0.25)
		(keepout
			(tracks not_allowed)
			(vias allowed)
			(pads allowed)
			(copperpour not_allowed)
			(footprints allowed)
		)
		(placement
			(enabled no)
			(sheetname "")
		)
		(fill
			(thermal_gap 0.5)
			(thermal_bridge_width 0.5)
			(island_removal_mode 0)
		)
		(polygon
			(pts
				(xy 413.819086 -3.789172) (xy 415.127186 -3.789172) (xy 415.127186 -4.982972) (xy 413.819086 -4.982972)
			)
		)
	)
	(zone
		(layer "In1.Cu")
		(hatch none 0.5)
		(connect_pads
			(clearance 0)
		)
		(min_thickness 0.25)
		(keepout
			(tracks not_allowed)
			(vias allowed)
			(pads allowed)
			(copperpour not_allowed)
			(footprints allowed)
		)
		(placement
			(enabled no)
			(sheetname "")
		)
		(fill
			(thermal_gap 0.5)
			(thermal_bridge_width 0.5)
			(island_removal_mode 0)
		)
		(polygon
			(pts
				(xy 195.270374 0.080518) (xy 195.270374 -1.722882) (xy 195.829174 -1.722882) (xy 195.829174 0.080518)
			)
		)
	)
	(zone
		(layer "In1.Cu")
		(hatch none 0.5)
		(connect_pads
			(clearance 0)
		)
		(min_thickness 0.25)
		(keepout
			(tracks not_allowed)
			(vias allowed)
			(pads allowed)
			(copperpour not_allowed)
			(footprints allowed)
		)
		(placement
			(enabled no)
			(sheetname "")
		)
		(fill
			(thermal_gap 0.5)
			(thermal_bridge_width 0.5)
			(island_removal_mode 0)
		)
		(polygon
			(pts
				(xy 145.02003 -136.774682) (xy 145.02003 -138.578082) (xy 145.57883 -138.578082) (xy 145.57883 -136.774682)
			)
		)
	)
	(zone
		(layer "In1.Cu")
		(hatch none 0.5)
		(connect_pads
			(clearance 0)
		)
		(min_thickness 0.25)
		(keepout
			(tracks not_allowed)
			(vias allowed)
			(pads allowed)
			(copperpour not_allowed)
			(footprints allowed)
		)
		(placement
			(enabled no)
			(sheetname "")
		)
		(fill
			(thermal_gap 0.5)
			(thermal_bridge_width 0.5)
			(island_removal_mode 0)
		)
		(polygon
			(pts
				(xy 201.220578 -9.520682) (xy 201.220578 -11.324082) (xy 201.779378 -11.324082) (xy 201.779378 -9.520682)
			)
		)
	)
	(zone
		(layer "In1.Cu")
		(hatch none 0.5)
		(connect_pads
			(clearance 0)
		)
		(min_thickness 0.25)
		(keepout
			(tracks not_allowed)
			(vias allowed)
			(pads allowed)
			(copperpour not_allowed)
			(footprints allowed)
		)
		(placement
			(enabled no)
			(sheetname "")
		)
		(fill
			(thermal_gap 0.5)
			(thermal_bridge_width 0.5)
			(island_removal_mode 0)
		)
		(polygon
			(pts
				(xy 252.220476 -151.377142) (xy 252.220476 -153.180542) (xy 252.779276 -153.180542) (xy 252.779276 -151.377142)
			)
		)
	)
	(zone
		(layer "In1.Cu")
		(hatch none 0.5)
		(connect_pads
			(clearance 0)
		)
		(min_thickness 0.25)
		(keepout
			(tracks not_allowed)
			(vias allowed)
			(pads allowed)
			(copperpour not_allowed)
			(footprints allowed)
		)
		(placement
			(enabled no)
			(sheetname "")
		)
		(fill
			(thermal_gap 0.5)
			(thermal_bridge_width 0.5)
			(island_removal_mode 0)
		)
		(polygon
			(pts
				(xy 146.720052 -19.121882) (xy 146.720052 -20.925282) (xy 147.278852 -20.925282) (xy 147.278852 -19.121882)
			)
		)
	)
	(zone
		(layer "In1.Cu")
		(hatch none 0.5)
		(connect_pads
			(clearance 0)
		)
		(min_thickness 0.25)
		(keepout
			(tracks not_allowed)
			(vias allowed)
			(pads allowed)
			(copperpour not_allowed)
			(footprints allowed)
		)
		(placement
			(enabled no)
			(sheetname "")
		)
		(fill
			(thermal_gap 0.5)
			(thermal_bridge_width 0.5)
			(island_removal_mode 0)
		)
		(polygon
			(pts
				(xy 60.870084 -4.920742) (xy 60.870084 -6.724142) (xy 61.428884 -6.724142) (xy 61.428884 -4.920742)
			)
		)
	)
	(zone
		(layer "In1.Cu")
		(hatch none 0.5)
		(connect_pads
			(clearance 0)
		)
		(min_thickness 0.25)
		(keepout
			(tracks not_allowed)
			(vias allowed)
			(pads allowed)
			(copperpour not_allowed)
			(footprints allowed)
		)
		(placement
			(enabled no)
			(sheetname "")
		)
		(fill
			(thermal_gap 0.5)
			(thermal_bridge_width 0.5)
			(island_removal_mode 0)
		)
		(polygon
			(pts
				(xy 233.520488 -151.377142) (xy 233.520488 -153.180542) (xy 234.079288 -153.180542) (xy 234.079288 -151.377142)
			)
		)
	)
	(zone
		(layer "In1.Cu")
		(hatch none 0.5)
		(connect_pads
			(clearance 0)
		)
		(min_thickness 0.25)
		(keepout
			(tracks not_allowed)
			(vias allowed)
			(pads allowed)
			(copperpour not_allowed)
			(footprints allowed)
		)
		(placement
			(enabled no)
			(sheetname "")
		)
		(fill
			(thermal_gap 0.5)
			(thermal_bridge_width 0.5)
			(island_removal_mode 0)
		)
		(polygon
			(pts
				(xy 253.070614 0.080518) (xy 253.070614 -1.722882) (xy 253.629414 -1.722882) (xy 253.629414 0.080518)
			)
		)
	)
	(zone
		(layer "In1.Cu")
		(hatch none 0.5)
		(connect_pads
			(clearance 0)
		)
		(min_thickness 0.25)
		(keepout
			(tracks not_allowed)
			(vias allowed)
			(pads allowed)
			(copperpour not_allowed)
			(footprints allowed)
		)
		(placement
			(enabled no)
			(sheetname "")
		)
		(fill
			(thermal_gap 0.5)
			(thermal_bridge_width 0.5)
			(island_removal_mode 0)
		)
		(polygon
			(pts
				(xy 62.570106 4.680458) (xy 62.570106 2.877058) (xy 63.128906 2.877058) (xy 63.128906 4.680458)
			)
		)
	)
	(zone
		(layer "In1.Cu")
		(hatch none 0.5)
		(connect_pads
			(clearance 0)
		)
		(min_thickness 0.25)
		(keepout
			(tracks not_allowed)
			(vias allowed)
			(pads allowed)
			(copperpour not_allowed)
			(footprints allowed)
		)
		(placement
			(enabled no)
			(sheetname "")
		)
		(fill
			(thermal_gap 0.5)
			(thermal_bridge_width 0.5)
			(island_removal_mode 0)
		)
		(polygon
			(pts
				(xy 30.269942 -136.774682) (xy 30.269942 -138.578082) (xy 30.828742 -138.578082) (xy 30.828742 -136.774682)
			)
		)
	)
	(zone
		(layer "In1.Cu")
		(hatch none 0.5)
		(connect_pads
			(clearance 0)
		)
		(min_thickness 0.25)
		(keepout
			(tracks not_allowed)
			(vias allowed)
			(pads allowed)
			(copperpour not_allowed)
			(footprints allowed)
		)
		(placement
			(enabled no)
			(sheetname "")
		)
		(fill
			(thermal_gap 0.5)
			(thermal_bridge_width 0.5)
			(island_removal_mode 0)
		)
		(polygon
			(pts
				(xy 287.070546 -151.377142) (xy 287.070546 -153.180542) (xy 287.629346 -153.180542) (xy 287.629346 -151.377142)
			)
		)
	)
	(zone
		(layer "In1.Cu")
		(hatch none 0.5)
		(connect_pads
			(clearance 0)
		)
		(min_thickness 0.25)
		(keepout
			(tracks not_allowed)
			(vias allowed)
			(pads allowed)
			(copperpour not_allowed)
			(footprints allowed)
		)
		(placement
			(enabled no)
			(sheetname "")
		)
		(fill
			(thermal_gap 0.5)
			(thermal_bridge_width 0.5)
			(island_removal_mode 0)
		)
		(polygon
			(pts
				(xy 283.670502 -132.174742) (xy 283.670502 -133.978142) (xy 284.229302 -133.978142) (xy 284.229302 -132.174742)
			)
		)
	)
	(zone
		(layer "In1.Cu")
		(hatch none 0.5)
		(connect_pads
			(clearance 0)
		)
		(min_thickness 0.25)
		(keepout
			(tracks not_allowed)
			(vias allowed)
			(pads allowed)
			(copperpour not_allowed)
			(footprints allowed)
		)
		(placement
			(enabled no)
			(sheetname "")
		)
		(fill
			(thermal_gap 0.5)
			(thermal_bridge_width 0.5)
			(island_removal_mode 0)
		)
		(polygon
			(pts
				(xy 240.320576 -155.977082) (xy 240.320576 -157.780482) (xy 240.879376 -157.780482) (xy 240.879376 -155.977082)
			)
		)
	)
	(zone
		(layer "In1.Cu")
		(hatch none 0.5)
		(connect_pads
			(clearance 0)
		)
		(min_thickness 0.25)
		(keepout
			(tracks not_allowed)
			(vias allowed)
			(pads allowed)
			(copperpour not_allowed)
			(footprints allowed)
		)
		(placement
			(enabled no)
			(sheetname "")
		)
		(fill
			(thermal_gap 0.5)
			(thermal_bridge_width 0.5)
			(island_removal_mode 0)
		)
		(polygon
			(pts
				(xy 124.62002 0.080518) (xy 124.62002 -1.722882) (xy 125.17882 -1.722882) (xy 125.17882 0.080518)
			)
		)
	)
	(zone
		(layer "In1.Cu")
		(hatch none 0.5)
		(connect_pads
			(clearance 0)
		)
		(min_thickness 0.25)
		(keepout
			(tracks not_allowed)
			(vias allowed)
			(pads allowed)
			(copperpour not_allowed)
			(footprints allowed)
		)
		(placement
			(enabled no)
			(sheetname "")
		)
		(fill
			(thermal_gap 0.5)
			(thermal_bridge_width 0.5)
			(island_removal_mode 0)
		)
		(polygon
			(pts
				(xy 213.970362 0.080518) (xy 213.970362 -1.722882) (xy 214.529162 -1.722882) (xy 214.529162 0.080518)
			)
		)
	)
	(zone
		(layer "In1.Cu")
		(hatch none 0.5)
		(connect_pads
			(clearance 0)
		)
		(min_thickness 0.25)
		(keepout
			(tracks not_allowed)
			(vias allowed)
			(pads allowed)
			(copperpour not_allowed)
			(footprints allowed)
		)
		(placement
			(enabled no)
			(sheetname "")
		)
		(fill
			(thermal_gap 0.5)
			(thermal_bridge_width 0.5)
			(island_removal_mode 0)
		)
		(polygon
			(pts
				(xy 283.670502 -136.774682) (xy 283.670502 -138.578082) (xy 284.229302 -138.578082) (xy 284.229302 -136.774682)
			)
		)
	)
	(zone
		(layer "In1.Cu")
		(hatch none 0.5)
		(connect_pads
			(clearance 0)
		)
		(min_thickness 0.25)
		(keepout
			(tracks not_allowed)
			(vias allowed)
			(pads allowed)
			(copperpour not_allowed)
			(footprints allowed)
		)
		(placement
			(enabled no)
			(sheetname "")
		)
		(fill
			(thermal_gap 0.5)
			(thermal_bridge_width 0.5)
			(island_removal_mode 0)
		)
		(polygon
			(pts
				(xy 441.022486 -7.192772) (xy 442.330586 -7.192772) (xy 442.330586 -8.386572) (xy 441.022486 -8.386572)
			)
		)
	)
	(zone
		(layer "In1.Cu")
		(hatch none 0.5)
		(connect_pads
			(clearance 0)
		)
		(min_thickness 0.25)
		(keepout
			(tracks not_allowed)
			(vias allowed)
			(pads allowed)
			(copperpour not_allowed)
			(footprints allowed)
		)
		(placement
			(enabled no)
			(sheetname "")
		)
		(fill
			(thermal_gap 0.5)
			(thermal_bridge_width 0.5)
			(island_removal_mode 0)
		)
		(polygon
			(pts
				(xy 293.87038 0.080518) (xy 293.87038 -1.722882) (xy 294.42918 -1.722882) (xy 294.42918 0.080518)
			)
		)
	)
	(zone
		(layer "In1.Cu")
		(hatch none 0.5)
		(connect_pads
			(clearance 0)
		)
		(min_thickness 0.25)
		(keepout
			(tracks not_allowed)
			(vias allowed)
			(pads allowed)
			(copperpour not_allowed)
			(footprints allowed)
		)
		(placement
			(enabled no)
			(sheetname "")
		)
		(fill
			(thermal_gap 0.5)
			(thermal_bridge_width 0.5)
			(island_removal_mode 0)
		)
		(polygon
			(pts
				(xy 247.970548 -19.121882) (xy 247.970548 -20.925282) (xy 248.529348 -20.925282) (xy 248.529348 -19.121882)
			)
		)
	)
	(zone
		(layer "In1.Cu")
		(hatch none 0.5)
		(connect_pads
			(clearance 0)
		)
		(min_thickness 0.25)
		(keepout
			(tracks not_allowed)
			(vias allowed)
			(pads allowed)
			(copperpour not_allowed)
			(footprints allowed)
		)
		(placement
			(enabled no)
			(sheetname "")
		)
		(fill
			(thermal_gap 0.5)
			(thermal_bridge_width 0.5)
			(island_removal_mode 0)
		)
		(polygon
			(pts
				(xy 252.220476 -136.774682) (xy 252.220476 -138.578082) (xy 252.779276 -138.578082) (xy 252.779276 -136.774682)
			)
		)
	)
	(zone
		(layer "In1.Cu")
		(hatch none 0.5)
		(connect_pads
			(clearance 0)
		)
		(min_thickness 0.25)
		(keepout
			(tracks not_allowed)
			(vias allowed)
			(pads allowed)
			(copperpour not_allowed)
			(footprints allowed)
		)
		(placement
			(enabled no)
			(sheetname "")
		)
		(fill
			(thermal_gap 0.5)
			(thermal_bridge_width 0.5)
			(island_removal_mode 0)
		)
		(polygon
			(pts
				(xy 46.420024 4.680458) (xy 46.420024 2.877058) (xy 46.978824 2.877058) (xy 46.978824 4.680458)
			)
		)
	)
	(zone
		(layer "In1.Cu")
		(hatch none 0.5)
		(connect_pads
			(clearance 0)
		)
		(min_thickness 0.25)
		(keepout
			(tracks not_allowed)
			(vias allowed)
			(pads allowed)
			(copperpour not_allowed)
			(footprints allowed)
		)
		(placement
			(enabled no)
			(sheetname "")
		)
		(fill
			(thermal_gap 0.5)
			(thermal_bridge_width 0.5)
			(island_removal_mode 0)
		)
		(polygon
			(pts
				(xy 79.570072 -132.174742) (xy 79.570072 -133.978142) (xy 80.128872 -133.978142) (xy 80.128872 -132.174742)
			)
		)
	)
	(zone
		(layer "In1.Cu")
		(hatch none 0.5)
		(connect_pads
			(clearance 0)
		)
		(min_thickness 0.25)
		(keepout
			(tracks not_allowed)
			(vias allowed)
			(pads allowed)
			(copperpour not_allowed)
			(footprints allowed)
		)
		(placement
			(enabled no)
			(sheetname "")
		)
		(fill
			(thermal_gap 0.5)
			(thermal_bridge_width 0.5)
			(island_removal_mode 0)
		)
		(polygon
			(pts
				(xy 310.870346 -14.521942) (xy 310.870346 -16.325342) (xy 311.429146 -16.325342) (xy 311.429146 -14.521942)
			)
		)
	)
	(zone
		(layer "In1.Cu")
		(hatch none 0.5)
		(connect_pads
			(clearance 0)
		)
		(min_thickness 0.25)
		(keepout
			(tracks not_allowed)
			(vias allowed)
			(pads allowed)
			(copperpour not_allowed)
			(footprints allowed)
		)
		(placement
			(enabled no)
			(sheetname "")
		)
		(fill
			(thermal_gap 0.5)
			(thermal_bridge_width 0.5)
			(island_removal_mode 0)
		)
		(polygon
			(pts
				(xy 311.720484 -14.521942) (xy 311.720484 -16.325342) (xy 312.279284 -16.325342) (xy 312.279284 -14.521942)
			)
		)
	)
	(zone
		(layer "In1.Cu")
		(hatch none 0.5)
		(connect_pads
			(clearance 0)
		)
		(min_thickness 0.25)
		(keepout
			(tracks not_allowed)
			(vias allowed)
			(pads allowed)
			(copperpour not_allowed)
			(footprints allowed)
		)
		(placement
			(enabled no)
			(sheetname "")
		)
		(fill
			(thermal_gap 0.5)
			(thermal_bridge_width 0.5)
			(island_removal_mode 0)
		)
		(polygon
			(pts
				(xy 110.16996 -19.121882) (xy 110.16996 -20.925282) (xy 110.72876 -20.925282) (xy 110.72876 -19.121882)
			)
		)
	)
	(zone
		(layer "In1.Cu")
		(hatch none 0.5)
		(connect_pads
			(clearance 0)
		)
		(min_thickness 0.25)
		(keepout
			(tracks not_allowed)
			(vias allowed)
			(pads allowed)
			(copperpour not_allowed)
			(footprints allowed)
		)
		(placement
			(enabled no)
			(sheetname "")
		)
		(fill
			(thermal_gap 0.5)
			(thermal_bridge_width 0.5)
			(island_removal_mode 0)
		)
		(polygon
			(pts
				(xy 56.620156 0.080518) (xy 56.620156 -1.722882) (xy 57.178956 -1.722882) (xy 57.178956 0.080518)
			)
		)
	)
	(zone
		(layer "In1.Cu")
		(hatch none 0.5)
		(connect_pads
			(clearance 0)
		)
		(min_thickness 0.25)
		(keepout
			(tracks not_allowed)
			(vias allowed)
			(pads allowed)
			(copperpour not_allowed)
			(footprints allowed)
		)
		(placement
			(enabled no)
			(sheetname "")
		)
		(fill
			(thermal_gap 0.5)
			(thermal_bridge_width 0.5)
			(island_removal_mode 0)
		)
		(polygon
			(pts
				(xy 60.019946 -9.520682) (xy 60.019946 -11.324082) (xy 60.578746 -11.324082) (xy 60.578746 -9.520682)
			)
		)
	)
	(zone
		(layer "In1.Cu")
		(hatch none 0.5)
		(connect_pads
			(clearance 0)
		)
		(min_thickness 0.25)
		(keepout
			(tracks not_allowed)
			(vias allowed)
			(pads allowed)
			(copperpour not_allowed)
			(footprints allowed)
		)
		(placement
			(enabled no)
			(sheetname "")
		)
		(fill
			(thermal_gap 0.5)
			(thermal_bridge_width 0.5)
			(island_removal_mode 0)
		)
		(polygon
			(pts
				(xy 225.020378 -9.520682) (xy 225.020378 -11.324082) (xy 225.579178 -11.324082) (xy 225.579178 -9.520682)
			)
		)
	)
	(zone
		(layer "In1.Cu")
		(hatch none 0.5)
		(connect_pads
			(clearance 0)
		)
		(min_thickness 0.25)
		(keepout
			(tracks not_allowed)
			(vias allowed)
			(pads allowed)
			(copperpour not_allowed)
			(footprints allowed)
		)
		(placement
			(enabled no)
			(sheetname "")
		)
		(fill
			(thermal_gap 0.5)
			(thermal_bridge_width 0.5)
			(island_removal_mode 0)
		)
		(polygon
			(pts
				(xy 111.020098 -14.521942) (xy 111.020098 -16.325342) (xy 111.578898 -16.325342) (xy 111.578898 -14.521942)
			)
		)
	)
	(zone
		(layer "In1.Cu")
		(hatch none 0.5)
		(connect_pads
			(clearance 0)
		)
		(min_thickness 0.25)
		(keepout
			(tracks not_allowed)
			(vias allowed)
			(pads allowed)
			(copperpour not_allowed)
			(footprints allowed)
		)
		(placement
			(enabled no)
			(sheetname "")
		)
		(fill
			(thermal_gap 0.5)
			(thermal_bridge_width 0.5)
			(island_removal_mode 0)
		)
		(polygon
			(pts
				(xy 68.520056 -151.377142) (xy 68.520056 -153.180542) (xy 69.078856 -153.180542) (xy 69.078856 -151.377142)
			)
		)
	)
	(zone
		(layer "In1.Cu")
		(hatch none 0.5)
		(connect_pads
			(clearance 0)
		)
		(min_thickness 0.25)
		(keepout
			(tracks not_allowed)
			(vias allowed)
			(pads allowed)
			(copperpour not_allowed)
			(footprints allowed)
		)
		(placement
			(enabled no)
			(sheetname "")
		)
		(fill
			(thermal_gap 0.5)
			(thermal_bridge_width 0.5)
			(island_removal_mode 0)
		)
		(polygon
			(pts
				(xy 112.72012 -4.920742) (xy 112.72012 -6.724142) (xy 113.27892 -6.724142) (xy 113.27892 -4.920742)
			)
		)
	)
	(zone
		(layer "In1.Cu")
		(hatch none 0.5)
		(connect_pads
			(clearance 0)
		)
		(min_thickness 0.25)
		(keepout
			(tracks not_allowed)
			(vias allowed)
			(pads allowed)
			(copperpour not_allowed)
			(footprints allowed)
		)
		(placement
			(enabled no)
			(sheetname "")
		)
		(fill
			(thermal_gap 0.5)
			(thermal_bridge_width 0.5)
			(island_removal_mode 0)
		)
		(polygon
			(pts
				(xy 87.220044 -136.774682) (xy 87.220044 -138.578082) (xy 87.778844 -138.578082) (xy 87.778844 -136.774682)
			)
		)
	)
	(zone
		(layer "In1.Cu")
		(hatch none 0.5)
		(connect_pads
			(clearance 0)
		)
		(min_thickness 0.25)
		(keepout
			(tracks not_allowed)
			(vias allowed)
			(pads allowed)
			(copperpour not_allowed)
			(footprints allowed)
		)
		(placement
			(enabled no)
			(sheetname "")
		)
		(fill
			(thermal_gap 0.5)
			(thermal_bridge_width 0.5)
			(island_removal_mode 0)
		)
		(polygon
			(pts
				(xy 289.620452 0.080518) (xy 289.620452 -1.722882) (xy 290.179252 -1.722882) (xy 290.179252 0.080518)
			)
		)
	)
	(zone
		(layer "In1.Cu")
		(hatch none 0.5)
		(connect_pads
			(clearance 0)
		)
		(min_thickness 0.25)
		(keepout
			(tracks not_allowed)
			(vias allowed)
			(pads allowed)
			(copperpour not_allowed)
			(footprints allowed)
		)
		(placement
			(enabled no)
			(sheetname "")
		)
		(fill
			(thermal_gap 0.5)
			(thermal_bridge_width 0.5)
			(island_removal_mode 0)
		)
		(polygon
			(pts
				(xy 293.020496 -19.121882) (xy 293.020496 -20.925282) (xy 293.579296 -20.925282) (xy 293.579296 -19.121882)
			)
		)
	)
	(zone
		(layer "In1.Cu")
		(hatch none 0.5)
		(connect_pads
			(clearance 0)
		)
		(min_thickness 0.25)
		(keepout
			(tracks not_allowed)
			(vias allowed)
			(pads allowed)
			(copperpour not_allowed)
			(footprints allowed)
		)
		(placement
			(enabled no)
			(sheetname "")
		)
		(fill
			(thermal_gap 0.5)
			(thermal_bridge_width 0.5)
			(island_removal_mode 0)
		)
		(polygon
			(pts
				(xy 210.570572 -146.375882) (xy 210.570572 -148.179282) (xy 211.129372 -148.179282) (xy 211.129372 -146.375882)
			)
		)
	)
	(zone
		(layer "In1.Cu")
		(hatch none 0.5)
		(connect_pads
			(clearance 0)
		)
		(min_thickness 0.25)
		(keepout
			(tracks not_allowed)
			(vias allowed)
			(pads allowed)
			(copperpour not_allowed)
			(footprints allowed)
		)
		(placement
			(enabled no)
			(sheetname "")
		)
		(fill
			(thermal_gap 0.5)
			(thermal_bridge_width 0.5)
			(island_removal_mode 0)
		)
		(polygon
			(pts
				(xy 122.070114 -151.377142) (xy 122.070114 -153.180542) (xy 122.628914 -153.180542) (xy 122.628914 -151.377142)
			)
		)
	)
	(zone
		(layer "In1.Cu")
		(hatch none 0.5)
		(connect_pads
			(clearance 0)
		)
		(min_thickness 0.25)
		(keepout
			(tracks not_allowed)
			(vias allowed)
			(pads allowed)
			(copperpour not_allowed)
			(footprints allowed)
		)
		(placement
			(enabled no)
			(sheetname "")
		)
		(fill
			(thermal_gap 0.5)
			(thermal_bridge_width 0.5)
			(island_removal_mode 0)
		)
		(polygon
			(pts
				(xy 256.470404 -4.920742) (xy 256.470404 -6.724142) (xy 257.029204 -6.724142) (xy 257.029204 -4.920742)
			)
		)
	)
	(zone
		(layer "In1.Cu")
		(hatch none 0.5)
		(connect_pads
			(clearance 0)
		)
		(min_thickness 0.25)
		(keepout
			(tracks not_allowed)
			(vias allowed)
			(pads allowed)
			(copperpour not_allowed)
			(footprints allowed)
		)
		(placement
			(enabled no)
			(sheetname "")
		)
		(fill
			(thermal_gap 0.5)
			(thermal_bridge_width 0.5)
			(island_removal_mode 0)
		)
		(polygon
			(pts
				(xy 295.570402 -19.121882) (xy 295.570402 -20.925282) (xy 296.129202 -20.925282) (xy 296.129202 -19.121882)
			)
		)
	)
	(zone
		(layer "In1.Cu")
		(hatch none 0.5)
		(connect_pads
			(clearance 0)
		)
		(min_thickness 0.25)
		(keepout
			(tracks not_allowed)
			(vias allowed)
			(pads allowed)
			(copperpour not_allowed)
			(footprints allowed)
		)
		(placement
			(enabled no)
			(sheetname "")
		)
		(fill
			(thermal_gap 0.5)
			(thermal_bridge_width 0.5)
			(island_removal_mode 0)
		)
		(polygon
			(pts
				(xy 65.97015 -9.520682) (xy 65.97015 -11.324082) (xy 66.52895 -11.324082) (xy 66.52895 -9.520682)
			)
		)
	)
	(zone
		(layer "In1.Cu")
		(hatch none 0.5)
		(connect_pads
			(clearance 0)
		)
		(min_thickness 0.25)
		(keepout
			(tracks not_allowed)
			(vias allowed)
			(pads allowed)
			(copperpour not_allowed)
			(footprints allowed)
		)
		(placement
			(enabled no)
			(sheetname "")
		)
		(fill
			(thermal_gap 0.5)
			(thermal_bridge_width 0.5)
			(island_removal_mode 0)
		)
		(polygon
			(pts
				(xy 107.620054 -132.174742) (xy 107.620054 -133.978142) (xy 108.178854 -133.978142) (xy 108.178854 -132.174742)
			)
		)
	)
	(zone
		(layer "In1.Cu")
		(hatch none 0.5)
		(connect_pads
			(clearance 0)
		)
		(min_thickness 0.25)
		(keepout
			(tracks not_allowed)
			(vias allowed)
			(pads allowed)
			(copperpour not_allowed)
			(footprints allowed)
		)
		(placement
			(enabled no)
			(sheetname "")
		)
		(fill
			(thermal_gap 0.5)
			(thermal_bridge_width 0.5)
			(island_removal_mode 0)
		)
		(polygon
			(pts
				(xy 225.870516 -141.775942) (xy 225.870516 -143.579342) (xy 226.429316 -143.579342) (xy 226.429316 -141.775942)
			)
		)
	)
	(zone
		(layer "In1.Cu")
		(hatch none 0.5)
		(connect_pads
			(clearance 0)
		)
		(min_thickness 0.25)
		(keepout
			(tracks not_allowed)
			(vias allowed)
			(pads allowed)
			(copperpour not_allowed)
			(footprints allowed)
		)
		(placement
			(enabled no)
			(sheetname "")
		)
		(fill
			(thermal_gap 0.5)
			(thermal_bridge_width 0.5)
			(island_removal_mode 0)
		)
		(polygon
			(pts
				(xy 227.570538 -132.174742) (xy 227.570538 -133.978142) (xy 228.129338 -133.978142) (xy 228.129338 -132.174742)
			)
		)
	)
	(zone
		(layer "In1.Cu")
		(hatch none 0.5)
		(connect_pads
			(clearance 0)
		)
		(min_thickness 0.25)
		(keepout
			(tracks not_allowed)
			(vias allowed)
			(pads allowed)
			(copperpour not_allowed)
			(footprints allowed)
		)
		(placement
			(enabled no)
			(sheetname "")
		)
		(fill
			(thermal_gap 0.5)
			(thermal_bridge_width 0.5)
			(island_removal_mode 0)
		)
		(polygon
			(pts
				(xy 91.469972 -146.375882) (xy 91.469972 -148.179282) (xy 92.028772 -148.179282) (xy 92.028772 -146.375882)
			)
		)
	)
	(zone
		(layer "In1.Cu")
		(hatch none 0.5)
		(connect_pads
			(clearance 0)
		)
		(min_thickness 0.25)
		(keepout
			(tracks not_allowed)
			(vias allowed)
			(pads allowed)
			(copperpour not_allowed)
			(footprints allowed)
		)
		(placement
			(enabled no)
			(sheetname "")
		)
		(fill
			(thermal_gap 0.5)
			(thermal_bridge_width 0.5)
			(island_removal_mode 0)
		)
		(polygon
			(pts
				(xy 50.669952 -9.520682) (xy 50.669952 -11.324082) (xy 51.228752 -11.324082) (xy 51.228752 -9.520682)
			)
		)
	)
	(zone
		(layer "In1.Cu")
		(hatch none 0.5)
		(connect_pads
			(clearance 0)
		)
		(min_thickness 0.25)
		(keepout
			(tracks not_allowed)
			(vias allowed)
			(pads allowed)
			(copperpour not_allowed)
			(footprints allowed)
		)
		(placement
			(enabled no)
			(sheetname "")
		)
		(fill
			(thermal_gap 0.5)
			(thermal_bridge_width 0.5)
			(island_removal_mode 0)
		)
		(polygon
			(pts
				(xy 239.470438 -141.775942) (xy 239.470438 -143.579342) (xy 240.029238 -143.579342) (xy 240.029238 -141.775942)
			)
		)
	)
	(zone
		(layer "In1.Cu")
		(hatch none 0.5)
		(connect_pads
			(clearance 0)
		)
		(min_thickness 0.25)
		(keepout
			(tracks not_allowed)
			(vias allowed)
			(pads allowed)
			(copperpour not_allowed)
			(footprints allowed)
		)
		(placement
			(enabled no)
			(sheetname "")
		)
		(fill
			(thermal_gap 0.5)
			(thermal_bridge_width 0.5)
			(island_removal_mode 0)
		)
		(polygon
			(pts
				(xy 54.069996 0.080518) (xy 54.069996 -1.722882) (xy 54.628796 -1.722882) (xy 54.628796 0.080518)
			)
		)
	)
	(zone
		(layer "In1.Cu")
		(hatch none 0.5)
		(connect_pads
			(clearance 0)
		)
		(min_thickness 0.25)
		(keepout
			(tracks not_allowed)
			(vias allowed)
			(pads allowed)
			(copperpour not_allowed)
			(footprints allowed)
		)
		(placement
			(enabled no)
			(sheetname "")
		)
		(fill
			(thermal_gap 0.5)
			(thermal_bridge_width 0.5)
			(island_removal_mode 0)
		)
		(polygon
			(pts
				(xy 65.120012 -151.377142) (xy 65.120012 -153.180542) (xy 65.678812 -153.180542) (xy 65.678812 -151.377142)
			)
		)
	)
	(zone
		(layer "In1.Cu")
		(hatch none 0.5)
		(connect_pads
			(clearance 0)
		)
		(min_thickness 0.25)
		(keepout
			(tracks not_allowed)
			(vias allowed)
			(pads allowed)
			(copperpour not_allowed)
			(footprints allowed)
		)
		(placement
			(enabled no)
			(sheetname "")
		)
		(fill
			(thermal_gap 0.5)
			(thermal_bridge_width 0.5)
			(island_removal_mode 0)
		)
		(polygon
			(pts
				(xy 236.070394 -9.520682) (xy 236.070394 -11.324082) (xy 236.629194 -11.324082) (xy 236.629194 -9.520682)
			)
		)
	)
	(zone
		(layer "In1.Cu")
		(hatch none 0.5)
		(connect_pads
			(clearance 0)
		)
		(min_thickness 0.25)
		(keepout
			(tracks not_allowed)
			(vias allowed)
			(pads allowed)
			(copperpour not_allowed)
			(footprints allowed)
		)
		(placement
			(enabled no)
			(sheetname "")
		)
		(fill
			(thermal_gap 0.5)
			(thermal_bridge_width 0.5)
			(island_removal_mode 0)
		)
		(polygon
			(pts
				(xy 134.819898 -141.775942) (xy 134.819898 -143.579342) (xy 135.378698 -143.579342) (xy 135.378698 -141.775942)
			)
		)
	)
	(zone
		(layer "In1.Cu")
		(hatch none 0.5)
		(connect_pads
			(clearance 0)
		)
		(min_thickness 0.25)
		(keepout
			(tracks not_allowed)
			(vias allowed)
			(pads allowed)
			(copperpour not_allowed)
			(footprints allowed)
		)
		(placement
			(enabled no)
			(sheetname "")
		)
		(fill
			(thermal_gap 0.5)
			(thermal_bridge_width 0.5)
			(island_removal_mode 0)
		)
		(polygon
			(pts
				(xy 72.769984 -4.920742) (xy 72.769984 -6.724142) (xy 73.328784 -6.724142) (xy 73.328784 -4.920742)
			)
		)
	)
	(zone
		(layer "In1.Cu")
		(hatch none 0.5)
		(connect_pads
			(clearance 0)
		)
		(min_thickness 0.25)
		(keepout
			(tracks not_allowed)
			(vias allowed)
			(pads allowed)
			(copperpour not_allowed)
			(footprints allowed)
		)
		(placement
			(enabled no)
			(sheetname "")
		)
		(fill
			(thermal_gap 0.5)
			(thermal_bridge_width 0.5)
			(island_removal_mode 0)
		)
		(polygon
			(pts
				(xy 285.370524 -141.775942) (xy 285.370524 -143.579342) (xy 285.929324 -143.579342) (xy 285.929324 -141.775942)
			)
		)
	)
	(zone
		(layer "In1.Cu")
		(hatch none 0.5)
		(connect_pads
			(clearance 0)
		)
		(min_thickness 0.25)
		(keepout
			(tracks not_allowed)
			(vias allowed)
			(pads allowed)
			(copperpour not_allowed)
			(footprints allowed)
		)
		(placement
			(enabled no)
			(sheetname "")
		)
		(fill
			(thermal_gap 0.5)
			(thermal_bridge_width 0.5)
			(island_removal_mode 0)
		)
		(polygon
			(pts
				(xy 231.820466 -141.775942) (xy 231.820466 -143.579342) (xy 232.379266 -143.579342) (xy 232.379266 -141.775942)
			)
		)
	)
	(zone
		(layer "In1.Cu")
		(hatch none 0.5)
		(connect_pads
			(clearance 0)
		)
		(min_thickness 0.25)
		(keepout
			(tracks not_allowed)
			(vias allowed)
			(pads allowed)
			(copperpour not_allowed)
			(footprints allowed)
		)
		(placement
			(enabled no)
			(sheetname "")
		)
		(fill
			(thermal_gap 0.5)
			(thermal_bridge_width 0.5)
			(island_removal_mode 0)
		)
		(polygon
			(pts
				(xy 47.270162 -155.977082) (xy 47.270162 -157.780482) (xy 47.828962 -157.780482) (xy 47.828962 -155.977082)
			)
		)
	)
	(zone
		(layer "In1.Cu")
		(hatch none 0.5)
		(connect_pads
			(clearance 0)
		)
		(min_thickness 0.25)
		(keepout
			(tracks not_allowed)
			(vias allowed)
			(pads allowed)
			(copperpour not_allowed)
			(footprints allowed)
		)
		(placement
			(enabled no)
			(sheetname "")
		)
		(fill
			(thermal_gap 0.5)
			(thermal_bridge_width 0.5)
			(island_removal_mode 0)
		)
		(polygon
			(pts
				(xy 130.56997 -146.375882) (xy 130.56997 -148.179282) (xy 131.12877 -148.179282) (xy 131.12877 -146.375882)
			)
		)
	)
	(zone
		(layer "In1.Cu")
		(hatch none 0.5)
		(connect_pads
			(clearance 0)
		)
		(min_thickness 0.25)
		(keepout
			(tracks not_allowed)
			(vias allowed)
			(pads allowed)
			(copperpour not_allowed)
			(footprints allowed)
		)
		(placement
			(enabled no)
			(sheetname "")
		)
		(fill
			(thermal_gap 0.5)
			(thermal_bridge_width 0.5)
			(island_removal_mode 0)
		)
		(polygon
			(pts
				(xy 291.320474 -136.774682) (xy 291.320474 -138.578082) (xy 291.879274 -138.578082) (xy 291.879274 -136.774682)
			)
		)
	)
	(zone
		(layer "In1.Cu")
		(hatch none 0.5)
		(connect_pads
			(clearance 0)
		)
		(min_thickness 0.25)
		(keepout
			(tracks not_allowed)
			(vias allowed)
			(pads allowed)
			(copperpour not_allowed)
			(footprints allowed)
		)
		(placement
			(enabled no)
			(sheetname "")
		)
		(fill
			(thermal_gap 0.5)
			(thermal_bridge_width 0.5)
			(island_removal_mode 0)
		)
		(polygon
			(pts
				(xy 310.020462 -19.121882) (xy 310.020462 -20.925282) (xy 310.579262 -20.925282) (xy 310.579262 -19.121882)
			)
		)
	)
	(zone
		(layer "In1.Cu")
		(hatch none 0.5)
		(connect_pads
			(clearance 0)
		)
		(min_thickness 0.25)
		(keepout
			(tracks not_allowed)
			(vias allowed)
			(pads allowed)
			(copperpour not_allowed)
			(footprints allowed)
		)
		(placement
			(enabled no)
			(sheetname "")
		)
		(fill
			(thermal_gap 0.5)
			(thermal_bridge_width 0.5)
			(island_removal_mode 0)
		)
		(polygon
			(pts
				(xy 242.020852 -146.375882) (xy 242.020852 -148.179282) (xy 242.579652 -148.179282) (xy 242.579652 -146.375882)
			)
		)
	)
	(zone
		(layer "In1.Cu")
		(hatch none 0.5)
		(connect_pads
			(clearance 0)
		)
		(min_thickness 0.25)
		(keepout
			(tracks not_allowed)
			(vias allowed)
			(pads allowed)
			(copperpour not_allowed)
			(footprints allowed)
		)
		(placement
			(enabled no)
			(sheetname "")
		)
		(fill
			(thermal_gap 0.5)
			(thermal_bridge_width 0.5)
			(island_removal_mode 0)
		)
		(polygon
			(pts
				(xy 129.720086 -132.174742) (xy 129.720086 -133.978142) (xy 130.278886 -133.978142) (xy 130.278886 -132.174742)
			)
		)
	)
	(zone
		(layer "In1.Cu")
		(hatch none 0.5)
		(connect_pads
			(clearance 0)
		)
		(min_thickness 0.25)
		(keepout
			(tracks not_allowed)
			(vias allowed)
			(pads allowed)
			(copperpour not_allowed)
			(footprints allowed)
		)
		(placement
			(enabled no)
			(sheetname "")
		)
		(fill
			(thermal_gap 0.5)
			(thermal_bridge_width 0.5)
			(island_removal_mode 0)
		)
		(polygon
			(pts
				(xy 36.220146 -155.977082) (xy 36.220146 -157.780482) (xy 36.778946 -157.780482) (xy 36.778946 -155.977082)
			)
		)
	)
	(zone
		(layer "In1.Cu")
		(hatch none 0.5)
		(connect_pads
			(clearance 0)
		)
		(min_thickness 0.25)
		(keepout
			(tracks not_allowed)
			(vias allowed)
			(pads allowed)
			(copperpour not_allowed)
			(footprints allowed)
		)
		(placement
			(enabled no)
			(sheetname "")
		)
		(fill
			(thermal_gap 0.5)
			(thermal_bridge_width 0.5)
			(island_removal_mode 0)
		)
		(polygon
			(pts
				(xy 196.120512 -132.174742) (xy 196.120512 -133.978142) (xy 196.679312 -133.978142) (xy 196.679312 -132.174742)
			)
		)
	)
	(zone
		(layer "In1.Cu")
		(hatch none 0.5)
		(connect_pads
			(clearance 0)
		)
		(min_thickness 0.25)
		(keepout
			(tracks not_allowed)
			(vias allowed)
			(pads allowed)
			(copperpour not_allowed)
			(footprints allowed)
		)
		(placement
			(enabled no)
			(sheetname "")
		)
		(fill
			(thermal_gap 0.5)
			(thermal_bridge_width 0.5)
			(island_removal_mode 0)
		)
		(polygon
			(pts
				(xy 398.665192 -9.774936) (xy 399.173192 -9.774936) (xy 399.173192 -11.171936) (xy 398.665192 -11.171936)
			)
		)
	)
	(zone
		(layer "In1.Cu")
		(hatch none 0.5)
		(connect_pads
			(clearance 0)
		)
		(min_thickness 0.25)
		(keepout
			(tracks not_allowed)
			(vias allowed)
			(pads allowed)
			(copperpour not_allowed)
			(footprints allowed)
		)
		(placement
			(enabled no)
			(sheetname "")
		)
		(fill
			(thermal_gap 0.5)
			(thermal_bridge_width 0.5)
			(island_removal_mode 0)
		)
		(polygon
			(pts
				(xy 137.370058 -151.377142) (xy 137.370058 -153.180542) (xy 137.928858 -153.180542) (xy 137.928858 -151.377142)
			)
		)
	)
	(zone
		(layer "In1.Cu")
		(hatch none 0.5)
		(connect_pads
			(clearance 0)
		)
		(min_thickness 0.25)
		(keepout
			(tracks not_allowed)
			(vias allowed)
			(pads allowed)
			(copperpour not_allowed)
			(footprints allowed)
		)
		(placement
			(enabled no)
			(sheetname "")
		)
		(fill
			(thermal_gap 0.5)
			(thermal_bridge_width 0.5)
			(island_removal_mode 0)
		)
		(polygon
			(pts
				(xy 366.031018 -3.792982) (xy 367.339118 -3.792982) (xy 367.339118 -4.986782) (xy 366.031018 -4.986782)
			)
		)
	)
	(zone
		(layer "In1.Cu")
		(hatch none 0.5)
		(connect_pads
			(clearance 0)
		)
		(min_thickness 0.25)
		(keepout
			(tracks not_allowed)
			(vias allowed)
			(pads allowed)
			(copperpour not_allowed)
			(footprints allowed)
		)
		(placement
			(enabled no)
			(sheetname "")
		)
		(fill
			(thermal_gap 0.5)
			(thermal_bridge_width 0.5)
			(island_removal_mode 0)
		)
		(polygon
			(pts
				(xy 270.07058 -4.920742) (xy 270.07058 -6.724142) (xy 270.62938 -6.724142) (xy 270.62938 -4.920742)
			)
		)
	)
	(zone
		(layer "In1.Cu")
		(hatch none 0.5)
		(connect_pads
			(clearance 0)
		)
		(min_thickness 0.25)
		(keepout
			(tracks not_allowed)
			(vias allowed)
			(pads allowed)
			(copperpour not_allowed)
			(footprints allowed)
		)
		(placement
			(enabled no)
			(sheetname "")
		)
		(fill
			(thermal_gap 0.5)
			(thermal_bridge_width 0.5)
			(island_removal_mode 0)
		)
		(polygon
			(pts
				(xy 213.120478 -14.521942) (xy 213.120478 -16.325342) (xy 213.679278 -16.325342) (xy 213.679278 -14.521942)
			)
		)
	)
	(zone
		(layer "In1.Cu")
		(hatch none 0.5)
		(connect_pads
			(clearance 0)
		)
		(min_thickness 0.25)
		(keepout
			(tracks not_allowed)
			(vias allowed)
			(pads allowed)
			(copperpour not_allowed)
			(footprints allowed)
		)
		(placement
			(enabled no)
			(sheetname "")
		)
		(fill
			(thermal_gap 0.5)
			(thermal_bridge_width 0.5)
			(island_removal_mode 0)
		)
		(polygon
			(pts
				(xy 303.220374 0.080518) (xy 303.220374 -1.722882) (xy 303.779174 -1.722882) (xy 303.779174 0.080518)
			)
		)
	)
	(zone
		(layers "In1.Cu" "In2.Cu" "In3.Cu" "In4.Cu" "In5.Cu" "In6.Cu" "In7.Cu"
			"In8.Cu" "In9.Cu" "In10.Cu" "In11.Cu" "In12.Cu"
		)
		(hatch none 0.5)
		(connect_pads
			(clearance 0)
		)
		(min_thickness 0.25)
		(keepout
			(tracks not_allowed)
			(vias allowed)
			(pads allowed)
			(copperpour not_allowed)
			(footprints allowed)
		)
		(placement
			(enabled no)
			(sheetname "")
		)
		(fill yes
			(thermal_gap 0.5)
			(thermal_bridge_width 0.5)
			(island_removal_mode 0)
		)
		(polygon
			(pts
				(arc
					(start 455.565256 -114.020092)
					(mid 455.181462 -114.403505)
					(end 455.565002 -114.787172)
				)
				(arc
					(start 456.835002 -114.787172)
					(mid 457.105306 -114.675732)
					(end 457.218542 -114.406172)
				)
				(arc
					(start 457.101702 -114.406172)
					(mid 456.835002 -114.670344)
					(end 456.568302 -114.406172)
				)
				(arc
					(start 455.831702 -114.406172)
					(mid 455.565002 -114.670344)
					(end 455.298302 -114.406172)
				)
				(arc
					(start 455.298302 -114.403632)
					(mid 455.565002 -114.136932)
					(end 455.831702 -114.403632)
				)
				(arc
					(start 456.568302 -114.403632)
					(mid 456.835002 -114.136932)
					(end 457.101702 -114.403632)
				)
				(arc
					(start 457.218542 -114.403632)
					(mid 457.106206 -114.132428)
					(end 456.835002 -114.020092)
				)
			)
		)
	)
	(zone
		(layers "In1.Cu" "In2.Cu" "In3.Cu" "In4.Cu" "In5.Cu" "In6.Cu" "In7.Cu"
			"In8.Cu" "In9.Cu" "In10.Cu" "In11.Cu" "In12.Cu"
		)
		(hatch none 0.5)
		(connect_pads
			(clearance 0)
		)
		(min_thickness 0.25)
		(keepout
			(tracks not_allowed)
			(vias allowed)
			(pads allowed)
			(copperpour not_allowed)
			(footprints allowed)
		)
		(placement
			(enabled no)
			(sheetname "")
		)
		(fill yes
			(thermal_gap 0.5)
			(thermal_bridge_width 0.5)
			(island_removal_mode 0)
		)
		(polygon
			(pts
				(arc
					(start 384.92303 -26.551128)
					(mid 384.53949 -26.167588)
					(end 384.15595 -26.551128)
				)
				(arc
					(start 384.15595 -27.516328)
					(mid 384.53822 -27.899866)
					(end 384.92303 -27.518868)
				)
				(arc
					(start 384.80619 -27.518868)
					(mid 384.53949 -27.78304)
					(end 384.27279 -27.518868)
				)
				(arc
					(start 384.27279 -27.516328)
					(mid 384.53949 -27.249628)
					(end 384.80619 -27.516328)
				)
				(xy 384.92303 -27.516328) (xy 384.92303 -26.553668)
				(arc
					(start 384.80619 -26.553668)
					(mid 384.53949 -26.81784)
					(end 384.27279 -26.553668)
				)
				(arc
					(start 384.27279 -26.551128)
					(mid 384.53949 -26.284428)
					(end 384.80619 -26.551128)
				)
			)
		)
	)
	(zone
		(layers "In1.Cu" "In2.Cu" "In3.Cu" "In4.Cu" "In5.Cu" "In6.Cu" "In7.Cu"
			"In8.Cu" "In9.Cu" "In10.Cu" "In11.Cu" "In12.Cu"
		)
		(hatch none 0.5)
		(connect_pads
			(clearance 0)
		)
		(min_thickness 0.25)
		(keepout
			(tracks not_allowed)
			(vias allowed)
			(pads allowed)
			(copperpour not_allowed)
			(footprints allowed)
		)
		(placement
			(enabled no)
			(sheetname "")
		)
		(fill yes
			(thermal_gap 0.5)
			(thermal_bridge_width 0.5)
			(island_removal_mode 0)
		)
		(polygon
			(pts
				(arc
					(start 446.701672 -49.614582)
					(mid 446.318132 -49.998122)
					(end 446.701672 -50.381662)
				)
				(arc
					(start 447.971418 -50.381662)
					(mid 448.241886 -50.270312)
					(end 448.355212 -50.000662)
				)
				(arc
					(start 448.238372 -50.000662)
					(mid 447.971672 -50.264834)
					(end 447.704972 -50.000662)
				)
				(arc
					(start 446.968372 -50.000662)
					(mid 446.701672 -50.264834)
					(end 446.434972 -50.000662)
				)
				(arc
					(start 446.434972 -49.998122)
					(mid 446.701672 -49.731422)
					(end 446.968372 -49.998122)
				)
				(arc
					(start 447.704972 -49.998122)
					(mid 447.971672 -49.731422)
					(end 448.238372 -49.998122)
				)
				(arc
					(start 448.355212 -49.998122)
					(mid 448.242876 -49.726918)
					(end 447.971672 -49.614582)
				)
			)
		)
	)
	(zone
		(layers "In1.Cu" "In2.Cu" "In3.Cu" "In4.Cu" "In5.Cu" "In6.Cu" "In7.Cu"
			"In8.Cu" "In9.Cu" "In10.Cu" "In11.Cu" "In12.Cu"
		)
		(hatch none 0.5)
		(connect_pads
			(clearance 0)
		)
		(min_thickness 0.25)
		(keepout
			(tracks not_allowed)
			(vias allowed)
			(pads allowed)
			(copperpour not_allowed)
			(footprints allowed)
		)
		(placement
			(enabled no)
			(sheetname "")
		)
		(fill yes
			(thermal_gap 0.5)
			(thermal_bridge_width 0.5)
			(island_removal_mode 0)
		)
		(polygon
			(pts
				(arc
					(start 465.199984 -114.06886)
					(mid 464.81619 -114.452273)
					(end 465.19973 -114.83594)
				)
				(arc
					(start 466.46973 -114.83594)
					(mid 466.740034 -114.7245)
					(end 466.85327 -114.45494)
				)
				(arc
					(start 466.73643 -114.45494)
					(mid 466.46973 -114.719112)
					(end 466.20303 -114.45494)
				)
				(arc
					(start 465.46643 -114.45494)
					(mid 465.19973 -114.719112)
					(end 464.93303 -114.45494)
				)
				(arc
					(start 464.93303 -114.4524)
					(mid 465.19973 -114.1857)
					(end 465.46643 -114.4524)
				)
				(arc
					(start 466.20303 -114.4524)
					(mid 466.46973 -114.1857)
					(end 466.73643 -114.4524)
				)
				(arc
					(start 466.85327 -114.4524)
					(mid 466.740934 -114.181196)
					(end 466.46973 -114.06886)
				)
			)
		)
	)
	(zone
		(layers "In1.Cu" "In2.Cu" "In3.Cu" "In4.Cu" "In5.Cu" "In6.Cu" "In7.Cu"
			"In8.Cu" "In9.Cu" "In10.Cu" "In11.Cu" "In12.Cu"
		)
		(hatch none 0.5)
		(connect_pads
			(clearance 0)
		)
		(min_thickness 0.25)
		(keepout
			(tracks not_allowed)
			(vias allowed)
			(pads allowed)
			(copperpour not_allowed)
			(footprints allowed)
		)
		(placement
			(enabled no)
			(sheetname "")
		)
		(fill yes
			(thermal_gap 0.5)
			(thermal_bridge_width 0.5)
			(island_removal_mode 0)
		)
		(polygon
			(pts
				(arc
					(start 440.325002 -49.597564)
					(mid 439.941462 -49.981104)
					(end 440.325002 -50.364644)
				)
				(arc
					(start 441.594748 -50.364644)
					(mid 441.865216 -50.253294)
					(end 441.978542 -49.983644)
				)
				(arc
					(start 441.861702 -49.983644)
					(mid 441.595002 -50.247816)
					(end 441.328302 -49.983644)
				)
				(arc
					(start 440.591702 -49.983644)
					(mid 440.325002 -50.247816)
					(end 440.058302 -49.983644)
				)
				(arc
					(start 440.058302 -49.981104)
					(mid 440.325002 -49.714404)
					(end 440.591702 -49.981104)
				)
				(arc
					(start 441.328302 -49.981104)
					(mid 441.595002 -49.714404)
					(end 441.861702 -49.981104)
				)
				(arc
					(start 441.978542 -49.981104)
					(mid 441.866206 -49.7099)
					(end 441.595002 -49.597564)
				)
			)
		)
	)
	(zone
		(layers "In1.Cu" "In2.Cu" "In3.Cu" "In4.Cu" "In5.Cu" "In6.Cu" "In7.Cu"
			"In8.Cu" "In9.Cu" "In10.Cu" "In11.Cu" "In12.Cu"
		)
		(hatch none 0.5)
		(connect_pads
			(clearance 0)
		)
		(min_thickness 0.25)
		(keepout
			(tracks not_allowed)
			(vias allowed)
			(pads allowed)
			(copperpour not_allowed)
			(footprints allowed)
		)
		(placement
			(enabled no)
			(sheetname "")
		)
		(fill yes
			(thermal_gap 0.5)
			(thermal_bridge_width 0.5)
			(island_removal_mode 0)
		)
		(polygon
			(pts
				(arc
					(start 13.482066 -30.1625)
					(mid 13.098526 -29.77896)
					(end 12.714986 -30.1625)
				)
				(arc
					(start 12.714986 -31.432246)
					(mid 13.097129 -31.816038)
					(end 13.482066 -31.43504)
				)
				(arc
					(start 13.365226 -31.43504)
					(mid 13.098526 -31.699212)
					(end 12.831826 -31.43504)
				)
				(arc
					(start 12.831826 -31.4325)
					(mid 13.098526 -31.1658)
					(end 13.365226 -31.4325)
				)
				(xy 13.482066 -31.4325) (xy 13.482066 -30.16504)
				(arc
					(start 13.365226 -30.16504)
					(mid 13.098526 -30.429212)
					(end 12.831826 -30.16504)
				)
				(arc
					(start 12.831826 -30.1625)
					(mid 13.098526 -29.8958)
					(end 13.365226 -30.1625)
				)
			)
		)
	)
	(zone
		(layers "In1.Cu" "In2.Cu" "In3.Cu" "In4.Cu" "In5.Cu" "In6.Cu" "In7.Cu"
			"In8.Cu" "In9.Cu" "In10.Cu" "In11.Cu" "In12.Cu"
		)
		(hatch none 0.5)
		(connect_pads
			(clearance 0)
		)
		(min_thickness 0.25)
		(keepout
			(tracks not_allowed)
			(vias allowed)
			(pads allowed)
			(copperpour not_allowed)
			(footprints allowed)
		)
		(placement
			(enabled no)
			(sheetname "")
		)
		(fill yes
			(thermal_gap 0.5)
			(thermal_bridge_width 0.5)
			(island_removal_mode 0)
		)
		(polygon
			(pts
				(arc
					(start 443.504828 -49.614582)
					(mid 443.121288 -49.998122)
					(end 443.504828 -50.381662)
				)
				(arc
					(start 444.774574 -50.381662)
					(mid 445.045042 -50.270312)
					(end 445.158368 -50.000662)
				)
				(arc
					(start 445.041528 -50.000662)
					(mid 444.774828 -50.264834)
					(end 444.508128 -50.000662)
				)
				(arc
					(start 443.771528 -50.000662)
					(mid 443.504828 -50.264834)
					(end 443.238128 -50.000662)
				)
				(arc
					(start 443.238128 -49.998122)
					(mid 443.504828 -49.731422)
					(end 443.771528 -49.998122)
				)
				(arc
					(start 444.508128 -49.998122)
					(mid 444.774828 -49.731422)
					(end 445.041528 -49.998122)
				)
				(arc
					(start 445.158368 -49.998122)
					(mid 445.046032 -49.726918)
					(end 444.774828 -49.614582)
				)
			)
		)
	)
	(zone
		(layers "In1.Cu" "In2.Cu" "In3.Cu" "In4.Cu" "In5.Cu" "In6.Cu" "In7.Cu"
			"In8.Cu" "In9.Cu" "In10.Cu" "In11.Cu" "In12.Cu"
		)
		(hatch none 0.5)
		(connect_pads
			(clearance 0)
		)
		(min_thickness 0.25)
		(keepout
			(tracks not_allowed)
			(vias allowed)
			(pads allowed)
			(copperpour not_allowed)
			(footprints allowed)
		)
		(placement
			(enabled no)
			(sheetname "")
		)
		(fill yes
			(thermal_gap 0.5)
			(thermal_bridge_width 0.5)
			(island_removal_mode 0)
		)
		(polygon
			(pts
				(arc
					(start 384.92303 -29.551122)
					(mid 384.53949 -29.167582)
					(end 384.15595 -29.551122)
				)
				(arc
					(start 384.15595 -30.516322)
					(mid 384.53822 -30.89986)
					(end 384.92303 -30.518862)
				)
				(arc
					(start 384.80619 -30.518862)
					(mid 384.53949 -30.783034)
					(end 384.27279 -30.518862)
				)
				(arc
					(start 384.27279 -30.516322)
					(mid 384.53949 -30.249622)
					(end 384.80619 -30.516322)
				)
				(xy 384.92303 -30.516322) (xy 384.92303 -29.553662)
				(arc
					(start 384.80619 -29.553662)
					(mid 384.53949 -29.817834)
					(end 384.27279 -29.553662)
				)
				(arc
					(start 384.27279 -29.551122)
					(mid 384.53949 -29.284422)
					(end 384.80619 -29.551122)
				)
			)
		)
	)
	(zone
		(layers "In1.Cu" "In2.Cu" "In3.Cu" "In4.Cu" "In5.Cu" "In6.Cu" "In7.Cu"
			"In8.Cu" "In9.Cu" "In10.Cu" "In11.Cu" "In12.Cu"
		)
		(hatch none 0.5)
		(connect_pads
			(clearance 0)
		)
		(min_thickness 0.25)
		(keepout
			(tracks not_allowed)
			(vias allowed)
			(pads allowed)
			(copperpour not_allowed)
			(footprints allowed)
		)
		(placement
			(enabled no)
			(sheetname "")
		)
		(fill yes
			(thermal_gap 0.5)
			(thermal_bridge_width 0.5)
			(island_removal_mode 0)
		)
		(polygon
			(pts
				(arc
					(start 458.765148 -114.020092)
					(mid 458.381354 -114.403505)
					(end 458.764894 -114.787172)
				)
				(arc
					(start 460.034894 -114.787172)
					(mid 460.305198 -114.675732)
					(end 460.418434 -114.406172)
				)
				(arc
					(start 460.301594 -114.406172)
					(mid 460.034894 -114.670344)
					(end 459.768194 -114.406172)
				)
				(arc
					(start 459.031594 -114.406172)
					(mid 458.764894 -114.670344)
					(end 458.498194 -114.406172)
				)
				(arc
					(start 458.498194 -114.403632)
					(mid 458.764894 -114.136932)
					(end 459.031594 -114.403632)
				)
				(arc
					(start 459.768194 -114.403632)
					(mid 460.034894 -114.136932)
					(end 460.301594 -114.403632)
				)
				(arc
					(start 460.418434 -114.403632)
					(mid 460.306098 -114.132428)
					(end 460.034894 -114.020092)
				)
			)
		)
	)
	(zone
		(layers "In1.Cu" "In2.Cu" "In3.Cu" "In4.Cu" "In5.Cu" "In6.Cu" "In7.Cu"
			"In8.Cu" "In9.Cu" "In10.Cu" "In11.Cu" "In12.Cu"
		)
		(hatch none 0.5)
		(connect_pads
			(clearance 0)
		)
		(min_thickness 0.25)
		(keepout
			(tracks not_allowed)
			(vias allowed)
			(pads allowed)
			(copperpour not_allowed)
			(footprints allowed)
		)
		(placement
			(enabled no)
			(sheetname "")
		)
		(fill yes
			(thermal_gap 0.5)
			(thermal_bridge_width 0.5)
			(island_removal_mode 0)
		)
		(polygon
			(pts
				(arc
					(start 453.095614 -49.614074)
					(mid 452.712074 -49.997614)
					(end 453.095614 -50.381154)
				)
				(arc
					(start 454.36536 -50.381154)
					(mid 454.635828 -50.269804)
					(end 454.749154 -50.000154)
				)
				(arc
					(start 454.632314 -50.000154)
					(mid 454.365614 -50.264326)
					(end 454.098914 -50.000154)
				)
				(arc
					(start 453.362314 -50.000154)
					(mid 453.095614 -50.264326)
					(end 452.828914 -50.000154)
				)
				(arc
					(start 452.828914 -49.997614)
					(mid 453.095614 -49.730914)
					(end 453.362314 -49.997614)
				)
				(arc
					(start 454.098914 -49.997614)
					(mid 454.365614 -49.730914)
					(end 454.632314 -49.997614)
				)
				(arc
					(start 454.749154 -49.997614)
					(mid 454.636818 -49.72641)
					(end 454.365614 -49.614074)
				)
			)
		)
	)
	(zone
		(layers "In1.Cu" "In2.Cu" "In3.Cu" "In4.Cu" "In5.Cu" "In6.Cu" "In7.Cu"
			"In8.Cu" "In9.Cu" "In10.Cu" "In11.Cu" "In12.Cu"
		)
		(hatch none 0.5)
		(connect_pads
			(clearance 0)
		)
		(min_thickness 0.25)
		(keepout
			(tracks not_allowed)
			(vias allowed)
			(pads allowed)
			(copperpour not_allowed)
			(footprints allowed)
		)
		(placement
			(enabled no)
			(sheetname "")
		)
		(fill yes
			(thermal_gap 0.5)
			(thermal_bridge_width 0.5)
			(island_removal_mode 0)
		)
		(polygon
			(pts
				(arc
					(start 456.296014 -49.614074)
					(mid 455.912474 -49.997614)
					(end 456.296014 -50.381154)
				)
				(arc
					(start 457.56576 -50.381154)
					(mid 457.836228 -50.269804)
					(end 457.949554 -50.000154)
				)
				(arc
					(start 457.832714 -50.000154)
					(mid 457.566014 -50.264326)
					(end 457.299314 -50.000154)
				)
				(arc
					(start 456.562714 -50.000154)
					(mid 456.296014 -50.264326)
					(end 456.029314 -50.000154)
				)
				(arc
					(start 456.029314 -49.997614)
					(mid 456.296014 -49.730914)
					(end 456.562714 -49.997614)
				)
				(arc
					(start 457.299314 -49.997614)
					(mid 457.566014 -49.730914)
					(end 457.832714 -49.997614)
				)
				(arc
					(start 457.949554 -49.997614)
					(mid 457.837218 -49.72641)
					(end 457.566014 -49.614074)
				)
			)
		)
	)
	(zone
		(layers "In1.Cu" "In2.Cu" "In3.Cu" "In4.Cu" "In5.Cu" "In6.Cu" "In7.Cu"
			"In8.Cu" "In9.Cu" "In10.Cu" "In11.Cu" "In12.Cu"
		)
		(hatch none 0.5)
		(connect_pads
			(clearance 0)
		)
		(min_thickness 0.25)
		(keepout
			(tracks not_allowed)
			(vias allowed)
			(pads allowed)
			(copperpour not_allowed)
			(footprints allowed)
		)
		(placement
			(enabled no)
			(sheetname "")
		)
		(fill yes
			(thermal_gap 0.5)
			(thermal_bridge_width 0.5)
			(island_removal_mode 0)
		)
		(polygon
			(pts
				(arc
					(start 449.165218 -114.020092)
					(mid 448.781678 -114.403505)
					(end 449.164964 -114.787172)
				)
				(arc
					(start 450.434964 -114.787172)
					(mid 450.705268 -114.675732)
					(end 450.818504 -114.406172)
				)
				(arc
					(start 450.701664 -114.406172)
					(mid 450.434964 -114.670344)
					(end 450.168264 -114.406172)
				)
				(arc
					(start 449.431664 -114.406172)
					(mid 449.164964 -114.670344)
					(end 448.898264 -114.406172)
				)
				(arc
					(start 448.898264 -114.403632)
					(mid 449.164964 -114.136932)
					(end 449.431664 -114.403632)
				)
				(arc
					(start 450.168264 -114.403632)
					(mid 450.434964 -114.136932)
					(end 450.701664 -114.403632)
				)
				(arc
					(start 450.818504 -114.403632)
					(mid 450.706168 -114.132428)
					(end 450.434964 -114.020092)
				)
			)
		)
	)
	(zone
		(layers "In1.Cu" "In2.Cu" "In3.Cu" "In4.Cu" "In5.Cu" "In6.Cu" "In7.Cu"
			"In8.Cu" "In9.Cu" "In10.Cu" "In11.Cu" "In12.Cu"
		)
		(hatch none 0.5)
		(connect_pads
			(clearance 0)
		)
		(min_thickness 0.25)
		(keepout
			(tracks not_allowed)
			(vias allowed)
			(pads allowed)
			(copperpour not_allowed)
			(footprints allowed)
		)
		(placement
			(enabled no)
			(sheetname "")
		)
		(fill yes
			(thermal_gap 0.5)
			(thermal_bridge_width 0.5)
			(island_removal_mode 0)
		)
		(polygon
			(pts
				(arc
					(start 461.965294 -114.020092)
					(mid 461.5815 -114.403505)
					(end 461.96504 -114.787172)
				)
				(arc
					(start 463.23504 -114.787172)
					(mid 463.505344 -114.675732)
					(end 463.61858 -114.406172)
				)
				(arc
					(start 463.50174 -114.406172)
					(mid 463.23504 -114.670344)
					(end 462.96834 -114.406172)
				)
				(arc
					(start 462.23174 -114.406172)
					(mid 461.96504 -114.670344)
					(end 461.69834 -114.406172)
				)
				(arc
					(start 461.69834 -114.403632)
					(mid 461.96504 -114.136932)
					(end 462.23174 -114.403632)
				)
				(arc
					(start 462.96834 -114.403632)
					(mid 463.23504 -114.136932)
					(end 463.50174 -114.403632)
				)
				(arc
					(start 463.61858 -114.403632)
					(mid 463.506244 -114.132428)
					(end 463.23504 -114.020092)
				)
			)
		)
	)
	(zone
		(layers "In1.Cu" "In2.Cu" "In3.Cu" "In4.Cu" "In5.Cu" "In6.Cu" "In7.Cu"
			"In8.Cu" "In9.Cu" "In10.Cu" "In11.Cu" "In12.Cu"
		)
		(hatch none 0.5)
		(connect_pads
			(clearance 0)
		)
		(min_thickness 0.25)
		(keepout
			(tracks not_allowed)
			(vias allowed)
			(pads allowed)
			(copperpour not_allowed)
			(footprints allowed)
		)
		(placement
			(enabled no)
			(sheetname "")
		)
		(fill yes
			(thermal_gap 0.5)
			(thermal_bridge_width 0.5)
			(island_removal_mode 0)
		)
		(polygon
			(pts
				(arc
					(start 384.038602 -24.522684)
					(mid 384.305302 -24.255984)
					(end 384.572002 -24.522684)
				)
				(xy 384.692906 -24.522684) (xy 384.771646 -23.636224) (xy 384.771392 -23.63597) (xy 384.769106 -23.635716)
				(xy 384.77063 -23.604474)
				(arc
					(start 384.65379 -23.604474)
					(mid 384.38709 -23.868646)
					(end 384.12039 -23.604474)
				)
				(arc
					(start 384.12039 -23.601934)
					(mid 384.38709 -23.335234)
					(end 384.65379 -23.601934)
				)
				(arc
					(start 384.77063 -23.601934)
					(mid 384.403999 -23.218513)
					(end 384.005074 -23.568152)
				)
				(xy 384.002534 -23.567898) (xy 383.920746 -24.488648)
				(arc
					(start 383.923286 -24.488902)
					(mid 384.27152 -24.9047)
					(end 384.687318 -24.556466)
				)
				(xy 384.689858 -24.55672) (xy 384.692652 -24.525224)
				(arc
					(start 384.572002 -24.525224)
					(mid 384.305302 -24.789396)
					(end 384.038602 -24.525224)
				)
			)
		)
	)
	(zone
		(layers "In1.Cu" "In2.Cu" "In3.Cu" "In4.Cu" "In5.Cu" "In6.Cu" "In7.Cu"
			"In8.Cu" "In9.Cu" "In10.Cu" "In11.Cu" "In12.Cu"
		)
		(hatch none 0.5)
		(connect_pads
			(clearance 0)
		)
		(min_thickness 0.25)
		(keepout
			(tracks not_allowed)
			(vias allowed)
			(pads allowed)
			(copperpour not_allowed)
			(footprints allowed)
		)
		(placement
			(enabled no)
			(sheetname "")
		)
		(fill yes
			(thermal_gap 0.5)
			(thermal_bridge_width 0.5)
			(island_removal_mode 0)
		)
		(polygon
			(pts
				(arc
					(start 459.496414 -49.614074)
					(mid 459.112874 -49.997614)
					(end 459.496414 -50.381154)
				)
				(arc
					(start 460.76616 -50.381154)
					(mid 461.036628 -50.269804)
					(end 461.149954 -50.000154)
				)
				(arc
					(start 461.033114 -50.000154)
					(mid 460.766414 -50.264326)
					(end 460.499714 -50.000154)
				)
				(arc
					(start 459.763114 -50.000154)
					(mid 459.496414 -50.264326)
					(end 459.229714 -50.000154)
				)
				(arc
					(start 459.229714 -49.997614)
					(mid 459.496414 -49.730914)
					(end 459.763114 -49.997614)
				)
				(arc
					(start 460.499714 -49.997614)
					(mid 460.766414 -49.730914)
					(end 461.033114 -49.997614)
				)
				(arc
					(start 461.149954 -49.997614)
					(mid 461.037618 -49.72641)
					(end 460.766414 -49.614074)
				)
			)
		)
	)
	(zone
		(layers "In1.Cu" "In2.Cu" "In3.Cu" "In4.Cu" "In5.Cu" "In6.Cu" "In7.Cu"
			"In8.Cu" "In9.Cu" "In10.Cu" "In11.Cu" "In12.Cu"
		)
		(hatch none 0.5)
		(connect_pads
			(clearance 0)
		)
		(min_thickness 0.25)
		(keepout
			(tracks not_allowed)
			(vias allowed)
			(pads allowed)
			(copperpour not_allowed)
			(footprints allowed)
		)
		(placement
			(enabled no)
			(sheetname "")
		)
		(fill yes
			(thermal_gap 0.5)
			(thermal_bridge_width 0.5)
			(island_removal_mode 0)
		)
		(polygon
			(pts
				(arc
					(start 13.482066 -33.7185)
					(mid 13.098526 -33.33496)
					(end 12.714986 -33.7185)
				)
				(arc
					(start 12.714986 -34.988246)
					(mid 13.097129 -35.372038)
					(end 13.482066 -34.99104)
				)
				(arc
					(start 13.365226 -34.99104)
					(mid 13.098526 -35.255212)
					(end 12.831826 -34.99104)
				)
				(arc
					(start 12.831826 -34.9885)
					(mid 13.098526 -34.7218)
					(end 13.365226 -34.9885)
				)
				(xy 13.482066 -34.9885) (xy 13.482066 -33.72104)
				(arc
					(start 13.365226 -33.72104)
					(mid 13.098526 -33.985212)
					(end 12.831826 -33.72104)
				)
				(arc
					(start 12.831826 -33.7185)
					(mid 13.098526 -33.4518)
					(end 13.365226 -33.7185)
				)
			)
		)
	)
	(zone
		(layers "In1.Cu" "In2.Cu" "In3.Cu" "In4.Cu" "In5.Cu" "In6.Cu" "In7.Cu"
			"In8.Cu" "In9.Cu" "In10.Cu" "In11.Cu" "In12.Cu"
		)
		(hatch none 0.5)
		(connect_pads
			(clearance 0)
		)
		(min_thickness 0.25)
		(keepout
			(tracks not_allowed)
			(vias allowed)
			(pads allowed)
			(copperpour not_allowed)
			(footprints allowed)
		)
		(placement
			(enabled no)
			(sheetname "")
		)
		(fill yes
			(thermal_gap 0.5)
			(thermal_bridge_width 0.5)
			(island_removal_mode 0)
		)
		(polygon
			(pts
				(arc
					(start 431.888646 -138.461242)
					(mid 431.504852 -138.844655)
					(end 431.888392 -139.228322)
				)
				(arc
					(start 433.158392 -139.228322)
					(mid 433.428696 -139.116882)
					(end 433.541932 -138.847322)
				)
				(arc
					(start 433.425092 -138.847322)
					(mid 433.158392 -139.111494)
					(end 432.891692 -138.847322)
				)
				(arc
					(start 432.155092 -138.847322)
					(mid 431.888392 -139.111494)
					(end 431.621692 -138.847322)
				)
				(arc
					(start 431.621692 -138.844782)
					(mid 431.888392 -138.578082)
					(end 432.155092 -138.844782)
				)
				(arc
					(start 432.891692 -138.844782)
					(mid 433.158392 -138.578082)
					(end 433.425092 -138.844782)
				)
				(arc
					(start 433.541932 -138.844782)
					(mid 433.429596 -138.573578)
					(end 433.158392 -138.461242)
				)
			)
		)
	)
	(zone
		(layers "In1.Cu" "In2.Cu" "In3.Cu" "In4.Cu" "In5.Cu" "In6.Cu" "In7.Cu"
			"In8.Cu" "In9.Cu" "In10.Cu" "In11.Cu" "In12.Cu"
		)
		(hatch none 0.5)
		(connect_pads
			(clearance 0)
		)
		(min_thickness 0.25)
		(keepout
			(tracks not_allowed)
			(vias allowed)
			(pads allowed)
			(copperpour not_allowed)
			(footprints allowed)
		)
		(placement
			(enabled no)
			(sheetname "")
		)
		(fill yes
			(thermal_gap 0.5)
			(thermal_bridge_width 0.5)
			(island_removal_mode 0)
		)
		(polygon
			(pts
				(arc
					(start 13.434314 -23.0505)
					(mid 13.050774 -22.66696)
					(end 12.667234 -23.0505)
				)
				(arc
					(start 12.667234 -24.3205)
					(mid 13.049504 -24.704038)
					(end 13.434314 -24.32304)
				)
				(arc
					(start 13.317474 -24.32304)
					(mid 13.050774 -24.587212)
					(end 12.784074 -24.32304)
				)
				(arc
					(start 12.784074 -24.3205)
					(mid 13.050774 -24.0538)
					(end 13.317474 -24.3205)
				)
				(xy 13.434314 -24.3205) (xy 13.434314 -23.05304)
				(arc
					(start 13.317474 -23.05304)
					(mid 13.050774 -23.317212)
					(end 12.784074 -23.05304)
				)
				(arc
					(start 12.784074 -23.0505)
					(mid 13.050774 -22.7838)
					(end 13.317474 -23.0505)
				)
			)
		)
	)
	(zone
		(layers "In1.Cu" "In2.Cu" "In3.Cu" "In4.Cu" "In5.Cu" "In6.Cu" "In7.Cu"
			"In8.Cu" "In9.Cu" "In10.Cu" "In11.Cu" "In12.Cu"
		)
		(hatch none 0.5)
		(connect_pads
			(clearance 0)
		)
		(min_thickness 0.25)
		(keepout
			(tracks not_allowed)
			(vias allowed)
			(pads allowed)
			(copperpour not_allowed)
			(footprints allowed)
		)
		(placement
			(enabled no)
			(sheetname "")
		)
		(fill yes
			(thermal_gap 0.5)
			(thermal_bridge_width 0.5)
			(island_removal_mode 0)
		)
		(polygon
			(pts
				(arc
					(start 12.29614 -24.8285)
					(mid 11.9126 -24.44496)
					(end 11.52906 -24.8285)
				)
				(arc
					(start 11.52906 -26.098246)
					(mid 11.911203 -26.482038)
					(end 12.29614 -26.10104)
				)
				(arc
					(start 12.1793 -26.10104)
					(mid 11.9126 -26.365212)
					(end 11.6459 -26.10104)
				)
				(arc
					(start 11.6459 -26.0985)
					(mid 11.9126 -25.8318)
					(end 12.1793 -26.0985)
				)
				(xy 12.29614 -26.0985) (xy 12.29614 -24.83104)
				(arc
					(start 12.1793 -24.83104)
					(mid 11.9126 -25.095212)
					(end 11.6459 -24.83104)
				)
				(arc
					(start 11.6459 -24.8285)
					(mid 11.9126 -24.5618)
					(end 12.1793 -24.8285)
				)
			)
		)
	)
	(zone
		(layers "In1.Cu" "In2.Cu" "In3.Cu" "In4.Cu" "In5.Cu" "In6.Cu" "In7.Cu"
			"In8.Cu" "In9.Cu" "In10.Cu" "In11.Cu" "In12.Cu"
		)
		(hatch none 0.5)
		(connect_pads
			(clearance 0)
		)
		(min_thickness 0.25)
		(keepout
			(tracks not_allowed)
			(vias allowed)
			(pads allowed)
			(copperpour not_allowed)
			(footprints allowed)
		)
		(placement
			(enabled no)
			(sheetname "")
		)
		(fill yes
			(thermal_gap 0.5)
			(thermal_bridge_width 0.5)
			(island_removal_mode 0)
		)
		(polygon
			(pts
				(arc
					(start 445.965072 -114.020092)
					(mid 445.581532 -114.403505)
					(end 445.964818 -114.787172)
				)
				(arc
					(start 447.234818 -114.787172)
					(mid 447.505122 -114.675732)
					(end 447.618358 -114.406172)
				)
				(arc
					(start 447.501518 -114.406172)
					(mid 447.234818 -114.670344)
					(end 446.968118 -114.406172)
				)
				(arc
					(start 446.231518 -114.406172)
					(mid 445.964818 -114.670344)
					(end 445.698118 -114.406172)
				)
				(arc
					(start 445.698118 -114.403632)
					(mid 445.964818 -114.136932)
					(end 446.231518 -114.403632)
				)
				(arc
					(start 446.968118 -114.403632)
					(mid 447.234818 -114.136932)
					(end 447.501518 -114.403632)
				)
				(arc
					(start 447.618358 -114.403632)
					(mid 447.506022 -114.132428)
					(end 447.234818 -114.020092)
				)
			)
		)
	)
	(zone
		(layers "In1.Cu" "In2.Cu" "In3.Cu" "In4.Cu" "In5.Cu" "In6.Cu" "In7.Cu"
			"In8.Cu" "In9.Cu" "In10.Cu" "In11.Cu" "In12.Cu"
		)
		(hatch none 0.5)
		(connect_pads
			(clearance 0)
		)
		(min_thickness 0.25)
		(keepout
			(tracks not_allowed)
			(vias allowed)
			(pads allowed)
			(copperpour not_allowed)
			(footprints allowed)
		)
		(placement
			(enabled no)
			(sheetname "")
		)
		(fill yes
			(thermal_gap 0.5)
			(thermal_bridge_width 0.5)
			(island_removal_mode 0)
		)
		(polygon
			(pts
				(arc
					(start 452.36511 -114.020092)
					(mid 451.981316 -114.403505)
					(end 452.364856 -114.787172)
				)
				(arc
					(start 453.634856 -114.787172)
					(mid 453.90516 -114.675732)
					(end 454.018396 -114.406172)
				)
				(arc
					(start 453.901556 -114.406172)
					(mid 453.634856 -114.670344)
					(end 453.368156 -114.406172)
				)
				(arc
					(start 452.631556 -114.406172)
					(mid 452.364856 -114.670344)
					(end 452.098156 -114.406172)
				)
				(arc
					(start 452.098156 -114.403632)
					(mid 452.364856 -114.136932)
					(end 452.631556 -114.403632)
				)
				(arc
					(start 453.368156 -114.403632)
					(mid 453.634856 -114.136932)
					(end 453.901556 -114.403632)
				)
				(arc
					(start 454.018396 -114.403632)
					(mid 453.90606 -114.132428)
					(end 453.634856 -114.020092)
				)
			)
		)
	)
	(zone
		(layers "In1.Cu" "In2.Cu" "In3.Cu" "In4.Cu" "In5.Cu" "In6.Cu" "In7.Cu"
			"In8.Cu" "In9.Cu" "In10.Cu" "In11.Cu" "In12.Cu"
		)
		(hatch none 0.5)
		(connect_pads
			(clearance 0)
		)
		(min_thickness 0.25)
		(keepout
			(tracks not_allowed)
			(vias allowed)
			(pads allowed)
			(copperpour not_allowed)
			(footprints allowed)
		)
		(placement
			(enabled no)
			(sheetname "")
		)
		(fill yes
			(thermal_gap 0.5)
			(thermal_bridge_width 0.5)
			(island_removal_mode 0)
		)
		(polygon
			(pts
				(arc
					(start 442.76518 -114.020092)
					(mid 442.381386 -114.403505)
					(end 442.764926 -114.787172)
				)
				(arc
					(start 444.034926 -114.787172)
					(mid 444.30523 -114.675732)
					(end 444.418466 -114.406172)
				)
				(arc
					(start 444.301626 -114.406172)
					(mid 444.034926 -114.670344)
					(end 443.768226 -114.406172)
				)
				(arc
					(start 443.031626 -114.406172)
					(mid 442.764926 -114.670344)
					(end 442.498226 -114.406172)
				)
				(arc
					(start 442.498226 -114.403632)
					(mid 442.764926 -114.136932)
					(end 443.031626 -114.403632)
				)
				(arc
					(start 443.768226 -114.403632)
					(mid 444.034926 -114.136932)
					(end 444.301626 -114.403632)
				)
				(arc
					(start 444.418466 -114.403632)
					(mid 444.30613 -114.132428)
					(end 444.034926 -114.020092)
				)
			)
		)
	)
	(zone
		(layers "In1.Cu" "In2.Cu" "In3.Cu" "In4.Cu" "In5.Cu" "In6.Cu" "In7.Cu"
			"In8.Cu" "In9.Cu" "In10.Cu" "In11.Cu" "In12.Cu"
		)
		(hatch none 0.5)
		(connect_pads
			(clearance 0)
		)
		(min_thickness 0.25)
		(keepout
			(tracks not_allowed)
			(vias allowed)
			(pads allowed)
			(copperpour not_allowed)
			(footprints allowed)
		)
		(placement
			(enabled no)
			(sheetname "")
		)
		(fill yes
			(thermal_gap 0.5)
			(thermal_bridge_width 0.5)
			(island_removal_mode 0)
		)
		(polygon
			(pts
				(arc
					(start 462.707228 -49.614074)
					(mid 462.323688 -49.997614)
					(end 462.707228 -50.381154)
				)
				(arc
					(start 463.976974 -50.381154)
					(mid 464.247442 -50.269804)
					(end 464.360768 -50.000154)
				)
				(arc
					(start 464.243928 -50.000154)
					(mid 463.977228 -50.264326)
					(end 463.710528 -50.000154)
				)
				(arc
					(start 462.973928 -50.000154)
					(mid 462.707228 -50.264326)
					(end 462.440528 -50.000154)
				)
				(arc
					(start 462.440528 -49.997614)
					(mid 462.707228 -49.730914)
					(end 462.973928 -49.997614)
				)
				(arc
					(start 463.710528 -49.997614)
					(mid 463.977228 -49.730914)
					(end 464.243928 -49.997614)
				)
				(arc
					(start 464.360768 -49.997614)
					(mid 464.248432 -49.72641)
					(end 463.977228 -49.614074)
				)
			)
		)
	)
	(zone
		(layers "In1.Cu" "In2.Cu" "In3.Cu" "In4.Cu" "In5.Cu" "In6.Cu" "In7.Cu"
			"In8.Cu" "In9.Cu" "In10.Cu" "In11.Cu" "In12.Cu"
		)
		(hatch none 0.5)
		(connect_pads
			(clearance 0)
		)
		(min_thickness 0.25)
		(keepout
			(tracks not_allowed)
			(vias allowed)
			(pads allowed)
			(copperpour not_allowed)
			(footprints allowed)
		)
		(placement
			(enabled no)
			(sheetname "")
		)
		(fill yes
			(thermal_gap 0.5)
			(thermal_bridge_width 0.5)
			(island_removal_mode 0)
		)
		(polygon
			(pts
				(arc
					(start 449.895214 -49.614074)
					(mid 449.511674 -49.997614)
					(end 449.895214 -50.381154)
				)
				(arc
					(start 451.16496 -50.381154)
					(mid 451.435428 -50.269804)
					(end 451.548754 -50.000154)
				)
				(arc
					(start 451.431914 -50.000154)
					(mid 451.165214 -50.264326)
					(end 450.898514 -50.000154)
				)
				(arc
					(start 450.161914 -50.000154)
					(mid 449.895214 -50.264326)
					(end 449.628514 -50.000154)
				)
				(arc
					(start 449.628514 -49.997614)
					(mid 449.895214 -49.730914)
					(end 450.161914 -49.997614)
				)
				(arc
					(start 450.898514 -49.997614)
					(mid 451.165214 -49.730914)
					(end 451.431914 -49.997614)
				)
				(arc
					(start 451.548754 -49.997614)
					(mid 451.436418 -49.72641)
					(end 451.165214 -49.614074)
				)
			)
		)
	)
	(zone
		(layers "In1.Cu" "In2.Cu" "In3.Cu" "In4.Cu" "In5.Cu" "In6.Cu" "In7.Cu"
			"In8.Cu" "In9.Cu" "In10.Cu" "In12.Cu"
		)
		(hatch none 0.5)
		(connect_pads
			(clearance 0)
		)
		(min_thickness 0.25)
		(keepout
			(tracks not_allowed)
			(vias allowed)
			(pads allowed)
			(copperpour not_allowed)
			(footprints allowed)
		)
		(placement
			(enabled no)
			(sheetname "")
		)
		(fill yes
			(thermal_gap 0.5)
			(thermal_bridge_width 0.5)
			(island_removal_mode 0)
		)
		(polygon
			(pts
				(arc
					(start 381.35179 -22.016974)
					(mid 380.96825 -21.633434)
					(end 380.58471 -22.016974)
				)
				(arc
					(start 380.58471 -22.982174)
					(mid 380.96698 -23.365712)
					(end 381.35179 -22.984714)
				)
				(arc
					(start 381.23495 -22.984714)
					(mid 380.96825 -23.248886)
					(end 380.70155 -22.984714)
				)
				(arc
					(start 380.70155 -22.982174)
					(mid 380.96825 -22.715474)
					(end 381.23495 -22.982174)
				)
				(xy 381.35179 -22.982174) (xy 381.35179 -22.019514)
				(arc
					(start 381.23495 -22.019514)
					(mid 380.96825 -22.283686)
					(end 380.70155 -22.019514)
				)
				(arc
					(start 380.70155 -22.016974)
					(mid 380.96825 -21.750274)
					(end 381.23495 -22.016974)
				)
			)
		)
	)
	(zone
		(layers "In1.Cu" "In2.Cu" "In3.Cu" "In4.Cu" "In5.Cu" "In6.Cu" "In7.Cu"
			"In8.Cu" "In9.Cu" "In10.Cu" "In12.Cu"
		)
		(hatch none 0.5)
		(connect_pads
			(clearance 0)
		)
		(min_thickness 0.25)
		(keepout
			(tracks not_allowed)
			(vias allowed)
			(pads allowed)
			(copperpour not_allowed)
			(footprints allowed)
		)
		(placement
			(enabled no)
			(sheetname "")
		)
		(fill yes
			(thermal_gap 0.5)
			(thermal_bridge_width 0.5)
			(island_removal_mode 0)
		)
		(polygon
			(pts
				(arc
					(start 381.49911 -28.176982)
					(mid 381.11557 -27.793442)
					(end 380.73203 -28.176982)
				)
				(arc
					(start 380.73203 -29.054552)
					(mid 381.1143 -29.43809)
					(end 381.49911 -29.057092)
				)
				(arc
					(start 381.38227 -29.057092)
					(mid 381.11557 -29.321264)
					(end 380.84887 -29.057092)
				)
				(arc
					(start 380.84887 -29.054552)
					(mid 381.11557 -28.787852)
					(end 381.38227 -29.054552)
				)
				(xy 381.49911 -29.054552) (xy 381.49911 -28.179522)
				(arc
					(start 381.38227 -28.179522)
					(mid 381.11557 -28.443694)
					(end 380.84887 -28.179522)
				)
				(arc
					(start 380.84887 -28.176982)
					(mid 381.11557 -27.910282)
					(end 381.38227 -28.176982)
				)
			)
		)
	)
	(zone
		(layers "In1.Cu" "In2.Cu" "In3.Cu" "In4.Cu" "In5.Cu" "In6.Cu" "In7.Cu"
			"In8.Cu" "In9.Cu" "In10.Cu" "In12.Cu"
		)
		(hatch none 0.5)
		(connect_pads
			(clearance 0)
		)
		(min_thickness 0.25)
		(keepout
			(tracks not_allowed)
			(vias allowed)
			(pads allowed)
			(copperpour not_allowed)
			(footprints allowed)
		)
		(placement
			(enabled no)
			(sheetname "")
		)
		(fill yes
			(thermal_gap 0.5)
			(thermal_bridge_width 0.5)
			(island_removal_mode 0)
		)
		(polygon
			(pts
				(arc
					(start 380.39294 -26.097484)
					(mid 380.65964 -25.830784)
					(end 380.92634 -26.097484)
				)
				(xy 381.04318 -26.097484) (xy 381.05461 -25.284176) (xy 381.05461 -25.281128)
				(arc
					(start 380.93777 -25.281128)
					(mid 380.67107 -25.5453)
					(end 380.40437 -25.281128)
				)
				(arc
					(start 380.40437 -25.278588)
					(mid 380.67107 -25.011888)
					(end 380.93777 -25.278588)
				)
				(arc
					(start 381.05461 -25.278588)
					(mid 380.673737 -24.895057)
					(end 380.28753 -25.273254)
				)
				(arc
					(start 380.2761 -26.09215)
					(mid 380.654306 -26.481024)
					(end 381.04318 -26.102818)
				)
				(xy 381.04318 -26.100024)
				(arc
					(start 380.92634 -26.100024)
					(mid 380.65964 -26.364196)
					(end 380.39294 -26.100024)
				)
			)
		)
	)
	(zone
		(layers "In1.Cu" "In2.Cu" "In3.Cu" "In4.Cu" "In5.Cu" "In6.Cu" "In7.Cu"
			"In8.Cu" "In10.Cu" "In11.Cu" "In12.Cu"
		)
		(hatch none 0.5)
		(connect_pads
			(clearance 0)
		)
		(min_thickness 0.25)
		(keepout
			(tracks not_allowed)
			(vias allowed)
			(pads allowed)
			(copperpour not_allowed)
			(footprints allowed)
		)
		(placement
			(enabled no)
			(sheetname "")
		)
		(fill yes
			(thermal_gap 0.5)
			(thermal_bridge_width 0.5)
			(island_removal_mode 0)
		)
		(polygon
			(pts
				(arc
					(start 417.036504 -91.567)
					(mid 416.627564 -91.15806)
					(end 416.218624 -91.567)
				)
				(arc
					(start 416.218624 -92.836746)
					(mid 416.626167 -93.245938)
					(end 417.036504 -92.83954)
				)
				(arc
					(start 416.894264 -92.83954)
					(mid 416.627564 -93.103712)
					(end 416.360864 -92.83954)
				)
				(arc
					(start 416.360864 -92.837)
					(mid 416.627564 -92.5703)
					(end 416.894264 -92.837)
				)
				(xy 417.036504 -92.837) (xy 417.036504 -91.56954)
				(arc
					(start 416.894264 -91.56954)
					(mid 416.627564 -91.833712)
					(end 416.360864 -91.56954)
				)
				(arc
					(start 416.360864 -91.567)
					(mid 416.627564 -91.3003)
					(end 416.894264 -91.567)
				)
			)
		)
	)
	(zone
		(net "P12V_MB0_SW")
		(layers "In1.Cu" "In2.Cu" "In3.Cu" "In4.Cu" "In5.Cu" "In9.Cu" "In10.Cu"
			"In11.Cu"
		)
		(hatch none 0.5)
		(connect_pads
			(clearance 0.5)
		)
		(min_thickness 0.25)
		(fill yes
			(thermal_gap 0.5)
			(thermal_bridge_width 0.5)
			(island_removal_mode 0)
		)
		(polygon
			(pts
				(xy 18.39341 -56.7182) (xy 13.462 -56.7182) (xy 13.1572 -57.023) (xy 13.1572 -65.7606) (xy 15.235936 -67.839336)
				(xy 18.519648 -67.839336) (xy 18.930366 -67.428618) (xy 18.930366 -67.413632) (xy 19.046952 -67.297046)
				(xy 19.046952 -66.1797) (xy 19.046952 -57.057036) (xy 18.708116 -56.7182)
			)
		)
	)
	(zone
		(layers "In1.Cu" "In3.Cu" "In4.Cu" "In5.Cu" "In6.Cu" "In7.Cu" "In8.Cu"
			"In9.Cu" "In10.Cu" "In11.Cu" "In12.Cu"
		)
		(hatch none 0.5)
		(connect_pads
			(clearance 0)
		)
		(min_thickness 0.25)
		(keepout
			(tracks not_allowed)
			(vias allowed)
			(pads allowed)
			(copperpour not_allowed)
			(footprints allowed)
		)
		(placement
			(enabled no)
			(sheetname "")
		)
		(fill yes
			(thermal_gap 0.5)
			(thermal_bridge_width 0.5)
			(island_removal_mode 0)
		)
		(polygon
			(pts
				(arc
					(start 426.630592 -9.639808)
					(mid 426.247052 -10.023348)
					(end 426.630592 -10.406888)
				)
				(arc
					(start 427.900338 -10.406888)
					(mid 428.170806 -10.295538)
					(end 428.284132 -10.025888)
				)
				(arc
					(start 428.167292 -10.025888)
					(mid 427.900592 -10.29006)
					(end 427.633892 -10.025888)
				)
				(arc
					(start 426.897292 -10.025888)
					(mid 426.630592 -10.29006)
					(end 426.363892 -10.025888)
				)
				(arc
					(start 426.363892 -10.023348)
					(mid 426.630592 -9.756648)
					(end 426.897292 -10.023348)
				)
				(arc
					(start 427.633892 -10.023348)
					(mid 427.900592 -9.756648)
					(end 428.167292 -10.023348)
				)
				(arc
					(start 428.284132 -10.023348)
					(mid 428.171796 -9.752144)
					(end 427.900592 -9.639808)
				)
			)
		)
	)
	(zone
		(net "GND")
		(layers "In1.Cu" "In3.Cu" "In5.Cu" "In6.Cu" "In7.Cu" "In8.Cu" "In10.Cu"
			"In12.Cu"
		)
		(hatch none 0.5)
		(connect_pads
			(clearance 0.5)
		)
		(min_thickness 0.25)
		(fill yes
			(thermal_gap 0.5)
			(thermal_bridge_width 0.5)
			(island_removal_mode 0)
		)
		(polygon
			(pts
				(xy -5.03174 15.24) (xy -5.03174 8.763) (xy 413.4358 8.763) (xy 501.2182 8.763) (xy 501.2182 8.7884)
				(xy 501.2182 15.24)
			)
		)
	)
	(zone
		(layers "In1.Cu" "In3.Cu" "In5.Cu" "In6.Cu" "In7.Cu" "In8.Cu" "In10.Cu"
			"In12.Cu"
		)
		(hatch none 0.5)
		(connect_pads
			(clearance 0)
		)
		(min_thickness 0.25)
		(keepout
			(tracks not_allowed)
			(vias allowed)
			(pads allowed)
			(copperpour not_allowed)
			(footprints allowed)
		)
		(placement
			(enabled no)
			(sheetname "")
		)
		(fill yes
			(thermal_gap 0.5)
			(thermal_bridge_width 0.5)
			(island_removal_mode 0)
		)
		(polygon
			(pts
				(arc
					(start 429.82007 -135.580374)
					(mid 429.05553 -136.344914)
					(end 429.82007 -137.109454)
				)
				(arc
					(start 431.09007 -137.109454)
					(mid 431.629783 -136.886423)
					(end 431.85461 -136.347454)
				)
				(xy 431.666142 -136.347454) (xy 431.666142 -136.344914)
				(arc
					(start 431.85461 -136.344914)
					(mid 431.630681 -135.804303)
					(end 431.09007 -135.580374)
				)
			)
		)
	)
	(zone
		(layers "In1.Cu" "In3.Cu" "In5.Cu" "In6.Cu" "In7.Cu" "In8.Cu" "In10.Cu"
			"In12.Cu"
		)
		(hatch none 0.5)
		(connect_pads
			(clearance 0)
		)
		(min_thickness 0.25)
		(keepout
			(tracks not_allowed)
			(vias allowed)
			(pads allowed)
			(copperpour not_allowed)
			(footprints allowed)
		)
		(placement
			(enabled no)
			(sheetname "")
		)
		(fill yes
			(thermal_gap 0.5)
			(thermal_bridge_width 0.5)
			(island_removal_mode 0)
		)
		(polygon
			(pts
				(arc
					(start 394.671296 -105.832656)
					(mid 394.31341 -106.190923)
					(end 394.67155 -106.548936)
				)
				(arc
					(start 394.829792 -106.548936)
					(mid 394.925934 -106.510591)
					(end 394.969238 -106.416602)
				)
				(arc
					(start 394.969238 -106.416602)
					(mid 395.174344 -106.223154)
					(end 395.364208 -106.431588)
				)
				(arc
					(start 395.364208 -106.431588)
					(mid 395.404397 -106.515143)
					(end 395.4907 -106.548936)
				)
				(arc
					(start 395.66215 -106.548936)
					(mid 395.914494 -106.444936)
					(end 396.02029 -106.193336)
				)
				(arc
					(start 395.92885 -106.193336)
					(mid 395.66215 -106.457508)
					(end 395.39545 -106.193336)
				)
				(arc
					(start 394.93825 -106.193336)
					(mid 394.67155 -106.457508)
					(end 394.40485 -106.193336)
				)
				(arc
					(start 394.40485 -106.190796)
					(mid 394.67155 -105.924096)
					(end 394.93825 -106.190796)
				)
				(arc
					(start 395.39545 -106.190796)
					(mid 395.66215 -105.924096)
					(end 395.92885 -106.190796)
				)
				(arc
					(start 396.02029 -106.190796)
					(mid 395.915393 -105.937553)
					(end 395.66215 -105.832656)
				)
			)
		)
	)
	(zone
		(layers "In1.Cu" "In3.Cu" "In5.Cu" "In6.Cu" "In7.Cu" "In8.Cu" "In10.Cu"
			"In12.Cu"
		)
		(hatch none 0.5)
		(connect_pads
			(clearance 0)
		)
		(min_thickness 0.25)
		(keepout
			(tracks not_allowed)
			(vias allowed)
			(pads allowed)
			(copperpour not_allowed)
			(footprints allowed)
		)
		(placement
			(enabled no)
			(sheetname "")
		)
		(fill yes
			(thermal_gap 0.5)
			(thermal_bridge_width 0.5)
			(island_removal_mode 0)
		)
		(polygon
			(pts
				(arc
					(start 433.63007 -135.580374)
					(mid 432.86553 -136.344914)
					(end 433.63007 -137.109454)
				)
				(arc
					(start 434.90007 -137.109454)
					(mid 435.439783 -136.886423)
					(end 435.66461 -136.347454)
				)
				(xy 435.473856 -136.347454) (xy 435.473856 -136.344914)
				(arc
					(start 435.66461 -136.344914)
					(mid 435.440681 -135.804303)
					(end 434.90007 -135.580374)
				)
			)
		)
	)
	(zone
		(net "GND")
		(layers "In1.Cu" "In3.Cu" "In5.Cu" "In6.Cu" "In7.Cu" "In8.Cu" "In10.Cu"
			"In12.Cu"
		)
		(hatch none 0.5)
		(connect_pads
			(clearance 0.5)
		)
		(min_thickness 0.25)
		(fill yes
			(thermal_gap 0.5)
			(thermal_bridge_width 0.5)
			(island_removal_mode 0)
		)
		(polygon
			(pts
				(arc
					(start -5.184648 -161.9504)
					(mid -5.224047 -162.020639)
					(end -5.237734 -162.100006)
				)
				(arc
					(start -5.237734 -168.099994)
					(mid -5.1681 -168.268104)
					(end -4.99999 -168.337738)
				)
				(xy 501.0404 -168.337738) (xy 501.0404 -161.9504)
			)
		)
	)
	(zone
		(layers "In1.Cu" "In3.Cu" "In5.Cu" "In6.Cu" "In7.Cu" "In8.Cu" "In10.Cu"
			"In12.Cu"
		)
		(hatch none 0.5)
		(connect_pads
			(clearance 0)
		)
		(min_thickness 0.25)
		(keepout
			(tracks not_allowed)
			(vias allowed)
			(pads allowed)
			(copperpour not_allowed)
			(footprints allowed)
		)
		(placement
			(enabled no)
			(sheetname "")
		)
		(fill yes
			(thermal_gap 0.5)
			(thermal_bridge_width 0.5)
			(island_removal_mode 0)
		)
		(polygon
			(pts
				(arc
					(start 397.147796 -104.974136)
					(mid 396.78991 -105.332403)
					(end 397.14805 -105.690416)
				)
				(arc
					(start 397.306292 -105.690416)
					(mid 397.402434 -105.652071)
					(end 397.445738 -105.558082)
				)
				(arc
					(start 397.445738 -105.558082)
					(mid 397.650844 -105.364634)
					(end 397.840708 -105.573068)
				)
				(arc
					(start 397.840708 -105.573068)
					(mid 397.880897 -105.656623)
					(end 397.9672 -105.690416)
				)
				(arc
					(start 398.13865 -105.690416)
					(mid 398.390994 -105.586416)
					(end 398.49679 -105.334816)
				)
				(arc
					(start 398.40535 -105.334816)
					(mid 398.13865 -105.598988)
					(end 397.87195 -105.334816)
				)
				(arc
					(start 397.41475 -105.334816)
					(mid 397.14805 -105.598988)
					(end 396.88135 -105.334816)
				)
				(arc
					(start 396.88135 -105.332276)
					(mid 397.14805 -105.065576)
					(end 397.41475 -105.332276)
				)
				(arc
					(start 397.87195 -105.332276)
					(mid 398.13865 -105.065576)
					(end 398.40535 -105.332276)
				)
				(arc
					(start 398.49679 -105.332276)
					(mid 398.391893 -105.079033)
					(end 398.13865 -104.974136)
				)
			)
		)
	)
	(zone
		(layers "In1.Cu" "In3.Cu" "In5.Cu" "In6.Cu" "In7.Cu" "In8.Cu" "In10.Cu"
			"In12.Cu"
		)
		(hatch none 0.5)
		(connect_pads
			(clearance 0)
		)
		(min_thickness 0.25)
		(keepout
			(tracks not_allowed)
			(vias allowed)
			(pads allowed)
			(copperpour not_allowed)
			(footprints allowed)
		)
		(placement
			(enabled no)
			(sheetname "")
		)
		(fill yes
			(thermal_gap 0.5)
			(thermal_bridge_width 0.5)
			(island_removal_mode 0)
		)
		(polygon
			(pts
				(arc
					(start 398.138396 -103.257096)
					(mid 397.78051 -103.615363)
					(end 398.13865 -103.973376)
				)
				(arc
					(start 398.296892 -103.973376)
					(mid 398.393034 -103.935031)
					(end 398.436338 -103.841042)
				)
				(arc
					(start 398.436338 -103.841042)
					(mid 398.641444 -103.647594)
					(end 398.831308 -103.856028)
				)
				(arc
					(start 398.831308 -103.856028)
					(mid 398.871497 -103.939583)
					(end 398.9578 -103.973376)
				)
				(arc
					(start 399.12925 -103.973376)
					(mid 399.381594 -103.869376)
					(end 399.48739 -103.617776)
				)
				(arc
					(start 399.39595 -103.617776)
					(mid 399.12925 -103.881948)
					(end 398.86255 -103.617776)
				)
				(arc
					(start 398.40535 -103.617776)
					(mid 398.13865 -103.881948)
					(end 397.87195 -103.617776)
				)
				(arc
					(start 397.87195 -103.615236)
					(mid 398.13865 -103.348536)
					(end 398.40535 -103.615236)
				)
				(arc
					(start 398.86255 -103.615236)
					(mid 399.12925 -103.348536)
					(end 399.39595 -103.615236)
				)
				(arc
					(start 399.48739 -103.615236)
					(mid 399.382493 -103.361993)
					(end 399.12925 -103.257096)
				)
			)
		)
	)
	(zone
		(layers "In1.Cu" "In3.Cu" "In5.Cu" "In8.Cu" "In10.Cu" "In12.Cu")
		(hatch none 0.5)
		(connect_pads
			(clearance 0)
		)
		(min_thickness 0.25)
		(keepout
			(tracks not_allowed)
			(vias allowed)
			(pads allowed)
			(copperpour not_allowed)
			(footprints allowed)
		)
		(placement
			(enabled no)
			(sheetname "")
		)
		(fill yes
			(thermal_gap 0.5)
			(thermal_bridge_width 0.5)
			(island_removal_mode 0)
		)
		(polygon
			(pts
				(xy 6.068314 -87.447374) (xy 10.369042 -87.447374) (xy 11.361928 -86.454488) (xy 11.361928 -50.143156)
				(xy 9.981946 -48.763174) (xy 2.834894 -48.763174) (xy 1.802892 -49.795176) (xy 1.802892 -58.587132)
				(xy 0.540512 -59.849512) (xy 0.540512 -67.265296) (xy 2.240534 -68.965318) (xy 2.240534 -86.092792)
				(xy 3.595116 -87.447374) (xy 6.06806 -87.447374) (xy 6.06806 -86.177374) (xy 4.122674 -86.177374)
				(xy 3.50393 -85.55863) (xy 3.50393 -68.436744) (xy 2.29362 -67.22618) (xy 2.29362 -59.890406) (xy 3.072638 -59.111388)
				(xy 3.072638 -50.31994) (xy 3.359658 -50.03292) (xy 9.45896 -50.03292) (xy 10.092944 -50.666904)
				(xy 10.092944 -85.929978) (xy 9.845548 -86.177374) (xy 6.068314 -86.177374)
			)
		)
	)
	(zone
		(layers "In1.Cu" "In5.Cu")
		(hatch none 0.5)
		(connect_pads
			(clearance 0)
		)
		(min_thickness 0.25)
		(keepout
			(tracks not_allowed)
			(vias allowed)
			(pads allowed)
			(copperpour not_allowed)
			(footprints allowed)
		)
		(placement
			(enabled no)
			(sheetname "")
		)
		(fill yes
			(thermal_gap 0.5)
			(thermal_bridge_width 0.5)
			(island_removal_mode 0)
		)
		(polygon
			(pts
				(arc
					(start 445.89065 -136.294114)
					(mid 445.38011 -135.783574)
					(end 444.86957 -136.294114)
				)
				(arc
					(start 444.86957 -136.395714)
					(mid 445.38011 -136.906254)
					(end 445.89065 -136.395714)
				)
				(xy 445.89065 -136.296654) (xy 445.79921 -136.296654)
				(arc
					(start 445.79921 -136.395714)
					(mid 445.38011 -136.814814)
					(end 444.96101 -136.395714)
				)
				(arc
					(start 444.96101 -136.294114)
					(mid 445.38011 -135.875014)
					(end 445.79921 -136.294114)
				)
			)
		)
	)
	(zone
		(layers "In1.Cu" "In5.Cu")
		(hatch none 0.5)
		(connect_pads
			(clearance 0)
		)
		(min_thickness 0.25)
		(keepout
			(tracks not_allowed)
			(vias allowed)
			(pads allowed)
			(copperpour not_allowed)
			(footprints allowed)
		)
		(placement
			(enabled no)
			(sheetname "")
		)
		(fill yes
			(thermal_gap 0.5)
			(thermal_bridge_width 0.5)
			(island_removal_mode 0)
		)
		(polygon
			(pts
				(arc
					(start 444.890652 -136.294114)
					(mid 444.380112 -135.783574)
					(end 443.869572 -136.294114)
				)
				(arc
					(start 443.869572 -136.395714)
					(mid 444.380112 -136.906254)
					(end 444.890652 -136.395714)
				)
				(xy 444.890652 -136.296654) (xy 444.799212 -136.296654)
				(arc
					(start 444.799212 -136.395714)
					(mid 444.380112 -136.814814)
					(end 443.961012 -136.395714)
				)
				(arc
					(start 443.961012 -136.294114)
					(mid 444.380112 -135.875014)
					(end 444.799212 -136.294114)
				)
			)
		)
	)
	(zone
		(layers "In1.Cu" "In5.Cu")
		(hatch none 0.5)
		(connect_pads
			(clearance 0)
		)
		(min_thickness 0.25)
		(keepout
			(tracks not_allowed)
			(vias allowed)
			(pads allowed)
			(copperpour not_allowed)
			(footprints allowed)
		)
		(placement
			(enabled no)
			(sheetname "")
		)
		(fill yes
			(thermal_gap 0.5)
			(thermal_bridge_width 0.5)
			(island_removal_mode 0)
		)
		(polygon
			(pts
				(arc
					(start 432.97221 -136.344914)
					(mid 431.747929 -136.346184)
					(end 432.97221 -136.347454)
				)
				(arc
					(start 432.88077 -136.347454)
					(mid 432.36007 -136.86562)
					(end 431.83937 -136.347454)
				)
				(arc
					(start 431.83937 -136.344914)
					(mid 432.36007 -135.824214)
					(end 432.88077 -136.344914)
				)
			)
		)
	)
	(zone
		(layers "In1.Cu" "In5.Cu")
		(hatch none 0.5)
		(connect_pads
			(clearance 0)
		)
		(min_thickness 0.25)
		(keepout
			(tracks not_allowed)
			(vias allowed)
			(pads allowed)
			(copperpour not_allowed)
			(footprints allowed)
		)
		(placement
			(enabled no)
			(sheetname "")
		)
		(fill yes
			(thermal_gap 0.5)
			(thermal_bridge_width 0.5)
			(island_removal_mode 0)
		)
		(polygon
			(pts
				(arc
					(start 436.78221 -136.344914)
					(mid 435.557929 -136.346184)
					(end 436.78221 -136.347454)
				)
				(arc
					(start 436.69077 -136.347454)
					(mid 436.17007 -136.86562)
					(end 435.64937 -136.347454)
				)
				(arc
					(start 435.64937 -136.344914)
					(mid 436.17007 -135.824214)
					(end 436.69077 -136.344914)
				)
			)
		)
	)
	(zone
		(layers "In1.Cu" "In5.Cu")
		(hatch none 0.5)
		(connect_pads
			(clearance 0)
		)
		(min_thickness 0.25)
		(keepout
			(tracks not_allowed)
			(vias allowed)
			(pads allowed)
			(copperpour not_allowed)
			(footprints allowed)
		)
		(placement
			(enabled no)
			(sheetname "")
		)
		(fill yes
			(thermal_gap 0.5)
			(thermal_bridge_width 0.5)
			(island_removal_mode 0)
		)
		(polygon
			(pts
				(arc
					(start 429.16221 -136.344914)
					(mid 427.937929 -136.346184)
					(end 429.16221 -136.347454)
				)
				(arc
					(start 429.07077 -136.347454)
					(mid 428.55007 -136.86562)
					(end 428.02937 -136.347454)
				)
				(arc
					(start 428.02937 -136.344914)
					(mid 428.55007 -135.824214)
					(end 429.07077 -136.344914)
				)
			)
		)
	)
	(zone
		(layer "In2.Cu")
		(hatch none 0.5)
		(connect_pads
			(clearance 0)
		)
		(min_thickness 0.25)
		(keepout
			(tracks allowed)
			(vias allowed)
			(pads allowed)
			(copperpour allowed)
			(footprints allowed)
		)
		(placement
			(enabled no)
			(sheetname "")
		)
		(fill
			(thermal_gap 0.5)
			(thermal_bridge_width 0.5)
			(island_removal_mode 0)
		)
		(polygon
			(pts
				(xy 128.242568 -101.727) (xy 127.607568 -102.362) (xy 125.575568 -102.362) (xy 124.178568 -103.759)
				(xy 122.908568 -103.759) (xy 122.019568 -104.648) (xy 122.019568 -106.299) (xy 122.273568 -106.553)
				(xy 123.416568 -106.553) (xy 124.686568 -107.823) (xy 125.321568 -107.823) (xy 126.591568 -106.553)
				(xy 130.147568 -106.553) (xy 130.147568 -105.918) (xy 132.560568 -105.918) (xy 132.560568 -103.124)
				(xy 130.147568 -103.124) (xy 130.147568 -102.362) (xy 129.512568 -101.727) (xy 128.623568 -101.727)
			)
		)
	)
	(zone
		(net "P1V8_MCP_CPU1")
		(layer "In2.Cu")
		(hatch none 0.5)
		(connect_pads
			(clearance 0.5)
		)
		(min_thickness 0.25)
		(fill yes
			(thermal_gap 0.5)
			(thermal_bridge_width 0.5)
			(island_removal_mode 0)
		)
		(polygon
			(pts
				(xy 167.513 -35.433) (xy 167.513 -41.5798) (xy 164.846 -44.2468) (xy 163.6268 -44.2468) (xy 163.3855 -44.4881)
				(xy 163.3855 -45.9105) (xy 161.544 -47.752) (xy 161.544 -47.92726) (xy 160.4391 -49.03216) (xy 155.1305 -49.03216)
				(xy 150.80742 -53.35524) (xy 150.80742 -71.0057) (xy 149.04212 -72.771) (xy 139.319 -72.771) (xy 129.921 -76.2)
				(xy 122.936 -80.264) (xy 121.412 -80.264) (xy 121.285 -80.264) (xy 120.5992 -80.9498) (xy 119.2276 -80.9498)
				(xy 119.0498 -80.772) (xy 119.0498 -80.0354) (xy 118.8974 -79.883) (xy 118.8974 -77.47) (xy 119.1006 -77.2668)
				(xy 120.5992 -77.2668) (xy 120.777 -77.089) (xy 121.158 -76.708) (xy 129.921 -74.295) (xy 134.874 -71.882)
				(xy 138.811 -70.739) (xy 142.494 -69.342) (xy 144.3482 -69.342) (xy 146.91868 -66.77152) (xy 146.91868 -52.324)
				(xy 151.50338 -47.7393) (xy 151.50338 -46.41342) (xy 159.004 -38.9128) (xy 159.004 -36.1823) (xy 160.1343 -35.052)
				(xy 164.465 -35.052) (xy 167.132 -35.052)
			)
		)
	)
	(zone
		(layer "In2.Cu")
		(hatch none 0.5)
		(connect_pads
			(clearance 0)
		)
		(min_thickness 0.25)
		(keepout
			(tracks not_allowed)
			(vias allowed)
			(pads allowed)
			(copperpour not_allowed)
			(footprints allowed)
		)
		(placement
			(enabled no)
			(sheetname "")
		)
		(fill
			(thermal_gap 0.5)
			(thermal_bridge_width 0.5)
			(island_removal_mode 0)
		)
		(polygon
			(pts
				(xy 424.17365 -1.967484) (xy 424.17365 -1.710944) (xy 424.3705 -1.514094)
				(arc
					(start 424.425364 -1.514094)
					(mid 424.949345 -1.583151)
					(end 424.425872 -1.656334)
				)
				(xy 424.31335 -1.768856) (xy 424.31335 -1.967484)
				(arc
					(start 424.682666 -1.967484)
					(mid 425.066206 -1.583944)
					(end 424.682666 -1.200404)
				)
				(arc
					(start 423.41292 -1.200404)
					(mid 423.02938 -1.583817)
					(end 423.412666 -1.967484)
				)
				(xy 423.88155 -1.967484) (xy 423.88155 -1.756156) (xy 423.779188 -1.653794)
				(arc
					(start 423.669968 -1.653794)
					(mid 423.146051 -1.583944)
					(end 423.669968 -1.514094)
				)
				(xy 423.8371 -1.514094) (xy 424.02125 -1.698244) (xy 424.02125 -1.967484)
			)
		)
	)
	(zone
		(layer "In2.Cu")
		(hatch none 0.5)
		(connect_pads
			(clearance 0)
		)
		(min_thickness 0.25)
		(keepout
			(tracks not_allowed)
			(vias allowed)
			(pads allowed)
			(copperpour not_allowed)
			(footprints allowed)
		)
		(placement
			(enabled no)
			(sheetname "")
		)
		(fill
			(thermal_gap 0.5)
			(thermal_bridge_width 0.5)
			(island_removal_mode 0)
		)
		(polygon
			(pts
				(arc
					(start 378.485654 -131.699)
					(mid 378.1044 -132.079873)
					(end 378.4854 -132.461)
				)
				(xy 378.59335 -132.461)
				(arc
					(start 378.59335 -132.32384)
					(mid 378.310175 -131.878985)
					(end 378.712222 -132.220208)
				)
				(arc
					(start 378.712222 -132.220208)
					(mid 378.723271 -132.246061)
					(end 378.730256 -132.273294)
				)
				(xy 378.73305 -132.276088) (xy 378.73305 -132.461) (xy 378.88545 -132.461) (xy 378.88545 -132.288788)
				(arc
					(start 378.888244 -132.285994)
					(mid 378.898599 -132.249503)
					(end 378.916184 -132.21589)
				)
				(arc
					(start 378.916184 -132.21589)
					(mid 379.327692 -131.8849)
					(end 379.02515 -132.317744)
				)
				(xy 379.02515 -132.461)
				(arc
					(start 379.1458 -132.461)
					(mid 379.5268 -132.08)
					(end 379.1458 -131.699)
				)
			)
		)
	)
	(zone
		(layer "In2.Cu")
		(hatch none 0.5)
		(connect_pads
			(clearance 0)
		)
		(min_thickness 0.25)
		(keepout
			(tracks allowed)
			(vias allowed)
			(pads allowed)
			(copperpour allowed)
			(footprints allowed)
		)
		(placement
			(enabled no)
			(sheetname "")
		)
		(fill
			(thermal_gap 0.5)
			(thermal_bridge_width 0.5)
			(island_removal_mode 0)
		)
		(polygon
			(pts
				(xy 67.028568 -90.424) (xy 80.617568 -90.424) (xy 82.649568 -88.392) (xy 84.935568 -88.392) (xy 85.951568 -89.408)
				(xy 85.951568 -94.742) (xy 85.951568 -100.457) (xy 85.316568 -101.092) (xy 85.316568 -105.283) (xy 67.155568 -105.283)
				(xy 64.234568 -102.362) (xy 64.234568 -94.869) (xy 66.012568 -93.091) (xy 66.266568 -93.091) (xy 66.266568 -91.567)
				(xy 66.774568 -91.059) (xy 66.774568 -90.678)
			)
		)
	)
	(zone
		(layer "In2.Cu")
		(hatch none 0.5)
		(connect_pads
			(clearance 0)
		)
		(min_thickness 0.25)
		(keepout
			(tracks not_allowed)
			(vias allowed)
			(pads allowed)
			(copperpour not_allowed)
			(footprints allowed)
		)
		(placement
			(enabled no)
			(sheetname "")
		)
		(fill
			(thermal_gap 0.5)
			(thermal_bridge_width 0.5)
			(island_removal_mode 0)
		)
		(polygon
			(pts
				(arc
					(start 419.844982 -147.24507)
					(mid 419.793814 -147.343508)
					(end 419.695376 -147.394676)
				)
				(xy 419.692582 -147.39747) (xy 419.430454 -147.39747)
				(arc
					(start 419.428676 -147.395438)
					(mid 419.41143 -147.392956)
					(end 419.394386 -147.389342)
				)
				(xy 419.394386 -147.54479) (xy 419.41623 -147.547584) (xy 419.45179 -147.55114) (xy 419.452806 -147.551394)
				(xy 419.480746 -147.554188)
				(arc
					(start 419.483032 -147.556982)
					(mid 419.51237 -147.5679)
					(end 419.53942 -147.583652)
				)
				(xy 419.543484 -147.583652)
				(arc
					(start 419.645338 -147.685506)
					(mid 419.966503 -148.105477)
					(end 419.546532 -147.784312)
				)
				(arc
					(start 419.465252 -147.703032)
					(mid 419.452995 -147.694433)
					(end 419.438582 -147.690332)
				)
				(xy 419.405308 -147.68703) (xy 419.402006 -147.686522) (xy 419.394386 -147.68576)
				(arc
					(start 419.394386 -147.916646)
					(mid 419.777799 -148.30044)
					(end 420.161466 -147.9169)
				)
				(arc
					(start 420.161466 -146.9009)
					(mid 419.777926 -146.51736)
					(end 419.394386 -146.9009)
				)
				(arc
					(start 419.394386 -147.239482)
					(mid 419.419809 -147.251236)
					(end 419.447218 -147.257008)
				)
				(xy 419.447726 -147.257008) (xy 419.459664 -147.25777)
				(arc
					(start 419.663626 -147.25777)
					(mid 419.695057 -147.244751)
					(end 419.708076 -147.21332)
				)
				(arc
					(start 419.708076 -147.158202)
					(mid 419.777926 -146.634285)
					(end 419.847776 -147.158202)
				)
				(xy 419.847776 -147.242276)
			)
		)
	)
	(zone
		(layer "In2.Cu")
		(hatch none 0.5)
		(connect_pads
			(clearance 0)
		)
		(min_thickness 0.25)
		(keepout
			(tracks not_allowed)
			(vias allowed)
			(pads allowed)
			(copperpour not_allowed)
			(footprints allowed)
		)
		(placement
			(enabled no)
			(sheetname "")
		)
		(fill
			(thermal_gap 0.5)
			(thermal_bridge_width 0.5)
			(island_removal_mode 0)
		)
		(polygon
			(pts
				(xy 428.60468 -2.6543) (xy 428.789846 -2.839466) (xy 428.789846 -3.10769) (xy 428.942246 -3.10769)
				(xy 428.942246 -2.82829) (xy 429.116236 -2.6543)
				(arc
					(start 429.24349 -2.6543)
					(mid 429.767407 -2.72415)
					(end 429.24349 -2.794)
				)
				(xy 429.174148 -2.794) (xy 429.081946 -2.886202) (xy 429.081946 -3.10769)
				(arc
					(start 429.500538 -3.10769)
					(mid 429.884332 -2.724277)
					(end 429.500792 -2.34061)
				)
				(arc
					(start 428.230792 -2.34061)
					(mid 427.847252 -2.72415)
					(end 428.230792 -3.10769)
				)
				(xy 428.650146 -3.10769) (xy 428.650146 -2.897378) (xy 428.546768 -2.794)
				(arc
					(start 428.488094 -2.794)
					(mid 427.964177 -2.72415)
					(end 428.488094 -2.6543)
				)
			)
		)
	)
	(zone
		(layer "In2.Cu")
		(hatch none 0.5)
		(connect_pads
			(clearance 0)
		)
		(min_thickness 0.25)
		(keepout
			(tracks allowed)
			(vias allowed)
			(pads allowed)
			(copperpour allowed)
			(footprints allowed)
		)
		(placement
			(enabled no)
			(sheetname "")
		)
		(fill
			(thermal_gap 0.5)
			(thermal_bridge_width 0.5)
			(island_removal_mode 0)
		)
		(polygon
			(pts
				(xy 179.197 -71.628) (xy 179.197 -68.58) (xy 182.88 -68.58) (xy 182.88 -71.628)
			)
		)
	)
	(zone
		(net "GND")
		(layer "In2.Cu")
		(hatch none 0.5)
		(connect_pads
			(clearance 0.5)
		)
		(min_thickness 0.25)
		(fill yes
			(thermal_gap 0.5)
			(thermal_bridge_width 0.5)
			(island_removal_mode 0)
		)
		(polygon
			(pts
				(xy -5.03174 15.24) (xy -5.03174 8.763) (xy 413.4358 8.763) (xy 501.2182 8.763) (xy 501.2182 8.7884)
				(xy 501.2182 15.24)
			)
		)
		(polygon
			(pts
				(xy 189.6618 14.5288) (xy 122.301 14.5288) (xy 122.301 9.4742) (xy 189.6618 9.4742) (xy 189.6618 9.4996)
				(xy 192.5066 9.4996) (xy 198.934578 9.4996) (xy 198.934578 14.5034) (xy 198.934578 14.5288)
			)
		)
		(polygon
			(pts
				(xy 100.1776 14.61262) (xy 14.224 14.61262) (xy 14.224 9.4742) (xy 36.957 9.4742) (xy 36.957 9.9187)
				(xy 100.838 9.9187) (xy 100.838 9.9314) (xy 103.505 9.9314) (xy 114.39652 9.9314) (xy 114.39652 14.605)
				(xy 103.505 14.605) (xy 101.0158 14.605) (xy 100.1776 14.605)
			)
		)
		(polygon
			(pts
				(xy 273.4818 14.5034) (xy 206.629 14.5034) (xy 206.629 9.4234) (xy 273.4818 9.4234) (xy 283.28239 9.4234)
				(xy 283.28239 9.4488) (xy 283.28239 14.5034) (xy 276.5552 14.5034)
			)
		)
	)
	(zone
		(layer "In2.Cu")
		(hatch none 0.5)
		(connect_pads
			(clearance 0)
		)
		(min_thickness 0.25)
		(keepout
			(tracks not_allowed)
			(vias allowed)
			(pads allowed)
			(copperpour not_allowed)
			(footprints allowed)
		)
		(placement
			(enabled no)
			(sheetname "")
		)
		(fill
			(thermal_gap 0.5)
			(thermal_bridge_width 0.5)
			(island_removal_mode 0)
		)
		(polygon
			(pts
				(xy 384.40741 -34.889186)
				(arc
					(start 384.40741 -34.974022)
					(mid 384.418161 -34.943409)
					(end 384.432556 -34.914332)
				)
			)
		)
	)
	(zone
		(net "GND")
		(layer "In2.Cu")
		(hatch none 0.5)
		(connect_pads
			(clearance 0.5)
		)
		(min_thickness 0.25)
		(fill yes
			(thermal_gap 0.5)
			(thermal_bridge_width 0.5)
			(island_removal_mode 0)
		)
		(polygon
			(pts
				(xy 199.4154 -93.711776) (xy 199.4154 -94.62516) (xy 199.4154 -101.797612) (xy 199.751188 -102.1334)
				(xy 200.500996 -102.1334) (xy 200.8886 -101.745796) (xy 206.561436 -101.745796) (xy 207.899 -100.407978)
				(xy 207.899 -93.73235) (xy 207.705706 -93.539056) (xy 199.58812 -93.539056)
			)
		)
	)
	(zone
		(net "PVCCIO_CPU0")
		(layer "In2.Cu")
		(hatch none 0.5)
		(connect_pads
			(clearance 0.5)
		)
		(min_thickness 0.25)
		(fill yes
			(thermal_gap 0.5)
			(thermal_bridge_width 0.5)
			(island_removal_mode 0)
		)
		(polygon
			(pts
				(xy 274.5994 -63.881) (xy 274.5994 -61.341) (xy 274.63877 -61.30163) (xy 274.63877 -59.77509) (xy 275.76526 -58.6486)
				(xy 288.7726 -58.6486) (xy 289.9918 -57.4294) (xy 289.9918 -56.8452) (xy 293.0398 -53.7972) (xy 301.1932 -53.7972)
				(xy 302.6664 -52.324) (xy 305.4858 -52.324) (xy 307.7718 -54.61) (xy 307.7718 -65.024) (xy 306.7685 -66.0273)
				(xy 299.50918 -66.0273) (xy 299.50918 -65.34404) (xy 297.55592 -63.39078) (xy 296.350944 -63.39078)
				(xy 296.114216 -63.154052) (xy 295.533064 -63.154052) (xy 295.296336 -63.39078) (xy 294.164512 -63.39078)
				(xy 292.625272 -64.93002) (xy 291.5158 -64.93002) (xy 291.20338 -65.24244) (xy 289.97656 -65.24244)
				(xy 286.5882 -68.6308) (xy 283.5402 -68.6308) (xy 281.1018 -68.6308) (xy 278.3586 -65.8876) (xy 276.606 -65.8876)
			)
		)
	)
	(zone
		(layer "In2.Cu")
		(hatch none 0.5)
		(connect_pads
			(clearance 0)
		)
		(min_thickness 0.25)
		(keepout
			(tracks not_allowed)
			(vias allowed)
			(pads allowed)
			(copperpour not_allowed)
			(footprints allowed)
		)
		(placement
			(enabled no)
			(sheetname "")
		)
		(fill
			(thermal_gap 0.5)
			(thermal_bridge_width 0.5)
			(island_removal_mode 0)
		)
		(polygon
			(pts
				(xy 417.647628 -92.930472) (xy 417.647628 -91.52509) (xy 419.052756 -91.52509) (xy 419.052756 -92.930472)
			)
		)
	)
	(zone
		(layer "In2.Cu")
		(hatch none 0.5)
		(connect_pads
			(clearance 0)
		)
		(min_thickness 0.25)
		(keepout
			(tracks not_allowed)
			(vias allowed)
			(pads allowed)
			(copperpour not_allowed)
			(footprints allowed)
		)
		(placement
			(enabled no)
			(sheetname "")
		)
		(fill
			(thermal_gap 0.5)
			(thermal_bridge_width 0.5)
			(island_removal_mode 0)
		)
		(polygon
			(pts
				(arc
					(start 413.157416 -141.021054)
					(mid 412.774003 -140.63726)
					(end 412.390336 -141.0208)
				)
				(xy 412.390336 -141.327378)
				(arc
					(start 412.659576 -141.327378)
					(mid 412.691007 -141.314359)
					(end 412.704026 -141.282928)
				)
				(arc
					(start 412.704026 -141.278102)
					(mid 412.773876 -140.754185)
					(end 412.843726 -141.278102)
				)
				(xy 412.843726 -141.311884)
				(arc
					(start 412.840932 -141.314678)
					(mid 412.789764 -141.413116)
					(end 412.691326 -141.464284)
				)
				(xy 412.688532 -141.467078) (xy 412.390336 -141.467078) (xy 412.390336 -141.619478) (xy 412.688532 -141.619478)
				(arc
					(start 412.691326 -141.622272)
					(mid 412.789764 -141.67344)
					(end 412.840932 -141.771878)
				)
				(xy 412.843726 -141.774672)
				(arc
					(start 412.843726 -141.779498)
					(mid 412.776518 -142.303466)
					(end 412.69793 -141.781022)
				)
				(arc
					(start 412.69793 -141.781022)
					(mid 412.681632 -141.76506)
					(end 412.659576 -141.759178)
				)
				(xy 412.390336 -141.759178)
				(arc
					(start 412.390336 -142.0368)
					(mid 412.773876 -142.42034)
					(end 413.157416 -142.0368)
				)
			)
		)
	)
	(zone
		(net "GND")
		(layer "In2.Cu")
		(hatch none 0.5)
		(connect_pads
			(clearance 0.5)
		)
		(min_thickness 0.25)
		(fill yes
			(thermal_gap 0.5)
			(thermal_bridge_width 0.5)
			(island_removal_mode 0)
		)
		(polygon
			(pts
				(xy -5.300472 -62.36081) (xy -3.537458 -62.36081) (xy -3.326638 -62.57163) (xy -3.326638 -67.01409)
				(xy -3.4925 -67.179952) (xy -5.323078 -67.179952) (xy -5.486146 -67.016884) (xy -5.486146 -62.546484)
			)
		)
	)
	(zone
		(layer "In2.Cu")
		(hatch none 0.5)
		(connect_pads
			(clearance 0)
		)
		(min_thickness 0.25)
		(keepout
			(tracks not_allowed)
			(vias allowed)
			(pads allowed)
			(copperpour not_allowed)
			(footprints allowed)
		)
		(placement
			(enabled no)
			(sheetname "")
		)
		(fill
			(thermal_gap 0.5)
			(thermal_bridge_width 0.5)
			(island_removal_mode 0)
		)
		(polygon
			(pts
				(xy 417.444428 -9.953498) (xy 417.599622 -10.108692) (xy 417.599622 -10.406888) (xy 417.752022 -10.406888)
				(xy 417.752022 -10.108692) (xy 417.907216 -9.953498)
				(arc
					(start 418.04209 -9.953498)
					(mid 418.566007 -10.023348)
					(end 418.04209 -10.093198)
				)
				(xy 417.965128 -10.093198) (xy 417.891722 -10.166604) (xy 417.891722 -10.406888)
				(arc
					(start 418.299138 -10.406888)
					(mid 418.682932 -10.023475)
					(end 418.299392 -9.639808)
				)
				(arc
					(start 417.029392 -9.639808)
					(mid 416.645852 -10.023348)
					(end 417.029392 -10.406888)
				)
				(xy 417.459922 -10.406888) (xy 417.459922 -10.166604) (xy 417.386516 -10.093198)
				(arc
					(start 417.286694 -10.093198)
					(mid 416.762777 -10.023348)
					(end 417.286694 -9.953498)
				)
			)
		)
	)
	(zone
		(net "P5V_STBY")
		(layer "In2.Cu")
		(hatch none 0.5)
		(connect_pads
			(clearance 0.5)
		)
		(min_thickness 0.25)
		(fill yes
			(thermal_gap 0.5)
			(thermal_bridge_width 0.5)
			(island_removal_mode 0)
		)
		(polygon
			(pts
				(xy 357.39451 -2.4384) (xy 356.699312 -3.133598) (xy 355.677724 -3.133598) (xy 355.4222 -3.389122)
				(xy 355.4222 -4.924552) (xy 355.628448 -5.1308) (xy 356.0318 -5.1308) (xy 369.7986 -5.1308) (xy 372.4402 -2.4892)
				(xy 372.4402 -0.7366) (xy 372.4402 1.27) (xy 373.888 2.7178) (xy 381.1524 2.7178) (xy 381.635 2.2352)
				(xy 393.6492 2.2352) (xy 393.8016 2.2352) (xy 394.081 2.5146) (xy 394.081 5.0292) (xy 393.5857 5.5245)
				(xy 393.2047 5.5245) (xy 392.96975 5.5245) (xy 379.1839 5.5245) (xy 379.165866 5.542534) (xy 365.313468 5.542534)
				(xy 364.72241 4.951476) (xy 364.72241 1.660906) (xy 364.635542 0.931164) (xy 364.357412 0.140208)
				(xy 364.00105 -0.47244) (xy 363.396276 -1.049528) (xy 363.310932 -1.15443) (xy 363.292136 -1.173988)
				(xy 362.723684 -1.628394) (xy 362.032804 -1.94564) (xy 361.167934 -2.201926) (xy 360.331004 -2.203196)
				(xy 357.629714 -2.203196)
			)
		)
	)
	(zone
		(layer "In2.Cu")
		(hatch none 0.5)
		(connect_pads
			(clearance 0)
		)
		(min_thickness 0.25)
		(keepout
			(tracks allowed)
			(vias allowed)
			(pads allowed)
			(copperpour allowed)
			(footprints allowed)
		)
		(placement
			(enabled no)
			(sheetname "")
		)
		(fill
			(thermal_gap 0.5)
			(thermal_bridge_width 0.5)
			(island_removal_mode 0)
		)
		(polygon
			(pts
				(xy 205.232 -52.451) (xy 205.232 -50.546) (xy 208.28 -50.546) (xy 208.28 -52.451)
			)
		)
	)
	(zone
		(layer "In2.Cu")
		(hatch none 0.5)
		(connect_pads
			(clearance 0)
		)
		(min_thickness 0.25)
		(keepout
			(tracks not_allowed)
			(vias allowed)
			(pads allowed)
			(copperpour not_allowed)
			(footprints allowed)
		)
		(placement
			(enabled no)
			(sheetname "")
		)
		(fill
			(thermal_gap 0.5)
			(thermal_bridge_width 0.5)
			(island_removal_mode 0)
		)
		(polygon
			(pts
				(xy 406.596342 -96.824546) (xy 406.596342 -95.375984) (xy 408.018234 -95.375984) (xy 408.018234 -96.824546)
			)
		)
	)
	(zone
		(layer "In2.Cu")
		(hatch none 0.5)
		(connect_pads
			(clearance 0)
		)
		(min_thickness 0.25)
		(keepout
			(tracks allowed)
			(vias allowed)
			(pads allowed)
			(copperpour allowed)
			(footprints allowed)
		)
		(placement
			(enabled no)
			(sheetname "")
		)
		(fill
			(thermal_gap 0.5)
			(thermal_bridge_width 0.5)
			(island_removal_mode 0)
		)
		(polygon
			(pts
				(xy 119.327168 -53.9496) (xy 121.130568 -53.9496) (xy 121.714768 -53.3654) (xy 123.594368 -53.3654)
				(xy 123.721368 -53.4924) (xy 123.721368 -54.0766) (xy 123.568968 -54.229) (xy 123.568968 -55.3974)
				(xy 124.254768 -55.3974) (xy 124.407168 -55.5498) (xy 124.407168 -55.9054) (xy 124.127768 -56.1848)
				(xy 124.127768 -56.5404) (xy 124.724668 -57.1373) (xy 124.724668 -57.3659) (xy 123.594368 -58.4962)
				(xy 121.689368 -58.4962) (xy 119.327168 -56.134)
			)
		)
	)
	(zone
		(layer "In2.Cu")
		(hatch none 0.5)
		(connect_pads
			(clearance 0)
		)
		(min_thickness 0.25)
		(keepout
			(tracks not_allowed)
			(vias allowed)
			(pads allowed)
			(copperpour not_allowed)
			(footprints allowed)
		)
		(placement
			(enabled no)
			(sheetname "")
		)
		(fill
			(thermal_gap 0.5)
			(thermal_bridge_width 0.5)
			(island_removal_mode 0)
		)
		(polygon
			(pts
				(arc
					(start 335.622646 -71.946008)
					(mid 336.042617 -71.624843)
					(end 335.721452 -72.044814)
				)
				(xy 335.57845 -72.187816) (xy 335.57845 -72.19696)
				(arc
					(start 335.853786 -72.19696)
					(mid 336.23758 -71.813547)
					(end 335.85404 -71.42988)
				)
				(arc
					(start 334.962754 -71.42988)
					(mid 334.579214 -71.81342)
					(end 334.962754 -72.19696)
				)
				(xy 335.14665 -72.19696) (xy 335.14665 -72.096122)
				(arc
					(start 335.095342 -72.044814)
					(mid 334.774177 -71.624843)
					(end 335.194148 -71.946008)
				)
				(xy 335.28635 -72.03821) (xy 335.28635 -72.19696) (xy 335.43875 -72.19696) (xy 335.43875 -72.129904)
			)
		)
	)
	(zone
		(net "VR_FET_SW_P12V_STBY_PVPP_ABC")
		(layer "In2.Cu")
		(hatch none 0.5)
		(connect_pads
			(clearance 0.5)
		)
		(min_thickness 0.25)
		(fill yes
			(thermal_gap 0.5)
			(thermal_bridge_width 0.5)
			(island_removal_mode 0)
		)
		(polygon
			(pts
				(xy 342.6206 -26.797) (xy 341.5284 -26.797) (xy 341.3506 -26.6192) (xy 341.3506 -26.4668) (xy 341.5284 -26.289)
				(xy 342.011 -26.289) (xy 343.0016 -25.2984) (xy 348.488 -25.2984) (xy 348.6404 -25.4508) (xy 348.6404 -25.8826)
				(xy 348.5134 -26.0096) (xy 343.408 -26.0096)
			)
		)
	)
	(zone
		(layer "In2.Cu")
		(hatch none 0.5)
		(connect_pads
			(clearance 0)
		)
		(min_thickness 0.25)
		(keepout
			(tracks not_allowed)
			(vias allowed)
			(pads allowed)
			(copperpour not_allowed)
			(footprints allowed)
		)
		(placement
			(enabled no)
			(sheetname "")
		)
		(fill
			(thermal_gap 0.5)
			(thermal_bridge_width 0.5)
			(island_removal_mode 0)
		)
		(polygon
			(pts
				(xy 382.9939 -147.7391) (xy 382.9939 -144.8689) (xy 386.6769 -144.8689) (xy 386.6769 -147.7391)
			)
		)
	)
	(zone
		(net "P3V3_STBY")
		(layer "In2.Cu")
		(hatch none 0.5)
		(connect_pads
			(clearance 0.5)
		)
		(min_thickness 0.25)
		(fill yes
			(thermal_gap 0.5)
			(thermal_bridge_width 0.5)
			(island_removal_mode 0)
		)
		(polygon
			(pts
				(arc
					(start 393.822428 -103.574342)
					(mid 393.797283 -103.495314)
					(end 393.72159 -103.461312)
				)
				(xy 388.719568 -103.461312) (xy 388.648448 -103.389938) (xy 388.559548 -103.301038) (xy 388.492746 -103.368094)
				(arc
					(start 388.518654 -103.403146)
					(mid 388.583955 -103.673247)
					(end 388.435342 -103.908098)
				)
				(arc
					(start 388.435342 -103.908098)
					(mid 388.392508 -103.977203)
					(end 388.414006 -104.055672)
				)
				(arc
					(start 388.414006 -104.055672)
					(mid 388.486853 -104.347389)
					(end 388.310374 -104.59085)
				)
				(arc
					(start 388.310374 -104.59085)
					(mid 388.258007 -104.67975)
					(end 388.310374 -104.76865)
				)
				(arc
					(start 388.310374 -104.76865)
					(mid 388.34033 -105.372296)
					(end 387.785356 -105.132886)
				)
				(arc
					(start 387.785356 -105.132886)
					(mid 387.736732 -105.089451)
					(end 387.68528 -105.129584)
				)
				(arc
					(start 387.68528 -105.129584)
					(mid 387.671805 -105.176579)
					(end 387.652006 -105.221278)
				)
				(xy 387.63448 -105.254552) (xy 387.68528 -105.305352) (xy 387.68528 -105.72623) (xy 387.68782 -105.741978)
				(arc
					(start 387.68909 -105.745534)
					(mid 387.706086 -105.852519)
					(end 387.690106 -105.959656)
				)
				(xy 387.68782 -105.966768) (xy 387.68528 -105.974896) (xy 387.68528 -106.093006) (xy 387.96976 -106.377486)
				(xy 387.96976 -109.898434)
				(arc
					(start 388.510018 -110.438692)
					(mid 388.587205 -110.468328)
					(end 388.660894 -110.430818)
				)
				(arc
					(start 388.660894 -110.430818)
					(mid 388.968431 -110.300337)
					(end 389.24865 -110.482126)
				)
				(arc
					(start 389.24865 -110.482126)
					(mid 389.33755 -110.534493)
					(end 389.42645 -110.482126)
				)
				(arc
					(start 389.42645 -110.482126)
					(mid 389.7376 -110.299102)
					(end 390.04875 -110.482126)
				)
				(arc
					(start 390.04875 -110.482126)
					(mid 390.13765 -110.534493)
					(end 390.22655 -110.482126)
				)
				(arc
					(start 390.22655 -110.482126)
					(mid 390.5377 -110.299102)
					(end 390.84885 -110.482126)
				)
				(arc
					(start 390.84885 -110.482126)
					(mid 390.93775 -110.534493)
					(end 391.02665 -110.482126)
				)
				(arc
					(start 391.02665 -110.482126)
					(mid 391.589528 -110.403372)
					(end 391.510774 -110.96625)
				)
				(arc
					(start 391.510774 -110.96625)
					(mid 391.458407 -111.05515)
					(end 391.510774 -111.14405)
				)
				(arc
					(start 391.510774 -111.14405)
					(mid 391.689339 -111.399033)
					(end 391.599166 -111.697008)
				)
				(arc
					(start 391.599166 -112.013492)
					(mid 391.626111 -112.046423)
					(end 391.64895 -112.082326)
				)
				(arc
					(start 391.64895 -112.082326)
					(mid 391.73785 -112.134693)
					(end 391.82675 -112.082326)
				)
				(arc
					(start 391.82675 -112.082326)
					(mid 391.890242 -111.999421)
					(end 391.975086 -111.938562)
				)
				(arc
					(start 391.975086 -111.938562)
					(mid 392.030224 -111.851385)
					(end 391.980674 -111.761016)
				)
				(arc
					(start 391.980674 -111.761016)
					(mid 392.174613 -111.099184)
					(end 392.326114 -111.771938)
				)
				(arc
					(start 392.326114 -111.771938)
					(mid 392.270976 -111.859115)
					(end 392.320526 -111.949484)
				)
				(arc
					(start 392.320526 -111.949484)
					(mid 392.385839 -112.511038)
					(end 391.82675 -112.428274)
				)
				(arc
					(start 391.82675 -112.428274)
					(mid 391.73785 -112.375907)
					(end 391.64895 -112.428274)
				)
				(arc
					(start 391.64895 -112.428274)
					(mid 391.626124 -112.464186)
					(end 391.599166 -112.497108)
				)
				(arc
					(start 391.599166 -112.813592)
					(mid 391.693866 -113.0554)
					(end 391.599166 -113.297208)
				)
				(arc
					(start 391.599166 -113.613692)
					(mid 391.693866 -113.8555)
					(end 391.599166 -114.097308)
				)
				(arc
					(start 391.599166 -114.413792)
					(mid 391.693866 -114.6556)
					(end 391.599166 -114.897408)
				)
				(xy 391.599166 -115.05946) (xy 391.873232 -115.333526) (xy 393.163298 -115.333526) (xy 393.33805 -115.158774)
				(arc
					(start 393.341606 -115.146074)
					(mid 393.432389 -114.991493)
					(end 393.58697 -114.90071)
				)
				(xy 393.59967 -114.897154) (xy 393.895834 -114.60099)
				(arc
					(start 393.874498 -114.5667)
					(mid 393.820426 -114.390185)
					(end 393.862052 -114.210338)
				)
				(arc
					(start 393.862052 -114.210338)
					(mid 393.867343 -114.179352)
					(end 393.853416 -114.151156)
				)
				(arc
					(start 393.853416 -114.151156)
					(mid 393.815185 -114.090786)
					(end 393.804902 -114.020092)
				)
				(arc
					(start 393.804902 -114.020092)
					(mid 393.748586 -113.975666)
					(end 393.71524 -113.912142)
				)
				(arc
					(start 393.71524 -113.912142)
					(mid 393.697788 -113.885926)
					(end 393.66825 -113.875058)
				)
				(arc
					(start 393.66825 -113.875058)
					(mid 393.432327 -113.264293)
					(end 394.037058 -113.515394)
				)
				(arc
					(start 394.037058 -113.515394)
					(mid 394.068812 -113.587919)
					(end 394.142976 -113.615724)
				)
				(arc
					(start 394.142976 -113.615724)
					(mid 394.357464 -113.636838)
					(end 394.557504 -113.71707)
				)
				(arc
					(start 394.557504 -113.71707)
					(mid 394.67155 -113.747584)
					(end 394.785596 -113.71707)
				)
				(arc
					(start 394.785596 -113.71707)
					(mid 394.867162 -113.637074)
					(end 394.899896 -113.527586)
				)
				(xy 394.899896 -113.497614)
				(arc
					(start 394.899896 -113.491264)
					(mid 394.917062 -113.355937)
					(end 394.958062 -113.225834)
				)
				(arc
					(start 394.958062 -113.225834)
					(mid 394.986019 -113.166098)
					(end 395.019022 -113.108994)
				)
				(arc
					(start 395.019022 -113.108994)
					(mid 395.032196 -113.030859)
					(end 394.98524 -112.967008)
				)
				(arc
					(start 394.98524 -112.967008)
					(mid 394.858371 -112.482759)
					(end 395.341094 -112.350042)
				)
				(arc
					(start 395.341094 -112.350042)
					(mid 395.419703 -112.358688)
					(end 395.480794 -112.308386)
				)
				(arc
					(start 395.480794 -112.308386)
					(mid 395.496918 -112.27906)
					(end 395.514322 -112.250474)
				)
				(arc
					(start 395.514322 -112.250474)
					(mid 395.527496 -112.172339)
					(end 395.48054 -112.108488)
				)
				(arc
					(start 395.48054 -112.108488)
					(mid 395.306037 -111.802164)
					(end 395.48054 -111.49584)
				)
				(arc
					(start 395.48054 -111.49584)
					(mid 395.526962 -111.434325)
					(end 395.516862 -111.357918)
				)
				(xy 395.498574 -111.3282) (xy 395.482826 -111.300006)
				(arc
					(start 395.480794 -111.295942)
					(mid 395.41965 -111.245352)
					(end 395.34084 -111.254286)
				)
				(arc
					(start 395.34084 -111.254286)
					(mid 394.813127 -110.984276)
					(end 395.26591 -110.601506)
				)
				(xy 395.26591 -109.726476)
				(arc
					(start 394.484352 -108.944918)
					(mid 393.907654 -109.000167)
					(end 394.041884 -108.436664)
				)
				(xy 394.07338 -108.42371) (xy 394.07338 -107.391962)
				(arc
					(start 394.041884 -107.379008)
					(mid 393.820229 -107.049316)
					(end 394.041884 -106.719624)
				)
				(xy 394.07338 -106.70667) (xy 394.07338 -105.878122) (xy 394.07338 -105.673144)
				(arc
					(start 394.069316 -105.671874)
					(mid 393.990331 -105.028638)
					(end 394.527532 -105.391458)
				)
				(arc
					(start 394.527532 -105.391458)
					(mid 394.550157 -105.473778)
					(end 394.627608 -105.509822)
				)
				(arc
					(start 394.733018 -105.509822)
					(mid 394.813879 -105.469401)
					(end 394.830554 -105.380536)
				)
				(arc
					(start 394.830554 -105.380536)
					(mid 394.91134 -105.041445)
					(end 395.242796 -104.93375)
				)
				(arc
					(start 395.242796 -104.93375)
					(mid 395.327009 -104.91266)
					(end 395.364208 -104.834182)
				)
				(arc
					(start 395.364208 -104.062784)
					(mid 395.326558 -103.983835)
					(end 395.241526 -103.96347)
				)
				(arc
					(start 395.241526 -103.96347)
					(mid 394.92741 -103.878887)
					(end 394.813028 -103.574342)
				)
				(arc
					(start 394.813028 -103.574342)
					(mid 394.787883 -103.495314)
					(end 394.71219 -103.461312)
				)
				(arc
					(start 394.63091 -103.461312)
					(mid 394.55513 -103.495237)
					(end 394.530072 -103.574342)
				)
				(arc
					(start 394.530072 -103.574342)
					(mid 394.17625 -103.971413)
					(end 393.822428 -103.574342)
				)
			)
		)
	)
	(zone
		(layer "In2.Cu")
		(hatch none 0.5)
		(connect_pads
			(clearance 0)
		)
		(min_thickness 0.25)
		(keepout
			(tracks not_allowed)
			(vias allowed)
			(pads allowed)
			(copperpour not_allowed)
			(footprints allowed)
		)
		(placement
			(enabled no)
			(sheetname "")
		)
		(fill
			(thermal_gap 0.5)
			(thermal_bridge_width 0.5)
			(island_removal_mode 0)
		)
		(polygon
			(pts
				(xy 332.221332 -2.487422) (xy 332.221332 -4.217416) (xy 331.114654 -4.217416) (xy 331.114654 -7.199884)
				(xy 335.945734 -7.199884) (xy 335.945734 -8.502904) (xy 331.114654 -8.502904) (xy 331.114654 -9.546844)
				(xy 341.407242 -9.546844) (xy 342.008206 -8.94588) (xy 342.008206 -2.487422) (xy 337.947 -2.487422)
				(xy 337.947 -4.572) (xy 337.947 -6.858) (xy 337.947 -7.239) (xy 337.7692 -7.4168) (xy 336.8548 -7.4168)
				(xy 336.5754 -7.1374) (xy 336.5754 -6.858) (xy 336.111596 -6.858) (xy 336.111596 -6.223) (xy 335.153 -6.223)
				(xy 335.153 -2.487422)
			)
		)
	)
	(zone
		(net "VR_FET_SW_P12V_STBY_PVDDQ_KLM")
		(layer "In2.Cu")
		(hatch none 0.5)
		(connect_pads
			(clearance 0.5)
		)
		(min_thickness 0.25)
		(fill yes
			(thermal_gap 0.5)
			(thermal_bridge_width 0.5)
			(island_removal_mode 0)
		)
		(polygon
			(pts
				(xy 15.8877 -126.987554) (xy 15.8877 -131.80822) (xy 15.8877 -136.5758) (xy 16.0528 -136.7409) (xy 16.3195 -137.0076)
				(xy 16.3195 -149.659086) (xy 14.645386 -151.3332) (xy 1.3716 -151.3332) (xy -1.3208 -151.3332) (xy -1.7272 -150.9268)
				(xy -1.7272 -148.5646) (xy -0.7874 -147.6248) (xy 0.508 -147.6248) (xy 0.5842 -147.6248) (xy 1.2192 -146.9898)
				(xy 1.2192 -146.9136) (xy 1.2192 -143.8656) (xy 1.2192 -143.5608) (xy 0.762 -143.1036) (xy 0.4572 -143.1036)
				(xy -0.762 -143.1036) (xy -1.397 -142.4686) (xy -1.41605 -142.44955) (xy -1.41605 -139.87145) (xy -0.0508 -138.5062)
				(xy 3.62458 -138.5062) (xy 3.75158 -138.6332) (xy 3.9624 -138.6332) (xy 4.45389 -138.14171) (xy 4.45389 -137.67689)
				(xy 4.57835 -137.55243) (xy 4.57835 -134.20725) (xy 4.57835 -133.29031) (xy 4.57835 -130.014726)
				(xy 6.206998 -128.386078) (xy 6.206998 -128.1938) (xy 6.206998 -127.334518) (xy 6.835648 -126.705868)
				(xy 15.606014 -126.705868)
			)
		)
	)
	(zone
		(net "VR_FET_SW_P12V_STBY_PVCCIN_CPU0")
		(layer "In2.Cu")
		(hatch none 0.5)
		(connect_pads
			(clearance 0.5)
		)
		(min_thickness 0.25)
		(fill yes
			(thermal_gap 0.5)
			(thermal_bridge_width 0.5)
			(island_removal_mode 0)
		)
		(polygon
			(pts
				(xy 186.588908 -59.147202) (xy 189.738254 -59.147202) (xy 190.79845 -58.087006) (xy 190.79845 -54.111906)
				(xy 187.124594 -50.43805) (xy 182.65775 -50.43805) (xy 182.2958 -50.8) (xy 181.8132 -50.8) (xy 181.4957 -50.4825)
				(xy 180.6575 -50.4825) (xy 180.3019 -50.8381) (xy 179.9209 -50.8381) (xy 179.592224 -50.509424)
				(xy 177.814224 -50.509424) (xy 177.563272 -50.760376) (xy 177.563272 -53.753004) (xy 177.853848 -54.04358)
				(xy 179.837588 -54.04358) (xy 179.854606 -54.026562) (xy 180.058568 -53.8226) (xy 181.77129 -53.8226)
				(xy 181.975252 -54.026562) (xy 182.8038 -54.85511) (xy 182.8038 -58.1152) (xy 182.5498 -58.3692)
				(xy 182.4228 -58.4962) (xy 177.1142 -58.4962) (xy 176.8094 -58.801) (xy 176.8094 -59.9186) (xy 177.1396 -60.2488)
				(xy 183.6166 -60.2488) (xy 183.9214 -59.944) (xy 184.718198 -59.147202)
			)
		)
	)
	(zone
		(layer "In2.Cu")
		(hatch none 0.5)
		(connect_pads
			(clearance 0)
		)
		(min_thickness 0.25)
		(keepout
			(tracks allowed)
			(vias allowed)
			(pads allowed)
			(copperpour allowed)
			(footprints allowed)
		)
		(placement
			(enabled no)
			(sheetname "")
		)
		(fill
			(thermal_gap 0.5)
			(thermal_bridge_width 0.5)
			(island_removal_mode 0)
		)
		(polygon
			(pts
				(xy 120.622568 -49.149) (xy 120.622568 -50.673) (xy 119.479568 -51.816) (xy 119.479568 -54.864)
				(xy 117.574568 -54.864) (xy 116.812568 -54.102) (xy 114.145568 -54.102) (xy 114.145568 -51.689)
				(xy 113.256568 -50.8) (xy 113.256568 -48.514) (xy 113.256568 -48.26) (xy 113.383568 -48.133) (xy 119.987568 -48.133)
				(xy 120.622568 -48.768)
			)
		)
	)
	(zone
		(net "P3V3_STBY")
		(layer "In2.Cu")
		(hatch none 0.5)
		(connect_pads
			(clearance 0.5)
		)
		(min_thickness 0.25)
		(fill yes
			(thermal_gap 0.5)
			(thermal_bridge_width 0.5)
			(island_removal_mode 0)
		)
		(polygon
			(pts
				(xy 387.280658 -102.766114) (xy 387.096254 -102.950518) (xy 387.096254 -104.670352) (xy 387.07314 -104.693466)
				(xy 387.137148 -104.757474)
				(arc
					(start 387.170422 -104.739948)
					(mid 387.443876 -104.714739)
					(end 387.654038 -104.891586)
				)
				(arc
					(start 387.654038 -104.891586)
					(mid 387.741215 -104.946724)
					(end 387.831584 -104.897174)
				)
				(arc
					(start 387.831584 -104.897174)
					(mid 387.889517 -104.824138)
					(end 387.964426 -104.76865)
				)
				(arc
					(start 387.964426 -104.76865)
					(mid 388.016793 -104.67975)
					(end 387.964426 -104.59085)
				)
				(arc
					(start 387.964426 -104.59085)
					(mid 387.78183 -104.297143)
					(end 387.934708 -103.986838)
				)
				(arc
					(start 387.934708 -103.986838)
					(mid 387.977542 -103.917733)
					(end 387.956044 -103.839264)
				)
				(arc
					(start 387.956044 -103.839264)
					(mid 387.918649 -103.447598)
					(end 388.264908 -103.260652)
				)
				(arc
					(start 388.264908 -103.260652)
					(mid 388.365983 -103.202593)
					(end 388.345934 -103.087678)
				)
				(arc
					(start 388.192772 -102.934516)
					(mid 388.110417 -102.905282)
					(end 388.0358 -102.950772)
				)
				(arc
					(start 388.0358 -102.950772)
					(mid 387.661683 -103.104573)
					(end 387.385052 -102.809294)
				)
				(xy 387.378702 -102.766114)
			)
		)
	)
	(zone
		(net "GND")
		(layer "In2.Cu")
		(hatch none 0.5)
		(connect_pads
			(clearance 0.5)
		)
		(min_thickness 0.25)
		(fill yes
			(thermal_gap 0.5)
			(thermal_bridge_width 0.5)
			(island_removal_mode 0)
		)
		(polygon
			(pts
				(xy -1.098296 -86.8426) (xy 1.1684 -86.8426) (xy 2.2352 -85.7758) (xy 2.2352 -69.0372) (xy 0.508 -67.31)
				(xy 0.508 -59.6392) (xy 1.778 -58.3692) (xy 1.778 -49.7332) (xy 2.8448 -48.6664) (xy 11.0236 -48.6664)
				(xy 13.1318 -46.5582) (xy 13.1318 -43.9674) (xy 12.3698 -43.2054) (xy -0.98298 -43.2054) (xy -2.34696 -44.56938)
				(xy -4.111498 -46.333918) (xy -4.111498 -59.93765) (xy -1.899158 -62.14999) (xy -1.899158 -77.297788)
				(xy -3.721862 -79.120492) (xy -3.721862 -86.157308) (xy -3.03657 -86.8426)
			)
		)
	)
	(zone
		(layer "In2.Cu")
		(hatch none 0.5)
		(connect_pads
			(clearance 0)
		)
		(min_thickness 0.25)
		(keepout
			(tracks not_allowed)
			(vias allowed)
			(pads allowed)
			(copperpour not_allowed)
			(footprints allowed)
		)
		(placement
			(enabled no)
			(sheetname "")
		)
		(fill
			(thermal_gap 0.5)
			(thermal_bridge_width 0.5)
			(island_removal_mode 0)
		)
		(polygon
			(pts
				(arc
					(start 338.606638 -69.891148)
					(mid 338.955846 -70.287951)
					(end 338.51469 -69.996812)
				)
				(xy 338.441792 -69.923914) (xy 338.441792 -69.732398) (xy 338.438744 -69.72935) (xy 338.16925 -69.72935)
				(xy 338.16925 -69.91223) (xy 338.128356 -69.953124) (xy 338.122006 -69.953124)
				(arc
					(start 338.094828 -69.980302)
					(mid 337.674857 -70.301467)
					(end 337.996022 -69.881496)
				)
				(xy 338.02955 -69.847968) (xy 338.02955 -69.733414) (xy 338.025486 -69.72935)
				(arc
					(start 337.863434 -69.72935)
					(mid 337.479894 -70.11289)
					(end 337.863434 -70.49643)
				)
				(arc
					(start 338.754466 -70.49643)
					(mid 339.13826 -70.113017)
					(end 338.75472 -69.72935)
				)
				(xy 338.581492 -69.72935) (xy 338.581492 -69.866002)
			)
		)
	)
	(zone
		(net "PVCCIO_CPU1")
		(layer "In2.Cu")
		(hatch none 0.5)
		(connect_pads
			(clearance 0.5)
		)
		(min_thickness 0.25)
		(fill yes
			(thermal_gap 0.5)
			(thermal_bridge_width 0.5)
			(island_removal_mode 0)
		)
		(polygon
			(pts
				(xy 115.5192 -70.0024) (xy 115.309904 -69.793104) (xy 115.116102 -69.793104) (xy 113.551716 -69.793104)
				(xy 112.96396 -70.38086)
				(arc
					(start 112.96396 -74.771504)
					(mid 113.013018 -74.858463)
					(end 113.112804 -74.86142)
				)
				(arc
					(start 113.112804 -74.86142)
					(mid 113.382416 -74.811165)
					(end 113.60785 -74.967338)
				)
				(arc
					(start 113.60785 -74.967338)
					(mid 113.688876 -75.007573)
					(end 113.769902 -74.967338)
				)
				(arc
					(start 113.769902 -74.967338)
					(mid 113.824211 -74.901538)
					(end 113.892584 -74.850498)
				)
				(arc
					(start 113.892584 -74.850498)
					(mid 113.937191 -74.768077)
					(end 113.895378 -74.684128)
				)
				(arc
					(start 113.895378 -74.684128)
					(mid 113.81318 -74.149631)
					(end 114.354102 -74.149458)
				)
				(arc
					(start 114.354102 -74.149458)
					(mid 114.441846 -74.175944)
					(end 114.515138 -74.12101)
				)
				(arc
					(start 114.515138 -74.12101)
					(mid 114.744005 -73.912956)
					(end 115.0493 -73.96226)
				)
				(arc
					(start 115.0493 -73.96226)
					(mid 115.120021 -73.973493)
					(end 115.180618 -73.935336)
				)
				(arc
					(start 115.180618 -73.935336)
					(mid 115.83007 -74.058185)
					(end 115.276884 -74.419968)
				)
				(arc
					(start 115.276884 -74.419968)
					(mid 115.206163 -74.408735)
					(end 115.145566 -74.446892)
				)
				(arc
					(start 115.145566 -74.446892)
					(mid 114.870377 -74.610059)
					(end 114.575082 -74.48677)
				)
				(arc
					(start 114.575082 -74.48677)
					(mid 114.487338 -74.460284)
					(end 114.414046 -74.515218)
				)
				(arc
					(start 114.414046 -74.515218)
					(mid 114.352238 -74.615877)
					(end 114.260884 -74.690732)
				)
				(arc
					(start 114.260884 -74.690732)
					(mid 114.216277 -74.773153)
					(end 114.25809 -74.857102)
				)
				(arc
					(start 114.25809 -74.857102)
					(mid 114.320108 -74.905996)
					(end 114.36985 -74.967338)
				)
				(arc
					(start 114.36985 -74.967338)
					(mid 114.450876 -75.007573)
					(end 114.531902 -74.967338)
				)
				(arc
					(start 114.531902 -74.967338)
					(mid 114.794277 -74.80511)
					(end 115.08486 -74.90841)
				)
				(arc
					(start 115.08486 -74.90841)
					(mid 115.156068 -74.931954)
					(end 115.224052 -74.900282)
				)
				(arc
					(start 115.224052 -74.900282)
					(mid 115.861825 -75.0966)
					(end 115.253008 -75.36942)
				)
				(arc
					(start 115.253008 -75.36942)
					(mid 115.1818 -75.345876)
					(end 115.113816 -75.377548)
				)
				(arc
					(start 115.113816 -75.377548)
					(mid 114.816196 -75.51562)
					(end 114.531902 -75.351894)
				)
				(arc
					(start 114.531902 -75.351894)
					(mid 114.450876 -75.311659)
					(end 114.36985 -75.351894)
				)
				(arc
					(start 114.36985 -75.351894)
					(mid 114.069876 -75.515924)
					(end 113.769902 -75.351894)
				)
				(arc
					(start 113.769902 -75.351894)
					(mid 113.688876 -75.311659)
					(end 113.60785 -75.351894)
				)
				(arc
					(start 113.60785 -75.351894)
					(mid 113.38241 -75.508041)
					(end 113.112804 -75.457812)
				)
				(arc
					(start 113.112804 -75.457812)
					(mid 113.013033 -75.460793)
					(end 112.96396 -75.547728)
				)
				(xy 112.96396 -78.79334) (xy 115.25631 -81.08569) (xy 115.25631 -82.956654) (xy 117.7671 -85.467444)
				(xy 118.177564 -85.878162) (xy 118.230904 -85.931502) (xy 118.230904 -86.287102)
				(arc
					(start 118.349522 -86.405466)
					(mid 118.425643 -86.434962)
					(end 118.498874 -86.398862)
				)
				(arc
					(start 118.498874 -86.398862)
					(mid 118.934913 -86.290106)
					(end 119.130826 -86.694518)
				)
				(arc
					(start 119.130826 -86.694518)
					(mid 119.154957 -86.774713)
					(end 119.231156 -86.80958)
				)
				(xy 119.447564 -86.80958)
				(arc
					(start 119.46255 -86.800944)
					(mid 119.998688 -87.108538)
					(end 119.46255 -87.416132)
				)
				(xy 119.447564 -87.407496) (xy 118.50624 -87.407496)
				(arc
					(start 118.382542 -87.283798)
					(mid 118.302997 -87.254313)
					(end 118.228872 -87.295482)
				)
				(arc
					(start 118.228872 -87.295482)
					(mid 118.077538 -87.430896)
					(end 117.876828 -87.461598)
				)
				(arc
					(start 117.876828 -87.461598)
					(mid 117.801129 -87.489028)
					(end 117.769132 -87.562944)
				)
				(arc
					(start 117.769132 -87.644732)
					(mid 117.80108 -87.718699)
					(end 117.876828 -87.746078)
				)
				(arc
					(start 117.876828 -87.746078)
					(mid 118.281718 -88.100287)
					(end 117.874542 -88.451944)
				)
				(arc
					(start 117.874542 -88.451944)
					(mid 117.799015 -88.479472)
					(end 117.7671 -88.55329)
				)
				(arc
					(start 117.7671 -88.635586)
					(mid 117.798956 -88.709466)
					(end 117.874542 -88.736932)
				)
				(arc
					(start 117.874542 -88.736932)
					(mid 118.281787 -89.089738)
					(end 117.874542 -89.442544)
				)
				(arc
					(start 117.874542 -89.442544)
					(mid 117.799015 -89.470072)
					(end 117.7671 -89.54389)
				)
				(arc
					(start 117.7671 -89.626186)
					(mid 117.798956 -89.700066)
					(end 117.874542 -89.727532)
				)
				(arc
					(start 117.874542 -89.727532)
					(mid 118.281787 -90.080338)
					(end 117.874542 -90.433144)
				)
				(arc
					(start 117.874542 -90.433144)
					(mid 117.799015 -90.460672)
					(end 117.7671 -90.53449)
				)
				(arc
					(start 117.7671 -90.616786)
					(mid 117.798956 -90.690666)
					(end 117.874542 -90.718132)
				)
				(arc
					(start 117.874542 -90.718132)
					(mid 118.206156 -90.851401)
					(end 118.255288 -91.205304)
				)
				(xy 118.23954 -91.24442)
				(arc
					(start 118.3513 -91.35618)
					(mid 118.426242 -91.385908)
					(end 118.499128 -91.351608)
				)
				(arc
					(start 118.499128 -91.351608)
					(mid 119.035884 -91.313962)
					(end 118.998238 -91.850718)
				)
				(arc
					(start 118.998238 -91.850718)
					(mid 118.964113 -91.923609)
					(end 118.993666 -91.998546)
				)
				(arc
					(start 119.113046 -92.117926)
					(mid 119.218961 -92.141835)
					(end 119.28602 -92.056458)
				)
				(arc
					(start 119.28602 -92.056458)
					(mid 119.894394 -91.809526)
					(end 119.647462 -92.4179)
				)
				(arc
					(start 119.647462 -92.4179)
					(mid 119.562113 -92.484969)
					(end 119.585994 -92.590874)
				)
				(xy 119.694198 -92.699078)
				(arc
					(start 119.712994 -92.702888)
					(mid 119.894336 -92.800184)
					(end 119.991632 -92.981526)
				)
				(xy 119.995442 -93.000322)
				(arc
					(start 120.270524 -93.275404)
					(mid 120.341415 -93.228496)
					(end 120.4214 -93.199712)
				)
				(arc
					(start 120.4214 -93.199712)
					(mid 120.617574 -93.210376)
					(end 120.77827 -93.32341)
				)
				(arc
					(start 120.77827 -93.32341)
					(mid 120.857166 -93.53804)
					(end 120.789446 -93.75648)
				)
				(xy 120.774206 -93.779086)
				(arc
					(start 120.887236 -93.892116)
					(mid 120.969483 -93.921434)
					(end 121.044208 -93.876114)
				)
				(arc
					(start 121.044208 -93.876114)
					(mid 121.611124 -93.790782)
					(end 121.525792 -94.357698)
				)
				(arc
					(start 121.525792 -94.357698)
					(mid 121.480291 -94.432405)
					(end 121.50979 -94.51467)
				)
				(xy 122.169174 -95.174054)
				(arc
					(start 122.197622 -95.17253)
					(mid 122.469715 -95.276357)
					(end 122.573542 -95.54845)
				)
				(xy 122.572018 -95.576898)
				(arc
					(start 122.751342 -95.756222)
					(mid 122.771851 -95.769956)
					(end 122.796046 -95.774764)
				)
				(arc
					(start 122.838464 -95.758508)
					(mid 123.328176 -95.77197)
					(end 123.341638 -96.261682)
				)
				(arc
					(start 123.325382 -96.3041)
					(mid 123.330333 -96.328429)
					(end 123.344178 -96.349058)
				)
				(arc
					(start 123.431808 -96.436688)
					(mid 123.522596 -96.46476)
					(end 123.596908 -96.405446)
				)
				(arc
					(start 123.596908 -96.405446)
					(mid 123.973969 -96.164762)
					(end 124.289058 -96.482154)
				)
				(xy 124.290836 -96.499172)
				(arc
					(start 124.441712 -96.704658)
					(mid 124.505141 -96.744603)
					(end 124.578618 -96.730058)
				)
				(arc
					(start 124.578618 -96.730058)
					(mid 125.11471 -96.86073)
					(end 124.880116 -97.360232)
				)
				(xy 124.859796 -97.365312) (xy 124.819664 -97.413826)
				(arc
					(start 124.821696 -97.43948)
					(mid 124.824482 -97.509838)
					(end 124.821696 -97.580196)
				)
				(xy 124.819664 -97.60585) (xy 124.859796 -97.654364)
				(arc
					(start 124.880116 -97.659444)
					(mid 125.143688 -97.940007)
					(end 124.99848 -98.296476)
				)
				(arc
					(start 124.99848 -98.7044)
					(mid 125.08599 -98.792514)
					(end 125.137926 -98.905314)
				)
				(xy 125.142244 -98.921824) (xy 125.428756 -99.208336)
				(arc
					(start 125.471174 -99.183444)
					(mid 125.903832 -99.23872)
					(end 125.959108 -99.671378)
				)
				(xy 125.934216 -99.713796)
				(arc
					(start 126.04496 -99.82454)
					(mid 126.125771 -99.853922)
					(end 126.200154 -99.810824)
				)
				(arc
					(start 126.200154 -99.810824)
					(mid 126.647796 -99.657583)
					(end 126.852934 -100.083874)
				)
				(arc
					(start 126.852934 -100.083874)
					(mid 126.873906 -100.168276)
					(end 126.952502 -100.20554)
				)
				(xy 127.14351 -100.20554)
				(arc
					(start 127.154178 -100.197158)
					(mid 127.206948 -100.164112)
					(end 127.264668 -100.14077)
				)
				(arc
					(start 127.264668 -100.14077)
					(mid 127.620836 -100.22961)
					(end 127.709676 -100.585778)
				)
				(arc
					(start 127.811276 -100.687378)
					(mid 127.898996 -100.736489)
					(end 127.994918 -100.706428)
				)
				(arc
					(start 127.994918 -100.706428)
					(mid 128.530093 -100.789297)
					(end 128.36525 -101.30536)
				)
				(arc
					(start 128.36525 -101.30536)
					(mid 128.28974 -101.397837)
					(end 128.324356 -101.512116)
				)
				(arc
					(start 129.515616 -102.703376)
					(mid 129.604903 -102.740619)
					(end 129.694432 -102.704138)
				)
				(arc
					(start 129.694432 -102.704138)
					(mid 130.046552 -102.616755)
					(end 130.292856 -102.883208)
				)
				(xy 130.303524 -102.9335)
				(arc
					(start 130.46329 -102.9335)
					(mid 130.580794 -102.854686)
					(end 130.552444 -102.716076)
				)
				(arc
					(start 130.552444 -102.716076)
					(mid 130.802888 -102.106241)
					(end 131.053332 -102.716076)
				)
				(arc
					(start 131.053332 -102.716076)
					(mid 131.024997 -102.85468)
					(end 131.142486 -102.9335)
				)
				(xy 131.302252 -102.9335)
				(arc
					(start 131.31292 -102.883208)
					(mid 131.661408 -102.601685)
					(end 132.009896 -102.883208)
				)
				(xy 132.020564 -102.9335)
				(arc
					(start 132.180076 -102.9335)
					(mid 132.29758 -102.854686)
					(end 132.26923 -102.716076)
				)
				(arc
					(start 132.26923 -102.716076)
					(mid 132.519674 -102.106241)
					(end 132.770118 -102.716076)
				)
				(arc
					(start 132.770118 -102.716076)
					(mid 132.741783 -102.85468)
					(end 132.859272 -102.9335)
				)
				(xy 133.019038 -102.9335)
				(arc
					(start 133.029706 -102.883208)
					(mid 133.378194 -102.601685)
					(end 133.726682 -102.883208)
				)
				(xy 133.73735 -102.9335)
				(arc
					(start 133.897116 -102.9335)
					(mid 134.01462 -102.854686)
					(end 133.98627 -102.716076)
				)
				(arc
					(start 133.98627 -102.716076)
					(mid 134.340828 -102.12179)
					(end 134.302754 -102.81285)
				)
				(arc
					(start 134.302754 -102.81285)
					(mid 134.204881 -102.900142)
					(end 134.23646 -103.02748)
				)
				(xy 134.43712 -103.22814) (xy 135.49122 -103.22814)
				(arc
					(start 135.769096 -102.950264)
					(mid 135.805628 -102.848981)
					(end 135.751316 -102.755954)
				)
				(arc
					(start 135.751316 -102.755954)
					(mid 135.701715 -102.210545)
					(end 136.247124 -102.260146)
				)
				(arc
					(start 136.247124 -102.260146)
					(mid 136.34014 -102.314578)
					(end 136.441434 -102.277926)
				)
				(xy 136.529318 -102.190042)
				(arc
					(start 136.50468 -102.147624)
					(mid 136.560237 -101.715501)
					(end 136.99236 -101.659944)
				)
				(xy 137.034778 -101.684582)
				(arc
					(start 137.322306 -101.397054)
					(mid 137.418744 -101.219934)
					(end 137.595864 -101.123496)
				)
				(arc
					(start 137.672572 -101.046788)
					(mid 137.704206 -100.919302)
					(end 137.606024 -100.832158)
				)
				(arc
					(start 137.606024 -100.832158)
					(mid 137.328099 -100.384282)
					(end 137.799826 -100.149406)
				)
				(arc
					(start 137.799826 -100.149406)
					(mid 137.917514 -100.135831)
					(end 137.9728 -100.031042)
				)
				(arc
					(start 137.9728 -99.94138)
					(mid 137.917526 -99.836574)
					(end 137.799826 -99.823016)
				)
				(arc
					(start 137.799826 -99.823016)
					(mid 137.314385 -99.490784)
					(end 137.799826 -99.158552)
				)
				(arc
					(start 137.799826 -99.158552)
					(mid 137.917514 -99.144977)
					(end 137.9728 -99.040188)
				)
				(arc
					(start 137.9728 -98.95078)
					(mid 137.917526 -98.845974)
					(end 137.799826 -98.832416)
				)
				(arc
					(start 137.799826 -98.832416)
					(mid 137.314385 -98.500184)
					(end 137.799826 -98.167952)
				)
				(arc
					(start 137.799826 -98.167952)
					(mid 137.917514 -98.154377)
					(end 137.9728 -98.049588)
				)
				(arc
					(start 137.9728 -97.96018)
					(mid 137.917526 -97.855374)
					(end 137.799826 -97.841816)
				)
				(arc
					(start 137.799826 -97.841816)
					(mid 137.314385 -97.509584)
					(end 137.799826 -97.177352)
				)
				(arc
					(start 137.799826 -97.177352)
					(mid 137.917514 -97.163777)
					(end 137.9728 -97.058988)
				)
				(arc
					(start 137.9728 -96.96958)
					(mid 137.917526 -96.864774)
					(end 137.799826 -96.851216)
				)
				(arc
					(start 137.799826 -96.851216)
					(mid 137.314385 -96.518984)
					(end 137.799826 -96.186752)
				)
				(arc
					(start 137.799826 -96.186752)
					(mid 137.917514 -96.173177)
					(end 137.9728 -96.068388)
				)
				(arc
					(start 137.9728 -95.97898)
					(mid 137.917526 -95.874174)
					(end 137.799826 -95.860616)
				)
				(arc
					(start 137.799826 -95.860616)
					(mid 137.314385 -95.528384)
					(end 137.799826 -95.196152)
				)
				(arc
					(start 137.799826 -95.196152)
					(mid 137.917514 -95.182577)
					(end 137.9728 -95.077788)
				)
				(arc
					(start 137.9728 -93.99778)
					(mid 137.917526 -93.892974)
					(end 137.799826 -93.879416)
				)
				(arc
					(start 137.799826 -93.879416)
					(mid 137.314385 -93.547184)
					(end 137.799826 -93.214952)
				)
				(arc
					(start 137.799826 -93.214952)
					(mid 137.917514 -93.201377)
					(end 137.9728 -93.096588)
				)
				(arc
					(start 137.9728 -92.01658)
					(mid 137.917526 -91.911774)
					(end 137.799826 -91.898216)
				)
				(arc
					(start 137.799826 -91.898216)
					(mid 137.314385 -91.565984)
					(end 137.799826 -91.233752)
				)
				(arc
					(start 137.799826 -91.233752)
					(mid 137.917514 -91.220177)
					(end 137.9728 -91.115388)
				)
				(arc
					(start 137.9728 -91.02598)
					(mid 137.917526 -90.921174)
					(end 137.799826 -90.907616)
				)
				(arc
					(start 137.799826 -90.907616)
					(mid 137.325926 -90.48542)
					(end 137.945622 -90.348562)
				)
				(arc
					(start 137.945622 -90.348562)
					(mid 138.037479 -90.394394)
					(end 138.133328 -90.357452)
				)
				(xy 138.22299 -90.26779)
				(arc
					(start 138.204956 -90.227658)
					(mid 138.27741 -89.828434)
					(end 138.676634 -89.75598)
				)
				(xy 138.716766 -89.774014)
				(arc
					(start 139.073128 -89.417652)
					(mid 139.124466 -89.344763)
					(end 139.192254 -89.286842)
				)
				(arc
					(start 139.192254 -88.892126)
					(mid 139.031476 -88.599678)
					(end 139.18311 -88.302338)
				)
				(arc
					(start 139.18311 -87.895176)
					(mid 139.081251 -87.422077)
					(end 139.54506 -87.283798)
				)
				(arc
					(start 139.54506 -87.283798)
					(mid 139.668142 -87.277515)
					(end 139.72794 -87.169752)
				)
				(arc
					(start 139.72794 -87.046816)
					(mid 139.668142 -86.939053)
					(end 139.54506 -86.93277)
				)
				(arc
					(start 139.54506 -86.93277)
					(mid 139.031487 -86.612984)
					(end 139.54506 -86.293198)
				)
				(arc
					(start 139.54506 -86.293198)
					(mid 139.668142 -86.286915)
					(end 139.72794 -86.179152)
				)
				(arc
					(start 139.72794 -85.065616)
					(mid 139.668142 -84.957853)
					(end 139.54506 -84.95157)
				)
				(arc
					(start 139.54506 -84.95157)
					(mid 139.031487 -84.631784)
					(end 139.54506 -84.311998)
				)
				(arc
					(start 139.54506 -84.311998)
					(mid 139.668142 -84.305715)
					(end 139.72794 -84.197952)
				)
				(xy 139.72794 -83.48218) (xy 139.198096 -82.952336)
				(arc
					(start 139.192508 -82.94878)
					(mid 139.146623 -82.912895)
					(end 139.107164 -82.87004)
				)
				(arc
					(start 138.989054 -82.87004)
					(mid 138.886333 -82.922358)
					(end 138.868404 -83.036156)
				)
				(arc
					(start 138.868404 -83.036156)
					(mid 138.529314 -83.502618)
					(end 138.190224 -83.036156)
				)
				(arc
					(start 138.190224 -83.036156)
					(mid 138.17216 -82.922457)
					(end 138.069574 -82.87004)
				)
				(arc
					(start 137.951464 -82.87004)
					(mid 137.670794 -83.006866)
					(end 137.390124 -82.87004)
				)
				(arc
					(start 137.272014 -82.87004)
					(mid 137.169293 -82.922358)
					(end 137.151364 -83.036156)
				)
				(arc
					(start 137.151364 -83.036156)
					(mid 136.746563 -83.496509)
					(end 136.536176 -82.92084)
				)
				(arc
					(start 136.536176 -82.92084)
					(mid 136.564617 -82.834102)
					(end 136.52754 -82.75066)
				)
				(xy 136.10336 -82.32648) (xy 135.9662 -82.32648) (xy 135.24992 -81.6102) (xy 135.12673 -81.48701)
				(xy 133.65099 -81.48701) (xy 129.48539 -81.48701) (xy 129.018284 -81.019904) (xy 121.6914 -81.019904)
				(xy 121.228104 -81.4832) (xy 119.4816 -81.4832) (xy 118.5164 -80.518) (xy 118.5164 -79.7306) (xy 118.5164 -78.105)
				(xy 117.7798 -78.105) (xy 117.5004 -77.8256) (xy 117.5004 -74.4474) (xy 119.4054 -72.5424) (xy 119.4054 -72.1614)
				(xy 120.9294 -70.6374) (xy 121.2342 -70.6374) (xy 121.5136 -70.358) (xy 121.5136 -70.2056) (xy 120.8278 -69.5198)
				(xy 119.9388 -69.5198) (xy 119.4562 -70.0024)
			)
		)
	)
	(zone
		(layer "In2.Cu")
		(hatch none 0.5)
		(connect_pads
			(clearance 0)
		)
		(min_thickness 0.25)
		(keepout
			(tracks allowed)
			(vias allowed)
			(pads allowed)
			(copperpour allowed)
			(footprints allowed)
		)
		(placement
			(enabled no)
			(sheetname "")
		)
		(fill
			(thermal_gap 0.5)
			(thermal_bridge_width 0.5)
			(island_removal_mode 0)
		)
		(polygon
			(pts
				(xy 293.243 -101.727) (xy 292.608 -102.362) (xy 290.576 -102.362) (xy 289.179 -103.759) (xy 287.909 -103.759)
				(xy 287.02 -104.648) (xy 287.02 -106.299) (xy 287.274 -106.553) (xy 288.417 -106.553) (xy 289.687 -107.823)
				(xy 290.322 -107.823) (xy 291.592 -106.553) (xy 295.148 -106.553) (xy 295.148 -105.918) (xy 297.561 -105.918)
				(xy 297.561 -103.124) (xy 295.148 -103.124) (xy 295.148 -102.362) (xy 294.513 -101.727) (xy 293.624 -101.727)
			)
		)
	)
	(zone
		(layer "In2.Cu")
		(hatch none 0.5)
		(connect_pads
			(clearance 0)
		)
		(min_thickness 0.25)
		(keepout
			(tracks not_allowed)
			(vias allowed)
			(pads allowed)
			(copperpour not_allowed)
			(footprints allowed)
		)
		(placement
			(enabled no)
			(sheetname "")
		)
		(fill
			(thermal_gap 0.5)
			(thermal_bridge_width 0.5)
			(island_removal_mode 0)
		)
		(polygon
			(pts
				(xy 415.013902 -10.055098) (xy 415.169096 -10.210292) (xy 415.169096 -10.508488) (xy 415.321496 -10.508488)
				(xy 415.321496 -10.210292) (xy 415.47669 -10.055098)
				(arc
					(start 415.64179 -10.055098)
					(mid 416.165707 -10.124948)
					(end 415.64179 -10.194798)
				)
				(xy 415.534602 -10.194798) (xy 415.461196 -10.268204) (xy 415.461196 -10.508488)
				(arc
					(start 415.898838 -10.508488)
					(mid 416.282632 -10.125075)
					(end 415.899092 -9.741408)
				)
				(arc
					(start 414.629092 -9.741408)
					(mid 414.245552 -10.124948)
					(end 414.629092 -10.508488)
				)
				(xy 415.029396 -10.508488) (xy 415.029396 -10.268204) (xy 414.95599 -10.194798)
				(arc
					(start 414.886394 -10.194798)
					(mid 414.362477 -10.124948)
					(end 414.886394 -10.055098)
				)
			)
		)
	)
	(zone
		(layer "In2.Cu")
		(hatch none 0.5)
		(connect_pads
			(clearance 0)
		)
		(min_thickness 0.25)
		(keepout
			(tracks allowed)
			(vias allowed)
			(pads allowed)
			(copperpour allowed)
			(footprints allowed)
		)
		(placement
			(enabled no)
			(sheetname "")
		)
		(fill
			(thermal_gap 0.5)
			(thermal_bridge_width 0.5)
			(island_removal_mode 0)
		)
		(polygon
			(pts
				(xy 354.203 -119.888) (xy 354.203 -118.745) (xy 355.473 -118.745) (xy 355.473 -119.888)
			)
		)
	)
	(zone
		(layer "In2.Cu")
		(hatch none 0.5)
		(connect_pads
			(clearance 0)
		)
		(min_thickness 0.25)
		(keepout
			(tracks not_allowed)
			(vias allowed)
			(pads allowed)
			(copperpour not_allowed)
			(footprints allowed)
		)
		(placement
			(enabled no)
			(sheetname "")
		)
		(fill
			(thermal_gap 0.5)
			(thermal_bridge_width 0.5)
			(island_removal_mode 0)
		)
		(polygon
			(pts
				(arc
					(start 455.874882 -3.278632)
					(mid 455.759334 -3.209376)
					(end 455.69251 -3.09245)
				)
				(xy 455.617834 -3.09245) (xy 455.520044 -3.19024) (xy 455.520044 -3.275838)
			)
		)
	)
	(zone
		(layer "In2.Cu")
		(hatch none 0.5)
		(connect_pads
			(clearance 0)
		)
		(min_thickness 0.25)
		(keepout
			(tracks not_allowed)
			(vias allowed)
			(pads allowed)
			(copperpour not_allowed)
			(footprints allowed)
		)
		(placement
			(enabled no)
			(sheetname "")
		)
		(fill
			(thermal_gap 0.5)
			(thermal_bridge_width 0.5)
			(island_removal_mode 0)
		)
		(polygon
			(pts
				(arc
					(start 376.190256 -129.158238)
					(mid 376.610227 -128.837073)
					(end 376.289062 -129.257044)
				)
				(arc
					(start 376.269504 -129.276602)
					(mid 376.25998 -129.29095)
					(end 376.25655 -129.307844)
				)
				(xy 376.25655 -129.40665)
				(arc
					(start 376.42165 -129.40665)
					(mid 376.80265 -129.02565)
					(end 376.42165 -128.64465)
				)
				(arc
					(start 375.761504 -128.64465)
					(mid 375.38025 -129.025523)
					(end 375.76125 -129.40665)
				)
				(xy 375.82475 -129.40665)
				(arc
					(start 375.82475 -129.28473)
					(mid 375.621067 -128.798706)
					(end 375.96445 -129.19837)
				)
				(xy 375.96445 -129.40665) (xy 376.11685 -129.40665) (xy 376.11685 -129.278888)
				(arc
					(start 376.119644 -129.276094)
					(mid 376.130928 -129.237319)
					(end 376.150378 -129.201926)
				)
				(xy 376.150378 -129.198116) (xy 376.170698 -129.177796) (xy 376.170952 -129.177542)
			)
		)
	)
	(zone
		(net "P3V3_STBY_MNG")
		(layer "In2.Cu")
		(hatch none 0.5)
		(connect_pads
			(clearance 0.5)
		)
		(min_thickness 0.25)
		(fill yes
			(thermal_gap 0.5)
			(thermal_bridge_width 0.5)
			(island_removal_mode 0)
		)
		(polygon
			(pts
				(xy 482.418644 -30.854142) (xy 480.501198 -30.854142) (xy 480.25177 -30.604714) (xy 480.25177 -29.466794)
				(xy 479.332036 -28.54706) (xy 475.591124 -28.54706) (xy 475.177358 -28.133294) (xy 475.177358 -26.650442)
				(xy 475.990412 -25.837388) (xy 479.0186 -25.837388) (xy 479.021394 -25.834594) (xy 479.478594 -25.834594)
				(xy 479.9076 -26.2636) (xy 479.9076 -26.924) (xy 481.1268 -28.1432) (xy 482.3714 -28.1432) (xy 482.63683 -28.40863)
				(xy 482.63683 -30.635956)
			)
		)
	)
	(zone
		(net "GND")
		(layer "In2.Cu")
		(hatch none 0.5)
		(connect_pads
			(clearance 0.5)
		)
		(min_thickness 0.25)
		(fill yes
			(thermal_gap 0.5)
			(thermal_bridge_width 0.5)
			(island_removal_mode 0)
		)
		(polygon
			(pts
				(arc
					(start -5.184648 -161.9504)
					(mid -5.224047 -162.020639)
					(end -5.237734 -162.100006)
				)
				(arc
					(start -5.237734 -168.099994)
					(mid -5.1681 -168.268104)
					(end -4.99999 -168.337738)
				)
				(xy 501.0404 -168.337738) (xy 501.0404 -161.9504)
			)
		)
		(polygon
			(pts
				(xy 241.6302 -162.5346) (xy 239.1664 -162.5346) (xy 236.5756 -162.5346) (xy 236.5756 -167.5384)
				(xy 239.1664 -167.5384) (xy 241.6302 -167.5384) (xy 309.0672 -167.5384) (xy 309.0672 -162.5346)
			)
		)
		(polygon
			(pts
				(xy 73.4822 -162.56) (xy 63.627 -162.56) (xy 61.3156 -162.56) (xy 61.1124 -162.56) (xy 61.1124 -162.5854)
				(xy 61.1124 -167.5384) (xy 61.3156 -167.5384) (xy 63.627 -167.5384) (xy 73.4822 -167.5384) (xy 101.4222 -167.5384)
				(xy 101.4222 -162.56)
			)
		)
	)
	(zone
		(net "P1V8_MCP_CPU0")
		(layer "In2.Cu")
		(hatch none 0.5)
		(connect_pads
			(clearance 0.5)
		)
		(min_thickness 0.25)
		(fill yes
			(thermal_gap 0.5)
			(thermal_bridge_width 0.5)
			(island_removal_mode 0)
		)
		(polygon
			(pts
				(xy 317.5 -45.3898) (xy 317.5 -49.403) (xy 314.071 -52.832) (xy 314.071 -64.008) (xy 314.071 -66.421)
				(xy 309.499 -70.993) (xy 307.975 -70.993) (xy 307.213 -70.993) (xy 306.705 -71.501) (xy 305.435 -71.501)
				(xy 304.8 -70.866) (xy 304.165 -70.866) (xy 300.99 -72.771) (xy 297.434 -72.771) (xy 294.894 -74.295)
				(xy 293.243 -74.295) (xy 291.465 -75.311) (xy 288.036 -75.311) (xy 286.512 -76.2) (xy 286.512 -78.9178)
				(xy 286.5628 -78.9686) (xy 286.5628 -79.2226) (xy 286.3215 -79.4639) (xy 286.0421 -79.4639) (xy 284.48 -81.026)
				(xy 283.972 -81.026) (xy 283.591 -80.645) (xy 283.591 -78.232) (xy 283.718 -78.105) (xy 284.353 -78.105)
				(xy 285.115 -77.343) (xy 285.115 -74.549) (xy 285.75 -73.914) (xy 286.893 -72.771) (xy 290.576 -72.771)
				(xy 292.354 -71.755) (xy 294.259 -71.755) (xy 298.130722 -69.525896) (xy 298.460922 -69.856096)
				(xy 302.224694 -69.856096) (xy 302.742346 -69.338444) (xy 303.921414 -69.338444) (xy 304.032412 -69.449442)
				(xy 304.81016 -69.449442) (xy 305.312826 -68.946776) (xy 305.596036 -68.946776) (xy 305.98872 -68.554092)
				(xy 305.98872 -68.5038) (xy 306.350162 -68.5038) (xy 306.384198 -68.537836) (xy 306.554124 -68.537836)
				(xy 306.74056 -68.3514) (xy 307.09616 -67.9958) (xy 307.4924 -67.9958) (xy 308.04358 -67.44462)
				(xy 308.04358 -67.04838) (xy 308.356 -66.73596) (xy 311.9374 -63.15456) (xy 311.9374 -62.738) (xy 311.9374 -57.0738)
				(xy 311.1754 -56.3118) (xy 311.1754 -45.43044) (xy 311.51322 -45.09262) (xy 312.86704 -45.09262)
				(xy 314.52566 -43.434) (xy 316.8904 -43.434) (xy 317.0936 -43.6372) (xy 317.0936 -44.2468) (xy 316.9412 -44.3992)
				(xy 316.484 -44.3992) (xy 316.3316 -44.5516) (xy 316.3316 -45.0596) (xy 316.4586 -45.1866) (xy 317.2968 -45.1866)
			)
		)
	)
	(zone
		(layer "In2.Cu")
		(hatch none 0.5)
		(connect_pads
			(clearance 0)
		)
		(min_thickness 0.25)
		(keepout
			(tracks allowed)
			(vias allowed)
			(pads allowed)
			(copperpour allowed)
			(footprints allowed)
		)
		(placement
			(enabled no)
			(sheetname "")
		)
		(fill
			(thermal_gap 0.5)
			(thermal_bridge_width 0.5)
			(island_removal_mode 0)
		)
		(polygon
			(pts
				(xy 107.312968 -47.9298) (xy 111.986568 -47.9298) (xy 113.332768 -49.276) (xy 113.332768 -50.7746)
				(xy 114.094768 -51.5366) (xy 114.170968 -51.6128) (xy 114.170968 -53.1368) (xy 114.247168 -53.213)
				(xy 114.247168 -54.7624) (xy 112.570768 -54.7624) (xy 112.570768 -53.6194) (xy 112.342168 -53.3908)
				(xy 111.249968 -53.3908) (xy 110.767368 -53.8734) (xy 108.354368 -53.8734) (xy 108.252768 -53.7718)
				(xy 108.252768 -51.943) (xy 107.135168 -50.8254) (xy 107.135168 -48.1076)
			)
		)
	)
	(zone
		(layer "In2.Cu")
		(hatch none 0.5)
		(connect_pads
			(clearance 0)
		)
		(min_thickness 0.25)
		(keepout
			(tracks not_allowed)
			(vias allowed)
			(pads allowed)
			(copperpour not_allowed)
			(footprints allowed)
		)
		(placement
			(enabled no)
			(sheetname "")
		)
		(fill
			(thermal_gap 0.5)
			(thermal_bridge_width 0.5)
			(island_removal_mode 0)
		)
		(polygon
			(pts
				(arc
					(start 421.32377 -139.59586)
					(mid 420.965376 -139.953873)
					(end 421.323516 -140.31214)
				)
				(arc
					(start 422.593516 -140.31214)
					(mid 422.951656 -139.954)
					(end 422.593516 -139.59586)
				)
				(xy 422.21785 -139.59586)
				(arc
					(start 422.21785 -139.827)
					(mid 422.234589 -139.867411)
					(end 422.275 -139.88415)
				)
				(arc
					(start 422.336214 -139.88415)
					(mid 422.860131 -139.954)
					(end 422.336214 -140.02385)
				)
				(xy 422.246044 -140.02385)
				(arc
					(start 422.243504 -140.02131)
					(mid 422.135809 -139.966191)
					(end 422.08069 -139.858496)
				)
				(xy 422.07815 -139.855956) (xy 422.07815 -139.59586) (xy 421.92575 -139.59586) (xy 421.92575 -139.855956)
				(arc
					(start 421.92321 -139.858496)
					(mid 421.868091 -139.966191)
					(end 421.760396 -140.02131)
				)
				(xy 421.757856 -140.02385)
				(arc
					(start 421.580818 -140.02385)
					(mid 421.056901 -139.954)
					(end 421.580818 -139.88415)
				)
				(arc
					(start 421.7289 -139.88415)
					(mid 421.769311 -139.867411)
					(end 421.78605 -139.827)
				)
				(xy 421.78605 -139.59586)
			)
		)
	)
	(zone
		(layer "In2.Cu")
		(hatch none 0.5)
		(connect_pads
			(clearance 0)
		)
		(min_thickness 0.25)
		(keepout
			(tracks not_allowed)
			(vias allowed)
			(pads allowed)
			(copperpour not_allowed)
			(footprints allowed)
		)
		(placement
			(enabled no)
			(sheetname "")
		)
		(fill
			(thermal_gap 0.5)
			(thermal_bridge_width 0.5)
			(island_removal_mode 0)
		)
		(polygon
			(pts
				(xy 426.20438 -2.820924) (xy 426.4025 -3.019044) (xy 426.4025 -3.274314) (xy 426.5549 -3.274314)
				(xy 426.5549 -2.976118) (xy 426.710094 -2.820924)
				(arc
					(start 426.82541 -2.820924)
					(mid 427.349327 -2.890774)
					(end 426.82541 -2.960624)
				)
				(xy 426.768006 -2.960624) (xy 426.6946 -3.03403) (xy 426.6946 -3.274314)
				(arc
					(start 427.082458 -3.274314)
					(mid 427.466252 -2.890901)
					(end 427.082712 -2.507234)
				)
				(arc
					(start 425.812712 -2.507234)
					(mid 425.429172 -2.890774)
					(end 425.812712 -3.274314)
				)
				(xy 426.2628 -3.274314) (xy 426.2628 -3.076956) (xy 426.146468 -2.960624)
				(arc
					(start 426.070014 -2.960624)
					(mid 425.546097 -2.890774)
					(end 426.070014 -2.820924)
				)
			)
		)
	)
	(zone
		(layer "In2.Cu")
		(hatch none 0.5)
		(connect_pads
			(clearance 0)
		)
		(min_thickness 0.25)
		(keepout
			(tracks not_allowed)
			(vias allowed)
			(pads allowed)
			(copperpour not_allowed)
			(footprints allowed)
		)
		(placement
			(enabled no)
			(sheetname "")
		)
		(fill
			(thermal_gap 0.5)
			(thermal_bridge_width 0.5)
			(island_removal_mode 0)
		)
		(polygon
			(pts
				(arc
					(start 346.383356 -67.310762)
					(mid 345.963385 -67.631927)
					(end 346.28455 -67.211956)
				)
				(xy 346.37345 -67.123056) (xy 346.37345 -67.05981)
				(arc
					(start 346.152216 -67.05981)
					(mid 345.768676 -67.443223)
					(end 346.151962 -67.82689)
				)
				(arc
					(start 347.043248 -67.82689)
					(mid 347.426788 -67.44335)
					(end 347.043248 -67.05981)
				)
				(xy 346.80525 -67.05981) (xy 346.80525 -67.106546)
				(arc
					(start 346.91066 -67.211956)
					(mid 347.231825 -67.631927)
					(end 346.811854 -67.310762)
				)
				(xy 346.66555 -67.164458) (xy 346.66555 -67.05981) (xy 346.51315 -67.05981) (xy 346.51315 -67.180968)
			)
		)
	)
	(zone
		(layer "In2.Cu")
		(hatch none 0.5)
		(connect_pads
			(clearance 0)
		)
		(min_thickness 0.25)
		(keepout
			(tracks allowed)
			(vias allowed)
			(pads allowed)
			(copperpour allowed)
			(footprints allowed)
		)
		(placement
			(enabled no)
			(sheetname "")
		)
		(fill
			(thermal_gap 0.5)
			(thermal_bridge_width 0.5)
			(island_removal_mode 0)
		)
		(polygon
			(pts
				(xy 403.733 -120.65) (xy 403.733 -119.634) (xy 405.13 -119.634) (xy 405.13 -120.65)
			)
		)
	)
	(zone
		(net "VR_FET_SW_P12V_STBY_PVDDQ_DEF")
		(layer "In2.Cu")
		(hatch none 0.5)
		(connect_pads
			(clearance 0.5)
		)
		(min_thickness 0.25)
		(fill yes
			(thermal_gap 0.5)
			(thermal_bridge_width 0.5)
			(island_removal_mode 0)
		)
		(polygon
			(pts
				(xy 348.9198 -145.0086) (xy 351.1296 -145.0086) (xy 351.839022 -144.299178) (xy 351.839022 -141.606016)
				(xy 351.480374 -141.247368) (xy 348.644972 -141.247368) (xy 348.3102 -141.58214) (xy 348.3102 -144.399)
			)
		)
	)
	(zone
		(layer "In2.Cu")
		(hatch none 0.5)
		(connect_pads
			(clearance 0)
		)
		(min_thickness 0.25)
		(keepout
			(tracks not_allowed)
			(vias allowed)
			(pads allowed)
			(copperpour not_allowed)
			(footprints allowed)
		)
		(placement
			(enabled no)
			(sheetname "")
		)
		(fill
			(thermal_gap 0.5)
			(thermal_bridge_width 0.5)
			(island_removal_mode 0)
		)
		(polygon
			(pts
				(xy 465.2518 -10.0076) (xy 464.997038 -10.262362) (xy 464.997038 -17.399) (xy 467.6648 -17.399)
				(xy 467.6648 -14.986) (xy 470.97823 -14.986) (xy 470.97823 -17.0688) (xy 473.4814 -17.0688) (xy 474.0148 -16.5354)
				(xy 474.0148 -11.809984) (xy 474.015308 -11.810492) (xy 474.015308 -10.819892) (xy 474.016324 -10.818876)
				(xy 474.016324 -10.76706) (xy 469.34374 -10.76706) (xy 468.58428 -10.0076)
				(arc
					(start 466.99043 -10.0076)
					(mid 466.979 -10.515857)
					(end 466.96757 -10.0076)
				)
			)
		)
	)
	(zone
		(layer "In2.Cu")
		(hatch none 0.5)
		(connect_pads
			(clearance 0)
		)
		(min_thickness 0.25)
		(keepout
			(tracks allowed)
			(vias allowed)
			(pads allowed)
			(copperpour allowed)
			(footprints allowed)
		)
		(placement
			(enabled no)
			(sheetname "")
		)
		(fill
			(thermal_gap 0.5)
			(thermal_bridge_width 0.5)
			(island_removal_mode 0)
		)
		(polygon
			(pts
				(xy 119.581168 -53.1876) (xy 119.581168 -52.3748) (xy 121.740168 -50.2158) (xy 123.340368 -50.2158)
				(xy 125.169168 -52.0446) (xy 126.515368 -52.0446) (xy 126.515368 -53.9242) (xy 125.372368 -55.0672)
				(xy 125.372368 -56.7182) (xy 124.724668 -57.3659) (xy 124.724668 -57.1373) (xy 124.127768 -56.5404)
				(xy 124.127768 -56.1848) (xy 124.407168 -55.9054) (xy 124.407168 -55.5498) (xy 124.254768 -55.3974)
				(xy 123.568968 -55.3974) (xy 123.568968 -54.229) (xy 123.721368 -54.0766) (xy 123.721368 -53.4924)
				(xy 123.594368 -53.3654) (xy 121.714768 -53.3654) (xy 121.130568 -53.9496) (xy 119.327168 -53.9496)
				(xy 119.327168 -53.4416)
			)
		)
	)
	(zone
		(layer "In2.Cu")
		(hatch none 0.5)
		(connect_pads
			(clearance 0)
		)
		(min_thickness 0.25)
		(keepout
			(tracks not_allowed)
			(vias allowed)
			(pads allowed)
			(copperpour not_allowed)
			(footprints allowed)
		)
		(placement
			(enabled no)
			(sheetname "")
		)
		(fill
			(thermal_gap 0.5)
			(thermal_bridge_width 0.5)
			(island_removal_mode 0)
		)
		(polygon
			(pts
				(arc
					(start 458.26045 -2.49936)
					(mid 458.229837 -2.488609)
					(end 458.20076 -2.474214)
				)
				(xy 458.175614 -2.49936)
			)
		)
	)
	(zone
		(layer "In2.Cu")
		(hatch none 0.5)
		(connect_pads
			(clearance 0)
		)
		(min_thickness 0.25)
		(keepout
			(tracks not_allowed)
			(vias allowed)
			(pads allowed)
			(copperpour not_allowed)
			(footprints allowed)
		)
		(placement
			(enabled no)
			(sheetname "")
		)
		(fill
			(thermal_gap 0.5)
			(thermal_bridge_width 0.5)
			(island_removal_mode 0)
		)
		(polygon
			(pts
				(xy 407.982166 -142.227554) (xy 407.98242 -142.227808)
				(arc
					(start 408.180794 -142.426182)
					(mid 408.501959 -142.846153)
					(end 408.081988 -142.524988)
				)
				(xy 407.929842 -142.372842)
				(arc
					(start 407.929842 -142.657322)
					(mid 408.313255 -143.041116)
					(end 408.696922 -142.657576)
				)
				(arc
					(start 408.696922 -141.641576)
					(mid 408.313382 -141.258036)
					(end 407.929842 -141.641576)
				)
				(xy 407.929842 -141.881606)
				(arc
					(start 407.956258 -141.881606)
					(mid 407.973185 -141.878257)
					(end 407.9875 -141.868652)
				)
				(arc
					(start 408.081988 -141.774164)
					(mid 408.501959 -141.452999)
					(end 408.180794 -141.87297)
				)
				(xy 408.08656 -141.967204) (xy 408.086306 -141.967458) (xy 408.065986 -141.987778)
				(arc
					(start 408.062176 -141.987778)
					(mid 408.02679 -142.007247)
					(end 407.988008 -142.018512)
				)
				(xy 407.985214 -142.021306) (xy 407.929842 -142.021306)
				(arc
					(start 407.929842 -142.190978)
					(mid 407.944303 -142.198475)
					(end 407.958036 -142.207234)
				)
				(xy 407.961846 -142.207234)
			)
		)
	)
	(zone
		(layer "In2.Cu")
		(hatch none 0.5)
		(connect_pads
			(clearance 0)
		)
		(min_thickness 0.25)
		(keepout
			(tracks allowed)
			(vias allowed)
			(pads allowed)
			(copperpour allowed)
			(footprints allowed)
		)
		(placement
			(enabled no)
			(sheetname "")
		)
		(fill
			(thermal_gap 0.5)
			(thermal_bridge_width 0.5)
			(island_removal_mode 0)
		)
		(polygon
			(pts
				(xy 285.623 -49.149) (xy 285.623 -50.673) (xy 284.48 -51.816) (xy 284.48 -54.864) (xy 282.575 -54.864)
				(xy 281.813 -54.102) (xy 279.146 -54.102) (xy 279.146 -51.689) (xy 278.257 -50.8) (xy 278.257 -48.514)
				(xy 278.257 -48.26) (xy 278.384 -48.133) (xy 284.988 -48.133) (xy 285.623 -48.768)
			)
		)
	)
	(zone
		(layer "In2.Cu")
		(hatch none 0.5)
		(connect_pads
			(clearance 0)
		)
		(min_thickness 0.25)
		(keepout
			(tracks not_allowed)
			(vias allowed)
			(pads allowed)
			(copperpour not_allowed)
			(footprints allowed)
		)
		(placement
			(enabled no)
			(sheetname "")
		)
		(fill
			(thermal_gap 0.5)
			(thermal_bridge_width 0.5)
			(island_removal_mode 0)
		)
		(polygon
			(pts
				(xy 455.014076 -2.94259) (xy 455.227944 -3.156458) (xy 455.227944 -3.273298) (xy 455.380344 -3.274568)
				(xy 455.380344 -3.132328) (xy 455.559922 -2.95275)
				(arc
					(start 455.69251 -2.95275)
					(mid 455.760917 -2.834446)
					(end 455.878946 -2.765552)
				)
				(arc
					(start 454.754742 -2.756408)
					(mid 454.87029 -2.825664)
					(end 454.937114 -2.94259)
				)
			)
		)
	)
	(zone
		(layer "In2.Cu")
		(hatch none 0.5)
		(connect_pads
			(clearance 0)
		)
		(min_thickness 0.25)
		(keepout
			(tracks allowed)
			(vias allowed)
			(pads allowed)
			(copperpour allowed)
			(footprints allowed)
		)
		(placement
			(enabled no)
			(sheetname "")
		)
		(fill
			(thermal_gap 0.5)
			(thermal_bridge_width 0.5)
			(island_removal_mode 0)
		)
		(polygon
			(pts
				(xy 262.269224 -91.26474) (xy 262.269224 -88.537034) (xy 268.298676 -88.537034) (xy 268.298676 -91.26474)
			)
		)
	)
	(zone
		(layer "In2.Cu")
		(hatch none 0.5)
		(connect_pads
			(clearance 0)
		)
		(min_thickness 0.25)
		(keepout
			(tracks not_allowed)
			(vias allowed)
			(pads allowed)
			(copperpour not_allowed)
			(footprints allowed)
		)
		(placement
			(enabled no)
			(sheetname "")
		)
		(fill
			(thermal_gap 0.5)
			(thermal_bridge_width 0.5)
			(island_removal_mode 0)
		)
		(polygon
			(pts
				(arc
					(start 424.078654 -139.454636)
					(mid 423.69486 -139.838049)
					(end 424.0784 -140.221716)
				)
				(xy 424.340528 -140.221716)
				(arc
					(start 424.340528 -140.012928)
					(mid 424.335368 -139.980177)
					(end 424.320208 -139.950698)
				)
				(arc
					(start 424.320208 -139.950698)
					(mid 423.813983 -139.803305)
					(end 424.341036 -139.792202)
				)
				(arc
					(start 424.341036 -139.792202)
					(mid 424.433825 -139.869581)
					(end 424.478196 -139.98194)
				)
				(xy 424.480228 -139.983972) (xy 424.480228 -140.221716) (xy 424.632628 -140.221716) (xy 424.632628 -139.92352)
				(arc
					(start 424.635422 -139.920726)
					(mid 424.68659 -139.822288)
					(end 424.785028 -139.77112)
				)
				(xy 424.787822 -139.768326)
				(arc
					(start 425.091098 -139.768326)
					(mid 425.615015 -139.838176)
					(end 425.091098 -139.908026)
				)
				(arc
					(start 424.816778 -139.908026)
					(mid 424.785347 -139.921045)
					(end 424.772328 -139.952476)
				)
				(xy 424.772328 -140.221716)
				(arc
					(start 425.3484 -140.221716)
					(mid 425.73194 -139.838176)
					(end 425.3484 -139.454636)
				)
			)
		)
	)
	(zone
		(layer "In2.Cu")
		(hatch none 0.5)
		(connect_pads
			(clearance 0)
		)
		(min_thickness 0.25)
		(keepout
			(tracks not_allowed)
			(vias allowed)
			(pads allowed)
			(copperpour not_allowed)
			(footprints allowed)
		)
		(placement
			(enabled no)
			(sheetname "")
		)
		(fill
			(thermal_gap 0.5)
			(thermal_bridge_width 0.5)
			(island_removal_mode 0)
		)
		(polygon
			(pts
				(xy 424.68292 -9.953498) (xy 424.82135 -10.091928) (xy 424.82135 -10.406888) (xy 424.97375 -10.406888)
				(xy 424.97375 -10.080498) (xy 425.10075 -9.953498)
				(arc
					(start 425.24299 -9.953498)
					(mid 425.766907 -10.023348)
					(end 425.24299 -10.093198)
				)
				(xy 425.158662 -10.093198) (xy 425.11345 -10.13841) (xy 425.11345 -10.406888)
				(arc
					(start 425.500038 -10.406888)
					(mid 425.883832 -10.023475)
					(end 425.500292 -9.639808)
				)
				(arc
					(start 424.230292 -9.639808)
					(mid 423.846752 -10.023348)
					(end 424.230292 -10.406888)
				)
				(xy 424.68165 -10.406888) (xy 424.68165 -10.14984) (xy 424.625008 -10.093198)
				(arc
					(start 424.487594 -10.093198)
					(mid 423.963677 -10.023348)
					(end 424.487594 -9.953498)
				)
			)
		)
	)
	(zone
		(layer "In2.Cu")
		(hatch none 0.5)
		(connect_pads
			(clearance 0)
		)
		(min_thickness 0.25)
		(keepout
			(tracks not_allowed)
			(vias allowed)
			(pads allowed)
			(copperpour not_allowed)
			(footprints allowed)
		)
		(placement
			(enabled no)
			(sheetname "")
		)
		(fill
			(thermal_gap 0.5)
			(thermal_bridge_width 0.5)
			(island_removal_mode 0)
		)
		(polygon
			(pts
				(arc
					(start 383.191258 -127.390652)
					(mid 382.810004 -127.771525)
					(end 383.191004 -128.152652)
				)
				(arc
					(start 383.290826 -128.152652)
					(mid 383.284491 -128.114987)
					(end 383.28092 -128.07696)
				)
				(xy 383.280158 -128.076198)
				(arc
					(start 383.280158 -128.023112)
					(mid 383.029318 -127.55943)
					(end 383.409698 -127.924306)
				)
				(arc
					(start 383.409698 -127.924306)
					(mid 383.414317 -127.94091)
					(end 383.417572 -127.957834)
				)
				(xy 383.419858 -127.96012)
				(arc
					(start 383.419858 -128.047242)
					(mid 383.423563 -128.100458)
					(end 383.43459 -128.152652)
				)
				(arc
					(start 383.597658 -128.152652)
					(mid 383.582816 -128.116432)
					(end 383.57429 -128.07823)
				)
				(xy 383.572258 -128.076198) (xy 383.572258 -127.972312)
				(arc
					(start 383.575052 -127.969518)
					(mid 383.583641 -127.938399)
					(end 383.597658 -127.90932)
				)
				(arc
					(start 383.597658 -127.90932)
					(mid 384.004823 -127.573869)
					(end 383.711958 -128.012698)
				)
				(arc
					(start 383.711958 -128.047242)
					(mid 383.738889 -128.112259)
					(end 383.803906 -128.13919)
				)
				(arc
					(start 383.926334 -128.13919)
					(mid 384.203613 -127.721038)
					(end 383.826004 -127.390652)
				)
			)
		)
	)
	(zone
		(layer "In2.Cu")
		(hatch none 0.5)
		(connect_pads
			(clearance 0)
		)
		(min_thickness 0.25)
		(keepout
			(tracks not_allowed)
			(vias allowed)
			(pads allowed)
			(copperpour not_allowed)
			(footprints allowed)
		)
		(placement
			(enabled no)
			(sheetname "")
		)
		(fill
			(thermal_gap 0.5)
			(thermal_bridge_width 0.5)
			(island_removal_mode 0)
		)
		(polygon
			(pts
				(xy 411.781498 -2.66192) (xy 411.936692 -2.817114) (xy 411.936692 -3.07086) (xy 411.892242 -3.11531)
				(xy 412.089092 -3.11531) (xy 412.089092 -2.817114) (xy 412.244286 -2.66192)
				(arc
					(start 412.44139 -2.66192)
					(mid 412.965307 -2.73177)
					(end 412.44139 -2.80162)
				)
				(xy 412.302198 -2.80162) (xy 412.228792 -2.875026) (xy 412.228792 -3.11531)
				(arc
					(start 412.698438 -3.11531)
					(mid 413.082232 -2.731897)
					(end 412.698692 -2.34823)
				)
				(arc
					(start 411.428692 -2.34823)
					(mid 411.045152 -2.73177)
					(end 411.428692 -3.11531)
				)
				(xy 411.69463 -3.11531) (xy 411.796992 -3.012948) (xy 411.796992 -2.875026) (xy 411.723586 -2.80162)
				(arc
					(start 411.685994 -2.80162)
					(mid 411.162077 -2.73177)
					(end 411.685994 -2.66192)
				)
			)
		)
	)
	(zone
		(layer "In2.Cu")
		(hatch none 0.5)
		(connect_pads
			(clearance 0)
		)
		(min_thickness 0.25)
		(keepout
			(tracks allowed)
			(vias allowed)
			(pads allowed)
			(copperpour allowed)
			(footprints allowed)
		)
		(placement
			(enabled no)
			(sheetname "")
		)
		(fill
			(thermal_gap 0.5)
			(thermal_bridge_width 0.5)
			(island_removal_mode 0)
		)
		(polygon
			(pts
				(xy 272.3134 -47.9298) (xy 276.987 -47.9298) (xy 278.3332 -49.276) (xy 278.3332 -50.7746) (xy 279.0952 -51.5366)
				(xy 279.1714 -51.6128) (xy 279.1714 -53.1368) (xy 279.2476 -53.213) (xy 279.2476 -54.7624) (xy 277.5712 -54.7624)
				(xy 277.5712 -53.6194) (xy 277.3426 -53.3908) (xy 276.2504 -53.3908) (xy 275.7678 -53.8734) (xy 273.3548 -53.8734)
				(xy 273.2532 -53.7718) (xy 273.2532 -51.943) (xy 272.1356 -50.8254) (xy 272.1356 -48.1076)
			)
		)
	)
	(zone
		(layer "In2.Cu")
		(hatch none 0.5)
		(connect_pads
			(clearance 0)
		)
		(min_thickness 0.25)
		(keepout
			(tracks not_allowed)
			(vias allowed)
			(pads allowed)
			(copperpour not_allowed)
			(footprints allowed)
		)
		(placement
			(enabled no)
			(sheetname "")
		)
		(fill
			(thermal_gap 0.5)
			(thermal_bridge_width 0.5)
			(island_removal_mode 0)
		)
		(polygon
			(pts
				(arc
					(start 454.937114 -3.08229)
					(mid 454.868707 -3.200594)
					(end 454.750678 -3.269488)
				)
				(xy 455.088244 -3.272282) (xy 455.088244 -3.21437) (xy 454.956164 -3.08229)
			)
		)
	)
	(zone
		(net "PVCCIN_CPU0")
		(layer "In2.Cu")
		(hatch none 0.5)
		(connect_pads
			(clearance 0.5)
		)
		(min_thickness 0.25)
		(fill yes
			(thermal_gap 0.5)
			(thermal_bridge_width 0.5)
			(island_removal_mode 0)
		)
		(polygon
			(pts
				(xy 210.9724 -54.3306) (xy 208.434432 -54.3306) (xy 208.434432 -92.105988) (xy 209.165444 -92.837)
				(xy 218.591638 -92.837) (xy 227.982018 -83.44662) (xy 231.683052 -83.44662) (xy 233.588052 -83.44662)
				(xy 236.364272 -80.6704) (xy 243.918232 -80.6704) (xy 249.455432 -80.6704) (xy 252.782832 -83.9978)
				(xy 256.300732 -87.5157) (xy 259.88772 -87.5157) (xy 260.01726 -87.38616) (xy 261.10184 -87.38616)
				(xy 261.54634 -87.83066) (xy 262.43534 -87.83066) (xy 263.0297 -87.83066) (xy 263.51484 -88.3158)
				(xy 263.69264 -88.4936) (xy 267.0429 -88.4936) (xy 267.2207 -88.3158) (xy 267.6906 -87.8459) (xy 267.6906 -87.83066)
				(xy 270.5989 -87.83066) (xy 270.78178 -87.64778) (xy 275.5392 -87.64778) (xy 279.427432 -83.759548)
				(xy 279.427432 -71.604632) (xy 275.9964 -68.1736) (xy 275.9964 -67.5894) (xy 276.098 -67.4878) (xy 276.098 -66.8782)
				(xy 275.8948 -66.675) (xy 273.839178 -66.675) (xy 273.723862 -66.790316) (xy 273.723862 -67.88785)
				(xy 273.647662 -67.96405) (xy 270.67891 -67.96405) (xy 267.087858 -67.96405) (xy 262.773922 -67.96405)
				(xy 261.484872 -66.675) (xy 233.453432 -66.675) (xy 233.453432 -68.834) (xy 232.310432 -69.977)
				(xy 226.6188 -69.977)
			)
		)
	)
	(zone
		(layer "In2.Cu")
		(hatch none 0.5)
		(connect_pads
			(clearance 0)
		)
		(min_thickness 0.25)
		(keepout
			(tracks not_allowed)
			(vias allowed)
			(pads allowed)
			(copperpour not_allowed)
			(footprints allowed)
		)
		(placement
			(enabled no)
			(sheetname "")
		)
		(fill
			(thermal_gap 0.5)
			(thermal_bridge_width 0.5)
			(island_removal_mode 0)
		)
		(polygon
			(pts
				(arc
					(start 383.104644 -131.466082)
					(mid 382.703578 -131.810235)
					(end 383.00025 -131.372864)
				)
				(xy 383.098294 -131.27482)
				(arc
					(start 383.098802 -131.27482)
					(mid 383.123474 -131.252204)
					(end 383.14884 -131.23037)
				)
				(arc
					(start 382.881124 -131.23037)
					(mid 382.49987 -131.611243)
					(end 382.88087 -131.99237)
				)
				(arc
					(start 383.54127 -131.99237)
					(mid 383.873426 -131.798007)
					(end 383.866644 -131.41325)
				)
				(arc
					(start 383.836418 -131.41325)
					(mid 383.819228 -131.416687)
					(end 383.804668 -131.426458)
				)
				(arc
					(start 383.765044 -131.466082)
					(mid 383.363978 -131.810235)
					(end 383.66065 -131.372864)
				)
				(xy 383.726436 -131.307078) (xy 383.730246 -131.307078)
				(arc
					(start 383.75209 -131.29387)
					(mid 383.651365 -131.24657)
					(end 383.54127 -131.23037)
				)
				(arc
					(start 383.39776 -131.23037)
					(mid 383.281073 -131.303949)
					(end 383.176526 -131.393946)
				)
			)
		)
	)
	(zone
		(layer "In2.Cu")
		(hatch none 0.5)
		(connect_pads
			(clearance 0)
		)
		(min_thickness 0.25)
		(keepout
			(tracks not_allowed)
			(vias allowed)
			(pads allowed)
			(copperpour not_allowed)
			(footprints allowed)
		)
		(placement
			(enabled no)
			(sheetname "")
		)
		(fill
			(thermal_gap 0.5)
			(thermal_bridge_width 0.5)
			(island_removal_mode 0)
		)
		(polygon
			(pts
				(arc
					(start 377.366276 -128.651)
					(mid 376.985022 -129.031873)
					(end 377.366022 -129.413)
				)
				(xy 377.37923 -129.413)
				(arc
					(start 377.37923 -129.298446)
					(mid 377.279067 -128.779695)
					(end 377.51893 -129.25044)
				)
				(xy 377.51893 -129.413) (xy 377.67133 -129.413) (xy 377.67133 -129.38633)
				(arc
					(start 377.672854 -129.384806)
					(mid 377.694912 -129.297054)
					(end 377.741434 -129.219452)
				)
				(xy 377.741434 -129.217166)
				(arc
					(start 377.794774 -129.16408)
					(mid 378.216021 -128.844357)
					(end 377.893072 -129.26314)
				)
				(arc
					(start 377.860814 -129.295398)
					(mid 377.82442 -129.349334)
					(end 377.81103 -129.413)
				)
				(arc
					(start 378.026422 -129.413)
					(mid 378.407422 -129.032)
					(end 378.026422 -128.651)
				)
			)
		)
	)
	(zone
		(layer "In2.Cu")
		(hatch none 0.5)
		(connect_pads
			(clearance 0)
		)
		(min_thickness 0.25)
		(keepout
			(tracks not_allowed)
			(vias allowed)
			(pads allowed)
			(copperpour not_allowed)
			(footprints allowed)
		)
		(placement
			(enabled no)
			(sheetname "")
		)
		(fill
			(thermal_gap 0.5)
			(thermal_bridge_width 0.5)
			(island_removal_mode 0)
		)
		(polygon
			(pts
				(xy 457.978002 -2.49936)
				(arc
					(start 458.101954 -2.375408)
					(mid 458.086363 -2.142217)
					(end 458.26045 -1.98628)
				)
				(arc
					(start 457.136246 -1.98628)
					(mid 457.310341 -2.142214)
					(end 457.294742 -2.375408)
				)
				(xy 457.418694 -2.49936)
			)
		)
	)
	(zone
		(layer "In2.Cu")
		(hatch none 0.5)
		(connect_pads
			(clearance 0)
		)
		(min_thickness 0.25)
		(keepout
			(tracks not_allowed)
			(vias allowed)
			(pads allowed)
			(copperpour not_allowed)
			(footprints allowed)
		)
		(placement
			(enabled no)
			(sheetname "")
		)
		(fill
			(thermal_gap 0.5)
			(thermal_bridge_width 0.5)
			(island_removal_mode 0)
		)
		(polygon
			(pts
				(xy 422.569894 -10.391902) (xy 422.569894 -10.147046) (xy 422.763442 -9.953498)
				(arc
					(start 422.84269 -9.953498)
					(mid 423.366607 -10.023348)
					(end 422.84269 -10.093198)
				)
				(xy 422.821354 -10.093198) (xy 422.709594 -10.204958) (xy 422.709594 -10.406888)
				(arc
					(start 423.099738 -10.406888)
					(mid 423.483532 -10.023475)
					(end 423.099992 -9.639808)
				)
				(arc
					(start 421.829992 -9.639808)
					(mid 421.446452 -10.023348)
					(end 421.829992 -10.406888)
				)
				(xy 422.14165 -10.406888) (xy 422.277794 -10.270744) (xy 422.277794 -10.166604) (xy 422.204388 -10.093198)
				(arc
					(start 422.087294 -10.093198)
					(mid 421.563377 -10.023348)
					(end 422.087294 -9.953498)
				)
				(xy 422.2623 -9.953498) (xy 422.417494 -10.108692) (xy 422.417494 -10.328656) (xy 422.339262 -10.406888)
				(xy 422.554908 -10.406888)
			)
		)
	)
	(zone
		(layer "In2.Cu")
		(hatch none 0.5)
		(connect_pads
			(clearance 0)
		)
		(min_thickness 0.25)
		(keepout
			(tracks allowed)
			(vias allowed)
			(pads allowed)
			(copperpour allowed)
			(footprints allowed)
		)
		(placement
			(enabled no)
			(sheetname "")
		)
		(fill
			(thermal_gap 0.5)
			(thermal_bridge_width 0.5)
			(island_removal_mode 0)
		)
		(polygon
			(pts
				(xy 228.694996 -103.140002) (xy 228.694996 -94.996) (xy 230.632 -93.058996) (xy 230.632 -83.058)
				(xy 229.616 -82.042) (xy 229.616 -60.833) (xy 230.886 -59.563) (xy 230.886 -53.594) (xy 231.648 -52.832)
				(xy 231.648 -51.926744) (xy 234.409996 -49.165002) (xy 235.044996 -48.530002) (xy 236.356398 -47.2186)
				(xy 248.8946 -47.2186) (xy 249.555 -47.879) (xy 270.8148 -47.879) (xy 271.7546 -46.9392) (xy 278.781002 -46.9392)
				(xy 285.6484 -46.9392) (xy 290.449 -51.7398) (xy 309.339996 -51.7398) (xy 309.339996 -101.235002)
				(xy 306.164996 -104.410002) (xy 304.292 -104.410002) (xy 304.236628 -104.465628) (xy 303.403 -103.632)
				(xy 297.815 -103.632) (xy 297.815 -106.172) (xy 295.529 -106.172) (xy 295.529 -106.807) (xy 291.592 -106.807)
				(xy 290.068 -108.331) (xy 288.3916 -108.331) (xy 272.288 -108.331) (xy 270.764 -108.331) (xy 270.764 -105.918)
				(xy 231.472994 -105.918)
			)
		)
	)
	(zone
		(net "PVCCIO_CPU1")
		(layer "In2.Cu")
		(hatch none 0.5)
		(connect_pads
			(clearance 0.5)
		)
		(min_thickness 0.25)
		(fill yes
			(thermal_gap 0.5)
			(thermal_bridge_width 0.5)
			(island_removal_mode 0)
		)
		(polygon
			(pts
				(xy 108.67898 -59.4106) (xy 108.67898 -62.31382) (xy 108.67898 -62.85738) (xy 109.5248 -63.7032)
				(xy 109.5248 -63.9572) (xy 109.5248 -64.389) (xy 111.76 -66.6242) (xy 112.1918 -66.6242) (xy 112.45977 -66.89217)
				(xy 113.25733 -66.89217) (xy 113.54943 -67.18427) (xy 113.80597 -67.18427) (xy 113.81994 -67.1703)
				(xy 113.8809 -67.1703) (xy 114.2365 -66.8147) (xy 115.54206 -66.8147) (xy 116.3574 -67.63004) (xy 117.59438 -67.63004)
				(xy 118.92661 -66.29781) (xy 118.92661 -63.72479) (xy 119.9896 -62.6618) (xy 122.9106 -62.6618)
				(xy 124.6505 -62.6618) (xy 126.3523 -60.96) (xy 126.7079 -60.96) (xy 126.9746 -60.6933) (xy 127.19685 -60.47105)
				(xy 127.6223 -60.47105) (xy 128.22555 -59.8678) (xy 128.5621 -59.8678) (xy 129.0955 -59.3344) (xy 129.1717 -59.3344)
				(xy 129.6162 -59.3344) (xy 130.05308 -59.3344) (xy 130.1623 -59.3344) (xy 130.429 -59.0677) (xy 130.429 -56.642)
				(xy 130.6322 -56.4388) (xy 131.064 -56.007) (xy 131.064 -55.5498) (xy 131.064 -55.4736) (xy 131.5085 -55.0291)
				(xy 132.7023 -55.0291) (xy 133.0071 -54.7243) (xy 133.0071 -54.2925) (xy 133.0071 -54.2798) (xy 133.1468 -54.1401)
				(xy 133.1468 -53.6956) (xy 133.1468 -53.4035) (xy 132.82422 -53.08092) (xy 131.445 -53.08092) (xy 126.6825 -53.08092)
				(xy 125.54966 -54.21376) (xy 125.40234 -54.21376) (xy 125.34138 -54.27472) (xy 125.34138 -54.42204)
				(xy 125.34138 -55.6768) (xy 125.7046 -56.04002) (xy 125.7046 -56.2356) (xy 125.6919 -56.2483) (xy 125.476 -56.2483)
				(xy 125.4252 -56.2991) (xy 125.4252 -56.3372) (xy 125.3998 -56.3626) (xy 124.4473 -57.3151) (xy 124.3965 -57.3151)
				(xy 124.2314 -57.3151) (xy 122.82678 -58.71972) (xy 122.8217 -58.71972) (xy 122.79122 -58.7502)
				(xy 121.3866 -58.7502) (xy 121.38025 -58.74385) (xy 109.34573 -58.74385) (xy 108.79455 -58.74385)
				(xy 108.67898 -58.85942)
			)
		)
	)
	(zone
		(layer "In2.Cu")
		(hatch none 0.5)
		(connect_pads
			(clearance 0)
		)
		(min_thickness 0.25)
		(keepout
			(tracks allowed)
			(vias allowed)
			(pads allowed)
			(copperpour allowed)
			(footprints allowed)
		)
		(placement
			(enabled no)
			(sheetname "")
		)
		(fill
			(thermal_gap 0.5)
			(thermal_bridge_width 0.5)
			(island_removal_mode 0)
		)
		(polygon
			(pts
				(xy 397.14678 -128.6764) (xy 397.14678 -127.73914) (xy 397.86052 -127.73914) (xy 397.86052 -128.6764)
			)
		)
	)
	(zone
		(layer "In2.Cu")
		(hatch none 0.5)
		(connect_pads
			(clearance 0)
		)
		(min_thickness 0.25)
		(keepout
			(tracks allowed)
			(vias allowed)
			(pads allowed)
			(copperpour allowed)
			(footprints allowed)
		)
		(placement
			(enabled no)
			(sheetname "")
		)
		(fill
			(thermal_gap 0.5)
			(thermal_bridge_width 0.5)
			(island_removal_mode 0)
		)
		(polygon
			(pts
				(xy 63.694564 -103.140002) (xy 63.694564 -94.996) (xy 65.631568 -93.058996) (xy 65.631568 -83.058)
				(xy 64.615568 -82.042) (xy 64.615568 -60.833) (xy 65.885568 -59.563) (xy 65.885568 -53.594) (xy 66.647568 -52.832)
				(xy 66.647568 -51.926744) (xy 69.409564 -49.165002) (xy 70.044564 -48.530002) (xy 71.355966 -47.2186)
				(xy 83.894168 -47.2186) (xy 84.554568 -47.879) (xy 105.814368 -47.879) (xy 106.754168 -46.9392)
				(xy 113.78057 -46.9392) (xy 120.647968 -46.9392) (xy 125.448568 -51.7398) (xy 144.339564 -51.7398)
				(xy 144.339564 -101.235002) (xy 141.164564 -104.410002) (xy 139.291568 -104.410002) (xy 139.236196 -104.465628)
				(xy 138.402568 -103.632) (xy 132.814568 -103.632) (xy 132.814568 -106.172) (xy 130.528568 -106.172)
				(xy 130.528568 -106.807) (xy 126.591568 -106.807) (xy 125.067568 -108.331) (xy 123.391168 -108.331)
				(xy 107.287568 -108.331) (xy 105.763568 -108.331) (xy 105.763568 -105.918) (xy 66.472562 -105.918)
			)
		)
	)
	(zone
		(layer "In2.Cu")
		(hatch none 0.5)
		(connect_pads
			(clearance 0)
		)
		(min_thickness 0.25)
		(keepout
			(tracks allowed)
			(vias allowed)
			(pads allowed)
			(copperpour allowed)
			(footprints allowed)
		)
		(placement
			(enabled no)
			(sheetname "")
		)
		(fill
			(thermal_gap 0.5)
			(thermal_bridge_width 0.5)
			(island_removal_mode 0)
		)
		(polygon
			(pts
				(xy 271.272 -108.077) (xy 271.272 -99.314) (xy 274.574 -96.012) (xy 289.687 -96.012) (xy 293.243 -99.568)
				(xy 293.243 -101.727) (xy 292.608 -102.362) (xy 290.576 -102.362) (xy 289.179 -103.759) (xy 287.909 -103.759)
				(xy 287.02 -104.648) (xy 287.02 -108.077)
			)
		)
	)
	(zone
		(layer "In2.Cu")
		(hatch none 0.5)
		(connect_pads
			(clearance 0)
		)
		(min_thickness 0.25)
		(keepout
			(tracks not_allowed)
			(vias allowed)
			(pads allowed)
			(copperpour not_allowed)
			(footprints allowed)
		)
		(placement
			(enabled no)
			(sheetname "")
		)
		(fill
			(thermal_gap 0.5)
			(thermal_bridge_width 0.5)
			(island_removal_mode 0)
		)
		(polygon
			(pts
				(xy 461.0354 -41.8592) (xy 461.0354 -39.2176) (xy 462.7626 -39.2176) (xy 462.7626 -41.8592)
			)
		)
	)
	(zone
		(layer "In2.Cu")
		(hatch none 0.5)
		(connect_pads
			(clearance 0)
		)
		(min_thickness 0.25)
		(keepout
			(tracks not_allowed)
			(vias allowed)
			(pads allowed)
			(copperpour not_allowed)
			(footprints allowed)
		)
		(placement
			(enabled no)
			(sheetname "")
		)
		(fill
			(thermal_gap 0.5)
			(thermal_bridge_width 0.5)
			(island_removal_mode 0)
		)
		(polygon
			(pts
				(arc
					(start 451.941438 -138.444986)
					(mid 448.918838 -138.444986)
					(end 451.941438 -138.444986)
				)
			)
		)
	)
	(zone
		(layer "In2.Cu")
		(hatch none 0.5)
		(connect_pads
			(clearance 0)
		)
		(min_thickness 0.25)
		(keepout
			(tracks allowed)
			(vias allowed)
			(pads allowed)
			(copperpour allowed)
			(footprints allowed)
		)
		(placement
			(enabled no)
			(sheetname "")
		)
		(fill
			(thermal_gap 0.5)
			(thermal_bridge_width 0.5)
			(island_removal_mode 0)
		)
		(polygon
			(pts
				(xy 106.271568 -108.077) (xy 106.271568 -99.314) (xy 109.573568 -96.012) (xy 124.686568 -96.012)
				(xy 128.242568 -99.568) (xy 128.242568 -101.727) (xy 127.607568 -102.362) (xy 125.575568 -102.362)
				(xy 124.178568 -103.759) (xy 122.908568 -103.759) (xy 122.019568 -104.648) (xy 122.019568 -108.077)
			)
		)
	)
	(zone
		(layer "In2.Cu")
		(hatch none 0.5)
		(connect_pads
			(clearance 0)
		)
		(min_thickness 0.25)
		(keepout
			(tracks not_allowed)
			(vias allowed)
			(pads allowed)
			(copperpour not_allowed)
			(footprints allowed)
		)
		(placement
			(enabled no)
			(sheetname "")
		)
		(fill
			(thermal_gap 0.5)
			(thermal_bridge_width 0.5)
			(island_removal_mode 0)
		)
		(polygon
			(pts
				(arc
					(start 380.562612 -128.711706)
					(mid 380.181358 -129.092579)
					(end 380.562358 -129.473706)
				)
				(xy 380.664212 -129.473706) (xy 380.663196 -129.458466) (xy 380.66218 -129.457704)
				(arc
					(start 380.66218 -129.340102)
					(mid 380.392134 -128.887296)
					(end 380.786894 -129.236724)
				)
				(arc
					(start 380.786894 -129.236724)
					(mid 380.794209 -129.256938)
					(end 380.799086 -129.277872)
				)
				(xy 380.80188 -129.280666)
				(arc
					(start 380.80188 -129.428748)
					(mid 380.802557 -129.451272)
					(end 380.804674 -129.473706)
				)
				(xy 380.95936 -129.473706) (xy 380.95682 -129.460244) (xy 380.95428 -129.457704) (xy 380.95428 -129.309622)
				(arc
					(start 380.957074 -129.306828)
					(mid 380.968358 -129.268053)
					(end 380.987808 -129.23266)
				)
				(xy 380.987808 -129.22885)
				(arc
					(start 380.991364 -129.225294)
					(mid 381.409151 -128.90197)
					(end 381.095504 -129.327148)
				)
				(xy 381.09398 -129.338578)
				(arc
					(start 381.09398 -129.428748)
					(mid 381.099653 -129.453689)
					(end 381.11557 -129.473706)
				)
				(arc
					(start 381.222758 -129.473706)
					(mid 381.603758 -129.092706)
					(end 381.222758 -128.711706)
				)
			)
		)
	)
	(zone
		(layer "In2.Cu")
		(hatch none 0.5)
		(connect_pads
			(clearance 0)
		)
		(min_thickness 0.25)
		(keepout
			(tracks allowed)
			(vias allowed)
			(pads allowed)
			(copperpour allowed)
			(footprints allowed)
		)
		(placement
			(enabled no)
			(sheetname "")
		)
		(fill
			(thermal_gap 0.5)
			(thermal_bridge_width 0.5)
			(island_removal_mode 0)
		)
		(polygon
			(pts
				(xy 350.266 -122.047) (xy 350.266 -121.031) (xy 351.282 -121.031) (xy 351.282 -122.047)
			)
		)
	)
	(zone
		(layer "In2.Cu")
		(hatch none 0.5)
		(connect_pads
			(clearance 0)
		)
		(min_thickness 0.25)
		(keepout
			(tracks not_allowed)
			(vias allowed)
			(pads allowed)
			(copperpour not_allowed)
			(footprints allowed)
		)
		(placement
			(enabled no)
			(sheetname "")
		)
		(fill
			(thermal_gap 0.5)
			(thermal_bridge_width 0.5)
			(island_removal_mode 0)
		)
		(polygon
			(pts
				(xy 374.936766 -145.955004) (xy 377.806966 -145.955004) (xy 377.806966 -149.930104) (xy 374.936766 -149.930104)
			)
		)
	)
	(zone
		(net "PVDDQ_GHJ")
		(layer "In2.Cu")
		(hatch none 0.5)
		(connect_pads
			(clearance 0.5)
		)
		(min_thickness 0.25)
		(fill yes
			(thermal_gap 0.5)
			(thermal_bridge_width 0.5)
			(island_removal_mode 0)
		)
		(polygon
			(pts
				(xy 168.0972 -0.7366) (xy 169.3164 -0.7366) (xy 169.7482 -1.1684) (xy 169.7482 -1.6256) (xy 170.2816 -2.159)
				(xy 172.2882 -2.159) (xy 173.4312 -3.302) (xy 176.2506 -3.302) (xy 176.37125 -3.42265) (xy 176.37125 -4.50215)
				(xy 176.37125 -4.69138) (xy 176.13503 -4.9276) (xy 175.9458 -4.9276) (xy 169.545 -4.9276) (xy 167.767 -3.1496)
				(xy 167.767 -1.0668)
			)
		)
	)
	(zone
		(layer "In2.Cu")
		(hatch none 0.5)
		(connect_pads
			(clearance 0)
		)
		(min_thickness 0.25)
		(keepout
			(tracks not_allowed)
			(vias allowed)
			(pads allowed)
			(copperpour not_allowed)
			(footprints allowed)
		)
		(placement
			(enabled no)
			(sheetname "")
		)
		(fill
			(thermal_gap 0.5)
			(thermal_bridge_width 0.5)
			(island_removal_mode 0)
		)
		(polygon
			(pts
				(arc
					(start 350.121982 -67.329812)
					(mid 349.702011 -67.650977)
					(end 350.023176 -67.231006)
				)
				(xy 350.084644 -67.169538) (xy 350.084644 -67.07886)
				(arc
					(start 349.890588 -67.07886)
					(mid 349.507048 -67.4624)
					(end 349.890588 -67.84594)
				)
				(arc
					(start 350.78162 -67.84594)
					(mid 351.165414 -67.462527)
					(end 350.781874 -67.07886)
				)
				(xy 350.516444 -67.07886) (xy 350.516444 -67.098164)
				(arc
					(start 350.649286 -67.231006)
					(mid 350.970451 -67.650977)
					(end 350.55048 -67.329812)
				)
				(xy 350.376744 -67.156076) (xy 350.376744 -67.07886) (xy 350.224344 -67.07886) (xy 350.224344 -67.22745)
			)
		)
	)
	(zone
		(layer "In2.Cu")
		(hatch none 0.5)
		(connect_pads
			(clearance 0)
		)
		(min_thickness 0.25)
		(keepout
			(tracks not_allowed)
			(vias allowed)
			(pads allowed)
			(copperpour not_allowed)
			(footprints allowed)
		)
		(placement
			(enabled no)
			(sheetname "")
		)
		(fill
			(thermal_gap 0.5)
			(thermal_bridge_width 0.5)
			(island_removal_mode 0)
		)
		(polygon
			(pts
				(xy 377.8377 -139.91082) (xy 377.8377 -142.4178) (xy 376.7328 -142.4178) (xy 374.9675 -142.4178)
				(xy 374.9675 -139.50188) (xy 374.9675 -138.77798) (xy 376.7328 -138.77798) (xy 377.8377 -139.88288)
			)
		)
	)
	(zone
		(net "PVCCIO_CPU1")
		(layer "In2.Cu")
		(hatch none 0.5)
		(connect_pads
			(clearance 0.5)
		)
		(min_thickness 0.25)
		(fill yes
			(thermal_gap 0.5)
			(thermal_bridge_width 0.5)
			(island_removal_mode 0)
		)
		(polygon
			(pts
				(xy 149.44344 -46.34992) (xy 148.89607 -46.34992) (xy 141.65326 -53.59273) (xy 136.358884 -56.416702)
				(xy 136.358884 -56.617616) (xy 136.434068 -56.6928) (xy 136.434068 -57.024016) (xy 136.133078 -57.325006)
				(xy 135.707882 -57.325006) (xy 135.230362 -57.802526) (xy 134.838948 -57.802526) (xy 134.56412 -58.077354)
				(xy 134.56412 -68.496942) (xy 134.59968 -68.532502) (xy 134.770876 -68.703698) (xy 134.770876 -68.859908)
				(xy 134.676896 -68.953888) (xy 134.673086 -68.953888) (xy 134.59968 -69.027294) (xy 134.59968 -70.55485)
				(xy 134.812532 -70.767702) (xy 134.812532 -71.26859) (xy 134.816342 -71.2724) (xy 137.668 -71.2724)
				(xy 137.8204 -71.12) (xy 138.303 -71.12) (xy 140.208 -69.215) (xy 141.224 -69.215) (xy 146.12366 -64.31534)
				(xy 146.12366 -51.87188) (xy 150.02764 -47.9679) (xy 150.02764 -46.93412)
			)
		)
	)
	(zone
		(layer "In2.Cu")
		(hatch none 0.5)
		(connect_pads
			(clearance 0)
		)
		(min_thickness 0.25)
		(keepout
			(tracks not_allowed)
			(vias allowed)
			(pads allowed)
			(copperpour not_allowed)
			(footprints allowed)
		)
		(placement
			(enabled no)
			(sheetname "")
		)
		(fill
			(thermal_gap 0.5)
			(thermal_bridge_width 0.5)
			(island_removal_mode 0)
		)
		(polygon
			(pts
				(arc
					(start 384.432556 -34.214308)
					(mid 384.418168 -34.185228)
					(end 384.40741 -34.154618)
				)
				(xy 384.40741 -34.239454)
			)
		)
	)
	(zone
		(layer "In2.Cu")
		(hatch none 0.5)
		(connect_pads
			(clearance 0)
		)
		(min_thickness 0.25)
		(keepout
			(tracks not_allowed)
			(vias allowed)
			(pads allowed)
			(copperpour not_allowed)
			(footprints allowed)
		)
		(placement
			(enabled no)
			(sheetname "")
		)
		(fill
			(thermal_gap 0.5)
			(thermal_bridge_width 0.5)
			(island_removal_mode 0)
		)
		(polygon
			(pts
				(arc
					(start 384.92049 -34.154618)
					(mid 384.764556 -34.328713)
					(end 384.531362 -34.313114)
				)
				(xy 384.40741 -34.437066) (xy 384.40741 -34.691574)
				(arc
					(start 384.531362 -34.815526)
					(mid 384.764553 -34.799935)
					(end 384.92049 -34.974022)
				)
			)
		)
	)
	(zone
		(layer "In2.Cu")
		(hatch none 0.5)
		(connect_pads
			(clearance 0)
		)
		(min_thickness 0.25)
		(keepout
			(tracks allowed)
			(vias allowed)
			(pads allowed)
			(copperpour allowed)
			(footprints allowed)
		)
		(placement
			(enabled no)
			(sheetname "")
		)
		(fill
			(thermal_gap 0.5)
			(thermal_bridge_width 0.5)
			(island_removal_mode 0)
		)
		(polygon
			(pts
				(xy 279.2476 -57.7088) (xy 278.2316 -58.7248) (xy 275.5646 -58.7248) (xy 273.3548 -56.515) (xy 273.3548 -53.8734)
				(xy 275.7678 -53.8734) (xy 276.2504 -53.3908) (xy 277.3426 -53.3908) (xy 277.5712 -53.6194) (xy 277.5712 -54.7624)
				(xy 279.146 -54.7624) (xy 279.146 -54.102) (xy 281.813 -54.102) (xy 282.575 -54.864) (xy 284.099 -54.864)
				(xy 284.4546 -55.2196) (xy 284.4546 -56.7944) (xy 283.5656 -57.6834) (xy 279.273 -57.6834)
			)
		)
	)
	(zone
		(layer "In2.Cu")
		(hatch none 0.5)
		(connect_pads
			(clearance 0)
		)
		(min_thickness 0.25)
		(keepout
			(tracks not_allowed)
			(vias allowed)
			(pads allowed)
			(copperpour not_allowed)
			(footprints allowed)
		)
		(placement
			(enabled no)
			(sheetname "")
		)
		(fill
			(thermal_gap 0.5)
			(thermal_bridge_width 0.5)
			(island_removal_mode 0)
		)
		(polygon
			(pts
				(xy 332.2066 -27.8892) (xy 332.2066 -31.4706)
				(arc
					(start 335.958688 -31.4706)
					(mid 336.1944 -31.094337)
					(end 336.430112 -31.4706)
				)
				(arc
					(start 336.720688 -31.4706)
					(mid 336.9564 -31.094337)
					(end 337.192112 -31.4706)
				)
				(xy 340.868 -31.4706) (xy 340.868 -27.8892)
			)
		)
	)
	(zone
		(layer "In2.Cu")
		(hatch none 0.5)
		(connect_pads
			(clearance 0)
		)
		(min_thickness 0.25)
		(keepout
			(tracks not_allowed)
			(vias allowed)
			(pads allowed)
			(copperpour not_allowed)
			(footprints allowed)
		)
		(placement
			(enabled no)
			(sheetname "")
		)
		(fill
			(thermal_gap 0.5)
			(thermal_bridge_width 0.5)
			(island_removal_mode 0)
		)
		(polygon
			(pts
				(arc
					(start 341.523066 -67.963542)
					(mid 341.103095 -68.284707)
					(end 341.42426 -67.864736)
				)
				(xy 341.537544 -67.751452) (xy 341.537544 -67.71259)
				(arc
					(start 341.291672 -67.71259)
					(mid 340.908132 -68.09613)
					(end 341.291672 -68.47967)
				)
				(arc
					(start 342.256618 -68.47967)
					(mid 342.640412 -68.096257)
					(end 342.256872 -67.71259)
				)
				(xy 341.972138 -67.71259)
				(arc
					(start 342.124284 -67.864736)
					(mid 342.445449 -68.284707)
					(end 342.025478 -67.963542)
				)
				(xy 341.829644 -67.767708) (xy 341.829644 -67.71259) (xy 341.677244 -67.71259) (xy 341.677244 -67.809364)
			)
		)
	)
	(zone
		(net "P12V")
		(layer "In2.Cu")
		(hatch none 0.5)
		(connect_pads
			(clearance 0.5)
		)
		(min_thickness 0.25)
		(fill yes
			(thermal_gap 0.5)
			(thermal_bridge_width 0.5)
			(island_removal_mode 0)
		)
		(polygon
			(pts
				(xy 490.406436 -20.864576) (xy 496.403376 -20.864576) (xy 496.71351 -20.554442) (xy 496.71351 -20.351242)
				(xy 493.458754 -17.096486) (xy 490.162596 -17.096486) (xy 489.83646 -17.422622) (xy 489.83646 -20.2946)
			)
		)
	)
	(zone
		(layer "In2.Cu")
		(hatch none 0.5)
		(connect_pads
			(clearance 0)
		)
		(min_thickness 0.25)
		(keepout
			(tracks not_allowed)
			(vias allowed)
			(pads allowed)
			(copperpour not_allowed)
			(footprints allowed)
		)
		(placement
			(enabled no)
			(sheetname "")
		)
		(fill
			(thermal_gap 0.5)
			(thermal_bridge_width 0.5)
			(island_removal_mode 0)
		)
		(polygon
			(pts
				(arc
					(start 328.893678 -130.259074)
					(mid 325.823265 -129.059632)
					(end 326.22363 -132.331714)
				)
				(arc
					(start 326.22363 -132.331714)
					(mid 326.320024 -132.348618)
					(end 326.402954 -132.400548)
				)
				(arc
					(start 326.402954 -132.400548)
					(mid 328.116197 -132.13829)
					(end 328.91984 -130.602736)
				)
				(arc
					(start 328.91984 -130.602736)
					(mid 328.840761 -130.43591)
					(end 328.893678 -130.259074)
				)
			)
		)
	)
	(zone
		(layer "In2.Cu")
		(hatch none 0.5)
		(connect_pads
			(clearance 0)
		)
		(min_thickness 0.25)
		(keepout
			(tracks not_allowed)
			(vias allowed)
			(pads allowed)
			(copperpour not_allowed)
			(footprints allowed)
		)
		(placement
			(enabled no)
			(sheetname "")
		)
		(fill
			(thermal_gap 0.5)
			(thermal_bridge_width 0.5)
			(island_removal_mode 0)
		)
		(polygon
			(pts
				(arc
					(start 161.402014 -156.397452)
					(mid 162.687354 -152.780659)
					(end 161.22269 -156.328618)
				)
				(arc
					(start 161.22269 -156.328618)
					(mid 161.319084 -156.345522)
					(end 161.402014 -156.397452)
				)
			)
		)
	)
	(zone
		(layer "In2.Cu")
		(hatch none 0.5)
		(connect_pads
			(clearance 0)
		)
		(min_thickness 0.25)
		(keepout
			(tracks not_allowed)
			(vias allowed)
			(pads allowed)
			(copperpour not_allowed)
			(footprints allowed)
		)
		(placement
			(enabled no)
			(sheetname "")
		)
		(fill
			(thermal_gap 0.5)
			(thermal_bridge_width 0.5)
			(island_removal_mode 0)
		)
		(polygon
			(pts
				(arc
					(start 380.772162 -131.266184)
					(mid 380.791631 -131.30157)
					(end 380.802896 -131.340352)
				)
				(xy 380.80569 -131.343146) (xy 380.80569 -131.475988) (xy 380.95809 -131.475988)
				(arc
					(start 380.95809 -131.261612)
					(mid 381.312102 -130.871591)
					(end 381.09779 -131.352798)
				)
				(xy 381.09779 -131.475988)
				(arc
					(start 381.16637 -131.475988)
					(mid 381.54737 -131.094988)
					(end 381.16637 -130.713988)
				)
				(arc
					(start 380.506224 -130.713988)
					(mid 380.12497 -131.094861)
					(end 380.50597 -131.475988)
				)
				(xy 380.66599 -131.475988)
				(arc
					(start 380.66599 -131.372102)
					(mid 380.662641 -131.355175)
					(end 380.653036 -131.34086)
				)
				(arc
					(start 380.638558 -131.326382)
					(mid 380.317393 -130.906411)
					(end 380.737364 -131.227576)
				)
				(xy 380.751588 -131.2418) (xy 380.751842 -131.242054) (xy 380.772162 -131.262374)
			)
		)
	)
	(zone
		(layer "In2.Cu")
		(hatch none 0.5)
		(connect_pads
			(clearance 0)
		)
		(min_thickness 0.25)
		(keepout
			(tracks allowed)
			(vias allowed)
			(pads allowed)
			(copperpour allowed)
			(footprints allowed)
		)
		(placement
			(enabled no)
			(sheetname "")
		)
		(fill
			(thermal_gap 0.5)
			(thermal_bridge_width 0.5)
			(island_removal_mode 0)
		)
		(polygon
			(pts
				(xy 284.5816 -53.1876) (xy 284.5816 -52.3748) (xy 286.7406 -50.2158) (xy 288.3408 -50.2158) (xy 290.1696 -52.0446)
				(xy 291.5158 -52.0446) (xy 291.5158 -53.9242) (xy 290.3728 -55.0672) (xy 290.3728 -56.7182) (xy 289.7251 -57.3659)
				(xy 289.7251 -57.1373) (xy 289.1282 -56.5404) (xy 289.1282 -56.1848) (xy 289.4076 -55.9054) (xy 289.4076 -55.5498)
				(xy 289.2552 -55.3974) (xy 288.5694 -55.3974) (xy 288.5694 -54.229) (xy 288.7218 -54.0766) (xy 288.7218 -53.4924)
				(xy 288.5948 -53.3654) (xy 286.7152 -53.3654) (xy 286.131 -53.9496) (xy 284.3276 -53.9496) (xy 284.3276 -53.4416)
			)
		)
	)
	(zone
		(layer "In2.Cu")
		(hatch none 0.5)
		(connect_pads
			(clearance 0)
		)
		(min_thickness 0.25)
		(keepout
			(tracks allowed)
			(vias allowed)
			(pads allowed)
			(copperpour allowed)
			(footprints allowed)
		)
		(placement
			(enabled no)
			(sheetname "")
		)
		(fill
			(thermal_gap 0.5)
			(thermal_bridge_width 0.5)
			(island_removal_mode 0)
		)
		(polygon
			(pts
				(xy 77.061568 -49.403) (xy 84.173568 -49.403) (xy 85.189568 -50.419) (xy 85.189568 -56.515) (xy 85.697568 -57.023)
				(xy 85.951568 -57.023) (xy 86.332568 -57.404) (xy 86.332568 -62.738) (xy 85.697568 -63.373) (xy 81.633568 -63.373)
				(xy 80.617568 -62.357) (xy 80.617568 -61.214) (xy 78.839568 -59.436) (xy 78.839568 -57.785) (xy 78.585568 -57.531)
				(xy 74.394568 -57.531) (xy 71.473568 -60.452) (xy 67.028568 -60.452) (xy 66.266568 -59.69) (xy 66.266568 -54.864)
				(xy 66.139568 -54.737) (xy 66.139568 -53.848) (xy 66.901568 -53.086) (xy 66.901568 -52.07) (xy 70.330568 -48.641)
				(xy 73.759568 -48.641) (xy 75.029568 -47.371) (xy 75.537568 -47.371) (xy 76.807568 -48.641) (xy 76.807568 -49.149)
			)
		)
	)
	(zone
		(net "GND")
		(layer "In2.Cu")
		(hatch none 0.5)
		(connect_pads
			(clearance 0.5)
		)
		(min_thickness 0.25)
		(fill yes
			(thermal_gap 0.5)
			(thermal_bridge_width 0.5)
			(island_removal_mode 0)
		)
		(polygon
			(pts
				(xy 199.37984 -60.84824) (xy 199.37984 -62.40526) (xy 199.37984 -77.07884) (xy 199.37984 -78.59776)
				(xy 199.37984 -84.77504) (xy 199.37984 -86.52256) (xy 199.37984 -92.902532) (xy 199.507348 -93.03004)
				(xy 207.725518 -93.03004) (xy 207.899 -92.856558) (xy 207.899 -53.2638) (xy 207.1878 -52.5526) (xy 206.1972 -52.5526)
				(xy 206.0194 -52.3748) (xy 204.7748 -52.3748) (xy 204.0636 -51.6636) (xy 199.515222 -51.6636) (xy 199.37984 -51.798982)
			)
		)
	)
	(zone
		(layer "In2.Cu")
		(hatch none 0.5)
		(connect_pads
			(clearance 0)
		)
		(min_thickness 0.25)
		(keepout
			(tracks not_allowed)
			(vias allowed)
			(pads allowed)
			(copperpour not_allowed)
			(footprints allowed)
		)
		(placement
			(enabled no)
			(sheetname "")
		)
		(fill
			(thermal_gap 0.5)
			(thermal_bridge_width 0.5)
			(island_removal_mode 0)
		)
		(polygon
			(pts
				(arc
					(start 336.987134 -70.803008)
					(mid 337.308299 -71.222979)
					(end 336.888328 -70.901814)
				)
				(xy 336.637376 -70.650862) (xy 336.484722 -70.650862) (xy 336.484722 -70.876922)
				(arc
					(start 336.45983 -70.901814)
					(mid 336.046354 -71.229259)
					(end 336.345022 -70.794626)
				)
				(xy 336.345022 -70.650862)
				(arc
					(start 336.228436 -70.650862)
					(mid 335.844896 -71.034402)
					(end 336.228436 -71.417942)
				)
				(arc
					(start 337.119468 -71.417942)
					(mid 337.503262 -71.034529)
					(end 337.119722 -70.650862)
				)
				(xy 336.834988 -70.650862)
			)
		)
	)
	(zone
		(net "GND")
		(layer "In2.Cu")
		(hatch none 0.5)
		(connect_pads
			(clearance 0.5)
		)
		(min_thickness 0.25)
		(fill yes
			(thermal_gap 0.5)
			(thermal_bridge_width 0.5)
			(island_removal_mode 0)
		)
		(polygon
			(pts
				(xy 346.2909 -157.3657) (xy 347.1926 -156.464) (xy 347.1926 -152.1206) (xy 346.3798 -151.3078) (xy 346.3798 -150.0378)
				(xy 347.1418 -149.2758) (xy 347.1418 -144.3228) (xy 345.9861 -143.1671) (xy 345.9861 -140.4747)
				(xy 345.73718 -140.22578) (xy 338.8868 -140.22578) (xy 337.9978 -141.11478) (xy 337.9978 -144.1831)
				(xy 339.3694 -145.5547) (xy 339.3694 -156.6164) (xy 340.1187 -157.3657) (xy 340.583012 -157.830012)
				(xy 345.826588 -157.830012)
			)
		)
	)
	(zone
		(layer "In2.Cu")
		(hatch none 0.5)
		(connect_pads
			(clearance 0)
		)
		(min_thickness 0.25)
		(keepout
			(tracks not_allowed)
			(vias allowed)
			(pads allowed)
			(copperpour not_allowed)
			(footprints allowed)
		)
		(placement
			(enabled no)
			(sheetname "")
		)
		(fill
			(thermal_gap 0.5)
			(thermal_bridge_width 0.5)
			(island_removal_mode 0)
		)
		(polygon
			(pts
				(xy 407.64333 -147.577048) (xy 407.643584 -147.577302)
				(arc
					(start 407.789888 -147.723606)
					(mid 408.111053 -148.143577)
					(end 407.691082 -147.822412)
				)
				(xy 407.544524 -147.675854) (xy 407.538936 -147.671028)
				(arc
					(start 407.538936 -147.954746)
					(mid 407.922349 -148.33854)
					(end 408.306016 -147.955)
				)
				(arc
					(start 408.306016 -146.939)
					(mid 407.922476 -146.55546)
					(end 407.538936 -146.939)
				)
				(xy 407.538936 -147.222972) (xy 407.544524 -147.218146)
				(arc
					(start 407.691082 -147.071588)
					(mid 408.111053 -146.750423)
					(end 407.789888 -147.170394)
				)
				(xy 407.643584 -147.316698) (xy 407.64333 -147.316952) (xy 407.62301 -147.337272)
				(arc
					(start 407.6192 -147.337272)
					(mid 407.583814 -147.356741)
					(end 407.545032 -147.368006)
				)
				(xy 407.542238 -147.3708) (xy 407.538936 -147.3708) (xy 407.538936 -147.5232) (xy 407.542238 -147.5232)
				(arc
					(start 407.545032 -147.525994)
					(mid 407.583807 -147.537278)
					(end 407.6192 -147.556728)
				)
				(xy 407.62301 -147.556728)
			)
		)
	)
	(zone
		(layer "In2.Cu")
		(hatch none 0.5)
		(connect_pads
			(clearance 0)
		)
		(min_thickness 0.25)
		(keepout
			(tracks allowed)
			(vias allowed)
			(pads allowed)
			(copperpour allowed)
			(footprints allowed)
		)
		(placement
			(enabled no)
			(sheetname "")
		)
		(fill
			(thermal_gap 0.5)
			(thermal_bridge_width 0.5)
			(island_removal_mode 0)
		)
		(polygon
			(pts
				(xy 284.3276 -53.9496) (xy 286.131 -53.9496) (xy 286.7152 -53.3654) (xy 288.5948 -53.3654) (xy 288.7218 -53.4924)
				(xy 288.7218 -54.0766) (xy 288.5694 -54.229) (xy 288.5694 -55.3974) (xy 289.2552 -55.3974) (xy 289.4076 -55.5498)
				(xy 289.4076 -55.9054) (xy 289.1282 -56.1848) (xy 289.1282 -56.5404) (xy 289.7251 -57.1373) (xy 289.7251 -57.3659)
				(xy 288.5948 -58.4962) (xy 286.6898 -58.4962) (xy 284.3276 -56.134)
			)
		)
	)
	(zone
		(net "PVCCIOMCP_CPU1")
		(layer "In2.Cu")
		(hatch none 0.5)
		(connect_pads
			(clearance 0.5)
		)
		(min_thickness 0.25)
		(fill yes
			(thermal_gap 0.5)
			(thermal_bridge_width 0.5)
			(island_removal_mode 0)
		)
		(polygon
			(pts
				(xy 157.7975 -99.6823) (xy 157.7975 -78.2701) (xy 155.7782 -76.2508) (xy 134.3152 -76.2508) (xy 133.6294 -76.9366)
				(xy 131.0894 -76.9366) (xy 130.4036 -77.6224) (xy 129.4638 -77.6224) (xy 129.2606 -77.8256) (xy 129.2606 -81.026)
				(xy 129.4384 -81.2038) (xy 135.4328 -81.2038) (xy 135.89 -81.661) (xy 139.0142 -81.661) (xy 139.0142 -82.3468)
				(xy 140.0302 -83.3628) (xy 140.0302 -89.3318) (xy 138.3792 -90.9828) (xy 138.3792 -104.013) (xy 141.224 -106.8578)
				(xy 143.7894 -109.4232) (xy 157.7086 -109.4232) (xy 158.75 -109.4232) (xy 160.274 -107.8992) (xy 160.274 -102.1588)
			)
		)
	)
	(zone
		(layer "In2.Cu")
		(hatch none 0.5)
		(connect_pads
			(clearance 0)
		)
		(min_thickness 0.25)
		(keepout
			(tracks not_allowed)
			(vias allowed)
			(pads allowed)
			(copperpour not_allowed)
			(footprints allowed)
		)
		(placement
			(enabled no)
			(sheetname "")
		)
		(fill
			(thermal_gap 0.5)
			(thermal_bridge_width 0.5)
			(island_removal_mode 0)
		)
		(polygon
			(pts
				(xy 414.156398 -1.6637) (xy 414.311592 -1.818894) (xy 414.311592 -2.11709) (xy 414.463992 -2.11709)
				(xy 414.463992 -1.818894) (xy 414.619186 -1.6637)
				(arc
					(start 414.81629 -1.6637)
					(mid 415.340207 -1.73355)
					(end 414.81629 -1.8034)
				)
				(xy 414.677098 -1.8034) (xy 414.603692 -1.876806) (xy 414.603692 -2.11709)
				(arc
					(start 415.073338 -2.11709)
					(mid 415.457132 -1.733677)
					(end 415.073592 -1.35001)
				)
				(arc
					(start 413.803592 -1.35001)
					(mid 413.420052 -1.73355)
					(end 413.803592 -2.11709)
				)
				(xy 414.171892 -2.11709) (xy 414.171892 -1.876806) (xy 414.098486 -1.8034)
				(arc
					(start 414.060894 -1.8034)
					(mid 413.536977 -1.73355)
					(end 414.060894 -1.6637)
				)
			)
		)
	)
	(zone
		(net "P1V2_AUX_BMC")
		(layer "In2.Cu")
		(hatch none 0.5)
		(connect_pads
			(clearance 0.5)
		)
		(min_thickness 0.25)
		(fill yes
			(thermal_gap 0.5)
			(thermal_bridge_width 0.5)
			(island_removal_mode 0)
		)
		(polygon
			(pts
				(xy 419.2524 -37.0078) (xy 419.7096 -37.0078) (xy 419.9382 -36.7792) (xy 419.9382 -32.9946) (xy 420.0906 -32.8422)
				(xy 420.0906 -32.0548) (xy 419.9382 -31.9024) (xy 419.9382 -31.5722) (xy 419.6588 -31.2928) (xy 419.0746 -31.2928)
				(xy 418.8968 -31.4706) (xy 418.8968 -33.0454) (xy 418.4396 -33.5026) (xy 418.4396 -35.4584) (xy 418.8968 -35.9156)
				(xy 418.8968 -36.6522)
			)
		)
	)
	(zone
		(net "P3V3")
		(layer "In2.Cu")
		(hatch none 0.5)
		(connect_pads
			(clearance 0.5)
		)
		(min_thickness 0.25)
		(fill yes
			(thermal_gap 0.5)
			(thermal_bridge_width 0.5)
			(island_removal_mode 0)
		)
		(polygon
			(pts
				(xy 481.955094 -113.284) (xy 477.3422 -113.284) (xy 477.0882 -113.538) (xy 477.0882 -116.459) (xy 477.901 -117.2718)
				(xy 479.3996 -117.2718) (xy 482.40696 -117.2718) (xy 482.82606 -116.8527) (xy 482.82606 -114.243866)
				(xy 482.72446 -114.142266) (xy 482.211634 -114.142266) (xy 482.05644 -114.142266) (xy 481.84181 -113.927636)
				(xy 481.84181 -113.620804) (xy 482.00056 -113.462054) (xy 482.00056 -113.329466)
			)
		)
	)
	(zone
		(layer "In2.Cu")
		(hatch none 0.5)
		(connect_pads
			(clearance 0)
		)
		(min_thickness 0.25)
		(keepout
			(tracks allowed)
			(vias allowed)
			(pads allowed)
			(copperpour allowed)
			(footprints allowed)
		)
		(placement
			(enabled no)
			(sheetname "")
		)
		(fill
			(thermal_gap 0.5)
			(thermal_bridge_width 0.5)
			(island_removal_mode 0)
		)
		(polygon
			(pts
				(xy 242.062 -49.403) (xy 249.174 -49.403) (xy 250.19 -50.419) (xy 250.19 -56.515) (xy 250.698 -57.023)
				(xy 250.952 -57.023) (xy 251.333 -57.404) (xy 251.333 -62.738) (xy 250.698 -63.373) (xy 246.634 -63.373)
				(xy 245.618 -62.357) (xy 245.618 -61.214) (xy 243.84 -59.436) (xy 243.84 -57.785) (xy 243.586 -57.531)
				(xy 239.395 -57.531) (xy 236.474 -60.452) (xy 232.029 -60.452) (xy 231.267 -59.69) (xy 231.267 -54.864)
				(xy 231.14 -54.737) (xy 231.14 -53.848) (xy 231.902 -53.086) (xy 231.902 -52.07) (xy 235.331 -48.641)
				(xy 238.76 -48.641) (xy 240.03 -47.371) (xy 240.538 -47.371) (xy 241.808 -48.641) (xy 241.808 -49.149)
			)
		)
	)
	(zone
		(layer "In2.Cu")
		(hatch none 0.5)
		(connect_pads
			(clearance 0)
		)
		(min_thickness 0.25)
		(keepout
			(tracks not_allowed)
			(vias allowed)
			(pads allowed)
			(copperpour not_allowed)
			(footprints allowed)
		)
		(placement
			(enabled no)
			(sheetname "")
		)
		(fill
			(thermal_gap 0.5)
			(thermal_bridge_width 0.5)
			(island_removal_mode 0)
		)
		(polygon
			(pts
				(xy 344.023442 -67.10299) (xy 344.023442 -67.30111)
				(arc
					(start 343.789 -67.535552)
					(mid 343.263077 -67.525603)
					(end 343.7636 -67.363594)
				)
				(xy 343.883742 -67.243198) (xy 343.883742 -67.10299)
				(arc
					(start 343.526872 -67.10299)
					(mid 343.143332 -67.48653)
					(end 343.526872 -67.87007)
				)
				(arc
					(start 344.491818 -67.87007)
					(mid 344.875612 -67.486657)
					(end 344.492072 -67.10299)
				)
				(xy 344.315542 -67.10299) (xy 344.315542 -67.211194)
				(arc
					(start 344.359484 -67.255136)
					(mid 344.680649 -67.675107)
					(end 344.260678 -67.353942)
				)
				(xy 344.175842 -67.269106) (xy 344.175842 -67.10299)
			)
		)
	)
	(zone
		(layer "In2.Cu")
		(hatch none 0.5)
		(connect_pads
			(clearance 0)
		)
		(min_thickness 0.25)
		(keepout
			(tracks allowed)
			(vias allowed)
			(pads allowed)
			(copperpour allowed)
			(footprints allowed)
		)
		(placement
			(enabled no)
			(sheetname "")
		)
		(fill
			(thermal_gap 0.5)
			(thermal_bridge_width 0.5)
			(island_removal_mode 0)
		)
		(polygon
			(pts
				(xy 114.247168 -57.7088) (xy 113.231168 -58.7248) (xy 110.564168 -58.7248) (xy 108.354368 -56.515)
				(xy 108.354368 -53.8734) (xy 110.767368 -53.8734) (xy 111.249968 -53.3908) (xy 112.342168 -53.3908)
				(xy 112.570768 -53.6194) (xy 112.570768 -54.7624) (xy 114.145568 -54.7624) (xy 114.145568 -54.102)
				(xy 116.812568 -54.102) (xy 117.574568 -54.864) (xy 119.098568 -54.864) (xy 119.454168 -55.2196)
				(xy 119.454168 -56.7944) (xy 118.565168 -57.6834) (xy 114.272568 -57.6834)
			)
		)
	)
	(zone
		(layer "In2.Cu")
		(hatch none 0.5)
		(connect_pads
			(clearance 0)
		)
		(min_thickness 0.25)
		(keepout
			(tracks not_allowed)
			(vias allowed)
			(pads allowed)
			(copperpour not_allowed)
			(footprints allowed)
		)
		(placement
			(enabled no)
			(sheetname "")
		)
		(fill
			(thermal_gap 0.5)
			(thermal_bridge_width 0.5)
			(island_removal_mode 0)
		)
		(polygon
			(pts
				(xy 406.584404 -144.992598) (xy 406.584658 -144.992852)
				(arc
					(start 406.730962 -145.139156)
					(mid 407.052127 -145.559127)
					(end 406.632156 -145.237962)
				)
				(xy 406.485598 -145.091404) (xy 406.48001 -145.086578)
				(arc
					(start 406.48001 -145.370296)
					(mid 406.863423 -145.75409)
					(end 407.24709 -145.37055)
				)
				(arc
					(start 407.24709 -144.35455)
					(mid 406.86355 -143.97101)
					(end 406.48001 -144.35455)
				)
				(xy 406.48001 -144.638522) (xy 406.485598 -144.633696)
				(arc
					(start 406.632156 -144.487138)
					(mid 407.052127 -144.165973)
					(end 406.730962 -144.585944)
				)
				(xy 406.584658 -144.732248) (xy 406.584404 -144.732502) (xy 406.564084 -144.752822)
				(arc
					(start 406.560274 -144.752822)
					(mid 406.524888 -144.772291)
					(end 406.486106 -144.783556)
				)
				(xy 406.483312 -144.78635) (xy 406.48001 -144.78635) (xy 406.48001 -144.93875) (xy 406.483312 -144.93875)
				(arc
					(start 406.486106 -144.941544)
					(mid 406.524881 -144.952828)
					(end 406.560274 -144.972278)
				)
				(xy 406.564084 -144.972278)
			)
		)
	)
	(zone
		(net "PVCCIN_CPU1")
		(layer "In2.Cu")
		(hatch none 0.5)
		(connect_pads
			(clearance 0.5)
		)
		(min_thickness 0.25)
		(fill yes
			(thermal_gap 0.5)
			(thermal_bridge_width 0.5)
			(island_removal_mode 0)
		)
		(polygon
			(pts
				(xy 43.434 -92.837) (xy 53.591206 -92.837) (xy 56.385206 -90.043) (xy 62.981586 -83.44662) (xy 66.68262 -83.44662)
				(xy 68.58762 -83.44662) (xy 71.36384 -80.6704) (xy 78.9178 -80.6704) (xy 84.455 -80.6704) (xy 87.7824 -83.9978)
				(xy 91.567 -87.7824) (xy 96.0882 -87.7824) (xy 98.6028 -85.2678) (xy 103.0097 -85.2678) (xy 109.540294 -85.2678)
				(xy 109.94136 -85.668866) (xy 109.94136 -87.213694) (xy 109.655864 -87.49919) (xy 107.606338 -87.49919)
				(xy 107.453176 -87.652352) (xy 107.453176 -89.385394) (xy 108.110782 -90.043) (xy 111.76 -90.043)
				(xy 114.3381 -87.4649) (xy 114.3381 -80.91678) (xy 112.54486 -79.12354) (xy 112.54486 -68.3133)
				(xy 110.90656 -66.675) (xy 108.939076 -66.675) (xy 108.77042 -66.843656) (xy 108.77042 -66.846196)
				(xy 108.66755 -66.949066) (xy 108.66755 -67.72021) (xy 108.45546 -67.9323) (xy 106.1593 -67.9323)
				(xy 101.9429 -67.9323) (xy 98.806 -67.9323) (xy 98.6917 -67.818) (xy 97.5487 -66.675) (xy 68.453 -66.675)
				(xy 68.453 -68.834) (xy 68.453 -69.1388) (xy 67.6148 -69.977) (xy 67.31 -69.977) (xy 61.5188 -69.977)
				(xy 42.9514 -51.4096) (xy 40.9956 -51.4096) (xy 40.767 -51.181) (xy 37.719 -51.181) (xy 37.3126 -50.7746)
				(xy 33.3502 -50.7746) (xy 30.734 -53.3908) (xy 30.734 -54.483) (xy 30.988 -54.737) (xy 31.242 -54.737)
				(xy 31.369 -54.61) (xy 31.369 -53.594) (xy 33.4518 -51.5112) (xy 37.2872 -51.5112) (xy 37.465 -51.689)
				(xy 39.624 -51.689) (xy 39.9542 -52.0192) (xy 41.1988 -52.0192) (xy 41.3766 -52.197) (xy 42.545 -52.197)
				(xy 43.434 -53.086) (xy 43.7134 -53.3654) (xy 43.7134 -54.5084) (xy 43.434 -54.7878)
			)
		)
	)
	(zone
		(layer "In2.Cu")
		(hatch none 0.5)
		(connect_pads
			(clearance 0)
		)
		(min_thickness 0.25)
		(keepout
			(tracks not_allowed)
			(vias allowed)
			(pads allowed)
			(copperpour not_allowed)
			(footprints allowed)
		)
		(placement
			(enabled no)
			(sheetname "")
		)
		(fill
			(thermal_gap 0.5)
			(thermal_bridge_width 0.5)
			(island_removal_mode 0)
		)
		(polygon
			(pts
				(arc
					(start 339.689186 -68.893182)
					(mid 339.269215 -69.214347)
					(end 339.59038 -68.794376)
				)
				(xy 339.695282 -68.689474) (xy 339.695282 -68.64223)
				(arc
					(start 339.457792 -68.64223)
					(mid 339.074252 -69.02577)
					(end 339.457792 -69.40931)
				)
				(arc
					(start 340.422738 -69.40931)
					(mid 340.806532 -69.025897)
					(end 340.422992 -68.64223)
				)
				(xy 340.138258 -68.64223)
				(arc
					(start 340.290404 -68.794376)
					(mid 340.611569 -69.214347)
					(end 340.191598 -68.893182)
				)
				(xy 339.987382 -68.688966) (xy 339.987382 -68.64223) (xy 339.834982 -68.64223) (xy 339.834982 -68.747386)
			)
		)
	)
	(zone
		(layer "In2.Cu")
		(hatch none 0.5)
		(connect_pads
			(clearance 0)
		)
		(min_thickness 0.25)
		(keepout
			(tracks not_allowed)
			(vias allowed)
			(pads allowed)
			(copperpour not_allowed)
			(footprints allowed)
		)
		(placement
			(enabled no)
			(sheetname "")
		)
		(fill
			(thermal_gap 0.5)
			(thermal_bridge_width 0.5)
			(island_removal_mode 0)
		)
		(polygon
			(pts
				(xy 389.636 -147.7264) (xy 389.636 -144.8562) (xy 393.319 -144.8562) (xy 393.319 -147.7264)
			)
		)
	)
	(zone
		(net "P12V_FAN")
		(layer "In2.Cu")
		(hatch none 0.5)
		(connect_pads
			(clearance 0.5)
		)
		(min_thickness 0.25)
		(fill yes
			(thermal_gap 0.5)
			(thermal_bridge_width 0.5)
			(island_removal_mode 0)
		)
		(polygon
			(pts
				(xy 14.2494 -117.901212) (xy 14.2494 -119.2784) (xy 13.8176 -119.7102) (xy 6.3754 -119.7102) (xy 4.696968 -119.7102)
				(xy 3.597656 -118.610888) (xy 3.597656 -115.04168) (xy 4.593844 -114.045492) (xy 4.999736 -113.6396)
				(xy 8.4582 -113.6396) (xy 10.0076 -113.6396) (xy 10.930128 -113.6396) (xy 10.936732 -113.646204)
				(xy 12.875006 -113.646204) (xy 14.2494 -115.020598)
			)
		)
	)
	(zone
		(net "GND")
		(layer "In2.Cu")
		(hatch none 0.5)
		(connect_pads
			(clearance 0.5)
		)
		(min_thickness 0.25)
		(fill yes
			(thermal_gap 0.5)
			(thermal_bridge_width 0.5)
			(island_removal_mode 0)
		)
		(polygon
			(pts
				(xy 35.414966 -51.943) (xy 34.5948 -52.763166) (xy 34.5948 -92.854272) (xy 34.770568 -93.03004)
				(xy 42.755058 -93.03004) (xy 42.911268 -92.87383) (xy 42.911268 -90.810334) (xy 42.58056 -90.479626)
				(xy 42.58056 -89.134442) (xy 42.911268 -88.803734) (xy 42.911268 -82.689192) (xy 42.579798 -82.357722)
				(xy 42.579798 -81.01584) (xy 42.911268 -80.68437) (xy 42.911268 -74.555604) (xy 42.578782 -74.223118)
				(xy 42.578782 -72.892412) (xy 42.911268 -72.559926) (xy 42.911268 -66.394076) (xy 42.580814 -66.063622)
				(xy 42.580814 -64.725296) (xy 42.911268 -64.394842) (xy 42.911268 -58.261758) (xy 42.602658 -57.953148)
				(xy 42.602658 -56.644794) (xy 42.911268 -56.336184) (xy 42.911268 -54.6862) (xy 43.1038 -54.493668)
				(xy 43.1038 -53.405532) (xy 42.911268 -53.213) (xy 42.200068 -52.5018) (xy 41.3258 -52.5018) (xy 41.0972 -52.2732)
				(xy 39.736268 -52.2732) (xy 39.406068 -51.943)
			)
		)
	)
	(zone
		(layer "In2.Cu")
		(hatch none 0.5)
		(connect_pads
			(clearance 0)
		)
		(min_thickness 0.25)
		(keepout
			(tracks not_allowed)
			(vias allowed)
			(pads allowed)
			(copperpour not_allowed)
			(footprints allowed)
		)
		(placement
			(enabled no)
			(sheetname "")
		)
		(fill
			(thermal_gap 0.5)
			(thermal_bridge_width 0.5)
			(island_removal_mode 0)
		)
		(polygon
			(pts
				(arc
					(start 25.715468 -130.576066)
					(mid 22.383496 -130.576066)
					(end 25.715468 -130.576066)
				)
			)
		)
	)
	(zone
		(layer "In2.Cu")
		(hatch none 0.5)
		(connect_pads
			(clearance 0)
		)
		(min_thickness 0.25)
		(keepout
			(tracks not_allowed)
			(vias allowed)
			(pads allowed)
			(copperpour not_allowed)
			(footprints allowed)
		)
		(placement
			(enabled no)
			(sheetname "")
		)
		(fill
			(thermal_gap 0.5)
			(thermal_bridge_width 0.5)
			(island_removal_mode 0)
		)
		(polygon
			(pts
				(xy 429.457104 -9.953498) (xy 429.60925 -10.105644) (xy 429.60925 -10.406888) (xy 429.76165 -10.406888)
				(xy 429.76165 -10.067798) (xy 429.87595 -9.953498)
				(arc
					(start 430.04359 -9.953498)
					(mid 430.567507 -10.023348)
					(end 430.04359 -10.093198)
				)
				(xy 429.933862 -10.093198) (xy 429.90135 -10.12571) (xy 429.90135 -10.406888)
				(arc
					(start 430.300892 -10.406888)
					(mid 430.684432 -10.023348)
					(end 430.300892 -9.639808)
				)
				(arc
					(start 429.031146 -9.639808)
					(mid 428.647352 -10.023221)
					(end 429.030892 -10.406888)
				)
				(xy 429.46955 -10.406888) (xy 429.46955 -10.163556) (xy 429.399192 -10.093198)
				(arc
					(start 429.288194 -10.093198)
					(mid 428.764277 -10.023348)
					(end 429.288194 -9.953498)
				)
			)
		)
	)
	(zone
		(layer "In2.Cu")
		(hatch none 0.5)
		(connect_pads
			(clearance 0)
		)
		(min_thickness 0.25)
		(keepout
			(tracks not_allowed)
			(vias allowed)
			(pads allowed)
			(copperpour not_allowed)
			(footprints allowed)
		)
		(placement
			(enabled no)
			(sheetname "")
		)
		(fill
			(thermal_gap 0.5)
			(thermal_bridge_width 0.5)
			(island_removal_mode 0)
		)
		(polygon
			(pts
				(arc
					(start 457.195936 -2.474214)
					(mid 457.166856 -2.488602)
					(end 457.136246 -2.49936)
				)
				(xy 457.221082 -2.49936)
			)
		)
	)
	(zone
		(layer "In2.Cu")
		(hatch none 0.5)
		(connect_pads
			(clearance 0)
		)
		(min_thickness 0.25)
		(keepout
			(tracks not_allowed)
			(vias allowed)
			(pads allowed)
			(copperpour not_allowed)
			(footprints allowed)
		)
		(placement
			(enabled no)
			(sheetname "")
		)
		(fill
			(thermal_gap 0.5)
			(thermal_bridge_width 0.5)
			(island_removal_mode 0)
		)
		(polygon
			(pts
				(xy 427.044104 -9.953498) (xy 427.19625 -10.105644) (xy 427.19625 -10.406888) (xy 427.34865 -10.406888)
				(xy 427.34865 -10.092944) (xy 427.488096 -9.953498)
				(arc
					(start 427.64329 -9.953498)
					(mid 428.167207 -10.023348)
					(end 427.64329 -10.093198)
				)
				(xy 427.546008 -10.093198) (xy 427.48835 -10.150856) (xy 427.48835 -10.406888)
				(arc
					(start 427.900338 -10.406888)
					(mid 428.284132 -10.023475)
					(end 427.900592 -9.639808)
				)
				(arc
					(start 426.630592 -9.639808)
					(mid 426.247052 -10.023348)
					(end 426.630592 -10.406888)
				)
				(xy 427.05655 -10.406888) (xy 427.05655 -10.163556) (xy 426.986192 -10.093198)
				(arc
					(start 426.887894 -10.093198)
					(mid 426.363977 -10.023348)
					(end 426.887894 -9.953498)
				)
			)
		)
	)
	(zone
		(layer "In2.Cu")
		(hatch none 0.5)
		(connect_pads
			(clearance 0)
		)
		(min_thickness 0.25)
		(keepout
			(tracks not_allowed)
			(vias allowed)
			(pads allowed)
			(copperpour not_allowed)
			(footprints allowed)
		)
		(placement
			(enabled no)
			(sheetname "")
		)
		(fill
			(thermal_gap 0.5)
			(thermal_bridge_width 0.5)
			(island_removal_mode 0)
		)
		(polygon
			(pts
				(arc
					(start 382.774444 -129.32283)
					(mid 382.39319 -129.703703)
					(end 382.77419 -130.08483)
				)
				(xy 382.844802 -130.08483)
				(arc
					(start 382.844802 -130.04292)
					(mid 382.842813 -130.00285)
					(end 382.836928 -129.963164)
				)
				(arc
					(start 382.836928 -129.963164)
					(mid 382.642756 -129.471421)
					(end 382.96342 -129.89179)
				)
				(arc
					(start 382.96342 -129.89179)
					(mid 382.976996 -129.951925)
					(end 382.98374 -130.013202)
				)
				(xy 382.984502 -130.013964) (xy 382.984502 -130.056636) (xy 382.985518 -130.08483) (xy 383.136902 -130.08483)
				(xy 383.136902 -129.995168)
				(arc
					(start 383.138426 -129.993644)
					(mid 383.159084 -129.911913)
					(end 383.20218 -129.839466)
				)
				(xy 383.20218 -129.83718)
				(arc
					(start 383.203196 -129.836164)
					(mid 383.622875 -129.515006)
					(end 383.304034 -129.936494)
				)
				(arc
					(start 383.304034 -129.936494)
					(mid 383.283624 -129.978084)
					(end 383.276602 -130.02387)
				)
				(arc
					(start 383.276602 -130.056636)
					(mid 383.27741 -130.070832)
					(end 383.279904 -130.08483)
				)
				(arc
					(start 383.43459 -130.08483)
					(mid 383.81559 -129.70383)
					(end 383.43459 -129.32283)
				)
			)
		)
	)
	(zone
		(layer "In2.Cu")
		(hatch none 0.5)
		(connect_pads
			(clearance 0)
		)
		(min_thickness 0.25)
		(keepout
			(tracks allowed)
			(vias allowed)
			(pads allowed)
			(copperpour allowed)
			(footprints allowed)
		)
		(placement
			(enabled no)
			(sheetname "")
		)
		(fill
			(thermal_gap 0.5)
			(thermal_bridge_width 0.5)
			(island_removal_mode 0)
		)
		(polygon
			(pts
				(xy 367.411 -113.538) (xy 367.411 -112.522) (xy 368.173 -112.522) (xy 368.173 -113.538)
			)
		)
	)
	(zone
		(net "VCC_D_3V3")
		(layer "In2.Cu")
		(hatch none 0.5)
		(connect_pads
			(clearance 0.5)
		)
		(min_thickness 0.25)
		(fill yes
			(thermal_gap 0.5)
			(thermal_bridge_width 0.5)
			(island_removal_mode 0)
		)
		(polygon
			(pts
				(xy 418.614098 -32.8422) (xy 418.614098 -30.000702) (xy 418.180774 -29.567378) (xy 411.70733 -29.567378)
				(xy 411.038294 -30.236414) (xy 410.59862 -30.236414) (xy 410.19476 -30.640274) (xy 410.19476 -30.825694)
				(xy 410.181806 -30.838648) (xy 410.181806 -37.987732) (xy 410.60116 -38.407086) (xy 411.709108 -38.407086)
				(xy 412.237174 -38.935152) (xy 412.237174 -39.649654) (xy 412.95066 -40.36314) (xy 416.21329 -40.36314)
				(xy 417.501578 -39.074852) (xy 418.15385 -38.42258) (xy 419.2016 -38.42258) (xy 419.332156 -38.292024)
				(xy 419.332156 -37.773356) (xy 418.614098 -37.055298) (xy 418.614098 -36.217098) (xy 418.0332 -35.6362)
				(xy 418.0332 -33.423098)
			)
		)
		(polygon
			(pts
				(xy 410.916882 -30.681676) (xy 410.912564 -30.681676) (xy 410.862018 -30.731968)
				(arc
					(start 410.336492 -30.731968)
					(mid 410.257059 -30.77022)
					(end 410.237432 -30.856174)
				)
				(arc
					(start 410.237432 -30.856174)
					(mid 410.239659 -31.003095)
					(end 410.182314 -31.138368)
				)
				(xy 410.182314 -31.563564)
				(arc
					(start 410.19095 -31.578804)
					(mid 410.281948 -31.632266)
					(end 410.37129 -31.57601)
				)
				(arc
					(start 410.37129 -31.57601)
					(mid 410.936309 -31.476855)
					(end 410.863288 -32.045656)
				)
				(arc
					(start 410.863288 -32.045656)
					(mid 410.810921 -32.134556)
					(end 410.863288 -32.223456)
				)
				(arc
					(start 410.863288 -32.223456)
					(mid 410.942043 -32.282739)
					(end 411.001464 -32.361378)
				)
				(arc
					(start 411.001464 -32.361378)
					(mid 411.090302 -32.413745)
					(end 411.17901 -32.361378)
				)
				(arc
					(start 411.17901 -32.361378)
					(mid 411.490271 -32.178485)
					(end 411.80131 -32.361632)
				)
				(arc
					(start 411.80131 -32.361632)
					(mid 411.89021 -32.413999)
					(end 411.97911 -32.361632)
				)
				(arc
					(start 411.97911 -32.361632)
					(mid 412.038393 -32.282877)
					(end 412.117032 -32.223456)
				)
				(arc
					(start 412.117032 -32.223456)
					(mid 412.169177 -32.134748)
					(end 412.117032 -32.04591)
				)
				(arc
					(start 412.117032 -32.04591)
					(mid 412.038444 -31.482944)
					(end 412.60141 -31.561532)
				)
				(arc
					(start 412.60141 -31.561532)
					(mid 412.690248 -31.613899)
					(end 412.778956 -31.561532)
				)
				(arc
					(start 412.778956 -31.561532)
					(mid 412.841159 -31.480108)
					(end 412.92399 -31.4198)
				)
				(arc
					(start 412.92399 -31.4198)
					(mid 412.978314 -31.330735)
					(end 412.925514 -31.24073)
				)
				(arc
					(start 412.925514 -31.24073)
					(mid 412.740381 -30.934454)
					(end 412.914846 -30.621986)
				)
				(arc
					(start 412.914846 -30.621986)
					(mid 412.964611 -30.533759)
					(end 412.913322 -30.446472)
				)
				(arc
					(start 412.913322 -30.446472)
					(mid 412.836342 -30.387175)
					(end 412.778194 -30.309312)
				)
				(arc
					(start 412.778194 -30.309312)
					(mid 412.689688 -30.256814)
					(end 412.600648 -30.30855)
				)
				(arc
					(start 412.600648 -30.30855)
					(mid 412.267575 -30.489902)
					(end 411.959806 -30.268164)
				)
				(xy 411.947106 -30.236414)
				(arc
					(start 411.948884 -30.236414)
					(mid 412.1533 -29.805851)
					(end 412.602934 -29.96438)
				)
				(arc
					(start 412.602934 -29.96438)
					(mid 412.691693 -30.017364)
					(end 412.780988 -29.965142)
				)
				(arc
					(start 412.780988 -29.965142)
					(mid 412.840865 -29.885573)
					(end 412.920434 -29.825696)
				)
				(arc
					(start 412.920434 -29.825696)
					(mid 412.972932 -29.736452)
					(end 412.919926 -29.647388)
				)
				(arc
					(start 412.919926 -29.647388)
					(mid 412.866952 -29.612074)
					(end 412.82112 -29.567886)
				)
				(xy 411.707584 -29.567886) (xy 411.236668 -30.038802) (xy 411.236668 -30.236414) (xy 411.357572 -30.236414)
				(xy 411.236668 -30.357318) (xy 411.236668 -30.361636)
			)
		)
		(polygon
			(pts
				(arc
					(start 416.885374 -29.626052)
					(mid 416.851464 -29.598934)
					(end 416.821112 -29.567886)
				)
				(arc
					(start 414.959038 -29.567886)
					(mid 414.914561 -29.611052)
					(end 414.86328 -29.645864)
				)
				(arc
					(start 414.86328 -29.645864)
					(mid 414.811043 -29.734702)
					(end 414.86328 -29.82341)
				)
				(arc
					(start 414.86328 -29.82341)
					(mid 414.942035 -29.882693)
					(end 415.001456 -29.961332)
				)
				(arc
					(start 415.001456 -29.961332)
					(mid 415.090294 -30.013699)
					(end 415.179002 -29.961332)
				)
				(arc
					(start 415.179002 -29.961332)
					(mid 415.490325 -29.778439)
					(end 415.801556 -29.961586)
				)
				(arc
					(start 415.801556 -29.961586)
					(mid 415.890394 -30.013953)
					(end 415.979102 -29.961586)
				)
				(arc
					(start 415.979102 -29.961586)
					(mid 416.281997 -29.778789)
					(end 416.59302 -29.947362)
				)
				(arc
					(start 416.59302 -29.947362)
					(mid 416.686589 -29.99527)
					(end 416.772598 -29.934662)
				)
				(arc
					(start 416.772598 -29.934662)
					(mid 416.820591 -29.855379)
					(end 416.887406 -29.791152)
				)
				(arc
					(start 416.887406 -29.791152)
					(mid 416.928753 -29.708095)
					(end 416.885374 -29.626052)
				)
			)
		)
	)
	(zone
		(layer "In2.Cu")
		(hatch none 0.5)
		(connect_pads
			(clearance 0)
		)
		(min_thickness 0.25)
		(keepout
			(tracks allowed)
			(vias allowed)
			(pads allowed)
			(copperpour allowed)
			(footprints allowed)
		)
		(placement
			(enabled no)
			(sheetname "")
		)
		(fill
			(thermal_gap 0.5)
			(thermal_bridge_width 0.5)
			(island_removal_mode 0)
		)
		(polygon
			(pts
				(xy 232.029 -90.424) (xy 245.618 -90.424) (xy 247.65 -88.392) (xy 249.936 -88.392) (xy 250.952 -89.408)
				(xy 250.952 -94.742) (xy 250.952 -100.457) (xy 250.317 -101.092) (xy 250.317 -105.283) (xy 232.156 -105.283)
				(xy 229.235 -102.362) (xy 229.235 -94.869) (xy 231.013 -93.091) (xy 231.267 -93.091) (xy 231.267 -91.567)
				(xy 231.775 -91.059) (xy 231.775 -90.678)
			)
		)
	)
	(zone
		(layer "In2.Cu")
		(hatch none 0.5)
		(connect_pads
			(clearance 0)
		)
		(min_thickness 0.25)
		(keepout
			(tracks not_allowed)
			(vias allowed)
			(pads allowed)
			(copperpour not_allowed)
			(footprints allowed)
		)
		(placement
			(enabled no)
			(sheetname "")
		)
		(fill
			(thermal_gap 0.5)
			(thermal_bridge_width 0.5)
			(island_removal_mode 0)
		)
		(polygon
			(pts
				(xy 412.576264 -10.520934) (xy 412.57728 -10.280904) (xy 412.50489 -10.20699)
				(arc
					(start 412.406084 -10.206228)
					(mid 411.8827 -10.132751)
					(end 412.4071 -10.066528)
				)
				(xy 412.505906 -10.06729) (xy 412.50616 -10.06729) (xy 412.534862 -10.067544) (xy 412.563818 -10.067798)
				(xy 412.584138 -10.088372) (xy 412.604458 -10.108946) (xy 412.697168 -10.203434) (xy 412.717488 -10.223754)
				(xy 412.717488 -10.224008) (xy 412.717488 -10.224262) (xy 412.717234 -10.252964) (xy 412.715964 -10.52195)
				(xy 412.868618 -10.522966) (xy 412.869634 -10.282428) (xy 412.86938 -10.282428) (xy 412.869634 -10.253726)
				(xy 412.869634 -10.22477) (xy 412.869888 -10.22477) (xy 412.869888 -10.224516) (xy 412.890462 -10.20445)
				(xy 412.910782 -10.18413) (xy 412.911036 -10.18413) (xy 412.98495 -10.110978) (xy 413.005524 -10.090658)
				(xy 413.026098 -10.070338) (xy 413.055054 -10.070592) (xy 413.08401 -10.070846)
				(arc
					(start 413.182816 -10.071608)
					(mid 413.7062 -10.145085)
					(end 413.1818 -10.211308)
				)
				(xy 413.082994 -10.210546) (xy 413.009334 -10.28319) (xy 413.008318 -10.523982)
				(arc
					(start 413.436816 -10.526776)
					(mid 413.822895 -10.145903)
					(end 413.44215 -9.759696)
				)
				(arc
					(start 412.15183 -9.75106)
					(mid 411.76575 -10.13206)
					(end 412.14675 -10.51814)
				)
			)
		)
	)
	(zone
		(net "VR_FET_SW_P12V_STBY_PVPP_KLM")
		(layer "In2.Cu")
		(hatch none 0.5)
		(connect_pads
			(clearance 0.5)
		)
		(min_thickness 0.25)
		(fill yes
			(thermal_gap 0.5)
			(thermal_bridge_width 0.5)
			(island_removal_mode 0)
		)
		(polygon
			(pts
				(xy 181.991 -132.969) (xy 179.197 -132.969) (xy 178.598576 -133.567424) (xy 173.74997 -133.567424)
				(xy 173.503082 -133.814312) (xy 173.305724 -134.01167) (xy 173.305724 -136.147048) (xy 173.503082 -136.344406)
				(xy 173.683676 -136.525) (xy 174.1424 -136.525) (xy 182.0418 -136.525) (xy 182.6768 -137.16) (xy 186.9694 -137.16)
				(xy 187.452 -136.6774) (xy 187.452 -135.6106) (xy 187.325 -135.4836) (xy 185.928 -135.4836) (xy 185.674 -135.2296)
				(xy 185.6613 -135.2169) (xy 185.6613 -134.4041) (xy 185.57875 -134.32155) (xy 184.2262 -132.969)
			)
		)
	)
	(zone
		(layer "In2.Cu")
		(hatch none 0.5)
		(connect_pads
			(clearance 0)
		)
		(min_thickness 0.25)
		(keepout
			(tracks not_allowed)
			(vias allowed)
			(pads allowed)
			(copperpour not_allowed)
			(footprints allowed)
		)
		(placement
			(enabled no)
			(sheetname "")
		)
		(fill
			(thermal_gap 0.5)
			(thermal_bridge_width 0.5)
			(island_removal_mode 0)
		)
		(polygon
			(pts
				(xy 421.741092 -2.973324) (xy 421.741092 -2.695448) (xy 421.927274 -2.509266)
				(arc
					(start 421.98544 -2.509266)
					(mid 422.509357 -2.579116)
					(end 421.98544 -2.648966)
				)
				(xy 421.985186 -2.648966) (xy 421.880792 -2.75336) (xy 421.880792 -2.970276)
				(arc
					(start 422.250362 -2.962656)
					(mid 422.626279 -2.571369)
					(end 422.234868 -2.195576)
				)
				(arc
					(start 420.963852 -2.221992)
					(mid 420.588186 -2.613406)
					(end 420.9796 -2.989072)
				)
				(xy 421.448992 -2.97942) (xy 421.448992 -2.778252) (xy 421.346122 -2.675382)
				(arc
					(start 421.229028 -2.675382)
					(mid 420.705111 -2.605532)
					(end 421.229028 -2.535682)
				)
				(xy 421.404034 -2.535682) (xy 421.588692 -2.72034) (xy 421.588692 -2.976372)
			)
		)
	)
	(zone
		(layer "In2.Cu")
		(hatch none 0.5)
		(connect_pads
			(clearance 0)
		)
		(min_thickness 0.25)
		(keepout
			(tracks not_allowed)
			(vias allowed)
			(pads allowed)
			(copperpour not_allowed)
			(footprints allowed)
		)
		(placement
			(enabled no)
			(sheetname "")
		)
		(fill
			(thermal_gap 0.5)
			(thermal_bridge_width 0.5)
			(island_removal_mode 0)
		)
		(polygon
			(pts
				(xy 416.951922 -3.20421) (xy 416.951922 -2.942082) (xy 417.143184 -2.75082)
				(arc
					(start 417.284408 -2.75082)
					(mid 417.808325 -2.82067)
					(end 417.284408 -2.89052)
				)
				(xy 417.201096 -2.89052) (xy 417.091622 -2.999994) (xy 417.091622 -3.20421)
				(arc
					(start 417.541456 -3.20421)
					(mid 417.92525 -2.820797)
					(end 417.54171 -2.43713)
				)
				(arc
					(start 416.27171 -2.43713)
					(mid 415.88817 -2.82067)
					(end 416.27171 -3.20421)
				)
				(xy 416.659822 -3.20421) (xy 416.659822 -2.963926) (xy 416.586416 -2.89052)
				(arc
					(start 416.529012 -2.89052)
					(mid 416.005095 -2.82067)
					(end 416.529012 -2.75082)
				)
				(xy 416.644328 -2.75082) (xy 416.799522 -2.906014) (xy 416.799522 -3.20421)
			)
		)
	)
	(zone
		(layer "In2.Cu")
		(hatch none 0.5)
		(connect_pads
			(clearance 0)
		)
		(min_thickness 0.25)
		(keepout
			(tracks not_allowed)
			(vias allowed)
			(pads allowed)
			(copperpour not_allowed)
			(footprints allowed)
		)
		(placement
			(enabled no)
			(sheetname "")
		)
		(fill
			(thermal_gap 0.5)
			(thermal_bridge_width 0.5)
			(island_removal_mode 0)
		)
		(polygon
			(pts
				(xy 420.16045 -10.406888) (xy 420.16045 -10.118598) (xy 420.32555 -9.953498)
				(arc
					(start 420.44239 -9.953498)
					(mid 420.966307 -10.023348)
					(end 420.44239 -10.093198)
				)
				(xy 420.383462 -10.093198) (xy 420.30015 -10.17651) (xy 420.30015 -10.406888)
				(arc
					(start 420.699438 -10.406888)
					(mid 421.083232 -10.023475)
					(end 420.699692 -9.639808)
				)
				(arc
					(start 419.429692 -9.639808)
					(mid 419.046152 -10.023348)
					(end 419.429692 -10.406888)
				)
				(xy 419.86835 -10.406888) (xy 419.86835 -10.163556) (xy 419.797992 -10.093198)
				(arc
					(start 419.686994 -10.093198)
					(mid 419.163077 -10.023348)
					(end 419.686994 -9.953498)
				)
				(xy 419.855904 -9.953498) (xy 420.00805 -10.105644) (xy 420.00805 -10.406888)
			)
		)
	)
	(zone
		(layer "In2.Cu")
		(hatch none 0.5)
		(connect_pads
			(clearance 0)
		)
		(min_thickness 0.25)
		(keepout
			(tracks not_allowed)
			(vias allowed)
			(pads allowed)
			(copperpour not_allowed)
			(footprints allowed)
		)
		(placement
			(enabled no)
			(sheetname "")
		)
		(fill
			(thermal_gap 0.5)
			(thermal_bridge_width 0.5)
			(island_removal_mode 0)
		)
		(polygon
			(pts
				(arc
					(start 426.951394 -139.705588)
					(mid 426.531423 -140.026753)
					(end 426.852588 -139.606782)
				)
				(xy 427.004734 -139.454636)
				(arc
					(start 426.720254 -139.454636)
					(mid 426.33646 -139.838049)
					(end 426.72 -140.221716)
				)
				(arc
					(start 427.99 -140.221716)
					(mid 428.37354 -139.838176)
					(end 427.99 -139.454636)
				)
				(xy 427.705266 -139.454636)
				(arc
					(start 427.857412 -139.606782)
					(mid 428.178577 -140.026753)
					(end 427.758606 -139.705588)
				)
				(xy 427.507654 -139.454636) (xy 427.202346 -139.454636)
			)
		)
	)
	(zone
		(layer "In2.Cu")
		(hatch none 0.5)
		(connect_pads
			(clearance 0)
		)
		(min_thickness 0.25)
		(keepout
			(tracks allowed)
			(vias allowed)
			(pads allowed)
			(copperpour allowed)
			(footprints allowed)
		)
		(placement
			(enabled no)
			(sheetname "")
		)
		(fill
			(thermal_gap 0.5)
			(thermal_bridge_width 0.5)
			(island_removal_mode 0)
		)
		(polygon
			(pts
				(xy 354.076 -122.174) (xy 354.076 -120.904) (xy 355.473 -120.904) (xy 355.473 -122.174)
			)
		)
	)
	(zone
		(net "P1V2_AUX_BMC")
		(layer "In2.Cu")
		(hatch none 0.5)
		(connect_pads
			(clearance 0.5)
		)
		(min_thickness 0.25)
		(fill yes
			(thermal_gap 0.5)
			(thermal_bridge_width 0.5)
			(island_removal_mode 0)
		)
		(polygon
			(pts
				(xy 466.9536 -39.624) (xy 469.1126 -37.465) (xy 469.138 -37.4904) (xy 470.281 -37.4904) (xy 471.82151 -35.94989)
				(xy 472.1352 -35.6362) (xy 472.1352 -35.0139) (xy 471.92692 -34.80562) (xy 471.604848 -34.80562)
				(xy 471.585544 -34.786316) (xy 470.212674 -33.4137) (xy 458.5589 -33.4137) (xy 457.835 -32.6898)
				(xy 457.835 -29.337) (xy 456.692 -28.194) (xy 450.152008 -28.194) (xy 448.831208 -29.5148) (xy 448.831208 -30.322266)
				(xy 448.547744 -30.60573) (xy 448.14363 -30.60573) (xy 447.806064 -30.268164) (xy 447.806064 -28.090622)
				(xy 444.881 -25.165558) (xy 444.881 -25.146) (xy 443.611 -23.876) (xy 436.118 -23.876) (xy 435.356 -24.638)
				(xy 435.356 -25.3492) (xy 435.5338 -25.527) (xy 438.785 -25.527) (xy 440.055 -26.797) (xy 440.055 -27.854148)
				(xy 441.523628 -29.322776) (xy 442.392816 -29.322776) (xy 442.554614 -29.322776) (xy 443.056772 -29.824934)
				(xy 443.056772 -29.986732) (xy 443.056772 -31.525464) (xy 443.288928 -31.75762) (xy 443.288928 -35.741356)
				(xy 443.062106 -35.968178) (xy 443.062106 -36.306506) (xy 443.7634 -37.0078) (xy 443.7634 -38.5064)
				(xy 443.7634 -41.7195) (xy 444.68796 -42.64406) (xy 463.93354 -42.64406)
			)
		)
	)
	(zone
		(layer "In2.Cu")
		(hatch none 0.5)
		(connect_pads
			(clearance 0)
		)
		(min_thickness 0.25)
		(keepout
			(tracks allowed)
			(vias allowed)
			(pads allowed)
			(copperpour allowed)
			(footprints allowed)
		)
		(placement
			(enabled no)
			(sheetname "")
		)
		(fill
			(thermal_gap 0.5)
			(thermal_bridge_width 0.5)
			(island_removal_mode 0)
		)
		(polygon
			(pts
				(xy 97.268792 -91.26474) (xy 97.268792 -88.537034) (xy 103.298244 -88.537034) (xy 103.298244 -91.26474)
			)
		)
	)
	(zone
		(net "P12V_PSU")
		(layer "In2.Cu")
		(hatch none 0.5)
		(connect_pads
			(clearance 0.5)
		)
		(min_thickness 0.25)
		(fill yes
			(thermal_gap 0.5)
			(thermal_bridge_width 0.5)
			(island_removal_mode 0)
		)
		(polygon
			(pts
				(xy 3.0734 -52.4002) (xy 3.0734 -59.1566) (xy 2.3114 -59.9186) (xy 2.3114 -67.1322) (xy 3.5306 -68.3514)
				(xy 3.5306 -85.583268) (xy 4.128516 -86.181184) (xy 9.83996 -86.181184) (xy 10.0584 -85.962744)
				(xy 10.092436 -85.928708) (xy 10.092436 -50.671476) (xy 9.45896 -50.038) (xy 3.361944 -50.038) (xy 3.0734 -50.326544)
				(xy 3.0734 -50.3682)
			)
		)
	)
	(zone
		(net "GND")
		(layer "In2.Cu")
		(hatch none 0.5)
		(connect_pads
			(clearance 0.5)
		)
		(min_thickness 0.25)
		(fill yes
			(thermal_gap 0.5)
			(thermal_bridge_width 0.5)
			(island_removal_mode 0)
		)
		(polygon
			(pts
				(xy 34.5948 -93.650816) (xy 34.5948 -99.7204) (xy 33.1724 -101.1428) (xy 33.1724 -102.3874) (xy 33.401 -102.616)
				(xy 36.7538 -102.616) (xy 37.5666 -101.8032) (xy 41.465246 -101.8032) (xy 42.911268 -100.357178)
				(xy 42.911268 -93.733874) (xy 42.71645 -93.539056) (xy 34.70656 -93.539056)
			)
		)
	)
	(zone
		(layer "In2.Cu")
		(hatch none 0.5)
		(connect_pads
			(clearance 0)
		)
		(min_thickness 0.25)
		(keepout
			(tracks not_allowed)
			(vias allowed)
			(pads allowed)
			(copperpour not_allowed)
			(footprints allowed)
		)
		(placement
			(enabled no)
			(sheetname "")
		)
		(fill
			(thermal_gap 0.5)
			(thermal_bridge_width 0.5)
			(island_removal_mode 0)
		)
		(polygon
			(pts
				(xy 419.236398 -1.5367) (xy 419.391592 -1.691894) (xy 419.391592 -1.99009) (xy 419.543992 -1.99009)
				(xy 419.543992 -1.691894) (xy 419.699186 -1.5367)
				(arc
					(start 419.79469 -1.5367)
					(mid 420.318607 -1.60655)
					(end 419.79469 -1.6764)
				)
				(xy 419.757098 -1.6764) (xy 419.683692 -1.749806) (xy 419.683692 -1.99009)
				(arc
					(start 420.051738 -1.99009)
					(mid 420.435532 -1.606677)
					(end 420.051992 -1.22301)
				)
				(arc
					(start 418.781992 -1.22301)
					(mid 418.398452 -1.60655)
					(end 418.781992 -1.99009)
				)
				(xy 419.233096 -1.99009) (xy 419.251892 -1.971294) (xy 419.251892 -1.749806) (xy 419.178486 -1.6764)
				(arc
					(start 419.039294 -1.6764)
					(mid 418.515377 -1.60655)
					(end 419.039294 -1.5367)
				)
			)
		)
	)
	(zone
		(layer "In2.Cu")
		(hatch none 0.5)
		(connect_pads
			(clearance 0)
		)
		(min_thickness 0.25)
		(keepout
			(tracks not_allowed)
			(vias allowed)
			(pads allowed)
			(copperpour not_allowed)
			(footprints allowed)
		)
		(placement
			(enabled no)
			(sheetname "")
		)
		(fill
			(thermal_gap 0.5)
			(thermal_bridge_width 0.5)
			(island_removal_mode 0)
		)
		(polygon
			(pts
				(xy 331.45222 4.572) (xy 337.0834 4.572) (xy 337.82 3.8354) (xy 337.82 3.0988) (xy 337.6676 2.9464)
				(xy 335.834736 2.9464) (xy 335.3308 3.450336) (xy 331.942186 3.450336) (xy 331.942186 2.947416)
				(xy 331.098398 2.947416) (xy 331.098398 -0.155956) (xy 335.842864 -0.155956) (xy 335.842864 2.244598)
				(xy 337.566 2.244598) (xy 337.566 -0.116586) (xy 338.011262 -0.561848) (xy 338.011262 -2.038604)
				(xy 341.9729 -2.038604) (xy 341.9729 3.808222) (xy 341.505032 3.808222) (xy 341.505032 5.025136)
				(xy 331.45222 5.025136)
			)
		)
	)
	(zone
		(layers "In2.Cu" "In4.Cu" "Cmts.User" "In9.Cu")
		(hatch none 0.5)
		(connect_pads
			(clearance 0)
		)
		(min_thickness 0.25)
		(keepout
			(tracks allowed)
			(vias allowed)
			(pads allowed)
			(copperpour allowed)
			(footprints allowed)
		)
		(placement
			(enabled no)
			(sheetname "")
		)
		(fill yes
			(thermal_gap 0.5)
			(thermal_bridge_width 0.5)
			(island_removal_mode 0)
		)
		(polygon
			(pts
				(xy 322.279772 -125.349) (xy 322.279772 -157.861) (xy 194.009772 -157.861) (xy 194.009772 -127.2794)
				(xy 195.939156 -125.350016) (xy 195.961 -125.350016) (xy 197.028816 -124.2822) (xy 244.729 -124.2822)
				(xy 244.729 -126.873) (xy 244.856 -127) (xy 288.544 -127) (xy 288.544 -124.2822) (xy 321.212972 -124.2822)
			)
		)
	)
	(zone
		(layers "In2.Cu" "In4.Cu" "In9.Cu")
		(hatch none 0.5)
		(connect_pads
			(clearance 0)
		)
		(min_thickness 0.25)
		(keepout
			(tracks allowed)
			(vias allowed)
			(pads allowed)
			(copperpour allowed)
			(footprints allowed)
		)
		(placement
			(enabled no)
			(sheetname "")
		)
		(fill yes
			(thermal_gap 0.5)
			(thermal_bridge_width 0.5)
			(island_removal_mode 0)
		)
		(polygon
			(pts
				(xy 157.27934 -125.349) (xy 157.27934 -157.861) (xy 29.00934 -157.861) (xy 29.00934 -127.2794) (xy 30.938724 -125.350016)
				(xy 30.960568 -125.350016) (xy 32.028384 -124.2822) (xy 79.728568 -124.2822) (xy 79.728568 -126.873)
				(xy 79.855568 -127) (xy 123.543568 -127) (xy 123.543568 -124.2822) (xy 156.21254 -124.2822)
			)
		)
	)
	(zone
		(layers "In2.Cu" "In4.Cu" "In9.Cu" "In11.Cu")
		(hatch none 0.5)
		(connect_pads
			(clearance 0)
		)
		(min_thickness 0.25)
		(keepout
			(tracks not_allowed)
			(vias allowed)
			(pads allowed)
			(copperpour not_allowed)
			(footprints allowed)
		)
		(placement
			(enabled no)
			(sheetname "")
		)
		(fill yes
			(thermal_gap 0.5)
			(thermal_bridge_width 0.5)
			(island_removal_mode 0)
		)
		(polygon
			(pts
				(arc
					(start 328.666348 -17.723612)
					(mid 325.334376 -17.723612)
					(end 328.666348 -17.723612)
				)
			)
		)
	)
	(zone
		(layers "In2.Cu" "In4.Cu" "In9.Cu" "In11.Cu")
		(hatch none 0.5)
		(connect_pads
			(clearance 0)
		)
		(min_thickness 0.25)
		(keepout
			(tracks not_allowed)
			(vias allowed)
			(pads allowed)
			(copperpour not_allowed)
			(footprints allowed)
		)
		(placement
			(enabled no)
			(sheetname "")
		)
		(fill yes
			(thermal_gap 0.5)
			(thermal_bridge_width 0.5)
			(island_removal_mode 0)
		)
		(polygon
			(pts
				(arc
					(start 328.666348 -12.923012)
					(mid 325.334376 -12.923012)
					(end 328.666348 -12.923012)
				)
			)
		)
	)
	(zone
		(layers "In2.Cu" "In4.Cu" "In9.Cu" "In11.Cu")
		(hatch none 0.5)
		(connect_pads
			(clearance 0)
		)
		(min_thickness 0.25)
		(keepout
			(tracks not_allowed)
			(vias allowed)
			(pads allowed)
			(copperpour not_allowed)
			(footprints allowed)
		)
		(placement
			(enabled no)
			(sheetname "")
		)
		(fill yes
			(thermal_gap 0.5)
			(thermal_bridge_width 0.5)
			(island_removal_mode 0)
		)
		(polygon
			(pts
				(arc
					(start 328.666348 1.478788)
					(mid 325.334376 1.478788)
					(end 328.666348 1.478788)
				)
			)
		)
	)
	(zone
		(layers "In2.Cu" "In4.Cu" "In9.Cu" "In11.Cu")
		(hatch none 0.5)
		(connect_pads
			(clearance 0)
		)
		(min_thickness 0.25)
		(keepout
			(tracks not_allowed)
			(vias allowed)
			(pads allowed)
			(copperpour not_allowed)
			(footprints allowed)
		)
		(placement
			(enabled no)
			(sheetname "")
		)
		(fill yes
			(thermal_gap 0.5)
			(thermal_bridge_width 0.5)
			(island_removal_mode 0)
		)
		(polygon
			(pts
				(arc
					(start 429.641 -116.216938)
					(mid 431.6984 -118.274338)
					(end 433.7558 -116.216938)
				)
				(arc
					(start 433.7558 -114.565938)
					(mid 431.6984 -112.508538)
					(end 429.641 -114.565938)
				)
			)
		)
	)
	(zone
		(layers "In2.Cu" "In4.Cu" "In9.Cu" "In11.Cu")
		(hatch none 0.5)
		(connect_pads
			(clearance 0)
		)
		(min_thickness 0.25)
		(keepout
			(tracks not_allowed)
			(vias allowed)
			(pads allowed)
			(copperpour not_allowed)
			(footprints allowed)
		)
		(placement
			(enabled no)
			(sheetname "")
		)
		(fill yes
			(thermal_gap 0.5)
			(thermal_bridge_width 0.5)
			(island_removal_mode 0)
		)
		(polygon
			(pts
				(arc
					(start 328.666348 -8.122412)
					(mid 325.334376 -8.122412)
					(end 328.666348 -8.122412)
				)
			)
		)
	)
	(zone
		(layers "In2.Cu" "In4.Cu" "In9.Cu" "In11.Cu")
		(hatch none 0.5)
		(connect_pads
			(clearance 0)
		)
		(min_thickness 0.25)
		(keepout
			(tracks not_allowed)
			(vias allowed)
			(pads allowed)
			(copperpour not_allowed)
			(footprints allowed)
		)
		(placement
			(enabled no)
			(sheetname "")
		)
		(fill yes
			(thermal_gap 0.5)
			(thermal_bridge_width 0.5)
			(island_removal_mode 0)
		)
		(polygon
			(pts
				(arc
					(start 494.641124 -116.216938)
					(mid 496.698524 -118.274338)
					(end 498.755924 -116.216938)
				)
				(arc
					(start 498.755924 -114.565938)
					(mid 496.698524 -112.508538)
					(end 494.641124 -114.565938)
				)
			)
		)
	)
	(zone
		(layers "In2.Cu" "In4.Cu" "In9.Cu" "In11.Cu")
		(hatch none 0.5)
		(connect_pads
			(clearance 0)
		)
		(min_thickness 0.25)
		(keepout
			(tracks not_allowed)
			(vias allowed)
			(pads allowed)
			(copperpour not_allowed)
			(footprints allowed)
		)
		(placement
			(enabled no)
			(sheetname "")
		)
		(fill yes
			(thermal_gap 0.5)
			(thermal_bridge_width 0.5)
			(island_removal_mode 0)
		)
		(polygon
			(pts
				(arc
					(start 476.255842 -58.9661)
					(mid 474.198442 -56.9087)
					(end 472.141042 -58.9661)
				)
				(arc
					(start 472.141042 -60.6171)
					(mid 474.198442 -62.6745)
					(end 476.255842 -60.6171)
				)
			)
		)
	)
	(zone
		(layers "In2.Cu" "In4.Cu" "In9.Cu" "In11.Cu")
		(hatch none 0.5)
		(connect_pads
			(clearance 0)
		)
		(min_thickness 0.25)
		(keepout
			(tracks not_allowed)
			(vias allowed)
			(pads allowed)
			(copperpour not_allowed)
			(footprints allowed)
		)
		(placement
			(enabled no)
			(sheetname "")
		)
		(fill yes
			(thermal_gap 0.5)
			(thermal_bridge_width 0.5)
			(island_removal_mode 0)
		)
		(polygon
			(pts
				(arc
					(start 433.7558 -58.9661)
					(mid 431.6984 -56.9087)
					(end 429.641 -58.9661)
				)
				(arc
					(start 429.641 -60.6171)
					(mid 431.6984 -62.6745)
					(end 433.7558 -60.6171)
				)
			)
		)
	)
	(zone
		(layers "In2.Cu" "In4.Cu" "In9.Cu" "In11.Cu")
		(hatch none 0.5)
		(connect_pads
			(clearance 0)
		)
		(min_thickness 0.25)
		(keepout
			(tracks not_allowed)
			(vias allowed)
			(pads allowed)
			(copperpour not_allowed)
			(footprints allowed)
		)
		(placement
			(enabled no)
			(sheetname "")
		)
		(fill yes
			(thermal_gap 0.5)
			(thermal_bridge_width 0.5)
			(island_removal_mode 0)
		)
		(polygon
			(pts
				(arc
					(start 467.345522 -32.577532)
					(mid 469.402922 -30.520132)
					(end 467.345522 -28.462732)
				)
				(arc
					(start 465.694522 -28.462732)
					(mid 463.637122 -30.520132)
					(end 465.694522 -32.577532)
				)
			)
		)
	)
	(zone
		(layers "In2.Cu" "In4.Cu" "In9.Cu" "In11.Cu")
		(hatch none 0.5)
		(connect_pads
			(clearance 0)
		)
		(min_thickness 0.25)
		(keepout
			(tracks not_allowed)
			(vias allowed)
			(pads allowed)
			(copperpour not_allowed)
			(footprints allowed)
		)
		(placement
			(enabled no)
			(sheetname "")
		)
		(fill yes
			(thermal_gap 0.5)
			(thermal_bridge_width 0.5)
			(island_removal_mode 0)
		)
		(polygon
			(pts
				(arc
					(start 497.345716 -32.577532)
					(mid 499.403116 -30.520132)
					(end 497.345716 -28.462732)
				)
				(arc
					(start 495.694716 -28.462732)
					(mid 493.637316 -30.520132)
					(end 495.694716 -32.577532)
				)
			)
		)
	)
	(zone
		(layers "In2.Cu" "In4.Cu" "In9.Cu" "In11.Cu")
		(hatch none 0.5)
		(connect_pads
			(clearance 0)
		)
		(min_thickness 0.25)
		(keepout
			(tracks not_allowed)
			(vias allowed)
			(pads allowed)
			(copperpour not_allowed)
			(footprints allowed)
		)
		(placement
			(enabled no)
			(sheetname "")
		)
		(fill yes
			(thermal_gap 0.5)
			(thermal_bridge_width 0.5)
			(island_removal_mode 0)
		)
		(polygon
			(pts
				(arc
					(start 328.666348 -22.524212)
					(mid 325.334376 -22.524212)
					(end 328.666348 -22.524212)
				)
			)
		)
	)
	(zone
		(layers "In2.Cu" "In4.Cu" "In9.Cu" "In11.Cu")
		(hatch none 0.5)
		(connect_pads
			(clearance 0)
		)
		(min_thickness 0.25)
		(keepout
			(tracks not_allowed)
			(vias allowed)
			(pads allowed)
			(copperpour not_allowed)
			(footprints allowed)
		)
		(placement
			(enabled no)
			(sheetname "")
		)
		(fill yes
			(thermal_gap 0.5)
			(thermal_bridge_width 0.5)
			(island_removal_mode 0)
		)
		(polygon
			(pts
				(arc
					(start 25.715468 -135.37057)
					(mid 22.383496 -135.37057)
					(end 25.715468 -135.37057)
				)
			)
		)
	)
	(zone
		(layers "In2.Cu" "In4.Cu" "In9.Cu" "In11.Cu")
		(hatch none 0.5)
		(connect_pads
			(clearance 0)
		)
		(min_thickness 0.25)
		(keepout
			(tracks not_allowed)
			(vias allowed)
			(pads allowed)
			(copperpour not_allowed)
			(footprints allowed)
		)
		(placement
			(enabled no)
			(sheetname "")
		)
		(fill yes
			(thermal_gap 0.5)
			(thermal_bridge_width 0.5)
			(island_removal_mode 0)
		)
		(polygon
			(pts
				(arc
					(start 328.666348 -3.321812)
					(mid 325.334376 -3.321812)
					(end 328.666348 -3.321812)
				)
			)
		)
	)
	(zone
		(layers "In2.Cu" "In11.Cu")
		(hatch none 0.5)
		(connect_pads
			(clearance 0)
		)
		(min_thickness 0.25)
		(keepout
			(tracks not_allowed)
			(vias allowed)
			(pads allowed)
			(copperpour not_allowed)
			(footprints allowed)
		)
		(placement
			(enabled no)
			(sheetname "")
		)
		(fill yes
			(thermal_gap 0.5)
			(thermal_bridge_width 0.5)
			(island_removal_mode 0)
		)
		(polygon
			(pts
				(arc
					(start 435.069996 -144.239996)
					(mid 431.46218 -144.239996)
					(end 435.069996 -144.239996)
				)
			)
		)
	)
	(zone
		(net "PVDDQ_ABC")
		(layer "In3.Cu")
		(hatch none 0.5)
		(connect_pads
			(clearance 0.5)
		)
		(min_thickness 0.25)
		(fill yes
			(thermal_gap 0.5)
			(thermal_bridge_width 0.5)
			(island_removal_mode 0)
		)
		(polygon
			(pts
				(arc
					(start 337.3882 -12.699492)
					(mid 337.460042 -12.669734)
					(end 337.4898 -12.597892)
				)
				(xy 337.4898 3.5052) (xy 336.296 4.699) (xy 332.486 4.699) (xy 331.22108 3.43408) (xy 326.1868 3.43408)
				(xy 324.995286 2.242566) (xy 323.842634 2.242566) (xy 323.6595 2.4257) (xy 322.9102 3.175)
				(arc
					(start 261.920736 3.175)
					(mid 261.828009 3.114925)
					(end 261.845044 3.005836)
				)
				(arc
					(start 261.845044 3.005836)
					(mid 261.820194 2.506173)
					(end 261.32028 2.524252)
				)
				(arc
					(start 261.32028 2.524252)
					(mid 261.245555 2.556096)
					(end 261.171436 2.522982)
				)
				(arc
					(start 261.171436 2.522982)
					(mid 260.904391 2.407407)
					(end 260.640322 2.529586)
				)
				(arc
					(start 260.640322 2.529586)
					(mid 260.564426 2.564586)
					(end 260.487922 2.530856)
				)
				(arc
					(start 260.487922 2.530856)
					(mid 259.985586 2.503382)
					(end 259.957316 3.005836)
				)
				(arc
					(start 259.957316 3.005836)
					(mid 259.974223 3.114868)
					(end 259.881624 3.175)
				)
				(xy 242.664996 3.175) (xy 242.664996 2.104644)
				(arc
					(start 242.667028 2.097786)
					(mid 242.681368 1.994154)
					(end 242.667028 1.890522)
				)
				(xy 242.664996 1.883664) (xy 242.664996 1.05029)
				(arc
					(start 242.667028 1.043432)
					(mid 242.681368 0.9398)
					(end 242.667028 0.836168)
				)
				(xy 242.664996 0.82931) (xy 242.664996 -7.496556)
				(arc
					(start 242.667028 -7.503414)
					(mid 242.681368 -7.607046)
					(end 242.667028 -7.710678)
				)
				(xy 242.664996 -7.717536) (xy 242.664996 -8.55091)
				(arc
					(start 242.667028 -8.557768)
					(mid 242.681368 -8.6614)
					(end 242.667028 -8.765032)
				)
				(xy 242.664996 -8.77189) (xy 242.664996 -12.567666)
				(arc
					(start 242.667028 -12.574524)
					(mid 242.681368 -12.678156)
					(end 242.667028 -12.781788)
				)
				(xy 242.664996 -12.788646) (xy 242.664996 -13.253466)
				(arc
					(start 242.667028 -13.260324)
					(mid 242.681368 -13.363956)
					(end 242.667028 -13.467588)
				)
				(xy 242.664996 -13.474446) (xy 242.664996 -17.097756)
				(arc
					(start 242.667028 -17.104614)
					(mid 242.681368 -17.208246)
					(end 242.667028 -17.311878)
				)
				(xy 242.664996 -17.318736) (xy 242.664996 -17.3863)
				(arc
					(start 242.912646 -17.3863)
					(mid 243.262512 -16.881631)
					(end 243.45773 -17.46377)
				)
				(arc
					(start 243.45773 -17.46377)
					(mid 243.428282 -17.539259)
					(end 243.463318 -17.61236)
				)
				(arc
					(start 243.463318 -17.61236)
					(mid 243.582054 -17.937102)
					(end 243.369084 -18.209514)
				)
				(arc
					(start 243.369084 -18.48231)
					(mid 243.480834 -18.799234)
					(end 243.279168 -19.068034)
				)
				(xy 243.249958 -19.08175)
				(arc
					(start 243.249958 -21.79193)
					(mid 243.26369 -21.826667)
					(end 243.297456 -21.84273)
				)
				(arc
					(start 243.297456 -21.84273)
					(mid 243.630677 -22.198076)
					(end 243.297456 -22.553422)
				)
				(arc
					(start 243.297456 -22.553422)
					(mid 243.263612 -22.569412)
					(end 243.249958 -22.604222)
				)
				(xy 243.249958 -23.19147)
				(arc
					(start 243.281962 -23.20417)
					(mid 243.50599 -23.534878)
					(end 243.281962 -23.865586)
				)
				(xy 243.249958 -23.878286) (xy 243.249958 -25.070562) (xy 244.6909 -26.511504) (xy 244.6909 -29.4259)
				(xy 249.936 -34.671)
				(arc
					(start 249.936 -40.3352)
					(mid 250.285655 -41.550082)
					(end 249.936 -42.764964)
				)
				(xy 249.936 -49.6062) (xy 250.2027 -49.8729) (xy 250.2027 -50.292) (xy 250.2916 -50.3809) (xy 250.2916 -50.7746)
				(xy 250.2027 -50.8635) (xy 250.2027 -51.259994) (xy 250.180094 -51.2826) (xy 250.180094 -54.356)
				(xy 249.9868 -54.549294)
				(arc
					(start 249.9868 -54.652672)
					(mid 250.026482 -54.733225)
					(end 250.114562 -54.75097)
				)
				(arc
					(start 250.114562 -54.75097)
					(mid 250.56013 -55.051158)
					(end 250.201176 -55.450994)
				)
				(arc
					(start 250.201176 -55.450994)
					(mid 250.105826 -55.51297)
					(end 250.12777 -55.624476)
				)
				(xy 250.180094 -55.6768)
				(arc
					(start 250.180094 -55.67934)
					(mid 250.193908 -55.714163)
					(end 250.227846 -55.729886)
				)
				(arc
					(start 250.227846 -55.729886)
					(mid 250.562988 -56.085486)
					(end 250.227846 -56.441086)
				)
				(arc
					(start 250.227846 -56.441086)
					(mid 250.194026 -56.45692)
					(end 250.180094 -56.491632)
				)
				(arc
					(start 250.180094 -56.66994)
					(mid 250.193908 -56.704763)
					(end 250.227846 -56.720486)
				)
				(arc
					(start 250.227846 -56.720486)
					(mid 250.473292 -56.839741)
					(end 250.56211 -57.097676)
				)
				(xy 250.56084 -57.120536) (xy 251.12091 -57.680606) (xy 251.12091 -58.208418)
				(arc
					(start 251.158502 -58.218578)
					(mid 251.419539 -58.526231)
					(end 251.225812 -58.880248)
				)
				(xy 251.197872 -58.894218) (xy 251.197872 -59.220862)
				(arc
					(start 251.225812 -59.234832)
					(mid 251.421512 -59.55284)
					(end 251.225812 -59.870848)
				)
				(xy 251.197872 -59.884818) (xy 251.197872 -60.211462)
				(arc
					(start 251.225812 -60.225432)
					(mid 251.421512 -60.54344)
					(end 251.225812 -60.861448)
				)
				(xy 251.197872 -60.875418) (xy 251.197872 -61.202062)
				(arc
					(start 251.225812 -61.216032)
					(mid 251.421512 -61.53404)
					(end 251.225812 -61.852048)
				)
				(xy 251.197872 -61.866018) (xy 251.197872 -62.120272) (xy 251.5362 -62.4586) (xy 252.43028 -62.4586)
				(arc
					(start 252.441202 -62.422278)
					(mid 252.782324 -62.168491)
					(end 253.123446 -62.422278)
				)
				(xy 253.134368 -62.4586) (xy 254.147066 -62.4586)
				(arc
					(start 254.157988 -62.422278)
					(mid 254.49911 -62.168491)
					(end 254.840232 -62.422278)
				)
				(xy 254.851154 -62.4586) (xy 255.864106 -62.4586)
				(arc
					(start 255.875028 -62.422278)
					(mid 256.21615 -62.168491)
					(end 256.557272 -62.422278)
				)
				(xy 256.568194 -62.4586) (xy 257.581146 -62.4586)
				(arc
					(start 257.592068 -62.422278)
					(mid 257.93319 -62.168491)
					(end 258.274312 -62.422278)
				)
				(xy 258.285234 -62.4586) (xy 258.7117 -62.4586) (xy 258.957572 -62.704472)
				(arc
					(start 258.963922 -62.708028)
					(mid 259.043491 -62.767905)
					(end 259.103368 -62.847474)
				)
				(xy 259.106924 -62.853824) (xy 259.463286 -63.210186)
				(arc
					(start 259.495544 -63.194438)
					(mid 259.902065 -63.263405)
					(end 259.971032 -63.669926)
				)
				(xy 259.955284 -63.702184)
				(arc
					(start 260.066536 -63.813436)
					(mid 260.146256 -63.842708)
					(end 260.22046 -63.801244)
				)
				(arc
					(start 260.22046 -63.801244)
					(mid 260.760553 -63.758483)
					(end 260.717792 -64.298576)
				)
				(arc
					(start 260.717792 -64.298576)
					(mid 260.676142 -64.372765)
					(end 260.7056 -64.4525)
				)
				(arc
					(start 261.410958 -65.157858)
					(mid 261.517587 -65.18151)
					(end 261.583932 -65.094866)
				)
				(arc
					(start 261.583932 -65.094866)
					(mid 262.190618 -64.873752)
					(end 261.969504 -65.480438)
				)
				(arc
					(start 261.969504 -65.480438)
					(mid 261.883024 -65.546842)
					(end 261.906512 -65.653412)
				)
				(xy 263.927082 -67.673982) (xy 266.77874 -67.673982) (xy 266.781788 -67.671188) (xy 271.266412 -67.671188)
				(xy 273.534632 -67.671188) (xy 273.71675 -67.48907) (xy 273.71675 -67.2846) (xy 269.588996 -63.156846)
				(xy 269.588996 -61.69406) (xy 269.588996 -61.533786) (xy 269.588996 -61.387482) (xy 269.588996 -61.19241)
				(xy 269.588996 -60.994798) (xy 269.588996 -57.404) (xy 269.24 -57.055004) (xy 269.24 -51.910996)
				(xy 269.588996 -51.562) (xy 269.588996 -50.028348) (xy 270.241522 -49.375822) (xy 270.241522 -33.618678)
				(xy 278.90597 -24.95423) (xy 278.90597 -23.187406)
				(arc
					(start 278.869394 -23.176738)
					(mid 278.612081 -22.8346)
					(end 278.869394 -22.492462)
				)
				(xy 278.90597 -22.481794) (xy 278.90597 -22.021292)
				(arc
					(start 278.8666 -22.012148)
					(mid 278.59113 -21.665184)
					(end 278.8666 -21.31822)
				)
				(xy 278.90597 -21.309076) (xy 278.90597 -19.047968)
				(arc
					(start 278.866346 -19.039078)
					(mid 278.598859 -18.777255)
					(end 278.713184 -18.420842)
				)
				(arc
					(start 278.713184 -18.420842)
					(mid 278.74854 -18.345682)
					(end 278.715978 -18.269204)
				)
				(arc
					(start 278.715978 -18.269204)
					(mid 278.601689 -17.997044)
					(end 278.73198 -17.732248)
				)
				(arc
					(start 278.73198 -17.732248)
					(mid 278.769059 -17.65287)
					(end 278.73071 -17.574006)
				)
				(arc
					(start 278.73071 -17.574006)
					(mid 278.603854 -17.218933)
					(end 278.867108 -16.948912)
				)
				(xy 278.90597 -16.939514) (xy 278.90597 -15.262352) (xy 279.182322 -14.986) (xy 334.42783 -14.986)
				(xy 334.703928 -14.709902) (xy 335.143856 -14.709902) (xy 335.419954 -14.986) (xy 336.296 -14.986)
				(xy 336.985356 -14.296644)
				(arc
					(start 336.969354 -14.264132)
					(mid 337.005224 -13.869339)
					(end 337.372198 -13.719556)
				)
				(arc
					(start 337.372198 -13.719556)
					(mid 337.454141 -13.696517)
					(end 337.4898 -13.619226)
				)
				(arc
					(start 337.4898 -13.564108)
					(mid 337.460042 -13.492266)
					(end 337.3882 -13.462508)
				)
				(arc
					(start 337.3882 -13.462508)
					(mid 337.154865 -13.3829)
					(end 337.018884 -13.177266)
				)
				(arc
					(start 337.018884 -13.177266)
					(mid 336.951526 -13.105969)
					(end 336.855308 -13.124942)
				)
				(arc
					(start 336.855308 -13.124942)
					(mid 336.285182 -12.750046)
					(end 336.967576 -12.751054)
				)
				(arc
					(start 336.967576 -12.751054)
					(mid 337.037424 -12.81982)
					(end 337.13293 -12.797536)
				)
				(arc
					(start 337.13293 -12.797536)
					(mid 337.251471 -12.724831)
					(end 337.3882 -12.699492)
				)
			)
		)
	)
	(zone
		(net "PVDDQ_GHJ")
		(layer "In3.Cu")
		(hatch none 0.5)
		(connect_pads
			(clearance 0.5)
		)
		(min_thickness 0.25)
		(fill yes
			(thermal_gap 0.5)
			(thermal_bridge_width 0.5)
			(island_removal_mode 0)
		)
		(polygon
			(pts
				(xy 26.5557 3.175) (xy 25.4635 2.0828)
				(arc
					(start 25.475946 2.051558)
					(mid 25.136419 0.391851)
					(end 23.476712 0.052324)
				)
				(xy 23.44547 0.06477) (xy 15.10792 -8.27278) (xy 15.10792 -19.931888) (xy 15.69466 -20.518628) (xy 28.375102 -20.518628)
				(xy 30.507432 -18.386298) (xy 30.507432 -17.47012) (xy 31.043372 -16.93418) (xy 31.043372 -16.845788)
				(xy 31.043372 -16.669766)
				(arc
					(start 31.04515 -16.651732)
					(mid 31.147654 -16.43572)
					(end 31.363666 -16.333216)
				)
				(xy 31.3817 -16.331438) (xy 31.534862 -16.178276) (xy 76.745084 -16.178276) (xy 76.762356 -16.195548)
				(xy 77.121004 -16.195548) (xy 77.93736 -17.011904)
				(arc
					(start 77.973174 -16.976598)
					(mid 78.458886 -16.980727)
					(end 78.454504 -17.46631)
				)
				(xy 78.454504 -17.466564) (xy 78.418436 -17.502632) (xy 78.55839 -17.642586) (xy 78.55839 -17.743678)
				(arc
					(start 78.561946 -17.752568)
					(mid 78.58614 -17.8816)
					(end 78.561946 -18.010632)
				)
				(xy 78.55839 -18.019522) (xy 78.55839 -19.355054) (xy 78.261718 -19.651726) (xy 78.261718 -21.726906)
				(xy 78.197456 -21.791168) (xy 78.24851 -21.842222)
				(arc
					(start 78.269846 -21.841968)
					(mid 78.629788 -22.179012)
					(end 78.307946 -22.55266)
				)
				(arc
					(start 78.307946 -22.55266)
					(mid 78.222003 -22.619482)
					(end 78.24597 -22.725634)
				)
				(xy 78.261718 -22.741382) (xy 78.261718 -23.19528)
				(arc
					(start 78.292198 -23.208742)
					(mid 78.505458 -23.534878)
					(end 78.292198 -23.861014)
				)
				(xy 78.261718 -23.874476) (xy 78.261718 -25.082754) (xy 79.690468 -26.511504) (xy 79.690468 -29.4259)
				(xy 84.582 -34.317432)
				(arc
					(start 84.582 -39.90086)
					(mid 85.270702 -41.292513)
					(end 84.911184 -42.803064)
				)
				(xy 84.888578 -42.837608) (xy 85.113368 -43.062398) (xy 85.113368 -43.986704) (xy 85.103462 -43.99661)
				(arc
					(start 85.103462 -50.268632)
					(mid 85.174831 -50.32526)
					(end 85.229446 -50.398172)
				)
				(xy 85.232748 -50.404268) (xy 85.465158 -50.636678)
				(arc
					(start 85.465158 -54.850284)
					(mid 85.562451 -55.094886)
					(end 85.465158 -55.339488)
				)
				(arc
					(start 85.465158 -55.840884)
					(mid 85.562451 -56.085486)
					(end 85.465158 -56.330088)
				)
				(arc
					(start 85.465158 -56.831484)
					(mid 85.537282 -56.944583)
					(end 85.56244 -57.07634)
				)
				(xy 85.56244 -57.097422) (xy 86.127844 -57.662826) (xy 86.127844 -58.209688)
				(arc
					(start 86.16442 -58.220356)
					(mid 86.416306 -58.50498)
					(end 86.267798 -58.854848)
				)
				(arc
					(start 86.267798 -59.260232)
					(mid 86.418682 -59.512703)
					(end 86.32825 -59.792616)
				)
				(arc
					(start 86.32825 -60.303664)
					(mid 86.421042 -60.54344)
					(end 86.32825 -60.783216)
				)
				(xy 86.32825 -61.120782) (xy 86.327488 -61.121544)
				(arc
					(start 86.327488 -61.293502)
					(mid 86.420993 -61.53404)
					(end 86.327488 -61.774578)
				)
				(xy 86.327488 -62.25032) (xy 86.535768 -62.4586) (xy 87.429848 -62.4586)
				(arc
					(start 87.44077 -62.422278)
					(mid 87.781892 -62.168491)
					(end 88.123014 -62.422278)
				)
				(xy 88.133936 -62.4586) (xy 89.146634 -62.4586)
				(arc
					(start 89.157556 -62.422278)
					(mid 89.498678 -62.168491)
					(end 89.8398 -62.422278)
				)
				(xy 89.850722 -62.4586) (xy 90.863674 -62.4586)
				(arc
					(start 90.874596 -62.422278)
					(mid 91.215718 -62.168491)
					(end 91.55684 -62.422278)
				)
				(xy 91.567762 -62.4586) (xy 92.580714 -62.4586)
				(arc
					(start 92.591636 -62.422278)
					(mid 92.932758 -62.168491)
					(end 93.27388 -62.422278)
				)
				(xy 93.284802 -62.4586) (xy 93.711268 -62.4586) (xy 93.95714 -62.704472)
				(arc
					(start 93.96349 -62.708028)
					(mid 94.043059 -62.767905)
					(end 94.102936 -62.847474)
				)
				(xy 94.106492 -62.853824) (xy 94.350078 -63.09741)
				(arc
					(start 94.350078 -63.102744)
					(mid 94.397649 -63.188533)
					(end 94.49562 -63.194184)
				)
				(arc
					(start 94.49562 -63.194184)
					(mid 94.975212 -63.369117)
					(end 94.787212 -63.843662)
				)
				(arc
					(start 94.787212 -63.843662)
					(mid 94.726827 -63.917803)
					(end 94.7547 -64.00927)
				)
				(xy 94.771972 -64.026542) (xy 95.149416 -64.026542)
				(arc
					(start 95.15348 -63.98006)
					(mid 95.683472 -63.700214)
					(end 95.71736 -64.298576)
				)
				(arc
					(start 95.71736 -64.298576)
					(mid 95.67571 -64.372765)
					(end 95.705168 -64.4525)
				)
				(arc
					(start 96.410526 -65.157858)
					(mid 96.517155 -65.18151)
					(end 96.5835 -65.094866)
				)
				(arc
					(start 96.5835 -65.094866)
					(mid 97.190186 -64.873752)
					(end 96.969072 -65.480438)
				)
				(arc
					(start 96.969072 -65.480438)
					(mid 96.882592 -65.546842)
					(end 96.90608 -65.653412)
				)
				(xy 98.92665 -67.673982) (xy 101.778308 -67.673982) (xy 101.782372 -67.670172) (xy 106.142028 -67.670172)
				(xy 108.45927 -67.670172) (xy 108.655866 -67.473576) (xy 108.655866 -66.9544) (xy 108.427266 -66.7258)
				(xy 107.569 -66.7258) (xy 107.4928 -66.6496) (xy 107.4928 -65.650872) (xy 107.3404 -65.498472) (xy 106.182668 -65.498472)
				(xy 104.064054 -63.379858) (xy 104.064054 -62.817756) (xy 104.064054 -61.613034) (xy 104.064054 -61.539374)
				(xy 104.064054 -61.42482) (xy 104.064054 -50.552858) (xy 105.24109 -49.375822) (xy 105.24109 -33.618678)
				(xy 113.88344 -24.976328) (xy 113.88344 -23.182326)
				(arc
					(start 113.849404 -23.170388)
					(mid 113.611729 -22.8346)
					(end 113.849404 -22.498812)
				)
				(xy 113.88344 -22.486874) (xy 113.88344 -22.017736)
				(arc
					(start 113.846864 -22.007068)
					(mid 113.59071 -21.665184)
					(end 113.846864 -21.3233)
				)
				(xy 113.88344 -21.312632) (xy 113.88344 -19.044666)
				(arc
					(start 113.84661 -19.033998)
					(mid 113.596316 -18.767498)
					(end 113.712752 -18.420842)
				)
				(arc
					(start 113.712752 -18.420842)
					(mid 113.748108 -18.345682)
					(end 113.715546 -18.269204)
				)
				(arc
					(start 113.715546 -18.269204)
					(mid 113.601257 -17.997044)
					(end 113.731548 -17.732248)
				)
				(arc
					(start 113.731548 -17.732248)
					(mid 113.768627 -17.65287)
					(end 113.730278 -17.574006)
				)
				(arc
					(start 113.730278 -17.574006)
					(mid 113.601425 -17.228744)
					(end 113.847372 -16.954246)
				)
				(xy 113.88344 -16.943324) (xy 113.88344 -16.67129) (xy 113.865406 -16.653256)
				(arc
					(start 113.865406 -14.251178)
					(mid 113.682995 -13.940282)
					(end 113.865406 -13.629386)
				)
				(xy 113.865406 -13.308584)
				(arc
					(start 113.827306 -13.298678)
					(mid 113.560819 -12.954)
					(end 113.827306 -12.609322)
				)
				(xy 113.865406 -12.599416) (xy 113.865406 -12.285218)
				(arc
					(start 113.828068 -12.274804)
					(mid 113.56719 -11.93165)
					(end 113.828068 -11.588496)
				)
				(xy 113.865406 -11.578082) (xy 113.865406 -9.440418)
				(arc
					(start 113.82502 -9.432036)
					(mid 113.541032 -9.083294)
					(end 113.82502 -8.734552)
				)
				(xy 113.865406 -8.72617) (xy 113.865406 -8.461502)
				(arc
					(start 113.820956 -8.455914)
					(mid 113.517538 -8.029581)
					(end 113.966498 -7.76097)
				)
				(xy 113.995454 -7.769352) (xy 114.0968 -7.668006)
				(arc
					(start 114.0968 -7.571232)
					(mid 114.054541 -7.488763)
					(end 113.962942 -7.474966)
				)
				(arc
					(start 113.962942 -7.474966)
					(mid 113.493256 -7.1374)
					(end 113.962942 -6.799834)
				)
				(arc
					(start 113.962942 -6.799834)
					(mid 114.054499 -6.785978)
					(end 114.0968 -6.703568)
				)
				(xy 114.0968 -6.606794) (xy 113.865406 -6.3754)
				(arc
					(start 113.865406 -4.639564)
					(mid 113.662391 -4.318)
					(end 113.865406 -3.996436)
				)
				(xy 113.865406 -3.838702)
				(arc
					(start 113.820956 -3.833114)
					(mid 113.529346 -3.595671)
					(end 113.613184 -3.229102)
				)
				(arc
					(start 113.613184 -3.229102)
					(mid 113.642491 -3.155036)
					(end 113.609374 -3.082544)
				)
				(arc
					(start 113.609374 -3.082544)
					(mid 113.512093 -2.705029)
					(end 113.818924 -2.464562)
				)
				(arc
					(start 113.818924 -2.464562)
					(mid 113.851973 -2.448327)
					(end 113.865406 -2.414016)
				)
				(arc
					(start 113.865406 1.367536)
					(mid 113.832717 1.442195)
					(end 113.755678 1.468882)
				)
				(arc
					(start 113.755678 1.468882)
					(mid 113.370979 1.82372)
					(end 113.755678 2.178558)
				)
				(arc
					(start 113.755678 2.178558)
					(mid 113.832765 2.205193)
					(end 113.865406 2.279904)
				)
				(xy 113.865406 2.925318) (xy 113.615724 3.175)
				(arc
					(start 96.920304 3.175)
					(mid 96.827577 3.114925)
					(end 96.844612 3.005836)
				)
				(arc
					(start 96.844612 3.005836)
					(mid 96.819762 2.506173)
					(end 96.319848 2.524252)
				)
				(arc
					(start 96.319848 2.524252)
					(mid 96.245123 2.556096)
					(end 96.171004 2.522982)
				)
				(arc
					(start 96.171004 2.522982)
					(mid 95.903959 2.407407)
					(end 95.63989 2.529586)
				)
				(arc
					(start 95.63989 2.529586)
					(mid 95.563994 2.564586)
					(end 95.48749 2.530856)
				)
				(arc
					(start 95.48749 2.530856)
					(mid 94.985154 2.503382)
					(end 94.956884 3.005836)
				)
				(arc
					(start 94.956884 3.005836)
					(mid 94.973791 3.114868)
					(end 94.881192 3.175)
				)
			)
		)
	)
	(zone
		(net "PVDDQ_DEF")
		(layer "In3.Cu")
		(hatch none 0.5)
		(connect_pads
			(clearance 0.5)
		)
		(min_thickness 0.25)
		(fill yes
			(thermal_gap 0.5)
			(thermal_bridge_width 0.5)
			(island_removal_mode 0)
		)
		(polygon
			(pts
				(arc
					(start 252.240796 -88.937592)
					(mid 252.095389 -89.087353)
					(end 251.891038 -89.12987)
				)
				(xy 251.867416 -89.127584) (xy 251.149104 -89.845896) (xy 251.149104 -89.91346)
				(arc
					(start 251.18314 -89.925398)
					(mid 251.421394 -90.26144)
					(end 251.18314 -90.597482)
				)
				(xy 251.149104 -90.60942) (xy 251.149104 -90.90406)
				(arc
					(start 251.18314 -90.915998)
					(mid 251.421394 -91.25204)
					(end 251.18314 -91.588082)
				)
				(xy 251.149104 -91.60002) (xy 251.149104 -91.89466)
				(arc
					(start 251.18314 -91.906598)
					(mid 251.421394 -92.24264)
					(end 251.18314 -92.578682)
				)
				(xy 251.149104 -92.59062) (xy 251.149104 -93.005656) (xy 251.05106 -93.1037) (xy 251.05106 -93.36278)
				(xy 251.149104 -93.460824) (xy 251.149104 -93.875606)
				(arc
					(start 251.18314 -93.887544)
					(mid 251.417851 -94.273696)
					(end 251.084842 -94.579186)
				)
				(xy 251.065538 -94.580202)
				(arc
					(start 250.95962 -94.68612)
					(mid 250.939056 -94.800285)
					(end 251.038868 -94.859348)
				)
				(arc
					(start 251.038868 -94.859348)
					(mid 251.394702 -95.349615)
					(end 250.79706 -95.448628)
				)
				(arc
					(start 250.79706 -95.448628)
					(mid 250.684811 -95.420422)
					(end 250.619006 -95.515684)
				)
				(arc
					(start 250.619006 -95.903796)
					(mid 250.684785 -95.999126)
					(end 250.79706 -95.970852)
				)
				(arc
					(start 250.79706 -95.970852)
					(mid 251.421357 -96.20504)
					(end 250.79706 -96.439228)
				)
				(arc
					(start 250.79706 -96.439228)
					(mid 250.684811 -96.411022)
					(end 250.619006 -96.506284)
				)
				(xy 250.619006 -98.023172) (xy 250.317 -98.325178) (xy 250.317 -108.220002) (xy 250.007628 -108.529628)
				(xy 249.9868 -108.550456)
				(arc
					(start 249.9868 -110.417864)
					(mid 250.28673 -111.549942)
					(end 249.9868 -112.68202)
				)
				(xy 249.9868 -120.484392) (xy 243.6749 -126.796292)
				(arc
					(start 243.6749 -129.169414)
					(mid 243.725082 -129.257043)
					(end 243.82603 -129.25806)
				)
				(arc
					(start 243.82603 -129.25806)
					(mid 244.355913 -129.568956)
					(end 243.82603 -129.879852)
				)
				(arc
					(start 243.82603 -129.879852)
					(mid 243.72511 -129.880917)
					(end 243.6749 -129.968498)
				)
				(arc
					(start 243.6749 -136.002268)
					(mid 243.725928 -136.090134)
					(end 243.827554 -136.089898)
				)
				(arc
					(start 243.827554 -136.089898)
					(mid 244.343238 -136.387078)
					(end 243.827554 -136.684258)
				)
				(arc
					(start 243.827554 -136.684258)
					(mid 243.725909 -136.68399)
					(end 243.6749 -136.771888)
				)
				(arc
					(start 243.6749 -138.785346)
					(mid 243.725928 -138.873212)
					(end 243.827554 -138.872976)
				)
				(arc
					(start 243.827554 -138.872976)
					(mid 244.343238 -139.170156)
					(end 243.827554 -139.467336)
				)
				(arc
					(start 243.827554 -139.467336)
					(mid 243.725909 -139.467068)
					(end 243.6749 -139.554966)
				)
				(arc
					(start 243.6749 -145.603468)
					(mid 243.725928 -145.691334)
					(end 243.827554 -145.691098)
				)
				(arc
					(start 243.827554 -145.691098)
					(mid 244.334533 -146.065115)
					(end 243.715286 -146.180556)
				)
				(arc
					(start 243.715286 -146.180556)
					(mid 243.640865 -146.136395)
					(end 243.55933 -146.16557)
				)
				(xy 242.824 -146.9009)
				(arc
					(start 242.824 -149.065996)
					(mid 242.879346 -149.156457)
					(end 242.985036 -149.148292)
				)
				(arc
					(start 242.985036 -149.148292)
					(mid 243.468665 -149.20984)
					(end 243.437664 -149.696424)
				)
				(arc
					(start 243.437664 -149.696424)
					(mid 243.405752 -149.772047)
					(end 243.440204 -149.846538)
				)
				(arc
					(start 243.440204 -149.846538)
					(mid 243.56079 -150.130442)
					(end 243.41455 -150.402036)
				)
				(arc
					(start 243.41455 -150.402036)
					(mid 243.373042 -150.474612)
					(end 243.400072 -150.553674)
				)
				(arc
					(start 243.400072 -150.553674)
					(mid 243.418597 -151.002672)
					(end 242.976908 -151.08555)
				)
				(arc
					(start 242.976908 -151.08555)
					(mid 242.875095 -151.085085)
					(end 242.824 -151.17318)
				)
				(arc
					(start 242.824 -153.935176)
					(mid 242.890234 -154.030422)
					(end 243.002562 -154.00147)
				)
				(arc
					(start 243.002562 -154.00147)
					(mid 243.62837 -154.23388)
					(end 243.002562 -154.46629)
				)
				(arc
					(start 243.002562 -154.46629)
					(mid 242.890242 -154.437359)
					(end 242.824 -154.532584)
				)
				(xy 242.824 -154.727148) (xy 243.091208 -154.994356)
				(arc
					(start 243.115084 -154.99207)
					(mid 243.418344 -155.112544)
					(end 243.496084 -155.429458)
				)
				(xy 243.506244 -155.453334) (xy 243.510054 -155.463494) (xy 243.859558 -155.812998)
				(arc
					(start 247.816624 -155.812998)
					(mid 247.899233 -155.770544)
					(end 247.91289 -155.678632)
				)
				(arc
					(start 247.91289 -155.678632)
					(mid 248.249948 -155.208085)
					(end 248.587006 -155.678632)
				)
				(arc
					(start 248.587006 -155.678632)
					(mid 248.60059 -155.770596)
					(end 248.683272 -155.812998)
				)
				(arc
					(start 249.516646 -155.812998)
					(mid 249.599255 -155.770544)
					(end 249.612912 -155.678632)
				)
				(arc
					(start 249.612912 -155.678632)
					(mid 249.94997 -155.208085)
					(end 250.287028 -155.678632)
				)
				(arc
					(start 250.287028 -155.678632)
					(mid 250.300612 -155.770596)
					(end 250.383294 -155.812998)
				)
				(arc
					(start 252.926088 -155.812998)
					(mid 253.010391 -155.768104)
					(end 253.020322 -155.673044)
				)
				(arc
					(start 253.020322 -155.673044)
					(mid 253.350014 -155.182657)
					(end 253.679706 -155.673044)
				)
				(arc
					(start 253.679706 -155.673044)
					(mid 253.689521 -155.768182)
					(end 253.77394 -155.812998)
				)
				(arc
					(start 254.625856 -155.812998)
					(mid 254.710186 -155.768064)
					(end 254.719836 -155.673044)
				)
				(arc
					(start 254.719836 -155.673044)
					(mid 255.049782 -155.182771)
					(end 255.379728 -155.673044)
				)
				(arc
					(start 255.379728 -155.673044)
					(mid 255.389457 -155.768011)
					(end 255.473708 -155.812998)
				)
				(xy 255.900174 -155.812998) (xy 257.033776 -156.9466) (xy 260.35 -156.9466) (xy 261.258812 -156.037788)
				(arc
					(start 261.243064 -156.005276)
					(mid 261.311533 -155.597749)
					(end 261.71906 -155.52928)
				)
				(xy 261.751572 -155.545028) (xy 262.685276 -154.611324)
				(arc
					(start 262.685276 -153.956512)
					(mid 263.59993 -153.041858)
					(end 264.514584 -153.956512)
				)
				(xy 264.514584 -155.201112) (xy 264.514584 -155.497784) (xy 264.80135 -155.78455) (xy 264.911586 -155.78455)
				(xy 264.911586 -155.72613)
				(arc
					(start 264.9093 -155.719018)
					(mid 265.223732 -155.259992)
					(end 265.602212 -155.667964)
				)
				(arc
					(start 265.602212 -155.667964)
					(mid 265.625695 -155.749171)
					(end 265.702542 -155.78455)
				)
				(arc
					(start 266.497308 -155.78455)
					(mid 266.574274 -155.749274)
					(end 266.597638 -155.667964)
				)
				(arc
					(start 266.597638 -155.667964)
					(mid 266.949936 -155.258895)
					(end 267.302234 -155.667964)
				)
				(arc
					(start 267.302234 -155.667964)
					(mid 267.325717 -155.749171)
					(end 267.402564 -155.78455)
				)
				(arc
					(start 269.897098 -155.78455)
					(mid 269.974052 -155.749288)
					(end 269.997682 -155.667964)
				)
				(arc
					(start 269.997682 -155.667964)
					(mid 270.349726 -155.258854)
					(end 270.70177 -155.667964)
				)
				(arc
					(start 270.70177 -155.667964)
					(mid 270.725329 -155.749349)
					(end 270.802354 -155.78455)
				)
				(arc
					(start 271.59712 -155.78455)
					(mid 271.674074 -155.749288)
					(end 271.697704 -155.667964)
				)
				(arc
					(start 271.697704 -155.667964)
					(mid 272.049748 -155.258854)
					(end 272.401792 -155.667964)
				)
				(arc
					(start 272.401792 -155.667964)
					(mid 272.425351 -155.749349)
					(end 272.502376 -155.78455)
				)
				(arc
					(start 273.297142 -155.78455)
					(mid 273.374096 -155.749288)
					(end 273.397726 -155.667964)
				)
				(arc
					(start 273.397726 -155.667964)
					(mid 273.74977 -155.258854)
					(end 274.101814 -155.667964)
				)
				(arc
					(start 274.101814 -155.667964)
					(mid 274.125373 -155.749349)
					(end 274.202398 -155.78455)
				)
				(arc
					(start 274.997164 -155.78455)
					(mid 275.074118 -155.749288)
					(end 275.097748 -155.667964)
				)
				(arc
					(start 275.097748 -155.667964)
					(mid 275.449792 -155.258854)
					(end 275.801836 -155.667964)
				)
				(arc
					(start 275.801836 -155.667964)
					(mid 275.825395 -155.749349)
					(end 275.90242 -155.78455)
				)
				(arc
					(start 278.280368 -155.78455)
					(mid 278.357334 -155.749274)
					(end 278.380698 -155.667964)
				)
				(arc
					(start 278.380698 -155.667964)
					(mid 278.732996 -155.259186)
					(end 279.085294 -155.667964)
				)
				(arc
					(start 279.085294 -155.667964)
					(mid 279.108777 -155.749171)
					(end 279.185624 -155.78455)
				)
				(arc
					(start 279.249886 -155.78455)
					(mid 279.327933 -155.747998)
					(end 279.349708 -155.664662)
				)
				(arc
					(start 279.349708 -155.664662)
					(mid 279.699974 -155.243988)
					(end 280.05024 -155.664662)
				)
				(arc
					(start 280.05024 -155.664662)
					(mid 280.072104 -155.747923)
					(end 280.150062 -155.78455)
				)
				(arc
					(start 280.947622 -155.78455)
					(mid 281.024923 -155.749179)
					(end 281.048206 -155.667456)
				)
				(arc
					(start 281.048206 -155.667456)
					(mid 281.399996 -155.256843)
					(end 281.751786 -155.667456)
				)
				(arc
					(start 281.751786 -155.667456)
					(mid 281.77513 -155.749127)
					(end 281.85237 -155.78455)
				)
				(arc
					(start 282.592272 -155.78455)
					(mid 282.670319 -155.747998)
					(end 282.692094 -155.664662)
				)
				(arc
					(start 282.692094 -155.664662)
					(mid 282.703365 -155.490916)
					(end 282.795726 -155.343352)
				)
				(arc
					(start 282.795726 -155.343352)
					(mid 282.827047 -155.269946)
					(end 282.795726 -155.19654)
				)
				(arc
					(start 282.795726 -155.19654)
					(mid 282.686351 -154.934355)
					(end 282.8036 -154.675586)
				)
				(arc
					(start 282.8036 -154.675586)
					(mid 282.836863 -154.601213)
					(end 282.80487 -154.526234)
				)
				(arc
					(start 282.80487 -154.526234)
					(mid 282.692828 -154.268696)
					(end 282.80233 -154.010106)
				)
				(arc
					(start 282.80233 -154.010106)
					(mid 282.833651 -153.9367)
					(end 282.80233 -153.863294)
				)
				(arc
					(start 282.80233 -153.863294)
					(mid 283.048964 -153.25045)
					(end 283.295598 -153.863294)
				)
				(arc
					(start 283.295598 -153.863294)
					(mid 283.264277 -153.9367)
					(end 283.295598 -154.010106)
				)
				(arc
					(start 283.295598 -154.010106)
					(mid 283.404973 -154.272291)
					(end 283.287724 -154.53106)
				)
				(arc
					(start 283.287724 -154.53106)
					(mid 283.254461 -154.605433)
					(end 283.286454 -154.680412)
				)
				(arc
					(start 283.286454 -154.680412)
					(mid 283.398496 -154.93795)
					(end 283.288994 -155.19654)
				)
				(arc
					(start 283.288994 -155.19654)
					(mid 283.257673 -155.269946)
					(end 283.288994 -155.343352)
				)
				(arc
					(start 283.288994 -155.343352)
					(mid 283.381252 -155.490949)
					(end 283.392626 -155.664662)
				)
				(arc
					(start 283.392626 -155.664662)
					(mid 283.41449 -155.747923)
					(end 283.492448 -155.78455)
				)
				(arc
					(start 283.910532 -155.78455)
					(mid 283.993071 -155.742194)
					(end 284.006798 -155.650438)
				)
				(arc
					(start 284.006798 -155.650438)
					(mid 283.998217 -155.45369)
					(end 284.095444 -155.282392)
				)
				(arc
					(start 284.095444 -155.282392)
					(mid 284.125981 -155.208758)
					(end 284.09392 -155.135834)
				)
				(arc
					(start 284.09392 -155.135834)
					(mid 283.981611 -154.877503)
					(end 284.092142 -154.618436)
				)
				(arc
					(start 284.092142 -154.618436)
					(mid 284.123542 -154.544942)
					(end 284.092142 -154.47137)
				)
				(arc
					(start 284.092142 -154.47137)
					(mid 283.981679 -154.213021)
					(end 284.092904 -153.954988)
				)
				(arc
					(start 284.092904 -153.954988)
					(mid 284.124566 -153.881779)
					(end 284.093666 -153.808176)
				)
				(arc
					(start 284.093666 -153.808176)
					(mid 284.342857 -153.196119)
					(end 284.585918 -153.810716)
				)
				(arc
					(start 284.585918 -153.810716)
					(mid 284.554256 -153.883925)
					(end 284.585156 -153.957528)
				)
				(arc
					(start 284.585156 -153.957528)
					(mid 284.693788 -154.214817)
					(end 284.583378 -154.47137)
				)
				(arc
					(start 284.583378 -154.47137)
					(mid 284.551794 -154.544942)
					(end 284.583378 -154.618436)
				)
				(arc
					(start 284.583378 -154.618436)
					(mid 284.693834 -154.873911)
					(end 284.58668 -155.130754)
				)
				(arc
					(start 284.58668 -155.130754)
					(mid 284.556143 -155.204388)
					(end 284.588204 -155.277312)
				)
				(arc
					(start 284.588204 -155.277312)
					(mid 284.689784 -155.450131)
					(end 284.68193 -155.650438)
				)
				(arc
					(start 284.68193 -155.650438)
					(mid 284.69565 -155.742198)
					(end 284.778196 -155.78455)
				)
				(arc
					(start 285.19755 -155.78455)
					(mid 285.274851 -155.749179)
					(end 285.298134 -155.667456)
				)
				(arc
					(start 285.298134 -155.667456)
					(mid 285.649924 -155.256843)
					(end 286.001714 -155.667456)
				)
				(arc
					(start 286.001714 -155.667456)
					(mid 286.025058 -155.749127)
					(end 286.102298 -155.78455)
				)
				(arc
					(start 286.897572 -155.78455)
					(mid 286.974873 -155.749179)
					(end 286.998156 -155.667456)
				)
				(arc
					(start 286.998156 -155.667456)
					(mid 287.349946 -155.256843)
					(end 287.701736 -155.667456)
				)
				(arc
					(start 287.701736 -155.667456)
					(mid 287.72508 -155.749127)
					(end 287.80232 -155.78455)
				)
				(arc
					(start 288.59988 -155.78455)
					(mid 288.677927 -155.747998)
					(end 288.699702 -155.664662)
				)
				(arc
					(start 288.699702 -155.664662)
					(mid 289.049968 -155.243988)
					(end 289.400234 -155.664662)
				)
				(arc
					(start 289.400234 -155.664662)
					(mid 289.422098 -155.747923)
					(end 289.500056 -155.78455)
				)
				(arc
					(start 289.570414 -155.78455)
					(mid 289.664038 -155.722411)
					(end 289.643058 -155.612084)
				)
				(arc
					(start 289.643058 -155.612084)
					(mid 289.898328 -155.007482)
					(end 290.153598 -155.612084)
				)
				(arc
					(start 290.153598 -155.612084)
					(mid 290.132725 -155.722367)
					(end 290.226242 -155.78455)
				)
				(arc
					(start 290.297616 -155.78455)
					(mid 290.374917 -155.749179)
					(end 290.3982 -155.667456)
				)
				(arc
					(start 290.3982 -155.667456)
					(mid 290.74999 -155.256843)
					(end 291.10178 -155.667456)
				)
				(arc
					(start 291.10178 -155.667456)
					(mid 291.125124 -155.749127)
					(end 291.202364 -155.78455)
				)
				(arc
					(start 291.94252 -155.78455)
					(mid 292.020567 -155.747998)
					(end 292.042342 -155.664662)
				)
				(arc
					(start 292.042342 -155.664662)
					(mid 292.053613 -155.490916)
					(end 292.145974 -155.343352)
				)
				(arc
					(start 292.145974 -155.343352)
					(mid 292.177295 -155.269946)
					(end 292.145974 -155.19654)
				)
				(arc
					(start 292.145974 -155.19654)
					(mid 292.036599 -154.934355)
					(end 292.153848 -154.675586)
				)
				(arc
					(start 292.153848 -154.675586)
					(mid 292.187111 -154.601213)
					(end 292.155118 -154.526234)
				)
				(arc
					(start 292.155118 -154.526234)
					(mid 292.043076 -154.268696)
					(end 292.152578 -154.010106)
				)
				(arc
					(start 292.152578 -154.010106)
					(mid 292.183899 -153.9367)
					(end 292.152578 -153.863294)
				)
				(arc
					(start 292.152578 -153.863294)
					(mid 292.399212 -153.25045)
					(end 292.645846 -153.863294)
				)
				(arc
					(start 292.645846 -153.863294)
					(mid 292.614525 -153.9367)
					(end 292.645846 -154.010106)
				)
				(arc
					(start 292.645846 -154.010106)
					(mid 292.755221 -154.272291)
					(end 292.637972 -154.53106)
				)
				(arc
					(start 292.637972 -154.53106)
					(mid 292.604709 -154.605433)
					(end 292.636702 -154.680412)
				)
				(arc
					(start 292.636702 -154.680412)
					(mid 292.748744 -154.93795)
					(end 292.639242 -155.19654)
				)
				(arc
					(start 292.639242 -155.19654)
					(mid 292.607921 -155.269946)
					(end 292.639242 -155.343352)
				)
				(arc
					(start 292.639242 -155.343352)
					(mid 292.7315 -155.490949)
					(end 292.742874 -155.664662)
				)
				(arc
					(start 292.742874 -155.664662)
					(mid 292.764738 -155.747923)
					(end 292.842696 -155.78455)
				)
				(arc
					(start 293.26078 -155.78455)
					(mid 293.343319 -155.742194)
					(end 293.357046 -155.650438)
				)
				(arc
					(start 293.357046 -155.650438)
					(mid 293.348465 -155.45369)
					(end 293.445692 -155.282392)
				)
				(arc
					(start 293.445692 -155.282392)
					(mid 293.476229 -155.208758)
					(end 293.444168 -155.135834)
				)
				(arc
					(start 293.444168 -155.135834)
					(mid 293.331859 -154.877503)
					(end 293.44239 -154.618436)
				)
				(arc
					(start 293.44239 -154.618436)
					(mid 293.47379 -154.544942)
					(end 293.44239 -154.47137)
				)
				(arc
					(start 293.44239 -154.47137)
					(mid 293.331927 -154.213021)
					(end 293.443152 -153.954988)
				)
				(arc
					(start 293.443152 -153.954988)
					(mid 293.474814 -153.881779)
					(end 293.443914 -153.808176)
				)
				(arc
					(start 293.443914 -153.808176)
					(mid 293.693105 -153.196119)
					(end 293.936166 -153.810716)
				)
				(arc
					(start 293.936166 -153.810716)
					(mid 293.904504 -153.883925)
					(end 293.935404 -153.957528)
				)
				(arc
					(start 293.935404 -153.957528)
					(mid 294.044036 -154.214817)
					(end 293.933626 -154.47137)
				)
				(arc
					(start 293.933626 -154.47137)
					(mid 293.902042 -154.544942)
					(end 293.933626 -154.618436)
				)
				(arc
					(start 293.933626 -154.618436)
					(mid 294.044082 -154.873911)
					(end 293.936928 -155.130754)
				)
				(arc
					(start 293.936928 -155.130754)
					(mid 293.906391 -155.204388)
					(end 293.938452 -155.277312)
				)
				(arc
					(start 293.938452 -155.277312)
					(mid 294.040032 -155.450131)
					(end 294.032178 -155.650438)
				)
				(arc
					(start 294.032178 -155.650438)
					(mid 294.045898 -155.742198)
					(end 294.128444 -155.78455)
				)
				(arc
					(start 294.547544 -155.78455)
					(mid 294.624845 -155.749179)
					(end 294.648128 -155.667456)
				)
				(arc
					(start 294.648128 -155.667456)
					(mid 294.999918 -155.256843)
					(end 295.351708 -155.667456)
				)
				(arc
					(start 295.351708 -155.667456)
					(mid 295.375052 -155.749127)
					(end 295.452292 -155.78455)
				)
				(arc
					(start 296.247566 -155.78455)
					(mid 296.324867 -155.749179)
					(end 296.34815 -155.667456)
				)
				(arc
					(start 296.34815 -155.667456)
					(mid 296.69994 -155.256843)
					(end 297.05173 -155.667456)
				)
				(arc
					(start 297.05173 -155.667456)
					(mid 297.075074 -155.749127)
					(end 297.152314 -155.78455)
				)
				(arc
					(start 297.949874 -155.78455)
					(mid 298.027921 -155.747998)
					(end 298.049696 -155.664662)
				)
				(arc
					(start 298.049696 -155.664662)
					(mid 298.399962 -155.243988)
					(end 298.750228 -155.664662)
				)
				(arc
					(start 298.750228 -155.664662)
					(mid 298.772092 -155.747923)
					(end 298.85005 -155.78455)
				)
				(arc
					(start 299.64761 -155.78455)
					(mid 299.724911 -155.749179)
					(end 299.748194 -155.667456)
				)
				(arc
					(start 299.748194 -155.667456)
					(mid 300.099984 -155.256843)
					(end 300.451774 -155.667456)
				)
				(arc
					(start 300.451774 -155.667456)
					(mid 300.475118 -155.749127)
					(end 300.552358 -155.78455)
				)
				(arc
					(start 301.292514 -155.78455)
					(mid 301.370561 -155.747998)
					(end 301.392336 -155.664662)
				)
				(arc
					(start 301.392336 -155.664662)
					(mid 301.403607 -155.490916)
					(end 301.495968 -155.343352)
				)
				(arc
					(start 301.495968 -155.343352)
					(mid 301.527289 -155.269946)
					(end 301.495968 -155.19654)
				)
				(arc
					(start 301.495968 -155.19654)
					(mid 301.386593 -154.934355)
					(end 301.503842 -154.675586)
				)
				(arc
					(start 301.503842 -154.675586)
					(mid 301.537105 -154.601213)
					(end 301.505112 -154.526234)
				)
				(arc
					(start 301.505112 -154.526234)
					(mid 301.39307 -154.268696)
					(end 301.502572 -154.010106)
				)
				(arc
					(start 301.502572 -154.010106)
					(mid 301.533893 -153.9367)
					(end 301.502572 -153.863294)
				)
				(arc
					(start 301.502572 -153.863294)
					(mid 301.749206 -153.25045)
					(end 301.99584 -153.863294)
				)
				(arc
					(start 301.99584 -153.863294)
					(mid 301.964519 -153.9367)
					(end 301.99584 -154.010106)
				)
				(arc
					(start 301.99584 -154.010106)
					(mid 302.105215 -154.272291)
					(end 301.987966 -154.53106)
				)
				(arc
					(start 301.987966 -154.53106)
					(mid 301.954703 -154.605433)
					(end 301.986696 -154.680412)
				)
				(arc
					(start 301.986696 -154.680412)
					(mid 302.098738 -154.93795)
					(end 301.989236 -155.19654)
				)
				(arc
					(start 301.989236 -155.19654)
					(mid 301.957915 -155.269946)
					(end 301.989236 -155.343352)
				)
				(arc
					(start 301.989236 -155.343352)
					(mid 302.081494 -155.490949)
					(end 302.092868 -155.664662)
				)
				(arc
					(start 302.092868 -155.664662)
					(mid 302.114732 -155.747923)
					(end 302.19269 -155.78455)
				)
				(arc
					(start 302.610774 -155.78455)
					(mid 302.693313 -155.742194)
					(end 302.70704 -155.650438)
				)
				(arc
					(start 302.70704 -155.650438)
					(mid 302.698459 -155.45369)
					(end 302.795686 -155.282392)
				)
				(arc
					(start 302.795686 -155.282392)
					(mid 302.826223 -155.208758)
					(end 302.794162 -155.135834)
				)
				(arc
					(start 302.794162 -155.135834)
					(mid 302.681853 -154.877503)
					(end 302.792384 -154.618436)
				)
				(arc
					(start 302.792384 -154.618436)
					(mid 302.823784 -154.544942)
					(end 302.792384 -154.47137)
				)
				(arc
					(start 302.792384 -154.47137)
					(mid 302.681921 -154.213021)
					(end 302.793146 -153.954988)
				)
				(arc
					(start 302.793146 -153.954988)
					(mid 302.824808 -153.881779)
					(end 302.793908 -153.808176)
				)
				(arc
					(start 302.793908 -153.808176)
					(mid 303.043099 -153.196119)
					(end 303.28616 -153.810716)
				)
				(arc
					(start 303.28616 -153.810716)
					(mid 303.254498 -153.883925)
					(end 303.285398 -153.957528)
				)
				(arc
					(start 303.285398 -153.957528)
					(mid 303.39403 -154.214817)
					(end 303.28362 -154.47137)
				)
				(arc
					(start 303.28362 -154.47137)
					(mid 303.252036 -154.544942)
					(end 303.28362 -154.618436)
				)
				(arc
					(start 303.28362 -154.618436)
					(mid 303.394076 -154.873911)
					(end 303.286922 -155.130754)
				)
				(arc
					(start 303.286922 -155.130754)
					(mid 303.256385 -155.204388)
					(end 303.288446 -155.277312)
				)
				(arc
					(start 303.288446 -155.277312)
					(mid 303.390026 -155.450131)
					(end 303.382172 -155.650438)
				)
				(arc
					(start 303.382172 -155.650438)
					(mid 303.395892 -155.742198)
					(end 303.478438 -155.78455)
				)
				(arc
					(start 303.897538 -155.78455)
					(mid 303.974839 -155.749179)
					(end 303.998122 -155.667456)
				)
				(arc
					(start 303.998122 -155.667456)
					(mid 304.349912 -155.256843)
					(end 304.701702 -155.667456)
				)
				(arc
					(start 304.701702 -155.667456)
					(mid 304.725046 -155.749127)
					(end 304.802286 -155.78455)
				)
				(arc
					(start 305.59756 -155.78455)
					(mid 305.674861 -155.749179)
					(end 305.698144 -155.667456)
				)
				(arc
					(start 305.698144 -155.667456)
					(mid 306.049934 -155.256843)
					(end 306.401724 -155.667456)
				)
				(arc
					(start 306.401724 -155.667456)
					(mid 306.425068 -155.749127)
					(end 306.502308 -155.78455)
				)
				(arc
					(start 307.299868 -155.78455)
					(mid 307.377915 -155.747998)
					(end 307.39969 -155.664662)
				)
				(arc
					(start 307.39969 -155.664662)
					(mid 307.749956 -155.243988)
					(end 308.100222 -155.664662)
				)
				(arc
					(start 308.100222 -155.664662)
					(mid 308.122086 -155.747923)
					(end 308.200044 -155.78455)
				)
				(arc
					(start 308.997604 -155.78455)
					(mid 309.074905 -155.749179)
					(end 309.098188 -155.667456)
				)
				(arc
					(start 309.098188 -155.667456)
					(mid 309.449978 -155.256843)
					(end 309.801768 -155.667456)
				)
				(arc
					(start 309.801768 -155.667456)
					(mid 309.825112 -155.749127)
					(end 309.902352 -155.78455)
				)
				(arc
					(start 310.642508 -155.78455)
					(mid 310.720555 -155.747998)
					(end 310.74233 -155.664662)
				)
				(arc
					(start 310.74233 -155.664662)
					(mid 310.753601 -155.490916)
					(end 310.845962 -155.343352)
				)
				(arc
					(start 310.845962 -155.343352)
					(mid 310.877283 -155.269946)
					(end 310.845962 -155.19654)
				)
				(arc
					(start 310.845962 -155.19654)
					(mid 310.736587 -154.934355)
					(end 310.853836 -154.675586)
				)
				(arc
					(start 310.853836 -154.675586)
					(mid 310.887099 -154.601213)
					(end 310.855106 -154.526234)
				)
				(arc
					(start 310.855106 -154.526234)
					(mid 310.743064 -154.268696)
					(end 310.852566 -154.010106)
				)
				(arc
					(start 310.852566 -154.010106)
					(mid 310.883887 -153.9367)
					(end 310.852566 -153.863294)
				)
				(arc
					(start 310.852566 -153.863294)
					(mid 311.0992 -153.25045)
					(end 311.345834 -153.863294)
				)
				(arc
					(start 311.345834 -153.863294)
					(mid 311.314513 -153.9367)
					(end 311.345834 -154.010106)
				)
				(arc
					(start 311.345834 -154.010106)
					(mid 311.455209 -154.272291)
					(end 311.33796 -154.53106)
				)
				(arc
					(start 311.33796 -154.53106)
					(mid 311.304697 -154.605433)
					(end 311.33669 -154.680412)
				)
				(arc
					(start 311.33669 -154.680412)
					(mid 311.448732 -154.93795)
					(end 311.33923 -155.19654)
				)
				(arc
					(start 311.33923 -155.19654)
					(mid 311.307909 -155.269946)
					(end 311.33923 -155.343352)
				)
				(arc
					(start 311.33923 -155.343352)
					(mid 311.431488 -155.490949)
					(end 311.442862 -155.664662)
				)
				(arc
					(start 311.442862 -155.664662)
					(mid 311.464726 -155.747923)
					(end 311.542684 -155.78455)
				)
				(arc
					(start 311.960768 -155.78455)
					(mid 312.043307 -155.742194)
					(end 312.057034 -155.650438)
				)
				(arc
					(start 312.057034 -155.650438)
					(mid 312.048453 -155.45369)
					(end 312.14568 -155.282392)
				)
				(arc
					(start 312.14568 -155.282392)
					(mid 312.176217 -155.208758)
					(end 312.144156 -155.135834)
				)
				(arc
					(start 312.144156 -155.135834)
					(mid 312.031847 -154.877503)
					(end 312.142378 -154.618436)
				)
				(arc
					(start 312.142378 -154.618436)
					(mid 312.173778 -154.544942)
					(end 312.142378 -154.47137)
				)
				(arc
					(start 312.142378 -154.47137)
					(mid 312.031915 -154.213021)
					(end 312.14314 -153.954988)
				)
				(arc
					(start 312.14314 -153.954988)
					(mid 312.174802 -153.881779)
					(end 312.143902 -153.808176)
				)
				(arc
					(start 312.143902 -153.808176)
					(mid 312.393093 -153.196119)
					(end 312.636154 -153.810716)
				)
				(arc
					(start 312.636154 -153.810716)
					(mid 312.604492 -153.883925)
					(end 312.635392 -153.957528)
				)
				(arc
					(start 312.635392 -153.957528)
					(mid 312.744024 -154.214817)
					(end 312.633614 -154.47137)
				)
				(arc
					(start 312.633614 -154.47137)
					(mid 312.60203 -154.544942)
					(end 312.633614 -154.618436)
				)
				(arc
					(start 312.633614 -154.618436)
					(mid 312.74407 -154.873911)
					(end 312.636916 -155.130754)
				)
				(arc
					(start 312.636916 -155.130754)
					(mid 312.606379 -155.204388)
					(end 312.63844 -155.277312)
				)
				(arc
					(start 312.63844 -155.277312)
					(mid 312.74002 -155.450131)
					(end 312.732166 -155.650438)
				)
				(arc
					(start 312.732166 -155.650438)
					(mid 312.745886 -155.742198)
					(end 312.828432 -155.78455)
				)
				(arc
					(start 313.247532 -155.78455)
					(mid 313.324833 -155.749179)
					(end 313.348116 -155.667456)
				)
				(arc
					(start 313.348116 -155.667456)
					(mid 313.699906 -155.256843)
					(end 314.051696 -155.667456)
				)
				(arc
					(start 314.051696 -155.667456)
					(mid 314.07504 -155.749127)
					(end 314.15228 -155.78455)
				)
				(arc
					(start 314.947554 -155.78455)
					(mid 315.024855 -155.749179)
					(end 315.048138 -155.667456)
				)
				(arc
					(start 315.048138 -155.667456)
					(mid 315.399928 -155.256843)
					(end 315.751718 -155.667456)
				)
				(arc
					(start 315.751718 -155.667456)
					(mid 315.775062 -155.749127)
					(end 315.852302 -155.78455)
				)
				(arc
					(start 316.647576 -155.78455)
					(mid 316.724877 -155.749179)
					(end 316.74816 -155.667456)
				)
				(arc
					(start 316.74816 -155.667456)
					(mid 317.09995 -155.256843)
					(end 317.45174 -155.667456)
				)
				(arc
					(start 317.45174 -155.667456)
					(mid 317.475084 -155.749127)
					(end 317.552324 -155.78455)
				)
				(xy 317.611506 -155.78455) (xy 317.611506 -155.72613)
				(arc
					(start 317.60922 -155.719018)
					(mid 317.92367 -155.259662)
					(end 318.301878 -155.667964)
				)
				(arc
					(start 318.301878 -155.667964)
					(mid 318.325437 -155.749349)
					(end 318.402462 -155.78455)
				)
				(xy 318.461644 -155.78455) (xy 318.461644 -155.72613)
				(arc
					(start 318.459358 -155.719018)
					(mid 318.773808 -155.259662)
					(end 319.152016 -155.667964)
				)
				(arc
					(start 319.152016 -155.667964)
					(mid 319.175575 -155.749349)
					(end 319.2526 -155.78455)
				)
				(xy 319.311528 -155.78455) (xy 319.311528 -155.72613)
				(arc
					(start 319.309242 -155.719018)
					(mid 319.623692 -155.259662)
					(end 320.0019 -155.667964)
				)
				(arc
					(start 320.0019 -155.667964)
					(mid 320.025459 -155.749349)
					(end 320.102484 -155.78455)
				)
				(xy 320.161666 -155.78455) (xy 320.161666 -155.72613)
				(arc
					(start 320.15938 -155.719018)
					(mid 320.47383 -155.259662)
					(end 320.852038 -155.667964)
				)
				(arc
					(start 320.852038 -155.667964)
					(mid 320.875597 -155.749349)
					(end 320.952622 -155.78455)
				)
				(xy 321.01155 -155.78455) (xy 321.01155 -155.72613)
				(arc
					(start 321.009264 -155.719018)
					(mid 321.323714 -155.259662)
					(end 321.701922 -155.667964)
				)
				(arc
					(start 321.701922 -155.667964)
					(mid 321.725481 -155.749349)
					(end 321.802506 -155.78455)
				)
				(arc
					(start 325.788782 -155.78455)
					(mid 325.881693 -155.72406)
					(end 325.863966 -155.614624)
				)
				(arc
					(start 325.863966 -155.614624)
					(mid 326.999854 -153.041559)
					(end 328.135742 -155.614624)
				)
				(arc
					(start 328.135742 -155.614624)
					(mid 328.118021 -155.724058)
					(end 328.210926 -155.78455)
				)
				(xy 328.4601 -155.78455) (xy 329.05065 -155.194) (xy 336.4738 -155.194) (xy 336.8167 -154.8511)
				(xy 336.8167 -145.9611) (xy 336.0293 -145.1737) (xy 336.0293 -139.1031) (xy 334.66405 -137.73785)
				(arc
					(start 332.6511 -137.73785)
					(mid 332.577914 -137.769241)
					(end 332.549754 -137.843768)
				)
				(arc
					(start 332.549754 -137.843768)
					(mid 332.170518 -138.21389)
					(end 331.843126 -137.797286)
				)
				(xy 331.843888 -137.792968) (xy 331.843888 -137.73785) (xy 331.71765 -137.73785) (xy 331.4573 -137.9982)
				(xy 323.85 -137.9982) (xy 323.3928 -137.541) (xy 279.30094 -137.541) (xy 278.892 -137.13206) (xy 278.892 -136.68629)
				(arc
					(start 278.84882 -136.679686)
					(mid 278.554542 -136.404727)
					(end 278.705056 -136.031224)
				)
				(arc
					(start 278.705056 -136.031224)
					(mid 278.750241 -135.950732)
					(end 278.71166 -135.866886)
				)
				(arc
					(start 278.71166 -135.866886)
					(mid 278.577313 -135.610042)
					(end 278.678386 -135.338312)
				)
				(arc
					(start 278.678386 -135.338312)
					(mid 278.707256 -135.261706)
					(end 278.670258 -135.188706)
				)
				(arc
					(start 278.670258 -135.188706)
					(mid 278.542797 -134.87398)
					(end 278.73706 -134.595362)
				)
				(xy 278.765 -134.581138) (xy 278.765 -131.7498) (xy 278.892 -131.6228) (xy 278.892 -131.235958)
				(arc
					(start 278.856948 -131.224528)
					(mid 278.638678 -131.021323)
					(end 278.651462 -130.723386)
				)
				(arc
					(start 278.651462 -130.723386)
					(mid 278.656056 -130.640729)
					(end 278.597614 -130.582162)
				)
				(arc
					(start 278.597614 -130.582162)
					(mid 278.380509 -130.159971)
					(end 278.775922 -129.897124)
				)
				(arc
					(start 278.775922 -129.897124)
					(mid 278.856941 -129.873345)
					(end 278.892 -129.79654)
				)
				(xy 278.892 -127.762) (xy 270.165576 -119.035576) (xy 270.165576 -109.462824) (xy 270.161004 -109.457998)
				(xy 270.161004 -93.783404) (xy 268.47546 -92.09786) (xy 262.979408 -92.09786) (xy 262.894318 -92.01277)
				(xy 262.778748 -91.8972) (xy 260.130544 -89.248996) (xy 258.118864 -89.248996) (xy 257.80746 -88.937592)
				(xy 255.904238 -88.937592) (xy 255.610868 -89.230962) (xy 255.228344 -89.230962) (xy 254.934974 -88.937592)
				(arc
					(start 254.893826 -88.937592)
					(mid 254.805683 -88.98866)
					(end 254.806196 -89.0905)
				)
				(arc
					(start 254.806196 -89.0905)
					(mid 254.49911 -89.626964)
					(end 254.192024 -89.0905)
				)
				(arc
					(start 254.192024 -89.0905)
					(mid 254.192489 -88.988687)
					(end 254.104394 -88.937592)
				)
				(arc
					(start 253.957836 -88.937592)
					(mid 253.640844 -89.131414)
					(end 253.323852 -88.937592)
				)
				(arc
					(start 253.17704 -88.937592)
					(mid 253.088897 -88.98866)
					(end 253.08941 -89.0905)
				)
				(arc
					(start 253.08941 -89.0905)
					(mid 252.782324 -89.626964)
					(end 252.475238 -89.0905)
				)
				(arc
					(start 252.475238 -89.0905)
					(mid 252.475703 -88.988687)
					(end 252.387608 -88.937592)
				)
			)
		)
	)
	(zone
		(net "P12V_PSU")
		(layer "In3.Cu")
		(hatch none 0.5)
		(connect_pads
			(clearance 0.5)
		)
		(min_thickness 0.25)
		(fill yes
			(thermal_gap 0.5)
			(thermal_bridge_width 0.5)
			(island_removal_mode 0)
		)
		(polygon
			(pts
				(xy 3.537458 -68.446396) (xy 3.537458 -85.554058) (xy 4.1402 -86.1568) (xy 9.8298 -86.1568) (xy 10.0584 -85.9282)
				(xy 10.0584 -50.673) (xy 9.4488 -50.0634) (xy 3.4036 -50.0634) (xy 3.0988 -50.3682) (xy 3.0988 -59.101228)
				(xy 2.305304 -59.894724) (xy 2.305304 -67.214496)
			)
		)
	)
	(zone
		(net "PVDDQ_KLM")
		(layer "In3.Cu")
		(hatch none 0.5)
		(connect_pads
			(clearance 0.5)
		)
		(min_thickness 0.25)
		(fill yes
			(thermal_gap 0.5)
			(thermal_bridge_width 0.5)
			(island_removal_mode 0)
		)
		(polygon
			(pts
				(arc
					(start 95.861886 -88.81872)
					(mid 95.608012 -89.11731)
					(end 95.23349 -89.0016)
				)
				(arc
					(start 95.075756 -89.0016)
					(mid 94.99181 -89.045967)
					(end 94.981268 -89.140284)
				)
				(arc
					(start 94.981268 -89.140284)
					(mid 94.649798 -89.627094)
					(end 94.318328 -89.140284)
				)
				(arc
					(start 94.318328 -89.140284)
					(mid 94.307707 -89.04602)
					(end 94.22384 -89.0016)
				)
				(arc
					(start 94.066106 -89.0016)
					(mid 93.791278 -89.131303)
					(end 93.51645 -89.0016)
				)
				(arc
					(start 93.358716 -89.0016)
					(mid 93.27477 -89.045967)
					(end 93.264228 -89.140284)
				)
				(arc
					(start 93.264228 -89.140284)
					(mid 92.932758 -89.627094)
					(end 92.601288 -89.140284)
				)
				(arc
					(start 92.601288 -89.140284)
					(mid 92.590667 -89.04602)
					(end 92.5068 -89.0016)
				)
				(arc
					(start 92.349066 -89.0016)
					(mid 92.074238 -89.131303)
					(end 91.79941 -89.0016)
				)
				(arc
					(start 91.641676 -89.0016)
					(mid 91.55773 -89.045967)
					(end 91.547188 -89.140284)
				)
				(arc
					(start 91.547188 -89.140284)
					(mid 91.215718 -89.627094)
					(end 90.884248 -89.140284)
				)
				(arc
					(start 90.884248 -89.140284)
					(mid 90.873627 -89.04602)
					(end 90.78976 -89.0016)
				)
				(arc
					(start 90.632026 -89.0016)
					(mid 90.357198 -89.131303)
					(end 90.08237 -89.0016)
				)
				(arc
					(start 89.924636 -89.0016)
					(mid 89.84069 -89.045967)
					(end 89.830148 -89.140284)
				)
				(arc
					(start 89.830148 -89.140284)
					(mid 89.498678 -89.627094)
					(end 89.167208 -89.140284)
				)
				(arc
					(start 89.167208 -89.140284)
					(mid 89.156587 -89.04602)
					(end 89.07272 -89.0016)
				)
				(arc
					(start 88.91524 -89.0016)
					(mid 88.640412 -89.131303)
					(end 88.365584 -89.0016)
				)
				(arc
					(start 88.20785 -89.0016)
					(mid 88.123904 -89.045967)
					(end 88.113362 -89.140284)
				)
				(arc
					(start 88.113362 -89.140284)
					(mid 87.781892 -89.627094)
					(end 87.450422 -89.140284)
				)
				(arc
					(start 87.450422 -89.140284)
					(mid 87.439801 -89.04602)
					(end 87.355934 -89.0016)
				)
				(arc
					(start 87.1982 -89.0016)
					(mid 87.178284 -89.023948)
					(end 87.156544 -89.044526)
				)
				(xy 87.148924 -89.050876) (xy 86.454488 -89.745312) (xy 86.454488 -91.309698) (xy 86.40445 -91.359736)
				(arc
					(start 86.40064 -91.370658)
					(mid 86.331797 -91.48776)
					(end 86.22411 -91.570556)
				)
				(arc
					(start 86.22411 -91.924124)
					(mid 86.420265 -92.220336)
					(end 86.262718 -92.538804)
				)
				(xy 86.262718 -92.964762) (xy 86.0552 -93.17228) (xy 86.0552 -93.32214) (xy 86.262718 -93.529658)
				(arc
					(start 86.262718 -93.927422)
					(mid 86.420445 -94.245893)
					(end 86.22411 -94.542102)
				)
				(xy 86.22411 -94.659704)
				(arc
					(start 86.165182 -94.718632)
					(mid 86.13764 -94.810567)
					(end 86.198964 -94.884494)
				)
				(arc
					(start 86.198964 -94.884494)
					(mid 86.392301 -95.354539)
					(end 85.918802 -95.539306)
				)
				(arc
					(start 85.918802 -95.539306)
					(mid 85.822042 -95.546612)
					(end 85.775546 -95.631762)
				)
				(arc
					(start 85.775546 -95.787718)
					(mid 85.822062 -95.872836)
					(end 85.918802 -95.880174)
				)
				(arc
					(start 85.918802 -95.880174)
					(mid 86.421038 -96.20504)
					(end 85.918802 -96.529906)
				)
				(arc
					(start 85.918802 -96.529906)
					(mid 85.822042 -96.537212)
					(end 85.775546 -96.622362)
				)
				(xy 85.775546 -100.6348) (xy 85.393276 -101.01707) (xy 85.393276 -107.4674) (xy 85.344 -107.516676)
				(xy 85.344 -119.250968) (xy 85.332316 -119.262652) (xy 85.332316 -120.070118) (xy 78.795372 -126.607062)
				(arc
					(start 78.795372 -129.122932)
					(mid 78.833624 -129.202365)
					(end 78.919578 -129.221992)
				)
				(arc
					(start 78.919578 -129.221992)
					(mid 79.355347 -129.568956)
					(end 78.919578 -129.91592)
				)
				(arc
					(start 78.919578 -129.91592)
					(mid 78.83362 -129.935542)
					(end 78.795372 -130.01498)
				)
				(xy 78.795372 -131.740402) (xy 78.5241 -132.011674)
				(arc
					(start 78.5241 -134.087362)
					(mid 78.6257 -134.331202)
					(end 78.5241 -134.575042)
				)
				(arc
					(start 78.5241 -135.20674)
					(mid 78.586027 -135.4074)
					(end 78.5241 -135.60806)
				)
				(xy 78.5241 -136.501632)
				(arc
					(start 78.453742 -136.57199)
					(mid 78.40123 -136.638858)
					(end 78.334362 -136.69137)
				)
				(xy 78.283054 -136.742678) (xy 78.16723 -136.742678) (xy 78.13167 -136.742678) (xy 77.910182 -136.742678)
				(xy 77.177138 -137.475722) (xy 24.052022 -137.475722) (xy 23.288244 -136.711944)
				(arc
					(start 23.282402 -136.708642)
					(mid 22.962457 -136.463437)
					(end 22.717252 -136.143492)
				)
				(xy 22.71395 -136.13765) (xy 22.606 -136.0297) (xy 18.288 -136.0297) (xy 17.1831 -137.1346) (xy 17.1831 -155.9814)
				(xy 17.8308 -156.6291) (xy 21.785834 -156.6291) (xy 22.257766 -156.6291) (xy 22.733 -156.153866)
				(arc
					(start 22.733 -155.372562)
					(mid 23.228032 -153.279122)
					(end 25.33142 -153.730452)
				)
				(xy 26.762964 -155.161996) (xy 29.530294 -155.161996) (xy 29.74467 -155.376372) (xy 30.359096 -155.990798)
				(xy 91.444572 -155.990798) (xy 92.389706 -156.935932) (xy 95.324168 -156.935932) (xy 96.110552 -156.149548)
				(xy 97.1931 -155.067) (xy 97.354644 -155.067) (xy 97.6122 -155.067) (xy 97.663 -155.0162) (xy 97.663 -154.758644)
				(xy 97.684844 -154.7368)
				(arc
					(start 97.684844 -153.956512)
					(mid 98.599498 -153.041858)
					(end 99.514152 -153.956512)
				)
				(arc
					(start 99.514152 -155.201112)
					(mid 99.450728 -155.536028)
					(end 99.269042 -155.824428)
				)
				(arc
					(start 99.269042 -155.824428)
					(mid 99.250385 -155.934112)
					(end 99.343464 -155.995116)
				)
				(arc
					(start 99.886008 -155.995116)
					(mid 99.977085 -155.938544)
					(end 99.96678 -155.831794)
				)
				(arc
					(start 99.96678 -155.831794)
					(mid 100.249228 -155.258747)
					(end 100.531676 -155.831794)
				)
				(arc
					(start 100.531676 -155.831794)
					(mid 100.521322 -155.938568)
					(end 100.612448 -155.995116)
				)
				(arc
					(start 101.586284 -155.995116)
					(mid 101.677395 -155.938474)
					(end 101.666802 -155.831794)
				)
				(arc
					(start 101.666802 -155.831794)
					(mid 101.949504 -155.258954)
					(end 102.232206 -155.831794)
				)
				(arc
					(start 102.232206 -155.831794)
					(mid 102.221744 -155.93841)
					(end 102.312724 -155.995116)
				)
				(arc
					(start 104.986074 -155.995116)
					(mid 105.077151 -155.938544)
					(end 105.066846 -155.831794)
				)
				(arc
					(start 105.066846 -155.831794)
					(mid 105.349294 -155.258747)
					(end 105.631742 -155.831794)
				)
				(arc
					(start 105.631742 -155.831794)
					(mid 105.621388 -155.938568)
					(end 105.712514 -155.995116)
				)
				(arc
					(start 106.686096 -155.995116)
					(mid 106.777173 -155.938544)
					(end 106.766868 -155.831794)
				)
				(arc
					(start 106.766868 -155.831794)
					(mid 107.049316 -155.258747)
					(end 107.331764 -155.831794)
				)
				(arc
					(start 107.331764 -155.831794)
					(mid 107.32141 -155.938568)
					(end 107.412536 -155.995116)
				)
				(arc
					(start 108.386118 -155.995116)
					(mid 108.477195 -155.938544)
					(end 108.46689 -155.831794)
				)
				(arc
					(start 108.46689 -155.831794)
					(mid 108.749338 -155.258747)
					(end 109.031786 -155.831794)
				)
				(arc
					(start 109.031786 -155.831794)
					(mid 109.021432 -155.938568)
					(end 109.112558 -155.995116)
				)
				(arc
					(start 110.08614 -155.995116)
					(mid 110.177217 -155.938544)
					(end 110.166912 -155.831794)
				)
				(arc
					(start 110.166912 -155.831794)
					(mid 110.44936 -155.258747)
					(end 110.731808 -155.831794)
				)
				(arc
					(start 110.731808 -155.831794)
					(mid 110.721454 -155.938568)
					(end 110.81258 -155.995116)
				)
				(xy 112.842294 -155.995116) (xy 114.253772 -154.583638)
				(arc
					(start 114.253772 -150.507446)
					(mid 114.207697 -150.422361)
					(end 114.111278 -150.414482)
				)
				(arc
					(start 114.111278 -150.414482)
					(mid 113.708542 -150.332723)
					(end 113.65103 -149.925786)
				)
				(arc
					(start 113.65103 -149.925786)
					(mid 113.655624 -149.843129)
					(end 113.597182 -149.784562)
				)
				(arc
					(start 113.597182 -149.784562)
					(mid 113.597617 -149.119423)
					(end 114.041428 -149.61489)
				)
				(arc
					(start 114.041428 -149.61489)
					(mid 114.036834 -149.697547)
					(end 114.095276 -149.756114)
				)
				(arc
					(start 114.111278 -149.762718)
					(mid 114.207676 -149.754807)
					(end 114.253772 -149.669754)
				)
				(arc
					(start 114.253772 -146.349466)
					(mid 114.196148 -146.257876)
					(end 114.088672 -146.270218)
				)
				(arc
					(start 114.088672 -146.270218)
					(mid 113.509773 -145.992342)
					(end 114.088672 -145.714466)
				)
				(arc
					(start 114.088672 -145.714466)
					(mid 114.196127 -145.726763)
					(end 114.253772 -145.635218)
				)
				(arc
					(start 114.253772 -144.919954)
					(mid 114.193937 -144.827335)
					(end 114.084862 -144.843754)
				)
				(arc
					(start 114.084862 -144.843754)
					(mid 113.493448 -144.5768)
					(end 114.084862 -144.309846)
				)
				(arc
					(start 114.084862 -144.309846)
					(mid 114.193967 -144.32633)
					(end 114.253772 -144.233646)
				)
				(arc
					(start 114.253772 -140.906246)
					(mid 114.207697 -140.821161)
					(end 114.111278 -140.813282)
				)
				(arc
					(start 114.111278 -140.813282)
					(mid 113.611686 -140.4874)
					(end 114.111278 -140.161518)
				)
				(arc
					(start 114.111278 -140.161518)
					(mid 114.207676 -140.153607)
					(end 114.253772 -140.068554)
				)
				(arc
					(start 114.253772 -140.055346)
					(mid 114.202704 -139.967203)
					(end 114.100864 -139.967716)
				)
				(arc
					(start 114.100864 -139.967716)
					(mid 113.567964 -139.618223)
					(end 114.16792 -139.40282)
				)
				(xy 114.182652 -139.417044) (xy 114.253772 -139.417044) (xy 114.253772 -139.33551) (xy 114.20094 -139.282678)
				(xy 114.199924 -139.282678) (xy 113.764568 -138.847322) (xy 113.764568 -136.894824) (xy 113.575338 -136.705594)
				(xy 113.575338 -136.47039)
				(arc
					(start 113.571528 -136.461246)
					(mid 113.545523 -136.327642)
					(end 113.571528 -136.194038)
				)
				(xy 113.575338 -136.184894) (xy 113.575338 -135.068564)
				(arc
					(start 113.57102 -135.058658)
					(mid 113.540137 -134.913624)
					(end 113.57102 -134.76859)
				)
				(xy 113.575338 -134.758684) (xy 113.575338 -134.507478) (xy 113.64722 -134.435596) (xy 113.64722 -131.041648)
				(arc
					(start 113.642902 -131.031742)
					(mid 113.61179 -130.8862)
					(end 113.642902 -130.740658)
				)
				(xy 113.64722 -130.730752) (xy 113.64722 -130.59918)
				(arc
					(start 113.612422 -130.58775)
					(mid 113.37839 -130.165456)
					(end 113.780316 -129.897886)
				)
				(arc
					(start 113.780316 -129.897886)
					(mid 113.862259 -129.874847)
					(end 113.897918 -129.797556)
				)
				(xy 113.897918 -127.76835) (xy 105.165144 -119.035576) (xy 105.165144 -109.462824) (xy 105.160572 -109.457998)
				(xy 105.160572 -96.3676)
				(arc
					(start 104.944926 -96.151954)
					(mid 104.836262 -96.129359)
					(end 104.771698 -96.219772)
				)
				(arc
					(start 104.771698 -96.219772)
					(mid 104.164002 -96.456882)
					(end 104.401112 -95.849186)
				)
				(arc
					(start 104.401112 -95.849186)
					(mid 104.491715 -95.784696)
					(end 104.46893 -95.675958)
				)
				(xy 104.359456 -95.566484)
				(arc
					(start 104.34447 -95.563182)
					(mid 104.128057 -95.424117)
					(end 104.061768 -95.175578)
				)
				(arc
					(start 104.061768 -95.175578)
					(mid 104.07956 -95.096995)
					(end 104.1146 -95.024448)
				)
				(xy 104.1146 -93.72092) (xy 103.46944 -93.07576) (xy 103.46944 -91.10218) (xy 102.58298 -90.21572)
				(xy 102.23246 -90.21572) (xy 101.98608 -89.96934) (xy 101.98608 -89.408) (xy 102.5779 -88.81618)
				(xy 104.65308 -88.81618) (xy 106.24058 -88.81618) (xy 106.84002 -88.21674) (xy 106.84002 -87.586058)
				(xy 107.031536 -87.394542) (xy 107.034584 -87.394542) (xy 107.184952 -87.244174) (xy 109.578648 -87.244174)
				(xy 109.701838 -87.120984) (xy 109.701838 -85.753194) (xy 109.455204 -85.50656) (xy 106.53522 -85.50656)
				(xy 100.15474 -85.50656) (xy 99.80168 -85.85962) (xy 99.80168 -85.86724) (xy 96.8502 -88.81872)
			)
		)
	)
	(zone
		(layer "In3.Cu")
		(hatch none 0.5)
		(connect_pads
			(clearance 0)
		)
		(min_thickness 0.25)
		(keepout
			(tracks not_allowed)
			(vias allowed)
			(pads allowed)
			(copperpour not_allowed)
			(footprints allowed)
		)
		(placement
			(enabled no)
			(sheetname "")
		)
		(fill
			(thermal_gap 0.5)
			(thermal_bridge_width 0.5)
			(island_removal_mode 0)
		)
		(polygon
			(pts
				(arc
					(start 481.973382 -125.222)
					(mid 480.229418 -125.222)
					(end 481.973382 -125.222)
				)
			)
		)
	)
	(zone
		(net "GND")
		(layer "In3.Cu")
		(hatch none 0.5)
		(connect_pads
			(clearance 0.5)
		)
		(min_thickness 0.25)
		(fill yes
			(thermal_gap 0.5)
			(thermal_bridge_width 0.5)
			(island_removal_mode 0)
		)
		(polygon
			(pts
				(arc
					(start -3.675126 5.542788)
					(mid -4.995762 4.995762)
					(end -5.542788 3.675126)
				)
				(arc
					(start -5.542788 -156.77515)
					(mid -5.137161 -157.937055)
					(end -4.096766 -158.594552)
				)
				(xy -4.031742 -158.6103) (xy 392.647424 -158.6103) (xy 392.648186 -158.611062) (xy 395.46149 -158.611062)
				(xy 395.49324 -158.642812)
				(arc
					(start 499.674896 -158.642812)
					(mid 500.848392 -158.228174)
					(end 501.500902 -157.168342)
				)
				(arc
					(start 501.500902 -111.810038)
					(mid 500.991406 -110.878754)
					(end 500.056658 -110.3757)
				)
				(xy 488.315 -110.3757) (xy 488.315 -110.565438)
				(arc
					(start 488.212638 -110.6678)
					(mid 487.948431 -110.986367)
					(end 487.561382 -110.839758)
				)
				(arc
					(start 487.561382 -110.839758)
					(mid 487.4768 -110.794491)
					(end 487.392218 -110.839758)
				)
				(arc
					(start 487.392218 -110.839758)
					(mid 487.0958 -110.998509)
					(end 486.799382 -110.839758)
				)
				(arc
					(start 486.799382 -110.839758)
					(mid 486.7148 -110.794491)
					(end 486.630218 -110.839758)
				)
				(arc
					(start 486.630218 -110.839758)
					(mid 486.230812 -110.982887)
					(end 485.977946 -110.642146)
				)
				(xy 485.775 -110.4392) (xy 485.775 -110.3503) (xy 427.5836 -110.3503) (xy 426.72 -109.4867) (xy 426.72 -108.6739)
				(xy 426.7327 -108.6612) (xy 426.7327 -79.434944) (xy 426.7327 -78.214982) (xy 426.7327 -68.2879)
				(xy 427.609 -67.4116)
				(arc
					(start 478.3963 -67.4116)
					(mid 478.834477 -67.161972)
					(end 479.007932 -66.688462)
				)
				(xy 479.007932 -63.078868) (xy 479.86442 -62.22238) (xy 480.614736 -62.22238) (xy 480.65563 -62.221872)
				(arc
					(start 499.674896 -62.221872)
					(mid 500.930712 -61.73672)
					(end 501.534176 -60.53328)
				)
				(xy 501.534176 -16.903954) (xy 501.532144 -16.902176) (xy 501.532144 -14.982444) (xy 501.03278 -14.48308)
				(xy 482.929184 -14.48308) (xy 480.732084 -12.28598) (xy 480.732084 1.05918) (xy 483.137464 3.46456)
				(xy 501.04548 3.46456) (xy 501.52046 3.93954) (xy 501.52046 5.02666) (xy 501.00738 5.53974) (xy 486.94594 5.53974)
				(xy 486.9434 5.5372) (xy 478.3074 5.5372) (xy 478.2947 5.5245) (xy 478.147888 5.5245) (xy 478.1296 5.542788)
				(xy 280.680414 5.542788) (xy 280.673302 5.542534) (xy 279.828498 5.542534) (xy 279.821386 5.542788)
				(xy 279.499314 5.542788) (xy 279.492202 5.542534) (xy 278.647398 5.542534) (xy 278.640286 5.542788)
				(xy 278.564594 5.542788) (xy 278.55799 5.542534) (xy 278.557736 5.542788) (xy 18.097246 5.535676)
			)
		)
		(polygon
			(pts
				(arc
					(start 370.834158 -77.667866)
					(mid 370.745258 -77.615499)
					(end 370.656358 -77.667866)
				)
				(arc
					(start 370.656358 -77.667866)
					(mid 370.597075 -77.746621)
					(end 370.518436 -77.806042)
				)
				(arc
					(start 370.518436 -77.806042)
					(mid 370.466069 -77.89488)
					(end 370.518436 -77.983588)
				)
				(arc
					(start 370.518436 -77.983588)
					(mid 370.701329 -78.294849)
					(end 370.518182 -78.605888)
				)
				(arc
					(start 370.518182 -78.605888)
					(mid 370.465815 -78.694788)
					(end 370.518182 -78.783688)
				)
				(arc
					(start 370.518182 -78.783688)
					(mid 370.596936 -78.84311)
					(end 370.656358 -78.921864)
				)
				(arc
					(start 370.656358 -78.921864)
					(mid 370.745258 -78.974231)
					(end 370.834158 -78.921864)
				)
				(arc
					(start 370.834158 -78.921864)
					(mid 371.145197 -78.73884)
					(end 371.456458 -78.92161)
				)
				(arc
					(start 371.456458 -78.92161)
					(mid 371.545296 -78.973977)
					(end 371.634004 -78.92161)
				)
				(arc
					(start 371.634004 -78.92161)
					(mid 371.693338 -78.843022)
					(end 371.771926 -78.783688)
				)
				(arc
					(start 371.771926 -78.783688)
					(mid 371.824071 -78.69498)
					(end 371.771926 -78.606142)
				)
				(arc
					(start 371.771926 -78.606142)
					(mid 371.588902 -78.29493)
					(end 371.771926 -77.983588)
				)
				(arc
					(start 371.771926 -77.983588)
					(mid 371.823941 -77.89488)
					(end 371.771926 -77.806042)
				)
				(arc
					(start 371.771926 -77.806042)
					(mid 371.693338 -77.746708)
					(end 371.634004 -77.66812)
				)
				(arc
					(start 371.634004 -77.66812)
					(mid 371.545296 -77.615975)
					(end 371.456458 -77.66812)
				)
				(arc
					(start 371.456458 -77.66812)
					(mid 371.145197 -77.851013)
					(end 370.834158 -77.667866)
				)
			)
		)
		(polygon
			(pts
				(xy 19.132042 -55.673244) (xy 13.030454 -55.673244) (xy 12.106402 -56.597296) (xy 12.106402 -66.189606)
				(xy 14.783816 -68.86702) (xy 18.957798 -68.86702) (xy 20.08378 -67.741038) (xy 20.08378 -56.624982)
			)
		)
	)
	(zone
		(layers "In3.Cu" "In4.Cu" "In5.Cu" "In6.Cu" "In7.Cu" "In8.Cu" "In9.Cu"
			"In12.Cu"
		)
		(hatch none 0.5)
		(connect_pads
			(clearance 0)
		)
		(min_thickness 0.25)
		(keepout
			(tracks not_allowed)
			(vias allowed)
			(pads allowed)
			(copperpour not_allowed)
			(footprints allowed)
		)
		(placement
			(enabled no)
			(sheetname "")
		)
		(fill yes
			(thermal_gap 0.5)
			(thermal_bridge_width 0.5)
			(island_removal_mode 0)
		)
		(polygon
			(pts
				(xy 469.033098 -67.42176) (xy 469.033098 -110.33633)
				(arc
					(start 428.390558 -110.33633)
					(mid 427.22546 -109.85373)
					(end 426.74286 -108.688632)
				)
				(arc
					(start 426.74286 -69.069458)
					(mid 427.22546 -67.90436)
					(end 428.390558 -67.42176)
				)
			)
		)
	)
	(zone
		(layers "In3.Cu" "In8.Cu")
		(hatch none 0.5)
		(connect_pads
			(clearance 0)
		)
		(min_thickness 0.25)
		(keepout
			(tracks not_allowed)
			(vias allowed)
			(pads allowed)
			(copperpour not_allowed)
			(footprints allowed)
		)
		(placement
			(enabled no)
			(sheetname "")
		)
		(fill yes
			(thermal_gap 0.5)
			(thermal_bridge_width 0.5)
			(island_removal_mode 0)
		)
		(polygon
			(pts
				(xy 469.51646 -141.79296) (xy 469.51646 -143.19504) (xy 470.91854 -143.19504) (xy 470.91854 -142.49654)
				(arc
					(start 470.8271 -142.49654)
					(mid 470.2175 -143.103605)
					(end 469.6079 -142.49654)
				)
				(arc
					(start 469.6079 -142.494)
					(mid 470.2175 -141.8844)
					(end 470.8271 -142.494)
				)
				(xy 470.91854 -142.494) (xy 470.91854 -141.79296)
			)
		)
	)
	(zone
		(layers "In3.Cu" "In8.Cu")
		(hatch none 0.5)
		(connect_pads
			(clearance 0)
		)
		(min_thickness 0.25)
		(keepout
			(tracks not_allowed)
			(vias allowed)
			(pads allowed)
			(copperpour not_allowed)
			(footprints allowed)
		)
		(placement
			(enabled no)
			(sheetname "")
		)
		(fill yes
			(thermal_gap 0.5)
			(thermal_bridge_width 0.5)
			(island_removal_mode 0)
		)
		(polygon
			(pts
				(arc
					(start 438.72404 3.81)
					(mid 436.815484 3.81)
					(end 438.72404 3.81)
				)
			)
		)
	)
	(zone
		(layers "In3.Cu" "In8.Cu")
		(hatch none 0.5)
		(connect_pads
			(clearance 0)
		)
		(min_thickness 0.25)
		(keepout
			(tracks not_allowed)
			(vias allowed)
			(pads allowed)
			(copperpour not_allowed)
			(footprints allowed)
		)
		(placement
			(enabled no)
			(sheetname "")
		)
		(fill yes
			(thermal_gap 0.5)
			(thermal_bridge_width 0.5)
			(island_removal_mode 0)
		)
		(polygon
			(pts
				(arc
					(start 27.840686 -26.67)
					(mid 26.641805 -26.67127)
					(end 27.840686 -26.67254)
				)
				(arc
					(start 27.749246 -26.67254)
					(mid 27.241246 -27.178006)
					(end 26.733246 -26.67254)
				)
				(arc
					(start 26.733246 -26.67)
					(mid 27.241246 -26.162)
					(end 27.749246 -26.67)
				)
			)
		)
	)
	(zone
		(layers "In3.Cu" "In8.Cu")
		(hatch none 0.5)
		(connect_pads
			(clearance 0)
		)
		(min_thickness 0.25)
		(keepout
			(tracks not_allowed)
			(vias allowed)
			(pads allowed)
			(copperpour not_allowed)
			(footprints allowed)
		)
		(placement
			(enabled no)
			(sheetname "")
		)
		(fill yes
			(thermal_gap 0.5)
			(thermal_bridge_width 0.5)
			(island_removal_mode 0)
		)
		(polygon
			(pts
				(arc
					(start 446.34404 3.81)
					(mid 444.435484 3.81)
					(end 446.34404 3.81)
				)
			)
		)
	)
	(zone
		(layers "In3.Cu" "In8.Cu")
		(hatch none 0.5)
		(connect_pads
			(clearance 0)
		)
		(min_thickness 0.25)
		(keepout
			(tracks not_allowed)
			(vias allowed)
			(pads allowed)
			(copperpour not_allowed)
			(footprints allowed)
		)
		(placement
			(enabled no)
			(sheetname "")
		)
		(fill yes
			(thermal_gap 0.5)
			(thermal_bridge_width 0.5)
			(island_removal_mode 0)
		)
		(polygon
			(pts
				(arc
					(start 489.420662 -129.156968)
					(mid 488.732322 -129.845308)
					(end 489.420662 -130.533648)
				)
				(arc
					(start 490.741462 -130.533648)
					(mid 491.227293 -130.332935)
					(end 491.429802 -129.847848)
				)
				(arc
					(start 491.338362 -129.847848)
					(mid 491.162639 -130.268281)
					(end 490.741462 -130.442208)
				)
				(arc
					(start 489.420662 -130.442208)
					(mid 488.999489 -130.268277)
					(end 488.823762 -129.847848)
				)
				(arc
					(start 488.823762 -129.845308)
					(mid 488.99859 -129.423236)
					(end 489.420662 -129.248408)
				)
				(arc
					(start 490.741462 -129.248408)
					(mid 491.163534 -129.423236)
					(end 491.338362 -129.845308)
				)
				(arc
					(start 491.429802 -129.845308)
					(mid 491.228192 -129.358578)
					(end 490.741462 -129.156968)
				)
			)
		)
	)
	(zone
		(layers "In3.Cu" "In8.Cu")
		(hatch none 0.5)
		(connect_pads
			(clearance 0)
		)
		(min_thickness 0.25)
		(keepout
			(tracks not_allowed)
			(vias allowed)
			(pads allowed)
			(copperpour not_allowed)
			(footprints allowed)
		)
		(placement
			(enabled no)
			(sheetname "")
		)
		(fill yes
			(thermal_gap 0.5)
			(thermal_bridge_width 0.5)
			(island_removal_mode 0)
		)
		(polygon
			(pts
				(arc
					(start 470.91854 -146.493992)
					(mid 469.516459 -146.495262)
					(end 470.91854 -146.496532)
				)
				(arc
					(start 470.8271 -146.496532)
					(mid 470.2175 -147.103597)
					(end 469.6079 -146.496532)
				)
				(arc
					(start 469.6079 -146.493992)
					(mid 470.2175 -145.884392)
					(end 470.8271 -146.493992)
				)
			)
		)
	)
	(zone
		(layers "In3.Cu" "In8.Cu")
		(hatch none 0.5)
		(connect_pads
			(clearance 0)
		)
		(min_thickness 0.25)
		(keepout
			(tracks not_allowed)
			(vias allowed)
			(pads allowed)
			(copperpour not_allowed)
			(footprints allowed)
		)
		(placement
			(enabled no)
			(sheetname "")
		)
		(fill yes
			(thermal_gap 0.5)
			(thermal_bridge_width 0.5)
			(island_removal_mode 0)
		)
		(polygon
			(pts
				(arc
					(start 16.26997 -118.679976)
					(mid 14.470126 -118.679976)
					(end 16.26997 -118.679976)
				)
			)
		)
	)
	(zone
		(layers "In3.Cu" "In8.Cu")
		(hatch none 0.5)
		(connect_pads
			(clearance 0)
		)
		(min_thickness 0.25)
		(keepout
			(tracks not_allowed)
			(vias allowed)
			(pads allowed)
			(copperpour not_allowed)
			(footprints allowed)
		)
		(placement
			(enabled no)
			(sheetname "")
		)
		(fill yes
			(thermal_gap 0.5)
			(thermal_bridge_width 0.5)
			(island_removal_mode 0)
		)
		(polygon
			(pts
				(arc
					(start 481.201984 -152.93467)
					(mid 479.469703 -152.93594)
					(end 481.201984 -152.93721)
				)
				(arc
					(start 481.110544 -152.93721)
					(mid 480.335844 -153.709374)
					(end 479.561144 -152.93721)
				)
				(arc
					(start 479.561144 -152.93467)
					(mid 480.335844 -152.15997)
					(end 481.110544 -152.93467)
				)
			)
		)
	)
	(zone
		(layers "In3.Cu" "In8.Cu")
		(hatch none 0.5)
		(connect_pads
			(clearance 0)
		)
		(min_thickness 0.25)
		(keepout
			(tracks not_allowed)
			(vias allowed)
			(pads allowed)
			(copperpour not_allowed)
			(footprints allowed)
		)
		(placement
			(enabled no)
			(sheetname "")
		)
		(fill yes
			(thermal_gap 0.5)
			(thermal_bridge_width 0.5)
			(island_removal_mode 0)
		)
		(polygon
			(pts
				(arc
					(start 496.802664 -153.849832)
					(mid 495.197383 -153.851102)
					(end 496.802664 -153.852372)
				)
				(arc
					(start 496.711224 -153.852372)
					(mid 496.000024 -154.561037)
					(end 495.288824 -153.852372)
				)
				(arc
					(start 495.288824 -153.849832)
					(mid 496.000024 -153.138632)
					(end 496.711224 -153.849832)
				)
			)
		)
	)
	(zone
		(layers "In3.Cu" "In8.Cu")
		(hatch none 0.5)
		(connect_pads
			(clearance 0)
		)
		(min_thickness 0.25)
		(keepout
			(tracks not_allowed)
			(vias allowed)
			(pads allowed)
			(copperpour not_allowed)
			(footprints allowed)
		)
		(placement
			(enabled no)
			(sheetname "")
		)
		(fill yes
			(thermal_gap 0.5)
			(thermal_bridge_width 0.5)
			(island_removal_mode 0)
		)
		(polygon
			(pts
				(arc
					(start 488.926632 -131.655312)
					(mid 487.575351 -131.656582)
					(end 488.926632 -131.657852)
				)
				(arc
					(start 488.835192 -131.657852)
					(mid 488.250992 -132.239518)
					(end 487.666792 -131.657852)
				)
				(arc
					(start 487.666792 -131.655312)
					(mid 488.250992 -131.071112)
					(end 488.835192 -131.655312)
				)
			)
		)
	)
	(zone
		(layers "In3.Cu" "In8.Cu")
		(hatch none 0.5)
		(connect_pads
			(clearance 0)
		)
		(min_thickness 0.25)
		(keepout
			(tracks not_allowed)
			(vias allowed)
			(pads allowed)
			(copperpour not_allowed)
			(footprints allowed)
		)
		(placement
			(enabled no)
			(sheetname "")
		)
		(fill yes
			(thermal_gap 0.5)
			(thermal_bridge_width 0.5)
			(island_removal_mode 0)
		)
		(polygon
			(pts
				(arc
					(start 446.34404 1.27)
					(mid 444.435484 1.27)
					(end 446.34404 1.27)
				)
			)
		)
	)
	(zone
		(layers "In3.Cu" "In8.Cu")
		(hatch none 0.5)
		(connect_pads
			(clearance 0)
		)
		(min_thickness 0.25)
		(keepout
			(tracks not_allowed)
			(vias allowed)
			(pads allowed)
			(copperpour not_allowed)
			(footprints allowed)
		)
		(placement
			(enabled no)
			(sheetname "")
		)
		(fill yes
			(thermal_gap 0.5)
			(thermal_bridge_width 0.5)
			(island_removal_mode 0)
		)
		(polygon
			(pts
				(arc
					(start 479.076258 -129.156968)
					(mid 478.387918 -129.845308)
					(end 479.076258 -130.533648)
				)
				(arc
					(start 479.685858 -130.533648)
					(mid 480.171689 -130.332935)
					(end 480.374198 -129.847848)
				)
				(arc
					(start 480.282758 -129.847848)
					(mid 480.107035 -130.268281)
					(end 479.685858 -130.442208)
				)
				(arc
					(start 479.076258 -130.442208)
					(mid 478.655085 -130.268277)
					(end 478.479358 -129.847848)
				)
				(arc
					(start 478.479358 -129.845308)
					(mid 478.654186 -129.423236)
					(end 479.076258 -129.248408)
				)
				(arc
					(start 479.685858 -129.248408)
					(mid 480.10793 -129.423236)
					(end 480.282758 -129.845308)
				)
				(arc
					(start 480.374198 -129.845308)
					(mid 480.172588 -129.358578)
					(end 479.685858 -129.156968)
				)
			)
		)
	)
	(zone
		(layers "In3.Cu" "In8.Cu")
		(hatch none 0.5)
		(connect_pads
			(clearance 0)
		)
		(min_thickness 0.25)
		(keepout
			(tracks not_allowed)
			(vias allowed)
			(pads allowed)
			(copperpour not_allowed)
			(footprints allowed)
		)
		(placement
			(enabled no)
			(sheetname "")
		)
		(fill yes
			(thermal_gap 0.5)
			(thermal_bridge_width 0.5)
			(island_removal_mode 0)
		)
		(polygon
			(pts
				(arc
					(start 463.01025 -157.140402)
					(mid 461.379569 -157.141672)
					(end 463.01025 -157.142942)
				)
				(arc
					(start 462.91881 -157.142942)
					(mid 462.19491 -157.864306)
					(end 461.47101 -157.142942)
				)
				(arc
					(start 461.47101 -157.140402)
					(mid 462.19491 -156.416502)
					(end 462.91881 -157.140402)
				)
			)
		)
	)
	(zone
		(layers "In3.Cu" "In8.Cu")
		(hatch none 0.5)
		(connect_pads
			(clearance 0)
		)
		(min_thickness 0.25)
		(keepout
			(tracks not_allowed)
			(vias allowed)
			(pads allowed)
			(copperpour not_allowed)
			(footprints allowed)
		)
		(placement
			(enabled no)
			(sheetname "")
		)
		(fill yes
			(thermal_gap 0.5)
			(thermal_bridge_width 0.5)
			(island_removal_mode 0)
		)
		(polygon
			(pts
				(arc
					(start 489.776262 -134.577074)
					(mid 489.087922 -135.265414)
					(end 489.776262 -135.953754)
				)
				(arc
					(start 490.385862 -135.953754)
					(mid 490.871693 -135.753041)
					(end 491.074202 -135.267954)
				)
				(arc
					(start 490.982762 -135.267954)
					(mid 490.807039 -135.688387)
					(end 490.385862 -135.862314)
				)
				(arc
					(start 489.776262 -135.862314)
					(mid 489.355089 -135.688383)
					(end 489.179362 -135.267954)
				)
				(arc
					(start 489.179362 -135.265414)
					(mid 489.35419 -134.843342)
					(end 489.776262 -134.668514)
				)
				(arc
					(start 490.385862 -134.668514)
					(mid 490.807934 -134.843342)
					(end 490.982762 -135.265414)
				)
				(arc
					(start 491.074202 -135.265414)
					(mid 490.872592 -134.778684)
					(end 490.385862 -134.577074)
				)
			)
		)
	)
	(zone
		(layers "In3.Cu" "In8.Cu")
		(hatch none 0.5)
		(connect_pads
			(clearance 0)
		)
		(min_thickness 0.25)
		(keepout
			(tracks not_allowed)
			(vias allowed)
			(pads allowed)
			(copperpour not_allowed)
			(footprints allowed)
		)
		(placement
			(enabled no)
			(sheetname "")
		)
		(fill yes
			(thermal_gap 0.5)
			(thermal_bridge_width 0.5)
			(island_removal_mode 0)
		)
		(polygon
			(pts
				(arc
					(start 398.42694 3.81)
					(mid 396.593059 3.80873)
					(end 398.42694 3.80746)
				)
				(arc
					(start 398.3355 3.80746)
					(mid 397.51 2.984496)
					(end 396.6845 3.80746)
				)
				(arc
					(start 396.6845 3.81)
					(mid 397.51 4.6355)
					(end 398.3355 3.81)
				)
			)
		)
	)
	(zone
		(layers "In3.Cu" "In8.Cu")
		(hatch none 0.5)
		(connect_pads
			(clearance 0)
		)
		(min_thickness 0.25)
		(keepout
			(tracks not_allowed)
			(vias allowed)
			(pads allowed)
			(copperpour not_allowed)
			(footprints allowed)
		)
		(placement
			(enabled no)
			(sheetname "")
		)
		(fill yes
			(thermal_gap 0.5)
			(thermal_bridge_width 0.5)
			(island_removal_mode 0)
		)
		(polygon
			(pts
				(arc
					(start 438.72404 1.27)
					(mid 436.815484 1.27)
					(end 438.72404 1.27)
				)
			)
		)
	)
	(zone
		(layers "In3.Cu" "In8.Cu")
		(hatch none 0.5)
		(connect_pads
			(clearance 0)
		)
		(min_thickness 0.25)
		(keepout
			(tracks not_allowed)
			(vias allowed)
			(pads allowed)
			(copperpour not_allowed)
			(footprints allowed)
		)
		(placement
			(enabled no)
			(sheetname "")
		)
		(fill yes
			(thermal_gap 0.5)
			(thermal_bridge_width 0.5)
			(island_removal_mode 0)
		)
		(polygon
			(pts
				(arc
					(start 478.720658 -134.577074)
					(mid 478.032318 -135.265414)
					(end 478.720658 -135.953754)
				)
				(arc
					(start 480.041458 -135.953754)
					(mid 480.527289 -135.753041)
					(end 480.729798 -135.267954)
				)
				(arc
					(start 480.638358 -135.267954)
					(mid 480.462635 -135.688387)
					(end 480.041458 -135.862314)
				)
				(arc
					(start 478.720658 -135.862314)
					(mid 478.299485 -135.688383)
					(end 478.123758 -135.267954)
				)
				(arc
					(start 478.123758 -135.265414)
					(mid 478.298586 -134.843342)
					(end 478.720658 -134.668514)
				)
				(arc
					(start 480.041458 -134.668514)
					(mid 480.46353 -134.843342)
					(end 480.638358 -135.265414)
				)
				(arc
					(start 480.729798 -135.265414)
					(mid 480.528188 -134.778684)
					(end 480.041458 -134.577074)
				)
			)
		)
	)
	(zone
		(layers "In3.Cu" "In10.Cu")
		(hatch none 0.5)
		(connect_pads
			(clearance 0)
		)
		(min_thickness 0.25)
		(keepout
			(tracks not_allowed)
			(vias allowed)
			(pads allowed)
			(copperpour not_allowed)
			(footprints allowed)
		)
		(placement
			(enabled no)
			(sheetname "")
		)
		(fill yes
			(thermal_gap 0.5)
			(thermal_bridge_width 0.5)
			(island_removal_mode 0)
		)
		(polygon
			(pts
				(arc
					(start 4.945888 -110.259876)
					(mid 2.934207 -110.261146)
					(end 4.945888 -110.262416)
				)
				(arc
					(start 4.854448 -110.262416)
					(mid 3.940048 -111.17428)
					(end 3.025648 -110.262416)
				)
				(arc
					(start 3.025648 -110.259876)
					(mid 3.940048 -109.345476)
					(end 4.854448 -110.259876)
				)
			)
		)
	)
	(zone
		(layers "In3.Cu" "In10.Cu")
		(hatch none 0.5)
		(connect_pads
			(clearance 0)
		)
		(min_thickness 0.25)
		(keepout
			(tracks not_allowed)
			(vias allowed)
			(pads allowed)
			(copperpour not_allowed)
			(footprints allowed)
		)
		(placement
			(enabled no)
			(sheetname "")
		)
		(fill yes
			(thermal_gap 0.5)
			(thermal_bridge_width 0.5)
			(island_removal_mode 0)
		)
		(polygon
			(pts
				(arc
					(start 354.374196 -6.089904)
					(mid 352.895915 -6.091174)
					(end 354.374196 -6.092444)
				)
				(arc
					(start 354.282756 -6.092444)
					(mid 353.635056 -6.737609)
					(end 352.987356 -6.092444)
				)
				(arc
					(start 352.987356 -6.089904)
					(mid 353.635056 -5.442204)
					(end 354.282756 -6.089904)
				)
			)
		)
	)
	(zone
		(layers "In3.Cu" "In10.Cu")
		(hatch none 0.5)
		(connect_pads
			(clearance 0)
		)
		(min_thickness 0.25)
		(keepout
			(tracks not_allowed)
			(vias allowed)
			(pads allowed)
			(copperpour not_allowed)
			(footprints allowed)
		)
		(placement
			(enabled no)
			(sheetname "")
		)
		(fill yes
			(thermal_gap 0.5)
			(thermal_bridge_width 0.5)
			(island_removal_mode 0)
		)
		(polygon
			(pts
				(arc
					(start 388.640574 -6.087872)
					(mid 387.009893 -6.089142)
					(end 388.640574 -6.090412)
				)
				(arc
					(start 388.549134 -6.090412)
					(mid 387.825234 -6.811776)
					(end 387.101334 -6.090412)
				)
				(arc
					(start 387.101334 -6.087872)
					(mid 387.825234 -5.363972)
					(end 388.549134 -6.087872)
				)
			)
		)
	)
	(zone
		(layers "In3.Cu" "In10.Cu")
		(hatch none 0.5)
		(connect_pads
			(clearance 0)
		)
		(min_thickness 0.25)
		(keepout
			(tracks not_allowed)
			(vias allowed)
			(pads allowed)
			(copperpour not_allowed)
			(footprints allowed)
		)
		(placement
			(enabled no)
			(sheetname "")
		)
		(fill yes
			(thermal_gap 0.5)
			(thermal_bridge_width 0.5)
			(island_removal_mode 0)
		)
		(polygon
			(pts
				(arc
					(start 4.71424 0)
					(mid -4.71424 -0.00127)
					(end 4.71424 -0.00254)
				)
				(arc
					(start 3.0353 -0.00254)
					(mid 0 -3.035301)
					(end -3.0353 -0.00254)
				)
				(arc
					(start -3.0353 0)
					(mid 0 3.0353)
					(end 3.0353 0)
				)
			)
		)
	)
	(zone
		(layers "In3.Cu" "In10.Cu")
		(hatch none 0.5)
		(connect_pads
			(clearance 0)
		)
		(min_thickness 0.25)
		(keepout
			(tracks not_allowed)
			(vias allowed)
			(pads allowed)
			(copperpour not_allowed)
			(footprints allowed)
		)
		(placement
			(enabled no)
			(sheetname "")
		)
		(fill yes
			(thermal_gap 0.5)
			(thermal_bridge_width 0.5)
			(island_removal_mode 0)
		)
		(polygon
			(pts
				(arc
					(start 478.74047 -6.087872)
					(mid 477.109789 -6.089142)
					(end 478.74047 -6.090412)
				)
				(arc
					(start 478.64903 -6.090412)
					(mid 477.92513 -6.811776)
					(end 477.20123 -6.090412)
				)
				(arc
					(start 477.20123 -6.087872)
					(mid 477.92513 -5.363972)
					(end 478.64903 -6.087872)
				)
			)
		)
	)
	(zone
		(layers "In3.Cu" "In10.Cu")
		(hatch none 0.5)
		(connect_pads
			(clearance 0)
		)
		(min_thickness 0.25)
		(keepout
			(tracks not_allowed)
			(vias allowed)
			(pads allowed)
			(copperpour not_allowed)
			(footprints allowed)
		)
		(placement
			(enabled no)
			(sheetname "")
		)
		(fill yes
			(thermal_gap 0.5)
			(thermal_bridge_width 0.5)
			(island_removal_mode 0)
		)
		(polygon
			(pts
				(arc
					(start 495.83594 -57.838594)
					(mid 495.2111 -57.213754)
					(end 494.58626 -57.838594)
				)
				(arc
					(start 494.58626 -58.321194)
					(mid 495.2111 -58.946034)
					(end 495.83594 -58.321194)
				)
				(xy 495.83594 -57.841134) (xy 495.7445 -57.841134)
				(arc
					(start 495.7445 -58.321194)
					(mid 495.2111 -58.854594)
					(end 494.6777 -58.321194)
				)
				(arc
					(start 494.6777 -57.838594)
					(mid 495.2111 -57.305194)
					(end 495.7445 -57.838594)
				)
			)
		)
	)
	(zone
		(layers "In3.Cu" "In10.Cu")
		(hatch none 0.5)
		(connect_pads
			(clearance 0)
		)
		(min_thickness 0.25)
		(keepout
			(tracks not_allowed)
			(vias allowed)
			(pads allowed)
			(copperpour not_allowed)
			(footprints allowed)
		)
		(placement
			(enabled no)
			(sheetname "")
		)
		(fill yes
			(thermal_gap 0.5)
			(thermal_bridge_width 0.5)
			(island_removal_mode 0)
		)
		(polygon
			(pts
				(arc
					(start 496.00612 -60.64123)
					(mid 495.24779 -60.033524)
					(end 494.58626 -60.74537)
				)
				(arc
					(start 494.58626 -61.35497)
					(mid 494.79531 -61.85966)
					(end 495.3 -62.06871)
				)
				(arc
					(start 496.443 -62.06871)
					(mid 497.129547 -61.550105)
					(end 496.818412 -60.74791)
				)
				(arc
					(start 496.579906 -60.74791)
					(mid 497.061483 -61.423846)
					(end 496.443 -61.97727)
				)
				(arc
					(start 495.3 -61.97727)
					(mid 494.859967 -61.795003)
					(end 494.6777 -61.35497)
				)
				(arc
					(start 494.6777 -60.74537)
					(mid 495.293648 -60.123102)
					(end 495.922046 -60.73267)
				)
				(arc
					(start 496.443 -60.73267)
					(mid 496.505807 -60.735848)
					(end 496.567968 -60.74537)
				)
				(arc
					(start 496.814348 -60.74537)
					(mid 496.635845 -60.667713)
					(end 496.443 -60.64123)
				)
			)
		)
	)
	(zone
		(layers "In3.Cu" "In10.Cu")
		(hatch none 0.5)
		(connect_pads
			(clearance 0)
		)
		(min_thickness 0.25)
		(keepout
			(tracks not_allowed)
			(vias allowed)
			(pads allowed)
			(copperpour not_allowed)
			(footprints allowed)
		)
		(placement
			(enabled no)
			(sheetname "")
		)
		(fill yes
			(thermal_gap 0.5)
			(thermal_bridge_width 0.5)
			(island_removal_mode 0)
		)
		(polygon
			(pts
				(arc
					(start 495.3 -52.091082)
					(mid 494.79531 -52.300132)
					(end 494.58626 -52.804822)
				)
				(arc
					(start 494.58626 -53.414422)
					(mid 495.247791 -54.12625)
					(end 496.00612 -53.518562)
				)
				(arc
					(start 496.443 -53.518562)
					(mid 496.538474 -53.512079)
					(end 496.63223 -53.492908)
				)
				(arc
					(start 496.63223 -53.492908)
					(mid 496.786537 -53.328271)
					(end 496.999006 -53.25237)
				)
				(arc
					(start 496.999006 -53.25237)
					(mid 497.115738 -53.043287)
					(end 497.15674 -52.807362)
				)
				(arc
					(start 497.0653 -52.807362)
					(mid 497.03513 -52.996254)
					(end 496.948968 -53.167026)
				)
				(arc
					(start 496.948968 -53.167026)
					(mid 496.736335 -53.251756)
					(end 496.574064 -53.413152)
				)
				(arc
					(start 496.574064 -53.413152)
					(mid 496.508903 -53.423611)
					(end 496.443 -53.427122)
				)
				(arc
					(start 495.922046 -53.427122)
					(mid 495.29365 -54.036565)
					(end 494.6777 -53.414422)
				)
				(arc
					(start 494.6777 -52.804822)
					(mid 494.859967 -52.364789)
					(end 495.3 -52.182522)
				)
				(arc
					(start 496.443 -52.182522)
					(mid 496.883033 -52.364789)
					(end 497.0653 -52.804822)
				)
				(arc
					(start 497.15674 -52.804822)
					(mid 496.94769 -52.300132)
					(end 496.443 -52.091082)
				)
			)
		)
	)
	(zone
		(layers "In3.Cu" "In10.Cu")
		(hatch none 0.5)
		(connect_pads
			(clearance 0)
		)
		(min_thickness 0.25)
		(keepout
			(tracks not_allowed)
			(vias allowed)
			(pads allowed)
			(copperpour not_allowed)
			(footprints allowed)
		)
		(placement
			(enabled no)
			(sheetname "")
		)
		(fill yes
			(thermal_gap 0.5)
			(thermal_bridge_width 0.5)
			(island_removal_mode 0)
		)
		(polygon
			(pts
				(arc
					(start 498.8052 -53.604922)
					(mid 497.834918 -53.606192)
					(end 498.8052 -53.607462)
				)
				(arc
					(start 498.71376 -53.607462)
					(mid 498.32006 -53.99863)
					(end 497.92636 -53.607462)
				)
				(arc
					(start 497.92636 -53.604922)
					(mid 498.32006 -53.211222)
					(end 498.71376 -53.604922)
				)
			)
		)
	)
	(zone
		(layers "In3.Cu" "In10.Cu")
		(hatch none 0.5)
		(connect_pads
			(clearance 0)
		)
		(min_thickness 0.25)
		(keepout
			(tracks not_allowed)
			(vias allowed)
			(pads allowed)
			(copperpour not_allowed)
			(footprints allowed)
		)
		(placement
			(enabled no)
			(sheetname "")
		)
		(fill yes
			(thermal_gap 0.5)
			(thermal_bridge_width 0.5)
			(island_removal_mode 0)
		)
		(polygon
			(pts
				(arc
					(start 495.83594 -55.838598)
					(mid 495.2111 -55.213758)
					(end 494.58626 -55.838598)
				)
				(arc
					(start 494.58626 -56.321198)
					(mid 495.2111 -56.946038)
					(end 495.83594 -56.321198)
				)
				(xy 495.83594 -55.841138) (xy 495.7445 -55.841138)
				(arc
					(start 495.7445 -56.321198)
					(mid 495.2111 -56.854598)
					(end 494.6777 -56.321198)
				)
				(arc
					(start 494.6777 -55.838598)
					(mid 495.2111 -55.305198)
					(end 495.7445 -55.838598)
				)
			)
		)
	)
	(zone
		(layers "In3.Cu" "In10.Cu")
		(hatch none 0.5)
		(connect_pads
			(clearance 0)
		)
		(min_thickness 0.25)
		(keepout
			(tracks not_allowed)
			(vias allowed)
			(pads allowed)
			(copperpour not_allowed)
			(footprints allowed)
		)
		(placement
			(enabled no)
			(sheetname "")
		)
		(fill yes
			(thermal_gap 0.5)
			(thermal_bridge_width 0.5)
			(island_removal_mode 0)
		)
		(polygon
			(pts
				(arc
					(start 6.512052 -45.310044)
					(mid 2.747772 -45.311314)
					(end 6.512052 -45.312584)
				)
				(arc
					(start 6.420612 -45.312584)
					(mid 4.629912 -47.100746)
					(end 2.839212 -45.312584)
				)
				(arc
					(start 2.839212 -45.310044)
					(mid 4.629912 -43.519344)
					(end 6.420612 -45.310044)
				)
			)
		)
	)
	(zone
		(layers "In3.Cu" "In10.Cu")
		(hatch none 0.5)
		(connect_pads
			(clearance 0)
		)
		(min_thickness 0.25)
		(keepout
			(tracks not_allowed)
			(vias allowed)
			(pads allowed)
			(copperpour not_allowed)
			(footprints allowed)
		)
		(placement
			(enabled no)
			(sheetname "")
		)
		(fill yes
			(thermal_gap 0.5)
			(thermal_bridge_width 0.5)
			(island_removal_mode 0)
		)
		(polygon
			(pts
				(arc
					(start 31.48076 -36.964874)
					(mid 29.469079 -36.966144)
					(end 31.48076 -36.967414)
				)
				(arc
					(start 31.38932 -36.967414)
					(mid 30.47492 -37.879278)
					(end 29.56052 -36.967414)
				)
				(arc
					(start 29.56052 -36.964874)
					(mid 30.47492 -36.050474)
					(end 31.38932 -36.964874)
				)
			)
		)
	)
	(zone
		(layers "In3.Cu" "In10.Cu")
		(hatch none 0.5)
		(connect_pads
			(clearance 0)
		)
		(min_thickness 0.25)
		(keepout
			(tracks not_allowed)
			(vias allowed)
			(pads allowed)
			(copperpour not_allowed)
			(footprints allowed)
		)
		(placement
			(enabled no)
			(sheetname "")
		)
		(fill yes
			(thermal_gap 0.5)
			(thermal_bridge_width 0.5)
			(island_removal_mode 0)
		)
		(polygon
			(pts
				(arc
					(start 1.382014 -45.310044)
					(mid -2.382266 -45.311314)
					(end 1.382014 -45.312584)
				)
				(arc
					(start 1.290574 -45.312584)
					(mid -0.500126 -47.100746)
					(end -2.290826 -45.312584)
				)
				(arc
					(start -2.290826 -45.310044)
					(mid -0.500126 -43.519344)
					(end 1.290574 -45.310044)
				)
			)
		)
	)
	(zone
		(layers "In3.Cu" "In10.Cu")
		(hatch none 0.5)
		(connect_pads
			(clearance 0)
		)
		(min_thickness 0.25)
		(keepout
			(tracks not_allowed)
			(vias allowed)
			(pads allowed)
			(copperpour not_allowed)
			(footprints allowed)
		)
		(placement
			(enabled no)
			(sheetname "")
		)
		(fill yes
			(thermal_gap 0.5)
			(thermal_bridge_width 0.5)
			(island_removal_mode 0)
		)
		(polygon
			(pts
				(arc
					(start 499.766082 -51.866038)
					(mid 499.052342 -52.579778)
					(end 499.766082 -53.293518)
				)
				(arc
					(start 500.934482 -53.293518)
					(mid 501.438274 -53.085366)
					(end 501.648222 -52.582318)
				)
				(arc
					(start 501.556782 -52.582318)
					(mid 501.373619 -53.020711)
					(end 500.934482 -53.202078)
				)
				(arc
					(start 499.766082 -53.202078)
					(mid 499.326948 -53.020708)
					(end 499.143782 -52.582318)
				)
				(arc
					(start 499.143782 -52.579778)
					(mid 499.326049 -52.139745)
					(end 499.766082 -51.957478)
				)
				(arc
					(start 500.934482 -51.957478)
					(mid 501.374515 -52.139745)
					(end 501.556782 -52.579778)
				)
				(arc
					(start 501.648222 -52.579778)
					(mid 501.439172 -52.075088)
					(end 500.934482 -51.866038)
				)
			)
		)
	)
	(zone
		(layers "In3.Cu" "In10.Cu")
		(hatch none 0.5)
		(connect_pads
			(clearance 0)
		)
		(min_thickness 0.25)
		(keepout
			(tracks not_allowed)
			(vias allowed)
			(pads allowed)
			(copperpour not_allowed)
			(footprints allowed)
		)
		(placement
			(enabled no)
			(sheetname "")
		)
		(fill yes
			(thermal_gap 0.5)
			(thermal_bridge_width 0.5)
			(island_removal_mode 0)
		)
		(polygon
			(pts
				(arc
					(start 419.210998 0.08001)
					(mid 417.631117 0.07874)
					(end 419.210998 0.07747)
				)
				(arc
					(start 419.119558 0.07747)
					(mid 418.421058 -0.618495)
					(end 417.722558 0.07747)
				)
				(arc
					(start 417.722558 0.08001)
					(mid 418.421058 0.77851)
					(end 419.119558 0.08001)
				)
			)
		)
	)
	(zone
		(layers "In3.Cu" "In10.Cu")
		(hatch none 0.5)
		(connect_pads
			(clearance 0)
		)
		(min_thickness 0.25)
		(keepout
			(tracks not_allowed)
			(vias allowed)
			(pads allowed)
			(copperpour not_allowed)
			(footprints allowed)
		)
		(placement
			(enabled no)
			(sheetname "")
		)
		(fill yes
			(thermal_gap 0.5)
			(thermal_bridge_width 0.5)
			(island_removal_mode 0)
		)
		(polygon
			(pts
				(xy 9.367774 -43.427904) (xy 9.367774 -47.192184) (xy 13.132054 -47.192184) (xy 13.132054 -45.312584)
				(arc
					(start 13.040614 -45.312584)
					(mid 11.249914 -47.100746)
					(end 9.459214 -45.312584)
				)
				(arc
					(start 9.459214 -45.310044)
					(mid 11.249914 -43.519344)
					(end 13.040614 -45.310044)
				)
				(xy 13.132054 -45.310044) (xy 13.132054 -43.427904)
			)
		)
	)
	(zone
		(layers "In3.Cu" "In10.Cu")
		(hatch none 0.5)
		(connect_pads
			(clearance 0)
		)
		(min_thickness 0.25)
		(keepout
			(tracks not_allowed)
			(vias allowed)
			(pads allowed)
			(copperpour not_allowed)
			(footprints allowed)
		)
		(placement
			(enabled no)
			(sheetname "")
		)
		(fill yes
			(thermal_gap 0.5)
			(thermal_bridge_width 0.5)
			(island_removal_mode 0)
		)
		(polygon
			(pts
				(arc
					(start 498.8052 -60.55487)
					(mid 497.834918 -60.55614)
					(end 498.8052 -60.55741)
				)
				(arc
					(start 498.71376 -60.55741)
					(mid 498.32006 -60.948578)
					(end 497.92636 -60.55741)
				)
				(arc
					(start 497.92636 -60.55487)
					(mid 498.32006 -60.16117)
					(end 498.71376 -60.55487)
				)
			)
		)
	)
	(zone
		(layers "In3.Cu" "In10.Cu")
		(hatch none 0.5)
		(connect_pads
			(clearance 0)
		)
		(min_thickness 0.25)
		(keepout
			(tracks not_allowed)
			(vias allowed)
			(pads allowed)
			(copperpour not_allowed)
			(footprints allowed)
		)
		(placement
			(enabled no)
			(sheetname "")
		)
		(fill yes
			(thermal_gap 0.5)
			(thermal_bridge_width 0.5)
			(island_removal_mode 0)
		)
		(polygon
			(pts
				(arc
					(start 385.274312 -6.089904)
					(mid 383.796031 -6.091174)
					(end 385.274312 -6.092444)
				)
				(arc
					(start 385.182872 -6.092444)
					(mid 384.535172 -6.737609)
					(end 383.887472 -6.092444)
				)
				(arc
					(start 383.887472 -6.089904)
					(mid 384.535172 -5.442204)
					(end 385.182872 -6.089904)
				)
			)
		)
	)
	(zone
		(layers "In3.Cu" "In10.Cu")
		(hatch none 0.5)
		(connect_pads
			(clearance 0)
		)
		(min_thickness 0.25)
		(keepout
			(tracks not_allowed)
			(vias allowed)
			(pads allowed)
			(copperpour not_allowed)
			(footprints allowed)
		)
		(placement
			(enabled no)
			(sheetname "")
		)
		(fill yes
			(thermal_gap 0.5)
			(thermal_bridge_width 0.5)
			(island_removal_mode 0)
		)
		(polygon
			(pts
				(arc
					(start 413.328866 -76.883768)
					(mid 406.110186 -76.885038)
					(end 413.328866 -76.886308)
				)
				(arc
					(start 413.237426 -76.886308)
					(mid 409.719526 -80.401669)
					(end 406.201626 -76.886308)
				)
				(arc
					(start 406.201626 -76.883768)
					(mid 409.719526 -73.365868)
					(end 413.237426 -76.883768)
				)
			)
		)
	)
	(zone
		(layers "In3.Cu" "In10.Cu")
		(hatch none 0.5)
		(connect_pads
			(clearance 0)
		)
		(min_thickness 0.25)
		(keepout
			(tracks not_allowed)
			(vias allowed)
			(pads allowed)
			(copperpour not_allowed)
			(footprints allowed)
		)
		(placement
			(enabled no)
			(sheetname "")
		)
		(fill yes
			(thermal_gap 0.5)
			(thermal_bridge_width 0.5)
			(island_removal_mode 0)
		)
		(polygon
			(pts
				(arc
					(start 499.766082 -60.866274)
					(mid 499.052342 -61.580014)
					(end 499.766082 -62.293754)
				)
				(arc
					(start 500.934482 -62.293754)
					(mid 501.438274 -62.085602)
					(end 501.648222 -61.582554)
				)
				(arc
					(start 501.556782 -61.582554)
					(mid 501.373619 -62.020947)
					(end 500.934482 -62.202314)
				)
				(arc
					(start 499.766082 -62.202314)
					(mid 499.326948 -62.020944)
					(end 499.143782 -61.582554)
				)
				(arc
					(start 499.143782 -61.580014)
					(mid 499.326049 -61.139981)
					(end 499.766082 -60.957714)
				)
				(arc
					(start 500.934482 -60.957714)
					(mid 501.374515 -61.139981)
					(end 501.556782 -61.580014)
				)
				(arc
					(start 501.648222 -61.580014)
					(mid 501.439172 -61.075324)
					(end 500.934482 -60.866274)
				)
			)
		)
	)
	(zone
		(net "VR_FET_SW_P12V_STBY_PVCCIO_CPU0")
		(layer "In4.Cu")
		(hatch none 0.5)
		(connect_pads
			(clearance 0.5)
		)
		(min_thickness 0.25)
		(fill yes
			(thermal_gap 0.5)
			(thermal_bridge_width 0.5)
			(island_removal_mode 0)
		)
		(polygon
			(pts
				(xy 352.2726 -103.505) (xy 352.6282 -103.1494) (xy 352.6282 -100.7618) (xy 352.2218 -100.3554) (xy 350.4946 -100.3554)
				(xy 350.1898 -100.0506) (xy 350.1898 -97.3836) (xy 351.0534 -96.52) (xy 351.0534 -94.0054) (xy 350.774 -93.726)
				(xy 348.869 -93.726) (xy 344.143838 -93.726) (xy 343.408 -94.461838) (xy 343.408 -95.377) (xy 343.408 -99.568)
				(xy 346.9132 -103.0732) (xy 347.345 -103.505)
			)
		)
	)
	(zone
		(net "VR_FET_SW_P12V_STBY_PVCCIN_CPU0")
		(layer "In4.Cu")
		(hatch none 0.5)
		(connect_pads
			(clearance 0.5)
		)
		(min_thickness 0.25)
		(fill yes
			(thermal_gap 0.5)
			(thermal_bridge_width 0.5)
			(island_removal_mode 0)
		)
		(polygon
			(pts
				(xy 191.9986 -100.5586) (xy 192.8114 -101.3714) (xy 197.1294 -101.3714) (xy 198.3486 -100.1522)
				(xy 199.0852 -99.4156) (xy 199.0852 -94.2848) (xy 199.0852 -93.2688) (xy 199.0852 -86.0806) (xy 199.0852 -85.6234)
				(xy 199.0852 -69.6976) (xy 199.0852 -69.1896) (xy 199.0852 -61.8998) (xy 199.0852 -61.087) (xy 199.0852 -55.78094)
				(xy 198.3232 -55.01894) (xy 197.53326 -54.229) (xy 195.83908 -54.229) (xy 194.691 -53.08092) (xy 190.06312 -53.08092)
				(xy 187.4774 -50.4952) (xy 181.82844 -50.4952) (xy 178.4858 -50.4952) (xy 177.7238 -51.2572) (xy 177.7238 -59.5376)
				(xy 178.1302 -59.944) (xy 185.5978 -59.944) (xy 186.4487 -60.7949) (xy 186.4487 -69.6849) (xy 186.5884 -69.8246)
				(xy 186.5884 -73.3044) (xy 188.5188 -75.2348) (xy 188.5188 -95.7834) (xy 188.5315 -95.7961) (xy 188.5315 -99.1997)
				(xy 189.8904 -100.5586)
			)
		)
	)
	(zone
		(layer "In4.Cu")
		(hatch none 0.5)
		(connect_pads
			(clearance 0)
		)
		(min_thickness 0.25)
		(keepout
			(tracks not_allowed)
			(vias allowed)
			(pads allowed)
			(copperpour not_allowed)
			(footprints allowed)
		)
		(placement
			(enabled no)
			(sheetname "")
		)
		(fill
			(thermal_gap 0.5)
			(thermal_bridge_width 0.5)
			(island_removal_mode 0)
		)
		(polygon
			(pts
				(arc
					(start 440.077606 -127.018288)
					(mid 440.599895 -126.94534)
					(end 440.123072 -127.170434)
				)
				(xy 439.93435 -127.359156) (xy 439.93435 -127.40513)
				(arc
					(start 440.344306 -127.40513)
					(mid 440.727846 -127.02159)
					(end 440.344306 -126.63805)
				)
				(arc
					(start 439.07456 -126.63805)
					(mid 438.690766 -127.021463)
					(end 439.074306 -127.40513)
				)
				(xy 439.50255 -127.40513) (xy 439.50255 -127.359156)
				(arc
					(start 439.302652 -127.159258)
					(mid 438.814621 -126.961107)
					(end 439.33999 -126.998984)
				)
				(xy 439.64225 -127.301244) (xy 439.64225 -127.40513) (xy 439.79465 -127.40513) (xy 439.79465 -127.301244)
			)
		)
	)
	(zone
		(layer "In4.Cu")
		(hatch none 0.5)
		(connect_pads
			(clearance 0)
		)
		(min_thickness 0.25)
		(keepout
			(tracks not_allowed)
			(vias allowed)
			(pads allowed)
			(copperpour not_allowed)
			(footprints allowed)
		)
		(placement
			(enabled no)
			(sheetname "")
		)
		(fill
			(thermal_gap 0.5)
			(thermal_bridge_width 0.5)
			(island_removal_mode 0)
		)
		(polygon
			(pts
				(xy 445.96685 -125.703584) (xy 445.96685 -126.00178) (xy 445.811656 -126.156974)
				(arc
					(start 445.665352 -126.156974)
					(mid 445.141435 -126.087124)
					(end 445.665352 -126.017274)
				)
				(xy 445.753744 -126.017274) (xy 445.82715 -125.943868) (xy 445.82715 -125.703584)
				(arc
					(start 445.408304 -125.703584)
					(mid 445.02451 -126.086997)
					(end 445.40805 -126.470664)
				)
				(arc
					(start 446.67805 -126.470664)
					(mid 447.06159 -126.087124)
					(end 446.67805 -125.703584)
				)
				(xy 446.25895 -125.703584) (xy 446.25895 -125.943868) (xy 446.332356 -126.017274)
				(arc
					(start 446.420748 -126.017274)
					(mid 446.944665 -126.087124)
					(end 446.420748 -126.156974)
				)
				(xy 446.274444 -126.156974) (xy 446.11925 -126.00178) (xy 446.11925 -125.703584)
			)
		)
	)
	(zone
		(net "VR_FET_SW_P12V_STBY_PVDDQ_KLM")
		(layer "In4.Cu")
		(hatch none 0.5)
		(connect_pads
			(clearance 0.5)
		)
		(min_thickness 0.25)
		(fill yes
			(thermal_gap 0.5)
			(thermal_bridge_width 0.5)
			(island_removal_mode 0)
		)
		(polygon
			(pts
				(xy 15.9893 -127.65278) (xy 15.9893 -130.175) (xy 15.9893 -131.858004) (xy 16.100298 -131.969002)
				(xy 16.324326 -132.19303) (xy 16.3576 -132.226304) (xy 16.3576 -132.369052) (xy 16.3576 -133.8834)
				(xy 16.3576 -134.984236) (xy 16.24711 -135.094726) (xy 15.52194 -135.094726) (xy 14.96949 -135.647176)
				(xy 14.96949 -136.550146) (xy 15.333472 -136.914128) (xy 16.205708 -136.914128) (xy 16.304006 -136.914128)
				(xy 16.355568 -136.96569) (xy 16.3576 -136.967722) (xy 16.3576 -137.069322) (xy 16.3576 -149.8346)
				(xy 15.0876 -151.1046) (xy 14.9352 -151.257) (xy 1.27 -151.257) (xy -1.524 -151.257) (xy -1.651 -151.13)
				(xy -1.651 -148.463) (xy -0.8128 -147.6248) (xy 0.5842 -147.6248) (xy 1.1684 -147.0406) (xy 1.1684 -145.38706)
				(xy 1.1684 -145.18005) (xy 1.191768 -145.156682) (xy 1.355598 -145.156682) (xy 1.929384 -145.156682)
				(xy 2.064512 -145.021554) (xy 2.483612 -144.602454) (xy 2.483612 -143.53921) (xy 2.042922 -143.09852)
				(xy 0.786892 -143.09852) (xy 0.781812 -143.1036) (xy -0.8128 -143.1036) (xy -1.651 -142.2654) (xy -1.651 -140.6652)
				(xy -1.651 -139.432538) (xy -1.651 -138.397488) (xy -1.651 -138.16584) (xy 1.02997 -135.48487) (xy 1.86563 -135.48487)
				(xy 2.2225 -135.128) (xy 2.2225 -134.29234) (xy 4.79425 -131.72059) (xy 4.79425 -131.54787) (xy 4.79425 -125.78715)
				(xy 5.204968 -125.376432) (xy 9.591548 -125.376432) (xy 15.586456 -125.376432) (xy 15.9893 -125.779276)
			)
		)
	)
	(zone
		(net "PVCCIN_CPU0")
		(layer "In4.Cu")
		(hatch none 0.5)
		(connect_pads
			(clearance 0.5)
		)
		(min_thickness 0.25)
		(fill yes
			(thermal_gap 0.5)
			(thermal_bridge_width 0.5)
			(island_removal_mode 0)
		)
		(polygon
			(pts
				(xy 208.993232 -92.5068) (xy 211.94014 -92.5068) (xy 214.68461 -89.76233) (xy 216.38387 -89.76233)
				(xy 228.831394 -77.314806) (xy 248.637806 -77.314806) (xy 254.415036 -83.092036) (xy 254.415036 -85.505036)
				(xy 254.508 -85.598) (xy 254.762 -85.598) (xy 255.2446 -86.0806) (xy 255.6002 -86.0806) (xy 256.5146 -86.995)
				(xy 256.5146 -87.260684) (xy 256.8194 -87.565484) (xy 257.389884 -87.565484) (xy 257.6322 -87.8078)
				(xy 261.012432 -87.8078) (xy 263.247632 -90.043) (xy 276.760432 -90.043) (xy 279.325832 -87.4776)
				(xy 279.9842 -87.4776) (xy 280.0604 -87.4014) (xy 280.0604 -86.5632) (xy 279.614884 -86.117684)
				(xy 279.058116 -86.117684) (xy 276.0472 -83.106768) (xy 276.0472 -67.5386) (xy 276.0726 -67.5132)
				(xy 276.0726 -67.0814) (xy 275.8948 -66.9036) (xy 275.8948 -64.813434) (xy 275.89099 -64.809624)
				(xy 275.5646 -64.6176) (xy 274.257516 -64.553084) (xy 272.259044 -62.554612) (xy 271.99463 -62.554612)
				(xy 271.812004 -62.737238) (xy 271.812004 -65.23863) (xy 271.955006 -65.381632) (xy 272.627598 -65.381632)
				(xy 273.771614 -66.525648) (xy 273.771614 -67.637406) (xy 273.46402 -67.945) (xy 266.827 -67.945)
				(xy 263.779 -67.945) (xy 263.779 -67.920616) (xy 258.953 -63.094616) (xy 255.702816 -63.094616)
				(xy 248.058432 -70.739) (xy 234.342432 -70.739) (xy 233.707432 -70.104) (xy 227.611432 -70.104)
				(xy 210.568032 -53.0606) (xy 209.044032 -53.0606) (xy 208.612232 -53.4924) (xy 208.612232 -92.1258)
			)
		)
	)
	(zone
		(layer "In4.Cu")
		(hatch none 0.5)
		(connect_pads
			(clearance 0)
		)
		(min_thickness 0.25)
		(keepout
			(tracks not_allowed)
			(vias allowed)
			(pads allowed)
			(copperpour not_allowed)
			(footprints allowed)
		)
		(placement
			(enabled no)
			(sheetname "")
		)
		(fill
			(thermal_gap 0.5)
			(thermal_bridge_width 0.5)
			(island_removal_mode 0)
		)
		(polygon
			(pts
				(arc
					(start 357.89235 -109.420152)
					(mid 357.9622 -108.896235)
					(end 358.03205 -109.420152)
				)
				(xy 358.03205 -109.508544) (xy 358.105456 -109.58195) (xy 358.34574 -109.58195)
				(arc
					(start 358.34574 -109.16285)
					(mid 357.9622 -108.77931)
					(end 357.57866 -109.16285)
				)
				(arc
					(start 357.57866 -110.432596)
					(mid 357.962073 -110.81639)
					(end 358.34574 -110.43285)
				)
				(xy 358.34574 -110.01375) (xy 358.105456 -110.01375) (xy 358.03205 -110.087156)
				(arc
					(start 358.03205 -110.175548)
					(mid 357.9622 -110.699465)
					(end 357.89235 -110.175548)
				)
				(xy 357.89235 -110.029244) (xy 358.047544 -109.87405) (xy 358.34574 -109.87405) (xy 358.34574 -109.72165)
				(xy 358.047544 -109.72165) (xy 357.89235 -109.566456)
			)
		)
	)
	(zone
		(layer "In4.Cu")
		(hatch none 0.5)
		(connect_pads
			(clearance 0)
		)
		(min_thickness 0.25)
		(keepout
			(tracks not_allowed)
			(vias allowed)
			(pads allowed)
			(copperpour not_allowed)
			(footprints allowed)
		)
		(placement
			(enabled no)
			(sheetname "")
		)
		(fill
			(thermal_gap 0.5)
			(thermal_bridge_width 0.5)
			(island_removal_mode 0)
		)
		(polygon
			(pts
				(xy 373.628158 -1.349756) (xy 373.783352 -1.50495) (xy 373.783352 -1.803146) (xy 373.935752 -1.803146)
				(xy 373.935752 -1.50495) (xy 374.090946 -1.349756)
				(arc
					(start 374.23725 -1.349756)
					(mid 374.761167 -1.419606)
					(end 374.23725 -1.489456)
				)
				(xy 374.148858 -1.489456) (xy 374.075452 -1.562862) (xy 374.075452 -1.803146)
				(arc
					(start 374.494298 -1.803146)
					(mid 374.878092 -1.419733)
					(end 374.494552 -1.036066)
				)
				(arc
					(start 373.224552 -1.036066)
					(mid 372.841012 -1.419606)
					(end 373.224552 -1.803146)
				)
				(xy 373.643652 -1.803146) (xy 373.643652 -1.562862) (xy 373.570246 -1.489456)
				(arc
					(start 373.481854 -1.489456)
					(mid 372.957937 -1.419606)
					(end 373.481854 -1.349756)
				)
			)
		)
	)
	(zone
		(net "P5V_STBY")
		(layer "In4.Cu")
		(hatch none 0.5)
		(connect_pads
			(clearance 0.5)
		)
		(min_thickness 0.25)
		(fill yes
			(thermal_gap 0.5)
			(thermal_bridge_width 0.5)
			(island_removal_mode 0)
		)
		(polygon
			(pts
				(xy 332.7781 -39.397432) (xy 332.7781 -36.4744) (xy 338.4804 -36.4744) (xy 340.8426 -34.1122) (xy 340.8426 -25.3238)
				(xy 340.3092 -24.7904) (xy 340.225634 -24.706834) (xy 336.55635 -24.706834) (xy 336.319622 -24.943562)
				(xy 336.319622 -25.662636) (xy 336.802222 -26.145236) (xy 337.447636 -26.145236) (xy 337.7946 -26.4922)
				(xy 337.7946 -33.6804) (xy 337.2866 -34.1884) (xy 331.96022 -34.1884) (xy 330.94168 -35.20694) (xy 330.2508 -35.89782)
				(xy 330.2508 -38.61181) (xy 329.65644 -39.20617) (xy 329.25385 -39.60876) (xy 328.327512 -39.60876)
				(xy 328.032364 -39.903908) (xy 327.360788 -40.575484) (xy 327.360788 -41.650412) (xy 327.360788 -42.213022)
				(xy 327.520046 -42.37228) (xy 329.803252 -42.37228)
			)
		)
	)
	(zone
		(layer "In4.Cu")
		(hatch none 0.5)
		(connect_pads
			(clearance 0)
		)
		(min_thickness 0.25)
		(keepout
			(tracks allowed)
			(vias allowed)
			(pads allowed)
			(copperpour allowed)
			(footprints allowed)
		)
		(placement
			(enabled no)
			(sheetname "")
		)
		(fill
			(thermal_gap 0.5)
			(thermal_bridge_width 0.5)
			(island_removal_mode 0)
		)
		(polygon
			(pts
				(xy 402.336 -122.301) (xy 402.336 -121.158) (xy 403.733 -121.158) (xy 403.733 -122.301)
			)
		)
	)
	(zone
		(net "GND")
		(layer "In4.Cu")
		(hatch none 0.5)
		(connect_pads
			(clearance 0.5)
		)
		(min_thickness 0.25)
		(fill yes
			(thermal_gap 0.5)
			(thermal_bridge_width 0.5)
			(island_removal_mode 0)
		)
		(polygon
			(pts
				(xy 339.2932 -157.734) (xy 345.9226 -157.734) (xy 347.1926 -156.464) (xy 347.1926 -152.1206) (xy 346.3798 -151.3078)
				(xy 346.3798 -150.0378) (xy 347.1418 -149.2758) (xy 347.1418 -144.3228) (xy 345.9861 -143.1671)
				(xy 345.9861 -142.766542) (xy 345.9861 -142.731998) (xy 345.975686 -142.721584) (xy 345.189302 -141.9352)
				(xy 345.127834 -141.9352) (xy 343.8652 -141.9352) (xy 342.392 -140.462) (xy 338.0232 -140.462) (xy 337.7946 -140.6906)
				(xy 337.7946 -143.0528) (xy 337.7946 -156.2354)
			)
		)
	)
	(zone
		(layer "In4.Cu")
		(hatch none 0.5)
		(connect_pads
			(clearance 0)
		)
		(min_thickness 0.25)
		(keepout
			(tracks not_allowed)
			(vias allowed)
			(pads allowed)
			(copperpour not_allowed)
			(footprints allowed)
		)
		(placement
			(enabled no)
			(sheetname "")
		)
		(fill
			(thermal_gap 0.5)
			(thermal_bridge_width 0.5)
			(island_removal_mode 0)
		)
		(polygon
			(pts
				(arc
					(start 450.929248 -53.684424)
					(mid 451.453165 -53.754274)
					(end 450.929248 -53.824124)
				)
				(xy 450.84111 -53.824124) (xy 450.76745 -53.897784) (xy 450.76745 -54.137814)
				(arc
					(start 451.186296 -54.137814)
					(mid 451.57009 -53.754401)
					(end 451.18655 -53.370734)
				)
				(arc
					(start 449.91655 -53.370734)
					(mid 449.53301 -53.754274)
					(end 449.91655 -54.137814)
				)
				(xy 450.33565 -54.137814) (xy 450.33565 -53.89753) (xy 450.262244 -53.824124)
				(arc
					(start 450.173852 -53.824124)
					(mid 449.649935 -53.754274)
					(end 450.173852 -53.684424)
				)
				(xy 450.320156 -53.684424) (xy 450.47535 -53.839618) (xy 450.47535 -54.137814) (xy 450.62775 -54.137814)
				(xy 450.62775 -53.839872) (xy 450.783198 -53.684424)
			)
		)
	)
	(zone
		(net "VR_FET_SW_P12V_STBY_PVDDQ_ABC")
		(layer "In4.Cu")
		(hatch none 0.5)
		(connect_pads
			(clearance 0.5)
		)
		(min_thickness 0.25)
		(fill yes
			(thermal_gap 0.5)
			(thermal_bridge_width 0.5)
			(island_removal_mode 0)
		)
		(polygon
			(pts
				(xy 355.5746 -20.170902) (xy 355.5746 -14.3002) (xy 355.092 -13.8176) (xy 352.6028 -13.8176) (xy 352.2218 -14.1986)
				(xy 351.933764 -14.486636) (xy 351.933764 -20.178776) (xy 352.205798 -20.45081) (xy 355.294692 -20.45081)
			)
		)
	)
	(zone
		(net "P12V_PSU")
		(layer "In4.Cu")
		(hatch none 0.5)
		(connect_pads
			(clearance 0.5)
		)
		(min_thickness 0.25)
		(fill yes
			(thermal_gap 0.5)
			(thermal_bridge_width 0.5)
			(island_removal_mode 0)
		)
		(polygon
			(pts
				(xy 9.5758 -86.181692) (xy 4.115054 -86.181692) (xy 3.5179 -85.584538) (xy 3.5179 -68.3895) (xy 3.5179 -68.3387)
				(xy 2.3114 -67.1322) (xy 2.3114 -59.874658) (xy 3.0734 -59.112658) (xy 3.0734 -58.928) (xy 3.0734 -50.3682)
				(xy 3.403346 -50.038254) (xy 9.45896 -50.038254) (xy 10.058146 -50.63744) (xy 10.058146 -85.968332)
				(xy 9.844786 -86.181692)
			)
		)
	)
	(zone
		(layer "In4.Cu")
		(hatch none 0.5)
		(connect_pads
			(clearance 0)
		)
		(min_thickness 0.25)
		(keepout
			(tracks not_allowed)
			(vias allowed)
			(pads allowed)
			(copperpour not_allowed)
			(footprints allowed)
		)
		(placement
			(enabled no)
			(sheetname "")
		)
		(fill
			(thermal_gap 0.5)
			(thermal_bridge_width 0.5)
			(island_removal_mode 0)
		)
		(polygon
			(pts
				(arc
					(start 358.999028 -112.651794)
					(mid 359.353394 -111.496897)
					(end 358.146858 -111.556292)
				)
				(arc
					(start 358.146858 -111.556292)
					(mid 358.37088 -111.864344)
					(end 358.040432 -112.053624)
				)
				(arc
					(start 358.040432 -112.053624)
					(mid 358.187898 -112.402145)
					(end 358.488742 -112.631728)
				)
				(arc
					(start 358.488742 -112.631728)
					(mid 358.753306 -112.404506)
					(end 358.999028 -112.651794)
				)
			)
		)
	)
	(zone
		(layer "In4.Cu")
		(hatch none 0.5)
		(connect_pads
			(clearance 0)
		)
		(min_thickness 0.25)
		(keepout
			(tracks not_allowed)
			(vias allowed)
			(pads allowed)
			(copperpour not_allowed)
			(footprints allowed)
		)
		(placement
			(enabled no)
			(sheetname "")
		)
		(fill
			(thermal_gap 0.5)
			(thermal_bridge_width 0.5)
			(island_removal_mode 0)
		)
		(polygon
			(pts
				(xy 404.593298 -2.827274) (xy 404.748492 -2.982468) (xy 404.748492 -3.280664) (xy 404.900892 -3.280664)
				(xy 404.900892 -2.982468) (xy 405.056086 -2.827274)
				(arc
					(start 405.08809 -2.827274)
					(mid 405.611881 -2.887255)
					(end 405.094186 -2.986786)
				)
				(xy 405.040592 -3.04038) (xy 405.040592 -3.280664)
				(arc
					(start 405.345138 -3.280664)
					(mid 405.728932 -2.897251)
					(end 405.345392 -2.513584)
				)
				(arc
					(start 404.329392 -2.513584)
					(mid 403.945852 -2.897124)
					(end 404.329392 -3.280664)
				)
				(xy 404.608792 -3.280664) (xy 404.608792 -3.04038)
				(arc
					(start 404.573232 -3.00482)
					(mid 404.063586 -2.877041)
					(end 404.586694 -2.827274)
				)
			)
		)
	)
	(zone
		(layer "In4.Cu")
		(hatch none 0.5)
		(connect_pads
			(clearance 0)
		)
		(min_thickness 0.25)
		(keepout
			(tracks not_allowed)
			(vias allowed)
			(pads allowed)
			(copperpour not_allowed)
			(footprints allowed)
		)
		(placement
			(enabled no)
			(sheetname "")
		)
		(fill
			(thermal_gap 0.5)
			(thermal_bridge_width 0.5)
			(island_removal_mode 0)
		)
		(polygon
			(pts
				(arc
					(start 474.21927 -21.465286)
					(mid 471.166189 -21.466556)
					(end 474.21927 -21.467826)
				)
				(arc
					(start 472.95943 -21.467826)
					(mid 472.69273 -21.731998)
					(end 472.42603 -21.467826)
				)
				(arc
					(start 472.42603 -21.465286)
					(mid 472.69273 -21.198586)
					(end 472.95943 -21.465286)
				)
			)
		)
	)
	(zone
		(layer "In4.Cu")
		(hatch none 0.5)
		(connect_pads
			(clearance 0)
		)
		(min_thickness 0.25)
		(keepout
			(tracks not_allowed)
			(vias allowed)
			(pads allowed)
			(copperpour not_allowed)
			(footprints allowed)
		)
		(placement
			(enabled no)
			(sheetname "")
		)
		(fill
			(thermal_gap 0.5)
			(thermal_bridge_width 0.5)
			(island_removal_mode 0)
		)
		(polygon
			(pts
				(arc
					(start 328.920094 -135.371332)
					(mid 325.953231 -133.761568)
					(end 326.22363 -137.126218)
				)
				(arc
					(start 326.22363 -137.126218)
					(mid 326.320024 -137.143122)
					(end 326.402954 -137.195052)
				)
				(arc
					(start 326.402954 -137.195052)
					(mid 327.983214 -137.019701)
					(end 328.88936 -135.713216)
				)
				(arc
					(start 328.88936 -135.713216)
					(mid 328.839841 -135.536423)
					(end 328.920094 -135.371332)
				)
			)
		)
	)
	(zone
		(layer "In4.Cu")
		(hatch none 0.5)
		(connect_pads
			(clearance 0)
		)
		(min_thickness 0.25)
		(keepout
			(tracks allowed)
			(vias allowed)
			(pads allowed)
			(copperpour allowed)
			(footprints allowed)
		)
		(placement
			(enabled no)
			(sheetname "")
		)
		(fill
			(thermal_gap 0.5)
			(thermal_bridge_width 0.5)
			(island_removal_mode 0)
		)
		(polygon
			(pts
				(xy 394.081 -129.794) (xy 394.081 -128.397) (xy 395.859 -128.397) (xy 395.859 -129.794)
			)
		)
	)
	(zone
		(layer "In4.Cu")
		(hatch none 0.5)
		(connect_pads
			(clearance 0)
		)
		(min_thickness 0.25)
		(keepout
			(tracks allowed)
			(vias allowed)
			(pads allowed)
			(copperpour allowed)
			(footprints allowed)
		)
		(placement
			(enabled no)
			(sheetname "")
		)
		(fill
			(thermal_gap 0.5)
			(thermal_bridge_width 0.5)
			(island_removal_mode 0)
		)
		(polygon
			(pts
				(xy 269.31874 -59.247532) (xy 272.363692 -59.247532) (xy 275.54047 -56.070754) (xy 275.54047 -49.543462)
				(xy 278.040846 -47.043086) (xy 278.040846 -45.574458) (xy 277.727156 -45.260768) (xy 271.505172 -45.260768)
				(xy 270.234664 -46.531276) (xy 270.234664 -50.03038) (xy 269.029942 -51.235102) (xy 269.029942 -58.958734)
			)
		)
	)
	(zone
		(layer "In4.Cu")
		(hatch none 0.5)
		(connect_pads
			(clearance 0)
		)
		(min_thickness 0.25)
		(keepout
			(tracks allowed)
			(vias allowed)
			(pads allowed)
			(copperpour allowed)
			(footprints allowed)
		)
		(placement
			(enabled no)
			(sheetname "")
		)
		(fill
			(thermal_gap 0.5)
			(thermal_bridge_width 0.5)
			(island_removal_mode 0)
		)
		(polygon
			(pts
				(xy 111.561118 -61.774324) (xy 120.603518 -61.774324) (xy 120.639332 -61.738764) (xy 121.291604 -61.738764)
				(xy 123.797568 -59.2328) (xy 123.797568 -58.433716) (xy 123.733052 -58.3692) (xy 123.733052 -53.7972)
				(xy 123.949968 -53.7972) (xy 124.153168 -53.594) (xy 124.153168 -52.4002) (xy 123.492768 -51.7398)
				(xy 120.952768 -51.7398) (xy 120.038368 -50.8254) (xy 119.149368 -50.8254) (xy 117.066568 -52.9082)
				(xy 113.205768 -52.9082) (xy 113.129568 -52.9844) (xy 113.154968 -53.0098) (xy 113.154968 -53.8988)
				(xy 111.300514 -53.8988) (xy 111.300514 -61.51372)
			)
		)
	)
	(zone
		(layer "In4.Cu")
		(hatch none 0.5)
		(connect_pads
			(clearance 0)
		)
		(min_thickness 0.25)
		(keepout
			(tracks not_allowed)
			(vias allowed)
			(pads allowed)
			(copperpour not_allowed)
			(footprints allowed)
		)
		(placement
			(enabled no)
			(sheetname "")
		)
		(fill
			(thermal_gap 0.5)
			(thermal_bridge_width 0.5)
			(island_removal_mode 0)
		)
		(polygon
			(pts
				(arc
					(start 457.330302 -53.836824)
					(mid 457.854219 -53.906674)
					(end 457.330302 -53.976524)
				)
				(xy 457.242164 -53.976524) (xy 457.113132 -54.105556) (xy 457.113132 -54.290214)
				(arc
					(start 457.58735 -54.290214)
					(mid 457.971144 -53.906801)
					(end 457.587604 -53.523134)
				)
				(arc
					(start 456.317604 -53.523134)
					(mid 455.934064 -53.906674)
					(end 456.317604 -54.290214)
				)
				(xy 456.681332 -54.290214) (xy 456.681332 -54.108858)
				(arc
					(start 456.56881 -53.996336)
					(mid 456.051154 -53.896807)
					(end 456.574906 -53.836824)
				)
				(xy 456.60691 -53.836824) (xy 456.821032 -54.050946) (xy 456.821032 -54.290214) (xy 456.973432 -54.290214)
				(xy 456.973432 -54.047644) (xy 457.184252 -53.836824)
			)
		)
	)
	(zone
		(layer "In4.Cu")
		(hatch none 0.5)
		(connect_pads
			(clearance 0)
		)
		(min_thickness 0.25)
		(keepout
			(tracks not_allowed)
			(vias allowed)
			(pads allowed)
			(copperpour not_allowed)
			(footprints allowed)
		)
		(placement
			(enabled no)
			(sheetname "")
		)
		(fill
			(thermal_gap 0.5)
			(thermal_bridge_width 0.5)
			(island_removal_mode 0)
		)
		(polygon
			(pts
				(xy 3.61315 -107.52836) (xy 3.61315 -107.826556) (xy 3.457956 -107.98175)
				(arc
					(start 3.311652 -107.98175)
					(mid 2.787735 -107.9119)
					(end 3.311652 -107.84205)
				)
				(xy 3.400044 -107.84205) (xy 3.47345 -107.768644) (xy 3.47345 -107.52836)
				(arc
					(start 3.054604 -107.52836)
					(mid 2.67081 -107.911773)
					(end 3.05435 -108.29544)
				)
				(arc
					(start 4.32435 -108.29544)
					(mid 4.70789 -107.9119)
					(end 4.32435 -107.52836)
				)
				(xy 3.90525 -107.52836) (xy 3.90525 -107.768644) (xy 3.978656 -107.84205)
				(arc
					(start 4.067048 -107.84205)
					(mid 4.590965 -107.9119)
					(end 4.067048 -107.98175)
				)
				(xy 3.920744 -107.98175) (xy 3.76555 -107.826556) (xy 3.76555 -107.52836)
			)
		)
	)
	(zone
		(net "GND")
		(layer "In4.Cu")
		(hatch none 0.5)
		(connect_pads
			(clearance 0.5)
		)
		(min_thickness 0.25)
		(fill yes
			(thermal_gap 0.5)
			(thermal_bridge_width 0.5)
			(island_removal_mode 0)
		)
		(polygon
			(pts
				(xy -5.03174 15.24) (xy -5.03174 8.763) (xy 413.4358 8.763) (xy 501.2182 8.763) (xy 501.2182 8.7884)
				(xy 501.2182 15.24)
			)
		)
		(polygon
			(pts
				(xy 189.6618 14.5288) (xy 127.3302 14.5288) (xy 127.3302 9.4742) (xy 189.6618 9.4742) (xy 189.6618 9.4996)
				(xy 192.5066 9.4996) (xy 194.1322 9.4996) (xy 198.934578 9.4996) (xy 198.934578 14.528546) (xy 189.6618 14.528546)
			)
		)
		(polygon
			(pts
				(xy 100.1776 14.61262) (xy 19.05 14.61262) (xy 19.05 9.4742) (xy 36.957 9.4742) (xy 36.957 9.9187)
				(xy 100.838 9.9187) (xy 100.838 9.9314) (xy 103.505 9.9314) (xy 106.214926 9.9314) (xy 114.39652 9.9314)
				(xy 114.39652 14.605) (xy 106.2228 14.605) (xy 103.505 14.605) (xy 100.1776 14.605)
			)
		)
		(polygon
			(pts
				(xy 273.4818 14.5034) (xy 211.836 14.5034) (xy 211.836 9.4234) (xy 273.4818 9.4234) (xy 283.28239 9.4234)
				(xy 283.28239 14.5034) (xy 277.9268 14.5034) (xy 276.5552 14.5034)
			)
		)
	)
	(zone
		(layer "In4.Cu")
		(hatch none 0.5)
		(connect_pads
			(clearance 0)
		)
		(min_thickness 0.25)
		(keepout
			(tracks allowed)
			(vias allowed)
			(pads allowed)
			(copperpour allowed)
			(footprints allowed)
		)
		(placement
			(enabled no)
			(sheetname "")
		)
		(fill
			(thermal_gap 0.5)
			(thermal_bridge_width 0.5)
			(island_removal_mode 0)
		)
		(polygon
			(pts
				(xy 76.972668 -68.5165) (xy 78.649068 -70.1929) (xy 81.277968 -70.1929) (xy 82.776568 -68.6943)
				(xy 82.776568 -54.7624) (xy 83.576668 -53.9623) (xy 83.576668 -51.3715) (xy 84.211668 -50.7365)
				(xy 84.211668 -50.0761) (xy 83.703668 -49.5681) (xy 80.731868 -49.5681) (xy 80.725518 -49.57445)
				(xy 80.242918 -49.57445) (xy 80.236568 -49.5681) (xy 79.677768 -49.5681) (xy 79.353918 -49.89195)
				(xy 77.156818 -49.89195) (xy 76.959968 -50.0888) (xy 76.959968 -50.5206) (xy 76.972668 -50.5333)
			)
		)
	)
	(zone
		(layer "In4.Cu")
		(hatch none 0.5)
		(connect_pads
			(clearance 0)
		)
		(min_thickness 0.25)
		(keepout
			(tracks allowed)
			(vias allowed)
			(pads allowed)
			(copperpour allowed)
			(footprints allowed)
		)
		(placement
			(enabled no)
			(sheetname "")
		)
		(fill
			(thermal_gap 0.5)
			(thermal_bridge_width 0.5)
			(island_removal_mode 0)
		)
		(polygon
			(pts
				(xy 233.299 -44.831) (xy 236.347 -44.831) (xy 241.173 -49.657) (xy 241.173 -53.34) (xy 239.903 -54.61)
				(xy 235.077 -54.61) (xy 229.489 -49.022) (xy 229.489 -48.641)
			)
		)
	)
	(zone
		(layer "In4.Cu")
		(hatch none 0.5)
		(connect_pads
			(clearance 0)
		)
		(min_thickness 0.25)
		(keepout
			(tracks not_allowed)
			(vias allowed)
			(pads allowed)
			(copperpour not_allowed)
			(footprints allowed)
		)
		(placement
			(enabled no)
			(sheetname "")
		)
		(fill
			(thermal_gap 0.5)
			(thermal_bridge_width 0.5)
			(island_removal_mode 0)
		)
		(polygon
			(pts
				(arc
					(start 449.31965 -44.7675)
					(mid 449.843567 -44.83735)
					(end 449.31965 -44.9072)
				)
				(xy 449.231512 -44.9072) (xy 449.157852 -44.98086) (xy 449.157852 -45.22089)
				(arc
					(start 449.576952 -45.22089)
					(mid 449.960492 -44.83735)
					(end 449.576952 -44.45381)
				)
				(arc
					(start 448.307206 -44.45381)
					(mid 447.923412 -44.837223)
					(end 448.306952 -45.22089)
				)
				(xy 448.726052 -45.22089) (xy 448.726052 -45.002958) (xy 448.630294 -44.9072)
				(arc
					(start 448.564254 -44.9072)
					(mid 448.040337 -44.83735)
					(end 448.564254 -44.7675)
				)
				(xy 448.688206 -44.7675) (xy 448.865752 -44.945046) (xy 448.865752 -45.22089) (xy 449.018152 -45.22089)
				(xy 449.018152 -44.922948) (xy 449.1736 -44.7675)
			)
		)
	)
	(zone
		(layer "In4.Cu")
		(hatch none 0.5)
		(connect_pads
			(clearance 0)
		)
		(min_thickness 0.25)
		(keepout
			(tracks allowed)
			(vias allowed)
			(pads allowed)
			(copperpour allowed)
			(footprints allowed)
		)
		(placement
			(enabled no)
			(sheetname "")
		)
		(fill
			(thermal_gap 0.5)
			(thermal_bridge_width 0.5)
			(island_removal_mode 0)
		)
		(polygon
			(pts
				(xy 104.318308 -59.247532) (xy 107.36326 -59.247532) (xy 110.540038 -56.070754) (xy 110.540038 -49.543462)
				(xy 113.040414 -47.043086) (xy 113.040414 -45.574458) (xy 112.726724 -45.260768) (xy 106.50474 -45.260768)
				(xy 105.234232 -46.531276) (xy 105.234232 -50.03038) (xy 104.02951 -51.235102) (xy 104.02951 -58.958734)
			)
		)
	)
	(zone
		(layer "In4.Cu")
		(hatch none 0.5)
		(connect_pads
			(clearance 0)
		)
		(min_thickness 0.25)
		(keepout
			(tracks not_allowed)
			(vias allowed)
			(pads allowed)
			(copperpour not_allowed)
			(footprints allowed)
		)
		(placement
			(enabled no)
			(sheetname "")
		)
		(fill
			(thermal_gap 0.5)
			(thermal_bridge_width 0.5)
			(island_removal_mode 0)
		)
		(polygon
			(pts
				(xy 354.339906 -115.80495) (xy 354.4951 -115.960144)
				(arc
					(start 354.4951 -115.963192)
					(mid 354.446699 -116.486244)
					(end 354.315014 -115.97767)
				)
				(xy 354.281994 -115.94465) (xy 354.10394 -115.94465) (xy 354.04171 -116.00688)
				(arc
					(start 354.04171 -116.22024)
					(mid 354.425123 -116.604034)
					(end 354.80879 -116.220494)
				)
				(arc
					(start 354.80879 -115.204494)
					(mid 354.42525 -114.820954)
					(end 354.04171 -115.204494)
				)
				(xy 354.04171 -115.51285) (xy 354.28174 -115.51285)
				(arc
					(start 354.338128 -115.456462)
					(mid 354.434288 -114.938042)
					(end 354.4951 -115.461796)
				)
				(xy 354.4951 -115.497102) (xy 354.339652 -115.65255) (xy 354.04171 -115.65255) (xy 354.04171 -115.809268)
				(xy 354.046028 -115.80495)
			)
		)
	)
	(zone
		(net "PVCCIOMCP_CPU1")
		(layer "In4.Cu")
		(hatch none 0.5)
		(connect_pads
			(clearance 0.5)
		)
		(min_thickness 0.25)
		(fill yes
			(thermal_gap 0.5)
			(thermal_bridge_width 0.5)
			(island_removal_mode 0)
		)
		(polygon
			(pts
				(xy 128.143 -80.2386) (xy 127.6858 -79.7814) (xy 127.6858 -76.0476) (xy 127.889 -75.8444) (xy 127.9906 -75.7428)
				(xy 134.1882 -75.7428) (xy 134.2898 -75.8444) (xy 134.7216 -76.2762) (xy 134.7216 -80.0862) (xy 134.5692 -80.2386)
				(xy 134.4168 -80.391) (xy 128.2954 -80.391)
			)
		)
	)
	(zone
		(net "PVDDQ_ABC")
		(layer "In4.Cu")
		(hatch none 0.5)
		(connect_pads
			(clearance 0.5)
		)
		(min_thickness 0.25)
		(fill yes
			(thermal_gap 0.5)
			(thermal_bridge_width 0.5)
			(island_removal_mode 0)
		)
		(polygon
			(pts
				(xy 266.9286 -67.6402) (xy 263.8044 -67.6402) (xy 258.8768 -62.7126) (xy 251.46 -62.7126) (xy 251.079 -62.3316)
				(xy 251.079 -59.0804) (xy 251.4854 -58.674) (xy 258.3434 -58.674) (xy 258.4958 -58.5216) (xy 268.6558 -58.5216)
				(xy 269.0114 -58.8772) (xy 271.6022 -61.468) (xy 271.6022 -65.408302) (xy 271.79016 -65.596262)
				(xy 272.56994 -65.596262) (xy 273.539204 -66.565526) (xy 273.539204 -67.523868) (xy 273.422872 -67.6402)
				(xy 270.9418 -67.6402)
			)
		)
	)
	(zone
		(layer "In4.Cu")
		(hatch none 0.5)
		(connect_pads
			(clearance 0)
		)
		(min_thickness 0.25)
		(keepout
			(tracks not_allowed)
			(vias allowed)
			(pads allowed)
			(copperpour not_allowed)
			(footprints allowed)
		)
		(placement
			(enabled no)
			(sheetname "")
		)
		(fill
			(thermal_gap 0.5)
			(thermal_bridge_width 0.5)
			(island_removal_mode 0)
		)
		(polygon
			(pts
				(arc
					(start 460.530448 -53.836824)
					(mid 461.054365 -53.906674)
					(end 460.530448 -53.976524)
				)
				(xy 460.44231 -53.976524) (xy 460.36865 -54.050184) (xy 460.36865 -54.290214)
				(arc
					(start 460.787496 -54.290214)
					(mid 461.17129 -53.906801)
					(end 460.78775 -53.523134)
				)
				(arc
					(start 459.51775 -53.523134)
					(mid 459.13421 -53.906674)
					(end 459.51775 -54.290214)
				)
				(xy 459.93685 -54.290214) (xy 459.93685 -54.04993) (xy 459.863444 -53.976524)
				(arc
					(start 459.775052 -53.976524)
					(mid 459.251135 -53.906674)
					(end 459.775052 -53.836824)
				)
				(xy 459.921356 -53.836824) (xy 460.07655 -53.992018) (xy 460.07655 -54.290214) (xy 460.22895 -54.290214)
				(xy 460.22895 -53.992272) (xy 460.384398 -53.836824)
			)
		)
	)
	(zone
		(layer "In4.Cu")
		(hatch none 0.5)
		(connect_pads
			(clearance 0)
		)
		(min_thickness 0.25)
		(keepout
			(tracks allowed)
			(vias allowed)
			(pads allowed)
			(copperpour allowed)
			(footprints allowed)
		)
		(placement
			(enabled no)
			(sheetname "")
		)
		(fill
			(thermal_gap 0.5)
			(thermal_bridge_width 0.5)
			(island_removal_mode 0)
		)
		(polygon
			(pts
				(xy 276.56155 -61.774324) (xy 285.60395 -61.774324) (xy 285.639764 -61.738764) (xy 286.292036 -61.738764)
				(xy 288.798 -59.2328) (xy 288.798 -58.433716) (xy 288.733484 -58.3692) (xy 288.733484 -53.7972)
				(xy 288.9504 -53.7972) (xy 289.1536 -53.594) (xy 289.1536 -52.4002) (xy 288.4932 -51.7398) (xy 285.9532 -51.7398)
				(xy 285.0388 -50.8254) (xy 284.1498 -50.8254) (xy 282.067 -52.9082) (xy 278.2062 -52.9082) (xy 278.13 -52.9844)
				(xy 278.1554 -53.0098) (xy 278.1554 -53.8988) (xy 276.300946 -53.8988) (xy 276.300946 -61.51372)
			)
		)
	)
	(zone
		(layer "In4.Cu")
		(hatch none 0.5)
		(connect_pads
			(clearance 0)
		)
		(min_thickness 0.25)
		(keepout
			(tracks not_allowed)
			(vias allowed)
			(pads allowed)
			(copperpour not_allowed)
			(footprints allowed)
		)
		(placement
			(enabled no)
			(sheetname "")
		)
		(fill
			(thermal_gap 0.5)
			(thermal_bridge_width 0.5)
			(island_removal_mode 0)
		)
		(polygon
			(pts
				(xy 356.219506 -115.788694) (xy 356.3747 -115.943888)
				(arc
					(start 356.3747 -115.963192)
					(mid 356.320111 -116.486671)
					(end 356.206044 -115.972844)
				)
				(xy 356.161594 -115.928394) (xy 355.975158 -115.928394) (xy 355.92131 -115.982242)
				(arc
					(start 355.92131 -116.220494)
					(mid 356.30485 -116.604034)
					(end 356.68839 -116.220494)
				)
				(arc
					(start 356.68839 -115.204748)
					(mid 356.304977 -114.820954)
					(end 355.92131 -115.204494)
				)
				(xy 355.92131 -115.496594) (xy 356.161594 -115.496594)
				(arc
					(start 356.206044 -115.452144)
					(mid 356.320112 -114.938298)
					(end 356.3747 -115.461796)
				)
				(xy 356.3747 -115.4811) (xy 356.219506 -115.636294) (xy 355.92131 -115.636294) (xy 355.92131 -115.788694)
			)
		)
	)
	(zone
		(net "VR_FET_SW_P12V_STBY_PVDDQ_DEF")
		(layer "In4.Cu")
		(hatch none 0.5)
		(connect_pads
			(clearance 0.5)
		)
		(min_thickness 0.25)
		(fill yes
			(thermal_gap 0.5)
			(thermal_bridge_width 0.5)
			(island_removal_mode 0)
		)
		(polygon
			(pts
				(xy 355.4222 -146.5834) (xy 354.3554 -145.5166) (xy 354.076 -145.5166) (xy 351.19691 -142.63751)
				(xy 350.94037 -142.63751) (xy 350.940116 -142.637256) (xy 350.935544 -142.637256) (xy 350.5962 -142.9766)
				(xy 350.0882 -142.9766) (xy 349.699072 -142.587472) (xy 349.042228 -142.587472) (xy 348.6023 -143.0274)
				(xy 348.6023 -152.4508) (xy 349.1611 -153.0096) (xy 350.324166 -153.0096) (xy 350.728026 -152.60574)
				(xy 354.656136 -152.60574) (xy 354.70846 -152.60574) (xy 355.5111 -151.8031) (xy 356.0953 -151.8031)
				(xy 357.7463 -151.8031) (xy 358.6734 -150.876) (xy 358.9782 -150.5712) (xy 362.7628 -150.5712) (xy 365.154972 -152.963372)
				(xy 365.154972 -154.835606) (xy 365.566706 -155.24734) (xy 367.43894 -155.24734) (xy 370.21262 -155.24734)
				(xy 370.221764 -155.256484) (xy 370.880386 -155.256484) (xy 370.904516 -155.232354) (xy 371.253258 -154.883612)
				(xy 371.253258 -151.989536) (xy 370.910358 -151.646636) (xy 370.147596 -151.646636) (xy 368.4143 -149.91334)
				(xy 367.33734 -149.91334) (xy 364.1344 -146.7104) (xy 363.5756 -146.7104) (xy 358.1908 -146.7104)
				(xy 355.5492 -146.7104)
			)
		)
	)
	(zone
		(layer "In4.Cu")
		(hatch none 0.5)
		(connect_pads
			(clearance 0)
		)
		(min_thickness 0.25)
		(keepout
			(tracks allowed)
			(vias allowed)
			(pads allowed)
			(copperpour allowed)
			(footprints allowed)
		)
		(placement
			(enabled no)
			(sheetname "")
		)
		(fill
			(thermal_gap 0.5)
			(thermal_bridge_width 0.5)
			(island_removal_mode 0)
		)
		(polygon
			(pts
				(xy 105.890568 -107.823) (xy 124.813568 -107.823) (xy 126.845568 -107.823) (xy 127.226568 -107.442)
				(xy 127.226568 -106.68) (xy 127.798068 -106.1085) (xy 127.798068 -104.8385) (xy 127.861568 -104.775)
				(xy 127.861568 -104.013) (xy 124.813568 -100.965) (xy 124.813568 -98.171) (xy 124.305568 -97.663)
				(xy 124.305568 -94.107) (xy 122.527568 -92.329) (xy 121.130568 -92.329) (xy 120.495568 -92.964)
				(xy 117.828568 -92.964) (xy 117.193568 -93.599) (xy 113.129568 -93.599) (xy 113.129568 -95.504)
				(xy 105.890568 -95.504)
			)
		)
	)
	(zone
		(layer "In4.Cu")
		(hatch none 0.5)
		(connect_pads
			(clearance 0)
		)
		(min_thickness 0.25)
		(keepout
			(tracks not_allowed)
			(vias allowed)
			(pads allowed)
			(copperpour not_allowed)
			(footprints allowed)
		)
		(placement
			(enabled no)
			(sheetname "")
		)
		(fill
			(thermal_gap 0.5)
			(thermal_bridge_width 0.5)
			(island_removal_mode 0)
		)
		(polygon
			(pts
				(xy 453.68845 -123.99264) (xy 453.500236 -123.80468)
				(arc
					(start 453.269604 -123.80468)
					(mid 452.88581 -124.188093)
					(end 453.26935 -124.57176)
				)
				(arc
					(start 454.53935 -124.57176)
					(mid 454.92289 -124.18822)
					(end 454.53935 -123.80468)
				)
				(xy 454.11136 -123.80468) (xy 454.12025 -123.81357) (xy 454.12025 -123.842526) (xy 454.12025 -123.871482)
				(xy 454.12025 -124.044964) (xy 454.193656 -124.11837)
				(arc
					(start 454.282048 -124.11837)
					(mid 454.805965 -124.18822)
					(end 454.282048 -124.25807)
				)
				(xy 454.135744 -124.25807) (xy 453.98055 -124.102876) (xy 453.98055 -123.871482) (xy 453.913748 -123.80468)
				(xy 453.697848 -123.80468) (xy 453.787256 -123.893834) (xy 453.807576 -123.914154) (xy 453.82815 -123.934728)
				(xy 453.82815 -123.963684) (xy 453.82815 -123.99264) (xy 453.82815 -124.102876) (xy 453.672956 -124.25807)
				(arc
					(start 453.526652 -124.25807)
					(mid 453.002735 -124.18822)
					(end 453.526652 -124.11837)
				)
				(xy 453.615044 -124.11837) (xy 453.68845 -124.044964)
			)
		)
	)
	(zone
		(net "PVTT_GHJ")
		(layer "In4.Cu")
		(hatch none 0.5)
		(connect_pads
			(clearance 0.5)
		)
		(min_thickness 0.25)
		(fill yes
			(thermal_gap 0.5)
			(thermal_bridge_width 0.5)
			(island_removal_mode 0)
		)
		(polygon
			(pts
				(xy 136.8552 -6.6802) (xy 165.1254 -6.6802) (xy 165.6334 -6.1722) (xy 165.6334 -2.2606) (xy 164.846 -1.4732)
				(xy 160.3502 -1.4732) (xy 155.194 3.683) (xy 118.745 3.683) (xy 118.364 3.302) (xy 117.856 2.794)
				(xy 116.84 1.778) (xy 101.346 1.778) (xy 100.076 3.048) (xy 94.107 3.048) (xy 93.3958 2.3368) (xy 93.3958 -1.27)
				(xy 93.3958 -5.461) (xy 94.2848 -6.35) (xy 121.031 -6.35) (xy 125.3998 -1.9812) (xy 132.1562 -1.9812)
			)
		)
	)
	(zone
		(layer "In4.Cu")
		(hatch none 0.5)
		(connect_pads
			(clearance 0)
		)
		(min_thickness 0.25)
		(keepout
			(tracks not_allowed)
			(vias allowed)
			(pads allowed)
			(copperpour not_allowed)
			(footprints allowed)
		)
		(placement
			(enabled no)
			(sheetname "")
		)
		(fill
			(thermal_gap 0.5)
			(thermal_bridge_width 0.5)
			(island_removal_mode 0)
		)
		(polygon
			(pts
				(xy 1.07315 -107.52836) (xy 1.07315 -107.826556) (xy 0.917956 -107.98175)
				(arc
					(start 0.771652 -107.98175)
					(mid 0.247735 -107.9119)
					(end 0.771652 -107.84205)
				)
				(xy 0.860044 -107.84205) (xy 0.93345 -107.768644) (xy 0.93345 -107.52836)
				(arc
					(start 0.514604 -107.52836)
					(mid 0.13081 -107.911773)
					(end 0.51435 -108.29544)
				)
				(arc
					(start 1.78435 -108.29544)
					(mid 2.16789 -107.9119)
					(end 1.78435 -107.52836)
				)
				(xy 1.36525 -107.52836) (xy 1.36525 -107.768644) (xy 1.438656 -107.84205)
				(arc
					(start 1.527048 -107.84205)
					(mid 2.050965 -107.9119)
					(end 1.527048 -107.98175)
				)
				(xy 1.380744 -107.98175) (xy 1.22555 -107.826556) (xy 1.22555 -107.52836)
			)
		)
	)
	(zone
		(layer "In4.Cu")
		(hatch none 0.5)
		(connect_pads
			(clearance 0)
		)
		(min_thickness 0.25)
		(keepout
			(tracks allowed)
			(vias allowed)
			(pads allowed)
			(copperpour allowed)
			(footprints allowed)
		)
		(placement
			(enabled no)
			(sheetname "")
		)
		(fill
			(thermal_gap 0.5)
			(thermal_bridge_width 0.5)
			(island_removal_mode 0)
		)
		(polygon
			(pts
				(xy 322.326 -62.992) (xy 322.326 -60.96) (xy 324.231 -60.96) (xy 324.231 -62.992)
			)
		)
	)
	(zone
		(layer "In4.Cu")
		(hatch none 0.5)
		(connect_pads
			(clearance 0)
		)
		(min_thickness 0.25)
		(keepout
			(tracks not_allowed)
			(vias allowed)
			(pads allowed)
			(copperpour not_allowed)
			(footprints allowed)
		)
		(placement
			(enabled no)
			(sheetname "")
		)
		(fill
			(thermal_gap 0.5)
			(thermal_bridge_width 0.5)
			(island_removal_mode 0)
		)
		(polygon
			(pts
				(arc
					(start 355.885242 -109.420152)
					(mid 355.955092 -108.896235)
					(end 356.024942 -109.420152)
				)
				(xy 356.024942 -109.508544) (xy 356.098348 -109.58195) (xy 356.338632 -109.58195)
				(arc
					(start 356.338632 -109.16285)
					(mid 355.955092 -108.77931)
					(end 355.571552 -109.16285)
				)
				(arc
					(start 355.571552 -110.432596)
					(mid 355.954965 -110.81639)
					(end 356.338632 -110.43285)
				)
				(xy 356.338632 -110.01375) (xy 356.098348 -110.01375) (xy 356.024942 -110.087156)
				(arc
					(start 356.024942 -110.175548)
					(mid 355.955092 -110.699465)
					(end 355.885242 -110.175548)
				)
				(xy 355.885242 -110.029244) (xy 356.040436 -109.87405) (xy 356.338632 -109.87405) (xy 356.338632 -109.72165)
				(xy 356.040436 -109.72165) (xy 355.885242 -109.566456)
			)
		)
	)
	(zone
		(layer "In4.Cu")
		(hatch none 0.5)
		(connect_pads
			(clearance 0)
		)
		(min_thickness 0.25)
		(keepout
			(tracks allowed)
			(vias allowed)
			(pads allowed)
			(copperpour allowed)
			(footprints allowed)
		)
		(placement
			(enabled no)
			(sheetname "")
		)
		(fill
			(thermal_gap 0.5)
			(thermal_bridge_width 0.5)
			(island_removal_mode 0)
		)
		(polygon
			(pts
				(xy 403.606 -125.857) (xy 403.606 -124.587) (xy 404.622 -124.587) (xy 404.622 -125.857)
			)
		)
	)
	(zone
		(layer "In4.Cu")
		(hatch none 0.5)
		(connect_pads
			(clearance 0)
		)
		(min_thickness 0.25)
		(keepout
			(tracks not_allowed)
			(vias allowed)
			(pads allowed)
			(copperpour not_allowed)
			(footprints allowed)
		)
		(placement
			(enabled no)
			(sheetname "")
		)
		(fill
			(thermal_gap 0.5)
			(thermal_bridge_width 0.5)
			(island_removal_mode 0)
		)
		(polygon
			(pts
				(xy 462.61655 -123.80468) (xy 462.61655 -124.102876) (xy 462.461356 -124.25807)
				(arc
					(start 462.315052 -124.25807)
					(mid 461.791135 -124.18822)
					(end 462.315052 -124.11837)
				)
				(xy 462.403444 -124.11837) (xy 462.47685 -124.044964) (xy 462.47685 -123.80468)
				(arc
					(start 462.058004 -123.80468)
					(mid 461.67421 -124.188093)
					(end 462.05775 -124.57176)
				)
				(arc
					(start 463.32775 -124.57176)
					(mid 463.71129 -124.18822)
					(end 463.32775 -123.80468)
				)
				(xy 462.90865 -123.80468) (xy 462.90865 -123.999244) (xy 463.027776 -124.11837)
				(arc
					(start 463.070448 -124.11837)
					(mid 463.594365 -124.18822)
					(end 463.070448 -124.25807)
				)
				(xy 462.969864 -124.25807) (xy 462.76895 -124.057156) (xy 462.76895 -123.80468)
			)
		)
	)
	(zone
		(layer "In4.Cu")
		(hatch none 0.5)
		(connect_pads
			(clearance 0)
		)
		(min_thickness 0.25)
		(keepout
			(tracks not_allowed)
			(vias allowed)
			(pads allowed)
			(copperpour not_allowed)
			(footprints allowed)
		)
		(placement
			(enabled no)
			(sheetname "")
		)
		(fill
			(thermal_gap 0.5)
			(thermal_bridge_width 0.5)
			(island_removal_mode 0)
		)
		(polygon
			(pts
				(xy 395.361414 -3.509264) (xy 395.361414 -3.265932)
				(arc
					(start 395.502892 -3.124454)
					(mid 396.024657 -3.047798)
					(end 395.54912 -3.275838)
				)
				(xy 395.501114 -3.323844) (xy 395.501114 -3.509264)
				(arc
					(start 395.769592 -3.509264)
					(mid 396.153132 -3.125724)
					(end 395.769592 -2.742184)
				)
				(arc
					(start 394.753846 -2.742184)
					(mid 394.370052 -3.125597)
					(end 394.753592 -3.509264)
				)
				(xy 395.069314 -3.509264) (xy 395.069314 -3.307588)
				(arc
					(start 394.996924 -3.235198)
					(mid 394.487682 -3.105209)
					(end 395.010894 -3.055874)
				)
				(xy 395.015212 -3.055874) (xy 395.209014 -3.249676) (xy 395.209014 -3.509264)
			)
		)
	)
	(zone
		(layer "In4.Cu")
		(hatch none 0.5)
		(connect_pads
			(clearance 0)
		)
		(min_thickness 0.25)
		(keepout
			(tracks not_allowed)
			(vias allowed)
			(pads allowed)
			(copperpour not_allowed)
			(footprints allowed)
		)
		(placement
			(enabled no)
			(sheetname "")
		)
		(fill
			(thermal_gap 0.5)
			(thermal_bridge_width 0.5)
			(island_removal_mode 0)
		)
		(polygon
			(pts
				(arc
					(start 349.712788 -23.414228)
					(mid 349.099435 -23.164236)
					(end 349.358966 -23.773638)
				)
				(arc
					(start 349.358966 -23.680928)
					(mid 349.168478 -23.605247)
					(end 349.087948 -23.416768)
				)
				(arc
					(start 349.087948 -23.414228)
					(mid 349.354648 -23.147528)
					(end 349.621348 -23.414228)
				)
			)
		)
	)
	(zone
		(layer "In4.Cu")
		(hatch none 0.5)
		(connect_pads
			(clearance 0)
		)
		(min_thickness 0.25)
		(keepout
			(tracks not_allowed)
			(vias allowed)
			(pads allowed)
			(copperpour not_allowed)
			(footprints allowed)
		)
		(placement
			(enabled no)
			(sheetname "")
		)
		(fill
			(thermal_gap 0.5)
			(thermal_bridge_width 0.5)
			(island_removal_mode 0)
		)
		(polygon
			(pts
				(xy 363.883956 -1.900174) (xy 364.03915 -2.055368) (xy 364.03915 -2.353564) (xy 364.19155 -2.353564)
				(xy 364.19155 -2.055368) (xy 364.346744 -1.900174)
				(arc
					(start 364.493048 -1.900174)
					(mid 365.016965 -1.970024)
					(end 364.493048 -2.039874)
				)
				(xy 364.404656 -2.039874) (xy 364.33125 -2.11328) (xy 364.33125 -2.353564)
				(arc
					(start 364.750096 -2.353564)
					(mid 365.13389 -1.970151)
					(end 364.75035 -1.586484)
				)
				(arc
					(start 363.48035 -1.586484)
					(mid 363.09681 -1.970024)
					(end 363.48035 -2.353564)
				)
				(xy 363.89945 -2.353564) (xy 363.89945 -2.11328) (xy 363.826044 -2.039874)
				(arc
					(start 363.737652 -2.039874)
					(mid 363.213735 -1.970024)
					(end 363.737652 -1.900174)
				)
			)
		)
	)
	(zone
		(net "GND")
		(layer "In4.Cu")
		(hatch none 0.5)
		(connect_pads
			(clearance 0.5)
		)
		(min_thickness 0.25)
		(fill yes
			(thermal_gap 0.5)
			(thermal_bridge_width 0.5)
			(island_removal_mode 0)
		)
		(polygon
			(pts
				(xy -3.302 -43.053) (xy 11.7856 -43.053) (xy 12.9794 -44.2468) (xy 12.9794 -46.0248) (xy 12.9794 -47.1932)
				(xy 11.5062 -48.6664) (xy 2.8448 -48.6664) (xy 1.778 -49.7332) (xy 1.778 -58.3692) (xy 0.508 -59.6392)
				(xy 0.508 -67.31) (xy 2.2352 -69.0372) (xy 2.2352 -85.8266) (xy 1.2573 -86.8045) (xy -3.3401 -86.8045)
				(xy -4.7752 -85.3694) (xy -4.7752 -44.5262)
			)
		)
	)
	(zone
		(layer "In4.Cu")
		(hatch none 0.5)
		(connect_pads
			(clearance 0)
		)
		(min_thickness 0.25)
		(keepout
			(tracks not_allowed)
			(vias allowed)
			(pads allowed)
			(copperpour not_allowed)
			(footprints allowed)
		)
		(placement
			(enabled no)
			(sheetname "")
		)
		(fill
			(thermal_gap 0.5)
			(thermal_bridge_width 0.5)
			(island_removal_mode 0)
		)
		(polygon
			(pts
				(xy 16.434816 -102.81793) (xy 16.598392 -102.981506) (xy 16.705834 -102.873302) (xy 16.537686 -102.705154)
				(arc
					(start 16.537686 -102.684834)
					(mid 16.592676 -102.161332)
					(end 16.70558 -102.675436)
				)
				(xy 16.804132 -102.773988)
				(arc
					(start 16.879824 -102.697788)
					(mid 16.877792 -102.155244)
					(end 16.335248 -102.157276)
				)
				(arc
					(start 15.741396 -102.755954)
					(mid 15.735205 -103.301005)
					(end 16.280384 -103.3018)
				)
				(xy 16.452596 -103.128318)
				(arc
					(start 16.256508 -103.128318)
					(mid 15.754472 -103.103953)
					(end 16.167862 -102.81793)
				)
			)
		)
	)
	(zone
		(layer "In4.Cu")
		(hatch none 0.5)
		(connect_pads
			(clearance 0)
		)
		(min_thickness 0.25)
		(keepout
			(tracks allowed)
			(vias allowed)
			(pads allowed)
			(copperpour allowed)
			(footprints allowed)
		)
		(placement
			(enabled no)
			(sheetname "")
		)
		(fill
			(thermal_gap 0.5)
			(thermal_bridge_width 0.5)
			(island_removal_mode 0)
		)
		(polygon
			(pts
				(xy 369.316 -115.951) (xy 369.316 -113.919) (xy 372.999 -113.919) (xy 372.999 -115.951)
			)
		)
	)
	(zone
		(net "PVTT_KLM")
		(layer "In4.Cu")
		(hatch none 0.5)
		(connect_pads
			(clearance 0.5)
		)
		(min_thickness 0.25)
		(fill yes
			(thermal_gap 0.5)
			(thermal_bridge_width 0.5)
			(island_removal_mode 0)
		)
		(polygon
			(pts
				(xy 159.9946 -144.9578) (xy 167.1574 -144.9578) (xy 168.021 -145.8214) (xy 168.021 -155.7274) (xy 168.021 -156.55417)
				(xy 168.576752 -157.109922) (xy 169.4688 -157.109922) (xy 169.842688 -157.48381) (xy 169.842688 -158.137098)
				(xy 169.344086 -158.6357) (xy 166.878 -158.6357) (xy 116.8273 -158.6357) (xy 114.61242 -156.42082)
				(xy 93.25102 -156.42082) (xy 93.0148 -156.1846) (xy 93.0148 -149.098) (xy 93.7006 -148.4122) (xy 94.5134 -147.5994)
				(xy 99.8474 -147.5994) (xy 121.9708 -147.5994) (xy 122.7836 -148.4122) (xy 122.7836 -151.0792) (xy 123.698 -151.9936)
				(xy 157.5308 -151.9936) (xy 158.2166 -151.3078) (xy 158.2166 -151.13) (xy 158.2166 -146.7358)
			)
		)
	)
	(zone
		(layer "In4.Cu")
		(hatch none 0.5)
		(connect_pads
			(clearance 0)
		)
		(min_thickness 0.25)
		(keepout
			(tracks not_allowed)
			(vias allowed)
			(pads allowed)
			(copperpour not_allowed)
			(footprints allowed)
		)
		(placement
			(enabled no)
			(sheetname "")
		)
		(fill
			(thermal_gap 0.5)
			(thermal_bridge_width 0.5)
			(island_removal_mode 0)
		)
		(polygon
			(pts
				(xy 12.427966 -107.13593) (xy 12.58316 -107.291124)
				(arc
					(start 12.58316 -107.437428)
					(mid 12.51331 -107.961345)
					(end 12.44346 -107.437428)
				)
				(xy 12.44346 -107.349036) (xy 12.370054 -107.27563) (xy 12.12977 -107.27563)
				(arc
					(start 12.12977 -107.694476)
					(mid 12.513183 -108.07827)
					(end 12.89685 -107.69473)
				)
				(arc
					(start 12.89685 -106.42473)
					(mid 12.51331 -106.04119)
					(end 12.12977 -106.42473)
				)
				(xy 12.12977 -106.84383) (xy 12.370054 -106.84383) (xy 12.44346 -106.770424)
				(arc
					(start 12.44346 -106.682032)
					(mid 12.51331 -106.158115)
					(end 12.58316 -106.682032)
				)
				(xy 12.58316 -106.828336) (xy 12.427966 -106.98353) (xy 12.12977 -106.98353) (xy 12.12977 -107.13593)
			)
		)
	)
	(zone
		(net "GND")
		(layer "In4.Cu")
		(hatch none 0.5)
		(connect_pads
			(clearance 0.5)
		)
		(min_thickness 0.25)
		(fill yes
			(thermal_gap 0.5)
			(thermal_bridge_width 0.5)
			(island_removal_mode 0)
		)
		(polygon
			(pts
				(xy 34.5948 -93.748352) (xy 34.5948 -100.1268) (xy 33.274 -101.4476) (xy 33.274 -101.894132) (xy 33.279334 -101.899466)
				(xy 33.279334 -102.367334) (xy 33.528 -102.616) (xy 36.46678 -102.616) (xy 37.92474 -101.15804)
				(xy 38.2397 -101.15804) (xy 41.18356 -101.15804) (xy 43.023282 -99.318318) (xy 43.023282 -99.182682)
				(xy 43.023282 -96.81591) (xy 43.239944 -96.599248) (xy 43.239944 -93.764608) (xy 43.005756 -93.53042)
				(xy 34.812732 -93.53042)
			)
		)
	)
	(zone
		(layer "In4.Cu")
		(hatch none 0.5)
		(connect_pads
			(clearance 0)
		)
		(min_thickness 0.25)
		(keepout
			(tracks allowed)
			(vias allowed)
			(pads allowed)
			(copperpour allowed)
			(footprints allowed)
		)
		(placement
			(enabled no)
			(sheetname "")
		)
		(fill
			(thermal_gap 0.5)
			(thermal_bridge_width 0.5)
			(island_removal_mode 0)
		)
		(polygon
			(pts
				(xy 143.36522 -105.179622) (xy 131.544568 -105.179622) (xy 131.544568 -105.156) (xy 130.909568 -104.521)
				(xy 128.115568 -104.521) (xy 128.115568 -105.156) (xy 128.115568 -106.934) (xy 127.480568 -107.569)
				(xy 127.099568 -107.95) (xy 105.509568 -107.95) (xy 105.509568 -104.775) (xy 85.443568 -104.775)
				(xy 85.443568 -105.156) (xy 67.663568 -105.156) (xy 66.901568 -105.156) (xy 64.361568 -102.616)
				(xy 64.361568 -82.1436) (xy 65.479168 -81.026) (xy 65.479168 -72.2122) (xy 63.345568 -70.0786) (xy 63.345568 -61.5188)
				(xy 63.497968 -61.3664) (xy 65.656968 -59.2074) (xy 65.656968 -57.277) (xy 67.282568 -55.6514) (xy 67.282568 -52.1716)
				(xy 63.866268 -48.7553) (xy 70.076568 -42.545) (xy 72.489568 -44.958) (xy 72.489568 -45.5422) (xy 72.768968 -45.5422)
				(xy 75.816968 -48.5902) (xy 76.566268 -49.3395) (xy 83.995768 -49.3395) (xy 85.773768 -47.5615)
				(xy 104.994964 -47.5615) (xy 104.994964 -45.978572) (xy 105.902506 -45.07103) (xy 113.147602 -45.07103)
				(xy 113.147602 -45.377354) (xy 113.642648 -45.8724) (xy 118.717568 -45.8724) (xy 118.723918 -45.87875)
				(xy 121.302018 -45.87875) (xy 121.638568 -46.2153) (xy 121.638568 -48.2346) (xy 121.638568 -48.7934)
				(xy 124.841762 -51.996594) (xy 127.375666 -51.996594) (xy 142.763748 -51.996594) (xy 144.214596 -53.447442)
				(xy 145.412968 -54.645814) (xy 145.412968 -57.912) (xy 145.362168 -57.9628) (xy 145.333974 -57.9628)
				(xy 145.333974 -103.210868)
			)
		)
	)
	(zone
		(layer "In4.Cu")
		(hatch none 0.5)
		(connect_pads
			(clearance 0)
		)
		(min_thickness 0.25)
		(keepout
			(tracks not_allowed)
			(vias allowed)
			(pads allowed)
			(copperpour not_allowed)
			(footprints allowed)
		)
		(placement
			(enabled no)
			(sheetname "")
		)
		(fill
			(thermal_gap 0.5)
			(thermal_bridge_width 0.5)
			(island_removal_mode 0)
		)
		(polygon
			(pts
				(xy 332.2066 -27.8892) (xy 332.2066 -31.4706)
				(arc
					(start 335.958688 -31.4706)
					(mid 336.1944 -31.094337)
					(end 336.430112 -31.4706)
				)
				(arc
					(start 336.720688 -31.4706)
					(mid 336.9564 -31.094337)
					(end 337.192112 -31.4706)
				)
				(xy 337.7184 -31.4706) (xy 337.7184 -27.8892)
			)
		)
	)
	(zone
		(layer "In4.Cu")
		(hatch none 0.5)
		(connect_pads
			(clearance 0)
		)
		(min_thickness 0.25)
		(keepout
			(tracks not_allowed)
			(vias allowed)
			(pads allowed)
			(copperpour not_allowed)
			(footprints allowed)
		)
		(placement
			(enabled no)
			(sheetname "")
		)
		(fill
			(thermal_gap 0.5)
			(thermal_bridge_width 0.5)
			(island_removal_mode 0)
		)
		(polygon
			(pts
				(arc
					(start 320.590926 -98.549968)
					(mid 315.409326 -98.549968)
					(end 320.590926 -98.549968)
				)
			)
		)
	)
	(zone
		(layer "In4.Cu")
		(hatch none 0.5)
		(connect_pads
			(clearance 0)
		)
		(min_thickness 0.25)
		(keepout
			(tracks allowed)
			(vias allowed)
			(pads allowed)
			(copperpour allowed)
			(footprints allowed)
		)
		(placement
			(enabled no)
			(sheetname "")
		)
		(fill
			(thermal_gap 0.5)
			(thermal_bridge_width 0.5)
			(island_removal_mode 0)
		)
		(polygon
			(pts
				(xy 270.891 -107.823) (xy 289.814 -107.823) (xy 291.846 -107.823) (xy 292.227 -107.442) (xy 292.227 -106.68)
				(xy 292.7985 -106.1085) (xy 292.7985 -104.8385) (xy 292.862 -104.775) (xy 292.862 -104.013) (xy 289.814 -100.965)
				(xy 289.814 -98.171) (xy 289.306 -97.663) (xy 289.306 -94.107) (xy 287.528 -92.329) (xy 286.131 -92.329)
				(xy 285.496 -92.964) (xy 282.829 -92.964) (xy 282.194 -93.599) (xy 278.13 -93.599) (xy 278.13 -95.504)
				(xy 270.891 -95.504)
			)
		)
	)
	(zone
		(net "P5V_STBY")
		(layer "In4.Cu")
		(hatch none 0.5)
		(connect_pads
			(clearance 0.5)
		)
		(min_thickness 0.25)
		(fill yes
			(thermal_gap 0.5)
			(thermal_bridge_width 0.5)
			(island_removal_mode 0)
		)
		(polygon
			(pts
				(xy 317.820802 -45.218858) (xy 319.040256 -45.218858) (xy 319.483994 -44.77512) (xy 319.913 -44.77512)
				(xy 320.103246 -44.584874) (xy 320.103246 -43.775376) (xy 318.362076 -43.775376) (xy 317.65494 -44.482512)
				(xy 317.65494 -45.052996)
			)
		)
	)
	(zone
		(layer "In4.Cu")
		(hatch none 0.5)
		(connect_pads
			(clearance 0)
		)
		(min_thickness 0.25)
		(keepout
			(tracks not_allowed)
			(vias allowed)
			(pads allowed)
			(copperpour not_allowed)
			(footprints allowed)
		)
		(placement
			(enabled no)
			(sheetname "")
		)
		(fill
			(thermal_gap 0.5)
			(thermal_bridge_width 0.5)
			(island_removal_mode 0)
		)
		(polygon
			(pts
				(xy 376.103896 -2.867152) (xy 376.25909 -3.022346) (xy 376.25909 -3.320542) (xy 376.41149 -3.320542)
				(xy 376.41149 -3.022346) (xy 376.566684 -2.867152)
				(arc
					(start 376.712988 -2.867152)
					(mid 377.236905 -2.937002)
					(end 376.712988 -3.006852)
				)
				(xy 376.624596 -3.006852) (xy 376.55119 -3.080258) (xy 376.55119 -3.320542)
				(arc
					(start 376.970036 -3.320542)
					(mid 377.35383 -2.937129)
					(end 376.97029 -2.553462)
				)
				(arc
					(start 375.70029 -2.553462)
					(mid 375.31675 -2.937002)
					(end 375.70029 -3.320542)
				)
				(xy 376.11939 -3.320542) (xy 376.11939 -3.080258) (xy 376.045984 -3.006852)
				(arc
					(start 375.957592 -3.006852)
					(mid 375.433675 -2.937002)
					(end 375.957592 -2.867152)
				)
			)
		)
	)
	(zone
		(layer "In4.Cu")
		(hatch none 0.5)
		(connect_pads
			(clearance 0)
		)
		(min_thickness 0.25)
		(keepout
			(tracks not_allowed)
			(vias allowed)
			(pads allowed)
			(copperpour not_allowed)
			(footprints allowed)
		)
		(placement
			(enabled no)
			(sheetname "")
		)
		(fill
			(thermal_gap 0.5)
			(thermal_bridge_width 0.5)
			(island_removal_mode 0)
		)
		(polygon
			(pts
				(arc
					(start 455.719688 -44.7675)
					(mid 456.243605 -44.83735)
					(end 455.719688 -44.9072)
				)
				(xy 455.63155 -44.9072) (xy 455.55789 -44.98086) (xy 455.55789 -45.22089)
				(arc
					(start 455.97699 -45.22089)
					(mid 456.36053 -44.83735)
					(end 455.97699 -44.45381)
				)
				(arc
					(start 454.707244 -44.45381)
					(mid 454.32345 -44.837223)
					(end 454.70699 -45.22089)
				)
				(xy 455.12609 -45.22089) (xy 455.12609 -44.980606) (xy 455.052684 -44.9072)
				(arc
					(start 454.964292 -44.9072)
					(mid 454.440375 -44.83735)
					(end 454.964292 -44.7675)
				)
				(xy 455.110596 -44.7675) (xy 455.26579 -44.922694) (xy 455.26579 -45.22089) (xy 455.41819 -45.22089)
				(xy 455.41819 -44.922948) (xy 455.573638 -44.7675)
			)
		)
	)
	(zone
		(layer "In4.Cu")
		(hatch none 0.5)
		(connect_pads
			(clearance 0)
		)
		(min_thickness 0.25)
		(keepout
			(tracks not_allowed)
			(vias allowed)
			(pads allowed)
			(copperpour not_allowed)
			(footprints allowed)
		)
		(placement
			(enabled no)
			(sheetname "")
		)
		(fill
			(thermal_gap 0.5)
			(thermal_bridge_width 0.5)
			(island_removal_mode 0)
		)
		(polygon
			(pts
				(xy 459.39075 -123.835668) (xy 459.308962 -123.75388)
				(arc
					(start 458.971904 -123.75388)
					(mid 458.58811 -124.137293)
					(end 458.97165 -124.52096)
				)
				(arc
					(start 460.24165 -124.52096)
					(mid 460.62519 -124.13742)
					(end 460.24165 -123.75388)
				)
				(xy 459.82255 -123.75388) (xy 459.82255 -123.994164) (xy 459.895956 -124.06757)
				(arc
					(start 459.984348 -124.06757)
					(mid 460.508265 -124.13742)
					(end 459.984348 -124.20727)
				)
				(xy 459.838044 -124.20727) (xy 459.68285 -124.052076) (xy 459.68285 -123.75388) (xy 459.506574 -123.75388)
				(xy 459.509876 -123.757182) (xy 459.53045 -123.777756) (xy 459.53045 -123.806712) (xy 459.53045 -123.835668)
				(xy 459.53045 -124.052076) (xy 459.375256 -124.20727)
				(arc
					(start 459.228952 -124.20727)
					(mid 458.705035 -124.13742)
					(end 459.228952 -124.06757)
				)
				(xy 459.317344 -124.06757) (xy 459.39075 -123.994164)
			)
		)
	)
	(zone
		(layer "In4.Cu")
		(hatch none 0.5)
		(connect_pads
			(clearance 0)
		)
		(min_thickness 0.25)
		(keepout
			(tracks not_allowed)
			(vias allowed)
			(pads allowed)
			(copperpour not_allowed)
			(footprints allowed)
		)
		(placement
			(enabled no)
			(sheetname "")
		)
		(fill
			(thermal_gap 0.5)
			(thermal_bridge_width 0.5)
			(island_removal_mode 0)
		)
		(polygon
			(pts
				(xy 13.1572 -57.023) (xy 13.1572 -62.23) (xy 13.081 -62.3062) (xy 13.081 -62.611) (xy 13.1572 -62.6872)
				(xy 13.1572 -65.7606) (xy 15.79118 -68.39458) (xy 15.79118 -68.52666) (xy 15.46606 -68.85178) (xy 14.45006 -68.85178)
				(xy 12.278868 -66.680588) (xy 12.278868 -57.023)
			)
		)
	)
	(zone
		(net "VR_FET_SW_P12V_STBY_PVCCIN_CPU1")
		(layer "In4.Cu")
		(hatch none 0.5)
		(connect_pads
			(clearance 0.5)
		)
		(min_thickness 0.25)
		(fill yes
			(thermal_gap 0.5)
			(thermal_bridge_width 0.5)
			(island_removal_mode 0)
		)
		(polygon
			(pts
				(xy 26.289 -96.266) (xy 28.956 -93.599) (xy 29.0576 -93.599) (xy 29.0576 -91.1352) (xy 30.5308 -89.662)
				(xy 30.5308 -87.6808) (xy 30.5308 -86.6394) (xy 29.4132 -85.5218) (xy 29.4132 -85.471) (xy 29.4132 -81.153)
				(xy 30.353 -80.2132) (xy 30.353 -79.375) (xy 30.353 -77.978) (xy 30.353 -77.4954) (xy 29.21 -76.3524)
				(xy 29.21 -75.057) (xy 30.5054 -73.7616) (xy 30.5054 -70.3834) (xy 30.353 -70.231) (xy 30.3403 -70.2183)
				(xy 29.21 -69.088) (xy 29.21 -66.3702) (xy 30.6832 -64.897) (xy 30.6832 -63.6651) (xy 30.56128 -63.54318)
				(xy 30.2895 -63.54318) (xy 30.18028 -63.43396) (xy 30.18028 -61.34608) (xy 29.21 -60.3758) (xy 29.21 -58.2676)
				(xy 29.91231 -57.56529) (xy 29.91231 -53.61305) (xy 29.23286 -52.9336) (xy 25.9334 -52.9336) (xy 24.9936 -51.9938)
				(xy 24.638 -51.6382) (xy 24.3586 -51.3588) (xy 24.3586 -49.4792) (xy 24.638 -49.1998) (xy 24.8158 -49.022)
				(xy 27.94 -49.022) (xy 27.9527 -49.0347) (xy 28.5369 -49.0347) (xy 29.5402 -50.038) (xy 30.8102 -50.038)
				(xy 32.004 -50.038) (xy 32.0929 -50.1269) (xy 34.3408 -52.3748) (xy 34.3408 -53.467) (xy 34.3408 -99.949)
				(xy 32.8168 -101.473) (xy 32.8168 -102.330758) (xy 32.814006 -102.333552) (xy 32.814006 -102.923594)
				(xy 32.0294 -103.7082) (xy 31.439104 -103.7082) (xy 29.5148 -103.7082) (xy 29.156914 -104.066086)
				(xy 29.156914 -104.294686) (xy 29.156914 -104.818942) (xy 29.156914 -107.241848) (xy 28.92552 -107.473242)
				(xy 24.72309 -107.473242) (xy 23.780242 -107.473242) (xy 23.368 -107.061) (xy 23.368 -99.187)
			)
		)
	)
	(zone
		(net "PVDDQ_GHJ")
		(layer "In4.Cu")
		(hatch none 0.5)
		(connect_pads
			(clearance 0.5)
		)
		(min_thickness 0.25)
		(fill yes
			(thermal_gap 0.5)
			(thermal_bridge_width 0.5)
			(island_removal_mode 0)
		)
		(polygon
			(pts
				(xy 89.9922 -58.5978) (xy 103.7336 -58.5978) (xy 104.521 -59.3852) (xy 104.521 -63.6778) (xy 106.33202 -65.48882)
				(xy 107.315 -65.48882) (xy 107.4928 -65.66662) (xy 107.4928 -66.6242) (xy 107.6198 -66.7512) (xy 108.447586 -66.7512)
				(xy 108.650786 -66.9544) (xy 108.650786 -67.502532) (xy 108.360718 -67.7926) (xy 106.1466 -67.7926)
				(xy 101.7524 -67.7926) (xy 91.3638 -67.7926) (xy 89.1286 -65.5574) (xy 87.376 -65.5574) (xy 86.36 -64.5414)
				(xy 86.36 -58.9788) (xy 86.741 -58.5978) (xy 89.7128 -58.5978)
			)
		)
	)
	(zone
		(layer "In4.Cu")
		(hatch none 0.5)
		(connect_pads
			(clearance 0)
		)
		(min_thickness 0.25)
		(keepout
			(tracks not_allowed)
			(vias allowed)
			(pads allowed)
			(copperpour not_allowed)
			(footprints allowed)
		)
		(placement
			(enabled no)
			(sheetname "")
		)
		(fill
			(thermal_gap 0.5)
			(thermal_bridge_width 0.5)
			(island_removal_mode 0)
		)
		(polygon
			(pts
				(xy 16.354806 -100.24237) (xy 16.51 -100.397564)
				(arc
					(start 16.51 -100.490528)
					(mid 16.44015 -101.014445)
					(end 16.3703 -100.490528)
				)
				(xy 16.3703 -100.455476) (xy 16.296894 -100.38207) (xy 16.254476 -100.38207) (xy 16.249396 -100.38715)
				(xy 16.05661 -100.38715)
				(arc
					(start 16.05661 -100.74783)
					(mid 16.44015 -101.13137)
					(end 16.82369 -100.74783)
				)
				(arc
					(start 16.82369 -99.478084)
					(mid 16.440277 -99.09429)
					(end 16.05661 -99.47783)
				)
				(xy 16.05661 -99.95535) (xy 16.191484 -99.95535) (xy 16.3703 -99.776534)
				(arc
					(start 16.3703 -99.735132)
					(mid 16.44015 -99.211215)
					(end 16.51 -99.735132)
				)
				(xy 16.51 -99.834446) (xy 16.249396 -100.09505) (xy 16.05661 -100.09505) (xy 16.05661 -100.24745)
				(xy 16.191484 -100.24745) (xy 16.196564 -100.24237)
			)
		)
	)
	(zone
		(layer "In4.Cu")
		(hatch none 0.5)
		(connect_pads
			(clearance 0)
		)
		(min_thickness 0.25)
		(keepout
			(tracks allowed)
			(vias allowed)
			(pads allowed)
			(copperpour allowed)
			(footprints allowed)
		)
		(placement
			(enabled no)
			(sheetname "")
		)
		(fill
			(thermal_gap 0.5)
			(thermal_bridge_width 0.5)
			(island_removal_mode 0)
		)
		(polygon
			(pts
				(xy 74.013568 -68.4022) (xy 74.013568 -60.198) (xy 73.200768 -59.3852) (xy 73.200768 -56.8198) (xy 71.651368 -55.2704)
				(xy 71.346568 -54.9656) (xy 69.695568 -54.9656) (xy 69.492368 -54.7624) (xy 68.958968 -54.7624)
				(xy 68.908168 -54.8132) (xy 68.908168 -58.0898) (xy 68.501768 -58.4962) (xy 68.171568 -58.4962)
				(xy 67.434968 -57.7596) (xy 67.434968 -57.4294) (xy 66.901568 -56.896) (xy 66.495168 -56.896) (xy 66.012568 -57.3786)
				(xy 66.012568 -58.039) (xy 67.130168 -59.1566) (xy 66.520568 -59.7662) (xy 66.495168 -59.7662) (xy 65.783968 -60.4774)
				(xy 65.783968 -61.2902) (xy 64.412368 -62.6618) (xy 64.412368 -63.8048) (xy 65.631568 -65.024) (xy 65.631568 -68.072)
				(xy 66.825368 -69.2658) (xy 66.825368 -70.2564) (xy 68.374768 -70.2564) (xy 68.958968 -70.8406)
				(xy 70.965568 -70.8406) (xy 71.422768 -70.3834) (xy 71.422768 -70.2564) (xy 72.159368 -70.2564)
			)
		)
	)
	(zone
		(layer "In4.Cu")
		(hatch none 0.5)
		(connect_pads
			(clearance 0)
		)
		(min_thickness 0.25)
		(keepout
			(tracks allowed)
			(vias allowed)
			(pads allowed)
			(copperpour allowed)
			(footprints allowed)
		)
		(placement
			(enabled no)
			(sheetname "")
		)
		(fill
			(thermal_gap 0.5)
			(thermal_bridge_width 0.5)
			(island_removal_mode 0)
		)
		(polygon
			(pts
				(xy 239.014 -68.4022) (xy 239.014 -60.198) (xy 238.2012 -59.3852) (xy 238.2012 -56.8198) (xy 236.6518 -55.2704)
				(xy 236.347 -54.9656) (xy 234.696 -54.9656) (xy 234.4928 -54.7624) (xy 233.9594 -54.7624) (xy 233.9086 -54.8132)
				(xy 233.9086 -58.0898) (xy 233.5022 -58.4962) (xy 233.172 -58.4962) (xy 232.4354 -57.7596) (xy 232.4354 -57.4294)
				(xy 231.902 -56.896) (xy 231.4956 -56.896) (xy 231.013 -57.3786) (xy 231.013 -58.039) (xy 232.1306 -59.1566)
				(xy 231.521 -59.7662) (xy 231.4956 -59.7662) (xy 230.7844 -60.4774) (xy 230.7844 -61.2902) (xy 229.4128 -62.6618)
				(xy 229.4128 -63.8048) (xy 230.632 -65.024) (xy 230.632 -68.072) (xy 231.8258 -69.2658) (xy 231.8258 -70.2564)
				(xy 233.3752 -70.2564) (xy 233.9594 -70.8406) (xy 235.966 -70.8406) (xy 236.4232 -70.3834) (xy 236.4232 -70.2564)
				(xy 237.1598 -70.2564)
			)
		)
	)
	(zone
		(net "PVCCIN_CPU1")
		(layer "In4.Cu")
		(hatch none 0.5)
		(connect_pads
			(clearance 0.5)
		)
		(min_thickness 0.25)
		(fill yes
			(thermal_gap 0.5)
			(thermal_bridge_width 0.5)
			(island_removal_mode 0)
		)
		(polygon
			(pts
				(xy 43.9928 -92.5068) (xy 48.7934 -92.5068) (xy 61.8998 -79.4004) (xy 63.16472 -78.13548) (xy 65.22212 -78.13548)
				(xy 65.8622 -77.4954) (xy 69.06768 -77.4954) (xy 69.66204 -78.08976) (xy 69.9643 -78.08976) (xy 70.5104 -78.63586)
				(xy 70.8914 -78.63586) (xy 71.29272 -79.03718) (xy 71.67118 -79.03718) (xy 72.00138 -78.70698) (xy 72.62368 -78.70698)
				(xy 73.05802 -79.14132) (xy 73.46188 -79.14132) (xy 74.00036 -79.6798) (xy 74.3331 -79.6798) (xy 74.73442 -80.08112)
				(xy 75.12304 -80.08112) (xy 75.54468 -79.65948) (xy 76.05776 -79.65948) (xy 76.53528 -80.137) (xy 76.9493 -80.137)
				(xy 77.4446 -80.6323) (xy 79.0575 -80.6323) (xy 84.3661 -80.6323) (xy 87.7316 -83.9978) (xy 91.5416 -87.8078)
				(xy 96.012 -87.8078) (xy 96.2152 -87.8078) (xy 98.7552 -85.2678) (xy 102.7938 -85.2678) (xy 106.46664 -85.2678)
				(xy 109.544866 -85.2678) (xy 109.736128 -85.459062) (xy 109.951774 -85.674708) (xy 109.951774 -87.207598)
				(xy 109.673136 -87.486236) (xy 107.311698 -87.486236) (xy 106.91114 -87.886794) (xy 106.91114 -89.26068)
				(xy 106.80954 -89.36228) (xy 106.80954 -89.98966) (xy 106.86288 -90.043) (xy 111.76 -90.043) (xy 114.3762 -87.4268)
				(xy 114.3762 -81.0768) (xy 112.6998 -79.4004) (xy 112.6998 -67.9958) (xy 106.1974 -61.4934) (xy 105.1052 -61.4934)
				(xy 104.8258 -61.7728) (xy 104.8258 -63.6016) (xy 106.473752 -65.249552) (xy 108.241846 -65.249552)
				(xy 108.85805 -65.865756) (xy 108.85805 -67.695318) (xy 108.328968 -68.2244) (xy 106.0958 -68.2244)
				(xy 101.4984 -68.2244) (xy 91.44 -68.2244) (xy 90.9066 -67.691) (xy 89.3064 -66.0908) (xy 87.7062 -66.0908)
				(xy 83.058 -70.739) (xy 69.342 -70.739) (xy 68.707 -70.104) (xy 61.6458 -70.104) (xy 45.0342 -53.4924)
				(xy 43.8658 -53.4924) (xy 43.6118 -53.7464) (xy 43.6118 -92.1258)
			)
		)
	)
	(zone
		(layer "In4.Cu")
		(hatch none 0.5)
		(connect_pads
			(clearance 0)
		)
		(min_thickness 0.25)
		(keepout
			(tracks not_allowed)
			(vias allowed)
			(pads allowed)
			(copperpour not_allowed)
			(footprints allowed)
		)
		(placement
			(enabled no)
			(sheetname "")
		)
		(fill
			(thermal_gap 0.5)
			(thermal_bridge_width 0.5)
			(island_removal_mode 0)
		)
		(polygon
			(pts
				(xy 371.303804 -2.867152) (xy 371.458998 -3.022346) (xy 371.458998 -3.320542) (xy 371.611398 -3.320542)
				(xy 371.611398 -3.022346) (xy 371.766592 -2.867152)
				(arc
					(start 371.912896 -2.867152)
					(mid 372.436813 -2.937002)
					(end 371.912896 -3.006852)
				)
				(xy 371.824504 -3.006852) (xy 371.751098 -3.080258) (xy 371.751098 -3.320542)
				(arc
					(start 372.169944 -3.320542)
					(mid 372.553738 -2.937129)
					(end 372.170198 -2.553462)
				)
				(arc
					(start 370.900198 -2.553462)
					(mid 370.516658 -2.937002)
					(end 370.900198 -3.320542)
				)
				(xy 371.319298 -3.320542) (xy 371.319298 -3.080258) (xy 371.245892 -3.006852)
				(arc
					(start 371.1575 -3.006852)
					(mid 370.633583 -2.937002)
					(end 371.1575 -2.867152)
				)
			)
		)
	)
	(zone
		(layer "In4.Cu")
		(hatch none 0.5)
		(connect_pads
			(clearance 0)
		)
		(min_thickness 0.25)
		(keepout
			(tracks not_allowed)
			(vias allowed)
			(pads allowed)
			(copperpour not_allowed)
			(footprints allowed)
		)
		(placement
			(enabled no)
			(sheetname "")
		)
		(fill
			(thermal_gap 0.5)
			(thermal_bridge_width 0.5)
			(island_removal_mode 0)
		)
		(polygon
			(pts
				(arc
					(start 439.71972 -44.7675)
					(mid 440.243637 -44.83735)
					(end 439.71972 -44.9072)
				)
				(xy 439.64606 -44.9072) (xy 439.572654 -44.980606) (xy 439.572654 -45.22089)
				(arc
					(start 439.977022 -45.22089)
					(mid 440.360562 -44.83735)
					(end 439.977022 -44.45381)
				)
				(arc
					(start 438.707276 -44.45381)
					(mid 438.323736 -44.837223)
					(end 438.707022 -45.22089)
				)
				(xy 439.140854 -45.22089) (xy 439.140854 -44.995338) (xy 439.052716 -44.9072)
				(arc
					(start 438.964324 -44.9072)
					(mid 438.440407 -44.83735)
					(end 438.964324 -44.7675)
				)
				(xy 439.110628 -44.7675) (xy 439.280554 -44.937426) (xy 439.280554 -45.22089) (xy 439.432954 -45.22089)
				(xy 439.432954 -44.922694) (xy 439.588148 -44.7675)
			)
		)
	)
	(zone
		(layer "In4.Cu")
		(hatch none 0.5)
		(connect_pads
			(clearance 0)
		)
		(min_thickness 0.25)
		(keepout
			(tracks not_allowed)
			(vias allowed)
			(pads allowed)
			(copperpour not_allowed)
			(footprints allowed)
		)
		(placement
			(enabled no)
			(sheetname "")
		)
		(fill
			(thermal_gap 0.5)
			(thermal_bridge_width 0.5)
			(island_removal_mode 0)
		)
		(polygon
			(pts
				(arc
					(start 454.129648 -53.684424)
					(mid 454.653565 -53.754274)
					(end 454.129648 -53.824124)
				)
				(xy 454.041256 -53.824124) (xy 453.96785 -53.89753) (xy 453.96785 -54.137814)
				(arc
					(start 454.386696 -54.137814)
					(mid 454.77049 -53.754401)
					(end 454.38695 -53.370734)
				)
				(arc
					(start 453.11695 -53.370734)
					(mid 452.73341 -53.754274)
					(end 453.11695 -54.137814)
				)
				(xy 453.53605 -54.137814) (xy 453.53605 -53.89753) (xy 453.462644 -53.824124)
				(arc
					(start 453.374252 -53.824124)
					(mid 452.850335 -53.754274)
					(end 453.374252 -53.684424)
				)
				(xy 453.520556 -53.684424) (xy 453.67575 -53.839618) (xy 453.67575 -54.137814) (xy 453.82815 -54.137814)
				(xy 453.82815 -53.839618) (xy 453.983344 -53.684424)
			)
		)
	)
	(zone
		(net "PVCCIO_CPU1")
		(layer "In4.Cu")
		(hatch none 0.5)
		(connect_pads
			(clearance 0.5)
		)
		(min_thickness 0.25)
		(fill yes
			(thermal_gap 0.5)
			(thermal_bridge_width 0.5)
			(island_removal_mode 0)
		)
		(polygon
			(pts
				(xy 144.38122 -52.57038) (xy 125.807978 -52.57038) (xy 124.510546 -53.867812) (xy 124.510546 -55.194454)
				(xy 124.50064 -55.20436) (xy 124.50064 -58.56478) (xy 124.49683 -58.56859) (xy 124.49683 -60.49137)
				(xy 123.5456 -61.4426) (xy 121.62282 -61.4426) (xy 120.8278 -61.4426) (xy 119.88038 -62.39002) (xy 113.32464 -62.39002)
				(xy 111.74476 -60.81014) (xy 110.20806 -60.81014) (xy 109.41304 -61.60516) (xy 109.41304 -63.53048)
				(xy 113.03254 -67.14998) (xy 113.03254 -79.35214) (xy 115.5954 -81.915) (xy 115.6462 -81.915) (xy 118.9228 -85.1916)
				(xy 121.3612 -85.1916) (xy 122.047 -84.5058) (xy 122.047 -80.0608) (xy 119.7356 -77.7494) (xy 119.7356 -70.9422)
				(xy 118.5926 -69.7992) (xy 118.5926 -66.7004) (xy 119.12346 -66.16954) (xy 121.15038 -66.16954)
				(xy 122.1867 -65.13322) (xy 122.89028 -65.13322) (xy 123.76658 -64.25692) (xy 124.98578 -64.25692)
				(xy 126.59614 -62.64656) (xy 133.467094 -62.64656) (xy 134.416038 -61.697616) (xy 140.715492 -61.697616)
				(xy 141.216634 -62.198758) (xy 144.581372 -62.198758) (xy 144.750028 -62.367414) (xy 148.064982 -62.367414)
				(xy 148.149564 -62.451996) (xy 162.832796 -62.451996) (xy 167.381428 -57.903364) (xy 167.381428 -53.429408)
				(xy 167.381428 -49.728628) (xy 167.381428 -44.790868) (xy 166.15664 -43.56608) (xy 153.38552 -43.56608)
				(xy 149.352 -47.5996)
			)
		)
	)
	(zone
		(layer "In4.Cu")
		(hatch none 0.5)
		(connect_pads
			(clearance 0)
		)
		(min_thickness 0.25)
		(keepout
			(tracks not_allowed)
			(vias allowed)
			(pads allowed)
			(copperpour not_allowed)
			(footprints allowed)
		)
		(placement
			(enabled no)
			(sheetname "")
		)
		(fill
			(thermal_gap 0.5)
			(thermal_bridge_width 0.5)
			(island_removal_mode 0)
		)
		(polygon
			(pts
				(arc
					(start 393.104116 -3.148838)
					(mid 393.629957 -3.120629)
					(end 393.139168 -3.311398)
				)
				(xy 393.05865 -3.391916) (xy 393.05865 -3.560064)
				(arc
					(start 393.369038 -3.560064)
					(mid 393.752832 -3.176651)
					(end 393.369292 -2.792984)
				)
				(arc
					(start 392.353292 -2.792984)
					(mid 391.969752 -3.176524)
					(end 392.353292 -3.560064)
				)
				(xy 392.62685 -3.560064) (xy 392.62685 -3.384296)
				(arc
					(start 392.571986 -3.329432)
					(mid 392.099336 -3.095313)
					(end 392.619992 -3.179826)
				)
				(xy 392.76655 -3.326384) (xy 392.76655 -3.560064) (xy 392.91895 -3.560064) (xy 392.91895 -3.334004)
			)
		)
	)
	(zone
		(net "GND")
		(layer "In4.Cu")
		(hatch none 0.5)
		(connect_pads
			(clearance 0.5)
		)
		(min_thickness 0.25)
		(fill yes
			(thermal_gap 0.5)
			(thermal_bridge_width 0.5)
			(island_removal_mode 0)
		)
		(polygon
			(pts
				(xy 199.4916 -51.7144) (xy 199.348852 -51.857148) (xy 199.348852 -54.32806) (xy 199.349868 -54.329076)
				(xy 199.349868 -92.831158) (xy 199.4662 -92.94749) (xy 199.54875 -93.03004) (xy 207.689196 -93.03004)
				(xy 207.8482 -92.871036) (xy 207.8482 -53.213) (xy 207.1878 -52.5526) (xy 206.248 -52.5526) (xy 206.0702 -52.3748)
				(xy 204.8256 -52.3748) (xy 204.1652 -51.7144)
			)
		)
	)
	(zone
		(net "P1V8_MCP_CPU0")
		(layer "In4.Cu")
		(hatch none 0.5)
		(connect_pads
			(clearance 0.5)
		)
		(min_thickness 0.25)
		(fill yes
			(thermal_gap 0.5)
			(thermal_bridge_width 0.5)
			(island_removal_mode 0)
		)
		(polygon
			(pts
				(xy 329.438508 -37.897308) (xy 329.438508 -39.040816) (xy 329.153774 -39.32555) (xy 328.19213 -39.32555)
				(xy 326.06742 -41.45026) (xy 324.53834 -42.97934) (xy 323.01434 -42.97934) (xy 323.0118 -42.9768)
				(xy 322.185538 -42.9768) (xy 321.979544 -42.770806) (xy 321.12077 -42.770806) (xy 321.028822 -42.678858)
				(xy 320.715132 -42.678858) (xy 320.41719 -42.9768) (xy 319.2272 -42.9768) (xy 318.3509 -42.9768)
				(xy 316.930532 -44.397168) (xy 316.54115 -44.397168) (xy 316.018418 -44.9199) (xy 314.8076 -44.9199)
				(xy 314.7441 -44.9834) (xy 312.51906 -47.20844) (xy 311.52084 -47.20844) (xy 311.2008 -46.8884)
				(xy 311.2008 -45.97273) (xy 311.2008 -45.3136) (xy 311.2008 -43.5356) (xy 315.1886 -39.5478) (xy 318.2874 -39.5478)
				(xy 321.420744 -36.414456) (xy 322.30949 -36.414456) (xy 322.393818 -36.330128) (xy 322.408042 -36.330128)
				(xy 323.262752 -36.330128) (xy 323.573394 -36.019486) (xy 323.573394 -35.954462) (xy 323.612256 -35.9156)
				(xy 327.4568 -35.9156)
			)
		)
	)
	(zone
		(layer "In4.Cu")
		(hatch none 0.5)
		(connect_pads
			(clearance 0)
		)
		(min_thickness 0.25)
		(keepout
			(tracks allowed)
			(vias allowed)
			(pads allowed)
			(copperpour allowed)
			(footprints allowed)
		)
		(placement
			(enabled no)
			(sheetname "")
		)
		(fill
			(thermal_gap 0.5)
			(thermal_bridge_width 0.5)
			(island_removal_mode 0)
		)
		(polygon
			(pts
				(xy 68.298568 -44.831) (xy 71.346568 -44.831) (xy 76.172568 -49.657) (xy 76.172568 -53.34) (xy 74.902568 -54.61)
				(xy 70.076568 -54.61) (xy 64.488568 -49.022) (xy 64.488568 -48.641)
			)
		)
	)
	(zone
		(layer "In4.Cu")
		(hatch none 0.5)
		(connect_pads
			(clearance 0)
		)
		(min_thickness 0.25)
		(keepout
			(tracks not_allowed)
			(vias allowed)
			(pads allowed)
			(copperpour not_allowed)
			(footprints allowed)
		)
		(placement
			(enabled no)
			(sheetname "")
		)
		(fill
			(thermal_gap 0.5)
			(thermal_bridge_width 0.5)
			(island_removal_mode 0)
		)
		(polygon
			(pts
				(arc
					(start 447.728848 -53.684424)
					(mid 448.252765 -53.754274)
					(end 447.728848 -53.824124)
				)
				(xy 447.640456 -53.824124) (xy 447.531744 -53.932836) (xy 447.531744 -54.137814)
				(arc
					(start 447.985896 -54.137814)
					(mid 448.36969 -53.754401)
					(end 447.98615 -53.370734)
				)
				(arc
					(start 446.71615 -53.370734)
					(mid 446.33261 -53.754274)
					(end 446.71615 -54.137814)
				)
				(xy 447.099944 -54.137814) (xy 447.099944 -53.862224) (xy 447.061844 -53.824124)
				(arc
					(start 446.973452 -53.824124)
					(mid 446.449535 -53.754274)
					(end 446.973452 -53.684424)
				)
				(xy 447.119756 -53.684424) (xy 447.239644 -53.804312) (xy 447.239644 -54.137814) (xy 447.392044 -54.137814)
				(xy 447.392044 -53.874924) (xy 447.582544 -53.684424)
			)
		)
	)
	(zone
		(layer "In4.Cu")
		(hatch none 0.5)
		(connect_pads
			(clearance 0)
		)
		(min_thickness 0.25)
		(keepout
			(tracks not_allowed)
			(vias allowed)
			(pads allowed)
			(copperpour not_allowed)
			(footprints allowed)
		)
		(placement
			(enabled no)
			(sheetname "")
		)
		(fill
			(thermal_gap 0.5)
			(thermal_bridge_width 0.5)
			(island_removal_mode 0)
		)
		(polygon
			(pts
				(arc
					(start 442.919866 -44.7675)
					(mid 443.443783 -44.83735)
					(end 442.919866 -44.9072)
				)
				(xy 442.831728 -44.9072) (xy 442.758068 -44.98086) (xy 442.758068 -45.22089)
				(arc
					(start 443.177168 -45.22089)
					(mid 443.560708 -44.83735)
					(end 443.177168 -44.45381)
				)
				(arc
					(start 441.907422 -44.45381)
					(mid 441.523882 -44.837223)
					(end 441.907168 -45.22089)
				)
				(xy 442.326268 -45.22089) (xy 442.326268 -44.980606) (xy 442.252862 -44.9072)
				(arc
					(start 442.16447 -44.9072)
					(mid 441.640553 -44.83735)
					(end 442.16447 -44.7675)
				)
				(xy 442.310774 -44.7675) (xy 442.465968 -44.922694) (xy 442.465968 -45.22089) (xy 442.618368 -45.22089)
				(xy 442.618368 -44.922948) (xy 442.773816 -44.7675)
			)
		)
	)
	(zone
		(layer "In4.Cu")
		(hatch none 0.5)
		(connect_pads
			(clearance 0)
		)
		(min_thickness 0.25)
		(keepout
			(tracks allowed)
			(vias allowed)
			(pads allowed)
			(copperpour allowed)
			(footprints allowed)
		)
		(placement
			(enabled no)
			(sheetname "")
		)
		(fill
			(thermal_gap 0.5)
			(thermal_bridge_width 0.5)
			(island_removal_mode 0)
		)
		(polygon
			(pts
				(xy 382.905 -33.655) (xy 382.905 -32.512) (xy 384.048 -32.512) (xy 384.048 -33.655)
			)
		)
	)
	(zone
		(layer "In4.Cu")
		(hatch none 0.5)
		(connect_pads
			(clearance 0)
		)
		(min_thickness 0.25)
		(keepout
			(tracks not_allowed)
			(vias allowed)
			(pads allowed)
			(copperpour not_allowed)
			(footprints allowed)
		)
		(placement
			(enabled no)
			(sheetname "")
		)
		(fill
			(thermal_gap 0.5)
			(thermal_bridge_width 0.5)
			(island_removal_mode 0)
		)
		(polygon
			(pts
				(arc
					(start 452.519796 -44.7675)
					(mid 453.043713 -44.83735)
					(end 452.519796 -44.9072)
				)
				(xy 452.431658 -44.9072) (xy 452.357998 -44.98086) (xy 452.357998 -45.22089)
				(arc
					(start 452.776844 -45.22089)
					(mid 453.160638 -44.837477)
					(end 452.777098 -44.45381)
				)
				(arc
					(start 451.507098 -44.45381)
					(mid 451.123558 -44.83735)
					(end 451.507098 -45.22089)
				)
				(xy 451.926198 -45.22089) (xy 451.926198 -44.980606) (xy 451.852792 -44.9072)
				(arc
					(start 451.7644 -44.9072)
					(mid 451.240483 -44.83735)
					(end 451.7644 -44.7675)
				)
				(xy 451.910704 -44.7675) (xy 452.065898 -44.922694) (xy 452.065898 -45.22089) (xy 452.218298 -45.22089)
				(xy 452.218298 -44.922948) (xy 452.373746 -44.7675)
			)
		)
	)
	(zone
		(net "GND")
		(layer "In4.Cu")
		(hatch none 0.5)
		(connect_pads
			(clearance 0.5)
		)
		(min_thickness 0.25)
		(fill yes
			(thermal_gap 0.5)
			(thermal_bridge_width 0.5)
			(island_removal_mode 0)
		)
		(polygon
			(pts
				(arc
					(start -5.184648 -161.9504)
					(mid -5.224047 -162.020639)
					(end -5.237734 -162.100006)
				)
				(arc
					(start -5.237734 -168.099994)
					(mid -5.1681 -168.268104)
					(end -4.99999 -168.337738)
				)
				(xy 501.0404 -168.337738) (xy 501.0404 -161.9504)
			)
		)
		(polygon
			(pts
				(xy 322.2498 -162.5346) (xy 316.23 -162.5346) (xy 316.23 -167.5384) (xy 322.2498 -167.5384) (xy 388.6708 -167.5384)
				(xy 388.6708 -162.5346)
			)
		)
		(polygon
			(pts
				(xy 114.935 -162.5346) (xy 108.6104 -162.5346) (xy 108.6104 -167.5384) (xy 114.935 -167.5384) (xy 142.8242 -167.5384)
				(xy 142.8242 -167.513) (xy 149.225 -167.513) (xy 149.225 -162.5346) (xy 142.8242 -162.5346)
			)
		)
	)
	(zone
		(layer "In4.Cu")
		(hatch none 0.5)
		(connect_pads
			(clearance 0)
		)
		(min_thickness 0.25)
		(keepout
			(tracks not_allowed)
			(vias allowed)
			(pads allowed)
			(copperpour not_allowed)
			(footprints allowed)
		)
		(placement
			(enabled no)
			(sheetname "")
		)
		(fill
			(thermal_gap 0.5)
			(thermal_bridge_width 0.5)
			(island_removal_mode 0)
		)
		(polygon
			(pts
				(xy 456.60945 -123.823222) (xy 456.590908 -123.80468)
				(arc
					(start 456.216004 -123.80468)
					(mid 455.83221 -124.188093)
					(end 456.21575 -124.57176)
				)
				(arc
					(start 457.48575 -124.57176)
					(mid 457.86929 -124.18822)
					(end 457.48575 -123.80468)
				)
				(xy 457.04125 -123.80468) (xy 457.04125 -124.019564) (xy 457.140056 -124.11837)
				(arc
					(start 457.228448 -124.11837)
					(mid 457.752365 -124.18822)
					(end 457.228448 -124.25807)
				)
				(xy 457.082144 -124.25807) (xy 456.90155 -124.077476) (xy 456.90155 -123.80468) (xy 456.74915 -123.80468)
				(xy 456.74915 -124.128276) (xy 456.619356 -124.25807)
				(arc
					(start 456.473052 -124.25807)
					(mid 455.949135 -124.18822)
					(end 456.473052 -124.11837)
				)
				(xy 456.561444 -124.11837) (xy 456.60945 -124.070364)
			)
		)
	)
	(zone
		(layer "In4.Cu")
		(hatch none 0.5)
		(connect_pads
			(clearance 0)
		)
		(min_thickness 0.25)
		(keepout
			(tracks not_allowed)
			(vias allowed)
			(pads allowed)
			(copperpour not_allowed)
			(footprints allowed)
		)
		(placement
			(enabled no)
			(sheetname "")
		)
		(fill
			(thermal_gap 0.5)
			(thermal_bridge_width 0.5)
			(island_removal_mode 0)
		)
		(polygon
			(pts
				(arc
					(start 357.348282 -106.067352)
					(mid 357.418132 -105.543435)
					(end 357.487982 -106.067352)
				)
				(xy 357.487982 -106.142282) (xy 357.561388 -106.215688) (xy 357.801672 -106.215688)
				(arc
					(start 357.801672 -105.81005)
					(mid 357.418132 -105.42651)
					(end 357.034592 -105.81005)
				)
				(arc
					(start 357.034592 -107.079796)
					(mid 357.418005 -107.46359)
					(end 357.801672 -107.08005)
				)
				(xy 357.801672 -106.647488) (xy 357.561388 -106.647488) (xy 357.487982 -106.720894)
				(arc
					(start 357.487982 -106.822748)
					(mid 357.418132 -107.346665)
					(end 357.348282 -106.822748)
				)
				(xy 357.348282 -106.662982) (xy 357.503476 -106.507788) (xy 357.801672 -106.507788) (xy 357.801672 -106.355388)
				(xy 357.503476 -106.355388) (xy 357.348282 -106.200194)
			)
		)
	)
	(zone
		(layer "In4.Cu")
		(hatch none 0.5)
		(connect_pads
			(clearance 0)
		)
		(min_thickness 0.25)
		(keepout
			(tracks not_allowed)
			(vias allowed)
			(pads allowed)
			(copperpour not_allowed)
			(footprints allowed)
		)
		(placement
			(enabled no)
			(sheetname "")
		)
		(fill
			(thermal_gap 0.5)
			(thermal_bridge_width 0.5)
			(island_removal_mode 0)
		)
		(polygon
			(pts
				(xy 448.81165 -123.441714) (xy 448.774566 -123.40463)
				(arc
					(start 448.392804 -123.40463)
					(mid 448.00901 -123.788043)
					(end 448.39255 -124.17171)
				)
				(arc
					(start 449.66255 -124.17171)
					(mid 450.04609 -123.78817)
					(end 449.66255 -123.40463)
				)
				(xy 449.24345 -123.40463) (xy 449.24345 -123.644914) (xy 449.316856 -123.71832)
				(arc
					(start 449.405248 -123.71832)
					(mid 449.929165 -123.78817)
					(end 449.405248 -123.85802)
				)
				(xy 449.258944 -123.85802) (xy 449.10375 -123.702826) (xy 449.10375 -123.40463) (xy 448.95135 -123.40463)
				(xy 448.95135 -123.702826) (xy 448.796156 -123.85802)
				(arc
					(start 448.649852 -123.85802)
					(mid 448.125935 -123.78817)
					(end 448.649852 -123.71832)
				)
				(xy 448.738244 -123.71832) (xy 448.81165 -123.644914)
			)
		)
	)
	(zone
		(layer "In4.Cu")
		(hatch none 0.5)
		(connect_pads
			(clearance 0)
		)
		(min_thickness 0.25)
		(keepout
			(tracks not_allowed)
			(vias allowed)
			(pads allowed)
			(copperpour not_allowed)
			(footprints allowed)
		)
		(placement
			(enabled no)
			(sheetname "")
		)
		(fill
			(thermal_gap 0.5)
			(thermal_bridge_width 0.5)
			(island_removal_mode 0)
		)
		(polygon
			(pts
				(xy 378.551186 -1.685036) (xy 378.70638 -1.84023) (xy 378.70638 -2.138426) (xy 378.85878 -2.138426)
				(xy 378.85878 -1.84023) (xy 379.013974 -1.685036)
				(arc
					(start 379.160278 -1.685036)
					(mid 379.684195 -1.754886)
					(end 379.160278 -1.824736)
				)
				(xy 379.071886 -1.824736) (xy 378.99848 -1.898142) (xy 378.99848 -2.138426)
				(arc
					(start 379.417326 -2.138426)
					(mid 379.800866 -1.755013)
					(end 379.41758 -1.371346)
				)
				(arc
					(start 378.14758 -1.371346)
					(mid 377.76404 -1.754886)
					(end 378.14758 -2.138426)
				)
				(xy 378.56668 -2.138426) (xy 378.56668 -1.898142) (xy 378.493274 -1.824736)
				(arc
					(start 378.404882 -1.824736)
					(mid 377.880965 -1.754886)
					(end 378.404882 -1.685036)
				)
			)
		)
	)
	(zone
		(layer "In4.Cu")
		(hatch none 0.5)
		(connect_pads
			(clearance 0)
		)
		(min_thickness 0.25)
		(keepout
			(tracks not_allowed)
			(vias allowed)
			(pads allowed)
			(copperpour not_allowed)
			(footprints allowed)
		)
		(placement
			(enabled no)
			(sheetname "")
		)
		(fill
			(thermal_gap 0.5)
			(thermal_bridge_width 0.5)
			(island_removal_mode 0)
		)
		(polygon
			(pts
				(arc
					(start 357.11003 -103.934768)
					(mid 356.788865 -103.514797)
					(end 357.208836 -103.835962)
				)
				(xy 357.328724 -103.95585) (xy 357.360982 -103.95585)
				(arc
					(start 357.360982 -103.703374)
					(mid 356.977442 -103.319834)
					(end 356.593902 -103.703374)
				)
				(arc
					(start 356.593902 -104.97312)
					(mid 356.977315 -105.356914)
					(end 357.360982 -104.973374)
				)
				(xy 357.360982 -104.68864)
				(arc
					(start 357.208836 -104.840786)
					(mid 356.788865 -105.161951)
					(end 357.11003 -104.74198)
				)
				(xy 357.360982 -104.491028) (xy 357.360982 -104.09555) (xy 357.270812 -104.09555)
			)
		)
	)
	(zone
		(layer "In4.Cu")
		(hatch none 0.5)
		(connect_pads
			(clearance 0)
		)
		(min_thickness 0.25)
		(keepout
			(tracks allowed)
			(vias allowed)
			(pads allowed)
			(copperpour allowed)
			(footprints allowed)
		)
		(placement
			(enabled no)
			(sheetname "")
		)
		(fill
			(thermal_gap 0.5)
			(thermal_bridge_width 0.5)
			(island_removal_mode 0)
		)
		(polygon
			(pts
				(xy 286.16275 -49.02835) (xy 289.3314 -52.197) (xy 289.3187 -52.2097) (xy 290.0553 -52.2097) (xy 290.8808 -53.0352)
				(xy 289.7378 -54.1782) (xy 288.8488 -54.1782) (xy 288.6964 -54.0258) (xy 288.6964 -52.4764) (xy 288.2646 -52.4764)
				(xy 287.7312 -51.943) (xy 285.9532 -51.943) (xy 285.1404 -51.1302) (xy 284.0482 -51.1302) (xy 282.2194 -52.959)
				(xy 282.2194 -53.0098) (xy 282.0924 -53.1368) (xy 278.4602 -53.1368) (xy 278.2824 -53.3146) (xy 278.2824 -54.0258)
				(xy 276.098 -54.0258) (xy 275.9964 -53.9242) (xy 275.9964 -49.9364) (xy 278.2316 -47.7012) (xy 279.2095 -46.7233)
				(xy 285.8389 -46.7233) (xy 286.16275 -47.04715)
			)
		)
	)
	(zone
		(layer "In4.Cu")
		(hatch none 0.5)
		(connect_pads
			(clearance 0)
		)
		(min_thickness 0.25)
		(keepout
			(tracks allowed)
			(vias allowed)
			(pads allowed)
			(copperpour allowed)
			(footprints allowed)
		)
		(placement
			(enabled no)
			(sheetname "")
		)
		(fill
			(thermal_gap 0.5)
			(thermal_bridge_width 0.5)
			(island_removal_mode 0)
		)
		(polygon
			(pts
				(xy 368.554 -119.253) (xy 368.554 -117.602) (xy 370.84 -117.602) (xy 370.84 -119.253)
			)
		)
	)
	(zone
		(layer "In4.Cu")
		(hatch none 0.5)
		(connect_pads
			(clearance 0)
		)
		(min_thickness 0.25)
		(keepout
			(tracks allowed)
			(vias allowed)
			(pads allowed)
			(copperpour allowed)
			(footprints allowed)
		)
		(placement
			(enabled no)
			(sheetname "")
		)
		(fill
			(thermal_gap 0.5)
			(thermal_bridge_width 0.5)
			(island_removal_mode 0)
		)
		(polygon
			(pts
				(xy 16.129 -102.997) (xy 16.129 -102.362) (xy 16.891 -102.362) (xy 16.891 -102.997)
			)
		)
	)
	(zone
		(net "BMC_M_VREFCA")
		(layer "In4.Cu")
		(hatch none 0.5)
		(connect_pads
			(clearance 0.5)
		)
		(min_thickness 0.25)
		(fill yes
			(thermal_gap 0.5)
			(thermal_bridge_width 0.5)
			(island_removal_mode 0)
		)
		(polygon
			(pts
				(xy 417.4236 -32.253682) (xy 417.4236 -35.2044) (xy 417.6141 -35.3949) (xy 429.162464 -35.3949)
				(xy 429.407066 -35.150298) (xy 429.732948 -35.150298) (xy 429.97755 -35.3949) (xy 435.4957 -35.3949)
				(xy 435.62905 -35.3949) (xy 435.9402 -35.08375) (xy 440.65825 -35.08375) (xy 440.69 -35.052) (xy 441.452 -34.29)
				(xy 442.0489 -34.29) (xy 442.58865 -34.82975) (xy 443.79515 -34.82975) (xy 444.46825 -34.82975)
				(xy 444.7413 -34.5567) (xy 444.7413 -33.8836) (xy 444.7413 -33.8455) (xy 444.7413 -30.3403) (xy 443.7888 -29.3878)
				(xy 431.8635 -29.3878) (xy 429.6156 -31.6357) (xy 425.575476 -31.6357) (xy 425.305474 -31.905702)
				(xy 425.028868 -31.905702) (xy 424.758866 -31.6357) (xy 422.52138 -31.6357) (xy 422.08704 -32.07004)
				(xy 417.607242 -32.07004) (xy 417.606988 -32.07004) (xy 417.519104 -32.07004) (xy 417.4236 -32.165544)
			)
		)
	)
	(zone
		(layer "In4.Cu")
		(hatch none 0.5)
		(connect_pads
			(clearance 0)
		)
		(min_thickness 0.25)
		(keepout
			(tracks not_allowed)
			(vias allowed)
			(pads allowed)
			(copperpour not_allowed)
			(footprints allowed)
		)
		(placement
			(enabled no)
			(sheetname "")
		)
		(fill
			(thermal_gap 0.5)
			(thermal_bridge_width 0.5)
			(island_removal_mode 0)
		)
		(polygon
			(pts
				(arc
					(start 400.309334 -3.12166)
					(mid 400.834609 -3.142596)
					(end 400.33194 -3.296412)
				)
				(xy 400.252692 -3.37566) (xy 400.252692 -3.560064)
				(arc
					(start 400.569938 -3.560064)
					(mid 400.953732 -3.176651)
					(end 400.570192 -2.792984)
				)
				(arc
					(start 399.554192 -2.792984)
					(mid 399.170652 -3.176524)
					(end 399.554192 -3.560064)
				)
				(xy 399.820892 -3.560064) (xy 399.820892 -3.31978)
				(arc
					(start 399.794222 -3.29311)
					(mid 399.288954 -3.147277)
					(end 399.81378 -3.115056)
				)
				(xy 399.960592 -3.261868) (xy 399.960592 -3.560064) (xy 400.112992 -3.560064) (xy 400.112992 -3.317748)
			)
		)
	)
	(zone
		(net "GND")
		(layer "In4.Cu")
		(hatch none 0.5)
		(connect_pads
			(clearance 0.5)
		)
		(min_thickness 0.25)
		(fill yes
			(thermal_gap 0.5)
			(thermal_bridge_width 0.5)
			(island_removal_mode 0)
		)
		(polygon
			(pts
				(xy 199.4154 -93.740732) (xy 199.4154 -94.4499) (xy 199.40905 -94.45625) (xy 199.40905 -94.59595)
				(xy 199.40905 -101.707442) (xy 199.492108 -101.7905) (xy 201.33056 -101.7905) (xy 201.76617 -101.35489)
				(xy 206.41691 -101.35489) (xy 207.847692 -99.924108) (xy 207.847692 -93.748606) (xy 207.637634 -93.538548)
				(xy 199.617584 -93.538548)
			)
		)
	)
	(zone
		(layer "In4.Cu")
		(hatch none 0.5)
		(connect_pads
			(clearance 0)
		)
		(min_thickness 0.25)
		(keepout
			(tracks not_allowed)
			(vias allowed)
			(pads allowed)
			(copperpour not_allowed)
			(footprints allowed)
		)
		(placement
			(enabled no)
			(sheetname "")
		)
		(fill
			(thermal_gap 0.5)
			(thermal_bridge_width 0.5)
			(island_removal_mode 0)
		)
		(polygon
			(pts
				(arc
					(start 458.919834 -44.7675)
					(mid 459.443751 -44.83735)
					(end 458.919834 -44.9072)
				)
				(xy 458.831696 -44.9072) (xy 458.758036 -44.98086) (xy 458.758036 -45.22089)
				(arc
					(start 459.176882 -45.22089)
					(mid 459.560422 -44.837477)
					(end 459.177136 -44.45381)
				)
				(arc
					(start 457.907136 -44.45381)
					(mid 457.523596 -44.83735)
					(end 457.907136 -45.22089)
				)
				(xy 458.326236 -45.22089) (xy 458.326236 -44.980606) (xy 458.25283 -44.9072)
				(arc
					(start 458.164438 -44.9072)
					(mid 457.640521 -44.83735)
					(end 458.164438 -44.7675)
				)
				(xy 458.310742 -44.7675) (xy 458.465936 -44.922694) (xy 458.465936 -45.22089) (xy 458.618336 -45.22089)
				(xy 458.618336 -44.922948) (xy 458.773784 -44.7675)
			)
		)
	)
	(zone
		(layer "In4.Cu")
		(hatch none 0.5)
		(connect_pads
			(clearance 0)
		)
		(min_thickness 0.25)
		(keepout
			(tracks allowed)
			(vias allowed)
			(pads allowed)
			(copperpour allowed)
			(footprints allowed)
		)
		(placement
			(enabled no)
			(sheetname "")
		)
		(fill
			(thermal_gap 0.5)
			(thermal_bridge_width 0.5)
			(island_removal_mode 0)
		)
		(polygon
			(pts
				(xy 113.9952 4.7498) (xy 113.9952 5.2832) (xy 115.57 5.2832) (xy 115.57 4.7498)
			)
		)
	)
	(zone
		(layer "In4.Cu")
		(hatch none 0.5)
		(connect_pads
			(clearance 0)
		)
		(min_thickness 0.25)
		(keepout
			(tracks not_allowed)
			(vias allowed)
			(pads allowed)
			(copperpour not_allowed)
			(footprints allowed)
		)
		(placement
			(enabled no)
			(sheetname "")
		)
		(fill
			(thermal_gap 0.5)
			(thermal_bridge_width 0.5)
			(island_removal_mode 0)
		)
		(polygon
			(pts
				(arc
					(start 444.528448 -53.684424)
					(mid 445.052365 -53.754274)
					(end 444.528448 -53.824124)
				)
				(xy 444.440056 -53.824124) (xy 444.36665 -53.89753) (xy 444.36665 -54.137814)
				(arc
					(start 444.785496 -54.137814)
					(mid 445.16929 -53.754401)
					(end 444.78575 -53.370734)
				)
				(arc
					(start 443.51575 -53.370734)
					(mid 443.13221 -53.754274)
					(end 443.51575 -54.137814)
				)
				(xy 443.93485 -54.137814) (xy 443.93485 -53.89753) (xy 443.861444 -53.824124)
				(arc
					(start 443.773052 -53.824124)
					(mid 443.249135 -53.754274)
					(end 443.773052 -53.684424)
				)
				(xy 443.919356 -53.684424) (xy 444.07455 -53.839618) (xy 444.07455 -54.137814) (xy 444.22695 -54.137814)
				(xy 444.22695 -53.839618) (xy 444.382144 -53.684424)
			)
		)
	)
	(zone
		(layer "In4.Cu")
		(hatch none 0.5)
		(connect_pads
			(clearance 0)
		)
		(min_thickness 0.25)
		(keepout
			(tracks not_allowed)
			(vias allowed)
			(pads allowed)
			(copperpour not_allowed)
			(footprints allowed)
		)
		(placement
			(enabled no)
			(sheetname "")
		)
		(fill
			(thermal_gap 0.5)
			(thermal_bridge_width 0.5)
			(island_removal_mode 0)
		)
		(polygon
			(pts
				(xy 402.231098 -2.81432) (xy 402.386292 -2.969514) (xy 402.386292 -3.227832) (xy 402.346414 -3.26771)
				(xy 402.538692 -3.26771) (xy 402.538692 -2.969514) (xy 402.693886 -2.81432)
				(arc
					(start 402.84019 -2.81432)
					(mid 403.364107 -2.88417)
					(end 402.84019 -2.95402)
				)
				(xy 402.751798 -2.95402) (xy 402.678392 -3.027426) (xy 402.678392 -3.26771)
				(arc
					(start 403.097238 -3.26771)
					(mid 403.481032 -2.884297)
					(end 403.097492 -2.50063)
				)
				(arc
					(start 401.827492 -2.50063)
					(mid 401.443952 -2.88417)
					(end 401.827492 -3.26771)
				)
				(xy 402.148548 -3.26771) (xy 402.246592 -3.169666) (xy 402.246592 -3.027426) (xy 402.173186 -2.95402)
				(arc
					(start 402.084794 -2.95402)
					(mid 401.560877 -2.88417)
					(end 402.084794 -2.81432)
				)
			)
		)
	)
	(zone
		(layer "In4.Cu")
		(hatch none 0.5)
		(connect_pads
			(clearance 0)
		)
		(min_thickness 0.25)
		(keepout
			(tracks not_allowed)
			(vias allowed)
			(pads allowed)
			(copperpour not_allowed)
			(footprints allowed)
		)
		(placement
			(enabled no)
			(sheetname "")
		)
		(fill
			(thermal_gap 0.5)
			(thermal_bridge_width 0.5)
			(island_removal_mode 0)
		)
		(polygon
			(pts
				(xy 15.409926 -108.48467) (xy 15.56512 -108.639864)
				(arc
					(start 15.56512 -108.786168)
					(mid 15.49527 -109.310085)
					(end 15.42542 -108.786168)
				)
				(xy 15.42542 -108.697776) (xy 15.352014 -108.62437) (xy 15.116556 -108.62437) (xy 15.11173 -108.619544)
				(arc
					(start 15.11173 -109.043216)
					(mid 15.495143 -109.42701)
					(end 15.87881 -109.04347)
				)
				(arc
					(start 15.87881 -107.77347)
					(mid 15.49527 -107.38993)
					(end 15.11173 -107.77347)
				)
				(xy 15.11173 -108.008674) (xy 15.295626 -108.19257) (xy 15.352014 -108.19257) (xy 15.42542 -108.119164)
				(arc
					(start 15.42542 -108.030772)
					(mid 15.49527 -107.506855)
					(end 15.56512 -108.030772)
				)
				(xy 15.56512 -108.177076) (xy 15.409926 -108.33227) (xy 15.237714 -108.33227) (xy 15.11173 -108.206286)
				(xy 15.11173 -108.421932) (xy 15.174468 -108.48467)
			)
		)
	)
	(zone
		(layer "In4.Cu")
		(hatch none 0.5)
		(connect_pads
			(clearance 0)
		)
		(min_thickness 0.25)
		(keepout
			(tracks not_allowed)
			(vias allowed)
			(pads allowed)
			(copperpour not_allowed)
			(footprints allowed)
		)
		(placement
			(enabled no)
			(sheetname "")
		)
		(fill
			(thermal_gap 0.5)
			(thermal_bridge_width 0.5)
			(island_removal_mode 0)
		)
		(polygon
			(pts
				(xy 407.313892 -3.26771) (xy 407.313892 -2.990088) (xy 407.48966 -2.81432)
				(arc
					(start 407.64079 -2.81432)
					(mid 408.164707 -2.88417)
					(end 407.64079 -2.95402)
				)
				(xy 407.547572 -2.95402) (xy 407.453592 -3.048) (xy 407.453592 -3.26771)
				(arc
					(start 407.897838 -3.26771)
					(mid 408.281632 -2.884297)
					(end 407.898092 -2.50063)
				)
				(arc
					(start 406.628092 -2.50063)
					(mid 406.244552 -2.88417)
					(end 406.628092 -3.26771)
				)
				(xy 407.011378 -3.26771) (xy 407.021792 -3.253232) (xy 407.021792 -3.027426) (xy 406.948386 -2.95402)
				(arc
					(start 406.885394 -2.95402)
					(mid 406.361477 -2.88417)
					(end 406.885394 -2.81432)
				)
				(xy 407.006298 -2.81432) (xy 407.161492 -2.969514) (xy 407.161492 -3.26771)
			)
		)
	)
	(zone
		(layer "In4.Cu")
		(hatch none 0.5)
		(connect_pads
			(clearance 0)
		)
		(min_thickness 0.25)
		(keepout
			(tracks allowed)
			(vias allowed)
			(pads allowed)
			(copperpour allowed)
			(footprints allowed)
		)
		(placement
			(enabled no)
			(sheetname "")
		)
		(fill
			(thermal_gap 0.5)
			(thermal_bridge_width 0.5)
			(island_removal_mode 0)
		)
		(polygon
			(pts
				(xy 389.001 -129.54) (xy 389.001 -128.397) (xy 390.398 -128.397) (xy 390.398 -129.54)
			)
		)
	)
	(zone
		(net "PVCCIO_CPU0")
		(layer "In4.Cu")
		(hatch none 0.5)
		(connect_pads
			(clearance 0.5)
		)
		(min_thickness 0.25)
		(fill yes
			(thermal_gap 0.5)
			(thermal_bridge_width 0.5)
			(island_removal_mode 0)
		)
		(polygon
			(pts
				(xy 276.706838 -64.940942) (xy 275.274024 -64.066674) (xy 275.274024 -62.86246) (xy 275.28139 -62.855094)
				(xy 275.28139 -62.85484) (xy 276.073616 -62.062614) (xy 278.195024 -62.062614) (xy 278.957024 -62.824614)
				(xy 282.259024 -62.824614) (xy 283.65958 -62.824614) (xy 283.65958 -63.18758) (xy 283.65958 -63.238126)
				(xy 283.972762 -63.551308) (xy 283.972762 -66.197988) (xy 284.467554 -66.69278) (xy 284.5308 -66.69278)
				(xy 288.544 -66.69278) (xy 291.44976 -63.78702) (xy 291.465 -63.78702) (xy 291.5158 -63.73622) (xy 291.5158 -62.78626)
				(xy 291.3126 -62.58306) (xy 291.3126 -57.80024) (xy 293.19982 -55.91302) (xy 295.05402 -55.91302)
				(xy 295.2877 -56.1467) (xy 295.2877 -66.9163) (xy 294.4622 -67.7418) (xy 294.4622 -72.3392) (xy 293.9796 -72.8218)
				(xy 293.9796 -74.5744) (xy 294.64 -75.2348) (xy 295.1734 -75.2348) (xy 296.2656 -74.1426) (xy 296.2656 -68.4784)
				(xy 296.3418 -68.4784) (xy 297.0784 -67.7418) (xy 297.0784 -54.868064) (xy 297.082464 -54.864) (xy 298.098464 -53.848)
				(xy 299.0342 -53.848) (xy 299.6438 -53.2384) (xy 300.034452 -52.847748) (xy 300.068996 -52.847748)
				(xy 302.091852 -52.847748) (xy 302.3108 -52.6288) (xy 304.5206 -52.6288) (xy 307.5686 -55.6768)
				(xy 307.5686 -64.893444) (xy 306.765198 -65.696846) (xy 306.765198 -66.425064) (xy 306.765198 -71.542402)
				(xy 306.534312 -71.773288) (xy 305.9176 -72.39) (xy 305.262788 -73.044812) (xy 303.569624 -73.044812)
				(xy 303.247806 -73.36663) (xy 301.233078 -73.36663) (xy 299.81779 -74.781918) (xy 299.81779 -75.64755)
				(xy 300.01464 -75.8444) (xy 301.166784 -76.996544) (xy 301.166784 -77.301852) (xy 300.955202 -77.513434)
				(xy 300.955202 -77.926438) (xy 301.166784 -78.13802) (xy 301.35068 -78.321916) (xy 301.35068 -79.299562)
				(xy 301.227744 -79.422498) (xy 300.863508 -79.422498) (xy 300.747176 -79.53883) (xy 300.747176 -80.370934)
				(xy 300.747176 -80.603598) (xy 301.35068 -81.207102) (xy 301.35068 -85.9282) (xy 300.56201 -86.71687)
				(xy 300.56201 -89.48039) (xy 299.41266 -90.62974) (xy 298.46524 -90.62974) (xy 296.51452 -92.58046)
				(xy 291.57676 -92.58046) (xy 289.65398 -90.65768) (xy 289.65398 -90.65387) (xy 289.397694 -90.397584)
				(xy 289.397694 -85.163406) (xy 289.397948 -85.163152) (xy 289.397948 -84.903818) (xy 290.291774 -84.009992)
				(xy 290.31184 -83.989926) (xy 290.571174 -83.989926) (xy 291.14496 -83.41614) (xy 294.359076 -80.202024)
				(xy 294.844724 -80.202024) (xy 295.206928 -79.83982) (xy 295.329864 -79.71663) (xy 295.329864 -79.231236)
				(xy 295.329864 -78.126082) (xy 295.489122 -77.96657) (xy 295.572434 -77.96657) (xy 295.580562 -77.958442)
				(xy 295.580562 -77.934566) (xy 295.089326 -77.44333) (xy 295.080944 -77.44333) (xy 294.805862 -77.44333)
				(xy 293.59479 -77.44333) (xy 286.588454 -84.449666) (xy 286.513524 -84.449666) (xy 286.463994 -84.499196)
				(xy 286.463994 -84.501736) (xy 285.80715 -85.15858) (xy 281.30754 -85.15858) (xy 280.560272 -85.15858)
				(xy 277.33752 -81.935828) (xy 277.33752 -81.18856) (xy 277.33752 -66.952368) (xy 277.026116 -66.640964)
				(xy 277.026116 -65.26022)
			)
		)
	)
	(zone
		(layer "In4.Cu")
		(hatch none 0.5)
		(connect_pads
			(clearance 0)
		)
		(min_thickness 0.25)
		(keepout
			(tracks not_allowed)
			(vias allowed)
			(pads allowed)
			(copperpour not_allowed)
			(footprints allowed)
		)
		(placement
			(enabled no)
			(sheetname "")
		)
		(fill
			(thermal_gap 0.5)
			(thermal_bridge_width 0.5)
			(island_removal_mode 0)
		)
		(polygon
			(pts
				(arc
					(start 441.317634 -53.684424)
					(mid 441.841475 -53.747925)
					(end 441.32119 -53.836316)
				)
				(xy 441.12815 -54.029356) (xy 441.12815 -54.137814)
				(arc
					(start 441.574682 -54.137814)
					(mid 441.958222 -53.754401)
					(end 441.574936 -53.370734)
				)
				(arc
					(start 440.304936 -53.370734)
					(mid 439.921396 -53.754274)
					(end 440.304936 -54.137814)
				)
				(xy 440.68238 -54.137814) (xy 440.69635 -54.123844) (xy 440.69635 -54.029356)
				(arc
					(start 440.542426 -53.875432)
					(mid 440.040749 -53.717312)
					(end 440.566556 -53.70195)
				)
				(xy 440.83605 -53.971444) (xy 440.83605 -54.137814) (xy 440.98845 -54.137814) (xy 440.98845 -53.971444)
				(xy 441.27547 -53.684424)
			)
		)
	)
	(zone
		(layer "In4.Cu")
		(hatch none 0.5)
		(connect_pads
			(clearance 0)
		)
		(min_thickness 0.25)
		(keepout
			(tracks not_allowed)
			(vias allowed)
			(pads allowed)
			(copperpour not_allowed)
			(footprints allowed)
		)
		(placement
			(enabled no)
			(sheetname "")
		)
		(fill
			(thermal_gap 0.5)
			(thermal_bridge_width 0.5)
			(island_removal_mode 0)
		)
		(polygon
			(pts
				(arc
					(start 34.926524 -108.713016)
					(mid 31.701532 -105.819373)
					(end 36.024566 -105.52557)
				)
				(xy 36.024566 -107.614974)
			)
		)
	)
	(zone
		(layer "In4.Cu")
		(hatch none 0.5)
		(connect_pads
			(clearance 0)
		)
		(min_thickness 0.25)
		(keepout
			(tracks not_allowed)
			(vias allowed)
			(pads allowed)
			(copperpour not_allowed)
			(footprints allowed)
		)
		(placement
			(enabled no)
			(sheetname "")
		)
		(fill
			(thermal_gap 0.5)
			(thermal_bridge_width 0.5)
			(island_removal_mode 0)
		)
		(polygon
			(pts
				(arc
					(start 409.91028 -1.3081)
					(mid 410.434189 -1.375979)
					(end 409.911296 -1.45161)
				)
				(xy 409.707334 -1.655572) (xy 409.707334 -1.76149)
				(arc
					(start 410.167328 -1.76149)
					(mid 410.550868 -1.378077)
					(end 410.167582 -0.99441)
				)
				(arc
					(start 408.897582 -0.99441)
					(mid 408.514042 -1.37795)
					(end 408.897582 -1.76149)
				)
				(xy 409.275534 -1.76149) (xy 409.275534 -1.655572)
				(arc
					(start 409.129484 -1.509522)
					(mid 408.635933 -1.325768)
					(end 409.16225 -1.344422)
				)
				(xy 409.166822 -1.348994) (xy 409.166822 -1.349248) (xy 409.415234 -1.59766) (xy 409.415234 -1.76149)
				(xy 409.567634 -1.76149) (xy 409.567634 -1.59766) (xy 409.857194 -1.3081)
			)
		)
	)
	(zone
		(layer "In4.Cu")
		(hatch none 0.5)
		(connect_pads
			(clearance 0)
		)
		(min_thickness 0.25)
		(keepout
			(tracks not_allowed)
			(vias allowed)
			(pads allowed)
			(copperpour not_allowed)
			(footprints allowed)
		)
		(placement
			(enabled no)
			(sheetname "")
		)
		(fill
			(thermal_gap 0.5)
			(thermal_bridge_width 0.5)
			(island_removal_mode 0)
		)
		(polygon
			(pts
				(arc
					(start 6.139688 -111.853218)
					(mid 6.209538 -111.329301)
					(end 6.279388 -111.853218)
				)
				(xy 6.279388 -112.00003) (xy 6.352794 -112.073436) (xy 6.593078 -112.073436)
				(arc
					(start 6.593078 -111.59617)
					(mid 6.209665 -111.21263)
					(end 5.825998 -111.595916)
				)
				(arc
					(start 5.825998 -112.865916)
					(mid 6.209538 -113.249456)
					(end 6.593078 -112.865916)
				)
				(xy 6.593078 -112.505236) (xy 6.352794 -112.505236) (xy 6.279388 -112.578642)
				(arc
					(start 6.279388 -112.608614)
					(mid 6.209538 -113.132531)
					(end 6.139688 -112.608614)
				)
				(xy 6.139688 -112.52073) (xy 6.294882 -112.365536) (xy 6.593078 -112.365536) (xy 6.593078 -112.213136)
				(xy 6.294882 -112.213136) (xy 6.139688 -112.057942)
			)
		)
	)
	(zone
		(layer "In4.Cu")
		(hatch none 0.5)
		(connect_pads
			(clearance 0)
		)
		(min_thickness 0.25)
		(keepout
			(tracks not_allowed)
			(vias allowed)
			(pads allowed)
			(copperpour not_allowed)
			(footprints allowed)
		)
		(placement
			(enabled no)
			(sheetname "")
		)
		(fill
			(thermal_gap 0.5)
			(thermal_bridge_width 0.5)
			(island_removal_mode 0)
		)
		(polygon
			(pts
				(arc
					(start 358.3305 -115.963192)
					(mid 358.275911 -116.486671)
					(end 358.161844 -115.972844)
				)
				(xy 358.117394 -115.928394) (xy 357.896668 -115.928394) (xy 357.87711 -115.947952)
				(arc
					(start 357.87711 -116.220494)
					(mid 358.26065 -116.604034)
					(end 358.64419 -116.220494)
				)
				(arc
					(start 358.64419 -115.204748)
					(mid 358.260777 -114.820954)
					(end 357.87711 -115.204494)
				)
				(xy 357.87711 -115.496594) (xy 358.117394 -115.496594)
				(arc
					(start 358.161844 -115.452144)
					(mid 358.275912 -114.938298)
					(end 358.3305 -115.461796)
				)
				(xy 358.3305 -115.4811) (xy 358.175306 -115.636294) (xy 357.87711 -115.636294) (xy 357.87711 -115.788694)
				(xy 358.175306 -115.788694) (xy 358.3305 -115.943888)
			)
		)
	)
	(zone
		(layer "In4.Cu")
		(hatch none 0.5)
		(connect_pads
			(clearance 0)
		)
		(min_thickness 0.25)
		(keepout
			(tracks not_allowed)
			(vias allowed)
			(pads allowed)
			(copperpour not_allowed)
			(footprints allowed)
		)
		(placement
			(enabled no)
			(sheetname "")
		)
		(fill
			(thermal_gap 0.5)
			(thermal_bridge_width 0.5)
			(island_removal_mode 0)
		)
		(polygon
			(pts
				(xy 359.516172 -106.81843)
				(arc
					(start 359.516426 -106.916728)
					(mid 359.447608 -107.441011)
					(end 359.376726 -106.916982)
				)
				(xy 359.376472 -106.81843) (xy 359.376472 -106.789474) (xy 359.376472 -106.760772) (xy 359.376472 -106.760518)
				(xy 359.396792 -106.740198) (xy 359.417366 -106.719624) (xy 359.532682 -106.604308) (xy 359.814368 -106.604308)
				(xy 359.809288 -106.451908) (xy 359.508044 -106.451908) (xy 359.335578 -106.279442)
				(arc
					(start 359.335578 -106.185462)
					(mid 359.405428 -105.661545)
					(end 359.475278 -106.185462)
				)
				(xy 359.475278 -106.22153) (xy 359.565956 -106.312208) (xy 359.804462 -106.312208) (xy 359.791254 -105.915206)
				(arc
					(start 359.788714 -105.915206)
					(mid 359.392474 -105.544874)
					(end 359.022142 -105.941114)
				)
				(xy 359.019602 -105.941114) (xy 359.061258 -107.186984) (xy 359.061512 -107.187238)
				(arc
					(start 359.063798 -107.187238)
					(mid 359.460038 -107.55757)
					(end 359.83037 -107.16133)
				)
				(xy 359.83291 -107.16133) (xy 359.819448 -106.756454) (xy 359.807002 -106.744008) (xy 359.590594 -106.744008)
			)
		)
	)
	(zone
		(layer "In4.Cu")
		(hatch none 0.5)
		(connect_pads
			(clearance 0)
		)
		(min_thickness 0.25)
		(keepout
			(tracks not_allowed)
			(vias allowed)
			(pads allowed)
			(copperpour not_allowed)
			(footprints allowed)
		)
		(placement
			(enabled no)
			(sheetname "")
		)
		(fill
			(thermal_gap 0.5)
			(thermal_bridge_width 0.5)
			(island_removal_mode 0)
		)
		(polygon
			(pts
				(arc
					(start 397.878808 -3.198876)
					(mid 398.392756 -3.079611)
					(end 397.934434 -3.340862)
				)
				(xy 397.866616 -3.40868) (xy 397.866616 -3.560064)
				(arc
					(start 398.144238 -3.560064)
					(mid 398.528032 -3.176651)
					(end 398.144492 -2.792984)
				)
				(arc
					(start 397.128492 -2.792984)
					(mid 396.744952 -3.176524)
					(end 397.128492 -3.560064)
				)
				(xy 397.434816 -3.560064) (xy 397.434816 -3.34518)
				(arc
					(start 397.37284 -3.283204)
					(mid 396.862587 -3.157003)
					(end 397.385794 -3.106674)
				)
				(xy 397.393922 -3.106674) (xy 397.574516 -3.287268) (xy 397.574516 -3.560064) (xy 397.726916 -3.560064)
				(xy 397.726916 -3.350768)
			)
		)
	)
	(zone
		(layer "In4.Cu")
		(hatch none 0.5)
		(connect_pads
			(clearance 0)
		)
		(min_thickness 0.25)
		(keepout
			(tracks allowed)
			(vias allowed)
			(pads allowed)
			(copperpour allowed)
			(footprints allowed)
		)
		(placement
			(enabled no)
			(sheetname "")
		)
		(fill
			(thermal_gap 0.5)
			(thermal_bridge_width 0.5)
			(island_removal_mode 0)
		)
		(polygon
			(pts
				(xy 241.9731 -68.5165) (xy 243.6495 -70.1929) (xy 246.2784 -70.1929) (xy 247.777 -68.6943) (xy 247.777 -54.7624)
				(xy 248.5771 -53.9623) (xy 248.5771 -51.3715) (xy 249.2121 -50.7365) (xy 249.2121 -50.0761) (xy 248.7041 -49.5681)
				(xy 245.7323 -49.5681) (xy 245.72595 -49.57445) (xy 245.24335 -49.57445) (xy 245.237 -49.5681) (xy 244.6782 -49.5681)
				(xy 244.35435 -49.89195) (xy 242.15725 -49.89195) (xy 241.9604 -50.0888) (xy 241.9604 -50.5206)
				(xy 241.9731 -50.5333)
			)
		)
	)
	(zone
		(net "P5V")
		(layer "In4.Cu")
		(hatch none 0.5)
		(connect_pads
			(clearance 0.5)
		)
		(min_thickness 0.25)
		(fill yes
			(thermal_gap 0.5)
			(thermal_bridge_width 0.5)
			(island_removal_mode 0)
		)
		(polygon
			(pts
				(xy 437.3499 -126.5936) (xy 437.3499 -126.375922) (xy 437.646064 -126.079504) (xy 438.215786 -125.9459)
				(xy 438.6834 -125.9459) (xy 439.138314 -125.807724) (xy 441.472828 -125.807724) (xy 442.025532 -126.360428)
				(xy 442.191648 -126.526544) (xy 447.15303 -126.526544) (xy 447.314574 -126.365) (xy 450.3674 -126.365)
				(xy 450.90842 -126.90602) (xy 451.1421 -127.1397) (xy 456.4761 -127.1397) (xy 456.70978 -126.90602)
				(xy 458.1525 -125.4633) (xy 463.36712 -125.4633) (xy 463.41538 -125.41504) (xy 464.058 -125.41504)
				(xy 465.01304 -124.46) (xy 468.249 -124.46) (xy 468.503 -124.714) (xy 468.503 -125.603) (xy 467.995 -126.111)
				(xy 466.725 -126.111) (xy 464.8327 -128.0033) (xy 463.97418 -128.0033) (xy 463.68335 -128.0033)
				(xy 459.61808 -128.0033) (xy 458.7367 -128.88468) (xy 450.57822 -128.88468) (xy 450.57441 -128.88087)
				(xy 441.810648 -128.88087) (xy 441.277502 -128.347724) (xy 441.001658 -128.07188) (xy 441.001658 -126.867158)
				(xy 440.7662 -126.6317) (xy 438.7342 -126.6317) (xy 438.643776 -126.722124) (xy 438.561734 -126.804166)
				(xy 438.561734 -127.538734) (xy 438.438544 -127.661924) (xy 437.478424 -127.661924) (xy 437.3499 -127.5334)
			)
		)
	)
	(zone
		(layer "In4.Cu")
		(hatch none 0.5)
		(connect_pads
			(clearance 0)
		)
		(min_thickness 0.25)
		(keepout
			(tracks not_allowed)
			(vias allowed)
			(pads allowed)
			(copperpour not_allowed)
			(footprints allowed)
		)
		(placement
			(enabled no)
			(sheetname "")
		)
		(fill
			(thermal_gap 0.5)
			(thermal_bridge_width 0.5)
			(island_removal_mode 0)
		)
		(polygon
			(pts
				(xy 445.66586 -44.45381) (xy 445.66586 -44.752006) (xy 445.510666 -44.9072)
				(arc
					(start 445.364362 -44.9072)
					(mid 444.840445 -44.83735)
					(end 445.364362 -44.7675)
				)
				(xy 445.452754 -44.7675) (xy 445.52616 -44.694094) (xy 445.52616 -44.45381)
				(arc
					(start 445.107314 -44.45381)
					(mid 444.723774 -44.837223)
					(end 445.10706 -45.22089)
				)
				(arc
					(start 446.37706 -45.22089)
					(mid 446.7606 -44.83735)
					(end 446.37706 -44.45381)
				)
				(xy 445.95796 -44.45381) (xy 445.95796 -44.69384) (xy 446.03162 -44.7675)
				(arc
					(start 446.119758 -44.7675)
					(mid 446.643675 -44.83735)
					(end 446.119758 -44.9072)
				)
				(xy 445.973708 -44.9072) (xy 445.81826 -44.751752) (xy 445.81826 -44.45381)
			)
		)
	)
	(zone
		(layer "In4.Cu")
		(hatch none 0.5)
		(connect_pads
			(clearance 0)
		)
		(min_thickness 0.25)
		(keepout
			(tracks not_allowed)
			(vias allowed)
			(pads allowed)
			(copperpour not_allowed)
			(footprints allowed)
		)
		(placement
			(enabled no)
			(sheetname "")
		)
		(fill
			(thermal_gap 0.5)
			(thermal_bridge_width 0.5)
			(island_removal_mode 0)
		)
		(polygon
			(pts
				(xy 443.23635 -125.791976) (xy 443.146434 -125.70206)
				(arc
					(start 442.754004 -125.70206)
					(mid 442.37021 -126.085473)
					(end 442.75375 -126.46914)
				)
				(arc
					(start 444.02375 -126.46914)
					(mid 444.40729 -126.0856)
					(end 444.02375 -125.70206)
				)
				(xy 443.66815 -125.70206) (xy 443.66815 -125.891544)
				(arc
					(start 443.772544 -125.995938)
					(mid 444.2902 -126.095467)
					(end 443.766448 -126.15545)
				)
				(xy 443.734444 -126.15545) (xy 443.52845 -125.949456) (xy 443.52845 -125.70206) (xy 443.344046 -125.70206)
				(xy 443.37605 -125.734064) (xy 443.37605 -125.987556) (xy 443.208156 -126.15545)
				(arc
					(start 443.011052 -126.15545)
					(mid 442.487135 -126.0856)
					(end 443.011052 -126.01575)
				)
				(xy 443.150244 -126.01575) (xy 443.23635 -125.929644)
			)
		)
	)
	(zone
		(layer "In4.Cu")
		(hatch none 0.5)
		(connect_pads
			(clearance 0)
		)
		(min_thickness 0.25)
		(keepout
			(tracks allowed)
			(vias allowed)
			(pads allowed)
			(copperpour allowed)
			(footprints allowed)
		)
		(placement
			(enabled no)
			(sheetname "")
		)
		(fill
			(thermal_gap 0.5)
			(thermal_bridge_width 0.5)
			(island_removal_mode 0)
		)
		(polygon
			(pts
				(xy 231.14 -102.616) (xy 233.299 -104.775) (xy 249.682 -104.775) (xy 249.936 -104.521) (xy 249.936 -85.217)
				(xy 246.761 -82.042) (xy 236.855 -82.042) (xy 235.712 -80.899) (xy 231.394 -80.899) (xy 231.14 -81.153)
				(xy 229.616 -82.677) (xy 229.616 -101.092)
			)
		)
	)
	(zone
		(layer "In4.Cu")
		(hatch none 0.5)
		(connect_pads
			(clearance 0)
		)
		(min_thickness 0.25)
		(keepout
			(tracks not_allowed)
			(vias allowed)
			(pads allowed)
			(copperpour not_allowed)
			(footprints allowed)
		)
		(placement
			(enabled no)
			(sheetname "")
		)
		(fill
			(thermal_gap 0.5)
			(thermal_bridge_width 0.5)
			(island_removal_mode 0)
		)
		(polygon
			(pts
				(xy 366.503966 -2.867152) (xy 366.65916 -3.022346) (xy 366.65916 -3.320542) (xy 366.81156 -3.320542)
				(xy 366.81156 -3.022346) (xy 366.966754 -2.867152)
				(arc
					(start 367.113058 -2.867152)
					(mid 367.636975 -2.937002)
					(end 367.113058 -3.006852)
				)
				(xy 367.024666 -3.006852) (xy 366.95126 -3.080258) (xy 366.95126 -3.320542)
				(arc
					(start 367.37036 -3.320542)
					(mid 367.7539 -2.937002)
					(end 367.37036 -2.553462)
				)
				(arc
					(start 366.100614 -2.553462)
					(mid 365.717074 -2.936875)
					(end 366.10036 -3.320542)
				)
				(xy 366.51946 -3.320542) (xy 366.51946 -3.080258) (xy 366.446054 -3.006852)
				(arc
					(start 366.357662 -3.006852)
					(mid 365.833745 -2.937002)
					(end 366.357662 -2.867152)
				)
			)
		)
	)
	(zone
		(layer "In4.Cu")
		(hatch none 0.5)
		(connect_pads
			(clearance 0)
		)
		(min_thickness 0.25)
		(keepout
			(tracks not_allowed)
			(vias allowed)
			(pads allowed)
			(copperpour not_allowed)
			(footprints allowed)
		)
		(placement
			(enabled no)
			(sheetname "")
		)
		(fill
			(thermal_gap 0.5)
			(thermal_bridge_width 0.5)
			(island_removal_mode 0)
		)
		(polygon
			(pts
				(arc
					(start 463.720688 -53.819044)
					(mid 464.244605 -53.888894)
					(end 463.720688 -53.958744)
				)
				(xy 463.632296 -53.958744) (xy 463.55889 -54.03215) (xy 463.55889 -54.272434)
				(arc
					(start 463.977736 -54.272434)
					(mid 464.36153 -53.889021)
					(end 463.97799 -53.505354)
				)
				(arc
					(start 462.70799 -53.505354)
					(mid 462.32445 -53.888894)
					(end 462.70799 -54.272434)
				)
				(xy 463.12709 -54.272434) (xy 463.12709 -54.03215) (xy 463.053684 -53.958744)
				(arc
					(start 462.965292 -53.958744)
					(mid 462.441375 -53.888894)
					(end 462.965292 -53.819044)
				)
				(xy 463.111596 -53.819044) (xy 463.26679 -53.974238) (xy 463.26679 -54.272434) (xy 463.41919 -54.272434)
				(xy 463.41919 -53.974238) (xy 463.574384 -53.819044)
			)
		)
	)
	(zone
		(layer "In4.Cu")
		(hatch none 0.5)
		(connect_pads
			(clearance 0)
		)
		(min_thickness 0.25)
		(keepout
			(tracks allowed)
			(vias allowed)
			(pads allowed)
			(copperpour allowed)
			(footprints allowed)
		)
		(placement
			(enabled no)
			(sheetname "")
		)
		(fill
			(thermal_gap 0.5)
			(thermal_bridge_width 0.5)
			(island_removal_mode 0)
		)
		(polygon
			(pts
				(xy 277.9776 -158.623) (xy 277.9776 -158.1912) (xy 279.6286 -158.1912) (xy 279.6286 -158.623)
			)
		)
	)
	(zone
		(layer "In4.Cu")
		(hatch none 0.5)
		(connect_pads
			(clearance 0)
		)
		(min_thickness 0.25)
		(keepout
			(tracks not_allowed)
			(vias allowed)
			(pads allowed)
			(copperpour not_allowed)
			(footprints allowed)
		)
		(placement
			(enabled no)
			(sheetname "")
		)
		(fill
			(thermal_gap 0.5)
			(thermal_bridge_width 0.5)
			(island_removal_mode 0)
		)
		(polygon
			(pts
				(xy 368.70132 -1.349756) (xy 368.856514 -1.50495) (xy 368.856514 -1.803146) (xy 369.008914 -1.803146)
				(xy 369.008914 -1.50495) (xy 369.164108 -1.349756)
				(arc
					(start 369.310412 -1.349756)
					(mid 369.834329 -1.419606)
					(end 369.310412 -1.489456)
				)
				(xy 369.22202 -1.489456) (xy 369.148614 -1.562862) (xy 369.148614 -1.803146)
				(arc
					(start 369.56746 -1.803146)
					(mid 369.951254 -1.419733)
					(end 369.567714 -1.036066)
				)
				(arc
					(start 368.297714 -1.036066)
					(mid 367.914174 -1.419606)
					(end 368.297714 -1.803146)
				)
				(xy 368.716814 -1.803146) (xy 368.716814 -1.562862) (xy 368.643408 -1.489456)
				(arc
					(start 368.555016 -1.489456)
					(mid 368.031099 -1.419606)
					(end 368.555016 -1.349756)
				)
			)
		)
	)
	(zone
		(layer "In4.Cu")
		(hatch none 0.5)
		(connect_pads
			(clearance 0)
		)
		(min_thickness 0.25)
		(keepout
			(tracks not_allowed)
			(vias allowed)
			(pads allowed)
			(copperpour not_allowed)
			(footprints allowed)
		)
		(placement
			(enabled no)
			(sheetname "")
		)
		(fill
			(thermal_gap 0.5)
			(thermal_bridge_width 0.5)
			(island_removal_mode 0)
		)
		(polygon
			(pts
				(xy 361.703874 -2.867152) (xy 361.859068 -3.022346) (xy 361.859068 -3.320542) (xy 362.011468 -3.320542)
				(xy 362.011468 -3.022346) (xy 362.166662 -2.867152)
				(arc
					(start 362.312966 -2.867152)
					(mid 362.836883 -2.937002)
					(end 362.312966 -3.006852)
				)
				(xy 362.224574 -3.006852) (xy 362.151168 -3.080258) (xy 362.151168 -3.320542)
				(arc
					(start 362.570014 -3.320542)
					(mid 362.953808 -2.937129)
					(end 362.570268 -2.553462)
				)
				(arc
					(start 361.300268 -2.553462)
					(mid 360.916728 -2.937002)
					(end 361.300268 -3.320542)
				)
				(xy 361.719368 -3.320542) (xy 361.719368 -3.080258) (xy 361.645962 -3.006852)
				(arc
					(start 361.55757 -3.006852)
					(mid 361.033653 -2.937002)
					(end 361.55757 -2.867152)
				)
			)
		)
	)
	(zone
		(layer "In4.Cu")
		(hatch none 0.5)
		(connect_pads
			(clearance 0)
		)
		(min_thickness 0.25)
		(keepout
			(tracks allowed)
			(vias allowed)
			(pads allowed)
			(copperpour allowed)
			(footprints allowed)
		)
		(placement
			(enabled no)
			(sheetname "")
		)
		(fill
			(thermal_gap 0.5)
			(thermal_bridge_width 0.5)
			(island_removal_mode 0)
		)
		(polygon
			(pts
				(xy 121.162318 -49.02835) (xy 124.330968 -52.197) (xy 124.318268 -52.2097) (xy 125.054868 -52.2097)
				(xy 125.880368 -53.0352) (xy 124.737368 -54.1782) (xy 123.848368 -54.1782) (xy 123.695968 -54.0258)
				(xy 123.695968 -52.4764) (xy 123.264168 -52.4764) (xy 122.730768 -51.943) (xy 120.952768 -51.943)
				(xy 120.139968 -51.1302) (xy 119.047768 -51.1302) (xy 117.218968 -52.959) (xy 117.218968 -53.0098)
				(xy 117.091968 -53.1368) (xy 113.459768 -53.1368) (xy 113.281968 -53.3146) (xy 113.281968 -54.0258)
				(xy 111.097568 -54.0258) (xy 110.995968 -53.9242) (xy 110.995968 -49.9364) (xy 113.231168 -47.7012)
				(xy 114.209068 -46.7233) (xy 120.838468 -46.7233) (xy 121.162318 -47.04715)
			)
		)
	)
	(zone
		(layer "In4.Cu")
		(hatch none 0.5)
		(connect_pads
			(clearance 0)
		)
		(min_thickness 0.25)
		(keepout
			(tracks allowed)
			(vias allowed)
			(pads allowed)
			(copperpour allowed)
			(footprints allowed)
		)
		(placement
			(enabled no)
			(sheetname "")
		)
		(fill
			(thermal_gap 0.5)
			(thermal_bridge_width 0.5)
			(island_removal_mode 0)
		)
		(polygon
			(pts
				(xy 308.365652 -105.179622) (xy 296.545 -105.179622) (xy 296.545 -105.156) (xy 295.91 -104.521)
				(xy 293.116 -104.521) (xy 293.116 -105.156) (xy 293.116 -106.934) (xy 292.481 -107.569) (xy 292.1 -107.95)
				(xy 270.51 -107.95) (xy 270.51 -104.775) (xy 250.444 -104.775) (xy 250.444 -105.156) (xy 232.664 -105.156)
				(xy 231.902 -105.156) (xy 229.362 -102.616) (xy 229.362 -82.1436) (xy 230.4796 -81.026) (xy 230.4796 -72.2122)
				(xy 228.346 -70.0786) (xy 228.346 -61.5188) (xy 228.4984 -61.3664) (xy 230.6574 -59.2074) (xy 230.6574 -57.277)
				(xy 232.283 -55.6514) (xy 232.283 -52.1716) (xy 228.8667 -48.7553) (xy 235.077 -42.545) (xy 237.49 -44.958)
				(xy 237.49 -45.5422) (xy 237.7694 -45.5422) (xy 240.8174 -48.5902) (xy 241.5667 -49.3395) (xy 248.9962 -49.3395)
				(xy 250.7742 -47.5615) (xy 269.995396 -47.5615) (xy 269.995396 -45.978572) (xy 270.902938 -45.07103)
				(xy 278.148034 -45.07103) (xy 278.148034 -45.377354) (xy 278.64308 -45.8724) (xy 283.718 -45.8724)
				(xy 283.72435 -45.87875) (xy 286.30245 -45.87875) (xy 286.639 -46.2153) (xy 286.639 -48.2346) (xy 286.639 -48.7934)
				(xy 289.842194 -51.996594) (xy 292.376098 -51.996594) (xy 307.76418 -51.996594) (xy 309.215028 -53.447442)
				(xy 310.4134 -54.645814) (xy 310.4134 -57.912) (xy 310.3626 -57.9628) (xy 310.334406 -57.9628) (xy 310.334406 -103.210868)
			)
		)
	)
	(zone
		(layer "In4.Cu")
		(hatch none 0.5)
		(connect_pads
			(clearance 0)
		)
		(min_thickness 0.25)
		(keepout
			(tracks not_allowed)
			(vias allowed)
			(pads allowed)
			(copperpour not_allowed)
			(footprints allowed)
		)
		(placement
			(enabled no)
			(sheetname "")
		)
		(fill
			(thermal_gap 0.5)
			(thermal_bridge_width 0.5)
			(island_removal_mode 0)
		)
		(polygon
			(pts
				(arc
					(start 13.707364 -103.285798)
					(mid 13.777845 -102.761748)
					(end 13.847826 -103.285798)
				)
				(xy 13.847826 -103.342948) (xy 13.681456 -103.509318) (xy 13.780008 -103.626412) (xy 13.802868 -103.603552)
				(arc
					(start 14.06398 -103.603552)
					(mid 14.587897 -103.673402)
					(end 14.06398 -103.743252)
				)
				(xy 13.87856 -103.743252)
				(arc
					(start 14.027912 -103.920544)
					(mid 14.568424 -103.966772)
					(end 14.614652 -103.42626)
				)
				(arc
					(start 14.076934 -102.788466)
					(mid 13.534438 -102.732389)
					(end 13.484606 -103.275638)
				)
				(xy 13.591032 -103.40213)
			)
		)
	)
	(zone
		(layer "In4.Cu")
		(hatch none 0.5)
		(connect_pads
			(clearance 0)
		)
		(min_thickness 0.25)
		(keepout
			(tracks not_allowed)
			(vias allowed)
			(pads allowed)
			(copperpour not_allowed)
			(footprints allowed)
		)
		(placement
			(enabled no)
			(sheetname "")
		)
		(fill
			(thermal_gap 0.5)
			(thermal_bridge_width 0.5)
			(island_removal_mode 0)
		)
		(polygon
			(pts
				(arc
					(start 475.03207 -21.465286)
					(mid 471.978989 -21.466556)
					(end 475.03207 -21.467826)
				)
				(arc
					(start 473.77223 -21.467826)
					(mid 473.50553 -21.731998)
					(end 473.23883 -21.467826)
				)
				(arc
					(start 473.23883 -21.465286)
					(mid 473.50553 -21.198586)
					(end 473.77223 -21.465286)
				)
			)
		)
	)
	(zone
		(net "GND")
		(layer "In4.Cu")
		(hatch none 0.5)
		(connect_pads
			(clearance 0.5)
		)
		(min_thickness 0.25)
		(fill yes
			(thermal_gap 0.5)
			(thermal_bridge_width 0.5)
			(island_removal_mode 0)
		)
		(polygon
			(pts
				(xy 34.5948 -52.784756) (xy 34.5948 -92.68714) (xy 34.929572 -93.021912) (xy 42.973244 -93.021912)
				(xy 43.239944 -92.755212) (xy 43.239944 -53.541676) (xy 42.200068 -52.5018) (xy 41.260268 -52.5018)
				(xy 41.082468 -52.324) (xy 39.837868 -52.324) (xy 39.431468 -51.9176) (xy 39.13886 -51.624992) (xy 35.398964 -51.624992)
				(xy 35.304984 -51.718972) (xy 35.304984 -52.074572) (xy 35.26282 -52.116736)
			)
		)
	)
	(zone
		(layer "In4.Cu")
		(hatch none 0.5)
		(connect_pads
			(clearance 0)
		)
		(min_thickness 0.25)
		(keepout
			(tracks allowed)
			(vias allowed)
			(pads allowed)
			(copperpour allowed)
			(footprints allowed)
		)
		(placement
			(enabled no)
			(sheetname "")
		)
		(fill
			(thermal_gap 0.5)
			(thermal_bridge_width 0.5)
			(island_removal_mode 0)
		)
		(polygon
			(pts
				(xy 357.124 -125.73) (xy 357.124 -123.063) (xy 358.902 -123.063) (xy 358.902 -125.73)
			)
		)
	)
	(zone
		(layer "In4.Cu")
		(hatch none 0.5)
		(connect_pads
			(clearance 0)
		)
		(min_thickness 0.25)
		(keepout
			(tracks allowed)
			(vias allowed)
			(pads allowed)
			(copperpour allowed)
			(footprints allowed)
		)
		(placement
			(enabled no)
			(sheetname "")
		)
		(fill
			(thermal_gap 0.5)
			(thermal_bridge_width 0.5)
			(island_removal_mode 0)
		)
		(polygon
			(pts
				(xy 66.139568 -102.616) (xy 68.298568 -104.775) (xy 84.681568 -104.775) (xy 84.935568 -104.521)
				(xy 84.935568 -85.217) (xy 81.760568 -82.042) (xy 71.854568 -82.042) (xy 70.711568 -80.899) (xy 66.393568 -80.899)
				(xy 66.139568 -81.153) (xy 64.615568 -82.677) (xy 64.615568 -101.092)
			)
		)
	)
	(zone
		(layer "In4.Cu")
		(hatch none 0.5)
		(connect_pads
			(clearance 0)
		)
		(min_thickness 0.25)
		(keepout
			(tracks not_allowed)
			(vias allowed)
			(pads allowed)
			(copperpour not_allowed)
			(footprints allowed)
		)
		(placement
			(enabled no)
			(sheetname "")
		)
		(fill
			(thermal_gap 0.5)
			(thermal_bridge_width 0.5)
			(island_removal_mode 0)
		)
		(polygon
			(pts
				(xy 3.298444 -111.82985) (xy 3.298444 -112.128046) (xy 3.14325 -112.28324)
				(arc
					(start 2.996946 -112.28324)
					(mid 2.473029 -112.21339)
					(end 2.996946 -112.14354)
				)
				(xy 3.085338 -112.14354) (xy 3.158744 -112.070134) (xy 3.158744 -111.82985)
				(arc
					(start 2.739898 -111.82985)
					(mid 2.356104 -112.213263)
					(end 2.739644 -112.59693)
				)
				(arc
					(start 4.009644 -112.59693)
					(mid 4.393184 -112.21339)
					(end 4.009644 -111.82985)
				)
				(xy 3.61569 -111.82985) (xy 3.590544 -111.854996) (xy 3.590544 -112.070134) (xy 3.66395 -112.14354)
				(arc
					(start 3.752342 -112.14354)
					(mid 4.276259 -112.21339)
					(end 3.752342 -112.28324)
				)
				(xy 3.606038 -112.28324) (xy 3.450844 -112.128046) (xy 3.450844 -111.82985)
			)
		)
	)
	(zone
		(layer "In4.Cu")
		(hatch none 0.5)
		(connect_pads
			(clearance 0)
		)
		(min_thickness 0.25)
		(keepout
			(tracks not_allowed)
			(vias allowed)
			(pads allowed)
			(copperpour not_allowed)
			(footprints allowed)
		)
		(placement
			(enabled no)
			(sheetname "")
		)
		(fill
			(thermal_gap 0.5)
			(thermal_bridge_width 0.5)
			(island_removal_mode 0)
		)
		(polygon
			(pts
				(arc
					(start 155.64231 -98.549968)
					(mid 150.357586 -98.549968)
					(end 155.64231 -98.549968)
				)
			)
		)
	)
	(zone
		(net "P3V3_STBY")
		(layer "In4.Cu")
		(hatch none 0.5)
		(connect_pads
			(clearance 0.5)
		)
		(min_thickness 0.25)
		(fill yes
			(thermal_gap 0.5)
			(thermal_bridge_width 0.5)
			(island_removal_mode 0)
		)
		(polygon
			(pts
				(arc
					(start 391.97915 -102.181406)
					(mid 391.875736 -102.055865)
					(end 391.838942 -101.897434)
				)
				(arc
					(start 391.838942 -101.897434)
					(mid 391.809274 -101.825428)
					(end 391.737342 -101.79558)
				)
				(arc
					(start 391.662158 -101.79558)
					(mid 391.590226 -101.825428)
					(end 391.560558 -101.897434)
				)
				(arc
					(start 391.560558 -101.897434)
					(mid 391.20445 -102.254305)
					(end 390.848342 -101.897434)
				)
				(arc
					(start 390.848342 -101.897434)
					(mid 390.818674 -101.825428)
					(end 390.746742 -101.79558)
				)
				(arc
					(start 390.671558 -101.79558)
					(mid 390.599626 -101.825428)
					(end 390.569958 -101.897434)
				)
				(arc
					(start 390.569958 -101.897434)
					(mid 390.21385 -102.254305)
					(end 389.857742 -101.897434)
				)
				(arc
					(start 389.857742 -101.897434)
					(mid 389.828074 -101.825428)
					(end 389.756142 -101.79558)
				)
				(arc
					(start 389.680958 -101.79558)
					(mid 389.609026 -101.825428)
					(end 389.579358 -101.897434)
				)
				(arc
					(start 389.579358 -101.897434)
					(mid 389.22325 -102.254305)
					(end 388.867142 -101.897434)
				)
				(arc
					(start 388.867142 -101.897434)
					(mid 388.837474 -101.825428)
					(end 388.765542 -101.79558)
				)
				(arc
					(start 388.690358 -101.79558)
					(mid 388.618426 -101.825428)
					(end 388.588758 -101.897434)
				)
				(arc
					(start 388.588758 -101.897434)
					(mid 388.23265 -102.254305)
					(end 387.876542 -101.897434)
				)
				(arc
					(start 387.876542 -101.897434)
					(mid 387.846874 -101.825428)
					(end 387.774942 -101.79558)
				)
				(arc
					(start 387.699758 -101.79558)
					(mid 387.627826 -101.825428)
					(end 387.598158 -101.897434)
				)
				(arc
					(start 387.598158 -101.897434)
					(mid 387.24205 -102.254305)
					(end 386.885942 -101.897434)
				)
				(arc
					(start 386.885942 -101.897434)
					(mid 386.856274 -101.825428)
					(end 386.784342 -101.79558)
				)
				(arc
					(start 386.709158 -101.79558)
					(mid 386.637226 -101.825428)
					(end 386.607558 -101.897434)
				)
				(arc
					(start 386.607558 -101.897434)
					(mid 386.25145 -102.254305)
					(end 385.895342 -101.897434)
				)
				(arc
					(start 385.895342 -101.897434)
					(mid 385.865674 -101.825428)
					(end 385.793742 -101.79558)
				)
				(arc
					(start 385.718558 -101.79558)
					(mid 385.646626 -101.825428)
					(end 385.616958 -101.897434)
				)
				(arc
					(start 385.616958 -101.897434)
					(mid 385.26085 -102.254305)
					(end 384.904742 -101.897434)
				)
				(arc
					(start 384.904742 -101.897434)
					(mid 384.875074 -101.825428)
					(end 384.803142 -101.79558)
				)
				(xy 384.7084 -101.79558) (xy 384.626358 -101.877622)
				(arc
					(start 384.626358 -101.898704)
					(mid 384.522057 -102.150003)
					(end 384.270758 -102.254304)
				)
				(xy 384.249676 -102.254304) (xy 384.014726 -102.489254)
				(arc
					(start 384.04546 -102.525068)
					(mid 384.127685 -102.80585)
					(end 383.9718 -103.053388)
				)
				(xy 383.9718 -103.63835) (xy 384.2004 -103.86695)
				(arc
					(start 384.986022 -103.86695)
					(mid 385.494934 -103.864767)
					(end 385.486148 -104.37368)
				)
				(arc
					(start 385.486148 -104.621838)
					(mid 385.528733 -104.704541)
					(end 385.620768 -104.71785)
				)
				(arc
					(start 385.620768 -104.71785)
					(mid 386.093189 -105.0544)
					(end 385.620768 -105.39095)
				)
				(arc
					(start 385.620768 -105.39095)
					(mid 385.528773 -105.404315)
					(end 385.486148 -105.486962)
				)
				(xy 385.486148 -105.972356) (xy 385.660392 -106.1466) (xy 386.08 -106.1466) (xy 387.015736 -105.210864)
				(arc
					(start 387.004052 -105.18013)
					(mid 387.10947 -104.780619)
					(end 387.52145 -104.7496)
				)
				(xy 387.994398 -104.7496)
				(arc
					(start 388.012686 -104.746298)
					(mid 388.04217 -104.736735)
					(end 388.072376 -104.729788)
				)
				(arc
					(start 388.072376 -104.729788)
					(mid 388.113891 -104.67975)
					(end 388.072376 -104.629712)
				)
				(arc
					(start 388.072376 -104.629712)
					(mid 387.789284 -104.354212)
					(end 387.934708 -103.986838)
				)
				(arc
					(start 387.934708 -103.986838)
					(mid 387.977542 -103.917733)
					(end 387.956044 -103.839264)
				)
				(arc
					(start 387.956044 -103.839264)
					(mid 388.2836 -103.262717)
					(end 388.435342 -103.908098)
				)
				(arc
					(start 388.435342 -103.908098)
					(mid 388.392508 -103.977203)
					(end 388.414006 -104.055672)
				)
				(arc
					(start 388.414006 -104.055672)
					(mid 388.471379 -104.402816)
					(end 388.202424 -104.629712)
				)
				(arc
					(start 388.202424 -104.629712)
					(mid 388.160909 -104.67975)
					(end 388.202424 -104.729788)
				)
				(arc
					(start 388.202424 -104.729788)
					(mid 388.232756 -104.736735)
					(end 388.262368 -104.746298)
				)
				(xy 388.271004 -104.7496) (xy 389.516874 -104.7496) (xy 391.256774 -106.4895) (xy 394.6144 -106.4895)
				(xy 395.201648 -105.902252) (xy 395.201648 -104.93121) (xy 395.201648 -104.404668) (xy 394.8684 -104.07142)
				(xy 394.85062 -104.0892) (xy 393.1793 -104.0892) (xy 392.2395 -103.1494) (xy 392.2395 -102.441756)
			)
		)
	)
	(zone
		(net "P3V3_STBY")
		(layer "In4.Cu")
		(hatch none 0.5)
		(connect_pads
			(clearance 0.5)
		)
		(min_thickness 0.25)
		(fill yes
			(thermal_gap 0.5)
			(thermal_bridge_width 0.5)
			(island_removal_mode 0)
		)
		(polygon
			(pts
				(xy 480.0854 -124.1044) (xy 493.3188 -124.1044) (xy 493.395 -124.0282) (xy 493.395 -115.7478) (xy 492.71682 -115.06962)
				(xy 486.08996 -115.06962) (xy 485.333802 -114.313462) (xy 484.508556 -114.313462) (xy 484.205026 -114.009932)
				(xy 484.205026 -113.613184) (xy 484.053642 -113.4618) (xy 483.44328 -113.4618) (xy 483.380288 -113.524792)
				(xy 483.380288 -113.92662) (xy 483.079298 -114.22761) (xy 480.980242 -114.22761) (xy 480.89312 -114.22761)
				(xy 480.7966 -114.32413) (xy 480.7966 -114.521996) (xy 480.7966 -114.87658) (xy 480.984052 -115.064032)
				(xy 482.355398 -115.064032) (xy 482.558344 -115.266978) (xy 482.558344 -115.565682) (xy 482.296978 -115.827048)
				(xy 480.04349 -115.827048) (xy 479.933 -115.937538) (xy 479.933 -123.952)
			)
		)
	)
	(zone
		(layer "In4.Cu")
		(hatch none 0.5)
		(connect_pads
			(clearance 0)
		)
		(min_thickness 0.25)
		(keepout
			(tracks not_allowed)
			(vias allowed)
			(pads allowed)
			(copperpour not_allowed)
			(footprints allowed)
		)
		(placement
			(enabled no)
			(sheetname "")
		)
		(fill
			(thermal_gap 0.5)
			(thermal_bridge_width 0.5)
			(island_removal_mode 0)
		)
		(polygon
			(pts
				(arc
					(start 462.119726 -44.7675)
					(mid 462.643643 -44.83735)
					(end 462.119726 -44.9072)
				)
				(xy 462.031334 -44.9072) (xy 461.957928 -44.980606) (xy 461.957928 -45.22089)
				(arc
					(start 462.376774 -45.22089)
					(mid 462.760314 -44.837477)
					(end 462.377028 -44.45381)
				)
				(arc
					(start 461.107028 -44.45381)
					(mid 460.723488 -44.83735)
					(end 461.107028 -45.22089)
				)
				(xy 461.526128 -45.22089) (xy 461.526128 -44.980606) (xy 461.452722 -44.9072)
				(arc
					(start 461.36433 -44.9072)
					(mid 460.840413 -44.83735)
					(end 461.36433 -44.7675)
				)
				(xy 461.510634 -44.7675) (xy 461.665828 -44.922694) (xy 461.665828 -45.22089) (xy 461.818228 -45.22089)
				(xy 461.818228 -44.922694) (xy 461.973422 -44.7675)
			)
		)
	)
	(zone
		(layers "In4.Cu" "In9.Cu" "In11.Cu")
		(hatch none 0.5)
		(connect_pads
			(clearance 0)
		)
		(min_thickness 0.25)
		(keepout
			(tracks not_allowed)
			(vias allowed)
			(pads allowed)
			(copperpour not_allowed)
			(footprints allowed)
		)
		(placement
			(enabled no)
			(sheetname "")
		)
		(fill yes
			(thermal_gap 0.5)
			(thermal_bridge_width 0.5)
			(island_removal_mode 0)
		)
		(polygon
			(pts
				(arc
					(start 384.92049 -34.154618)
					(mid 384.66395 -34.348416)
					(end 384.40741 -34.154618)
				)
				(arc
					(start 384.40741 -34.974022)
					(mid 384.66395 -34.780224)
					(end 384.92049 -34.974022)
				)
			)
		)
	)
	(zone
		(net "PVDDQ_DEF")
		(layer "In5.Cu")
		(hatch none 0.5)
		(connect_pads
			(clearance 0.5)
		)
		(min_thickness 0.25)
		(fill yes
			(thermal_gap 0.5)
			(thermal_bridge_width 0.5)
			(island_removal_mode 0)
		)
		(polygon
			(pts
				(xy 251.662438 -89.571068) (xy 251.493528 -89.739978)
				(arc
					(start 251.493528 -90.43797)
					(mid 251.556996 -90.532143)
					(end 251.668026 -90.508582)
				)
				(arc
					(start 251.668026 -90.508582)
					(mid 252.280004 -90.756486)
					(end 251.668026 -91.00439)
				)
				(arc
					(start 251.668026 -91.00439)
					(mid 251.557038 -90.980931)
					(end 251.493528 -91.075002)
				)
				(arc
					(start 251.493528 -91.42857)
					(mid 251.556996 -91.522743)
					(end 251.668026 -91.499182)
				)
				(arc
					(start 251.668026 -91.499182)
					(mid 252.280004 -91.747086)
					(end 251.668026 -91.99499)
				)
				(arc
					(start 251.668026 -91.99499)
					(mid 251.562033 -91.96966)
					(end 251.494036 -92.054934)
				)
				(xy 251.407676 -92.141294)
				(arc
					(start 251.413518 -92.168218)
					(mid 251.317083 -92.494439)
					(end 250.990862 -92.590874)
				)
				(xy 250.963938 -92.585032) (xy 250.854464 -92.694506) (xy 250.846336 -92.702634) (xy 250.437396 -93.111828)
				(arc
					(start 250.313698 -93.235526)
					(mid 250.285796 -93.326829)
					(end 250.345956 -93.40088)
				)
				(arc
					(start 250.345956 -93.40088)
					(mid 250.548937 -93.826792)
					(end 250.150884 -94.08033)
				)
				(arc
					(start 250.150884 -94.08033)
					(mid 250.068941 -94.103369)
					(end 250.033282 -94.18066)
				)
				(arc
					(start 250.033282 -94.266766)
					(mid 250.06894 -94.344059)
					(end 250.150884 -94.367096)
				)
				(arc
					(start 250.150884 -94.367096)
					(mid 250.562964 -94.718886)
					(end 250.150884 -95.070676)
				)
				(arc
					(start 250.150884 -95.070676)
					(mid 250.068941 -95.093715)
					(end 250.033282 -95.171006)
				)
				(arc
					(start 250.033282 -95.257366)
					(mid 250.06894 -95.334659)
					(end 250.150884 -95.357696)
				)
				(arc
					(start 250.150884 -95.357696)
					(mid 250.562964 -95.709486)
					(end 250.150884 -96.061276)
				)
				(arc
					(start 250.150884 -96.061276)
					(mid 250.069126 -96.084426)
					(end 250.033536 -96.161606)
				)
				(arc
					(start 250.033536 -96.247966)
					(mid 250.069098 -96.325177)
					(end 250.150884 -96.348296)
				)
				(arc
					(start 250.150884 -96.348296)
					(mid 250.562964 -96.700086)
					(end 250.150884 -97.051876)
				)
				(arc
					(start 250.150884 -97.051876)
					(mid 250.069126 -97.075026)
					(end 250.033536 -97.152206)
				)
				(arc
					(start 250.033536 -97.238566)
					(mid 250.069098 -97.315777)
					(end 250.150884 -97.338896)
				)
				(arc
					(start 250.150884 -97.338896)
					(mid 250.562964 -97.690686)
					(end 250.150884 -98.042476)
				)
				(arc
					(start 250.150884 -98.042476)
					(mid 250.069126 -98.065626)
					(end 250.033536 -98.142806)
				)
				(xy 250.033536 -101.468682) (xy 250.094242 -101.529642) (xy 250.437396 -101.872796) (xy 250.437396 -119.931434)
				(xy 243.400072 -126.969012) (xy 243.400072 -129.914904)
				(arc
					(start 243.428774 -129.92862)
					(mid 243.630753 -130.249676)
					(end 243.428774 -130.570732)
				)
				(xy 243.399818 -130.584448)
				(arc
					(start 243.399818 -131.332986)
					(mid 243.505868 -131.586388)
					(end 243.400072 -131.83997)
				)
				(xy 243.400072 -134.006844)
				(arc
					(start 243.429028 -134.02056)
					(mid 243.626095 -134.331202)
					(end 243.429028 -134.641844)
				)
				(xy 243.400072 -134.65556)
				(arc
					(start 243.400072 -135.094218)
					(mid 243.58659 -135.4074)
					(end 243.400072 -135.720582)
				)
				(arc
					(start 243.400072 -136.133586)
					(mid 243.506047 -136.387078)
					(end 243.400072 -136.64057)
				)
				(arc
					(start 243.400072 -138.989308)
					(mid 243.506047 -139.2428)
					(end 243.400072 -139.496292)
				)
				(xy 243.400072 -139.880848)
				(arc
					(start 243.426488 -139.895326)
					(mid 243.612162 -140.208)
					(end 243.426488 -140.520674)
				)
				(xy 243.400072 -140.535152)
				(arc
					(start 243.400072 -140.95222)
					(mid 243.493445 -141.187678)
					(end 243.400072 -141.423136)
				)
				(arc
					(start 243.400072 -143.655288)
					(mid 243.571805 -143.952722)
					(end 243.400072 -144.250156)
				)
				(arc
					(start 243.400072 -144.695418)
					(mid 243.58659 -145.0086)
					(end 243.400072 -145.321782)
				)
				(arc
					(start 243.400072 -145.734786)
					(mid 243.506047 -145.988278)
					(end 243.400072 -146.24177)
				)
				(xy 243.400072 -146.657568) (xy 243.461032 -146.718782) (xy 243.65585 -146.9136) (xy 256.111502 -146.9136)
				(xy 256.834386 -147.636484) (xy 259.608574 -147.636484) (xy 260.200648 -147.04441) (xy 260.407658 -146.8374)
				(arc
					(start 260.396482 -146.80692)
					(mid 260.625702 -146.345057)
					(end 261.075932 -146.5961)
				)
				(xy 261.085584 -146.6342) (xy 278.28494 -146.6342) (xy 278.644096 -146.275044)
				(arc
					(start 278.609806 -146.23923)
					(mid 278.519635 -145.911362)
					(end 278.745696 -145.657316)
				)
				(xy 278.779224 -145.645124) (xy 278.779224 -144.927828)
				(arc
					(start 278.743664 -144.916652)
					(mid 278.493786 -144.5768)
					(end 278.743664 -144.236948)
				)
				(xy 278.779224 -144.225772)
				(arc
					(start 278.779224 -140.789406)
					(mid 278.611942 -140.4874)
					(end 278.779224 -140.185394)
				)
				(xy 278.779224 -139.987782)
				(arc
					(start 278.752808 -139.973304)
					(mid 278.566023 -139.660122)
					(end 278.752808 -139.34694)
				)
				(xy 278.779224 -139.332462) (xy 278.779224 -136.66343)
				(arc
					(start 278.750268 -136.649714)
					(mid 278.546068 -136.327642)
					(end 278.750268 -136.00557)
				)
				(xy 278.779224 -135.991854)
				(arc
					(start 278.779224 -135.908796)
					(mid 278.582022 -135.649483)
					(end 278.678386 -135.338312)
				)
				(arc
					(start 278.678386 -135.338312)
					(mid 278.707256 -135.261706)
					(end 278.670258 -135.188706)
				)
				(arc
					(start 278.670258 -135.188706)
					(mid 278.543428 -134.86696)
					(end 278.749506 -134.589266)
				)
				(xy 278.779224 -134.575804)
				(arc
					(start 278.779224 -131.330446)
					(mid 278.806313 -131.250588)
					(end 278.76373 -131.177792)
				)
				(arc
					(start 278.76373 -131.177792)
					(mid 278.622459 -130.971623)
					(end 278.651462 -130.723386)
				)
				(arc
					(start 278.651462 -130.723386)
					(mid 278.656056 -130.640729)
					(end 278.597614 -130.582162)
				)
				(arc
					(start 278.597614 -130.582162)
					(mid 278.395145 -130.115425)
					(end 278.866092 -129.922778)
				)
				(arc
					(start 278.866092 -129.922778)
					(mid 278.96213 -129.914264)
					(end 279.007824 -129.829306)
				)
				(xy 279.007824 -127.80391) (xy 270.773144 -119.568976) (xy 270.773144 -103.2002) (xy 270.349472 -102.776528)
				(xy 270.349472 -101.481128) (xy 269.853156 -100.984812)
				(arc
					(start 269.853156 -100.478844)
					(mid 269.788805 -100.384064)
					(end 269.677134 -100.409502)
				)
				(arc
					(start 269.677134 -100.409502)
					(mid 269.060237 -100.167186)
					(end 269.677134 -99.92487)
				)
				(arc
					(start 269.677134 -99.92487)
					(mid 269.788785 -99.950258)
					(end 269.853156 -99.855528)
				)
				(arc
					(start 269.853156 -99.488498)
					(mid 269.788805 -99.393718)
					(end 269.677134 -99.419156)
				)
				(arc
					(start 269.677134 -99.419156)
					(mid 269.060237 -99.17684)
					(end 269.677134 -98.934524)
				)
				(arc
					(start 269.677134 -98.934524)
					(mid 269.788785 -98.959912)
					(end 269.853156 -98.865182)
				)
				(arc
					(start 269.853156 -98.497898)
					(mid 269.788805 -98.403118)
					(end 269.677134 -98.428556)
				)
				(arc
					(start 269.677134 -98.428556)
					(mid 269.060237 -98.18624)
					(end 269.677134 -97.943924)
				)
				(arc
					(start 269.677134 -97.943924)
					(mid 269.788785 -97.969312)
					(end 269.853156 -97.874582)
				)
				(arc
					(start 269.853156 -97.507298)
					(mid 269.788805 -97.412518)
					(end 269.677134 -97.437956)
				)
				(arc
					(start 269.677134 -97.437956)
					(mid 269.060237 -97.19564)
					(end 269.677134 -96.953324)
				)
				(arc
					(start 269.677134 -96.953324)
					(mid 269.788785 -96.978712)
					(end 269.853156 -96.883982)
				)
				(arc
					(start 269.853156 -96.516698)
					(mid 269.788805 -96.421918)
					(end 269.677134 -96.447356)
				)
				(arc
					(start 269.677134 -96.447356)
					(mid 269.060237 -96.20504)
					(end 269.677134 -95.962724)
				)
				(arc
					(start 269.677134 -95.962724)
					(mid 269.788785 -95.988112)
					(end 269.853156 -95.893382)
				)
				(arc
					(start 269.853156 -95.526098)
					(mid 269.845743 -95.487745)
					(end 269.824454 -95.454978)
				)
				(xy 269.824454 -93.446854) (xy 268.42466 -92.04706) (xy 263.00938 -92.04706) (xy 262.91032 -91.948)
				(xy 260.53034 -89.56802) (xy 259.96646 -89.56802) (xy 259.963412 -89.571068)
				(arc
					(start 259.841746 -89.571068)
					(mid 259.65023 -89.626951)
					(end 259.458714 -89.571068)
				)
				(arc
					(start 258.124706 -89.571068)
					(mid 257.93319 -89.626951)
					(end 257.741674 -89.571068)
				)
				(arc
					(start 256.407666 -89.571068)
					(mid 256.21615 -89.626951)
					(end 256.024634 -89.571068)
				)
				(arc
					(start 254.690626 -89.571068)
					(mid 254.49911 -89.626951)
					(end 254.307594 -89.571068)
				)
				(arc
					(start 252.97384 -89.571068)
					(mid 252.782324 -89.626951)
					(end 252.590808 -89.571068)
				)
			)
		)
	)
	(zone
		(net "GND")
		(layer "In5.Cu")
		(hatch none 0.5)
		(connect_pads
			(clearance 0.5)
		)
		(min_thickness 0.25)
		(fill yes
			(thermal_gap 0.5)
			(thermal_bridge_width 0.5)
			(island_removal_mode 0)
		)
		(polygon
			(pts
				(arc
					(start -3.675126 5.542788)
					(mid -4.995762 4.995762)
					(end -5.542788 3.675126)
				)
				(arc
					(start -5.542788 -156.77515)
					(mid -5.149761 -157.921025)
					(end -4.13639 -158.5849)
				)
				(xy -3.893566 -158.641542) (xy 186.511946 -158.641542) (xy 375.031 -158.642812) (xy 375.031 -158.635446)
				(xy 377.5202 -158.635446) (xy 377.5202 -158.642812) (xy 393.6492 -158.642812) (xy 393.6492 -158.632652)
				(xy 399.227548 -158.632652) (xy 399.23212 -158.637224)
				(arc
					(start 499.818152 -158.637224)
					(mid 500.955892 -158.134223)
					(end 501.52554 -157.028388)
				)
				(arc
					(start 501.52554 -111.950246)
					(mid 500.985068 -110.872764)
					(end 499.898924 -110.349792)
				)
				(xy 488.530392 -110.349792)
				(arc
					(start 488.212892 -110.667038)
					(mid 487.948986 -110.986468)
					(end 487.561382 -110.839758)
				)
				(arc
					(start 487.561382 -110.839758)
					(mid 487.4768 -110.794491)
					(end 487.392218 -110.839758)
				)
				(arc
					(start 487.392218 -110.839758)
					(mid 487.0958 -110.998509)
					(end 486.799382 -110.839758)
				)
				(arc
					(start 486.799382 -110.839758)
					(mid 486.7148 -110.794491)
					(end 486.630218 -110.839758)
				)
				(arc
					(start 486.630218 -110.839758)
					(mid 486.230205 -110.982703)
					(end 485.977946 -110.640876)
				)
				(xy 485.699308 -110.362492) (xy 427.608492 -110.362492) (xy 426.7327 -109.4867) (xy 426.7327 -68.2752)
				(xy 427.5963 -67.4116) (xy 478.3963 -67.4116) (xy 478.9932 -66.8147) (xy 478.9932 -63.0809) (xy 479.8822 -62.1919)
				(arc
					(start 500.008144 -62.1919)
					(mid 501.108659 -61.551307)
					(end 501.542812 -60.35421)
				)
				(xy 501.542812 -19.177) (xy 501.542558 -19.177) (xy 501.542558 -16.999966) (xy 501.540526 -16.9545)
				(xy 501.540526 -14.967966) (xy 501.03278 -14.46022) (xy 483.95636 -14.46022) (xy 483.39248 -13.89634)
				(arc
					(start 483.39248 0.50038)
					(mid 483.412036 0.692917)
					(end 483.46995 0.87757)
				)
				(xy 483.3874 0.96012) (xy 483.3874 2.89306) (xy 483.95382 3.45948) (xy 501.014238 3.45948) (xy 501.542558 3.9878)
				(arc
					(start 501.542558 4.99999)
					(mid 501.383651 5.383627)
					(end 501.000014 5.542534)
				)
				(xy 499.596156 5.542534) (xy 499.595902 5.542788) (xy 488.090464 5.529834) (xy 354.902262 5.529834)
				(xy 354.1014 5.542788)
				(arc
					(start 280.680414 5.542788)
					(mid 280.597085 5.499315)
					(end 280.585164 5.406136)
				)
				(arc
					(start 280.585164 5.406136)
					(mid 280.2509 4.927046)
					(end 279.916636 5.406136)
				)
				(arc
					(start 279.916636 5.406136)
					(mid 279.904629 5.499255)
					(end 279.821386 5.542788)
				)
				(arc
					(start 279.499314 5.542788)
					(mid 279.415985 5.499315)
					(end 279.404064 5.406136)
				)
				(arc
					(start 279.404064 5.406136)
					(mid 279.0698 4.927046)
					(end 278.735536 5.406136)
				)
				(arc
					(start 278.735536 5.406136)
					(mid 278.723529 5.499255)
					(end 278.640286 5.542788)
				)
				(arc
					(start 278.564594 5.542788)
					(mid 278.476311 5.491474)
					(end 278.477218 5.389372)
				)
				(arc
					(start 278.477218 5.389372)
					(mid 278.171148 4.851484)
					(end 277.865078 5.389372)
				)
				(arc
					(start 277.865078 5.389372)
					(mid 277.865972 5.491466)
					(end 277.777702 5.542788)
				)
				(arc
					(start 248.323354 5.542788)
					(mid 248.238332 5.496811)
					(end 248.23039 5.400548)
				)
				(arc
					(start 248.23039 5.400548)
					(mid 247.904 4.901559)
					(end 247.57761 5.400548)
				)
				(arc
					(start 247.57761 5.400548)
					(mid 247.569549 5.496734)
					(end 247.484646 5.542788)
				)
				(arc
					(start 167.242744 5.542788)
					(mid 167.156891 5.495519)
					(end 167.15105 5.397754)
				)
				(arc
					(start 167.15105 5.397754)
					(mid 166.828978 4.889408)
					(end 166.506906 5.397754)
				)
				(arc
					(start 166.506906 5.397754)
					(mid 166.500948 5.495444)
					(end 166.415212 5.542788)
				)
				(xy 115.697 5.542788) (xy 115.697 5.3086) (xy 115.6208 5.2324) (xy 115.594638 5.2324)
				(arc
					(start 115.584732 5.1943)
					(mid 115.2398 4.926996)
					(end 114.894868 5.1943)
				)
				(xy 114.884962 5.2324) (xy 114.756438 5.2324)
				(arc
					(start 114.746532 5.1943)
					(mid 114.406589 4.927031)
					(end 114.059208 5.184648)
				)
				(xy 114.055652 5.197348) (xy 113.9444 5.3086) (xy 113.9444 5.542788) (xy 19.116548 5.53339)
			)
		)
		(polygon
			(pts
				(xy 85.9028 -89.7636) (xy 85.56244 -89.7636) (xy 85.56244 -89.878154) (xy 85.051646 -90.388948)
				(xy 85.049614 -90.388948) (xy 84.662264 -90.776298) (xy 84.334604 -90.776298) (xy 84.145628 -90.965274)
				(xy 84.145628 -91.092528) (xy 84.281772 -91.228672) (xy 84.503006 -91.228672) (xy 84.77758 -90.954098)
				(xy 85.038184 -90.954098) (xy 85.377274 -90.615008) (xy 85.377274 -90.427302) (xy 85.628988 -90.175588)
				(xy 85.878924 -90.175588) (xy 85.975952 -90.07856) (xy 85.975952 -89.836752)
			)
		)
		(polygon
			(pts
				(xy 19.136106 -55.677054) (xy 13.030708 -55.677054) (xy 12.110466 -56.597296) (xy 12.110466 -66.193162)
				(xy 14.788134 -68.87083) (xy 18.95221 -68.87083) (xy 20.083526 -67.739514) (xy 20.083526 -56.624474)
			)
		)
		(polygon
			(pts
				(xy 9.992106 -48.754538) (xy 2.82575 -48.754538) (xy 1.79959 -49.780698) (xy 1.79959 -58.58002)
				(xy 0.502158 -59.877452) (xy 0.502158 -67.247262) (xy 2.24155 -68.986654) (xy 2.24155 -86.10981)
				(xy 3.593338 -87.461598) (xy 10.381996 -87.461598) (xy 11.387328 -86.456266) (xy 11.387328 -50.14976)
			)
		)
		(polygon
			(pts
				(arc
					(start 483.391972 -11.388852)
					(mid 483.338904 -11.309477)
					(end 483.243382 -11.309096)
				)
				(arc
					(start 483.243382 -11.309096)
					(mid 482.908897 -11.40638)
					(end 482.56317 -11.363706)
				)
				(arc
					(start 482.56317 -11.363706)
					(mid 482.467253 -11.380574)
					(end 482.429566 -11.470386)
				)
				(arc
					(start 482.429566 -11.470386)
					(mid 482.43382 -11.58555)
					(end 482.422708 -11.700256)
				)
				(arc
					(start 482.422708 -11.700256)
					(mid 482.458247 -11.795014)
					(end 482.55809 -11.812016)
				)
				(arc
					(start 482.55809 -11.812016)
					(mid 482.905572 -11.764346)
					(end 483.240842 -11.867388)
				)
				(arc
					(start 483.240842 -11.867388)
					(mid 483.337582 -11.869195)
					(end 483.391972 -11.789156)
				)
			)
		)
		(polygon
			(pts
				(arc
					(start 483.391972 -9.388856)
					(mid 483.338904 -9.309481)
					(end 483.243382 -9.3091)
				)
				(arc
					(start 483.243382 -9.3091)
					(mid 482.908897 -9.406384)
					(end 482.56317 -9.36371)
				)
				(arc
					(start 482.56317 -9.36371)
					(mid 482.467253 -9.380578)
					(end 482.429566 -9.47039)
				)
				(arc
					(start 482.429566 -9.47039)
					(mid 482.43382 -9.585554)
					(end 482.422708 -9.70026)
				)
				(arc
					(start 482.422708 -9.70026)
					(mid 482.458247 -9.795018)
					(end 482.55809 -9.81202)
				)
				(arc
					(start 482.55809 -9.81202)
					(mid 482.905572 -9.76435)
					(end 483.240842 -9.867392)
				)
				(arc
					(start 483.240842 -9.867392)
					(mid 483.337582 -9.869199)
					(end 483.391972 -9.78916)
				)
			)
		)
		(polygon
			(pts
				(arc
					(start 483.391972 -7.300976)
					(mid 483.337595 -7.220911)
					(end 483.240842 -7.222744)
				)
				(arc
					(start 483.240842 -7.222744)
					(mid 482.878878 -7.327443)
					(end 482.50856 -7.257796)
				)
				(arc
					(start 482.50856 -7.257796)
					(mid 482.403723 -7.271226)
					(end 482.36759 -7.370572)
				)
				(arc
					(start 482.36759 -7.370572)
					(mid 482.383385 -7.530084)
					(end 482.36759 -7.689596)
				)
				(arc
					(start 482.36759 -7.689596)
					(mid 482.403701 -7.788969)
					(end 482.50856 -7.802372)
				)
				(arc
					(start 482.50856 -7.802372)
					(mid 482.87888 -7.732689)
					(end 483.240842 -7.837424)
				)
				(arc
					(start 483.240842 -7.837424)
					(mid 483.337582 -7.839231)
					(end 483.391972 -7.759192)
				)
			)
		)
		(polygon
			(pts
				(arc
					(start 483.391972 -5.241036)
					(mid 483.337595 -5.160971)
					(end 483.240842 -5.162804)
				)
				(arc
					(start 483.240842 -5.162804)
					(mid 482.878878 -5.267503)
					(end 482.50856 -5.197856)
				)
				(arc
					(start 482.50856 -5.197856)
					(mid 482.403723 -5.211286)
					(end 482.36759 -5.310632)
				)
				(arc
					(start 482.36759 -5.310632)
					(mid 482.383385 -5.470144)
					(end 482.36759 -5.629656)
				)
				(arc
					(start 482.36759 -5.629656)
					(mid 482.403701 -5.729029)
					(end 482.50856 -5.742432)
				)
				(arc
					(start 482.50856 -5.742432)
					(mid 482.87888 -5.672749)
					(end 483.240842 -5.777484)
				)
				(arc
					(start 483.240842 -5.777484)
					(mid 483.337582 -5.779291)
					(end 483.391972 -5.699252)
				)
			)
		)
		(polygon
			(pts
				(arc
					(start 483.391972 -3.211068)
					(mid 483.337595 -3.131003)
					(end 483.240842 -3.132836)
				)
				(arc
					(start 483.240842 -3.132836)
					(mid 482.878878 -3.237535)
					(end 482.50856 -3.167888)
				)
				(arc
					(start 482.50856 -3.167888)
					(mid 482.403723 -3.181318)
					(end 482.36759 -3.280664)
				)
				(arc
					(start 482.36759 -3.280664)
					(mid 482.383385 -3.440176)
					(end 482.36759 -3.599688)
				)
				(arc
					(start 482.36759 -3.599688)
					(mid 482.403701 -3.699061)
					(end 482.50856 -3.712464)
				)
				(arc
					(start 482.50856 -3.712464)
					(mid 482.87888 -3.642781)
					(end 483.240842 -3.747516)
				)
				(arc
					(start 483.240842 -3.747516)
					(mid 483.337582 -3.749323)
					(end 483.391972 -3.669284)
				)
			)
		)
		(polygon
			(pts
				(arc
					(start 483.391972 -1.1811)
					(mid 483.337595 -1.101035)
					(end 483.240842 -1.102868)
				)
				(arc
					(start 483.240842 -1.102868)
					(mid 482.878878 -1.207567)
					(end 482.50856 -1.13792)
				)
				(arc
					(start 482.50856 -1.13792)
					(mid 482.403723 -1.15135)
					(end 482.36759 -1.250696)
				)
				(arc
					(start 482.36759 -1.250696)
					(mid 482.383385 -1.410208)
					(end 482.36759 -1.56972)
				)
				(arc
					(start 482.36759 -1.56972)
					(mid 482.403701 -1.669093)
					(end 482.50856 -1.682496)
				)
				(arc
					(start 482.50856 -1.682496)
					(mid 482.87888 -1.612813)
					(end 483.240842 -1.717548)
				)
				(arc
					(start 483.240842 -1.717548)
					(mid 483.337582 -1.719355)
					(end 483.391972 -1.639316)
				)
			)
		)
		(polygon
			(pts
				(arc
					(start 483.446836 0.819404)
					(mid 483.406802 0.927079)
					(end 483.291896 0.928624)
				)
				(arc
					(start 483.291896 0.928624)
					(mid 482.908809 0.794446)
					(end 482.50856 0.862076)
				)
				(arc
					(start 482.50856 0.862076)
					(mid 482.403723 0.848646)
					(end 482.36759 0.7493)
				)
				(arc
					(start 482.36759 0.7493)
					(mid 482.383385 0.589788)
					(end 482.36759 0.430276)
				)
				(arc
					(start 482.36759 0.430276)
					(mid 482.403701 0.330903)
					(end 482.50856 0.3175)
				)
				(arc
					(start 482.50856 0.3175)
					(mid 482.87888 0.387183)
					(end 483.240842 0.282448)
				)
				(arc
					(start 483.240842 0.282448)
					(mid 483.337582 0.280641)
					(end 483.391972 0.36068)
				)
				(arc
					(start 483.391972 0.500126)
					(mid 483.40581 0.662101)
					(end 483.446836 0.819404)
				)
			)
		)
	)
	(zone
		(net "PVDDQ_ABC")
		(layer "In5.Cu")
		(hatch none 0.5)
		(connect_pads
			(clearance 0.5)
		)
		(min_thickness 0.25)
		(fill yes
			(thermal_gap 0.5)
			(thermal_bridge_width 0.5)
			(island_removal_mode 0)
		)
		(polygon
			(pts
				(xy 244.3099 -6.1214) (xy 243.586 -6.8453) (xy 243.586 -7.366) (xy 243.7638 -7.5438) (xy 243.7638 -8.3312)
				(xy 243.34724 -8.74776) (xy 243.301774 -8.793226) (xy 243.341398 -8.83285)
				(arc
					(start 243.345716 -8.835644)
					(mid 243.50416 -9.1692)
					(end 243.281708 -9.46404)
				)
				(xy 243.249704 -9.47674) (xy 243.249704 -12.527788)
				(arc
					(start 243.290344 -12.53617)
					(mid 243.5758 -12.885166)
					(end 243.290344 -13.234162)
				)
				(xy 243.249704 -13.242544) (xy 243.249704 -13.603224)
				(arc
					(start 243.280946 -13.616178)
					(mid 243.49337 -13.933678)
					(end 243.280946 -14.251178)
				)
				(xy 243.249704 -14.264132) (xy 243.249704 -16.877792)
				(arc
					(start 243.289328 -16.886682)
					(mid 243.543759 -17.125536)
					(end 243.45773 -17.46377)
				)
				(arc
					(start 243.45773 -17.46377)
					(mid 243.428282 -17.539259)
					(end 243.463318 -17.61236)
				)
				(arc
					(start 243.463318 -17.61236)
					(mid 243.573489 -17.97663)
					(end 243.291614 -18.232374)
				)
				(xy 243.249704 -18.23974) (xy 243.249704 -18.40865)
				(arc
					(start 243.278914 -18.422366)
					(mid 243.484828 -18.7452)
					(end 243.278914 -19.068034)
				)
				(xy 243.249704 -19.08175)
				(arc
					(start 243.249704 -21.79193)
					(mid 243.263343 -21.826822)
					(end 243.297202 -21.84273)
				)
				(arc
					(start 243.297202 -21.84273)
					(mid 243.629324 -22.167259)
					(end 243.358162 -22.544278)
				)
				(xy 243.354606 -22.54504) (xy 243.3193 -22.580346)
				(arc
					(start 243.3193 -23.221696)
					(mid 243.494431 -23.624719)
					(end 243.144802 -23.890986)
				)
				(arc
					(start 243.144802 -23.890986)
					(mid 243.072135 -23.920291)
					(end 243.041932 -23.992586)
				)
				(xy 243.041932 -24.311864) (xy 243.08562 -24.355806) (xy 243.3955 -24.665686) (xy 243.3955 -26.9367)
				(xy 243.9035 -27.4447) (xy 243.9035 -28.655772) (xy 249.677428 -34.4297)
				(arc
					(start 249.677428 -39.995856)
					(mid 250.286855 -41.550082)
					(end 249.677428 -43.104308)
				)
				(arc
					(start 249.677428 -50.137822)
					(mid 249.719231 -50.219962)
					(end 249.81027 -50.234596)
				)
				(arc
					(start 249.81027 -50.234596)
					(mid 250.275826 -50.573432)
					(end 249.81027 -50.912268)
				)
				(arc
					(start 249.81027 -50.912268)
					(mid 249.719177 -50.926828)
					(end 249.677428 -51.009042)
				)
				(xy 249.677428 -54.3179) (xy 249.4153 -54.580028) (xy 249.4153 -55.23865)
				(arc
					(start 249.451368 -55.249572)
					(mid 249.70437 -55.59044)
					(end 249.451368 -55.931308)
				)
				(xy 249.4153 -55.94223) (xy 249.4153 -56.22925)
				(arc
					(start 249.451368 -56.240172)
					(mid 249.654661 -56.399563)
					(end 249.696732 -56.654446)
				)
				(xy 249.686318 -56.70423) (xy 249.7074 -56.708548) (xy 249.7074 -57.1246) (xy 249.806968 -57.224168)
				(xy 249.862086 -57.169304)
				(arc
					(start 249.857006 -57.142888)
					(mid 250.418163 -56.789549)
					(end 250.246134 -57.429908)
				)
				(arc
					(start 250.246134 -57.429908)
					(mid 250.161315 -57.497392)
					(end 250.185682 -57.602882)
				)
				(xy 250.2662 -57.6834) (xy 250.2662 -57.713626)
				(arc
					(start 250.303284 -57.72404)
					(mid 250.562045 -58.095284)
					(end 250.247658 -58.420762)
				)
				(xy 250.2027 -58.425842) (xy 250.2027 -58.6613) (xy 250.244102 -58.702702)
				(arc
					(start 250.260612 -58.705242)
					(mid 250.458592 -58.805458)
					(end 250.558808 -59.003438)
				)
				(xy 250.561348 -59.019948) (xy 250.826524 -59.285124)
				(arc
					(start 250.861576 -59.26074)
					(mid 251.317097 -59.301027)
					(end 251.357384 -59.756548)
				)
				(xy 251.333 -59.7916) (xy 251.4092 -59.8678) (xy 251.4092 -60.45073)
				(arc
					(start 251.410724 -60.456826)
					(mid 251.421417 -60.54344)
					(end 251.410724 -60.630054)
				)
				(xy 251.4092 -60.63615) (xy 251.4092 -61.44133)
				(arc
					(start 251.410724 -61.447426)
					(mid 251.421417 -61.53404)
					(end 251.410724 -61.620654)
				)
				(xy 251.4092 -61.62675) (xy 251.4092 -62.0522) (xy 251.7394 -62.3824) (xy 252.45441 -62.3824)
				(arc
					(start 252.468888 -62.35573)
					(mid 252.782324 -62.168588)
					(end 253.09576 -62.35573)
				)
				(xy 253.110238 -62.3824) (xy 254.171196 -62.3824)
				(arc
					(start 254.185674 -62.35573)
					(mid 254.49911 -62.168588)
					(end 254.812546 -62.35573)
				)
				(xy 254.827024 -62.3824) (xy 255.888236 -62.3824)
				(arc
					(start 255.902714 -62.35573)
					(mid 256.21615 -62.168588)
					(end 256.529586 -62.35573)
				)
				(xy 256.544064 -62.3824) (xy 257.605276 -62.3824)
				(arc
					(start 257.619754 -62.35573)
					(mid 257.93319 -62.168588)
					(end 258.246626 -62.35573)
				)
				(xy 258.261104 -62.3824) (xy 258.6355 -62.3824) (xy 259.363972 -63.110872) (xy 259.897118 -63.110872)
				(xy 260.065012 -63.278766) (xy 260.065012 -63.78067) (xy 260.167882 -63.88354) (xy 268.62278 -63.88354)
				(xy 269.113 -63.39332) (xy 269.113 -60.4774) (xy 269.113 -55.615332) (xy 269.113 -54.671468) (xy 268.848332 -54.4068)
				(arc
					(start 268.848332 -53.5305)
					(mid 268.801781 -53.445106)
					(end 268.704822 -53.438044)
				)
				(arc
					(start 268.704822 -53.438044)
					(mid 268.201615 -53.113686)
					(end 268.704822 -52.789328)
				)
				(arc
					(start 268.704822 -52.789328)
					(mid 268.801733 -52.782192)
					(end 268.848332 -52.696872)
				)
				(xy 268.848332 -52.156868) (xy 269.16888 -51.83632) (xy 269.16888 -50.107088) (xy 269.9766 -49.299368)
				(xy 269.9766 -34.186368) (xy 278.827484 -25.335484) (xy 278.827484 -23.163022)
				(arc
					(start 278.80056 -23.148798)
					(mid 278.612077 -22.8346)
					(end 278.80056 -22.520402)
				)
				(xy 278.827484 -22.506178) (xy 278.827484 -22.001988)
				(arc
					(start 278.79802 -21.988526)
					(mid 278.591203 -21.665184)
					(end 278.79802 -21.341842)
				)
				(xy 278.827484 -21.32838) (xy 278.827484 -19.029426)
				(arc
					(start 278.797766 -19.015964)
					(mid 278.592078 -18.741663)
					(end 278.713184 -18.420842)
				)
				(arc
					(start 278.713184 -18.420842)
					(mid 278.74854 -18.345682)
					(end 278.715978 -18.269204)
				)
				(arc
					(start 278.715978 -18.269204)
					(mid 278.601689 -17.997044)
					(end 278.73198 -17.732248)
				)
				(arc
					(start 278.73198 -17.732248)
					(mid 278.769059 -17.65287)
					(end 278.73071 -17.574006)
				)
				(arc
					(start 278.73071 -17.574006)
					(mid 278.597916 -17.254873)
					(end 278.798528 -16.973296)
				)
				(xy 278.827484 -16.95958)
				(arc
					(start 278.827484 -14.226286)
					(mid 278.683512 -13.940282)
					(end 278.827484 -13.654278)
				)
				(xy 278.827484 -13.300456)
				(arc
					(start 278.79421 -13.288264)
					(mid 278.561158 -12.954)
					(end 278.79421 -12.619736)
				)
				(xy 278.827484 -12.607544) (xy 278.827484 -12.276328)
				(arc
					(start 278.794972 -12.263628)
					(mid 278.56767 -11.93165)
					(end 278.794972 -11.599672)
				)
				(xy 278.827484 -11.586972) (xy 278.827484 -9.434322)
				(arc
					(start 278.79167 -9.4234)
					(mid 278.541371 -9.083294)
					(end 278.79167 -8.743188)
				)
				(xy 278.827484 -8.732266) (xy 278.827484 -8.458962)
				(arc
					(start 278.78786 -8.449818)
					(mid 278.510566 -8.1026)
					(end 278.78786 -7.755382)
				)
				(xy 278.827484 -7.746238) (xy 278.827484 -7.495286)
				(arc
					(start 278.785828 -7.487666)
					(mid 278.49377 -7.1374)
					(end 278.785828 -6.787134)
				)
				(xy 278.827484 -6.779514) (xy 278.827484 -6.526784) (xy 278.4221 -6.1214)
				(arc
					(start 261.996174 -6.1214)
					(mid 261.963247 -6.152839)
					(end 261.926578 -6.17982)
				)
				(arc
					(start 261.926578 -6.17982)
					(mid 261.879785 -6.263691)
					(end 261.923784 -6.348984)
				)
				(arc
					(start 261.923784 -6.348984)
					(mid 261.715647 -6.998134)
					(end 261.529322 -6.34238)
				)
				(arc
					(start 261.529322 -6.34238)
					(mid 261.576115 -6.258509)
					(end 261.532116 -6.173216)
				)
				(arc
					(start 261.532116 -6.173216)
					(mid 261.500833 -6.148965)
					(end 261.472426 -6.1214)
				)
			)
		)
	)
	(zone
		(net "PVDDQ_GHJ")
		(layer "In5.Cu")
		(hatch none 0.5)
		(connect_pads
			(clearance 0.5)
		)
		(min_thickness 0.25)
		(fill yes
			(thermal_gap 0.5)
			(thermal_bridge_width 0.5)
			(island_removal_mode 0)
		)
		(polygon
			(pts
				(xy 79.309468 -6.1214) (xy 78.842108 -6.58876) (xy 78.643734 -6.787134) (xy 78.643734 -7.529576)
				(xy 78.643988 -7.538466) (xy 78.643988 -8.380222) (xy 78.6384 -8.385302) (xy 78.6384 -8.6106) (xy 78.386178 -8.862822)
				(arc
					(start 78.41742 -8.898636)
					(mid 78.495589 -9.216498)
					(end 78.281276 -9.46404)
				)
				(xy 78.249272 -9.47674) (xy 78.249272 -12.527788)
				(arc
					(start 78.289912 -12.53617)
					(mid 78.575368 -12.885166)
					(end 78.289912 -13.234162)
				)
				(xy 78.249272 -13.242544) (xy 78.249272 -13.603224)
				(arc
					(start 78.280514 -13.616178)
					(mid 78.492938 -13.933678)
					(end 78.280514 -14.251178)
				)
				(xy 78.249272 -14.264132) (xy 78.249272 -16.877792)
				(arc
					(start 78.288896 -16.886682)
					(mid 78.543327 -17.125536)
					(end 78.457298 -17.46377)
				)
				(arc
					(start 78.457298 -17.46377)
					(mid 78.42785 -17.539259)
					(end 78.462886 -17.61236)
				)
				(arc
					(start 78.462886 -17.61236)
					(mid 78.573057 -17.97663)
					(end 78.291182 -18.232374)
				)
				(xy 78.249018 -18.23974) (xy 78.249018 -18.40865)
				(arc
					(start 78.278482 -18.422366)
					(mid 78.484396 -18.7452)
					(end 78.278482 -19.068034)
				)
				(xy 78.249272 -19.08175)
				(arc
					(start 78.249272 -21.79193)
					(mid 78.262911 -21.826822)
					(end 78.29677 -21.84273)
				)
				(arc
					(start 78.29677 -21.84273)
					(mid 78.630228 -22.198076)
					(end 78.29677 -22.553422)
				)
				(arc
					(start 78.29677 -22.553422)
					(mid 78.263019 -22.56943)
					(end 78.249272 -22.604222)
				)
				(xy 78.249272 -23.191216)
				(arc
					(start 78.281276 -23.203916)
					(mid 78.5057 -23.534878)
					(end 78.281276 -23.86584)
				)
				(xy 78.249272 -23.87854) (xy 78.249272 -24.09825) (xy 78.270354 -24.119586) (xy 78.534768 -24.384)
				(xy 78.534768 -26.9367) (xy 79.055468 -27.4574) (xy 79.055468 -28.808172) (xy 84.676996 -34.4297)
				(arc
					(start 84.676996 -39.995856)
					(mid 85.286423 -41.550082)
					(end 84.676996 -43.104308)
				)
				(arc
					(start 84.676996 -50.137822)
					(mid 84.718799 -50.219962)
					(end 84.809838 -50.234596)
				)
				(arc
					(start 84.809838 -50.234596)
					(mid 85.275394 -50.573432)
					(end 84.809838 -50.912268)
				)
				(arc
					(start 84.809838 -50.912268)
					(mid 84.718745 -50.926828)
					(end 84.676996 -51.009042)
				)
				(xy 84.676996 -54.3179) (xy 84.414868 -54.580028) (xy 84.414868 -55.23865)
				(arc
					(start 84.450936 -55.249572)
					(mid 84.703938 -55.59044)
					(end 84.450936 -55.931308)
				)
				(xy 84.414868 -55.94223) (xy 84.414868 -56.22925)
				(arc
					(start 84.450936 -56.240172)
					(mid 84.67629 -56.443463)
					(end 84.663026 -56.746648)
				)
				(xy 84.657184 -56.757824) (xy 84.657184 -57.074816)
				(arc
					(start 84.679536 -57.097168)
					(mid 84.784949 -57.121317)
					(end 84.85251 -57.036716)
				)
				(arc
					(start 84.85251 -57.036716)
					(mid 85.458066 -56.824352)
					(end 85.245702 -57.429908)
				)
				(arc
					(start 85.245702 -57.429908)
					(mid 85.160883 -57.497392)
					(end 85.18525 -57.602882)
				)
				(xy 85.265768 -57.6834) (xy 85.265768 -57.713626)
				(arc
					(start 85.302852 -57.72404)
					(mid 85.561613 -58.095284)
					(end 85.247226 -58.420762)
				)
				(xy 85.202268 -58.425842) (xy 85.202268 -58.6613) (xy 85.24367 -58.702702)
				(arc
					(start 85.26018 -58.705242)
					(mid 85.45816 -58.805458)
					(end 85.558376 -59.003438)
				)
				(xy 85.560916 -59.019948)
				(arc
					(start 85.82787 -59.286902)
					(mid 86.316728 -59.300964)
					(end 86.33079 -59.789822)
				)
				(xy 86.408768 -59.8678) (xy 86.408768 -60.45073)
				(arc
					(start 86.410292 -60.456826)
					(mid 86.420985 -60.54344)
					(end 86.410292 -60.630054)
				)
				(xy 86.408768 -60.63615) (xy 86.408768 -61.44133)
				(arc
					(start 86.410292 -61.447426)
					(mid 86.420985 -61.53404)
					(end 86.410292 -61.620654)
				)
				(xy 86.408768 -61.62675) (xy 86.408768 -62.0522) (xy 86.738968 -62.3824) (xy 87.453978 -62.3824)
				(arc
					(start 87.468456 -62.35573)
					(mid 87.781892 -62.168588)
					(end 88.095328 -62.35573)
				)
				(xy 88.109806 -62.3824) (xy 89.170764 -62.3824)
				(arc
					(start 89.185242 -62.35573)
					(mid 89.498678 -62.168588)
					(end 89.812114 -62.35573)
				)
				(xy 89.826592 -62.3824) (xy 90.887804 -62.3824)
				(arc
					(start 90.902282 -62.35573)
					(mid 91.215718 -62.168588)
					(end 91.529154 -62.35573)
				)
				(xy 91.543632 -62.3824) (xy 92.604844 -62.3824)
				(arc
					(start 92.619322 -62.35573)
					(mid 92.932758 -62.168588)
					(end 93.246194 -62.35573)
				)
				(xy 93.260672 -62.3824) (xy 93.66758 -62.3824) (xy 94.383098 -63.097918) (xy 94.871794 -63.097918)
				(xy 95.132144 -63.358268) (xy 95.132144 -63.754762) (xy 95.260922 -63.88354) (xy 103.57866 -63.88354)
				(xy 104.05872 -63.40348) (xy 104.05872 -62.25032) (xy 104.05872 -56.293258) (xy 104.05872 -54.536848)
				(xy 103.8479 -54.325774)
				(arc
					(start 103.8479 -53.5305)
					(mid 103.801349 -53.445106)
					(end 103.70439 -53.438044)
				)
				(arc
					(start 103.70439 -53.438044)
					(mid 103.201183 -53.113686)
					(end 103.70439 -52.789328)
				)
				(arc
					(start 103.70439 -52.789328)
					(mid 103.801301 -52.782192)
					(end 103.8479 -52.696872)
				)
				(xy 103.8479 -52.156868) (xy 104.168448 -51.83632) (xy 104.168448 -50.107088) (xy 104.976168 -49.299368)
				(xy 104.976168 -34.186368) (xy 113.827052 -25.335484) (xy 113.827052 -23.163022)
				(arc
					(start 113.800128 -23.148798)
					(mid 113.611645 -22.8346)
					(end 113.800128 -22.520402)
				)
				(xy 113.827052 -22.506178) (xy 113.827052 -22.001988)
				(arc
					(start 113.797588 -21.988526)
					(mid 113.590771 -21.665184)
					(end 113.797588 -21.341842)
				)
				(xy 113.827052 -21.32838) (xy 113.827052 -19.029426)
				(arc
					(start 113.797334 -19.015964)
					(mid 113.591646 -18.741663)
					(end 113.712752 -18.420842)
				)
				(arc
					(start 113.712752 -18.420842)
					(mid 113.748108 -18.345682)
					(end 113.715546 -18.269204)
				)
				(arc
					(start 113.715546 -18.269204)
					(mid 113.601257 -17.997044)
					(end 113.731548 -17.732248)
				)
				(arc
					(start 113.731548 -17.732248)
					(mid 113.768627 -17.65287)
					(end 113.730278 -17.574006)
				)
				(arc
					(start 113.730278 -17.574006)
					(mid 113.597484 -17.254873)
					(end 113.798096 -16.973296)
				)
				(xy 113.827052 -16.95958)
				(arc
					(start 113.827052 -14.226286)
					(mid 113.68308 -13.940282)
					(end 113.827052 -13.654278)
				)
				(xy 113.827052 -13.300456)
				(arc
					(start 113.793778 -13.288264)
					(mid 113.560726 -12.954)
					(end 113.793778 -12.619736)
				)
				(xy 113.827052 -12.607544) (xy 113.827052 -12.276328)
				(arc
					(start 113.79454 -12.263628)
					(mid 113.567238 -11.93165)
					(end 113.79454 -11.599672)
				)
				(xy 113.827052 -11.586972) (xy 113.827052 -9.434322)
				(arc
					(start 113.791238 -9.4234)
					(mid 113.540939 -9.083294)
					(end 113.791238 -8.743188)
				)
				(xy 113.827052 -8.732266) (xy 113.827052 -8.458962)
				(arc
					(start 113.787428 -8.449818)
					(mid 113.510134 -8.1026)
					(end 113.787428 -7.755382)
				)
				(xy 113.827052 -7.746238) (xy 113.827052 -7.495286)
				(arc
					(start 113.785396 -7.487666)
					(mid 113.493338 -7.1374)
					(end 113.785396 -6.787134)
				)
				(xy 113.827052 -6.779514) (xy 113.827052 -6.526784) (xy 113.421668 -6.1214)
				(arc
					(start 97.165414 -6.1214)
					(mid 97.085408 -6.160377)
					(end 97.066862 -6.247384)
				)
				(arc
					(start 97.066862 -6.247384)
					(mid 97.056745 -6.452227)
					(end 96.93529 -6.617462)
				)
				(arc
					(start 96.93529 -6.617462)
					(mid 96.894751 -6.698665)
					(end 96.93529 -6.779768)
				)
				(arc
					(start 96.93529 -6.779768)
					(mid 96.721168 -7.420306)
					(end 96.507046 -6.779768)
				)
				(arc
					(start 96.507046 -6.779768)
					(mid 96.547382 -6.698666)
					(end 96.507046 -6.617462)
				)
				(arc
					(start 96.507046 -6.617462)
					(mid 96.385663 -6.452201)
					(end 96.375474 -6.247384)
				)
				(arc
					(start 96.375474 -6.247384)
					(mid 96.356868 -6.160424)
					(end 96.276922 -6.1214)
				)
			)
		)
	)
	(zone
		(net "PVDDQ_KLM")
		(layer "In5.Cu")
		(hatch none 0.5)
		(connect_pads
			(clearance 0.5)
		)
		(min_thickness 0.25)
		(fill yes
			(thermal_gap 0.5)
			(thermal_bridge_width 0.5)
			(island_removal_mode 0)
		)
		(polygon
			(pts
				(arc
					(start 96.506284 -89.5985)
					(mid 96.238405 -89.602971)
					(end 96.043242 -89.41943)
				)
				(xy 95.83039 -89.41943) (xy 95.82658 -89.42324)
				(arc
					(start 94.971616 -89.42324)
					(mid 94.649798 -89.626919)
					(end 94.32798 -89.42324)
				)
				(arc
					(start 93.254576 -89.42324)
					(mid 92.932758 -89.626919)
					(end 92.61094 -89.42324)
				)
				(arc
					(start 91.537536 -89.42324)
					(mid 91.215718 -89.626919)
					(end 90.8939 -89.42324)
				)
				(arc
					(start 89.820496 -89.42324)
					(mid 89.498678 -89.626919)
					(end 89.17686 -89.42324)
				)
				(arc
					(start 88.10371 -89.42324)
					(mid 87.781892 -89.626919)
					(end 87.460074 -89.42324)
				)
				(xy 86.514178 -89.42324) (xy 86.141052 -89.796366) (xy 86.074504 -89.862914) (xy 86.12124 -89.909396)
				(arc
					(start 86.136226 -89.912444)
					(mid 86.340084 -90.487582)
					(end 85.73643 -90.399108)
				)
				(arc
					(start 85.73643 -90.399108)
					(mid 85.662289 -90.338723)
					(end 85.570822 -90.366596)
				)
				(arc
					(start 85.480398 -90.45702)
					(mid 85.465602 -90.490863)
					(end 85.477604 -90.525854)
				)
				(arc
					(start 85.477604 -90.525854)
					(mid 85.465156 -91.001006)
					(end 84.991448 -91.040458)
				)
				(xy 84.956142 -91.013788) (xy 84.85251 -91.11742)
				(arc
					(start 84.85251 -91.36507)
					(mid 84.905921 -91.454515)
					(end 85.00999 -91.449906)
				)
				(arc
					(start 85.00999 -91.449906)
					(mid 85.562515 -91.74698)
					(end 85.010244 -92.044266)
				)
				(arc
					(start 85.010244 -92.044266)
					(mid 84.906182 -92.039669)
					(end 84.852764 -92.129102)
				)
				(arc
					(start 84.852764 -92.35567)
					(mid 84.906175 -92.445115)
					(end 85.010244 -92.440506)
				)
				(arc
					(start 85.010244 -92.440506)
					(mid 85.562375 -92.737792)
					(end 85.00999 -93.034866)
				)
				(arc
					(start 85.00999 -93.034866)
					(mid 84.905928 -93.030269)
					(end 84.85251 -93.119702)
				)
				(arc
					(start 84.85251 -93.346524)
					(mid 84.905921 -93.435969)
					(end 85.00999 -93.43136)
				)
				(arc
					(start 85.00999 -93.43136)
					(mid 85.562515 -93.72854)
					(end 85.00999 -94.02572)
				)
				(arc
					(start 85.00999 -94.02572)
					(mid 84.905928 -94.021123)
					(end 84.85251 -94.110556)
				)
				(arc
					(start 84.85251 -94.33687)
					(mid 84.905921 -94.426315)
					(end 85.00999 -94.421706)
				)
				(arc
					(start 85.00999 -94.421706)
					(mid 85.562515 -94.718886)
					(end 85.00999 -95.016066)
				)
				(arc
					(start 85.00999 -95.016066)
					(mid 84.905928 -95.011469)
					(end 84.85251 -95.100902)
				)
				(arc
					(start 84.85251 -95.32747)
					(mid 84.905921 -95.416915)
					(end 85.00999 -95.412306)
				)
				(arc
					(start 85.00999 -95.412306)
					(mid 85.562515 -95.70938)
					(end 85.010244 -96.006666)
				)
				(arc
					(start 85.010244 -96.006666)
					(mid 84.906182 -96.002069)
					(end 84.852764 -96.091502)
				)
				(arc
					(start 84.852764 -96.31807)
					(mid 84.906175 -96.407515)
					(end 85.010244 -96.402906)
				)
				(arc
					(start 85.010244 -96.402906)
					(mid 85.562375 -96.700086)
					(end 85.010244 -96.997266)
				)
				(arc
					(start 85.010244 -96.997266)
					(mid 84.906182 -96.992669)
					(end 84.852764 -97.082102)
				)
				(arc
					(start 84.852764 -97.30867)
					(mid 84.906175 -97.398115)
					(end 85.010244 -97.393506)
				)
				(arc
					(start 85.010244 -97.393506)
					(mid 85.562375 -97.690686)
					(end 85.010244 -97.987866)
				)
				(arc
					(start 85.010244 -97.987866)
					(mid 84.906182 -97.983269)
					(end 84.852764 -98.072702)
				)
				(xy 84.852764 -98.405696) (xy 84.97443 -98.527616) (xy 85.438996 -98.992182) (xy 85.438996 -119.931434)
				(xy 78.759304 -126.610872)
				(arc
					(start 78.759304 -129.132584)
					(mid 78.800809 -129.21476)
					(end 78.891638 -129.229612)
				)
				(arc
					(start 78.891638 -129.229612)
					(mid 79.355358 -129.568956)
					(end 78.891638 -129.9083)
				)
				(arc
					(start 78.891638 -129.9083)
					(mid 78.800847 -129.923203)
					(end 78.759304 -130.005328)
				)
				(xy 78.759304 -130.523488) (xy 78.494636 -130.788156) (xy 78.494636 -131.498848)
				(arc
					(start 78.495906 -131.504436)
					(mid 78.505487 -131.586478)
					(end 78.495906 -131.66852)
				)
				(xy 78.494636 -131.674108)
				(arc
					(start 78.494636 -134.0612)
					(mid 78.62579 -134.331202)
					(end 78.494636 -134.601204)
				)
				(arc
					(start 78.494636 -135.169148)
					(mid 78.586076 -135.4074)
					(end 78.494636 -135.645652)
				)
				(xy 78.494636 -136.299448)
				(arc
					(start 78.495906 -136.305036)
					(mid 78.505487 -136.387078)
					(end 78.495906 -136.46912)
				)
				(xy 78.494636 -136.474708) (xy 78.494636 -139.15517)
				(arc
					(start 78.495906 -139.160758)
					(mid 78.505487 -139.2428)
					(end 78.495906 -139.324842)
				)
				(xy 78.494636 -139.33043)
				(arc
					(start 78.494636 -139.942316)
					(mid 78.613587 -140.208)
					(end 78.494636 -140.473684)
				)
				(arc
					(start 78.494636 -143.736314)
					(mid 78.571391 -143.952722)
					(end 78.494636 -144.16913)
				)
				(arc
					(start 78.494636 -144.770348)
					(mid 78.586076 -145.0086)
					(end 78.494636 -145.246852)
				)
				(xy 78.494636 -145.900648)
				(arc
					(start 78.495906 -145.906236)
					(mid 78.505139 -145.970577)
					(end 78.50251 -146.035522)
				)
				(xy 78.498954 -146.060414) (xy 78.626462 -146.187922) (xy 78.684628 -146.129502)
				(arc
					(start 78.674468 -146.09953)
					(mid 79.193982 -145.705387)
					(end 79.011526 -146.331432)
				)
				(arc
					(start 79.011526 -146.331432)
					(mid 78.920459 -146.39586)
					(end 78.943454 -146.504914)
				)
				(xy 79.35214 -146.9136) (xy 90.726768 -146.9136) (xy 91.358212 -147.545044) (xy 91.564206 -147.750784)
				(xy 94.533974 -147.750784) (xy 95.173546 -147.111212)
				(arc
					(start 95.407988 -147.111212)
					(mid 95.501889 -147.04841)
					(end 95.479616 -146.93773)
				)
				(arc
					(start 95.479616 -146.93773)
					(mid 95.730568 -146.328841)
					(end 95.98152 -146.93773)
				)
				(arc
					(start 95.98152 -146.93773)
					(mid 95.959361 -147.048363)
					(end 96.053148 -147.111212)
				)
				(xy 96.103694 -147.111212) (xy 96.580706 -146.6342) (xy 113.47069 -146.6342) (xy 113.63706 -146.6342)
				(xy 113.69802 -146.57324) (xy 113.69802 -146.363944) (xy 113.69802 -146.316192) (xy 113.567718 -146.18589)
				(xy 113.529872 -146.120104) (xy 113.509806 -146.032982) (xy 113.507774 -145.971768) (xy 113.516156 -145.9103)
				(xy 113.567718 -145.77187) (xy 113.764822 -145.574766) (xy 113.764822 -145.4531) (xy 113.765584 -145.452338)
				(xy 113.765584 -144.92478)
				(arc
					(start 113.731548 -144.912842)
					(mid 113.493294 -144.5768)
					(end 113.731548 -144.240758)
				)
				(xy 113.765584 -144.22882) (xy 113.765584 -141.412976) (xy 113.600992 -141.248384) (xy 113.600992 -139.81557)
				(arc
					(start 113.596674 -139.805664)
					(mid 113.565562 -139.660122)
					(end 113.596674 -139.51458)
				)
				(xy 113.600992 -139.504674) (xy 113.600992 -139.500356) (xy 113.605564 -139.495784)
				(arc
					(start 113.60912 -139.489434)
					(mid 113.669805 -139.408387)
					(end 113.750852 -139.347702)
				)
				(xy 113.757202 -139.344146) (xy 113.955068 -139.14628) (xy 114.021108 -139.079986) (xy 114.021108 -136.974072)
				(xy 113.969292 -136.922256) (xy 113.866168 -136.819132) (xy 113.866168 -136.684258)
				(arc
					(start 113.826036 -136.675622)
					(mid 113.555703 -136.411819)
					(end 113.674652 -136.053322)
				)
				(arc
					(start 113.674652 -136.053322)
					(mid 113.711335 -135.979855)
					(end 113.681764 -135.903208)
				)
				(arc
					(start 113.681764 -135.903208)
					(mid 113.577973 -135.633155)
					(end 113.708942 -135.375142)
				)
				(arc
					(start 113.708942 -135.375142)
					(mid 113.746272 -135.29115)
					(end 113.70056 -135.211312)
				)
				(arc
					(start 113.70056 -135.211312)
					(mid 113.546418 -134.846067)
					(end 113.825528 -134.564628)
				)
				(xy 113.866168 -134.556246) (xy 113.866168 -131.2291)
				(arc
					(start 113.834418 -131.2164)
					(mid 113.633997 -131.010342)
					(end 113.65103 -130.723386)
				)
				(arc
					(start 113.65103 -130.723386)
					(mid 113.655624 -130.640729)
					(end 113.597182 -130.582162)
				)
				(arc
					(start 113.597182 -130.582162)
					(mid 113.397137 -130.109984)
					(end 113.876328 -129.927604)
				)
				(arc
					(start 113.876328 -129.927604)
					(mid 113.973972 -129.921403)
					(end 114.021108 -129.835656)
				)
				(xy 114.021108 -127.815594) (xy 105.774744 -119.568976) (xy 105.774744 -95.4786) (xy 103.4288 -93.132656)
				(xy 103.33482 -93.038676) (xy 103.33482 -90.97772) (xy 102.54996 -90.19286) (xy 102.21214 -90.19286)
				(xy 101.981 -89.96172) (xy 101.981 -89.41562) (xy 102.11308 -89.28354) (xy 102.5779 -88.81872) (xy 106.26598 -88.81872)
				(xy 106.80827 -88.27643) (xy 106.80827 -87.616284) (xy 107.178602 -87.245952) (xy 109.575854 -87.245952)
				(xy 109.702092 -87.119714) (xy 109.702092 -85.753194) (xy 109.460538 -85.51164) (xy 106.54792 -85.51164)
				(xy 100.16236 -85.51164) (xy 96.506284 -89.167716)
			)
		)
	)
	(zone
		(net "P12V_PSU")
		(layer "In5.Cu")
		(hatch none 0.5)
		(connect_pads
			(clearance 0.5)
		)
		(min_thickness 0.25)
		(fill yes
			(thermal_gap 0.5)
			(thermal_bridge_width 0.5)
			(island_removal_mode 0)
		)
		(polygon
			(pts
				(xy 3.0988 -59.1058) (xy 2.3114 -59.8932) (xy 1.824736 -60.379864) (xy 1.824736 -66.757042) (xy 2.3114 -67.243706)
				(xy 3.556 -68.488306) (xy 3.556 -85.610446) (xy 4.122674 -86.17712) (xy 9.845294 -86.17712) (xy 10.0838 -85.938614)
				(xy 10.0838 -50.6984) (xy 9.4488 -50.0634) (xy 3.3782 -50.0634) (xy 3.0988 -50.3428)
			)
		)
	)
	(zone
		(net "VR_FET_SW_P12V_STBY_PVCCIN_CPU1")
		(layer "In6.Cu")
		(hatch none 0.5)
		(connect_pads
			(clearance 0.5)
		)
		(min_thickness 0.25)
		(fill yes
			(thermal_gap 0.5)
			(thermal_bridge_width 0.5)
			(island_removal_mode 0)
		)
		(polygon
			(pts
				(xy 24.9174 -48.9712) (xy 24.2824 -49.6062) (xy 24.2824 -54.3052) (xy 25.7302 -55.753)
				(arc
					(start 25.7302 -74.04735)
					(mid 25.779706 -74.134325)
					(end 25.879806 -74.136758)
				)
				(arc
					(start 25.879806 -74.136758)
					(mid 26.441895 -74.4728)
					(end 25.879806 -74.808842)
				)
				(arc
					(start 25.879806 -74.808842)
					(mid 25.779653 -74.811185)
					(end 25.7302 -74.89825)
				)
				(xy 25.7302 -79.6798) (xy 27.04084 -80.99044) (xy 27.04084 -95.62084) (xy 24.1554 -98.50628) (xy 24.1554 -108.6358)
				(xy 24.6888 -109.1692) (xy 32.258 -109.1692) (xy 32.893 -108.5342) (xy 32.893 -108.261912)
				(arc
					(start 32.869378 -108.246926)
					(mid 31.956212 -106.571084)
					(end 32.893 -104.90835)
				)
				(xy 32.893 -103.0351) (xy 33.88614 -102.04196) (xy 33.88614 -52.13858) (xy 33.05556 -51.308) (xy 32.5628 -51.308)
				(xy 30.4038 -51.308) (xy 29.0576 -49.9618) (xy 29.0576 -49.149) (xy 28.8798 -48.9712)
			)
		)
		(polygon
			(pts
				(arc
					(start 32.831024 -54.087014)
					(mid 32.760648 -54.051414)
					(end 32.68599 -54.076854)
				)
				(arc
					(start 32.68599 -54.076854)
					(mid 32.491473 -54.164241)
					(end 32.281876 -54.12486)
				)
				(arc
					(start 32.281876 -54.12486)
					(mid 32.176263 -54.131026)
					(end 32.13354 -54.22773)
				)
				(arc
					(start 32.13354 -54.22773)
					(mid 32.10519 -54.632581)
					(end 31.920688 -54.994048)
				)
				(arc
					(start 31.920688 -54.994048)
					(mid 31.904321 -55.090906)
					(end 31.977584 -55.156354)
				)
				(arc
					(start 31.977584 -55.156354)
					(mid 32.098061 -55.206735)
					(end 32.1945 -55.294784)
				)
				(arc
					(start 32.1945 -55.294784)
					(mid 32.271967 -55.334078)
					(end 32.351472 -55.299102)
				)
				(arc
					(start 32.351472 -55.299102)
					(mid 32.53861 -55.181773)
					(end 32.759396 -55.18785)
				)
				(arc
					(start 32.759396 -55.18785)
					(mid 32.846721 -55.176653)
					(end 32.892492 -55.10149)
				)
				(arc
					(start 32.892492 -54.144164)
					(mid 32.86007 -54.117405)
					(end 32.831024 -54.087014)
				)
			)
		)
		(polygon
			(pts
				(arc
					(start 32.854646 -79.226156)
					(mid 32.486975 -79.04937)
					(end 32.218376 -78.742286)
				)
				(arc
					(start 32.218376 -78.742286)
					(mid 32.170507 -78.75871)
					(end 32.121348 -78.770734)
				)
				(arc
					(start 32.121348 -78.770734)
					(mid 32.109327 -79.103695)
					(end 31.990284 -79.414878)
				)
				(arc
					(start 31.990284 -79.414878)
					(mid 31.981652 -79.498516)
					(end 32.039052 -79.559912)
				)
				(arc
					(start 32.039052 -79.559912)
					(mid 32.113188 -79.600883)
					(end 32.176466 -79.657194)
				)
				(arc
					(start 32.176466 -79.657194)
					(mid 32.244967 -79.690751)
					(end 32.317436 -79.6671)
				)
				(arc
					(start 32.317436 -79.6671)
					(mid 32.523666 -79.579734)
					(end 32.743394 -79.623158)
				)
				(arc
					(start 32.743394 -79.623158)
					(mid 32.839223 -79.623256)
					(end 32.892492 -79.543656)
				)
				(xy 32.892492 -79.235554)
			)
		)
		(polygon
			(pts
				(arc
					(start 32.854646 -71.098156)
					(mid 32.491649 -70.924904)
					(end 32.224218 -70.624446)
				)
				(arc
					(start 32.224218 -70.624446)
					(mid 32.185053 -70.635024)
					(end 32.145224 -70.642734)
				)
				(arc
					(start 32.145224 -70.642734)
					(mid 32.11323 -70.661526)
					(end 32.102552 -70.69709)
				)
				(arc
					(start 32.102552 -70.69709)
					(mid 32.082735 -70.999315)
					(end 31.97479 -71.282306)
				)
				(arc
					(start 31.97479 -71.282306)
					(mid 31.967684 -71.366942)
					(end 32.027368 -71.42734)
				)
				(arc
					(start 32.027368 -71.42734)
					(mid 32.095658 -71.461165)
					(end 32.155892 -71.507858)
				)
				(arc
					(start 32.155892 -71.507858)
					(mid 32.226372 -71.535709)
					(end 32.296608 -71.507096)
				)
				(arc
					(start 32.296608 -71.507096)
					(mid 32.509735 -71.402594)
					(end 32.743394 -71.444358)
				)
				(arc
					(start 32.743394 -71.444358)
					(mid 32.839223 -71.444456)
					(end 32.892492 -71.364856)
				)
				(xy 32.892492 -71.107554)
			)
		)
		(polygon
			(pts
				(arc
					(start 32.854646 -62.970156)
					(mid 32.499144 -62.802483)
					(end 32.23387 -62.512448)
				)
				(arc
					(start 32.23387 -62.512448)
					(mid 32.168064 -62.53074)
					(end 32.10052 -62.540896)
				)
				(arc
					(start 32.10052 -62.540896)
					(mid 32.066532 -62.558443)
					(end 32.054292 -62.594744)
				)
				(arc
					(start 32.054292 -62.594744)
					(mid 32.031668 -62.877009)
					(end 31.932118 -63.142114)
				)
				(arc
					(start 31.932118 -63.142114)
					(mid 31.927873 -63.230361)
					(end 31.994348 -63.288672)
				)
				(arc
					(start 31.994348 -63.288672)
					(mid 32.087089 -63.328025)
					(end 32.166306 -63.390272)
				)
				(arc
					(start 32.166306 -63.390272)
					(mid 32.235805 -63.420766)
					(end 32.307022 -63.39459)
				)
				(arc
					(start 32.307022 -63.39459)
					(mid 32.516848 -63.298961)
					(end 32.743394 -63.341758)
				)
				(arc
					(start 32.743394 -63.341758)
					(mid 32.839223 -63.341856)
					(end 32.892492 -63.262256)
				)
				(xy 32.892492 -62.979554)
			)
		)
	)
	(zone
		(net "PVCCIOMCP_CPU1")
		(layer "In6.Cu")
		(hatch none 0.5)
		(connect_pads
			(clearance 0.5)
		)
		(min_thickness 0.25)
		(fill yes
			(thermal_gap 0.5)
			(thermal_bridge_width 0.5)
			(island_removal_mode 0)
		)
		(polygon
			(pts
				(xy 158.254192 -103.503984) (xy 155.78455 -105.973626) (xy 155.78455 -107.548426) (xy 156.249878 -108.013754)
				(xy 156.251402 -108.013754) (xy 156.74594 -108.508292) (xy 160.445704 -108.508292) (xy 160.940242 -108.013754)
				(xy 191.219582 -108.013754) (xy 192.758568 -106.474768) (xy 192.758568 -106.464354) (xy 193.510408 -105.712514)
				(xy 193.510408 -103.85552) (xy 193.158872 -103.503984) (xy 192.07861 -103.503984) (xy 185.998612 -103.503984)
				(xy 185.044588 -103.503984)
			)
		)
	)
	(zone
		(net "P12V_FAN")
		(layer "In6.Cu")
		(hatch none 0.5)
		(connect_pads
			(clearance 0.5)
		)
		(min_thickness 0.25)
		(fill yes
			(thermal_gap 0.5)
			(thermal_bridge_width 0.5)
			(island_removal_mode 0)
		)
		(polygon
			(pts
				(xy 10.550652 -30.347666) (xy 10.4267 -30.471618) (xy 10.4267 -39.7256) (xy 6.080252 -44.072048)
				(xy 6.090666 -44.085256) (xy 5.1689 -45.007022) (xy 5.1689 -85.2297) (xy 10.2489 -90.3097) (xy 10.2489 -104.5591)
				(xy 10.211308 -104.596946) (xy 10.211308 -104.70261) (xy 7.70001 -107.213908) (xy 7.594092 -107.213908)
				(xy 4.572 -110.236) (xy 4.572 -116.3574) (xy 4.7244 -116.5098) (xy 10.0965 -116.5098) (xy 11.211814 -115.394486)
				(xy 11.211814 -115.373658) (xy 11.232642 -115.373658) (xy 14.9606 -111.6457) (xy 14.9606 -100.6348)
				(xy 14.1732 -99.8474) (xy 14.1732 -87.223346) (xy 16.3576 -85.038946) (xy 16.3576 -68.002404) (xy 16.358108 -68.001896)
				(xy 16.358108 -66.927984) (xy 16.3576 -66.927476) (xy 16.3576 -49.3395) (xy 18.585688 -47.111412)
				(xy 18.585688 -43.9293) (xy 20.223988 -42.291) (xy 31.4452 -42.291) (xy 32.4739 -41.2623) (xy 32.4739 -32.0929)
				(xy 30.728666 -30.347666)
			)
		)
		(polygon
			(pts
				(arc
					(start 15.797784 -62.146942)
					(mid 15.722973 -62.115019)
					(end 15.648686 -62.148212)
				)
				(arc
					(start 15.648686 -62.148212)
					(mid 15.453747 -62.278466)
					(end 15.220442 -62.301628)
				)
				(arc
					(start 15.220442 -62.301628)
					(mid 15.134909 -62.328967)
					(end 15.104618 -62.413388)
				)
				(arc
					(start 15.104618 -62.413388)
					(mid 15.072081 -62.623825)
					(end 14.93774 -62.789054)
				)
				(arc
					(start 14.93774 -62.789054)
					(mid 14.896305 -62.85848)
					(end 14.91869 -62.93612)
				)
				(arc
					(start 14.91869 -62.93612)
					(mid 15.011721 -63.205283)
					(end 14.905482 -63.46952)
				)
				(arc
					(start 14.905482 -63.46952)
					(mid 14.878836 -63.5381)
					(end 14.905482 -63.60668)
				)
				(arc
					(start 14.905482 -63.60668)
					(mid 15.011811 -63.874249)
					(end 14.914372 -64.14516)
				)
				(arc
					(start 14.914372 -64.14516)
					(mid 14.889983 -64.2112)
					(end 14.914372 -64.27724)
				)
				(arc
					(start 14.914372 -64.27724)
					(mid 15.00881 -64.59228)
					(end 14.839442 -64.87414)
				)
				(arc
					(start 14.839442 -64.87414)
					(mid 14.796316 -64.957198)
					(end 14.839442 -65.040256)
				)
				(arc
					(start 14.839442 -65.040256)
					(mid 15.020443 -65.346584)
					(end 14.910308 -65.684908)
				)
				(arc
					(start 14.910308 -65.684908)
					(mid 14.883901 -65.752696)
					(end 14.909546 -65.820798)
				)
				(arc
					(start 14.909546 -65.820798)
					(mid 15.011837 -66.079253)
					(end 14.924278 -66.343022)
				)
				(arc
					(start 14.924278 -66.343022)
					(mid 14.90248 -66.409979)
					(end 14.929358 -66.475102)
				)
				(arc
					(start 14.929358 -66.475102)
					(mid 15.033658 -66.805872)
					(end 14.84503 -67.096894)
				)
				(arc
					(start 14.84503 -67.096894)
					(mid 14.821968 -67.130545)
					(end 14.83106 -67.1703)
				)
				(arc
					(start 14.839188 -67.18173)
					(mid 14.879371 -67.203795)
					(end 14.920976 -67.184524)
				)
				(arc
					(start 14.920976 -67.184524)
					(mid 15.214191 -67.030977)
					(end 15.52448 -67.14617)
				)
				(arc
					(start 15.52448 -67.14617)
					(mid 15.5956 -67.175188)
					(end 15.66672 -67.14617)
				)
				(arc
					(start 15.66672 -67.14617)
					(mid 15.965932 -67.030436)
					(end 16.256 -67.167506)
				)
				(arc
					(start 16.256 -67.167506)
					(mid 16.2941 -67.184644)
					(end 16.3322 -67.167506)
				)
				(xy 16.3576 -67.14109) (xy 16.3576 -66.928238) (xy 16.357092 -66.92773)
				(arc
					(start 16.357092 -62.380114)
					(mid 16.31696 -62.308992)
					(end 16.237458 -62.290452)
				)
				(arc
					(start 16.237458 -62.290452)
					(mid 15.999354 -62.274694)
					(end 15.797784 -62.146942)
				)
			)
		)
	)
	(zone
		(net "P3V3")
		(layer "In6.Cu")
		(hatch none 0.5)
		(connect_pads
			(clearance 0.5)
		)
		(min_thickness 0.25)
		(fill yes
			(thermal_gap 0.5)
			(thermal_bridge_width 0.5)
			(island_removal_mode 0)
		)
		(polygon
			(pts
				(xy 389.069326 -83.567524) (xy 403.709886 -83.567524) (xy 405.255984 -82.021426) (xy 405.255984 -79.008224)
				(xy 404.546054 -78.298294) (xy 388.816596 -78.298294) (xy 387.854444 -79.260446) (xy 387.854444 -82.352642)
			)
		)
	)
	(zone
		(net "P12V")
		(layer "In6.Cu")
		(hatch none 0.5)
		(connect_pads
			(clearance 0.5)
		)
		(min_thickness 0.25)
		(fill yes
			(thermal_gap 0.5)
			(thermal_bridge_width 0.5)
			(island_removal_mode 0)
		)
		(polygon
			(pts
				(xy 415.38144 -105.141268) (xy 417.739068 -107.498896) (xy 418.28085 -108.040678) (xy 418.281358 -108.040678)
				(xy 418.281358 -108.041186) (xy 418.81933 -108.579158) (xy 418.81933 -109.169454) (xy 418.81933 -110.083346)
				(xy 418.81933 -110.369604) (xy 418.81933 -111.016796) (xy 418.81933 -112.091724) (xy 418.81933 -112.416336)
				(xy 418.81933 -112.82172) (xy 418.81933 -113.16208) (xy 418.81933 -113.502694) (xy 418.81933 -113.827306)
				(xy 418.81933 -117.841776) (xy 418.81933 -118.11508) (xy 426.201332 -125.497082) (xy 426.363892 -125.659642)
				(xy 435.74589 -125.659642) (xy 437.109362 -127.023114) (xy 437.380888 -127.29464)
				(arc
					(start 441.6933 -127.29464)
					(mid 441.723268 -127.311247)
					(end 441.757054 -127.316992)
				)
				(xy 451.968108 -127.316992) (xy 452.708772 -127.316992) (xy 455.005948 -127.316992) (xy 455.28484 -127.0381)
				(xy 455.4601 -126.86284) (xy 455.4601 -122.978672) (xy 455.28484 -122.803412) (xy 454.731882 -122.2502)
				(xy 454.174098 -121.692416) (xy 454.150222 -121.66854) (xy 454.149968 -121.66854) (xy 454.053448 -121.57202)
				(xy 426.925232 -121.57202) (xy 421.724074 -116.370862) (xy 421.52189 -116.168678) (xy 421.52189 -114.994436)
				(xy 421.52189 -114.113564) (xy 421.52189 -112.454436) (xy 421.52189 -111.573564) (xy 421.52189 -109.914436)
				(xy 421.52189 -107.318556) (xy 421.521128 -107.31754) (xy 421.521128 -106.56824) (xy 420.788084 -105.835196)
				(xy 420.788084 -59.906916) (xy 423.661078 -57.033922) (xy 430.165764 -57.033922) (xy 430.677066 -56.52262)
				(xy 432.670204 -56.52262) (xy 432.816254 -56.66867) (xy 432.895248 -56.747664) (xy 433.960778 -57.81294)
				(xy 434.750718 -58.60288) (xy 438.338468 -58.60288) (xy 440.869578 -61.13399) (xy 440.876436 -61.13399)
				(xy 441.19165 -61.449204) (xy 441.30341 -61.560964) (xy 441.407042 -61.664596) (xy 443.338204 -61.664596)
				(xy 444.186056 -60.816744) (xy 444.186056 -59.761628) (xy 439.506614 -55.082186) (xy 437.221122 -55.082186)
				(xy 435.465982 -53.327046) (xy 434.851302 -52.712366) (xy 434.367432 -52.228496) (xy 425.87418 -52.228496)
				(xy 425.654978 -52.447698) (xy 424.818302 -52.447698) (xy 423.938954 -53.327046) (xy 423.521378 -53.744622)
				(xy 421.744902 -53.744622) (xy 421.061388 -54.428136) (xy 419.683692 -54.428136) (xy 419.233096 -53.97754)
				(xy 417.664138 -53.97754) (xy 415.804604 -55.837074) (xy 415.804604 -57.90692) (xy 415.38144 -58.330084)
				(xy 415.38144 -78.405228) (xy 414.935416 -78.851252) (xy 414.935416 -104.31018) (xy 414.935416 -104.695244)
			)
		)
	)
	(zone
		(net "PVCCMCP_CPU1")
		(layer "In6.Cu")
		(hatch none 0.5)
		(connect_pads
			(clearance 0.5)
		)
		(min_thickness 0.25)
		(fill yes
			(thermal_gap 0.5)
			(thermal_bridge_width 0.5)
			(island_removal_mode 0)
		)
		(polygon
			(pts
				(xy 149.379432 -45.235368) (xy 145.415 -49.1998) (xy 104.9528 -49.1998) (xy 104.237028 -49.915572)
				(xy 104.237028 -51.807364) (xy 104.242108 -52.26939) (xy 104.242108 -64.033908) (xy 104.2162 -78.8162)
				(xy 104.3686 -78.9686) (xy 112.6744 -78.9686) (xy 112.800892 -78.842108) (xy 112.800892 -78.10119)
				(xy 112.8014 -78.100936) (xy 112.8014 -77.978) (xy 113.1824 -77.597) (xy 119.014494 -77.597) (xy 119.014748 -77.596746)
				(xy 119.70131 -77.596746) (xy 119.70131 -77.597) (xy 120.734328 -77.597) (xy 121.905268 -78.76794)
				(xy 121.905268 -83.199732) (xy 120.929908 -84.175092) (xy 120.929908 -86.727538) (xy 120.929908 -89.518998)
				(xy 120.929908 -89.760806) (xy 120.929908 -90.130122) (xy 122.221752 -91.421966) (xy 123.81357 -91.421966)
				(xy 123.872244 -91.363292) (xy 124.017024 -91.218512) (xy 124.659898 -90.575384) (xy 125.259592 -89.97569)
				(xy 125.259592 -89.701878) (xy 125.259592 -86.500208) (xy 125.619764 -86.140036) (xy 126.16942 -85.59038)
				(xy 126.3396 -85.4202) (xy 126.5936 -85.4202) (xy 126.59487 -85.41893) (xy 126.718822 -85.41893)
				(xy 127.784352 -84.3534) (xy 128.670304 -84.3534) (xy 132.720334 -84.3534) (xy 132.740908 -84.332826)
				(xy 141.856206 -75.217528) (xy 141.856206 -75.212194) (xy 158.670244 -58.398156) (xy 158.670244 -56.971692)
				(xy 158.6992 -56.942736) (xy 158.6992 -56.6928) (xy 159.872426 -55.519574) (xy 160.5026 -55.519574)
				(xy 176.966626 -55.519574) (xy 177.4698 -55.0164) (xy 177.4698 -50.5968) (xy 177.9016 -50.165) (xy 182.1942 -50.165)
				(xy 183.769 -51.7398) (xy 184.416954 -52.387754) (xy 193.861944 -52.387754) (xy 194.3862 -52.387754)
				(xy 194.7926 -51.981354) (xy 194.7926 -48.3362) (xy 195.6816 -47.4472) (xy 195.6816 -45.0596) (xy 191.8081 -41.1861)
				(xy 153.4287 -41.1861)
			)
		)
	)
	(zone
		(net "P1V8_PCH_STBY")
		(layer "In6.Cu")
		(hatch none 0.5)
		(connect_pads
			(clearance 0.5)
		)
		(min_thickness 0.25)
		(fill yes
			(thermal_gap 0.5)
			(thermal_bridge_width 0.5)
			(island_removal_mode 0)
		)
		(polygon
			(pts
				(xy 395.891004 -104.843834) (xy 395.482318 -104.843834) (xy 394.864082 -104.843834) (xy 391.959338 -104.843834)
				(xy 390.413494 -104.843834) (xy 390.258554 -104.688894) (xy 389.45693 -103.88727) (xy 388.99338 -103.42372)
				(xy 388.878064 -103.308404) (xy 385.430268 -103.308404) (xy 384.90144 -103.837232) (xy 384.90144 -105.447592)
				(xy 386.349748 -106.8959) (xy 387.335522 -106.8959)
				(arc
					(start 387.706108 -106.8959)
					(mid 387.734626 -106.910598)
					(end 387.766306 -106.915712)
				)
				(xy 388.508494 -106.915712) (xy 391.705846 -106.915712)
				(arc
					(start 391.718292 -106.903266)
					(mid 391.741769 -106.912535)
					(end 391.766806 -106.915712)
				)
				(xy 392.321542 -106.915712) (xy 392.708638 -106.528616) (xy 393.407138 -106.528616) (xy 393.817094 -106.938572)
				(xy 393.817094 -106.938826) (xy 394.11402 -107.235752) (xy 394.11402 -107.416092) (xy 394.11402 -108.210604)
				(xy 394.372338 -108.468922) (xy 394.376148 -108.471716) (xy 394.471906 -108.567474) (xy 399.381472 -108.567474)
				(xy 399.44802 -108.500926) (xy 399.609564 -108.339382) (xy 402.345398 -108.339382) (xy 402.355304 -108.329476)
				(xy 402.594064 -108.329476) (xy 410.540708 -116.27612) (xy 410.540708 -119.719852) (xy 410.540708 -120.513348)
				(xy 410.540708 -120.842532) (xy 411.450282 -121.75236) (xy 411.450282 -127.039878) (xy 411.39745 -127.09271)
				(xy 411.393386 -127.09271) (xy 410.343096 -128.143) (xy 410.329888 -128.143) (xy 406.73528 -131.737862)
				(xy 405.32304 -133.150102) (xy 405.32304 -135.633206) (xy 405.32304 -138.448542) (xy 405.2062 -138.565128)
				(xy 405.2062 -138.5824) (xy 404.680674 -139.107926) (xy 404.680674 -144.185894) (xy 404.84298 -144.3482)
				(xy 404.969726 -144.474946) (xy 407.441654 -144.474946) (xy 407.758392 -144.474946) (xy 411.7086 -140.524738)
				(xy 411.7086 -140.208) (xy 411.7086 -130.266948) (xy 414.424368 -127.55118) (xy 414.556448 -127.4191)
				(xy 414.556448 -116.21135) (xy 414.424368 -116.07927) (xy 414.21304 -115.867942) (xy 413.391858 -115.04676)
				(xy 413.389826 -115.04676) (xy 413.389826 -115.044728) (xy 412.215584 -113.870486) (xy 411.353 -113.007902)
				(xy 409.213812 -110.868968) (xy 409.203906 -110.868968) (xy 408.711146 -110.376208) (xy 408.713432 -110.368588)
				(xy 404.904956 -106.560112) (xy 404.904956 -104.19461) (xy 404.083774 -103.373428) (xy 403.436836 -102.72649)
				(xy 399.781776 -102.72649) (xy 398.99209 -102.72649) (xy 398.27581 -102.72649) (xy 398.110202 -102.72649)
				(xy 398.008348 -102.72649)
			)
		)
	)
	(zone
		(net "PVCCMCP_CPU0")
		(layer "In6.Cu")
		(hatch none 0.5)
		(connect_pads
			(clearance 0.5)
		)
		(min_thickness 0.25)
		(fill yes
			(thermal_gap 0.5)
			(thermal_bridge_width 0.5)
			(island_removal_mode 0)
		)
		(polygon
			(pts
				(xy 317.868808 -47.879) (xy 311.912 -51.374294) (xy 311.800494 -51.4858) (xy 311.155334 -51.4858)
				(xy 269.4686 -51.4858) (xy 269.24 -51.7144) (xy 269.24 -52.267104) (xy 269.24254 -52.26939) (xy 269.24254 -64.033908)
				(xy 269.24254 -70.566788) (xy 269.24254 -79.00543) (xy 269.51051 -79.2734) (xy 273.7612 -79.2734)
				(xy 275.6916 -81.2038) (xy 276.225 -81.2038) (xy 276.2504 -81.1784) (xy 282.476194 -81.1784) (xy 282.48102 -81.183226)
				(xy 286.694626 -81.183226) (xy 286.82569 -81.31429) (xy 286.923734 -81.412334) (xy 286.923734 -81.42478)
				(xy 286.990028 -81.491074) (xy 286.990028 -82.804) (xy 286.923734 -82.870294) (xy 286.0929 -83.701128)
				(xy 286.0929 -83.7819) (xy 286.0929 -85.2043) (xy 285.9024 -85.3948) (xy 285.9024 -89.48801) (xy 285.9024 -89.792302)
				(xy 285.9024 -90.115644) (xy 287.328356 -91.5416) (xy 287.576006 -91.5416) (xy 288.5186 -91.5416)
				(xy 289.6616 -90.3986) (xy 289.6616 -88.723216) (xy 289.6616 -88.43137) (xy 289.6616 -87.766906)
				(xy 289.6616 -87.467948) (xy 289.6616 -86.7664) (xy 289.685476 -86.742524)
				(arc
					(start 289.78733 -86.64067)
					(mid 289.799989 -86.62524)
					(end 289.809428 -86.60765)
				)
				(arc
					(start 290.283646 -86.133432)
					(mid 290.30111 -86.124127)
					(end 290.316412 -86.111588)
				)
				(xy 290.405312 -86.022688) (xy 290.7792 -85.6488) (xy 291.010594 -85.6488) (xy 291.7952 -85.6488)
				(xy 292.303708 -85.140292) (xy 292.303962 -85.140038) (xy 292.8112 -84.6328) (xy 292.8112 -84.325714)
				(xy 292.8112 -81.28) (xy 292.7985 -81.2673) (xy 292.7985 -79.8703) (xy 292.6588 -79.7306) (xy 292.5064 -79.5782)
				(xy 292.5064 -76.0476) (xy 292.8874 -75.6666) (xy 292.9128 -75.6666) (xy 293.6494 -75.6666) (xy 294.132 -76.1492)
				(xy 294.3606 -76.1492) (xy 295.147492 -76.936092) (xy 295.782492 -76.936092) (xy 296.137838 -76.581)
				(xy 297.1292 -76.581) (xy 297.4721 -76.581) (xy 298.3738 -75.6793) (xy 300.228254 -73.824846) (xy 300.2788 -73.7743)
				(xy 300.303946 -73.749154) (xy 300.368208 -73.684892) (xy 306.688744 -73.684892) (xy 322.199508 -73.684892)
				(xy 341.636604 -73.684892) (xy 353.751896 -61.5696) (xy 353.751896 -42.542714) (xy 352.581464 -41.372282)
				(xy 324.375526 -41.372282)
			)
		)
	)
	(zone
		(net "GND")
		(layer "In6.Cu")
		(hatch none 0.5)
		(connect_pads
			(clearance 0.5)
		)
		(min_thickness 0.25)
		(fill yes
			(thermal_gap 0.5)
			(thermal_bridge_width 0.5)
			(island_removal_mode 0)
		)
		(polygon
			(pts
				(xy 97.163636 -63.026036) (xy 97.917 -63.7794) (xy 103.616252 -63.7794) (xy 103.870506 -63.525146)
				(xy 103.870506 -52.257706) (xy 103.1494 -51.5366) (xy 33.286954 -51.5366) (xy 33.1724 -51.651154)
				(xy 33.1724 -52.324) (xy 33.1724 -53.505354) (xy 33.1724 -54.20741) (xy 33.1724 -55.1434) (xy 33.147508 -55.168292)
				(xy 33.147508 -57.0738) (xy 33.1724 -57.0738) (xy 33.1724 -61.633354) (xy 33.1724 -62.33541) (xy 33.1724 -63.3857)
				(xy 33.147508 -63.3857) (xy 33.147508 -65.2145) (xy 33.1724 -65.2145) (xy 33.1724 -69.761354) (xy 33.18129 -69.770244)
				(xy 33.18129 -70.460616) (xy 33.1724 -70.46341) (xy 33.1724 -71.5137) (xy 33.147508 -71.5137) (xy 33.147508 -73.3298)
				(xy 33.1724 -73.3298) (xy 33.1724 -77.889354) (xy 33.1724 -78.59141) (xy 33.1724 -79.6417) (xy 33.147508 -79.6417)
				(xy 33.147508 -81.4578) (xy 33.1724 -81.4578) (xy 33.1724 -86.017354) (xy 33.1724 -86.71941) (xy 33.1724 -87.7824)
				(xy 33.147508 -87.7824) (xy 33.147508 -89.5985) (xy 33.1724 -89.5985) (xy 33.1724 -92.798392) (xy 33.3756 -93.001592)
				(xy 43.0149 -93.001592) (xy 43.210226 -92.806266) (xy 43.210226 -53.515006) (xy 43.505882 -53.21935)
				(xy 49.25695 -53.21935) (xy 58.9534 -62.9158) (xy 66.359278 -62.910974) (xy 97.048574 -62.910974)
			)
		)
	)
	(zone
		(net "GND")
		(layer "In6.Cu")
		(hatch none 0.5)
		(connect_pads
			(clearance 0.5)
		)
		(min_thickness 0.25)
		(fill yes
			(thermal_gap 0.5)
			(thermal_bridge_width 0.5)
			(island_removal_mode 0)
		)
		(polygon
			(pts
				(xy 245.74119 -88.54567) (xy 239.789462 -88.54567) (xy 239.308132 -89.027) (xy 235.053632 -93.2815)
				(xy 232.3465 -93.2815) (xy 224.777554 -100.850446) (xy 224.777554 -102.946708) (xy 225.843846 -104.013)
				(xy 279.0825 -104.013) (xy 279.158446 -103.937054) (xy 279.158446 -90.093546) (xy 279.0825 -90.0176)
				(xy 279.07615 -90.01125) (xy 278.231092 -90.01125) (xy 277.318216 -90.01125) (xy 269.849092 -90.01125)
				(xy 269.51305 -90.01125) (xy 269.282418 -89.780618) (xy 268.4018 -88.9) (xy 262.89 -88.9) (xy 262.636 -89.154)
				(xy 261.8994 -89.154) (xy 261.3914 -88.646) (xy 261.325106 -88.579706) (xy 257.869436 -88.579706)
				(xy 255.863598 -86.573868) (xy 255.737868 -86.573868) (xy 247.712992 -86.573868) (xy 247.54586 -86.741)
			)
		)
	)
	(zone
		(net "GND")
		(layer "In6.Cu")
		(hatch none 0.5)
		(connect_pads
			(clearance 0.5)
		)
		(min_thickness 0.25)
		(fill yes
			(thermal_gap 0.5)
			(thermal_bridge_width 0.5)
			(island_removal_mode 0)
		)
		(polygon
			(pts
				(xy 165.65245 -55.98795) (xy 166.90086 -57.23636) (xy 166.90086 -70.0786) (xy 161.59988 -75.37958)
				(xy 161.59988 -79.60614) (xy 149.45106 -91.75496) (xy 149.45106 -92.98686) (xy 150.36546 -93.90126)
				(xy 161.22142 -93.90126) (xy 163.28136 -95.9612) (xy 181.37378 -95.9612) (xy 183.45658 -98.044)
				(xy 183.45658 -103.07066) (xy 183.769 -103.38308) (xy 193.39052 -103.38308) (xy 193.7385 -103.73106)
				(xy 199.89038 -103.73106) (xy 199.89419 -103.72725) (xy 207.33258 -103.72725) (xy 207.74152 -103.31831)
				(xy 207.74152 -93.835728) (xy 207.4418 -93.536008) (xy 199.663304 -93.536008) (xy 199.553322 -93.64599)
				(xy 199.553322 -101.416358) (xy 198.57974 -102.38994) (xy 189.17666 -102.38994) (xy 188.16828 -101.38156)
				(xy 188.16828 -62.9158) (xy 185.4708 -60.21832) (xy 178.10226 -60.21832) (xy 177.49266 -59.60872)
				(xy 177.49266 -55.9308) (xy 177.34026 -55.7784) (xy 165.6842 -55.7784) (xy 165.65245 -55.81015)
			)
		)
	)
	(zone
		(net "PVCCIO_CPU1")
		(layer "In6.Cu")
		(hatch none 0.5)
		(connect_pads
			(clearance 0.5)
		)
		(min_thickness 0.25)
		(fill yes
			(thermal_gap 0.5)
			(thermal_bridge_width 0.5)
			(island_removal_mode 0)
		)
		(polygon
			(pts
				(xy 160.222946 -55.778654) (xy 158.924498 -57.077102) (xy 158.924498 -58.677302) (xy 141.650466 -75.951334)
				(xy 133.102096 -84.499704) (xy 133.034278 -84.567522) (xy 132.949188 -84.652612) (xy 130.404616 -84.652612)
				(xy 130.398774 -84.6582) (xy 129.44348 -84.6582) (xy 128.728216 -84.6582) (xy 127.9906 -84.6582)
				(xy 127.9398 -84.6582) (xy 127.893064 -84.6582) (xy 126.699264 -85.852) (xy 126.3904 -85.852) (xy 125.927358 -86.315042)
				(xy 125.473206 -86.769194) (xy 125.473206 -89.177622) (xy 125.474984 -89.1794) (xy 125.474984 -90.004392)
				(xy 125.474984 -90.120216) (xy 124.202444 -91.392756) (xy 124.030994 -91.564206) (xy 123.9774 -91.6178)
				(xy 122.545348 -91.6178) (xy 122.02795 -91.6178) (xy 120.6754 -90.26525) (xy 120.6754 -84.96681)
				(xy 120.6754 -84.097876) (xy 121.6406 -83.132676) (xy 121.6406 -82.72526) (xy 121.6406 -81.941924)
				(xy 121.6406 -79.1972) (xy 121.157238 -78.713838) (xy 120.3198 -77.8764) (xy 119.66575 -77.8764)
				(xy 119.050054 -77.8764) (xy 113.3856 -77.8764) (xy 113.0554 -78.2066) (xy 113.0554 -79.9592) (xy 115.6208 -82.5246)
				(xy 115.6208 -82.534252) (xy 115.740434 -82.653886) (xy 115.740434 -89.565734) (xy 115.740434 -95.699834)
				(xy 115.740434 -101.830632) (xy 117.358668 -103.448866) (xy 123.489466 -103.448866) (xy 136.418574 -103.448866)
				(xy 137.166096 -103.448866) (xy 137.372852 -103.24211) (xy 142.16888 -98.446082) (xy 142.16888 -98.44532)
				(xy 160.614868 -79.999332) (xy 160.8836 -79.7306) (xy 160.8836 -74.9554) (xy 166.497 -69.342) (xy 166.497 -64.991234)
				(xy 166.497 -63.775082) (xy 166.497 -57.4294) (xy 164.846254 -55.778654)
			)
		)
	)
	(zone
		(net "PVDDQ_ABC")
		(layer "In6.Cu")
		(hatch none 0.5)
		(connect_pads
			(clearance 0.5)
		)
		(min_thickness 0.25)
		(fill yes
			(thermal_gap 0.5)
			(thermal_bridge_width 0.5)
			(island_removal_mode 0)
		)
		(polygon
			(pts
				(xy 185.8264 4.0894) (xy 185.8264 3.458718) (xy 185.8264 -0.518922) (xy 185.8264 -2.4638) (xy 186.06389 -2.70129)
				(xy 186.064144 -2.701544) (xy 186.655964 -3.293364)
				(arc
					(start 186.66206 -3.296666)
					(mid 186.738692 -3.354908)
					(end 186.796934 -3.43154)
				)
				(xy 186.800236 -3.437636) (xy 186.9567 -3.5941) (xy 187.419996 -3.5941) (xy 189.1411 -3.5941) (xy 190.3984 -4.8514)
				(xy 193.4464 -7.8994) (xy 193.4464 -14.866874) (xy 193.4464 -15.460726) (xy 193.4464 -19.561302)
				(xy 193.4464 -20.933156) (xy 193.4464 -23.2664) (xy 193.0908 -23.622) (xy 193.0908 -24.003) (xy 193.3702 -24.2824)
				(xy 193.674238 -24.2824) (xy 194.0814 -24.2824) (xy 194.321176 -24.042624) (xy 194.437 -23.9268)
				(xy 194.648836 -23.9268) (xy 327.82383 -23.9268) (xy 327.914254 -24.017224) (xy 327.928224 -24.017224)
				(xy 328.1172 -24.2062) (xy 329.4634 -24.2062) (xy 329.7428 -23.9268) (xy 330.52385 -23.9268) (xy 330.708 -23.9268)
				(xy 332.023974 -22.610826) (xy 332.65872 -21.97608) (xy 335.788 -18.8468) (xy 335.788 -10.0584)
				(xy 337.82 -8.0264)
				(arc
					(start 337.82 4.145534)
					(mid 337.817623 4.167382)
					(end 337.810602 4.188206)
				)
				(xy 337.82 4.197604) (xy 337.82 5.043678) (xy 337.82 5.207) (xy 337.566 5.461) (xy 186.306714 5.461)
				(xy 185.8264 4.980686)
			)
		)
	)
	(zone
		(net "PVSA_CPU1")
		(layer "In6.Cu")
		(hatch none 0.5)
		(connect_pads
			(clearance 0.5)
		)
		(min_thickness 0.25)
		(fill yes
			(thermal_gap 0.5)
			(thermal_bridge_width 0.5)
			(island_removal_mode 0)
		)
		(polygon
			(pts
				(xy 79.896716 -80.809592) (xy 74.420984 -80.809592) (xy 73.54443 -80.809592) (xy 72.857868 -80.809592)
				(xy 69.519038 -84.148422) (xy 66.588132 -84.148422) (xy 66.586354 -84.1502) (xy 63.109856 -84.1502)
				(xy 54.499256 -92.7608) (xy 44.323 -92.7608) (xy 44.32046 -92.76334) (xy 43.88358 -92.76334) (xy 43.16984 -93.47708)
				(xy 43.16984 -99.027488) (xy 43.809412 -99.66706) (xy 43.809412 -102.802182) (xy 44.286932 -103.279702)
				(xy 56.740298 -103.279702) (xy 67.747388 -92.272612) (xy 70.097904 -92.272612) (xy 70.168516 -92.202)
				(xy 74.182986 -88.18753) (xy 80.46847 -88.18753) (xy 80.518 -88.138) (xy 81.476596 -87.179404) (xy 82.15757 -86.49843)
				(xy 82.281776 -86.374224) (xy 82.469228 -86.186772) (xy 85.962998 -86.186772) (xy 86.04377 -86.106)
				(xy 86.307168 -85.842602) (xy 86.307168 -82.60461) (xy 86.307168 -81.265268) (xy 85.606636 -80.564482)
				(xy 85.606636 -80.56118) (xy 85.5218 -80.476344) (xy 85.5218 -80.337914) (xy 85.5218 -79.553816)
				(xy 85.292184 -79.3242) (xy 85.290406 -79.322422) (xy 82.203544 -79.322422) (xy 82.201766 -79.3242)
				(xy 81.407 -79.3242) (xy 81.382108 -79.3242)
			)
		)
	)
	(zone
		(net "PVCCIN_CPU0")
		(layer "In6.Cu")
		(hatch none 0.5)
		(connect_pads
			(clearance 0.5)
		)
		(min_thickness 0.25)
		(fill yes
			(thermal_gap 0.5)
			(thermal_bridge_width 0.5)
			(island_removal_mode 0)
		)
		(polygon
			(pts
				(xy 208.8134 -53.5432) (xy 208.661 -53.6956) (xy 208.663032 -92.2274) (xy 208.815432 -92.3798) (xy 213.569042 -92.3798)
				(xy 215.876124 -92.3798) (xy 219.437204 -92.3798) (xy 219.778326 -92.075) (xy 227.968556 -83.88477)
				(xy 232.101898 -83.88477) (xy 234.248706 -83.88477) (xy 237.550452 -80.583024) (xy 244.7798 -80.583024)
				(xy 244.873526 -80.583024) (xy 246.373396 -79.0829) (xy 250.41098 -79.0829) (xy 250.487942 -79.159862)
				(xy 250.488196 -79.160116) (xy 250.576334 -79.248254) (xy 250.80468 -79.4766) (xy 250.80468 -80.40243)
				(xy 251.224542 -80.822292) (xy 251.51715 -81.1149) (xy 251.51715 -82.454242) (xy 251.51715 -85.209888)
				(xy 252.654054 -86.346792) (xy 256.151634 -86.346792) (xy 257.959606 -88.154764) (xy 261.712202 -88.154764)
				(xy 262.130286 -88.572848) (xy 269.09268 -88.572848) (xy 269.434564 -88.914732)
				(arc
					(start 269.452598 -88.91651)
					(mid 269.668138 -89.018978)
					(end 269.770606 -89.234518)
				)
				(xy 269.772384 -89.252552) (xy 270.080232 -89.5604) (xy 270.084042 -89.5604) (xy 270.170656 -89.647014)
				(xy 279.036018 -89.647014) (xy 279.15108 -89.647014) (xy 280.062432 -88.735662) (xy 280.062432 -88.38438)
				(xy 280.062432 -86.8934) (xy 279.131776 -85.962744)
				(arc
					(start 279.1206 -85.95868)
					(mid 278.975629 -85.867939)
					(end 278.884888 -85.722968)
				)
				(xy 278.880824 -85.711792) (xy 275.790152 -82.62112) (xy 274.92325 -81.754218) (xy 272.747232 -79.5782)
				(xy 269.3416 -79.5782) (xy 268.734032 -78.970632) (xy 268.734032 -64.2874) (xy 268.530832 -64.0842)
				(xy 262.707882 -64.0842) (xy 261.869682 -63.246) (xy 261.869174 -63.245492) (xy 231.494076 -63.245492)
				(xy 231.493568 -63.246) (xy 223.877632 -63.246) (xy 214.174832 -53.5432)
			)
		)
	)
	(zone
		(net "P1V05_PCH_STBY")
		(layer "In6.Cu")
		(hatch none 0.5)
		(connect_pads
			(clearance 0.5)
		)
		(min_thickness 0.25)
		(fill yes
			(thermal_gap 0.5)
			(thermal_bridge_width 0.5)
			(island_removal_mode 0)
		)
		(polygon
			(pts
				(xy 392.089386 -109.408468) (xy 391.33653 -110.161324) (xy 390.427718 -110.161324) (xy 390.309608 -110.279434)
				(xy 390.27354 -110.315502) (xy 390.27354 -111.082836) (xy 390.27354 -111.650018) (xy 389.95477 -111.968788)
				(xy 389.95477 -111.98352) (xy 389.458454 -112.479836) (xy 389.451088 -112.47247) (xy 388.493 -113.430558)
				(xy 388.493 -118.78945) (xy 385.11607 -122.16638) (xy 385.115562 -122.169428) (xy 385.1148 -122.174)
				(xy 385.1148 -122.507502) (xy 385.1148 -123.418346) (xy 385.1148 -123.751848)
				(arc
					(start 385.115562 -123.75642)
					(mid 385.121551 -123.821444)
					(end 385.115562 -123.886468)
				)
				(xy 385.1148 -123.89104) (xy 385.1148 -143.69415) (xy 385.1148 -144.077944) (xy 386.130038 -145.093182)
				(xy 386.512816 -145.093182) (xy 388.967472 -145.093182) (xy 388.975854 -145.0848) (xy 395.960854 -145.0848)
				(xy 397.710152 -145.0848) (xy 398.326864 -145.0848) (xy 400.91868 -142.492984) (xy 401.719034 -141.69263)
				(xy 405.068532 -138.343132) (xy 405.068532 -135.222488) (xy 405.068532 -133.030468) (xy 406.190958 -131.908042)
				(xy 406.207468 -131.905756) (xy 411.1752 -126.938024) (xy 411.1752 -124.907548) (xy 411.1752 -124.53112)
				(xy 411.17139 -124.52731)
				(arc
					(start 411.17139 -123.980194)
					(mid 411.174286 -123.966358)
					(end 411.1752 -123.952254)
				)
				(xy 411.1752 -121.8692) (xy 410.2862 -120.9802) (xy 410.2862 -120.953022) (xy 410.245814 -120.912636)
				(xy 410.245814 -116.355114) (xy 402.5011 -108.6104) (xy 402.379434 -108.6104) (xy 402.166836 -108.6104)
				(xy 401.590764 -108.6104) (xy 399.849594 -108.6104) (xy 399.551398 -108.908596) (xy 394.452094 -108.908596)
				(xy 393.919456 -108.375958) (xy 393.80414 -108.260642) (xy 393.80414 -107.41914) (xy 393.80414 -107.122214)
				(xy 393.38885 -106.706924) (xy 392.746738 -106.706924) (xy 392.16076 -107.292902) (xy 392.16076 -109.337094)
			)
		)
	)
	(zone
		(net "P5V_STBY")
		(layer "In6.Cu")
		(hatch none 0.5)
		(connect_pads
			(clearance 0.5)
		)
		(min_thickness 0.25)
		(fill yes
			(thermal_gap 0.5)
			(thermal_bridge_width 0.5)
			(island_removal_mode 0)
		)
		(polygon
			(pts
				(xy 9.906 -25.2476) (xy 8.767826 -24.109426)
				(arc
					(start 8.732012 -24.14016)
					(mid 8.482071 -24.232112)
					(end 8.232902 -24.138128)
				)
				(arc
					(start 8.232902 -24.138128)
					(mid 8.1661 -24.113118)
					(end 8.099298 -24.138128)
				)
				(arc
					(start 8.099298 -24.138128)
					(mid 8.002729 -24.19955)
					(end 7.892288 -24.229568)
				)
				(xy 4.3434 -20.68068) (xy 4.3434 -15.3924) (xy 1.44145 -12.49045) (xy 1.44145 -10.73785) (xy 0.8001 -10.0965)
				(xy -5.2451 -10.0965) (xy -5.5372 -10.3886) (xy -5.5372 -149.246082) (xy -4.990338 -149.792944)
				(xy -3.24104 -149.792944) (xy 4.16814 -149.792944) (xy 4.952492 -150.577296) (xy 6.806946 -152.43175)
				(xy 13.93825 -152.43175) (xy 15.621 -150.749) (xy 15.621 -136.144) (xy 23.749 -128.016) (xy 97.493328 -128.016)
				(xy 98.210624 -128.016) (xy 156.8196 -128.016) (xy 165.5064 -136.7028) (xy 181.4703 -136.7028) (xy 182.67045 -135.50265)
				(xy 182.67045 -134.65175) (xy 189.1792 -128.143) (xy 193.78422 -128.143)
				(arc
					(start 193.792856 -128.139698)
					(mid 193.929 -128.114577)
					(end 194.065144 -128.139698)
				)
				(xy 194.07378 -128.143) (xy 262.716772 -128.143) (xy 263.444228 -128.143)
				(arc
					(start 321.610228 -128.143)
					(mid 321.629233 -128.141207)
					(end 321.647566 -128.135888)
				)
				(arc
					(start 322.471288 -128.135888)
					(mid 322.489497 -128.141181)
					(end 322.508372 -128.143)
				)
				(xy 336.7786 -128.143) (xy 338.3026 -129.667) (xy 338.3026 -158.242) (xy 338.638896 -158.578296)
				(xy 353.6188 -158.578296) (xy 353.6188 -158.542736) (xy 353.86264 -158.298896) (xy 353.86264 -153.52776)
				(xy 355.6762 -151.7142) (xy 357.9876 -151.7142) (xy 358.9782 -150.7236) (xy 362.1024 -150.7236)
				(xy 364.63605 -153.25725) (xy 364.63605 -158.252414) (xy 364.961932 -158.578296) (xy 467.17204 -158.578296)
				(xy 467.2584 -158.491936) (xy 467.2584 -153.8986) (xy 469.7349 -151.4221) (xy 472.1225 -151.4221)
				(xy 472.694 -150.8506) (xy 476.0722 -150.8506) (xy 476.0849 -150.8633) (xy 476.4405 -150.8633)
				(arc
					(start 477.371664 -151.794464)
					(mid 477.38925 -151.808524)
					(end 477.40951 -151.81834)
				)
				(arc
					(start 477.81718 -152.22601)
					(mid 477.827021 -152.246254)
					(end 477.841056 -152.263856)
				)
				(xy 478.4598 -152.8826) (xy 478.4598 -153.7462) (xy 478.917 -154.2034) (xy 478.917 -158.320994)
				(xy 479.174302 -158.578296) (xy 499.584726 -158.578296) (xy 501.413018 -156.750004) (xy 501.413018 -125.874018)
				(xy 501.142 -125.603) (xy 491.744 -125.603) (xy 491.608618 -125.738382) (xy 491.219998 -126.127002)
				(xy 491.11916 -126.22784) (xy 487.930952 -126.22784) (xy 487.920792 -126.238) (xy 487.066336 -126.238)
				(xy 486.791 -126.238) (xy 486.249218 -125.696218) (xy 486.248964 -125.695964) (xy 485.648 -125.095)
				(xy 485.648 -120.396) (xy 487.426 -118.618) (xy 487.426 -118.237) (xy 487.045 -117.856) (xy 484.886 -117.856)
				(xy 484.124 -118.618) (xy 477.476058 -118.618) (xy 477.469708 -118.611396) (xy 477.463104 -118.618)
				(xy 456.114404 -118.618) (xy 455.93 -118.802404) (xy 455.93 -118.954042) (xy 455.93 -120.04421)
				(xy 455.928984 -120.044972) (xy 455.928984 -125.506988) (xy 455.93 -125.508004) (xy 455.93 -126.7714)
				(xy 455.1299 -127.5715) (xy 442.571124 -127.5715) (xy 438.490106 -127.5715) (xy 438.462674 -127.5715)
				(xy 437.144922 -127.5715) (xy 437.143906 -127.570484) (xy 437.088026 -127.570484) (xy 437.032908 -127.515366)
				(xy 435.431692 -125.91415) (xy 426.15485 -125.91415) (xy 426.1358 -125.8951)
				(arc
					(start 425.419266 -125.178566)
					(mid 425.403502 -125.165685)
					(end 425.385484 -125.156214)
				)
				(arc
					(start 425.022772 -124.793502)
					(mid 425.013291 -124.77549)
					(end 425.00042 -124.75972)
				)
				(xy 424.65498 -124.41428) (xy 424.646598 -124.417836) (xy 424.130724 -123.901962) (xy 424.13428 -123.89358)
				(xy 420.8018 -120.5611) (xy 420.8018 -120.46204) (xy 418.773102 -118.433342) (xy 418.76091 -118.433342)
				(xy 418.757862 -118.418102) (xy 418.512752 -118.172992) (xy 418.512752 -114.20729) (xy 418.512752 -109.099096)
				(xy 418.512244 -109.098588) (xy 418.512244 -108.676186) (xy 414.368742 -104.532684) (xy 414.368742 -104.49687)
				(xy 414.368742 -104.278938) (xy 414.368742 -92.725748) (xy 414.364424 -92.721176) (xy 414.364424 -82.107024)
				(xy 411.734 -79.4766) (xy 405.981916 -79.4766) (xy 405.634698 -79.823818) (xy 405.634698 -82.02168)
				(xy 403.93112 -83.725258) (xy 388.911338 -83.725258) (xy 387.62305 -82.43697) (xy 387.62305 -79.46009)
				(xy 381.9652 -73.80224) (xy 381.9652 -73.17486) (xy 381.9652 -72.7964) (xy 381.9652 -67.183) (xy 382.8542 -66.294)
				(xy 399.8214 -66.294) (xy 401.81022 -68.28282) (xy 404.35784 -68.28282) (xy 405.07666 -67.564) (xy 405.07666 -64.03086)
				(xy 405.07666 -63.29426) (xy 400.8882 -59.1058) (xy 393.4714 -51.689) (xy 393.4714 -40.8432) (xy 393.1412 -40.513)
				(xy 363.051852 -40.513) (xy 362.973874 -40.590978) (xy 359.570274 -37.187378) (xy 319.929256 -37.187378)
				(xy 312.920634 -44.196) (xy 311.541668 -45.574966) (xy 309.191406 -47.925228) (xy 309.033926 -47.925228)
				(xy 309.033418 -47.925736) (xy 207.585564 -47.925736) (xy 202.535282 -42.875708) (xy 197.226174 -37.5666)
				(xy 153.359104 -37.5666) (xy 148.049996 -42.875708) (xy 144.027398 -46.898052) (xy 143.971772 -46.898052)
				(xy 143.971518 -46.89856) (xy 103.469948 -46.89856) (xy 101.637084 -48.731424) (xy 29.529024 -48.731424)
				(xy 29.264356 -48.996092) (xy 29.312108 -49.04359) (xy 29.312108 -49.85639) (xy 30.50921 -51.053492)
				(xy 32.66821 -51.053492) (xy 32.711644 -51.09718) (xy 97.603056 -51.09718) (xy 97.606612 -51.093624)
				(xy 97.607374 -51.09718) (xy 102.350062 -51.09718) (xy 102.454202 -50.99304) (xy 103.137208 -50.310034)
				(xy 104.746298 -48.700944) (xy 145.086324 -48.700944) (xy 148.815806 -44.971462) (xy 152.817068 -40.9702)
				(xy 192.0748 -40.9702) (xy 195.9991 -44.8945) (xy 195.9991 -47.5361) (xy 195.0974 -48.4378) (xy 195.0974 -52.451)
				(xy 195.2117 -52.5653) (xy 195.9483 -52.5653) (xy 196.7992 -53.4162) (xy 197.7136 -53.4162) (xy 197.8152 -53.5178)
				(xy 197.8152 -53.9496) (xy 197.993 -54.1274) (xy 198.8058 -54.1274) (xy 199.1106 -53.8226) (xy 199.1106 -51.8414)
				(xy 199.7202 -51.2318) (xy 199.8472 -51.2318) (xy 202.3364 -51.2318) (xy 232.022904 -51.2318) (xy 262.849614 -51.2318)
				(xy 269.362936 -51.2318) (xy 269.36319 -51.231292) (xy 280.381202 -51.231292) (xy 286.386524 -51.231292)
				(xy 286.402272 -51.231292) (xy 297.425364 -51.231292) (xy 304.717704 -51.231292) (xy 311.193688 -51.231292)
				(xy 311.728358 -51.231292) (xy 312.06186 -50.89779) (xy 317.616332 -47.625) (xy 324.32244 -40.918892)
				(xy 353.44227 -40.918892) (xy 354.293424 -41.770046) (xy 354.293424 -61.791088) (xy 348.233492 -67.85102)
				(xy 348.233492 -82.524092) (xy 351.5868 -85.8774) (xy 351.5868 -87.48268) (xy 351.5868 -88.564466)
				(xy 351.5868 -98.131122) (xy 351.583244 -98.134932) (xy 351.583244 -102.878636) (xy 351.5868 -102.882192)
				(xy 351.5868 -103.926132) (xy 355.5492 -107.888532) (xy 355.5492 -108.578396) (xy 355.5492 -108.609892)
				(xy 355.5492 -110.922054) (xy 355.5492 -111.46409) (xy 355.5492 -113.32591) (xy 355.5492 -113.640108)
				(xy 354.840286 -114.349022) (xy 354.738178 -114.45113) (xy 351.292922 -114.45113) (xy 350.227392 -113.3856)
				(xy 350.134682 -113.3856) (xy 346.159582 -113.3856) (xy 345.956636 -113.3856) (xy 344.213434 -113.3856)
				(xy 343.832434 -113.7666) (xy 343.832434 -116.59489) (xy 343.80932 -116.618004) (xy 343.80932 -116.65585)
				(xy 340.425278 -120.039638) (xy 339.941662 -120.523508) (xy 339.903816 -120.523508) (xy 339.574124 -120.8532)
				(xy 181.164738 -120.8532) (xy 177.505868 -124.512324) (xy 177.505868 -125.335538) (xy 177.43043 -125.410722)
				(xy 177.43043 -125.5522) (xy 176.87544 -126.10719) (xy 174.817532 -126.10719) (xy 172.372528 -123.662186)
				(arc
					(start 172.339508 -123.679712)
					(mid 172.109595 -123.720435)
					(end 171.899072 -123.619514)
				)
				(arc
					(start 171.899072 -123.619514)
					(mid 171.833272 -123.591742)
					(end 171.765468 -123.61418)
				)
				(arc
					(start 171.765468 -123.61418)
					(mid 171.437568 -123.688092)
					(end 171.178474 -123.473972)
				)
				(xy 171.148502 -123.444)
				(arc
					(start 163.03625 -123.444)
					(mid 162.8521 -123.49531)
					(end 162.66795 -123.444)
				)
				(xy 160.102042 -123.444)
				(arc
					(start 160.095692 -123.445524)
					(mid 160.00222 -123.457154)
					(end 159.908748 -123.445524)
				)
				(xy 159.902398 -123.444) (xy 159.47263 -123.444)
				(arc
					(start 159.464248 -123.447048)
					(mid 159.3342 -123.469898)
					(end 159.204152 -123.447048)
				)
				(xy 159.19577 -123.444) (xy 17.653 -123.444) (xy 17.1323 -123.9647) (xy 17.0307 -123.9647) (xy 13.618972 -127.376428)
				(xy 13.618972 -127.404114) (xy 13.594334 -127.401066) (xy 7.6454 -133.35) (xy 3.057398 -133.35)
				(arc
					(start 2.165604 -132.458206)
					(mid 2.157726 -132.419735)
					(end 2.135886 -132.387086)
				)
				(arc
					(start 1.456944 -131.708144)
					(mid 1.383713 -131.678378)
					(end 1.311402 -131.710176)
				)
				(xy 1.311402 -117.31879)
				(arc
					(start -0.6096 -115.397788)
					(mid -0.61686 -115.360071)
					(end -0.63754 -115.327684)
				)
				(xy -0.6096 -115.299744) (xy -0.6096 -111.40567) (xy -0.6096 -111.405416) (xy -0.6096 -110.8964)
				(arc
					(start -0.6096 -109.853222)
					(mid -2.390136 -107.791634)
					(end 0.296164 -107.3404)
				)
				(xy 2.9464 -107.3404) (xy 3.3274 -106.9594) (xy 7.5946 -106.9594) (xy 9.9568 -104.5972) (xy 9.9568 -90.4494)
				(xy 8.5344 -89.027) (xy 8.49757 -89.027) (xy 4.5974 -85.12683) (xy 4.5974 -85.041994) (xy 4.5974 -44.3484)
				(xy 5.385308 -43.560492) (xy 9.554464 -39.391336)
				(arc
					(start 9.55294 -39.368476)
					(mid 9.633032 -39.110051)
					(end 9.864344 -38.969696)
				)
				(xy 9.906 -38.962076)
			)
		)
		(polygon
			(pts
				(arc
					(start 391.42543 -152.976834)
					(mid 391.336009 -152.917799)
					(end 391.243312 -152.971754)
				)
				(arc
					(start 391.243312 -152.971754)
					(mid 391.093854 -153.125768)
					(end 390.884918 -153.1747)
				)
				(arc
					(start 390.884918 -153.1747)
					(mid 390.811903 -153.200179)
					(end 390.777984 -153.269696)
				)
				(arc
					(start 390.777984 -153.269696)
					(mid 390.727955 -153.525767)
					(end 390.614408 -153.760678)
				)
				(arc
					(start 390.614408 -153.760678)
					(mid 390.625803 -153.834908)
					(end 390.63168 -153.909776)
				)
				(arc
					(start 390.63168 -153.909776)
					(mid 390.649589 -153.934499)
					(end 390.665462 -153.960576)
				)
				(arc
					(start 390.665462 -153.960576)
					(mid 390.752235 -154.012573)
					(end 390.840976 -153.963878)
				)
				(arc
					(start 390.840976 -153.963878)
					(mid 391.080247 -153.790018)
					(end 391.371836 -153.839418)
				)
				(arc
					(start 391.371836 -153.839418)
					(mid 391.481318 -153.838926)
					(end 391.526776 -153.739342)
				)
				(arc
					(start 391.526776 -153.739342)
					(mid 391.527731 -153.44826)
					(end 391.611104 -153.169366)
				)
				(arc
					(start 391.611104 -153.169366)
					(mid 391.502031 -153.088767)
					(end 391.42543 -152.976834)
				)
			)
		)
		(polygon
			(pts
				(arc
					(start 370.834158 -77.667866)
					(mid 370.745258 -77.615499)
					(end 370.656358 -77.667866)
				)
				(arc
					(start 370.656358 -77.667866)
					(mid 370.597075 -77.746621)
					(end 370.518436 -77.806042)
				)
				(arc
					(start 370.518436 -77.806042)
					(mid 370.466069 -77.89488)
					(end 370.518436 -77.983588)
				)
				(arc
					(start 370.518436 -77.983588)
					(mid 370.701329 -78.294849)
					(end 370.518182 -78.605888)
				)
				(arc
					(start 370.518182 -78.605888)
					(mid 370.465815 -78.694788)
					(end 370.518182 -78.783688)
				)
				(arc
					(start 370.518182 -78.783688)
					(mid 370.596936 -78.84311)
					(end 370.656358 -78.921864)
				)
				(arc
					(start 370.656358 -78.921864)
					(mid 370.745258 -78.974231)
					(end 370.834158 -78.921864)
				)
				(arc
					(start 370.834158 -78.921864)
					(mid 371.145197 -78.73884)
					(end 371.456458 -78.92161)
				)
				(arc
					(start 371.456458 -78.92161)
					(mid 371.545296 -78.973977)
					(end 371.634004 -78.92161)
				)
				(arc
					(start 371.634004 -78.92161)
					(mid 371.693338 -78.843022)
					(end 371.771926 -78.783688)
				)
				(arc
					(start 371.771926 -78.783688)
					(mid 371.824071 -78.69498)
					(end 371.771926 -78.606142)
				)
				(arc
					(start 371.771926 -78.606142)
					(mid 371.588902 -78.29493)
					(end 371.771926 -77.983588)
				)
				(arc
					(start 371.771926 -77.983588)
					(mid 371.823941 -77.89488)
					(end 371.771926 -77.806042)
				)
				(arc
					(start 371.771926 -77.806042)
					(mid 371.693338 -77.746708)
					(end 371.634004 -77.66812)
				)
				(arc
					(start 371.634004 -77.66812)
					(mid 371.545296 -77.615975)
					(end 371.456458 -77.66812)
				)
				(arc
					(start 371.456458 -77.66812)
					(mid 371.145197 -77.851013)
					(end 370.834158 -77.667866)
				)
			)
		)
		(polygon
			(pts
				(arc
					(start 368.434112 -77.667866)
					(mid 368.345212 -77.615499)
					(end 368.256312 -77.667866)
				)
				(arc
					(start 368.256312 -77.667866)
					(mid 368.197029 -77.746621)
					(end 368.11839 -77.806042)
				)
				(arc
					(start 368.11839 -77.806042)
					(mid 368.066023 -77.89488)
					(end 368.11839 -77.983588)
				)
				(arc
					(start 368.11839 -77.983588)
					(mid 368.301283 -78.294849)
					(end 368.118136 -78.605888)
				)
				(arc
					(start 368.118136 -78.605888)
					(mid 368.065769 -78.694788)
					(end 368.118136 -78.783688)
				)
				(arc
					(start 368.118136 -78.783688)
					(mid 368.19689 -78.84311)
					(end 368.256312 -78.921864)
				)
				(arc
					(start 368.256312 -78.921864)
					(mid 368.345212 -78.974231)
					(end 368.434112 -78.921864)
				)
				(arc
					(start 368.434112 -78.921864)
					(mid 368.745151 -78.73884)
					(end 369.056412 -78.92161)
				)
				(arc
					(start 369.056412 -78.92161)
					(mid 369.14525 -78.973977)
					(end 369.233958 -78.92161)
				)
				(arc
					(start 369.233958 -78.92161)
					(mid 369.293431 -78.843023)
					(end 369.372134 -78.783688)
				)
				(arc
					(start 369.372134 -78.783688)
					(mid 369.424501 -78.694788)
					(end 369.372134 -78.605888)
				)
				(arc
					(start 369.372134 -78.605888)
					(mid 369.18911 -78.294849)
					(end 369.37188 -77.983588)
				)
				(arc
					(start 369.37188 -77.983588)
					(mid 369.424025 -77.89488)
					(end 369.37188 -77.806042)
				)
				(arc
					(start 369.37188 -77.806042)
					(mid 369.293292 -77.746708)
					(end 369.233958 -77.66812)
				)
				(arc
					(start 369.233958 -77.66812)
					(mid 369.14525 -77.615975)
					(end 369.056412 -77.66812)
				)
				(arc
					(start 369.056412 -77.66812)
					(mid 368.745151 -77.851013)
					(end 368.434112 -77.667866)
				)
			)
		)
		(polygon
			(pts
				(arc
					(start 375.633742 -70.468236)
					(mid 375.544842 -70.415869)
					(end 375.455942 -70.468236)
				)
				(arc
					(start 375.455942 -70.468236)
					(mid 375.396659 -70.546991)
					(end 375.31802 -70.606412)
				)
				(arc
					(start 375.31802 -70.606412)
					(mid 375.265653 -70.69525)
					(end 375.31802 -70.783958)
				)
				(arc
					(start 375.31802 -70.783958)
					(mid 375.500913 -71.095108)
					(end 375.31802 -71.406258)
				)
				(arc
					(start 375.31802 -71.406258)
					(mid 375.265783 -71.495096)
					(end 375.31802 -71.583804)
				)
				(arc
					(start 375.31802 -71.583804)
					(mid 375.396774 -71.643226)
					(end 375.456196 -71.72198)
				)
				(arc
					(start 375.456196 -71.72198)
					(mid 375.545034 -71.774217)
					(end 375.633742 -71.72198)
				)
				(arc
					(start 375.633742 -71.72198)
					(mid 375.944892 -71.539087)
					(end 376.256042 -71.72198)
				)
				(arc
					(start 376.256042 -71.72198)
					(mid 376.34488 -71.774347)
					(end 376.433588 -71.72198)
				)
				(arc
					(start 376.433588 -71.72198)
					(mid 376.493061 -71.643393)
					(end 376.571764 -71.584058)
				)
				(arc
					(start 376.571764 -71.584058)
					(mid 376.624131 -71.495158)
					(end 376.571764 -71.406258)
				)
				(arc
					(start 376.571764 -71.406258)
					(mid 376.38874 -71.095219)
					(end 376.57151 -70.783958)
				)
				(arc
					(start 376.57151 -70.783958)
					(mid 376.623655 -70.69525)
					(end 376.57151 -70.606412)
				)
				(arc
					(start 376.57151 -70.606412)
					(mid 376.492922 -70.547078)
					(end 376.433588 -70.46849)
				)
				(arc
					(start 376.433588 -70.46849)
					(mid 376.34488 -70.416345)
					(end 376.256042 -70.46849)
				)
				(arc
					(start 376.256042 -70.46849)
					(mid 375.944781 -70.651383)
					(end 375.633742 -70.468236)
				)
			)
		)
		(polygon
			(pts
				(arc
					(start 389.8265 -106.605324)
					(mid 389.7376 -106.552957)
					(end 389.6487 -106.605324)
				)
				(arc
					(start 389.6487 -106.605324)
					(mid 389.33755 -106.788348)
					(end 389.0264 -106.605324)
				)
				(arc
					(start 389.0264 -106.605324)
					(mid 388.895211 -106.562768)
					(end 388.84225 -106.69016)
				)
				(arc
					(start 388.84225 -106.69016)
					(mid 388.861007 -106.764194)
					(end 388.863586 -106.840528)
				)
				(arc
					(start 388.863586 -106.840528)
					(mid 388.890336 -106.917173)
					(end 388.964678 -106.949748)
				)
				(arc
					(start 391.310622 -106.949748)
					(mid 391.384941 -106.917151)
					(end 391.411714 -106.840528)
				)
				(arc
					(start 391.411714 -106.840528)
					(mid 391.41425 -106.764188)
					(end 391.43305 -106.69016)
				)
				(arc
					(start 391.43305 -106.69016)
					(mid 391.380298 -106.562588)
					(end 391.2489 -106.605324)
				)
				(arc
					(start 391.2489 -106.605324)
					(mid 390.93775 -106.788348)
					(end 390.6266 -106.605324)
				)
				(arc
					(start 390.6266 -106.605324)
					(mid 390.5377 -106.552957)
					(end 390.4488 -106.605324)
				)
				(arc
					(start 390.4488 -106.605324)
					(mid 390.13765 -106.788348)
					(end 389.8265 -106.605324)
				)
			)
		)
	)
	(zone
		(net "P1V2_AUX_BMC")
		(layer "In6.Cu")
		(hatch none 0.5)
		(connect_pads
			(clearance 0.5)
		)
		(min_thickness 0.25)
		(fill yes
			(thermal_gap 0.5)
			(thermal_bridge_width 0.5)
			(island_removal_mode 0)
		)
		(polygon
			(pts
				(xy 418.9984 -30.5816) (xy 418.9984 -31.75) (xy 418.9984 -31.8262) (xy 418.9984 -33.274) (xy 418.9984 -36.703)
				(xy 419.1889 -36.8935) (xy 425.7421 -36.8935) (xy 425.765722 -36.8935) (xy 432.376326 -43.504104)
				(xy 434.820314 -43.504104) (xy 434.972714 -43.656504) (xy 436.37581 -45.0596) (xy 437.251094 -45.0596)
				(xy 438.084214 -45.0596) (xy 449.3514 -45.0596) (xy 454.7616 -39.6494) (xy 454.7616 -28.6893) (xy 454.1901 -28.1178)
				(xy 452.4502 -28.1178) (xy 449.28028 -28.1178) (xy 447.79184 -26.62936) (xy 447.79184 -25.174194)
				(xy 447.79184 -24.47544) (xy 447.2686 -23.9522) (xy 443.84976 -23.9522) (xy 440.8424 -23.9522) (xy 436.23484 -23.9522)
				(xy 435.375304 -23.9522) (xy 420.228522 -23.9522) (xy 419.559232 -24.62149) (xy 419.559232 -30.020768)
				(xy 419.3286 -30.2514)
			)
		)
	)
	(zone
		(net "PVCCIOMCP_CPU0")
		(layer "In6.Cu")
		(hatch none 0.5)
		(connect_pads
			(clearance 0.5)
		)
		(min_thickness 0.25)
		(fill yes
			(thermal_gap 0.5)
			(thermal_bridge_width 0.5)
			(island_removal_mode 0)
		)
		(polygon
			(pts
				(xy 300.509432 -73.927208) (xy 298.642786 -75.793854) (xy 298.642786 -75.804014) (xy 297.4848 -76.962)
				(xy 295.0464 -76.962) (xy 294.4876 -76.4032) (xy 293.8526 -76.4032) (xy 293.37 -75.9206) (xy 292.989 -75.9206)
				(xy 292.6842 -76.2254) (xy 292.6842 -79.3496) (xy 294.005 -80.6704) (xy 304.673 -80.6704) (xy 309.9562 -85.9536)
				(xy 334.858106 -85.9536)
				(arc
					(start 335.252568 -86.348062)
					(mid 335.261655 -86.364547)
					(end 335.27365 -86.37905)
				)
				(xy 340.0044 -91.1098) (xy 340.0044 -107.0737) (xy 343.640664 -110.709964) (xy 343.640664 -110.719362)
				(xy 344.5002 -111.578898) (xy 344.509598 -111.578898) (xy 346.1004 -113.1697) (xy 350.2787 -113.1697)
				(xy 350.2914 -113.1824) (xy 350.52 -113.1824) (xy 350.668082 -113.330482)
				(arc
					(start 350.677734 -113.334546)
					(mid 350.797106 -113.413294)
					(end 350.875854 -113.532666)
				)
				(xy 350.879918 -113.542318) (xy 351.536 -114.1984) (xy 354.5078 -114.1984) (xy 355.1428 -113.5634)
				(xy 355.1428 -107.9754) (xy 354.495862 -107.328462)
				(arc
					(start 354.486464 -107.324652)
					(mid 354.369271 -107.246773)
					(end 354.291392 -107.12958)
				)
				(xy 354.287582 -107.120182) (xy 351.1804 -104.013) (xy 351.1804 -103.43896) (xy 351.190052 -103.429308)
				(xy 351.190052 -99.024186) (xy 351.1804 -99.014534) (xy 351.1804 -85.725) (xy 347.8784 -82.423)
				(xy 347.8784 -74.79538) (xy 347.02242 -73.9394) (xy 306.645818 -73.9394) (xy 306.633626 -73.927208)
			)
		)
	)
	(zone
		(net "PVSA_CPU0")
		(layer "In6.Cu")
		(hatch none 0.5)
		(connect_pads
			(clearance 0.5)
		)
		(min_thickness 0.25)
		(fill yes
			(thermal_gap 0.5)
			(thermal_bridge_width 0.5)
			(island_removal_mode 0)
		)
		(polygon
			(pts
				(xy 246.407432 -79.3242) (xy 246.251222 -79.48041)
				(arc
					(start 246.247158 -79.490824)
					(mid 246.165915 -79.616591)
					(end 246.040148 -79.697834)
				)
				(xy 246.029734 -79.701898) (xy 245.011956 -80.719676) (xy 244.892576 -80.839056) (xy 237.928658 -80.839056)
				(xy 237.806738 -80.960976) (xy 234.631738 -84.135976) (xy 234.418124 -84.135976) (xy 234.415838 -84.138008)
				(xy 231.410764 -84.138008) (xy 231.398572 -84.1502) (xy 228.110288 -84.1502) (xy 219.499688 -92.7608)
				(xy 209.323432 -92.7608) (xy 209.316066 -92.768166) (xy 208.628234 -92.768166) (xy 208.5086 -92.8878)
				(xy 208.0133 -93.3831) (xy 208.0133 -102.5779) (xy 208.715102 -103.279702) (xy 209.287364 -103.279702)
				(xy 221.74073 -103.279702) (xy 232.633012 -92.38742) (xy 235.020104 -92.38742) (xy 235.205524 -92.202)
				(xy 239.134904 -88.27262) (xy 245.383812 -88.27262) (xy 245.518432 -88.138) (xy 246.477028 -87.179404)
				(xy 247.158002 -86.49843) (xy 247.282208 -86.374224) (xy 247.468898 -86.187534) (xy 250.954794 -86.187534)
				(xy 251.3076 -85.834728) (xy 251.3076 -85.658452) (xy 251.3076 -82.60461) (xy 251.3076 -81.265268)
				(xy 250.607068 -80.564482) (xy 250.607068 -80.562196) (xy 250.522232 -80.47736) (xy 250.522232 -80.337914)
				(xy 250.522232 -79.553816) (xy 250.292616 -79.3242) (xy 250.28779 -79.319374) (xy 246.42191 -79.319374)
				(xy 246.412258 -79.319374)
			)
		)
	)
	(zone
		(net "P3V3")
		(layer "In6.Cu")
		(hatch none 0.5)
		(connect_pads
			(clearance 0.5)
		)
		(min_thickness 0.25)
		(fill yes
			(thermal_gap 0.5)
			(thermal_bridge_width 0.5)
			(island_removal_mode 0)
		)
		(polygon
			(pts
				(xy 338.328 5.5118) (xy 338.2518 5.4356) (xy 338.2518 -0.635) (xy 338.2264 -0.6604) (xy 338.2264 -8.3566)
				(xy 336.0928 -10.4902) (xy 336.0928 -16.717518) (xy 336.078322 -16.731996) (xy 336.078322 -19.242278)
				(xy 330.8858 -24.4348) (xy 329.9968 -24.4348) (xy 329.311 -25.1206) (xy 327.3552 -25.1206) (xy 326.4408 -24.2062)
				(arc
					(start 263.090406 -24.2062)
					(mid 263.072468 -24.207796)
					(end 263.0551 -24.21255)
				)
				(arc
					(start 262.216646 -24.21255)
					(mid 262.199275 -24.207813)
					(end 262.18134 -24.2062)
				)
				(xy 194.618864 -24.2062) (xy 194.263264 -24.5618) (xy 193.1924 -24.5618) (xy 192.8876 -24.257) (xy 192.8876 -24.256492)
				(xy 192.836292 -24.205184) (xy 192.836292 -23.51659) (xy 192.83934 -23.513542) (xy 192.83934 -23.44166)
				(xy 193.191892 -23.089108) (xy 193.191892 -8.203692)
				(arc
					(start 192.309496 -7.321296)
					(mid 192.293379 -7.30823)
					(end 192.274952 -7.29869)
				)
				(xy 192.274952 -7.286752) (xy 188.849 -3.8608) (xy 186.7662 -3.8608) (xy 185.547 -2.6416) (xy 185.547 4.962144)
				(xy 185.073544 5.4356)
				(arc
					(start 180.781706 5.4356)
					(mid 180.759027 5.433037)
					(end 180.73751 5.42544)
				)
				(xy 180.72735 5.4356) (xy 179.9082 5.4356) (xy 179.705 5.2324) (xy 179.705 0.09779) (xy 177.34661 -2.2606)
				(xy 170.10253 -2.2606) (xy 169.7736 -2.58953) (xy 169.7736 -3.4036) (xy 168.1226 -5.0546) (xy 168.1226 -6.223)
				(xy 167.66794 -6.67766) (xy 167.66794 -8.479536) (xy 167.853106 -8.664702) (xy 169.50944 -8.664702)
				(xy 169.817542 -8.3566) (xy 176.3014 -8.3566) (xy 178.562 -6.096) (xy 180.7972 -6.096) (xy 187.1218 -12.4206)
				(xy 187.1218 -22.297136) (xy 187.26023 -22.435566) (xy 187.341256 -22.516338) (xy 193.39941 -28.574492)
				(xy 229.691692 -28.574492) (xy 231.896412 -30.779212) (xy 231.935782 -30.779212) (xy 233.918252 -32.761682)
				(xy 318.845946 -32.761682) (xy 320.828416 -30.779212) (xy 335.853024 -30.779212) (xy 342.392 -24.239982)
				(xy 342.392 -3.683) (xy 344.3732 -1.7018) (xy 344.978736 -1.7018) (xy 345.05519 -1.625092)
				(arc
					(start 347.415612 -1.625092)
					(mid 347.599 -1.574248)
					(end 347.782388 -1.625092)
				)
				(arc
					(start 348.030546 -1.625092)
					(mid 348.2594 -1.548841)
					(end 348.488254 -1.625092)
				)
				(arc
					(start 348.690946 -1.625092)
					(mid 348.9198 -1.548841)
					(end 349.148654 -1.625092)
				)
				(arc
					(start 349.396812 -1.625092)
					(mid 349.5802 -1.574248)
					(end 349.763588 -1.625092)
				)
				(arc
					(start 350.02851 -1.625092)
					(mid 350.047779 -1.623199)
					(end 350.066356 -1.617726)
				)
				(arc
					(start 350.922844 -1.617726)
					(mid 350.941412 -1.623243)
					(end 350.96069 -1.625092)
				)
				(arc
					(start 351.353374 -1.625092)
					(mid 351.385503 -1.619878)
					(end 351.414334 -1.604772)
				)
				(xy 351.565972 -1.604772) (xy 353.4664 -3.5052) (xy 353.5172 -3.5052) (xy 354.838 -4.826) (xy 382.9304 -4.826)
				(xy 386.969 -8.8646) (xy 386.969 -19.2532) (xy 387.2992 -19.5834) (xy 388.4676 -19.5834) (xy 389.001 -20.1168)
				(xy 389.001 -21.0058) (xy 388.2644 -21.7424) (xy 388.2644 -27.9908) (xy 388.5692 -28.2956) (xy 392.176 -28.2956)
				(xy 392.3792 -28.0924) (xy 392.3792 -26.0096) (xy 398.653 -19.7358) (xy 398.653 -5.5372) (xy 399.3642 -4.826)
				(xy 418.6936 -4.826) (xy 419.7858 -5.9182) (xy 419.7858 -23.238206) (xy 420.20617 -23.658576) (xy 435.261004 -23.658576)
				(xy 447.338196 -23.658576) (xy 448.085972 -24.406352) (xy 448.085972 -26.545032) (xy 449.396358 -27.855418)
				(xy 450.172582 -27.855418) (xy 450.181726 -27.846274) (xy 454.312274 -27.846274) (xy 455.041 -28.575)
				(xy 455.041 -39.243) (xy 455.041 -40.016684) (xy 455.055732 -40.031416) (xy 449.72732 -45.359828)
				(xy 438.367932 -45.359828) (xy 438.151778 -45.575982) (xy 438.151778 -48.895) (xy 438.151778 -51.919378)
				(xy 444.9064 -58.674) (xy 444.9064 -60.31103) (xy 443.29731 -61.92012) (xy 441.275724 -61.92012)
				(xy 441.217558 -61.861954) (xy 438.202578 -58.846974) (xy 434.634132 -58.846974) (xy 432.563778 -56.77662)
				(xy 430.782476 -56.77662) (xy 430.270412 -57.288684) (xy 423.768266 -57.288684) (xy 421.028114 -60.028836)
				(xy 421.028114 -105.682542) (xy 421.85082 -106.505248) (xy 421.85082 -115.843558) (xy 423.530014 -117.522752)
				(xy 423.530014 -117.523006) (xy 427.271434 -121.264172) (xy 454.378568 -121.264172) (xy 455.015346 -120.627394)
				(xy 455.015346 -118.648734) (xy 455.55408 -118.11) (xy 483.87 -118.11) (xy 484.505 -117.475) (xy 487.172 -117.475)
				(xy 487.807 -118.11) (xy 487.807 -118.745) (xy 486.283 -120.269) (xy 486.283 -125.222) (xy 486.918 -125.857)
				(xy 490.982 -125.857) (xy 491.617 -125.222)
				(arc
					(start 499.797324 -125.222)
					(mid 499.815528 -125.22031)
					(end 499.833138 -125.215396)
				)
				(arc
					(start 500.65178 -125.215396)
					(mid 500.669513 -125.220345)
					(end 500.687848 -125.222)
				)
				(xy 501.396 -125.222) (xy 501.542812 -125.075188)
				(arc
					(start 501.542812 -112.203992)
					(mid 501.103636 -111.000833)
					(end 499.99265 -110.363508)
				)
				(xy 488.28706 -110.363508) (xy 488.274868 -110.351316) (xy 427.597316 -110.351316) (xy 426.7327 -109.4867)
				(xy 426.7327 -68.2752) (xy 427.635162 -67.372738) (xy 475.423738 -67.372738) (xy 475.588584 -67.207892)
				(xy 475.588584 -61.671708) (xy 478.941384 -58.318908) (xy 488.178856 -58.318908) (xy 490.907832 -55.589932)
				(xy 490.907832 -38.386004) (xy 476.713296 -24.191468) (xy 474.77426 -24.191468) (xy 471.095324 -20.512532)
				(xy 471.095324 -19.341084) (xy 471.091768 -19.337528) (xy 471.091768 -16.880078) (xy 467.23681 -13.02512)
				(xy 467.23681 -5.1816) (xy 467.784688 -4.633722) (xy 467.929722 -4.488688) (xy 483.35692 -4.488688)
				(xy 483.39248 -4.453128)
				(arc
					(start 483.39248 0.500126)
					(mid 483.428074 0.758778)
					(end 483.53218 0.99822)
				)
				(xy 483.3366 1.1938) (xy 483.3366 2.8702) (xy 483.9462 3.4798) (xy 487.03738 3.4798) (xy 487.305096 3.747516)
				(xy 487.305096 5.287264) (xy 487.08056 5.5118) (xy 479.4758 5.5118) (xy 479.4758 0.3048) (xy 476.6564 -2.5146)
				(xy 472.567 -2.5146) (xy 471.7542 -1.7018) (xy 469.8238 -1.7018)
				(arc
					(start 467.93277 0.18923)
					(mid 467.905928 0.208407)
					(end 467.87435 0.217932)
				)
				(xy 467.438994 0.653288) (xy 467.438994 5.407406) (xy 467.3346 5.5118) (xy 364.9218 5.5118) (xy 364.9218 0.3556)
				(xy 363.0676 -1.4986) (xy 362.6866 -1.4986) (xy 362.1024 -2.0828) (xy 361.569 -2.0828) (xy 361.4166 -2.2352)
				(xy 359.4354 -2.2352) (xy 359.283 -2.0828) (xy 358.6734 -2.0828) (xy 357.9622 -1.3716) (xy 355.6762 -1.3716)
				(xy 353.6188 0.6858) (xy 353.6188 5.5118)
			)
		)
		(polygon
			(pts
				(arc
					(start 483.446836 0.819404)
					(mid 483.406802 0.927079)
					(end 483.291896 0.928624)
				)
				(arc
					(start 483.291896 0.928624)
					(mid 482.908809 0.794446)
					(end 482.50856 0.862076)
				)
				(arc
					(start 482.50856 0.862076)
					(mid 482.403723 0.848646)
					(end 482.36759 0.7493)
				)
				(arc
					(start 482.36759 0.7493)
					(mid 482.383385 0.589788)
					(end 482.36759 0.430276)
				)
				(arc
					(start 482.36759 0.430276)
					(mid 482.403701 0.330903)
					(end 482.50856 0.3175)
				)
				(arc
					(start 482.50856 0.3175)
					(mid 482.87888 0.387183)
					(end 483.240842 0.282448)
				)
				(arc
					(start 483.240842 0.282448)
					(mid 483.337582 0.280641)
					(end 483.391972 0.36068)
				)
				(arc
					(start 483.391972 0.500126)
					(mid 483.40581 0.662101)
					(end 483.446836 0.819404)
				)
			)
		)
		(polygon
			(pts
				(arc
					(start 483.391972 -3.211068)
					(mid 483.337595 -3.131003)
					(end 483.240842 -3.132836)
				)
				(arc
					(start 483.240842 -3.132836)
					(mid 482.905576 -3.235923)
					(end 482.55809 -3.188208)
				)
				(arc
					(start 482.55809 -3.188208)
					(mid 482.458149 -3.205091)
					(end 482.422708 -3.299968)
				)
				(arc
					(start 482.422708 -3.299968)
					(mid 482.433816 -3.414674)
					(end 482.429566 -3.529838)
				)
				(arc
					(start 482.429566 -3.529838)
					(mid 482.467241 -3.619664)
					(end 482.56317 -3.636518)
				)
				(arc
					(start 482.56317 -3.636518)
					(mid 482.908899 -3.593819)
					(end 483.243382 -3.691128)
				)
				(arc
					(start 483.243382 -3.691128)
					(mid 483.338946 -3.690826)
					(end 483.391972 -3.611372)
				)
			)
		)
		(polygon
			(pts
				(arc
					(start 483.391972 -1.1811)
					(mid 483.337595 -1.101035)
					(end 483.240842 -1.102868)
				)
				(arc
					(start 483.240842 -1.102868)
					(mid 482.878878 -1.207567)
					(end 482.50856 -1.13792)
				)
				(arc
					(start 482.50856 -1.13792)
					(mid 482.403723 -1.15135)
					(end 482.36759 -1.250696)
				)
				(arc
					(start 482.36759 -1.250696)
					(mid 482.383385 -1.410208)
					(end 482.36759 -1.56972)
				)
				(arc
					(start 482.36759 -1.56972)
					(mid 482.403701 -1.669093)
					(end 482.50856 -1.682496)
				)
				(arc
					(start 482.50856 -1.682496)
					(mid 482.87888 -1.612813)
					(end 483.240842 -1.717548)
				)
				(arc
					(start 483.240842 -1.717548)
					(mid 483.337582 -1.719355)
					(end 483.391972 -1.639316)
				)
			)
		)
	)
	(zone
		(net "PVNN_PCH_STBY")
		(layer "In6.Cu")
		(hatch none 0.5)
		(connect_pads
			(clearance 0.5)
		)
		(min_thickness 0.25)
		(fill yes
			(thermal_gap 0.5)
			(thermal_bridge_width 0.5)
			(island_removal_mode 0)
		)
		(polygon
			(pts
				(xy 375.130314 -104.859328) (xy 374.020842 -105.9688) (xy 371.312948 -105.9688) (xy 370.595652 -105.9688)
				(xy 369.57 -105.9688) (xy 366.830356 -108.708444) (xy 366.830356 -108.721906) (xy 366.72647 -108.825792)
				(xy 366.72647 -142.881096) (xy 366.72647 -143.474186) (xy 366.937036 -143.684752) (xy 367.117884 -143.8656)
				(xy 367.24209 -143.989806) (xy 384.79984 -143.989806) (xy 384.856736 -143.93291) (xy 384.856736 -143.79067)
				(xy 384.856736 -143.670528) (xy 384.856736 -143.497808) (xy 384.856736 -143.278352) (xy 384.856736 -135.12419)
				(xy 384.856736 -134.158736) (xy 384.856736 -124.279152) (xy 384.856736 -121.914412) (xy 388.210806 -118.560342)
				(xy 388.210806 -113.364772) (xy 388.210806 -113.352326) (xy 389.992108 -111.571024) (xy 389.992108 -111.477806)
				(xy 389.992108 -110.269782) (xy 390.019032 -110.242604) (xy 390.019032 -110.210092) (xy 390.322308 -109.906816)
				(xy 391.23112 -109.906816) (xy 391.8585 -109.279436) (xy 391.903458 -109.234478) (xy 391.903458 -107.3658)
				(xy 391.74166 -107.204002) (xy 391.414508 -107.204002) (xy 386.29844 -107.204002) (xy 385.196842 -106.102404)
				(xy 385.194556 -106.104182) (xy 384.689096 -105.598722) (xy 384.099816 -105.009442) (xy 383.949702 -104.859328)
				(xy 381.001524 -104.859328)
			)
		)
	)
	(zone
		(net "PVDDQ_GHJ")
		(layer "In6.Cu")
		(hatch none 0.5)
		(connect_pads
			(clearance 0.5)
		)
		(min_thickness 0.25)
		(fill yes
			(thermal_gap 0.5)
			(thermal_bridge_width 0.5)
			(island_removal_mode 0)
		)
		(polygon
			(pts
				(xy 17.3736 5.461) (xy 16.5989 4.6863) (xy 16.5989 -1.709166) (xy 16.5989 -2.680716) (xy 16.5989 -5.8801)
				(xy 14.6304 -7.8486) (xy 14.6304 -19.939) (xy 15.6464 -20.955) (xy 19.939 -20.955) (xy 21.407628 -22.423628)
				(arc
					(start 21.417788 -22.427692)
					(mid 21.551583 -22.514369)
					(end 21.63826 -22.648164)
				)
				(xy 21.642324 -22.658324) (xy 23.241 -24.257) (xy 156.3624 -24.257) (xy 157.2006 -23.4188)
				(arc
					(start 157.2006 -22.711664)
					(mid 157.147269 -22.524212)
					(end 157.2006 -22.33676)
				)
				(xy 157.2006 -17.862296)
				(arc
					(start 157.197044 -17.853406)
					(mid 157.172556 -17.723612)
					(end 157.197044 -17.593818)
				)
				(xy 157.2006 -17.584928)
				(arc
					(start 157.2006 -13.1191)
					(mid 157.141737 -12.923012)
					(end 157.2006 -12.726924)
				)
				(xy 157.2006 -12.319) (xy 160.653476 -8.866124) (xy 160.9598 -8.5598) (xy 163.603432 -8.5598) (xy 166.878 -8.5598)
				(xy 167.132 -8.3058) (xy 167.132 -8.185658)
				(arc
					(start 167.12565 -8.174228)
					(mid 167.080735 -7.994683)
					(end 167.132 -7.81685)
				)
				(xy 167.132 -6.7056) (xy 167.767 -6.0706) (xy 167.767 -4.8768) (xy 169.4942 -3.1496) (xy 169.4942 -0.3302)
				(xy 169.4942 -0.10922) (xy 168.657524 0.727456) (xy 168.657524 5.256276) (xy 168.5417 5.3721) (xy 168.4528 5.461)
			)
		)
	)
	(zone
		(net "VR_FET_SW_P12V_STBY_PVCCIN_CPU0")
		(layer "In6.Cu")
		(hatch none 0.5)
		(connect_pads
			(clearance 0.5)
		)
		(min_thickness 0.25)
		(fill yes
			(thermal_gap 0.5)
			(thermal_bridge_width 0.5)
			(island_removal_mode 0)
		)
		(polygon
			(pts
				(xy 178.435 -50.546) (xy 177.7238 -51.2572) (xy 177.7238 -57.212484) (xy 177.7238 -57.900316) (xy 177.7238 -59.5376)
				(xy 178.1302 -59.944) (xy 181.962552 -59.944) (xy 182.730648 -59.944) (xy 185.6232 -59.944) (xy 188.5696 -62.8904)
				(xy 188.5696 -69.583554) (xy 188.5696 -73.55078) (xy 188.569092 -73.551288) (xy 188.5696 -73.551796)
				(xy 188.5696 -77.985112) (xy 188.5696 -78.88097) (xy 188.5696 -101.2952) (xy 189.484 -102.2096)
				(xy 197.9422 -102.2096) (xy 198.415656 -102.2096) (xy 199.121014 -101.504242) (xy 199.121014 -55.661814)
				(xy 198.2724 -54.8132) (xy 197.79234 -54.33314) (xy 196.70268 -54.33314) (xy 195.44538 -53.07584)
				(xy 184.39384 -53.07584) (xy 184.1754 -52.8574) (xy 181.864 -50.546)
			)
		)
	)
	(zone
		(net "P3V3")
		(layer "In6.Cu")
		(hatch none 0.5)
		(connect_pads
			(clearance 0.5)
		)
		(min_thickness 0.25)
		(fill yes
			(thermal_gap 0.5)
			(thermal_bridge_width 0.5)
			(island_removal_mode 0)
		)
		(polygon
			(pts
				(xy 363.601 -63.119) (xy 364.9726 -63.119) (xy 365.3282 -62.7634) (xy 365.3282 -48.2854) (xy 364.9726 -47.9298)
				(xy 363.3724 -47.9298) (xy 363.1438 -48.1584) (xy 363.1438 -53.6702) (xy 363.1438 -62.6618)
			)
		)
	)
	(zone
		(net "PVDDQ_DEF")
		(layer "In6.Cu")
		(hatch none 0.5)
		(connect_pads
			(clearance 0.5)
		)
		(min_thickness 0.25)
		(fill yes
			(thermal_gap 0.5)
			(thermal_bridge_width 0.5)
			(island_removal_mode 0)
		)
		(polygon
			(pts
				(xy 192.4558 -142.6464) (xy 182.88 -142.6464) (xy 178.7906 -146.7358) (xy 177.6222 -146.7358) (xy 177.2666 -147.0914)
				(xy 177.2666 -150.5966) (xy 180.1368 -153.4668) (xy 180.1368 -154.3304) (xy 180.1368 -157.2514)
				(xy 181.483 -158.5976) (xy 181.506622 -158.621222) (xy 185.726578 -158.621222) (xy 185.728356 -158.623)
				(xy 336.804 -158.623) (xy 337.3374 -158.0896) (xy 337.3374 -130.5306) (xy 335.7626 -128.9558) (xy 327.616312 -128.9558)
				(xy 326.383396 -128.9558)
				(arc
					(start 325.374254 -128.9558)
					(mid 325.12 -129.052862)
					(end 324.865746 -128.9558)
				)
				(xy 264.079482 -128.9558) (xy 263.155938 -128.9558)
				(arc
					(start 263.151112 -128.960626)
					(mid 263.135931 -128.957023)
					(end 263.120378 -128.9558)
				)
				(arc
					(start 262.988552 -128.9558)
					(mid 262.6868 -129.122866)
					(end 262.385048 -128.9558)
				)
				(xy 194.6148 -128.9558) (xy 193.8782 -128.9558) (xy 193.1416 -129.6924) (xy 193.1416 -141.9606)
			)
		)
	)
	(zone
		(net "P3V3_STBY")
		(layer "In6.Cu")
		(hatch none 0.5)
		(connect_pads
			(clearance 0.5)
		)
		(min_thickness 0.25)
		(fill yes
			(thermal_gap 0.5)
			(thermal_bridge_width 0.5)
			(island_removal_mode 0)
		)
		(polygon
			(pts
				(xy -4.191 5.207) (xy -5.461 3.937)
				(arc
					(start -5.461 -6.189726)
					(mid -5.457491 -6.216453)
					(end -5.44703 -6.241288)
				)
				(arc
					(start -5.44703 -8.490966)
					(mid -5.457405 -8.515693)
					(end -5.461 -8.542274)
				)
				(xy -5.461 -9.503918) (xy -4.982718 -9.9822) (xy 0.81534 -9.9822) (xy 1.5748 -10.74166) (xy 1.5748 -12.36726)
				(xy 4.5339 -15.32636) (xy 4.5339 -20.50034) (xy 7.42696 -23.3934) (xy 7.433564 -23.3934) (xy 7.91972 -23.879556)
				(xy 8.897874 -23.879556) (xy 10.160508 -25.14219) (xy 10.160508 -29.39415) (xy 10.380218 -29.61386)
				(xy 16.764508 -29.61386) (xy 16.787114 -29.591) (xy 31.22168 -29.591) (xy 33.401 -31.77032) (xy 33.401 -40.85336)
				(xy 31.43504 -42.81932) (xy 20.173696 -42.81932) (xy 18.840196 -44.15282) (xy 18.840196 -47.3456)
				(xy 18.8468 -47.3456) (xy 16.6624 -49.53) (xy 16.6624 -85.1662) (xy 14.5542 -87.2744) (xy 14.5542 -99.6696)
				(xy 15.274544 -100.389944) (xy 15.274544 -112.276382) (xy 10.009378 -117.541548) (xy 3.070352 -117.541548)
				(xy 1.905 -118.7069) (xy 1.905 -130.60807) (xy 3.88493 -132.588) (xy 7.62 -132.588) (xy 10.042144 -130.165856)
				(xy 10.04062 -130.16357) (xy 10.04443 -130.16357) (xy 13.302996 -126.905004)
				(arc
					(start 13.306806 -126.894336)
					(mid 13.395363 -126.755563)
					(end 13.534136 -126.667006)
				)
				(xy 13.544804 -126.663196) (xy 17.399 -122.809)
				(arc
					(start 24.154892 -122.809)
					(mid 24.178677 -122.806177)
					(end 24.20112 -122.797824)
				)
				(arc
					(start 24.896826 -122.797824)
					(mid 24.919279 -122.806133)
					(end 24.943054 -122.809)
				)
				(xy 154.170634 -122.809) (xy 154.174444 -122.805444) (xy 154.233372 -122.805444) (xy 154.236166 -122.809)
				(arc
					(start 159.074358 -122.809)
					(mid 159.325107 -122.706956)
					(end 159.580326 -122.797062)
				)
				(xy 159.59455 -122.809)
				(arc
					(start 159.729424 -122.809)
					(mid 160.00222 -122.694194)
					(end 160.275016 -122.809)
				)
				(xy 162.718496 -122.809)
				(arc
					(start 162.727132 -122.805698)
					(mid 162.8521 -122.783053)
					(end 162.977068 -122.805698)
				)
				(xy 162.985704 -122.809)
				(arc
					(start 163.223448 -122.809)
					(mid 163.25262 -122.804722)
					(end 163.279328 -122.792236)
				)
				(arc
					(start 164.787326 -122.792236)
					(mid 164.813916 -122.804672)
					(end 164.842952 -122.809)
				)
				(arc
					(start 166.357046 -122.809)
					(mid 166.6494 -122.656165)
					(end 166.941754 -122.809)
				)
				(arc
					(start 169.070274 -122.809)
					(mid 169.291 -122.732332)
					(end 169.511726 -122.809)
				)
				(xy 171.895262 -122.809) (xy 174.960788 -125.874526) (xy 176.606962 -125.874526) (xy 177.25136 -125.230128)
				(xy 177.25136 -124.406914) (xy 181.389274 -120.269)
				(arc
					(start 318.762888 -120.269)
					(mid 318.800186 -120.261906)
					(end 318.83223 -120.241568)
				)
				(arc
					(start 320.286634 -120.241568)
					(mid 320.318703 -120.261845)
					(end 320.355976 -120.269)
				)
				(xy 339.836252 -120.269) (xy 340.686136 -119.419116) (xy 340.686136 -119.386858) (xy 340.712806 -119.392446)
				(xy 343.554812 -116.55044) (xy 343.554812 -111.278416) (xy 340.112096 -107.8357) (xy 339.386164 -107.8357)
				(xy 339.37321 -107.848908) (xy 333.86649 -107.848908) (xy 333.12354 -107.105704) (xy 308.63159 -107.105704)
				(xy 308.61 -107.084114) (xy 308.4068 -107.084114) (xy 305.843686 -104.521) (xy 207.51038 -104.521)
				(xy 207.47482 -104.521) (xy 195.1228 -104.521) (xy 191.3636 -108.2802) (xy 172.402754 -108.2802)
				(xy 172.4025 -108.279946) (xy 172.395388 -108.279946) (xy 172.395134 -108.2802) (xy 161.08426 -108.2802)
				(xy 160.567624 -108.796836) (xy 156.701236 -108.796836) (xy 156.172408 -108.268008) (xy 156.144468 -108.268008)
				(xy 155.530296 -107.653836) (xy 155.530296 -107.625896) (xy 155.5242 -107.6198) (xy 155.5242 -105.8926)
				(xy 155.530296 -105.886504) (xy 155.530296 -105.868216) (xy 158.148782 -103.249476) (xy 182.500524 -103.249476)
				(xy 182.9816 -102.7684) (xy 182.9816 -98.3742) (xy 180.848 -96.2406) (xy 162.5854 -96.2406) (xy 160.8836 -94.5388)
				(xy 146.7612 -94.5388)
				(arc
					(start 139.320016 -101.979984)
					(mid 139.313142 -101.987532)
					(end 139.307062 -101.995732)
				)
				(xy 139.262612 -102.040182) (xy 139.259818 -102.040182) (xy 137.39114 -103.90886) (xy 113.689638 -103.90886)
				(arc
					(start 113.681256 -103.911908)
					(mid 113.561114 -103.932784)
					(end 113.440972 -103.911908)
				)
				(xy 113.43259 -103.90886) (xy 108.908596 -103.90886)
				(arc
					(start 108.899706 -103.912416)
					(mid 108.768896 -103.937311)
					(end 108.638086 -103.912416)
				)
				(xy 108.629196 -103.90886) (xy 58.95594 -103.90886) (xy 58.95467 -103.91013) (xy 44.29379 -103.91013)
				(xy 43.7007 -104.50322) (xy 43.7007 -109.05998) (xy 43.33748 -109.4232) (xy 42.091864 -109.4232)
				(xy 42.09161 -109.423708) (xy 33.52419 -109.423708) (xy 33.523936 -109.4232) (xy 32.363664 -109.4232)
				(xy 32.36341 -109.423708) (xy 24.58339 -109.423708) (xy 24.583136 -109.4232) (xy 24.511 -109.4232)
				(xy 23.76297 -108.67517) (xy 23.76297 -81.195926) (xy 24.00427 -80.954626) (xy 24.00427 -80.94853)
				(xy 25.475692 -79.476854) (xy 25.475692 -55.955692) (xy 24.0538 -54.5338) (xy 24.0538 -54.436264)
				(xy 24.027892 -54.41061) (xy 24.027892 -49.50079) (xy 24.81199 -48.716692) (xy 24.841708 -48.716692)
				(xy 24.877522 -48.680878) (xy 28.894278 -48.680878) (xy 29.903674 -47.671482) (xy 102.337362 -47.671482)
				(xy 103.365046 -46.643798) (xy 143.921988 -46.643798) (xy 153.253186 -37.3126) (xy 197.332092 -37.3126)
				(xy 207.690974 -47.671482) (xy 308.928008 -47.671482) (xy 318.454532 -38.144958) (xy 318.569594 -38.144958)
				(xy 320.413888 -36.300664) (xy 360.13517 -36.300664) (xy 363.788706 -39.9542) (xy 393.5222 -39.9542)
				(xy 393.6746 -40.1066) (xy 393.6746 -51.562) (xy 405.2062 -63.0936) (xy 405.2062 -67.7037) (xy 404.49754 -68.41236)
				(xy 401.60448 -68.41236) (xy 400.01952 -66.8274) (xy 383.35077 -66.8274) (xy 382.77546 -67.40271)
				(xy 382.77546 -74.1172) (xy 386.62356 -77.9653) (xy 394.6398 -77.9653) (xy 394.643864 -77.961236)
				(xy 414.219644 -77.961236) (xy 415.054288 -77.126592) (xy 415.054288 -55.483252) (xy 417.298378 -53.239162)
				(xy 418.095938 -53.239162) (xy 418.25418 -53.08092) (xy 419.871652 -53.08092) (xy 420.124128 -53.333396)
				(xy 420.61511 -53.333396) (xy 421.279066 -52.66944) (xy 423.02176 -52.66944) (xy 424.557698 -51.133502)
				(xy 434.8226 -51.133502) (xy 436.482998 -52.7939) (xy 437.12892 -52.7939) (xy 437.791606 -52.13096)
				(xy 437.791606 -45.397928) (xy 437.691276 -45.297598) (xy 436.215028 -45.297598) (xy 435.126892 -44.209462)
				(xy 434.726842 -43.809412) (xy 432.320192 -43.809412) (xy 430.88306 -43.809412) (xy 430.5808 -44.111672)
				(xy 430.5808 -46.3804) (xy 430.5808 -46.86808) (xy 429.54194 -47.90694) (xy 426.3644 -47.90694)
				(xy 423.16146 -44.704) (xy 411.8356 -44.704) (xy 411.3022 -44.1706) (xy 411.3022 -42.182288) (xy 411.303216 -42.181272)
				(xy 411.303216 -33.362646) (xy 411.3022 -33.36163) (xy 411.3022 -30.734) (xy 411.9626 -30.0736)
				(xy 418.9984 -30.0736) (xy 419.2778 -29.7942) (xy 419.2778 -6.096) (xy 418.3888 -5.207) (xy 399.288 -5.207)
				(xy 398.8816 -5.6134) (xy 398.8816 -19.8882) (xy 392.6332 -26.1366) (xy 392.6332 -28.9306) (xy 392.6078 -28.956)
				(xy 388.4422 -28.956) (xy 386.7404 -27.2542) (xy 386.7404 -8.9408) (xy 383.0066 -5.207) (xy 361.22356 -5.207)
				(xy 361.21848 -5.20192) (xy 357.64724 -5.20192) (xy 357.641906 -5.207) (xy 354.7872 -5.207)
				(arc
					(start 353.561396 -3.981196)
					(mid 353.537988 -3.96379)
					(end 353.510596 -3.953764)
				)
				(arc
					(start 352.941636 -3.384804)
					(mid 352.931608 -3.357413)
					(end 352.914204 -3.334004)
				)
				(xy 351.4598 -1.8796) (xy 344.818716 -1.8796) (xy 342.6968 -4.001516) (xy 342.6968 -24.458168) (xy 335.97215 -31.182818)
				(xy 321.537584 -31.182818) (xy 319.420748 -33.299654) (xy 233.959654 -33.299654) (xy 229.489 -28.829)
				(xy 193.294 -28.829)
				(arc
					(start 188.365892 -23.900892)
					(mid 187.965904 -23.614099)
					(end 187.677044 -23.2156)
				)
				(xy 187.673234 -23.208234) (xy 186.703208 -22.238208) (xy 186.699398 -22.238208) (xy 186.6773 -22.21611)
				(xy 186.675268 -22.21611) (xy 186.675268 -22.210268) (xy 186.436 -21.971) (xy 186.436 -18.563336)
				(xy 186.43473 -18.562066) (xy 186.436 -18.560796) (xy 186.436 -12.446) (xy 180.467 -6.477) (xy 179.705 -6.477)
				(xy 179.688236 -6.493764) (xy 178.926236 -6.493764) (xy 176.022 -9.398) (xy 167.767 -9.398) (xy 167.7035 -9.4615)
				(arc
					(start 162.75431 -9.4615)
					(mid 162.104115 -9.656052)
					(end 161.43351 -9.55167)
				)
				(xy 161.402522 -9.539478) (xy 158.115 -12.827) (xy 158.115 -24.511) (xy 157.861 -24.765) (xy 22.987 -24.765)
				(xy 19.812 -21.59) (xy 15.113 -21.59) (xy 13.843 -20.32) (xy 13.843 -7.2898) (xy 16.1036 -5.0292)
				(xy 16.1036 4.2164) (xy 15.113 5.207)
			)
		)
		(polygon
			(pts
				(arc
					(start 415.05378 -70.186804)
					(mid 414.986821 -70.101268)
					(end 414.880806 -70.125082)
				)
				(xy 414.223708 -70.782434) (xy 414.223708 -70.872604) (xy 414.27908 -70.872604)
				(arc
					(start 414.283906 -70.871842)
					(mid 414.705707 -71.198054)
					(end 414.330642 -71.5772)
				)
				(arc
					(start 414.330642 -71.5772)
					(mid 414.255458 -71.604923)
					(end 414.223708 -71.678546)
				)
				(xy 414.223708 -71.896986)
				(arc
					(start 414.880806 -72.554338)
					(mid 414.98684 -72.578204)
					(end 415.05378 -72.492616)
				)
			)
		)
		(polygon
			(pts
				(xy 419.001702 -30.066234) (xy 418.240972 -30.066234) (xy 418.243004 -30.073092) (xy 418.994844 -30.073092)
			)
		)
		(polygon
			(pts
				(xy 344.709242 -9.039352) (xy 344.539824 -9.039352) (xy 344.539824 -9.22655) (xy 344.709242 -9.22655)
			)
		)
	)
	(zone
		(net "GND")
		(layer "In6.Cu")
		(hatch none 0.5)
		(connect_pads
			(clearance 0.5)
		)
		(min_thickness 0.25)
		(fill yes
			(thermal_gap 0.5)
			(thermal_bridge_width 0.5)
			(island_removal_mode 0)
		)
		(polygon
			(pts
				(xy 262.222234 -63.084202) (xy 262.917432 -63.7794) (xy 268.825218 -63.7794) (xy 268.988032 -63.616586)
				(xy 268.988032 -62.477396) (xy 268.988032 -51.770026) (xy 268.754606 -51.5366) (xy 268.149832 -51.5366)
				(xy 267.144754 -51.5366) (xy 233.36123 -51.5366) (xy 199.7964 -51.5366) (xy 199.39 -51.943) (xy 199.39 -52.602892)
				(xy 199.390508 -52.602892) (xy 199.390508 -54.05501) (xy 199.39 -54.055264) (xy 199.39 -54.102)
				(xy 199.376792 -54.115208) (xy 199.376792 -92.899992) (xy 199.503792 -93.026992) (xy 208.026 -93.026992)
				(xy 208.210658 -92.842334) (xy 208.210658 -53.515006) (xy 208.506314 -53.21935) (xy 214.257382 -53.21935)
				(xy 223.953832 -62.9158) (xy 231.337612 -62.910974) (xy 262.049006 -62.910974)
			)
		)
	)
	(zone
		(net "GND")
		(layer "In6.Cu")
		(hatch none 0.5)
		(connect_pads
			(clearance 0.5)
		)
		(min_thickness 0.25)
		(fill yes
			(thermal_gap 0.5)
			(thermal_bridge_width 0.5)
			(island_removal_mode 0)
		)
		(polygon
			(pts
				(xy 33.1724 -93.7006) (xy 33.1724 -94.145354) (xy 33.1724 -94.84741) (xy 33.1724 -95.8977) (xy 33.147508 -95.8977)
				(xy 33.147508 -97.7138) (xy 33.1724 -97.7138) (xy 33.1724 -102.491286) (xy 33.411414 -102.7303)
				(xy 38.4429 -102.7303) (xy 39.9669 -101.2063) (xy 39.9669 -101.1936) (xy 42.0497 -101.1936) (xy 42.90695 -100.33635)
				(xy 42.90695 -93.81363) (xy 42.603928 -93.510608) (xy 33.362392 -93.510608)
			)
		)
	)
	(zone
		(net "PVDDQ_KLM")
		(layer "In6.Cu")
		(hatch none 0.5)
		(connect_pads
			(clearance 0.5)
		)
		(min_thickness 0.25)
		(fill yes
			(thermal_gap 0.5)
			(thermal_bridge_width 0.5)
			(island_removal_mode 0)
		)
		(polygon
			(pts
				(xy 16.637 -137.2362) (xy 16.637 -157.982158) (xy 17.2974 -158.642558)
				(arc
					(start 90.175588 -158.642558)
					(mid 90.193921 -158.64089)
					(end 90.211656 -158.635954)
				)
				(arc
					(start 91.049856 -158.635954)
					(mid 91.067589 -158.640903)
					(end 91.085924 -158.642558)
				)
				(arc
					(start 101.125274 -158.642558)
					(mid 101.20851 -158.599219)
					(end 101.220778 -158.50616)
				)
				(arc
					(start 101.220778 -158.50616)
					(mid 101.555296 -158.027856)
					(end 101.889814 -158.50616)
				)
				(arc
					(start 101.889814 -158.50616)
					(mid 101.902044 -158.599245)
					(end 101.985318 -158.642558)
				)
				(arc
					(start 104.554274 -158.642558)
					(mid 104.63751 -158.599219)
					(end 104.649778 -158.50616)
				)
				(arc
					(start 104.649778 -158.50616)
					(mid 104.984296 -158.027856)
					(end 105.318814 -158.50616)
				)
				(arc
					(start 105.318814 -158.50616)
					(mid 105.331044 -158.599245)
					(end 105.414318 -158.642558)
				)
				(arc
					(start 108.112052 -158.642558)
					(mid 108.19561 -158.598755)
					(end 108.207048 -158.505144)
				)
				(arc
					(start 108.207048 -158.505144)
					(mid 108.540296 -158.023237)
					(end 108.873544 -158.505144)
				)
				(arc
					(start 108.873544 -158.505144)
					(mid 108.885045 -158.598712)
					(end 108.96854 -158.642558)
				)
				(xy 112.776 -158.642558) (xy 112.776 -158.635192) (xy 114.553746 -158.635192) (xy 114.554 -158.634938)
				(xy 114.554 -158.642558) (xy 167.087042 -158.642558) (xy 168.656 -157.0736) (xy 168.656 -153.3652)
				(xy 169.545 -152.4762) (xy 169.545 -150.49881) (xy 169.545 -149.625304)
				(arc
					(start 169.544746 -149.622256)
					(mid 169.542301 -149.5806)
					(end 169.544746 -149.538944)
				)
				(xy 169.545 -149.535896) (xy 169.545 -145.0594) (xy 169.5704 -145.034) (xy 169.5704 -143.2814) (xy 168.7576 -142.4686)
				(xy 157.5054 -142.4686) (xy 156.8958 -141.859) (xy 156.8958 -129.6162) (xy 156.7434 -129.4638) (xy 156.2608 -128.9812)
				(xy 156.21 -128.9304) (xy 24.461216 -128.9304) (xy 24.372316 -129.0193) (xy 16.637 -136.754616)
			)
		)
	)
	(zone
		(net "P1V15_AUX_BMC")
		(layer "In6.Cu")
		(hatch none 0.5)
		(connect_pads
			(clearance 0.5)
		)
		(min_thickness 0.25)
		(fill yes
			(thermal_gap 0.5)
			(thermal_bridge_width 0.5)
			(island_removal_mode 0)
		)
		(polygon
			(pts
				(xy 412.1912 -30.353) (xy 411.5054 -31.0388) (xy 411.5054 -44.1198) (xy 411.8864 -44.5008) (xy 423.43832 -44.5008)
				(xy 426.50664 -47.56912) (xy 429.46828 -47.56912) (xy 430.310036 -46.727364) (xy 430.310036 -46.319948)
				(xy 430.310036 -41.766236) (xy 425.6151 -37.0713) (xy 418.8587 -37.0713) (xy 418.719 -36.9316) (xy 418.719 -30.643576)
				(xy 418.428424 -30.353)
			)
		)
	)
	(zone
		(net "PVCCIO_CPU0")
		(layer "In6.Cu")
		(hatch none 0.5)
		(connect_pads
			(clearance 0.5)
		)
		(min_thickness 0.25)
		(fill yes
			(thermal_gap 0.5)
			(thermal_bridge_width 0.5)
			(island_removal_mode 0)
		)
		(polygon
			(pts
				(xy 294.012366 -81.018634) (xy 293.358062 -81.672938) (xy 293.065708 -81.965292) (xy 293.065708 -82.71891)
				(xy 293.065708 -83.590892) (xy 293.065708 -84.624418) (xy 293.064184 -84.625942) (xy 293.064184 -84.65058)
				(xy 293.065708 -84.652104) (xy 293.065708 -84.737956) (xy 291.934392 -85.869272) (xy 291.90061 -85.903308)
				(xy 290.88461 -85.903308) (xy 290.884356 -85.903308) (xy 290.0934 -86.694264) (xy 290.091876 -86.695788)
				(xy 290.091876 -89.531444) (xy 290.0934 -89.533222) (xy 290.0934 -89.716356) (xy 290.0934 -90.3478)
				(xy 290.049712 -90.391488) (xy 289.271456 -91.169744) (xy 289.157664 -91.283536) (xy 288.69005 -91.75115)
				(xy 288.645092 -91.796108) (xy 287.57753 -91.796108) (xy 287.4899 -91.796108) (xy 287.231328 -91.796108)
				(xy 287.14319 -91.796108) (xy 286.038036 -90.690954) (xy 286.004254 -90.657172) (xy 285.744158 -90.397076)
				(xy 285.744158 -90.395806) (xy 285.6484 -90.300048) (xy 285.6484 -85.15985) (xy 285.6484 -85.1408)
				(xy 285.7754 -85.0138) (xy 285.7754 -83.450938) (xy 286.8168 -82.409538) (xy 286.8168 -82.3214)
				(xy 286.8168 -82.042) (xy 286.8168 -81.749138) (xy 286.525462 -81.4578) (xy 286.156908 -81.4578)
				(xy 285.079948 -81.4578) (xy 282.780232 -81.4578) (xy 278.2316 -81.4578) (xy 278.06777 -81.4578)
				(xy 277.934674 -81.590896) (xy 277.934674 -84.386674) (xy 278.0792 -84.5312) (xy 278.854916 -85.306916)
				(xy 279.536652 -85.988652) (xy 279.8826 -86.3346) (xy 280.110184 -86.56193) (xy 280.31694 -86.768686)
				(xy 280.31694 -86.938866) (xy 280.31694 -86.93912) (xy 280.31694 -88.062308) (xy 280.31694 -103.455216)
				(xy 280.651712 -103.789988) (xy 305.675284 -103.789988) (xy 308.737 -106.85145) (xy 333.22895 -106.85145)
				(xy 333.9719 -107.5944) (xy 339.2678 -107.5944) (xy 339.748368 -107.113832) (xy 339.748368 -91.213432)
				(xy 337.639152 -89.10447) (xy 337.02879 -88.494108) (xy 336.654394 -88.119712) (xy 336.068416 -87.533734)
				(xy 334.74279 -86.208108) (xy 309.85079 -86.208108) (xy 309.339234 -85.696552) (xy 305.15433 -81.511648)
				(xy 304.60823 -80.965548) (xy 296.1259 -80.965548) (xy 296.001186 -80.965548) (xy 295.605454 -80.965548)
				(xy 294.065452 -80.965548)
			)
		)
	)
	(zone
		(net "GND")
		(layer "In6.Cu")
		(hatch none 0.5)
		(connect_pads
			(clearance 0.5)
		)
		(min_thickness 0.25)
		(fill yes
			(thermal_gap 0.5)
			(thermal_bridge_width 0.5)
			(island_removal_mode 0)
		)
		(polygon
			(pts
				(xy 70.3199 -92.8751) (xy 69.977 -93.218) (xy 67.437 -93.218) (xy 61.639704 -99.015296) (xy 61.639704 -101.766116)
				(xy 62.870588 -102.997) (xy 109.5756 -102.997) (xy 109.8296 -103.251) (xy 113.0808 -103.251) (xy 113.411 -102.9208)
				(xy 114.52352 -102.9208) (xy 114.80165 -102.64267) (xy 114.80165 -100.401374) (xy 114.7953 -100.395024)
				(xy 114.7953 -91.285314) (xy 114.7953 -90.9193) (xy 113.919 -90.043) (xy 113.303304 -90.043) (xy 112.176814 -90.043)
				(xy 104.871774 -90.043) (xy 104.648762 -90.043) (xy 104.356916 -89.751154) (xy 104.356154 -89.751154)
				(xy 103.505 -88.9) (xy 97.917 -88.9) (xy 96.266 -88.9) (xy 96.184466 -88.818466) (xy 95.885 -88.519)
				(xy 95.880936 -88.514936) (xy 95.876872 -88.519) (xy 93.306392 -88.519) (xy 93.30563 -88.518238)
				(xy 92.531438 -88.518238) (xy 92.472256 -88.459056) (xy 92.192856 -88.179656) (xy 92.192856 -88.164416)
				(xy 90.51544 -86.487) (xy 89.948258 -86.487) (xy 89.871296 -86.487) (xy 89.868756 -86.48446) (xy 83.082892 -86.48446)
				(xy 83.06054 -86.48446) (xy 83.058 -86.487) (xy 82.101944 -87.443056) (xy 81.39938 -88.14562) (xy 80.899 -88.646)
				(xy 74.93 -88.646) (xy 74.549 -88.646)
			)
		)
	)
	(zone
		(net "P12V")
		(layer "In6.Cu")
		(hatch none 0.5)
		(connect_pads
			(clearance 0.5)
		)
		(min_thickness 0.25)
		(fill yes
			(thermal_gap 0.5)
			(thermal_bridge_width 0.5)
			(island_removal_mode 0)
		)
		(polygon
			(pts
				(xy 468.159338 -4.7498) (xy 467.60257 -5.306568) (xy 467.60257 -9.23417) (xy 467.60257 -12.807188)
				(xy 471.547952 -16.75257) (xy 471.547952 -17.5006) (xy 471.827352 -17.78) (xy 472.1352 -17.78) (xy 472.5924 -18.2372)
				(xy 472.5924 -18.9484) (xy 472.1352 -19.4056) (xy 471.673428 -19.4056) (xy 471.546428 -19.5326)
				(xy 471.546428 -20.32) (xy 471.643202 -20.416774) (xy 475.03334 -23.806912) (xy 476.585026 -23.806912)
				(xy 476.81769 -24.039576) (xy 490.7153 -37.937186) (xy 491.276894 -38.49878) (xy 491.276894 -55.607458)
				(xy 490.7153 -56.169052) (xy 488.3023 -58.582052) (xy 479.333052 -58.582052) (xy 475.8182 -62.096904)
				(xy 475.8182 -67.323462) (xy 475.876112 -67.38112) (xy 478.574862 -67.38112) (xy 479.000312 -66.95567)
				(xy 479.000312 -63.050674) (xy 479.850196 -62.20079) (xy 498.77472 -62.20079) (xy 498.92966 -62.04585)
				(xy 498.92966 -61.27242) (xy 499.40972 -60.79236) (xy 501.367552 -60.79236) (xy 501.494552 -60.66536)
				(xy 501.494552 -53.49748) (xy 501.342152 -53.34508) (xy 499.35638 -53.34508) (xy 498.96776 -52.95646)
				(xy 498.96776 -52.26558) (xy 499.43766 -51.79568) (xy 501.423432 -51.79568) (xy 501.494552 -51.72456)
				(xy 501.494552 -14.906752) (xy 501.0658 -14.478) (xy 483.95128 -14.478) (xy 483.39248 -13.9192)
				(xy 483.39248 -4.7752) (xy 483.108 -4.7752) (xy 483.108 -4.7498)
			)
		)
		(polygon
			(pts
				(arc
					(start 483.391972 -5.271008)
					(mid 483.337595 -5.190943)
					(end 483.240842 -5.192776)
				)
				(arc
					(start 483.240842 -5.192776)
					(mid 482.878878 -5.297475)
					(end 482.50856 -5.227828)
				)
				(arc
					(start 482.50856 -5.227828)
					(mid 482.403723 -5.241258)
					(end 482.36759 -5.340604)
				)
				(arc
					(start 482.36759 -5.340604)
					(mid 482.382861 -5.473343)
					(end 482.376226 -5.606796)
				)
				(arc
					(start 482.376226 -5.606796)
					(mid 482.414718 -5.700648)
					(end 482.515164 -5.714492)
				)
				(arc
					(start 482.515164 -5.714492)
					(mid 482.883326 -5.652177)
					(end 483.243382 -5.751068)
				)
				(arc
					(start 483.243382 -5.751068)
					(mid 483.338946 -5.750766)
					(end 483.391972 -5.671312)
				)
			)
		)
		(polygon
			(pts
				(arc
					(start 483.391972 -9.388856)
					(mid 483.338904 -9.309481)
					(end 483.243382 -9.3091)
				)
				(arc
					(start 483.243382 -9.3091)
					(mid 482.908897 -9.406384)
					(end 482.56317 -9.36371)
				)
				(arc
					(start 482.56317 -9.36371)
					(mid 482.467253 -9.380578)
					(end 482.429566 -9.47039)
				)
				(arc
					(start 482.429566 -9.47039)
					(mid 482.43382 -9.585554)
					(end 482.422708 -9.70026)
				)
				(arc
					(start 482.422708 -9.70026)
					(mid 482.458247 -9.795018)
					(end 482.55809 -9.81202)
				)
				(arc
					(start 482.55809 -9.81202)
					(mid 482.905572 -9.76435)
					(end 483.240842 -9.867392)
				)
				(arc
					(start 483.240842 -9.867392)
					(mid 483.337582 -9.869199)
					(end 483.391972 -9.78916)
				)
			)
		)
		(polygon
			(pts
				(arc
					(start 483.391972 -11.388852)
					(mid 483.338904 -11.309477)
					(end 483.243382 -11.309096)
				)
				(arc
					(start 483.243382 -11.309096)
					(mid 482.908897 -11.40638)
					(end 482.56317 -11.363706)
				)
				(arc
					(start 482.56317 -11.363706)
					(mid 482.467253 -11.380574)
					(end 482.429566 -11.470386)
				)
				(arc
					(start 482.429566 -11.470386)
					(mid 482.43382 -11.58555)
					(end 482.422708 -11.700256)
				)
				(arc
					(start 482.422708 -11.700256)
					(mid 482.458247 -11.795014)
					(end 482.55809 -11.812016)
				)
				(arc
					(start 482.55809 -11.812016)
					(mid 482.905572 -11.764346)
					(end 483.240842 -11.867388)
				)
				(arc
					(start 483.240842 -11.867388)
					(mid 483.337582 -11.869195)
					(end 483.391972 -11.789156)
				)
			)
		)
	)
	(zone
		(net "PVCCIN_CPU1")
		(layer "In6.Cu")
		(hatch none 0.5)
		(connect_pads
			(clearance 0.5)
		)
		(min_thickness 0.25)
		(fill yes
			(thermal_gap 0.5)
			(thermal_bridge_width 0.5)
			(island_removal_mode 0)
		)
		(polygon
			(pts
				(xy 43.812968 -53.5432) (xy 43.660568 -53.6956) (xy 43.6626 -92.2274) (xy 43.815 -92.3798) (xy 54.436772 -92.3798)
				(xy 54.777894 -92.075) (xy 62.968124 -83.88477) (xy 69.363844 -83.88477) (xy 72.6186 -80.630014)
				(xy 79.737966 -80.630014) (xy 79.812642 -80.555338) (xy 79.817468 -80.550512) (xy 81.353152 -79.015082)
				(xy 81.435194 -79.015082) (xy 81.436464 -79.013812) (xy 84.028534 -79.013812) (xy 84.287868 -79.013812)
				(arc
					(start 84.291678 -79.013304)
					(mid 84.347812 -79.00885)
					(end 84.403946 -79.013304)
				)
				(xy 84.407756 -79.013812) (xy 84.750656 -79.013812) (xy 85.293962 -79.013812) (xy 85.297772 -79.017622)
				(xy 85.380576 -79.017622) (xy 85.86089 -79.497936) (xy 85.86089 -79.58074) (xy 85.86089 -79.810864)
				(xy 85.86089 -79.909416) (xy 85.86089 -80.459072) (xy 86.22411 -80.822292) (xy 86.561676 -81.159858)
				(xy 86.561676 -81.464404) (xy 86.561676 -82.217768) (xy 86.561676 -82.4992) (xy 86.561676 -82.640932)
				(xy 90.077544 -86.1568) (xy 90.219276 -86.1568) (xy 90.739468 -86.1568) (xy 90.887804 -86.1568)
				(xy 91.245182 -86.1568) (xy 92.935806 -87.847424) (xy 93.156786 -87.847424) (xy 96.585024 -87.847424)
				(xy 97.161604 -88.424004)
				(arc
					(start 97.185988 -88.421464)
					(mid 97.293477 -88.425858)
					(end 97.394776 -88.462104)
				)
				(xy 97.406206 -88.4682) (xy 103.928926 -88.4682) (xy 105.10012 -89.639394) (xy 105.158794 -89.639394)
				(xy 114.16919 -89.639394) (xy 114.248184 -89.5604) (xy 115.062 -88.746584) (xy 115.062 -88.38438)
				(xy 115.062 -86.8934) (xy 115.05438 -86.88578) (xy 115.05438 -85.51418) (xy 115.05438 -82.845402)
				(xy 111.583978 -79.375) (xy 108.9152 -79.375) (xy 107.5436 -79.375) (xy 104.0892 -79.375) (xy 103.7336 -79.0194)
				(xy 103.7336 -64.2874) (xy 103.5304 -64.0842) (xy 97.70745 -64.0842) (xy 96.86925 -63.246) (xy 96.865186 -63.241936)
				(xy 66.573908 -63.241936) (xy 66.569844 -63.246) (xy 58.8772 -63.246) (xy 49.1744 -53.5432)
			)
		)
	)
	(zone
		(net "GND")
		(layer "In6.Cu")
		(hatch none 0.5)
		(connect_pads
			(clearance 0.5)
		)
		(min_thickness 0.25)
		(fill yes
			(thermal_gap 0.5)
			(thermal_bridge_width 0.5)
			(island_removal_mode 0)
		)
		(polygon
			(pts
				(xy 488.500928 5.542788) (xy 488.2388 5.28066) (xy 488.2388 3.7084) (xy 488.4674 3.4798) (xy 501.0912 3.4798)
				(xy 501.471184 3.859784) (xy 501.471184 5.06984) (xy 500.998236 5.542788)
			)
		)
	)
	(zone
		(net "P12V_STBY")
		(layer "In7.Cu")
		(hatch none 0.5)
		(connect_pads
			(clearance 0.5)
		)
		(min_thickness 0.25)
		(fill yes
			(thermal_gap 0.5)
			(thermal_bridge_width 0.5)
			(island_removal_mode 0)
		)
		(polygon
			(pts
				(xy 355.7524 -114.0206) (xy 346.1766 -114.0206) (xy 339.990938 -107.834938) (xy 333.96682 -107.834938)
				(xy 333.23911 -107.107228) (xy 308.50967 -107.107228) (xy 308.468522 -107.065826) (xy 308.351174 -107.065826)
				(xy 305.857148 -104.5718)
				(arc
					(start 203.52639 -104.5718)
					(mid 203.494997 -104.576854)
					(end 203.4667 -104.591358)
				)
				(xy 202.59548 -104.591358) (xy 202.564238 -104.582722) (xy 202.543156 -104.575356) (xy 202.534266 -104.5718)
				(xy 195.6562 -104.5718) (xy 195.061586 -105.166414) (xy 195.057776 -105.174034) (xy 195.053966 -105.174034)
				(xy 191.981582 -108.246418) (xy 191.299846 -108.246418) (xy 191.278256 -108.268008)
				(arc
					(start 173.199806 -108.268008)
					(mid 173.113338 -108.325254)
					(end 173.122082 -108.428536)
				)
				(arc
					(start 173.122082 -108.428536)
					(mid 172.81398 -109.035119)
					(end 172.505878 -108.428536)
				)
				(arc
					(start 172.505878 -108.428536)
					(mid 172.514536 -108.325295)
					(end 172.428154 -108.268008)
				)
				(xy 159.91459 -108.268008)
				(arc
					(start 159.908494 -108.269532)
					(mid 159.8168 -108.280715)
					(end 159.725106 -108.269532)
				)
				(xy 159.71901 -108.268008)
				(arc
					(start 159.114998 -108.268008)
					(mid 158.8008 -108.433114)
					(end 158.486602 -108.268008)
				)
				(xy 156.144468 -108.268008) (xy 155.530296 -107.653836) (xy 155.530296 -105.868216) (xy 158.148782 -103.249476)
				(xy 181.154324 -103.249476) (xy 181.9148 -102.489) (xy 181.9148 -96.9772) (xy 181.1274 -96.1898)
				(xy 162.7378 -96.1898) (xy 161.2392 -94.6912) (xy 146.7612 -94.6912) (xy 137.5664 -103.886) (xy 113.737898 -103.886)
				(arc
					(start 113.726722 -103.891842)
					(mid 113.561114 -103.932698)
					(end 113.395506 -103.891842)
				)
				(xy 113.38433 -103.886)
				(arc
					(start 108.953046 -103.886)
					(mid 108.768896 -103.93731)
					(end 108.584746 -103.886)
				)
				(xy 44.07408 -103.886) (xy 43.73118 -104.2289) (xy 43.73118 -109.12348) (xy 43.43146 -109.4232)
				(xy 42.091864 -109.4232) (xy 42.09161 -109.423708) (xy 33.52419 -109.423708) (xy 33.523936 -109.4232)
				(xy 32.363664 -109.4232) (xy 32.36341 -109.423708) (xy 24.58339 -109.423708) (xy 24.583136 -109.4232)
				(xy 24.511 -109.4232) (xy 23.876 -108.7882) (xy 23.876 -94.973902) (xy 23.875746 -94.973902) (xy 23.875746 -94.335854)
				(xy 23.876 -94.3356) (xy 23.876 -89.395554) (xy 23.876 -89.369646) (xy 23.876 -88.735154) (xy 23.876 -88.709246)
				(xy 23.876 -81.1022) (xy 25.475692 -79.502254) (xy 25.475692 -55.858156) (xy 24.115268 -54.497732)
				(xy 24.027892 -54.41061) (xy 24.027892 -49.50079) (xy 24.81199 -48.716692) (xy 24.892508 -48.716692)
				(xy 24.9174 -48.6918) (xy 101.2698 -48.6918) (xy 103.3018 -46.6598) (xy 143.8402 -46.6598) (xy 147.9042 -42.5958)
				(xy 159.639 -42.5958) (xy 161.0868 -41.148) (xy 168.91 -41.148) (xy 171.9326 -44.1706) (xy 309.0164 -44.1706)
				(xy 312.4708 -47.625) (xy 317.769494 -47.625) (xy 317.770256 -47.624492) (xy 322.45681 -47.624492)
				(xy 322.457064 -47.625) (xy 322.513706 -47.625) (xy 324.485 -49.596294) (xy 324.485 -56.896) (xy 325.02348 -57.43448)
				(xy 345.4019 -57.43448) (xy 345.403932 -57.434734) (xy 347.045026 -57.434734) (xy 347.047312 -57.43448)
				(xy 347.506544 -57.43448) (xy 347.506798 -57.434734) (xy 349.014796 -57.434734) (xy 349.017082 -57.43448)
				(xy 357.081582 -57.43448) (xy 363.477302 -63.8302) (xy 384.9116 -63.8302) (xy 386.08635 -62.65545)
				(xy 386.08635 -60.68695) (xy 387.327394 -59.445906) (xy 396.39748 -59.445906) (xy 396.871952 -59.920378)
				(xy 396.871952 -60.612274) (xy 397.076168 -60.81649) (xy 409.682442 -60.81649) (xy 421.153082 -72.28713)
				(xy 421.153082 -73.657968) (xy 421.49268 -73.997566) (xy 421.49268 -74.593704) (xy 421.153082 -74.933302)
				(xy 421.153082 -114.171222) (xy 421.324024 -114.342164) (xy 421.364156 -114.382042) (xy 421.364156 -114.382804)
				(xy 426.614844 -119.633492) (xy 426.616114 -119.633492) (xy 426.634656 -119.652288) (xy 436.475378 -119.652288)
				(arc
					(start 436.48503 -119.648224)
					(mid 436.63362 -119.61811)
					(end 436.78221 -119.648224)
				)
				(xy 436.791862 -119.652288) (xy 438.023 -119.652288) (xy 438.041542 -119.633492) (xy 438.042812 -119.633492)
				(xy 440.207654 -117.468396) (xy 489.065316 -117.468396) (xy 489.107226 -117.426232) (xy 489.107988 -117.426232)
				(xy 490.392974 -116.140992) (xy 490.4994 -116.034566) (xy 490.4994 -111.494316) (xy 490.193584 -111.1885)
				(xy 489.2929 -111.1885) (xy 489.1151 -111.0107) (xy 489.1151 -110.4519) (xy 489.00715 -110.34395)
				(xy 484.21925 -110.34395) (xy 484.179118 -110.384082) (xy 427.630082 -110.384082) (xy 426.742352 -109.496352)
				(xy 426.742352 -69.069458) (xy 426.743876 -68.9991) (xy 426.743876 -68.238624) (xy 427.573186 -67.409314)
				(xy 468.065866 -67.409314) (xy 468.30361 -67.17157) (xy 468.30361 -66.937128) (xy 465.720176 -64.353694)
				(xy 441.62091 -64.353694) (xy 441.03925 -63.772034) (xy 441.03925 -59.647582) (xy 441.379102 -59.30773)
				(xy 469.878664 -59.30773) (xy 473.105734 -62.5348) (xy 478.74047 -62.5348) (xy 479.007932 -62.267338)
				(xy 479.007932 -51.691032) (xy 486.416858 -44.282106) (xy 486.416858 -37.886386) (xy 487.245406 -37.057838)
				(xy 490.290104 -37.057838) (xy 490.65815 -36.689792) (xy 490.65815 -31.33725) (xy 497.4082 -24.5872)
				(xy 497.4082 -20.809712) (xy 495.940588 -19.3421) (xy 485.5464 -19.3421) (xy 485.0638 -18.8595)
				(xy 481.0633 -18.8595) (xy 481.058728 -18.864072) (xy 476.146368 -18.864072) (xy 474.602302 -20.408138)
				(xy 472.749626 -20.408138) (xy 472.143582 -21.014182) (xy 472.143582 -25.463246) (xy 469.943942 -27.662886)
				(xy 469.943942 -35.048698) (xy 468.357712 -36.634928) (xy 468.357712 -42.550842) (xy 467.073742 -43.834812)
				(xy 459.907894 -43.834812) (xy 451.2691 -43.834812) (xy 449.77177 -45.332142) (xy 436.25897 -45.332142)
				(xy 434.76164 -43.834812) (xy 430.842166 -43.834812) (xy 430.586642 -44.090336) (xy 430.586642 -46.35373)
				(xy 430.586642 -46.872398) (xy 429.5394 -47.91964) (xy 426.375322 -47.91964) (xy 423.17416 -44.718478)
				(xy 411.903418 -44.718478) (xy 411.303216 -44.118276) (xy 411.303216 -43.075352) (xy 411.07741 -42.849546)
				(xy 402.919438 -42.849292) (xy 402.118068 -42.047922) (xy 402.118068 -24.812752) (xy 404.239476 -22.691344)
				(xy 404.239476 -17.423384) (xy 403.889718 -17.073626) (xy 394.821664 -17.073626) (xy 393.25931 -18.63598)
				(xy 393.25931 -42.15638) (xy 392.566398 -42.849292) (xy 373.430292 -42.849292) (xy 372.604284 -43.6753)
				(xy 368.9985 -43.6753) (xy 368.3 -42.9768) (xy 368.3 -15.6464) (xy 357.5939 -4.9403) (xy 355.2317 -4.9403)
				(xy 354.8761 -4.5847) (xy 354.8761 -0.7239) (xy 352.9838 1.1684) (xy 352.9838 5.339588) (xy 352.7806 5.542788)
				(xy 338.709 5.542788) (xy 338.0994 4.933188) (xy 338.0994 -17.7038) (xy 331.5716 -24.2316) (xy 330.1492 -24.2316)
				(xy 329.2348 -25.146) (xy 327.406 -25.146) (xy 326.4916 -24.2316) (xy 277.7236 -24.2316) (xy 274.32 -27.6352)
				(xy 266.7508 -27.6352) (xy 266.7254 -27.6098) (xy 257.81 -27.6098) (xy 254.4318 -24.2316) (xy 196.2912 -24.2316)
				(xy 196.2785 -24.2443) (xy 195.5927 -24.2443) (xy 194.9196 -24.9174) (xy 193.0654 -24.9174) (xy 192.6082 -24.4602)
				(xy 192.6082 -22.7076) (xy 193.167 -22.1488) (xy 193.167 -10.033) (xy 191.996568 -8.862568) (xy 170.978576 -8.862568)
				(xy 170.563286 -9.277858) (xy 164.1602 -9.277858) (xy 163.576 -9.862058) (xy 163.576 -23.1902) (xy 162.4838 -24.2824)
				(xy 156.696664 -24.2824) (xy 156.619956 -24.359108) (xy 156.46781 -24.511508) (xy 156.463492 -24.511508)
				(xy 156.4132 -24.5618) (xy 112.2172 -24.5618) (xy 109.207046 -27.571954) (xy 101.636322 -27.571954)
				(xy 99.199192 -25.134824) (xy 99.199192 -25.13203) (xy 99.17938 -25.112218) (xy 99.17938 -24.769064)
				(xy 98.972116 -24.5618) (xy 23.2156 -24.5618) (xy 23.165308 -24.511508) (xy 23.13559 -24.511508)
				(xy 22.983444 -24.359108) (xy 21.992336 -23.368) (xy 15.087346 -23.368) (xy 8.27024 -16.550894)
				(xy -4.776724 -16.550894) (xy -5.542788 -17.316958) (xy -5.542788 -149.5552) (xy -5.111496 -149.986492)
				(xy -3.047492 -149.986492) (xy -3.047492 -149.987) (xy -2.8194 -149.987) (xy -1.5494 -151.257) (xy 1.2192 -151.257)
				(xy 1.6002 -150.876)
				(arc
					(start 10.783062 -150.876)
					(mid 10.97534 -150.819626)
					(end 11.167618 -150.876)
				)
				(arc
					(start 11.622786 -150.876)
					(mid 11.811 -150.82219)
					(end 11.999214 -150.876)
				)
				(xy 14.732 -150.876) (xy 15.748 -149.86) (xy 15.748 -136.9568) (xy 23.927308 -128.777492) (xy 28.5242 -128.777492)
				(xy 28.524708 -128.778) (xy 29.6418 -128.778) (xy 29.642308 -128.777492) (xy 106.69524 -128.777492)
				(xy 109.568488 -125.904244) (xy 110.433612 -125.904244) (xy 113.30686 -128.777492) (xy 156.34081 -128.777492)
				(xy 157.4546 -129.891282) (xy 157.4546 -141.5288) (xy 157.8356 -141.9098) (xy 192.3034 -141.9098)
				(xy 192.6844 -141.5288) (xy 192.6844 -129.5908) (xy 193.4591 -128.8161) (xy 193.4591 -128.4605)
				(xy 193.802 -128.1176) (xy 194.310508 -128.1176) (xy 194.8942 -128.701292) (xy 251.46 -128.701292)
				(xy 254.280416 -125.880876) (xy 275.733764 -125.880876) (xy 275.75891 -125.906276) (xy 275.763736 -125.906276)
				(xy 278.559006 -128.701292) (xy 335.86801 -128.701292) (xy 335.868264 -128.7018) (xy 335.9912 -128.7018)
				(xy 337.566 -130.2766) (xy 337.566 -130.399536) (xy 337.566508 -130.39979) (xy 337.566508 -158.21152)
				(xy 337.9978 -158.642812) (xy 353.2378 -158.642812) (xy 353.5172 -158.363412) (xy 353.5172 -153.0858)
				(xy 356.1842 -150.4188) (xy 363.0422 -150.4188) (xy 365.379 -152.7556) (xy 365.379 -155.829) (xy 364.5916 -156.6164)
				(xy 364.5916 -158.3944) (xy 364.840012 -158.642812) (xy 370.642388 -158.642812) (xy 370.7892 -158.496)
				(xy 370.7892 -150.756112) (xy 370.755672 -150.722838) (xy 370.755672 -150.722076) (xy 368.969798 -148.936202)
				(xy 366.388904 -148.936202) (xy 354.7618 -137.309098) (xy 354.7618 -122.4026) (xy 358.1146 -119.0498)
				(xy 359.9688 -119.0498) (xy 360.538268 -118.480332) (xy 360.538268 -118.480078) (xy 360.6038 -118.4148)
				(xy 360.6038 -114.456464) (xy 362.61294 -112.447324) (xy 362.61294 -112.421924) (xy 362.994702 -112.040162)
				(xy 363.01807 -112.04194) (xy 363.160564 -111.8997) (xy 363.2708 -111.789464) (xy 363.2708 -102.3112)
				(xy 362.534708 -101.575108) (xy 362.482638 -101.575108) (xy 362.482384 -101.5746) (xy 353.3648 -101.5746)
				(xy 352.8822 -102.0572) (xy 352.8822 -105.3846) (xy 355.7778 -108.2802) (xy 356.3747 -108.2802)
				(xy 357.0351 -108.9406) (xy 357.0351 -112.7379)
			)
		)
		(polygon
			(pts
				(arc
					(start 349.354648 -23.047706)
					(mid 349.354648 -23.78075)
					(end 349.354648 -23.047706)
				)
			)
		)
		(polygon
			(pts
				(arc
					(start 182.510684 -126.707392)
					(mid 182.510684 -127.436372)
					(end 182.510684 -126.707392)
				)
			)
		)
		(polygon
			(pts
				(arc
					(start 28.616656 -32.352996)
					(mid 28.616656 -33.074864)
					(end 28.616656 -32.352996)
				)
			)
		)
		(polygon
			(pts
				(arc
					(start 11.1887 -127.714502)
					(mid 11.1887 -128.512062)
					(end 11.1887 -127.714502)
				)
			)
		)
		(polygon
			(pts
				(arc
					(start 462.840324 -59.194192)
					(mid 462.807883 -59.16894)
					(end 462.778348 -59.140344)
				)
				(arc
					(start 462.778348 -59.140344)
					(mid 462.712195 -59.108222)
					(end 462.641696 -59.129168)
				)
				(arc
					(start 462.641696 -59.129168)
					(mid 462.239479 -59.1526)
					(end 462.072736 -58.78576)
				)
				(arc
					(start 462.072736 -58.78576)
					(mid 462.050566 -58.702696)
					(end 461.97266 -58.66638)
				)
				(arc
					(start 460.257144 -58.66638)
					(mid 460.180109 -58.701737)
					(end 460.15656 -58.78322)
				)
				(arc
					(start 460.15656 -58.78322)
					(mid 459.804516 -59.19233)
					(end 459.452472 -58.78322)
				)
				(arc
					(start 459.452472 -58.78322)
					(mid 459.429024 -58.701651)
					(end 459.351888 -58.66638)
				)
				(arc
					(start 459.117446 -58.66638)
					(mid 459.025507 -58.724739)
					(end 459.039214 -58.83275)
				)
				(arc
					(start 459.039214 -58.83275)
					(mid 459.118503 -58.996831)
					(end 459.11262 -59.178952)
				)
				(arc
					(start 459.11262 -59.178952)
					(mid 459.126628 -59.26342)
					(end 459.20025 -59.307222)
				)
				(xy 462.845404 -59.307222) (xy 462.869534 -59.214512)
			)
		)
		(polygon
			(pts
				(arc
					(start 457.661772 -58.66638)
					(mid 457.584737 -58.701737)
					(end 457.561188 -58.78322)
				)
				(arc
					(start 457.561188 -58.78322)
					(mid 457.209144 -59.19233)
					(end 456.8571 -58.78322)
				)
				(arc
					(start 456.8571 -58.78322)
					(mid 456.833652 -58.701651)
					(end 456.756516 -58.66638)
				)
				(arc
					(start 455.98842 -58.66638)
					(mid 455.897902 -58.722339)
					(end 455.906886 -58.828432)
				)
				(arc
					(start 455.906886 -58.828432)
					(mid 455.976623 -58.994676)
					(end 455.962258 -59.17438)
				)
				(arc
					(start 455.962258 -59.17438)
					(mid 455.973588 -59.261509)
					(end 456.048618 -59.307222)
				)
				(arc
					(start 457.57592 -59.307222)
					(mid 457.649243 -59.264039)
					(end 457.664058 -59.180222)
				)
				(arc
					(start 457.664058 -59.180222)
					(mid 457.661281 -58.997421)
					(end 457.743814 -58.834274)
				)
				(arc
					(start 457.743814 -58.834274)
					(mid 457.759188 -58.725648)
					(end 457.666852 -58.66638)
				)
			)
		)
		(polygon
			(pts
				(arc
					(start 478.54108 -60.139326)
					(mid 478.458887 -60.097247)
					(end 478.376488 -60.139072)
				)
				(arc
					(start 478.376488 -60.139072)
					(mid 478.146947 -60.288264)
					(end 477.876616 -60.245244)
				)
				(arc
					(start 477.876616 -60.245244)
					(mid 477.775084 -60.245205)
					(end 477.724216 -60.333128)
				)
				(xy 477.724216 -60.773564) (xy 478.223326 -61.272928) (xy 479.007424 -61.272928)
				(arc
					(start 479.007424 -60.385452)
					(mid 478.970031 -60.316459)
					(end 478.894648 -60.294774)
				)
				(arc
					(start 478.894648 -60.294774)
					(mid 478.696707 -60.265138)
					(end 478.54108 -60.139326)
				)
			)
		)
		(polygon
			(pts
				(arc
					(start 447.165476 -58.799476)
					(mid 447.151132 -58.708355)
					(end 447.068956 -58.66638)
				)
				(arc
					(start 445.927226 -58.66638)
					(mid 445.848607 -58.703625)
					(end 445.827658 -58.788046)
				)
				(arc
					(start 445.827658 -58.788046)
					(mid 445.815082 -58.974513)
					(end 445.709802 -59.128914)
				)
				(arc
					(start 445.709802 -59.128914)
					(mid 445.678886 -59.236514)
					(end 445.765682 -59.307222)
				)
				(arc
					(start 447.165222 -59.307222)
					(mid 447.24929 -59.244128)
					(end 447.232532 -59.140344)
				)
				(arc
					(start 447.232532 -59.140344)
					(mid 447.154653 -58.978643)
					(end 447.165476 -58.799476)
				)
			)
		)
		(polygon
			(pts
				(arc
					(start 454.348596 -58.809382)
					(mid 454.341071 -58.712728)
					(end 454.255886 -58.66638)
				)
				(arc
					(start 453.154034 -58.66638)
					(mid 453.075415 -58.703625)
					(end 453.054466 -58.788046)
				)
				(arc
					(start 453.054466 -58.788046)
					(mid 453.041478 -58.974485)
					(end 452.935848 -59.12866)
				)
				(arc
					(start 452.935848 -59.12866)
					(mid 452.904598 -59.236352)
					(end 452.991474 -59.307222)
				)
				(arc
					(start 454.302368 -59.307222)
					(mid 454.383954 -59.249781)
					(end 454.377044 -59.15025)
				)
				(arc
					(start 454.377044 -59.15025)
					(mid 454.319269 -58.983461)
					(end 454.348596 -58.809382)
				)
			)
		)
		(polygon
			(pts
				(arc
					(start 452.355966 -58.788046)
					(mid 452.334994 -58.703644)
					(end 452.256398 -58.66638)
				)
				(arc
					(start 450.462904 -58.66638)
					(mid 450.382453 -58.70626)
					(end 450.36486 -58.794396)
				)
				(arc
					(start 450.36486 -58.794396)
					(mid 450.365593 -58.976539)
					(end 450.276214 -59.135264)
				)
				(arc
					(start 450.276214 -59.135264)
					(mid 450.253485 -59.240815)
					(end 450.338698 -59.307222)
				)
				(arc
					(start 452.418958 -59.307222)
					(mid 452.505803 -59.236342)
					(end 452.474584 -59.12866)
				)
				(arc
					(start 452.474584 -59.12866)
					(mid 452.36896 -58.974483)
					(end 452.355966 -58.788046)
				)
			)
		)
		(polygon
			(pts
				(arc
					(start 472.283028 -58.569352)
					(mid 472.231799 -58.459333)
					(end 472.111832 -58.476896)
				)
				(xy 471.922094 -58.66638)
				(arc
					(start 464.407758 -58.66638)
					(mid 464.321969 -58.713951)
					(end 464.316318 -58.811922)
				)
				(arc
					(start 464.316318 -58.811922)
					(mid 464.353533 -58.985944)
					(end 464.307682 -59.15787)
				)
				(arc
					(start 464.307682 -59.15787)
					(mid 464.307341 -59.253752)
					(end 464.38693 -59.307222)
				)
				(arc
					(start 467.228936 -59.307222)
					(mid 467.849712 -58.956188)
					(end 468.470488 -59.307222)
				)
				(xy 469.878918 -59.307222) (xy 473.105988 -62.534292)
				(arc
					(start 473.241116 -62.534292)
					(mid 473.33064 -62.452847)
					(end 473.278708 -62.343538)
				)
				(arc
					(start 473.278708 -62.343538)
					(mid 472.521391 -61.623884)
					(end 472.242388 -60.6171)
				)
				(arc
					(start 472.242388 -58.965846)
					(mid 472.252592 -58.766563)
					(end 472.283028 -58.569352)
				)
			)
		)
		(polygon
			(pts
				(xy 476.631 -61.226192) (xy 476.631 -58.670444)
				(arc
					(start 476.231204 -58.270394)
					(mid 476.106495 -58.255424)
					(end 476.062548 -58.37301)
				)
				(arc
					(start 476.062548 -58.37301)
					(mid 476.131333 -58.665632)
					(end 476.154496 -58.965338)
				)
				(arc
					(start 476.154496 -60.6171)
					(mid 475.875531 -61.623907)
					(end 475.118176 -62.343538)
				)
				(arc
					(start 475.118176 -62.343538)
					(mid 475.06626 -62.452844)
					(end 475.155768 -62.534292)
				)
				(xy 478.740216 -62.534292)
				(arc
					(start 478.827592 -62.446916)
					(mid 478.832389 -62.393718)
					(end 478.786952 -62.365636)
				)
				(xy 477.770698 -62.365636)
			)
		)
		(polygon
			(pts
				(arc
					(start 175.28032 -23.31974)
					(mid 175.28032 -24.008588)
					(end 175.28032 -23.31974)
				)
			)
		)
		(polygon
			(pts
				(arc
					(start 329.661012 -124.873766)
					(mid 329.661012 -125.646434)
					(end 329.661012 -124.873766)
				)
			)
		)
		(polygon
			(pts
				(xy 495.940334 -19.342608)
				(arc
					(start 495.460782 -19.342608)
					(mid 495.371615 -19.422324)
					(end 495.420142 -19.531584)
				)
				(arc
					(start 495.420142 -19.531584)
					(mid 495.715865 -19.789974)
					(end 495.891566 -20.141184)
				)
				(arc
					(start 495.891566 -20.141184)
					(mid 495.968861 -20.213794)
					(end 496.068604 -20.178014)
				)
				(arc
					(start 496.068604 -20.178014)
					(mid 496.208047 -20.067576)
					(end 496.381278 -20.027138)
				)
				(arc
					(start 496.381278 -20.027138)
					(mid 496.472269 -19.968645)
					(end 496.459002 -19.861276)
				)
			)
		)
		(polygon
			(pts
				(arc
					(start 365.040926 -156.415994)
					(mid 364.984517 -156.321372)
					(end 364.875064 -156.333698)
				)
				(xy 364.592108 -156.616654)
				(arc
					(start 364.592108 -157.752796)
					(mid 364.66051 -157.838835)
					(end 364.767114 -157.812232)
				)
				(arc
					(start 364.767114 -157.812232)
					(mid 364.861735 -157.739016)
					(end 364.974378 -157.698694)
				)
				(arc
					(start 364.974378 -157.698694)
					(mid 365.0523 -157.629264)
					(end 365.027972 -157.527752)
				)
				(arc
					(start 365.027972 -157.527752)
					(mid 364.928427 -157.175213)
					(end 365.171736 -156.901388)
				)
				(arc
					(start 365.171736 -156.901388)
					(mid 365.238476 -156.818753)
					(end 365.195104 -156.72181)
				)
				(arc
					(start 365.195104 -156.72181)
					(mid 365.078862 -156.588651)
					(end 365.040926 -156.415994)
				)
			)
		)
	)
	(zone
		(net "P12V")
		(layer "In7.Cu")
		(hatch none 0.5)
		(connect_pads
			(clearance 0.5)
		)
		(min_thickness 0.25)
		(fill yes
			(thermal_gap 0.5)
			(thermal_bridge_width 0.5)
			(island_removal_mode 0)
		)
		(polygon
			(pts
				(xy 416.433 -4.699) (xy 403.187154 -4.699) (xy 402.355558 -5.530596) (xy 402.355558 -10.0584) (xy 403.447758 -11.1506)
				(xy 468.6681 -11.1506) (xy 474.0529 -11.1506) (xy 474.1926 -11.0109) (xy 474.1926 -5.537962) (xy 473.731336 -5.076444)
				(xy 467.548214 -5.076444) (xy 467.1822 -5.442458) (xy 467.1822 -6.7564) (xy 466.1662 -7.7724) (xy 449.8086 -7.7724)
				(xy 446.7352 -4.699)
			)
		)
	)
	(zone
		(net "P3V3_STBY")
		(layer "In7.Cu")
		(hatch none 0.5)
		(connect_pads
			(clearance 0.5)
		)
		(min_thickness 0.25)
		(fill yes
			(thermal_gap 0.5)
			(thermal_bridge_width 0.5)
			(island_removal_mode 0)
		)
		(polygon
			(pts
				(xy 365.071406 5.534406) (xy 364.841536 5.304536) (xy 364.841536 -0.801624) (xy 365.16437 -1.124458)
				(xy 365.16437 -2.256028) (xy 364.617 -2.803398) (xy 364.617 -6.6802) (xy 373.0752 -15.1384) (xy 373.0752 -17.548606)
				(xy 373.7356 -18.209006) (xy 393.2809 -18.209006) (xy 394.746226 -16.74368) (xy 404.139146 -16.74368)
				(xy 404.560024 -17.164558) (xy 404.560024 -22.790404) (xy 402.522436 -24.827992) (xy 402.522436 -41.882314)
				(xy 403.062948 -42.422826) (xy 408.588972 -42.422826) (xy 408.601672 -42.435526) (xy 411.232096 -42.435526)
				(xy 411.560518 -42.763948) (xy 411.560518 -44.070778) (xy 411.841188 -44.351448) (xy 423.25544 -44.351448)
				(xy 426.468032 -47.56404) (xy 429.47844 -47.56404) (xy 430.345088 -46.697392) (xy 430.345088 -46.25594)
				(xy 430.345088 -43.790108) (xy 430.586134 -43.549062) (xy 432.361594 -43.549062) (xy 434.868066 -43.549062)
				(xy 436.174134 -44.85513) (xy 449.240148 -44.85513) (xy 450.952616 -43.142662) (xy 451.335902 -43.142662)
				(xy 451.341236 -43.137328) (xy 466.81009 -43.137328) (xy 467.679278 -42.26814) (xy 467.679278 -36.2839)
				(xy 469.211914 -34.751264) (xy 469.211914 -27.468576) (xy 471.537284 -25.143206) (xy 471.537284 -20.613878)
				(xy 472.326462 -19.8247) (xy 474.099382 -19.8247) (xy 475.572582 -18.3515) (xy 485.3051 -18.3515)
				(xy 486.0544 -19.1008) (xy 496.32108 -19.1008) (xy 497.77015 -20.54987) (xy 497.77015 -24.88565)
				(xy 491.085886 -31.569914) (xy 491.085886 -36.887658) (xy 490.55528 -37.418264) (xy 487.486452 -37.418264)
				(xy 486.95229 -37.952426) (xy 486.95229 -43.298364) (xy 486.947972 -43.302682) (xy 486.947972 -44.522898)
				(xy 479.270568 -52.200302) (xy 479.270568 -61.65596) (xy 479.82378 -62.209172) (xy 498.909848 -62.209172)
				(xy 499.02872 -62.0903) (xy 499.02872 -61.24448) (xy 499.47322 -60.79998) (xy 501.397016 -60.79998)
				(xy 501.536716 -60.66028) (xy 501.536716 -53.495956) (xy 501.42902 -53.38826) (xy 499.45798 -53.38826)
				(xy 499.01602 -52.9463) (xy 499.01602 -52.1589) (xy 499.38178 -51.79314) (xy 501.457976 -51.79314)
				(xy 501.536716 -51.7144) (xy 501.536716 -14.938756) (xy 501.06072 -14.46276) (xy 483.94366 -14.46276)
				(xy 483.39248 -13.91158)
				(arc
					(start 483.39248 0.500126)
					(mid 483.414449 0.704068)
					(end 483.479348 0.898652)
				)
				(xy 483.3747 1.0033) (xy 483.3747 2.88798) (xy 483.96906 3.48234) (xy 487.41838 3.48234) (xy 487.59618 3.66014)
				(xy 487.59618 5.41782) (xy 487.479594 5.534406) (xy 479.803206 5.534406) (xy 479.4504 5.1816) (xy 479.4504 0.3048)
				(xy 476.631 -2.5146) (xy 469.9 -2.5146) (xy 467.317836 0.067564) (xy 467.317836 5.34797) (xy 467.1314 5.534406)
			)
		)
		(polygon
			(pts
				(arc
					(start 490.675676 -18.302224)
					(mid 490.6391 -18.286694)
					(end 490.602524 -18.302224)
				)
				(arc
					(start 490.591856 -18.312892)
					(mid 490.576326 -18.349648)
					(end 490.59211 -18.386298)
				)
				(arc
					(start 490.59211 -18.386298)
					(mid 490.717538 -18.653801)
					(end 490.62894 -18.9357)
				)
				(arc
					(start 490.62894 -18.9357)
					(mid 490.614557 -19.038517)
					(end 490.698028 -19.100292)
				)
				(arc
					(start 491.243366 -19.100292)
					(mid 491.326883 -19.038536)
					(end 491.312454 -18.9357)
				)
				(arc
					(start 491.312454 -18.9357)
					(mid 491.223677 -18.6546)
					(end 491.348014 -18.387314)
				)
				(arc
					(start 491.348014 -18.387314)
					(mid 491.363544 -18.350738)
					(end 491.348014 -18.314162)
				)
				(arc
					(start 491.336076 -18.302224)
					(mid 491.2995 -18.286694)
					(end 491.262924 -18.302224)
				)
				(arc
					(start 491.262924 -18.302224)
					(mid 490.9693 -18.427431)
					(end 490.675676 -18.302224)
				)
			)
		)
		(polygon
			(pts
				(arc
					(start 483.391972 -11.388852)
					(mid 483.338904 -11.309477)
					(end 483.243382 -11.309096)
				)
				(arc
					(start 483.243382 -11.309096)
					(mid 482.908897 -11.40638)
					(end 482.56317 -11.363706)
				)
				(arc
					(start 482.56317 -11.363706)
					(mid 482.467253 -11.380574)
					(end 482.429566 -11.470386)
				)
				(arc
					(start 482.429566 -11.470386)
					(mid 482.43382 -11.58555)
					(end 482.422708 -11.700256)
				)
				(arc
					(start 482.422708 -11.700256)
					(mid 482.458247 -11.795014)
					(end 482.55809 -11.812016)
				)
				(arc
					(start 482.55809 -11.812016)
					(mid 482.905572 -11.764346)
					(end 483.240842 -11.867388)
				)
				(arc
					(start 483.240842 -11.867388)
					(mid 483.337582 -11.869195)
					(end 483.391972 -11.789156)
				)
			)
		)
		(polygon
			(pts
				(arc
					(start 483.391972 -9.388856)
					(mid 483.338904 -9.309481)
					(end 483.243382 -9.3091)
				)
				(arc
					(start 483.243382 -9.3091)
					(mid 482.908897 -9.406384)
					(end 482.56317 -9.36371)
				)
				(arc
					(start 482.56317 -9.36371)
					(mid 482.467253 -9.380578)
					(end 482.429566 -9.47039)
				)
				(arc
					(start 482.429566 -9.47039)
					(mid 482.43382 -9.585554)
					(end 482.422708 -9.70026)
				)
				(arc
					(start 482.422708 -9.70026)
					(mid 482.458247 -9.795018)
					(end 482.55809 -9.81202)
				)
				(arc
					(start 482.55809 -9.81202)
					(mid 482.905572 -9.76435)
					(end 483.240842 -9.867392)
				)
				(arc
					(start 483.240842 -9.867392)
					(mid 483.337582 -9.869199)
					(end 483.391972 -9.78916)
				)
			)
		)
		(polygon
			(pts
				(arc
					(start 483.391972 -5.271008)
					(mid 483.337595 -5.190943)
					(end 483.240842 -5.192776)
				)
				(arc
					(start 483.240842 -5.192776)
					(mid 482.878878 -5.297475)
					(end 482.50856 -5.227828)
				)
				(arc
					(start 482.50856 -5.227828)
					(mid 482.403723 -5.241258)
					(end 482.36759 -5.340604)
				)
				(arc
					(start 482.36759 -5.340604)
					(mid 482.382861 -5.473343)
					(end 482.376226 -5.606796)
				)
				(arc
					(start 482.376226 -5.606796)
					(mid 482.414718 -5.700648)
					(end 482.515164 -5.714492)
				)
				(arc
					(start 482.515164 -5.714492)
					(mid 482.883326 -5.652177)
					(end 483.243382 -5.751068)
				)
				(arc
					(start 483.243382 -5.751068)
					(mid 483.338946 -5.750766)
					(end 483.391972 -5.671312)
				)
			)
		)
		(polygon
			(pts
				(xy 446.821306 -4.401312) (xy 403.079712 -4.401312) (xy 402.540216 -4.940808) (xy 402.540216 -4.968748)
				(xy 402.019262 -5.489702) (xy 402.019262 -10.27684) (xy 403.201124 -11.458702) (xy 474.146372 -11.458702)
				(xy 474.46184 -11.143234) (xy 474.46184 -5.26161) (xy 474.461586 -5.261356) (xy 474.461586 -5.241798)
				(xy 473.977462 -4.757674) (xy 467.2965 -4.757674) (xy 467.090252 -4.963922) (xy 467.090252 -4.979416)
				(xy 466.92058 -5.149088) (xy 466.92058 -6.501638) (xy 465.919058 -7.50316) (xy 449.923154 -7.50316)
			)
		)
		(polygon
			(pts
				(arc
					(start 483.391972 -3.211068)
					(mid 483.337595 -3.131003)
					(end 483.240842 -3.132836)
				)
				(arc
					(start 483.240842 -3.132836)
					(mid 482.905576 -3.235923)
					(end 482.55809 -3.188208)
				)
				(arc
					(start 482.55809 -3.188208)
					(mid 482.458149 -3.205091)
					(end 482.422708 -3.299968)
				)
				(arc
					(start 482.422708 -3.299968)
					(mid 482.433816 -3.414674)
					(end 482.429566 -3.529838)
				)
				(arc
					(start 482.429566 -3.529838)
					(mid 482.467241 -3.619664)
					(end 482.56317 -3.636518)
				)
				(arc
					(start 482.56317 -3.636518)
					(mid 482.908899 -3.593819)
					(end 483.243382 -3.691128)
				)
				(arc
					(start 483.243382 -3.691128)
					(mid 483.338946 -3.690826)
					(end 483.391972 -3.611372)
				)
			)
		)
		(polygon
			(pts
				(arc
					(start 483.391972 -1.1811)
					(mid 483.337595 -1.101035)
					(end 483.240842 -1.102868)
				)
				(arc
					(start 483.240842 -1.102868)
					(mid 482.878878 -1.207567)
					(end 482.50856 -1.13792)
				)
				(arc
					(start 482.50856 -1.13792)
					(mid 482.403723 -1.15135)
					(end 482.36759 -1.250696)
				)
				(arc
					(start 482.36759 -1.250696)
					(mid 482.383385 -1.410208)
					(end 482.36759 -1.56972)
				)
				(arc
					(start 482.36759 -1.56972)
					(mid 482.403701 -1.669093)
					(end 482.50856 -1.682496)
				)
				(arc
					(start 482.50856 -1.682496)
					(mid 482.87888 -1.612813)
					(end 483.240842 -1.717548)
				)
				(arc
					(start 483.240842 -1.717548)
					(mid 483.337582 -1.719355)
					(end 483.391972 -1.639316)
				)
			)
		)
		(polygon
			(pts
				(arc
					(start 483.446836 0.819404)
					(mid 483.406802 0.927079)
					(end 483.291896 0.928624)
				)
				(arc
					(start 483.291896 0.928624)
					(mid 482.908809 0.794446)
					(end 482.50856 0.862076)
				)
				(arc
					(start 482.50856 0.862076)
					(mid 482.403723 0.848646)
					(end 482.36759 0.7493)
				)
				(arc
					(start 482.36759 0.7493)
					(mid 482.383385 0.589788)
					(end 482.36759 0.430276)
				)
				(arc
					(start 482.36759 0.430276)
					(mid 482.403701 0.330903)
					(end 482.50856 0.3175)
				)
				(arc
					(start 482.50856 0.3175)
					(mid 482.87888 0.387183)
					(end 483.240842 0.282448)
				)
				(arc
					(start 483.240842 0.282448)
					(mid 483.337582 0.280641)
					(end 483.391972 0.36068)
				)
				(arc
					(start 483.391972 0.500126)
					(mid 483.40581 0.662101)
					(end 483.446836 0.819404)
				)
			)
		)
	)
	(zone
		(net "GND")
		(layer "In7.Cu")
		(hatch none 0.5)
		(connect_pads
			(clearance 0.5)
		)
		(min_thickness 0.25)
		(fill yes
			(thermal_gap 0.5)
			(thermal_bridge_width 0.5)
			(island_removal_mode 0)
		)
		(polygon
			(pts
				(xy 97.1169 -62.9793) (xy 97.917 -63.7794) (xy 103.505 -63.7794) (xy 103.8479 -63.4365) (xy 103.8479 -52.2351)
				(xy 103.8479 -50.35804) (xy 102.3493 -48.85944) (xy 33.78454 -48.85944) (xy 33.1724 -49.47158) (xy 33.1724 -52.324)
				(xy 33.1724 -53.505354) (xy 33.173416 -53.505608) (xy 33.173416 -54.207156) (xy 33.1724 -54.20741)
				(xy 33.1724 -54.7116) (xy 32.7152 -55.1688) (xy 31.712916 -55.1688) (xy 31.636208 -55.245508) (xy 31.5722 -55.309516)
				(xy 31.5722 -57.009284) (xy 31.636208 -57.073292) (xy 32.968692 -57.073292) (xy 33.1724 -57.277)
				(xy 33.1724 -61.633354) (xy 33.173416 -61.63437) (xy 33.173416 -62.335156) (xy 33.1724 -62.33541)
				(xy 33.1724 -63.208408) (xy 32.9946 -63.386208) (xy 31.623508 -63.386208) (xy 31.623508 -65.213992)
				(xy 32.955992 -65.213992) (xy 33.1724 -65.4304) (xy 33.1724 -69.761354) (xy 33.1724 -70.46341) (xy 33.1724 -71.336408)
				(xy 32.9946 -71.514208) (xy 31.623508 -71.514208) (xy 31.5722 -71.565516) (xy 31.5722 -73.277984)
				(xy 31.623508 -73.329292) (xy 32.892492 -73.329292) (xy 33.1724 -73.6092) (xy 33.1724 -77.889354)
				(arc
					(start 33.208214 -77.900276)
					(mid 33.458513 -78.240382)
					(end 33.208214 -78.580488)
				)
				(xy 33.1724 -78.59141) (xy 33.1724 -79.489808) (xy 33.02 -79.642208) (xy 31.636208 -79.642208) (xy 31.5722 -79.706216)
				(xy 31.5722 -81.393284) (xy 31.636208 -81.457292) (xy 32.816292 -81.457292) (xy 33.1724 -81.8134)
				(xy 33.1724 -86.017354) (xy 33.1724 -86.71941) (xy 33.1724 -87.605108) (xy 32.9946 -87.782908) (xy 31.636208 -87.782908)
				(xy 31.5722 -87.846916) (xy 31.5722 -89.533984) (xy 31.636208 -89.597992) (xy 32.930592 -89.597992)
				(xy 33.1724 -89.8398) (xy 33.1724 -92.734892) (xy 33.4391 -93.001592) (xy 42.9895 -93.001592) (xy 43.210226 -92.780866)
				(xy 43.210226 -53.515006) (xy 43.505882 -53.21935) (xy 49.25695 -53.21935) (xy 58.9534 -62.9158)
				(xy 64.563244 -62.912244) (xy 64.5668 -62.9158) (xy 73.624948 -62.9158) (xy 73.6346 -62.906148)
				(xy 77.254608 -62.903608) (xy 77.2668 -62.903608) (xy 97.041208 -62.903608)
			)
		)
	)
	(zone
		(net "PVCCIO_CPU1")
		(layer "In7.Cu")
		(hatch none 0.5)
		(connect_pads
			(clearance 0.5)
		)
		(min_thickness 0.25)
		(fill yes
			(thermal_gap 0.5)
			(thermal_bridge_width 0.5)
			(island_removal_mode 0)
		)
		(polygon
			(pts
				(xy 160.259268 -55.74284) (xy 158.938976 -57.063132) (xy 158.938976 -58.686446) (xy 156.120084 -61.505084)
				(xy 156.120084 -61.505338) (xy 155.2448 -62.380622) (xy 141.552422 -76.073) (xy 133.094222 -84.5312)
				(xy 132.992622 -84.6328) (xy 128.5748 -84.6328) (xy 127.9652 -84.6328) (xy 127.480568 -85.117432)
				(xy 126.863856 -85.734144) (xy 126.746 -85.852) (xy 126.3904 -85.852) (xy 125.927358 -86.315042)
				(xy 125.3744 -86.868) (xy 125.3744 -89.790016) (xy 125.386592 -89.802208) (xy 125.386592 -90.208608)
				(xy 124.2949 -91.3003) (xy 124.230638 -91.364562) (xy 124.0282 -91.567) (xy 123.981464 -91.613736)
				(xy 122.576336 -91.613736) (xy 122.572272 -91.6178) (xy 122.1232 -91.6178) (xy 121.9454 -91.6178)
				(xy 120.9675 -90.6399) (xy 120.8024 -90.4748) (xy 120.6754 -90.3478) (xy 120.6754 -84.2772) (xy 120.6754 -83.9978)
				(xy 121.119646 -83.553554) (xy 121.6025 -83.0707) (xy 121.6025 -78.9559) (xy 120.523 -77.8764) (xy 120.2944 -77.8764)
				(arc
					(start 119.66575 -77.8764)
					(mid 119.357902 -78.053597)
					(end 119.050054 -77.8764)
				)
				(xy 113.411 -77.8764) (xy 113.0554 -78.232) (xy 113.0554 -79.9592) (xy 115.5954 -82.4992) (xy 115.731544 -82.635344)
				(xy 115.731544 -87.062056) (xy 115.740434 -87.0712) (xy 115.740434 -88.774778) (xy 115.740434 -89.404698)
				(xy 115.740434 -95.699834) (xy 115.740434 -102.430834) (xy 116.758466 -103.448866) (xy 123.489466 -103.448866)
				(xy 136.418574 -103.448866) (xy 137.165334 -103.448866) (xy 142.5067 -98.1075) (xy 160.61436 -79.99984)
				(xy 161.5186 -79.0956) (xy 161.5186 -74.6506) (xy 166.497 -69.6722) (xy 166.9034 -69.2658) (xy 166.9034 -57.8358)
				(xy 166.497 -57.4294) (xy 164.81044 -55.74284)
			)
		)
	)
	(zone
		(net "PVDDQ_GHJ")
		(layer "In7.Cu")
		(hatch none 0.5)
		(connect_pads
			(clearance 0.5)
		)
		(min_thickness 0.25)
		(fill yes
			(thermal_gap 0.5)
			(thermal_bridge_width 0.5)
			(island_removal_mode 0)
		)
		(polygon
			(pts
				(xy 17.5006 5.5372) (xy 16.5608 4.5974) (xy 16.5608 -4.431792) (xy 14.6304 -6.362192) (xy 14.6304 -7.7978)
				(xy 14.6304 -19.9136) (xy 15.6845 -20.9677) (xy 17.6403 -20.9677) (xy 17.653 -20.955) (xy 19.939 -20.955)
				(xy 21.407628 -22.423628)
				(arc
					(start 21.417788 -22.427692)
					(mid 21.551583 -22.514369)
					(end 21.63826 -22.648164)
				)
				(xy 21.642324 -22.658324) (xy 23.241 -24.257) (xy 97.292668 -24.257)
				(arc
					(start 97.305368 -24.22525)
					(mid 97.635568 -24.00249)
					(end 97.965768 -24.22525)
				)
				(xy 97.978468 -24.257) (xy 99.256088 -24.257) (xy 99.433634 -24.434546) (xy 99.433634 -25.006808)
				(xy 101.732588 -27.305762) (xy 109.111034 -27.305762) (xy 112.159796 -24.257) (xy 156.3624 -24.257)
				(xy 156.6291 -23.9903) (xy 159.5247 -23.9903) (xy 160.2994 -23.2156) (xy 160.2994 -11.9888) (xy 163.7157 -8.5725)
				(xy 166.9161 -8.5725) (xy 168.5417 -8.5725) (xy 169.4688 -7.6454) (xy 169.4688 -3.2004) (xy 169.4688 -0.2794)
				(xy 169.4688 -0.1524) (xy 168.6814 0.635) (xy 168.6814 5.2832) (xy 168.5544 5.4102) (xy 168.4274 5.5372)
				(xy 167.4876 5.5372) (xy 166.2176 5.5372) (xy 166.2049 5.5499) (xy 166.1922 5.5372) (xy 116.1542 5.5372)
				(xy 102.8954 5.5372) (xy 102.8827 5.5499) (xy 102.87 5.5372)
			)
		)
	)
	(zone
		(net "PVSA_CPU0")
		(layer "In7.Cu")
		(hatch none 0.5)
		(connect_pads
			(clearance 0.5)
		)
		(min_thickness 0.25)
		(fill yes
			(thermal_gap 0.5)
			(thermal_bridge_width 0.5)
			(island_removal_mode 0)
		)
		(polygon
			(pts
				(xy 244.908832 -80.8228) (xy 243.8146 -80.8228) (xy 237.898432 -80.8228) (xy 237.783116 -80.938116)
				(xy 234.571032 -84.1502) (xy 234.570016 -84.151216) (xy 234.545632 -84.1756) (xy 233.299 -84.1756)
				(xy 233.081322 -84.1756)
				(arc
					(start 233.078274 -84.175854)
					(mid 233.036618 -84.178299)
					(end 232.994962 -84.175854)
				)
				(xy 232.991914 -84.1756) (xy 232.6386 -84.1756) (xy 231.5464 -84.1756) (xy 228.094032 -84.1756)
				(xy 219.508832 -92.7608) (xy 209.323432 -92.7608) (xy 209.322416 -92.761816) (xy 208.685384 -92.761816)
				(xy 208.407 -93.0402) (xy 208.00822 -93.43898) (xy 208.00822 -102.72522) (xy 208.407 -103.124) (xy 208.661 -103.378)
				(xy 209.374232 -103.378) (xy 221.693232 -103.378) (xy 232.462832 -92.6084) (xy 235.0516 -92.6084)
				(xy 235.4453 -92.2147) (xy 239.4966 -88.1634) (xy 245.543832 -88.1634) (xy 245.7958 -88.1634) (xy 247.7516 -86.2076)
				(xy 257.2512 -86.2076) (xy 257.51282 -85.94598) (xy 260.05282 -85.94598) (xy 261.6835 -84.3153)
				(xy 261.6835 -82.8421) (xy 259.919216 -81.077816) (xy 251.001784 -81.077816) (xy 250.513596 -80.589628)
				(xy 250.513596 -79.548228) (xy 250.328684 -79.363316) (xy 246.4308 -79.363316) (xy 244.996208 -80.797908)
				(xy 244.971316 -80.8228)
			)
		)
	)
	(zone
		(layer "In7.Cu")
		(hatch none 0.5)
		(connect_pads
			(clearance 0)
		)
		(min_thickness 0.25)
		(keepout
			(tracks not_allowed)
			(vias allowed)
			(pads allowed)
			(copperpour not_allowed)
			(footprints allowed)
		)
		(placement
			(enabled no)
			(sheetname "")
		)
		(fill
			(thermal_gap 0.5)
			(thermal_bridge_width 0.5)
			(island_removal_mode 0)
		)
		(polygon
			(pts
				(arc
					(start 182.866792 -127.071882)
					(mid 182.154576 -127.071882)
					(end 182.866792 -127.071882)
				)
			)
		)
	)
	(zone
		(net "PVCCIOMCP_CPU1")
		(layer "In7.Cu")
		(hatch none 0.5)
		(connect_pads
			(clearance 0.5)
		)
		(min_thickness 0.25)
		(fill yes
			(thermal_gap 0.5)
			(thermal_bridge_width 0.5)
			(island_removal_mode 0)
		)
		(polygon
			(pts
				(xy 158.254192 -103.503984) (xy 155.78455 -105.973626) (xy 155.78455 -107.548426) (xy 156.249878 -108.013754)
				(xy 191.172846 -108.013754) (xy 191.3382 -107.8484) (xy 191.6684 -107.8484) (xy 193.4083 -106.1085)
				(xy 193.4083 -103.7209) (xy 193.191384 -103.503984) (xy 186.434984 -103.503984) (xy 186.422792 -103.491792)
				(xy 184.720992 -103.491792) (xy 184.7088 -103.503984)
			)
		)
	)
	(zone
		(net "GND")
		(layer "In7.Cu")
		(hatch none 0.5)
		(connect_pads
			(clearance 0.5)
		)
		(min_thickness 0.25)
		(fill yes
			(thermal_gap 0.5)
			(thermal_bridge_width 0.5)
			(island_removal_mode 0)
		)
		(polygon
			(pts
				(xy 168.148 -62.6745) (xy 168.148 -68.5546) (xy 162.052 -74.6506) (xy 162.052 -78.68666) (xy 146.91106 -93.8276)
				(xy 146.91106 -94.32798) (xy 147.12442 -94.54134) (xy 161.72434 -94.54134) (xy 163.0172 -95.8342)
				(xy 181.356 -95.8342) (xy 182.17388 -96.65208) (xy 182.17388 -102.58044) (xy 182.91302 -103.31958)
				(xy 193.39052 -103.31958) (xy 193.92646 -103.85552) (xy 199.832214 -103.85552) (xy 199.837294 -103.8606)
				(xy 206.5655 -103.8606) (xy 206.57185 -103.85425) (xy 207.37703 -103.85425) (xy 207.74152 -103.48976)
				(xy 207.74152 -93.830648) (xy 207.45958 -93.548708) (xy 199.644762 -93.548708) (xy 199.545448 -93.648022)
				(xy 199.545448 -100.634292) (xy 198.72198 -101.45776) (xy 194.5259 -101.45776) (xy 193.69024 -100.6221)
				(xy 189.94882 -100.6221) (xy 188.1886 -98.86188) (xy 188.1886 -63.3222) (xy 188.030104 -63.163704)
				(xy 188.030104 -63.1444) (xy 187.725558 -62.839854) (xy 187.357004 -62.4713) (xy 168.3512 -62.4713)
			)
		)
	)
	(zone
		(net "P12V")
		(layer "In7.Cu")
		(hatch none 0.5)
		(connect_pads
			(clearance 0.5)
		)
		(min_thickness 0.25)
		(fill yes
			(thermal_gap 0.5)
			(thermal_bridge_width 0.5)
			(island_removal_mode 0)
		)
		(polygon
			(pts
				(xy 469.7476 -59.563) (xy 472.99753 -62.81293) (xy 477.67113 -62.81293) (xy 478.535746 -62.81293)
				(xy 478.930208 -63.207392) (xy 478.930208 -67.094354) (xy 478.621344 -67.403218) (xy 478.580704 -67.412362)
				(xy 469.037162 -67.412362) (xy 468.1982 -66.5734) (xy 465.6582 -64.0334) (xy 441.8076 -64.0334)
				(xy 441.2996 -63.5254) (xy 441.2996 -59.817) (xy 441.5536 -59.563)
			)
		)
	)
	(zone
		(net "VR_FET_SW_P12V_STBY_PVCCIN_CPU0")
		(layer "In7.Cu")
		(hatch none 0.5)
		(connect_pads
			(clearance 0.5)
		)
		(min_thickness 0.25)
		(fill yes
			(thermal_gap 0.5)
			(thermal_bridge_width 0.5)
			(island_removal_mode 0)
		)
		(polygon
			(pts
				(xy 187.075318 -55.5244) (xy 187.075318 -59.283854) (xy 187.984384 -60.19292) (xy 187.984384 -62.305184)
				(xy 188.5696 -62.8904) (xy 188.5696 -98.7552) (xy 190.0936 -100.2792) (xy 193.802 -100.2792) (xy 194.7926 -101.2698)
				(xy 197.7898 -101.2698) (xy 197.795388 -101.264212) (xy 198.342758 -101.264212) (xy 199.12838 -100.47859)
				(xy 199.12838 -55.989474) (xy 196.710046 -53.57114) (xy 195.772786 -53.57114) (xy 195.516246 -53.3146)
				(xy 195.4022 -53.3146) (xy 193.2686 -55.4482) (xy 187.151518 -55.4482)
			)
		)
	)
	(zone
		(net "PVCCIN_CPU1")
		(layer "In7.Cu")
		(hatch none 0.5)
		(connect_pads
			(clearance 0.5)
		)
		(min_thickness 0.25)
		(fill yes
			(thermal_gap 0.5)
			(thermal_bridge_width 0.5)
			(island_removal_mode 0)
		)
		(polygon
			(pts
				(xy 43.801538 -53.546756) (xy 43.6626 -53.685694) (xy 43.6626 -92.2274) (xy 43.815 -92.3798) (xy 54.4576 -92.3798)
				(xy 62.941454 -83.8962) (xy 66.3448 -83.8962) (xy 69.215 -83.8962) (xy 69.2912 -83.82) (xy 72.5678 -80.5434)
				(xy 72.6948 -80.5434) (xy 79.889096 -80.5434) (xy 81.3054 -79.127096) (xy 85.515704 -79.127096)
				(xy 85.6996 -79.310738) (xy 85.6996 -79.3242) (xy 85.7758 -79.4004) (xy 85.7758 -80.45958) (xy 85.80628 -80.49006)
				(xy 86.11362 -80.7974) (xy 95.1738 -80.7974) (xy 97.0534 -82.677) (xy 97.0534 -84.3788) (xy 95.377 -86.0552)
				(xy 92.8116 -86.0552) (xy 92.3925 -86.4743) (xy 92.3925 -87.0839) (xy 93.1545 -87.8459) (xy 96.5835 -87.8459)
				(xy 97.161604 -88.424004) (xy 97.28708 -88.54948) (xy 103.70312 -88.54948) (xy 104.815386 -89.662)
				(xy 114.5032 -89.662) (xy 115.2906 -88.8746) (xy 115.2906 -85.7504) (xy 115.062 -85.5218) (xy 108.901484 -79.361284)
				(xy 107.506516 -79.361284) (xy 104.100884 -79.361284) (xy 103.8225 -79.0829) (xy 103.8225 -64.462914)
				(xy 103.7336 -64.374014) (xy 103.4542 -64.094614) (xy 97.700846 -64.094614) (xy 96.842834 -63.236856)
				(xy 96.839278 -63.2333) (xy 66.2813 -63.2333) (xy 66.277744 -63.236856) (xy 58.860944 -63.236856)
				(xy 49.171098 -53.546756)
			)
		)
	)
	(zone
		(layer "In7.Cu")
		(hatch none 0.5)
		(connect_pads
			(clearance 0)
		)
		(min_thickness 0.25)
		(keepout
			(tracks not_allowed)
			(vias allowed)
			(pads allowed)
			(copperpour not_allowed)
			(footprints allowed)
		)
		(placement
			(enabled no)
			(sheetname "")
		)
		(fill
			(thermal_gap 0.5)
			(thermal_bridge_width 0.5)
			(island_removal_mode 0)
		)
		(polygon
			(pts
				(arc
					(start 11.567922 -128.113282)
					(mid 10.809478 -128.113282)
					(end 11.567922 -128.113282)
				)
			)
		)
	)
	(zone
		(net "PVSA_CPU1")
		(layer "In7.Cu")
		(hatch none 0.5)
		(connect_pads
			(clearance 0.5)
		)
		(min_thickness 0.25)
		(fill yes
			(thermal_gap 0.5)
			(thermal_bridge_width 0.5)
			(island_removal_mode 0)
		)
		(polygon
			(pts
				(xy 79.9846 -80.7466) (xy 72.898 -80.7466) (xy 72.8218 -80.8228) (xy 69.5071 -84.1375) (xy 69.469 -84.1756)
				(xy 66.5734 -84.1756) (xy 63.0936 -84.1756) (xy 54.5084 -92.7608) (xy 44.323 -92.7608) (xy 44.32046 -92.76334)
				(xy 43.89628 -92.76334) (xy 43.16984 -93.48978) (xy 43.16984 -99.00412) (xy 43.815 -99.64928) (xy 43.815 -102.8192)
				(xy 44.3738 -103.378) (xy 56.6928 -103.378) (xy 67.852544 -92.218256) (xy 70.25386 -92.218256) (xy 70.351904 -92.218256)
				(xy 73.90638 -88.66378) (xy 74.127614 -88.4428) (xy 74.306938 -88.263476) (xy 80.237076 -88.263476)
				(xy 80.2386 -88.261698) (xy 80.445102 -88.261698) (xy 80.8228 -87.884) (xy 82.75701 -85.94979) (xy 82.9564 -85.94979)
				(xy 86.22919 -85.94979) (xy 86.233 -85.94598) (xy 94.78772 -85.94598) (xy 96.8121 -83.9216) (xy 96.8121 -82.9437)
				(xy 94.940882 -81.072482) (xy 85.996018 -81.072482) (xy 85.513164 -80.589628) (xy 85.513164 -79.629)
				(xy 85.208364 -79.3242) (xy 81.5086 -79.3242) (xy 80.0862 -80.7466)
			)
		)
	)
	(zone
		(net "PVTT_DEF")
		(layer "In7.Cu")
		(hatch none 0.5)
		(connect_pads
			(clearance 0.5)
		)
		(min_thickness 0.25)
		(fill yes
			(thermal_gap 0.5)
			(thermal_bridge_width 0.5)
			(island_removal_mode 0)
		)
		(polygon
			(pts
				(xy 259.0546 -137.4394) (xy 259.0546 -131.572) (xy 259.9182 -130.7084) (xy 260.7818 -130.7084) (xy 261.2644 -131.191)
				(xy 261.2644 -138.3284) (xy 261.239 -138.3538) (xy 261.239 -142.3924) (xy 260.5024 -143.129) (xy 258.5974 -143.129)
				(xy 258.0894 -142.621) (xy 258.0894 -138.4046)
			)
		)
	)
	(zone
		(net "PVCCIO_CPU0")
		(layer "In7.Cu")
		(hatch none 0.5)
		(connect_pads
			(clearance 0.5)
		)
		(min_thickness 0.25)
		(fill yes
			(thermal_gap 0.5)
			(thermal_bridge_width 0.5)
			(island_removal_mode 0)
		)
		(polygon
			(pts
				(xy 292.7858 -84.709) (xy 292.665658 -84.829142)
				(arc
					(start 292.663118 -84.832952)
					(mid 292.621066 -84.88361)
					(end 292.570408 -84.925662)
				)
				(xy 292.566598 -84.928202) (xy 292.413182 -85.081618) (xy 291.8968 -85.598) (xy 291.083238 -85.598)
				(xy 291.00653 -85.674708)
				(arc
					(start 290.996624 -85.712554)
					(mid 290.812105 -85.940486)
					(end 290.519104 -85.952584)
				)
				(xy 290.487862 -85.940138) (xy 290.0934 -86.3346) (xy 290.0807 -86.3473) (xy 290.0807 -90.5129)
				(xy 288.798 -91.7956) (xy 286.9946 -91.7956) (xy 285.5976 -90.3986) (xy 285.5976 -85.162136) (xy 285.7627 -84.997036)
				(xy 285.7627 -84.9884) (xy 285.9786 -84.7725) (xy 285.9786 -83.4644) (xy 286.8168 -82.6262) (xy 286.8168 -82.3214)
				(xy 286.8168 -81.9658) (xy 286.55391 -81.70291) (xy 278.00935 -81.70291) (xy 277.9268 -81.78546)
				(xy 277.9268 -84.312252) (xy 278.069548 -84.455) (xy 280.162 -86.547452) (xy 280.162 -86.7664) (xy 280.162 -102.5906)
				(xy 280.162 -103.378) (xy 280.44902 -103.66502) (xy 281.23642 -103.66502) (xy 305.42738 -103.66502)
				(xy 308.61508 -106.85272) (xy 333.34452 -106.85272) (xy 334.01 -107.5182) (xy 339.415374 -107.5182)
				(xy 339.750908 -107.182666) (xy 339.749892 -107.18165) (xy 339.749892 -91.313) (xy 334.645 -86.208108)
				(xy 309.982108 -86.208108) (xy 309.751476 -86.208108) (xy 304.4444 -80.901032) (xy 294.206676 -80.901032)
				(xy 294.1828 -80.924908) (xy 292.7858 -82.321908)
			)
		)
	)
	(zone
		(net "P3V3_STBY")
		(layer "In7.Cu")
		(hatch none 0.5)
		(connect_pads
			(clearance 0.5)
		)
		(min_thickness 0.25)
		(fill yes
			(thermal_gap 0.5)
			(thermal_bridge_width 0.5)
			(island_removal_mode 0)
		)
		(polygon
			(pts
				(xy 324.41388 -57.688988) (xy 324.036182 -58.066686) (xy 324.036182 -68.643246) (xy 324.036182 -72.017382)
				(xy 324.036182 -73.007982) (xy 324.37832 -73.35012) (xy 325.36892 -73.35012) (xy 331.29728 -73.35012)
				(xy 338.73948 -80.79232) (xy 338.73948 -80.7974) (xy 340.466172 -82.524092) (xy 340.471252 -82.524092)
				(xy 347.93301 -82.524092) (xy 347.937836 -82.529172) (xy 348.7166 -82.529172) (xy 352.0948 -85.907372)
				(xy 352.0948 -100.4824) (xy 352.932492 -101.320092) (xy 355.193092 -101.320092) (xy 362.63961 -101.320092)
				(xy 362.639864 -101.3206) (xy 362.6612 -101.3206) (xy 363.525308 -102.184708) (xy 363.525308 -111.580676)
				(xy 363.525308 -111.8108) (xy 363.525054 -111.811054) (xy 363.525054 -111.912654) (xy 360.858308 -114.5794)
				(xy 360.858308 -114.6556) (xy 360.858308 -118.52021) (xy 360.792522 -118.585742) (xy 360.792522 -118.5926)
				(xy 359.954322 -119.4308) (xy 358.4448 -119.4308) (xy 355.092 -122.7836) (xy 355.092 -128.20904)
				(xy 355.08692 -128.21412) (xy 355.092 -128.2192) (xy 355.092 -129.1844) (xy 355.092 -131.700016)
				(xy 355.092 -131.8514) (xy 355.092 -137.0838) (xy 360.7308 -142.7226) (xy 366.684814 -148.676614)
				(xy 369.178586 -148.676614) (xy 370.057426 -149.555454) (xy 370.484146 -149.982174) (xy 371.01018 -150.508208)
				(xy 371.01018 -150.61692) (xy 371.043708 -150.650194) (xy 371.043708 -157.936692) (xy 371.043708 -158.3944)
				(xy 371.283992 -158.634684) (xy 397.9418 -158.634684) (xy 466.9282 -158.634684) (xy 467.233 -158.329884)
				(xy 467.233 -153.6192) (xy 470.3064 -150.5458) (xy 476.9358 -150.5458) (xy 479.0694 -152.6794) (xy 479.0694 -158.339282)
				(xy 479.37293 -158.642812)
				(arc
					(start 499.674896 -158.642812)
					(mid 500.838343 -158.236231)
					(end 501.495314 -157.193488)
				)
				(arc
					(start 501.495314 -111.785908)
					(mid 500.963668 -110.852213)
					(end 500.005604 -110.365794)
				)
				(xy 492.100362 -110.365794) (xy 490.858556 -111.6076) (xy 490.858556 -113.87455) (xy 490.858556 -115.323874)
				(xy 490.858556 -116.41709) (xy 489.59516 -117.680486) (xy 489.213144 -117.680486) (xy 489.17098 -117.722904)
				(xy 440.38139 -117.722904) (xy 438.216548 -119.887746) (xy 438.147968 -119.887746) (xy 438.129172 -119.906796)
				(xy 437.116728 -119.906796) (xy 436.150512 -119.906796) (xy 426.528484 -119.906796) (xy 426.509688 -119.887746)
				(xy 426.483526 -119.887746) (xy 423.7101 -117.11432) (xy 423.187622 -116.591842)
				(arc
					(start 423.169588 -116.591842)
					(mid 423.159453 -116.568206)
					(end 423.14368 -116.5479)
				)
				(xy 421.45839 -114.86261) (xy 420.651178 -114.055398) (xy 420.651178 -75.057508) (xy 421.220646 -74.48804)
				(xy 421.220646 -74.155808) (xy 420.651178 -73.58634) (xy 420.651178 -72.545194) (xy 409.439872 -61.333888)
				(xy 408.497278 -61.333888) (xy 408.497024 -61.334142) (xy 407.5811 -61.334142) (xy 407.580846 -61.333888)
				(xy 396.695422 -61.333888) (xy 396.115794 -60.75426) (xy 396.115794 -60.274962) (xy 395.874748 -60.033916)
				(xy 387.976872 -60.033916) (xy 386.590794 -61.419994) (xy 386.590794 -63.141606) (xy 385.445 -64.2874)
				(xy 363.218476 -64.2874) (xy 356.620064 -57.688988) (xy 349.017844 -57.688988) (xy 347.384624 -57.688988)
				(xy 347.048074 -57.688988) (xy 345.400884 -57.688988)
			)
		)
		(polygon
			(pts
				(arc
					(start 389.8265 -106.605324)
					(mid 389.7376 -106.552957)
					(end 389.6487 -106.605324)
				)
				(arc
					(start 389.6487 -106.605324)
					(mid 389.33755 -106.788348)
					(end 389.0264 -106.605324)
				)
				(arc
					(start 389.0264 -106.605324)
					(mid 388.884627 -106.567791)
					(end 388.852918 -106.710988)
				)
				(arc
					(start 388.852918 -106.710988)
					(mid 388.897495 -106.805358)
					(end 388.912862 -106.9086)
				)
				(arc
					(start 388.912862 -106.908854)
					(mid 388.94262 -106.980442)
					(end 389.014208 -107.0102)
				)
				(arc
					(start 391.261092 -107.0102)
					(mid 391.33277 -106.980352)
					(end 391.362438 -106.9086)
				)
				(arc
					(start 391.362438 -106.9086)
					(mid 391.377738 -106.805338)
					(end 391.422382 -106.710988)
				)
				(arc
					(start 391.422382 -106.710988)
					(mid 391.390679 -106.567781)
					(end 391.2489 -106.605324)
				)
				(arc
					(start 391.2489 -106.605324)
					(mid 390.93775 -106.788348)
					(end 390.6266 -106.605324)
				)
				(arc
					(start 390.6266 -106.605324)
					(mid 390.5377 -106.552957)
					(end 390.4488 -106.605324)
				)
				(arc
					(start 390.4488 -106.605324)
					(mid 390.13765 -106.788348)
					(end 389.8265 -106.605324)
				)
			)
		)
		(polygon
			(pts
				(arc
					(start 408.154632 -135.206994)
					(mid 408.088476 -135.111777)
					(end 407.976324 -135.1407)
				)
				(arc
					(start 407.976324 -135.1407)
					(mid 406.750841 -135.805767)
					(end 405.392128 -135.49249)
				)
				(arc
					(start 405.392128 -135.49249)
					(mid 405.287885 -135.487386)
					(end 405.23414 -135.576818)
				)
				(arc
					(start 405.23414 -137.932668)
					(mid 405.296894 -138.026295)
					(end 405.407368 -138.004296)
				)
				(xy 408.154632 -135.257032)
			)
		)
		(polygon
			(pts
				(arc
					(start 408.189684 -130.51409)
					(mid 408.12693 -130.420463)
					(end 408.016456 -130.442462)
				)
				(arc
					(start 406.722834 -131.73583)
					(mid 406.698141 -131.83945)
					(end 406.779476 -131.908296)
				)
				(arc
					(start 406.779476 -131.908296)
					(mid 407.459691 -132.144313)
					(end 408.009598 -132.609082)
				)
				(arc
					(start 408.009598 -132.609082)
					(mid 408.12223 -132.640255)
					(end 408.189684 -132.54482)
				)
			)
		)
		(polygon
			(pts
				(arc
					(start 391.42543 -152.976834)
					(mid 391.336009 -152.917799)
					(end 391.243312 -152.971754)
				)
				(arc
					(start 391.243312 -152.971754)
					(mid 391.093854 -153.125768)
					(end 390.884918 -153.1747)
				)
				(arc
					(start 390.884918 -153.1747)
					(mid 390.811903 -153.200179)
					(end 390.777984 -153.269696)
				)
				(arc
					(start 390.777984 -153.269696)
					(mid 390.727955 -153.525767)
					(end 390.614408 -153.760678)
				)
				(arc
					(start 390.614408 -153.760678)
					(mid 390.625803 -153.834908)
					(end 390.63168 -153.909776)
				)
				(arc
					(start 390.63168 -153.909776)
					(mid 390.649589 -153.934499)
					(end 390.665462 -153.960576)
				)
				(arc
					(start 390.665462 -153.960576)
					(mid 390.752235 -154.012573)
					(end 390.840976 -153.963878)
				)
				(arc
					(start 390.840976 -153.963878)
					(mid 391.080247 -153.790018)
					(end 391.371836 -153.839418)
				)
				(arc
					(start 391.371836 -153.839418)
					(mid 391.481318 -153.838926)
					(end 391.526776 -153.739342)
				)
				(arc
					(start 391.526776 -153.739342)
					(mid 391.527731 -153.44826)
					(end 391.611104 -153.169366)
				)
				(arc
					(start 391.611104 -153.169366)
					(mid 391.502031 -153.088767)
					(end 391.42543 -152.976834)
				)
			)
		)
	)
	(zone
		(layer "In7.Cu")
		(hatch none 0.5)
		(connect_pads
			(clearance 0)
		)
		(min_thickness 0.25)
		(keepout
			(tracks not_allowed)
			(vias allowed)
			(pads allowed)
			(copperpour not_allowed)
			(footprints allowed)
		)
		(placement
			(enabled no)
			(sheetname "")
		)
		(fill
			(thermal_gap 0.5)
			(thermal_bridge_width 0.5)
			(island_removal_mode 0)
		)
		(polygon
			(pts
				(arc
					(start 330.04379 -125.2601)
					(mid 329.278234 -125.2601)
					(end 330.04379 -125.2601)
				)
			)
		)
	)
	(zone
		(net "PVCCMCP_CPU0")
		(layer "In7.Cu")
		(hatch none 0.5)
		(connect_pads
			(clearance 0.5)
		)
		(min_thickness 0.25)
		(fill yes
			(thermal_gap 0.5)
			(thermal_bridge_width 0.5)
			(island_removal_mode 0)
		)
		(polygon
			(pts
				(xy 317.8302 -47.879) (xy 317.7794 -47.9044) (xy 314.7822 -47.9044) (xy 311.3532 -51.3334) (xy 269.7734 -51.3334)
				(xy 269.621 -51.4858) (xy 269.2654 -51.8414) (xy 269.2654 -63.8302) (xy 269.0622 -64.0334) (xy 269.0622 -70.500748)
				(xy 269.0622 -71.182484) (xy 269.0622 -74.818748) (xy 269.0622 -75.500484) (xy 269.0622 -78.8162)
				(xy 269.5194 -79.2734) (xy 273.05 -79.2734) (xy 274.9804 -81.2038) (xy 275.6916 -81.2038) (xy 282.798012 -81.2038)
				(xy 283.529278 -81.2038) (xy 283.537406 -81.195672) (xy 283.5402 -81.2038) (xy 286.002222 -81.2038)
				(xy 286.422338 -81.2038) (xy 286.981138 -81.7626) (xy 286.981138 -82.951574) (xy 286.97682 -82.94878)
				(xy 286.70885 -83.21675)
				(arc
					(start 286.705548 -83.230466)
					(mid 286.591543 -83.416312)
					(end 286.390588 -83.500976)
				)
				(xy 286.3723 -83.5025) (xy 286.2072 -83.6676) (xy 286.2072 -84.9122) (xy 286.0929 -85.0265) (xy 285.9024 -85.217)
				(xy 285.7754 -85.344) (xy 285.7754 -90.1954) (xy 287.2232 -91.6432) (xy 288.5948 -91.6432) (xy 289.687 -90.551)
				(xy 289.687 -86.2076) (xy 290.4744 -85.4202) (xy 290.7284 -85.4202) (xy 290.945316 -85.4202) (xy 291.6174 -85.4202)
				(xy 292.134036 -84.903564) (xy 292.13302 -84.902548) (xy 292.5572 -84.478368) (xy 292.5572 -84.182204)
				(xy 292.5572 -82.1436) (xy 292.8112 -81.8896) (xy 294.334692 -80.366108) (xy 294.334692 -78.3844)
				(xy 294.334692 -78.105508) (xy 295.8592 -76.581) (xy 296.138092 -76.581) (xy 297.1292 -76.581) (xy 298.0182 -75.692)
				(xy 298.323 -75.692) (xy 298.3484 -75.692) (xy 300.4058 -73.6346) (xy 306.705 -73.6346) (xy 306.705508 -73.634092)
				(xy 322.308982 -73.634092) (xy 323.215508 -73.634092) (xy 323.6341 -73.2155) (xy 323.6341 -61.3029)
				(xy 323.6214 -61.2902) (xy 323.6214 -57.7342) (xy 324.0278 -57.3278) (xy 324.0278 -54.0512) (xy 324.0278 -49.5554)
				(xy 322.3514 -47.879)
			)
		)
	)
	(zone
		(net "PVCCIN_CPU0")
		(layer "In7.Cu")
		(hatch none 0.5)
		(connect_pads
			(clearance 0.5)
		)
		(min_thickness 0.25)
		(fill yes
			(thermal_gap 0.5)
			(thermal_bridge_width 0.5)
			(island_removal_mode 0)
		)
		(polygon
			(pts
				(xy 208.840832 -53.5432) (xy 208.663032 -53.721) (xy 208.5086 -53.875432) (xy 208.3816 -54.002432)
				(xy 208.3816 -55.5244) (xy 208.3816 -92.329) (xy 208.6102 -92.5576) (xy 208.788 -92.5576) (xy 219.280232 -92.5576)
				(xy 219.458032 -92.3798) (xy 227.891086 -83.947) (xy 234.3912 -83.947) (xy 237.7186 -80.6196) (xy 244.8306 -80.6196)
				(xy 246.38 -79.0702) (xy 250.2916 -79.0702) (xy 250.698 -79.4766) (xy 250.698 -80.355186) (xy 250.76785 -80.425036)
				(xy 251.114814 -80.772) (xy 259.9436 -80.772) (xy 261.874 -82.7024) (xy 261.874 -84.5566) (xy 260.35 -86.0806)
				(xy 257.683 -86.0806) (xy 257.3401 -86.4235) (xy 257.3401 -87.1347) (xy 258.024884 -87.819484) (xy 261.557516 -87.819484)
				(xy 262.162036 -88.424004) (xy 262.307832 -88.5698) (xy 268.9098 -88.5698) (xy 269.9004 -89.5604)
				(xy 270.084804 -89.5604) (xy 279.6032 -89.5604) (xy 279.999948 -89.163652) (xy 279.999948 -88.708484)
				(xy 279.999948 -88.658446)
				(arc
					(start 279.999186 -88.654382)
					(mid 279.994062 -88.594184)
					(end 279.999186 -88.533986)
				)
				(xy 279.999948 -88.529922) (xy 279.999948 -86.854538) (xy 279.999948 -86.705948) (xy 272.8722 -79.5782)
				(xy 272.723864 -79.5782) (xy 269.3416 -79.5782) (xy 268.8336 -79.0702) (xy 268.8336 -64.526414)
				(xy 268.7193 -64.412114) (xy 268.434312 -64.12738) (xy 261.352284 -64.12738) (xy 261.350252 -64.125348)
				(xy 261.153148 -64.125348) (xy 260.14934 -63.12154) (xy 223.74606 -63.12154) (xy 214.167974 -53.5432)
			)
		)
	)
	(zone
		(net "PVCCIO_CPU1")
		(layer "In7.Cu")
		(hatch none 0.5)
		(connect_pads
			(clearance 0.5)
		)
		(min_thickness 0.25)
		(fill yes
			(thermal_gap 0.5)
			(thermal_bridge_width 0.5)
			(island_removal_mode 0)
		)
		(polygon
			(pts
				(xy 212.228176 -49.27854) (xy 306.28082 -49.27854) (xy 307.51272 -48.04664) (xy 307.51272 -46.4693)
				(xy 307.51272 -44.541186) (xy 307.326538 -44.355004) (xy 201.506328 -44.355004) (xy 201.280014 -44.581318)
				(xy 201.280014 -44.987972) (xy 201.511408 -45.219366) (xy 208.169002 -45.219366)
			)
		)
	)
	(zone
		(net "GND")
		(layer "In7.Cu")
		(hatch none 0.5)
		(connect_pads
			(clearance 0.5)
		)
		(min_thickness 0.25)
		(fill yes
			(thermal_gap 0.5)
			(thermal_bridge_width 0.5)
			(island_removal_mode 0)
		)
		(polygon
			(pts
				(xy 268.8971 -52.2859) (xy 268.1478 -51.5366) (xy 267.9446 -51.3334) (xy 251.7902 -51.3334) (xy 251.7775 -51.3207)
				(xy 200.006458 -51.3207) (xy 199.381618 -51.94554) (xy 199.381618 -92.900754) (xy 199.520556 -93.039692)
				(xy 207.7974 -93.039692) (xy 208.026 -92.811092) (xy 208.026 -53.6956) (xy 208.1911 -53.5305) (xy 208.5086 -53.213)
				(xy 214.2744 -53.213) (xy 223.901 -62.8396) (xy 223.9645 -62.9031) (xy 260.1849 -62.9031) (xy 261.154672 -63.872872)
				(xy 261.457694 -63.872872) (xy 268.5542 -63.872872) (xy 268.8971 -63.529972)
			)
		)
	)
	(zone
		(net "P1V8_PCH_STBY")
		(layer "In7.Cu")
		(hatch none 0.5)
		(connect_pads
			(clearance 0.5)
		)
		(min_thickness 0.25)
		(fill yes
			(thermal_gap 0.5)
			(thermal_bridge_width 0.5)
			(island_removal_mode 0)
		)
		(polygon
			(pts
				(xy 395.8082 -104.8766) (xy 395.514576 -104.8766) (xy 394.831824 -104.8766) (xy 394.466318 -104.8766)
				(xy 393.886182 -104.8766) (xy 391.9474 -104.8766) (xy 391.922 -104.8766) (xy 391.4394 -105.3592)
				(xy 389.636 -105.3592) (xy 389.5344 -105.3592) (xy 388.874 -104.6988) (xy 388.874 -104.560624) (xy 388.874 -103.3526)
				(xy 388.7978 -103.2764) (xy 388.1374 -103.2764) (xy 388.0104 -103.4034) (xy 387.0452 -104.3686)
				(xy 387.0452 -104.638348) (xy 387.0452 -105.470452) (xy 387.0452 -106.1466) (xy 387.1722 -106.2736)
				(xy 391.6934 -106.2736) (xy 392.053572 -106.633772) (xy 392.0744 -106.633772) (xy 392.146028 -106.7054)
				(xy 393.5222 -106.7054) (xy 393.708382 -106.891582) (xy 394.038836 -107.222036) (xy 394.038836 -107.5055)
				(xy 394.038836 -107.99318) (xy 394.038836 -108.593636) (xy 394.335 -108.8898) (xy 403.15134 -108.8898)
				(xy 410.566108 -116.304568) (xy 410.566108 -119.70639) (xy 410.566108 -120.52681) (xy 410.566108 -120.867424)
				(xy 411.437836 -121.739406) (xy 411.437836 -121.746772) (xy 411.455108 -121.76379) (xy 411.455108 -122.12701)
				(xy 411.442408 -122.13971) (xy 411.442408 -127.01651) (xy 408.444192 -130.014472)
				(arc
					(start 408.444192 -134.05231)
					(mid 408.429804 -134.163171)
					(end 408.40914 -134.273036)
				)
				(xy 408.40914 -135.362442) (xy 405.23414 -138.537442) (xy 404.0886 -139.682982) (xy 404.0886 -143.5608)
				(xy 404.1013 -143.5735) (xy 404.1013 -144.7927) (xy 404.4442 -145.1356) (xy 407.1366 -145.1356)
				(xy 411.734 -140.5382) (xy 411.734 -140.1826) (xy 411.734 -130.2258) (xy 414.4264 -127.5334) (xy 414.8836 -127.0762)
				(xy 414.8836 -116.1542) (xy 404.911052 -106.181652) (xy 404.911052 -104.192578) (xy 404.092156 -103.373682)
				(xy 403.639274 -102.9208) (xy 397.764 -102.9208)
			)
		)
	)
	(zone
		(net "PVNN_PCH_STBY")
		(layer "In7.Cu")
		(hatch none 0.5)
		(connect_pads
			(clearance 0.5)
		)
		(min_thickness 0.25)
		(fill yes
			(thermal_gap 0.5)
			(thermal_bridge_width 0.5)
			(island_removal_mode 0)
		)
		(polygon
			(pts
				(xy 375.266712 -104.72293) (xy 374.122442 -105.8672) (xy 372.745 -105.8672) (xy 371.2718 -104.394)
				(xy 371.2718 -102.5906) (xy 370.6622 -101.981) (xy 367.6904 -101.981) (xy 366.5728 -103.0986) (xy 366.5728 -107.0864)
				(xy 366.5728 -142.9258) (xy 366.830356 -143.183356) (xy 367.331752 -143.684752) (xy 367.530126 -143.684752)
				(xy 384.6068 -143.684752) (xy 384.856736 -143.434816) (xy 384.856736 -135.12419) (xy 384.856736 -134.273798)
				(xy 384.856736 -124.279152) (xy 384.856736 -121.924064) (xy 388.2644 -118.5164) (xy 388.2644 -113.309908)
				(xy 388.264654 -113.309654) (xy 388.264654 -112.750346) (xy 389.1534 -111.8616) (xy 389.712708 -111.8616)
				(xy 389.992108 -111.5822) (xy 389.992108 -111.571786) (xy 389.992108 -110.269782) (xy 390.244838 -110.017052)
				(xy 391.205974 -110.017052) (xy 391.865358 -109.357668) (xy 391.9474 -109.275626) (xy 391.9474 -107.4674)
				(xy 391.9474 -107.2134) (xy 391.7442 -107.0102) (xy 386.104638 -107.0102) (xy 385.253992 -106.159808)
				(xy 385.253992 -104.964992) (xy 384.8354 -104.5464) (xy 375.443242 -104.5464)
			)
		)
	)
	(zone
		(net "VR_FET_SW_P12V_STBY_PVCCIN_CPU1")
		(layer "In7.Cu")
		(hatch none 0.5)
		(connect_pads
			(clearance 0.5)
		)
		(min_thickness 0.25)
		(fill yes
			(thermal_gap 0.5)
			(thermal_bridge_width 0.5)
			(island_removal_mode 0)
		)
		(polygon
			(pts
				(xy 24.9174 -48.9712) (xy 24.2824 -49.6062) (xy 24.2824 -54.3052) (xy 25.7302 -55.753) (xy 25.7302 -79.6798)
				(xy 25.72639 -79.68361) (xy 26.9875 -80.94472) (xy 26.9875 -95.61322) (xy 24.1554 -98.44532) (xy 24.1554 -108.6358)
				(xy 24.6888 -109.1692) (xy 32.258 -109.1692) (xy 32.893 -108.5342) (xy 32.893 -103.05288) (xy 33.88614 -102.05974)
				(xy 33.88614 -52.11572) (xy 33.07842 -51.308) (xy 32.5628 -51.308) (xy 30.4038 -51.308) (xy 29.0576 -49.9618)
				(xy 29.0576 -49.149) (xy 28.8798 -48.9712)
			)
		)
		(polygon
			(pts
				(arc
					(start 32.831024 -54.087014)
					(mid 32.760648 -54.051414)
					(end 32.68599 -54.076854)
				)
				(arc
					(start 32.68599 -54.076854)
					(mid 32.491473 -54.164241)
					(end 32.281876 -54.12486)
				)
				(arc
					(start 32.281876 -54.12486)
					(mid 32.176263 -54.131026)
					(end 32.13354 -54.22773)
				)
				(arc
					(start 32.13354 -54.22773)
					(mid 32.136541 -54.468226)
					(end 32.082994 -54.70271)
				)
				(arc
					(start 32.082994 -54.70271)
					(mid 32.092684 -54.791156)
					(end 32.168338 -54.838092)
				)
				(xy 32.384746 -54.838092) (xy 32.892492 -54.330346)
				(arc
					(start 32.892492 -54.144164)
					(mid 32.86007 -54.117405)
					(end 32.831024 -54.087014)
				)
			)
		)
	)
	(zone
		(net "P1V05_PCH_STBY")
		(layer "In7.Cu")
		(hatch none 0.5)
		(connect_pads
			(clearance 0.5)
		)
		(min_thickness 0.25)
		(fill yes
			(thermal_gap 0.5)
			(thermal_bridge_width 0.5)
			(island_removal_mode 0)
		)
		(polygon
			(pts
				(xy 392.176 -109.409738) (xy 392.173206 -109.409738) (xy 391.311384 -110.27156) (xy 390.898126 -110.27156)
				(xy 390.43864 -110.27156) (xy 390.1948 -110.5154) (xy 390.1948 -111.506) (xy 390.1948 -111.7092)
				(xy 389.8392 -112.0648) (xy 389.2042 -112.0648) (xy 388.5438 -112.7252) (xy 388.5438 -112.7506)
				(xy 388.5438 -118.6434) (xy 388.4676 -118.7196) (xy 385.1148 -122.0724) (xy 385.1148 -144.4498)
				(xy 386.0038 -145.3388) (xy 398.072864 -145.3388) (xy 398.096232 -145.3388) (xy 404.979632 -138.4554)
				(xy 404.979632 -138.432032) (xy 404.979632 -135.123936) (xy 404.979632 -133.105652) (xy 406.174702 -131.910582)
				(xy 406.190958 -131.908042) (xy 411.1879 -126.9111) (xy 411.1879 -124.810774) (xy 411.1879 -123.956826)
				(xy 411.1879 -122.0343) (xy 411.2006 -122.0216) (xy 411.2006 -121.8692) (xy 410.3116 -120.9802)
				(xy 410.3116 -120.573546) (xy 410.3116 -119.659654) (xy 410.3116 -116.41328) (xy 403.04212 -109.1438)
				(xy 399.5674 -109.1438) (xy 394.061696 -109.1438)
				(arc
					(start 393.983972 -109.066076)
					(mid 393.929027 -109.022645)
					(end 393.883642 -108.969302)
				)
				(xy 393.78128 -108.86694) (xy 393.78128 -108.095288) (xy 393.78128 -107.39628) (xy 393.27328 -106.88828)
				(xy 392.84148 -106.88828) (xy 392.45032 -106.88828) (xy 392.176 -107.1626)
			)
		)
	)
	(zone
		(net "GND")
		(layer "In7.Cu")
		(hatch none 0.5)
		(connect_pads
			(clearance 0.5)
		)
		(min_thickness 0.25)
		(fill yes
			(thermal_gap 0.5)
			(thermal_bridge_width 0.5)
			(island_removal_mode 0)
		)
		(polygon
			(pts
				(xy 245.5164 -88.7984) (xy 239.5093 -88.7984) (xy 239.2807 -89.027) (xy 235.0262 -93.2815) (xy 232.3465 -93.2815)
				(xy 222.123 -103.505) (xy 222.123 -104.013) (xy 279.0825 -104.013) (xy 279.1968 -103.8987) (xy 279.1968 -90.1319)
				(xy 279.0825 -90.0176) (xy 279.07615 -90.01125) (xy 278.9809 -89.916) (xy 269.6464 -89.916) (xy 268.6304 -88.9)
				(xy 268.4018 -88.9) (xy 262.89 -88.9) (xy 261.6454 -88.9) (xy 261.3914 -88.646) (xy 261.2644 -88.519)
				(xy 258.0386 -88.519) (xy 256.159 -86.6394) (xy 247.6754 -86.6394) (xy 247.5738 -86.741)
			)
		)
	)
	(zone
		(net "GND")
		(layer "In7.Cu")
		(hatch none 0.5)
		(connect_pads
			(clearance 0.5)
		)
		(min_thickness 0.25)
		(fill yes
			(thermal_gap 0.5)
			(thermal_bridge_width 0.5)
			(island_removal_mode 0)
		)
		(polygon
			(pts
				(xy 67.437 -93.218) (xy 64.2874 -96.3676) (xy 64.2874 -101.9556) (xy 65.3288 -102.997) (xy 109.5756 -102.997)
				(xy 109.8296 -103.251) (xy 113.0808 -103.251) (xy 114.471704 -103.251) (xy 114.817652 -102.905052)
				(xy 114.9604 -102.76205) (xy 114.9604 -90.551) (xy 114.4524 -90.043) (xy 113.919 -90.043) (xy 113.131854 -90.043)
				(xy 112.41659 -90.043) (xy 104.858312 -90.043) (xy 104.648 -90.043) (xy 104.356154 -89.751154) (xy 103.505 -88.9)
				(xy 97.917 -88.9) (xy 96.7486 -88.9) (xy 96.2406 -88.392) (xy 95.758 -88.392) (xy 92.6592 -88.392)
				(xy 90.6526 -86.3854) (xy 83.1596 -86.3854) (xy 83.058 -86.487) (xy 82.9818 -86.5632) (xy 81.0514 -88.4936)
				(xy 80.899 -88.646) (xy 77.6986 -88.646) (xy 74.93 -88.646) (xy 74.7903 -88.646) (xy 70.9295 -92.5068)
				(xy 68.1482 -92.5068)
			)
		)
	)
	(zone
		(net "PVDDQ_ABC")
		(layer "In7.Cu")
		(hatch none 0.5)
		(connect_pads
			(clearance 0.5)
		)
		(min_thickness 0.25)
		(fill yes
			(thermal_gap 0.5)
			(thermal_bridge_width 0.5)
			(island_removal_mode 0)
		)
		(polygon
			(pts
				(xy 193.4464 -9.5504) (xy 193.4464 -14.605) (xy 193.4464 -22.2758) (xy 193.3448 -22.3774) (xy 193.0908 -22.6314)
				(xy 192.8876 -22.8346) (xy 192.8876 -24.2062) (xy 193.1162 -24.4348) (xy 195.01612 -24.4348) (xy 195.1736 -24.27732)
				(xy 195.54444 -23.90648) (xy 254.9398 -23.90648) (xy 258.36372 -27.3304) (xy 266.9794 -27.3304)
				(xy 274.1676 -27.3304) (xy 274.35302 -27.14498) (xy 277.5712 -23.9268) (xy 327.8632 -23.9268) (xy 328.2188 -24.2824)
				(xy 329.5142 -24.2824) (xy 329.8698 -23.9268) (xy 330.52385 -23.9268) (xy 330.7588 -23.9268) (xy 330.7842 -23.9014)
				(xy 331.3938 -23.9014) (xy 337.7946 -17.5006) (xy 337.7946 -16.891) (xy 337.7946 -8.3312) (xy 337.7946 5.0038)
				(xy 337.7692 5.0292) (xy 337.255866 5.542534) (xy 280.8986 5.542534) (xy 261.803134 5.542534) (xy 187.304934 5.542534)
				(xy 186.441334 5.542534) (xy 186.4233 5.5245) (xy 181.4703 5.5245) (xy 180.7464 4.8006) (xy 180.7464 -6.1976)
				(xy 182.5244 -7.9756) (xy 191.8716 -7.9756)
			)
		)
	)
	(zone
		(net "GND")
		(layer "In7.Cu")
		(hatch none 0.5)
		(connect_pads
			(clearance 0.5)
		)
		(min_thickness 0.25)
		(fill yes
			(thermal_gap 0.5)
			(thermal_bridge_width 0.5)
			(island_removal_mode 0)
		)
		(polygon
			(pts
				(xy 488.130342 5.542788) (xy 488.130088 5.542534) (xy 487.8578 5.542534) (xy 487.8578 3.56362) (xy 487.951272 3.470148)
				(xy 501.001792 3.470148) (xy 501.542558 4.01066)
				(arc
					(start 501.542558 4.99999)
					(mid 501.383651 5.383627)
					(end 501.000014 5.542534)
				)
				(xy 499.596156 5.542534) (xy 499.595902 5.542788)
			)
		)
	)
	(zone
		(net "PVCCIOMCP_CPU0")
		(layer "In7.Cu")
		(hatch none 0.5)
		(connect_pads
			(clearance 0.5)
		)
		(min_thickness 0.25)
		(fill yes
			(thermal_gap 0.5)
			(thermal_bridge_width 0.5)
			(island_removal_mode 0)
		)
		(polygon
			(pts
				(xy 304.7238 -80.7212) (xy 309.9562 -85.9536) (xy 334.798416 -85.9536) (xy 334.8482 -85.9536) (xy 335.27365 -86.37905)
				(xy 340.0044 -91.1098) (xy 340.0044 -107.07624) (xy 343.800684 -110.872524) (xy 344.447876 -111.519716)
				(xy 346.10548 -113.17732) (xy 350.48952 -113.17732) (xy 354.71608 -113.17732) (xy 355.3968 -112.4966)
				(xy 355.3968 -108.2548) (xy 355.1428 -108.0008) (xy 354.448618 -107.306618)
				(arc
					(start 354.442776 -107.303316)
					(mid 354.367008 -107.244545)
					(end 354.30968 -107.16768)
				)
				(xy 353.8855 -106.7435) (xy 353.8855 -106.7308) (xy 351.40265 -104.24795) (xy 351.40265 -85.69325)
				(xy 348.488 -82.7786) (xy 347.8276 -82.7786) (xy 340.3346 -82.7786) (xy 339.950298 -82.394298) (xy 339.55482 -81.99882)
				(xy 339.531706 -81.99882) (xy 339.532722 -81.976722) (xy 333.502508 -75.946508) (xy 331.4446 -73.8886)
				(xy 328.294492 -73.8886) (xy 306.6034 -73.8886) (xy 300.5328 -73.8886) (xy 298.4754 -75.946) (xy 298.0436 -75.946)
				(xy 297.1546 -76.835) (xy 297.0784 -76.835) (xy 295.9862 -76.835) (xy 295.1226 -77.6986) (xy 295.1226 -80.2894)
				(xy 295.3639 -80.5307) (xy 304.5333 -80.5307)
			)
		)
	)
	(zone
		(net "P3V3")
		(layer "In7.Cu")
		(hatch none 0.5)
		(connect_pads
			(clearance 0.5)
		)
		(min_thickness 0.25)
		(fill yes
			(thermal_gap 0.5)
			(thermal_bridge_width 0.5)
			(island_removal_mode 0)
		)
		(polygon
			(pts
				(xy 373.1514 -41.856914) (xy 373.1514 -18.922492) (xy 373.6086 -18.465292) (xy 392.492484 -18.465292)
				(xy 392.9126 -18.885408) (xy 392.9126 -41.934384) (xy 392.406124 -42.44086) (xy 373.735346 -42.44086)
			)
		)
	)
	(zone
		(layer "In7.Cu")
		(hatch none 0.5)
		(connect_pads
			(clearance 0)
		)
		(min_thickness 0.25)
		(keepout
			(tracks not_allowed)
			(vias allowed)
			(pads allowed)
			(copperpour not_allowed)
			(footprints allowed)
		)
		(placement
			(enabled no)
			(sheetname "")
		)
		(fill
			(thermal_gap 0.5)
			(thermal_bridge_width 0.5)
			(island_removal_mode 0)
		)
		(polygon
			(pts
				(arc
					(start 28.97124 -32.71393)
					(mid 28.262072 -32.71393)
					(end 28.97124 -32.71393)
				)
			)
		)
	)
	(zone
		(net "PVDDQ_DEF")
		(layer "In7.Cu")
		(hatch none 0.5)
		(connect_pads
			(clearance 0.5)
		)
		(min_thickness 0.25)
		(fill yes
			(thermal_gap 0.5)
			(thermal_bridge_width 0.5)
			(island_removal_mode 0)
		)
		(polygon
			(pts
				(xy 251.6632 -128.9558) (xy 194.6148 -128.9558) (xy 193.84264 -128.9558) (xy 193.14668 -129.65176)
				(xy 193.14668 -141.93774) (xy 192.46342 -142.621) (xy 182.9054 -142.621) (xy 178.7652 -146.7612)
				(xy 177.5968 -146.7612) (xy 177.2412 -147.1168) (xy 177.2412 -150.5712) (xy 179.832 -153.162) (xy 179.8574 -153.162)
				(xy 180.489098 -153.793698) (xy 180.489098 -156.943298) (xy 182.188358 -158.642558) (xy 187.305442 -158.642558)
				(xy 277.7998 -158.642558) (xy 279.7048 -158.642558) (xy 336.759042 -158.642558) (xy 337.312 -158.0896)
				(xy 337.312 -130.5052) (xy 335.7626 -128.9558) (xy 327.8378 -128.9558) (xy 324.8152 -128.9558) (xy 278.453596 -128.9558)
				(xy 275.658326 -126.16053) (xy 274.270216 -126.16053) (xy 259.46227 -126.16053) (xy 259.4483 -126.1745)
				(xy 254.4445 -126.1745)
			)
		)
	)
	(zone
		(net "PVTT_ABC")
		(layer "In7.Cu")
		(hatch none 0.5)
		(connect_pads
			(clearance 0.5)
		)
		(min_thickness 0.25)
		(fill yes
			(thermal_gap 0.5)
			(thermal_bridge_width 0.5)
			(island_removal_mode 0)
		)
		(polygon
			(pts
				(xy 259.6388 -22.3774) (xy 261.0358 -22.3774) (xy 262.1026 -21.3106) (xy 262.1026 -15.875) (xy 261.7724 -15.5448)
				(xy 260.8326 -15.5448) (xy 259.461 -16.9164) (xy 259.461 -22.1996)
			)
		)
	)
	(zone
		(net "PVDDQ_KLM")
		(layer "In7.Cu")
		(hatch none 0.5)
		(connect_pads
			(clearance 0.5)
		)
		(min_thickness 0.25)
		(fill yes
			(thermal_gap 0.5)
			(thermal_bridge_width 0.5)
			(island_removal_mode 0)
		)
		(polygon
			(pts
				(xy 109.729016 -126.177802) (xy 106.874818 -129.032) (xy 99.3902 -129.032) (xy 97.4344 -129.032)
				(xy 29.5402 -129.032) (xy 29.5148 -129.032) (xy 28.4988 -129.032) (xy 24.8412 -129.032) (xy 24.34844 -129.032)
				(xy 16.6878 -136.69264) (xy 16.6878 -137.1854) (xy 16.6878 -158.0134) (xy 17.2974 -158.623)
				(arc
					(start 90.169238 -158.623)
					(mid 90.250997 -158.581716)
					(end 90.266266 -158.491428)
				)
				(arc
					(start 90.266266 -158.491428)
					(mid 90.630756 -157.997443)
					(end 90.995246 -158.491428)
				)
				(arc
					(start 90.995246 -158.491428)
					(mid 91.010554 -158.581687)
					(end 91.092274 -158.623)
				)
				(arc
					(start 101.11867 -158.623)
					(mid 101.200573 -158.58152)
					(end 101.215698 -158.49092)
				)
				(arc
					(start 101.215698 -158.49092)
					(mid 101.555296 -158.02795)
					(end 101.894894 -158.49092)
				)
				(arc
					(start 101.894894 -158.49092)
					(mid 101.909936 -158.581581)
					(end 101.991922 -158.623)
				)
				(arc
					(start 104.54767 -158.623)
					(mid 104.629573 -158.58152)
					(end 104.644698 -158.49092)
				)
				(arc
					(start 104.644698 -158.49092)
					(mid 104.984296 -158.02795)
					(end 105.323894 -158.49092)
				)
				(arc
					(start 105.323894 -158.49092)
					(mid 105.338936 -158.581581)
					(end 105.420922 -158.623)
				)
				(arc
					(start 108.105194 -158.623)
					(mid 108.187428 -158.581067)
					(end 108.201714 -158.489904)
				)
				(arc
					(start 108.201714 -158.489904)
					(mid 108.540296 -158.02326)
					(end 108.878878 -158.489904)
				)
				(arc
					(start 108.878878 -158.489904)
					(mid 108.893222 -158.581025)
					(end 108.975398 -158.623)
				)
				(xy 112.776 -158.623) (xy 112.776 -158.4452) (xy 112.876076 -158.345124)
				(arc
					(start 112.878362 -158.328106)
					(mid 113.17448 -158.006237)
					(end 113.578386 -158.173928)
				)
				(arc
					(start 113.578386 -158.173928)
					(mid 113.663984 -158.220853)
					(end 113.749582 -158.173928)
				)
				(arc
					(start 113.749582 -158.173928)
					(mid 114.164658 -158.008925)
					(end 114.451892 -158.350966)
				)
				(xy 114.453162 -158.369762) (xy 114.554 -158.4706) (xy 114.554 -158.623) (xy 167.1066 -158.623)
				(xy 168.656 -157.0736) (xy 168.656 -152.9588) (xy 168.656 -151.358854) (xy 169.545 -150.469854)
				(xy 169.545 -149.625304)
				(arc
					(start 169.544746 -149.622256)
					(mid 169.542301 -149.5806)
					(end 169.544746 -149.538944)
				)
				(xy 169.545 -149.535896) (xy 169.545 -143.2814) (xy 168.7322 -142.4686) (xy 157.0736 -142.4686)
				(xy 156.7688 -142.1638) (xy 156.6164 -142.0114) (xy 156.6164 -129.4638) (xy 156.1846 -129.032) (xy 113.124742 -129.032)
				(xy 111.2266 -127.133858) (xy 111.2266 -127.127) (xy 110.277402 -126.177802) (xy 110.270544 -126.177802)
			)
		)
	)
	(zone
		(net "P5V_STBY")
		(layer "In7.Cu")
		(hatch none 0.5)
		(connect_pads
			(clearance 0.5)
		)
		(min_thickness 0.25)
		(fill yes
			(thermal_gap 0.5)
			(thermal_bridge_width 0.5)
			(island_removal_mode 0)
		)
		(polygon
			(pts
				(xy 355.0666 -4.5466) (xy 355.0666 -3.8354) (xy 355.0666 -2.794) (xy 355.346 -2.5146) (xy 356.3874 -2.5146)
				(xy 359.3084 -2.5146) (xy 359.3338 -2.54) (xy 359.918 -2.54) (xy 368.2238 -10.8458) (xy 368.2238 -10.8712)
				(xy 372.5037 -15.1511) (xy 372.8212 -15.4686) (xy 372.8212 -42.823638) (xy 372.312184 -43.332654)
				(xy 369.42903 -43.332654) (xy 369.0366 -42.940224) (xy 369.0366 -42.672) (xy 369.0366 -15.7226)
				(xy 368.5286 -15.2146) (xy 368.2238 -14.9098) (xy 364.5916 -11.2776) (xy 358.0638 -4.7498) (xy 355.2698 -4.7498)
			)
		)
	)
	(zone
		(net "GND")
		(layer "In7.Cu")
		(hatch none 0.5)
		(connect_pads
			(clearance 0.5)
		)
		(min_thickness 0.25)
		(fill yes
			(thermal_gap 0.5)
			(thermal_bridge_width 0.5)
			(island_removal_mode 0)
		)
		(polygon
			(pts
				(xy 33.1724 -93.7133) (xy 33.1724 -94.145354) (xy 33.1724 -94.84614) (xy 33.173416 -94.847156) (xy 33.1724 -94.84741)
				(xy 33.1724 -95.644208) (xy 32.9184 -95.898208) (xy 31.636208 -95.898208) (xy 31.5722 -95.962216)
				(xy 31.5722 -97.649284) (xy 31.636208 -97.713292) (xy 32.867092 -97.713292) (xy 33.1724 -98.0186)
				(xy 33.1724 -102.5271) (xy 33.3756 -102.7303) (xy 38.4429 -102.7303) (xy 39.37 -101.8032) (xy 42.30878 -101.8032)
				(xy 42.926 -101.18598) (xy 42.926 -93.845888) (xy 42.59072 -93.510608) (xy 33.375092 -93.510608)
			)
		)
	)
	(zone
		(net "PVCCMCP_CPU1")
		(layer "In7.Cu")
		(hatch none 0.5)
		(connect_pads
			(clearance 0.5)
		)
		(min_thickness 0.25)
		(fill yes
			(thermal_gap 0.5)
			(thermal_bridge_width 0.5)
			(island_removal_mode 0)
		)
		(polygon
			(pts
				(xy 149.379432 -45.235368) (xy 145.415 -49.1998) (xy 104.9528 -49.1998) (xy 104.2162 -49.9364) (xy 104.2162 -52.243736)
				(xy 104.2162 -64.033908) (xy 104.2162 -66.6496) (xy 104.2162 -78.8924) (xy 104.2924 -78.9686) (xy 104.394 -79.0702)
				(xy 112.7252 -79.0702) (xy 112.8903 -78.9051) (xy 112.8903 -77.978) (xy 113.1951 -77.6732) (xy 120.6754 -77.6732)
				(xy 121.92 -78.9178) (xy 121.92 -83.185) (xy 120.929908 -84.175092) (xy 120.929908 -86.614) (xy 120.929654 -86.614254)
				(xy 120.929654 -90.1446)
				(arc
					(start 121.566432 -90.781378)
					(mid 121.599951 -90.80853)
					(end 121.629932 -90.839544)
				)
				(xy 122.03049 -91.240102) (xy 122.15368 -91.363292) (xy 122.51055 -91.363292) (xy 123.641866 -91.363292)
				(xy 123.901708 -91.363292) (xy 125.095 -90.17) (xy 125.095 -86.7156) (xy 125.095 -86.5886) (xy 126.1999 -85.4837)
				(xy 126.6571 -85.4837) (xy 127.7112 -84.4296) (xy 132.69468 -84.4296) (xy 141.6558 -75.46848) (xy 158.670498 -58.453782)
				(xy 158.670498 -56.696356) (xy 159.954468 -55.412386) (xy 160.020254 -55.3466) (xy 160.655 -55.3466)
				(xy 165.5826 -55.3466) (xy 167.5257 -57.2897) (xy 167.5257 -61.5315) (xy 168.1734 -62.1792) (xy 186.0423 -62.1792)
				(xy 186.6646 -61.5569) (xy 186.6646 -55.5879) (xy 186.9059 -55.3466) (xy 193.2432 -55.3466) (xy 195.301616 -53.288184)
				(xy 195.301616 -49.802796) (xy 195.301616 -47.954184) (xy 195.301616 -45.6946) (xy 194.842384 -45.235368)
				(xy 164.44341 -45.235368) (xy 163.511992 -46.166786) (xy 160.98901 -46.166786) (xy 160.057592 -45.235368)
			)
		)
	)
	(zone
		(net "PVDDQ_ABC")
		(layer "In8.Cu")
		(hatch none 0.5)
		(connect_pads
			(clearance 0.5)
		)
		(min_thickness 0.25)
		(fill yes
			(thermal_gap 0.5)
			(thermal_bridge_width 0.5)
			(island_removal_mode 0)
		)
		(polygon
			(pts
				(xy 266.51839 -16.63446) (xy 266.1158 -17.036796) (xy 266.1158 -18.275554) (xy 265.92784 -18.463514)
				(xy 265.92784 -19.052794) (xy 265.54938 -19.431254) (xy 265.54938 -23.113746)
				(arc
					(start 266.00404 -23.56866)
					(mid 266.045392 -23.630409)
					(end 266.05992 -23.70328)
				)
				(xy 266.05992 -26.16327) (xy 266.949682 -27.05354) (xy 273.81073 -27.05354) (xy 277.298404 -23.56866)
				(xy 278.64054 -22.22754) (xy 278.64054 -17.01673) (xy 278.258524 -16.63446)
			)
		)
	)
	(zone
		(net "P12V_PSU")
		(layer "In8.Cu")
		(hatch none 0.5)
		(connect_pads
			(clearance 0.5)
		)
		(min_thickness 0.25)
		(fill yes
			(thermal_gap 0.5)
			(thermal_bridge_width 0.5)
			(island_removal_mode 0)
		)
		(polygon
			(pts
				(xy 3.361944 -50.038) (xy 3.0734 -50.326544) (xy 3.0734 -59.089544) (xy 2.286 -59.876944) (xy 2.286 -67.224656)
				(xy 3.5052 -68.443856) (xy 3.5052 -85.563456) (xy 4.123944 -86.1822) (xy 9.844278 -86.1822) (xy 10.092436 -85.934042)
				(xy 10.092436 -50.67173) (xy 9.458706 -50.038)
			)
		)
	)
	(zone
		(layer "In8.Cu")
		(hatch none 0.5)
		(connect_pads
			(clearance 0)
		)
		(min_thickness 0.25)
		(keepout
			(tracks not_allowed)
			(vias allowed)
			(pads allowed)
			(copperpour not_allowed)
			(footprints allowed)
		)
		(placement
			(enabled no)
			(sheetname "")
		)
		(fill
			(thermal_gap 0.5)
			(thermal_bridge_width 0.5)
			(island_removal_mode 0)
		)
		(polygon
			(pts
				(arc
					(start 481.96754 -125.22073)
					(mid 480.235259 -125.222)
					(end 481.96754 -125.22327)
				)
				(arc
					(start 481.8761 -125.22327)
					(mid 481.1014 -125.995434)
					(end 480.3267 -125.22327)
				)
				(arc
					(start 480.3267 -125.22073)
					(mid 481.1014 -124.44603)
					(end 481.8761 -125.22073)
				)
			)
		)
	)
	(zone
		(net "PVDDQ_ABC")
		(layer "In8.Cu")
		(hatch none 0.5)
		(connect_pads
			(clearance 0.5)
		)
		(min_thickness 0.25)
		(fill yes
			(thermal_gap 0.5)
			(thermal_bridge_width 0.5)
			(island_removal_mode 0)
		)
		(polygon
			(pts
				(xy 246.509794 -16.50746) (xy 245.61546 -17.401794) (xy 245.61546 -22.579584) (xy 246.659654 -23.624794)
				(xy 255.655572 -23.624794) (xy 256.41808 -22.862286) (xy 256.41808 -16.639794) (xy 256.285746 -16.50746)
			)
		)
	)
	(zone
		(net "PVDDQ_DEF")
		(layer "In8.Cu")
		(hatch none 0.5)
		(connect_pads
			(clearance 0.5)
		)
		(min_thickness 0.25)
		(fill yes
			(thermal_gap 0.5)
			(thermal_bridge_width 0.5)
			(island_removal_mode 0)
		)
		(polygon
			(pts
				(xy 274.733004 -126.17704)
				(arc
					(start 271.930368 -128.976374)
					(mid 271.868575 -129.017536)
					(end 271.795748 -129.032)
				)
				(xy 264.969244 -129.032) (xy 264.742422 -129.258568) (xy 264.742422 -136.454388) (xy 265.046714 -136.75868)
				(xy 278.133556 -136.75868)
				(arc
					(start 278.290274 -136.602216)
					(mid 278.302145 -136.589195)
					(end 278.315166 -136.577324)
				)
				(xy 278.36622 -136.52627) (xy 278.36622 -129.267204) (xy 278.075644 -128.976374) (xy 275.279612 -126.17704)
			)
		)
	)
	(zone
		(net "GND")
		(layer "In8.Cu")
		(hatch none 0.5)
		(connect_pads
			(clearance 0.5)
		)
		(min_thickness 0.25)
		(fill yes
			(thermal_gap 0.5)
			(thermal_bridge_width 0.5)
			(island_removal_mode 0)
		)
		(polygon
			(pts
				(arc
					(start -4.99999 5.541772)
					(mid -5.383088 5.383088)
					(end -5.541772 4.99999)
				)
				(arc
					(start -5.541772 -158.100014)
					(mid -5.383088 -158.483112)
					(end -4.99999 -158.641796)
				)
				(arc
					(start 501.000014 -158.641796)
					(mid 501.383112 -158.483112)
					(end 501.541796 -158.100014)
				)
				(arc
					(start 501.541796 -110.87989)
					(mid 501.383112 -110.496792)
					(end 501.000014 -110.338108)
				)
				(xy 432.7398 -110.338108) (xy 432.7398 -110.337346)
				(arc
					(start 428.209964 -110.337346)
					(mid 427.17939 -109.910468)
					(end 426.752512 -108.879894)
				)
				(xy 426.752512 -82.949288) (xy 426.75175 -82.95005)
				(arc
					(start 426.75175 -68.879974)
					(mid 427.178851 -67.848861)
					(end 428.209964 -67.42176)
				)
				(arc
					(start 478.48012 -67.42176)
					(mid 478.863218 -67.263076)
					(end 479.021902 -66.879978)
				)
				(arc
					(start 479.021902 -63.680086)
					(mid 479.449003 -62.648973)
					(end 480.480116 -62.221872)
				)
				(arc
					(start 501.000014 -62.221872)
					(mid 501.383112 -62.063188)
					(end 501.541796 -61.68009)
				)
				(arc
					(start 501.541796 -14.99997)
					(mid 501.383112 -14.616872)
					(end 501.000014 -14.458188)
				)
				(arc
					(start 484.349806 -14.458188)
					(mid 483.67241 -14.177496)
					(end 483.391718 -13.5001)
				)
				(arc
					(start 483.391718 2.500122)
					(mid 483.67241 3.177518)
					(end 484.349806 3.45821)
				)
				(arc
					(start 501.000014 3.45821)
					(mid 501.383112 3.616894)
					(end 501.541796 3.999992)
				)
				(arc
					(start 501.541796 4.99999)
					(mid 501.383112 5.383088)
					(end 501.000014 5.541772)
				)
			)
		)
		(polygon
			(pts
				(arc
					(start 419.97884 -39.907718)
					(mid 419.890132 -39.855573)
					(end 419.801294 -39.907718)
				)
				(arc
					(start 419.801294 -39.907718)
					(mid 419.741821 -39.986305)
					(end 419.663118 -40.04564)
				)
				(arc
					(start 419.663118 -40.04564)
					(mid 419.610751 -40.13454)
					(end 419.663118 -40.22344)
				)
				(arc
					(start 419.663118 -40.22344)
					(mid 419.742797 -40.283649)
					(end 419.802564 -40.363648)
				)
				(arc
					(start 419.802564 -40.363648)
					(mid 419.888404 -40.416315)
					(end 419.977316 -40.369236)
				)
				(arc
					(start 419.977316 -40.369236)
					(mid 420.287789 -40.203992)
					(end 420.588694 -40.386)
				)
				(arc
					(start 420.588694 -40.386)
					(mid 420.68052 -40.437965)
					(end 420.769034 -40.380412)
				)
				(arc
					(start 420.769034 -40.380412)
					(mid 420.830772 -40.290455)
					(end 420.916862 -40.22344)
				)
				(arc
					(start 420.916862 -40.22344)
					(mid 420.969007 -40.134732)
					(end 420.916862 -40.045894)
				)
				(arc
					(start 420.916862 -40.045894)
					(mid 420.838274 -39.98656)
					(end 420.77894 -39.907972)
				)
				(arc
					(start 420.77894 -39.907972)
					(mid 420.690232 -39.855827)
					(end 420.601394 -39.907972)
				)
				(arc
					(start 420.601394 -39.907972)
					(mid 420.290071 -40.090865)
					(end 419.97884 -39.907718)
				)
			)
		)
		(polygon
			(pts
				(arc
					(start 419.178994 -40.707818)
					(mid 419.090286 -40.655673)
					(end 419.001448 -40.707818)
				)
				(arc
					(start 419.001448 -40.707818)
					(mid 418.943757 -40.784752)
					(end 418.86759 -40.843454)
				)
				(arc
					(start 418.86759 -40.843454)
					(mid 418.816553 -40.929546)
					(end 418.864034 -41.017698)
				)
				(arc
					(start 418.864034 -41.017698)
					(mid 418.916874 -41.580177)
					(end 418.359844 -41.485312)
				)
				(arc
					(start 418.359844 -41.485312)
					(mid 418.270779 -41.430988)
					(end 418.180774 -41.483788)
				)
				(arc
					(start 418.180774 -41.483788)
					(mid 417.884888 -41.66859)
					(end 417.573206 -41.511982)
				)
				(arc
					(start 417.573206 -41.511982)
					(mid 417.485647 -41.467421)
					(end 417.401248 -41.517824)
				)
				(arc
					(start 417.401248 -41.517824)
					(mid 417.343328 -41.592264)
					(end 417.267898 -41.648888)
				)
				(arc
					(start 417.267898 -41.648888)
					(mid 417.215884 -41.737077)
					(end 417.267136 -41.825672)
				)
				(arc
					(start 417.267136 -41.825672)
					(mid 417.343596 -41.884442)
					(end 417.401502 -41.961562)
				)
				(arc
					(start 417.401502 -41.961562)
					(mid 417.49034 -42.013799)
					(end 417.579048 -41.961562)
				)
				(arc
					(start 417.579048 -41.961562)
					(mid 417.890198 -41.778538)
					(end 418.201348 -41.961562)
				)
				(arc
					(start 418.201348 -41.961562)
					(mid 418.290186 -42.013799)
					(end 418.378894 -41.961562)
				)
				(arc
					(start 418.378894 -41.961562)
					(mid 418.690044 -41.778669)
					(end 419.001194 -41.961562)
				)
				(arc
					(start 419.001194 -41.961562)
					(mid 419.090032 -42.013929)
					(end 419.17874 -41.961562)
				)
				(arc
					(start 419.17874 -41.961562)
					(mid 419.238162 -41.882808)
					(end 419.316916 -41.823386)
				)
				(arc
					(start 419.316916 -41.823386)
					(mid 419.369061 -41.734678)
					(end 419.316916 -41.64584)
				)
				(arc
					(start 419.316916 -41.64584)
					(mid 419.134023 -41.334579)
					(end 419.31717 -41.02354)
				)
				(arc
					(start 419.31717 -41.02354)
					(mid 419.369537 -40.93464)
					(end 419.31717 -40.84574)
				)
				(arc
					(start 419.31717 -40.84574)
					(mid 419.238415 -40.786457)
					(end 419.178994 -40.707818)
				)
			)
		)
		(polygon
			(pts
				(arc
					(start 435.66461 -136.344914)
					(mid 435.440681 -135.804303)
					(end 434.90007 -135.580374)
				)
				(arc
					(start 433.63007 -135.580374)
					(mid 432.86553 -136.344914)
					(end 433.63007 -137.109454)
				)
				(arc
					(start 434.90007 -137.109454)
					(mid 435.439783 -136.886423)
					(end 435.66461 -136.347454)
				)
				(xy 435.473856 -136.347454) (xy 435.473856 -136.344914)
			)
		)
		(polygon
			(pts
				(arc
					(start 431.85461 -136.344914)
					(mid 431.630681 -135.804303)
					(end 431.09007 -135.580374)
				)
				(arc
					(start 429.82007 -135.580374)
					(mid 429.05553 -136.344914)
					(end 429.82007 -137.109454)
				)
				(arc
					(start 431.09007 -137.109454)
					(mid 431.629783 -136.886423)
					(end 431.85461 -136.347454)
				)
				(xy 431.666142 -136.347454) (xy 431.666142 -136.344914)
			)
		)
		(polygon
			(pts
				(xy 379.328934 -131.699) (xy 378.353066 -131.699) (xy 378.1298 -131.922266) (xy 378.1298 -132.237734)
				(xy 378.353066 -132.461) (xy 379.328934 -132.461) (xy 379.5522 -132.237734) (xy 379.5522 -131.922266)
			)
		)
		(polygon
			(pts
				(xy 383.681224 -131.20751) (xy 382.705356 -131.20751) (xy 382.48209 -131.430776) (xy 382.48209 -131.746244)
				(xy 382.705356 -131.96951) (xy 383.681224 -131.96951) (xy 383.90449 -131.746244) (xy 383.90449 -131.430776)
			)
		)
		(polygon
			(pts
				(xy 381.324104 -130.688588) (xy 380.348236 -130.688588) (xy 380.12497 -130.911854) (xy 380.12497 -131.227322)
				(xy 380.348236 -131.450588) (xy 381.324104 -131.450588) (xy 381.54737 -131.227322) (xy 381.54737 -130.911854)
			)
		)
		(polygon
			(pts
				(xy 383.592324 -129.32283) (xy 382.616456 -129.32283) (xy 382.39319 -129.546096) (xy 382.39319 -129.861564)
				(xy 382.620266 -130.08864) (xy 383.5908 -130.08864) (xy 383.81432 -129.86512) (xy 383.81432 -129.862834)
				(xy 383.81559 -129.861564) (xy 383.81559 -129.546096)
			)
		)
		(polygon
			(pts
				(xy 381.380492 -128.762506) (xy 380.404624 -128.762506) (xy 380.181358 -128.985772) (xy 380.181358 -129.30124)
				(xy 380.404624 -129.524506) (xy 381.380492 -129.524506) (xy 381.603758 -129.30124) (xy 381.603758 -128.985772)
			)
		)
		(polygon
			(pts
				(xy 254.585978 -128.761744) (xy 246.742712 -128.761744)
				(arc
					(start 245.149624 -130.355086)
					(mid 245.108272 -130.416835)
					(end 245.093744 -130.489706)
				)
				(xy 245.093744 -135.689848)
				(arc
					(start 246.46509 -137.06094)
					(mid 246.526839 -137.102292)
					(end 246.59971 -137.11682)
				)
				(arc
					(start 256.06248 -137.11682)
					(mid 256.135327 -137.102236)
					(end 256.1971 -137.06094)
				)
				(arc
					(start 256.749296 -136.508744)
					(mid 256.790648 -136.446995)
					(end 256.805176 -136.374124)
				)
				(xy 256.805176 -130.653282) (xy 256.805176 -130.633724) (xy 256.805176 -130.564382) (xy 256.756154 -130.515614)
				(xy 256.742438 -130.501644) (xy 256.197354 -129.95656) (xy 255.780794 -129.95656)
			)
		)
		(polygon
			(pts
				(xy 91.804236 -129.331212)
				(arc
					(start 91.297506 -128.824482)
					(mid 91.228766 -128.77601)
					(end 91.145868 -128.761744)
				)
				(xy 81.741772 -128.761744)
				(arc
					(start 80.148684 -130.355086)
					(mid 80.107332 -130.416835)
					(end 80.092804 -130.489706)
				)
				(xy 80.092804 -135.689848)
				(arc
					(start 81.71053 -137.30732)
					(mid 81.772279 -137.348672)
					(end 81.84515 -137.3632)
				)
				(xy 90.894154 -137.3632)
				(arc
					(start 91.748356 -136.508744)
					(mid 91.789708 -136.446995)
					(end 91.804236 -136.374124)
				)
			)
		)
		(polygon
			(pts
				(xy 378.204984 -128.651) (xy 377.229116 -128.651) (xy 377.00585 -128.874266) (xy 377.00585 -129.189734)
				(xy 377.229116 -129.413) (xy 378.204984 -129.413) (xy 378.42825 -129.189734) (xy 378.42825 -128.874266)
			)
		)
		(polygon
			(pts
				(xy 376.579384 -128.64465) (xy 375.603516 -128.64465) (xy 375.38025 -128.867916) (xy 375.38025 -129.183384)
				(xy 375.603516 -129.40665) (xy 376.579384 -129.40665) (xy 376.80265 -129.183384) (xy 376.80265 -128.867916)
			)
		)
		(polygon
			(pts
				(xy 383.983738 -127.390652) (xy 383.03327 -127.390652) (xy 382.810004 -127.613918) (xy 382.810004 -127.929386)
				(xy 383.03327 -128.152652) (xy 383.983738 -128.152652) (xy 384.207004 -127.929386) (xy 384.207004 -127.613918)
			)
		)
		(polygon
			(pts
				(xy 387.888734 -126.9492) (xy 387.573266 -126.9492) (xy 387.35 -127.172466) (xy 387.35 -128.122934)
				(xy 387.573266 -128.3462) (xy 387.888734 -128.3462) (xy 388.112 -128.122934) (xy 388.112 -127.172466)
			)
		)
		(polygon
			(pts
				(arc
					(start 275.49348 -125.85192)
					(mid 275.431599 -125.810573)
					(end 275.358606 -125.79604)
				)
				(xy 274.575524 -125.79604) (xy 274.51939 -125.85192) (xy 271.717008 -128.651) (xy 264.811764 -128.651)
				(xy 264.644886 -128.817624)
				(arc
					(start 264.417302 -129.0447)
					(mid 264.375955 -129.106581)
					(end 264.361422 -129.179574)
				)
				(arc
					(start 264.361422 -136.533382)
					(mid 264.376006 -136.606229)
					(end 264.417302 -136.668002)
				)
				(arc
					(start 264.825988 -137.076942)
					(mid 264.894728 -137.125414)
					(end 264.977626 -137.13968)
				)
				(arc
					(start 278.212296 -137.13968)
					(mid 278.285128 -137.125228)
					(end 278.346916 -137.084054)
				)
				(xy 278.565864 -136.86536) (xy 278.578056 -136.853168)
				(arc
					(start 278.69134 -136.740138)
					(mid 278.732687 -136.678257)
					(end 278.74722 -136.605264)
				)
				(xy 278.74722 -129.109724)
			)
		)
		(polygon
			(pts
				(arc
					(start 110.49254 -125.85192)
					(mid 110.430659 -125.810573)
					(end 110.357666 -125.79604)
				)
				(xy 109.574584 -125.79604) (xy 106.716068 -128.651) (xy 99.810824 -128.651)
				(arc
					(start 99.416362 -129.0447)
					(mid 99.375015 -129.106581)
					(end 99.360482 -129.179574)
				)
				(xy 99.360482 -136.777476)
				(arc
					(start 99.79152 -137.20826)
					(mid 99.853269 -137.249612)
					(end 99.92614 -137.26414)
				)
				(xy 113.434876 -137.26414)
				(arc
					(start 113.683288 -137.015982)
					(mid 113.731914 -136.947278)
					(end 113.74628 -136.864344)
				)
				(xy 113.74628 -129.109724)
			)
		)
		(polygon
			(pts
				(arc
					(start 370.834158 -77.667866)
					(mid 370.745258 -77.615499)
					(end 370.656358 -77.667866)
				)
				(arc
					(start 370.656358 -77.667866)
					(mid 370.597075 -77.746621)
					(end 370.518436 -77.806042)
				)
				(arc
					(start 370.518436 -77.806042)
					(mid 370.466069 -77.89488)
					(end 370.518436 -77.983588)
				)
				(arc
					(start 370.518436 -77.983588)
					(mid 370.701329 -78.294849)
					(end 370.518182 -78.605888)
				)
				(arc
					(start 370.518182 -78.605888)
					(mid 370.465815 -78.694788)
					(end 370.518182 -78.783688)
				)
				(arc
					(start 370.518182 -78.783688)
					(mid 370.596936 -78.84311)
					(end 370.656358 -78.921864)
				)
				(arc
					(start 370.656358 -78.921864)
					(mid 370.745258 -78.974231)
					(end 370.834158 -78.921864)
				)
				(arc
					(start 370.834158 -78.921864)
					(mid 371.145197 -78.73884)
					(end 371.456458 -78.92161)
				)
				(arc
					(start 371.456458 -78.92161)
					(mid 371.545296 -78.973977)
					(end 371.634004 -78.92161)
				)
				(arc
					(start 371.634004 -78.92161)
					(mid 371.693338 -78.843022)
					(end 371.771926 -78.783688)
				)
				(arc
					(start 371.771926 -78.783688)
					(mid 371.824071 -78.69498)
					(end 371.771926 -78.606142)
				)
				(arc
					(start 371.771926 -78.606142)
					(mid 371.588902 -78.29493)
					(end 371.771926 -77.983588)
				)
				(arc
					(start 371.771926 -77.983588)
					(mid 371.823941 -77.89488)
					(end 371.771926 -77.806042)
				)
				(arc
					(start 371.771926 -77.806042)
					(mid 371.693338 -77.746708)
					(end 371.634004 -77.66812)
				)
				(arc
					(start 371.634004 -77.66812)
					(mid 371.545296 -77.615975)
					(end 371.456458 -77.66812)
				)
				(arc
					(start 371.456458 -77.66812)
					(mid 371.145197 -77.851013)
					(end 370.834158 -77.667866)
				)
			)
		)
		(polygon
			(pts
				(arc
					(start 350.30664 -60.21451)
					(mid 350.255332 -60.164218)
					(end 350.20504 -60.215526)
				)
				(arc
					(start 350.20504 -60.222638)
					(mid 350.255332 -60.273946)
					(end 350.30664 -60.223654)
				)
			)
		)
		(polygon
			(pts
				(arc
					(start 339.235542 -59.773312)
					(mid 339.184234 -59.72302)
					(end 339.133942 -59.774328)
				)
				(arc
					(start 339.133942 -59.78144)
					(mid 339.184234 -59.832748)
					(end 339.235542 -59.782456)
				)
			)
		)
		(polygon
			(pts
				(arc
					(start 344.88755 -59.360562)
					(mid 344.836242 -59.31027)
					(end 344.78595 -59.361578)
				)
				(arc
					(start 344.78595 -59.36869)
					(mid 344.836242 -59.419998)
					(end 344.88755 -59.369706)
				)
			)
		)
		(polygon
			(pts
				(arc
					(start 346.481146 -59.068208)
					(mid 346.429838 -59.017916)
					(end 346.379546 -59.069224)
				)
				(arc
					(start 346.379546 -59.076336)
					(mid 346.429838 -59.127644)
					(end 346.481146 -59.077352)
				)
			)
		)
		(polygon
			(pts
				(xy 19.236944 -55.4482) (xy 12.944856 -55.4482) (xy 11.8872 -56.505856) (xy 11.8872 -66.303144)
				(xy 14.697456 -69.1134) (xy 19.033744 -69.1134) (xy 20.32 -67.827144) (xy 20.32 -56.531256)
			)
		)
		(polygon
			(pts
				(xy 9.984994 -48.768) (xy 2.835656 -48.768) (xy 1.8034 -49.800256) (xy 1.8034 -58.563256) (xy 1.016 -59.350656)
				(xy 1.016 -67.750944) (xy 2.2352 -68.970144) (xy 2.2352 -86.089744) (xy 3.597656 -87.4522) (xy 10.370566 -87.4522)
				(xy 11.362436 -86.46033) (xy 11.362436 -50.145442)
			)
		)
		(polygon
			(pts
				(arc
					(start 278.472392 -16.30934)
					(mid 278.410511 -16.267993)
					(end 278.337518 -16.25346)
				)
				(xy 266.36091 -16.25346) (xy 266.187936 -16.42618)
				(arc
					(start 265.79068 -16.822928)
					(mid 265.749333 -16.884809)
					(end 265.7348 -16.957802)
				)
				(xy 265.7348 -18.117566)
				(arc
					(start 265.60272 -18.2499)
					(mid 265.561368 -18.311649)
					(end 265.54684 -18.38452)
				)
				(xy 265.54684 -18.894806)
				(arc
					(start 265.22426 -19.21764)
					(mid 265.182908 -19.279389)
					(end 265.16838 -19.35226)
				)
				(xy 265.16838 -23.271734) (xy 265.67892 -23.782274) (xy 265.67892 -26.32075)
				(arc
					(start 266.728956 -27.371548)
					(mid 266.79766 -27.420174)
					(end 266.880594 -27.43454)
				)
				(xy 273.96821 -27.43454)
				(arc
					(start 278.96566 -22.441408)
					(mid 279.007007 -22.379527)
					(end 279.02154 -22.306534)
				)
				(xy 279.02154 -16.85925)
			)
		)
		(polygon
			(pts
				(xy 256.443734 -16.12646)
				(arc
					(start 246.4308 -16.12646)
					(mid 246.357953 -16.141044)
					(end 246.29618 -16.18234)
				)
				(xy 245.23446 -17.243806)
				(arc
					(start 245.23446 -22.658324)
					(mid 245.248912 -22.731156)
					(end 245.290086 -22.792944)
				)
				(arc
					(start 246.445786 -23.949914)
					(mid 246.507667 -23.991261)
					(end 246.58066 -24.005794)
				)
				(arc
					(start 255.72466 -24.005794)
					(mid 255.807567 -23.991551)
					(end 255.876298 -23.943056)
				)
				(xy 256.79908 -23.020274)
				(arc
					(start 256.79908 -16.5608)
					(mid 256.784496 -16.487953)
					(end 256.7432 -16.42618)
				)
			)
		)
		(polygon
			(pts
				(arc
					(start 91.39936 -16.05534)
					(mid 91.337611 -16.013988)
					(end 91.26474 -15.99946)
				)
				(xy 80.484726 -15.99946)
				(arc
					(start 79.943198 -16.540988)
					(mid 79.894726 -16.609728)
					(end 79.88046 -16.692626)
				)
				(xy 79.88046 -23.147274)
				(arc
					(start 81.06156 -24.32812)
					(mid 81.123309 -24.369472)
					(end 81.19618 -24.384)
				)
				(xy 91.089734 -24.384)
				(arc
					(start 91.75242 -23.72106)
					(mid 91.793772 -23.659311)
					(end 91.8083 -23.58644)
				)
				(xy 91.8083 -16.464026)
			)
		)
		(polygon
			(pts
				(arc
					(start 113.37036 -15.80388)
					(mid 113.308611 -15.762528)
					(end 113.23574 -15.748)
				)
				(arc
					(start 100.62718 -15.748)
					(mid 100.554333 -15.762584)
					(end 100.49256 -15.80388)
				)
				(arc
					(start 99.11334 -17.1831)
					(mid 99.071988 -17.244849)
					(end 99.05746 -17.31772)
				)
				(xy 99.05746 -25.181814)
				(arc
					(start 101.50856 -27.63266)
					(mid 101.570309 -27.674012)
					(end 101.64318 -27.68854)
				)
				(xy 109.250734 -27.68854)
				(arc
					(start 114.110262 -22.829012)
					(mid 114.158734 -22.760272)
					(end 114.173 -22.677374)
				)
				(xy 114.173 -16.606266)
			)
		)
		(polygon
			(pts
				(arc
					(start 483.39121 -11.36142)
					(mid 483.336833 -11.281355)
					(end 483.24008 -11.283188)
				)
				(arc
					(start 483.24008 -11.283188)
					(mid 482.878425 -11.387468)
					(end 482.50856 -11.317732)
				)
				(arc
					(start 482.50856 -11.317732)
					(mid 482.403723 -11.331162)
					(end 482.36759 -11.430508)
				)
				(arc
					(start 482.36759 -11.430508)
					(mid 482.383385 -11.59002)
					(end 482.36759 -11.749532)
				)
				(arc
					(start 482.36759 -11.749532)
					(mid 482.403701 -11.848905)
					(end 482.50856 -11.862308)
				)
				(arc
					(start 482.50856 -11.862308)
					(mid 482.878424 -11.792603)
					(end 483.24008 -11.896852)
				)
				(arc
					(start 483.24008 -11.896852)
					(mid 483.33682 -11.898659)
					(end 483.39121 -11.81862)
				)
			)
		)
		(polygon
			(pts
				(arc
					(start 483.39121 -9.331452)
					(mid 483.336833 -9.251387)
					(end 483.24008 -9.25322)
				)
				(arc
					(start 483.24008 -9.25322)
					(mid 482.878425 -9.3575)
					(end 482.50856 -9.287764)
				)
				(arc
					(start 482.50856 -9.287764)
					(mid 482.403723 -9.301194)
					(end 482.36759 -9.40054)
				)
				(arc
					(start 482.36759 -9.40054)
					(mid 482.383385 -9.560052)
					(end 482.36759 -9.719564)
				)
				(arc
					(start 482.36759 -9.719564)
					(mid 482.403701 -9.818937)
					(end 482.50856 -9.83234)
				)
				(arc
					(start 482.50856 -9.83234)
					(mid 482.878424 -9.762635)
					(end 483.24008 -9.866884)
				)
				(arc
					(start 483.24008 -9.866884)
					(mid 483.33682 -9.868691)
					(end 483.39121 -9.788652)
				)
			)
		)
		(polygon
			(pts
				(arc
					(start 483.39121 -7.301484)
					(mid 483.336833 -7.221419)
					(end 483.24008 -7.223252)
				)
				(arc
					(start 483.24008 -7.223252)
					(mid 482.878425 -7.327532)
					(end 482.50856 -7.257796)
				)
				(arc
					(start 482.50856 -7.257796)
					(mid 482.403723 -7.271226)
					(end 482.36759 -7.370572)
				)
				(arc
					(start 482.36759 -7.370572)
					(mid 482.383385 -7.530084)
					(end 482.36759 -7.689596)
				)
				(arc
					(start 482.36759 -7.689596)
					(mid 482.403701 -7.788969)
					(end 482.50856 -7.802372)
				)
				(arc
					(start 482.50856 -7.802372)
					(mid 482.878424 -7.732667)
					(end 483.24008 -7.836916)
				)
				(arc
					(start 483.24008 -7.836916)
					(mid 483.33682 -7.838723)
					(end 483.39121 -7.758684)
				)
			)
		)
		(polygon
			(pts
				(arc
					(start 483.39121 -5.271516)
					(mid 483.336833 -5.191451)
					(end 483.24008 -5.193284)
				)
				(arc
					(start 483.24008 -5.193284)
					(mid 482.864287 -5.298109)
					(end 482.482906 -5.21589)
				)
				(arc
					(start 482.482906 -5.21589)
					(mid 482.375359 -5.227301)
					(end 482.339142 -5.329174)
				)
				(arc
					(start 482.339142 -5.329174)
					(mid 482.35791 -5.500116)
					(end 482.339142 -5.671058)
				)
				(arc
					(start 482.339142 -5.671058)
					(mid 482.375396 -5.772884)
					(end 482.482906 -5.784342)
				)
				(arc
					(start 482.482906 -5.784342)
					(mid 482.864288 -5.702108)
					(end 483.24008 -5.806948)
				)
				(arc
					(start 483.24008 -5.806948)
					(mid 483.33682 -5.808755)
					(end 483.39121 -5.728716)
				)
			)
		)
		(polygon
			(pts
				(arc
					(start 483.39121 -3.241548)
					(mid 483.336833 -3.161483)
					(end 483.24008 -3.163316)
				)
				(arc
					(start 483.24008 -3.163316)
					(mid 482.878425 -3.267596)
					(end 482.50856 -3.19786)
				)
				(arc
					(start 482.50856 -3.19786)
					(mid 482.403723 -3.21129)
					(end 482.36759 -3.310636)
				)
				(arc
					(start 482.36759 -3.310636)
					(mid 482.383385 -3.470148)
					(end 482.36759 -3.62966)
				)
				(arc
					(start 482.36759 -3.62966)
					(mid 482.403701 -3.729033)
					(end 482.50856 -3.742436)
				)
				(arc
					(start 482.50856 -3.742436)
					(mid 482.878424 -3.672731)
					(end 483.24008 -3.77698)
				)
				(arc
					(start 483.24008 -3.77698)
					(mid 483.33682 -3.778787)
					(end 483.39121 -3.698748)
				)
			)
		)
		(polygon
			(pts
				(arc
					(start 483.39121 -1.21158)
					(mid 483.336833 -1.131515)
					(end 483.24008 -1.133348)
				)
				(arc
					(start 483.24008 -1.133348)
					(mid 482.878425 -1.237628)
					(end 482.50856 -1.167892)
				)
				(arc
					(start 482.50856 -1.167892)
					(mid 482.403723 -1.181322)
					(end 482.36759 -1.280668)
				)
				(arc
					(start 482.36759 -1.280668)
					(mid 482.383385 -1.44018)
					(end 482.36759 -1.599692)
				)
				(arc
					(start 482.36759 -1.599692)
					(mid 482.403701 -1.699065)
					(end 482.50856 -1.712468)
				)
				(arc
					(start 482.50856 -1.712468)
					(mid 482.878424 -1.642763)
					(end 483.24008 -1.747012)
				)
				(arc
					(start 483.24008 -1.747012)
					(mid 483.33682 -1.748819)
					(end 483.39121 -1.66878)
				)
			)
		)
		(polygon
			(pts
				(arc
					(start 483.39121 0.818388)
					(mid 483.336833 0.898453)
					(end 483.24008 0.89662)
				)
				(arc
					(start 483.24008 0.89662)
					(mid 482.878425 0.79234)
					(end 482.50856 0.862076)
				)
				(arc
					(start 482.50856 0.862076)
					(mid 482.403723 0.848646)
					(end 482.36759 0.7493)
				)
				(arc
					(start 482.36759 0.7493)
					(mid 482.383385 0.589788)
					(end 482.36759 0.430276)
				)
				(arc
					(start 482.36759 0.430276)
					(mid 482.403701 0.330903)
					(end 482.50856 0.3175)
				)
				(arc
					(start 482.50856 0.3175)
					(mid 482.878424 0.387205)
					(end 483.24008 0.282956)
				)
				(arc
					(start 483.24008 0.282956)
					(mid 483.33682 0.281149)
					(end 483.39121 0.361188)
				)
			)
		)
	)
	(zone
		(net "P12V_MB0_SW")
		(layer "In8.Cu")
		(hatch none 0.5)
		(connect_pads
			(clearance 0.5)
		)
		(min_thickness 0.25)
		(fill yes
			(thermal_gap 0.5)
			(thermal_bridge_width 0.5)
			(island_removal_mode 0)
		)
		(polygon
			(pts
				(xy 13.471144 -56.7182) (xy 13.1572 -57.032144) (xy 13.1572 -65.776856) (xy 15.223744 -67.8434)
				(xy 18.507456 -67.8434) (xy 19.05 -67.300856) (xy 19.05 -57.057544) (xy 18.710656 -56.7182)
			)
		)
	)
	(zone
		(net "PVDDQ_KLM")
		(layer "In8.Cu")
		(hatch none 0.5)
		(connect_pads
			(clearance 0.5)
		)
		(min_thickness 0.25)
		(fill yes
			(thermal_gap 0.5)
			(thermal_bridge_width 0.5)
			(island_removal_mode 0)
		)
		(polygon
			(pts
				(xy 81.89976 -129.142744) (xy 80.473804 -130.5687) (xy 80.473804 -135.53186) (xy 81.924144 -136.9822)
				(xy 90.736166 -136.9822) (xy 91.423236 -136.29513) (xy 91.423236 -129.4892) (xy 91.07678 -129.142744)
			)
		)
	)
	(zone
		(net "PVDDQ_GHJ")
		(layer "In8.Cu")
		(hatch none 0.5)
		(connect_pads
			(clearance 0.5)
		)
		(min_thickness 0.25)
		(fill yes
			(thermal_gap 0.5)
			(thermal_bridge_width 0.5)
			(island_removal_mode 0)
		)
		(polygon
			(pts
				(xy 100.706174 -16.129) (xy 99.43846 -17.396714) (xy 99.43846 -25.023826) (xy 101.722174 -27.30754)
				(xy 109.092746 -27.30754) (xy 113.792 -22.608286) (xy 113.792 -16.764254) (xy 113.156746 -16.129)
			)
		)
	)
	(zone
		(net "PVDDQ_DEF")
		(layer "In8.Cu")
		(hatch none 0.5)
		(connect_pads
			(clearance 0.5)
		)
		(min_thickness 0.25)
		(fill yes
			(thermal_gap 0.5)
			(thermal_bridge_width 0.5)
			(island_removal_mode 0)
		)
		(polygon
			(pts
				(xy 246.9007 -129.142744) (xy 245.474744 -130.5687) (xy 245.474744 -135.53186) (xy 246.678704 -136.73582)
				(xy 255.983486 -136.73582) (xy 256.424176 -136.29513) (xy 256.424176 -130.72237) (xy 256.039366 -130.33756)
				(xy 255.622806 -130.33756) (xy 254.42799 -129.142744)
			)
		)
	)
	(zone
		(net "PVDDQ_KLM")
		(layer "In8.Cu")
		(hatch none 0.5)
		(connect_pads
			(clearance 0.5)
		)
		(min_thickness 0.25)
		(fill yes
			(thermal_gap 0.5)
			(thermal_bridge_width 0.5)
			(island_removal_mode 0)
		)
		(polygon
			(pts
				(xy 109.732064 -126.17704)
				(arc
					(start 106.929428 -128.976374)
					(mid 106.867635 -129.017536)
					(end 106.794808 -129.032)
				)
				(xy 99.968304 -129.032) (xy 99.741482 -129.258568) (xy 99.741482 -136.619488) (xy 100.005134 -136.88314)
				(xy 113.277396 -136.88314) (xy 113.36528 -136.795256) (xy 113.36528 -129.267204) (xy 113.074704 -128.976374)
				(xy 110.278672 -126.17704)
			)
		)
	)
	(zone
		(net "PVDDQ_GHJ")
		(layer "In8.Cu")
		(hatch none 0.5)
		(connect_pads
			(clearance 0.5)
		)
		(min_thickness 0.25)
		(fill yes
			(thermal_gap 0.5)
			(thermal_bridge_width 0.5)
			(island_removal_mode 0)
		)
		(polygon
			(pts
				(xy 80.642714 -16.38046) (xy 80.26146 -16.761714) (xy 80.26146 -22.989286) (xy 81.275174 -24.003)
				(xy 90.931746 -24.003) (xy 91.4273 -23.507446) (xy 91.4273 -16.622014) (xy 91.185746 -16.38046)
			)
		)
	)
	(zone
		(layer "In8.Cu")
		(hatch none 0.5)
		(connect_pads
			(clearance 0)
		)
		(min_thickness 0.25)
		(keepout
			(tracks not_allowed)
			(vias allowed)
			(pads allowed)
			(copperpour not_allowed)
			(footprints allowed)
		)
		(placement
			(enabled no)
			(sheetname "")
		)
		(fill
			(thermal_gap 0.5)
			(thermal_bridge_width 0.5)
			(island_removal_mode 0)
		)
		(polygon
			(pts
				(arc
					(start 31.371286 -36.964874)
					(mid 29.578554 -36.964874)
					(end 31.371286 -36.964874)
				)
			)
		)
	)
	(zone
		(layer "Cmts.User")
		(hatch none 0.5)
		(connect_pads
			(clearance 0)
		)
		(min_thickness 0.25)
		(keepout
			(tracks allowed)
			(vias allowed)
			(pads allowed)
			(copperpour allowed)
			(footprints allowed)
		)
		(placement
			(enabled no)
			(sheetname "")
		)
		(fill
			(thermal_gap 0.5)
			(thermal_bridge_width 0.5)
			(island_removal_mode 0)
		)
		(polygon
			(pts
				(xy 13.6652 -96.0628) (xy 13.6652 -91.5416) (xy 17.1196 -91.5416) (xy 17.1196 -96.0628)
			)
		)
	)
	(zone
		(layer "Cmts.User")
		(hatch none 0.5)
		(connect_pads
			(clearance 0)
		)
		(min_thickness 0.25)
		(keepout
			(tracks allowed)
			(vias allowed)
			(pads allowed)
			(copperpour allowed)
			(footprints allowed)
		)
		(placement
			(enabled no)
			(sheetname "")
		)
		(fill
			(thermal_gap 0.5)
			(thermal_bridge_width 0.5)
			(island_removal_mode 0)
		)
		(polygon
			(pts
				(xy 435.40426 -40.005) (xy 446.12306 -40.005) (xy 446.37706 -39.751) (xy 446.37706 -23.3934) (xy 445.97066 -22.987)
				(xy 435.17566 -22.987) (xy 434.92166 -23.241) (xy 434.92166 -39.5224)
			)
		)
	)
	(zone
		(layer "Cmts.User")
		(hatch none 0.5)
		(connect_pads
			(clearance 0)
		)
		(min_thickness 0.25)
		(keepout
			(tracks allowed)
			(vias allowed)
			(pads allowed)
			(copperpour allowed)
			(footprints allowed)
		)
		(placement
			(enabled no)
			(sheetname "")
		)
		(fill
			(thermal_gap 0.5)
			(thermal_bridge_width 0.5)
			(island_removal_mode 0)
		)
		(polygon
			(pts
				(xy -4.576064 -22.451568) (xy 7.60222 -22.451568) (xy 8.296402 -21.757386) (xy 8.296402 -14.855952)
				(xy 7.370826 -13.930376) (xy 6.339586 -13.930376) (xy 5.035042 -15.23492) (xy 2.25806 -15.23492)
				(xy 1.079754 -14.056614) (xy -1.886712 -14.056614) (xy -5.063998 -17.2339) (xy -5.063998 -21.963634)
			)
		)
	)
	(zone
		(layer "Cmts.User")
		(hatch none 0.5)
		(connect_pads
			(clearance 0)
		)
		(min_thickness 0.25)
		(keepout
			(tracks allowed)
			(vias allowed)
			(pads allowed)
			(copperpour allowed)
			(footprints allowed)
		)
		(placement
			(enabled no)
			(sheetname "")
		)
		(fill
			(thermal_gap 0.5)
			(thermal_bridge_width 0.5)
			(island_removal_mode 0)
		)
		(polygon
			(pts
				(xy 31.620206 -97.806256) (xy 32.334962 -97.806256) (xy 32.908494 -97.232724) (xy 32.908494 -96.002094)
				(xy 32.745426 -95.839026) (xy 31.703772 -95.839026) (xy 31.461964 -96.080834) (xy 31.461964 -97.648014)
			)
		)
	)
	(zone
		(layer "Cmts.User")
		(hatch none 0.5)
		(connect_pads
			(clearance 0)
		)
		(min_thickness 0.25)
		(keepout
			(tracks allowed)
			(vias allowed)
			(pads allowed)
			(copperpour allowed)
			(footprints allowed)
		)
		(placement
			(enabled no)
			(sheetname "")
		)
		(fill
			(thermal_gap 0.5)
			(thermal_bridge_width 0.5)
			(island_removal_mode 0)
		)
		(polygon
			(pts
				(xy -2.860802 -142.174976) (xy 0.43815 -142.174976) (xy 0.837946 -141.77518) (xy 0.837946 -136.115298)
				(xy 1.300734 -135.65251) (xy 1.858264 -135.65251) (xy 2.005584 -135.50519) (xy 2.005584 -134.968742)
				(xy 1.721612 -134.68477) (xy -2.076196 -134.68477) (xy -3.065272 -135.673846) (xy -3.065272 -141.970506)
			)
		)
	)
	(zone
		(layer "Cmts.User")
		(hatch none 0.5)
		(connect_pads
			(clearance 0)
		)
		(min_thickness 0.25)
		(keepout
			(tracks allowed)
			(vias allowed)
			(pads allowed)
			(copperpour allowed)
			(footprints allowed)
		)
		(placement
			(enabled no)
			(sheetname "")
		)
		(fill
			(thermal_gap 0.5)
			(thermal_bridge_width 0.5)
			(island_removal_mode 0)
		)
		(polygon
			(pts
				(xy 372.9228 -127.9144) (xy 372.9228 -92.2528) (xy 402.6154 -92.2528) (xy 402.6154 -116.487956)
				(xy 403.363684 -116.487956) (xy 403.648672 -116.772944) (xy 403.648672 -117.671088) (xy 403.57425 -117.74551)
				(xy 402.689822 -117.74551) (xy 402.6154 -117.819932) (xy 402.6154 -127.9144)
			)
		)
	)
	(zone
		(layer "Cmts.User")
		(hatch none 0.5)
		(connect_pads
			(clearance 0)
		)
		(min_thickness 0.25)
		(keepout
			(tracks allowed)
			(vias allowed)
			(pads allowed)
			(copperpour allowed)
			(footprints allowed)
		)
		(placement
			(enabled no)
			(sheetname "")
		)
		(fill
			(thermal_gap 0.5)
			(thermal_bridge_width 0.5)
			(island_removal_mode 0)
		)
		(polygon
			(pts
				(xy 186.390026 -10.77849) (xy 187.396628 -10.77849) (xy 187.638436 -10.536682) (xy 187.638436 -8.272272)
				(xy 187.35167 -7.985506) (xy 186.391804 -7.985506) (xy 186.207654 -8.169656) (xy 186.207654 -10.596118)
			)
		)
	)
	(zone
		(layer "Cmts.User")
		(hatch none 0.5)
		(connect_pads
			(clearance 0)
		)
		(min_thickness 0.25)
		(keepout
			(tracks allowed)
			(vias allowed)
			(pads allowed)
			(copperpour allowed)
			(footprints allowed)
		)
		(placement
			(enabled no)
			(sheetname "")
		)
		(fill
			(thermal_gap 0.5)
			(thermal_bridge_width 0.5)
			(island_removal_mode 0)
		)
		(polygon
			(pts
				(xy 25.507188 -103.566214) (xy 28.063444 -103.566214) (xy 28.363418 -103.26624) (xy 28.363418 -101.63556)
				(xy 27.921712 -101.193854) (xy 25.459944 -101.193854) (xy 25.26538 -101.388418) (xy 25.26538 -103.324406)
			)
		)
	)
	(zone
		(layer "Cmts.User")
		(hatch none 0.5)
		(connect_pads
			(clearance 0)
		)
		(min_thickness 0.25)
		(keepout
			(tracks allowed)
			(vias allowed)
			(pads allowed)
			(copperpour allowed)
			(footprints allowed)
		)
		(placement
			(enabled no)
			(sheetname "")
		)
		(fill
			(thermal_gap 0.5)
			(thermal_bridge_width 0.5)
			(island_removal_mode 0)
		)
		(polygon
			(pts
				(xy 186.805062 -17.406112) (xy 185.78703 -17.406112) (xy 185.568844 -17.187926) (xy 185.568844 -15.75689)
				(xy 185.797444 -15.52829) (xy 186.72302 -15.52829) (xy 186.951874 -15.757144) (xy 186.951874 -17.2593)
			)
		)
	)
	(zone
		(layer "Cmts.User")
		(hatch none 0.5)
		(connect_pads
			(clearance 0)
		)
		(min_thickness 0.25)
		(keepout
			(tracks allowed)
			(vias allowed)
			(pads allowed)
			(copperpour allowed)
			(footprints allowed)
		)
		(placement
			(enabled no)
			(sheetname "")
		)
		(fill
			(thermal_gap 0.5)
			(thermal_bridge_width 0.5)
			(island_removal_mode 0)
		)
		(polygon
			(pts
				(xy 355.892862 -110.494826) (xy 355.892862 -109.095286) (xy 356.01656 -109.095286) (xy 356.01656 -110.494826)
			)
		)
	)
	(zone
		(layer "Cmts.User")
		(hatch none 0.5)
		(connect_pads
			(clearance 0)
		)
		(min_thickness 0.25)
		(keepout
			(tracks allowed)
			(vias allowed)
			(pads allowed)
			(copperpour allowed)
			(footprints allowed)
		)
		(placement
			(enabled no)
			(sheetname "")
		)
		(fill
			(thermal_gap 0.5)
			(thermal_bridge_width 0.5)
			(island_removal_mode 0)
		)
		(polygon
			(pts
				(xy 11.9634 -2.0574) (xy 11.9634 0.762) (xy 15.3416 0.762) (xy 15.3416 -2.0574)
			)
		)
	)
	(zone
		(layer "Cmts.User")
		(hatch none 0.5)
		(connect_pads
			(clearance 0)
		)
		(min_thickness 0.25)
		(keepout
			(tracks allowed)
			(vias allowed)
			(pads allowed)
			(copperpour allowed)
			(footprints allowed)
		)
		(placement
			(enabled no)
			(sheetname "")
		)
		(fill
			(thermal_gap 0.5)
			(thermal_bridge_width 0.5)
			(island_removal_mode 0)
		)
		(polygon
			(pts
				(xy 188.790326 -88.543384) (xy 190.962788 -88.543384) (xy 191.420496 -88.085676) (xy 191.420496 -84.840064)
				(xy 190.942214 -84.361782) (xy 189.032388 -84.361782) (xy 188.6331 -84.76107) (xy 188.6331 -88.386158)
			)
		)
	)
	(zone
		(layer "Cmts.User")
		(hatch none 0.5)
		(connect_pads
			(clearance 0)
		)
		(min_thickness 0.25)
		(keepout
			(tracks allowed)
			(vias allowed)
			(pads allowed)
			(copperpour allowed)
			(footprints allowed)
		)
		(placement
			(enabled no)
			(sheetname "")
		)
		(fill
			(thermal_gap 0.5)
			(thermal_bridge_width 0.5)
			(island_removal_mode 0)
		)
		(polygon
			(pts
				(xy 484.71836 -51.75758) (xy 485.3559 -51.75758) (xy 485.3559 -52.37988) (xy 484.71836 -52.37988)
			)
		)
	)
	(zone
		(layer "Cmts.User")
		(hatch none 0.5)
		(connect_pads
			(clearance 0)
		)
		(min_thickness 0.25)
		(keepout
			(tracks allowed)
			(vias allowed)
			(pads allowed)
			(copperpour allowed)
			(footprints allowed)
		)
		(placement
			(enabled no)
			(sheetname "")
		)
		(fill
			(thermal_gap 0.5)
			(thermal_bridge_width 0.5)
			(island_removal_mode 0)
		)
		(polygon
			(pts
				(xy 345.8972 -20.1422) (xy 345.8972 -19.2532) (xy 346.7608 -19.2532) (xy 346.7608 -20.1422)
			)
		)
	)
	(zone
		(layer "Cmts.User")
		(hatch none 0.5)
		(connect_pads
			(clearance 0)
		)
		(min_thickness 0.25)
		(keepout
			(tracks allowed)
			(vias allowed)
			(pads allowed)
			(copperpour allowed)
			(footprints allowed)
		)
		(placement
			(enabled no)
			(sheetname "")
		)
		(fill
			(thermal_gap 0.5)
			(thermal_bridge_width 0.5)
			(island_removal_mode 0)
		)
		(polygon
			(pts
				(xy 351.57918 -138.798046) (xy 353.346512 -138.798046) (xy 353.62007 -138.524488) (xy 353.62007 -135.86841)
				(xy 353.320096 -135.568436) (xy 349.43796 -135.568436) (xy 349.095314 -135.911082) (xy 349.095314 -137.229342)
				(xy 350.546162 -138.68019) (xy 351.461324 -138.68019)
			)
		)
	)
	(zone
		(layer "Cmts.User")
		(hatch none 0.5)
		(connect_pads
			(clearance 0)
		)
		(min_thickness 0.25)
		(keepout
			(tracks allowed)
			(vias allowed)
			(pads allowed)
			(copperpour allowed)
			(footprints allowed)
		)
		(placement
			(enabled no)
			(sheetname "")
		)
		(fill
			(thermal_gap 0.5)
			(thermal_bridge_width 0.5)
			(island_removal_mode 0)
		)
		(polygon
			(pts
				(xy 10.474198 -134.074662) (xy 17.028668 -134.074662) (xy 17.344136 -133.759194) (xy 17.344136 -129.908808)
				(xy 16.281146 -128.845818) (xy 16.281146 -127.730758) (xy 14.646656 -126.096268) (xy 8.205724 -126.096268)
				(xy 6.350254 -127.951738) (xy 6.350254 -132.223256) (xy 7.139178 -133.01218) (xy 9.411716 -133.01218)
			)
		)
	)
	(zone
		(layer "Cmts.User")
		(hatch none 0.5)
		(connect_pads
			(clearance 0)
		)
		(min_thickness 0.25)
		(keepout
			(tracks allowed)
			(vias allowed)
			(pads allowed)
			(copperpour allowed)
			(footprints allowed)
		)
		(placement
			(enabled no)
			(sheetname "")
		)
		(fill
			(thermal_gap 0.5)
			(thermal_bridge_width 0.5)
			(island_removal_mode 0)
		)
		(polygon
			(pts
				(xy 344.141552 -9.610852) (xy 345.403932 -9.610852) (xy 345.67749 -9.337294) (xy 345.67749 -3.961638)
				(xy 345.172284 -3.456432) (xy 344.299032 -3.456432) (xy 343.86774 -3.887724) (xy 343.86774 -9.33704)
			)
		)
	)
	(zone
		(layer "Cmts.User")
		(hatch none 0.5)
		(connect_pads
			(clearance 0)
		)
		(min_thickness 0.25)
		(keepout
			(tracks allowed)
			(vias allowed)
			(pads allowed)
			(copperpour allowed)
			(footprints allowed)
		)
		(placement
			(enabled no)
			(sheetname "")
		)
		(fill
			(thermal_gap 0.5)
			(thermal_bridge_width 0.5)
			(island_removal_mode 0)
		)
		(polygon
			(pts
				(xy 177.838862 -100.715318) (xy 179.51196 -100.715318) (xy 180.490368 -99.73691) (xy 180.490368 -97.43313)
				(xy 180.300884 -97.243646) (xy 178.302158 -97.243646) (xy 177.597308 -97.948496) (xy 177.597308 -100.473764)
			)
		)
	)
	(zone
		(layer "Cmts.User")
		(hatch none 0.5)
		(connect_pads
			(clearance 0)
		)
		(min_thickness 0.25)
		(keepout
			(tracks allowed)
			(vias allowed)
			(pads allowed)
			(copperpour allowed)
			(footprints allowed)
		)
		(placement
			(enabled no)
			(sheetname "")
		)
		(fill
			(thermal_gap 0.5)
			(thermal_bridge_width 0.5)
			(island_removal_mode 0)
		)
		(polygon
			(pts
				(xy 30.94482 -95.39732) (xy 33.218882 -95.39732) (xy 33.523936 -95.092266) (xy 33.523936 -94.235016)
				(xy 33.27654 -93.98762) (xy 30.97276 -93.98762) (xy 30.664912 -94.295468) (xy 30.664912 -95.117412)
			)
		)
	)
	(zone
		(layer "Cmts.User")
		(hatch none 0.5)
		(connect_pads
			(clearance 0)
		)
		(min_thickness 0.25)
		(keepout
			(tracks allowed)
			(vias allowed)
			(pads allowed)
			(copperpour allowed)
			(footprints allowed)
		)
		(placement
			(enabled no)
			(sheetname "")
		)
		(fill
			(thermal_gap 0.5)
			(thermal_bridge_width 0.5)
			(island_removal_mode 0)
		)
		(polygon
			(pts
				(xy 348.167198 -102.893368) (xy 352.126042 -102.893368) (xy 352.452178 -102.567232) (xy 352.452178 -100.505514)
				(xy 351.715578 -99.768914) (xy 347.802454 -99.768914) (xy 347.370908 -100.20046) (xy 347.370908 -102.004368)
				(xy 348.161102 -102.794562) (xy 348.161102 -102.887272)
			)
		)
	)
	(zone
		(layer "Cmts.User")
		(hatch none 0.5)
		(connect_pads
			(clearance 0)
		)
		(min_thickness 0.25)
		(keepout
			(tracks allowed)
			(vias allowed)
			(pads allowed)
			(copperpour allowed)
			(footprints allowed)
		)
		(placement
			(enabled no)
			(sheetname "")
		)
		(fill
			(thermal_gap 0.5)
			(thermal_bridge_width 0.5)
			(island_removal_mode 0)
		)
		(polygon
			(pts
				(xy 356.213664 -24.112982) (xy 357.333804 -24.112982) (xy 357.633778 -23.813008) (xy 357.633778 -23.108158)
				(xy 357.349806 -22.824186) (xy 356.192582 -22.824186) (xy 355.982016 -23.034752) (xy 355.982016 -23.881334)
			)
		)
	)
	(zone
		(layer "Cmts.User")
		(hatch none 0.5)
		(connect_pads
			(clearance 0)
		)
		(min_thickness 0.25)
		(keepout
			(tracks allowed)
			(vias allowed)
			(pads allowed)
			(copperpour allowed)
			(footprints allowed)
		)
		(placement
			(enabled no)
			(sheetname "")
		)
		(fill
			(thermal_gap 0.5)
			(thermal_bridge_width 0.5)
			(island_removal_mode 0)
		)
		(polygon
			(pts
				(xy -4.953 -105.664) (xy -4.953 -89.789) (xy 9.652 -89.789) (xy 9.652 -105.664)
			)
		)
	)
	(zone
		(layer "Cmts.User")
		(hatch none 0.5)
		(connect_pads
			(clearance 0)
		)
		(min_thickness 0.25)
		(keepout
			(tracks allowed)
			(vias allowed)
			(pads allowed)
			(copperpour allowed)
			(footprints allowed)
		)
		(placement
			(enabled no)
			(sheetname "")
		)
		(fill
			(thermal_gap 0.5)
			(thermal_bridge_width 0.5)
			(island_removal_mode 0)
		)
		(polygon
			(pts
				(xy 30.693868 -68.849494) (xy 32.335216 -68.849494) (xy 33.039812 -68.144898) (xy 33.039812 -63.515748)
				(xy 32.745426 -63.221362) (xy 31.761684 -63.221362) (xy 31.325058 -63.657988) (xy 31.325058 -66.91884)
				(xy 30.622748 -67.62115) (xy 30.622748 -68.778374)
			)
		)
	)
	(zone
		(layer "Cmts.User")
		(hatch none 0.5)
		(connect_pads
			(clearance 0)
		)
		(min_thickness 0.25)
		(keepout
			(tracks allowed)
			(vias allowed)
			(pads allowed)
			(copperpour allowed)
			(footprints allowed)
		)
		(placement
			(enabled no)
			(sheetname "")
		)
		(fill
			(thermal_gap 0.5)
			(thermal_bridge_width 0.5)
			(island_removal_mode 0)
		)
		(polygon
			(pts
				(xy 348.612206 -99.452938) (xy 350.13773 -99.452938) (xy 351.62109 -97.969578) (xy 351.62109 -94.508574)
				(xy 350.43237 -93.319854) (xy 348.62262 -93.319854) (xy 347.865192 -94.077282) (xy 347.865192 -98.705924)
			)
		)
	)
	(zone
		(layer "Cmts.User")
		(hatch none 0.5)
		(connect_pads
			(clearance 0)
		)
		(min_thickness 0.25)
		(keepout
			(tracks allowed)
			(vias allowed)
			(pads allowed)
			(copperpour allowed)
			(footprints allowed)
		)
		(placement
			(enabled no)
			(sheetname "")
		)
		(fill
			(thermal_gap 0.5)
			(thermal_bridge_width 0.5)
			(island_removal_mode 0)
		)
		(polygon
			(pts
				(xy 346.075 -84.9884) (xy 346.075 -83.9724) (xy 347.5482 -83.9724) (xy 347.5482 -84.9884)
			)
		)
	)
	(zone
		(layer "Cmts.User")
		(hatch none 0.5)
		(connect_pads
			(clearance 0)
		)
		(min_thickness 0.25)
		(keepout
			(tracks allowed)
			(vias allowed)
			(pads allowed)
			(copperpour allowed)
			(footprints allowed)
		)
		(placement
			(enabled no)
			(sheetname "")
		)
		(fill
			(thermal_gap 0.5)
			(thermal_bridge_width 0.5)
			(island_removal_mode 0)
		)
		(polygon
			(pts
				(xy 352.017076 -22.44852) (xy 353.458526 -22.44852) (xy 353.83724 -22.069806) (xy 353.83724 -20.428712)
				(xy 353.405948 -19.99742) (xy 352.227642 -19.99742) (xy 351.859342 -20.36572) (xy 351.859342 -22.290786)
			)
		)
	)
	(zone
		(layer "Cmts.User")
		(hatch none 0.5)
		(connect_pads
			(clearance 0)
		)
		(min_thickness 0.25)
		(keepout
			(tracks allowed)
			(vias allowed)
			(pads allowed)
			(copperpour allowed)
			(footprints allowed)
		)
		(placement
			(enabled no)
			(sheetname "")
		)
		(fill
			(thermal_gap 0.5)
			(thermal_bridge_width 0.5)
			(island_removal_mode 0)
		)
		(polygon
			(pts
				(xy 180.566568 -135.6106) (xy 182.062628 -135.6106) (xy 182.252112 -135.421116) (xy 182.252112 -133.12775)
				(xy 182.031132 -132.90677) (xy 180.342794 -132.90677) (xy 180.18506 -133.064504) (xy 180.18506 -135.229092)
			)
		)
	)
	(zone
		(layer "Cmts.User")
		(hatch none 0.5)
		(connect_pads
			(clearance 0)
		)
		(min_thickness 0.25)
		(keepout
			(tracks allowed)
			(vias allowed)
			(pads allowed)
			(copperpour allowed)
			(footprints allowed)
		)
		(placement
			(enabled no)
			(sheetname "")
		)
		(fill
			(thermal_gap 0.5)
			(thermal_bridge_width 0.5)
			(island_removal_mode 0)
		)
		(polygon
			(pts
				(xy 184.687718 -95.865442) (xy 186.402726 -95.865442) (xy 186.591956 -95.676212) (xy 186.591956 -92.383356)
				(xy 186.392058 -92.183458) (xy 184.803542 -92.183458) (xy 184.440576 -92.546424) (xy 184.440576 -95.6183)
			)
		)
	)
	(zone
		(layer "Cmts.User")
		(hatch none 0.5)
		(connect_pads
			(clearance 0)
		)
		(min_thickness 0.25)
		(keepout
			(tracks allowed)
			(vias allowed)
			(pads allowed)
			(copperpour allowed)
			(footprints allowed)
		)
		(placement
			(enabled no)
			(sheetname "")
		)
		(fill
			(thermal_gap 0.5)
			(thermal_bridge_width 0.5)
			(island_removal_mode 0)
		)
		(polygon
			(pts
				(xy 176.581054 -141.659864) (xy 180.758084 -141.659864) (xy 181.084474 -141.333474) (xy 181.084474 -140.32865)
				(xy 180.747924 -139.9921) (xy 176.73955 -139.9921) (xy 176.345088 -140.386562) (xy 176.345088 -141.423898)
			)
		)
	)
	(zone
		(layer "Cmts.User")
		(hatch none 0.5)
		(connect_pads
			(clearance 0)
		)
		(min_thickness 0.25)
		(keepout
			(tracks allowed)
			(vias allowed)
			(pads allowed)
			(copperpour allowed)
			(footprints allowed)
		)
		(placement
			(enabled no)
			(sheetname "")
		)
		(fill
			(thermal_gap 0.5)
			(thermal_bridge_width 0.5)
			(island_removal_mode 0)
		)
		(polygon
			(pts
				(xy 28.769564 -26.162) (xy 28.769564 4.572) (xy 157.039564 4.572) (xy 157.039564 -26.5684) (xy 143.990568 -26.5684)
				(xy 141.094968 -29.464) (xy 124.051568 -29.464) (xy 123.416568 -28.829) (xy 123.289568 -28.702)
				(xy 123.289568 -25.4254) (xy 122.959368 -25.0952) (xy 114.247168 -25.0952) (xy 114.247168 -24.511)
				(xy 113.993168 -24.257) (xy 79.030068 -24.257) (xy 78.395068 -24.892) (xy 78.395068 -27.4955) (xy 76.299568 -29.591)
				(xy 59.281568 -29.591) (xy 58.138568 -28.448) (xy 58.138568 -26.162)
			)
		)
	)
	(zone
		(layer "Cmts.User")
		(hatch none 0.5)
		(connect_pads
			(clearance 0)
		)
		(min_thickness 0.25)
		(keepout
			(tracks allowed)
			(vias allowed)
			(pads allowed)
			(copperpour allowed)
			(footprints allowed)
		)
		(placement
			(enabled no)
			(sheetname "")
		)
		(fill
			(thermal_gap 0.5)
			(thermal_bridge_width 0.5)
			(island_removal_mode 0)
		)
		(polygon
			(pts
				(xy 193.398648 -102.283006) (xy 195.9864 -102.283006) (xy 196.259958 -102.556564) (xy 201.80427 -102.556564)
				(xy 201.951336 -102.409498) (xy 201.951336 -101.009704) (xy 201.22007 -100.278438) (xy 201.22007 -95.275908)
				(xy 201.646028 -94.84995) (xy 201.646028 -93.545406) (xy 202.182476 -93.008958) (xy 205.506828 -93.008958)
				(xy 205.685644 -92.830142) (xy 205.685644 -92.477844) (xy 205.30693 -92.09913) (xy 201.772266 -92.09913)
				(xy 201.393552 -91.720416) (xy 201.393552 -87.070692) (xy 202.07732 -86.386924) (xy 202.07732 -84.146136)
				(xy 201.382884 -83.4517) (xy 201.382884 -79.022702) (xy 201.719688 -78.685898) (xy 206.148686 -78.685898)
				(xy 206.159354 -78.696566) (xy 206.369666 -78.696566) (xy 206.495904 -78.570328) (xy 206.495904 -76.340208)
				(xy 206.169768 -76.014072) (xy 201.793602 -76.014072) (xy 201.235818 -75.456288) (xy 201.235818 -70.99554)
				(xy 201.687938 -70.54342) (xy 206.948024 -70.54342) (xy 207.169004 -70.32244) (xy 207.169004 -68.755006)
				(xy 206.27467 -67.860672) (xy 201.67727 -67.860672) (xy 201.182986 -67.366388) (xy 201.182986 -61.148976)
				(xy 201.603864 -60.728098) (xy 205.653894 -60.728098) (xy 205.86446 -60.517532) (xy 205.86446 -60.023248)
				(xy 205.590902 -59.74969) (xy 201.572368 -59.74969) (xy 201.235564 -59.412886) (xy 201.235564 -54.889908)
				(xy 201.719942 -54.40553) (xy 206.19085 -54.40553) (xy 206.401416 -54.194964) (xy 206.401416 -52.564792)
				(xy 206.022448 -52.185824) (xy 204.844142 -52.185824) (xy 204.234034 -51.575716) (xy 195.386706 -51.575716)
				(xy 194.039998 -52.922424) (xy 194.039998 -74.277982) (xy 192.041018 -76.276962) (xy 192.041018 -100.925376)
			)
		)
	)
	(zone
		(layer "Cmts.User")
		(hatch none 0.5)
		(connect_pads
			(clearance 0)
		)
		(min_thickness 0.25)
		(keepout
			(tracks allowed)
			(vias allowed)
			(pads allowed)
			(copperpour allowed)
			(footprints allowed)
		)
		(placement
			(enabled no)
			(sheetname "")
		)
		(fill
			(thermal_gap 0.5)
			(thermal_bridge_width 0.5)
			(island_removal_mode 0)
		)
		(polygon
			(pts
				(xy 372.69293 -153.073862) (xy 374.734074 -153.073862) (xy 375.512584 -152.295352) (xy 379.047248 -152.295352)
				(xy 379.510036 -151.832564) (xy 379.510036 -151.075136) (xy 379.11024 -150.67534) (xy 372.940326 -150.67534)
				(xy 372.535196 -151.08047) (xy 372.535196 -152.916128)
			)
		)
	)
	(zone
		(layer "Cmts.User")
		(hatch none 0.5)
		(connect_pads
			(clearance 0)
		)
		(min_thickness 0.25)
		(keepout
			(tracks allowed)
			(vias allowed)
			(pads allowed)
			(copperpour allowed)
			(footprints allowed)
		)
		(placement
			(enabled no)
			(sheetname "")
		)
		(fill
			(thermal_gap 0.5)
			(thermal_bridge_width 0.5)
			(island_removal_mode 0)
		)
		(polygon
			(pts
				(xy 374.651778 -155.814522) (xy 380.58852 -155.814522) (xy 380.77267 -155.630372) (xy 380.77267 -154.815286)
				(xy 380.530608 -154.573224) (xy 374.880886 -154.573224) (xy 374.528588 -154.925522) (xy 374.528588 -155.691332)
			)
		)
	)
	(zone
		(layer "Cmts.User")
		(hatch none 0.5)
		(connect_pads
			(clearance 0)
		)
		(min_thickness 0.25)
		(keepout
			(tracks allowed)
			(vias allowed)
			(pads allowed)
			(copperpour allowed)
			(footprints allowed)
		)
		(placement
			(enabled no)
			(sheetname "")
		)
		(fill
			(thermal_gap 0.5)
			(thermal_bridge_width 0.5)
			(island_removal_mode 0)
		)
		(polygon
			(pts
				(xy 185.970926 -14.313154) (xy 187.428124 -14.313154) (xy 187.564776 -14.176502) (xy 187.564776 -13.063728)
				(xy 187.34405 -12.843002) (xy 186.741816 -12.843002) (xy 185.9026 -13.682218) (xy 185.9026 -14.244828)
			)
		)
	)
	(zone
		(layer "Cmts.User")
		(hatch none 0.5)
		(connect_pads
			(clearance 0)
		)
		(min_thickness 0.25)
		(keepout
			(tracks allowed)
			(vias allowed)
			(pads allowed)
			(copperpour allowed)
			(footprints allowed)
		)
		(placement
			(enabled no)
			(sheetname "")
		)
		(fill
			(thermal_gap 0.5)
			(thermal_bridge_width 0.5)
			(island_removal_mode 0)
		)
		(polygon
			(pts
				(xy 357.017828 -17.921732) (xy 359.34269 -17.921732) (xy 359.82148 -17.442942) (xy 359.82148 -13.876782)
				(xy 359.63733 -13.692632) (xy 357.538528 -13.692632) (xy 356.88651 -14.34465) (xy 356.88651 -17.790414)
			)
		)
	)
	(zone
		(layer "Cmts.User")
		(hatch none 0.5)
		(connect_pads
			(clearance 0)
		)
		(min_thickness 0.25)
		(keepout
			(tracks allowed)
			(vias allowed)
			(pads allowed)
			(copperpour allowed)
			(footprints allowed)
		)
		(placement
			(enabled no)
			(sheetname "")
		)
		(fill
			(thermal_gap 0.5)
			(thermal_bridge_width 0.5)
			(island_removal_mode 0)
		)
		(polygon
			(pts
				(xy 178.6382 -72.4916) (xy 178.6382 -68.6562) (xy 181.6862 -68.6562) (xy 181.6862 -72.4916)
			)
		)
	)
	(zone
		(layer "Cmts.User")
		(hatch none 0.5)
		(connect_pads
			(clearance 0)
		)
		(min_thickness 0.25)
		(keepout
			(tracks allowed)
			(vias allowed)
			(pads allowed)
			(copperpour allowed)
			(footprints allowed)
		)
		(placement
			(enabled no)
			(sheetname "")
		)
		(fill
			(thermal_gap 0.5)
			(thermal_bridge_width 0.5)
			(island_removal_mode 0)
		)
		(polygon
			(pts
				(xy 157.27934 -125.349) (xy 157.27934 -157.861) (xy 114.78133 -157.861) (xy 114.392456 -158.249874)
				(xy 112.571784 -158.249874) (xy 112.18291 -157.861) (xy 29.00934 -157.861) (xy 29.00934 -127.2794)
				(xy 30.938724 -125.350016) (xy 30.960568 -125.350016) (xy 32.028384 -124.2822) (xy 79.728568 -124.2822)
				(xy 79.728568 -126.873) (xy 79.855568 -127) (xy 123.543568 -127) (xy 123.543568 -124.2822) (xy 156.21254 -124.2822)
			)
		)
	)
	(zone
		(layer "Cmts.User")
		(hatch none 0.5)
		(connect_pads
			(clearance 0)
		)
		(min_thickness 0.25)
		(keepout
			(tracks allowed)
			(vias allowed)
			(pads allowed)
			(copperpour allowed)
			(footprints allowed)
		)
		(placement
			(enabled no)
			(sheetname "")
		)
		(fill
			(thermal_gap 0.5)
			(thermal_bridge_width 0.5)
			(island_removal_mode 0)
		)
		(polygon
			(pts
				(xy 393.9286 -150.7744) (xy 393.9286 -149.8092) (xy 395.5288 -149.8092) (xy 395.5288 -150.7744)
			)
		)
	)
	(zone
		(layer "Cmts.User")
		(hatch none 0.5)
		(connect_pads
			(clearance 0)
		)
		(min_thickness 0.25)
		(keepout
			(tracks allowed)
			(vias allowed)
			(pads allowed)
			(copperpour allowed)
			(footprints allowed)
		)
		(placement
			(enabled no)
			(sheetname "")
		)
		(fill
			(thermal_gap 0.5)
			(thermal_bridge_width 0.5)
			(island_removal_mode 0)
		)
		(polygon
			(pts
				(xy 426.5295 -23.424896) (xy 404.399496 -23.424896) (xy 404.399496 -29.083) (xy 402.5138 -29.083)
				(xy 401.6502 -29.083) (xy 400.4691 -30.2641) (xy 400.4691 -32.2961) (xy 400.7104 -32.5374) (xy 401.2946 -32.5374)
				(xy 404.145496 -32.5374) (xy 404.399496 -32.7914) (xy 404.399496 -47.464472) (xy 426.5295 -47.464472)
			)
		)
	)
	(zone
		(layer "Cmts.User")
		(hatch none 0.5)
		(connect_pads
			(clearance 0)
		)
		(min_thickness 0.25)
		(keepout
			(tracks allowed)
			(vias allowed)
			(pads allowed)
			(copperpour allowed)
			(footprints allowed)
		)
		(placement
			(enabled no)
			(sheetname "")
		)
		(fill
			(thermal_gap 0.5)
			(thermal_bridge_width 0.5)
			(island_removal_mode 0)
		)
		(polygon
			(pts
				(xy 22.235922 -66.135504) (xy 25.186386 -66.135504) (xy 25.459944 -65.861946) (xy 25.459944 -62.000892)
				(xy 25.023572 -61.56452) (xy 22.23008 -61.56452) (xy 21.877782 -61.916818) (xy 21.877782 -65.777364)
			)
		)
	)
	(zone
		(layer "Cmts.User")
		(hatch none 0.5)
		(connect_pads
			(clearance 0)
		)
		(min_thickness 0.25)
		(keepout
			(tracks allowed)
			(vias allowed)
			(pads allowed)
			(copperpour allowed)
			(footprints allowed)
		)
		(placement
			(enabled no)
			(sheetname "")
		)
		(fill
			(thermal_gap 0.5)
			(thermal_bridge_width 0.5)
			(island_removal_mode 0)
		)
		(polygon
			(pts
				(xy 187.301632 -136.943846) (xy 186.252358 -136.943846) (xy 185.939176 -136.630664) (xy 185.939176 -132.959856)
				(xy 186.181492 -132.71754) (xy 187.281058 -132.71754) (xy 187.559696 -132.996178) (xy 187.559696 -136.685782)
			)
		)
	)
	(zone
		(layer "Cmts.User")
		(hatch none 0.5)
		(connect_pads
			(clearance 0)
		)
		(min_thickness 0.25)
		(keepout
			(tracks allowed)
			(vias allowed)
			(pads allowed)
			(copperpour allowed)
			(footprints allowed)
		)
		(placement
			(enabled no)
			(sheetname "")
		)
		(fill
			(thermal_gap 0.5)
			(thermal_bridge_width 0.5)
			(island_removal_mode 0)
		)
		(polygon
			(pts
				(xy 344.905584 -100.14204) (xy 346.376752 -100.14204) (xy 346.545154 -99.973638) (xy 346.545154 -95.823278)
				(xy 345.593162 -94.871286) (xy 344.940636 -94.871286) (xy 344.751406 -95.060516) (xy 344.751406 -99.987862)
			)
		)
	)
	(zone
		(layer "Cmts.User")
		(hatch none 0.5)
		(connect_pads
			(clearance 0)
		)
		(min_thickness 0.25)
		(keepout
			(tracks allowed)
			(vias allowed)
			(pads allowed)
			(copperpour allowed)
			(footprints allowed)
		)
		(placement
			(enabled no)
			(sheetname "")
		)
		(fill
			(thermal_gap 0.5)
			(thermal_bridge_width 0.5)
			(island_removal_mode 0)
		)
		(polygon
			(pts
				(xy 30.554422 -85.292692) (xy 32.31388 -85.292692) (xy 33.46069 -84.145882) (xy 33.46069 -77.833982)
				(xy 32.8295 -77.202792) (xy 30.862016 -77.202792) (xy 30.167834 -77.896974) (xy 30.167834 -84.906104)
			)
		)
	)
	(zone
		(layer "Cmts.User")
		(hatch none 0.5)
		(connect_pads
			(clearance 0)
		)
		(min_thickness 0.25)
		(keepout
			(tracks allowed)
			(vias allowed)
			(pads allowed)
			(copperpour allowed)
			(footprints allowed)
		)
		(placement
			(enabled no)
			(sheetname "")
		)
		(fill
			(thermal_gap 0.5)
			(thermal_bridge_width 0.5)
			(island_removal_mode 0)
		)
		(polygon
			(pts
				(xy 351.54743 -132.812028) (xy 354.324666 -132.812028) (xy 354.692966 -132.443728) (xy 354.692966 -130.76047)
				(xy 353.91471 -129.982214) (xy 348.086172 -129.982214) (xy 347.065854 -131.002532) (xy 347.065854 -131.991354)
				(xy 347.39199 -132.31749) (xy 351.052892 -132.31749)
			)
		)
	)
	(zone
		(layer "Cmts.User")
		(hatch none 0.5)
		(connect_pads
			(clearance 0)
		)
		(min_thickness 0.25)
		(keepout
			(tracks allowed)
			(vias allowed)
			(pads allowed)
			(copperpour allowed)
			(footprints allowed)
		)
		(placement
			(enabled no)
			(sheetname "")
		)
		(fill
			(thermal_gap 0.5)
			(thermal_bridge_width 0.5)
			(island_removal_mode 0)
		)
		(polygon
			(pts
				(xy 180.51399 -12.309348) (xy 185.224166 -12.309348) (xy 185.539888 -11.993626) (xy 185.539888 -11.525504)
				(xy 185.360818 -11.346434) (xy 182.836058 -11.346434) (xy 182.63616 -11.146536) (xy 182.63616 -9.494774)
				(xy 182.347108 -9.205722) (xy 180.379624 -9.205722) (xy 180.158644 -9.426702) (xy 180.158644 -11.954002)
			)
		)
	)
	(zone
		(layer "Cmts.User")
		(hatch none 0.5)
		(connect_pads
			(clearance 0)
		)
		(min_thickness 0.25)
		(keepout
			(tracks allowed)
			(vias allowed)
			(pads allowed)
			(copperpour allowed)
			(footprints allowed)
		)
		(placement
			(enabled no)
			(sheetname "")
		)
		(fill
			(thermal_gap 0.5)
			(thermal_bridge_width 0.5)
			(island_removal_mode 0)
		)
		(polygon
			(pts
				(xy 349.075756 -154.983434) (xy 349.89643 -154.983434) (xy 350.064832 -154.815032) (xy 350.064832 -150.013162)
				(xy 349.559118 -149.507448) (xy 349.24365 -149.507448) (xy 349.05442 -149.696678) (xy 349.05442 -154.962098)
			)
		)
	)
	(zone
		(layer "Cmts.User")
		(hatch none 0.5)
		(connect_pads
			(clearance 0)
		)
		(min_thickness 0.25)
		(keepout
			(tracks allowed)
			(vias allowed)
			(pads allowed)
			(copperpour allowed)
			(footprints allowed)
		)
		(placement
			(enabled no)
			(sheetname "")
		)
		(fill
			(thermal_gap 0.5)
			(thermal_bridge_width 0.5)
			(island_removal_mode 0)
		)
		(polygon
			(pts
				(xy 193.769996 -26.162) (xy 193.769996 4.572) (xy 322.039996 4.572) (xy 322.039996 -26.5684) (xy 308.991 -26.5684)
				(xy 306.0954 -29.464) (xy 289.052 -29.464) (xy 288.417 -28.829) (xy 288.29 -28.702) (xy 288.29 -25.4254)
				(xy 287.9598 -25.0952) (xy 279.2476 -25.0952) (xy 279.2476 -24.511) (xy 278.9936 -24.257) (xy 244.0305 -24.257)
				(xy 243.3955 -24.892) (xy 243.3955 -27.4955) (xy 241.3 -29.591) (xy 224.282 -29.591) (xy 223.139 -28.448)
				(xy 223.139 -26.162)
			)
		)
	)
	(zone
		(layer "Cmts.User")
		(hatch none 0.5)
		(connect_pads
			(clearance 0)
		)
		(min_thickness 0.25)
		(keepout
			(tracks allowed)
			(vias allowed)
			(pads allowed)
			(copperpour allowed)
			(footprints allowed)
		)
		(placement
			(enabled no)
			(sheetname "")
		)
		(fill
			(thermal_gap 0.5)
			(thermal_bridge_width 0.5)
			(island_removal_mode 0)
		)
		(polygon
			(pts
				(xy 344.418412 -1.910334) (xy 348.801944 -1.910334) (xy 349.286068 -1.42621) (xy 349.286068 3.328924)
				(xy 349.748856 3.791712) (xy 350.106488 3.791712) (xy 350.632522 4.317746) (xy 350.632522 5.043678)
				(xy 350.485202 5.190998) (xy 341.74303 5.190998) (xy 341.48014 4.928108) (xy 341.48014 4.117848)
				(xy 341.900764 3.697224) (xy 343.71026 3.697224) (xy 344.036396 3.371088) (xy 344.036396 -1.528318)
			)
		)
	)
	(zone
		(layer "Cmts.User")
		(hatch none 0.5)
		(connect_pads
			(clearance 0)
		)
		(min_thickness 0.25)
		(keepout
			(tracks allowed)
			(vias allowed)
			(pads allowed)
			(copperpour allowed)
			(footprints allowed)
		)
		(placement
			(enabled no)
			(sheetname "")
		)
		(fill
			(thermal_gap 0.5)
			(thermal_bridge_width 0.5)
			(island_removal_mode 0)
		)
		(polygon
			(pts
				(xy 183.609234 -17.67967) (xy 184.582308 -17.67967) (xy 184.724294 -17.537684) (xy 184.724294 -16.538194)
				(xy 184.577228 -16.391128) (xy 183.64581 -16.391128) (xy 183.45404 -16.582898) (xy 183.45404 -17.524476)
			)
		)
	)
	(zone
		(layer "Cmts.User")
		(hatch none 0.5)
		(connect_pads
			(clearance 0)
		)
		(min_thickness 0.25)
		(keepout
			(tracks allowed)
			(vias allowed)
			(pads allowed)
			(copperpour allowed)
			(footprints allowed)
		)
		(placement
			(enabled no)
			(sheetname "")
		)
		(fill
			(thermal_gap 0.5)
			(thermal_bridge_width 0.5)
			(island_removal_mode 0)
		)
		(polygon
			(pts
				(xy 355.934518 -22.213824) (xy 358.385618 -22.213824) (xy 358.953816 -21.645626) (xy 358.953816 -20.215098)
				(xy 358.680258 -19.94154) (xy 356.197408 -19.94154) (xy 355.813614 -20.325334) (xy 355.813614 -22.09292)
			)
		)
	)
	(zone
		(layer "Cmts.User")
		(hatch none 0.5)
		(connect_pads
			(clearance 0)
		)
		(min_thickness 0.25)
		(keepout
			(tracks allowed)
			(vias allowed)
			(pads allowed)
			(copperpour allowed)
			(footprints allowed)
		)
		(placement
			(enabled no)
			(sheetname "")
		)
		(fill
			(thermal_gap 0.5)
			(thermal_bridge_width 0.5)
			(island_removal_mode 0)
		)
		(polygon
			(pts
				(xy 168.8846 -70.5866) (xy 168.8846 -69.5452) (xy 170.053 -69.5452) (xy 170.053 -70.5866)
			)
		)
	)
	(zone
		(layer "Cmts.User")
		(hatch none 0.5)
		(connect_pads
			(clearance 0)
		)
		(min_thickness 0.25)
		(keepout
			(tracks allowed)
			(vias allowed)
			(pads allowed)
			(copperpour allowed)
			(footprints allowed)
		)
		(placement
			(enabled no)
			(sheetname "")
		)
		(fill
			(thermal_gap 0.5)
			(thermal_bridge_width 0.5)
			(island_removal_mode 0)
		)
		(polygon
			(pts
				(xy -1.29794 -13.646404) (xy -0.009144 -13.646404) (xy 0.22225 -13.41501) (xy 0.22225 -12.336526)
				(xy -0.072136 -12.04214) (xy -1.308354 -12.04214) (xy -1.524 -12.257786) (xy -1.524 -13.420344)
			)
		)
	)
	(zone
		(layer "Cmts.User")
		(hatch none 0.5)
		(connect_pads
			(clearance 0)
		)
		(min_thickness 0.25)
		(keepout
			(tracks allowed)
			(vias allowed)
			(pads allowed)
			(copperpour allowed)
			(footprints allowed)
		)
		(placement
			(enabled no)
			(sheetname "")
		)
		(fill
			(thermal_gap 0.5)
			(thermal_bridge_width 0.5)
			(island_removal_mode 0)
		)
		(polygon
			(pts
				(xy 365.506 -81.407) (xy 365.506 -67.183) (xy 380.111 -67.183) (xy 380.111 -77.089) (xy 380.9238 -77.9018)
				(xy 380.9238 -78.8924) (xy 380.6952 -79.121) (xy 380.3396 -79.121) (xy 380.111 -79.3496) (xy 380.111 -81.407)
			)
		)
	)
	(zone
		(layer "Cmts.User")
		(hatch none 0.5)
		(connect_pads
			(clearance 0)
		)
		(min_thickness 0.25)
		(keepout
			(tracks allowed)
			(vias allowed)
			(pads allowed)
			(copperpour allowed)
			(footprints allowed)
		)
		(placement
			(enabled no)
			(sheetname "")
		)
		(fill
			(thermal_gap 0.5)
			(thermal_bridge_width 0.5)
			(island_removal_mode 0)
		)
		(polygon
			(pts
				(xy 348.08668 -149.055328) (xy 350.24314 -149.055328) (xy 350.979486 -148.318982) (xy 350.979486 -143.826484)
				(xy 351.515934 -143.290036) (xy 351.515934 -142.122398) (xy 351.06356 -141.670024) (xy 349.275146 -141.670024)
				(xy 347.91269 -143.03248) (xy 347.91269 -148.881338)
			)
		)
	)
	(zone
		(layer "Cmts.User")
		(hatch none 0.5)
		(connect_pads
			(clearance 0)
		)
		(min_thickness 0.25)
		(keepout
			(tracks allowed)
			(vias allowed)
			(pads allowed)
			(copperpour allowed)
			(footprints allowed)
		)
		(placement
			(enabled no)
			(sheetname "")
		)
		(fill
			(thermal_gap 0.5)
			(thermal_bridge_width 0.5)
			(island_removal_mode 0)
		)
		(polygon
			(pts
				(xy 344.5256 -19.4818) (xy 344.5256 -18.542) (xy 345.4654 -18.542) (xy 345.4654 -19.4818)
			)
		)
	)
	(zone
		(layer "Cmts.User")
		(hatch none 0.5)
		(connect_pads
			(clearance 0)
		)
		(min_thickness 0.25)
		(keepout
			(tracks allowed)
			(vias allowed)
			(pads allowed)
			(copperpour allowed)
			(footprints allowed)
		)
		(placement
			(enabled no)
			(sheetname "")
		)
		(fill
			(thermal_gap 0.5)
			(thermal_bridge_width 0.5)
			(island_removal_mode 0)
		)
		(polygon
			(pts
				(xy 22.369018 -60.381642) (xy 25.391618 -60.381642) (xy 25.554686 -60.218574) (xy 25.554686 -57.519316)
				(xy 25.286462 -57.251092) (xy 22.540722 -57.251092) (xy 22.162008 -57.629806) (xy 22.162008 -60.174632)
			)
		)
	)
	(zone
		(layer "Cmts.User")
		(hatch none 0.5)
		(connect_pads
			(clearance 0)
		)
		(min_thickness 0.25)
		(keepout
			(tracks allowed)
			(vias allowed)
			(pads allowed)
			(copperpour allowed)
			(footprints allowed)
		)
		(placement
			(enabled no)
			(sheetname "")
		)
		(fill
			(thermal_gap 0.5)
			(thermal_bridge_width 0.5)
			(island_removal_mode 0)
		)
		(polygon
			(pts
				(xy 33.589468 -102.561644) (xy 36.364418 -102.561644) (xy 36.485322 -102.44074) (xy 36.485322 -94.06636)
				(xy 35.954208 -93.535246) (xy 35.075876 -93.535246) (xy 34.502344 -94.108778) (xy 34.502344 -100.435918)
				(xy 33.393634 -101.544628) (xy 33.393634 -102.36581)
			)
		)
	)
	(zone
		(layer "Cmts.User")
		(hatch none 0.5)
		(connect_pads
			(clearance 0)
		)
		(min_thickness 0.25)
		(keepout
			(tracks allowed)
			(vias allowed)
			(pads allowed)
			(copperpour allowed)
			(footprints allowed)
		)
		(placement
			(enabled no)
			(sheetname "")
		)
		(fill
			(thermal_gap 0.5)
			(thermal_bridge_width 0.5)
			(island_removal_mode 0)
		)
		(polygon
			(pts
				(xy 355.411024 -146.846036) (xy 361.394248 -146.846036) (xy 361.773216 -146.467068) (xy 361.773216 -144.878552)
				(xy 361.52074 -144.626076) (xy 355.43236 -144.626076) (xy 354.947982 -145.110454) (xy 354.947982 -146.382994)
			)
		)
	)
	(zone
		(layer "Cmts.User")
		(hatch none 0.5)
		(connect_pads
			(clearance 0)
		)
		(min_thickness 0.25)
		(keepout
			(tracks allowed)
			(vias allowed)
			(pads allowed)
			(copperpour allowed)
			(footprints allowed)
		)
		(placement
			(enabled no)
			(sheetname "")
		)
		(fill
			(thermal_gap 0.5)
			(thermal_bridge_width 0.5)
			(island_removal_mode 0)
		)
		(polygon
			(pts
				(xy 40.635174 -92.17279) (xy 40.635174 -92.856812) (xy 40.47744 -93.014546) (xy 34.9123 -93.014546)
				(xy 34.554668 -92.656914) (xy 34.554668 -52.427886) (xy 35.080956 -51.901598) (xy 41.077388 -51.901598)
				(xy 41.698164 -52.522374) (xy 41.698164 -54.142386) (xy 41.46677 -54.37378) (xy 36.595812 -54.37378)
				(xy 36.196016 -54.773576) (xy 36.196016 -59.570874) (xy 36.490656 -59.865514) (xy 40.793416 -59.865514)
				(xy 40.956484 -60.028582) (xy 40.956484 -60.317888) (xy 40.619934 -60.654438) (xy 36.947856 -60.654438)
				(xy 36.500816 -61.101478) (xy 36.500816 -75.729592) (xy 36.963858 -76.192634) (xy 40.824658 -76.192634)
				(xy 40.992806 -76.360782) (xy 40.992806 -76.802742) (xy 40.708834 -77.086714) (xy 36.942522 -77.086714)
				(xy 36.500816 -77.52842) (xy 36.500816 -84.00923) (xy 36.858702 -84.367116) (xy 41.813734 -84.367116)
				(xy 42.150284 -84.703666) (xy 42.150284 -86.639146) (xy 41.740074 -87.049356) (xy 36.606226 -87.049356)
				(xy 36.269676 -87.385906) (xy 36.269676 -91.773248) (xy 36.574476 -92.078048) (xy 40.540432 -92.078048)
			)
		)
	)
	(zone
		(layer "Cmts.User")
		(hatch none 0.5)
		(connect_pads
			(clearance 0)
		)
		(min_thickness 0.25)
		(keepout
			(tracks allowed)
			(vias allowed)
			(pads allowed)
			(copperpour allowed)
			(footprints allowed)
		)
		(placement
			(enabled no)
			(sheetname "")
		)
		(fill
			(thermal_gap 0.5)
			(thermal_bridge_width 0.5)
			(island_removal_mode 0)
		)
		(polygon
			(pts
				(xy 184.75071 -88.98509) (xy 186.254898 -88.98509) (xy 186.623198 -88.61679) (xy 186.623198 -85.318346)
				(xy 186.103006 -84.798154) (xy 184.698132 -84.798154) (xy 184.466738 -85.029548) (xy 184.466738 -88.701118)
			)
		)
	)
	(zone
		(layer "Cmts.User")
		(hatch none 0.5)
		(connect_pads
			(clearance 0)
		)
		(min_thickness 0.25)
		(keepout
			(tracks allowed)
			(vias allowed)
			(pads allowed)
			(copperpour allowed)
			(footprints allowed)
		)
		(placement
			(enabled no)
			(sheetname "")
		)
		(fill
			(thermal_gap 0.5)
			(thermal_bridge_width 0.5)
			(island_removal_mode 0)
		)
		(polygon
			(pts
				(xy 7.244588 -150.701756) (xy 5.393182 -150.701756) (xy 4.898644 -150.207218) (xy 3.620262 -150.207218)
				(xy 3.141472 -149.728428) (xy 3.141472 -144.99463) (xy 3.962146 -144.173956) (xy 4.530344 -144.173956)
				(xy 5.098542 -144.742154) (xy 5.098542 -149.181566) (xy 5.41401 -149.497034) (xy 7.160514 -149.497034)
				(xy 7.347458 -149.683978) (xy 7.347458 -150.598886)
			)
		)
	)
	(zone
		(layer "Cmts.User")
		(hatch none 0.5)
		(connect_pads
			(clearance 0)
		)
		(min_thickness 0.25)
		(keepout
			(tracks allowed)
			(vias allowed)
			(pads allowed)
			(copperpour allowed)
			(footprints allowed)
		)
		(placement
			(enabled no)
			(sheetname "")
		)
		(fill
			(thermal_gap 0.5)
			(thermal_bridge_width 0.5)
			(island_removal_mode 0)
		)
		(polygon
			(pts
				(xy 357.3526 -135.4836) (xy 357.3526 -134.2136) (xy 359.3846 -134.2136) (xy 359.3846 -135.4836)
			)
		)
	)
	(zone
		(layer "Cmts.User")
		(hatch none 0.5)
		(connect_pads
			(clearance 0)
		)
		(min_thickness 0.25)
		(keepout
			(tracks allowed)
			(vias allowed)
			(pads allowed)
			(copperpour allowed)
			(footprints allowed)
		)
		(placement
			(enabled no)
			(sheetname "")
		)
		(fill
			(thermal_gap 0.5)
			(thermal_bridge_width 0.5)
			(island_removal_mode 0)
		)
		(polygon
			(pts
				(xy -4.953 -40.767) (xy -4.953 -24.892) (xy 9.906 -24.892) (xy 9.906 -40.767)
			)
		)
	)
	(zone
		(layer "Cmts.User")
		(hatch none 0.5)
		(connect_pads
			(clearance 0)
		)
		(min_thickness 0.25)
		(keepout
			(tracks allowed)
			(vias allowed)
			(pads allowed)
			(copperpour allowed)
			(footprints allowed)
		)
		(placement
			(enabled no)
			(sheetname "")
		)
		(fill
			(thermal_gap 0.5)
			(thermal_bridge_width 0.5)
			(island_removal_mode 0)
		)
		(polygon
			(pts
				(xy 344.949018 -155.92044) (xy 346.90177 -155.92044) (xy 347.176852 -155.645358) (xy 347.176852 -143.408654)
				(xy 346.300298 -142.5321) (xy 345.268804 -142.5321) (xy 344.942414 -142.85849) (xy 344.942414 -148.581364)
				(xy 344.375232 -149.148546) (xy 344.375232 -155.346654)
			)
		)
	)
	(zone
		(layer "Cmts.User")
		(hatch none 0.5)
		(connect_pads
			(clearance 0)
		)
		(min_thickness 0.25)
		(keepout
			(tracks allowed)
			(vias allowed)
			(pads allowed)
			(copperpour allowed)
			(footprints allowed)
		)
		(placement
			(enabled no)
			(sheetname "")
		)
		(fill
			(thermal_gap 0.5)
			(thermal_bridge_width 0.5)
			(island_removal_mode 0)
		)
		(polygon
			(pts
				(xy 181.266592 -140.299186) (xy 181.95036 -140.299186) (xy 182.113428 -140.136118) (xy 182.113428 -137.223246)
				(xy 181.762908 -136.872726) (xy 181.173882 -136.872726) (xy 180.88991 -137.156698) (xy 180.88991 -139.922504)
			)
		)
	)
	(zone
		(layer "Cmts.User")
		(hatch none 0.5)
		(connect_pads
			(clearance 0)
		)
		(min_thickness 0.25)
		(keepout
			(tracks allowed)
			(vias allowed)
			(pads allowed)
			(copperpour allowed)
			(footprints allowed)
		)
		(placement
			(enabled no)
			(sheetname "")
		)
		(fill
			(thermal_gap 0.5)
			(thermal_bridge_width 0.5)
			(island_removal_mode 0)
		)
		(polygon
			(pts
				(xy 380.380494 -157.72384) (xy 388.588758 -157.72384) (xy 389.030718 -157.28188) (xy 389.030718 -156.009086)
				(xy 388.336282 -155.31465) (xy 385.1275 -155.31465) (xy 385.096004 -155.346146) (xy 383.74955 -155.346146)
				(xy 383.549652 -155.546044) (xy 383.22377 -155.546044) (xy 382.613408 -156.156406) (xy 381.519176 -156.156406)
				(xy 381.392938 -156.282644) (xy 381.017018 -156.282644) (xy 380.306834 -156.992828) (xy 380.306834 -157.65018)
			)
		)
	)
	(zone
		(layer "Cmts.User")
		(hatch none 0.5)
		(connect_pads
			(clearance 0)
		)
		(min_thickness 0.25)
		(keepout
			(tracks allowed)
			(vias allowed)
			(pads allowed)
			(copperpour allowed)
			(footprints allowed)
		)
		(placement
			(enabled no)
			(sheetname "")
		)
		(fill
			(thermal_gap 0.5)
			(thermal_bridge_width 0.5)
			(island_removal_mode 0)
		)
		(polygon
			(pts
				(xy 183.66994 -136.01573) (xy 184.961276 -136.01573) (xy 185.176922 -135.800084) (xy 185.176922 -135.27913)
				(xy 185.014108 -135.116316) (xy 183.619902 -135.116316) (xy 183.56199 -135.174228) (xy 183.56199 -135.90778)
			)
		)
	)
	(zone
		(layer "Cmts.User")
		(hatch none 0.5)
		(connect_pads
			(clearance 0)
		)
		(min_thickness 0.25)
		(keepout
			(tracks allowed)
			(vias allowed)
			(pads allowed)
			(copperpour allowed)
			(footprints allowed)
		)
		(placement
			(enabled no)
			(sheetname "")
		)
		(fill
			(thermal_gap 0.5)
			(thermal_bridge_width 0.5)
			(island_removal_mode 0)
		)
		(polygon
			(pts
				(xy 174.7774 -18.05813) (xy 180.781706 -18.05813) (xy 182.33136 -16.508476) (xy 182.33136 -13.59789)
				(xy 182.188358 -13.454888) (xy 180.838602 -13.454888) (xy 180.28412 -14.00937) (xy 180.28412 -15.88516)
				(xy 180.078126 -16.091154) (xy 174.737014 -16.091154) (xy 174.445676 -16.382492) (xy 174.445676 -17.726406)
			)
		)
	)
	(zone
		(layer "Cmts.User")
		(hatch none 0.5)
		(connect_pads
			(clearance 0)
		)
		(min_thickness 0.25)
		(keepout
			(tracks allowed)
			(vias allowed)
			(pads allowed)
			(copperpour allowed)
			(footprints allowed)
		)
		(placement
			(enabled no)
			(sheetname "")
		)
		(fill
			(thermal_gap 0.5)
			(thermal_bridge_width 0.5)
			(island_removal_mode 0)
		)
		(polygon
			(pts
				(xy 343.807796 -137.57783) (xy 346.634816 -137.57783) (xy 346.834714 -137.377932) (xy 346.834714 -136.409938)
				(xy 346.456 -136.031224) (xy 342.994996 -136.031224) (xy 342.847676 -136.178544) (xy 342.847676 -136.61771)
			)
		)
	)
	(zone
		(layer "Cmts.User")
		(hatch none 0.5)
		(connect_pads
			(clearance 0)
		)
		(min_thickness 0.25)
		(keepout
			(tracks allowed)
			(vias allowed)
			(pads allowed)
			(copperpour allowed)
			(footprints allowed)
		)
		(placement
			(enabled no)
			(sheetname "")
		)
		(fill
			(thermal_gap 0.5)
			(thermal_bridge_width 0.5)
			(island_removal_mode 0)
		)
		(polygon
			(pts
				(xy 30.925262 -62.779402) (xy 33.1978 -62.779402) (xy 33.513268 -62.463934) (xy 33.513268 -61.695838)
				(xy 33.12414 -61.30671) (xy 31.177738 -61.30671) (xy 30.688788 -61.79566) (xy 30.688788 -62.542928)
			)
		)
	)
	(zone
		(layer "Cmts.User")
		(hatch none 0.5)
		(connect_pads
			(clearance 0)
		)
		(min_thickness 0.25)
		(keepout
			(tracks allowed)
			(vias allowed)
			(pads allowed)
			(copperpour allowed)
			(footprints allowed)
		)
		(placement
			(enabled no)
			(sheetname "")
		)
		(fill
			(thermal_gap 0.5)
			(thermal_bridge_width 0.5)
			(island_removal_mode 0)
		)
		(polygon
			(pts
				(xy 30.872938 -70.98538) (xy 31.409386 -70.98538) (xy 31.856426 -70.53834) (xy 33.302702 -70.53834)
				(xy 33.53435 -70.306692) (xy 33.53435 -69.486272) (xy 33.229296 -69.181218) (xy 30.90418 -69.181218)
				(xy 30.609794 -69.475604) (xy 30.609794 -70.722236)
			)
		)
	)
	(zone
		(layer "Cmts.User")
		(hatch none 0.5)
		(connect_pads
			(clearance 0)
		)
		(min_thickness 0.25)
		(keepout
			(tracks allowed)
			(vias allowed)
			(pads allowed)
			(copperpour allowed)
			(footprints allowed)
		)
		(placement
			(enabled no)
			(sheetname "")
		)
		(fill
			(thermal_gap 0.5)
			(thermal_bridge_width 0.5)
			(island_removal_mode 0)
		)
		(polygon
			(pts
				(xy 182.7911 -141.615922) (xy 186.031378 -141.615922) (xy 186.24169 -141.40561) (xy 186.24169 -139.396216)
				(xy 185.999628 -139.154154) (xy 182.86476 -139.154154) (xy 182.622952 -139.395962) (xy 182.622952 -141.447774)
			)
		)
	)
	(zone
		(layer "Cmts.User")
		(hatch none 0.5)
		(connect_pads
			(clearance 0)
		)
		(min_thickness 0.25)
		(keepout
			(tracks allowed)
			(vias allowed)
			(pads allowed)
			(copperpour allowed)
			(footprints allowed)
		)
		(placement
			(enabled no)
			(sheetname "")
		)
		(fill
			(thermal_gap 0.5)
			(thermal_bridge_width 0.5)
			(island_removal_mode 0)
		)
		(polygon
			(pts
				(xy 8.059674 -141.159738) (xy 8.059674 -141.780768) (xy 7.86511 -141.975332) (xy 3.920236 -141.975332)
				(xy 2.888996 -140.944092) (xy 2.888996 -135.558022) (xy 3.867404 -134.579614) (xy 7.980934 -134.579614)
				(xy 8.170164 -134.768844) (xy 8.170164 -135.447786) (xy 7.802372 -135.815578) (xy 5.177536 -135.815578)
				(xy 4.961636 -136.031478) (xy 4.961636 -140.707618) (xy 5.235194 -140.981176) (xy 7.881112 -140.981176)
			)
		)
	)
	(zone
		(layer "Cmts.User")
		(hatch none 0.5)
		(connect_pads
			(clearance 0)
		)
		(min_thickness 0.25)
		(keepout
			(tracks allowed)
			(vias allowed)
			(pads allowed)
			(copperpour allowed)
			(footprints allowed)
		)
		(placement
			(enabled no)
			(sheetname "")
		)
		(fill
			(thermal_gap 0.5)
			(thermal_bridge_width 0.5)
			(island_removal_mode 0)
		)
		(polygon
			(pts
				(xy 365.506 -81.407) (xy 365.506 -67.183) (xy 380.111 -67.183) (xy 380.111 -81.407)
			)
		)
	)
	(zone
		(layer "Cmts.User")
		(hatch none 0.5)
		(connect_pads
			(clearance 0)
		)
		(min_thickness 0.25)
		(keepout
			(tracks allowed)
			(vias allowed)
			(pads allowed)
			(copperpour allowed)
			(footprints allowed)
		)
		(placement
			(enabled no)
			(sheetname "")
		)
		(fill
			(thermal_gap 0.5)
			(thermal_bridge_width 0.5)
			(island_removal_mode 0)
		)
		(polygon
			(pts
				(xy 32.940244 -73.552304) (xy 31.4833 -73.552304) (xy 31.293816 -73.36282) (xy 31.293816 -71.62673)
				(xy 31.745936 -71.17461) (xy 32.871664 -71.17461) (xy 33.1978 -71.500746) (xy 33.1978 -73.294748)
			)
		)
	)
	(zone
		(layer "Cmts.User")
		(hatch none 0.5)
		(connect_pads
			(clearance 0)
		)
		(min_thickness 0.25)
		(keepout
			(tracks allowed)
			(vias allowed)
			(pads allowed)
			(copperpour allowed)
			(footprints allowed)
		)
		(placement
			(enabled no)
			(sheetname "")
		)
		(fill
			(thermal_gap 0.5)
			(thermal_bridge_width 0.5)
			(island_removal_mode 0)
		)
		(polygon
			(pts
				(xy 3.362706 -13.204698) (xy 1.206246 -13.204698) (xy 0.932688 -12.93114) (xy 0.932688 -11.616182)
				(xy 1.816354 -10.732516) (xy 1.816354 -7.986522) (xy 2.342388 -7.460488) (xy 3.310128 -7.460488)
				(xy 3.488944 -7.639304) (xy 3.488944 -13.07846)
			)
		)
	)
	(zone
		(layer "Cmts.User")
		(hatch none 0.5)
		(connect_pads
			(clearance 0)
		)
		(min_thickness 0.25)
		(keepout
			(tracks allowed)
			(vias allowed)
			(pads allowed)
			(copperpour allowed)
			(footprints allowed)
		)
		(placement
			(enabled no)
			(sheetname "")
		)
		(fill
			(thermal_gap 0.5)
			(thermal_bridge_width 0.5)
			(island_removal_mode 0)
		)
		(polygon
			(pts
				(xy 31.682944 -89.611454) (xy 32.60344 -89.611454) (xy 32.919162 -89.295732) (xy 32.919162 -87.791544)
				(xy 32.766508 -87.63889) (xy 31.772606 -87.63889) (xy 31.504128 -87.907368) (xy 31.504128 -89.432638)
			)
		)
	)
	(zone
		(layer "Cmts.User")
		(hatch none 0.5)
		(connect_pads
			(clearance 0)
		)
		(min_thickness 0.25)
		(keepout
			(tracks allowed)
			(vias allowed)
			(pads allowed)
			(copperpour allowed)
			(footprints allowed)
		)
		(placement
			(enabled no)
			(sheetname "")
		)
		(fill
			(thermal_gap 0.5)
			(thermal_bridge_width 0.5)
			(island_removal_mode 0)
		)
		(polygon
			(pts
				(xy -1.435608 -151.201374) (xy 0.643128 -151.201374) (xy 0.884936 -150.959566) (xy 0.884936 -145.578576)
				(xy 0.632206 -145.325846) (xy 0.211582 -145.325846) (xy -0.230124 -145.767552) (xy -0.230124 -148.976334)
				(xy -0.58801 -149.33422) (xy -1.47701 -149.33422) (xy -1.77673 -149.63394) (xy -1.77673 -150.860252)
			)
		)
	)
	(zone
		(layer "Cmts.User")
		(hatch none 0.5)
		(connect_pads
			(clearance 0)
		)
		(min_thickness 0.25)
		(keepout
			(tracks allowed)
			(vias allowed)
			(pads allowed)
			(copperpour allowed)
			(footprints allowed)
		)
		(placement
			(enabled no)
			(sheetname "")
		)
		(fill
			(thermal_gap 0.5)
			(thermal_bridge_width 0.5)
			(island_removal_mode 0)
		)
		(polygon
			(pts
				(xy 30.935676 -60.74918) (xy 32.135064 -60.74918) (xy 32.997648 -59.886596) (xy 32.997648 -55.37327)
				(xy 32.803338 -55.17896) (xy 31.793434 -55.17896) (xy 31.151576 -55.820818) (xy 31.151576 -58.918602)
				(xy 30.670246 -59.399932) (xy 30.670246 -60.48375)
			)
		)
	)
	(zone
		(layer "Cmts.User")
		(hatch none 0.5)
		(connect_pads
			(clearance 0)
		)
		(min_thickness 0.25)
		(keepout
			(tracks allowed)
			(vias allowed)
			(pads allowed)
			(copperpour allowed)
			(footprints allowed)
		)
		(placement
			(enabled no)
			(sheetname "")
		)
		(fill
			(thermal_gap 0.5)
			(thermal_bridge_width 0.5)
			(island_removal_mode 0)
		)
		(polygon
			(pts
				(xy 354.766626 -150.549356) (xy 358.469692 -150.549356) (xy 359.311448 -149.7076) (xy 359.311448 -148.361146)
				(xy 359.006394 -148.056092) (xy 354.935028 -148.056092) (xy 354.5459 -148.44522) (xy 354.5459 -150.32863)
			)
		)
	)
	(zone
		(layer "Cmts.User")
		(hatch none 0.5)
		(connect_pads
			(clearance 0)
		)
		(min_thickness 0.25)
		(keepout
			(tracks allowed)
			(vias allowed)
			(pads allowed)
			(copperpour allowed)
			(footprints allowed)
		)
		(placement
			(enabled no)
			(sheetname "")
		)
		(fill
			(thermal_gap 0.5)
			(thermal_bridge_width 0.5)
			(island_removal_mode 0)
		)
		(polygon
			(pts
				(xy 31.02102 -87.198708) (xy 33.196276 -87.198708) (xy 33.454086 -86.940898) (xy 33.454086 -86.162388)
				(xy 33.285938 -85.99424) (xy 31.113476 -85.99424) (xy 30.784546 -86.32317) (xy 30.784546 -86.962234)
			)
		)
	)
	(zone
		(layer "Cmts.User")
		(hatch none 0.5)
		(connect_pads
			(clearance 0)
		)
		(min_thickness 0.25)
		(keepout
			(tracks allowed)
			(vias allowed)
			(pads allowed)
			(copperpour allowed)
			(footprints allowed)
		)
		(placement
			(enabled no)
			(sheetname "")
		)
		(fill
			(thermal_gap 0.5)
			(thermal_bridge_width 0.5)
			(island_removal_mode 0)
		)
		(polygon
			(pts
				(xy 344.23604 -33.028382) (xy 354.893372 -33.028382) (xy 356.165912 -31.755842) (xy 356.165912 -28.105354)
				(xy 355.618796 -27.558238) (xy 355.618796 -25.748488) (xy 354.924614 -25.054306) (xy 348.328488 -25.054306)
				(xy 348.212664 -25.17013) (xy 348.212664 -30.630368) (xy 347.287342 -31.55569) (xy 344.130884 -31.55569)
				(xy 343.857326 -31.829248) (xy 343.857326 -32.649668)
			)
		)
	)
	(zone
		(layer "Cmts.User")
		(hatch none 0.5)
		(connect_pads
			(clearance 0)
		)
		(min_thickness 0.25)
		(keepout
			(tracks allowed)
			(vias allowed)
			(pads allowed)
			(copperpour allowed)
			(footprints allowed)
		)
		(placement
			(enabled no)
			(sheetname "")
		)
		(fill
			(thermal_gap 0.5)
			(thermal_bridge_width 0.5)
			(island_removal_mode 0)
		)
		(polygon
			(pts
				(xy 32.004 -54.356) (xy 32.004 -53.34) (xy 33.528 -53.34) (xy 33.528 -54.356)
			)
		)
	)
	(zone
		(layer "Cmts.User")
		(hatch none 0.5)
		(connect_pads
			(clearance 0)
		)
		(min_thickness 0.25)
		(keepout
			(tracks allowed)
			(vias allowed)
			(pads allowed)
			(copperpour allowed)
			(footprints allowed)
		)
		(placement
			(enabled no)
			(sheetname "")
		)
		(fill
			(thermal_gap 0.5)
			(thermal_bridge_width 0.5)
			(island_removal_mode 0)
		)
		(polygon
			(pts
				(xy -2.481326 -10.429494) (xy -0.187706 -10.429494) (xy 0.090932 -10.150856) (xy 0.090932 -9.393428)
				(xy -0.019558 -9.282938) (xy -2.144776 -9.282938) (xy -2.607564 -9.745726) (xy -2.607564 -10.303256)
			)
		)
	)
	(zone
		(layer "Cmts.User")
		(hatch none 0.5)
		(connect_pads
			(clearance 0)
		)
		(min_thickness 0.25)
		(keepout
			(tracks allowed)
			(vias allowed)
			(pads allowed)
			(copperpour allowed)
			(footprints allowed)
		)
		(placement
			(enabled no)
			(sheetname "")
		)
		(fill
			(thermal_gap 0.5)
			(thermal_bridge_width 0.5)
			(island_removal_mode 0)
		)
		(polygon
			(pts
				(xy 382.697736 -153.063702) (xy 387.558026 -153.063702) (xy 388.34695 -152.274778) (xy 388.34695 -151.496014)
				(xy 388.178802 -151.327866) (xy 382.876552 -151.327866) (xy 382.571498 -151.63292) (xy 382.571498 -152.937464)
			)
		)
	)
	(zone
		(layer "In9.Cu")
		(hatch none 0.5)
		(connect_pads
			(clearance 0)
		)
		(min_thickness 0.25)
		(keepout
			(tracks not_allowed)
			(vias allowed)
			(pads allowed)
			(copperpour not_allowed)
			(footprints allowed)
		)
		(placement
			(enabled no)
			(sheetname "")
		)
		(fill
			(thermal_gap 0.5)
			(thermal_bridge_width 0.5)
			(island_removal_mode 0)
		)
		(polygon
			(pts
				(xy 434.37175 -9.816846) (xy 434.37175 -9.845802) (xy 434.35143 -9.866122)
				(arc
					(start 434.227732 -9.990074)
					(mid 433.707574 -10.078302)
					(end 434.178964 -9.84123)
				)
				(xy 434.23205 -9.78789) (xy 434.23205 -9.61136)
				(arc
					(start 433.961032 -9.61136)
					(mid 433.577492 -9.9949)
					(end 433.961032 -10.37844)
				)
				(arc
					(start 434.925978 -10.37844)
					(mid 435.309772 -9.995027)
					(end 434.926232 -9.61136)
				)
				(xy 434.66385 -9.61136) (xy 434.66385 -9.826244)
				(arc
					(start 434.696616 -9.85901)
					(mid 435.186624 -10.052234)
					(end 434.660802 -10.020808)
				)
				(xy 434.52415 -9.884156) (xy 434.52415 -9.61136) (xy 434.37175 -9.61136)
			)
		)
	)
	(zone
		(layer "In9.Cu")
		(hatch none 0.5)
		(connect_pads
			(clearance 0)
		)
		(min_thickness 0.25)
		(keepout
			(tracks not_allowed)
			(vias allowed)
			(pads allowed)
			(copperpour not_allowed)
			(footprints allowed)
		)
		(placement
			(enabled no)
			(sheetname "")
		)
		(fill
			(thermal_gap 0.5)
			(thermal_bridge_width 0.5)
			(island_removal_mode 0)
		)
		(polygon
			(pts
				(arc
					(start 419.704266 -154.7368)
					(mid 419.320726 -154.35326)
					(end 418.937186 -154.7368)
				)
				(arc
					(start 418.937186 -156.006546)
					(mid 419.320599 -156.39034)
					(end 419.704266 -156.0068)
				)
				(xy 419.704266 -155.6004)
				(arc
					(start 419.435026 -155.6004)
					(mid 419.403595 -155.613419)
					(end 419.390576 -155.64485)
				)
				(arc
					(start 419.390576 -155.749498)
					(mid 419.320726 -156.273415)
					(end 419.250876 -155.749498)
				)
				(xy 419.250876 -155.615894)
				(arc
					(start 419.25367 -155.6131)
					(mid 419.304838 -155.514662)
					(end 419.403276 -155.463494)
				)
				(xy 419.40607 -155.4607) (xy 419.704266 -155.4607) (xy 419.704266 -155.3083) (xy 419.40607 -155.3083)
				(arc
					(start 419.403276 -155.305506)
					(mid 419.304838 -155.254338)
					(end 419.25367 -155.1559)
				)
				(xy 419.250876 -155.153106)
				(arc
					(start 419.250876 -154.994102)
					(mid 419.320726 -154.470185)
					(end 419.390576 -154.994102)
				)
				(arc
					(start 419.390576 -155.12415)
					(mid 419.403595 -155.155581)
					(end 419.435026 -155.1686)
				)
				(xy 419.704266 -155.1686)
			)
		)
	)
	(zone
		(layer "In9.Cu")
		(hatch none 0.5)
		(connect_pads
			(clearance 0)
		)
		(min_thickness 0.25)
		(keepout
			(tracks allowed)
			(vias allowed)
			(pads allowed)
			(copperpour allowed)
			(footprints allowed)
		)
		(placement
			(enabled no)
			(sheetname "")
		)
		(fill
			(thermal_gap 0.5)
			(thermal_bridge_width 0.5)
			(island_removal_mode 0)
		)
		(polygon
			(pts
				(xy 372.158006 -98.789998) (xy 372.158006 -96.431862) (xy 373.439944 -96.431862) (xy 373.439944 -98.789998)
			)
		)
	)
	(zone
		(layer "In9.Cu")
		(hatch none 0.5)
		(connect_pads
			(clearance 0)
		)
		(min_thickness 0.25)
		(keepout
			(tracks not_allowed)
			(vias allowed)
			(pads allowed)
			(copperpour not_allowed)
			(footprints allowed)
		)
		(placement
			(enabled no)
			(sheetname "")
		)
		(fill
			(thermal_gap 0.5)
			(thermal_bridge_width 0.5)
			(island_removal_mode 0)
		)
		(polygon
			(pts
				(arc
					(start 129.590546 -41.549828)
					(mid 124.409454 -41.549828)
					(end 129.590546 -41.549828)
				)
			)
		)
	)
	(zone
		(net "PVTT_GHJ")
		(layer "In9.Cu")
		(hatch none 0.5)
		(connect_pads
			(clearance 0.5)
		)
		(min_thickness 0.25)
		(fill yes
			(thermal_gap 0.5)
			(thermal_bridge_width 0.5)
			(island_removal_mode 0)
		)
		(polygon
			(pts
				(xy 96.902524 -22.279356) (xy 98.141536 -21.040344) (xy 98.141536 -15.6337) (xy 97.18294 -14.675104)
				(xy 97.18294 -9.6139) (xy 96.811338 -9.242298) (xy 94.541848 -9.242298) (xy 94.30766 -9.476486)
				(xy 94.30766 -16.27378) (xy 94.30766 -22.09292) (xy 94.494096 -22.279356)
			)
		)
	)
	(zone
		(layer "In9.Cu")
		(hatch none 0.5)
		(connect_pads
			(clearance 0)
		)
		(min_thickness 0.25)
		(keepout
			(tracks not_allowed)
			(vias allowed)
			(pads allowed)
			(copperpour not_allowed)
			(footprints allowed)
		)
		(placement
			(enabled no)
			(sheetname "")
		)
		(fill
			(thermal_gap 0.5)
			(thermal_bridge_width 0.5)
			(island_removal_mode 0)
		)
		(polygon
			(pts
				(arc
					(start 163.665408 -135.37057)
					(mid 160.333436 -135.37057)
					(end 163.665408 -135.37057)
				)
			)
		)
	)
	(zone
		(layer "In9.Cu")
		(hatch none 0.5)
		(connect_pads
			(clearance 0)
		)
		(min_thickness 0.25)
		(keepout
			(tracks not_allowed)
			(vias allowed)
			(pads allowed)
			(copperpour not_allowed)
			(footprints allowed)
		)
		(placement
			(enabled no)
			(sheetname "")
		)
		(fill
			(thermal_gap 0.5)
			(thermal_bridge_width 0.5)
			(island_removal_mode 0)
		)
		(polygon
			(pts
				(xy 445.29375 -9.80186) (xy 445.576706 -10.08507) (xy 445.737488 -10.029952) (xy 445.610234 -9.902698)
				(xy 445.610234 -9.73836)
				(arc
					(start 445.640206 -9.708388)
					(mid 446.055747 -9.382894)
					(end 445.749934 -9.813036)
				)
				(xy 445.749934 -9.844786) (xy 445.879982 -9.974834) (xy 445.89827 -9.974834) (xy 445.996822 -9.941052)
				(arc
					(start 445.99606 -9.938512)
					(mid 446.234312 -9.45134)
					(end 445.74714 -9.213088)
				)
				(xy 445.746378 -9.210548) (xy 444.883032 -9.506458) (xy 444.883032 -9.506712)
				(arc
					(start 444.883794 -9.508744)
					(mid 444.645262 -9.996095)
					(end 445.13246 -10.234422)
				)
				(xy 445.133222 -10.236962) (xy 445.42964 -10.135362)
				(arc
					(start 445.25819 -9.963912)
					(mid 444.741619 -9.859981)
					(end 445.265302 -9.80186)
				)
			)
		)
	)
	(zone
		(layer "In9.Cu")
		(hatch none 0.5)
		(connect_pads
			(clearance 0)
		)
		(min_thickness 0.25)
		(keepout
			(tracks not_allowed)
			(vias allowed)
			(pads allowed)
			(copperpour not_allowed)
			(footprints allowed)
		)
		(placement
			(enabled no)
			(sheetname "")
		)
		(fill
			(thermal_gap 0.5)
			(thermal_bridge_width 0.5)
			(island_removal_mode 0)
		)
		(polygon
			(pts
				(xy 407.11501 -151.195278) (xy 407.115264 -151.195532)
				(arc
					(start 407.262838 -151.343106)
					(mid 407.584003 -151.763077)
					(end 407.164032 -151.441912)
				)
				(xy 407.016204 -151.294084) (xy 407.011886 -151.290274)
				(arc
					(start 407.011886 -151.574246)
					(mid 407.395299 -151.95804)
					(end 407.778966 -151.5745)
				)
				(arc
					(start 407.778966 -150.5585)
					(mid 407.395426 -150.17496)
					(end 407.011886 -150.5585)
				)
				(xy 407.011886 -150.841964) (xy 407.018744 -150.836376)
				(arc
					(start 407.164032 -150.691088)
					(mid 407.584003 -150.369923)
					(end 407.262838 -150.789894)
				)
				(xy 407.117804 -150.934928) (xy 407.11755 -150.935182) (xy 407.09723 -150.955502)
				(arc
					(start 407.09342 -150.955502)
					(mid 407.058034 -150.974971)
					(end 407.019252 -150.986236)
				)
				(xy 407.016458 -150.98903) (xy 407.011886 -150.98903) (xy 407.011886 -151.14143) (xy 407.013918 -151.14143)
				(arc
					(start 407.016712 -151.144224)
					(mid 407.055487 -151.155508)
					(end 407.09088 -151.174958)
				)
				(xy 407.09469 -151.174958)
			)
		)
	)
	(zone
		(net "PVDDQ_DEF")
		(layer "In9.Cu")
		(hatch none 0.5)
		(connect_pads
			(clearance 0.5)
		)
		(min_thickness 0.25)
		(fill yes
			(thermal_gap 0.5)
			(thermal_bridge_width 0.5)
			(island_removal_mode 0)
		)
		(polygon
			(pts
				(xy 250.3932 -93.2688) (xy 250.3932 -92.456) (xy 258.5466 -84.3026) (xy 267.7414 -84.3026) (xy 271.3736 -84.3026)
				(xy 271.382236 -84.311236) (xy 274.197064 -84.311236) (xy 274.667218 -84.78139) (xy 274.667218 -86.298278)
				(xy 274.335494 -86.630002) (xy 272.72488 -86.630002) (xy 272.4404 -86.914482) (xy 272.4404 -87.4014)
				(xy 271.5641 -88.2777) (xy 265.8237 -88.2777) (xy 263.4996 -90.6018) (xy 263.4996 -91.313) (xy 264.0838 -91.8972)
				(xy 265.557 -91.8972) (xy 267.9954 -94.3356) (xy 267.9954 -99.7204) (xy 267.2334 -100.4824) (xy 253.4666 -100.4824)
				(xy 250.3932 -97.409)
			)
		)
	)
	(zone
		(layer "In9.Cu")
		(hatch none 0.5)
		(connect_pads
			(clearance 0)
		)
		(min_thickness 0.25)
		(keepout
			(tracks not_allowed)
			(vias allowed)
			(pads allowed)
			(copperpour not_allowed)
			(footprints allowed)
		)
		(placement
			(enabled no)
			(sheetname "")
		)
		(fill
			(thermal_gap 0.5)
			(thermal_bridge_width 0.5)
			(island_removal_mode 0)
		)
		(polygon
			(pts
				(xy 451.161912 -60.340748) (xy 451.097904 -60.40501) (xy 451.060566 -60.442348) (xy 451.008242 -60.442348)
				(arc
					(start 450.969634 -60.442348)
					(mid 450.443806 -60.378848)
					(end 450.969634 -60.315348)
				)
				(xy 451.008242 -60.315348) (xy 451.072504 -60.25134) (xy 451.072504 -59.969908)
				(arc
					(start 450.710808 -59.969908)
					(mid 450.301614 -60.378721)
					(end 450.710554 -60.787788)
				)
				(arc
					(start 451.980554 -60.787788)
					(mid 452.389494 -60.378848)
					(end 451.980554 -59.969908)
				)
				(xy 451.618604 -59.969908) (xy 451.618604 -60.25134) (xy 451.682612 -60.315348)
				(arc
					(start 451.721474 -60.315348)
					(mid 452.247302 -60.378848)
					(end 451.721474 -60.442348)
				)
				(xy 451.682612 -60.442348) (xy 451.630288 -60.442348) (xy 451.593204 -60.40501) (xy 451.528942 -60.340748)
				(xy 451.491604 -60.303664) (xy 451.491604 -60.25134) (xy 451.491604 -59.969908) (xy 451.198996 -59.969908)
				(xy 451.198996 -60.25134) (xy 451.19925 -60.25134) (xy 451.19925 -60.303664) (xy 451.198996 -60.303664)
			)
		)
	)
	(zone
		(layer "In9.Cu")
		(hatch none 0.5)
		(connect_pads
			(clearance 0)
		)
		(min_thickness 0.25)
		(keepout
			(tracks allowed)
			(vias allowed)
			(pads allowed)
			(copperpour allowed)
			(footprints allowed)
		)
		(placement
			(enabled no)
			(sheetname "")
		)
		(fill
			(thermal_gap 0.5)
			(thermal_bridge_width 0.5)
			(island_removal_mode 0)
		)
		(polygon
			(pts
				(xy 230.599996 -53.610002) (xy 230.599996 -98.171) (xy 231.7242 -99.295204) (xy 231.7242 -100.1268)
				(xy 233.0704 -101.473) (xy 234.5944 -101.9302) (xy 242.0366 -102.6414) (xy 248.7676 -101.7524) (xy 254.3556 -102.7176)
				(xy 266.8524 -102.7938) (xy 269.6718 -103.0732) (xy 277.5966 -104.7496) (xy 283.3624 -104.0384)
				(xy 284.3276 -104.0384) (xy 292.2524 -102.3874) (xy 298.8564 -103.7844) (xy 305.9684 -102.6668)
				(xy 308.3306 -97.536) (xy 308.3814 -97.4852) (xy 308.3814 -86.251796) (xy 309.974996 -84.6582) (xy 309.974996 -52.975002)
				(xy 306.935124 -49.934876) (xy 306.832 -50.038) (xy 289.052 -50.038) (xy 285.623 -53.467) (xy 268.097 -53.467)
				(xy 264.922 -50.292) (xy 264.2108 -50.292) (xy 264.0584 -50.1396) (xy 262.8138 -50.1396) (xy 262.5471 -50.4063)
				(xy 261.7216 -49.5808) (xy 251.714 -49.5808) (xy 250.825 -48.6918) (xy 236.533944 -48.6918) (xy 235.741972 -49.483772)
				(xy 234.725972 -49.483772)
			)
		)
	)
	(zone
		(net "GND")
		(layer "In9.Cu")
		(hatch none 0.5)
		(connect_pads
			(clearance 0.5)
		)
		(min_thickness 0.25)
		(fill yes
			(thermal_gap 0.5)
			(thermal_bridge_width 0.5)
			(island_removal_mode 0)
		)
		(polygon
			(pts
				(xy 199.38238 -60.41898) (xy 199.38238 -62.41542) (xy 199.38238 -77.25918) (xy 199.38238 -78.67142)
				(xy 199.38238 -84.75218) (xy 199.38238 -86.41842) (xy 199.38238 -92.904564) (xy 199.515984 -93.038168)
				(xy 207.640428 -93.038168) (xy 207.8482 -92.830396) (xy 207.8482 -54.102) (xy 207.8482 -53.876702)
				(xy 207.479138 -53.50764) (xy 206.66964 -53.50764) (xy 206.2226 -53.0606) (xy 206.2226 -52.5018)
				(xy 206.0194 -52.2986) (xy 205.486 -51.7652) (xy 204.1398 -51.7652) (xy 201.9808 -51.7652) (xy 201.6506 -52.0954)
				(xy 201.3204 -52.4256) (xy 199.526144 -52.4256) (xy 199.38238 -52.569364)
			)
		)
	)
	(zone
		(net "P12V_STBY")
		(layer "In9.Cu")
		(hatch none 0.5)
		(connect_pads
			(clearance 0.5)
		)
		(min_thickness 0.25)
		(fill yes
			(thermal_gap 0.5)
			(thermal_bridge_width 0.5)
			(island_removal_mode 0)
		)
		(polygon
			(pts
				(xy 483.164896 -25.677368) (xy 483.164896 -24.019764) (xy 483.164896 -23.953978) (xy 483.164896 -22.853904)
				(xy 483.4382 -22.5806) (xy 484.8352 -22.5806) (xy 485.041956 -22.787356) (xy 485.041956 -24.008588)
				(xy 485.041956 -24.100028) (xy 485.041956 -25.784048) (xy 484.970074 -25.85593) (xy 484.857552 -25.968452)
				(xy 483.343458 -25.968452) (xy 483.230936 -25.85593) (xy 483.164896 -25.78989)
			)
		)
	)
	(zone
		(net "P1V05_PCH_STBY_ISCLK_PLL")
		(layer "In9.Cu")
		(hatch none 0.5)
		(connect_pads
			(clearance 0.5)
		)
		(min_thickness 0.25)
		(fill yes
			(thermal_gap 0.5)
			(thermal_bridge_width 0.5)
			(island_removal_mode 0)
		)
		(polygon
			(pts
				(xy 372.7958 -131.7752) (xy 374.8532 -131.7752) (xy 375.1072 -131.5212) (xy 375.1072 -129.286) (xy 375.54789 -128.84531)
				(xy 376.877326 -128.84531) (xy 377.297696 -128.42494) (xy 377.300236 -128.4224) (xy 378.151136 -126.42469)
				(xy 382.29159 -119.38381) (xy 386.7912 -114.8842) (xy 386.7912 -114.046) (xy 386.334 -113.5888)
				(xy 384.4036 -113.5888) (xy 384.3528 -113.6396) (xy 380.873 -113.6396) (xy 377.1646 -117.348) (xy 377.1646 -121.0564)
				(xy 373.1514 -125.0696) (xy 373.1514 -127.381) (xy 372.491 -128.0414) (xy 372.491 -131.4704)
			)
		)
	)
	(zone
		(layer "In9.Cu")
		(hatch none 0.5)
		(connect_pads
			(clearance 0)
		)
		(min_thickness 0.25)
		(keepout
			(tracks not_allowed)
			(vias allowed)
			(pads allowed)
			(copperpour not_allowed)
			(footprints allowed)
		)
		(placement
			(enabled no)
			(sheetname "")
		)
		(fill
			(thermal_gap 0.5)
			(thermal_bridge_width 0.5)
			(island_removal_mode 0)
		)
		(polygon
			(pts
				(arc
					(start 15.381224 -32.197802)
					(mid 15.451074 -31.673885)
					(end 15.520924 -32.197802)
				)
				(xy 15.520924 -32.286194) (xy 15.59433 -32.3596) (xy 15.834614 -32.3596)
				(arc
					(start 15.834614 -31.940754)
					(mid 15.451201 -31.55696)
					(end 15.067534 -31.9405)
				)
				(arc
					(start 15.067534 -33.2105)
					(mid 15.451074 -33.59404)
					(end 15.834614 -33.2105)
				)
				(xy 15.834614 -32.7914) (xy 15.59433 -32.7914) (xy 15.520924 -32.864806)
				(arc
					(start 15.520924 -32.953198)
					(mid 15.451074 -33.477115)
					(end 15.381224 -32.953198)
				)
				(xy 15.381224 -32.806894) (xy 15.536418 -32.6517) (xy 15.834614 -32.6517) (xy 15.834614 -32.4993)
				(xy 15.536418 -32.4993) (xy 15.381224 -32.344106)
			)
		)
	)
	(zone
		(net "GND")
		(layer "In9.Cu")
		(hatch none 0.5)
		(connect_pads
			(clearance 0.5)
		)
		(min_thickness 0.25)
		(fill yes
			(thermal_gap 0.5)
			(thermal_bridge_width 0.5)
			(island_removal_mode 0)
		)
		(polygon
			(pts
				(xy -5.03174 15.24) (xy -5.03174 8.763) (xy 413.4358 8.763) (xy 501.2182 8.763) (xy 501.2182 8.7884)
				(xy 501.2182 15.24)
			)
		)
		(polygon
			(pts
				(xy 189.6618 14.5288) (xy 132.518658 14.5288) (xy 132.518658 9.4742) (xy 189.6618 9.4742) (xy 189.6618 9.4996)
				(xy 194.1322 9.4996) (xy 195.339462 9.4996) (xy 198.934578 9.4996) (xy 198.934578 14.5034) (xy 195.339462 14.5034)
				(xy 194.1322 14.5034) (xy 189.6618 14.5034)
			)
		)
		(polygon
			(pts
				(xy 100.1776 14.61262) (xy 24.2316 14.61262) (xy 24.2316 9.4742) (xy 36.957 9.4742) (xy 36.957 9.9187)
				(xy 100.838 9.9187) (xy 100.838 9.9314) (xy 106.214926 9.9314) (xy 108.6612 9.9314) (xy 114.39652 9.9314)
				(xy 114.39652 14.605) (xy 108.6612 14.605) (xy 106.2228 14.605) (xy 100.1776 14.605)
			)
		)
		(polygon
			(pts
				(xy 366.6744 14.5288) (xy 357.459788 14.5288) (xy 357.459788 9.4742) (xy 366.6744 9.4742) (xy 416.3568 9.4742)
				(xy 424.283632 9.4742) (xy 424.283632 14.5288) (xy 416.3568 14.5288)
			)
		)
		(polygon
			(pts
				(xy 273.4818 14.5034) (xy 216.909904 14.5034) (xy 216.909904 9.4234) (xy 273.4818 9.4234) (xy 283.28239 9.4234)
				(xy 283.28239 14.5034) (xy 279.202134 14.5034) (xy 277.9268 14.5034)
			)
		)
	)
	(zone
		(net "P1V8_PCH_STBY")
		(layer "In9.Cu")
		(hatch none 0.5)
		(connect_pads
			(clearance 0.5)
		)
		(min_thickness 0.25)
		(fill yes
			(thermal_gap 0.5)
			(thermal_bridge_width 0.5)
			(island_removal_mode 0)
		)
		(polygon
			(pts
				(xy 384.683 -102.87) (xy 384.683 -104.8258) (xy 385.2926 -105.4354) (xy 387.0706 -105.4354) (xy 388.436866 -104.069134)
				(xy 388.436866 -103.580692) (xy 387.777228 -102.921054) (xy 387.005322 -102.921054) (xy 386.861558 -103.064818)
				(xy 386.4737 -103.064818) (xy 386.13842 -102.729538) (xy 384.823462 -102.729538)
			)
		)
	)
	(zone
		(layer "In9.Cu")
		(hatch none 0.5)
		(connect_pads
			(clearance 0)
		)
		(min_thickness 0.25)
		(keepout
			(tracks allowed)
			(vias allowed)
			(pads allowed)
			(copperpour allowed)
			(footprints allowed)
		)
		(placement
			(enabled no)
			(sheetname "")
		)
		(fill
			(thermal_gap 0.5)
			(thermal_bridge_width 0.5)
			(island_removal_mode 0)
		)
		(polygon
			(pts
				(xy 370.586 -118.745) (xy 370.586 -117.475) (xy 372.2878 -117.475) (xy 372.2878 -118.745)
			)
		)
	)
	(zone
		(layer "In9.Cu")
		(hatch none 0.5)
		(connect_pads
			(clearance 0)
		)
		(min_thickness 0.25)
		(keepout
			(tracks not_allowed)
			(vias allowed)
			(pads allowed)
			(copperpour not_allowed)
			(footprints allowed)
		)
		(placement
			(enabled no)
			(sheetname "")
		)
		(fill
			(thermal_gap 0.5)
			(thermal_bridge_width 0.5)
			(island_removal_mode 0)
		)
		(polygon
			(pts
				(xy 409.5115 -152.847548) (xy 409.511754 -152.847802)
				(arc
					(start 409.658058 -152.994106)
					(mid 409.979223 -153.414077)
					(end 409.559252 -153.092912)
				)
				(xy 409.412694 -152.946354) (xy 409.407106 -152.941528)
				(arc
					(start 409.407106 -153.225246)
					(mid 409.790519 -153.60904)
					(end 410.174186 -153.2255)
				)
				(arc
					(start 410.174186 -152.2095)
					(mid 409.790646 -151.82596)
					(end 409.407106 -152.2095)
				)
				(xy 409.407106 -152.493472) (xy 409.412694 -152.488646)
				(arc
					(start 409.559252 -152.342088)
					(mid 409.979223 -152.020923)
					(end 409.658058 -152.440894)
				)
				(xy 409.511754 -152.587198) (xy 409.5115 -152.587452) (xy 409.49118 -152.607772)
				(arc
					(start 409.48737 -152.607772)
					(mid 409.451984 -152.627241)
					(end 409.413202 -152.638506)
				)
				(xy 409.410408 -152.6413) (xy 409.407106 -152.6413) (xy 409.407106 -152.7937) (xy 409.410408 -152.7937)
				(arc
					(start 409.413202 -152.796494)
					(mid 409.451977 -152.807778)
					(end 409.48737 -152.827228)
				)
				(xy 409.49118 -152.827228)
			)
		)
	)
	(zone
		(layer "In9.Cu")
		(hatch none 0.5)
		(connect_pads
			(clearance 0)
		)
		(min_thickness 0.25)
		(keepout
			(tracks not_allowed)
			(vias allowed)
			(pads allowed)
			(copperpour not_allowed)
			(footprints allowed)
		)
		(placement
			(enabled no)
			(sheetname "")
		)
		(fill
			(thermal_gap 0.5)
			(thermal_bridge_width 0.5)
			(island_removal_mode 0)
		)
		(polygon
			(pts
				(arc
					(start 15.381224 -35.753802)
					(mid 15.451074 -35.229885)
					(end 15.520924 -35.753802)
				)
				(xy 15.520924 -35.842194) (xy 15.600172 -35.921442) (xy 15.834614 -35.921442)
				(arc
					(start 15.834614 -35.496754)
					(mid 15.451201 -35.11296)
					(end 15.067534 -35.4965)
				)
				(arc
					(start 15.067534 -36.7665)
					(mid 15.451074 -37.15004)
					(end 15.834614 -36.7665)
				)
				(xy 15.834614 -36.353242) (xy 15.602966 -36.353242) (xy 15.520924 -36.435284)
				(arc
					(start 15.520924 -36.509198)
					(mid 15.451074 -37.033115)
					(end 15.381224 -36.509198)
				)
				(xy 15.381224 -36.377372) (xy 15.545054 -36.213542) (xy 15.834614 -36.213542) (xy 15.834614 -36.061142)
				(xy 15.54226 -36.061142) (xy 15.381224 -35.900106)
			)
		)
	)
	(zone
		(net "VR_FET_SW_P12V_STBY_PVCCIN_CPU0")
		(layer "In9.Cu")
		(hatch none 0.5)
		(connect_pads
			(clearance 0.5)
		)
		(min_thickness 0.25)
		(fill yes
			(thermal_gap 0.5)
			(thermal_bridge_width 0.5)
			(island_removal_mode 0)
		)
		(polygon
			(pts
				(xy 195.0212 -52.8828) (xy 193.6496 -52.8828) (xy 191.585342 -54.947058) (xy 188.238384 -54.947058)
				(xy 187.508642 -54.947058) (xy 187.1599 -55.2958) (xy 187.1599 -57.4548) (xy 187.89396 -58.18886)
				(xy 187.89396 -59.35218) (xy 187.89396 -61.8363) (xy 188.5696 -62.51194) (xy 188.5696 -62.74562)
				(xy 188.5696 -84.2391) (xy 188.5696 -98.33356) (xy 190.30442 -100.06838) (xy 193.59118 -100.06838)
				(xy 193.802 -100.2792) (xy 194.474084 -100.951284) (xy 198.761604 -100.951284) (xy 199.131936 -100.580698)
				(xy 199.131936 -56.016144) (xy 199.121776 -56.005984) (xy 199.121776 -54.148736) (xy 197.85584 -52.8828)
			)
		)
	)
	(zone
		(net "P12V")
		(layer "In9.Cu")
		(hatch none 0.5)
		(connect_pads
			(clearance 0.5)
		)
		(min_thickness 0.25)
		(fill yes
			(thermal_gap 0.5)
			(thermal_bridge_width 0.5)
			(island_removal_mode 0)
		)
		(polygon
			(pts
				(xy 490.406436 -20.864576) (xy 496.403376 -20.864576) (xy 496.71351 -20.554442) (xy 496.71351 -19.863816)
				(xy 494.43386 -17.584166) (xy 490.115098 -17.584166) (xy 489.83646 -17.862804) (xy 489.83646 -20.2946)
			)
		)
	)
	(zone
		(layer "In9.Cu")
		(hatch none 0.5)
		(connect_pads
			(clearance 0)
		)
		(min_thickness 0.25)
		(keepout
			(tracks not_allowed)
			(vias allowed)
			(pads allowed)
			(copperpour not_allowed)
			(footprints allowed)
		)
		(placement
			(enabled no)
			(sheetname "")
		)
		(fill
			(thermal_gap 0.5)
			(thermal_bridge_width 0.5)
			(island_removal_mode 0)
		)
		(polygon
			(pts
				(xy 396.57909 -127.950214) (xy 396.57909 -127.045212) (xy 395.89075 -127.045212) (xy 395.89075 -127.950214)
			)
		)
	)
	(zone
		(net "PVDDQ_KLM")
		(layer "In9.Cu")
		(hatch none 0.5)
		(connect_pads
			(clearance 0.5)
		)
		(min_thickness 0.25)
		(fill yes
			(thermal_gap 0.5)
			(thermal_bridge_width 0.5)
			(island_removal_mode 0)
		)
		(polygon
			(pts
				(xy 92.5322 -85.0138) (xy 102.7684 -85.0138) (xy 106.6292 -85.0138) (xy 109.46765 -85.0138) (xy 109.727492 -85.273642)
				(xy 109.727492 -86.853522) (xy 109.205014 -87.376) (xy 106.9594 -87.376) (xy 105.5624 -88.773) (xy 100.2284 -88.773)
				(xy 99.441 -89.5604) (xy 97.8408 -91.1606) (xy 97.8408 -92.1004) (xy 98.044 -92.3036) (xy 101.1174 -92.3036)
				(xy 103.7844 -94.9706) (xy 103.7844 -100.457) (xy 102.8573 -101.3841) (xy 89.0651 -101.3841) (xy 85.725 -98.044)
				(xy 85.725 -88.011) (xy 88.7222 -85.0138)
			)
		)
	)
	(zone
		(layer "In9.Cu")
		(hatch none 0.5)
		(connect_pads
			(clearance 0)
		)
		(min_thickness 0.25)
		(keepout
			(tracks not_allowed)
			(vias allowed)
			(pads allowed)
			(copperpour not_allowed)
			(footprints allowed)
		)
		(placement
			(enabled no)
			(sheetname "")
		)
		(fill
			(thermal_gap 0.5)
			(thermal_bridge_width 0.5)
			(island_removal_mode 0)
		)
		(polygon
			(pts
				(arc
					(start 417.036504 -91.567)
					(mid 416.627564 -91.15806)
					(end 416.218624 -91.567)
				)
				(xy 416.218624 -91.876372) (xy 416.500056 -91.876372)
				(arc
					(start 416.553396 -91.823032)
					(mid 416.633609 -91.300434)
					(end 416.691064 -91.82608)
				)
				(xy 416.691064 -91.864688) (xy 416.653726 -91.901772) (xy 416.589718 -91.966034) (xy 416.589464 -91.966034)
				(xy 416.55238 -92.003372) (xy 416.500056 -92.003372) (xy 416.218624 -92.003372) (xy 416.218624 -92.29598)
				(xy 416.500056 -92.29598) (xy 416.500056 -92.295726) (xy 416.55238 -92.295726) (xy 416.55238 -92.29598)
				(xy 416.589464 -92.333064) (xy 416.653726 -92.397072) (xy 416.691064 -92.43441) (xy 416.691064 -92.486734)
				(arc
					(start 416.691064 -92.57792)
					(mid 416.627564 -93.103748)
					(end 416.564064 -92.57792)
				)
				(xy 416.564064 -92.486734) (xy 416.500056 -92.422472) (xy 416.218624 -92.422472)
				(arc
					(start 416.218624 -92.836746)
					(mid 416.627437 -93.24594)
					(end 417.036504 -92.837)
				)
			)
		)
	)
	(zone
		(layer "In9.Cu")
		(hatch none 0.5)
		(connect_pads
			(clearance 0)
		)
		(min_thickness 0.25)
		(keepout
			(tracks not_allowed)
			(vias allowed)
			(pads allowed)
			(copperpour not_allowed)
			(footprints allowed)
		)
		(placement
			(enabled no)
			(sheetname "")
		)
		(fill
			(thermal_gap 0.5)
			(thermal_bridge_width 0.5)
			(island_removal_mode 0)
		)
		(polygon
			(pts
				(xy 395.117828 -106.163618) (xy 395.112494 -106.168952) (xy 395.033246 -106.247946) (xy 395.033246 -106.2482)
				(arc
					(start 394.9319 -106.2482)
					(mid 394.404947 -106.190796)
					(end 394.9319 -106.133392)
				)
				(xy 394.986002 -106.133392)
				(arc
					(start 395.020038 -106.099356)
					(mid 395.055959 -105.960335)
					(end 395.121638 -105.832656)
				)
				(arc
					(start 394.671804 -105.832656)
					(mid 394.31341 -106.190669)
					(end 394.67155 -106.548936)
				)
				(arc
					(start 395.66215 -106.548936)
					(mid 396.02029 -106.190796)
					(end 395.66215 -105.832656)
				)
				(arc
					(start 395.579346 -105.832656)
					(mid 395.536299 -105.86523)
					(end 395.4907 -105.894124)
				)
				(arc
					(start 395.4907 -105.894124)
					(mid 395.386622 -105.987096)
					(end 395.32814 -106.113834)
				)
				(xy 395.347698 -106.133392)
				(arc
					(start 395.4018 -106.133392)
					(mid 395.928753 -106.190796)
					(end 395.4018 -106.2482)
				)
				(xy 395.300454 -106.2482) (xy 395.300454 -106.247946) (xy 395.228318 -106.176064) (xy 395.222984 -106.17073)
				(xy 395.209014 -106.156506) (xy 395.209014 -106.136694) (xy 395.209014 -106.129074) (xy 395.209014 -106.109262)
				(arc
					(start 395.21257 -106.105452)
					(mid 395.270444 -105.954212)
					(end 395.377416 -105.832656)
				)
				(arc
					(start 395.266672 -105.832656)
					(mid 395.175951 -105.970809)
					(end 395.131798 -106.13009)
				)
				(xy 395.131798 -106.149394)
			)
		)
	)
	(zone
		(layer "In9.Cu")
		(hatch none 0.5)
		(connect_pads
			(clearance 0)
		)
		(min_thickness 0.25)
		(keepout
			(tracks not_allowed)
			(vias allowed)
			(pads allowed)
			(copperpour not_allowed)
			(footprints allowed)
		)
		(placement
			(enabled no)
			(sheetname "")
		)
		(fill
			(thermal_gap 0.5)
			(thermal_bridge_width 0.5)
			(island_removal_mode 0)
		)
		(polygon
			(pts
				(arc
					(start 16.537686 -26.863802)
					(mid 16.607536 -26.339885)
					(end 16.677386 -26.863802)
				)
				(xy 16.677386 -26.952194) (xy 16.750792 -27.0256) (xy 16.991076 -27.0256)
				(arc
					(start 16.991076 -26.6065)
					(mid 16.607536 -26.22296)
					(end 16.223996 -26.6065)
				)
				(arc
					(start 16.223996 -27.876246)
					(mid 16.607409 -28.26004)
					(end 16.991076 -27.8765)
				)
				(xy 16.991076 -27.4574) (xy 16.750792 -27.4574) (xy 16.677386 -27.530806)
				(arc
					(start 16.677386 -27.619198)
					(mid 16.607536 -28.143115)
					(end 16.537686 -27.619198)
				)
				(xy 16.537686 -27.472894) (xy 16.69288 -27.3177) (xy 16.991076 -27.3177) (xy 16.991076 -27.1653)
				(xy 16.69288 -27.1653) (xy 16.537686 -27.010106)
			)
		)
	)
	(zone
		(layer "In9.Cu")
		(hatch none 0.5)
		(connect_pads
			(clearance 0)
		)
		(min_thickness 0.25)
		(keepout
			(tracks not_allowed)
			(vias allowed)
			(pads allowed)
			(copperpour not_allowed)
			(footprints allowed)
		)
		(placement
			(enabled no)
			(sheetname "")
		)
		(fill
			(thermal_gap 0.5)
			(thermal_bridge_width 0.5)
			(island_removal_mode 0)
		)
		(polygon
			(pts
				(xy 436.767732 -9.74598) (xy 436.767732 -10.015728)
				(arc
					(start 436.626508 -10.156698)
					(mid 436.100772 -10.185651)
					(end 436.591456 -9.994646)
				)
				(xy 436.628032 -9.957816) (xy 436.628032 -9.74598)
				(arc
					(start 436.361332 -9.74598)
					(mid 435.977792 -10.12952)
					(end 436.361332 -10.51306)
				)
				(arc
					(start 437.326278 -10.51306)
					(mid 437.709818 -10.129647)
					(end 437.326532 -9.74598)
				)
				(xy 437.059832 -9.74598) (xy 437.059832 -9.93648)
				(arc
					(start 437.10479 -9.981438)
					(mid 437.582425 -10.205217)
					(end 437.059832 -10.134092)
				)
				(xy 436.920132 -9.994392) (xy 436.920132 -9.74598)
			)
		)
	)
	(zone
		(layer "In9.Cu")
		(hatch none 0.5)
		(connect_pads
			(clearance 0)
		)
		(min_thickness 0.25)
		(keepout
			(tracks not_allowed)
			(vias allowed)
			(pads allowed)
			(copperpour not_allowed)
			(footprints allowed)
		)
		(placement
			(enabled no)
			(sheetname "")
		)
		(fill
			(thermal_gap 0.5)
			(thermal_bridge_width 0.5)
			(island_removal_mode 0)
		)
		(polygon
			(pts
				(xy 398.591786 -103.562912) (xy 398.58696 -103.568754) (xy 398.534128 -103.635302) (xy 398.534128 -103.638858)
				(xy 398.519396 -103.653336) (xy 398.506696 -103.669592) (xy 398.50314 -103.669846) (xy 398.500346 -103.67264)
				(xy 398.480026 -103.67264) (xy 398.459452 -103.674926) (xy 398.456658 -103.67264)
				(arc
					(start 398.399 -103.67264)
					(mid 397.872047 -103.615236)
					(end 398.399 -103.557832)
				)
				(xy 398.449038 -103.557832)
				(arc
					(start 398.490186 -103.506524)
					(mid 398.526361 -103.376697)
					(end 398.588484 -103.257096)
				)
				(arc
					(start 398.138904 -103.257096)
					(mid 397.78051 -103.615109)
					(end 398.13865 -103.973376)
				)
				(arc
					(start 399.12925 -103.973376)
					(mid 399.484171 -103.663148)
					(end 399.224246 -103.269796)
				)
				(xy 399.136108 -103.269796)
				(arc
					(start 399.132298 -103.27005)
					(mid 398.916892 -103.345365)
					(end 398.795494 -103.538528)
				)
				(xy 398.814798 -103.557832)
				(arc
					(start 398.8689 -103.557832)
					(mid 399.395853 -103.615236)
					(end 398.8689 -103.67264)
				)
				(xy 398.767554 -103.67264) (xy 398.767554 -103.672386) (xy 398.695672 -103.600758) (xy 398.690338 -103.595424)
				(xy 398.676368 -103.5812) (xy 398.676368 -103.561388) (xy 398.676368 -103.553768) (xy 398.676368 -103.533956)
				(arc
					(start 398.679924 -103.530146)
					(mid 398.737393 -103.37906)
					(end 398.8435 -103.257096)
				)
				(arc
					(start 398.733264 -103.257096)
					(mid 398.647971 -103.384912)
					(end 398.602454 -103.53167)
				)
				(xy 398.604232 -103.547418)
			)
		)
	)
	(zone
		(layer "In9.Cu")
		(hatch none 0.5)
		(connect_pads
			(clearance 0)
		)
		(min_thickness 0.25)
		(keepout
			(tracks allowed)
			(vias allowed)
			(pads allowed)
			(copperpour allowed)
			(footprints allowed)
		)
		(placement
			(enabled no)
			(sheetname "")
		)
		(fill
			(thermal_gap 0.5)
			(thermal_bridge_width 0.5)
			(island_removal_mode 0)
		)
		(polygon
			(pts
				(xy 278.003 -158.5976) (xy 278.003 -158.2166) (xy 279.6286 -158.2166) (xy 279.6286 -158.5976)
			)
		)
	)
	(zone
		(layer "In9.Cu")
		(hatch none 0.5)
		(connect_pads
			(clearance 0)
		)
		(min_thickness 0.25)
		(keepout
			(tracks allowed)
			(vias allowed)
			(pads allowed)
			(copperpour allowed)
			(footprints allowed)
		)
		(placement
			(enabled no)
			(sheetname "")
		)
		(fill
			(thermal_gap 0.5)
			(thermal_bridge_width 0.5)
			(island_removal_mode 0)
		)
		(polygon
			(pts
				(xy 368.173 -117.094) (xy 368.173 -114.554) (xy 370.6368 -114.554) (xy 370.6368 -117.094)
			)
		)
	)
	(zone
		(net "PVTT_KLM")
		(layer "In9.Cu")
		(hatch none 0.5)
		(connect_pads
			(clearance 0.5)
		)
		(min_thickness 0.25)
		(fill yes
			(thermal_gap 0.5)
			(thermal_bridge_width 0.5)
			(island_removal_mode 0)
		)
		(polygon
			(pts
				(xy 95.14332 -138.54176) (xy 96.35236 -138.54176) (xy 96.93656 -137.95756) (xy 96.93656 -130.66268)
				(xy 96.5073 -130.23342) (xy 95.01632 -130.23342) (xy 94.40418 -130.84556) (xy 94.40418 -137.80262)
			)
		)
	)
	(zone
		(layer "In9.Cu")
		(hatch none 0.5)
		(connect_pads
			(clearance 0)
		)
		(min_thickness 0.25)
		(keepout
			(tracks not_allowed)
			(vias allowed)
			(pads allowed)
			(copperpour not_allowed)
			(footprints allowed)
		)
		(placement
			(enabled no)
			(sheetname "")
		)
		(fill
			(thermal_gap 0.5)
			(thermal_bridge_width 0.5)
			(island_removal_mode 0)
		)
		(polygon
			(pts
				(xy 432.03495 -9.694926) (xy 432.03495 -9.896856)
				(arc
					(start 431.880518 -10.051034)
					(mid 431.368248 -10.179512)
					(end 431.823114 -9.91108)
				)
				(xy 431.89525 -9.838944) (xy 431.89525 -9.694926)
				(arc
					(start 431.615342 -9.694926)
					(mid 431.231802 -10.078466)
					(end 431.615342 -10.462006)
				)
				(arc
					(start 432.580288 -10.462006)
					(mid 432.964082 -10.078593)
					(end 432.580542 -9.694926)
				)
				(xy 432.32705 -9.694926) (xy 432.32705 -9.902444)
				(arc
					(start 432.357276 -9.93267)
					(mid 432.837283 -10.150496)
					(end 432.314096 -10.086848)
				)
				(xy 432.18735 -9.960356) (xy 432.18735 -9.694926)
			)
		)
	)
	(zone
		(layer "In9.Cu")
		(hatch none 0.5)
		(connect_pads
			(clearance 0)
		)
		(min_thickness 0.25)
		(keepout
			(tracks not_allowed)
			(vias allowed)
			(pads allowed)
			(copperpour not_allowed)
			(footprints allowed)
		)
		(placement
			(enabled no)
			(sheetname "")
		)
		(fill
			(thermal_gap 0.5)
			(thermal_bridge_width 0.5)
			(island_removal_mode 0)
		)
		(polygon
			(pts
				(xy 420.94658 -153.609548) (xy 420.946834 -153.609802)
				(arc
					(start 421.093138 -153.756106)
					(mid 421.414303 -154.176077)
					(end 420.994332 -153.854912)
				)
				(xy 420.847774 -153.708354) (xy 420.842186 -153.703528)
				(arc
					(start 420.842186 -153.987246)
					(mid 421.225599 -154.37104)
					(end 421.609266 -153.9875)
				)
				(arc
					(start 421.609266 -152.9715)
					(mid 421.225726 -152.58796)
					(end 420.842186 -152.9715)
				)
				(xy 420.842186 -153.255472) (xy 420.847774 -153.250646)
				(arc
					(start 420.994332 -153.104088)
					(mid 421.414303 -152.782923)
					(end 421.093138 -153.202894)
				)
				(xy 420.946834 -153.349198) (xy 420.94658 -153.349452) (xy 420.92626 -153.369772)
				(arc
					(start 420.92245 -153.369772)
					(mid 420.887064 -153.389241)
					(end 420.848282 -153.400506)
				)
				(xy 420.845488 -153.4033) (xy 420.842186 -153.4033) (xy 420.842186 -153.5557) (xy 420.845488 -153.5557)
				(arc
					(start 420.848282 -153.558494)
					(mid 420.887057 -153.569778)
					(end 420.92245 -153.589228)
				)
				(xy 420.92626 -153.589228)
			)
		)
	)
	(zone
		(layer "In9.Cu")
		(hatch none 0.5)
		(connect_pads
			(clearance 0)
		)
		(min_thickness 0.25)
		(keepout
			(tracks not_allowed)
			(vias allowed)
			(pads allowed)
			(copperpour not_allowed)
			(footprints allowed)
		)
		(placement
			(enabled no)
			(sheetname "")
		)
		(fill
			(thermal_gap 0.5)
			(thermal_bridge_width 0.5)
			(island_removal_mode 0)
		)
		(polygon
			(pts
				(xy 395.612874 -107.022392) (xy 395.60754 -107.027726) (xy 395.528546 -107.106466) (xy 395.528546 -107.10672)
				(arc
					(start 395.4272 -107.10672)
					(mid 394.900247 -107.049316)
					(end 395.4272 -106.991912)
				)
				(xy 395.481302 -106.991912)
				(arc
					(start 395.515084 -106.95813)
					(mid 395.550981 -106.818978)
					(end 395.616684 -106.691176)
				)
				(arc
					(start 395.16685 -106.691176)
					(mid 394.80871 -107.049316)
					(end 395.16685 -107.407456)
				)
				(arc
					(start 396.157196 -107.407456)
					(mid 396.378166 -107.33136)
					(end 396.505176 -107.135168)
				)
				(xy 396.501112 -107.094782) (xy 396.500096 -107.093512) (xy 396.500096 -107.074462) (xy 396.499842 -107.071922)
				(xy 396.500096 -107.06608) (xy 396.500096 -107.040934)
				(arc
					(start 396.499842 -107.038902)
					(mid 396.45145 -106.873518)
					(end 396.328646 -106.752644)
				)
				(arc
					(start 396.328646 -106.752644)
					(mid 396.15745 -106.706793)
					(end 395.986254 -106.752644)
				)
				(arc
					(start 395.986254 -106.752644)
					(mid 395.882033 -106.84568)
					(end 395.823694 -106.972608)
				)
				(xy 395.842998 -106.991912)
				(arc
					(start 395.8971 -106.991912)
					(mid 396.424053 -107.049316)
					(end 395.8971 -107.10672)
				)
				(xy 395.795754 -107.10672) (xy 395.795754 -107.106466) (xy 395.723872 -107.034838) (xy 395.718538 -107.029504)
				(xy 395.704568 -107.01528) (xy 395.704568 -106.995468) (xy 395.704568 -106.987848) (xy 395.704568 -106.968036)
				(arc
					(start 395.708124 -106.964226)
					(mid 395.765997 -106.812887)
					(end 395.87297 -106.691176)
				)
				(arc
					(start 395.761718 -106.691176)
					(mid 395.670922 -106.82944)
					(end 395.626844 -106.988864)
				)
				(xy 395.626844 -107.008168)
			)
		)
	)
	(zone
		(layer "In9.Cu")
		(hatch none 0.5)
		(connect_pads
			(clearance 0)
		)
		(min_thickness 0.25)
		(keepout
			(tracks not_allowed)
			(vias allowed)
			(pads allowed)
			(copperpour not_allowed)
			(footprints allowed)
		)
		(placement
			(enabled no)
			(sheetname "")
		)
		(fill
			(thermal_gap 0.5)
			(thermal_bridge_width 0.5)
			(island_removal_mode 0)
		)
		(polygon
			(pts
				(arc
					(start 421.945308 -149.265894)
					(mid 421.624143 -148.845923)
					(end 422.044114 -149.167088)
				)
				(arc
					(start 422.167304 -149.290278)
					(mid 422.180587 -149.29943)
					(end 422.19626 -149.303232)
				)
				(arc
					(start 422.19626 -149.0345)
					(mid 421.844833 -148.652307)
					(end 421.434514 -148.970492)
				)
				(xy 421.4368 -148.972778)
				(arc
					(start 421.4368 -150.1267)
					(mid 421.851011 -150.432149)
					(end 422.19626 -150.0505)
				)
				(xy 422.19626 -149.765766)
				(arc
					(start 422.044114 -149.917912)
					(mid 421.624143 -150.239077)
					(end 421.945308 -149.819106)
				)
				(xy 422.11498 -149.649434) (xy 422.115234 -149.64918) (xy 422.135554 -149.62886)
				(arc
					(start 422.139364 -149.62886)
					(mid 422.16665 -149.612939)
					(end 422.19626 -149.601936)
				)
				(xy 422.19626 -149.442932) (xy 422.16959 -149.442932)
				(arc
					(start 422.166796 -149.440138)
					(mid 422.128021 -149.428854)
					(end 422.092628 -149.409404)
				)
				(xy 422.088818 -149.409404) (xy 422.068498 -149.389084) (xy 422.068244 -149.38883)
			)
		)
	)
	(zone
		(net "GND")
		(layer "In9.Cu")
		(hatch none 0.5)
		(connect_pads
			(clearance 0.5)
		)
		(min_thickness 0.25)
		(fill yes
			(thermal_gap 0.5)
			(thermal_bridge_width 0.5)
			(island_removal_mode 0)
		)
		(polygon
			(pts
				(arc
					(start -5.184648 -161.9504)
					(mid -5.224047 -162.020639)
					(end -5.237734 -162.100006)
				)
				(arc
					(start -5.237734 -168.099994)
					(mid -5.1681 -168.268104)
					(end -4.99999 -168.337738)
				)
				(xy 501.0404 -168.337738) (xy 501.0404 -161.9504)
			)
		)
		(polygon
			(pts
				(xy 388.5946 -162.5346) (xy 382.778 -162.5346) (xy 316.23 -162.5346) (xy 316.23 -167.5384) (xy 382.778 -167.5384)
				(xy 388.5946 -167.5384)
			)
		)
		(polygon
			(pts
				(xy 114.935 -162.5346) (xy 108.6104 -162.5346) (xy 108.6104 -167.5384) (xy 114.935 -167.5384) (xy 149.1996 -167.5384)
				(xy 149.1996 -162.5346)
			)
		)
	)
	(zone
		(layer "In9.Cu")
		(hatch none 0.5)
		(connect_pads
			(clearance 0)
		)
		(min_thickness 0.25)
		(keepout
			(tracks not_allowed)
			(vias allowed)
			(pads allowed)
			(copperpour not_allowed)
			(footprints allowed)
		)
		(placement
			(enabled no)
			(sheetname "")
		)
		(fill
			(thermal_gap 0.5)
			(thermal_bridge_width 0.5)
			(island_removal_mode 0)
		)
		(polygon
			(pts
				(xy 17.068038 -34.5694) (xy 16.827754 -34.5694) (xy 16.754348 -34.642806)
				(arc
					(start 16.754348 -34.731198)
					(mid 16.684498 -35.255115)
					(end 16.614648 -34.731198)
				)
				(xy 16.614648 -34.584894) (xy 16.769842 -34.4297) (xy 17.068038 -34.4297) (xy 17.068038 -34.2773)
				(xy 16.769842 -34.2773) (xy 16.614648 -34.122106)
				(arc
					(start 16.614648 -33.975802)
					(mid 16.684498 -33.451885)
					(end 16.754348 -33.975802)
				)
				(xy 16.754348 -34.064194) (xy 16.827754 -34.1376) (xy 17.068038 -34.1376)
				(arc
					(start 17.068038 -33.718754)
					(mid 16.684625 -33.33496)
					(end 16.300958 -33.7185)
				)
				(arc
					(start 16.300958 -34.9885)
					(mid 16.684498 -35.37204)
					(end 17.068038 -34.9885)
				)
			)
		)
	)
	(zone
		(layer "In9.Cu")
		(hatch none 0.5)
		(connect_pads
			(clearance 0)
		)
		(min_thickness 0.25)
		(keepout
			(tracks allowed)
			(vias allowed)
			(pads allowed)
			(copperpour allowed)
			(footprints allowed)
		)
		(placement
			(enabled no)
			(sheetname "")
		)
		(fill
			(thermal_gap 0.5)
			(thermal_bridge_width 0.5)
			(island_removal_mode 0)
		)
		(polygon
			(pts
				(xy 366.903 -113.792) (xy 366.903 -112.522) (xy 368.6048 -112.522) (xy 368.6048 -113.792)
			)
		)
	)
	(zone
		(layer "In9.Cu")
		(hatch none 0.5)
		(connect_pads
			(clearance 0)
		)
		(min_thickness 0.25)
		(keepout
			(tracks not_allowed)
			(vias allowed)
			(pads allowed)
			(copperpour not_allowed)
			(footprints allowed)
		)
		(placement
			(enabled no)
			(sheetname "")
		)
		(fill
			(thermal_gap 0.5)
			(thermal_bridge_width 0.5)
			(island_removal_mode 0)
		)
		(polygon
			(pts
				(arc
					(start 397.8783 -105.274872)
					(mid 398.405253 -105.332276)
					(end 397.8783 -105.38968)
				)
				(xy 397.824198 -105.38968)
				(arc
					(start 397.80464 -105.409238)
					(mid 398.001814 -105.64654)
					(end 398.309846 -105.629202)
				)
				(arc
					(start 398.309846 -105.629202)
					(mid 398.346839 -105.609445)
					(end 398.38503 -105.592118)
				)
				(arc
					(start 398.38503 -105.592118)
					(mid 398.471265 -105.199655)
					(end 398.13865 -104.974136)
				)
				(arc
					(start 397.148304 -104.974136)
					(mid 396.78991 -105.332149)
					(end 397.14805 -105.690416)
				)
				(arc
					(start 397.597884 -105.690416)
					(mid 397.532741 -105.563791)
					(end 397.496792 -105.426002)
				)
				(xy 397.496792 -105.425748) (xy 397.496538 -105.423716) (xy 397.462502 -105.38968)
				(arc
					(start 397.4084 -105.38968)
					(mid 396.881447 -105.332276)
					(end 397.4084 -105.274872)
				)
				(xy 397.509746 -105.274872) (xy 397.509746 -105.275126) (xy 397.588994 -105.35412) (xy 397.594328 -105.359454)
				(xy 397.608298 -105.373678) (xy 397.608298 -105.392982)
				(arc
					(start 397.610584 -105.409492)
					(mid 397.655888 -105.559778)
					(end 397.742918 -105.690416)
				)
				(arc
					(start 397.853662 -105.690416)
					(mid 397.746821 -105.568819)
					(end 397.68907 -105.41762)
				)
				(xy 397.685514 -105.41381) (xy 397.685514 -105.393998) (xy 397.685514 -105.386378) (xy 397.685514 -105.366566)
				(xy 397.699484 -105.352342) (xy 397.704818 -105.347008) (xy 397.776954 -105.275126) (xy 397.776954 -105.274872)
			)
		)
	)
	(zone
		(layer "In9.Cu")
		(hatch none 0.5)
		(connect_pads
			(clearance 0)
		)
		(min_thickness 0.25)
		(keepout
			(tracks not_allowed)
			(vias allowed)
			(pads allowed)
			(copperpour not_allowed)
			(footprints allowed)
		)
		(placement
			(enabled no)
			(sheetname "")
		)
		(fill
			(thermal_gap 0.5)
			(thermal_bridge_width 0.5)
			(island_removal_mode 0)
		)
		(polygon
			(pts
				(arc
					(start 446.921636 -60.315348)
					(mid 447.447464 -60.378848)
					(end 446.921636 -60.442348)
				)
				(xy 446.883028 -60.442348) (xy 446.81902 -60.506356) (xy 446.81902 -60.787788)
				(arc
					(start 447.180462 -60.787788)
					(mid 447.589656 -60.378975)
					(end 447.180716 -59.969908)
				)
				(arc
					(start 445.910716 -59.969908)
					(mid 445.501776 -60.378848)
					(end 445.910716 -60.787788)
				)
				(xy 446.27292 -60.787788) (xy 446.27292 -60.506356) (xy 446.208658 -60.442348)
				(arc
					(start 446.169796 -60.442348)
					(mid 445.643968 -60.378848)
					(end 446.169796 -60.315348)
				)
				(xy 446.208658 -60.315348) (xy 446.260982 -60.315348) (xy 446.29832 -60.352686) (xy 446.362328 -60.416948)
				(xy 446.399412 -60.454032) (xy 446.399666 -60.454032) (xy 446.399666 -60.506356) (xy 446.399412 -60.506356)
				(xy 446.399412 -60.787788) (xy 446.69202 -60.787788) (xy 446.69202 -60.506356) (xy 446.69202 -60.454032)
				(xy 446.729358 -60.416948) (xy 446.79362 -60.352686) (xy 446.830704 -60.315348) (xy 446.883028 -60.315348)
			)
		)
	)
	(zone
		(layer "In9.Cu")
		(hatch none 0.5)
		(connect_pads
			(clearance 0)
		)
		(min_thickness 0.25)
		(keepout
			(tracks not_allowed)
			(vias allowed)
			(pads allowed)
			(copperpour not_allowed)
			(footprints allowed)
		)
		(placement
			(enabled no)
			(sheetname "")
		)
		(fill
			(thermal_gap 0.5)
			(thermal_bridge_width 0.5)
			(island_removal_mode 0)
		)
		(polygon
			(pts
				(xy 408.66822 -95.836232)
				(arc
					(start 408.607514 -95.775526)
					(mid 408.280419 -95.358769)
					(end 408.697176 -95.685864)
				)
				(xy 408.738578 -95.727266) (xy 408.878024 -95.727266)
				(arc
					(start 408.878024 -95.547688)
					(mid 408.469211 -95.138494)
					(end 408.060144 -95.547434)
				)
				(arc
					(start 408.060144 -96.601788)
					(mid 408.469084 -97.010728)
					(end 408.878024 -96.601788)
				)
				(xy 408.878024 -96.30918) (xy 408.851354 -96.30918)
				(arc
					(start 408.697176 -96.463358)
					(mid 408.280419 -96.790453)
					(end 408.607514 -96.373696)
				)
				(xy 408.761692 -96.219518) (xy 408.79903 -96.18218) (xy 408.799792 -96.18218) (xy 408.854402 -96.12757)
				(xy 408.878024 -96.103948) (xy 408.878024 -95.889572) (xy 408.878024 -95.841312) (xy 408.6733 -95.841312)
			)
		)
	)
	(zone
		(layer "In9.Cu")
		(hatch none 0.5)
		(connect_pads
			(clearance 0)
		)
		(min_thickness 0.25)
		(keepout
			(tracks not_allowed)
			(vias allowed)
			(pads allowed)
			(copperpour not_allowed)
			(footprints allowed)
		)
		(placement
			(enabled no)
			(sheetname "")
		)
		(fill
			(thermal_gap 0.5)
			(thermal_bridge_width 0.5)
			(island_removal_mode 0)
		)
		(polygon
			(pts
				(xy 16.455898 -38.404292) (xy 16.585692 -38.534086) (xy 16.585692 -38.832028) (xy 16.611346 -38.857682)
				(xy 16.826992 -38.857682) (xy 16.738092 -38.768782) (xy 16.738092 -38.534086) (xy 16.867886 -38.404292)
				(arc
					(start 17.03959 -38.404292)
					(mid 17.563507 -38.474142)
					(end 17.03959 -38.543992)
				)
				(xy 16.925798 -38.543992) (xy 16.877792 -38.591998) (xy 16.877792 -38.71087) (xy 17.024604 -38.857682)
				(arc
					(start 17.296638 -38.857682)
					(mid 17.680432 -38.474269)
					(end 17.296892 -38.090602)
				)
				(arc
					(start 16.026892 -38.090602)
					(mid 15.643352 -38.474142)
					(end 16.026892 -38.857682)
				)
				(xy 16.445992 -38.857682) (xy 16.445992 -38.591998) (xy 16.397986 -38.543992)
				(arc
					(start 16.284194 -38.543992)
					(mid 15.760277 -38.474142)
					(end 16.284194 -38.404292)
				)
			)
		)
	)
	(zone
		(net "PVSA_CPU1")
		(layer "In9.Cu")
		(hatch none 0.5)
		(connect_pads
			(clearance 0.5)
		)
		(min_thickness 0.25)
		(fill yes
			(thermal_gap 0.5)
			(thermal_bridge_width 0.5)
			(island_removal_mode 0)
		)
		(polygon
			(pts
				(xy 76.39812 -84.036662) (xy 82.69224 -84.040472) (xy 82.694272 -84.042504) (xy 85.972904 -84.042504)
				(xy 89.170256 -84.044536) (xy 89.600786 -84.475066) (xy 93.001592 -84.475066) (xy 93.163644 -84.313014)
				(xy 93.788992 -84.313014) (xy 93.865192 -84.389214) (xy 93.865192 -84.398866) (xy 93.941392 -84.475066)
				(xy 96.505014 -84.475066) (xy 97.0407 -83.93938) (xy 97.0407 -82.15376) (xy 96.379792 -81.493614)
				(xy 92.874592 -81.493614) (xy 91.737688 -80.35671) (xy 91.223592 -80.35671) (xy 91.090496 -80.223614)
				(xy 90.213688 -80.223614) (xy 90.080592 -80.35671) (xy 88.156288 -80.35671) (xy 87.896192 -80.096614)
				(xy 86.651592 -80.096614) (xy 86.270592 -79.715614) (xy 86.016592 -79.715614) (xy 85.508592 -79.207614)
				(xy 81.190592 -79.207614) (xy 80.047592 -80.350614) (xy 76.250546 -80.350614) (xy 76.11618 -80.48498)
				(xy 76.11618 -83.754722)
			)
		)
	)
	(zone
		(layer "In9.Cu")
		(hatch none 0.5)
		(connect_pads
			(clearance 0)
		)
		(min_thickness 0.25)
		(keepout
			(tracks allowed)
			(vias allowed)
			(pads allowed)
			(copperpour allowed)
			(footprints allowed)
		)
		(placement
			(enabled no)
			(sheetname "")
		)
		(fill
			(thermal_gap 0.5)
			(thermal_bridge_width 0.5)
			(island_removal_mode 0)
		)
		(polygon
			(pts
				(xy 65.599564 -53.610002) (xy 65.599564 -98.171) (xy 66.723768 -99.295204) (xy 66.723768 -100.1268)
				(xy 68.069968 -101.473) (xy 69.593968 -101.9302) (xy 77.036168 -102.6414) (xy 83.767168 -101.7524)
				(xy 89.355168 -102.7176) (xy 101.851968 -102.7938) (xy 104.671368 -103.0732) (xy 112.596168 -104.7496)
				(xy 118.361968 -104.0384) (xy 119.327168 -104.0384) (xy 127.251968 -102.3874) (xy 133.855968 -103.7844)
				(xy 140.97 -102.743) (xy 141.097 -102.616) (xy 144.018 -97.536) (xy 144.026382 -97.527618) (xy 144.026382 -85.606382)
				(xy 144.974564 -84.6582) (xy 144.974564 -52.975002) (xy 141.934692 -49.934876) (xy 141.831568 -50.038)
				(xy 124.051568 -50.038) (xy 120.622568 -53.467) (xy 103.096568 -53.467) (xy 99.921568 -50.292) (xy 99.210368 -50.292)
				(xy 99.057968 -50.1396) (xy 97.813368 -50.1396) (xy 97.546668 -50.4063) (xy 96.721168 -49.5808)
				(xy 86.713568 -49.5808) (xy 85.824568 -48.6918) (xy 71.533512 -48.6918) (xy 70.74154 -49.483772)
				(xy 69.72554 -49.483772)
			)
		)
	)
	(zone
		(layer "In9.Cu")
		(hatch none 0.5)
		(connect_pads
			(clearance 0)
		)
		(min_thickness 0.25)
		(keepout
			(tracks allowed)
			(vias allowed)
			(pads allowed)
			(copperpour allowed)
			(footprints allowed)
		)
		(placement
			(enabled no)
			(sheetname "")
		)
		(fill
			(thermal_gap 0.5)
			(thermal_bridge_width 0.5)
			(island_removal_mode 0)
		)
		(polygon
			(pts
				(xy 311.023 -66.802) (xy 311.023 -65.659) (xy 311.785 -65.659) (xy 311.785 -66.802)
			)
		)
	)
	(zone
		(net "GND")
		(layer "In9.Cu")
		(hatch none 0.5)
		(connect_pads
			(clearance 0.5)
		)
		(min_thickness 0.25)
		(fill yes
			(thermal_gap 0.5)
			(thermal_bridge_width 0.5)
			(island_removal_mode 0)
		)
		(polygon
			(pts
				(xy 35.455606 -51.9176) (xy 34.5948 -52.778406) (xy 34.5948 -92.785692) (xy 34.8234 -93.014292)
				(xy 42.987722 -93.014292) (xy 43.245786 -92.756228) (xy 43.245786 -54.030118) (xy 43.245786 -53.537612)
				(xy 42.159174 -52.451) (xy 41.234868 -52.451) (xy 41.031668 -52.2478) (xy 39.685468 -52.2478) (xy 39.355268 -51.9176)
			)
		)
	)
	(zone
		(layer "In9.Cu")
		(hatch none 0.5)
		(connect_pads
			(clearance 0)
		)
		(min_thickness 0.25)
		(keepout
			(tracks allowed)
			(vias allowed)
			(pads allowed)
			(copperpour allowed)
			(footprints allowed)
		)
		(placement
			(enabled no)
			(sheetname "")
		)
		(fill
			(thermal_gap 0.5)
			(thermal_bridge_width 0.5)
			(island_removal_mode 0)
		)
		(polygon
			(pts
				(xy 431.8 1.524) (xy 431.8 3.429) (xy 462.915 3.429) (xy 462.915 1.524)
			)
		)
	)
	(zone
		(layer "In9.Cu")
		(hatch none 0.5)
		(connect_pads
			(clearance 0)
		)
		(min_thickness 0.25)
		(keepout
			(tracks not_allowed)
			(vias allowed)
			(pads allowed)
			(copperpour not_allowed)
			(footprints allowed)
		)
		(placement
			(enabled no)
			(sheetname "")
		)
		(fill
			(thermal_gap 0.5)
			(thermal_bridge_width 0.5)
			(island_removal_mode 0)
		)
		(polygon
			(pts
				(xy 17.03705 -23.231856) (xy 17.03705 -23.335742) (xy 17.173448 -23.47214)
				(arc
					(start 17.45615 -23.47214)
					(mid 17.83969 -23.0886)
					(end 17.45615 -22.70506)
				)
				(arc
					(start 16.186404 -22.70506)
					(mid 15.80261 -23.088473)
					(end 16.18615 -23.47214)
				)
				(xy 16.60525 -23.47214) (xy 16.60525 -23.231856) (xy 16.531844 -23.15845)
				(arc
					(start 16.443452 -23.15845)
					(mid 15.919535 -23.0886)
					(end 16.443452 -23.01875)
				)
				(xy 16.589756 -23.01875) (xy 16.74495 -23.173944) (xy 16.74495 -23.4569) (xy 16.76019 -23.47214)
				(xy 16.975836 -23.47214) (xy 16.938244 -23.434548) (xy 16.917924 -23.414228) (xy 16.89735 -23.393654)
				(xy 16.89735 -23.364698) (xy 16.89735 -23.335742) (xy 16.89735 -23.173944) (xy 17.052544 -23.01875)
				(arc
					(start 17.198848 -23.01875)
					(mid 17.722765 -23.0886)
					(end 17.198848 -23.15845)
				)
				(xy 17.110456 -23.15845)
			)
		)
	)
	(zone
		(layer "In9.Cu")
		(hatch none 0.5)
		(connect_pads
			(clearance 0)
		)
		(min_thickness 0.25)
		(keepout
			(tracks not_allowed)
			(vias allowed)
			(pads allowed)
			(copperpour not_allowed)
			(footprints allowed)
		)
		(placement
			(enabled no)
			(sheetname "")
		)
		(fill
			(thermal_gap 0.5)
			(thermal_bridge_width 0.5)
			(island_removal_mode 0)
		)
		(polygon
			(pts
				(xy 444.0174 -8.74141) (xy 444.0174 -9.039352)
				(arc
					(start 443.88659 -9.170162)
					(mid 443.360387 -9.167617)
					(end 443.859158 -8.999982)
				)
				(xy 443.8777 -8.98144) (xy 443.8777 -8.74141)
				(arc
					(start 443.6237 -8.74141)
					(mid 443.24016 -9.12495)
					(end 443.6237 -9.50849)
				)
				(arc
					(start 444.563246 -9.50849)
					(mid 444.94704 -9.125077)
					(end 444.5635 -8.74141)
				)
				(xy 444.3095 -8.74141) (xy 444.3095 -8.98144)
				(arc
					(start 444.328042 -8.999982)
					(mid 444.826792 -9.167613)
					(end 444.30061 -9.170162)
				)
				(xy 444.1698 -9.039352) (xy 444.1698 -8.74141)
			)
		)
	)
	(zone
		(layer "In9.Cu")
		(hatch none 0.5)
		(connect_pads
			(clearance 0)
		)
		(min_thickness 0.25)
		(keepout
			(tracks allowed)
			(vias allowed)
			(pads allowed)
			(copperpour allowed)
			(footprints allowed)
		)
		(placement
			(enabled no)
			(sheetname "")
		)
		(fill
			(thermal_gap 0.5)
			(thermal_bridge_width 0.5)
			(island_removal_mode 0)
		)
		(polygon
			(pts
				(xy 124.6886 -48.3108) (xy 135.7122 -35.4838) (xy 173.33595 -28.096718) (xy 187.481718 -28.096718)
				(xy 189.484 -30.099) (xy 207.899 -30.099) (xy 232.918 -31.369) (xy 234.696 -30.988) (xy 253.159768 -30.988)
				(xy 256.286 -32.258) (xy 292.227 -33.782) (xy 302.900842 -39.970964) (xy 307.3908 -49.6316) (xy 307.133244 -50.748438)
				(xy 288.824162 -50.748438) (xy 284.836362 -50.748438) (xy 281.4828 -54.102) (xy 277.346664 -54.102)
				(xy 270.2052 -49.8856) (xy 262.89 -49.8856) (xy 261.112 -48.1076) (xy 242.2906 -48.1076) (xy 241.7572 -47.5742)
				(xy 233.7562 -47.5742) (xy 232.9688 -48.3616) (xy 208.6864 -48.3616) (xy 206.8576 -46.5328) (xy 201.5236 -46.5328)
				(xy 199.5932 -48.4632) (xy 192.786 -48.4632) (xy 191.389 -49.8602) (xy 191.1604 -49.8602) (xy 166.8272 -52.451)
				(xy 146.533616 -55.601616) (xy 139.954 -49.022) (xy 125.323854 -49.022) (xy 124.686314 -48.38446)
			)
		)
	)
	(zone
		(net "GND")
		(layer "In9.Cu")
		(hatch none 0.5)
		(connect_pads
			(clearance 0.5)
		)
		(min_thickness 0.25)
		(fill yes
			(thermal_gap 0.5)
			(thermal_bridge_width 0.5)
			(island_removal_mode 0)
		)
		(polygon
			(pts
				(xy 38.526212 -101.447092) (xy 41.218612 -101.447092) (xy 42.860468 -99.80549) (xy 42.860468 -93.7514)
				(xy 42.632376 -93.523308) (xy 34.797492 -93.523308) (xy 34.5948 -93.726) (xy 34.5948 -99.2886) (xy 34.298128 -99.585526)
				(xy 34.298128 -100.521008) (xy 33.401 -101.417882) (xy 33.401 -102.362) (xy 33.655 -102.616) (xy 37.357558 -102.616)
			)
		)
	)
	(zone
		(layer "In9.Cu")
		(hatch none 0.5)
		(connect_pads
			(clearance 0)
		)
		(min_thickness 0.25)
		(keepout
			(tracks not_allowed)
			(vias allowed)
			(pads allowed)
			(copperpour not_allowed)
			(footprints allowed)
		)
		(placement
			(enabled no)
			(sheetname "")
		)
		(fill
			(thermal_gap 0.5)
			(thermal_bridge_width 0.5)
			(island_removal_mode 0)
		)
		(polygon
			(pts
				(arc
					(start 446.974722 -5.204714)
					(mid 447.419628 -4.919139)
					(end 447.0654 -5.311648)
				)
				(xy 446.970658 -5.40639) (xy 446.970658 -5.47243)
				(arc
					(start 447.211958 -5.47497)
					(mid 447.599562 -5.095494)
					(end 447.220086 -4.70789)
				)
				(arc
					(start 446.280286 -4.698238)
					(mid 445.892683 -5.077587)
					(end 446.271904 -5.465318)
				)
				(xy 446.538858 -5.468112) (xy 446.538858 -5.433568)
				(arc
					(start 446.414906 -5.309616)
					(mid 446.081762 -4.898861)
					(end 446.510918 -5.208016)
				)
				(xy 446.678558 -5.375656) (xy 446.678558 -5.469382) (xy 446.830958 -5.47116) (xy 446.830958 -5.348478)
			)
		)
	)
	(zone
		(layer "In9.Cu")
		(hatch none 0.5)
		(connect_pads
			(clearance 0)
		)
		(min_thickness 0.25)
		(keepout
			(tracks allowed)
			(vias allowed)
			(pads allowed)
			(copperpour allowed)
			(footprints allowed)
		)
		(placement
			(enabled no)
			(sheetname "")
		)
		(fill
			(thermal_gap 0.5)
			(thermal_bridge_width 0.5)
			(island_removal_mode 0)
		)
		(polygon
			(pts
				(xy 206.121 -52.451) (xy 206.121 -51.689) (xy 207.518 -51.689) (xy 207.518 -52.451)
			)
		)
	)
	(zone
		(layer "In9.Cu")
		(hatch none 0.5)
		(connect_pads
			(clearance 0)
		)
		(min_thickness 0.25)
		(keepout
			(tracks not_allowed)
			(vias allowed)
			(pads allowed)
			(copperpour not_allowed)
			(footprints allowed)
		)
		(placement
			(enabled no)
			(sheetname "")
		)
		(fill
			(thermal_gap 0.5)
			(thermal_bridge_width 0.5)
			(island_removal_mode 0)
		)
		(polygon
			(pts
				(arc
					(start 446.63487 -7.735062)
					(mid 446.251457 -7.351268)
					(end 445.86779 -7.734808)
				)
				(xy 445.86779 -8.003032) (xy 446.085722 -8.003032)
				(arc
					(start 446.121282 -7.967472)
					(mid 446.301006 -7.472935)
					(end 446.287144 -7.998968)
				)
				(xy 446.143634 -8.142732) (xy 445.86779 -8.142732) (xy 445.86779 -8.295132) (xy 446.127124 -8.295132)
				(arc
					(start 446.265554 -8.433816)
					(mid 446.318102 -8.95803)
					(end 446.108836 -8.474456)
				)
				(xy 446.069212 -8.434832) (xy 445.86779 -8.434832)
				(arc
					(start 445.86779 -8.700008)
					(mid 446.25133 -9.083548)
					(end 446.63487 -8.700008)
				)
			)
		)
	)
	(zone
		(net "P3V3_STBY")
		(layer "In9.Cu")
		(hatch none 0.5)
		(connect_pads
			(clearance 0.5)
		)
		(min_thickness 0.25)
		(fill yes
			(thermal_gap 0.5)
			(thermal_bridge_width 0.5)
			(island_removal_mode 0)
		)
		(polygon
			(pts
				(xy 481.9904 -112.7506) (xy 489.07065 -112.7506) (xy 489.07065 -115.51285) (xy 492.7346 -119.1768)
				(xy 492.94796 -119.39016) (xy 492.94796 -129.2987) (xy 492.4933 -129.75336) (xy 491.69066 -129.75336)
				(xy 490.1438 -128.2065) (xy 482.9429 -128.2065) (xy 479.7298 -124.9934) (xy 479.7298 -115.0112)
			)
		)
	)
	(zone
		(layer "In9.Cu")
		(hatch none 0.5)
		(connect_pads
			(clearance 0)
		)
		(min_thickness 0.25)
		(keepout
			(tracks not_allowed)
			(vias allowed)
			(pads allowed)
			(copperpour not_allowed)
			(footprints allowed)
		)
		(placement
			(enabled no)
			(sheetname "")
		)
		(fill
			(thermal_gap 0.5)
			(thermal_bridge_width 0.5)
			(island_removal_mode 0)
		)
		(polygon
			(pts
				(xy 433.558442 -2.476754) (xy 433.558442 -2.769108) (xy 433.397406 -2.930144)
				(arc
					(start 433.269136 -2.930144)
					(mid 432.745219 -2.860294)
					(end 433.269136 -2.790444)
				)
				(xy 433.339494 -2.790444) (xy 433.418742 -2.711196) (xy 433.418742 -2.476754)
				(arc
					(start 433.011834 -2.476754)
					(mid 432.628294 -2.860294)
					(end 433.011834 -3.243834)
				)
				(arc
					(start 434.28158 -3.243834)
					(mid 434.665374 -2.860421)
					(end 434.281834 -2.476754)
				)
				(xy 433.850542 -2.476754) (xy 433.850542 -2.698496) (xy 433.94249 -2.790444)
				(arc
					(start 434.024532 -2.790444)
					(mid 434.548449 -2.860294)
					(end 434.024532 -2.930144)
				)
				(xy 433.884578 -2.930144) (xy 433.710842 -2.756408) (xy 433.710842 -2.476754)
			)
		)
	)
	(zone
		(layer "In9.Cu")
		(hatch none 0.5)
		(connect_pads
			(clearance 0)
		)
		(min_thickness 0.25)
		(keepout
			(tracks not_allowed)
			(vias allowed)
			(pads allowed)
			(copperpour not_allowed)
			(footprints allowed)
		)
		(placement
			(enabled no)
			(sheetname "")
		)
		(fill
			(thermal_gap 0.5)
			(thermal_bridge_width 0.5)
			(island_removal_mode 0)
		)
		(polygon
			(pts
				(arc
					(start 441.110624 -9.675114)
					(mid 440.738514 -10.069576)
					(end 441.132976 -10.441686)
				)
				(xy 441.132976 -10.444226) (xy 442.122814 -10.41527) (xy 442.123068 -10.415016)
				(arc
					(start 442.123068 -10.41273)
					(mid 442.495178 -10.018268)
					(end 442.100716 -9.646158)
				)
				(xy 442.100716 -9.643618) (xy 441.85205 -9.650984) (xy 441.85205 -9.775444)
				(arc
					(start 441.920376 -9.84377)
					(mid 442.346886 -10.155662)
					(end 441.851288 -9.972294)
				)
				(xy 441.71235 -9.833356) (xy 441.71235 -9.655048) (xy 441.55995 -9.659366) (xy 441.55995 -9.871456)
				(arc
					(start 441.387992 -10.043414)
					(mid 440.871304 -10.149693)
					(end 441.33516 -9.898634)
				)
				(xy 441.42025 -9.813544) (xy 441.42025 -9.66343) (xy 441.110624 -9.672574)
			)
		)
	)
	(zone
		(layer "In9.Cu")
		(hatch none 0.5)
		(connect_pads
			(clearance 0)
		)
		(min_thickness 0.25)
		(keepout
			(tracks not_allowed)
			(vias allowed)
			(pads allowed)
			(copperpour not_allowed)
			(footprints allowed)
		)
		(placement
			(enabled no)
			(sheetname "")
		)
		(fill
			(thermal_gap 0.5)
			(thermal_bridge_width 0.5)
			(island_removal_mode 0)
		)
		(polygon
			(pts
				(arc
					(start 460.54772 -63.488062)
					(mid 460.130963 -63.815157)
					(end 460.458058 -63.3984)
				)
				(xy 460.638906 -63.217552)
				(arc
					(start 460.319882 -63.217552)
					(mid 459.910688 -63.626365)
					(end 460.319628 -64.035432)
				)
				(arc
					(start 461.589628 -64.035432)
					(mid 461.998568 -63.626492)
					(end 461.589628 -63.217552)
				)
				(xy 461.27035 -63.217552)
				(arc
					(start 461.451198 -63.3984)
					(mid 461.778293 -63.815157)
					(end 461.361536 -63.488062)
				)
				(xy 461.138016 -63.264288) (xy 461.100932 -63.227204) (xy 461.100678 -63.227204) (xy 461.100678 -63.217552)
				(xy 460.808324 -63.217552) (xy 460.808324 -63.227458) (xy 460.770986 -63.264796)
			)
		)
	)
	(zone
		(layer "In9.Cu")
		(hatch none 0.5)
		(connect_pads
			(clearance 0)
		)
		(min_thickness 0.25)
		(keepout
			(tracks allowed)
			(vias allowed)
			(pads allowed)
			(copperpour allowed)
			(footprints allowed)
		)
		(placement
			(enabled no)
			(sheetname "")
		)
		(fill
			(thermal_gap 0.5)
			(thermal_bridge_width 0.5)
			(island_removal_mode 0)
		)
		(polygon
			(pts
				(xy 451.1675 0.0254) (xy 451.1675 0.8636) (xy 452.9074 0.8636) (xy 452.9074 0.0254)
			)
		)
	)
	(zone
		(layer "In9.Cu")
		(hatch none 0.5)
		(connect_pads
			(clearance 0)
		)
		(min_thickness 0.25)
		(keepout
			(tracks not_allowed)
			(vias allowed)
			(pads allowed)
			(copperpour not_allowed)
			(footprints allowed)
		)
		(placement
			(enabled no)
			(sheetname "")
		)
		(fill
			(thermal_gap 0.5)
			(thermal_bridge_width 0.5)
			(island_removal_mode 0)
		)
		(polygon
			(pts
				(xy 419.68166 -92.468954) (xy 419.718998 -92.506292) (xy 419.718998 -92.559124)
				(arc
					(start 419.718998 -92.60332)
					(mid 419.655244 -93.129209)
					(end 419.59149 -92.60332)
				)
				(xy 419.59149 -92.559124) (xy 419.52672 -92.494354) (xy 419.246304 -92.494354)
				(arc
					(start 419.246304 -92.862146)
					(mid 419.655117 -93.27134)
					(end 420.064184 -92.8624)
				)
				(arc
					(start 420.064184 -91.5924)
					(mid 419.655244 -91.18346)
					(end 419.246304 -91.5924)
				)
				(xy 419.246304 -91.960446) (xy 419.52672 -91.960446) (xy 419.59149 -91.895676)
				(arc
					(start 419.59149 -91.85148)
					(mid 419.655244 -91.325591)
					(end 419.718998 -91.85148)
				)
				(xy 419.718998 -91.895676) (xy 419.718998 -91.948508) (xy 419.68166 -91.985846) (xy 419.61689 -92.050616)
				(xy 419.579552 -92.087954) (xy 419.52672 -92.087954) (xy 419.246304 -92.087954) (xy 419.246304 -92.366846)
				(xy 419.52672 -92.366846) (xy 419.579552 -92.366846) (xy 419.61689 -92.404184)
			)
		)
	)
	(zone
		(layer "In9.Cu")
		(hatch none 0.5)
		(connect_pads
			(clearance 0)
		)
		(min_thickness 0.25)
		(keepout
			(tracks not_allowed)
			(vias allowed)
			(pads allowed)
			(copperpour not_allowed)
			(footprints allowed)
		)
		(placement
			(enabled no)
			(sheetname "")
		)
		(fill
			(thermal_gap 0.5)
			(thermal_bridge_width 0.5)
			(island_removal_mode 0)
		)
		(polygon
			(pts
				(arc
					(start 406.523952 -95.592138)
					(mid 406.115139 -95.182944)
					(end 405.706072 -95.591884)
				)
				(xy 405.706072 -95.842328) (xy 405.774906 -95.842328)
				(arc
					(start 405.88692 -95.730314)
					(mid 406.303677 -95.403219)
					(end 405.976582 -95.819976)
				)
				(xy 405.864568 -95.93199) (xy 405.82723 -95.969328) (xy 405.774906 -95.969328) (xy 405.706072 -95.969328)
				(xy 405.706072 -96.261936) (xy 405.806656 -96.261936) (xy 405.806656 -96.261682) (xy 405.85898 -96.261682)
				(xy 405.85898 -96.261936) (xy 405.896064 -96.29902)
				(arc
					(start 405.976582 -96.379284)
					(mid 406.303677 -96.796041)
					(end 405.88692 -96.468946)
				)
				(xy 405.806656 -96.388428) (xy 405.706072 -96.388428)
				(arc
					(start 405.706072 -96.607376)
					(mid 406.115012 -97.016316)
					(end 406.523952 -96.607376)
				)
			)
		)
	)
	(zone
		(layer "In9.Cu")
		(hatch none 0.5)
		(connect_pads
			(clearance 0)
		)
		(min_thickness 0.25)
		(keepout
			(tracks not_allowed)
			(vias allowed)
			(pads allowed)
			(copperpour not_allowed)
			(footprints allowed)
		)
		(placement
			(enabled no)
			(sheetname "")
		)
		(fill
			(thermal_gap 0.5)
			(thermal_bridge_width 0.5)
			(island_removal_mode 0)
		)
		(polygon
			(pts
				(xy 439.1533 -9.64057) (xy 439.1533 -9.938766)
				(arc
					(start 439.017156 -10.07491)
					(mid 438.491129 -10.061375)
					(end 438.992518 -9.901936)
				)
				(xy 439.0136 -9.880854) (xy 439.0136 -9.64057)
				(arc
					(start 438.755536 -9.64057)
					(mid 438.371996 -10.023983)
					(end 438.755282 -10.40765)
				)
				(arc
					(start 439.720482 -10.40765)
					(mid 440.104022 -10.02411)
					(end 439.720482 -9.64057)
				)
				(xy 439.4454 -9.64057) (xy 439.4454 -9.786874)
				(arc
					(start 439.51398 -9.855454)
					(mid 439.965831 -10.128037)
					(end 439.455306 -9.994392)
				)
				(xy 439.3057 -9.844786) (xy 439.3057 -9.64057)
			)
		)
	)
	(zone
		(layer "In9.Cu")
		(hatch none 0.5)
		(connect_pads
			(clearance 0)
		)
		(min_thickness 0.25)
		(keepout
			(tracks not_allowed)
			(vias allowed)
			(pads allowed)
			(copperpour not_allowed)
			(footprints allowed)
		)
		(placement
			(enabled no)
			(sheetname "")
		)
		(fill
			(thermal_gap 0.5)
			(thermal_bridge_width 0.5)
			(island_removal_mode 0)
		)
		(polygon
			(pts
				(xy 431.088038 -2.490978) (xy 431.088038 -2.725928) (xy 430.869598 -2.944368)
				(arc
					(start 430.838102 -2.944368)
					(mid 430.314393 -2.885042)
					(end 430.831752 -2.784602)
				)
				(xy 430.948338 -2.668016) (xy 430.948338 -2.490978)
				(arc
					(start 430.5808 -2.490978)
					(mid 430.19726 -2.874518)
					(end 430.5808 -3.258058)
				)
				(arc
					(start 431.850546 -3.258058)
					(mid 432.23434 -2.874645)
					(end 431.8508 -2.490978)
				)
				(xy 431.380138 -2.490978) (xy 431.380138 -2.668016) (xy 431.51679 -2.804668)
				(arc
					(start 431.593498 -2.804668)
					(mid 432.117415 -2.874518)
					(end 431.593498 -2.944368)
				)
				(xy 431.458878 -2.944368) (xy 431.240438 -2.725928) (xy 431.240438 -2.490978)
			)
		)
	)
	(zone
		(layer "In9.Cu")
		(hatch none 0.5)
		(connect_pads
			(clearance 0)
		)
		(min_thickness 0.25)
		(keepout
			(tracks allowed)
			(vias allowed)
			(pads allowed)
			(copperpour allowed)
			(footprints allowed)
		)
		(placement
			(enabled no)
			(sheetname "")
		)
		(fill
			(thermal_gap 0.5)
			(thermal_bridge_width 0.5)
			(island_removal_mode 0)
		)
		(polygon
			(pts
				(xy 278.6888 4.7244) (xy 278.6888 5.1816) (xy 280.6954 5.1816) (xy 280.6954 4.7244)
			)
		)
	)
	(zone
		(net "P1V05_PCH_STBY_WM26_PLL")
		(layer "In9.Cu")
		(hatch none 0.5)
		(connect_pads
			(clearance 0.5)
		)
		(min_thickness 0.25)
		(fill yes
			(thermal_gap 0.5)
			(thermal_bridge_width 0.5)
			(island_removal_mode 0)
		)
		(polygon
			(pts
				(xy 388.874 -117.4242) (xy 388.874 -115.062) (xy 389.382 -114.554) (xy 393.40536 -114.554) (xy 394.61567 -115.76431)
				(xy 394.843 -115.99164) (xy 394.843 -116.459) (xy 394.6398 -116.6622) (xy 394.6398 -117.1956) (xy 395.224 -117.7798)
				(xy 396.0368 -118.5926) (xy 396.0368 -118.9736) (xy 396.7734 -119.7102) (xy 396.9766 -119.9134)
				(xy 400.3548 -119.9134) (xy 402.2598 -121.8184) (xy 405.4856 -121.8184) (xy 405.8412 -121.4628)
				(xy 407.0858 -121.4628) (xy 407.289 -121.666) (xy 407.289 -122.6058) (xy 406.781 -123.1138) (xy 400.8374 -123.1138)
				(xy 400.2278 -123.7234) (xy 399.0467 -123.7234) (xy 399.04035 -123.71705) (xy 394.30325 -123.71705)
				(xy 392.938 -122.3518) (xy 392.938 -121.8946) (xy 392.4554 -121.412) (xy 392.4554 -121.1326) (xy 392.2776 -120.9548)
				(xy 392.2776 -119.9134) (xy 392.2776 -118.0338) (xy 392.2014 -117.9576) (xy 389.4074 -117.9576)
			)
		)
	)
	(zone
		(layer "In9.Cu")
		(hatch none 0.5)
		(connect_pads
			(clearance 0)
		)
		(min_thickness 0.25)
		(keepout
			(tracks allowed)
			(vias allowed)
			(pads allowed)
			(copperpour allowed)
			(footprints allowed)
		)
		(placement
			(enabled no)
			(sheetname "")
		)
		(fill
			(thermal_gap 0.5)
			(thermal_bridge_width 0.5)
			(island_removal_mode 0)
		)
		(polygon
			(pts
				(xy 370.84 -117.094) (xy 370.84 -113.919) (xy 372.5418 -113.919) (xy 372.5418 -117.094)
			)
		)
	)
	(zone
		(net "VR_FET_SW_P12V_STBY_PVDDQ_GHJ")
		(layer "In9.Cu")
		(hatch none 0.5)
		(connect_pads
			(clearance 0.5)
		)
		(min_thickness 0.25)
		(fill yes
			(thermal_gap 0.5)
			(thermal_bridge_width 0.5)
			(island_removal_mode 0)
		)
		(polygon
			(pts
				(xy 5.0546 -7.6708) (xy 5.0546 -11.9888) (xy 5.3848 -12.319) (xy 5.3848 -14.9098) (xy 5.0292 -15.2654)
				(xy 5.0292 -18.923) (xy 5.0292 -20.066) (xy 4.318 -20.7772) (xy -0.26035 -20.7772) (xy -2.032 -19.00555)
				(xy -3.01625 -19.00555) (xy -3.490722 -18.531078) (xy -3.490722 -18.507964) (xy -3.951732 -18.046954)
				(xy -3.951732 -16.168116) (xy -3.490722 -15.707106) (xy -3.490722 -5.715) (xy -0.7366 -5.715) (xy -0.1524 -6.2992)
				(xy 0.8128 -7.2644) (xy 2.6416 -7.2644) (xy 4.6482 -7.2644) (xy 4.953 -7.5692)
			)
		)
	)
	(zone
		(net "VR_FET_SW_P12V_STBY_PVDDQ_DEF")
		(layer "In9.Cu")
		(hatch none 0.5)
		(connect_pads
			(clearance 0.5)
		)
		(min_thickness 0.25)
		(fill yes
			(thermal_gap 0.5)
			(thermal_bridge_width 0.5)
			(island_removal_mode 0)
		)
		(polygon
			(pts
				(xy 348.2213 -142.8623) (xy 347.3958 -143.6878) (xy 347.3958 -151.384) (xy 349.266002 -153.254202)
				(xy 352.847402 -153.254202) (xy 355.352604 -150.749) (xy 355.657404 -150.4442) (xy 355.809804 -150.2918)
				(xy 358.4448 -150.2918) (xy 358.6226 -150.114) (xy 362.8136 -150.114) (xy 365.68761 -152.98801)
				(xy 365.68761 -154.85745) (xy 365.68761 -155.145994) (xy 365.948976 -155.40736) (xy 366.23752 -155.40736)
				(xy 368.10696 -155.40736) (xy 368.4016 -155.702) (xy 369.3922 -156.6926) (xy 371.5004 -156.6926)
				(xy 371.58295 -156.77515) (xy 378.04217 -156.77515) (xy 378.95022 -157.6832) (xy 380.19228 -157.6832)
				(xy 380.602236 -157.273244) (xy 387.686804 -157.273244) (xy 388.09676 -157.6832) (xy 389.5852 -157.6832)
				(xy 390.4488 -156.8196) (xy 390.4488 -153.3398) (xy 388.4422 -151.3332) (xy 387.29031 -150.18131)
				(xy 381.512826 -150.18131) (xy 380.776988 -149.445472) (xy 370.224812 -149.445472) (xy 367.18494 -146.4056)
				(xy 366.649 -146.4056) (xy 365.1758 -146.4056) (xy 364.6932 -146.8882) (xy 358.3686 -146.8882) (xy 356.42296 -146.8882)
				(xy 356.11816 -146.5834) (xy 352.13036 -142.5956) (xy 350.7994 -142.5956) (xy 350.52 -142.3162)
				(xy 350.0374 -142.3162) (xy 349.8088 -142.5448) (xy 349.2246 -142.5448) (xy 348.9071 -142.8623)
			)
		)
	)
	(zone
		(net "VR_FET_SW_P12V_STBY_PVDDQ_ABC")
		(layer "In9.Cu")
		(hatch none 0.5)
		(connect_pads
			(clearance 0.5)
		)
		(min_thickness 0.25)
		(fill yes
			(thermal_gap 0.5)
			(thermal_bridge_width 0.5)
			(island_removal_mode 0)
		)
		(polygon
			(pts
				(xy 352.0694 -13.1064) (xy 352.0694 -18.0213) (xy 352.0694 -19.7104) (xy 352.0694 -20.042124) (xy 352.51263 -20.485354)
				(xy 354.850446 -20.485354) (xy 355.0158 -20.32) (xy 356.616 -18.7198) (xy 356.616 -10.033) (xy 358.265984 -8.383016)
				(xy 358.265984 -6.519672) (xy 352.116898 -0.370586) (xy 352.116898 3.459988) (xy 351.760536 3.81635)
				(xy 346.364814 3.81635) (xy 346.202 3.653536) (xy 346.202 3.556) (xy 346.202 -0.127) (xy 345.821 -0.508)
				(xy 345.821 -7.045706) (xy 346.33154 -7.556246) (xy 347.995494 -9.2202) (xy 349.70212 -9.2202) (xy 349.92818 -9.44626)
				(xy 349.92818 -10.746486) (xy 352.0694 -12.887706)
			)
		)
	)
	(zone
		(net "GND")
		(layer "In9.Cu")
		(hatch none 0.5)
		(connect_pads
			(clearance 0.5)
		)
		(min_thickness 0.25)
		(fill yes
			(thermal_gap 0.5)
			(thermal_bridge_width 0.5)
			(island_removal_mode 0)
		)
		(polygon
			(pts
				(xy -5.334 -58.4454) (xy -5.334 -44.6532) (xy -4.1656 -43.4848) (xy 9.017 -43.4848) (xy 9.525 -43.9928)
				(xy 10.541 -43.9928) (xy 10.5664 -43.9674) (xy 12.4206 -43.9674) (xy 12.9286 -44.4754) (xy 12.9286 -48.0314)
				(xy 12.2682 -48.6918) (xy 2.8448 -48.6918) (xy 1.778 -49.7586) (xy 1.778 -58.42) (xy 0.508 -59.69)
				(xy 0.508 -67.31) (xy 2.2352 -69.0372) (xy 2.2352 -74.857102) (xy 0.91186 -76.180442) (xy 0.59817 -76.494132)
				(xy 0.59817 -77.738224) (xy 0.91186 -78.051914) (xy 2.108708 -79.248762) (xy 2.108708 -86.156292)
				(xy 1.2446 -87.0204) (xy -4.4196 -87.0204) (xy -5.334 -86.106)
			)
		)
	)
	(zone
		(layer "In9.Cu")
		(hatch none 0.5)
		(connect_pads
			(clearance 0)
		)
		(min_thickness 0.25)
		(keepout
			(tracks not_allowed)
			(vias allowed)
			(pads allowed)
			(copperpour not_allowed)
			(footprints allowed)
		)
		(placement
			(enabled no)
			(sheetname "")
		)
		(fill
			(thermal_gap 0.5)
			(thermal_bridge_width 0.5)
			(island_removal_mode 0)
		)
		(polygon
			(pts
				(arc
					(start 448.604132 -6.231128)
					(mid 449.024103 -5.909963)
					(end 448.702938 -6.329934)
				)
				(xy 448.619372 -6.4135) (xy 448.619372 -6.48208)
				(arc
					(start 448.835526 -6.48208)
					(mid 449.219066 -6.09854)
					(end 448.835526 -5.715)
				)
				(arc
					(start 447.893694 -5.715)
					(mid 447.5099 -6.098413)
					(end 447.89344 -6.48208)
				)
				(xy 448.178174 -6.48208)
				(arc
					(start 448.026028 -6.329934)
					(mid 447.704863 -5.909963)
					(end 448.124834 -6.231128)
				)
				(xy 448.327272 -6.433566) (xy 448.327272 -6.48208) (xy 448.479672 -6.48208) (xy 448.479672 -6.355588)
			)
		)
	)
	(zone
		(layer "In9.Cu")
		(hatch none 0.5)
		(connect_pads
			(clearance 0)
		)
		(min_thickness 0.25)
		(keepout
			(tracks allowed)
			(vias allowed)
			(pads allowed)
			(copperpour allowed)
			(footprints allowed)
		)
		(placement
			(enabled no)
			(sheetname "")
		)
		(fill
			(thermal_gap 0.5)
			(thermal_bridge_width 0.5)
			(island_removal_mode 0)
		)
		(polygon
			(pts
				(xy 325.495158 -14.25067) (xy 325.495158 -6.75767) (xy 328.543158 -6.75767) (xy 328.543158 -14.25067)
			)
		)
	)
	(zone
		(net "PVDDQ_GHJ")
		(layer "In9.Cu")
		(hatch none 0.5)
		(connect_pads
			(clearance 0.5)
		)
		(min_thickness 0.25)
		(fill yes
			(thermal_gap 0.5)
			(thermal_bridge_width 0.5)
			(island_removal_mode 0)
		)
		(polygon
			(pts
				(xy 78.77556 -6.29158) (xy 78.09738 -6.96976) (xy 78.09738 -25.60828) (xy 85.3694 -32.8803) (xy 85.3694 -59.2074)
				(xy 93.9546 -67.7926) (xy 106.045 -67.7926) (xy 106.046524 -67.791076) (xy 108.382054 -67.791076)
				(xy 108.636816 -67.536314) (xy 108.636816 -66.9798) (xy 108.408216 -66.7512) (xy 107.6198 -66.7512)
				(xy 107.4928 -66.6242) (xy 107.4928 -65.644014) (xy 107.315 -65.466214) (xy 106.479848 -65.466214)
				(xy 106.4006 -65.386966) (xy 106.4006 -64.5922) (xy 104.2416 -62.4332) (xy 104.2416 -34.31286) (xy 107.65536 -30.8991)
				(xy 107.94746 -30.8991) (xy 115.42268 -23.42388) (xy 115.42268 -8.86206) (xy 112.8522 -6.29158)
			)
		)
		(polygon
			(pts
				(xy 97.01276 -8.91794) (xy 94.40672 -8.91794) (xy 94.04604 -9.27862) (xy 94.04604 -15.14602) (xy 93.83522 -15.35684)
				(xy 93.83522 -16.15186) (xy 93.8403 -16.15186) (xy 93.83522 -16.15694) (xy 93.83522 -22.07768) (xy 93.76156 -22.15134)
				(xy 94.2467 -22.63648) (xy 96.9645 -22.63648) (xy 98.42246 -21.17852) (xy 98.42246 -15.87754) (xy 98.43262 -15.86738)
				(xy 98.43262 -15.38732) (xy 97.46996 -14.42466) (xy 97.46996 -9.37514)
			)
		)
		(polygon
			(pts
				(xy 113.12906 -15.81658) (xy 101.04374 -15.81658) (xy 100.45954 -16.40078) (xy 100.45954 -23.09876)
				(xy 101.0412 -23.68042) (xy 101.0412 -26.90622) (xy 101.57714 -27.44216) (xy 108.85424 -27.44216)
				(xy 113.3221 -22.9743) (xy 113.3221 -16.00962)
			)
		)
		(polygon
			(pts
				(xy 89.65946 -15.76832) (xy 81.06918 -15.76832) (xy 80.58404 -16.25346) (xy 80.58404 -23.19528)
				(xy 81.50606 -24.1173) (xy 90.24366 -24.1173) (xy 90.51036 -23.8506) (xy 90.51036 -16.61922)
			)
		)
	)
	(zone
		(layer "In9.Cu")
		(hatch none 0.5)
		(connect_pads
			(clearance 0)
		)
		(min_thickness 0.25)
		(keepout
			(tracks not_allowed)
			(vias allowed)
			(pads allowed)
			(copperpour not_allowed)
			(footprints allowed)
		)
		(placement
			(enabled no)
			(sheetname "")
		)
		(fill
			(thermal_gap 0.5)
			(thermal_bridge_width 0.5)
			(island_removal_mode 0)
		)
		(polygon
			(pts
				(xy 407.103326 -154.168094) (xy 407.103834 -154.168602)
				(arc
					(start 407.250138 -154.314906)
					(mid 407.571303 -154.734877)
					(end 407.151332 -154.413712)
				)
				(xy 407.004774 -154.267154) (xy 406.999186 -154.262328)
				(arc
					(start 406.999186 -154.546046)
					(mid 407.382599 -154.92984)
					(end 407.766266 -154.5463)
				)
				(arc
					(start 407.766266 -153.5303)
					(mid 407.382726 -153.14676)
					(end 406.999186 -153.5303)
				)
				(xy 406.999186 -153.814272) (xy 407.004774 -153.809446)
				(arc
					(start 407.151332 -153.662888)
					(mid 407.571303 -153.341723)
					(end 407.250138 -153.761694)
				)
				(xy 407.103834 -153.907998) (xy 407.103326 -153.908506) (xy 407.08326 -153.928572)
				(arc
					(start 407.07945 -153.928572)
					(mid 407.044059 -153.948019)
					(end 407.005282 -153.959306)
				)
				(xy 407.002488 -153.9621) (xy 406.999186 -153.9621) (xy 406.999186 -154.1145) (xy 407.002488 -154.1145)
				(arc
					(start 407.005282 -154.117294)
					(mid 407.044074 -154.128545)
					(end 407.07945 -154.148028)
				)
				(xy 407.08326 -154.148028)
			)
		)
	)
	(zone
		(net "VR_FET_SW_P12V_STBY_PVCCIO_CPU0")
		(layer "In9.Cu")
		(hatch none 0.5)
		(connect_pads
			(clearance 0.5)
		)
		(min_thickness 0.25)
		(fill yes
			(thermal_gap 0.5)
			(thermal_bridge_width 0.5)
			(island_removal_mode 0)
		)
		(polygon
			(pts
				(xy 352.5774 -103.8606) (xy 352.806 -103.632) (xy 352.806 -99.441) (xy 351.663 -98.298) (xy 350.266 -98.298)
				(xy 349.758 -97.79) (xy 349.758 -96.012) (xy 350.8502 -94.9198) (xy 350.8502 -93.9292) (xy 350.139 -93.218)
				(xy 349.00108 -92.08008) (xy 346.70492 -92.08008) (xy 345.821 -92.964) (xy 345.30665 -92.964) (xy 344.54465 -93.726)
				(xy 344.54465 -100.08235) (xy 344.6653 -100.203) (xy 345.9734 -100.203) (xy 347.2561 -101.4857)
				(xy 347.2561 -103.505) (xy 347.6117 -103.8606)
			)
		)
	)
	(zone
		(net "GND")
		(layer "In9.Cu")
		(hatch none 0.5)
		(connect_pads
			(clearance 0.5)
		)
		(min_thickness 0.25)
		(fill yes
			(thermal_gap 0.5)
			(thermal_bridge_width 0.5)
			(island_removal_mode 0)
		)
		(polygon
			(pts
				(xy 347.1926 -156.406088) (xy 347.1926 -152.1206) (xy 346.3798 -151.3078) (xy 346.3798 -150.0378)
				(xy 347.1418 -149.2758) (xy 347.1418 -144.3228) (xy 345.9861 -143.1671) (xy 345.9861 -142.8369)
				(xy 345.2622 -142.113) (xy 344.9828 -142.113) (xy 342.4428 -139.573) (xy 338.6582 -139.573) (xy 338.2772 -139.954)
				(xy 338.2772 -156.227272) (xy 338.574634 -156.524706) (xy 347.073982 -156.524706)
			)
		)
	)
	(zone
		(net "P12V_PSU")
		(layer "In9.Cu")
		(hatch none 0.5)
		(connect_pads
			(clearance 0.5)
		)
		(min_thickness 0.25)
		(fill yes
			(thermal_gap 0.5)
			(thermal_bridge_width 0.5)
			(island_removal_mode 0)
		)
		(polygon
			(pts
				(xy 9.5758 -86.1822) (xy 4.128008 -86.1822) (xy 3.5306 -85.584792) (xy 3.5306 -68.3768) (xy 3.1242 -67.9704)
				(xy 2.3114 -67.1576) (xy 2.3114 -59.8932) (xy 3.0734 -59.1312) (xy 3.0734 -50.3428) (xy 3.3782 -50.038)
				(xy 9.2202 -50.038) (xy 9.45642 -50.038) (xy 10.092182 -50.673762) (xy 10.092182 -85.934296) (xy 9.844278 -86.1822)
			)
		)
	)
	(zone
		(net "P5V_USB")
		(layer "In9.Cu")
		(hatch none 0.5)
		(connect_pads
			(clearance 0.5)
		)
		(min_thickness 0.25)
		(fill yes
			(thermal_gap 0.5)
			(thermal_bridge_width 0.5)
			(island_removal_mode 0)
		)
		(polygon
			(pts
				(xy 475.3864 -132.7531) (xy 482.8921 -132.7531) (xy 483.1334 -132.5118) (xy 483.1334 -128.6256)
				(xy 482.8286 -128.3208) (xy 474.0402 -128.3208) (xy 472.821 -127.1016) (xy 466.9536 -127.1016) (xy 464.8962 -127.1016)
				(xy 463.2452 -128.7526) (xy 463.2452 -131.1656) (xy 464.3882 -132.3086) (xy 466.9028 -132.3086)
				(xy 467.3346 -132.7404) (xy 468.2236 -132.7404) (xy 468.2363 -132.7531)
			)
		)
	)
	(zone
		(net "PVCCIO_CPU1")
		(layer "In9.Cu")
		(hatch none 0.5)
		(connect_pads
			(clearance 0.5)
		)
		(min_thickness 0.25)
		(fill yes
			(thermal_gap 0.5)
			(thermal_bridge_width 0.5)
			(island_removal_mode 0)
		)
		(polygon
			(pts
				(xy 118.0084 -85.4202) (xy 127.1016 -85.4202) (xy 129.0066 -83.5152) (xy 129.0066 -75.0316) (xy 123.317 -69.342)
				(xy 114.1222 -69.342) (xy 113.03 -70.4342) (xy 113.03 -79.0448) (xy 117.5512 -83.566) (xy 117.5512 -84.963)
			)
		)
	)
	(zone
		(layer "In9.Cu")
		(hatch none 0.5)
		(connect_pads
			(clearance 0)
		)
		(min_thickness 0.25)
		(keepout
			(tracks not_allowed)
			(vias allowed)
			(pads allowed)
			(copperpour not_allowed)
			(footprints allowed)
		)
		(placement
			(enabled no)
			(sheetname "")
		)
		(fill
			(thermal_gap 0.5)
			(thermal_bridge_width 0.5)
			(island_removal_mode 0)
		)
		(polygon
			(pts
				(arc
					(start 16.54302 -30.414722)
					(mid 16.61287 -29.890805)
					(end 16.68272 -30.414722)
				)
				(xy 16.68272 -30.503114) (xy 16.761206 -30.5816) (xy 16.99641 -30.5816)
				(arc
					(start 16.99641 -30.15742)
					(mid 16.61287 -29.77388)
					(end 16.22933 -30.15742)
				)
				(arc
					(start 16.22933 -31.427166)
					(mid 16.612743 -31.81096)
					(end 16.99641 -31.42742)
				)
				(xy 16.99641 -31.0134) (xy 16.751046 -31.0134) (xy 16.68272 -31.081726)
				(arc
					(start 16.68272 -31.170118)
					(mid 16.61287 -31.694035)
					(end 16.54302 -31.170118)
				)
				(xy 16.54302 -31.023814) (xy 16.693134 -30.8737) (xy 16.99641 -30.8737) (xy 16.99641 -30.7213) (xy 16.703294 -30.7213)
				(xy 16.54302 -30.561026)
			)
		)
	)
	(zone
		(net "P12V_NVDIMM_KLM")
		(layer "In9.Cu")
		(hatch none 0.5)
		(connect_pads
			(clearance 0.5)
		)
		(min_thickness 0.25)
		(fill yes
			(thermal_gap 0.5)
			(thermal_bridge_width 0.5)
			(island_removal_mode 0)
		)
		(polygon
			(pts
				(xy 12.0396 -134.2898) (xy 16.9926 -134.2898) (xy 17.3228 -133.9596) (xy 17.3228 -131.1148) (xy 16.3576 -130.1496)
				(xy 13.484352 -130.1496) (xy 11.5062 -132.127752) (xy 11.5062 -133.7564)
			)
		)
	)
	(zone
		(net "GND")
		(layer "In9.Cu")
		(hatch none 0.5)
		(connect_pads
			(clearance 0.5)
		)
		(min_thickness 0.25)
		(fill yes
			(thermal_gap 0.5)
			(thermal_bridge_width 0.5)
			(island_removal_mode 0)
		)
		(polygon
			(pts
				(xy 199.488806 -101.727) (xy 202.0316 -101.727) (xy 202.2602 -101.4984) (xy 204.216 -101.4984) (xy 204.848968 -101.4984)
				(xy 206.2734 -101.4984) (xy 207.74152 -100.03028) (xy 207.74152 -93.836744) (xy 207.45196 -93.547184)
				(xy 199.608694 -93.547184) (xy 199.425052 -93.730826) (xy 199.425052 -101.663246)
			)
		)
	)
	(zone
		(layer "In9.Cu")
		(hatch none 0.5)
		(connect_pads
			(clearance 0)
		)
		(min_thickness 0.25)
		(keepout
			(tracks not_allowed)
			(vias allowed)
			(pads allowed)
			(copperpour not_allowed)
			(footprints allowed)
		)
		(placement
			(enabled no)
			(sheetname "")
		)
		(fill
			(thermal_gap 0.5)
			(thermal_bridge_width 0.5)
			(island_removal_mode 0)
		)
		(polygon
			(pts
				(arc
					(start 419.801802 -151.1427)
					(mid 419.750634 -151.241138)
					(end 419.652196 -151.292306)
				)
				(xy 419.649402 -151.2951) (xy 419.373304 -151.2951) (xy 419.371272 -151.293068) (xy 419.351206 -151.289512)
				(arc
					(start 419.351206 -151.444198)
					(mid 419.376679 -151.446687)
					(end 419.40226 -151.4475)
				)
				(xy 419.649402 -151.4475)
				(arc
					(start 419.652196 -151.450294)
					(mid 419.750634 -151.501462)
					(end 419.801802 -151.5999)
				)
				(xy 419.804596 -151.602694)
				(arc
					(start 419.804596 -151.621998)
					(mid 419.735269 -152.145914)
					(end 419.66388 -151.622252)
				)
				(arc
					(start 419.66388 -151.622252)
					(mid 419.648349 -151.597063)
					(end 419.620446 -151.5872)
				)
				(xy 419.373304 -151.5872) (xy 419.372542 -151.586438) (xy 419.351206 -151.58466)
				(arc
					(start 419.351206 -151.879046)
					(mid 419.734619 -152.26284)
					(end 420.118286 -151.8793)
				)
				(arc
					(start 420.118286 -150.8633)
					(mid 419.734746 -150.47976)
					(end 419.351206 -150.8633)
				)
				(arc
					(start 419.351206 -151.14143)
					(mid 419.37579 -151.151855)
					(end 419.40226 -151.1554)
				)
				(arc
					(start 419.620446 -151.1554)
					(mid 419.648356 -151.145545)
					(end 419.66388 -151.120348)
				)
				(arc
					(start 419.66388 -151.120348)
					(mid 419.73527 -150.596663)
					(end 419.804596 -151.120602)
				)
				(xy 419.804596 -151.139906)
			)
		)
	)
	(zone
		(layer "In9.Cu")
		(hatch none 0.5)
		(connect_pads
			(clearance 0)
		)
		(min_thickness 0.25)
		(keepout
			(tracks not_allowed)
			(vias allowed)
			(pads allowed)
			(copperpour not_allowed)
			(footprints allowed)
		)
		(placement
			(enabled no)
			(sheetname "")
		)
		(fill
			(thermal_gap 0.5)
			(thermal_bridge_width 0.5)
			(island_removal_mode 0)
		)
		(polygon
			(pts
				(arc
					(start 15.34795 -28.641802)
					(mid 15.4178 -28.117885)
					(end 15.48765 -28.641802)
				)
				(xy 15.48765 -28.717748) (xy 15.561056 -28.791154) (xy 15.80134 -28.791154)
				(arc
					(start 15.80134 -28.384754)
					(mid 15.417927 -28.00096)
					(end 15.03426 -28.3845)
				)
				(arc
					(start 15.03426 -29.6545)
					(mid 15.4178 -30.03804)
					(end 15.80134 -29.6545)
				)
				(xy 15.80134 -29.222954) (xy 15.573502 -29.222954) (xy 15.48765 -29.308806)
				(arc
					(start 15.48765 -29.397198)
					(mid 15.4178 -29.921115)
					(end 15.34795 -29.397198)
				)
				(xy 15.34795 -29.250894) (xy 15.51559 -29.083254) (xy 15.80134 -29.083254) (xy 15.80134 -28.930854)
				(xy 15.503144 -28.930854) (xy 15.34795 -28.77566)
			)
		)
	)
	(zone
		(net "PVDDQ_ABC")
		(layer "In9.Cu")
		(hatch none 0.5)
		(connect_pads
			(clearance 0.5)
		)
		(min_thickness 0.25)
		(fill yes
			(thermal_gap 0.5)
			(thermal_bridge_width 0.5)
			(island_removal_mode 0)
		)
		(polygon
			(pts
				(xy 266.6238 -67.8434) (xy 264.0584 -67.8434) (xy 258.9022 -62.6872) (xy 258.318 -62.6872) (xy 253.3142 -62.6872)
				(xy 251.1044 -60.4774) (xy 250.63704 -60.01004) (xy 250.63704 -53.72862) (xy 251.1044 -53.26126)
				(xy 251.64796 -52.7177) (xy 258.05892 -52.7177) (xy 258.064 -52.72278) (xy 266.88034 -57.65927)
				(xy 269.52956 -59.39536) (xy 269.9131 -59.7789) (xy 269.9131 -63.4111) (xy 273.721576 -67.219576)
				(xy 273.721576 -67.6275) (xy 273.505676 -67.8434) (xy 270.7894 -67.8434)
			)
		)
	)
	(zone
		(layer "In9.Cu")
		(hatch none 0.5)
		(connect_pads
			(clearance 0)
		)
		(min_thickness 0.25)
		(keepout
			(tracks not_allowed)
			(vias allowed)
			(pads allowed)
			(copperpour not_allowed)
			(footprints allowed)
		)
		(placement
			(enabled no)
			(sheetname "")
		)
		(fill
			(thermal_gap 0.5)
			(thermal_bridge_width 0.5)
			(island_removal_mode 0)
		)
		(polygon
			(pts
				(xy 435.97195 -2.45618) (xy 435.97195 -2.723642) (xy 435.786022 -2.90957)
				(arc
					(start 435.68874 -2.90957)
					(mid 435.164823 -2.83972)
					(end 435.68874 -2.76987)
				)
				(xy 435.72811 -2.76987) (xy 435.83225 -2.66573) (xy 435.83225 -2.45618)
				(arc
					(start 435.431438 -2.45618)
					(mid 435.047898 -2.83972)
					(end 435.431438 -3.22326)
				)
				(arc
					(start 436.701184 -3.22326)
					(mid 437.084724 -2.839847)
					(end 436.701438 -2.45618)
				)
				(xy 436.26405 -2.45618) (xy 436.26405 -2.70383) (xy 436.33009 -2.76987)
				(arc
					(start 436.444136 -2.76987)
					(mid 436.968053 -2.83972)
					(end 436.444136 -2.90957)
				)
				(xy 436.272178 -2.90957) (xy 436.12435 -2.761742) (xy 436.12435 -2.45618)
			)
		)
	)
	(zone
		(layer "In9.Cu")
		(hatch none 0.5)
		(connect_pads
			(clearance 0)
		)
		(min_thickness 0.25)
		(keepout
			(tracks allowed)
			(vias allowed)
			(pads allowed)
			(copperpour allowed)
			(footprints allowed)
		)
		(placement
			(enabled no)
			(sheetname "")
		)
		(fill
			(thermal_gap 0.5)
			(thermal_bridge_width 0.5)
			(island_removal_mode 0)
		)
		(polygon
			(pts
				(xy 262.0264 -9.3599) (xy 262.0264 -1.8669) (xy 265.0744 -1.8669) (xy 265.0744 -9.3599)
			)
		)
	)
	(zone
		(layer "In9.Cu")
		(hatch none 0.5)
		(connect_pads
			(clearance 0)
		)
		(min_thickness 0.25)
		(keepout
			(tracks not_allowed)
			(vias allowed)
			(pads allowed)
			(copperpour not_allowed)
			(footprints allowed)
		)
		(placement
			(enabled no)
			(sheetname "")
		)
		(fill
			(thermal_gap 0.5)
			(thermal_bridge_width 0.5)
			(island_removal_mode 0)
		)
		(polygon
			(pts
				(xy 12.740386 -39.32428) (xy 12.740386 -39.4716) (xy 12.837414 -39.589964)
				(arc
					(start 13.032232 -39.589964)
					(mid 13.416026 -39.206551)
					(end 13.032486 -38.822884)
				)
				(arc
					(start 12.016486 -38.822884)
					(mid 11.632946 -39.206424)
					(end 12.016486 -39.589964)
				)
				(xy 12.308586 -39.589964) (xy 12.308586 -39.34968)
				(arc
					(start 12.264136 -39.30523)
					(mid 11.75029 -39.191162)
					(end 12.273788 -39.136574)
				)
				(xy 12.293092 -39.136574) (xy 12.448286 -39.291768) (xy 12.448286 -39.576248) (xy 12.459462 -39.589964)
				(xy 12.65682 -39.589964) (xy 12.61872 -39.543482) (xy 12.600686 -39.525448) (xy 12.600686 -39.521384)
				(xy 12.598146 -39.518336) (xy 12.600686 -39.492936) (xy 12.600686 -39.266368) (xy 12.73048 -39.136574)
				(arc
					(start 12.775184 -39.136574)
					(mid 13.29912 -39.201654)
					(end 12.777978 -39.286434)
				)
			)
		)
	)
	(zone
		(layer "In9.Cu")
		(hatch none 0.5)
		(connect_pads
			(clearance 0)
		)
		(min_thickness 0.25)
		(keepout
			(tracks allowed)
			(vias allowed)
			(pads allowed)
			(copperpour allowed)
			(footprints allowed)
		)
		(placement
			(enabled no)
			(sheetname "")
		)
		(fill
			(thermal_gap 0.5)
			(thermal_bridge_width 0.5)
			(island_removal_mode 0)
		)
		(polygon
			(pts
				(xy 368.681 -118.745) (xy 368.681 -117.475) (xy 370.3828 -117.475) (xy 370.3828 -118.745)
			)
		)
	)
	(zone
		(layer "In9.Cu")
		(hatch none 0.5)
		(connect_pads
			(clearance 0)
		)
		(min_thickness 0.25)
		(keepout
			(tracks not_allowed)
			(vias allowed)
			(pads allowed)
			(copperpour not_allowed)
			(footprints allowed)
		)
		(placement
			(enabled no)
			(sheetname "")
		)
		(fill
			(thermal_gap 0.5)
			(thermal_bridge_width 0.5)
			(island_removal_mode 0)
		)
		(polygon
			(pts
				(xy 443.319408 -5.508498) (xy 443.319408 -5.806694) (xy 443.164214 -5.961888)
				(arc
					(start 443.01791 -5.961888)
					(mid 442.493993 -5.892038)
					(end 443.01791 -5.822188)
				)
				(xy 443.106302 -5.822188) (xy 443.179708 -5.748782) (xy 443.179708 -5.508498)
				(arc
					(start 442.760608 -5.508498)
					(mid 442.377068 -5.892038)
					(end 442.760608 -6.275578)
				)
				(arc
					(start 444.030354 -6.275578)
					(mid 444.414148 -5.892165)
					(end 444.030608 -5.508498)
				)
				(xy 443.696852 -5.508498) (xy 443.611508 -5.594604) (xy 443.611508 -5.748782) (xy 443.684914 -5.822188)
				(arc
					(start 443.773306 -5.822188)
					(mid 444.297223 -5.892038)
					(end 443.773306 -5.961888)
				)
				(xy 443.627002 -5.961888) (xy 443.471808 -5.806694) (xy 443.471808 -5.566156) (xy 443.471554 -5.5372)
				(xy 443.471808 -5.5372) (xy 443.471808 -5.536946) (xy 443.492128 -5.516626) (xy 443.500256 -5.508498)
			)
		)
	)
	(zone
		(net "P1V05_PCH_STBY")
		(layer "In9.Cu")
		(hatch none 0.5)
		(connect_pads
			(clearance 0.5)
		)
		(min_thickness 0.25)
		(fill yes
			(thermal_gap 0.5)
			(thermal_bridge_width 0.5)
			(island_removal_mode 0)
		)
		(polygon
			(pts
				(xy 382.67767 -123.63323) (xy 383.82321 -122.48769) (xy 383.82321 -121.70791) (xy 385.43992 -120.0912)
				(xy 388.1374 -120.0912) (xy 388.5184 -119.7102) (xy 388.5184 -114.5032) (xy 388.747 -114.2746) (xy 393.446 -114.2746)
				(xy 394.5636 -115.3922) (xy 394.716 -115.5446) (xy 395.5288 -115.5446) (xy 395.7447 -115.3287) (xy 395.7447 -112.3696)
				(xy 393.9159 -110.5408) (xy 393.9159 -108.0135) (xy 393.364974 -107.462574) (xy 393.364974 -106.265472)
				(xy 392.723878 -105.624376) (xy 389.530336 -105.624376) (xy 388.71398 -104.80802) (xy 388.71398 -104.79024)
				(xy 387.96976 -104.79024) (xy 387.1468 -105.6132) (xy 385.191 -105.6132) (xy 384.5052 -104.9274)
				(xy 384.5052 -104.267) (xy 384.175 -103.9368) (xy 383.23901 -103.9368) (xy 382.93675 -104.23906)
				(xy 381.72898 -104.23906) (xy 380.435866 -104.23906) (xy 379.84938 -104.825546) (xy 379.84938 -107.902502)
				(xy 379.857 -107.910122) (xy 379.857 -112.9284) (xy 380.130558 -113.201958) (xy 381.605282 -113.201958)
				(xy 381.708406 -113.098834) (xy 382.103376 -113.098834) (xy 382.567942 -113.5634) (xy 384.048 -113.5634)
				(xy 386.6896 -113.5634) (xy 386.8928 -113.7666) (xy 386.8928 -115.062) (xy 382.48082 -119.47398)
				(xy 378.390404 -126.446534) (xy 377.45924 -128.6129) (xy 377.44654 -128.6129) (xy 377.01982 -129.03962)
				(xy 375.87936 -129.03962) (xy 375.4374 -129.48158) (xy 375.4374 -131.7752) (xy 374.9421 -132.2705)
				(xy 371.6655 -132.2705) (xy 370.4844 -133.4516) (xy 370.4844 -135.0518) (xy 370.4844 -137.1473)
				(xy 371.746018 -138.408918) (xy 371.746018 -141.312392) (xy 372.377208 -141.943582) (xy 374.632982 -141.943582)
				(xy 375.4374 -142.748) (xy 376.7328 -144.0434) (xy 388.192264 -144.0434) (xy 389.315452 -145.166588)
				(xy 392.331702 -145.166588) (xy 393.561316 -145.166588) (xy 393.828016 -144.899888) (xy 393.828016 -140.539216)
				(xy 390.971532 -137.682732) (xy 388.949692 -137.682732) (xy 385.22656 -133.9596) (xy 383.5019 -132.23494)
				(xy 383.5019 -129.77114) (xy 381.88646 -128.1557) (xy 381.88646 -126.15418) (xy 382.67767 -125.36297)
			)
		)
	)
	(zone
		(layer "In9.Cu")
		(hatch none 0.5)
		(connect_pads
			(clearance 0)
		)
		(min_thickness 0.25)
		(keepout
			(tracks not_allowed)
			(vias allowed)
			(pads allowed)
			(copperpour not_allowed)
			(footprints allowed)
		)
		(placement
			(enabled no)
			(sheetname "")
		)
		(fill
			(thermal_gap 0.5)
			(thermal_bridge_width 0.5)
			(island_removal_mode 0)
		)
		(polygon
			(pts
				(arc
					(start 15.378684 -25.087326)
					(mid 15.438185 -24.561745)
					(end 15.518384 -25.084532)
				)
				(xy 15.519908 -25.151334) (xy 15.594584 -25.22474) (xy 15.826994 -25.22474)
				(arc
					(start 15.826994 -24.8285)
					(mid 15.443454 -24.44496)
					(end 15.059914 -24.8285)
				)
				(arc
					(start 15.059914 -26.098246)
					(mid 15.443327 -26.48204)
					(end 15.826994 -26.0985)
				)
				(xy 15.826994 -25.65654) (xy 15.61719 -25.65654) (xy 15.520416 -25.753314)
				(arc
					(start 15.518638 -25.842468)
					(mid 15.43844 -26.365219)
					(end 15.378938 -25.839674)
				)
				(xy 15.381224 -25.723088) (xy 15.381224 -25.694894) (xy 15.381732 -25.694386) (xy 15.381732 -25.693624)
				(xy 15.402306 -25.674066) (xy 15.559278 -25.51684) (xy 15.826994 -25.51684) (xy 15.826994 -25.36444)
				(xy 15.56639 -25.36444) (xy 15.537942 -25.364694) (xy 15.537688 -25.36444) (xy 15.53718 -25.36444)
				(xy 15.517114 -25.34412) (xy 15.401798 -25.231344) (xy 15.381224 -25.211532) (xy 15.381224 -25.211278)
				(xy 15.38097 -25.211024) (xy 15.380716 -25.182322)
			)
		)
	)
	(zone
		(layer "In9.Cu")
		(hatch none 0.5)
		(connect_pads
			(clearance 0)
		)
		(min_thickness 0.25)
		(keepout
			(tracks not_allowed)
			(vias allowed)
			(pads allowed)
			(copperpour not_allowed)
			(footprints allowed)
		)
		(placement
			(enabled no)
			(sheetname "")
		)
		(fill
			(thermal_gap 0.5)
			(thermal_bridge_width 0.5)
			(island_removal_mode 0)
		)
		(polygon
			(pts
				(arc
					(start 455.747628 -63.488062)
					(mid 455.330871 -63.815157)
					(end 455.657966 -63.3984)
				)
				(xy 455.838814 -63.217552)
				(arc
					(start 455.519536 -63.217552)
					(mid 455.110596 -63.626492)
					(end 455.519536 -64.035432)
				)
				(arc
					(start 456.789282 -64.035432)
					(mid 457.198476 -63.626619)
					(end 456.789536 -63.217552)
				)
				(xy 456.470258 -63.217552)
				(arc
					(start 456.651106 -63.3984)
					(mid 456.978201 -63.815157)
					(end 456.561444 -63.488062)
				)
				(xy 456.337924 -63.264288) (xy 456.30084 -63.227204) (xy 456.300586 -63.227204) (xy 456.300586 -63.217552)
				(xy 456.008232 -63.217552) (xy 456.008232 -63.227458) (xy 455.970894 -63.264796)
			)
		)
	)
	(zone
		(layer "In9.Cu")
		(hatch none 0.5)
		(connect_pads
			(clearance 0)
		)
		(min_thickness 0.25)
		(keepout
			(tracks not_allowed)
			(vias allowed)
			(pads allowed)
			(copperpour not_allowed)
			(footprints allowed)
		)
		(placement
			(enabled no)
			(sheetname "")
		)
		(fill
			(thermal_gap 0.5)
			(thermal_bridge_width 0.5)
			(island_removal_mode 0)
		)
		(polygon
			(pts
				(xy 440.80811 -5.283708) (xy 440.80811 -5.568696) (xy 440.639708 -5.737098)
				(arc
					(start 440.481974 -5.737098)
					(mid 439.958057 -5.667248)
					(end 440.481974 -5.597398)
				)
				(xy 440.581796 -5.597398) (xy 440.66841 -5.510784) (xy 440.66841 -5.283708)
				(arc
					(start 440.224672 -5.283708)
					(mid 439.841132 -5.667248)
					(end 440.224672 -6.050788)
				)
				(arc
					(start 441.494418 -6.050788)
					(mid 441.878212 -5.667375)
					(end 441.494672 -5.283708)
				)
				(xy 441.10021 -5.283708) (xy 441.10021 -5.493004) (xy 441.204604 -5.597398)
				(arc
					(start 441.23737 -5.597398)
					(mid 441.761287 -5.667248)
					(end 441.23737 -5.737098)
				)
				(xy 441.146692 -5.737098) (xy 440.96051 -5.550916) (xy 440.96051 -5.283708)
			)
		)
	)
	(zone
		(layer "In9.Cu")
		(hatch none 0.5)
		(connect_pads
			(clearance 0)
		)
		(min_thickness 0.25)
		(keepout
			(tracks not_allowed)
			(vias allowed)
			(pads allowed)
			(copperpour not_allowed)
			(footprints allowed)
		)
		(placement
			(enabled no)
			(sheetname "")
		)
		(fill
			(thermal_gap 0.5)
			(thermal_bridge_width 0.5)
			(island_removal_mode 0)
		)
		(polygon
			(pts
				(xy 438.376822 -2.507234) (xy 438.376822 -2.818384) (xy 438.234582 -2.960624)
				(arc
					(start 438.071514 -2.960624)
					(mid 437.547597 -2.890774)
					(end 438.071514 -2.820924)
				)
				(xy 438.17667 -2.820924) (xy 438.237122 -2.760472) (xy 438.237122 -2.507234)
				(arc
					(start 437.814212 -2.507234)
					(mid 437.430672 -2.890774)
					(end 437.814212 -3.274314)
				)
				(arc
					(start 439.083958 -3.274314)
					(mid 439.467752 -2.890901)
					(end 439.084212 -2.507234)
				)
				(xy 438.695084 -2.507234) (xy 438.668922 -2.533396) (xy 438.668922 -2.756916) (xy 438.73293 -2.820924)
				(arc
					(start 438.82691 -2.820924)
					(mid 439.350827 -2.890774)
					(end 438.82691 -2.960624)
				)
				(xy 438.675018 -2.960624) (xy 438.529222 -2.814828) (xy 438.529222 -2.507234)
			)
		)
	)
	(zone
		(layer "In9.Cu")
		(hatch none 0.5)
		(connect_pads
			(clearance 0)
		)
		(min_thickness 0.25)
		(keepout
			(tracks allowed)
			(vias allowed)
			(pads allowed)
			(copperpour allowed)
			(footprints allowed)
		)
		(placement
			(enabled no)
			(sheetname "")
		)
		(fill
			(thermal_gap 0.5)
			(thermal_bridge_width 0.5)
			(island_removal_mode 0)
		)
		(polygon
			(pts
				(xy 187.579 -9.398) (xy 187.579 -1.905) (xy 190.627 -1.905) (xy 190.627 -9.398)
			)
		)
	)
	(zone
		(layer "In9.Cu")
		(hatch none 0.5)
		(connect_pads
			(clearance 0)
		)
		(min_thickness 0.25)
		(keepout
			(tracks not_allowed)
			(vias allowed)
			(pads allowed)
			(copperpour not_allowed)
			(footprints allowed)
		)
		(placement
			(enabled no)
			(sheetname "")
		)
		(fill
			(thermal_gap 0.5)
			(thermal_bridge_width 0.5)
			(island_removal_mode 0)
		)
		(polygon
			(pts
				(arc
					(start 409.963366 -148.845016)
					(mid 409.579826 -148.461476)
					(end 409.196286 -148.845016)
				)
				(xy 409.196286 -149.146514)
				(arc
					(start 409.465526 -149.146514)
					(mid 409.496867 -149.133585)
					(end 409.509976 -149.102318)
				)
				(arc
					(start 409.509976 -149.102318)
					(mid 409.579826 -148.578401)
					(end 409.649676 -149.102318)
				)
				(xy 409.649676 -149.13102)
				(arc
					(start 409.646882 -149.133814)
					(mid 409.595714 -149.232252)
					(end 409.497276 -149.28342)
				)
				(xy 409.494482 -149.286214) (xy 409.196286 -149.286214) (xy 409.196286 -149.438614) (xy 409.466034 -149.438614)
				(arc
					(start 409.46832 -149.4409)
					(mid 409.580874 -149.494591)
					(end 409.643834 -149.60219)
				)
				(arc
					(start 409.643834 -149.60219)
					(mid 409.590276 -150.127434)
					(end 409.495752 -149.608032)
				)
				(arc
					(start 409.495752 -149.608032)
					(mid 409.469953 -149.586201)
					(end 409.437078 -149.578314)
				)
				(xy 409.196286 -149.578314)
				(arc
					(start 409.196286 -149.860762)
					(mid 409.579699 -150.244556)
					(end 409.963366 -149.861016)
				)
			)
		)
	)
	(zone
		(net "VCC_PA_3V3")
		(layer "In9.Cu")
		(hatch none 0.5)
		(connect_pads
			(clearance 0.5)
		)
		(min_thickness 0.25)
		(fill yes
			(thermal_gap 0.5)
			(thermal_bridge_width 0.5)
			(island_removal_mode 0)
		)
		(polygon
			(pts
				(xy 422.637966 -40.182038) (xy 424.144186 -40.182038) (xy 424.46321 -39.863014) (xy 424.46321 -34.25952)
				(xy 424.46321 -33.969198) (xy 424.46321 -32.63265) (xy 424.13682 -32.30626) (xy 419.52418 -32.30626)
				(xy 419.19398 -32.63646) (xy 419.19398 -33.694624) (xy 419.101524 -33.78708) (xy 418.922708 -33.965896)
				(xy 418.922708 -36.795964) (xy 418.941758 -36.795964) (xy 419.133274 -36.98748) (xy 422.203372 -36.98748)
				(xy 422.254426 -37.038534) (xy 422.254426 -39.798498)
			)
		)
	)
	(zone
		(net "PVSA_CPU0")
		(layer "In9.Cu")
		(hatch none 0.5)
		(connect_pads
			(clearance 0.5)
		)
		(min_thickness 0.25)
		(fill yes
			(thermal_gap 0.5)
			(thermal_bridge_width 0.5)
			(island_removal_mode 0)
		)
		(polygon
			(pts
				(xy 236.412024 -84.033614) (xy 254.170688 -84.044536) (xy 254.601218 -84.475066) (xy 258.002024 -84.475066)
				(xy 258.164076 -84.313014) (xy 258.789424 -84.313014) (xy 258.865624 -84.389214) (xy 258.865624 -84.398866)
				(xy 258.941824 -84.475066) (xy 261.366 -84.475066) (xy 261.874 -83.967066) (xy 261.874 -82.8294)
				(xy 260.538214 -81.493614) (xy 257.875024 -81.493614) (xy 256.73812 -80.35671) (xy 256.224024 -80.35671)
				(xy 256.090928 -80.223614) (xy 255.21412 -80.223614) (xy 255.081024 -80.35671) (xy 253.15672 -80.35671)
				(xy 252.896624 -80.096614) (xy 251.652024 -80.096614) (xy 251.271024 -79.715614) (xy 251.017024 -79.715614)
				(xy 250.509024 -79.207614) (xy 246.191024 -79.207614) (xy 245.048024 -80.350614) (xy 238.317024 -80.350614)
				(xy 233.872024 -77.810614) (xy 229.910386 -77.810614) (xy 215.8746 -91.8464) (xy 215.8746 -92.456)
				(xy 215.4682 -92.8624) (xy 208.6356 -92.8624) (xy 208.407 -93.091) (xy 208.00568 -93.49232) (xy 208.00568 -99.16668)
				(xy 208.407 -99.568) (xy 208.9658 -100.1268) (xy 214.5284 -100.1268) (xy 223.6343 -91.0209) (xy 225.4123 -91.0209)
				(xy 229.286054 -87.147146) (xy 229.362 -87.0712) (xy 230.9368 -85.4964) (xy 230.9368 -85.1408) (xy 232.043986 -84.033614)
				(xy 233.034586 -84.033614)
			)
		)
	)
	(zone
		(net "PVDDQ_ABC")
		(layer "In10.Cu")
		(hatch none 0.5)
		(connect_pads
			(clearance 0.5)
		)
		(min_thickness 0.25)
		(fill yes
			(thermal_gap 0.5)
			(thermal_bridge_width 0.5)
			(island_removal_mode 0)
		)
		(polygon
			(pts
				(xy 243.549932 2.753868) (xy 243.489734 2.693924) (xy 243.200428 2.404872)
				(arc
					(start 243.200428 2.280412)
					(mid 243.227887 2.210945)
					(end 243.295424 2.179066)
				)
				(arc
					(start 243.295424 2.179066)
					(mid 243.628407 1.82372)
					(end 243.295424 1.468374)
				)
				(arc
					(start 243.295424 1.468374)
					(mid 243.227915 1.436468)
					(end 243.200428 1.367028)
				)
				(xy 243.200428 0.822706)
				(arc
					(start 243.238528 0.813054)
					(mid 243.503369 0.51152)
					(end 243.3193 0.15494)
				)
				(arc
					(start 243.3193 -2.049018)
					(mid 243.505951 -2.3622)
					(end 243.3193 -2.675382)
				)
				(xy 243.3193 -3.00609)
				(arc
					(start 243.352574 -3.018282)
					(mid 243.556363 -3.496247)
					(end 243.066316 -3.668776)
				)
				(xy 243.033296 -3.651504) (xy 242.8494 -3.8354)
				(arc
					(start 242.8494 -3.93446)
					(mid 242.897586 -4.020886)
					(end 242.996466 -4.025392)
				)
				(arc
					(start 242.996466 -4.025392)
					(mid 243.493158 -4.332478)
					(end 242.996466 -4.639564)
				)
				(arc
					(start 242.996466 -4.639564)
					(mid 242.897552 -4.644015)
					(end 242.8494 -4.730496)
				)
				(xy 242.8494 -6.731) (xy 242.951254 -6.832854)
				(arc
					(start 242.984782 -6.814566)
					(mid 243.453138 -6.954657)
					(end 243.3066 -7.421118)
				)
				(xy 243.3066 -7.798816)
				(arc
					(start 243.3447 -7.808468)
					(mid 243.612004 -8.1534)
					(end 243.3447 -8.498332)
				)
				(xy 243.3066 -8.507984)
				(arc
					(start 243.3066 -8.813292)
					(mid 243.506005 -9.133078)
					(end 243.3066 -9.452864)
				)
				(xy 243.3066 -12.537948)
				(arc
					(start 243.340128 -12.55014)
					(mid 243.575734 -12.885849)
					(end 243.338858 -13.2207)
				)
				(xy 243.32819 -13.22451) (xy 243.1669 -13.3858) (xy 243.1669 -13.587984)
				(arc
					(start 243.209064 -13.59535)
					(mid 243.490955 -13.893211)
					(end 243.286534 -14.248638)
				)
				(arc
					(start 243.286534 -14.248638)
					(mid 243.227125 -14.322841)
					(end 243.255038 -14.413738)
				)
				(xy 243.2558 -14.4145) (xy 243.2558 -16.878554)
				(arc
					(start 243.294662 -16.887952)
					(mid 243.54449 -17.128178)
					(end 243.45773 -17.46377)
				)
				(arc
					(start 243.45773 -17.46377)
					(mid 243.428282 -17.539259)
					(end 243.463318 -17.61236)
				)
				(arc
					(start 243.463318 -17.61236)
					(mid 243.574236 -17.973891)
					(end 243.297202 -18.231358)
				)
				(xy 243.2558 -18.239232) (xy 243.2558 -18.410936)
				(arc
					(start 243.284502 -18.424906)
					(mid 243.482275 -18.701764)
					(end 243.3574 -19.01825)
				)
				(xy 243.3574 -21.849842)
				(arc
					(start 243.391436 -21.86178)
					(mid 243.630611 -22.198076)
					(end 243.391436 -22.534372)
				)
				(xy 243.3574 -22.54631) (xy 243.3574 -23.0759)
				(arc
					(start 243.343176 -23.090124)
					(mid 243.313942 -23.1703)
					(end 243.35613 -23.244556)
				)
				(arc
					(start 243.35613 -23.244556)
					(mid 243.497033 -23.614323)
					(end 243.209318 -23.885906)
				)
				(xy 243.1669 -23.893272) (xy 243.1669 -25.1968) (xy 243.489734 -25.519634) (xy 243.489734 -26.766774)
				(xy 251.076968 -34.354008) (xy 251.076968 -51.039268) (xy 251.4981 -51.4604)
				(arc
					(start 251.4981 -51.800252)
					(mid 251.560902 -51.894153)
					(end 251.671582 -51.87188)
				)
				(arc
					(start 251.671582 -51.87188)
					(mid 252.279961 -52.12334)
					(end 251.671582 -52.3748)
				)
				(arc
					(start 251.671582 -52.3748)
					(mid 251.560949 -52.352641)
					(end 251.4981 -52.446428)
				)
				(arc
					(start 251.4981 -52.790598)
					(mid 251.560902 -52.884499)
					(end 251.671582 -52.862226)
				)
				(arc
					(start 251.671582 -52.862226)
					(mid 252.273393 -53.181772)
					(end 251.595636 -53.252116)
				)
				(xy 251.582682 -53.221128) (xy 251.4981 -53.221128) (xy 251.4981 -53.380132) (xy 251.808234 -53.690266)
				(xy 252.076966 -53.690266) (xy 252.3236 -53.9369) (xy 252.3236 -63.1698)
				(arc
					(start 252.40234 -63.24854)
					(mid 252.471795 -63.278286)
					(end 252.542548 -63.251842)
				)
				(arc
					(start 252.542548 -63.251842)
					(mid 252.877466 -63.171992)
					(end 253.123446 -63.412878)
				)
				(xy 253.134368 -63.4492)
				(arc
					(start 253.321566 -63.4492)
					(mid 253.415705 -63.385816)
					(end 253.392432 -63.274702)
				)
				(arc
					(start 253.392432 -63.274702)
					(mid 253.640844 -62.663678)
					(end 253.889256 -63.274702)
				)
				(arc
					(start 253.889256 -63.274702)
					(mid 253.865922 -63.385841)
					(end 253.960122 -63.4492)
				)
				(xy 254.147066 -63.4492)
				(arc
					(start 254.157988 -63.412878)
					(mid 254.49911 -63.159091)
					(end 254.840232 -63.412878)
				)
				(xy 254.851154 -63.4492)
				(arc
					(start 255.038352 -63.4492)
					(mid 255.132491 -63.385816)
					(end 255.109218 -63.274702)
				)
				(arc
					(start 255.109218 -63.274702)
					(mid 255.35763 -62.663678)
					(end 255.606042 -63.274702)
				)
				(arc
					(start 255.606042 -63.274702)
					(mid 255.582708 -63.385841)
					(end 255.676908 -63.4492)
				)
				(xy 255.864106 -63.4492)
				(arc
					(start 255.875028 -63.412878)
					(mid 256.21615 -63.159091)
					(end 256.557272 -63.412878)
				)
				(xy 256.568194 -63.4492)
				(arc
					(start 256.755392 -63.4492)
					(mid 256.849531 -63.385816)
					(end 256.826258 -63.274702)
				)
				(arc
					(start 256.826258 -63.274702)
					(mid 257.145497 -62.670562)
					(end 257.204972 -63.351156)
				)
				(xy 257.172714 -63.363856) (xy 257.172714 -63.4492) (xy 257.31343 -63.4492) (xy 257.33883 -63.4238)
				(xy 257.587242 -63.4238)
				(arc
					(start 257.599434 -63.39078)
					(mid 257.93319 -63.159033)
					(end 258.266946 -63.39078)
				)
				(xy 258.279138 -63.4238) (xy 258.448302 -63.4238) (xy 258.721098 -63.4238) (xy 259.067554 -63.077344)
				(xy 259.143246 -63.077344) (xy 259.145278 -63.075312) (xy 259.817108 -63.075312) (xy 260.053836 -63.31204)
				(xy 260.053836 -63.767716) (xy 263.96696 -67.68084) (xy 271.24914 -67.68084) (xy 273.52371 -67.68084)
				(xy 273.714464 -67.490086) (xy 273.714464 -67.263264) (xy 269.463266 -63.012066) (xy 269.463266 -60.96)
				(xy 269.463266 -50.964846) (xy 270.761968 -49.666144) (xy 270.761968 -36.162996) (xy 278.8666 -28.058364)
				(xy 278.8666 -23.1775)
				(arc
					(start 278.83485 -23.1648)
					(mid 278.61209 -22.8346)
					(end 278.83485 -22.5044)
				)
				(xy 278.8666 -22.4917) (xy 278.8666 -22.013926)
				(arc
					(start 278.83231 -22.002242)
					(mid 278.591216 -21.665184)
					(end 278.83231 -21.328126)
				)
				(xy 278.8666 -21.316442) (xy 278.8666 -19.04111)
				(arc
					(start 278.831802 -19.029426)
					(mid 278.595008 -18.759734)
					(end 278.713184 -18.420842)
				)
				(arc
					(start 278.713184 -18.420842)
					(mid 278.74854 -18.345682)
					(end 278.715978 -18.269204)
				)
				(arc
					(start 278.715978 -18.269204)
					(mid 278.601689 -17.997044)
					(end 278.73198 -17.732248)
				)
				(arc
					(start 278.73198 -17.732248)
					(mid 278.769059 -17.65287)
					(end 278.73071 -17.574006)
				)
				(arc
					(start 278.73071 -17.574006)
					(mid 278.600481 -17.236492)
					(end 278.832818 -16.959072)
				)
				(xy 278.8666 -16.947134)
				(arc
					(start 278.8666 -14.251432)
					(mid 278.683576 -13.940282)
					(end 278.8666 -13.629132)
				)
				(xy 278.8666 -13.308584)
				(arc
					(start 278.8285 -13.298932)
					(mid 278.561196 -12.954)
					(end 278.8285 -12.609068)
				)
				(xy 278.8666 -12.599416) (xy 278.8666 -12.285218)
				(arc
					(start 278.829262 -12.275058)
					(mid 278.56758 -11.93165)
					(end 278.829262 -11.588242)
				)
				(xy 278.8666 -11.578082) (xy 278.8666 -9.440418)
				(arc
					(start 278.82596 -9.432036)
					(mid 278.543986 -9.124734)
					(end 278.74722 -8.76046)
				)
				(arc
					(start 278.74722 -8.76046)
					(mid 278.804592 -8.685956)
					(end 278.776176 -8.596376)
				)
				(xy 278.4348 -8.255)
				(arc
					(start 278.4348 -7.431278)
					(mid 278.370665 -7.336838)
					(end 278.259286 -7.361682)
				)
				(arc
					(start 278.259286 -7.361682)
					(mid 277.65158 -7.043609)
					(end 278.335994 -6.999986)
				)
				(xy 278.347932 -7.034022) (xy 278.4348 -7.034022) (xy 278.4348 -6.858) (xy 278.8666 -6.4262) (xy 278.8666 -5.08)
				(xy 278.384 -4.5974) (xy 278.384 -4.515612) (xy 278.306784 -4.515612)
				(arc
					(start 278.291544 -4.537202)
					(mid 277.64782 -4.385267)
					(end 278.219662 -4.052824)
				)
				(arc
					(start 278.219662 -4.052824)
					(mid 278.326891 -4.064237)
					(end 278.384 -3.972814)
				)
				(arc
					(start 278.384 -2.67716)
					(mid 278.326858 -2.585803)
					(end 278.219662 -2.59715)
				)
				(arc
					(start 278.219662 -2.59715)
					(mid 277.685426 -2.149465)
					(end 278.355298 -2.342134)
				)
				(arc
					(start 278.355298 -2.342134)
					(mid 278.41442 -2.441651)
					(end 278.528272 -2.421128)
				)
				(xy 278.8666 -2.0828) (xy 278.8666 0.880872)
				(arc
					(start 278.553926 1.193546)
					(mid 278.446099 1.216753)
					(end 278.380698 1.128014)
				)
				(arc
					(start 278.380698 1.128014)
					(mid 277.730184 0.882376)
					(end 277.975822 1.53289)
				)
				(arc
					(start 277.975822 1.53289)
					(mid 278.064457 1.59833)
					(end 278.041354 1.706118)
				)
				(xy 277.720806 2.026666) (xy 277.6093 1.91516) (xy 275.76272 1.91516) (xy 275.59254 2.08534) (xy 275.24456 2.08534)
				(xy 275.02104 1.86182) (xy 274.17268 1.86182) (xy 273.95678 2.07772) (xy 273.58086 2.07772) (xy 273.43354 1.9304)
				(xy 273.43354 1.91516) (xy 272.472658 1.91516)
				(arc
					(start 272.35912 2.028698)
					(mid 272.217633 1.462834)
					(end 271.683734 1.697736)
				)
				(arc
					(start 271.683734 1.697736)
					(mid 271.611326 1.767732)
					(end 271.514316 1.740916)
				)
				(xy 271.4498 1.6764) (xy 270.710152 1.6764)
				(arc
					(start 270.69669 1.646682)
					(mid 270.349726 1.423875)
					(end 270.002762 1.646682)
				)
				(xy 269.9893 1.6764) (xy 269.01013 1.6764)
				(arc
					(start 268.996668 1.646682)
					(mid 268.649704 1.423875)
					(end 268.30274 1.646682)
				)
				(xy 268.289278 1.6764) (xy 265.6713 1.6764) (xy 265.226546 2.121154)
				(arc
					(start 265.199368 2.115566)
					(mid 264.964601 2.146033)
					(end 264.800842 2.316988)
				)
				(xy 264.787126 2.34696)
				(arc
					(start 264.606024 2.34696)
					(mid 264.529235 2.311888)
					(end 264.50544 2.230882)
				)
				(arc
					(start 264.50544 2.230882)
					(mid 264.512324 2.166148)
					(end 264.514584 2.101088)
				)
				(arc
					(start 264.514584 0.856488)
					(mid 263.59993 -0.058166)
					(end 262.685276 0.856488)
				)
				(arc
					(start 262.685276 2.101088)
					(mid 262.687226 2.161542)
					(end 262.69315 2.221738)
				)
				(arc
					(start 262.69315 2.221738)
					(mid 262.668935 2.302029)
					(end 262.592566 2.3368)
				)
				(xy 262.265922 2.3368) (xy 262.151622 2.2225) (xy 262.151622 1.93548) (xy 261.539736 1.323594) (xy 261.099808 1.323594)
				(xy 260.882638 1.540764) (xy 260.882638 2.022348) (xy 260.568186 2.3368) (xy 259.842 2.3368)
				(arc
					(start 259.798312 2.380488)
					(mid 259.705505 2.408086)
					(end 259.631688 2.345436)
				)
				(arc
					(start 259.631688 2.345436)
					(mid 259.166265 2.144597)
					(end 258.971796 2.612898)
				)
				(arc
					(start 258.971796 2.612898)
					(mid 258.962737 2.708536)
					(end 258.87807 2.753868)
				)
				(arc
					(start 258.053332 2.753868)
					(mid 257.970003 2.710395)
					(end 257.958082 2.617216)
				)
				(arc
					(start 257.958082 2.617216)
					(mid 257.756786 2.137829)
					(end 257.264154 2.304288)
				)
				(arc
					(start 257.264154 2.304288)
					(mid 257.17494 2.357406)
					(end 257.085592 2.304288)
				)
				(arc
					(start 257.085592 2.304288)
					(mid 256.592923 2.137748)
					(end 256.391664 2.617216)
				)
				(arc
					(start 256.391664 2.617216)
					(mid 256.379657 2.710335)
					(end 256.296414 2.753868)
				)
				(arc
					(start 254.66294 2.753868)
					(mid 254.581493 2.713004)
					(end 254.565658 2.623312)
				)
				(arc
					(start 254.565658 2.623312)
					(mid 254.199898 2.133352)
					(end 253.834138 2.623312)
				)
				(arc
					(start 253.834138 2.623312)
					(mid 253.818223 2.712944)
					(end 253.736856 2.753868)
				)
				(arc
					(start 252.953266 2.753868)
					(mid 252.869937 2.710395)
					(end 252.858016 2.617216)
				)
				(arc
					(start 252.858016 2.617216)
					(mid 252.499876 2.1041)
					(end 252.141736 2.617216)
				)
				(arc
					(start 252.141736 2.617216)
					(mid 252.129729 2.710335)
					(end 252.046486 2.753868)
				)
				(arc
					(start 249.553222 2.753868)
					(mid 249.469893 2.710395)
					(end 249.457972 2.617216)
				)
				(arc
					(start 249.457972 2.617216)
					(mid 249.099832 2.1041)
					(end 248.741692 2.617216)
				)
				(arc
					(start 248.741692 2.617216)
					(mid 248.729685 2.710335)
					(end 248.646442 2.753868)
				)
				(arc
					(start 247.862852 2.753868)
					(mid 247.781405 2.713004)
					(end 247.76557 2.623312)
				)
				(arc
					(start 247.76557 2.623312)
					(mid 247.39981 2.133352)
					(end 247.03405 2.623312)
				)
				(arc
					(start 247.03405 2.623312)
					(mid 247.018135 2.712944)
					(end 246.936768 2.753868)
				)
			)
		)
	)
	(zone
		(net "P12V_PSU")
		(layer "In10.Cu")
		(hatch none 0.5)
		(connect_pads
			(clearance 0.5)
		)
		(min_thickness 0.25)
		(fill yes
			(thermal_gap 0.5)
			(thermal_bridge_width 0.5)
			(island_removal_mode 0)
		)
		(polygon
			(pts
				(xy 3.361182 -50.038762) (xy 3.1242 -50.275744) (xy 3.1242 -59.1058) (xy 1.827022 -60.402978) (xy 1.827022 -66.673222)
				(xy 3.553206 -68.399406) (xy 3.553206 -85.569806) (xy 4.1402 -86.1568) (xy 9.8044 -86.1568) (xy 10.033 -85.9282)
				(xy 10.033 -50.6984) (xy 9.373362 -50.038762)
			)
		)
	)
	(zone
		(net "PVDDQ_DEF")
		(layer "In10.Cu")
		(hatch none 0.5)
		(connect_pads
			(clearance 0.5)
		)
		(min_thickness 0.25)
		(fill yes
			(thermal_gap 0.5)
			(thermal_bridge_width 0.5)
			(island_removal_mode 0)
		)
		(polygon
			(pts
				(xy 262.056118 -85.217) (xy 261.33806 -85.935058)
				(arc
					(start 261.36473 -85.970364)
					(mid 261.315998 -86.451319)
					(end 260.8326 -86.440518)
				)
				(xy 260.006338 -87.26678)
				(arc
					(start 260.006338 -87.288116)
					(mid 259.902039 -87.541449)
					(end 259.648706 -87.645748)
				)
				(xy 259.62737 -87.645748)
				(arc
					(start 258.959604 -88.313514)
					(mid 258.930521 -88.397233)
					(end 258.978146 -88.47201)
				)
				(arc
					(start 258.978146 -88.47201)
					(mid 259.022164 -89.046626)
					(end 258.462272 -88.91016)
				)
				(xy 258.449318 -88.878664)
				(arc
					(start 258.286758 -88.878664)
					(mid 258.194895 -88.936861)
					(end 258.208272 -89.04478)
				)
				(arc
					(start 258.208272 -89.04478)
					(mid 257.93319 -89.626892)
					(end 257.658108 -89.04478)
				)
				(arc
					(start 257.658108 -89.04478)
					(mid 257.671484 -88.936861)
					(end 257.579622 -88.878664)
				)
				(xy 257.417062 -88.878664)
				(arc
					(start 257.404108 -88.91016)
					(mid 257.07467 -89.131264)
					(end 256.745232 -88.91016)
				)
				(xy 256.732278 -88.878664)
				(arc
					(start 256.569718 -88.878664)
					(mid 256.477855 -88.936861)
					(end 256.491232 -89.04478)
				)
				(arc
					(start 256.491232 -89.04478)
					(mid 256.21615 -89.626892)
					(end 255.941068 -89.04478)
				)
				(arc
					(start 255.941068 -89.04478)
					(mid 255.954444 -88.936861)
					(end 255.862582 -88.878664)
				)
				(xy 255.700022 -88.878664)
				(arc
					(start 255.687068 -88.91016)
					(mid 255.35763 -89.131264)
					(end 255.028192 -88.91016)
				)
				(xy 255.015238 -88.878664)
				(arc
					(start 254.852678 -88.878664)
					(mid 254.760815 -88.936861)
					(end 254.774192 -89.04478)
				)
				(arc
					(start 254.774192 -89.04478)
					(mid 254.681145 -89.576841)
					(end 254.169164 -89.404698)
				)
				(arc
					(start 254.169164 -89.404698)
					(mid 254.095182 -89.343191)
					(end 254.003048 -89.370916)
				)
				(xy 253.975362 -89.398602) (xy 253.52502 -89.398602) (xy 253.162816 -89.760806) (xy 253.162816 -95.205042)
				(xy 253.138686 -95.229172)
				(arc
					(start 253.136908 -95.24746)
					(mid 253.034227 -95.466164)
					(end 252.815598 -95.569024)
				)
				(xy 252.79731 -95.570802)
				(arc
					(start 252.692154 -95.675958)
					(mid 252.670916 -95.788616)
					(end 252.7681 -95.849186)
				)
				(arc
					(start 252.7681 -95.849186)
					(mid 253.034152 -96.456868)
					(end 252.42647 -96.190816)
				)
				(arc
					(start 252.42647 -96.190816)
					(mid 252.365734 -96.093643)
					(end 252.253242 -96.11487)
				)
				(arc
					(start 252.114558 -96.253554)
					(mid 252.085363 -96.334185)
					(end 252.128274 -96.408494)
				)
				(arc
					(start 252.128274 -96.408494)
					(mid 252.276505 -96.749442)
					(end 252.04039 -97.036636)
				)
				(xy 252.0061 -97.04832) (xy 252.0061 -97.342452) (xy 252.0061 -97.54489) (xy 251.841254 -97.709736)
				(xy 251.841254 -98.239326) (xy 250.851924 -99.228656) (xy 250.851924 -99.418394) (xy 250.851924 -101.11232)
				(xy 250.854972 -101.115368) (xy 250.854972 -118.265702) (xy 243.965222 -125.155452) (xy 243.965222 -127.667512)
				(xy 243.968524 -127.67056) (xy 243.968524 -129.085086) (xy 243.916708 -129.136902) (xy 243.96827 -129.18821)
				(arc
					(start 243.98986 -129.187448)
					(mid 244.354814 -129.70891)
					(end 243.732304 -129.84099)
				)
				(arc
					(start 243.732304 -129.84099)
					(mid 243.621695 -129.819597)
					(end 243.55933 -129.91338)
				)
				(xy 243.55933 -130.0353)
				(arc
					(start 243.56822 -130.048254)
					(mid 243.613482 -130.358955)
					(end 243.395246 -130.584702)
				)
				(xy 243.384578 -130.588512) (xy 243.329206 -130.643884)
				(arc
					(start 243.329206 -131.278884)
					(mid 243.505902 -131.581927)
					(end 243.33708 -131.8895)
				)
				(xy 243.33708 -133.989826)
				(arc
					(start 243.374418 -134.00024)
					(mid 243.626153 -134.331202)
					(end 243.374418 -134.662164)
				)
				(xy 243.33708 -134.672578) (xy 243.33708 -135.047736)
				(arc
					(start 243.368322 -135.078978)
					(mid 243.586607 -135.4074)
					(end 243.368322 -135.735822)
				)
				(xy 243.363242 -135.737854) (xy 243.33708 -135.763508)
				(arc
					(start 243.33708 -136.084056)
					(mid 243.506064 -136.387078)
					(end 243.33708 -136.6901)
				)
				(arc
					(start 243.33708 -138.939778)
					(mid 243.506064 -139.2428)
					(end 243.33708 -139.545822)
				)
				(xy 243.33708 -139.859258)
				(arc
					(start 243.37137 -139.871196)
					(mid 243.612052 -140.208)
					(end 243.37137 -140.544804)
				)
				(xy 243.33708 -140.556742)
				(arc
					(start 243.33708 -140.899896)
					(mid 243.493192 -141.187678)
					(end 243.33708 -141.47546)
				)
				(xy 243.33708 -142.142972) (xy 243.028216 -142.451836)
				(arc
					(start 243.028216 -143.51889)
					(mid 243.066468 -143.598323)
					(end 243.152422 -143.61795)
				)
				(arc
					(start 243.152422 -143.61795)
					(mid 243.571646 -143.952722)
					(end 243.152422 -144.287494)
				)
				(arc
					(start 243.152422 -144.287494)
					(mid 243.066464 -144.307116)
					(end 243.028216 -144.386554)
				)
				(arc
					(start 243.028216 -144.562068)
					(mid 243.066371 -144.641424)
					(end 243.152168 -144.661128)
				)
				(arc
					(start 243.152168 -144.661128)
					(mid 243.58657 -145.0086)
					(end 243.152168 -145.356072)
				)
				(arc
					(start 243.152168 -145.356072)
					(mid 243.066402 -145.375815)
					(end 243.028216 -145.455132)
				)
				(arc
					(start 243.028216 -145.531078)
					(mid 243.059611 -145.604521)
					(end 243.134388 -145.632424)
				)
				(arc
					(start 243.134388 -145.632424)
					(mid 243.506073 -145.988278)
					(end 243.134388 -146.344132)
				)
				(arc
					(start 243.134388 -146.344132)
					(mid 243.059716 -146.372144)
					(end 243.028216 -146.445478)
				)
				(arc
					(start 243.028216 -148.9837)
					(mid 243.063193 -149.060407)
					(end 243.14404 -149.084284)
				)
				(arc
					(start 243.14404 -149.084284)
					(mid 243.51486 -149.282863)
					(end 243.437664 -149.696424)
				)
				(arc
					(start 243.437664 -149.696424)
					(mid 243.405752 -149.772047)
					(end 243.440204 -149.846538)
				)
				(arc
					(start 243.440204 -149.846538)
					(mid 243.56079 -150.130442)
					(end 243.41455 -150.402036)
				)
				(arc
					(start 243.41455 -150.402036)
					(mid 243.373042 -150.474612)
					(end 243.400072 -150.553674)
				)
				(arc
					(start 243.400072 -150.553674)
					(mid 243.461912 -150.932243)
					(end 243.134388 -151.132032)
				)
				(arc
					(start 243.134388 -151.132032)
					(mid 243.059716 -151.160044)
					(end 243.028216 -151.233378)
				)
				(arc
					(start 243.028216 -153.799032)
					(mid 243.070149 -153.881266)
					(end 243.161312 -153.895552)
				)
				(arc
					(start 243.161312 -153.895552)
					(mid 243.622769 -154.170914)
					(end 243.286026 -154.589734)
				)
				(arc
					(start 243.286026 -154.589734)
					(mid 243.195224 -154.654109)
					(end 243.217954 -154.762962)
				)
				(xy 243.513356 -155.058364) (xy 243.519452 -155.06446) (xy 243.519452 -155.459684) (xy 244.256052 -156.196284)
				(arc
					(start 261.17677 -156.196284)
					(mid 261.265777 -156.143677)
					(end 261.262622 -156.040328)
				)
				(arc
					(start 261.262622 -156.040328)
					(mid 261.563358 -155.493443)
					(end 261.864094 -156.040328)
				)
				(arc
					(start 261.864094 -156.040328)
					(mid 261.860928 -156.143683)
					(end 261.949946 -156.196284)
				)
				(arc
					(start 262.085582 -156.196284)
					(mid 262.175685 -156.14114)
					(end 262.168132 -156.035756)
				)
				(arc
					(start 262.168132 -156.035756)
					(mid 262.171581 -155.617489)
					(end 262.570214 -155.490926)
				)
				(arc
					(start 262.570214 -155.490926)
					(mid 262.669351 -155.470784)
					(end 262.701786 -155.375102)
				)
				(arc
					(start 262.701786 -155.375102)
					(mid 262.689369 -155.288502)
					(end 262.685276 -155.201112)
				)
				(arc
					(start 262.685276 -153.956512)
					(mid 263.59993 -153.041858)
					(end 264.514584 -153.956512)
				)
				(arc
					(start 264.514584 -155.201112)
					(mid 264.385818 -155.669056)
					(end 264.035794 -156.005276)
				)
				(arc
					(start 264.035794 -156.005276)
					(mid 263.985579 -156.119695)
					(end 264.084308 -156.196284)
				)
				(xy 264.98423 -156.196284)
				(arc
					(start 265.07694 -156.103574)
					(mid 265.105899 -156.018839)
					(end 265.05662 -155.944062)
				)
				(arc
					(start 265.05662 -155.944062)
					(mid 265.091911 -155.267868)
					(end 265.624818 -155.68549)
				)
				(arc
					(start 265.624818 -155.68549)
					(mid 265.646451 -155.769126)
					(end 265.72464 -155.805886)
				)
				(arc
					(start 266.47521 -155.805886)
					(mid 266.553417 -155.769141)
					(end 266.575032 -155.68549)
				)
				(arc
					(start 266.575032 -155.68549)
					(mid 266.949936 -155.233683)
					(end 267.32484 -155.68549)
				)
				(arc
					(start 267.32484 -155.68549)
					(mid 267.346473 -155.769126)
					(end 267.424662 -155.805886)
				)
				(arc
					(start 269.875 -155.805886)
					(mid 269.953207 -155.769141)
					(end 269.974822 -155.68549)
				)
				(arc
					(start 269.974822 -155.68549)
					(mid 270.349726 -155.233382)
					(end 270.72463 -155.68549)
				)
				(arc
					(start 270.72463 -155.68549)
					(mid 270.746263 -155.769126)
					(end 270.824452 -155.805886)
				)
				(arc
					(start 271.60093 -155.805886)
					(mid 271.67947 -155.768738)
					(end 271.700498 -155.684474)
				)
				(arc
					(start 271.700498 -155.684474)
					(mid 272.049748 -155.258761)
					(end 272.398998 -155.684474)
				)
				(arc
					(start 272.398998 -155.684474)
					(mid 272.420088 -155.768687)
					(end 272.498566 -155.805886)
				)
				(arc
					(start 273.275044 -155.805886)
					(mid 273.353251 -155.769141)
					(end 273.374866 -155.68549)
				)
				(arc
					(start 273.374866 -155.68549)
					(mid 273.74977 -155.233382)
					(end 274.124674 -155.68549)
				)
				(arc
					(start 274.124674 -155.68549)
					(mid 274.146307 -155.769126)
					(end 274.224496 -155.805886)
				)
				(arc
					(start 274.975066 -155.805886)
					(mid 275.053273 -155.769141)
					(end 275.074888 -155.68549)
				)
				(arc
					(start 275.074888 -155.68549)
					(mid 275.449792 -155.233382)
					(end 275.824696 -155.68549)
				)
				(arc
					(start 275.824696 -155.68549)
					(mid 275.846329 -155.769126)
					(end 275.924518 -155.805886)
				)
				(xy 276.967188 -155.805886) (xy 276.97811 -155.816808) (xy 277.438866 -155.816808) (xy 277.608792 -155.646628)
				(xy 277.608792 -148.595842) (xy 278.910288 -147.294346)
				(arc
					(start 278.910288 -146.39925)
					(mid 278.895677 -146.363599)
					(end 278.86025 -146.34845)
				)
				(arc
					(start 278.86025 -146.34845)
					(mid 278.509936 -145.992342)
					(end 278.86025 -145.636234)
				)
				(arc
					(start 278.86025 -145.636234)
					(mid 278.895681 -145.621089)
					(end 278.910288 -145.585434)
				)
				(arc
					(start 278.910288 -145.03273)
					(mid 278.883782 -144.96404)
					(end 278.817832 -144.931384)
				)
				(arc
					(start 278.817832 -144.931384)
					(mid 278.493811 -144.5768)
					(end 278.817832 -144.222216)
				)
				(arc
					(start 278.817832 -144.222216)
					(mid 278.883711 -144.189496)
					(end 278.910288 -144.12087)
				)
				(xy 278.910288 -140.840968)
				(arc
					(start 278.87295 -140.830554)
					(mid 278.612072 -140.4874)
					(end 278.87295 -140.144246)
				)
				(xy 278.910288 -140.133832) (xy 278.910288 -140.01877)
				(arc
					(start 278.867362 -140.011912)
					(mid 278.565969 -139.660122)
					(end 278.867362 -139.308332)
				)
				(xy 278.910288 -139.301474) (xy 278.910288 -136.686544)
				(arc
					(start 278.864822 -136.681718)
					(mid 278.5564 -136.412576)
					(end 278.705056 -136.031224)
				)
				(arc
					(start 278.705056 -136.031224)
					(mid 278.750241 -135.950732)
					(end 278.71166 -135.866886)
				)
				(arc
					(start 278.71166 -135.866886)
					(mid 278.577313 -135.610042)
					(end 278.678386 -135.338312)
				)
				(arc
					(start 278.678386 -135.338312)
					(mid 278.707256 -135.261706)
					(end 278.670258 -135.188706)
				)
				(arc
					(start 278.670258 -135.188706)
					(mid 278.556111 -134.808866)
					(end 278.86406 -134.55904)
				)
				(arc
					(start 278.86406 -134.55904)
					(mid 278.896957 -134.542727)
					(end 278.910288 -134.508494)
				)
				(xy 278.910288 -131.239768)
				(arc
					(start 278.87295 -131.229354)
					(mid 278.64196 -131.029009)
					(end 278.651462 -130.723386)
				)
				(arc
					(start 278.651462 -130.723386)
					(mid 278.656056 -130.640729)
					(end 278.597614 -130.582162)
				)
				(arc
					(start 278.597614 -130.582162)
					(mid 278.382564 -130.15298)
					(end 278.790146 -129.899664)
				)
				(arc
					(start 278.790146 -129.899664)
					(mid 278.873692 -129.877834)
					(end 278.910288 -129.799588)
				)
				(xy 278.910288 -126.481078) (xy 271.323308 -118.894098) (xy 271.323308 -101.625908) (xy 271.0307 -101.3333)
				(xy 270.6116 -100.914454) (xy 270.6116 -100.907088) (xy 270.170656 -100.466144) (xy 270.170656 -100.457508)
				(arc
					(start 269.92961 -100.216462)
					(mid 269.831737 -100.189998)
					(end 269.759684 -100.26142)
				)
				(arc
					(start 269.759684 -100.26142)
					(mid 269.224407 -100.467178)
					(end 269.18666 -99.894898)
				)
				(arc
					(start 269.18666 -99.894898)
					(mid 269.222696 -99.821578)
					(end 269.19301 -99.745546)
				)
				(xy 269.088108 -99.640644) (xy 269.088108 -99.315524)
				(arc
					(start 269.084552 -99.306634)
					(mid 269.060064 -99.17684)
					(end 269.084552 -99.047046)
				)
				(xy 269.088108 -99.038156) (xy 269.088108 -98.324924)
				(arc
					(start 269.084552 -98.316034)
					(mid 269.060064 -98.18624)
					(end 269.084552 -98.056446)
				)
				(xy 269.088108 -98.047556) (xy 269.088108 -97.334324)
				(arc
					(start 269.084552 -97.325434)
					(mid 269.060064 -97.19564)
					(end 269.084552 -97.065846)
				)
				(xy 269.088108 -97.056956) (xy 269.088108 -96.343724)
				(arc
					(start 269.084552 -96.334834)
					(mid 269.060064 -96.20504)
					(end 269.084552 -96.075246)
				)
				(xy 269.088108 -96.066356) (xy 269.088108 -95.353124)
				(arc
					(start 269.084552 -95.344234)
					(mid 269.060064 -95.21444)
					(end 269.084552 -95.084646)
				)
				(xy 269.088108 -95.075756) (xy 269.088108 -93.0148) (xy 272.4912 -89.611708) (xy 272.4912 -86.835488)
				(xy 272.709894 -86.616794) (xy 272.841974 -86.484714) (xy 274.622006 -86.484714) (xy 274.748752 -86.357968)
				(xy 274.748752 -85.360764) (xy 274.605242 -85.217) (xy 272.0086 -85.217) (xy 268.4272 -85.217)
			)
		)
	)
	(zone
		(net "GND")
		(layer "In10.Cu")
		(hatch none 0.5)
		(connect_pads
			(clearance 0.5)
		)
		(min_thickness 0.25)
		(fill yes
			(thermal_gap 0.5)
			(thermal_bridge_width 0.5)
			(island_removal_mode 0)
		)
		(polygon
			(pts
				(arc
					(start -3.675126 5.542788)
					(mid -4.995762 4.995762)
					(end -5.542788 3.675126)
				)
				(arc
					(start -5.542788 -156.77515)
					(mid -5.113232 -157.966885)
					(end -4.02209 -158.6103)
				)
				(xy 91.059 -158.6103) (xy 91.059 -158.642812) (xy 97.465642 -158.63824) (xy 112.649 -158.642812)
				(xy 112.795812 -158.496)
				(arc
					(start 112.799114 -158.496)
					(mid 112.872202 -158.464974)
					(end 112.900714 -158.390844)
				)
				(arc
					(start 112.900714 -158.390844)
					(mid 113.279399 -158.023585)
					(end 113.608104 -158.43631)
				)
				(xy 113.607342 -158.440374) (xy 113.607342 -158.496) (xy 113.720626 -158.496) (xy 113.720626 -158.440374)
				(arc
					(start 113.719864 -158.43631)
					(mid 114.04856 -158.023447)
					(end 114.427254 -158.390844)
				)
				(arc
					(start 114.427254 -158.390844)
					(mid 114.455722 -158.465018)
					(end 114.528854 -158.496)
				)
				(xy 114.554 -158.496) (xy 114.6683 -158.6103) (xy 186.5503 -158.6103) (xy 186.563 -158.623) (xy 375.050812 -158.623)
				(xy 375.070624 -158.642812) (xy 393.7 -158.642812) (xy 393.860528 -158.482284) (xy 393.859258 -158.47949)
				(arc
					(start 394.349224 -157.989524)
					(mid 394.422768 -158.048468)
					(end 394.478256 -158.124652)
				)
				(arc
					(start 394.478256 -158.124652)
					(mid 394.557615 -158.177363)
					(end 394.645642 -158.141162)
				)
				(arc
					(start 394.645642 -158.141162)
					(mid 394.921541 -158.012996)
					(end 395.195806 -158.144718)
				)
				(arc
					(start 395.195806 -158.144718)
					(mid 395.2748 -158.182381)
					(end 395.353794 -158.144718)
				)
				(arc
					(start 395.353794 -158.144718)
					(mid 395.615465 -158.013205)
					(end 395.887194 -158.122366)
				)
				(arc
					(start 395.887194 -158.122366)
					(mid 395.9606 -158.153687)
					(end 396.034006 -158.122366)
				)
				(arc
					(start 396.034006 -158.122366)
					(mid 396.296475 -158.013261)
					(end 396.555214 -158.131002)
				)
				(arc
					(start 396.864078 -158.131002)
					(mid 397.317865 -158.067079)
					(end 397.458946 -158.503112)
				)
				(arc
					(start 397.458946 -158.503112)
					(mid 397.454175 -158.518199)
					(end 397.451834 -158.533846)
				)
				(xy 397.5608 -158.642812)
				(arc
					(start 499.674896 -158.642812)
					(mid 500.835787 -158.238263)
					(end 501.49379 -157.199838)
				)
				(xy 501.49379 -112.117632) (xy 499.738142 -110.361984)
				(arc
					(start 488.199684 -110.361984)
					(mid 488.167428 -110.418728)
					(end 488.176316 -110.483396)
				)
				(arc
					(start 488.176316 -110.483396)
					(mid 488.036104 -110.950258)
					(end 487.561382 -110.839758)
				)
				(arc
					(start 487.561382 -110.839758)
					(mid 487.4768 -110.794491)
					(end 487.392218 -110.839758)
				)
				(arc
					(start 487.392218 -110.839758)
					(mid 487.0958 -110.998509)
					(end 486.799382 -110.839758)
				)
				(arc
					(start 486.799382 -110.839758)
					(mid 486.7148 -110.794491)
					(end 486.630218 -110.839758)
				)
				(arc
					(start 486.630218 -110.839758)
					(mid 486.155533 -110.950195)
					(end 486.015284 -110.483396)
				)
				(arc
					(start 486.015284 -110.483396)
					(mid 486.02184 -110.409088)
					(end 485.975914 -110.3503)
				)
				(xy 427.609 -110.3503) (xy 426.7327 -109.474) (xy 426.7327 -68.2752) (xy 427.58614 -67.42176)
				(arc
					(start 478.274634 -67.42176)
					(mid 478.746113 -67.250097)
					(end 478.996756 -66.815462)
				)
				(xy 478.996756 -63.077344) (xy 479.8695 -62.2046)
				(arc
					(start 499.928388 -62.2046)
					(mid 500.931764 -61.735775)
					(end 501.493282 -60.781184)
				)
				(xy 501.493282 -37.659818) (xy 501.542812 -37.610288) (xy 501.542812 -17.3736) (xy 501.542558 -17.3736)
				(xy 501.542558 -16.999966) (xy 501.541288 -16.96212) (xy 501.541288 -14.983968) (xy 501.01754 -14.46022)
				(xy 483.95382 -14.46022) (xy 483.39248 -13.89888)
				(arc
					(start 483.39248 0.500126)
					(mid 483.413538 0.699305)
					(end 483.475538 0.889762)
				)
				(xy 483.3874 0.9779) (xy 483.3874 2.90068) (xy 483.94874 3.46202) (xy 487.263186 3.46202) (xy 487.264456 3.463544)
				(xy 501.049544 3.463544) (xy 501.53824 3.95224) (xy 501.53824 5.05206) (xy 501.0531 5.5372) (xy 487.299 5.5372)
				(xy 487.29646 5.53466) (xy 478.874328 5.53466) (xy 478.864168 5.5245) (xy 355.0031 5.5245) (xy 354.7745 5.2959)
				(xy 354.2538 5.2959) (xy 354.2538 5.301488) (xy 354.0125 5.542788)
				(arc
					(start 167.242744 5.542788)
					(mid 167.156891 5.495519)
					(end 167.15105 5.397754)
				)
				(arc
					(start 167.15105 5.397754)
					(mid 166.828978 4.889408)
					(end 166.506906 5.397754)
				)
				(arc
					(start 166.506906 5.397754)
					(mid 166.500948 5.495444)
					(end 166.415212 5.542788)
				)
				(xy 115.829588 5.542788) (xy 115.595654 5.308854)
				(arc
					(start 115.595908 5.287518)
					(mid 115.320019 4.936218)
					(end 114.917982 5.1308)
				)
				(arc
					(start 114.723418 5.1308)
					(mid 114.289975 4.945208)
					(end 114.05235 5.352288)
				)
				(xy 114.053366 5.357368) (xy 114.058954 5.384546) (xy 113.900712 5.542788) (xy 17.489678 5.542788)
				(xy 17.166082 5.219192) (xy 17.079722 5.219192) (xy 16.860774 5.43814) (xy 16.860774 5.542788)
			)
		)
		(polygon
			(pts
				(arc
					(start 419.97884 -39.907718)
					(mid 419.890132 -39.855573)
					(end 419.801294 -39.907718)
				)
				(arc
					(start 419.801294 -39.907718)
					(mid 419.741821 -39.986305)
					(end 419.663118 -40.04564)
				)
				(arc
					(start 419.663118 -40.04564)
					(mid 419.610751 -40.13454)
					(end 419.663118 -40.22344)
				)
				(arc
					(start 419.663118 -40.22344)
					(mid 419.742797 -40.283649)
					(end 419.802564 -40.363648)
				)
				(arc
					(start 419.802564 -40.363648)
					(mid 419.888404 -40.416315)
					(end 419.977316 -40.369236)
				)
				(arc
					(start 419.977316 -40.369236)
					(mid 420.287789 -40.203992)
					(end 420.588694 -40.386)
				)
				(arc
					(start 420.588694 -40.386)
					(mid 420.68052 -40.437965)
					(end 420.769034 -40.380412)
				)
				(arc
					(start 420.769034 -40.380412)
					(mid 420.830772 -40.290455)
					(end 420.916862 -40.22344)
				)
				(arc
					(start 420.916862 -40.22344)
					(mid 420.969007 -40.134732)
					(end 420.916862 -40.045894)
				)
				(arc
					(start 420.916862 -40.045894)
					(mid 420.838274 -39.98656)
					(end 420.77894 -39.907972)
				)
				(arc
					(start 420.77894 -39.907972)
					(mid 420.690232 -39.855827)
					(end 420.601394 -39.907972)
				)
				(arc
					(start 420.601394 -39.907972)
					(mid 420.290071 -40.090865)
					(end 419.97884 -39.907718)
				)
			)
		)
		(polygon
			(pts
				(arc
					(start 419.178994 -40.707818)
					(mid 419.090286 -40.655673)
					(end 419.001448 -40.707818)
				)
				(arc
					(start 419.001448 -40.707818)
					(mid 418.943757 -40.784752)
					(end 418.86759 -40.843454)
				)
				(arc
					(start 418.86759 -40.843454)
					(mid 418.816553 -40.929546)
					(end 418.864034 -41.017698)
				)
				(arc
					(start 418.864034 -41.017698)
					(mid 418.916874 -41.580177)
					(end 418.359844 -41.485312)
				)
				(arc
					(start 418.359844 -41.485312)
					(mid 418.270779 -41.430988)
					(end 418.180774 -41.483788)
				)
				(arc
					(start 418.180774 -41.483788)
					(mid 417.884888 -41.66859)
					(end 417.573206 -41.511982)
				)
				(arc
					(start 417.573206 -41.511982)
					(mid 417.485647 -41.467421)
					(end 417.401248 -41.517824)
				)
				(arc
					(start 417.401248 -41.517824)
					(mid 417.343328 -41.592264)
					(end 417.267898 -41.648888)
				)
				(arc
					(start 417.267898 -41.648888)
					(mid 417.215884 -41.737077)
					(end 417.267136 -41.825672)
				)
				(arc
					(start 417.267136 -41.825672)
					(mid 417.343596 -41.884442)
					(end 417.401502 -41.961562)
				)
				(arc
					(start 417.401502 -41.961562)
					(mid 417.49034 -42.013799)
					(end 417.579048 -41.961562)
				)
				(arc
					(start 417.579048 -41.961562)
					(mid 417.890198 -41.778538)
					(end 418.201348 -41.961562)
				)
				(arc
					(start 418.201348 -41.961562)
					(mid 418.290186 -42.013799)
					(end 418.378894 -41.961562)
				)
				(arc
					(start 418.378894 -41.961562)
					(mid 418.690044 -41.778669)
					(end 419.001194 -41.961562)
				)
				(arc
					(start 419.001194 -41.961562)
					(mid 419.090032 -42.013929)
					(end 419.17874 -41.961562)
				)
				(arc
					(start 419.17874 -41.961562)
					(mid 419.238162 -41.882808)
					(end 419.316916 -41.823386)
				)
				(arc
					(start 419.316916 -41.823386)
					(mid 419.369061 -41.734678)
					(end 419.316916 -41.64584)
				)
				(arc
					(start 419.316916 -41.64584)
					(mid 419.134023 -41.334579)
					(end 419.31717 -41.02354)
				)
				(arc
					(start 419.31717 -41.02354)
					(mid 419.369537 -40.93464)
					(end 419.31717 -40.84574)
				)
				(arc
					(start 419.31717 -40.84574)
					(mid 419.238415 -40.786457)
					(end 419.178994 -40.707818)
				)
			)
		)
		(polygon
			(pts
				(arc
					(start 370.834158 -77.667866)
					(mid 370.745258 -77.615499)
					(end 370.656358 -77.667866)
				)
				(arc
					(start 370.656358 -77.667866)
					(mid 370.597075 -77.746621)
					(end 370.518436 -77.806042)
				)
				(arc
					(start 370.518436 -77.806042)
					(mid 370.466069 -77.89488)
					(end 370.518436 -77.983588)
				)
				(arc
					(start 370.518436 -77.983588)
					(mid 370.701329 -78.294849)
					(end 370.518182 -78.605888)
				)
				(arc
					(start 370.518182 -78.605888)
					(mid 370.465815 -78.694788)
					(end 370.518182 -78.783688)
				)
				(arc
					(start 370.518182 -78.783688)
					(mid 370.596936 -78.84311)
					(end 370.656358 -78.921864)
				)
				(arc
					(start 370.656358 -78.921864)
					(mid 370.745258 -78.974231)
					(end 370.834158 -78.921864)
				)
				(arc
					(start 370.834158 -78.921864)
					(mid 371.145197 -78.73884)
					(end 371.456458 -78.92161)
				)
				(arc
					(start 371.456458 -78.92161)
					(mid 371.545296 -78.973977)
					(end 371.634004 -78.92161)
				)
				(arc
					(start 371.634004 -78.92161)
					(mid 371.693338 -78.843022)
					(end 371.771926 -78.783688)
				)
				(arc
					(start 371.771926 -78.783688)
					(mid 371.824071 -78.69498)
					(end 371.771926 -78.606142)
				)
				(arc
					(start 371.771926 -78.606142)
					(mid 371.588902 -78.29493)
					(end 371.771926 -77.983588)
				)
				(arc
					(start 371.771926 -77.983588)
					(mid 371.823941 -77.89488)
					(end 371.771926 -77.806042)
				)
				(arc
					(start 371.771926 -77.806042)
					(mid 371.693338 -77.746708)
					(end 371.634004 -77.66812)
				)
				(arc
					(start 371.634004 -77.66812)
					(mid 371.545296 -77.615975)
					(end 371.456458 -77.66812)
				)
				(arc
					(start 371.456458 -77.66812)
					(mid 371.145197 -77.851013)
					(end 370.834158 -77.667866)
				)
			)
		)
		(polygon
			(pts
				(xy 19.143726 -55.6768) (xy 13.022834 -55.6768) (xy 12.114276 -56.585358) (xy 12.114276 -66.215006)
				(xy 14.799818 -68.900548) (xy 14.799818 -68.90639) (xy 18.930366 -68.90639) (xy 20.083526 -67.75323)
				(xy 20.083526 -56.6166)
			)
		)
		(polygon
			(pts
				(xy 9.982454 -48.76292) (xy 2.834386 -48.76292) (xy 1.802384 -49.794922) (xy 1.802384 -58.586878)
				(xy 0.540004 -59.849258) (xy 0.540004 -67.265296) (xy 2.24028 -68.965572) (xy 2.24028 -86.093046)
				(xy 3.618484 -87.47125) (xy 10.368026 -87.47125) (xy 11.362436 -86.47684) (xy 11.362436 -50.142902)
			)
		)
		(polygon
			(pts
				(arc
					(start 483.391972 -11.388852)
					(mid 483.338904 -11.309477)
					(end 483.243382 -11.309096)
				)
				(arc
					(start 483.243382 -11.309096)
					(mid 482.908897 -11.40638)
					(end 482.56317 -11.363706)
				)
				(arc
					(start 482.56317 -11.363706)
					(mid 482.467253 -11.380574)
					(end 482.429566 -11.470386)
				)
				(arc
					(start 482.429566 -11.470386)
					(mid 482.43382 -11.58555)
					(end 482.422708 -11.700256)
				)
				(arc
					(start 482.422708 -11.700256)
					(mid 482.458247 -11.795014)
					(end 482.55809 -11.812016)
				)
				(arc
					(start 482.55809 -11.812016)
					(mid 482.905572 -11.764346)
					(end 483.240842 -11.867388)
				)
				(arc
					(start 483.240842 -11.867388)
					(mid 483.337582 -11.869195)
					(end 483.391972 -11.789156)
				)
			)
		)
		(polygon
			(pts
				(arc
					(start 483.391972 -9.388856)
					(mid 483.338904 -9.309481)
					(end 483.243382 -9.3091)
				)
				(arc
					(start 483.243382 -9.3091)
					(mid 482.908897 -9.406384)
					(end 482.56317 -9.36371)
				)
				(arc
					(start 482.56317 -9.36371)
					(mid 482.467253 -9.380578)
					(end 482.429566 -9.47039)
				)
				(arc
					(start 482.429566 -9.47039)
					(mid 482.43382 -9.585554)
					(end 482.422708 -9.70026)
				)
				(arc
					(start 482.422708 -9.70026)
					(mid 482.458247 -9.795018)
					(end 482.55809 -9.81202)
				)
				(arc
					(start 482.55809 -9.81202)
					(mid 482.905572 -9.76435)
					(end 483.240842 -9.867392)
				)
				(arc
					(start 483.240842 -9.867392)
					(mid 483.337582 -9.869199)
					(end 483.391972 -9.78916)
				)
			)
		)
		(polygon
			(pts
				(arc
					(start 483.391972 -7.300976)
					(mid 483.337595 -7.220911)
					(end 483.240842 -7.222744)
				)
				(arc
					(start 483.240842 -7.222744)
					(mid 482.878878 -7.327443)
					(end 482.50856 -7.257796)
				)
				(arc
					(start 482.50856 -7.257796)
					(mid 482.403723 -7.271226)
					(end 482.36759 -7.370572)
				)
				(arc
					(start 482.36759 -7.370572)
					(mid 482.383385 -7.530084)
					(end 482.36759 -7.689596)
				)
				(arc
					(start 482.36759 -7.689596)
					(mid 482.403701 -7.788969)
					(end 482.50856 -7.802372)
				)
				(arc
					(start 482.50856 -7.802372)
					(mid 482.87888 -7.732689)
					(end 483.240842 -7.837424)
				)
				(arc
					(start 483.240842 -7.837424)
					(mid 483.337582 -7.839231)
					(end 483.391972 -7.759192)
				)
			)
		)
		(polygon
			(pts
				(arc
					(start 483.391972 -5.241036)
					(mid 483.337595 -5.160971)
					(end 483.240842 -5.162804)
				)
				(arc
					(start 483.240842 -5.162804)
					(mid 482.878878 -5.267503)
					(end 482.50856 -5.197856)
				)
				(arc
					(start 482.50856 -5.197856)
					(mid 482.403723 -5.211286)
					(end 482.36759 -5.310632)
				)
				(arc
					(start 482.36759 -5.310632)
					(mid 482.383385 -5.470144)
					(end 482.36759 -5.629656)
				)
				(arc
					(start 482.36759 -5.629656)
					(mid 482.403701 -5.729029)
					(end 482.50856 -5.742432)
				)
				(arc
					(start 482.50856 -5.742432)
					(mid 482.87888 -5.672749)
					(end 483.240842 -5.777484)
				)
				(arc
					(start 483.240842 -5.777484)
					(mid 483.337582 -5.779291)
					(end 483.391972 -5.699252)
				)
			)
		)
		(polygon
			(pts
				(arc
					(start 483.391972 -3.211068)
					(mid 483.337595 -3.131003)
					(end 483.240842 -3.132836)
				)
				(arc
					(start 483.240842 -3.132836)
					(mid 482.878878 -3.237535)
					(end 482.50856 -3.167888)
				)
				(arc
					(start 482.50856 -3.167888)
					(mid 482.403723 -3.181318)
					(end 482.36759 -3.280664)
				)
				(arc
					(start 482.36759 -3.280664)
					(mid 482.383385 -3.440176)
					(end 482.36759 -3.599688)
				)
				(arc
					(start 482.36759 -3.599688)
					(mid 482.403701 -3.699061)
					(end 482.50856 -3.712464)
				)
				(arc
					(start 482.50856 -3.712464)
					(mid 482.87888 -3.642781)
					(end 483.240842 -3.747516)
				)
				(arc
					(start 483.240842 -3.747516)
					(mid 483.337582 -3.749323)
					(end 483.391972 -3.669284)
				)
			)
		)
		(polygon
			(pts
				(arc
					(start 483.391972 -1.1811)
					(mid 483.337595 -1.101035)
					(end 483.240842 -1.102868)
				)
				(arc
					(start 483.240842 -1.102868)
					(mid 482.878878 -1.207567)
					(end 482.50856 -1.13792)
				)
				(arc
					(start 482.50856 -1.13792)
					(mid 482.403723 -1.15135)
					(end 482.36759 -1.250696)
				)
				(arc
					(start 482.36759 -1.250696)
					(mid 482.383385 -1.410208)
					(end 482.36759 -1.56972)
				)
				(arc
					(start 482.36759 -1.56972)
					(mid 482.403701 -1.669093)
					(end 482.50856 -1.682496)
				)
				(arc
					(start 482.50856 -1.682496)
					(mid 482.87888 -1.612813)
					(end 483.240842 -1.717548)
				)
				(arc
					(start 483.240842 -1.717548)
					(mid 483.337582 -1.719355)
					(end 483.391972 -1.639316)
				)
			)
		)
		(polygon
			(pts
				(arc
					(start 483.446836 0.819404)
					(mid 483.406802 0.927079)
					(end 483.291896 0.928624)
				)
				(arc
					(start 483.291896 0.928624)
					(mid 482.908809 0.794446)
					(end 482.50856 0.862076)
				)
				(arc
					(start 482.50856 0.862076)
					(mid 482.403723 0.848646)
					(end 482.36759 0.7493)
				)
				(arc
					(start 482.36759 0.7493)
					(mid 482.383385 0.589788)
					(end 482.36759 0.430276)
				)
				(arc
					(start 482.36759 0.430276)
					(mid 482.403701 0.330903)
					(end 482.50856 0.3175)
				)
				(arc
					(start 482.50856 0.3175)
					(mid 482.87888 0.387183)
					(end 483.240842 0.282448)
				)
				(arc
					(start 483.240842 0.282448)
					(mid 483.337582 0.280641)
					(end 483.391972 0.36068)
				)
				(arc
					(start 483.391972 0.500126)
					(mid 483.40581 0.662101)
					(end 483.446836 0.819404)
				)
			)
		)
	)
	(zone
		(net "PVDDQ_GHJ")
		(layer "In10.Cu")
		(hatch none 0.5)
		(connect_pads
			(clearance 0.5)
		)
		(min_thickness 0.25)
		(fill yes
			(thermal_gap 0.5)
			(thermal_bridge_width 0.5)
			(island_removal_mode 0)
		)
		(polygon
			(pts
				(xy 78.5495 2.753868) (xy 78.489302 2.693924) (xy 78.199996 2.404872)
				(arc
					(start 78.199996 2.280412)
					(mid 78.227023 2.211408)
					(end 78.293722 2.179066)
				)
				(arc
					(start 78.293722 2.179066)
					(mid 78.627895 1.82372)
					(end 78.293722 1.468374)
				)
				(arc
					(start 78.293722 1.468374)
					(mid 78.226986 1.436066)
					(end 78.199996 1.367028)
				)
				(xy 78.199996 0.82296)
				(arc
					(start 78.238096 0.813054)
					(mid 78.402301 0.718926)
					(end 78.495144 0.553974)
				)
				(arc
					(start 78.495144 0.553974)
					(mid 78.475302 0.324263)
					(end 78.318868 0.15494)
				)
				(arc
					(start 78.318868 -2.049018)
					(mid 78.505519 -2.3622)
					(end 78.318868 -2.675382)
				)
				(xy 78.318868 -3.00609)
				(arc
					(start 78.352142 -3.018282)
					(mid 78.582662 -3.402152)
					(end 78.255622 -3.707892)
				)
				(arc
					(start 78.255622 -3.707892)
					(mid 78.158045 -3.701477)
					(end 78.065884 -3.668776)
				)
				(xy 78.032864 -3.651504) (xy 77.848968 -3.8354)
				(arc
					(start 77.848968 -3.93446)
					(mid 77.895237 -4.019672)
					(end 77.99197 -4.027424)
				)
				(arc
					(start 77.99197 -4.027424)
					(mid 78.492754 -4.332478)
					(end 77.99197 -4.637532)
				)
				(arc
					(start 77.99197 -4.637532)
					(mid 77.895146 -4.645144)
					(end 77.848968 -4.730496)
				)
				(xy 77.848968 -6.731) (xy 77.950822 -6.832854)
				(arc
					(start 77.98435 -6.814566)
					(mid 78.452706 -6.954657)
					(end 78.306168 -7.421118)
				)
				(xy 78.306168 -7.798562)
				(arc
					(start 78.344268 -7.808468)
					(mid 78.611572 -8.1534)
					(end 78.344268 -8.498332)
				)
				(xy 78.306168 -8.508238)
				(arc
					(start 78.306168 -8.813292)
					(mid 78.505573 -9.133078)
					(end 78.306168 -9.452864)
				)
				(xy 78.306168 -12.537948)
				(arc
					(start 78.332584 -12.5476)
					(mid 78.575354 -12.882073)
					(end 78.338426 -13.2207)
				)
				(xy 78.327758 -13.22451) (xy 78.166468 -13.3858) (xy 78.166468 -13.587984)
				(arc
					(start 78.208632 -13.59535)
					(mid 78.361473 -13.663466)
					(end 78.463902 -13.795756)
				)
				(arc
					(start 78.463902 -13.795756)
					(mid 78.468409 -14.06083)
					(end 78.2828 -14.250162)
				)
				(arc
					(start 78.2828 -14.250162)
					(mid 78.226389 -14.324634)
					(end 78.254606 -14.413738)
				)
				(xy 78.255368 -14.4145) (xy 78.255368 -16.878554)
				(arc
					(start 78.287372 -16.886174)
					(mid 78.543312 -17.124895)
					(end 78.457044 -17.464024)
				)
				(arc
					(start 78.457044 -17.464024)
					(mid 78.427794 -17.537373)
					(end 78.459838 -17.609566)
				)
				(arc
					(start 78.459838 -17.609566)
					(mid 78.573877 -17.974171)
					(end 78.292198 -18.23212)
				)
				(xy 78.255368 -18.239232) (xy 78.255368 -18.410936)
				(arc
					(start 78.28407 -18.424906)
					(mid 78.481843 -18.701764)
					(end 78.356968 -19.01825)
				)
				(xy 78.356968 -21.849842)
				(arc
					(start 78.384146 -21.859494)
					(mid 78.630143 -22.194462)
					(end 78.391004 -22.534372)
				)
				(xy 78.356968 -22.54631) (xy 78.356968 -23.0759)
				(arc
					(start 78.342744 -23.090124)
					(mid 78.31351 -23.1703)
					(end 78.355698 -23.244556)
				)
				(arc
					(start 78.355698 -23.244556)
					(mid 78.399592 -23.281395)
					(end 78.436978 -23.32482)
				)
				(arc
					(start 78.436978 -23.32482)
					(mid 78.478103 -23.671933)
					(end 78.202536 -23.886922)
				)
				(xy 78.166468 -23.893272) (xy 78.166468 -25.1968) (xy 78.489302 -25.519634) (xy 78.489302 -26.766774)
				(xy 86.076536 -34.354008) (xy 86.076536 -51.039268) (xy 86.497668 -51.4604)
				(arc
					(start 86.497668 -51.800252)
					(mid 86.56047 -51.894153)
					(end 86.67115 -51.87188)
				)
				(arc
					(start 86.67115 -51.87188)
					(mid 87.279529 -52.12334)
					(end 86.67115 -52.3748)
				)
				(arc
					(start 86.67115 -52.3748)
					(mid 86.560517 -52.352641)
					(end 86.497668 -52.446428)
				)
				(arc
					(start 86.497668 -52.790598)
					(mid 86.56047 -52.884499)
					(end 86.67115 -52.862226)
				)
				(arc
					(start 86.67115 -52.862226)
					(mid 87.272983 -53.181657)
					(end 86.595204 -53.25237)
				)
				(xy 86.58225 -53.221128) (xy 86.497668 -53.221128) (xy 86.497668 -53.380132) (xy 86.807802 -53.690266)
				(xy 87.076534 -53.690266) (xy 87.323168 -53.9369) (xy 87.323168 -63.1698)
				(arc
					(start 87.401908 -63.24854)
					(mid 87.471363 -63.278286)
					(end 87.542116 -63.251842)
				)
				(arc
					(start 87.542116 -63.251842)
					(mid 87.877034 -63.171992)
					(end 88.123014 -63.412878)
				)
				(xy 88.133936 -63.4492)
				(arc
					(start 88.321134 -63.4492)
					(mid 88.414512 -63.387638)
					(end 88.394794 -63.277496)
				)
				(arc
					(start 88.394794 -63.277496)
					(mid 88.640412 -62.663604)
					(end 88.88603 -63.277496)
				)
				(arc
					(start 88.88603 -63.277496)
					(mid 88.866231 -63.387673)
					(end 88.95969 -63.4492)
				)
				(xy 89.146634 -63.4492)
				(arc
					(start 89.157556 -63.412878)
					(mid 89.498678 -63.159091)
					(end 89.8398 -63.412878)
				)
				(xy 89.850722 -63.4492)
				(arc
					(start 90.03792 -63.4492)
					(mid 90.131298 -63.387638)
					(end 90.11158 -63.277496)
				)
				(arc
					(start 90.11158 -63.277496)
					(mid 90.357198 -62.663604)
					(end 90.602816 -63.277496)
				)
				(arc
					(start 90.602816 -63.277496)
					(mid 90.583017 -63.387673)
					(end 90.676476 -63.4492)
				)
				(xy 90.863674 -63.4492)
				(arc
					(start 90.874596 -63.412878)
					(mid 91.215718 -63.159091)
					(end 91.55684 -63.412878)
				)
				(xy 91.567762 -63.4492)
				(arc
					(start 91.75496 -63.4492)
					(mid 91.848338 -63.387638)
					(end 91.82862 -63.277496)
				)
				(arc
					(start 91.82862 -63.277496)
					(mid 91.762141 -62.848252)
					(end 92.16009 -62.673992)
				)
				(arc
					(start 92.16009 -62.673992)
					(mid 92.42986 -62.996349)
					(end 92.20454 -63.351156)
				)
				(xy 92.172282 -63.363856) (xy 92.172282 -63.4492) (xy 92.312998 -63.4492) (xy 92.338398 -63.4238)
				(xy 92.58681 -63.4238)
				(arc
					(start 92.599002 -63.39078)
					(mid 92.932758 -63.159033)
					(end 93.266514 -63.39078)
				)
				(xy 93.278706 -63.4238)
				(arc
					(start 93.44787 -63.4238)
					(mid 93.469033 -63.421517)
					(end 93.489272 -63.41491)
				)
				(xy 94.023688 -63.41491) (xy 94.054422 -63.384176) (xy 94.340426 -63.098172) (xy 94.926404 -63.098172)
				(xy 95.037148 -63.208916) (xy 95.037148 -63.734188) (xy 99.01174 -67.70878) (xy 106.03738 -67.70878)
				(xy 106.037888 -67.708272) (xy 108.419392 -67.708272) (xy 108.650024 -67.47764) (xy 108.650024 -66.9544)
				(xy 108.446824 -66.7512) (xy 107.5436 -66.7512) (xy 107.4928 -66.7004) (xy 107.4928 -65.65646) (xy 107.335574 -65.499234)
				(xy 106.4006 -64.56426) (xy 104.462834 -62.626494) (xy 104.462834 -62.108334) (xy 104.462834 -50.964846)
				(xy 105.761536 -49.666144) (xy 105.761536 -36.162996) (xy 113.866168 -28.058364) (xy 113.866168 -23.1775)
				(arc
					(start 113.834418 -23.1648)
					(mid 113.611658 -22.8346)
					(end 113.834418 -22.5044)
				)
				(xy 113.866168 -22.4917) (xy 113.866168 -22.013926)
				(arc
					(start 113.831878 -22.002242)
					(mid 113.590784 -21.665184)
					(end 113.831878 -21.328126)
				)
				(xy 113.866168 -21.316442) (xy 113.866168 -19.04111)
				(arc
					(start 113.83137 -19.029426)
					(mid 113.594576 -18.759734)
					(end 113.712752 -18.420842)
				)
				(arc
					(start 113.712752 -18.420842)
					(mid 113.748108 -18.345682)
					(end 113.715546 -18.269204)
				)
				(arc
					(start 113.715546 -18.269204)
					(mid 113.602017 -18.033109)
					(end 113.680748 -17.783302)
				)
				(arc
					(start 113.680748 -17.783302)
					(mid 113.705547 -17.755777)
					(end 113.733072 -17.730978)
				)
				(arc
					(start 113.733072 -17.730978)
					(mid 113.768637 -17.65368)
					(end 113.733072 -17.576292)
				)
				(arc
					(start 113.733072 -17.576292)
					(mid 113.627942 -17.44411)
					(end 113.595404 -17.27835)
				)
				(arc
					(start 113.595404 -17.27835)
					(mid 113.665194 -17.082558)
					(end 113.832386 -16.959072)
				)
				(xy 113.866168 -16.947134)
				(arc
					(start 113.866168 -14.251432)
					(mid 113.683144 -13.940282)
					(end 113.866168 -13.629132)
				)
				(xy 113.866168 -13.308838)
				(arc
					(start 113.828068 -13.298932)
					(mid 113.560764 -12.954)
					(end 113.828068 -12.609068)
				)
				(xy 113.866168 -12.599162) (xy 113.866168 -12.285218)
				(arc
					(start 113.82883 -12.275058)
					(mid 113.567148 -11.93165)
					(end 113.82883 -11.588242)
				)
				(xy 113.866168 -11.578082) (xy 113.866168 -9.440418)
				(arc
					(start 113.825528 -9.432036)
					(mid 113.563159 -9.206573)
					(end 113.615978 -8.8646)
				)
				(arc
					(start 113.615978 -8.8646)
					(mid 113.675187 -8.804748)
					(end 113.746788 -8.76046)
				)
				(arc
					(start 113.746788 -8.76046)
					(mid 113.80416 -8.685956)
					(end 113.775744 -8.596376)
				)
				(xy 113.434368 -8.255)
				(arc
					(start 113.434368 -7.431278)
					(mid 113.370233 -7.336838)
					(end 113.258854 -7.361682)
				)
				(arc
					(start 113.258854 -7.361682)
					(mid 112.844311 -7.438128)
					(end 112.647222 -7.065518)
				)
				(arc
					(start 112.647222 -7.065518)
					(mid 112.965756 -6.763067)
					(end 113.335562 -6.999986)
				)
				(xy 113.3475 -7.034022) (xy 113.434368 -7.034022) (xy 113.434368 -6.858) (xy 113.866168 -6.4262)
				(xy 113.866168 -5.08) (xy 113.383568 -4.5974) (xy 113.383568 -4.515612) (xy 113.306352 -4.515612)
				(arc
					(start 113.291112 -4.537202)
					(mid 112.647153 -4.383658)
					(end 113.22177 -4.054856)
				)
				(arc
					(start 113.22177 -4.054856)
					(mid 113.327952 -4.063589)
					(end 113.383568 -3.972814)
				)
				(arc
					(start 113.383568 -2.67716)
					(mid 113.327881 -2.586526)
					(end 113.22177 -2.595118)
				)
				(arc
					(start 113.22177 -2.595118)
					(mid 112.777036 -2.594931)
					(end 112.67948 -2.161032)
				)
				(arc
					(start 112.67948 -2.161032)
					(mid 113.092015 -1.972892)
					(end 113.354866 -2.342134)
				)
				(arc
					(start 113.354866 -2.342134)
					(mid 113.413988 -2.441651)
					(end 113.52784 -2.421128)
				)
				(xy 113.866168 -2.0828) (xy 113.866168 0.880872) (xy 113.866168 1.221232) (xy 111.82858 3.25882)
				(xy 102.21976 3.25882) (xy 100.94468 1.98374) (xy 100.363528 1.98374) (xy 100.226114 2.121154)
				(arc
					(start 100.203508 2.116582)
					(mid 99.963629 2.146318)
					(end 99.79787 2.322322)
				)
				(xy 99.786694 2.34696)
				(arc
					(start 99.605592 2.34696)
					(mid 99.529393 2.312564)
					(end 99.504754 2.23266)
				)
				(arc
					(start 99.504754 2.23266)
					(mid 99.51183 2.167044)
					(end 99.514152 2.101088)
				)
				(arc
					(start 99.514152 0.856488)
					(mid 98.599498 -0.058166)
					(end 97.684844 0.856488)
				)
				(arc
					(start 97.684844 2.101088)
					(mid 97.68687 2.162184)
					(end 97.692972 2.223008)
				)
				(arc
					(start 97.692972 2.223008)
					(mid 97.668145 2.302574)
					(end 97.592134 2.3368)
				)
				(xy 94.841568 2.3368)
				(arc
					(start 94.79788 2.380488)
					(mid 94.706807 2.408435)
					(end 94.632526 2.348738)
				)
				(arc
					(start 94.632526 2.348738)
					(mid 94.165976 2.144333)
					(end 93.972126 2.615184)
				)
				(arc
					(start 93.972126 2.615184)
					(mid 93.961505 2.709448)
					(end 93.877638 2.753868)
				)
				(arc
					(start 93.0529 2.753868)
					(mid 92.969571 2.710395)
					(end 92.95765 2.617216)
				)
				(arc
					(start 92.95765 2.617216)
					(mid 92.756354 2.137829)
					(end 92.263722 2.304288)
				)
				(arc
					(start 92.263722 2.304288)
					(mid 92.174508 2.357406)
					(end 92.08516 2.304288)
				)
				(arc
					(start 92.08516 2.304288)
					(mid 91.592491 2.137748)
					(end 91.391232 2.617216)
				)
				(arc
					(start 91.391232 2.617216)
					(mid 91.379225 2.710335)
					(end 91.295982 2.753868)
				)
				(arc
					(start 89.662508 2.753868)
					(mid 89.581375 2.713423)
					(end 89.564972 2.624328)
				)
				(arc
					(start 89.564972 2.624328)
					(mid 89.199466 2.133306)
					(end 88.83396 2.624328)
				)
				(arc
					(start 88.83396 2.624328)
					(mid 88.817445 2.713338)
					(end 88.736424 2.753868)
				)
				(arc
					(start 87.952834 2.753868)
					(mid 87.869505 2.710395)
					(end 87.857584 2.617216)
				)
				(arc
					(start 87.857584 2.617216)
					(mid 87.499444 2.1041)
					(end 87.141304 2.617216)
				)
				(arc
					(start 87.141304 2.617216)
					(mid 87.129297 2.710335)
					(end 87.046054 2.753868)
				)
				(arc
					(start 84.55279 2.753868)
					(mid 84.469461 2.710395)
					(end 84.45754 2.617216)
				)
				(arc
					(start 84.45754 2.617216)
					(mid 84.0994 2.1041)
					(end 83.74126 2.617216)
				)
				(arc
					(start 83.74126 2.617216)
					(mid 83.729253 2.710335)
					(end 83.64601 2.753868)
				)
				(arc
					(start 82.86242 2.753868)
					(mid 82.781287 2.713423)
					(end 82.764884 2.624328)
				)
				(arc
					(start 82.764884 2.624328)
					(mid 82.399378 2.133306)
					(end 82.033872 2.624328)
				)
				(arc
					(start 82.033872 2.624328)
					(mid 82.017357 2.713338)
					(end 81.936336 2.753868)
				)
			)
		)
	)
	(zone
		(layer "In10.Cu")
		(hatch none 0.5)
		(connect_pads
			(clearance 0)
		)
		(min_thickness 0.25)
		(keepout
			(tracks allowed)
			(vias allowed)
			(pads allowed)
			(copperpour allowed)
			(footprints allowed)
		)
		(placement
			(enabled no)
			(sheetname "")
		)
		(fill
			(thermal_gap 0.5)
			(thermal_bridge_width 0.5)
			(island_removal_mode 0)
		)
		(polygon
			(pts
				(xy 234.109768 -103.79583) (xy 301.211996 -103.79583) (xy 309.967884 -95.039942) (xy 309.967884 -54.986682)
				(xy 305.894486 -50.913284) (xy 256.356358 -50.913284) (xy 253.928626 -48.485552) (xy 235.268262 -48.485552)
				(xy 230.951278 -52.802536) (xy 230.951278 -100.63734)
			)
		)
	)
	(zone
		(net "PVDDQ_KLM")
		(layer "In10.Cu")
		(hatch none 0.5)
		(connect_pads
			(clearance 0.5)
		)
		(min_thickness 0.25)
		(fill yes
			(thermal_gap 0.5)
			(thermal_bridge_width 0.5)
			(island_removal_mode 0)
		)
		(polygon
			(pts
				(xy 88.974422 -89.576402) (xy 88.161368 -90.389456) (xy 88.161368 -95.69704)
				(arc
					(start 88.041226 -95.817182)
					(mid 88.011459 -95.887807)
					(end 88.039448 -95.959168)
				)
				(arc
					(start 88.039448 -95.959168)
					(mid 88.033922 -96.45707)
					(end 87.53602 -96.462596)
				)
				(arc
					(start 87.53602 -96.462596)
					(mid 87.464659 -96.434576)
					(end 87.394034 -96.464374)
				)
				(xy 87.264494 -96.593914)
				(arc
					(start 87.27059 -96.621346)
					(mid 87.23992 -96.863051)
					(end 87.06104 -97.028508)
				)
				(xy 87.051642 -97.032572) (xy 87.008716 -97.075752) (xy 87.030052 -97.096834) (xy 87.030052 -97.34931)
				(arc
					(start 87.061294 -97.362264)
					(mid 87.26184 -97.802151)
					(end 86.839044 -98.036634)
				)
				(xy 86.811358 -98.029776) (xy 86.567264 -98.27387)
				(arc
					(start 86.567264 -98.300794)
					(mid 86.620923 -98.390372)
					(end 86.725252 -98.385376)
				)
				(arc
					(start 86.725252 -98.385376)
					(mid 87.275207 -98.736297)
					(end 86.64448 -98.90252)
				)
				(xy 86.625684 -98.879152)
				(arc
					(start 86.567264 -98.889058)
					(mid 86.537763 -98.898908)
					(end 86.512654 -98.917252)
				)
				(xy 85.856572 -99.573334) (xy 85.856572 -118.265702) (xy 78.745334 -125.37694)
				(arc
					(start 78.745334 -129.110486)
					(mid 78.787462 -129.192861)
					(end 78.878938 -129.207006)
				)
				(arc
					(start 78.878938 -129.207006)
					(mid 79.380783 -129.568956)
					(end 78.878938 -129.930906)
				)
				(arc
					(start 78.878938 -129.930906)
					(mid 78.787411 -129.94498)
					(end 78.745334 -130.027426)
				)
				(xy 78.745334 -130.359404) (xy 78.283562 -130.821176) (xy 78.283562 -131.255008)
				(arc
					(start 78.311248 -131.269232)
					(mid 78.505573 -131.586478)
					(end 78.311248 -131.903724)
				)
				(xy 78.283562 -131.917948) (xy 78.283562 -133.985)
				(arc
					(start 78.327758 -133.990842)
					(mid 78.6202 -134.270125)
					(end 78.44409 -134.634224)
				)
				(arc
					(start 78.44409 -134.634224)
					(mid 78.391381 -134.708816)
					(end 78.41996 -134.795514)
				)
				(xy 78.488032 -134.863586)
				(arc
					(start 78.488032 -135.162036)
					(mid 78.586059 -135.4074)
					(end 78.488032 -135.652764)
				)
				(xy 78.488032 -136.276588)
				(arc
					(start 78.490318 -136.2837)
					(mid 78.505649 -136.387078)
					(end 78.490318 -136.490456)
				)
				(xy 78.488032 -136.497568) (xy 78.488032 -139.13231)
				(arc
					(start 78.490318 -139.139422)
					(mid 78.505649 -139.2428)
					(end 78.490318 -139.346178)
				)
				(xy 78.488032 -139.35329)
				(arc
					(start 78.488032 -139.936728)
					(mid 78.601745 -140.298586)
					(end 78.32471 -140.557758)
				)
				(xy 78.283562 -140.565632) (xy 78.283562 -140.870178)
				(arc
					(start 78.310486 -140.884402)
					(mid 78.492829 -141.187678)
					(end 78.310486 -141.490954)
				)
				(xy 78.283562 -141.505178) (xy 78.283562 -143.6116)
				(arc
					(start 78.320646 -143.622014)
					(mid 78.571393 -143.952722)
					(end 78.320646 -144.28343)
				)
				(xy 78.283562 -144.293844) (xy 78.283562 -144.53235) (xy 78.281784 -144.534128) (xy 78.281784 -144.676114)
				(xy 78.30058 -144.69491) (xy 78.39837 -144.69491)
				(arc
					(start 78.543912 -144.840452)
					(mid 78.504859 -145.235027)
					(end 78.125066 -145.34896)
				)
				(arc
					(start 78.125066 -145.34896)
					(mid 78.034807 -145.364268)
					(end 77.993494 -145.445988)
				)
				(arc
					(start 77.993494 -145.533872)
					(mid 78.027607 -145.60982)
					(end 78.107032 -145.63471)
				)
				(arc
					(start 78.107032 -145.63471)
					(mid 78.505553 -145.988278)
					(end 78.107032 -146.341846)
				)
				(arc
					(start 78.107032 -146.341846)
					(mid 78.027645 -146.366779)
					(end 77.993494 -146.442684)
				)
				(arc
					(start 77.993494 -148.989796)
					(mid 78.031434 -149.068979)
					(end 78.116938 -149.08911)
				)
				(arc
					(start 78.116938 -149.08911)
					(mid 78.508319 -149.270764)
					(end 78.437232 -149.696424)
				)
				(arc
					(start 78.437232 -149.696424)
					(mid 78.40532 -149.772047)
					(end 78.439772 -149.846538)
				)
				(arc
					(start 78.439772 -149.846538)
					(mid 78.560358 -150.130442)
					(end 78.414118 -150.402036)
				)
				(arc
					(start 78.414118 -150.402036)
					(mid 78.37261 -150.474612)
					(end 78.39964 -150.553674)
				)
				(arc
					(start 78.39964 -150.553674)
					(mid 78.468294 -150.91637)
					(end 78.1685 -151.131778)
				)
				(arc
					(start 78.1685 -151.131778)
					(mid 78.100368 -151.163356)
					(end 78.072488 -151.233124)
				)
				(arc
					(start 78.072488 -153.78684)
					(mid 78.11043 -153.865771)
					(end 78.195678 -153.8859)
				)
				(arc
					(start 78.195678 -153.8859)
					(mid 78.628103 -154.23388)
					(end 78.195678 -154.58186)
				)
				(arc
					(start 78.195678 -154.58186)
					(mid 78.11041 -154.601963)
					(end 78.072488 -154.68092)
				)
				(xy 78.072488 -154.74188) (xy 79.165704 -155.835096)
				(arc
					(start 82.896202 -155.835096)
					(mid 82.915721 -155.784159)
					(end 82.906108 -155.730448)
				)
				(arc
					(start 82.906108 -155.730448)
					(mid 83.249516 -155.182492)
					(end 83.592924 -155.730448)
				)
				(arc
					(start 83.592924 -155.730448)
					(mid 83.598332 -155.828616)
					(end 83.684364 -155.876244)
				)
				(arc
					(start 84.51469 -155.876244)
					(mid 84.600756 -155.828637)
					(end 84.60613 -155.730448)
				)
				(arc
					(start 84.60613 -155.730448)
					(mid 84.949538 -155.182492)
					(end 85.292946 -155.730448)
				)
				(arc
					(start 85.292946 -155.730448)
					(mid 85.298354 -155.828616)
					(end 85.384386 -155.876244)
				)
				(arc
					(start 87.927942 -155.876244)
					(mid 88.015571 -155.826062)
					(end 88.016588 -155.725114)
				)
				(arc
					(start 88.016588 -155.725114)
					(mid 88.349582 -155.157045)
					(end 88.682576 -155.725114)
				)
				(arc
					(start 88.682576 -155.725114)
					(mid 88.683641 -155.826034)
					(end 88.771222 -155.876244)
				)
				(arc
					(start 89.62771 -155.876244)
					(mid 89.715339 -155.826062)
					(end 89.716356 -155.725114)
				)
				(arc
					(start 89.716356 -155.725114)
					(mid 90.04935 -155.157423)
					(end 90.382344 -155.725114)
				)
				(arc
					(start 90.382344 -155.725114)
					(mid 90.383409 -155.826034)
					(end 90.47099 -155.876244)
				)
				(arc
					(start 91.345512 -155.876244)
					(mid 91.435151 -155.822945)
					(end 91.430602 -155.718764)
				)
				(arc
					(start 91.430602 -155.718764)
					(mid 91.553803 -155.181264)
					(end 92.08516 -155.328112)
				)
				(arc
					(start 92.08516 -155.328112)
					(mid 92.174508 -155.381453)
					(end 92.263722 -155.328112)
				)
				(arc
					(start 92.263722 -155.328112)
					(mid 92.794963 -155.181458)
					(end 92.91828 -155.718764)
				)
				(arc
					(start 92.91828 -155.718764)
					(mid 92.913744 -155.822938)
					(end 93.00337 -155.876244)
				)
				(arc
					(start 93.862144 -155.876244)
					(mid 93.949015 -155.827332)
					(end 93.952314 -155.727654)
				)
				(arc
					(start 93.952314 -155.727654)
					(mid 94.040259 -155.289405)
					(end 94.487238 -155.282392)
				)
				(arc
					(start 94.487238 -155.282392)
					(mid 94.590532 -155.295618)
					(end 94.651068 -155.211018)
				)
				(arc
					(start 94.651068 -155.211018)
					(mid 95.332317 -155.098837)
					(end 94.786704 -155.521914)
				)
				(arc
					(start 94.786704 -155.521914)
					(mid 94.68341 -155.508688)
					(end 94.622874 -155.593288)
				)
				(arc
					(start 94.622874 -155.593288)
					(mid 94.60997 -155.662407)
					(end 94.583758 -155.727654)
				)
				(arc
					(start 94.583758 -155.727654)
					(mid 94.58699 -155.827373)
					(end 94.673928 -155.876244)
				)
				(xy 95.959168 -155.876244) (xy 97.373186 -155.876244) (xy 97.684844 -155.564586) (xy 97.684844 -155.128468)
				(arc
					(start 97.684844 -153.956512)
					(mid 98.599498 -153.041858)
					(end 99.514152 -153.956512)
				)
				(arc
					(start 99.514152 -155.201112)
					(mid 99.47336 -155.471217)
					(end 99.35464 -155.71724)
				)
				(arc
					(start 99.35464 -155.71724)
					(mid 99.348591 -155.822021)
					(end 99.43846 -155.876244)
				)
				(arc
					(start 99.793298 -155.876244)
					(mid 99.87614 -155.833463)
					(end 99.88931 -155.741116)
				)
				(arc
					(start 99.88931 -155.741116)
					(mid 100.249228 -155.233464)
					(end 100.609146 -155.741116)
				)
				(arc
					(start 100.609146 -155.741116)
					(mid 100.622236 -155.83352)
					(end 100.705158 -155.876244)
				)
				(arc
					(start 101.493574 -155.876244)
					(mid 101.576441 -155.833429)
					(end 101.589332 -155.741116)
				)
				(arc
					(start 101.589332 -155.741116)
					(mid 101.949504 -155.233562)
					(end 102.309676 -155.741116)
				)
				(arc
					(start 102.309676 -155.741116)
					(mid 102.322683 -155.833347)
					(end 102.405434 -155.876244)
				)
				(arc
					(start 104.893364 -155.876244)
					(mid 104.976206 -155.833463)
					(end 104.989376 -155.741116)
				)
				(arc
					(start 104.989376 -155.741116)
					(mid 105.349294 -155.233464)
					(end 105.709212 -155.741116)
				)
				(arc
					(start 105.709212 -155.741116)
					(mid 105.722302 -155.83352)
					(end 105.805224 -155.876244)
				)
				(xy 106.220514 -155.876244) (xy 106.801158 -155.2956) (xy 106.891328 -155.2956)
				(arc
					(start 106.901234 -155.291028)
					(mid 107.049316 -155.258778)
					(end 107.197398 -155.291028)
				)
				(xy 107.207304 -155.2956) (xy 107.341924 -155.2956) (xy 107.77728 -155.730956)
				(arc
					(start 108.266484 -155.730956)
					(mid 108.339395 -155.700113)
					(end 108.368084 -155.626308)
				)
				(arc
					(start 108.368084 -155.626308)
					(mid 108.749338 -155.233453)
					(end 109.130592 -155.626308)
				)
				(arc
					(start 109.130592 -155.626308)
					(mid 109.159248 -155.700145)
					(end 109.232192 -155.730956)
				)
				(arc
					(start 109.966506 -155.730956)
					(mid 110.039417 -155.700113)
					(end 110.068106 -155.626308)
				)
				(arc
					(start 110.068106 -155.626308)
					(mid 110.44936 -155.233453)
					(end 110.830614 -155.626308)
				)
				(arc
					(start 110.830614 -155.626308)
					(mid 110.85927 -155.700145)
					(end 110.932214 -155.730956)
				)
				(xy 112.596168 -155.730956) (xy 112.939576 -155.387548) (xy 112.939576 -155.28417)
				(arc
					(start 112.90173 -155.274264)
					(mid 112.617968 -154.905456)
					(end 112.90173 -154.536648)
				)
				(xy 112.939576 -154.526742) (xy 112.939576 -153.95067)
				(arc
					(start 112.90173 -153.940764)
					(mid 112.617968 -153.571956)
					(end 112.90173 -153.203148)
				)
				(xy 112.939576 -153.193242) (xy 112.939576 -151.378412) (xy 112.94364 -151.374348) (xy 112.94364 -151.143208)
				(arc
					(start 112.906048 -151.133048)
					(mid 112.643373 -150.789386)
					(end 112.906048 -150.445724)
				)
				(xy 112.94364 -150.435564) (xy 112.94364 -149.12721)
				(arc
					(start 112.906048 -149.11705)
					(mid 112.643373 -148.773388)
					(end 112.906048 -148.429726)
				)
				(xy 112.94364 -148.419566) (xy 112.94364 -147.992592) (xy 114.148362 -146.78787)
				(arc
					(start 114.148362 -146.412712)
					(mid 114.102622 -146.327846)
					(end 114.00663 -146.319494)
				)
				(arc
					(start 114.00663 -146.319494)
					(mid 113.509783 -145.992342)
					(end 114.00663 -145.66519)
				)
				(arc
					(start 114.00663 -145.66519)
					(mid 114.102562 -145.656746)
					(end 114.148362 -145.571972)
				)
				(arc
					(start 114.148362 -144.989804)
					(mid 114.100995 -144.90389)
					(end 114.003074 -144.89811)
				)
				(arc
					(start 114.003074 -144.89811)
					(mid 113.493237 -144.5768)
					(end 114.003074 -144.25549)
				)
				(arc
					(start 114.003074 -144.25549)
					(mid 114.100979 -144.249685)
					(end 114.148362 -144.163796)
				)
				(arc
					(start 114.148362 -140.93825)
					(mid 114.112115 -140.860458)
					(end 114.029236 -140.838174)
				)
				(arc
					(start 114.029236 -140.838174)
					(mid 113.611649 -140.4874)
					(end 114.029236 -140.136626)
				)
				(arc
					(start 114.029236 -140.136626)
					(mid 114.112114 -140.114341)
					(end 114.148362 -140.03655)
				)
				(xy 114.148362 -139.976098) (xy 114.086132 -139.976098)
				(arc
					(start 114.075718 -139.981178)
					(mid 113.566675 -139.690426)
					(end 114.019076 -139.317476)
				)
				(arc
					(start 114.019076 -139.317476)
					(mid 114.107961 -139.300828)
					(end 114.148362 -139.21994)
				)
				(arc
					(start 114.148362 -136.761728)
					(mid 114.106103 -136.679259)
					(end 114.014504 -136.665462)
				)
				(arc
					(start 114.014504 -136.665462)
					(mid 113.590352 -136.500518)
					(end 113.674652 -136.053322)
				)
				(arc
					(start 113.674652 -136.053322)
					(mid 113.711335 -135.979855)
					(end 113.681764 -135.903208)
				)
				(arc
					(start 113.681764 -135.903208)
					(mid 113.577973 -135.633155)
					(end 113.708942 -135.375142)
				)
				(arc
					(start 113.708942 -135.375142)
					(mid 113.746272 -135.29115)
					(end 113.70056 -135.211312)
				)
				(arc
					(start 113.70056 -135.211312)
					(mid 113.576688 -134.75608)
					(end 114.013234 -134.577328)
				)
				(arc
					(start 114.013234 -134.577328)
					(mid 114.105638 -134.564238)
					(end 114.148362 -134.481316)
				)
				(xy 114.148362 -131.6355) (xy 114.148362 -129.688844) (xy 113.923826 -129.464308) (xy 113.923826 -126.470918)
				(xy 106.324908 -118.872) (xy 106.324908 -101.649022) (xy 105.218484 -100.542598) (xy 105.218484 -92.873068)
				(xy 105.202228 -92.856812) (xy 105.202228 -91.421712) (xy 107.32008 -89.30386) (xy 107.32008 -87.345012)
				(xy 107.41406 -87.251032) (xy 109.573568 -87.251032) (xy 109.700822 -87.123778) (xy 109.700822 -85.753194)
				(xy 109.510068 -85.56244) (xy 106.91622 -85.56244) (xy 99.5172 -85.56244) (xy 95.90024 -89.1794)
				(xy 89.371424 -89.1794)
			)
		)
	)
	(zone
		(net "P3V3")
		(layer "In11.Cu")
		(hatch none 0.5)
		(connect_pads
			(clearance 0.5)
		)
		(min_thickness 0.25)
		(fill yes
			(thermal_gap 0.5)
			(thermal_bridge_width 0.5)
			(island_removal_mode 0)
		)
		(polygon
			(pts
				(xy 193.421 -27.5844) (xy 193.421 -25.9842) (xy 193.6496 -25.7556) (xy 194.7926 -25.7556) (xy 194.9196 -25.8826)
				(xy 194.9196 -26.5938) (xy 195.199 -26.8732) (xy 195.199 -27.7876) (xy 194.8434 -28.1432) (xy 193.9798 -28.1432)
			)
		)
	)
	(zone
		(net "PVCCIOMCP_CPU1")
		(layer "In11.Cu")
		(hatch none 0.5)
		(connect_pads
			(clearance 0.5)
		)
		(min_thickness 0.25)
		(fill yes
			(thermal_gap 0.5)
			(thermal_bridge_width 0.5)
			(island_removal_mode 0)
		)
		(polygon
			(pts
				(xy 156.1338 -108.2548) (xy 146.8628 -98.9838) (xy 146.8628 -91.0336) (xy 145.2626 -89.4334) (xy 143.129 -89.4334)
				(xy 142.3162 -88.6206) (xy 142.3162 -86.487) (xy 139.879832 -84.050632) (xy 139.879832 -83.249516)
				(xy 139.592304 -82.961988) (xy 136.924796 -82.961988) (xy 136.05383 -82.091022) (xy 133.764274 -82.091022)
				(xy 132.832602 -81.15935) (xy 131.47675 -81.15935) (xy 130.5052 -80.1878) (xy 130.5052 -79.1718)
				(xy 129.6924 -78.359) (xy 128.8796 -78.359) (xy 128.778 -78.4606) (xy 128.778 -79.4512) (xy 128.6256 -79.6036)
				(xy 127.8636 -79.6036) (xy 127.7112 -79.4512) (xy 127.7112 -76.0476) (xy 127.8636 -75.8952) (xy 131.953 -75.8952)
				(xy 141.2494 -75.8952) (xy 160.6296 -95.2754) (xy 160.6296 -107.0356) (xy 160.6296 -107.6198) (xy 159.8676 -108.3818)
				(xy 156.2608 -108.3818)
			)
		)
	)
	(zone
		(layer "In11.Cu")
		(hatch none 0.5)
		(connect_pads
			(clearance 0)
		)
		(min_thickness 0.25)
		(keepout
			(tracks allowed)
			(vias allowed)
			(pads allowed)
			(copperpour allowed)
			(footprints allowed)
		)
		(placement
			(enabled no)
			(sheetname "")
		)
		(fill
			(thermal_gap 0.5)
			(thermal_bridge_width 0.5)
			(island_removal_mode 0)
		)
		(polygon
			(pts
				(xy 252.652022 -67.48399) (xy 246.482616 -67.48399) (xy 246.482616 -55.797704) (xy 244.592856 -53.907944)
				(xy 244.001544 -53.907944) (xy 241.9604 -51.8668) (xy 241.9604 -51.432968) (xy 243.317014 -50.076354)
				(xy 243.361464 -50.031904) (xy 251.848874 -50.031904) (xy 252.652022 -50.835052) (xy 252.652022 -54.054756)
			)
		)
	)
	(zone
		(layer "In11.Cu")
		(hatch none 0.5)
		(connect_pads
			(clearance 0)
		)
		(min_thickness 0.25)
		(keepout
			(tracks not_allowed)
			(vias allowed)
			(pads allowed)
			(copperpour not_allowed)
			(footprints allowed)
		)
		(placement
			(enabled no)
			(sheetname "")
		)
		(fill
			(thermal_gap 0.5)
			(thermal_bridge_width 0.5)
			(island_removal_mode 0)
		)
		(polygon
			(pts
				(xy 11.753596 -32.64535) (xy 11.98245 -32.874204)
				(arc
					(start 11.98245 -32.953198)
					(mid 11.9126 -33.477115)
					(end 11.84275 -32.953198)
				)
				(xy 11.84275 -32.932116) (xy 11.695684 -32.78505) (xy 11.52906 -32.78505)
				(arc
					(start 11.52906 -33.2105)
					(mid 11.9126 -33.59404)
					(end 12.29614 -33.2105)
				)
				(arc
					(start 12.29614 -31.940754)
					(mid 11.912727 -31.55696)
					(end 11.52906 -31.9405)
				)
				(xy 11.52906 -32.35325) (xy 11.693144 -32.35325) (xy 11.84275 -32.203644)
				(arc
					(start 11.84275 -32.197802)
					(mid 11.9126 -31.673885)
					(end 11.98245 -32.197802)
				)
				(xy 11.98245 -32.261556) (xy 11.751056 -32.49295) (xy 11.52906 -32.49295) (xy 11.52906 -32.64535)
			)
		)
	)
	(zone
		(net "PVTT_GHJ")
		(layer "In11.Cu")
		(hatch none 0.5)
		(connect_pads
			(clearance 0.5)
		)
		(min_thickness 0.25)
		(fill yes
			(thermal_gap 0.5)
			(thermal_bridge_width 0.5)
			(island_removal_mode 0)
		)
		(polygon
			(pts
				(xy 92.6846 -10.668) (xy 95.8342 -10.668) (xy 96.8248 -9.6774) (xy 96.8248 -7.50824) (xy 97.079562 -7.253478)
				(xy 97.079562 1.663446) (xy 96.8248 1.918208) (xy 96.352868 2.39014) (xy 94.619064 2.39014) (xy 94.52864 2.480564)
				(xy 93.979492 2.480564) (xy 93.611192 2.112264) (xy 92.152216 2.112264) (xy 91.49334 1.453388) (xy 91.49334 1.434338)
				(xy 91.255088 1.196086) (xy 91.255088 -5.956554) (xy 91.49334 -6.194806) (xy 91.817444 -6.51891)
				(xy 92.127832 -6.829298) (xy 92.127832 -10.111232)
			)
		)
	)
	(zone
		(layer "In11.Cu")
		(hatch none 0.5)
		(connect_pads
			(clearance 0)
		)
		(min_thickness 0.25)
		(keepout
			(tracks allowed)
			(vias allowed)
			(pads allowed)
			(copperpour allowed)
			(footprints allowed)
		)
		(placement
			(enabled no)
			(sheetname "")
		)
		(fill
			(thermal_gap 0.5)
			(thermal_bridge_width 0.5)
			(island_removal_mode 0)
		)
		(polygon
			(pts
				(xy 278.765 4.6482) (xy 278.765 5.1308) (xy 280.5684 5.1308) (xy 280.5684 4.6482)
			)
		)
	)
	(zone
		(layer "In11.Cu")
		(hatch none 0.5)
		(connect_pads
			(clearance 0)
		)
		(min_thickness 0.25)
		(keepout
			(tracks allowed)
			(vias allowed)
			(pads allowed)
			(copperpour allowed)
			(footprints allowed)
		)
		(placement
			(enabled no)
			(sheetname "")
		)
		(fill
			(thermal_gap 0.5)
			(thermal_bridge_width 0.5)
			(island_removal_mode 0)
		)
		(polygon
			(pts
				(xy 363.093 -113.919) (xy 363.093 -112.014) (xy 364.236 -112.014) (xy 364.236 -113.919)
			)
		)
	)
	(zone
		(layer "In11.Cu")
		(hatch none 0.5)
		(connect_pads
			(clearance 0)
		)
		(min_thickness 0.25)
		(keepout
			(tracks not_allowed)
			(vias allowed)
			(pads allowed)
			(copperpour not_allowed)
			(footprints allowed)
		)
		(placement
			(enabled no)
			(sheetname "")
		)
		(fill
			(thermal_gap 0.5)
			(thermal_bridge_width 0.5)
			(island_removal_mode 0)
		)
		(polygon
			(pts
				(arc
					(start 387.664452 -29.662628)
					(mid 387.734302 -29.138711)
					(end 387.804152 -29.662628)
				)
				(xy 387.804152 -29.75102) (xy 387.877558 -29.824426) (xy 388.117842 -29.824426)
				(arc
					(start 388.117842 -29.40558)
					(mid 387.734429 -29.02204)
					(end 387.350762 -29.405326)
				)
				(arc
					(start 387.350762 -30.675326)
					(mid 387.734302 -31.058866)
					(end 388.117842 -30.675326)
				)
				(xy 388.117842 -30.256226) (xy 387.877558 -30.256226) (xy 387.804152 -30.329632)
				(arc
					(start 387.804152 -30.418024)
					(mid 387.734302 -30.941941)
					(end 387.664452 -30.418024)
				)
				(xy 387.664452 -30.27172) (xy 387.819646 -30.116526) (xy 388.117842 -30.116526) (xy 388.117842 -29.964126)
				(xy 387.819646 -29.964126) (xy 387.664452 -29.808932)
			)
		)
	)
	(zone
		(net "VR_FET_SW_P12V_STBY_PVDDQ_DEF")
		(layer "In11.Cu")
		(hatch none 0.5)
		(connect_pads
			(clearance 0.5)
		)
		(min_thickness 0.25)
		(fill yes
			(thermal_gap 0.5)
			(thermal_bridge_width 0.5)
			(island_removal_mode 0)
		)
		(polygon
			(pts
				(xy 380.003304 -157.21965) (xy 387.34111 -157.21965) (xy 387.43382 -157.31236) (xy 389.56234 -157.31236)
				(xy 390.02335 -156.85135) (xy 390.02335 -156.58465) (xy 390.02335 -152.53081) (xy 390.02335 -152.45461)
				(xy 389.28294 -151.7142) (xy 388.306818 -150.738078) (xy 383.07645 -150.738078) (xy 381.656844 -149.318472)
				(xy 370.241576 -149.318472) (xy 369.670584 -148.74748) (xy 368.368072 -148.74748) (xy 367.935002 -148.31441)
				(xy 366.014 -148.31441) (xy 365.01959 -147.32) (xy 362.204 -147.32) (xy 362.077 -147.32) (xy 361.486958 -147.910042)
				(xy 355.18217 -147.910042) (xy 354.704396 -148.387816) (xy 354.704396 -150.262336) (xy 354.86975 -150.42769)
				(xy 362.789724 -150.42769) (xy 365.8108 -153.448766) (xy 365.8108 -154.9654) (xy 366.8522 -156.0068)
				(xy 367.85296 -157.00756) (xy 373.373904 -157.00756) (xy 373.585994 -157.21965)
			)
		)
	)
	(zone
		(layer "In11.Cu")
		(hatch none 0.5)
		(connect_pads
			(clearance 0)
		)
		(min_thickness 0.25)
		(keepout
			(tracks allowed)
			(vias allowed)
			(pads allowed)
			(copperpour allowed)
			(footprints allowed)
		)
		(placement
			(enabled no)
			(sheetname "")
		)
		(fill
			(thermal_gap 0.5)
			(thermal_bridge_width 0.5)
			(island_removal_mode 0)
		)
		(polygon
			(pts
				(xy 85.497162 -50.030634) (xy 82.891376 -50.030634) (xy 82.891376 -49.155858) (xy 85.497162 -49.155858)
			)
		)
	)
	(zone
		(layer "In11.Cu")
		(hatch none 0.5)
		(connect_pads
			(clearance 0)
		)
		(min_thickness 0.25)
		(keepout
			(tracks not_allowed)
			(vias allowed)
			(pads allowed)
			(copperpour not_allowed)
			(footprints allowed)
		)
		(placement
			(enabled no)
			(sheetname "")
		)
		(fill
			(thermal_gap 0.5)
			(thermal_bridge_width 0.5)
			(island_removal_mode 0)
		)
		(polygon
			(pts
				(arc
					(start 387.506464 -127.473964)
					(mid 387.919527 -127.141673)
					(end 387.587236 -127.554736)
				)
				(xy 387.532372 -127.6096) (xy 387.359398 -127.6096) (xy 387.35 -127.600202) (xy 387.35 -127.6858)
				(xy 387.532372 -127.6858)
				(arc
					(start 387.587236 -127.740664)
					(mid 387.919527 -128.153727)
					(end 387.506464 -127.821436)
				)
				(xy 387.485128 -127.8001) (xy 387.35 -127.8001)
				(arc
					(start 387.35 -127.964946)
					(mid 387.730873 -128.3462)
					(end 388.112 -127.9652)
				)
				(arc
					(start 388.112 -127.3302)
					(mid 387.746507 -126.949516)
					(end 387.35127 -127.299212)
				)
				(xy 387.35127 -127.439928) (xy 387.406642 -127.4953) (xy 387.485128 -127.4953)
			)
		)
	)
	(zone
		(layer "In11.Cu")
		(hatch none 0.5)
		(connect_pads
			(clearance 0)
		)
		(min_thickness 0.25)
		(keepout
			(tracks not_allowed)
			(vias allowed)
			(pads allowed)
			(copperpour not_allowed)
			(footprints allowed)
		)
		(placement
			(enabled no)
			(sheetname "")
		)
		(fill
			(thermal_gap 0.5)
			(thermal_bridge_width 0.5)
			(island_removal_mode 0)
		)
		(polygon
			(pts
				(xy 356.892098 -104.414574) (xy 357.047292 -104.569768)
				(arc
					(start 357.047292 -104.716072)
					(mid 356.977442 -105.239989)
					(end 356.907592 -104.716072)
				)
				(xy 356.907592 -104.62768) (xy 356.834186 -104.554274) (xy 356.593902 -104.554274)
				(arc
					(start 356.593902 -104.97312)
					(mid 356.977315 -105.356914)
					(end 357.360982 -104.973374)
				)
				(arc
					(start 357.360982 -103.703374)
					(mid 356.977442 -103.319834)
					(end 356.593902 -103.703374)
				)
				(xy 356.593902 -104.122474) (xy 356.834186 -104.122474) (xy 356.907592 -104.049068)
				(arc
					(start 356.907592 -103.960676)
					(mid 356.977442 -103.436759)
					(end 357.047292 -103.960676)
				)
				(xy 357.047292 -104.10698) (xy 356.892098 -104.262174) (xy 356.593902 -104.262174) (xy 356.593902 -104.414574)
			)
		)
	)
	(zone
		(net "VR_FET_SW_P12V_STBY_PVDDQ_DEF")
		(layer "In11.Cu")
		(hatch none 0.5)
		(connect_pads
			(clearance 0.5)
		)
		(min_thickness 0.25)
		(fill yes
			(thermal_gap 0.5)
			(thermal_bridge_width 0.5)
			(island_removal_mode 0)
		)
		(polygon
			(pts
				(xy 348.6912 -144.9324) (xy 349.758 -144.9324) (xy 351.3836 -143.3068) (xy 351.3836 -141.6304) (xy 351.028 -141.2748)
				(xy 348.8944 -141.2748) (xy 348.1832 -141.986) (xy 348.1832 -144.4244)
			)
		)
	)
	(zone
		(layer "In11.Cu")
		(hatch none 0.5)
		(connect_pads
			(clearance 0)
		)
		(min_thickness 0.25)
		(keepout
			(tracks allowed)
			(vias allowed)
			(pads allowed)
			(copperpour allowed)
			(footprints allowed)
		)
		(placement
			(enabled no)
			(sheetname "")
		)
		(fill
			(thermal_gap 0.5)
			(thermal_bridge_width 0.5)
			(island_removal_mode 0)
		)
		(polygon
			(pts
				(xy 322.279772 -125.349) (xy 322.279772 -157.861) (xy 194.009772 -157.861) (xy 194.009772 -128.143)
				(xy 222.631 -128.143) (xy 223.647 -127.127) (xy 223.647 -124.2822) (xy 244.729 -124.2822) (xy 244.729 -126.111)
				(xy 288.544 -126.111) (xy 288.544 -124.2822) (xy 321.212972 -124.2822)
			)
		)
	)
	(zone
		(layer "In11.Cu")
		(hatch none 0.5)
		(connect_pads
			(clearance 0)
		)
		(min_thickness 0.25)
		(keepout
			(tracks allowed)
			(vias allowed)
			(pads allowed)
			(copperpour allowed)
			(footprints allowed)
		)
		(placement
			(enabled no)
			(sheetname "")
		)
		(fill
			(thermal_gap 0.5)
			(thermal_bridge_width 0.5)
			(island_removal_mode 0)
		)
		(polygon
			(pts
				(xy 157.27934 -125.349) (xy 157.27934 -157.861) (xy 29.00934 -157.861) (xy 29.00934 -128.143) (xy 57.630568 -128.143)
				(xy 58.646568 -127.127) (xy 58.646568 -124.2822) (xy 79.728568 -124.2822) (xy 79.728568 -126.873)
				(xy 79.855568 -127) (xy 123.543568 -127) (xy 123.543568 -124.2822) (xy 156.21254 -124.2822)
			)
		)
	)
	(zone
		(layer "In11.Cu")
		(hatch none 0.5)
		(connect_pads
			(clearance 0)
		)
		(min_thickness 0.25)
		(keepout
			(tracks allowed)
			(vias allowed)
			(pads allowed)
			(copperpour allowed)
			(footprints allowed)
		)
		(placement
			(enabled no)
			(sheetname "")
		)
		(fill
			(thermal_gap 0.5)
			(thermal_bridge_width 0.5)
			(island_removal_mode 0)
		)
		(polygon
			(pts
				(xy 250.497594 -50.030634) (xy 247.891808 -50.030634) (xy 247.891808 -49.155858) (xy 250.497594 -49.155858)
			)
		)
	)
	(zone
		(net "PVPP_DEF")
		(layer "In11.Cu")
		(hatch none 0.5)
		(connect_pads
			(clearance 0.5)
		)
		(min_thickness 0.25)
		(fill yes
			(thermal_gap 0.5)
			(thermal_bridge_width 0.5)
			(island_removal_mode 0)
		)
		(polygon
			(pts
				(xy 330.9366 -136.4742) (xy 330.9366 -129.0828) (xy 330.1365 -128.2827) (xy 324.8533 -128.2827)
				(xy 323.9262 -127.3556) (xy 318.5922 -127.3556) (xy 317.2206 -128.7272) (xy 317.2206 -131.1402)
				(xy 317.0682 -131.2926) (xy 317.0682 -155.4988) (xy 317.4238 -155.8544) (xy 321.564 -155.8544) (xy 322.8721 -154.5463)
				(xy 322.8721 -142.1765) (xy 323.6087 -141.4399) (xy 323.6087 -139.7635) (xy 323.7738 -139.5984)
				(xy 323.7738 -138.7602) (xy 323.0118 -137.9982) (xy 323.0118 -137.5664) (xy 323.1896 -137.3886)
				(xy 324.0278 -137.3886) (xy 324.1802 -137.541) (xy 329.1332 -137.541) (xy 329.6158 -137.0584) (xy 330.3524 -137.0584)
			)
		)
	)
	(zone
		(layer "In11.Cu")
		(hatch none 0.5)
		(connect_pads
			(clearance 0)
		)
		(min_thickness 0.25)
		(keepout
			(tracks not_allowed)
			(vias allowed)
			(pads allowed)
			(copperpour not_allowed)
			(footprints allowed)
		)
		(placement
			(enabled no)
			(sheetname "")
		)
		(fill
			(thermal_gap 0.5)
			(thermal_bridge_width 0.5)
			(island_removal_mode 0)
		)
		(polygon
			(pts
				(xy 358.057958 -115.76685)
				(arc
					(start 358.24541 -115.954302)
					(mid 358.352163 -116.470925)
					(end 358.10063 -116.007134)
				)
				(xy 358.000046 -115.90655) (xy 357.87711 -115.90655)
				(arc
					(start 357.87711 -116.220494)
					(mid 358.26065 -116.604034)
					(end 358.64419 -116.220494)
				)
				(arc
					(start 358.64419 -115.204748)
					(mid 358.260777 -114.820954)
					(end 357.87711 -115.204494)
				)
				(xy 357.87711 -115.47475) (xy 358.017064 -115.47475)
				(arc
					(start 358.085898 -115.405916)
					(mid 358.372273 -114.962318)
					(end 358.221026 -115.468146)
				)
				(xy 358.074976 -115.61445) (xy 357.87711 -115.61445) (xy 357.87711 -115.76685)
			)
		)
	)
	(zone
		(layer "In11.Cu")
		(hatch none 0.5)
		(connect_pads
			(clearance 0)
		)
		(min_thickness 0.25)
		(keepout
			(tracks allowed)
			(vias allowed)
			(pads allowed)
			(copperpour allowed)
			(footprints allowed)
		)
		(placement
			(enabled no)
			(sheetname "")
		)
		(fill
			(thermal_gap 0.5)
			(thermal_bridge_width 0.5)
			(island_removal_mode 0)
		)
		(polygon
			(pts
				(xy 277.170642 -61.59881) (xy 271.046702 -61.59881) (xy 271.046702 -53.248052) (xy 271.046702 -50.503836)
				(xy 271.046702 -47.875698) (xy 271.8054 -47.117) (xy 278.1554 -47.117) (xy 278.4856 -47.4472) (xy 278.4856 -48.707548)
				(xy 277.158704 -50.034444) (xy 277.170642 -50.046382) (xy 277.170642 -53.248052)
			)
		)
	)
	(zone
		(net "VR_FET_SW_P12V_STBY_PVDDQ_KLM")
		(layer "In11.Cu")
		(hatch none 0.5)
		(connect_pads
			(clearance 0.5)
		)
		(min_thickness 0.25)
		(fill yes
			(thermal_gap 0.5)
			(thermal_bridge_width 0.5)
			(island_removal_mode 0)
		)
		(polygon
			(pts
				(xy 16.08201 -126.47041) (xy 16.08201 -131.92887) (xy 16.3576 -132.20446) (xy 16.3576 -133.8834)
				(xy 16.3576 -148.6154) (xy 16.3576 -150.60295) (xy 15.818612 -151.141938) (xy 0.4826 -151.141938)
				(xy -1.385062 -151.141938) (xy -1.389126 -151.137874) (xy -1.506728 -151.137874) (xy -1.722628 -150.921974)
				(xy -1.722628 -148.55317) (xy -0.78867 -147.619212) (xy 0.38989 -147.619212) (xy 1.1176 -146.891502)
				(xy 1.1176 -146.002502) (xy 1.1176 -143.50238) (xy 0.726186 -143.110966) (xy -0.794258 -143.110966)
				(xy -1.567942 -142.337282) (xy -1.567942 -139.108942) (xy -1.376172 -138.917172) (xy -1.016 -138.557)
				(xy -1.016 -136.7536) (xy -0.8128 -136.5504) (xy -0.779018 -136.5504) (xy -0.163576 -135.934958)
				(xy 1.313942 -135.934958) (xy 4.224528 -133.024372) (xy 4.224528 -129.435352) (xy 8.26008 -125.3998)
				(xy 13.963904 -125.3998) (xy 14.06271 -125.498606) (xy 14.06271 -126.044198) (xy 14.350492 -126.33198)
				(xy 16.054578 -126.33198) (xy 16.08201 -126.359412)
			)
		)
	)
	(zone
		(net "GND")
		(layer "In11.Cu")
		(hatch none 0.5)
		(connect_pads
			(clearance 0.5)
		)
		(min_thickness 0.25)
		(fill yes
			(thermal_gap 0.5)
			(thermal_bridge_width 0.5)
			(island_removal_mode 0)
		)
		(polygon
			(pts
				(xy -3.7592 -87.0458) (xy 1.524 -87.0458) (xy 2.2352 -86.3346) (xy 2.2352 -68.862702) (xy 0.508 -67.135502)
				(xy 0.508 -59.6392) (xy 1.778 -58.3692) (xy 1.778 -49.7332) (xy 2.8194 -48.6918) (xy 4.6736 -48.6918)
				(xy 11.9888 -48.6918) (xy 12.5984 -48.0822) (xy 12.5984 -46.7106) (xy 12.5984 -43.8404) (xy 11.8618 -43.1038)
				(xy -3.3528 -43.1038) (xy -4.318 -44.069) (xy -4.318 -86.487)
			)
		)
	)
	(zone
		(layer "In11.Cu")
		(hatch none 0.5)
		(connect_pads
			(clearance 0)
		)
		(min_thickness 0.25)
		(keepout
			(tracks not_allowed)
			(vias allowed)
			(pads allowed)
			(copperpour not_allowed)
			(footprints allowed)
		)
		(placement
			(enabled no)
			(sheetname "")
		)
		(fill
			(thermal_gap 0.5)
			(thermal_bridge_width 0.5)
			(island_removal_mode 0)
		)
		(polygon
			(pts
				(xy 463.900774 -121.069608) (xy 464.1088 -121.277634) (xy 464.1088 -121.522998) (xy 464.2612 -121.522998)
				(xy 464.2612 -121.272554) (xy 464.464146 -121.069608)
				(arc
					(start 464.554316 -121.069608)
					(mid 465.078233 -121.139458)
					(end 464.554316 -121.209308)
				)
				(xy 464.522058 -121.209308) (xy 464.4009 -121.330466) (xy 464.4009 -121.522998)
				(arc
					(start 464.811618 -121.522998)
					(mid 465.195158 -121.139458)
					(end 464.811618 -120.755918)
				)
				(arc
					(start 463.625692 -120.755918)
					(mid 463.241898 -121.139331)
					(end 463.625438 -121.522998)
				)
				(xy 463.9691 -121.522998) (xy 463.9691 -121.335546)
				(arc
					(start 463.872834 -121.23928)
					(mid 463.359211 -121.12417)
					(end 463.88274 -121.069608)
				)
			)
		)
	)
	(zone
		(layer "In11.Cu")
		(hatch none 0.5)
		(connect_pads
			(clearance 0)
		)
		(min_thickness 0.25)
		(keepout
			(tracks allowed)
			(vias allowed)
			(pads allowed)
			(copperpour allowed)
			(footprints allowed)
		)
		(placement
			(enabled no)
			(sheetname "")
		)
		(fill
			(thermal_gap 0.5)
			(thermal_bridge_width 0.5)
			(island_removal_mode 0)
		)
		(polygon
			(pts
				(xy 351.282 -114.427) (xy 351.282 -112.522) (xy 352.425 -112.522) (xy 352.425 -114.427)
			)
		)
	)
	(zone
		(layer "In11.Cu")
		(hatch none 0.5)
		(connect_pads
			(clearance 0)
		)
		(min_thickness 0.25)
		(keepout
			(tracks not_allowed)
			(vias allowed)
			(pads allowed)
			(copperpour not_allowed)
			(footprints allowed)
		)
		(placement
			(enabled no)
			(sheetname "")
		)
		(fill
			(thermal_gap 0.5)
			(thermal_bridge_width 0.5)
			(island_removal_mode 0)
		)
		(polygon
			(pts
				(xy 395.50086 -34.703004)
				(arc
					(start 395.50086 -34.985452)
					(mid 395.569931 -34.86866)
					(end 395.68755 -34.801048)
				)
				(xy 395.68755 -34.77641) (xy 395.614144 -34.703004)
			)
		)
	)
	(zone
		(layer "In11.Cu")
		(hatch none 0.5)
		(connect_pads
			(clearance 0)
		)
		(min_thickness 0.25)
		(keepout
			(tracks not_allowed)
			(vias allowed)
			(pads allowed)
			(copperpour not_allowed)
			(footprints allowed)
		)
		(placement
			(enabled no)
			(sheetname "")
		)
		(fill
			(thermal_gap 0.5)
			(thermal_bridge_width 0.5)
			(island_removal_mode 0)
		)
		(polygon
			(pts
				(xy 388.14629 -26.828242) (xy 388.11962 -26.382472) (xy 388.119366 -26.382218)
				(arc
					(start 388.11708 -26.382472)
					(mid 387.711442 -26.022554)
					(end 387.351524 -26.428192)
				)
				(xy 387.348984 -26.428446) (xy 387.425184 -27.698446)
				(arc
					(start 387.427724 -27.698192)
					(mid 387.833362 -28.05811)
					(end 388.19328 -27.652472)
				)
				(xy 388.19582 -27.652218) (xy 388.172198 -27.260042) (xy 388.085076 -27.260042)
				(arc
					(start 387.91515 -27.429968)
					(mid 387.792603 -27.941362)
					(end 387.740652 -27.41803)
				)
				(xy 387.740652 -27.406854) (xy 388.027164 -27.120342) (xy 388.163816 -27.120342) (xy 388.154672 -26.967942)
				(xy 387.96976 -26.967942)
				(arc
					(start 387.664706 -26.662888)
					(mid 387.711066 -26.139597)
					(end 387.84657 -26.64714)
				)
				(xy 388.027672 -26.828242)
			)
		)
	)
	(zone
		(layer "In11.Cu")
		(hatch none 0.5)
		(connect_pads
			(clearance 0)
		)
		(min_thickness 0.25)
		(keepout
			(tracks allowed)
			(vias allowed)
			(pads allowed)
			(copperpour allowed)
			(footprints allowed)
		)
		(placement
			(enabled no)
			(sheetname "")
		)
		(fill
			(thermal_gap 0.5)
			(thermal_bridge_width 0.5)
			(island_removal_mode 0)
		)
		(polygon
			(pts
				(xy 88.364568 -97.155) (xy 88.364568 -86.614) (xy 84.173568 -82.423) (xy 69.441568 -82.423) (xy 66.520568 -85.344)
				(xy 65.377568 -85.344) (xy 63.218568 -87.503) (xy 63.218568 -98.552) (xy 70.584568 -105.918) (xy 74.140568 -105.918)
				(xy 76.299568 -103.759) (xy 85.697568 -103.759) (xy 85.824568 -103.632) (xy 85.824568 -103.124)
				(xy 85.824568 -99.695)
			)
		)
	)
	(zone
		(net "GND")
		(layer "In11.Cu")
		(hatch none 0.5)
		(connect_pads
			(clearance 0.5)
		)
		(min_thickness 0.25)
		(fill yes
			(thermal_gap 0.5)
			(thermal_bridge_width 0.5)
			(island_removal_mode 0)
		)
		(polygon
			(pts
				(xy -5.03174 15.24) (xy -5.03174 8.763) (xy 413.4358 8.763) (xy 501.2182 8.763) (xy 501.2182 8.7884)
				(xy 501.2182 15.24)
			)
		)
		(polygon
			(pts
				(xy 189.6618 14.5288) (xy 137.5156 14.5288) (xy 137.5156 9.4742) (xy 189.6618 9.4742) (xy 189.6618 9.4996)
				(xy 195.339462 9.4996) (xy 196.6976 9.4996) (xy 198.934578 9.4996) (xy 198.934578 14.5034) (xy 196.6976 14.5034)
				(xy 195.339462 14.5034) (xy 189.6618 14.5034)
			)
		)
		(polygon
			(pts
				(xy 100.1776 14.61262) (xy 29.3116 14.61262) (xy 29.3116 9.4742) (xy 36.957 9.4742) (xy 36.957 9.9187)
				(xy 100.838 9.9187) (xy 100.838 9.9314) (xy 108.6612 9.9314) (xy 110.6678 9.9314) (xy 114.39652 9.9314)
				(xy 114.39652 14.605) (xy 110.6678 14.605) (xy 108.6612 14.605) (xy 100.1776 14.605)
			)
		)
		(polygon
			(pts
				(xy 292.466522 9.4996) (xy 344.3478 9.4996) (xy 348.223078 9.4996) (xy 348.223078 14.5288) (xy 344.3478 14.5288)
				(xy 292.466522 14.5288)
			)
		)
		(polygon
			(pts
				(xy 366.6744 14.5288) (xy 362.677964 14.5288) (xy 362.677964 9.4742) (xy 416.3568 9.4742) (xy 424.283632 9.4742)
				(xy 424.283632 14.5288) (xy 416.3568 14.5288)
			)
		)
		(polygon
			(pts
				(xy 273.4818 14.5034) (xy 222.013272 14.5034) (xy 222.013272 9.4234) (xy 273.4818 9.4234) (xy 283.28239 9.4234)
				(xy 283.28239 14.5034) (xy 281.145996 14.5034) (xy 279.202134 14.5034)
			)
		)
	)
	(zone
		(net "ISENSE_TMP421_1_BC")
		(layer "In11.Cu")
		(hatch none 0.5)
		(connect_pads
			(clearance 0.5)
		)
		(min_thickness 0.25)
		(fill yes
			(thermal_gap 0.5)
			(thermal_bridge_width 0.5)
			(island_removal_mode 0)
		)
		(polygon
			(pts
				(xy 488.817666 -126.527814) (xy 492.197644 -126.527814) (xy 492.63554 -126.527814) (xy 492.83747 -126.325884)
				(xy 492.83747 -124.725684) (xy 490.272324 -122.160538) (xy 488.753404 -122.160538) (xy 488.424728 -122.489214)
				(xy 488.424728 -123.033028) (xy 488.424728 -126.134876)
			)
		)
	)
	(zone
		(net "GND")
		(layer "In11.Cu")
		(hatch none 0.5)
		(connect_pads
			(clearance 0.5)
		)
		(min_thickness 0.25)
		(fill yes
			(thermal_gap 0.5)
			(thermal_bridge_width 0.5)
			(island_removal_mode 0)
		)
		(polygon
			(pts
				(xy 34.5948 -52.6288) (xy 34.5948 -89.7636) (xy 34.5821 -89.7763) (xy 34.5821 -92.772992) (xy 34.8234 -93.014292)
				(xy 43.0276 -93.014292) (xy 43.2054 -92.836492) (xy 43.2054 -53.456332) (xy 42.250868 -52.5018)
				(xy 41.488868 -52.5018) (xy 41.178734 -52.191666) (xy 39.644066 -52.191666) (xy 39.37 -51.9176)
				(xy 39.070534 -51.618134) (xy 35.175444 -51.618134) (xy 34.5948 -52.198778)
			)
		)
	)
	(zone
		(layer "In11.Cu")
		(hatch none 0.5)
		(connect_pads
			(clearance 0)
		)
		(min_thickness 0.25)
		(keepout
			(tracks allowed)
			(vias allowed)
			(pads allowed)
			(copperpour allowed)
			(footprints allowed)
		)
		(placement
			(enabled no)
			(sheetname "")
		)
		(fill
			(thermal_gap 0.5)
			(thermal_bridge_width 0.5)
			(island_removal_mode 0)
		)
		(polygon
			(pts
				(xy 347.726 -113.03) (xy 349.631 -113.03) (xy 349.631 -114.173) (xy 347.726 -114.173)
			)
		)
	)
	(zone
		(net "P1V05_PCH_STBY")
		(layer "In11.Cu")
		(hatch none 0.5)
		(connect_pads
			(clearance 0.5)
		)
		(min_thickness 0.25)
		(fill yes
			(thermal_gap 0.5)
			(thermal_bridge_width 0.5)
			(island_removal_mode 0)
		)
		(polygon
			(pts
				(xy 377.7488 -116.384578)
				(arc
					(start 377.909582 -116.384578)
					(mid 377.9947 -116.338062)
					(end 378.002038 -116.241322)
				)
				(arc
					(start 378.002038 -116.241322)
					(mid 378.32665 -115.738601)
					(end 378.651262 -116.241322)
				)
				(arc
					(start 378.651262 -116.241322)
					(mid 378.658568 -116.338082)
					(end 378.743718 -116.384578)
				)
				(arc
					(start 378.900182 -116.384578)
					(mid 378.9853 -116.338062)
					(end 378.992638 -116.241322)
				)
				(arc
					(start 378.992638 -116.241322)
					(mid 379.31725 -115.738601)
					(end 379.641862 -116.241322)
				)
				(arc
					(start 379.641862 -116.241322)
					(mid 379.649168 -116.338082)
					(end 379.734318 -116.384578)
				)
				(arc
					(start 379.890782 -116.384578)
					(mid 379.9759 -116.338062)
					(end 379.983238 -116.241322)
				)
				(arc
					(start 379.983238 -116.241322)
					(mid 380.30785 -115.738601)
					(end 380.632462 -116.241322)
				)
				(arc
					(start 380.632462 -116.241322)
					(mid 380.639768 -116.338082)
					(end 380.724918 -116.384578)
				)
				(arc
					(start 380.881382 -116.384578)
					(mid 380.9665 -116.338062)
					(end 380.973838 -116.241322)
				)
				(arc
					(start 380.973838 -116.241322)
					(mid 381.29845 -115.738601)
					(end 381.623062 -116.241322)
				)
				(arc
					(start 381.623062 -116.241322)
					(mid 381.630368 -116.338082)
					(end 381.715518 -116.384578)
				)
				(arc
					(start 382.862582 -116.384578)
					(mid 382.9477 -116.338062)
					(end 382.955038 -116.241322)
				)
				(arc
					(start 382.955038 -116.241322)
					(mid 382.932153 -116.016673)
					(end 383.049018 -115.823492)
				)
				(arc
					(start 383.049018 -115.823492)
					(mid 383.084193 -115.755167)
					(end 383.061464 -115.68176)
				)
				(arc
					(start 383.061464 -115.68176)
					(mid 383.138726 -115.159974)
					(end 383.65049 -115.287044)
				)
				(arc
					(start 383.65049 -115.287044)
					(mid 383.741488 -115.340373)
					(end 383.83083 -115.28425)
				)
				(arc
					(start 383.83083 -115.28425)
					(mid 384.505669 -115.437434)
					(end 383.83591 -115.611656)
				)
				(arc
					(start 383.83591 -115.611656)
					(mid 383.744912 -115.558327)
					(end 383.65557 -115.61445)
				)
				(arc
					(start 383.65557 -115.61445)
					(mid 383.617223 -115.675196)
					(end 383.567432 -115.726972)
				)
				(arc
					(start 383.567432 -115.726972)
					(mid 383.532257 -115.795297)
					(end 383.554986 -115.868704)
				)
				(arc
					(start 383.554986 -115.868704)
					(mid 383.632815 -116.047991)
					(end 383.604262 -116.241322)
				)
				(arc
					(start 383.604262 -116.241322)
					(mid 383.611568 -116.338082)
					(end 383.696718 -116.384578)
				)
				(arc
					(start 384.843782 -116.384578)
					(mid 384.9289 -116.338062)
					(end 384.936238 -116.241322)
				)
				(arc
					(start 384.936238 -116.241322)
					(mid 385.26085 -115.738601)
					(end 385.585462 -116.241322)
				)
				(arc
					(start 385.585462 -116.241322)
					(mid 385.592768 -116.338082)
					(end 385.677918 -116.384578)
				)
				(arc
					(start 385.834382 -116.384578)
					(mid 385.9195 -116.338062)
					(end 385.926838 -116.241322)
				)
				(arc
					(start 385.926838 -116.241322)
					(mid 386.25145 -115.738601)
					(end 386.576062 -116.241322)
				)
				(arc
					(start 386.576062 -116.241322)
					(mid 386.583368 -116.338082)
					(end 386.668518 -116.384578)
				)
				(arc
					(start 387.815582 -116.384578)
					(mid 387.9007 -116.338062)
					(end 387.908038 -116.241322)
				)
				(arc
					(start 387.908038 -116.241322)
					(mid 388.23265 -115.738601)
					(end 388.557262 -116.241322)
				)
				(arc
					(start 388.557262 -116.241322)
					(mid 388.564568 -116.338082)
					(end 388.649718 -116.384578)
				)
				(arc
					(start 390.787382 -116.384578)
					(mid 390.8725 -116.338062)
					(end 390.879838 -116.241322)
				)
				(arc
					(start 390.879838 -116.241322)
					(mid 390.861299 -115.999371)
					(end 391.002012 -115.801648)
				)
				(arc
					(start 391.002012 -115.801648)
					(mid 391.044045 -115.737302)
					(end 391.028936 -115.661948)
				)
				(arc
					(start 391.028936 -115.661948)
					(mid 390.981534 -115.374503)
					(end 391.164572 -115.147852)
				)
				(arc
					(start 391.164572 -115.147852)
					(mid 391.21989 -115.058847)
					(end 391.167112 -114.968274)
				)
				(arc
					(start 391.167112 -114.968274)
					(mid 391.086958 -114.908398)
					(end 391.02665 -114.828574)
				)
				(arc
					(start 391.02665 -114.828574)
					(mid 390.93775 -114.776207)
					(end 390.84885 -114.828574)
				)
				(arc
					(start 390.84885 -114.828574)
					(mid 390.5377 -115.011598)
					(end 390.22655 -114.828574)
				)
				(arc
					(start 390.22655 -114.828574)
					(mid 390.13765 -114.776207)
					(end 390.04875 -114.828574)
				)
				(arc
					(start 390.04875 -114.828574)
					(mid 389.7376 -115.011598)
					(end 389.42645 -114.828574)
				)
				(arc
					(start 389.42645 -114.828574)
					(mid 389.33755 -114.776207)
					(end 389.24865 -114.828574)
				)
				(arc
					(start 389.24865 -114.828574)
					(mid 388.581502 -114.6556)
					(end 389.24865 -114.482626)
				)
				(arc
					(start 389.24865 -114.482626)
					(mid 389.33755 -114.534993)
					(end 389.42645 -114.482626)
				)
				(arc
					(start 389.42645 -114.482626)
					(mid 389.7376 -114.299602)
					(end 390.04875 -114.482626)
				)
				(arc
					(start 390.04875 -114.482626)
					(mid 390.13765 -114.534993)
					(end 390.22655 -114.482626)
				)
				(arc
					(start 390.22655 -114.482626)
					(mid 390.5377 -114.299602)
					(end 390.84885 -114.482626)
				)
				(arc
					(start 390.84885 -114.482626)
					(mid 390.93775 -114.534993)
					(end 391.02665 -114.482626)
				)
				(arc
					(start 391.02665 -114.482626)
					(mid 391.3378 -114.299602)
					(end 391.64895 -114.482626)
				)
				(arc
					(start 391.64895 -114.482626)
					(mid 391.73785 -114.534993)
					(end 391.82675 -114.482626)
				)
				(arc
					(start 391.82675 -114.482626)
					(mid 392.493898 -114.6556)
					(end 391.82675 -114.828574)
				)
				(arc
					(start 391.82675 -114.828574)
					(mid 391.73785 -114.776207)
					(end 391.64895 -114.828574)
				)
				(arc
					(start 391.64895 -114.828574)
					(mid 391.584846 -114.912072)
					(end 391.49909 -114.9731)
				)
				(arc
					(start 391.49909 -114.9731)
					(mid 391.443772 -115.062105)
					(end 391.49655 -115.152678)
				)
				(arc
					(start 391.49655 -115.152678)
					(mid 391.681603 -115.446707)
					(end 391.5283 -115.758468)
				)
				(arc
					(start 391.5283 -115.758468)
					(mid 391.486267 -115.822814)
					(end 391.501376 -115.898168)
				)
				(arc
					(start 391.501376 -115.898168)
					(mid 391.559411 -116.066173)
					(end 391.529062 -116.241322)
				)
				(arc
					(start 391.529062 -116.241322)
					(mid 391.536368 -116.338082)
					(end 391.621518 -116.384578)
				)
				(arc
					(start 391.777982 -116.384578)
					(mid 391.8631 -116.338062)
					(end 391.870438 -116.241322)
				)
				(arc
					(start 391.870438 -116.241322)
					(mid 392.19505 -115.738601)
					(end 392.519662 -116.241322)
				)
				(arc
					(start 392.519662 -116.241322)
					(mid 392.526968 -116.338082)
					(end 392.612118 -116.384578)
				)
				(arc
					(start 392.768582 -116.384578)
					(mid 392.8537 -116.338062)
					(end 392.861038 -116.241322)
				)
				(arc
					(start 392.861038 -116.241322)
					(mid 393.18565 -115.738601)
					(end 393.510262 -116.241322)
				)
				(arc
					(start 393.510262 -116.241322)
					(mid 393.517568 -116.338082)
					(end 393.602718 -116.384578)
				)
				(arc
					(start 393.759182 -116.384578)
					(mid 393.8443 -116.338062)
					(end 393.851638 -116.241322)
				)
				(arc
					(start 393.851638 -116.241322)
					(mid 394.17625 -115.738601)
					(end 394.500862 -116.241322)
				)
				(arc
					(start 394.500862 -116.241322)
					(mid 394.508168 -116.338082)
					(end 394.593318 -116.384578)
				)
				(arc
					(start 394.749782 -116.384578)
					(mid 394.8349 -116.338062)
					(end 394.842238 -116.241322)
				)
				(arc
					(start 394.842238 -116.241322)
					(mid 394.955636 -115.807603)
					(end 395.403324 -115.828318)
				)
				(arc
					(start 395.403324 -115.828318)
					(mid 395.473763 -115.853981)
					(end 395.542516 -115.824254)
				)
				(arc
					(start 395.61643 -115.75034)
					(mid 395.642727 -115.652097)
					(end 395.57071 -115.580414)
				)
				(arc
					(start 395.57071 -115.580414)
					(mid 395.344286 -115.075693)
					(end 395.884908 -114.958368)
				)
				(arc
					(start 395.884908 -114.958368)
					(mid 395.992248 -114.97072)
					(end 396.050008 -114.879374)
				)
				(xy 396.050008 -114.644424)
				(arc
					(start 396.651734 -114.042952)
					(mid 396.676589 -113.939828)
					(end 396.596108 -113.87074)
				)
				(arc
					(start 396.596108 -113.87074)
					(mid 396.305539 -113.441212)
					(end 396.75181 -113.177066)
				)
				(arc
					(start 396.75181 -113.177066)
					(mid 396.841019 -113.16068)
					(end 396.881604 -113.07953)
				)
				(xy 396.881604 -112.87379)
				(arc
					(start 396.67942 -112.671352)
					(mid 396.577293 -112.646181)
					(end 396.507716 -112.724946)
				)
				(arc
					(start 396.507716 -112.724946)
					(mid 395.905641 -112.912493)
					(end 396.093188 -112.310418)
				)
				(arc
					(start 396.093188 -112.310418)
					(mid 396.171788 -112.24079)
					(end 396.146782 -112.138714)
				)
				(xy 396.042388 -112.034574) (xy 396.042388 -111.990378) (xy 395.96568 -111.990378)
				(arc
					(start 395.95044 -112.011206)
					(mid 395.385308 -112.026146)
					(end 395.517878 -111.476536)
				)
				(arc
					(start 395.517878 -111.476536)
					(mid 395.576654 -111.402296)
					(end 395.548612 -111.311944)
				)
				(arc
					(start 395.53261 -111.295942)
					(mid 395.470241 -111.221495)
					(end 395.37386 -111.233458)
				)
				(arc
					(start 395.37386 -111.233458)
					(mid 394.918321 -111.198749)
					(end 394.871702 -110.744254)
				)
				(arc
					(start 394.871702 -110.744254)
					(mid 394.877082 -110.639946)
					(end 394.787628 -110.586012)
				)
				(xy 394.626846 -110.586012) (xy 393.941808 -109.900974) (xy 393.941808 -109.530896) (xy 393.555982 -109.14507)
				(xy 393.555982 -109.035596)
				(arc
					(start 393.46505 -108.944664)
					(mid 393.395954 -108.914928)
					(end 393.32535 -108.940854)
				)
				(arc
					(start 393.32535 -108.940854)
					(mid 392.734565 -108.720558)
					(end 393.250928 -108.35894)
				)
				(arc
					(start 393.250928 -108.35894)
					(mid 393.350487 -108.355524)
					(end 393.399264 -108.26877)
				)
				(xy 393.399264 -106.531664) (xy 393.0904 -106.2228) (xy 392.02614 -106.2228) (xy 391.7696 -106.2228)
				(xy 391.6934 -106.299)
				(arc
					(start 391.6934 -106.637836)
					(mid 391.648813 -106.827816)
					(end 391.510774 -106.96575)
				)
				(arc
					(start 391.510774 -106.96575)
					(mid 391.458407 -107.05465)
					(end 391.510774 -107.14355)
				)
				(arc
					(start 391.510774 -107.14355)
					(mid 391.693798 -107.4547)
					(end 391.510774 -107.76585)
				)
				(arc
					(start 391.510774 -107.76585)
					(mid 391.458407 -107.85475)
					(end 391.510774 -107.94365)
				)
				(arc
					(start 391.510774 -107.94365)
					(mid 391.589528 -108.003072)
					(end 391.64895 -108.081826)
				)
				(arc
					(start 391.64895 -108.081826)
					(mid 391.73785 -108.134193)
					(end 391.82675 -108.081826)
				)
				(arc
					(start 391.82675 -108.081826)
					(mid 392.389628 -108.003072)
					(end 392.310874 -108.56595)
				)
				(arc
					(start 392.310874 -108.56595)
					(mid 392.258507 -108.65485)
					(end 392.310874 -108.74375)
				)
				(arc
					(start 392.310874 -108.74375)
					(mid 392.389628 -109.306628)
					(end 391.82675 -109.227874)
				)
				(arc
					(start 391.82675 -109.227874)
					(mid 391.73785 -109.175507)
					(end 391.64895 -109.227874)
				)
				(arc
					(start 391.64895 -109.227874)
					(mid 391.3378 -109.410898)
					(end 391.02665 -109.227874)
				)
				(arc
					(start 391.02665 -109.227874)
					(mid 390.93775 -109.175507)
					(end 390.84885 -109.227874)
				)
				(arc
					(start 390.84885 -109.227874)
					(mid 390.5377 -109.410898)
					(end 390.22655 -109.227874)
				)
				(arc
					(start 390.22655 -109.227874)
					(mid 390.13765 -109.175507)
					(end 390.04875 -109.227874)
				)
				(arc
					(start 390.04875 -109.227874)
					(mid 389.7376 -109.410898)
					(end 389.42645 -109.227874)
				)
				(arc
					(start 389.42645 -109.227874)
					(mid 389.33755 -109.175507)
					(end 389.24865 -109.227874)
				)
				(arc
					(start 389.24865 -109.227874)
					(mid 388.685772 -109.306628)
					(end 388.764526 -108.74375)
				)
				(arc
					(start 388.764526 -108.74375)
					(mid 388.816893 -108.65485)
					(end 388.764526 -108.56595)
				)
				(arc
					(start 388.764526 -108.56595)
					(mid 388.581502 -108.2548)
					(end 388.764526 -107.94365)
				)
				(arc
					(start 388.764526 -107.94365)
					(mid 388.816893 -107.85475)
					(end 388.764526 -107.76585)
				)
				(arc
					(start 388.764526 -107.76585)
					(mid 388.581502 -107.4547)
					(end 388.764526 -107.14355)
				)
				(arc
					(start 388.764526 -107.14355)
					(mid 388.816893 -107.05465)
					(end 388.764526 -106.96575)
				)
				(arc
					(start 388.764526 -106.96575)
					(mid 388.685772 -106.402872)
					(end 389.24865 -106.481626)
				)
				(arc
					(start 389.24865 -106.481626)
					(mid 389.33755 -106.533993)
					(end 389.42645 -106.481626)
				)
				(arc
					(start 389.42645 -106.481626)
					(mid 389.485872 -106.402872)
					(end 389.564626 -106.34345)
				)
				(arc
					(start 389.564626 -106.34345)
					(mid 389.616993 -106.25455)
					(end 389.564626 -106.16565)
				)
				(arc
					(start 389.564626 -106.16565)
					(mid 389.485872 -105.602772)
					(end 390.04875 -105.681526)
				)
				(arc
					(start 390.04875 -105.681526)
					(mid 390.13765 -105.733893)
					(end 390.22655 -105.681526)
				)
				(arc
					(start 390.22655 -105.681526)
					(mid 390.285972 -105.602772)
					(end 390.364726 -105.54335)
				)
				(arc
					(start 390.364726 -105.54335)
					(mid 390.417093 -105.45445)
					(end 390.364726 -105.36555)
				)
				(arc
					(start 390.364726 -105.36555)
					(mid 390.281821 -105.302058)
					(end 390.220962 -105.217214)
				)
				(arc
					(start 390.220962 -105.217214)
					(mid 390.133785 -105.162076)
					(end 390.043416 -105.211626)
				)
				(arc
					(start 390.043416 -105.211626)
					(mid 389.381584 -105.017687)
					(end 390.054338 -104.866186)
				)
				(arc
					(start 390.054338 -104.866186)
					(mid 390.141515 -104.921324)
					(end 390.231884 -104.871774)
				)
				(arc
					(start 390.231884 -104.871774)
					(mid 390.543215 -104.698247)
					(end 390.84885 -104.881426)
				)
				(arc
					(start 390.84885 -104.881426)
					(mid 390.93775 -104.933793)
					(end 391.02665 -104.881426)
				)
				(arc
					(start 391.02665 -104.881426)
					(mid 391.086072 -104.802672)
					(end 391.164826 -104.74325)
				)
				(arc
					(start 391.164826 -104.74325)
					(mid 391.217193 -104.65435)
					(end 391.164826 -104.56545)
				)
				(arc
					(start 391.164826 -104.56545)
					(mid 391.027718 -104.429182)
					(end 390.981946 -104.241346)
				)
				(xy 390.544558 -103.803958)
				(arc
					(start 390.515602 -103.803958)
					(mid 390.045426 -103.928669)
					(end 389.889746 -103.467916)
				)
				(arc
					(start 389.889746 -103.467916)
					(mid 389.879376 -103.365854)
					(end 389.785352 -103.324914)
				)
				(xy 389.154924 -102.694486) (xy 383.507488 -102.694486) (xy 382.98628 -103.215694) (xy 382.98628 -107.637326)
				(xy 382.184656 -108.43895) (xy 381.308356 -108.43895) (xy 378.841 -110.906306) (xy 378.841 -111.9632)
				(xy 378.841 -113.538) (xy 377.5456 -114.8334) (xy 377.5456 -116.181378)
			)
		)
	)
	(zone
		(layer "In11.Cu")
		(hatch none 0.5)
		(connect_pads
			(clearance 0)
		)
		(min_thickness 0.25)
		(keepout
			(tracks allowed)
			(vias allowed)
			(pads allowed)
			(copperpour allowed)
			(footprints allowed)
		)
		(placement
			(enabled no)
			(sheetname "")
		)
		(fill
			(thermal_gap 0.5)
			(thermal_bridge_width 0.5)
			(island_removal_mode 0)
		)
		(polygon
			(pts
				(xy 391.287 -129.667) (xy 391.287 -128.524) (xy 392.176 -128.524) (xy 392.176 -129.667)
			)
		)
	)
	(zone
		(layer "In11.Cu")
		(hatch none 0.5)
		(connect_pads
			(clearance 0)
		)
		(min_thickness 0.25)
		(keepout
			(tracks not_allowed)
			(vias allowed)
			(pads allowed)
			(copperpour not_allowed)
			(footprints allowed)
		)
		(placement
			(enabled no)
			(sheetname "")
		)
		(fill
			(thermal_gap 0.5)
			(thermal_bridge_width 0.5)
			(island_removal_mode 0)
		)
		(polygon
			(pts
				(xy 380.660656 -22.575774)
				(arc
					(start 380.835662 -22.75078)
					(mid 381.156827 -23.170751)
					(end 380.736856 -22.849586)
				)
				(xy 380.602744 -22.715474) (xy 380.58471 -22.715474)
				(arc
					(start 380.58471 -22.982174)
					(mid 380.96825 -23.365714)
					(end 381.35179 -22.982174)
				)
				(arc
					(start 381.35179 -22.017228)
					(mid 380.968377 -21.633434)
					(end 380.58471 -22.016974)
				)
				(xy 380.58471 -22.283674) (xy 380.602744 -22.283674)
				(arc
					(start 380.736856 -22.149562)
					(mid 381.156827 -21.828397)
					(end 380.835662 -22.248368)
				)
				(xy 380.660656 -22.423374) (xy 380.58471 -22.423374) (xy 380.58471 -22.575774)
			)
		)
	)
	(zone
		(layer "In11.Cu")
		(hatch none 0.5)
		(connect_pads
			(clearance 0)
		)
		(min_thickness 0.25)
		(keepout
			(tracks not_allowed)
			(vias allowed)
			(pads allowed)
			(copperpour not_allowed)
			(footprints allowed)
		)
		(placement
			(enabled no)
			(sheetname "")
		)
		(fill
			(thermal_gap 0.5)
			(thermal_bridge_width 0.5)
			(island_removal_mode 0)
		)
		(polygon
			(pts
				(arc
					(start 356.215188 -115.4557)
					(mid 356.314717 -114.938044)
					(end 356.3747 -115.461796)
				)
				(xy 356.3747 -115.4938) (xy 356.22865 -115.63985) (xy 355.947726 -115.63985) (xy 355.92131 -115.613434)
				(xy 355.92131 -115.79225) (xy 356.15245 -115.79225)
				(arc
					(start 356.314248 -115.954048)
					(mid 356.376107 -116.477407)
					(end 356.159562 -115.996974)
				)
				(xy 356.094538 -115.93195) (xy 355.92131 -115.93195)
				(arc
					(start 355.92131 -116.220494)
					(mid 356.30485 -116.604034)
					(end 356.68839 -116.220494)
				)
				(arc
					(start 356.68839 -115.204748)
					(mid 356.372311 -114.826933)
					(end 355.944932 -115.071906)
				)
				(xy 355.944932 -115.439444) (xy 356.005638 -115.50015) (xy 356.170738 -115.50015)
			)
		)
	)
	(zone
		(layer "In11.Cu")
		(hatch none 0.5)
		(connect_pads
			(clearance 0)
		)
		(min_thickness 0.25)
		(keepout
			(tracks not_allowed)
			(vias allowed)
			(pads allowed)
			(copperpour not_allowed)
			(footprints allowed)
		)
		(placement
			(enabled no)
			(sheetname "")
		)
		(fill
			(thermal_gap 0.5)
			(thermal_bridge_width 0.5)
			(island_removal_mode 0)
		)
		(polygon
			(pts
				(xy 451.22465 -120.28043) (xy 451.22465 -120.53189) (xy 451.02272 -120.73382)
				(arc
					(start 450.929502 -120.73382)
					(mid 450.405585 -120.66397)
					(end 450.929502 -120.59412)
				)
				(xy 450.964808 -120.59412) (xy 451.08495 -120.473978) (xy 451.08495 -120.28043)
				(arc
					(start 450.672454 -120.28043)
					(mid 450.28866 -120.663843)
					(end 450.6722 -121.04751)
				)
				(arc
					(start 451.9422 -121.04751)
					(mid 452.32574 -120.66397)
					(end 451.9422 -120.28043)
				)
				(xy 451.51675 -120.28043) (xy 451.51675 -120.50649) (xy 451.60438 -120.59412)
				(arc
					(start 451.684898 -120.59412)
					(mid 452.208815 -120.66397)
					(end 451.684898 -120.73382)
				)
				(xy 451.546468 -120.73382) (xy 451.37705 -120.564402) (xy 451.37705 -120.28043)
			)
		)
	)
	(zone
		(net "P0V9_LAN")
		(layer "In11.Cu")
		(hatch none 0.5)
		(connect_pads
			(clearance 0.5)
		)
		(min_thickness 0.25)
		(fill yes
			(thermal_gap 0.5)
			(thermal_bridge_width 0.5)
			(island_removal_mode 0)
		)
		(polygon
			(pts
				(xy 486.695242 -47.76216) (xy 488.412536 -47.76216) (xy 489.793026 -46.38167) (xy 489.793026 -39.14394)
				(xy 489.09859 -38.449504) (xy 483.418134 -38.449504) (xy 481.81895 -40.048688) (xy 480.619816 -41.247822)
				(xy 479.651568 -41.247822) (xy 478.67316 -42.22623) (xy 478.67316 -43.48861) (xy 479.3361 -44.15155)
				(xy 479.3361 -44.158916) (xy 479.615246 -44.438062) (xy 479.615246 -48.686974) (xy 479.76663 -48.838358)
				(xy 480.170998 -48.838358) (xy 480.52355 -48.485806) (xy 480.792028 -48.217328) (xy 485.639872 -48.217328)
				(xy 486.09504 -47.76216)
			)
		)
	)
	(zone
		(net "P12V_PSU")
		(layer "In11.Cu")
		(hatch none 0.5)
		(connect_pads
			(clearance 0.5)
		)
		(min_thickness 0.25)
		(fill yes
			(thermal_gap 0.5)
			(thermal_bridge_width 0.5)
			(island_removal_mode 0)
		)
		(polygon
			(pts
				(xy 2.3114 -59.9186) (xy 2.9464 -59.2836) (xy 3.0734 -59.1566) (xy 3.0734 -51.8668) (xy 3.0734 -50.3682)
				(xy 3.4036 -50.038) (xy 9.3726 -50.038) (xy 9.451848 -50.038) (xy 10.09269 -50.678842) (xy 10.09269 -64.17691)
				(xy 7.5692 -66.7004) (xy 7.5692 -70.52691) (xy 10.09269 -73.0504) (xy 10.09269 -85.92947) (xy 9.845548 -86.176612)
				(xy 9.6012 -86.176612) (xy 4.109212 -86.176612) (xy 3.5306 -85.597746) (xy 3.5306 -68.3514) (xy 2.3114 -67.1322)
			)
		)
	)
	(zone
		(layer "In11.Cu")
		(hatch none 0.5)
		(connect_pads
			(clearance 0)
		)
		(min_thickness 0.25)
		(keepout
			(tracks not_allowed)
			(vias allowed)
			(pads allowed)
			(copperpour not_allowed)
			(footprints allowed)
		)
		(placement
			(enabled no)
			(sheetname "")
		)
		(fill
			(thermal_gap 0.5)
			(thermal_bridge_width 0.5)
			(island_removal_mode 0)
		)
		(polygon
			(pts
				(arc
					(start 320.667126 -98.549968)
					(mid 315.333126 -98.549968)
					(end 320.667126 -98.549968)
				)
			)
		)
	)
	(zone
		(layer "In11.Cu")
		(hatch none 0.5)
		(connect_pads
			(clearance 0)
		)
		(min_thickness 0.25)
		(keepout
			(tracks not_allowed)
			(vias allowed)
			(pads allowed)
			(copperpour not_allowed)
			(footprints allowed)
		)
		(placement
			(enabled no)
			(sheetname "")
		)
		(fill
			(thermal_gap 0.5)
			(thermal_bridge_width 0.5)
			(island_removal_mode 0)
		)
		(polygon
			(pts
				(arc
					(start 23.453598 -132.401056)
					(mid 24.738938 -128.784263)
					(end 23.274274 -132.332222)
				)
				(arc
					(start 23.274274 -132.332222)
					(mid 23.370668 -132.349126)
					(end 23.453598 -132.401056)
				)
			)
		)
	)
	(zone
		(layer "In11.Cu")
		(hatch none 0.5)
		(connect_pads
			(clearance 0)
		)
		(min_thickness 0.25)
		(keepout
			(tracks not_allowed)
			(vias allowed)
			(pads allowed)
			(copperpour not_allowed)
			(footprints allowed)
		)
		(placement
			(enabled no)
			(sheetname "")
		)
		(fill
			(thermal_gap 0.5)
			(thermal_bridge_width 0.5)
			(island_removal_mode 0)
		)
		(polygon
			(pts
				(xy 381.379222 -28.53944)
				(arc
					(start 381.248158 -28.408376)
					(mid 380.926993 -27.988405)
					(end 381.346964 -28.30957)
				)
				(xy 381.437134 -28.39974) (xy 381.49911 -28.39974)
				(arc
					(start 381.49911 -28.177236)
					(mid 381.115697 -27.793442)
					(end 380.73203 -28.176982)
				)
				(arc
					(start 380.73203 -29.054552)
					(mid 381.11557 -29.438092)
					(end 381.49911 -29.054552)
				)
				(xy 381.49911 -28.83154) (xy 381.437388 -28.83154)
				(arc
					(start 381.346964 -28.921964)
					(mid 380.926993 -29.243129)
					(end 381.248158 -28.823158)
				)
				(xy 381.379476 -28.69184) (xy 381.49911 -28.69184) (xy 381.49911 -28.53944)
			)
		)
	)
	(zone
		(layer "In11.Cu")
		(hatch none 0.5)
		(connect_pads
			(clearance 0)
		)
		(min_thickness 0.25)
		(keepout
			(tracks not_allowed)
			(vias allowed)
			(pads allowed)
			(copperpour not_allowed)
			(footprints allowed)
		)
		(placement
			(enabled no)
			(sheetname "")
		)
		(fill
			(thermal_gap 0.5)
			(thermal_bridge_width 0.5)
			(island_removal_mode 0)
		)
		(polygon
			(pts
				(xy 355.869748 -109.87405) (xy 356.024942 -110.029244)
				(arc
					(start 356.024942 -110.175548)
					(mid 355.955092 -110.699465)
					(end 355.885242 -110.175548)
				)
				(xy 355.885242 -110.087156) (xy 355.811836 -110.01375) (xy 355.571552 -110.01375)
				(arc
					(start 355.571552 -110.432596)
					(mid 355.954965 -110.81639)
					(end 356.338632 -110.43285)
				)
				(arc
					(start 356.338632 -109.16285)
					(mid 355.955092 -108.77931)
					(end 355.571552 -109.16285)
				)
				(xy 355.571552 -109.58195) (xy 355.811836 -109.58195) (xy 355.885242 -109.508544)
				(arc
					(start 355.885242 -109.420152)
					(mid 355.955092 -108.896235)
					(end 356.024942 -109.420152)
				)
				(xy 356.024942 -109.566456) (xy 355.869748 -109.72165) (xy 355.571552 -109.72165) (xy 355.571552 -109.87405)
			)
		)
	)
	(zone
		(layer "In11.Cu")
		(hatch none 0.5)
		(connect_pads
			(clearance 0)
		)
		(min_thickness 0.25)
		(keepout
			(tracks not_allowed)
			(vias allowed)
			(pads allowed)
			(copperpour not_allowed)
			(footprints allowed)
		)
		(placement
			(enabled no)
			(sheetname "")
		)
		(fill
			(thermal_gap 0.5)
			(thermal_bridge_width 0.5)
			(island_removal_mode 0)
		)
		(polygon
			(pts
				(arc
					(start 395.693646 -25.879298)
					(mid 395.663033 -25.868547)
					(end 395.633956 -25.854152)
				)
				(xy 395.60881 -25.879298)
			)
		)
	)
	(zone
		(layer "In11.Cu")
		(hatch none 0.5)
		(connect_pads
			(clearance 0)
		)
		(min_thickness 0.25)
		(keepout
			(tracks allowed)
			(vias allowed)
			(pads allowed)
			(copperpour allowed)
			(footprints allowed)
		)
		(placement
			(enabled no)
			(sheetname "")
		)
		(fill
			(thermal_gap 0.5)
			(thermal_bridge_width 0.5)
			(island_removal_mode 0)
		)
		(polygon
			(pts
				(xy 270.256 -90.551) (xy 276.479 -90.551) (xy 277.876 -89.154) (xy 286.258 -89.154) (xy 295.91 -98.806)
				(xy 295.91 -101.727) (xy 298.196 -104.013) (xy 298.196 -104.902) (xy 286.385 -104.902) (xy 286.385 -107.188)
				(xy 278.765 -107.188) (xy 278.765 -104.902) (xy 271.272 -104.902) (xy 270.129 -103.759) (xy 270.129 -90.678)
			)
		)
	)
	(zone
		(layer "In11.Cu")
		(hatch none 0.5)
		(connect_pads
			(clearance 0)
		)
		(min_thickness 0.25)
		(keepout
			(tracks allowed)
			(vias allowed)
			(pads allowed)
			(copperpour allowed)
			(footprints allowed)
		)
		(placement
			(enabled no)
			(sheetname "")
		)
		(fill
			(thermal_gap 0.5)
			(thermal_bridge_width 0.5)
			(island_removal_mode 0)
		)
		(polygon
			(pts
				(xy 347.345 -115.57) (xy 348.361 -115.57) (xy 348.361 -116.459) (xy 347.345 -116.459)
			)
		)
	)
	(zone
		(layer "In11.Cu")
		(hatch none 0.5)
		(connect_pads
			(clearance 0)
		)
		(min_thickness 0.25)
		(keepout
			(tracks allowed)
			(vias allowed)
			(pads allowed)
			(copperpour allowed)
			(footprints allowed)
		)
		(placement
			(enabled no)
			(sheetname "")
		)
		(fill
			(thermal_gap 0.5)
			(thermal_bridge_width 0.5)
			(island_removal_mode 0)
		)
		(polygon
			(pts
				(xy 112.17021 -61.59881) (xy 106.04627 -61.59881) (xy 106.04627 -53.248052) (xy 106.04627 -50.503836)
				(xy 106.04627 -47.875698) (xy 106.804968 -47.117) (xy 113.154968 -47.117) (xy 113.485168 -47.4472)
				(xy 113.485168 -48.707548) (xy 112.158272 -50.034444) (xy 112.17021 -50.046382) (xy 112.17021 -53.248052)
			)
		)
	)
	(zone
		(net "P1V2_AUX_BMC")
		(layer "In11.Cu")
		(hatch none 0.5)
		(connect_pads
			(clearance 0.5)
		)
		(min_thickness 0.25)
		(fill yes
			(thermal_gap 0.5)
			(thermal_bridge_width 0.5)
			(island_removal_mode 0)
		)
		(polygon
			(pts
				(xy 435.118256 -24.656034) (xy 435.83987 -23.93442) (xy 436.584598 -23.93442) (xy 444.144146 -23.93442)
				(xy 444.627 -24.417274) (xy 444.627 -28.7782) (xy 444.627 -37.3126) (xy 444.0682 -37.8714) (xy 444.0682 -38.227)
				(xy 443.8396 -38.4556) (xy 436.0418 -38.4556) (xy 436.038244 -38.452044) (xy 435.207156 -38.452044)
				(xy 434.999638 -38.244526) (xy 434.999638 -24.774652)
			)
		)
	)
	(zone
		(layer "In11.Cu")
		(hatch none 0.5)
		(connect_pads
			(clearance 0)
		)
		(min_thickness 0.25)
		(keepout
			(tracks not_allowed)
			(vias allowed)
			(pads allowed)
			(copperpour not_allowed)
			(footprints allowed)
		)
		(placement
			(enabled no)
			(sheetname "")
		)
		(fill
			(thermal_gap 0.5)
			(thermal_bridge_width 0.5)
			(island_removal_mode 0)
		)
		(polygon
			(pts
				(xy 460.7687 -121.124218) (xy 460.754222 -121.10974)
				(arc
					(start 460.343504 -121.10974)
					(mid 459.95971 -121.493153)
					(end 460.34325 -121.87682)
				)
				(arc
					(start 461.61325 -121.87682)
					(mid 461.99679 -121.49328)
					(end 461.61325 -121.10974)
				)
				(xy 461.2005 -121.10974) (xy 461.2005 -121.325894) (xy 461.298036 -121.42343)
				(arc
					(start 461.355948 -121.42343)
					(mid 461.879865 -121.49328)
					(end 461.355948 -121.56313)
				)
				(xy 461.240124 -121.56313) (xy 461.0608 -121.383806) (xy 461.0608 -121.10974) (xy 460.9084 -121.10974)
				(xy 460.9084 -121.383806) (xy 460.729076 -121.56313)
				(arc
					(start 460.600552 -121.56313)
					(mid 460.076635 -121.49328)
					(end 460.600552 -121.42343)
				)
				(xy 460.671164 -121.42343) (xy 460.7687 -121.325894)
			)
		)
	)
	(zone
		(layer "In11.Cu")
		(hatch none 0.5)
		(connect_pads
			(clearance 0)
		)
		(min_thickness 0.25)
		(keepout
			(tracks allowed)
			(vias allowed)
			(pads allowed)
			(copperpour allowed)
			(footprints allowed)
		)
		(placement
			(enabled no)
			(sheetname "")
		)
		(fill
			(thermal_gap 0.5)
			(thermal_bridge_width 0.5)
			(island_removal_mode 0)
		)
		(polygon
			(pts
				(xy 351.282 -115.951) (xy 351.282 -114.046) (xy 352.425 -114.046) (xy 352.425 -115.951)
			)
		)
	)
	(zone
		(net "PVCCIN_CPU1")
		(layer "In11.Cu")
		(hatch none 0.5)
		(connect_pads
			(clearance 0.5)
		)
		(min_thickness 0.25)
		(fill yes
			(thermal_gap 0.5)
			(thermal_bridge_width 0.5)
			(island_removal_mode 0)
		)
		(polygon
			(pts
				(xy 115.941602 -68.28409) (xy 116.0018 -68.223892) (xy 116.0018 -67.5386) (xy 110.926118 -64.516)
				(xy 110.2868 -64.516) (xy 110.0074 -64.7954) (xy 110.0074 -65.0748) (xy 110.5408 -65.6082) (xy 110.5408 -67.8688)
				(xy 110.1852 -68.2244) (xy 108.585 -68.2244) (xy 108.4326 -68.072) (xy 108.34624 -67.98564) (xy 106.29138 -67.98564)
				(xy 98.92792 -67.98564) (xy 95.191834 -64.249554) (xy 94.601284 -64.249554) (xy 90.11412 -66.7258)
				(xy 88.1634 -67.8434) (xy 88.138 -67.8688) (xy 85.5472 -67.8688) (xy 78.359 -67.8688) (xy 76.7334 -69.4944)
				(xy 72.7964 -69.4944) (xy 71.512684 -68.210684) (xy 65.037462 -68.210684) (xy 65.023746 -68.2244)
				(xy 60.071 -68.2244) (xy 60.071 -68.184268) (xy 44.3484 -52.461668) (xy 43.931332 -52.461668) (xy 43.660568 -52.732432)
				(xy 43.660568 -92.202) (xy 43.688 -92.202) (xy 43.9166 -92.4306) (xy 48.3743 -92.4306) (xy 49.00168 -91.80322)
				(xy 52.60594 -91.80322) (xy 61.13526 -83.31708) (xy 64.28232 -83.35772) (xy 67.94246 -80.27924)
				(xy 68.88734 -80.75168) (xy 72.40016 -78.72476) (xy 74.8157 -78.28026) (xy 75.8444 -77.9018) (xy 77.82814 -78.80096)
				(xy 79.19212 -79.7052) (xy 80.28686 -79.54264) (xy 88.7984 -84.455) (xy 91.758008 -86.1822) (xy 94.792038 -87.877142)
				(xy 96.072198 -87.877142) (xy 98.69424 -85.2551) (xy 107.45724 -85.2551) (xy 107.462828 -85.260688)
				(xy 109.415072 -85.260688) (xy 109.799882 -85.645498) (xy 109.799882 -86.611714) (xy 110.046008 -86.85784)
				(xy 112.91316 -86.85784) (xy 113.27384 -86.49716) (xy 113.27384 -86.37016) (xy 116.25326 -83.39074)
				(xy 116.25326 -68.595748)
			)
		)
	)
	(zone
		(layer "In11.Cu")
		(hatch none 0.5)
		(connect_pads
			(clearance 0)
		)
		(min_thickness 0.25)
		(keepout
			(tracks not_allowed)
			(vias allowed)
			(pads allowed)
			(copperpour not_allowed)
			(footprints allowed)
		)
		(placement
			(enabled no)
			(sheetname "")
		)
		(fill
			(thermal_gap 0.5)
			(thermal_bridge_width 0.5)
			(island_removal_mode 0)
		)
		(polygon
			(pts
				(xy 381.03048 -25.478232) (xy 381.051816 -25.478232)
				(arc
					(start 381.05461 -25.284176)
					(mid 380.676531 -24.895304)
					(end 380.28753 -25.273254)
				)
				(arc
					(start 380.2761 -26.09215)
					(mid 380.654306 -26.481024)
					(end 381.04318 -26.102818)
				)
				(xy 381.045974 -25.910032) (xy 381.014478 -25.910032)
				(arc
					(start 380.91237 -26.01214)
					(mid 380.438777 -26.24667)
					(end 380.832614 -25.894284)
				)
				(xy 380.956566 -25.770332) (xy 381.047752 -25.770332) (xy 381.050038 -25.617932) (xy 380.972568 -25.617932)
				(arc
					(start 380.839726 -25.48509)
					(mid 380.453599 -25.124334)
					(end 380.921768 -25.36952)
				)
			)
		)
	)
	(zone
		(net "P3V3_STBY")
		(layer "In11.Cu")
		(hatch none 0.5)
		(connect_pads
			(clearance 0.5)
		)
		(min_thickness 0.25)
		(fill yes
			(thermal_gap 0.5)
			(thermal_bridge_width 0.5)
			(island_removal_mode 0)
		)
		(polygon
			(pts
				(xy 480.441 -120.7262) (xy 484.57866 -120.7262) (xy 484.95712 -120.34774) (xy 484.95712 -113.72088)
				(xy 484.16464 -112.9284) (xy 479.9838 -112.9284) (xy 479.8568 -113.0554) (xy 479.8568 -120.142)
			)
		)
	)
	(zone
		(layer "In11.Cu")
		(hatch none 0.5)
		(connect_pads
			(clearance 0)
		)
		(min_thickness 0.25)
		(keepout
			(tracks not_allowed)
			(vias allowed)
			(pads allowed)
			(copperpour not_allowed)
			(footprints allowed)
		)
		(placement
			(enabled no)
			(sheetname "")
		)
		(fill
			(thermal_gap 0.5)
			(thermal_bridge_width 0.5)
			(island_removal_mode 0)
		)
		(polygon
			(pts
				(xy 395.50086 -32.58947)
				(arc
					(start 395.50086 -32.674306)
					(mid 395.511611 -32.643693)
					(end 395.526006 -32.614616)
				)
			)
		)
	)
	(zone
		(layer "In11.Cu")
		(hatch none 0.5)
		(connect_pads
			(clearance 0)
		)
		(min_thickness 0.25)
		(keepout
			(tracks not_allowed)
			(vias allowed)
			(pads allowed)
			(copperpour not_allowed)
			(footprints allowed)
		)
		(placement
			(enabled no)
			(sheetname "")
		)
		(fill
			(thermal_gap 0.5)
			(thermal_bridge_width 0.5)
			(island_removal_mode 0)
		)
		(polygon
			(pts
				(xy 359.83291 -107.16133) (xy 359.791254 -105.915206)
				(arc
					(start 359.788714 -105.915206)
					(mid 359.392474 -105.544874)
					(end 359.022142 -105.941114)
				)
				(xy 359.019602 -105.941114) (xy 359.032556 -106.326686) (xy 359.262172 -106.326686) (xy 359.335578 -106.25328)
				(arc
					(start 359.335578 -106.185462)
					(mid 359.405428 -105.661545)
					(end 359.475278 -106.185462)
				)
				(xy 359.475278 -106.311192) (xy 359.320084 -106.466386) (xy 359.037128 -106.466386) (xy 359.042208 -106.618786)
				(xy 359.301288 -106.618786) (xy 359.516934 -106.834432)
				(arc
					(start 359.516934 -106.916982)
					(mid 359.447084 -107.440899)
					(end 359.377234 -106.916982)
				)
				(xy 359.377234 -106.892344) (xy 359.243376 -106.758486) (xy 359.047034 -106.758486) (xy 359.061258 -107.186984)
				(xy 359.061512 -107.187238)
				(arc
					(start 359.063798 -107.187238)
					(mid 359.460038 -107.55757)
					(end 359.83037 -107.16133)
				)
			)
		)
	)
	(zone
		(layer "In11.Cu")
		(hatch none 0.5)
		(connect_pads
			(clearance 0)
		)
		(min_thickness 0.25)
		(keepout
			(tracks not_allowed)
			(vias allowed)
			(pads allowed)
			(copperpour not_allowed)
			(footprints allowed)
		)
		(placement
			(enabled no)
			(sheetname "")
		)
		(fill
			(thermal_gap 0.5)
			(thermal_bridge_width 0.5)
			(island_removal_mode 0)
		)
		(polygon
			(pts
				(arc
					(start 406.48509 -136.204452)
					(mid 408.759336 -134.444829)
					(end 407.627074 -131.801616)
				)
				(arc
					(start 405.343106 -131.801616)
					(mid 404.21081 -134.444838)
					(end 406.48509 -136.204452)
				)
			)
		)
	)
	(zone
		(layer "In11.Cu")
		(hatch none 0.5)
		(connect_pads
			(clearance 0)
		)
		(min_thickness 0.25)
		(keepout
			(tracks not_allowed)
			(vias allowed)
			(pads allowed)
			(copperpour not_allowed)
			(footprints allowed)
		)
		(placement
			(enabled no)
			(sheetname "")
		)
		(fill
			(thermal_gap 0.5)
			(thermal_bridge_width 0.5)
			(island_removal_mode 0)
		)
		(polygon
			(pts
				(xy 395.672056 -34.563304) (xy 395.82725 -34.718498)
				(arc
					(start 395.82725 -34.801048)
					(mid 395.944811 -34.868718)
					(end 396.01394 -34.985452)
				)
				(arc
					(start 396.01394 -33.988502)
					(mid 395.944869 -34.105294)
					(end 395.82725 -34.172906)
				)
				(xy 395.82725 -34.25571) (xy 395.672056 -34.410904) (xy 395.50086 -34.410904) (xy 395.50086 -34.563304)
			)
		)
	)
	(zone
		(layer "In11.Cu")
		(hatch none 0.5)
		(connect_pads
			(clearance 0)
		)
		(min_thickness 0.25)
		(keepout
			(tracks not_allowed)
			(vias allowed)
			(pads allowed)
			(copperpour not_allowed)
			(footprints allowed)
		)
		(placement
			(enabled no)
			(sheetname "")
		)
		(fill
			(thermal_gap 0.5)
			(thermal_bridge_width 0.5)
			(island_removal_mode 0)
		)
		(polygon
			(pts
				(arc
					(start 357.186738 -105.942638)
					(mid 357.606709 -105.621473)
					(end 357.285544 -106.041444)
				)
				(xy 357.034592 -106.292396) (xy 357.034592 -106.597704)
				(arc
					(start 357.285544 -106.848656)
					(mid 357.606709 -107.268627)
					(end 357.186738 -106.947462)
				)
				(xy 357.034592 -106.795316)
				(arc
					(start 357.034592 -107.079796)
					(mid 357.418005 -107.46359)
					(end 357.801672 -107.08005)
				)
				(arc
					(start 357.801672 -105.81005)
					(mid 357.418132 -105.42651)
					(end 357.034592 -105.81005)
				)
				(xy 357.034592 -106.094784)
			)
		)
	)
	(zone
		(layer "In11.Cu")
		(hatch none 0.5)
		(connect_pads
			(clearance 0)
		)
		(min_thickness 0.25)
		(keepout
			(tracks not_allowed)
			(vias allowed)
			(pads allowed)
			(copperpour not_allowed)
			(footprints allowed)
		)
		(placement
			(enabled no)
			(sheetname "")
		)
		(fill
			(thermal_gap 0.5)
			(thermal_bridge_width 0.5)
			(island_removal_mode 0)
		)
		(polygon
			(pts
				(arc
					(start 395.68755 -34.172906)
					(mid 395.569989 -34.105236)
					(end 395.50086 -33.988502)
				)
				(xy 395.50086 -34.271204) (xy 395.614144 -34.271204) (xy 395.68755 -34.197798)
			)
		)
	)
	(zone
		(net "VR_FET_SW_P12V_STBY_PVDDQ_ABC")
		(layer "In11.Cu")
		(hatch none 0.5)
		(connect_pads
			(clearance 0.5)
		)
		(min_thickness 0.25)
		(fill yes
			(thermal_gap 0.5)
			(thermal_bridge_width 0.5)
			(island_removal_mode 0)
		)
		(polygon
			(pts
				(xy 349.939356 5.207) (xy 347.9546 5.207) (xy 345.821 3.0734) (xy 345.821 -2.463038) (xy 347.2688 -3.910838)
				(xy 347.2688 -9.13892) (xy 347.42374 -9.29386) (xy 349.68942 -9.29386) (xy 349.84309 -9.44753) (xy 349.84309 -10.88009)
				(xy 351.917 -12.954) (xy 351.917 -19.05) (xy 351.912428 -19.054572) (xy 351.912428 -20.261834) (xy 352.065844 -20.41525)
				(xy 355.253798 -20.41525) (xy 355.727 -19.942048) (xy 355.727 -19.05) (xy 356.616 -18.161) (xy 356.616 -12.475972)
				(xy 356.545388 -12.40536) (xy 355.737414 -11.597386) (xy 355.737414 -10.299192) (xy 356.611682 -9.424924)
				(xy 357.224076 -9.424924) (xy 358.800908 -7.848092) (xy 358.800908 -4.048506) (xy 358.800908 -2.77876)
				(xy 357.760016 -1.737868) (xy 355.574346 -1.737868) (xy 353.695 0.141478) (xy 353.695 1.057402)
				(xy 353.695 4.26466) (xy 352.75266 5.207) (xy 350.699832 5.207)
			)
		)
	)
	(zone
		(net "P3V3")
		(layer "In11.Cu")
		(hatch none 0.5)
		(connect_pads
			(clearance 0.5)
		)
		(min_thickness 0.25)
		(fill yes
			(thermal_gap 0.5)
			(thermal_bridge_width 0.5)
			(island_removal_mode 0)
		)
		(polygon
			(pts
				(xy 180.721 -81.4324) (xy 182.4736 -81.4324) (xy 182.6768 -81.6356) (xy 182.6768 -82.8802) (xy 182.118 -83.439)
				(xy 180.6194 -83.439) (xy 180.5178 -83.3374) (xy 180.2892 -83.1088) (xy 180.2892 -81.8642) (xy 180.5178 -81.6356)
			)
		)
	)
	(zone
		(net "GND")
		(layer "In11.Cu")
		(hatch none 0.5)
		(connect_pads
			(clearance 0.5)
		)
		(min_thickness 0.25)
		(fill yes
			(thermal_gap 0.5)
			(thermal_bridge_width 0.5)
			(island_removal_mode 0)
		)
		(polygon
			(pts
				(xy 36.835588 -101.681026) (xy 43.2054 -95.311468) (xy 43.2054 -93.7514) (xy 42.977308 -93.523308)
				(xy 34.784792 -93.523308) (xy 34.5821 -93.726) (xy 34.5821 -99.7331) (xy 33.3502 -100.965) (xy 33.3502 -102.489)
				(xy 33.4772 -102.616) (xy 36.587176 -102.616) (xy 36.619434 -102.583742) (xy 36.835588 -102.367334)
			)
		)
	)
	(zone
		(net "P1V15_AUX_BMC")
		(layer "In11.Cu")
		(hatch none 0.5)
		(connect_pads
			(clearance 0.5)
		)
		(min_thickness 0.25)
		(fill yes
			(thermal_gap 0.5)
			(thermal_bridge_width 0.5)
			(island_removal_mode 0)
		)
		(polygon
			(pts
				(xy 427.0756 -47.8028) (xy 427.4566 -47.8028) (xy 431.6222 -47.8028) (xy 432.308 -47.117) (xy 434.594 -47.117)
				(xy 435.8767 -48.3997) (xy 435.8767 -48.5521) (xy 436.1688 -48.8442) (xy 459.232 -48.8442) (xy 459.9813 -48.0949)
				(xy 459.9813 -47.4599) (xy 459.9813 -41.0464) (xy 459.613 -40.6781) (xy 457.3397 -40.6781) (xy 445.098932 -40.6781)
				(xy 444.7667 -41.010332) (xy 439.770012 -41.010332) (xy 428.218346 -41.010332) (xy 426.6692 -42.559478)
				(xy 426.5295 -42.699178) (xy 426.5295 -43.14952) (xy 426.5295 -47.62754) (xy 426.70476 -47.8028)
			)
		)
	)
	(zone
		(net "PVCCIO_CPU1")
		(layer "In11.Cu")
		(hatch none 0.5)
		(connect_pads
			(clearance 0.5)
		)
		(min_thickness 0.25)
		(fill yes
			(thermal_gap 0.5)
			(thermal_bridge_width 0.5)
			(island_removal_mode 0)
		)
		(polygon
			(pts
				(xy 127.4445 -73.4695) (xy 123.317 -69.342) (xy 120.4468 -69.342) (xy 118.9228 -70.866) (xy 118.9228 -71.7804)
				(xy 118.9101 -71.7931) (xy 118.999 -71.882) (xy 118.999 -72.136) (xy 120.65 -72.136) (xy 121.539 -73.025)
				(xy 121.539 -73.787) (xy 120.142 -73.787) (xy 119.5578 -73.2028) (xy 117.5004 -73.2028) (xy 117.5004 -80.3656)
				(xy 118.6307 -81.4959) (xy 118.6307 -84.2137) (xy 119.2022 -84.7852) (xy 121.0056 -84.7852) (xy 122.0978 -83.693)
				(xy 122.0978 -82.7786) (xy 122.9106 -81.9658) (xy 123.2662 -81.9658) (xy 123.7488 -81.4832) (xy 124.3076 -81.4832)
				(xy 127.4445 -78.3463)
			)
		)
	)
	(zone
		(net "PVTT_ABC")
		(layer "In11.Cu")
		(hatch none 0.5)
		(connect_pads
			(clearance 0.5)
		)
		(min_thickness 0.25)
		(fill yes
			(thermal_gap 0.5)
			(thermal_bridge_width 0.5)
			(island_removal_mode 0)
		)
		(polygon
			(pts
				(xy 257.76428 -10.61974) (xy 260.59638 -10.61974) (xy 262.69188 -8.52424) (xy 262.69188 1.73228)
				(xy 261.60476 2.8194) (xy 258.67868 2.8194) (xy 257.38582 1.52654) (xy 257.38582 -10.24128)
			)
		)
	)
	(zone
		(net "P12V")
		(layer "In11.Cu")
		(hatch none 0.5)
		(connect_pads
			(clearance 0.5)
		)
		(min_thickness 0.25)
		(fill yes
			(thermal_gap 0.5)
			(thermal_bridge_width 0.5)
			(island_removal_mode 0)
		)
		(polygon
			(pts
				(xy 492.890556 -20.864576) (xy 496.403376 -20.864576) (xy 496.71351 -20.554442) (xy 496.71351 -19.863816)
				(xy 496.71351 -17.99463) (xy 496.303046 -17.584166) (xy 494.43386 -17.584166) (xy 490.115098 -17.584166)
				(xy 489.83646 -17.862804) (xy 489.83646 -18.76552) (xy 490.25683 -19.18589) (xy 491.21187 -19.18589)
			)
		)
	)
	(zone
		(net "GND")
		(layer "In11.Cu")
		(hatch none 0.5)
		(connect_pads
			(clearance 0.5)
		)
		(min_thickness 0.25)
		(fill yes
			(thermal_gap 0.5)
			(thermal_bridge_width 0.5)
			(island_removal_mode 0)
		)
		(polygon
			(pts
				(xy 110.2614 -66.929) (xy 110.2614 -65.6082) (xy 109.728 -65.0748) (xy 109.728 -63.673228) (xy 109.549946 -63.495174)
				(xy 109.549946 -62.983618) (xy 108.643928 -62.0776) (xy 106.6546 -62.0776) (xy 106.299 -62.4332)
				(xy 106.299 -63.627) (xy 106.7308 -64.0588) (xy 106.7308 -65.786) (xy 107.4928 -66.548) (xy 107.776772 -66.831972)
				(xy 108.423456 -66.831972) (xy 108.626402 -67.034918) (xy 108.626402 -67.630802) (xy 108.9152 -67.9196)
				(xy 109.9566 -67.9196) (xy 110.1344 -67.7418) (xy 110.2614 -67.6148)
			)
		)
	)
	(zone
		(layer "In11.Cu")
		(hatch none 0.5)
		(connect_pads
			(clearance 0)
		)
		(min_thickness 0.25)
		(keepout
			(tracks allowed)
			(vias allowed)
			(pads allowed)
			(copperpour allowed)
			(footprints allowed)
		)
		(placement
			(enabled no)
			(sheetname "")
		)
		(fill
			(thermal_gap 0.5)
			(thermal_bridge_width 0.5)
			(island_removal_mode 0)
		)
		(polygon
			(pts
				(xy 353.822 -114.554) (xy 353.822 -112.649) (xy 354.965 -112.649) (xy 354.965 -114.554)
			)
		)
	)
	(zone
		(layer "In11.Cu")
		(hatch none 0.5)
		(connect_pads
			(clearance 0)
		)
		(min_thickness 0.25)
		(keepout
			(tracks allowed)
			(vias allowed)
			(pads allowed)
			(copperpour allowed)
			(footprints allowed)
		)
		(placement
			(enabled no)
			(sheetname "")
		)
		(fill
			(thermal_gap 0.5)
			(thermal_bridge_width 0.5)
			(island_removal_mode 0)
		)
		(polygon
			(pts
				(xy 347.726 -114.3) (xy 349.631 -114.3) (xy 349.631 -115.443) (xy 347.726 -115.443)
			)
		)
	)
	(zone
		(layer "In11.Cu")
		(hatch none 0.5)
		(connect_pads
			(clearance 0)
		)
		(min_thickness 0.25)
		(keepout
			(tracks allowed)
			(vias allowed)
			(pads allowed)
			(copperpour allowed)
			(footprints allowed)
		)
		(placement
			(enabled no)
			(sheetname "")
		)
		(fill
			(thermal_gap 0.5)
			(thermal_bridge_width 0.5)
			(island_removal_mode 0)
		)
		(polygon
			(pts
				(xy 352.552 -116.205) (xy 352.552 -114.3) (xy 353.695 -114.3) (xy 353.695 -116.205)
			)
		)
	)
	(zone
		(layer "In11.Cu")
		(hatch none 0.5)
		(connect_pads
			(clearance 0)
		)
		(min_thickness 0.25)
		(keepout
			(tracks allowed)
			(vias allowed)
			(pads allowed)
			(copperpour allowed)
			(footprints allowed)
		)
		(placement
			(enabled no)
			(sheetname "")
		)
		(fill
			(thermal_gap 0.5)
			(thermal_bridge_width 0.5)
			(island_removal_mode 0)
		)
		(polygon
			(pts
				(xy 253.365 -97.155) (xy 253.365 -86.614) (xy 249.174 -82.423) (xy 234.442 -82.423) (xy 231.521 -85.344)
				(xy 230.378 -85.344) (xy 228.219 -87.503) (xy 228.219 -98.552) (xy 235.585 -105.918) (xy 239.141 -105.918)
				(xy 241.3 -103.759) (xy 250.698 -103.759) (xy 250.825 -103.632) (xy 250.825 -103.124) (xy 250.825 -99.695)
			)
		)
	)
	(zone
		(net "PVCCIN_CPU0")
		(layer "In11.Cu")
		(hatch none 0.5)
		(connect_pads
			(clearance 0.5)
		)
		(min_thickness 0.25)
		(fill yes
			(thermal_gap 0.5)
			(thermal_bridge_width 0.5)
			(island_removal_mode 0)
		)
		(polygon
			(pts
				(xy 259.359654 -64.001142) (xy 257.609086 -65.013078) (xy 250.6853 -69.4055) (xy 250.0884 -70.0024)
				(xy 236.22 -70.0024) (xy 235.3564 -69.1388) (xy 230.96601 -69.1388) (xy 230.062278 -68.235068) (xy 225.384868 -68.235068)
				(xy 225.3234 -68.1736) (xy 225.3234 -68.108068) (xy 210.961732 -53.7464) (xy 208.534 -53.7464) (xy 208.434432 -53.845968)
				(xy 208.434432 -92.105988) (xy 208.822036 -92.493592) (xy 216.072974 -92.493592) (xy 225.421952 -83.144614)
				(xy 228.284024 -83.144614)
				(arc
					(start 231.767126 -83.144614)
					(mid 231.907277 -82.999409)
					(end 232.101898 -82.945986)
				)
				(arc
					(start 232.749598 -82.945986)
					(mid 233.022575 -83.061086)
					(end 233.130852 -83.336892)
				)
				(arc
					(start 233.130852 -83.336892)
					(mid 233.159699 -83.410135)
					(end 233.232198 -83.440778)
				)
				(xy 233.844338 -83.440778) (xy 238.932974 -80.485742) (xy 248.871232 -80.485742) (xy 257.10769 -88.7222)
				(xy 258.2164 -88.7222) (xy 259.217414 -87.721186) (xy 259.813552 -87.721186) (xy 260.203696 -87.331042)
				(xy 260.203696 -86.734904) (xy 262.001 -84.9376) (xy 268.478 -84.9376) (xy 268.49959 -84.95919)
				(xy 272.16227 -84.95919) (xy 274.593558 -84.95919) (xy 274.829016 -85.194648) (xy 274.87626 -85.241892)
				(xy 274.87626 -86.187026) (xy 274.998434 -86.3092) (xy 276.164294 -86.3092) (xy 280.750264 -81.723484)
				(xy 280.750264 -67.567556) (xy 280.75255 -67.56527) (xy 276.356826 -64.714374) (xy 276.077426 -64.714374)
				(xy 275.9202 -64.8716) (xy 275.9202 -65.9511) (xy 275.7678 -66.1035) (xy 275.7678 -66.3702) (xy 275.761704 -66.376296)
				(xy 275.761704 -66.496692) (xy 275.724366 -66.53403) (xy 275.724366 -67.79387) (xy 275.420074 -68.098162)
				(xy 273.58975 -68.098162) (xy 271.427702 -68.098162) (xy 271.26184 -67.9323) (xy 263.88822 -67.9323)
				(xy 259.957062 -64.001142)
			)
		)
		(polygon
			(pts
				(arc
					(start 236.980222 -80.912208)
					(mid 236.883772 -80.885447)
					(end 236.811312 -80.954372)
				)
				(arc
					(start 236.811312 -80.954372)
					(mid 236.480499 -81.206455)
					(end 236.136434 -80.972914)
				)
				(arc
					(start 236.136434 -80.972914)
					(mid 236.062815 -80.908615)
					(end 235.969048 -80.936084)
				)
				(xy 235.910374 -80.995012) (xy 235.835952 -80.995012) (xy 235.835952 -81.068164)
				(arc
					(start 235.852462 -81.08315)
					(mid 235.910327 -81.54086)
					(end 235.467906 -81.671668)
				)
				(arc
					(start 235.467906 -81.671668)
					(mid 235.371508 -81.679579)
					(end 235.325412 -81.764632)
				)
				(arc
					(start 235.325412 -81.918048)
					(mid 235.371487 -82.003133)
					(end 235.467906 -82.011012)
				)
				(arc
					(start 235.467906 -82.011012)
					(mid 235.689727 -81.989028)
					(end 235.881164 -82.103214)
				)
				(arc
					(start 235.881164 -82.103214)
					(mid 235.913674 -82.120378)
					(end 235.949236 -82.111088)
				)
				(arc
					(start 235.949236 -82.111088)
					(mid 236.025639 -82.06146)
					(end 236.106716 -82.019902)
				)
				(arc
					(start 236.106716 -82.019902)
					(mid 236.132427 -81.993797)
					(end 236.133894 -81.957164)
				)
				(arc
					(start 236.133894 -81.957164)
					(mid 236.292662 -81.532518)
					(end 236.739684 -81.60766)
				)
				(arc
					(start 236.739684 -81.60766)
					(mid 236.772194 -81.624824)
					(end 236.807756 -81.615534)
				)
				(arc
					(start 236.807756 -81.615534)
					(mid 236.884164 -81.566028)
					(end 236.965236 -81.524602)
				)
				(arc
					(start 236.965236 -81.524602)
					(mid 236.990947 -81.498497)
					(end 236.992414 -81.461864)
				)
				(arc
					(start 236.992414 -81.461864)
					(mid 236.978931 -81.281612)
					(end 237.05566 -81.117948)
				)
				(arc
					(start 237.05566 -81.117948)
					(mid 237.078881 -81.048413)
					(end 237.04931 -80.981296)
				)
			)
		)
		(polygon
			(pts
				(arc
					(start 280.283412 -74.423778)
					(mid 280.207088 -74.408679)
					(end 280.142442 -74.451972)
				)
				(arc
					(start 280.142442 -74.451972)
					(mid 279.871637 -74.609801)
					(end 279.581102 -74.492358)
				)
				(arc
					(start 279.581102 -74.492358)
					(mid 279.488735 -74.459924)
					(end 279.411938 -74.520552)
				)
				(arc
					(start 279.411938 -74.520552)
					(mid 279.352375 -74.615749)
					(end 279.266142 -74.687684)
				)
				(arc
					(start 279.266142 -74.687684)
					(mid 279.216731 -74.773043)
					(end 279.263094 -74.86015)
				)
				(arc
					(start 279.263094 -74.86015)
					(mid 279.320197 -74.905841)
					(end 279.366726 -74.962258)
				)
				(arc
					(start 279.366726 -74.962258)
					(mid 279.451308 -75.007525)
					(end 279.53589 -74.962258)
				)
				(arc
					(start 279.53589 -74.962258)
					(mid 279.794075 -74.805565)
					(end 280.079704 -74.903584)
				)
				(arc
					(start 280.079704 -74.903584)
					(mid 280.156691 -74.932168)
					(end 280.229564 -74.89444)
				)
				(arc
					(start 280.229564 -74.89444)
					(mid 280.4055 -74.776703)
					(end 280.617168 -74.779632)
				)
				(arc
					(start 280.617168 -74.779632)
					(mid 280.704101 -74.76817)
					(end 280.749756 -74.693272)
				)
				(arc
					(start 280.749756 -74.543412)
					(mid 280.701624 -74.466865)
					(end 280.61158 -74.459084)
				)
				(arc
					(start 280.61158 -74.459084)
					(mid 280.443163 -74.48173)
					(end 280.283412 -74.423778)
				)
			)
		)
	)
	(zone
		(layer "In11.Cu")
		(hatch none 0.5)
		(connect_pads
			(clearance 0)
		)
		(min_thickness 0.25)
		(keepout
			(tracks allowed)
			(vias allowed)
			(pads allowed)
			(copperpour allowed)
			(footprints allowed)
		)
		(placement
			(enabled no)
			(sheetname "")
		)
		(fill
			(thermal_gap 0.5)
			(thermal_bridge_width 0.5)
			(island_removal_mode 0)
		)
		(polygon
			(pts
				(xy 353.822 -112.8014) (xy 353.822 -110.8964) (xy 354.965 -110.8964) (xy 354.965 -112.8014)
			)
		)
	)
	(zone
		(net "PVTT_DEF")
		(layer "In11.Cu")
		(hatch none 0.5)
		(connect_pads
			(clearance 0.5)
		)
		(min_thickness 0.25)
		(fill yes
			(thermal_gap 0.5)
			(thermal_bridge_width 0.5)
			(island_removal_mode 0)
		)
		(polygon
			(pts
				(xy 256.159 -156.464) (xy 262.128 -156.464) (xy 262.4582 -156.1338) (xy 262.4582 -147.32) (xy 261.3406 -146.2024)
				(xy 260.8834 -146.2024) (xy 258.5212 -148.5646) (xy 256.5908 -148.5646) (xy 256.5654 -148.5392)
				(xy 255.7526 -149.352) (xy 255.7526 -156.0576)
			)
		)
	)
	(zone
		(net "GND")
		(layer "In11.Cu")
		(hatch none 0.5)
		(connect_pads
			(clearance 0.5)
		)
		(min_thickness 0.25)
		(fill yes
			(thermal_gap 0.5)
			(thermal_bridge_width 0.5)
			(island_removal_mode 0)
		)
		(polygon
			(pts
				(xy 275.463 -66.294) (xy 275.463 -64.4144) (xy 275.6408 -64.2366) (xy 276.0091 -64.2366) (xy 276.1234 -64.1223)
				(xy 276.1234 -63.6143) (xy 275.9456 -63.4365) (xy 275.6916 -63.4365) (xy 275.463 -63.2079) (xy 275.463 -62.3824)
				(xy 275.1328 -62.0522) (xy 274.4724 -62.0522) (xy 274.32 -62.2046) (xy 273.6596 -62.2046) (xy 273.05 -61.595)
				(xy 272.161 -61.595) (xy 271.7038 -62.0522) (xy 271.7038 -65.4812) (xy 273.0754 -66.8528) (xy 273.4564 -66.8528)
				(xy 273.575526 -66.971926) (xy 273.575526 -67.81292) (xy 273.703796 -67.94119) (xy 275.16201 -67.94119)
				(xy 275.336 -67.7672) (xy 275.463 -67.6402) (xy 275.463 -67.4624)
			)
		)
	)
	(zone
		(layer "In11.Cu")
		(hatch none 0.5)
		(connect_pads
			(clearance 0)
		)
		(min_thickness 0.25)
		(keepout
			(tracks not_allowed)
			(vias allowed)
			(pads allowed)
			(copperpour not_allowed)
			(footprints allowed)
		)
		(placement
			(enabled no)
			(sheetname "")
		)
		(fill
			(thermal_gap 0.5)
			(thermal_bridge_width 0.5)
			(island_removal_mode 0)
		)
		(polygon
			(pts
				(arc
					(start 394.948156 -25.366218)
					(mid 395.122251 -25.522152)
					(end 395.106652 -25.755346)
				)
				(xy 395.230604 -25.879298) (xy 395.411198 -25.879298)
				(arc
					(start 395.53515 -25.755346)
					(mid 395.519559 -25.522155)
					(end 395.693646 -25.366218)
				)
			)
		)
	)
	(zone
		(net "VR_FET_SW_P12V_STBY_PVCCIO_CPU0")
		(layer "In11.Cu")
		(hatch none 0.5)
		(connect_pads
			(clearance 0.5)
		)
		(min_thickness 0.25)
		(fill yes
			(thermal_gap 0.5)
			(thermal_bridge_width 0.5)
			(island_removal_mode 0)
		)
		(polygon
			(pts
				(xy 352.6282 -102.1842) (xy 352.6282 -100.9904) (xy 351.9932 -100.3554) (xy 350.4946 -100.3554)
				(xy 350.1898 -100.0506) (xy 350.1898 -97.365312) (xy 350.8248 -96.730312) (xy 350.8248 -93.965268)
				(xy 350.636332 -93.7768) (xy 348.816168 -93.7768) (xy 348.584012 -94.008956) (xy 348.237302 -94.008956)
				(xy 348.005146 -93.7768) (xy 344.1192 -93.7768) (xy 343.281 -94.615) (xy 343.281 -99.06) (xy 345.16187 -100.94087)
				(xy 346.075 -100.94087) (xy 346.640404 -101.506274) (xy 346.640404 -102.419404) (xy 346.9132 -102.6922)
				(xy 347.1418 -102.9208) (xy 351.8916 -102.9208)
			)
		)
	)
	(zone
		(layer "In11.Cu")
		(hatch none 0.5)
		(connect_pads
			(clearance 0)
		)
		(min_thickness 0.25)
		(keepout
			(tracks allowed)
			(vias allowed)
			(pads allowed)
			(copperpour allowed)
			(footprints allowed)
		)
		(placement
			(enabled no)
			(sheetname "")
		)
		(fill
			(thermal_gap 0.5)
			(thermal_bridge_width 0.5)
			(island_removal_mode 0)
		)
		(polygon
			(pts
				(xy 353.8982 -110.236) (xy 353.8982 -108.331) (xy 355.0412 -108.331) (xy 355.0412 -110.236)
			)
		)
	)
	(zone
		(layer "In11.Cu")
		(hatch none 0.5)
		(connect_pads
			(clearance 0)
		)
		(min_thickness 0.25)
		(keepout
			(tracks not_allowed)
			(vias allowed)
			(pads allowed)
			(copperpour not_allowed)
			(footprints allowed)
		)
		(placement
			(enabled no)
			(sheetname "")
		)
		(fill
			(thermal_gap 0.5)
			(thermal_bridge_width 0.5)
			(island_removal_mode 0)
		)
		(polygon
			(pts
				(xy 448.063874 -120.43283) (xy 448.063874 -120.623076) (xy 447.80073 -120.88622)
				(arc
					(start 447.729102 -120.88622)
					(mid 447.205185 -120.81637)
					(end 447.729102 -120.74652)
				)
				(xy 447.742818 -120.74652) (xy 447.924174 -120.565164) (xy 447.924174 -120.43283)
				(arc
					(start 447.472054 -120.43283)
					(mid 447.08826 -120.816243)
					(end 447.4718 -121.19991)
				)
				(arc
					(start 448.7418 -121.19991)
					(mid 449.12534 -120.81637)
					(end 448.7418 -120.43283)
				)
				(xy 448.355974 -120.43283) (xy 448.355974 -120.555004)
				(arc
					(start 448.501516 -120.700546)
					(mid 449.006967 -120.844035)
					(end 448.48272 -120.879108)
				)
				(xy 448.216274 -120.612916) (xy 448.216274 -120.43283)
			)
		)
	)
	(zone
		(net "VR_FET_SW_P12V_STBY_PVCCIN_CPU1")
		(layer "In11.Cu")
		(hatch none 0.5)
		(connect_pads
			(clearance 0.5)
		)
		(min_thickness 0.25)
		(fill yes
			(thermal_gap 0.5)
			(thermal_bridge_width 0.5)
			(island_removal_mode 0)
		)
		(polygon
			(pts
				(xy 33.824164 -99.779836) (xy 32.9184 -100.6856) (xy 32.253428 -101.350572) (xy 30.01645 -101.350572)
				(xy 28.576524 -102.790498) (xy 28.576524 -105.37952) (xy 28.032964 -105.92308) (xy 24.97328 -105.92308)
				(xy 24.749252 -105.699052) (xy 24.749252 -99.366832) (xy 26.4668 -97.649284) (xy 26.4668 -83.215226)
				(xy 25.245314 -81.99374) (xy 25.245314 -79.467456) (xy 25.563322 -79.149448) (xy 26.583894 -79.149448)
				(xy 27.065478 -78.667864) (xy 27.065478 -77.004164) (xy 26.436828 -76.375514) (xy 26.436828 -73.383648)
				(xy 27.083004 -72.737472) (xy 27.083004 -62.12713) (xy 27.04973 -62.093856) (xy 27.04973 -55.268622)
				(xy 28.0924 -54.225952) (xy 30.324552 -51.9938) (xy 31.030672 -51.28768) (xy 32.893 -51.28768) (xy 33.92678 -52.32146)
				(xy 33.92678 -99.67722)
			)
		)
	)
	(zone
		(layer "In11.Cu")
		(hatch none 0.5)
		(connect_pads
			(clearance 0)
		)
		(min_thickness 0.25)
		(keepout
			(tracks allowed)
			(vias allowed)
			(pads allowed)
			(copperpour allowed)
			(footprints allowed)
		)
		(placement
			(enabled no)
			(sheetname "")
		)
		(fill
			(thermal_gap 0.5)
			(thermal_bridge_width 0.5)
			(island_removal_mode 0)
		)
		(polygon
			(pts
				(xy 323.469 12.9286) (xy 323.469 14.0462) (xy 324.485 14.0462) (xy 324.485 12.9286)
			)
		)
	)
	(zone
		(layer "In11.Cu")
		(hatch none 0.5)
		(connect_pads
			(clearance 0)
		)
		(min_thickness 0.25)
		(keepout
			(tracks not_allowed)
			(vias allowed)
			(pads allowed)
			(copperpour not_allowed)
			(footprints allowed)
		)
		(placement
			(enabled no)
			(sheetname "")
		)
		(fill
			(thermal_gap 0.5)
			(thermal_bridge_width 0.5)
			(island_removal_mode 0)
		)
		(polygon
			(pts
				(arc
					(start 420.844218 -142.98422)
					(mid 420.264352 -143.705383)
					(end 419.435534 -143.293846)
				)
				(arc
					(start 419.435534 -142.674594)
					(mid 420.264349 -142.263073)
					(end 420.844218 -142.98422)
				)
			)
		)
	)
	(zone
		(layer "In11.Cu")
		(hatch none 0.5)
		(connect_pads
			(clearance 0)
		)
		(min_thickness 0.25)
		(keepout
			(tracks not_allowed)
			(vias allowed)
			(pads allowed)
			(copperpour not_allowed)
			(footprints allowed)
		)
		(placement
			(enabled no)
			(sheetname "")
		)
		(fill
			(thermal_gap 0.5)
			(thermal_bridge_width 0.5)
			(island_removal_mode 0)
		)
		(polygon
			(pts
				(xy 11.814556 -29.08935) (xy 11.98245 -29.257244)
				(arc
					(start 11.98245 -29.397198)
					(mid 11.9126 -29.921115)
					(end 11.84275 -29.397198)
				)
				(xy 11.84275 -29.315156) (xy 11.756644 -29.22905) (xy 11.52906 -29.22905)
				(arc
					(start 11.52906 -29.6545)
					(mid 11.9126 -30.03804)
					(end 12.29614 -29.6545)
				)
				(arc
					(start 12.29614 -28.384754)
					(mid 11.912727 -28.00096)
					(end 11.52906 -28.3845)
				)
				(xy 11.52906 -28.79725) (xy 11.756644 -28.79725) (xy 11.84275 -28.711144)
				(arc
					(start 11.84275 -28.641802)
					(mid 11.9126 -28.117885)
					(end 11.98245 -28.641802)
				)
				(xy 11.98245 -28.769056) (xy 11.814556 -28.93695) (xy 11.52906 -28.93695) (xy 11.52906 -29.08935)
			)
		)
	)
	(zone
		(layer "In11.Cu")
		(hatch none 0.5)
		(connect_pads
			(clearance 0)
		)
		(min_thickness 0.25)
		(keepout
			(tracks not_allowed)
			(vias allowed)
			(pads allowed)
			(copperpour not_allowed)
			(footprints allowed)
		)
		(placement
			(enabled no)
			(sheetname "")
		)
		(fill
			(thermal_gap 0.5)
			(thermal_bridge_width 0.5)
			(island_removal_mode 0)
		)
		(polygon
			(pts
				(arc
					(start 395.007846 -25.854152)
					(mid 394.978766 -25.86854)
					(end 394.948156 -25.879298)
				)
				(xy 395.032992 -25.879298)
			)
		)
	)
	(zone
		(layer "In11.Cu")
		(hatch none 0.5)
		(connect_pads
			(clearance 0)
		)
		(min_thickness 0.25)
		(keepout
			(tracks allowed)
			(vias allowed)
			(pads allowed)
			(copperpour allowed)
			(footprints allowed)
		)
		(placement
			(enabled no)
			(sheetname "")
		)
		(fill
			(thermal_gap 0.5)
			(thermal_bridge_width 0.5)
			(island_removal_mode 0)
		)
		(polygon
			(pts
				(xy 66.672968 -80.899) (xy 66.672968 -83.82) (xy 66.266568 -83.82) (xy 63.091568 -86.995) (xy 63.091568 -98.679)
				(xy 70.457568 -106.045) (xy 74.546968 -106.045) (xy 75.537568 -105.0544) (xy 76.578968 -104.013)
				(xy 85.062568 -104.013) (xy 85.062568 -105.0544) (xy 106.144568 -105.0544) (xy 106.144568 -107.442)
				(xy 121.765568 -107.442) (xy 121.765568 -106.045) (xy 124.940568 -106.045) (xy 124.940568 -105.664)
				(xy 127.861568 -105.664) (xy 127.861568 -105.0544) (xy 134.211568 -105.0544) (xy 135.430768 -105.0544)
				(xy 139.799568 -105.0544) (xy 139.799568 -100.6856) (xy 145.311368 -95.1738) (xy 145.311368 -56.134)
				(xy 141.501368 -52.324) (xy 126.947168 -52.324) (xy 126.858268 -52.2351) (xy 126.655068 -52.2351)
				(xy 121.638568 -47.2186) (xy 121.638568 -46.7106) (xy 121.054368 -46.1264) (xy 106.093768 -46.1264)
				(xy 105.509568 -46.7106) (xy 86.307168 -46.7106) (xy 86.307168 -47.5234) (xy 85.291168 -48.5394)
				(xy 76.020168 -48.5394) (xy 74.673968 -48.5394) (xy 74.673968 -47.9806) (xy 73.734168 -47.0408)
				(xy 72.184768 -47.0408) (xy 70.686168 -48.5394) (xy 70.076568 -48.5394) (xy 69.847968 -48.3108)
				(xy 68.958968 -48.3108) (xy 66.114168 -51.1556) (xy 66.114168 -52.3494) (xy 65.250568 -53.213) (xy 64.437768 -53.213)
				(xy 64.437768 -60.4774) (xy 64.767968 -60.8076) (xy 65.352168 -60.8076) (xy 65.352168 -79.5782)
			)
		)
	)
	(zone
		(layer "In11.Cu")
		(hatch none 0.5)
		(connect_pads
			(clearance 0)
		)
		(min_thickness 0.25)
		(keepout
			(tracks allowed)
			(vias allowed)
			(pads allowed)
			(copperpour allowed)
			(footprints allowed)
		)
		(placement
			(enabled no)
			(sheetname "")
		)
		(fill
			(thermal_gap 0.5)
			(thermal_bridge_width 0.5)
			(island_removal_mode 0)
		)
		(polygon
			(pts
				(xy 392.938 -130.302) (xy 392.938 -129.032) (xy 393.827 -129.032) (xy 393.827 -130.302)
			)
		)
	)
	(zone
		(layer "In11.Cu")
		(hatch none 0.5)
		(connect_pads
			(clearance 0)
		)
		(min_thickness 0.25)
		(keepout
			(tracks allowed)
			(vias allowed)
			(pads allowed)
			(copperpour allowed)
			(footprints allowed)
		)
		(placement
			(enabled no)
			(sheetname "")
		)
		(fill
			(thermal_gap 0.5)
			(thermal_bridge_width 0.5)
			(island_removal_mode 0)
		)
		(polygon
			(pts
				(xy 87.65159 -67.48399) (xy 81.482184 -67.48399) (xy 81.482184 -55.797704) (xy 79.592424 -53.907944)
				(xy 79.001112 -53.907944) (xy 76.959968 -51.8668) (xy 76.959968 -51.432968) (xy 78.316582 -50.076354)
				(xy 78.361032 -50.031904) (xy 86.848442 -50.031904) (xy 87.65159 -50.835052) (xy 87.65159 -54.054756)
			)
		)
	)
	(zone
		(layer "In11.Cu")
		(hatch none 0.5)
		(connect_pads
			(clearance 0)
		)
		(min_thickness 0.25)
		(keepout
			(tracks allowed)
			(vias allowed)
			(pads allowed)
			(copperpour allowed)
			(footprints allowed)
		)
		(placement
			(enabled no)
			(sheetname "")
		)
		(fill
			(thermal_gap 0.5)
			(thermal_bridge_width 0.5)
			(island_removal_mode 0)
		)
		(polygon
			(pts
				(xy 113.783618 -64.712088) (xy 113.783618 -52.850542) (xy 113.783618 -50.237898) (xy 113.780316 -50.2412)
				(xy 113.739168 -50.2412) (xy 113.739168 -47.3456) (xy 113.739168 -47.1424) (xy 114.374168 -46.5074)
				(xy 120.724168 -46.5074) (xy 121.130568 -46.9138) (xy 121.130568 -47.5996) (xy 121.765568 -47.5996)
				(xy 125.956568 -51.7906) (xy 125.956568 -52.451) (xy 125.778768 -52.6288) (xy 125.778768 -53.18633)
				(xy 125.397768 -53.56733) (xy 124.736098 -54.229) (xy 124.736098 -64.712088) (xy 123.818142 -65.630044)
				(xy 114.701574 -65.630044)
			)
		)
	)
	(zone
		(layer "In11.Cu")
		(hatch none 0.5)
		(connect_pads
			(clearance 0)
		)
		(min_thickness 0.25)
		(keepout
			(tracks not_allowed)
			(vias allowed)
			(pads allowed)
			(copperpour not_allowed)
			(footprints allowed)
		)
		(placement
			(enabled no)
			(sheetname "")
		)
		(fill
			(thermal_gap 0.5)
			(thermal_bridge_width 0.5)
			(island_removal_mode 0)
		)
		(polygon
			(pts
				(arc
					(start 353.230688 -31.250636)
					(mid 352.785803 -31.401216)
					(end 352.407728 -31.679896)
				)
				(arc
					(start 352.407728 -31.679896)
					(mid 352.436228 -32.014615)
					(end 352.111818 -32.102044)
				)
				(arc
					(start 352.111818 -32.102044)
					(mid 352.032914 -32.305357)
					(end 351.983802 -32.517842)
				)
				(arc
					(start 351.983802 -32.517842)
					(mid 352.482101 -32.653102)
					(end 351.966784 -32.684974)
				)
				(arc
					(start 351.966784 -32.684974)
					(mid 353.456358 -34.280762)
					(end 355.01834 -32.75584)
				)
				(arc
					(start 354.528628 -32.75584)
					(mid 354.2538 -33.02814)
					(end 353.978972 -32.75584)
				)
				(arc
					(start 353.7585 -32.75584)
					(mid 353.4918 -33.020012)
					(end 353.2251 -32.75584)
				)
				(arc
					(start 353.2251 -32.7533)
					(mid 353.4918 -32.4866)
					(end 353.7585 -32.7533)
				)
				(arc
					(start 353.978972 -32.7533)
					(mid 354.2538 -32.478472)
					(end 354.528628 -32.7533)
				)
				(arc
					(start 355.01834 -32.7533)
					(mid 354.837146 -32.033203)
					(end 354.33762 -31.483808)
				)
				(arc
					(start 354.33762 -31.483808)
					(mid 354.134075 -31.469021)
					(end 354.000054 -31.315152)
				)
				(arc
					(start 354.000054 -31.315152)
					(mid 353.877833 -31.277722)
					(end 353.752912 -31.250636)
				)
				(arc
					(start 353.752912 -31.250636)
					(mid 353.4918 -31.491282)
					(end 353.230688 -31.250636)
				)
			)
		)
	)
	(zone
		(layer "In11.Cu")
		(hatch none 0.5)
		(connect_pads
			(clearance 0)
		)
		(min_thickness 0.25)
		(keepout
			(tracks allowed)
			(vias allowed)
			(pads allowed)
			(copperpour allowed)
			(footprints allowed)
		)
		(placement
			(enabled no)
			(sheetname "")
		)
		(fill
			(thermal_gap 0.5)
			(thermal_bridge_width 0.5)
			(island_removal_mode 0)
		)
		(polygon
			(pts
				(xy 231.6734 -80.899) (xy 231.6734 -83.82) (xy 231.267 -83.82) (xy 228.092 -86.995) (xy 228.092 -98.679)
				(xy 235.458 -106.045) (xy 239.5474 -106.045) (xy 240.538 -105.0544) (xy 241.5794 -104.013) (xy 250.063 -104.013)
				(xy 250.063 -105.0544) (xy 271.145 -105.0544) (xy 271.145 -107.442) (xy 286.766 -107.442) (xy 286.766 -106.045)
				(xy 289.941 -106.045) (xy 289.941 -105.664) (xy 292.862 -105.664) (xy 292.862 -105.0544) (xy 299.212 -105.0544)
				(xy 300.4312 -105.0544) (xy 304.8 -105.0544) (xy 304.8 -100.6856) (xy 310.3118 -95.1738) (xy 310.3118 -56.134)
				(xy 306.5018 -52.324) (xy 291.9476 -52.324) (xy 291.8587 -52.2351) (xy 291.6555 -52.2351) (xy 286.639 -47.2186)
				(xy 286.639 -46.7106) (xy 286.0548 -46.1264) (xy 271.0942 -46.1264) (xy 270.51 -46.7106) (xy 251.3076 -46.7106)
				(xy 251.3076 -47.5234) (xy 250.2916 -48.5394) (xy 241.0206 -48.5394) (xy 239.6744 -48.5394) (xy 239.6744 -47.9806)
				(xy 238.7346 -47.0408) (xy 237.1852 -47.0408) (xy 235.6866 -48.5394) (xy 235.077 -48.5394) (xy 234.8484 -48.3108)
				(xy 233.9594 -48.3108) (xy 231.1146 -51.1556) (xy 231.1146 -52.3494) (xy 230.251 -53.213) (xy 229.4382 -53.213)
				(xy 229.4382 -60.4774) (xy 229.7684 -60.8076) (xy 230.3526 -60.8076) (xy 230.3526 -79.5782)
			)
		)
	)
	(zone
		(layer "In11.Cu")
		(hatch none 0.5)
		(connect_pads
			(clearance 0)
		)
		(min_thickness 0.25)
		(keepout
			(tracks not_allowed)
			(vias allowed)
			(pads allowed)
			(copperpour not_allowed)
			(footprints allowed)
		)
		(placement
			(enabled no)
			(sheetname "")
		)
		(fill
			(thermal_gap 0.5)
			(thermal_bridge_width 0.5)
			(island_removal_mode 0)
		)
		(polygon
			(pts
				(arc
					(start 353.990402 -31.25089)
					(mid 353.862081 -31.279086)
					(end 353.736656 -31.3182)
				)
				(arc
					(start 353.736656 -31.3182)
					(mid 353.608225 -31.46233)
					(end 353.415854 -31.478474)
				)
				(arc
					(start 353.415854 -31.478474)
					(mid 353.528208 -34.097734)
					(end 355.78034 -32.75584)
				)
				(arc
					(start 354.5205 -32.75584)
					(mid 354.2538 -33.020012)
					(end 353.9871 -32.75584)
				)
				(arc
					(start 353.9871 -32.7533)
					(mid 354.2538 -32.4866)
					(end 354.5205 -32.7533)
				)
				(arc
					(start 355.78034 -32.7533)
					(mid 355.756837 -32.487471)
					(end 355.687376 -32.229806)
				)
				(arc
					(start 355.687376 -32.229806)
					(mid 355.210349 -32.234564)
					(end 355.473762 -31.836868)
				)
				(arc
					(start 355.473762 -31.836868)
					(mid 355.051258 -31.452823)
					(end 354.517198 -31.25089)
				)
				(arc
					(start 354.517198 -31.25089)
					(mid 354.2538 -31.493581)
					(end 353.990402 -31.25089)
				)
			)
		)
	)
	(zone
		(layer "In11.Cu")
		(hatch none 0.5)
		(connect_pads
			(clearance 0)
		)
		(min_thickness 0.25)
		(keepout
			(tracks allowed)
			(vias allowed)
			(pads allowed)
			(copperpour allowed)
			(footprints allowed)
		)
		(placement
			(enabled no)
			(sheetname "")
		)
		(fill
			(thermal_gap 0.5)
			(thermal_bridge_width 0.5)
			(island_removal_mode 0)
		)
		(polygon
			(pts
				(xy 242.44935 -69.62013) (xy 234.155488 -69.62013) (xy 231.297988 -66.76263) (xy 231.297988 -63.4746)
				(xy 230.9114 -63.4746) (xy 230.632 -63.1952) (xy 230.632 -60.833) (xy 230.124 -60.325) (xy 230.124 -53.721)
				(xy 231.103424 -53.721) (xy 232.137712 -52.686712) (xy 234.781344 -50.043334) (xy 235.839 -50.043334)
				(xy 235.839 -48.9458) (xy 239.4712 -48.9458) (xy 240.2078 -49.6824) (xy 240.2078 -50.043334) (xy 240.2332 -50.043334)
				(xy 240.2332 -50.419) (xy 244.229382 -54.415182) (xy 245.025418 -54.415182) (xy 246.451628 -55.841392)
				(xy 246.451628 -65.617852)
			)
		)
	)
	(zone
		(net "GND")
		(layer "In11.Cu")
		(hatch none 0.5)
		(connect_pads
			(clearance 0.5)
		)
		(min_thickness 0.25)
		(fill yes
			(thermal_gap 0.5)
			(thermal_bridge_width 0.5)
			(island_removal_mode 0)
		)
		(polygon
			(pts
				(xy 339.2932 -157.734) (xy 345.9226 -157.734) (xy 347.1926 -156.464) (xy 347.1926 -152.1206) (xy 346.3798 -151.3078)
				(xy 346.3798 -150.0378) (xy 347.1418 -149.2758) (xy 347.1418 -144.3228) (xy 345.9861 -143.1671)
				(xy 345.9861 -140.4747) (xy 344.3478 -138.8364) (xy 338.2264 -138.8364) (xy 337.7946 -139.2682)
				(xy 337.7946 -143.0528) (xy 337.7946 -156.2354)
			)
		)
	)
	(zone
		(layer "In11.Cu")
		(hatch none 0.5)
		(connect_pads
			(clearance 0)
		)
		(min_thickness 0.25)
		(keepout
			(tracks not_allowed)
			(vias allowed)
			(pads allowed)
			(copperpour not_allowed)
			(footprints allowed)
		)
		(placement
			(enabled no)
			(sheetname "")
		)
		(fill
			(thermal_gap 0.5)
			(thermal_bridge_width 0.5)
			(island_removal_mode 0)
		)
		(polygon
			(pts
				(arc
					(start 444.579502 -123.98502)
					(mid 444.05584 -123.928009)
					(end 444.571374 -123.81992)
				)
				(xy 444.750698 -123.640596) (xy 444.750698 -123.53163)
				(arc
					(start 444.322454 -123.53163)
					(mid 443.93866 -123.915043)
					(end 444.3222 -124.29871)
				)
				(arc
					(start 445.5922 -124.29871)
					(mid 445.97574 -123.91517)
					(end 445.5922 -123.53163)
				)
				(xy 445.182498 -123.53163) (xy 445.182498 -123.640596)
				(arc
					(start 445.348614 -123.806712)
					(mid 445.858053 -123.935657)
					(end 445.334898 -123.98502)
				)
				(xy 445.32931 -123.98502) (xy 445.042798 -123.698508) (xy 445.042798 -123.53163) (xy 444.890398 -123.53163)
				(xy 444.890398 -123.698508) (xy 444.603886 -123.98502)
			)
		)
	)
	(zone
		(net "PVPP_ABC")
		(layer "In11.Cu")
		(hatch none 0.5)
		(connect_pads
			(clearance 0.5)
		)
		(min_thickness 0.25)
		(fill yes
			(thermal_gap 0.5)
			(thermal_bridge_width 0.5)
			(island_removal_mode 0)
		)
		(polygon
			(pts
				(xy 297.198034 -52.286662) (xy 301.842678 -52.286662) (xy 302.319944 -51.809396) (xy 302.728884 -51.400456)
				(xy 302.728884 -49.150524) (xy 302.728884 -47.602648) (xy 316.517274 -33.814258) (xy 318.423544 -33.814258)
				(xy 320.01206 -32.225742) (xy 320.01206 -30.573726) (xy 321.346322 -29.239464) (xy 321.346322 -28.635706)
				(xy 320.774568 -28.063952) (xy 320.774568 -24.283162) (xy 320.869818 -24.187912) (xy 320.869818 -23.330154)
				(xy 320.583814 -23.04415) (xy 318.10579 -23.04415) (xy 317.534036 -23.615904) (xy 317.534036 -30.097222)
				(xy 298.225972 -49.405286) (xy 298.225972 -49.486058) (xy 296.737786 -50.974244) (xy 296.737786 -51.826414)
			)
		)
	)
	(zone
		(layer "In11.Cu")
		(hatch none 0.5)
		(connect_pads
			(clearance 0)
		)
		(min_thickness 0.25)
		(keepout
			(tracks not_allowed)
			(vias allowed)
			(pads allowed)
			(copperpour not_allowed)
			(footprints allowed)
		)
		(placement
			(enabled no)
			(sheetname "")
		)
		(fill
			(thermal_gap 0.5)
			(thermal_bridge_width 0.5)
			(island_removal_mode 0)
		)
		(polygon
			(pts
				(xy 357.876856 -109.87405) (xy 358.03205 -110.029244)
				(arc
					(start 358.03205 -110.175548)
					(mid 357.9622 -110.699465)
					(end 357.89235 -110.175548)
				)
				(xy 357.89235 -110.087156) (xy 357.818944 -110.01375) (xy 357.57866 -110.01375)
				(arc
					(start 357.57866 -110.432596)
					(mid 357.962073 -110.81639)
					(end 358.34574 -110.43285)
				)
				(arc
					(start 358.34574 -109.16285)
					(mid 357.9622 -108.77931)
					(end 357.57866 -109.16285)
				)
				(xy 357.57866 -109.58195) (xy 357.818944 -109.58195) (xy 357.89235 -109.508544)
				(arc
					(start 357.89235 -109.420152)
					(mid 357.9622 -108.896235)
					(end 358.03205 -109.420152)
				)
				(xy 358.03205 -109.566456) (xy 357.876856 -109.72165) (xy 357.57866 -109.72165) (xy 357.57866 -109.87405)
			)
		)
	)
	(zone
		(layer "In11.Cu")
		(hatch none 0.5)
		(connect_pads
			(clearance 0)
		)
		(min_thickness 0.25)
		(keepout
			(tracks not_allowed)
			(vias allowed)
			(pads allowed)
			(copperpour not_allowed)
			(footprints allowed)
		)
		(placement
			(enabled no)
			(sheetname "")
		)
		(fill
			(thermal_gap 0.5)
			(thermal_bridge_width 0.5)
			(island_removal_mode 0)
		)
		(polygon
			(pts
				(arc
					(start 395.526006 -31.737046)
					(mid 395.511618 -31.707966)
					(end 395.50086 -31.677356)
				)
				(xy 395.50086 -31.762192)
			)
		)
	)
	(zone
		(layer "In11.Cu")
		(hatch none 0.5)
		(connect_pads
			(clearance 0)
		)
		(min_thickness 0.25)
		(keepout
			(tracks allowed)
			(vias allowed)
			(pads allowed)
			(copperpour allowed)
			(footprints allowed)
		)
		(placement
			(enabled no)
			(sheetname "")
		)
		(fill
			(thermal_gap 0.5)
			(thermal_bridge_width 0.5)
			(island_removal_mode 0)
		)
		(polygon
			(pts
				(xy 352.552 -114.3254) (xy 352.552 -112.4204) (xy 353.695 -112.4204) (xy 353.695 -114.3254)
			)
		)
	)
	(zone
		(net "PVTT_KLM")
		(layer "In11.Cu")
		(hatch none 0.5)
		(connect_pads
			(clearance 0.5)
		)
		(min_thickness 0.25)
		(fill yes
			(thermal_gap 0.5)
			(thermal_bridge_width 0.5)
			(island_removal_mode 0)
		)
		(polygon
			(pts
				(xy 93.5228 -156.1084) (xy 97.536 -156.1084) (xy 97.7138 -155.9306) (xy 97.7138 -148.2344) (xy 96.393 -146.9136)
				(xy 94.869 -146.9136) (xy 92.6846 -149.098) (xy 92.6846 -155.2702)
			)
		)
	)
	(zone
		(net "GND")
		(layer "In11.Cu")
		(hatch none 0.5)
		(connect_pads
			(clearance 0.5)
		)
		(min_thickness 0.25)
		(fill yes
			(thermal_gap 0.5)
			(thermal_bridge_width 0.5)
			(island_removal_mode 0)
		)
		(polygon
			(pts
				(arc
					(start -5.184648 -161.9504)
					(mid -5.224047 -162.020639)
					(end -5.237734 -162.100006)
				)
				(arc
					(start -5.237734 -168.099994)
					(mid -5.1681 -168.268104)
					(end -4.99999 -168.337738)
				)
				(xy 501.0404 -168.337738) (xy 501.0404 -161.9504)
			)
		)
		(polygon
			(pts
				(xy 242.3922 -162.5346) (xy 236.4486 -162.5346) (xy 236.4486 -167.5384) (xy 242.3922 -167.5384)
				(xy 309.0164 -167.5384) (xy 309.0164 -162.5346)
			)
		)
		(polygon
			(pts
				(xy 67.9704 -162.5346) (xy 60.9092 -162.5346) (xy 60.9092 -167.5384) (xy 67.9704 -167.5384) (xy 101.6254 -167.5384)
				(xy 101.6254 -162.5346)
			)
		)
	)
	(zone
		(layer "In11.Cu")
		(hatch none 0.5)
		(connect_pads
			(clearance 0)
		)
		(min_thickness 0.25)
		(keepout
			(tracks not_allowed)
			(vias allowed)
			(pads allowed)
			(copperpour not_allowed)
			(footprints allowed)
		)
		(placement
			(enabled no)
			(sheetname "")
		)
		(fill
			(thermal_gap 0.5)
			(thermal_bridge_width 0.5)
			(island_removal_mode 0)
		)
		(polygon
			(pts
				(xy 455.21245 -121.35866) (xy 455.21245 -121.656856) (xy 455.057256 -121.81205)
				(arc
					(start 454.910952 -121.81205)
					(mid 454.387035 -121.7422)
					(end 454.910952 -121.67235)
				)
				(xy 454.999344 -121.67235) (xy 455.07275 -121.598944) (xy 455.07275 -121.35866)
				(arc
					(start 454.653904 -121.35866)
					(mid 454.27011 -121.742073)
					(end 454.65365 -122.12574)
				)
				(arc
					(start 455.92365 -122.12574)
					(mid 456.30719 -121.7422)
					(end 455.92365 -121.35866)
				)
				(xy 455.50455 -121.35866) (xy 455.50455 -121.598944) (xy 455.577956 -121.67235)
				(arc
					(start 455.666348 -121.67235)
					(mid 456.190265 -121.7422)
					(end 455.666348 -121.81205)
				)
				(xy 455.520044 -121.81205) (xy 455.36485 -121.656856) (xy 455.36485 -121.35866)
			)
		)
	)
	(zone
		(layer "In11.Cu")
		(hatch none 0.5)
		(connect_pads
			(clearance 0)
		)
		(min_thickness 0.25)
		(keepout
			(tracks not_allowed)
			(vias allowed)
			(pads allowed)
			(copperpour not_allowed)
			(footprints allowed)
		)
		(placement
			(enabled no)
			(sheetname "")
		)
		(fill
			(thermal_gap 0.5)
			(thermal_bridge_width 0.5)
			(island_removal_mode 0)
		)
		(polygon
			(pts
				(arc
					(start 396.01394 -31.677356)
					(mid 395.858006 -31.851451)
					(end 395.624812 -31.835852)
				)
				(xy 395.50086 -31.959804) (xy 395.50086 -32.391858)
				(arc
					(start 395.624812 -32.51581)
					(mid 395.858003 -32.500219)
					(end 396.01394 -32.674306)
				)
			)
		)
	)
	(zone
		(layer "In11.Cu")
		(hatch none 0.5)
		(connect_pads
			(clearance 0)
		)
		(min_thickness 0.25)
		(keepout
			(tracks not_allowed)
			(vias allowed)
			(pads allowed)
			(copperpour not_allowed)
			(footprints allowed)
		)
		(placement
			(enabled no)
			(sheetname "")
		)
		(fill
			(thermal_gap 0.5)
			(thermal_bridge_width 0.5)
			(island_removal_mode 0)
		)
		(polygon
			(pts
				(xy 354.300028 -115.759738) (xy 354.4951 -115.95481)
				(arc
					(start 354.4951 -115.963192)
					(mid 354.444116 -116.486489)
					(end 354.318824 -115.975892)
				)
				(xy 354.242116 -115.899438) (xy 354.04171 -115.899438)
				(arc
					(start 354.04171 -116.22024)
					(mid 354.425123 -116.604034)
					(end 354.80879 -116.220494)
				)
				(arc
					(start 354.80879 -115.204494)
					(mid 354.42525 -114.820954)
					(end 354.04171 -115.204494)
				)
				(xy 354.04171 -115.467638) (xy 354.28174 -115.467638)
				(arc
					(start 354.306124 -115.443254)
					(mid 354.457851 -114.93981)
					(end 354.481892 -115.465098)
				)
				(xy 354.339652 -115.607338) (xy 354.04171 -115.607338) (xy 354.04171 -115.759738)
			)
		)
	)
	(zone
		(layer "In11.Cu")
		(hatch none 0.5)
		(connect_pads
			(clearance 0)
		)
		(min_thickness 0.25)
		(keepout
			(tracks allowed)
			(vias allowed)
			(pads allowed)
			(copperpour allowed)
			(footprints allowed)
		)
		(placement
			(enabled no)
			(sheetname "")
		)
		(fill
			(thermal_gap 0.5)
			(thermal_bridge_width 0.5)
			(island_removal_mode 0)
		)
		(polygon
			(pts
				(xy 277.8506 -158.6484) (xy 277.8506 -157.6324) (xy 279.8064 -157.6324) (xy 279.8064 -158.6484)
			)
		)
	)
	(zone
		(layer "In11.Cu")
		(hatch none 0.5)
		(connect_pads
			(clearance 0)
		)
		(min_thickness 0.25)
		(keepout
			(tracks allowed)
			(vias allowed)
			(pads allowed)
			(copperpour allowed)
			(footprints allowed)
		)
		(placement
			(enabled no)
			(sheetname "")
		)
		(fill
			(thermal_gap 0.5)
			(thermal_bridge_width 0.5)
			(island_removal_mode 0)
		)
		(polygon
			(pts
				(xy 278.78405 -64.712088) (xy 278.78405 -52.850542) (xy 278.78405 -50.237898) (xy 278.780748 -50.2412)
				(xy 278.7396 -50.2412) (xy 278.7396 -47.3456) (xy 278.7396 -47.1424) (xy 279.3746 -46.5074) (xy 285.7246 -46.5074)
				(xy 286.131 -46.9138) (xy 286.131 -47.5996) (xy 286.766 -47.5996) (xy 290.957 -51.7906) (xy 290.957 -52.451)
				(xy 290.7792 -52.6288) (xy 290.7792 -53.18633) (xy 290.3982 -53.56733) (xy 289.73653 -54.229) (xy 289.73653 -64.712088)
				(xy 288.818574 -65.630044) (xy 279.702006 -65.630044)
			)
		)
	)
	(zone
		(layer "In11.Cu")
		(hatch none 0.5)
		(connect_pads
			(clearance 0)
		)
		(min_thickness 0.25)
		(keepout
			(tracks allowed)
			(vias allowed)
			(pads allowed)
			(copperpour allowed)
			(footprints allowed)
		)
		(placement
			(enabled no)
			(sheetname "")
		)
		(fill
			(thermal_gap 0.5)
			(thermal_bridge_width 0.5)
			(island_removal_mode 0)
		)
		(polygon
			(pts
				(xy 105.255568 -90.551) (xy 111.478568 -90.551) (xy 112.875568 -89.154) (xy 121.257568 -89.154)
				(xy 130.909568 -98.806) (xy 130.909568 -101.727) (xy 133.195568 -104.013) (xy 133.195568 -104.902)
				(xy 121.384568 -104.902) (xy 121.384568 -107.188) (xy 113.764568 -107.188) (xy 113.764568 -104.902)
				(xy 106.271568 -104.902) (xy 105.128568 -103.759) (xy 105.128568 -90.678)
			)
		)
	)
	(zone
		(layer "In11.Cu")
		(hatch none 0.5)
		(connect_pads
			(clearance 0)
		)
		(min_thickness 0.25)
		(keepout
			(tracks not_allowed)
			(vias allowed)
			(pads allowed)
			(copperpour not_allowed)
			(footprints allowed)
		)
		(placement
			(enabled no)
			(sheetname "")
		)
		(fill
			(thermal_gap 0.5)
			(thermal_bridge_width 0.5)
			(island_removal_mode 0)
		)
		(polygon
			(pts
				(arc
					(start 328.920094 -154.573732)
					(mid 325.953231 -152.963968)
					(end 326.22363 -156.328618)
				)
				(arc
					(start 326.22363 -156.328618)
					(mid 326.320024 -156.345522)
					(end 326.402954 -156.397452)
				)
				(arc
					(start 326.402954 -156.397452)
					(mid 327.983214 -156.222101)
					(end 328.88936 -154.915616)
				)
				(arc
					(start 328.88936 -154.915616)
					(mid 328.839841 -154.738823)
					(end 328.920094 -154.573732)
				)
			)
		)
	)
	(zone
		(net "VR_FET_SW_P12V_STBY_PVDDQ_GHJ")
		(layer "In11.Cu")
		(hatch none 0.5)
		(connect_pads
			(clearance 0.5)
		)
		(min_thickness 0.25)
		(fill yes
			(thermal_gap 0.5)
			(thermal_bridge_width 0.5)
			(island_removal_mode 0)
		)
		(polygon
			(pts
				(xy -1.361948 -5.6642) (xy -2.3876 -5.6642) (xy -3.1623 -6.4389) (xy -3.1623 -15.509494) (xy -3.1623 -15.738348)
				(xy -3.975354 -16.551402) (xy -3.975354 -18.071846) (xy -3.437636 -18.609564) (xy -1.837436 -18.609564)
				(xy -1.1176 -19.3294) (xy 0.381 -20.828) (xy 3.7592 -20.828) (xy 5.0292 -19.558) (xy 5.0292 -15.2654)
				(xy 5.3848 -14.9098) (xy 5.3848 -12.319) (xy 5.0546 -11.9888) (xy 5.0546 -8.2804) (xy 5.0546 -7.540752)
				(xy 4.733544 -7.219696) (xy 0.193548 -7.219696)
			)
		)
	)
	(zone
		(layer "In11.Cu")
		(hatch none 0.5)
		(connect_pads
			(clearance 0)
		)
		(min_thickness 0.25)
		(keepout
			(tracks not_allowed)
			(vias allowed)
			(pads allowed)
			(copperpour not_allowed)
			(footprints allowed)
		)
		(placement
			(enabled no)
			(sheetname "")
		)
		(fill
			(thermal_gap 0.5)
			(thermal_bridge_width 0.5)
			(island_removal_mode 0)
		)
		(polygon
			(pts
				(xy 12.921996 -27.32659) (xy 13.120624 -27.525218)
				(arc
					(start 13.120624 -27.619198)
					(mid 13.050774 -28.143115)
					(end 12.980924 -27.619198)
				)
				(xy 12.980924 -27.58313) (xy 12.864084 -27.46629) (xy 12.667234 -27.46629)
				(arc
					(start 12.667234 -27.8765)
					(mid 13.050774 -28.26004)
					(end 13.434314 -27.8765)
				)
				(arc
					(start 13.434314 -26.606754)
					(mid 13.050901 -26.22296)
					(end 12.667234 -26.6065)
				)
				(xy 12.667234 -27.03449) (xy 12.866624 -27.03449) (xy 12.980924 -26.92019)
				(arc
					(start 12.980924 -26.863802)
					(mid 13.050774 -26.339885)
					(end 13.120624 -26.863802)
				)
				(xy 13.120624 -26.978102) (xy 12.924536 -27.17419) (xy 12.667234 -27.17419) (xy 12.667234 -27.32659)
			)
		)
	)
	(zone
		(layer "In11.Cu")
		(hatch none 0.5)
		(connect_pads
			(clearance 0)
		)
		(min_thickness 0.25)
		(keepout
			(tracks not_allowed)
			(vias allowed)
			(pads allowed)
			(copperpour not_allowed)
			(footprints allowed)
		)
		(placement
			(enabled no)
			(sheetname "")
		)
		(fill
			(thermal_gap 0.5)
			(thermal_bridge_width 0.5)
			(island_removal_mode 0)
		)
		(polygon
			(pts
				(arc
					(start 320.667126 -54.550056)
					(mid 315.333126 -54.550056)
					(end 320.667126 -54.550056)
				)
			)
		)
	)
	(zone
		(layer "In11.Cu")
		(hatch none 0.5)
		(connect_pads
			(clearance 0)
		)
		(min_thickness 0.25)
		(keepout
			(tracks not_allowed)
			(vias allowed)
			(pads allowed)
			(copperpour not_allowed)
			(footprints allowed)
		)
		(placement
			(enabled no)
			(sheetname "")
		)
		(fill
			(thermal_gap 0.5)
			(thermal_bridge_width 0.5)
			(island_removal_mode 0)
		)
		(polygon
			(pts
				(xy 441.5917 -123.536964) (xy 441.560966 -123.50623)
				(arc
					(start 441.172854 -123.50623)
					(mid 440.78906 -123.889643)
					(end 441.1726 -124.27331)
				)
				(arc
					(start 442.4426 -124.27331)
					(mid 442.82614 -123.88977)
					(end 442.4426 -123.50623)
				)
				(xy 442.0235 -123.50623) (xy 442.0235 -123.746514) (xy 442.096906 -123.81992)
				(arc
					(start 442.185298 -123.81992)
					(mid 442.709215 -123.88977)
					(end 442.185298 -123.95962)
				)
				(xy 442.038994 -123.95962) (xy 441.8838 -123.804426) (xy 441.8838 -123.50623) (xy 441.7314 -123.50623)
				(xy 441.7314 -123.794774) (xy 441.566554 -123.95962)
				(arc
					(start 441.429902 -123.95962)
					(mid 440.905985 -123.88977)
					(end 441.429902 -123.81992)
				)
				(xy 441.508642 -123.81992) (xy 441.5917 -123.736862)
			)
		)
	)
	(zone
		(layer "In11.Cu")
		(hatch none 0.5)
		(connect_pads
			(clearance 0)
		)
		(min_thickness 0.25)
		(keepout
			(tracks not_allowed)
			(vias allowed)
			(pads allowed)
			(copperpour not_allowed)
			(footprints allowed)
		)
		(placement
			(enabled no)
			(sheetname "")
		)
		(fill
			(thermal_gap 0.5)
			(thermal_bridge_width 0.5)
			(island_removal_mode 0)
		)
		(polygon
			(pts
				(xy 457.990956 -120.31472) (xy 458.14615 -120.469914) (xy 458.14615 -120.76811) (xy 458.29855 -120.76811)
				(xy 458.29855 -120.469914) (xy 458.453744 -120.31472)
				(arc
					(start 458.600048 -120.31472)
					(mid 459.123965 -120.38457)
					(end 458.600048 -120.45442)
				)
				(xy 458.511656 -120.45442) (xy 458.43825 -120.527826) (xy 458.43825 -120.76811)
				(arc
					(start 458.85735 -120.76811)
					(mid 459.24089 -120.38457)
					(end 458.85735 -120.00103)
				)
				(arc
					(start 457.587604 -120.00103)
					(mid 457.20381 -120.384443)
					(end 457.58735 -120.76811)
				)
				(xy 458.00645 -120.76811) (xy 458.00645 -120.527826) (xy 457.933044 -120.45442)
				(arc
					(start 457.844652 -120.45442)
					(mid 457.320735 -120.38457)
					(end 457.844652 -120.31472)
				)
			)
		)
	)
	(zone
		(net "PVPP_GHJ")
		(layer "In11.Cu")
		(hatch none 0.5)
		(connect_pads
			(clearance 0.5)
		)
		(min_thickness 0.25)
		(fill yes
			(thermal_gap 0.5)
			(thermal_bridge_width 0.5)
			(island_removal_mode 0)
		)
		(polygon
			(pts
				(xy 133.203442 -52.097686) (xy 135.606028 -52.097686) (xy 135.982964 -51.72075) (xy 136.988042 -51.72075)
				(xy 137.50163 -51.207162) (xy 138.947652 -51.207162) (xy 156.256736 -33.898078) (xy 156.256736 -23.08987)
				(xy 155.872688 -22.705822) (xy 154.514296 -22.705822) (xy 154.159966 -23.060152) (xy 154.159966 -23.114)
				(xy 153.416 -23.857966) (xy 153.416 -30.226) (xy 133.112002 -50.529998) (xy 133.112002 -51.215798)
				(xy 133.112002 -52.006246)
			)
		)
	)
	(zone
		(layer "In11.Cu")
		(hatch none 0.5)
		(connect_pads
			(clearance 0)
		)
		(min_thickness 0.25)
		(keepout
			(tracks not_allowed)
			(vias allowed)
			(pads allowed)
			(copperpour not_allowed)
			(footprints allowed)
		)
		(placement
			(enabled no)
			(sheetname "")
		)
		(fill
			(thermal_gap 0.5)
			(thermal_bridge_width 0.5)
			(island_removal_mode 0)
		)
		(polygon
			(pts
				(xy 11.784076 -36.24707) (xy 11.98245 -36.445444)
				(arc
					(start 11.98245 -36.509198)
					(mid 11.9126 -37.033115)
					(end 11.84275 -36.509198)
				)
				(xy 11.84275 -36.503356) (xy 11.726164 -36.38677) (xy 11.52906 -36.38677)
				(arc
					(start 11.52906 -36.7665)
					(mid 11.9126 -37.15004)
					(end 12.29614 -36.7665)
				)
				(arc
					(start 12.29614 -35.496754)
					(mid 11.912727 -35.11296)
					(end 11.52906 -35.4965)
				)
				(xy 11.52906 -35.95497) (xy 11.725148 -35.95497) (xy 11.84275 -35.837368)
				(arc
					(start 11.84275 -35.753802)
					(mid 11.9126 -35.229885)
					(end 11.98245 -35.753802)
				)
				(xy 11.98245 -35.89528) (xy 11.78306 -36.09467) (xy 11.52906 -36.09467) (xy 11.52906 -36.24707)
			)
		)
	)
	(zone
		(layer "In11.Cu")
		(hatch none 0.5)
		(connect_pads
			(clearance 0)
		)
		(min_thickness 0.25)
		(keepout
			(tracks not_allowed)
			(vias allowed)
			(pads allowed)
			(copperpour not_allowed)
			(footprints allowed)
		)
		(placement
			(enabled no)
			(sheetname "")
		)
		(fill
			(thermal_gap 0.5)
			(thermal_bridge_width 0.5)
			(island_removal_mode 0)
		)
		(polygon
			(pts
				(xy 387.707632 -24.40051) (xy 387.862826 -24.555704)
				(arc
					(start 387.862826 -24.702008)
					(mid 387.792976 -25.225925)
					(end 387.723126 -24.702008)
				)
				(xy 387.723126 -24.613616) (xy 387.64972 -24.54021) (xy 387.409436 -24.54021)
				(arc
					(start 387.409436 -24.95931)
					(mid 387.792976 -25.34285)
					(end 388.176516 -24.95931)
				)
				(arc
					(start 388.176516 -23.689564)
					(mid 387.793103 -23.30577)
					(end 387.409436 -23.68931)
				)
				(xy 387.409436 -24.10841) (xy 387.64972 -24.10841) (xy 387.723126 -24.035004)
				(arc
					(start 387.723126 -23.946612)
					(mid 387.792976 -23.422695)
					(end 387.862826 -23.946612)
				)
				(xy 387.862826 -24.092916) (xy 387.707632 -24.24811) (xy 387.409436 -24.24811) (xy 387.409436 -24.40051)
			)
		)
	)
	(zone
		(net "GND")
		(layer "In11.Cu")
		(hatch none 0.5)
		(connect_pads
			(clearance 0.5)
		)
		(min_thickness 0.25)
		(fill yes
			(thermal_gap 0.5)
			(thermal_bridge_width 0.5)
			(island_removal_mode 0)
		)
		(polygon
			(pts
				(xy 201.846688 -102.158292) (xy 204.51064 -99.49434) (xy 206.54264 -99.49434) (xy 207.8482 -98.18878)
				(xy 207.8482 -54.102) (xy 207.8482 -53.1622) (xy 207.2386 -52.5526) (xy 206.4766 -52.5526) (xy 206.03972 -52.11572)
				(xy 203.966318 -52.11572) (xy 203.931266 -52.11572) (xy 203.529946 -51.7144) (xy 199.4916 -51.7144)
				(xy 199.377808 -51.828192) (xy 199.377808 -60.414408) (xy 199.377808 -62.419992) (xy 199.377808 -77.254608)
				(xy 199.377808 -78.675992) (xy 199.377808 -84.747608) (xy 199.377808 -86.422992) (xy 199.377808 -92.347288)
				(xy 199.92086 -92.89034) (xy 199.92086 -94.16796) (xy 199.418448 -94.670372) (xy 199.418448 -101.825806)
				(xy 199.750934 -102.158292)
			)
		)
	)
	(zone
		(layer "In11.Cu")
		(hatch none 0.5)
		(connect_pads
			(clearance 0)
		)
		(min_thickness 0.25)
		(keepout
			(tracks allowed)
			(vias allowed)
			(pads allowed)
			(copperpour allowed)
			(footprints allowed)
		)
		(placement
			(enabled no)
			(sheetname "")
		)
		(fill
			(thermal_gap 0.5)
			(thermal_bridge_width 0.5)
			(island_removal_mode 0)
		)
		(polygon
			(pts
				(xy 77.448918 -69.62013) (xy 69.155056 -69.62013) (xy 66.297556 -66.76263) (xy 66.297556 -63.4746)
				(xy 65.910968 -63.4746) (xy 65.631568 -63.1952) (xy 65.631568 -60.833) (xy 65.123568 -60.325) (xy 65.123568 -53.721)
				(xy 66.102992 -53.721) (xy 67.13728 -52.686712) (xy 69.780912 -50.043334) (xy 70.838568 -50.043334)
				(xy 70.838568 -48.9458) (xy 74.470768 -48.9458) (xy 75.207368 -49.6824) (xy 75.207368 -50.043334)
				(xy 75.232768 -50.043334) (xy 75.232768 -50.419) (xy 79.22895 -54.415182) (xy 80.024986 -54.415182)
				(xy 81.451196 -55.841392) (xy 81.451196 -65.617852)
			)
		)
	)
	(zone
		(layer "In12.Cu")
		(hatch none 0.5)
		(connect_pads
			(clearance 0)
		)
		(min_thickness 0.25)
		(keepout
			(tracks not_allowed)
			(vias allowed)
			(pads allowed)
			(copperpour not_allowed)
			(footprints allowed)
		)
		(placement
			(enabled no)
			(sheetname "")
		)
		(fill
			(thermal_gap 0.5)
			(thermal_bridge_width 0.5)
			(island_removal_mode 0)
		)
		(polygon
			(pts
				(xy 304.070512 -4.720082) (xy 304.629312 -4.720082) (xy 304.629312 -6.523482) (xy 304.070512 -6.523482)
			)
		)
	)
	(zone
		(layer "In12.Cu")
		(hatch none 0.5)
		(connect_pads
			(clearance 0)
		)
		(min_thickness 0.25)
		(keepout
			(tracks not_allowed)
			(vias allowed)
			(pads allowed)
			(copperpour not_allowed)
			(footprints allowed)
		)
		(placement
			(enabled no)
			(sheetname "")
		)
		(fill
			(thermal_gap 0.5)
			(thermal_bridge_width 0.5)
			(island_removal_mode 0)
		)
		(polygon
			(pts
				(xy 71.069962 -0.120142) (xy 71.628762 -0.120142) (xy 71.628762 -1.923542) (xy 71.069962 -1.923542)
			)
		)
	)
	(zone
		(layer "In12.Cu")
		(hatch none 0.5)
		(connect_pads
			(clearance 0)
		)
		(min_thickness 0.25)
		(keepout
			(tracks not_allowed)
			(vias allowed)
			(pads allowed)
			(copperpour not_allowed)
			(footprints allowed)
		)
		(placement
			(enabled no)
			(sheetname "")
		)
		(fill
			(thermal_gap 0.5)
			(thermal_bridge_width 0.5)
			(island_removal_mode 0)
		)
		(polygon
			(pts
				(xy 100.819966 -23.922482) (xy 101.378766 -23.922482) (xy 101.378766 -25.725882) (xy 100.819966 -25.725882)
			)
		)
	)
	(zone
		(layer "In12.Cu")
		(hatch none 0.5)
		(connect_pads
			(clearance 0)
		)
		(min_thickness 0.25)
		(keepout
			(tracks not_allowed)
			(vias allowed)
			(pads allowed)
			(copperpour not_allowed)
			(footprints allowed)
		)
		(placement
			(enabled no)
			(sheetname "")
		)
		(fill
			(thermal_gap 0.5)
			(thermal_bridge_width 0.5)
			(island_removal_mode 0)
		)
		(polygon
			(pts
				(xy 99.970082 -0.120142) (xy 100.528882 -0.120142) (xy 100.528882 -1.923542) (xy 99.970082 -1.923542)
			)
		)
	)
	(zone
		(layer "In12.Cu")
		(hatch none 0.5)
		(connect_pads
			(clearance 0)
		)
		(min_thickness 0.25)
		(keepout
			(tracks not_allowed)
			(vias allowed)
			(pads allowed)
			(copperpour not_allowed)
			(footprints allowed)
		)
		(placement
			(enabled no)
			(sheetname "")
		)
		(fill
			(thermal_gap 0.5)
			(thermal_bridge_width 0.5)
			(island_removal_mode 0)
		)
		(polygon
			(pts
				(xy 65.120012 -141.575282) (xy 65.678812 -141.575282) (xy 65.678812 -143.378682) (xy 65.120012 -143.378682)
			)
		)
	)
	(zone
		(layer "In12.Cu")
		(hatch none 0.5)
		(connect_pads
			(clearance 0)
		)
		(min_thickness 0.25)
		(keepout
			(tracks not_allowed)
			(vias allowed)
			(pads allowed)
			(copperpour not_allowed)
			(footprints allowed)
		)
		(placement
			(enabled no)
			(sheetname "")
		)
		(fill
			(thermal_gap 0.5)
			(thermal_bridge_width 0.5)
			(island_removal_mode 0)
		)
		(polygon
			(pts
				(xy 196.120512 -23.922482) (xy 196.679312 -23.922482) (xy 196.679312 -25.725882) (xy 196.120512 -25.725882)
			)
		)
	)
	(zone
		(layer "In12.Cu")
		(hatch none 0.5)
		(connect_pads
			(clearance 0)
		)
		(min_thickness 0.25)
		(keepout
			(tracks not_allowed)
			(vias allowed)
			(pads allowed)
			(copperpour not_allowed)
			(footprints allowed)
		)
		(placement
			(enabled no)
			(sheetname "")
		)
		(fill
			(thermal_gap 0.5)
			(thermal_bridge_width 0.5)
			(island_removal_mode 0)
		)
		(polygon
			(pts
				(xy 256.470404 -19.322542) (xy 257.029204 -19.322542) (xy 257.029204 -21.125942) (xy 256.470404 -21.125942)
			)
		)
	)
	(zone
		(layer "In12.Cu")
		(hatch none 0.5)
		(connect_pads
			(clearance 0)
		)
		(min_thickness 0.25)
		(keepout
			(tracks not_allowed)
			(vias allowed)
			(pads allowed)
			(copperpour not_allowed)
			(footprints allowed)
		)
		(placement
			(enabled no)
			(sheetname "")
		)
		(fill
			(thermal_gap 0.5)
			(thermal_bridge_width 0.5)
			(island_removal_mode 0)
		)
		(polygon
			(pts
				(xy 281.97048 -0.120142) (xy 282.52928 -0.120142) (xy 282.52928 -1.923542) (xy 281.97048 -1.923542)
			)
		)
	)
	(zone
		(layer "In12.Cu")
		(hatch none 0.5)
		(connect_pads
			(clearance 0)
		)
		(min_thickness 0.25)
		(keepout
			(tracks not_allowed)
			(vias allowed)
			(pads allowed)
			(copperpour not_allowed)
			(footprints allowed)
		)
		(placement
			(enabled no)
			(sheetname "")
		)
		(fill
			(thermal_gap 0.5)
			(thermal_bridge_width 0.5)
			(island_removal_mode 0)
		)
		(polygon
			(pts
				(xy 309.170324 -4.720082) (xy 309.729124 -4.720082) (xy 309.729124 -6.523482) (xy 309.170324 -6.523482)
			)
		)
	)
	(zone
		(layer "In12.Cu")
		(hatch none 0.5)
		(connect_pads
			(clearance 0)
		)
		(min_thickness 0.25)
		(keepout
			(tracks not_allowed)
			(vias allowed)
			(pads allowed)
			(copperpour not_allowed)
			(footprints allowed)
		)
		(placement
			(enabled no)
			(sheetname "")
		)
		(fill
			(thermal_gap 0.5)
			(thermal_bridge_width 0.5)
			(island_removal_mode 0)
		)
		(polygon
			(pts
				(xy 122.919998 -9.721342) (xy 123.478798 -9.721342) (xy 123.478798 -11.524742) (xy 122.919998 -11.524742)
			)
		)
	)
	(zone
		(layer "In12.Cu")
		(hatch none 0.5)
		(connect_pads
			(clearance 0)
		)
		(min_thickness 0.25)
		(keepout
			(tracks not_allowed)
			(vias allowed)
			(pads allowed)
			(copperpour not_allowed)
			(footprints allowed)
		)
		(placement
			(enabled no)
			(sheetname "")
		)
		(fill
			(thermal_gap 0.5)
			(thermal_bridge_width 0.5)
			(island_removal_mode 0)
		)
		(polygon
			(pts
				(xy 230.120444 -14.321282) (xy 230.679244 -14.321282) (xy 230.679244 -16.124682) (xy 230.120444 -16.124682)
			)
		)
	)
	(zone
		(layer "In12.Cu")
		(hatch none 0.5)
		(connect_pads
			(clearance 0)
		)
		(min_thickness 0.25)
		(keepout
			(tracks not_allowed)
			(vias allowed)
			(pads allowed)
			(copperpour not_allowed)
			(footprints allowed)
		)
		(placement
			(enabled no)
			(sheetname "")
		)
		(fill
			(thermal_gap 0.5)
			(thermal_bridge_width 0.5)
			(island_removal_mode 0)
		)
		(polygon
			(pts
				(xy 297.270424 -127.374142) (xy 297.829224 -127.374142) (xy 297.829224 -129.177542) (xy 297.270424 -129.177542)
			)
		)
	)
	(zone
		(layer "In12.Cu")
		(hatch none 0.5)
		(connect_pads
			(clearance 0)
		)
		(min_thickness 0.25)
		(keepout
			(tracks not_allowed)
			(vias allowed)
			(pads allowed)
			(copperpour not_allowed)
			(footprints allowed)
		)
		(placement
			(enabled no)
			(sheetname "")
		)
		(fill
			(thermal_gap 0.5)
			(thermal_bridge_width 0.5)
			(island_removal_mode 0)
		)
		(polygon
			(pts
				(xy 427.355 -142.1384) (xy 428.117 -142.1384) (xy 428.117 -141.1478) (xy 427.355 -141.1478)
			)
		)
	)
	(zone
		(layer "In12.Cu")
		(hatch none 0.5)
		(connect_pads
			(clearance 0)
		)
		(min_thickness 0.25)
		(keepout
			(tracks not_allowed)
			(vias allowed)
			(pads allowed)
			(copperpour not_allowed)
			(footprints allowed)
		)
		(placement
			(enabled no)
			(sheetname "")
		)
		(fill
			(thermal_gap 0.5)
			(thermal_bridge_width 0.5)
			(island_removal_mode 0)
		)
		(polygon
			(pts
				(xy 280.270458 -0.120142) (xy 280.829258 -0.120142) (xy 280.829258 -1.923542) (xy 280.270458 -1.923542)
			)
		)
	)
	(zone
		(layer "In12.Cu")
		(hatch none 0.5)
		(connect_pads
			(clearance 0)
		)
		(min_thickness 0.25)
		(keepout
			(tracks not_allowed)
			(vias allowed)
			(pads allowed)
			(copperpour not_allowed)
			(footprints allowed)
		)
		(placement
			(enabled no)
			(sheetname "")
		)
		(fill
			(thermal_gap 0.5)
			(thermal_bridge_width 0.5)
			(island_removal_mode 0)
		)
		(polygon
			(pts
				(xy 60.870084 -4.720082) (xy 61.428884 -4.720082) (xy 61.428884 -6.523482) (xy 60.870084 -6.523482)
			)
		)
	)
	(zone
		(layer "In12.Cu")
		(hatch none 0.5)
		(connect_pads
			(clearance 0)
		)
		(min_thickness 0.25)
		(keepout
			(tracks not_allowed)
			(vias allowed)
			(pads allowed)
			(copperpour not_allowed)
			(footprints allowed)
		)
		(placement
			(enabled no)
			(sheetname "")
		)
		(fill
			(thermal_gap 0.5)
			(thermal_bridge_width 0.5)
			(island_removal_mode 0)
		)
		(polygon
			(pts
				(xy 99.970082 -146.576542) (xy 100.528882 -146.576542) (xy 100.528882 -148.379942) (xy 99.970082 -148.379942)
			)
		)
	)
	(zone
		(layer "In12.Cu")
		(hatch none 0.5)
		(connect_pads
			(clearance 0)
		)
		(min_thickness 0.25)
		(keepout
			(tracks not_allowed)
			(vias allowed)
			(pads allowed)
			(copperpour not_allowed)
			(footprints allowed)
		)
		(placement
			(enabled no)
			(sheetname "")
		)
		(fill
			(thermal_gap 0.5)
			(thermal_bridge_width 0.5)
			(island_removal_mode 0)
		)
		(polygon
			(pts
				(xy 296.42054 -151.176482) (xy 296.97934 -151.176482) (xy 296.97934 -152.979882) (xy 296.42054 -152.979882)
			)
		)
	)
	(zone
		(layer "In12.Cu")
		(hatch none 0.5)
		(connect_pads
			(clearance 0)
		)
		(min_thickness 0.25)
		(keepout
			(tracks not_allowed)
			(vias allowed)
			(pads allowed)
			(copperpour not_allowed)
			(footprints allowed)
		)
		(placement
			(enabled no)
			(sheetname "")
		)
		(fill
			(thermal_gap 0.5)
			(thermal_bridge_width 0.5)
			(island_removal_mode 0)
		)
		(polygon
			(pts
				(xy 126.320042 -9.721342) (xy 126.878842 -9.721342) (xy 126.878842 -11.524742) (xy 126.320042 -11.524742)
			)
		)
	)
	(zone
		(layer "In12.Cu")
		(hatch none 0.5)
		(connect_pads
			(clearance 0)
		)
		(min_thickness 0.25)
		(keepout
			(tracks not_allowed)
			(vias allowed)
			(pads allowed)
			(copperpour not_allowed)
			(footprints allowed)
		)
		(placement
			(enabled no)
			(sheetname "")
		)
		(fill
			(thermal_gap 0.5)
			(thermal_bridge_width 0.5)
			(island_removal_mode 0)
		)
		(polygon
			(pts
				(xy 202.9206 -0.120142) (xy 203.4794 -0.120142) (xy 203.4794 -1.923542) (xy 202.9206 -1.923542)
			)
		)
	)
	(zone
		(layer "In12.Cu")
		(hatch none 0.5)
		(connect_pads
			(clearance 0)
		)
		(min_thickness 0.25)
		(keepout
			(tracks not_allowed)
			(vias allowed)
			(pads allowed)
			(copperpour not_allowed)
			(footprints allowed)
		)
		(placement
			(enabled no)
			(sheetname "")
		)
		(fill
			(thermal_gap 0.5)
			(thermal_bridge_width 0.5)
			(island_removal_mode 0)
		)
		(polygon
			(pts
				(xy 244.570504 -23.922482) (xy 245.129304 -23.922482) (xy 245.129304 -25.725882) (xy 244.570504 -25.725882)
			)
		)
	)
	(zone
		(layer "In12.Cu")
		(hatch none 0.5)
		(connect_pads
			(clearance 0)
		)
		(min_thickness 0.25)
		(keepout
			(tracks not_allowed)
			(vias allowed)
			(pads allowed)
			(copperpour not_allowed)
			(footprints allowed)
		)
		(placement
			(enabled no)
			(sheetname "")
		)
		(fill
			(thermal_gap 0.5)
			(thermal_bridge_width 0.5)
			(island_removal_mode 0)
		)
		(polygon
			(pts
				(xy 122.919998 -0.120142) (xy 123.478798 -0.120142) (xy 123.478798 -1.923542) (xy 122.919998 -1.923542)
			)
		)
	)
	(zone
		(layer "In12.Cu")
		(hatch none 0.5)
		(connect_pads
			(clearance 0)
		)
		(min_thickness 0.25)
		(keepout
			(tracks not_allowed)
			(vias allowed)
			(pads allowed)
			(copperpour not_allowed)
			(footprints allowed)
		)
		(placement
			(enabled no)
			(sheetname "")
		)
		(fill
			(thermal_gap 0.5)
			(thermal_bridge_width 0.5)
			(island_removal_mode 0)
		)
		(polygon
			(pts
				(xy 33.669986 -136.975342) (xy 34.228786 -136.975342) (xy 34.228786 -138.778742) (xy 33.669986 -138.778742)
			)
		)
	)
	(zone
		(layer "In12.Cu")
		(hatch none 0.5)
		(connect_pads
			(clearance 0)
		)
		(min_thickness 0.25)
		(keepout
			(tracks not_allowed)
			(vias allowed)
			(pads allowed)
			(copperpour not_allowed)
			(footprints allowed)
		)
		(placement
			(enabled no)
			(sheetname "")
		)
		(fill
			(thermal_gap 0.5)
			(thermal_bridge_width 0.5)
			(island_removal_mode 0)
		)
		(polygon
			(pts
				(xy 293.020496 -14.321282) (xy 293.579296 -14.321282) (xy 293.579296 -16.124682) (xy 293.020496 -16.124682)
			)
		)
	)
	(zone
		(layer "In12.Cu")
		(hatch none 0.5)
		(connect_pads
			(clearance 0)
		)
		(min_thickness 0.25)
		(keepout
			(tracks not_allowed)
			(vias allowed)
			(pads allowed)
			(copperpour not_allowed)
			(footprints allowed)
		)
		(placement
			(enabled no)
			(sheetname "")
		)
		(fill
			(thermal_gap 0.5)
			(thermal_bridge_width 0.5)
			(island_removal_mode 0)
		)
		(polygon
			(pts
				(xy 69.36994 -146.576542) (xy 69.92874 -146.576542) (xy 69.92874 -148.379942) (xy 69.36994 -148.379942)
			)
		)
	)
	(zone
		(layer "In12.Cu")
		(hatch none 0.5)
		(connect_pads
			(clearance 0)
		)
		(min_thickness 0.25)
		(keepout
			(tracks not_allowed)
			(vias allowed)
			(pads allowed)
			(copperpour not_allowed)
			(footprints allowed)
		)
		(placement
			(enabled no)
			(sheetname "")
		)
		(fill
			(thermal_gap 0.5)
			(thermal_bridge_width 0.5)
			(island_removal_mode 0)
		)
		(polygon
			(pts
				(xy 66.820034 -23.922482) (xy 67.378834 -23.922482) (xy 67.378834 -25.725882) (xy 66.820034 -25.725882)
			)
		)
	)
	(zone
		(layer "In12.Cu")
		(hatch none 0.5)
		(connect_pads
			(clearance 0)
		)
		(min_thickness 0.25)
		(keepout
			(tracks not_allowed)
			(vias allowed)
			(pads allowed)
			(copperpour not_allowed)
			(footprints allowed)
		)
		(placement
			(enabled no)
			(sheetname "")
		)
		(fill
			(thermal_gap 0.5)
			(thermal_bridge_width 0.5)
			(island_removal_mode 0)
		)
		(polygon
			(pts
				(xy 266.670536 -127.374142) (xy 267.229336 -127.374142) (xy 267.229336 -129.177542) (xy 266.670536 -129.177542)
			)
		)
	)
	(zone
		(layer "In12.Cu")
		(hatch none 0.5)
		(connect_pads
			(clearance 0)
		)
		(min_thickness 0.25)
		(keepout
			(tracks not_allowed)
			(vias allowed)
			(pads allowed)
			(copperpour not_allowed)
			(footprints allowed)
		)
		(placement
			(enabled no)
			(sheetname "")
		)
		(fill
			(thermal_gap 0.5)
			(thermal_bridge_width 0.5)
			(island_removal_mode 0)
		)
		(polygon
			(pts
				(xy 284.520386 -19.322542) (xy 285.079186 -19.322542) (xy 285.079186 -21.125942) (xy 284.520386 -21.125942)
			)
		)
	)
	(zone
		(layer "In12.Cu")
		(hatch none 0.5)
		(connect_pads
			(clearance 0)
		)
		(min_thickness 0.25)
		(keepout
			(tracks not_allowed)
			(vias allowed)
			(pads allowed)
			(copperpour not_allowed)
			(footprints allowed)
		)
		(placement
			(enabled no)
			(sheetname "")
		)
		(fill
			(thermal_gap 0.5)
			(thermal_bridge_width 0.5)
			(island_removal_mode 0)
		)
		(polygon
			(pts
				(xy 347.570806 -59.225434) (xy 347.570806 -61.511434) (xy 347.062806 -61.511434) (xy 347.062806 -59.225434)
			)
		)
	)
	(zone
		(layer "In12.Cu")
		(hatch none 0.5)
		(connect_pads
			(clearance 0)
		)
		(min_thickness 0.25)
		(keepout
			(tracks not_allowed)
			(vias allowed)
			(pads allowed)
			(copperpour not_allowed)
			(footprints allowed)
		)
		(placement
			(enabled no)
			(sheetname "")
		)
		(fill
			(thermal_gap 0.5)
			(thermal_bridge_width 0.5)
			(island_removal_mode 0)
		)
		(polygon
			(pts
				(xy 314.27039 -136.975342) (xy 314.82919 -136.975342) (xy 314.82919 -138.778742) (xy 314.27039 -138.778742)
			)
		)
	)
	(zone
		(layer "In12.Cu")
		(hatch none 0.5)
		(connect_pads
			(clearance 0)
		)
		(min_thickness 0.25)
		(keepout
			(tracks not_allowed)
			(vias allowed)
			(pads allowed)
			(copperpour not_allowed)
			(footprints allowed)
		)
		(placement
			(enabled no)
			(sheetname "")
		)
		(fill
			(thermal_gap 0.5)
			(thermal_bridge_width 0.5)
			(island_removal_mode 0)
		)
		(polygon
			(pts
				(xy 46.420024 -14.321282) (xy 46.978824 -14.321282) (xy 46.978824 -16.124682) (xy 46.420024 -16.124682)
			)
		)
	)
	(zone
		(layer "In12.Cu")
		(hatch none 0.5)
		(connect_pads
			(clearance 0)
		)
		(min_thickness 0.25)
		(keepout
			(tracks not_allowed)
			(vias allowed)
			(pads allowed)
			(copperpour not_allowed)
			(footprints allowed)
		)
		(placement
			(enabled no)
			(sheetname "")
		)
		(fill
			(thermal_gap 0.5)
			(thermal_bridge_width 0.5)
			(island_removal_mode 0)
		)
		(polygon
			(pts
				(xy 220.77045 -14.321282) (xy 221.32925 -14.321282) (xy 221.32925 -16.124682) (xy 220.77045 -16.124682)
			)
		)
	)
	(zone
		(layer "In12.Cu")
		(hatch none 0.5)
		(connect_pads
			(clearance 0)
		)
		(min_thickness 0.25)
		(keepout
			(tracks not_allowed)
			(vias allowed)
			(pads allowed)
			(copperpour not_allowed)
			(footprints allowed)
		)
		(placement
			(enabled no)
			(sheetname "")
		)
		(fill
			(thermal_gap 0.5)
			(thermal_bridge_width 0.5)
			(island_removal_mode 0)
		)
		(polygon
			(pts
				(xy 134.819898 -141.575282) (xy 135.378698 -141.575282) (xy 135.378698 -143.378682) (xy 134.819898 -143.378682)
			)
		)
	)
	(zone
		(layer "In12.Cu")
		(hatch none 0.5)
		(connect_pads
			(clearance 0)
		)
		(min_thickness 0.25)
		(keepout
			(tracks not_allowed)
			(vias allowed)
			(pads allowed)
			(copperpour not_allowed)
			(footprints allowed)
		)
		(placement
			(enabled no)
			(sheetname "")
		)
		(fill
			(thermal_gap 0.5)
			(thermal_bridge_width 0.5)
			(island_removal_mode 0)
		)
		(polygon
			(pts
				(xy 141.619986 -136.975342) (xy 142.178786 -136.975342) (xy 142.178786 -138.778742) (xy 141.619986 -138.778742)
			)
		)
	)
	(zone
		(layer "In12.Cu")
		(hatch none 0.5)
		(connect_pads
			(clearance 0)
		)
		(min_thickness 0.25)
		(keepout
			(tracks not_allowed)
			(vias allowed)
			(pads allowed)
			(copperpour not_allowed)
			(footprints allowed)
		)
		(placement
			(enabled no)
			(sheetname "")
		)
		(fill
			(thermal_gap 0.5)
			(thermal_bridge_width 0.5)
			(island_removal_mode 0)
		)
		(polygon
			(pts
				(xy 38.770052 -151.176482) (xy 39.328852 -151.176482) (xy 39.328852 -152.979882) (xy 38.770052 -152.979882)
			)
		)
	)
	(zone
		(layer "In12.Cu")
		(hatch none 0.5)
		(connect_pads
			(clearance 0)
		)
		(min_thickness 0.25)
		(keepout
			(tracks not_allowed)
			(vias allowed)
			(pads allowed)
			(copperpour not_allowed)
			(footprints allowed)
		)
		(placement
			(enabled no)
			(sheetname "")
		)
		(fill
			(thermal_gap 0.5)
			(thermal_bridge_width 0.5)
			(island_removal_mode 0)
		)
		(polygon
			(pts
				(xy 128.020064 -23.922482) (xy 128.578864 -23.922482) (xy 128.578864 -25.725882) (xy 128.020064 -25.725882)
			)
		)
	)
	(zone
		(layer "In12.Cu")
		(hatch none 0.5)
		(connect_pads
			(clearance 0)
		)
		(min_thickness 0.25)
		(keepout
			(tracks not_allowed)
			(vias allowed)
			(pads allowed)
			(copperpour not_allowed)
			(footprints allowed)
		)
		(placement
			(enabled no)
			(sheetname "")
		)
		(fill
			(thermal_gap 0.5)
			(thermal_bridge_width 0.5)
			(island_removal_mode 0)
		)
		(polygon
			(pts
				(xy 88.920066 -141.575282) (xy 89.478866 -141.575282) (xy 89.478866 -143.378682) (xy 88.920066 -143.378682)
			)
		)
	)
	(zone
		(layer "In12.Cu")
		(hatch none 0.5)
		(connect_pads
			(clearance 0)
		)
		(min_thickness 0.25)
		(keepout
			(tracks not_allowed)
			(vias allowed)
			(pads allowed)
			(copperpour not_allowed)
			(footprints allowed)
		)
		(placement
			(enabled no)
			(sheetname "")
		)
		(fill
			(thermal_gap 0.5)
			(thermal_bridge_width 0.5)
			(island_removal_mode 0)
		)
		(polygon
			(pts
				(xy 65.120012 -151.176482) (xy 65.678812 -151.176482) (xy 65.678812 -152.979882) (xy 65.120012 -152.979882)
			)
		)
	)
	(zone
		(layer "In12.Cu")
		(hatch none 0.5)
		(connect_pads
			(clearance 0)
		)
		(min_thickness 0.25)
		(keepout
			(tracks not_allowed)
			(vias allowed)
			(pads allowed)
			(copperpour not_allowed)
			(footprints allowed)
		)
		(placement
			(enabled no)
			(sheetname "")
		)
		(fill
			(thermal_gap 0.5)
			(thermal_bridge_width 0.5)
			(island_removal_mode 0)
		)
		(polygon
			(pts
				(xy 124.62002 -136.975342) (xy 125.17882 -136.975342) (xy 125.17882 -138.778742) (xy 124.62002 -138.778742)
			)
		)
	)
	(zone
		(layer "In12.Cu")
		(hatch none 0.5)
		(connect_pads
			(clearance 0)
		)
		(min_thickness 0.25)
		(keepout
			(tracks not_allowed)
			(vias allowed)
			(pads allowed)
			(copperpour not_allowed)
			(footprints allowed)
		)
		(placement
			(enabled no)
			(sheetname "")
		)
		(fill
			(thermal_gap 0.5)
			(thermal_bridge_width 0.5)
			(island_removal_mode 0)
		)
		(polygon
			(pts
				(xy 216.520522 -151.176482) (xy 217.079322 -151.176482) (xy 217.079322 -152.979882) (xy 216.520522 -152.979882)
			)
		)
	)
	(zone
		(layer "In12.Cu")
		(hatch none 0.5)
		(connect_pads
			(clearance 0)
		)
		(min_thickness 0.25)
		(keepout
			(tracks not_allowed)
			(vias allowed)
			(pads allowed)
			(copperpour not_allowed)
			(footprints allowed)
		)
		(placement
			(enabled no)
			(sheetname "")
		)
		(fill
			(thermal_gap 0.5)
			(thermal_bridge_width 0.5)
			(island_removal_mode 0)
		)
		(polygon
			(pts
				(xy 300.670468 -9.721342) (xy 301.229268 -9.721342) (xy 301.229268 -11.524742) (xy 300.670468 -11.524742)
			)
		)
	)
	(zone
		(layer "In12.Cu")
		(hatch none 0.5)
		(connect_pads
			(clearance 0)
		)
		(min_thickness 0.25)
		(keepout
			(tracks not_allowed)
			(vias allowed)
			(pads allowed)
			(copperpour not_allowed)
			(footprints allowed)
		)
		(placement
			(enabled no)
			(sheetname "")
		)
		(fill
			(thermal_gap 0.5)
			(thermal_bridge_width 0.5)
			(island_removal_mode 0)
		)
		(polygon
			(pts
				(xy 253.920498 -14.321282) (xy 254.479298 -14.321282) (xy 254.479298 -16.124682) (xy 253.920498 -16.124682)
			)
		)
	)
	(zone
		(layer "In12.Cu")
		(hatch none 0.5)
		(connect_pads
			(clearance 0)
		)
		(min_thickness 0.25)
		(keepout
			(tracks not_allowed)
			(vias allowed)
			(pads allowed)
			(copperpour not_allowed)
			(footprints allowed)
		)
		(placement
			(enabled no)
			(sheetname "")
		)
		(fill
			(thermal_gap 0.5)
			(thermal_bridge_width 0.5)
			(island_removal_mode 0)
		)
		(polygon
			(pts
				(xy 200.37044 -19.322542) (xy 200.92924 -19.322542) (xy 200.92924 -21.125942) (xy 200.37044 -21.125942)
			)
		)
	)
	(zone
		(layer "In12.Cu")
		(hatch none 0.5)
		(connect_pads
			(clearance 0)
		)
		(min_thickness 0.25)
		(keepout
			(tracks not_allowed)
			(vias allowed)
			(pads allowed)
			(copperpour not_allowed)
			(footprints allowed)
		)
		(placement
			(enabled no)
			(sheetname "")
		)
		(fill
			(thermal_gap 0.5)
			(thermal_bridge_width 0.5)
			(island_removal_mode 0)
		)
		(polygon
			(pts
				(xy 215.670384 -146.576542) (xy 216.229184 -146.576542) (xy 216.229184 -148.379942) (xy 215.670384 -148.379942)
			)
		)
	)
	(zone
		(layer "In12.Cu")
		(hatch none 0.5)
		(connect_pads
			(clearance 0)
		)
		(min_thickness 0.25)
		(keepout
			(tracks not_allowed)
			(vias allowed)
			(pads allowed)
			(copperpour not_allowed)
			(footprints allowed)
		)
		(placement
			(enabled no)
			(sheetname "")
		)
		(fill
			(thermal_gap 0.5)
			(thermal_bridge_width 0.5)
			(island_removal_mode 0)
		)
		(polygon
			(pts
				(xy 63.41999 -23.922482) (xy 63.97879 -23.922482) (xy 63.97879 -25.725882) (xy 63.41999 -25.725882)
			)
		)
	)
	(zone
		(layer "In12.Cu")
		(hatch none 0.5)
		(connect_pads
			(clearance 0)
		)
		(min_thickness 0.25)
		(keepout
			(tracks not_allowed)
			(vias allowed)
			(pads allowed)
			(copperpour not_allowed)
			(footprints allowed)
		)
		(placement
			(enabled no)
			(sheetname "")
		)
		(fill
			(thermal_gap 0.5)
			(thermal_bridge_width 0.5)
			(island_removal_mode 0)
		)
		(polygon
			(pts
				(xy 308.32044 -0.120142) (xy 308.87924 -0.120142) (xy 308.87924 -1.923542) (xy 308.32044 -1.923542)
			)
		)
	)
	(zone
		(layer "In12.Cu")
		(hatch none 0.5)
		(connect_pads
			(clearance 0)
		)
		(min_thickness 0.25)
		(keepout
			(tracks not_allowed)
			(vias allowed)
			(pads allowed)
			(copperpour not_allowed)
			(footprints allowed)
		)
		(placement
			(enabled no)
			(sheetname "")
		)
		(fill
			(thermal_gap 0.5)
			(thermal_bridge_width 0.5)
			(island_removal_mode 0)
		)
		(polygon
			(pts
				(xy 128.869948 -127.374142) (xy 129.428748 -127.374142) (xy 129.428748 -129.177542) (xy 128.869948 -129.177542)
			)
		)
	)
	(zone
		(layer "In12.Cu")
		(hatch none 0.5)
		(connect_pads
			(clearance 0)
		)
		(min_thickness 0.25)
		(keepout
			(tracks not_allowed)
			(vias allowed)
			(pads allowed)
			(copperpour not_allowed)
			(footprints allowed)
		)
		(placement
			(enabled no)
			(sheetname "")
		)
		(fill
			(thermal_gap 0.5)
			(thermal_bridge_width 0.5)
			(island_removal_mode 0)
		)
		(polygon
			(pts
				(xy 368.963956 -121.697242) (xy 366.677956 -121.697242) (xy 366.677956 -121.189242) (xy 368.963956 -121.189242)
			)
		)
	)
	(zone
		(layer "In12.Cu")
		(hatch none 0.5)
		(connect_pads
			(clearance 0)
		)
		(min_thickness 0.25)
		(keepout
			(tracks not_allowed)
			(vias allowed)
			(pads allowed)
			(copperpour not_allowed)
			(footprints allowed)
		)
		(placement
			(enabled no)
			(sheetname "")
		)
		(fill
			(thermal_gap 0.5)
			(thermal_bridge_width 0.5)
			(island_removal_mode 0)
		)
		(polygon
			(pts
				(xy 111.020098 -127.374142) (xy 111.578898 -127.374142) (xy 111.578898 -129.177542) (xy 111.020098 -129.177542)
			)
		)
	)
	(zone
		(layer "In12.Cu")
		(hatch none 0.5)
		(connect_pads
			(clearance 0)
		)
		(min_thickness 0.25)
		(keepout
			(tracks not_allowed)
			(vias allowed)
			(pads allowed)
			(copperpour not_allowed)
			(footprints allowed)
		)
		(placement
			(enabled no)
			(sheetname "")
		)
		(fill
			(thermal_gap 0.5)
			(thermal_bridge_width 0.5)
			(island_removal_mode 0)
		)
		(polygon
			(pts
				(xy 133.119876 -131.974082) (xy 133.678676 -131.974082) (xy 133.678676 -133.777482) (xy 133.119876 -133.777482)
			)
		)
	)
	(zone
		(layer "In12.Cu")
		(hatch none 0.5)
		(connect_pads
			(clearance 0)
		)
		(min_thickness 0.25)
		(keepout
			(tracks not_allowed)
			(vias allowed)
			(pads allowed)
			(copperpour not_allowed)
			(footprints allowed)
		)
		(placement
			(enabled no)
			(sheetname "")
		)
		(fill
			(thermal_gap 0.5)
			(thermal_bridge_width 0.5)
			(island_removal_mode 0)
		)
		(polygon
			(pts
				(xy 311.720484 -9.721342) (xy 312.279284 -9.721342) (xy 312.279284 -11.524742) (xy 311.720484 -11.524742)
			)
		)
	)
	(zone
		(layer "In12.Cu")
		(hatch none 0.5)
		(connect_pads
			(clearance 0)
		)
		(min_thickness 0.25)
		(keepout
			(tracks not_allowed)
			(vias allowed)
			(pads allowed)
			(copperpour not_allowed)
			(footprints allowed)
		)
		(placement
			(enabled no)
			(sheetname "")
		)
		(fill
			(thermal_gap 0.5)
			(thermal_bridge_width 0.5)
			(island_removal_mode 0)
		)
		(polygon
			(pts
				(xy 301.520352 -141.575282) (xy 302.079152 -141.575282) (xy 302.079152 -143.378682) (xy 301.520352 -143.378682)
			)
		)
	)
	(zone
		(layer "In12.Cu")
		(hatch none 0.5)
		(connect_pads
			(clearance 0)
		)
		(min_thickness 0.25)
		(keepout
			(tracks not_allowed)
			(vias allowed)
			(pads allowed)
			(copperpour not_allowed)
			(footprints allowed)
		)
		(placement
			(enabled no)
			(sheetname "")
		)
		(fill
			(thermal_gap 0.5)
			(thermal_bridge_width 0.5)
			(island_removal_mode 0)
		)
		(polygon
			(pts
				(xy 36.220146 -127.374142) (xy 36.778946 -127.374142) (xy 36.778946 -129.177542) (xy 36.220146 -129.177542)
			)
		)
	)
	(zone
		(layer "In12.Cu")
		(hatch none 0.5)
		(connect_pads
			(clearance 0)
		)
		(min_thickness 0.25)
		(keepout
			(tracks not_allowed)
			(vias allowed)
			(pads allowed)
			(copperpour not_allowed)
			(footprints allowed)
		)
		(placement
			(enabled no)
			(sheetname "")
		)
		(fill
			(thermal_gap 0.5)
			(thermal_bridge_width 0.5)
			(island_removal_mode 0)
		)
		(polygon
			(pts
				(xy 283.670502 -151.176482) (xy 284.229302 -151.176482) (xy 284.229302 -152.979882) (xy 283.670502 -152.979882)
			)
		)
	)
	(zone
		(layer "In12.Cu")
		(hatch none 0.5)
		(connect_pads
			(clearance 0)
		)
		(min_thickness 0.25)
		(keepout
			(tracks not_allowed)
			(vias allowed)
			(pads allowed)
			(copperpour not_allowed)
			(footprints allowed)
		)
		(placement
			(enabled no)
			(sheetname "")
		)
		(fill
			(thermal_gap 0.5)
			(thermal_bridge_width 0.5)
			(island_removal_mode 0)
		)
		(polygon
			(pts
				(xy 236.070394 -136.975342) (xy 236.629194 -136.975342) (xy 236.629194 -138.778742) (xy 236.070394 -138.778742)
			)
		)
	)
	(zone
		(layer "In12.Cu")
		(hatch none 0.5)
		(connect_pads
			(clearance 0)
		)
		(min_thickness 0.25)
		(keepout
			(tracks not_allowed)
			(vias allowed)
			(pads allowed)
			(copperpour not_allowed)
			(footprints allowed)
		)
		(placement
			(enabled no)
			(sheetname "")
		)
		(fill
			(thermal_gap 0.5)
			(thermal_bridge_width 0.5)
			(island_removal_mode 0)
		)
		(polygon
			(pts
				(xy 149.269958 -19.322542) (xy 149.828758 -19.322542) (xy 149.828758 -21.125942) (xy 149.269958 -21.125942)
			)
		)
	)
	(zone
		(layer "In12.Cu")
		(hatch none 0.5)
		(connect_pads
			(clearance 0)
		)
		(min_thickness 0.25)
		(keepout
			(tracks not_allowed)
			(vias allowed)
			(pads allowed)
			(copperpour not_allowed)
			(footprints allowed)
		)
		(placement
			(enabled no)
			(sheetname "")
		)
		(fill
			(thermal_gap 0.5)
			(thermal_bridge_width 0.5)
			(island_removal_mode 0)
		)
		(polygon
			(pts
				(xy 55.770018 -151.176482) (xy 56.328818 -151.176482) (xy 56.328818 -152.979882) (xy 55.770018 -152.979882)
			)
		)
	)
	(zone
		(net "PVDDQ_ABC")
		(layer "In12.Cu")
		(hatch none 0.5)
		(connect_pads
			(clearance 0.5)
		)
		(min_thickness 0.25)
		(fill yes
			(thermal_gap 0.5)
			(thermal_bridge_width 0.5)
			(island_removal_mode 0)
		)
		(polygon
			(pts
				(xy 265.153394 -11.5443) (xy 264.9601 -11.737594) (xy 264.9601 -12.849606) (xy 265.178794 -13.0683)
				(xy 267.637006 -13.0683) (xy 268.373606 -12.3317) (xy 268.805406 -12.3317) (xy 268.9733 -12.163806)
				(xy 268.9733 -11.762994) (xy 268.754606 -11.5443)
			)
		)
	)
	(zone
		(layer "In12.Cu")
		(hatch none 0.5)
		(connect_pads
			(clearance 0)
		)
		(min_thickness 0.25)
		(keepout
			(tracks not_allowed)
			(vias allowed)
			(pads allowed)
			(copperpour not_allowed)
			(footprints allowed)
		)
		(placement
			(enabled no)
			(sheetname "")
		)
		(fill
			(thermal_gap 0.5)
			(thermal_bridge_width 0.5)
			(island_removal_mode 0)
		)
		(polygon
			(pts
				(xy 128.020064 -127.374142) (xy 128.578864 -127.374142) (xy 128.578864 -129.177542) (xy 128.020064 -129.177542)
			)
		)
	)
	(zone
		(layer "In12.Cu")
		(hatch none 0.5)
		(connect_pads
			(clearance 0)
		)
		(min_thickness 0.25)
		(keepout
			(tracks not_allowed)
			(vias allowed)
			(pads allowed)
			(copperpour not_allowed)
			(footprints allowed)
		)
		(placement
			(enabled no)
			(sheetname "")
		)
		(fill
			(thermal_gap 0.5)
			(thermal_bridge_width 0.5)
			(island_removal_mode 0)
		)
		(polygon
			(pts
				(xy 17.58442 -99.46132) (xy 18.98142 -99.46132) (xy 18.98142 -99.96932) (xy 17.58442 -99.96932)
			)
		)
	)
	(zone
		(layer "In12.Cu")
		(hatch none 0.5)
		(connect_pads
			(clearance 0)
		)
		(min_thickness 0.25)
		(keepout
			(tracks not_allowed)
			(vias allowed)
			(pads allowed)
			(copperpour not_allowed)
			(footprints allowed)
		)
		(placement
			(enabled no)
			(sheetname "")
		)
		(fill
			(thermal_gap 0.5)
			(thermal_bridge_width 0.5)
			(island_removal_mode 0)
		)
		(polygon
			(pts
				(xy 213.970362 -19.322542) (xy 214.529162 -19.322542) (xy 214.529162 -21.125942) (xy 213.970362 -21.125942)
			)
		)
	)
	(zone
		(layer "In12.Cu")
		(hatch none 0.5)
		(connect_pads
			(clearance 0)
		)
		(min_thickness 0.25)
		(keepout
			(tracks not_allowed)
			(vias allowed)
			(pads allowed)
			(copperpour not_allowed)
			(footprints allowed)
		)
		(placement
			(enabled no)
			(sheetname "")
		)
		(fill
			(thermal_gap 0.5)
			(thermal_bridge_width 0.5)
			(island_removal_mode 0)
		)
		(polygon
			(pts
				(xy 198.670418 -136.975342) (xy 199.229218 -136.975342) (xy 199.229218 -138.778742) (xy 198.670418 -138.778742)
			)
		)
	)
	(zone
		(layer "In12.Cu")
		(hatch none 0.5)
		(connect_pads
			(clearance 0)
		)
		(min_thickness 0.25)
		(keepout
			(tracks not_allowed)
			(vias allowed)
			(pads allowed)
			(copperpour not_allowed)
			(footprints allowed)
		)
		(placement
			(enabled no)
			(sheetname "")
		)
		(fill
			(thermal_gap 0.5)
			(thermal_bridge_width 0.5)
			(island_removal_mode 0)
		)
		(polygon
			(pts
				(xy 52.369974 -127.374142) (xy 52.928774 -127.374142) (xy 52.928774 -129.177542) (xy 52.369974 -129.177542)
			)
		)
	)
	(zone
		(layer "In12.Cu")
		(hatch none 0.5)
		(connect_pads
			(clearance 0)
		)
		(min_thickness 0.25)
		(keepout
			(tracks not_allowed)
			(vias allowed)
			(pads allowed)
			(copperpour not_allowed)
			(footprints allowed)
		)
		(placement
			(enabled no)
			(sheetname "")
		)
		(fill
			(thermal_gap 0.5)
			(thermal_bridge_width 0.5)
			(island_removal_mode 0)
		)
		(polygon
			(pts
				(xy 408.1018 -154.1018) (xy 408.1018 -154.8638) (xy 409.0924 -154.8638) (xy 409.0924 -154.1018)
			)
		)
	)
	(zone
		(layer "In12.Cu")
		(hatch none 0.5)
		(connect_pads
			(clearance 0)
		)
		(min_thickness 0.25)
		(keepout
			(tracks not_allowed)
			(vias allowed)
			(pads allowed)
			(copperpour not_allowed)
			(footprints allowed)
		)
		(placement
			(enabled no)
			(sheetname "")
		)
		(fill
			(thermal_gap 0.5)
			(thermal_bridge_width 0.5)
			(island_removal_mode 0)
		)
		(polygon
			(pts
				(xy 54.920134 -9.721342) (xy 55.478934 -9.721342) (xy 55.478934 -11.524742) (xy 54.920134 -11.524742)
			)
		)
	)
	(zone
		(layer "In12.Cu")
		(hatch none 0.5)
		(connect_pads
			(clearance 0)
		)
		(min_thickness 0.25)
		(keepout
			(tracks not_allowed)
			(vias allowed)
			(pads allowed)
			(copperpour not_allowed)
			(footprints allowed)
		)
		(placement
			(enabled no)
			(sheetname "")
		)
		(fill
			(thermal_gap 0.5)
			(thermal_bridge_width 0.5)
			(island_removal_mode 0)
		)
		(polygon
			(pts
				(xy 125.469904 -14.321282) (xy 126.028704 -14.321282) (xy 126.028704 -16.124682) (xy 125.469904 -16.124682)
			)
		)
	)
	(zone
		(layer "In12.Cu")
		(hatch none 0.5)
		(connect_pads
			(clearance 0)
		)
		(min_thickness 0.25)
		(keepout
			(tracks not_allowed)
			(vias allowed)
			(pads allowed)
			(copperpour not_allowed)
			(footprints allowed)
		)
		(placement
			(enabled no)
			(sheetname "")
		)
		(fill
			(thermal_gap 0.5)
			(thermal_bridge_width 0.5)
			(island_removal_mode 0)
		)
		(polygon
			(pts
				(xy 78.719934 -0.120142) (xy 79.278734 -0.120142) (xy 79.278734 -1.923542) (xy 78.719934 -1.923542)
			)
		)
	)
	(zone
		(layer "In12.Cu")
		(hatch none 0.5)
		(connect_pads
			(clearance 0)
		)
		(min_thickness 0.25)
		(keepout
			(tracks not_allowed)
			(vias allowed)
			(pads allowed)
			(copperpour not_allowed)
			(footprints allowed)
		)
		(placement
			(enabled no)
			(sheetname "")
		)
		(fill
			(thermal_gap 0.5)
			(thermal_bridge_width 0.5)
			(island_removal_mode 0)
		)
		(polygon
			(pts
				(xy 216.520522 -131.974082) (xy 217.079322 -131.974082) (xy 217.079322 -133.777482) (xy 216.520522 -133.777482)
			)
		)
	)
	(zone
		(layer "In12.Cu")
		(hatch none 0.5)
		(connect_pads
			(clearance 0)
		)
		(min_thickness 0.25)
		(keepout
			(tracks not_allowed)
			(vias allowed)
			(pads allowed)
			(copperpour not_allowed)
			(footprints allowed)
		)
		(placement
			(enabled no)
			(sheetname "")
		)
		(fill
			(thermal_gap 0.5)
			(thermal_bridge_width 0.5)
			(island_removal_mode 0)
		)
		(polygon
			(pts
				(xy 300.670468 -127.374142) (xy 301.229268 -127.374142) (xy 301.229268 -129.177542) (xy 300.670468 -129.177542)
			)
		)
	)
	(zone
		(layer "In12.Cu")
		(hatch none 0.5)
		(connect_pads
			(clearance 0)
		)
		(min_thickness 0.25)
		(keepout
			(tracks not_allowed)
			(vias allowed)
			(pads allowed)
			(copperpour not_allowed)
			(footprints allowed)
		)
		(placement
			(enabled no)
			(sheetname "")
		)
		(fill
			(thermal_gap 0.5)
			(thermal_bridge_width 0.5)
			(island_removal_mode 0)
		)
		(polygon
			(pts
				(xy 82.970116 -19.322542) (xy 83.528916 -19.322542) (xy 83.528916 -21.125942) (xy 82.970116 -21.125942)
			)
		)
	)
	(zone
		(layer "In12.Cu")
		(hatch none 0.5)
		(connect_pads
			(clearance 0)
		)
		(min_thickness 0.25)
		(keepout
			(tracks not_allowed)
			(vias allowed)
			(pads allowed)
			(copperpour not_allowed)
			(footprints allowed)
		)
		(placement
			(enabled no)
			(sheetname "")
		)
		(fill
			(thermal_gap 0.5)
			(thermal_bridge_width 0.5)
			(island_removal_mode 0)
		)
		(polygon
			(pts
				(xy 195.270374 -146.576542) (xy 195.829174 -146.576542) (xy 195.829174 -148.379942) (xy 195.270374 -148.379942)
			)
		)
	)
	(zone
		(layer "In12.Cu")
		(hatch none 0.5)
		(connect_pads
			(clearance 0)
		)
		(min_thickness 0.25)
		(keepout
			(tracks not_allowed)
			(vias allowed)
			(pads allowed)
			(copperpour not_allowed)
			(footprints allowed)
		)
		(placement
			(enabled no)
			(sheetname "")
		)
		(fill
			(thermal_gap 0.5)
			(thermal_bridge_width 0.5)
			(island_removal_mode 0)
		)
		(polygon
			(pts
				(xy 128.020064 -131.974082) (xy 128.578864 -131.974082) (xy 128.578864 -133.777482) (xy 128.020064 -133.777482)
			)
		)
	)
	(zone
		(layer "In12.Cu")
		(hatch none 0.5)
		(connect_pads
			(clearance 0)
		)
		(min_thickness 0.25)
		(keepout
			(tracks not_allowed)
			(vias allowed)
			(pads allowed)
			(copperpour not_allowed)
			(footprints allowed)
		)
		(placement
			(enabled no)
			(sheetname "")
		)
		(fill
			(thermal_gap 0.5)
			(thermal_bridge_width 0.5)
			(island_removal_mode 0)
		)
		(polygon
			(pts
				(xy 82.970116 -146.576542) (xy 83.528916 -146.576542) (xy 83.528916 -148.379942) (xy 82.970116 -148.379942)
			)
		)
	)
	(zone
		(layer "In12.Cu")
		(hatch none 0.5)
		(connect_pads
			(clearance 0)
		)
		(min_thickness 0.25)
		(keepout
			(tracks not_allowed)
			(vias allowed)
			(pads allowed)
			(copperpour not_allowed)
			(footprints allowed)
		)
		(placement
			(enabled no)
			(sheetname "")
		)
		(fill
			(thermal_gap 0.5)
			(thermal_bridge_width 0.5)
			(island_removal_mode 0)
		)
		(polygon
			(pts
				(xy 52.369974 -19.322542) (xy 52.928774 -19.322542) (xy 52.928774 -21.125942) (xy 52.369974 -21.125942)
			)
		)
	)
	(zone
		(layer "In12.Cu")
		(hatch none 0.5)
		(connect_pads
			(clearance 0)
		)
		(min_thickness 0.25)
		(keepout
			(tracks not_allowed)
			(vias allowed)
			(pads allowed)
			(copperpour not_allowed)
			(footprints allowed)
		)
		(placement
			(enabled no)
			(sheetname "")
		)
		(fill
			(thermal_gap 0.5)
			(thermal_bridge_width 0.5)
			(island_removal_mode 0)
		)
		(polygon
			(pts
				(xy 112.72012 -146.576542) (xy 113.27892 -146.576542) (xy 113.27892 -148.379942) (xy 112.72012 -148.379942)
			)
		)
	)
	(zone
		(layer "In12.Cu")
		(hatch none 0.5)
		(connect_pads
			(clearance 0)
		)
		(min_thickness 0.25)
		(keepout
			(tracks not_allowed)
			(vias allowed)
			(pads allowed)
			(copperpour not_allowed)
			(footprints allowed)
		)
		(placement
			(enabled no)
			(sheetname "")
		)
		(fill
			(thermal_gap 0.5)
			(thermal_bridge_width 0.5)
			(island_removal_mode 0)
		)
		(polygon
			(pts
				(xy 242.870482 -23.922482) (xy 243.429282 -23.922482) (xy 243.429282 -25.725882) (xy 242.870482 -25.725882)
			)
		)
	)
	(zone
		(layer "In12.Cu")
		(hatch none 0.5)
		(connect_pads
			(clearance 0)
		)
		(min_thickness 0.25)
		(keepout
			(tracks not_allowed)
			(vias allowed)
			(pads allowed)
			(copperpour not_allowed)
			(footprints allowed)
		)
		(placement
			(enabled no)
			(sheetname "")
		)
		(fill
			(thermal_gap 0.5)
			(thermal_bridge_width 0.5)
			(island_removal_mode 0)
		)
		(polygon
			(pts
				(xy 299.82033 -4.720082) (xy 300.37913 -4.720082) (xy 300.37913 -6.523482) (xy 299.82033 -6.523482)
			)
		)
	)
	(zone
		(layer "In12.Cu")
		(hatch none 0.5)
		(connect_pads
			(clearance 0)
		)
		(min_thickness 0.25)
		(keepout
			(tracks not_allowed)
			(vias allowed)
			(pads allowed)
			(copperpour not_allowed)
			(footprints allowed)
		)
		(placement
			(enabled no)
			(sheetname "")
		)
		(fill
			(thermal_gap 0.5)
			(thermal_bridge_width 0.5)
			(island_removal_mode 0)
		)
		(polygon
			(pts
				(xy 72.769984 -127.374142) (xy 73.328784 -127.374142) (xy 73.328784 -129.177542) (xy 72.769984 -129.177542)
			)
		)
	)
	(zone
		(layer "In12.Cu")
		(hatch none 0.5)
		(connect_pads
			(clearance 0)
		)
		(min_thickness 0.25)
		(keepout
			(tracks not_allowed)
			(vias allowed)
			(pads allowed)
			(copperpour not_allowed)
			(footprints allowed)
		)
		(placement
			(enabled no)
			(sheetname "")
		)
		(fill
			(thermal_gap 0.5)
			(thermal_bridge_width 0.5)
			(island_removal_mode 0)
		)
		(polygon
			(pts
				(xy 76.170282 -23.922482) (xy 76.729082 -23.922482) (xy 76.729082 -25.725882) (xy 76.170282 -25.725882)
			)
		)
	)
	(zone
		(layer "In12.Cu")
		(hatch none 0.5)
		(connect_pads
			(clearance 0)
		)
		(min_thickness 0.25)
		(keepout
			(tracks not_allowed)
			(vias allowed)
			(pads allowed)
			(copperpour not_allowed)
			(footprints allowed)
		)
		(placement
			(enabled no)
			(sheetname "")
		)
		(fill
			(thermal_gap 0.5)
			(thermal_bridge_width 0.5)
			(island_removal_mode 0)
		)
		(polygon
			(pts
				(xy 339.188806 -59.225434) (xy 339.188806 -61.511434) (xy 338.680806 -61.511434) (xy 338.680806 -59.225434)
			)
		)
	)
	(zone
		(layer "In12.Cu")
		(hatch none 0.5)
		(connect_pads
			(clearance 0)
		)
		(min_thickness 0.25)
		(keepout
			(tracks not_allowed)
			(vias allowed)
			(pads allowed)
			(copperpour not_allowed)
			(footprints allowed)
		)
		(placement
			(enabled no)
			(sheetname "")
		)
		(fill
			(thermal_gap 0.5)
			(thermal_bridge_width 0.5)
			(island_removal_mode 0)
		)
		(polygon
			(pts
				(xy 128.020064 -14.321282) (xy 128.578864 -14.321282) (xy 128.578864 -16.124682) (xy 128.020064 -16.124682)
			)
		)
	)
	(zone
		(layer "In12.Cu")
		(hatch none 0.5)
		(connect_pads
			(clearance 0)
		)
		(min_thickness 0.25)
		(keepout
			(tracks not_allowed)
			(vias allowed)
			(pads allowed)
			(copperpour not_allowed)
			(footprints allowed)
		)
		(placement
			(enabled no)
			(sheetname "")
		)
		(fill
			(thermal_gap 0.5)
			(thermal_bridge_width 0.5)
			(island_removal_mode 0)
		)
		(polygon
			(pts
				(xy 61.719968 -127.374142) (xy 62.278768 -127.374142) (xy 62.278768 -129.177542) (xy 61.719968 -129.177542)
			)
		)
	)
	(zone
		(layer "In12.Cu")
		(hatch none 0.5)
		(connect_pads
			(clearance 0)
		)
		(min_thickness 0.25)
		(keepout
			(tracks not_allowed)
			(vias allowed)
			(pads allowed)
			(copperpour not_allowed)
			(footprints allowed)
		)
		(placement
			(enabled no)
			(sheetname "")
		)
		(fill
			(thermal_gap 0.5)
			(thermal_bridge_width 0.5)
			(island_removal_mode 0)
		)
		(polygon
			(pts
				(xy 305.770534 -23.922482) (xy 306.329334 -23.922482) (xy 306.329334 -25.725882) (xy 305.770534 -25.725882)
			)
		)
	)
	(zone
		(layer "In12.Cu")
		(hatch none 0.5)
		(connect_pads
			(clearance 0)
		)
		(min_thickness 0.25)
		(keepout
			(tracks not_allowed)
			(vias allowed)
			(pads allowed)
			(copperpour not_allowed)
			(footprints allowed)
		)
		(placement
			(enabled no)
			(sheetname "")
		)
		(fill
			(thermal_gap 0.5)
			(thermal_bridge_width 0.5)
			(island_removal_mode 0)
		)
		(polygon
			(pts
				(xy 43.870118 -23.922482) (xy 44.428918 -23.922482) (xy 44.428918 -25.725882) (xy 43.870118 -25.725882)
			)
		)
	)
	(zone
		(layer "In12.Cu")
		(hatch none 0.5)
		(connect_pads
			(clearance 0)
		)
		(min_thickness 0.25)
		(keepout
			(tracks not_allowed)
			(vias allowed)
			(pads allowed)
			(copperpour not_allowed)
			(footprints allowed)
		)
		(placement
			(enabled no)
			(sheetname "")
		)
		(fill
			(thermal_gap 0.5)
			(thermal_bridge_width 0.5)
			(island_removal_mode 0)
		)
		(polygon
			(pts
				(xy 135.670036 -9.721342) (xy 136.228836 -9.721342) (xy 136.228836 -11.524742) (xy 135.670036 -11.524742)
			)
		)
	)
	(zone
		(layer "In12.Cu")
		(hatch none 0.5)
		(connect_pads
			(clearance 0)
		)
		(min_thickness 0.25)
		(keepout
			(tracks not_allowed)
			(vias allowed)
			(pads allowed)
			(copperpour not_allowed)
			(footprints allowed)
		)
		(placement
			(enabled no)
			(sheetname "")
		)
		(fill
			(thermal_gap 0.5)
			(thermal_bridge_width 0.5)
			(island_removal_mode 0)
		)
		(polygon
			(pts
				(xy 74.470006 -131.974082) (xy 75.028806 -131.974082) (xy 75.028806 -133.777482) (xy 74.470006 -133.777482)
			)
		)
	)
	(zone
		(layer "In12.Cu")
		(hatch none 0.5)
		(connect_pads
			(clearance 0)
		)
		(min_thickness 0.25)
		(keepout
			(tracks not_allowed)
			(vias allowed)
			(pads allowed)
			(copperpour not_allowed)
			(footprints allowed)
		)
		(placement
			(enabled no)
			(sheetname "")
		)
		(fill
			(thermal_gap 0.5)
			(thermal_bridge_width 0.5)
			(island_removal_mode 0)
		)
		(polygon
			(pts
				(xy 55.770018 -131.974082) (xy 56.328818 -131.974082) (xy 56.328818 -133.777482) (xy 55.770018 -133.777482)
			)
		)
	)
	(zone
		(layer "In12.Cu")
		(hatch none 0.5)
		(connect_pads
			(clearance 0)
		)
		(min_thickness 0.25)
		(keepout
			(tracks not_allowed)
			(vias allowed)
			(pads allowed)
			(copperpour not_allowed)
			(footprints allowed)
		)
		(placement
			(enabled no)
			(sheetname "")
		)
		(fill
			(thermal_gap 0.5)
			(thermal_bridge_width 0.5)
			(island_removal_mode 0)
		)
		(polygon
			(pts
				(xy 300.670468 -146.576542) (xy 301.229268 -146.576542) (xy 301.229268 -148.379942) (xy 300.670468 -148.379942)
			)
		)
	)
	(zone
		(layer "In12.Cu")
		(hatch none 0.5)
		(connect_pads
			(clearance 0)
		)
		(min_thickness 0.25)
		(keepout
			(tracks not_allowed)
			(vias allowed)
			(pads allowed)
			(copperpour not_allowed)
			(footprints allowed)
		)
		(placement
			(enabled no)
			(sheetname "")
		)
		(fill
			(thermal_gap 0.5)
			(thermal_bridge_width 0.5)
			(island_removal_mode 0)
		)
		(polygon
			(pts
				(xy 200.37044 -14.321282) (xy 200.92924 -14.321282) (xy 200.92924 -16.124682) (xy 200.37044 -16.124682)
			)
		)
	)
	(zone
		(layer "In12.Cu")
		(hatch none 0.5)
		(connect_pads
			(clearance 0)
		)
		(min_thickness 0.25)
		(keepout
			(tracks not_allowed)
			(vias allowed)
			(pads allowed)
			(copperpour not_allowed)
			(footprints allowed)
		)
		(placement
			(enabled no)
			(sheetname "")
		)
		(fill
			(thermal_gap 0.5)
			(thermal_bridge_width 0.5)
			(island_removal_mode 0)
		)
		(polygon
			(pts
				(xy 315.120528 -131.974082) (xy 315.679328 -131.974082) (xy 315.679328 -133.777482) (xy 315.120528 -133.777482)
			)
		)
	)
	(zone
		(layer "In12.Cu")
		(hatch none 0.5)
		(connect_pads
			(clearance 0)
		)
		(min_thickness 0.25)
		(keepout
			(tracks not_allowed)
			(vias allowed)
			(pads allowed)
			(copperpour not_allowed)
			(footprints allowed)
		)
		(placement
			(enabled no)
			(sheetname "")
		)
		(fill
			(thermal_gap 0.5)
			(thermal_bridge_width 0.5)
			(island_removal_mode 0)
		)
		(polygon
			(pts
				(xy 303.220374 -146.576542) (xy 303.779174 -146.576542) (xy 303.779174 -148.379942) (xy 303.220374 -148.379942)
			)
		)
	)
	(zone
		(layer "In12.Cu")
		(hatch none 0.5)
		(connect_pads
			(clearance 0)
		)
		(min_thickness 0.25)
		(keepout
			(tracks not_allowed)
			(vias allowed)
			(pads allowed)
			(copperpour not_allowed)
			(footprints allowed)
		)
		(placement
			(enabled no)
			(sheetname "")
		)
		(fill
			(thermal_gap 0.5)
			(thermal_bridge_width 0.5)
			(island_removal_mode 0)
		)
		(polygon
			(pts
				(xy 105.070148 -23.922482) (xy 105.628948 -23.922482) (xy 105.628948 -25.725882) (xy 105.070148 -25.725882)
			)
		)
	)
	(zone
		(layer "In12.Cu")
		(hatch none 0.5)
		(connect_pads
			(clearance 0)
		)
		(min_thickness 0.25)
		(keepout
			(tracks not_allowed)
			(vias allowed)
			(pads allowed)
			(copperpour not_allowed)
			(footprints allowed)
		)
		(placement
			(enabled no)
			(sheetname "")
		)
		(fill
			(thermal_gap 0.5)
			(thermal_bridge_width 0.5)
			(island_removal_mode 0)
		)
		(polygon
			(pts
				(xy 284.520386 -9.721342) (xy 285.079186 -9.721342) (xy 285.079186 -11.524742) (xy 284.520386 -11.524742)
			)
		)
	)
	(zone
		(layer "In12.Cu")
		(hatch none 0.5)
		(connect_pads
			(clearance 0)
		)
		(min_thickness 0.25)
		(keepout
			(tracks not_allowed)
			(vias allowed)
			(pads allowed)
			(copperpour not_allowed)
			(footprints allowed)
		)
		(placement
			(enabled no)
			(sheetname "")
		)
		(fill
			(thermal_gap 0.5)
			(thermal_bridge_width 0.5)
			(island_removal_mode 0)
		)
		(polygon
			(pts
				(xy 44.720002 -136.975342) (xy 45.278802 -136.975342) (xy 45.278802 -138.778742) (xy 44.720002 -138.778742)
			)
		)
	)
	(zone
		(layer "In12.Cu")
		(hatch none 0.5)
		(connect_pads
			(clearance 0)
		)
		(min_thickness 0.25)
		(keepout
			(tracks not_allowed)
			(vias allowed)
			(pads allowed)
			(copperpour not_allowed)
			(footprints allowed)
		)
		(placement
			(enabled no)
			(sheetname "")
		)
		(fill
			(thermal_gap 0.5)
			(thermal_bridge_width 0.5)
			(island_removal_mode 0)
		)
		(polygon
			(pts
				(xy 241.170714 -131.974082) (xy 241.729514 -131.974082) (xy 241.729514 -133.777482) (xy 241.170714 -133.777482)
			)
		)
	)
	(zone
		(layer "In12.Cu")
		(hatch none 0.5)
		(connect_pads
			(clearance 0)
		)
		(min_thickness 0.25)
		(keepout
			(tracks not_allowed)
			(vias allowed)
			(pads allowed)
			(copperpour not_allowed)
			(footprints allowed)
		)
		(placement
			(enabled no)
			(sheetname "")
		)
		(fill
			(thermal_gap 0.5)
			(thermal_bridge_width 0.5)
			(island_removal_mode 0)
		)
		(polygon
			(pts
				(xy 85.520022 -127.374142) (xy 86.078822 -127.374142) (xy 86.078822 -129.177542) (xy 85.520022 -129.177542)
			)
		)
	)
	(zone
		(layer "In12.Cu")
		(hatch none 0.5)
		(connect_pads
			(clearance 0)
		)
		(min_thickness 0.25)
		(keepout
			(tracks not_allowed)
			(vias allowed)
			(pads allowed)
			(copperpour not_allowed)
			(footprints allowed)
		)
		(placement
			(enabled no)
			(sheetname "")
		)
		(fill
			(thermal_gap 0.5)
			(thermal_bridge_width 0.5)
			(island_removal_mode 0)
		)
		(polygon
			(pts
				(xy 114.419888 -4.720082) (xy 114.978688 -4.720082) (xy 114.978688 -6.523482) (xy 114.419888 -6.523482)
			)
		)
	)
	(zone
		(layer "In12.Cu")
		(hatch none 0.5)
		(connect_pads
			(clearance 0)
		)
		(min_thickness 0.25)
		(keepout
			(tracks not_allowed)
			(vias allowed)
			(pads allowed)
			(copperpour not_allowed)
			(footprints allowed)
		)
		(placement
			(enabled no)
			(sheetname "")
		)
		(fill
			(thermal_gap 0.5)
			(thermal_bridge_width 0.5)
			(island_removal_mode 0)
		)
		(polygon
			(pts
				(xy 71.069962 -146.576542) (xy 71.628762 -146.576542) (xy 71.628762 -148.379942) (xy 71.069962 -148.379942)
			)
		)
	)
	(zone
		(layer "In12.Cu")
		(hatch none 0.5)
		(connect_pads
			(clearance 0)
		)
		(min_thickness 0.25)
		(keepout
			(tracks not_allowed)
			(vias allowed)
			(pads allowed)
			(copperpour not_allowed)
			(footprints allowed)
		)
		(placement
			(enabled no)
			(sheetname "")
		)
		(fill
			(thermal_gap 0.5)
			(thermal_bridge_width 0.5)
			(island_removal_mode 0)
		)
		(polygon
			(pts
				(xy 135.670036 -127.374142) (xy 136.228836 -127.374142) (xy 136.228836 -129.177542) (xy 135.670036 -129.177542)
			)
		)
	)
	(zone
		(layer "In12.Cu")
		(hatch none 0.5)
		(connect_pads
			(clearance 0)
		)
		(min_thickness 0.25)
		(keepout
			(tracks not_allowed)
			(vias allowed)
			(pads allowed)
			(copperpour not_allowed)
			(footprints allowed)
		)
		(placement
			(enabled no)
			(sheetname "")
		)
		(fill
			(thermal_gap 0.5)
			(thermal_bridge_width 0.5)
			(island_removal_mode 0)
		)
		(polygon
			(pts
				(xy 83.82 -23.922482) (xy 84.3788 -23.922482) (xy 84.3788 -25.725882) (xy 83.82 -25.725882)
			)
		)
	)
	(zone
		(layer "In12.Cu")
		(hatch none 0.5)
		(connect_pads
			(clearance 0)
		)
		(min_thickness 0.25)
		(keepout
			(tracks not_allowed)
			(vias allowed)
			(pads allowed)
			(copperpour not_allowed)
			(footprints allowed)
		)
		(placement
			(enabled no)
			(sheetname "")
		)
		(fill
			(thermal_gap 0.5)
			(thermal_bridge_width 0.5)
			(island_removal_mode 0)
		)
		(polygon
			(pts
				(xy 349.717614 -123.830842) (xy 347.431614 -123.830842) (xy 347.431614 -123.322842) (xy 349.717614 -123.322842)
			)
		)
	)
	(zone
		(layer "In12.Cu")
		(hatch none 0.5)
		(connect_pads
			(clearance 0)
		)
		(min_thickness 0.25)
		(keepout
			(tracks not_allowed)
			(vias allowed)
			(pads allowed)
			(copperpour not_allowed)
			(footprints allowed)
		)
		(placement
			(enabled no)
			(sheetname "")
		)
		(fill
			(thermal_gap 0.5)
			(thermal_bridge_width 0.5)
			(island_removal_mode 0)
		)
		(polygon
			(pts
				(xy 253.920498 -4.720082) (xy 254.479298 -4.720082) (xy 254.479298 -6.523482) (xy 253.920498 -6.523482)
			)
		)
	)
	(zone
		(layer "In12.Cu")
		(hatch none 0.5)
		(connect_pads
			(clearance 0)
		)
		(min_thickness 0.25)
		(keepout
			(tracks not_allowed)
			(vias allowed)
			(pads allowed)
			(copperpour not_allowed)
			(footprints allowed)
		)
		(placement
			(enabled no)
			(sheetname "")
		)
		(fill
			(thermal_gap 0.5)
			(thermal_bridge_width 0.5)
			(island_removal_mode 0)
		)
		(polygon
			(pts
				(xy 210.570572 -127.374142) (xy 211.129372 -127.374142) (xy 211.129372 -129.177542) (xy 210.570572 -129.177542)
			)
		)
	)
	(zone
		(layer "In12.Cu")
		(hatch none 0.5)
		(connect_pads
			(clearance 0)
		)
		(min_thickness 0.25)
		(keepout
			(tracks not_allowed)
			(vias allowed)
			(pads allowed)
			(copperpour not_allowed)
			(footprints allowed)
		)
		(placement
			(enabled no)
			(sheetname "")
		)
		(fill
			(thermal_gap 0.5)
			(thermal_bridge_width 0.5)
			(island_removal_mode 0)
		)
		(polygon
			(pts
				(xy 228.420422 -146.576542) (xy 228.979222 -146.576542) (xy 228.979222 -148.379942) (xy 228.420422 -148.379942)
			)
		)
	)
	(zone
		(layer "In12.Cu")
		(hatch none 0.5)
		(connect_pads
			(clearance 0)
		)
		(min_thickness 0.25)
		(keepout
			(tracks not_allowed)
			(vias allowed)
			(pads allowed)
			(copperpour not_allowed)
			(footprints allowed)
		)
		(placement
			(enabled no)
			(sheetname "")
		)
		(fill
			(thermal_gap 0.5)
			(thermal_bridge_width 0.5)
			(island_removal_mode 0)
		)
		(polygon
			(pts
				(xy 146.720052 -14.321282) (xy 147.278852 -14.321282) (xy 147.278852 -16.124682) (xy 146.720052 -16.124682)
			)
		)
	)
	(zone
		(layer "In12.Cu")
		(hatch none 0.5)
		(connect_pads
			(clearance 0)
		)
		(min_thickness 0.25)
		(keepout
			(tracks not_allowed)
			(vias allowed)
			(pads allowed)
			(copperpour not_allowed)
			(footprints allowed)
		)
		(placement
			(enabled no)
			(sheetname "")
		)
		(fill
			(thermal_gap 0.5)
			(thermal_bridge_width 0.5)
			(island_removal_mode 0)
		)
		(polygon
			(pts
				(xy 297.270424 -146.576542) (xy 297.829224 -146.576542) (xy 297.829224 -148.379942) (xy 297.270424 -148.379942)
			)
		)
	)
	(zone
		(layer "In12.Cu")
		(hatch none 0.5)
		(connect_pads
			(clearance 0)
		)
		(min_thickness 0.25)
		(keepout
			(tracks not_allowed)
			(vias allowed)
			(pads allowed)
			(copperpour not_allowed)
			(footprints allowed)
		)
		(placement
			(enabled no)
			(sheetname "")
		)
		(fill
			(thermal_gap 0.5)
			(thermal_bridge_width 0.5)
			(island_removal_mode 0)
		)
		(polygon
			(pts
				(xy 247.12041 -141.575282) (xy 247.67921 -141.575282) (xy 247.67921 -143.378682) (xy 247.12041 -143.378682)
			)
		)
	)
	(zone
		(layer "In12.Cu")
		(hatch none 0.5)
		(connect_pads
			(clearance 0)
		)
		(min_thickness 0.25)
		(keepout
			(tracks not_allowed)
			(vias allowed)
			(pads allowed)
			(copperpour not_allowed)
			(footprints allowed)
		)
		(placement
			(enabled no)
			(sheetname "")
		)
		(fill
			(thermal_gap 0.5)
			(thermal_bridge_width 0.5)
			(island_removal_mode 0)
		)
		(polygon
			(pts
				(xy 92.32011 -131.974082) (xy 92.87891 -131.974082) (xy 92.87891 -133.777482) (xy 92.32011 -133.777482)
			)
		)
	)
	(zone
		(layer "In12.Cu")
		(hatch none 0.5)
		(connect_pads
			(clearance 0)
		)
		(min_thickness 0.25)
		(keepout
			(tracks not_allowed)
			(vias allowed)
			(pads allowed)
			(copperpour not_allowed)
			(footprints allowed)
		)
		(placement
			(enabled no)
			(sheetname "")
		)
		(fill
			(thermal_gap 0.5)
			(thermal_bridge_width 0.5)
			(island_removal_mode 0)
		)
		(polygon
			(pts
				(xy 78.719934 -136.975342) (xy 79.278734 -136.975342) (xy 79.278734 -138.778742) (xy 78.719934 -138.778742)
			)
		)
	)
	(zone
		(layer "In12.Cu")
		(hatch none 0.5)
		(connect_pads
			(clearance 0)
		)
		(min_thickness 0.25)
		(keepout
			(tracks not_allowed)
			(vias allowed)
			(pads allowed)
			(copperpour not_allowed)
			(footprints allowed)
		)
		(placement
			(enabled no)
			(sheetname "")
		)
		(fill
			(thermal_gap 0.5)
			(thermal_bridge_width 0.5)
			(island_removal_mode 0)
		)
		(polygon
			(pts
				(xy 138.219942 -9.721342) (xy 138.778742 -9.721342) (xy 138.778742 -11.524742) (xy 138.219942 -11.524742)
			)
		)
	)
	(zone
		(layer "In12.Cu")
		(hatch none 0.5)
		(connect_pads
			(clearance 0)
		)
		(min_thickness 0.25)
		(keepout
			(tracks not_allowed)
			(vias allowed)
			(pads allowed)
			(copperpour not_allowed)
			(footprints allowed)
		)
		(placement
			(enabled no)
			(sheetname "")
		)
		(fill
			(thermal_gap 0.5)
			(thermal_bridge_width 0.5)
			(island_removal_mode 0)
		)
		(polygon
			(pts
				(xy 53.220112 -131.974082) (xy 53.778912 -131.974082) (xy 53.778912 -133.777482) (xy 53.220112 -133.777482)
			)
		)
	)
	(zone
		(layer "In12.Cu")
		(hatch none 0.5)
		(connect_pads
			(clearance 0)
		)
		(min_thickness 0.25)
		(keepout
			(tracks not_allowed)
			(vias allowed)
			(pads allowed)
			(copperpour not_allowed)
			(footprints allowed)
		)
		(placement
			(enabled no)
			(sheetname "")
		)
		(fill
			(thermal_gap 0.5)
			(thermal_bridge_width 0.5)
			(island_removal_mode 0)
		)
		(polygon
			(pts
				(xy 30.269942 -9.721342) (xy 30.828742 -9.721342) (xy 30.828742 -11.524742) (xy 30.269942 -11.524742)
			)
		)
	)
	(zone
		(layer "In12.Cu")
		(hatch none 0.5)
		(connect_pads
			(clearance 0)
		)
		(min_thickness 0.25)
		(keepout
			(tracks not_allowed)
			(vias allowed)
			(pads allowed)
			(copperpour not_allowed)
			(footprints allowed)
		)
		(placement
			(enabled no)
			(sheetname "")
		)
		(fill
			(thermal_gap 0.5)
			(thermal_bridge_width 0.5)
			(island_removal_mode 0)
		)
		(polygon
			(pts
				(xy 202.070462 -23.922482) (xy 202.629262 -23.922482) (xy 202.629262 -25.725882) (xy 202.070462 -25.725882)
			)
		)
	)
	(zone
		(layer "In12.Cu")
		(hatch none 0.5)
		(connect_pads
			(clearance 0)
		)
		(min_thickness 0.25)
		(keepout
			(tracks not_allowed)
			(vias allowed)
			(pads allowed)
			(copperpour not_allowed)
			(footprints allowed)
		)
		(placement
			(enabled no)
			(sheetname "")
		)
		(fill
			(thermal_gap 0.5)
			(thermal_bridge_width 0.5)
			(island_removal_mode 0)
		)
		(polygon
			(pts
				(xy 35.370008 -131.974082) (xy 35.928808 -131.974082) (xy 35.928808 -133.777482) (xy 35.370008 -133.777482)
			)
		)
	)
	(zone
		(layer "In12.Cu")
		(hatch none 0.5)
		(connect_pads
			(clearance 0)
		)
		(min_thickness 0.25)
		(keepout
			(tracks not_allowed)
			(vias allowed)
			(pads allowed)
			(copperpour not_allowed)
			(footprints allowed)
		)
		(placement
			(enabled no)
			(sheetname "")
		)
		(fill
			(thermal_gap 0.5)
			(thermal_bridge_width 0.5)
			(island_removal_mode 0)
		)
		(polygon
			(pts
				(xy 237.770416 -14.321282) (xy 238.329216 -14.321282) (xy 238.329216 -16.124682) (xy 237.770416 -16.124682)
			)
		)
	)
	(zone
		(layer "In12.Cu")
		(hatch none 0.5)
		(connect_pads
			(clearance 0)
		)
		(min_thickness 0.25)
		(keepout
			(tracks not_allowed)
			(vias allowed)
			(pads allowed)
			(copperpour not_allowed)
			(footprints allowed)
		)
		(placement
			(enabled no)
			(sheetname "")
		)
		(fill
			(thermal_gap 0.5)
			(thermal_bridge_width 0.5)
			(island_removal_mode 0)
		)
		(polygon
			(pts
				(xy 444.395606 -51.199034) (xy 444.903606 -51.199034) (xy 444.903606 -52.596034) (xy 444.395606 -52.596034)
			)
		)
	)
	(zone
		(layer "In12.Cu")
		(hatch none 0.5)
		(connect_pads
			(clearance 0)
		)
		(min_thickness 0.25)
		(keepout
			(tracks not_allowed)
			(vias allowed)
			(pads allowed)
			(copperpour not_allowed)
			(footprints allowed)
		)
		(placement
			(enabled no)
			(sheetname "")
		)
		(fill
			(thermal_gap 0.5)
			(thermal_bridge_width 0.5)
			(island_removal_mode 0)
		)
		(polygon
			(pts
				(xy 38.770052 -4.720082) (xy 39.328852 -4.720082) (xy 39.328852 -6.523482) (xy 38.770052 -6.523482)
			)
		)
	)
	(zone
		(layer "In12.Cu")
		(hatch none 0.5)
		(connect_pads
			(clearance 0)
		)
		(min_thickness 0.25)
		(keepout
			(tracks not_allowed)
			(vias allowed)
			(pads allowed)
			(copperpour not_allowed)
			(footprints allowed)
		)
		(placement
			(enabled no)
			(sheetname "")
		)
		(fill
			(thermal_gap 0.5)
			(thermal_bridge_width 0.5)
			(island_removal_mode 0)
		)
		(polygon
			(pts
				(xy 202.070462 -4.720082) (xy 202.629262 -4.720082) (xy 202.629262 -6.523482) (xy 202.070462 -6.523482)
			)
		)
	)
	(zone
		(layer "In12.Cu")
		(hatch none 0.5)
		(connect_pads
			(clearance 0)
		)
		(min_thickness 0.25)
		(keepout
			(tracks not_allowed)
			(vias allowed)
			(pads allowed)
			(copperpour not_allowed)
			(footprints allowed)
		)
		(placement
			(enabled no)
			(sheetname "")
		)
		(fill
			(thermal_gap 0.5)
			(thermal_bridge_width 0.5)
			(island_removal_mode 0)
		)
		(polygon
			(pts
				(xy 209.720434 -141.575282) (xy 210.279234 -141.575282) (xy 210.279234 -143.378682) (xy 209.720434 -143.378682)
			)
		)
	)
	(zone
		(layer "In12.Cu")
		(hatch none 0.5)
		(connect_pads
			(clearance 0)
		)
		(min_thickness 0.25)
		(keepout
			(tracks not_allowed)
			(vias allowed)
			(pads allowed)
			(copperpour not_allowed)
			(footprints allowed)
		)
		(placement
			(enabled no)
			(sheetname "")
		)
		(fill
			(thermal_gap 0.5)
			(thermal_bridge_width 0.5)
			(island_removal_mode 0)
		)
		(polygon
			(pts
				(xy 233.520488 -14.321282) (xy 234.079288 -14.321282) (xy 234.079288 -16.124682) (xy 233.520488 -16.124682)
			)
		)
	)
	(zone
		(layer "In12.Cu")
		(hatch none 0.5)
		(connect_pads
			(clearance 0)
		)
		(min_thickness 0.25)
		(keepout
			(tracks not_allowed)
			(vias allowed)
			(pads allowed)
			(copperpour not_allowed)
			(footprints allowed)
		)
		(placement
			(enabled no)
			(sheetname "")
		)
		(fill
			(thermal_gap 0.5)
			(thermal_bridge_width 0.5)
			(island_removal_mode 0)
		)
		(polygon
			(pts
				(xy 44.720002 -141.575282) (xy 45.278802 -141.575282) (xy 45.278802 -143.378682) (xy 44.720002 -143.378682)
			)
		)
	)
	(zone
		(layer "In12.Cu")
		(hatch none 0.5)
		(connect_pads
			(clearance 0)
		)
		(min_thickness 0.25)
		(keepout
			(tracks not_allowed)
			(vias allowed)
			(pads allowed)
			(copperpour not_allowed)
			(footprints allowed)
		)
		(placement
			(enabled no)
			(sheetname "")
		)
		(fill
			(thermal_gap 0.5)
			(thermal_bridge_width 0.5)
			(island_removal_mode 0)
		)
		(polygon
			(pts
				(xy 196.120512 -131.974082) (xy 196.679312 -131.974082) (xy 196.679312 -133.777482) (xy 196.120512 -133.777482)
			)
		)
	)
	(zone
		(layer "In12.Cu")
		(hatch none 0.5)
		(connect_pads
			(clearance 0)
		)
		(min_thickness 0.25)
		(keepout
			(tracks not_allowed)
			(vias allowed)
			(pads allowed)
			(copperpour not_allowed)
			(footprints allowed)
		)
		(placement
			(enabled no)
			(sheetname "")
		)
		(fill
			(thermal_gap 0.5)
			(thermal_bridge_width 0.5)
			(island_removal_mode 0)
		)
		(polygon
			(pts
				(xy 273.47037 -136.975342) (xy 274.02917 -136.975342) (xy 274.02917 -138.778742) (xy 273.47037 -138.778742)
			)
		)
	)
	(zone
		(layer "In12.Cu")
		(hatch none 0.5)
		(connect_pads
			(clearance 0)
		)
		(min_thickness 0.25)
		(keepout
			(tracks not_allowed)
			(vias allowed)
			(pads allowed)
			(copperpour not_allowed)
			(footprints allowed)
		)
		(placement
			(enabled no)
			(sheetname "")
		)
		(fill
			(thermal_gap 0.5)
			(thermal_bridge_width 0.5)
			(island_removal_mode 0)
		)
		(polygon
			(pts
				(xy 281.120342 -23.922482) (xy 281.679142 -23.922482) (xy 281.679142 -25.725882) (xy 281.120342 -25.725882)
			)
		)
	)
	(zone
		(layer "In12.Cu")
		(hatch none 0.5)
		(connect_pads
			(clearance 0)
		)
		(min_thickness 0.25)
		(keepout
			(tracks not_allowed)
			(vias allowed)
			(pads allowed)
			(copperpour not_allowed)
			(footprints allowed)
		)
		(placement
			(enabled no)
			(sheetname "")
		)
		(fill
			(thermal_gap 0.5)
			(thermal_bridge_width 0.5)
			(island_removal_mode 0)
		)
		(polygon
			(pts
				(xy 119.519954 -127.374142) (xy 120.078754 -127.374142) (xy 120.078754 -129.177542) (xy 119.519954 -129.177542)
			)
		)
	)
	(zone
		(layer "In12.Cu")
		(hatch none 0.5)
		(connect_pads
			(clearance 0)
		)
		(min_thickness 0.25)
		(keepout
			(tracks not_allowed)
			(vias allowed)
			(pads allowed)
			(copperpour not_allowed)
			(footprints allowed)
		)
		(placement
			(enabled no)
			(sheetname "")
		)
		(fill
			(thermal_gap 0.5)
			(thermal_bridge_width 0.5)
			(island_removal_mode 0)
		)
		(polygon
			(pts
				(xy 196.970396 -127.374142) (xy 197.529196 -127.374142) (xy 197.529196 -129.177542) (xy 196.970396 -129.177542)
			)
		)
	)
	(zone
		(layer "In12.Cu")
		(hatch none 0.5)
		(connect_pads
			(clearance 0)
		)
		(min_thickness 0.25)
		(keepout
			(tracks not_allowed)
			(vias allowed)
			(pads allowed)
			(copperpour not_allowed)
			(footprints allowed)
		)
		(placement
			(enabled no)
			(sheetname "")
		)
		(fill
			(thermal_gap 0.5)
			(thermal_bridge_width 0.5)
			(island_removal_mode 0)
		)
		(polygon
			(pts
				(xy 196.120512 -151.176482) (xy 196.679312 -151.176482) (xy 196.679312 -152.979882) (xy 196.120512 -152.979882)
			)
		)
	)
	(zone
		(layer "In12.Cu")
		(hatch none 0.5)
		(connect_pads
			(clearance 0)
		)
		(min_thickness 0.25)
		(keepout
			(tracks not_allowed)
			(vias allowed)
			(pads allowed)
			(copperpour not_allowed)
			(footprints allowed)
		)
		(placement
			(enabled no)
			(sheetname "")
		)
		(fill
			(thermal_gap 0.5)
			(thermal_bridge_width 0.5)
			(island_removal_mode 0)
		)
		(polygon
			(pts
				(xy 117.819932 -14.321282) (xy 118.378732 -14.321282) (xy 118.378732 -16.124682) (xy 117.819932 -16.124682)
			)
		)
	)
	(zone
		(layer "In12.Cu")
		(hatch none 0.5)
		(connect_pads
			(clearance 0)
		)
		(min_thickness 0.25)
		(keepout
			(tracks not_allowed)
			(vias allowed)
			(pads allowed)
			(copperpour not_allowed)
			(footprints allowed)
		)
		(placement
			(enabled no)
			(sheetname "")
		)
		(fill
			(thermal_gap 0.5)
			(thermal_bridge_width 0.5)
			(island_removal_mode 0)
		)
		(polygon
			(pts
				(xy 89.76995 -136.975342) (xy 90.32875 -136.975342) (xy 90.32875 -138.778742) (xy 89.76995 -138.778742)
			)
		)
	)
	(zone
		(layer "In12.Cu")
		(hatch none 0.5)
		(connect_pads
			(clearance 0)
		)
		(min_thickness 0.25)
		(keepout
			(tracks not_allowed)
			(vias allowed)
			(pads allowed)
			(copperpour not_allowed)
			(footprints allowed)
		)
		(placement
			(enabled no)
			(sheetname "")
		)
		(fill
			(thermal_gap 0.5)
			(thermal_bridge_width 0.5)
			(island_removal_mode 0)
		)
		(polygon
			(pts
				(xy 246.270526 -23.922482) (xy 246.829326 -23.922482) (xy 246.829326 -25.725882) (xy 246.270526 -25.725882)
			)
		)
	)
	(zone
		(layer "In12.Cu")
		(hatch none 0.5)
		(connect_pads
			(clearance 0)
		)
		(min_thickness 0.25)
		(keepout
			(tracks not_allowed)
			(vias allowed)
			(pads allowed)
			(copperpour not_allowed)
			(footprints allowed)
		)
		(placement
			(enabled no)
			(sheetname "")
		)
		(fill
			(thermal_gap 0.5)
			(thermal_bridge_width 0.5)
			(island_removal_mode 0)
		)
		(polygon
			(pts
				(xy 140.770102 -23.922482) (xy 141.328902 -23.922482) (xy 141.328902 -25.725882) (xy 140.770102 -25.725882)
			)
		)
	)
	(zone
		(layer "In12.Cu")
		(hatch none 0.5)
		(connect_pads
			(clearance 0)
		)
		(min_thickness 0.25)
		(keepout
			(tracks not_allowed)
			(vias allowed)
			(pads allowed)
			(copperpour not_allowed)
			(footprints allowed)
		)
		(placement
			(enabled no)
			(sheetname "")
		)
		(fill
			(thermal_gap 0.5)
			(thermal_bridge_width 0.5)
			(island_removal_mode 0)
		)
		(polygon
			(pts
				(xy 293.87038 -19.322542) (xy 294.42918 -19.322542) (xy 294.42918 -21.125942) (xy 293.87038 -21.125942)
			)
		)
	)
	(zone
		(layer "In12.Cu")
		(hatch none 0.5)
		(connect_pads
			(clearance 0)
		)
		(min_thickness 0.25)
		(keepout
			(tracks not_allowed)
			(vias allowed)
			(pads allowed)
			(copperpour not_allowed)
			(footprints allowed)
		)
		(placement
			(enabled no)
			(sheetname "")
		)
		(fill
			(thermal_gap 0.5)
			(thermal_bridge_width 0.5)
			(island_removal_mode 0)
		)
		(polygon
			(pts
				(xy 204.620368 -19.322542) (xy 205.179168 -19.322542) (xy 205.179168 -21.125942) (xy 204.620368 -21.125942)
			)
		)
	)
	(zone
		(layer "In12.Cu")
		(hatch none 0.5)
		(connect_pads
			(clearance 0)
		)
		(min_thickness 0.25)
		(keepout
			(tracks not_allowed)
			(vias allowed)
			(pads allowed)
			(copperpour not_allowed)
			(footprints allowed)
		)
		(placement
			(enabled no)
			(sheetname "")
		)
		(fill
			(thermal_gap 0.5)
			(thermal_bridge_width 0.5)
			(island_removal_mode 0)
		)
		(polygon
			(pts
				(xy 292.170358 -23.922482) (xy 292.729158 -23.922482) (xy 292.729158 -25.725882) (xy 292.170358 -25.725882)
			)
		)
	)
	(zone
		(layer "In12.Cu")
		(hatch none 0.5)
		(connect_pads
			(clearance 0)
		)
		(min_thickness 0.25)
		(keepout
			(tracks not_allowed)
			(vias allowed)
			(pads allowed)
			(copperpour not_allowed)
			(footprints allowed)
		)
		(placement
			(enabled no)
			(sheetname "")
		)
		(fill
			(thermal_gap 0.5)
			(thermal_bridge_width 0.5)
			(island_removal_mode 0)
		)
		(polygon
			(pts
				(xy 219.070428 -146.576542) (xy 219.629228 -146.576542) (xy 219.629228 -148.379942) (xy 219.070428 -148.379942)
			)
		)
	)
	(zone
		(layer "In12.Cu")
		(hatch none 0.5)
		(connect_pads
			(clearance 0)
		)
		(min_thickness 0.25)
		(keepout
			(tracks not_allowed)
			(vias allowed)
			(pads allowed)
			(copperpour not_allowed)
			(footprints allowed)
		)
		(placement
			(enabled no)
			(sheetname "")
		)
		(fill
			(thermal_gap 0.5)
			(thermal_bridge_width 0.5)
			(island_removal_mode 0)
		)
		(polygon
			(pts
				(xy 54.069996 -151.176482) (xy 54.628796 -151.176482) (xy 54.628796 -152.979882) (xy 54.069996 -152.979882)
			)
		)
	)
	(zone
		(layer "In12.Cu")
		(hatch none 0.5)
		(connect_pads
			(clearance 0)
		)
		(min_thickness 0.25)
		(keepout
			(tracks not_allowed)
			(vias allowed)
			(pads allowed)
			(copperpour not_allowed)
			(footprints allowed)
		)
		(placement
			(enabled no)
			(sheetname "")
		)
		(fill
			(thermal_gap 0.5)
			(thermal_bridge_width 0.5)
			(island_removal_mode 0)
		)
		(polygon
			(pts
				(xy 135.670036 -0.120142) (xy 136.228836 -0.120142) (xy 136.228836 -1.923542) (xy 135.670036 -1.923542)
			)
		)
	)
	(zone
		(layer "In12.Cu")
		(hatch none 0.5)
		(connect_pads
			(clearance 0)
		)
		(min_thickness 0.25)
		(keepout
			(tracks not_allowed)
			(vias allowed)
			(pads allowed)
			(copperpour not_allowed)
			(footprints allowed)
		)
		(placement
			(enabled no)
			(sheetname "")
		)
		(fill
			(thermal_gap 0.5)
			(thermal_bridge_width 0.5)
			(island_removal_mode 0)
		)
		(polygon
			(pts
				(xy 244.570504 -4.720082) (xy 245.129304 -4.720082) (xy 245.129304 -6.523482) (xy 244.570504 -6.523482)
			)
		)
	)
	(zone
		(layer "In12.Cu")
		(hatch none 0.5)
		(connect_pads
			(clearance 0)
		)
		(min_thickness 0.25)
		(keepout
			(tracks not_allowed)
			(vias allowed)
			(pads allowed)
			(copperpour not_allowed)
			(footprints allowed)
		)
		(placement
			(enabled no)
			(sheetname "")
		)
		(fill
			(thermal_gap 0.5)
			(thermal_bridge_width 0.5)
			(island_removal_mode 0)
		)
		(polygon
			(pts
				(xy 225.870516 -23.922482) (xy 226.429316 -23.922482) (xy 226.429316 -25.725882) (xy 225.870516 -25.725882)
			)
		)
	)
	(zone
		(layer "In12.Cu")
		(hatch none 0.5)
		(connect_pads
			(clearance 0)
		)
		(min_thickness 0.25)
		(keepout
			(tracks not_allowed)
			(vias allowed)
			(pads allowed)
			(copperpour not_allowed)
			(footprints allowed)
		)
		(placement
			(enabled no)
			(sheetname "")
		)
		(fill
			(thermal_gap 0.5)
			(thermal_bridge_width 0.5)
			(island_removal_mode 0)
		)
		(polygon
			(pts
				(xy 221.620588 -9.721342) (xy 222.179388 -9.721342) (xy 222.179388 -11.524742) (xy 221.620588 -11.524742)
			)
		)
	)
	(zone
		(layer "In12.Cu")
		(hatch none 0.5)
		(connect_pads
			(clearance 0)
		)
		(min_thickness 0.25)
		(keepout
			(tracks not_allowed)
			(vias allowed)
			(pads allowed)
			(copperpour not_allowed)
			(footprints allowed)
		)
		(placement
			(enabled no)
			(sheetname "")
		)
		(fill
			(thermal_gap 0.5)
			(thermal_bridge_width 0.5)
			(island_removal_mode 0)
		)
		(polygon
			(pts
				(xy 242.020852 -146.576542) (xy 242.579652 -146.576542) (xy 242.579652 -148.379942) (xy 242.020852 -148.379942)
			)
		)
	)
	(zone
		(layer "In12.Cu")
		(hatch none 0.5)
		(connect_pads
			(clearance 0)
		)
		(min_thickness 0.25)
		(keepout
			(tracks not_allowed)
			(vias allowed)
			(pads allowed)
			(copperpour not_allowed)
			(footprints allowed)
		)
		(placement
			(enabled no)
			(sheetname "")
		)
		(fill
			(thermal_gap 0.5)
			(thermal_bridge_width 0.5)
			(island_removal_mode 0)
		)
		(polygon
			(pts
				(xy 231.820466 -141.575282) (xy 232.379266 -141.575282) (xy 232.379266 -143.378682) (xy 231.820466 -143.378682)
			)
		)
	)
	(zone
		(layer "In12.Cu")
		(hatch none 0.5)
		(connect_pads
			(clearance 0)
		)
		(min_thickness 0.25)
		(keepout
			(tracks not_allowed)
			(vias allowed)
			(pads allowed)
			(copperpour not_allowed)
			(footprints allowed)
		)
		(placement
			(enabled no)
			(sheetname "")
		)
		(fill
			(thermal_gap 0.5)
			(thermal_bridge_width 0.5)
			(island_removal_mode 0)
		)
		(polygon
			(pts
				(xy 309.170324 -14.321282) (xy 309.729124 -14.321282) (xy 309.729124 -16.124682) (xy 309.170324 -16.124682)
			)
		)
	)
	(zone
		(layer "In12.Cu")
		(hatch none 0.5)
		(connect_pads
			(clearance 0)
		)
		(min_thickness 0.25)
		(keepout
			(tracks not_allowed)
			(vias allowed)
			(pads allowed)
			(copperpour not_allowed)
			(footprints allowed)
		)
		(placement
			(enabled no)
			(sheetname "")
		)
		(fill
			(thermal_gap 0.5)
			(thermal_bridge_width 0.5)
			(island_removal_mode 0)
		)
		(polygon
			(pts
				(xy 38.770052 -23.922482) (xy 39.328852 -23.922482) (xy 39.328852 -25.725882) (xy 38.770052 -25.725882)
			)
		)
	)
	(zone
		(layer "In12.Cu")
		(hatch none 0.5)
		(connect_pads
			(clearance 0)
		)
		(min_thickness 0.25)
		(keepout
			(tracks not_allowed)
			(vias allowed)
			(pads allowed)
			(copperpour not_allowed)
			(footprints allowed)
		)
		(placement
			(enabled no)
			(sheetname "")
		)
		(fill
			(thermal_gap 0.5)
			(thermal_bridge_width 0.5)
			(island_removal_mode 0)
		)
		(polygon
			(pts
				(xy 293.020496 -0.120142) (xy 293.579296 -0.120142) (xy 293.579296 -1.923542) (xy 293.020496 -1.923542)
			)
		)
	)
	(zone
		(layer "In12.Cu")
		(hatch none 0.5)
		(connect_pads
			(clearance 0)
		)
		(min_thickness 0.25)
		(keepout
			(tracks not_allowed)
			(vias allowed)
			(pads allowed)
			(copperpour not_allowed)
			(footprints allowed)
		)
		(placement
			(enabled no)
			(sheetname "")
		)
		(fill
			(thermal_gap 0.5)
			(thermal_bridge_width 0.5)
			(island_removal_mode 0)
		)
		(polygon
			(pts
				(xy 128.869948 -136.975342) (xy 129.428748 -136.975342) (xy 129.428748 -138.778742) (xy 128.869948 -138.778742)
			)
		)
	)
	(zone
		(layer "In12.Cu")
		(hatch none 0.5)
		(connect_pads
			(clearance 0)
		)
		(min_thickness 0.25)
		(keepout
			(tracks not_allowed)
			(vias allowed)
			(pads allowed)
			(copperpour not_allowed)
			(footprints allowed)
		)
		(placement
			(enabled no)
			(sheetname "")
		)
		(fill
			(thermal_gap 0.5)
			(thermal_bridge_width 0.5)
			(island_removal_mode 0)
		)
		(polygon
			(pts
				(xy 147.569936 -0.120142) (xy 148.128736 -0.120142) (xy 148.128736 -1.923542) (xy 147.569936 -1.923542)
			)
		)
	)
	(zone
		(layer "In12.Cu")
		(hatch none 0.5)
		(connect_pads
			(clearance 0)
		)
		(min_thickness 0.25)
		(keepout
			(tracks not_allowed)
			(vias allowed)
			(pads allowed)
			(copperpour not_allowed)
			(footprints allowed)
		)
		(placement
			(enabled no)
			(sheetname "")
		)
		(fill
			(thermal_gap 0.5)
			(thermal_bridge_width 0.5)
			(island_removal_mode 0)
		)
		(polygon
			(pts
				(xy 230.970582 -9.721342) (xy 231.529382 -9.721342) (xy 231.529382 -11.524742) (xy 230.970582 -11.524742)
			)
		)
	)
	(zone
		(layer "In12.Cu")
		(hatch none 0.5)
		(connect_pads
			(clearance 0)
		)
		(min_thickness 0.25)
		(keepout
			(tracks not_allowed)
			(vias allowed)
			(pads allowed)
			(copperpour not_allowed)
			(footprints allowed)
		)
		(placement
			(enabled no)
			(sheetname "")
		)
		(fill
			(thermal_gap 0.5)
			(thermal_bridge_width 0.5)
			(island_removal_mode 0)
		)
		(polygon
			(pts
				(xy 242.020852 -19.322542) (xy 242.579652 -19.322542) (xy 242.579652 -21.125942) (xy 242.020852 -21.125942)
			)
		)
	)
	(zone
		(layer "In12.Cu")
		(hatch none 0.5)
		(connect_pads
			(clearance 0)
		)
		(min_thickness 0.25)
		(keepout
			(tracks not_allowed)
			(vias allowed)
			(pads allowed)
			(copperpour not_allowed)
			(footprints allowed)
		)
		(placement
			(enabled no)
			(sheetname "")
		)
		(fill
			(thermal_gap 0.5)
			(thermal_bridge_width 0.5)
			(island_removal_mode 0)
		)
		(polygon
			(pts
				(xy 17.58442 -100.35032) (xy 18.98142 -100.35032) (xy 18.98142 -100.85832) (xy 17.58442 -100.85832)
			)
		)
	)
	(zone
		(layer "In12.Cu")
		(hatch none 0.5)
		(connect_pads
			(clearance 0)
		)
		(min_thickness 0.25)
		(keepout
			(tracks not_allowed)
			(vias allowed)
			(pads allowed)
			(copperpour not_allowed)
			(footprints allowed)
		)
		(placement
			(enabled no)
			(sheetname "")
		)
		(fill
			(thermal_gap 0.5)
			(thermal_bridge_width 0.5)
			(island_removal_mode 0)
		)
		(polygon
			(pts
				(xy 76.170282 -14.321282) (xy 76.729082 -14.321282) (xy 76.729082 -16.124682) (xy 76.170282 -16.124682)
			)
		)
	)
	(zone
		(layer "In12.Cu")
		(hatch none 0.5)
		(connect_pads
			(clearance 0)
		)
		(min_thickness 0.25)
		(keepout
			(tracks not_allowed)
			(vias allowed)
			(pads allowed)
			(copperpour not_allowed)
			(footprints allowed)
		)
		(placement
			(enabled no)
			(sheetname "")
		)
		(fill
			(thermal_gap 0.5)
			(thermal_bridge_width 0.5)
			(island_removal_mode 0)
		)
		(polygon
			(pts
				(xy 350.276414 -125.481842) (xy 347.990414 -125.481842) (xy 347.990414 -124.973842) (xy 350.276414 -124.973842)
			)
		)
	)
	(zone
		(layer "In12.Cu")
		(hatch none 0.5)
		(connect_pads
			(clearance 0)
		)
		(min_thickness 0.25)
		(keepout
			(tracks not_allowed)
			(vias allowed)
			(pads allowed)
			(copperpour not_allowed)
			(footprints allowed)
		)
		(placement
			(enabled no)
			(sheetname "")
		)
		(fill
			(thermal_gap 0.5)
			(thermal_bridge_width 0.5)
			(island_removal_mode 0)
		)
		(polygon
			(pts
				(xy 50.669952 -127.374142) (xy 51.228752 -127.374142) (xy 51.228752 -129.177542) (xy 50.669952 -129.177542)
			)
		)
	)
	(zone
		(layer "In12.Cu")
		(hatch none 0.5)
		(connect_pads
			(clearance 0)
		)
		(min_thickness 0.25)
		(keepout
			(tracks not_allowed)
			(vias allowed)
			(pads allowed)
			(copperpour not_allowed)
			(footprints allowed)
		)
		(placement
			(enabled no)
			(sheetname "")
		)
		(fill
			(thermal_gap 0.5)
			(thermal_bridge_width 0.5)
			(island_removal_mode 0)
		)
		(polygon
			(pts
				(xy 252.220476 -14.321282) (xy 252.779276 -14.321282) (xy 252.779276 -16.124682) (xy 252.220476 -16.124682)
			)
		)
	)
	(zone
		(layer "In12.Cu")
		(hatch none 0.5)
		(connect_pads
			(clearance 0)
		)
		(min_thickness 0.25)
		(keepout
			(tracks not_allowed)
			(vias allowed)
			(pads allowed)
			(copperpour not_allowed)
			(footprints allowed)
		)
		(placement
			(enabled no)
			(sheetname "")
		)
		(fill
			(thermal_gap 0.5)
			(thermal_bridge_width 0.5)
			(island_removal_mode 0)
		)
		(polygon
			(pts
				(xy 123.769882 -131.974082) (xy 124.328682 -131.974082) (xy 124.328682 -133.777482) (xy 123.769882 -133.777482)
			)
		)
	)
	(zone
		(layer "In12.Cu")
		(hatch none 0.5)
		(connect_pads
			(clearance 0)
		)
		(min_thickness 0.25)
		(keepout
			(tracks not_allowed)
			(vias allowed)
			(pads allowed)
			(copperpour not_allowed)
			(footprints allowed)
		)
		(placement
			(enabled no)
			(sheetname "")
		)
		(fill
			(thermal_gap 0.5)
			(thermal_bridge_width 0.5)
			(island_removal_mode 0)
		)
		(polygon
			(pts
				(xy 240.320576 -19.322542) (xy 240.879376 -19.322542) (xy 240.879376 -21.125942) (xy 240.320576 -21.125942)
			)
		)
	)
	(zone
		(layer "In12.Cu")
		(hatch none 0.5)
		(connect_pads
			(clearance 0)
		)
		(min_thickness 0.25)
		(keepout
			(tracks not_allowed)
			(vias allowed)
			(pads allowed)
			(copperpour not_allowed)
			(footprints allowed)
		)
		(placement
			(enabled no)
			(sheetname "")
		)
		(fill
			(thermal_gap 0.5)
			(thermal_bridge_width 0.5)
			(island_removal_mode 0)
		)
		(polygon
			(pts
				(xy 236.920532 -141.575282) (xy 237.479332 -141.575282) (xy 237.479332 -143.378682) (xy 236.920532 -143.378682)
			)
		)
	)
	(zone
		(layer "In12.Cu")
		(hatch none 0.5)
		(connect_pads
			(clearance 0)
		)
		(min_thickness 0.25)
		(keepout
			(tracks not_allowed)
			(vias allowed)
			(pads allowed)
			(copperpour not_allowed)
			(footprints allowed)
		)
		(placement
			(enabled no)
			(sheetname "")
		)
		(fill
			(thermal_gap 0.5)
			(thermal_bridge_width 0.5)
			(island_removal_mode 0)
		)
		(polygon
			(pts
				(xy 233.520488 -151.176482) (xy 234.079288 -151.176482) (xy 234.079288 -152.979882) (xy 233.520488 -152.979882)
			)
		)
	)
	(zone
		(layer "In12.Cu")
		(hatch none 0.5)
		(connect_pads
			(clearance 0)
		)
		(min_thickness 0.25)
		(keepout
			(tracks not_allowed)
			(vias allowed)
			(pads allowed)
			(copperpour not_allowed)
			(footprints allowed)
		)
		(placement
			(enabled no)
			(sheetname "")
		)
		(fill
			(thermal_gap 0.5)
			(thermal_bridge_width 0.5)
			(island_removal_mode 0)
		)
		(polygon
			(pts
				(xy 137.370058 -127.374142) (xy 137.928858 -127.374142) (xy 137.928858 -129.177542) (xy 137.370058 -129.177542)
			)
		)
	)
	(zone
		(layer "In12.Cu")
		(hatch none 0.5)
		(connect_pads
			(clearance 0)
		)
		(min_thickness 0.25)
		(keepout
			(tracks not_allowed)
			(vias allowed)
			(pads allowed)
			(copperpour not_allowed)
			(footprints allowed)
		)
		(placement
			(enabled no)
			(sheetname "")
		)
		(fill
			(thermal_gap 0.5)
			(thermal_bridge_width 0.5)
			(island_removal_mode 0)
		)
		(polygon
			(pts
				(xy 16.56842 -108.57992) (xy 17.96542 -108.57992) (xy 17.96542 -109.08792) (xy 16.56842 -109.08792)
			)
		)
	)
	(zone
		(layer "In12.Cu")
		(hatch none 0.5)
		(connect_pads
			(clearance 0)
		)
		(min_thickness 0.25)
		(keepout
			(tracks not_allowed)
			(vias allowed)
			(pads allowed)
			(copperpour not_allowed)
			(footprints allowed)
		)
		(placement
			(enabled no)
			(sheetname "")
		)
		(fill
			(thermal_gap 0.5)
			(thermal_bridge_width 0.5)
			(island_removal_mode 0)
		)
		(polygon
			(pts
				(xy 58.319924 -136.975342) (xy 58.878724 -136.975342) (xy 58.878724 -138.778742) (xy 58.319924 -138.778742)
			)
		)
	)
	(zone
		(layer "In12.Cu")
		(hatch none 0.5)
		(connect_pads
			(clearance 0)
		)
		(min_thickness 0.25)
		(keepout
			(tracks not_allowed)
			(vias allowed)
			(pads allowed)
			(copperpour not_allowed)
			(footprints allowed)
		)
		(placement
			(enabled no)
			(sheetname "")
		)
		(fill
			(thermal_gap 0.5)
			(thermal_bridge_width 0.5)
			(island_removal_mode 0)
		)
		(polygon
			(pts
				(xy 299.82033 -151.176482) (xy 300.37913 -151.176482) (xy 300.37913 -152.979882) (xy 299.82033 -152.979882)
			)
		)
	)
	(zone
		(layer "In12.Cu")
		(hatch none 0.5)
		(connect_pads
			(clearance 0)
		)
		(min_thickness 0.25)
		(keepout
			(tracks not_allowed)
			(vias allowed)
			(pads allowed)
			(copperpour not_allowed)
			(footprints allowed)
		)
		(placement
			(enabled no)
			(sheetname "")
		)
		(fill
			(thermal_gap 0.5)
			(thermal_bridge_width 0.5)
			(island_removal_mode 0)
		)
		(polygon
			(pts
				(xy 35.370008 -23.922482) (xy 35.928808 -23.922482) (xy 35.928808 -25.725882) (xy 35.370008 -25.725882)
			)
		)
	)
	(zone
		(layer "In12.Cu")
		(hatch none 0.5)
		(connect_pads
			(clearance 0)
		)
		(min_thickness 0.25)
		(keepout
			(tracks not_allowed)
			(vias allowed)
			(pads allowed)
			(copperpour not_allowed)
			(footprints allowed)
		)
		(placement
			(enabled no)
			(sheetname "")
		)
		(fill
			(thermal_gap 0.5)
			(thermal_bridge_width 0.5)
			(island_removal_mode 0)
		)
		(polygon
			(pts
				(xy 257.320542 -131.974082) (xy 257.879342 -131.974082) (xy 257.879342 -133.777482) (xy 257.320542 -133.777482)
			)
		)
	)
	(zone
		(layer "In12.Cu")
		(hatch none 0.5)
		(connect_pads
			(clearance 0)
		)
		(min_thickness 0.25)
		(keepout
			(tracks not_allowed)
			(vias allowed)
			(pads allowed)
			(copperpour not_allowed)
			(footprints allowed)
		)
		(placement
			(enabled no)
			(sheetname "")
		)
		(fill
			(thermal_gap 0.5)
			(thermal_bridge_width 0.5)
			(island_removal_mode 0)
		)
		(polygon
			(pts
				(xy 143.320008 -19.322542) (xy 143.878808 -19.322542) (xy 143.878808 -21.125942) (xy 143.320008 -21.125942)
			)
		)
	)
	(zone
		(layer "In12.Cu")
		(hatch none 0.5)
		(connect_pads
			(clearance 0)
		)
		(min_thickness 0.25)
		(keepout
			(tracks not_allowed)
			(vias allowed)
			(pads allowed)
			(copperpour not_allowed)
			(footprints allowed)
		)
		(placement
			(enabled no)
			(sheetname "")
		)
		(fill
			(thermal_gap 0.5)
			(thermal_bridge_width 0.5)
			(island_removal_mode 0)
		)
		(polygon
			(pts
				(xy 54.920134 -136.975342) (xy 55.478934 -136.975342) (xy 55.478934 -138.778742) (xy 54.920134 -138.778742)
			)
		)
	)
	(zone
		(layer "In12.Cu")
		(hatch none 0.5)
		(connect_pads
			(clearance 0)
		)
		(min_thickness 0.25)
		(keepout
			(tracks not_allowed)
			(vias allowed)
			(pads allowed)
			(copperpour not_allowed)
			(footprints allowed)
		)
		(placement
			(enabled no)
			(sheetname "")
		)
		(fill
			(thermal_gap 0.5)
			(thermal_bridge_width 0.5)
			(island_removal_mode 0)
		)
		(polygon
			(pts
				(xy 247.970548 -19.322542) (xy 248.529348 -19.322542) (xy 248.529348 -21.125942) (xy 247.970548 -21.125942)
			)
		)
	)
	(zone
		(layer "In12.Cu")
		(hatch none 0.5)
		(connect_pads
			(clearance 0)
		)
		(min_thickness 0.25)
		(keepout
			(tracks not_allowed)
			(vias allowed)
			(pads allowed)
			(copperpour not_allowed)
			(footprints allowed)
		)
		(placement
			(enabled no)
			(sheetname "")
		)
		(fill
			(thermal_gap 0.5)
			(thermal_bridge_width 0.5)
			(island_removal_mode 0)
		)
		(polygon
			(pts
				(xy 105.070148 -136.975342) (xy 105.628948 -136.975342) (xy 105.628948 -138.778742) (xy 105.070148 -138.778742)
			)
		)
	)
	(zone
		(layer "In12.Cu")
		(hatch none 0.5)
		(connect_pads
			(clearance 0)
		)
		(min_thickness 0.25)
		(keepout
			(tracks not_allowed)
			(vias allowed)
			(pads allowed)
			(copperpour not_allowed)
			(footprints allowed)
		)
		(placement
			(enabled no)
			(sheetname "")
		)
		(fill
			(thermal_gap 0.5)
			(thermal_bridge_width 0.5)
			(island_removal_mode 0)
		)
		(polygon
			(pts
				(xy 36.220146 -136.975342) (xy 36.778946 -136.975342) (xy 36.778946 -138.778742) (xy 36.220146 -138.778742)
			)
		)
	)
	(zone
		(layer "In12.Cu")
		(hatch none 0.5)
		(connect_pads
			(clearance 0)
		)
		(min_thickness 0.25)
		(keepout
			(tracks not_allowed)
			(vias allowed)
			(pads allowed)
			(copperpour not_allowed)
			(footprints allowed)
		)
		(placement
			(enabled no)
			(sheetname "")
		)
		(fill
			(thermal_gap 0.5)
			(thermal_bridge_width 0.5)
			(island_removal_mode 0)
		)
		(polygon
			(pts
				(xy 272.620486 -14.321282) (xy 273.179286 -14.321282) (xy 273.179286 -16.124682) (xy 272.620486 -16.124682)
			)
		)
	)
	(zone
		(layer "In12.Cu")
		(hatch none 0.5)
		(connect_pads
			(clearance 0)
		)
		(min_thickness 0.25)
		(keepout
			(tracks not_allowed)
			(vias allowed)
			(pads allowed)
			(copperpour not_allowed)
			(footprints allowed)
		)
		(placement
			(enabled no)
			(sheetname "")
		)
		(fill
			(thermal_gap 0.5)
			(thermal_bridge_width 0.5)
			(island_removal_mode 0)
		)
		(polygon
			(pts
				(xy 85.520022 -136.975342) (xy 86.078822 -136.975342) (xy 86.078822 -138.778742) (xy 85.520022 -138.778742)
			)
		)
	)
	(zone
		(layer "In12.Cu")
		(hatch none 0.5)
		(connect_pads
			(clearance 0)
		)
		(min_thickness 0.25)
		(keepout
			(tracks not_allowed)
			(vias allowed)
			(pads allowed)
			(copperpour not_allowed)
			(footprints allowed)
		)
		(placement
			(enabled no)
			(sheetname "")
		)
		(fill
			(thermal_gap 0.5)
			(thermal_bridge_width 0.5)
			(island_removal_mode 0)
		)
		(polygon
			(pts
				(xy 385.09194 -30.317694) (xy 386.48894 -30.317694) (xy 386.48894 -30.825694) (xy 385.09194 -30.825694)
			)
		)
	)
	(zone
		(layer "In12.Cu")
		(hatch none 0.5)
		(connect_pads
			(clearance 0)
		)
		(min_thickness 0.25)
		(keepout
			(tracks not_allowed)
			(vias allowed)
			(pads allowed)
			(copperpour not_allowed)
			(footprints allowed)
		)
		(placement
			(enabled no)
			(sheetname "")
		)
		(fill
			(thermal_gap 0.5)
			(thermal_bridge_width 0.5)
			(island_removal_mode 0)
		)
		(polygon
			(pts
				(xy 37.920168 -0.120142) (xy 38.478968 -0.120142) (xy 38.478968 -1.923542) (xy 37.920168 -1.923542)
			)
		)
	)
	(zone
		(layer "In12.Cu")
		(hatch none 0.5)
		(connect_pads
			(clearance 0)
		)
		(min_thickness 0.25)
		(keepout
			(tracks not_allowed)
			(vias allowed)
			(pads allowed)
			(copperpour not_allowed)
			(footprints allowed)
		)
		(placement
			(enabled no)
			(sheetname "")
		)
		(fill
			(thermal_gap 0.5)
			(thermal_bridge_width 0.5)
			(island_removal_mode 0)
		)
		(polygon
			(pts
				(xy 253.070614 -0.120142) (xy 253.629414 -0.120142) (xy 253.629414 -1.923542) (xy 253.070614 -1.923542)
			)
		)
	)
	(zone
		(layer "In12.Cu")
		(hatch none 0.5)
		(connect_pads
			(clearance 0)
		)
		(min_thickness 0.25)
		(keepout
			(tracks not_allowed)
			(vias allowed)
			(pads allowed)
			(copperpour not_allowed)
			(footprints allowed)
		)
		(placement
			(enabled no)
			(sheetname "")
		)
		(fill
			(thermal_gap 0.5)
			(thermal_bridge_width 0.5)
			(island_removal_mode 0)
		)
		(polygon
			(pts
				(xy 39.619936 -19.322542) (xy 40.178736 -19.322542) (xy 40.178736 -21.125942) (xy 39.619936 -21.125942)
			)
		)
	)
	(zone
		(layer "In12.Cu")
		(hatch none 0.5)
		(connect_pads
			(clearance 0)
		)
		(min_thickness 0.25)
		(keepout
			(tracks not_allowed)
			(vias allowed)
			(pads allowed)
			(copperpour not_allowed)
			(footprints allowed)
		)
		(placement
			(enabled no)
			(sheetname "")
		)
		(fill
			(thermal_gap 0.5)
			(thermal_bridge_width 0.5)
			(island_removal_mode 0)
		)
		(polygon
			(pts
				(xy 280.270458 -136.975342) (xy 280.829258 -136.975342) (xy 280.829258 -138.778742) (xy 280.270458 -138.778742)
			)
		)
	)
	(zone
		(layer "In12.Cu")
		(hatch none 0.5)
		(connect_pads
			(clearance 0)
		)
		(min_thickness 0.25)
		(keepout
			(tracks not_allowed)
			(vias allowed)
			(pads allowed)
			(copperpour not_allowed)
			(footprints allowed)
		)
		(placement
			(enabled no)
			(sheetname "")
		)
		(fill
			(thermal_gap 0.5)
			(thermal_bridge_width 0.5)
			(island_removal_mode 0)
		)
		(polygon
			(pts
				(xy 150.96998 -0.120142) (xy 151.52878 -0.120142) (xy 151.52878 -1.923542) (xy 150.96998 -1.923542)
			)
		)
	)
	(zone
		(layer "In12.Cu")
		(hatch none 0.5)
		(connect_pads
			(clearance 0)
		)
		(min_thickness 0.25)
		(keepout
			(tracks not_allowed)
			(vias allowed)
			(pads allowed)
			(copperpour not_allowed)
			(footprints allowed)
		)
		(placement
			(enabled no)
			(sheetname "")
		)
		(fill
			(thermal_gap 0.5)
			(thermal_bridge_width 0.5)
			(island_removal_mode 0)
		)
		(polygon
			(pts
				(xy 87.220044 -14.321282) (xy 87.778844 -14.321282) (xy 87.778844 -16.124682) (xy 87.220044 -16.124682)
			)
		)
	)
	(zone
		(layer "In12.Cu")
		(hatch none 0.5)
		(connect_pads
			(clearance 0)
		)
		(min_thickness 0.25)
		(keepout
			(tracks not_allowed)
			(vias allowed)
			(pads allowed)
			(copperpour not_allowed)
			(footprints allowed)
		)
		(placement
			(enabled no)
			(sheetname "")
		)
		(fill
			(thermal_gap 0.5)
			(thermal_bridge_width 0.5)
			(island_removal_mode 0)
		)
		(polygon
			(pts
				(xy 276.02053 -9.721342) (xy 276.57933 -9.721342) (xy 276.57933 -11.524742) (xy 276.02053 -11.524742)
			)
		)
	)
	(zone
		(layer "In12.Cu")
		(hatch none 0.5)
		(connect_pads
			(clearance 0)
		)
		(min_thickness 0.25)
		(keepout
			(tracks not_allowed)
			(vias allowed)
			(pads allowed)
			(copperpour not_allowed)
			(footprints allowed)
		)
		(placement
			(enabled no)
			(sheetname "")
		)
		(fill
			(thermal_gap 0.5)
			(thermal_bridge_width 0.5)
			(island_removal_mode 0)
		)
		(polygon
			(pts
				(xy 55.770018 -141.575282) (xy 56.328818 -141.575282) (xy 56.328818 -143.378682) (xy 55.770018 -143.378682)
			)
		)
	)
	(zone
		(layer "In12.Cu")
		(hatch none 0.5)
		(connect_pads
			(clearance 0)
		)
		(min_thickness 0.25)
		(keepout
			(tracks not_allowed)
			(vias allowed)
			(pads allowed)
			(copperpour not_allowed)
			(footprints allowed)
		)
		(placement
			(enabled no)
			(sheetname "")
		)
		(fill
			(thermal_gap 0.5)
			(thermal_bridge_width 0.5)
			(island_removal_mode 0)
		)
		(polygon
			(pts
				(xy 302.37049 -9.721342) (xy 302.92929 -9.721342) (xy 302.92929 -11.524742) (xy 302.37049 -11.524742)
			)
		)
	)
	(zone
		(layer "In12.Cu")
		(hatch none 0.5)
		(connect_pads
			(clearance 0)
		)
		(min_thickness 0.25)
		(keepout
			(tracks not_allowed)
			(vias allowed)
			(pads allowed)
			(copperpour not_allowed)
			(footprints allowed)
		)
		(placement
			(enabled no)
			(sheetname "")
		)
		(fill
			(thermal_gap 0.5)
			(thermal_bridge_width 0.5)
			(island_removal_mode 0)
		)
		(polygon
			(pts
				(xy 289.620452 -0.120142) (xy 290.179252 -0.120142) (xy 290.179252 -1.923542) (xy 289.620452 -1.923542)
			)
		)
	)
	(zone
		(layer "In12.Cu")
		(hatch none 0.5)
		(connect_pads
			(clearance 0)
		)
		(min_thickness 0.25)
		(keepout
			(tracks not_allowed)
			(vias allowed)
			(pads allowed)
			(copperpour not_allowed)
			(footprints allowed)
		)
		(placement
			(enabled no)
			(sheetname "")
		)
		(fill
			(thermal_gap 0.5)
			(thermal_bridge_width 0.5)
			(island_removal_mode 0)
		)
		(polygon
			(pts
				(xy 426.339 -142.1384) (xy 427.101 -142.1384) (xy 427.101 -141.1478) (xy 426.339 -141.1478)
			)
		)
	)
	(zone
		(layer "In12.Cu")
		(hatch none 0.5)
		(connect_pads
			(clearance 0)
		)
		(min_thickness 0.25)
		(keepout
			(tracks not_allowed)
			(vias allowed)
			(pads allowed)
			(copperpour not_allowed)
			(footprints allowed)
		)
		(placement
			(enabled no)
			(sheetname "")
		)
		(fill
			(thermal_gap 0.5)
			(thermal_bridge_width 0.5)
			(island_removal_mode 0)
		)
		(polygon
			(pts
				(xy 251.370592 -23.922482) (xy 251.929392 -23.922482) (xy 251.929392 -25.725882) (xy 251.370592 -25.725882)
			)
		)
	)
	(zone
		(layer "In12.Cu")
		(hatch none 0.5)
		(connect_pads
			(clearance 0)
		)
		(min_thickness 0.25)
		(keepout
			(tracks not_allowed)
			(vias allowed)
			(pads allowed)
			(copperpour not_allowed)
			(footprints allowed)
		)
		(placement
			(enabled no)
			(sheetname "")
		)
		(fill
			(thermal_gap 0.5)
			(thermal_bridge_width 0.5)
			(island_removal_mode 0)
		)
		(polygon
			(pts
				(xy 41.319958 -146.576542) (xy 41.878758 -146.576542) (xy 41.878758 -148.379942) (xy 41.319958 -148.379942)
			)
		)
	)
	(zone
		(layer "In12.Cu")
		(hatch none 0.5)
		(connect_pads
			(clearance 0)
		)
		(min_thickness 0.25)
		(keepout
			(tracks not_allowed)
			(vias allowed)
			(pads allowed)
			(copperpour not_allowed)
			(footprints allowed)
		)
		(placement
			(enabled no)
			(sheetname "")
		)
		(fill
			(thermal_gap 0.5)
			(thermal_bridge_width 0.5)
			(island_removal_mode 0)
		)
		(polygon
			(pts
				(xy 421.132 -142.0114) (xy 421.894 -142.0114) (xy 421.894 -141.0208) (xy 421.132 -141.0208)
			)
		)
	)
	(zone
		(layer "In12.Cu")
		(hatch none 0.5)
		(connect_pads
			(clearance 0)
		)
		(min_thickness 0.25)
		(keepout
			(tracks not_allowed)
			(vias allowed)
			(pads allowed)
			(copperpour not_allowed)
			(footprints allowed)
		)
		(placement
			(enabled no)
			(sheetname "")
		)
		(fill
			(thermal_gap 0.5)
			(thermal_bridge_width 0.5)
			(island_removal_mode 0)
		)
		(polygon
			(pts
				(xy 42.170096 -14.321282) (xy 42.728896 -14.321282) (xy 42.728896 -16.124682) (xy 42.170096 -16.124682)
			)
		)
	)
	(zone
		(layer "In12.Cu")
		(hatch none 0.5)
		(connect_pads
			(clearance 0)
		)
		(min_thickness 0.25)
		(keepout
			(tracks not_allowed)
			(vias allowed)
			(pads allowed)
			(copperpour not_allowed)
			(footprints allowed)
		)
		(placement
			(enabled no)
			(sheetname "")
		)
		(fill
			(thermal_gap 0.5)
			(thermal_bridge_width 0.5)
			(island_removal_mode 0)
		)
		(polygon
			(pts
				(xy 267.52042 -9.721342) (xy 268.07922 -9.721342) (xy 268.07922 -11.524742) (xy 267.52042 -11.524742)
			)
		)
	)
	(zone
		(layer "In12.Cu")
		(hatch none 0.5)
		(connect_pads
			(clearance 0)
		)
		(min_thickness 0.25)
		(keepout
			(tracks not_allowed)
			(vias allowed)
			(pads allowed)
			(copperpour not_allowed)
			(footprints allowed)
		)
		(placement
			(enabled no)
			(sheetname "")
		)
		(fill
			(thermal_gap 0.5)
			(thermal_bridge_width 0.5)
			(island_removal_mode 0)
		)
		(polygon
			(pts
				(xy 249.67057 -23.922482) (xy 250.22937 -23.922482) (xy 250.22937 -25.725882) (xy 249.67057 -25.725882)
			)
		)
	)
	(zone
		(layer "In12.Cu")
		(hatch none 0.5)
		(connect_pads
			(clearance 0)
		)
		(min_thickness 0.25)
		(keepout
			(tracks not_allowed)
			(vias allowed)
			(pads allowed)
			(copperpour not_allowed)
			(footprints allowed)
		)
		(placement
			(enabled no)
			(sheetname "")
		)
		(fill
			(thermal_gap 0.5)
			(thermal_bridge_width 0.5)
			(island_removal_mode 0)
		)
		(polygon
			(pts
				(xy 39.619936 -127.374142) (xy 40.178736 -127.374142) (xy 40.178736 -129.177542) (xy 39.619936 -129.177542)
			)
		)
	)
	(zone
		(layer "In12.Cu")
		(hatch none 0.5)
		(connect_pads
			(clearance 0)
		)
		(min_thickness 0.25)
		(keepout
			(tracks not_allowed)
			(vias allowed)
			(pads allowed)
			(copperpour not_allowed)
			(footprints allowed)
		)
		(placement
			(enabled no)
			(sheetname "")
		)
		(fill
			(thermal_gap 0.5)
			(thermal_bridge_width 0.5)
			(island_removal_mode 0)
		)
		(polygon
			(pts
				(xy 100.819966 -141.575282) (xy 101.378766 -141.575282) (xy 101.378766 -143.378682) (xy 100.819966 -143.378682)
			)
		)
	)
	(zone
		(layer "In12.Cu")
		(hatch none 0.5)
		(connect_pads
			(clearance 0)
		)
		(min_thickness 0.25)
		(keepout
			(tracks not_allowed)
			(vias allowed)
			(pads allowed)
			(copperpour not_allowed)
			(footprints allowed)
		)
		(placement
			(enabled no)
			(sheetname "")
		)
		(fill
			(thermal_gap 0.5)
			(thermal_bridge_width 0.5)
			(island_removal_mode 0)
		)
		(polygon
			(pts
				(xy 239.470438 -131.974082) (xy 240.029238 -131.974082) (xy 240.029238 -133.777482) (xy 239.470438 -133.777482)
			)
		)
	)
	(zone
		(layer "In12.Cu")
		(hatch none 0.5)
		(connect_pads
			(clearance 0)
		)
		(min_thickness 0.25)
		(keepout
			(tracks not_allowed)
			(vias allowed)
			(pads allowed)
			(copperpour not_allowed)
			(footprints allowed)
		)
		(placement
			(enabled no)
			(sheetname "")
		)
		(fill
			(thermal_gap 0.5)
			(thermal_bridge_width 0.5)
			(island_removal_mode 0)
		)
		(polygon
			(pts
				(xy 54.069996 -9.721342) (xy 54.628796 -9.721342) (xy 54.628796 -11.524742) (xy 54.069996 -11.524742)
			)
		)
	)
	(zone
		(layer "In12.Cu")
		(hatch none 0.5)
		(connect_pads
			(clearance 0)
		)
		(min_thickness 0.25)
		(keepout
			(tracks not_allowed)
			(vias allowed)
			(pads allowed)
			(copperpour not_allowed)
			(footprints allowed)
		)
		(placement
			(enabled no)
			(sheetname "")
		)
		(fill
			(thermal_gap 0.5)
			(thermal_bridge_width 0.5)
			(island_removal_mode 0)
		)
		(polygon
			(pts
				(xy 72.769984 -4.720082) (xy 73.328784 -4.720082) (xy 73.328784 -6.523482) (xy 72.769984 -6.523482)
			)
		)
	)
	(zone
		(layer "In12.Cu")
		(hatch none 0.5)
		(connect_pads
			(clearance 0)
		)
		(min_thickness 0.25)
		(keepout
			(tracks not_allowed)
			(vias allowed)
			(pads allowed)
			(copperpour not_allowed)
			(footprints allowed)
		)
		(placement
			(enabled no)
			(sheetname "")
		)
		(fill
			(thermal_gap 0.5)
			(thermal_bridge_width 0.5)
			(island_removal_mode 0)
		)
		(polygon
			(pts
				(xy 247.12041 -136.975342) (xy 247.67921 -136.975342) (xy 247.67921 -138.778742) (xy 247.12041 -138.778742)
			)
		)
	)
	(zone
		(layer "In12.Cu")
		(hatch none 0.5)
		(connect_pads
			(clearance 0)
		)
		(min_thickness 0.25)
		(keepout
			(tracks not_allowed)
			(vias allowed)
			(pads allowed)
			(copperpour not_allowed)
			(footprints allowed)
		)
		(placement
			(enabled no)
			(sheetname "")
		)
		(fill
			(thermal_gap 0.5)
			(thermal_bridge_width 0.5)
			(island_removal_mode 0)
		)
		(polygon
			(pts
				(xy 49.820068 -141.575282) (xy 50.378868 -141.575282) (xy 50.378868 -143.378682) (xy 49.820068 -143.378682)
			)
		)
	)
	(zone
		(layer "In12.Cu")
		(hatch none 0.5)
		(connect_pads
			(clearance 0)
		)
		(min_thickness 0.25)
		(keepout
			(tracks not_allowed)
			(vias allowed)
			(pads allowed)
			(copperpour not_allowed)
			(footprints allowed)
		)
		(placement
			(enabled no)
			(sheetname "")
		)
		(fill
			(thermal_gap 0.5)
			(thermal_bridge_width 0.5)
			(island_removal_mode 0)
		)
		(polygon
			(pts
				(xy 282.820364 -141.575282) (xy 283.379164 -141.575282) (xy 283.379164 -143.378682) (xy 282.820364 -143.378682)
			)
		)
	)
	(zone
		(layer "In12.Cu")
		(hatch none 0.5)
		(connect_pads
			(clearance 0)
		)
		(min_thickness 0.25)
		(keepout
			(tracks not_allowed)
			(vias allowed)
			(pads allowed)
			(copperpour not_allowed)
			(footprints allowed)
		)
		(placement
			(enabled no)
			(sheetname "")
		)
		(fill
			(thermal_gap 0.5)
			(thermal_bridge_width 0.5)
			(island_removal_mode 0)
		)
		(polygon
			(pts
				(xy 147.569936 -146.576542) (xy 148.128736 -146.576542) (xy 148.128736 -148.379942) (xy 147.569936 -148.379942)
			)
		)
	)
	(zone
		(net "PVDDQ_DEF")
		(layer "In12.Cu")
		(hatch none 0.5)
		(connect_pads
			(clearance 0.5)
		)
		(min_thickness 0.25)
		(fill yes
			(thermal_gap 0.5)
			(thermal_bridge_width 0.5)
			(island_removal_mode 0)
		)
		(polygon
			(pts
				(xy 244.020594 -129.1463) (xy 243.7765 -129.390394)
				(arc
					(start 243.7765 -130.4036)
					(mid 243.761916 -130.476447)
					(end 243.72062 -130.53822)
				)
				(xy 242.8875 -131.371594) (xy 242.8875 -131.848606) (xy 243.029994 -131.9911) (xy 258.442206 -131.9911)
				(xy 258.7117 -131.721606) (xy 258.7117 -129.542794) (xy 258.315206 -129.1463)
			)
		)
	)
	(zone
		(layer "In12.Cu")
		(hatch none 0.5)
		(connect_pads
			(clearance 0)
		)
		(min_thickness 0.25)
		(keepout
			(tracks not_allowed)
			(vias allowed)
			(pads allowed)
			(copperpour not_allowed)
			(footprints allowed)
		)
		(placement
			(enabled no)
			(sheetname "")
		)
		(fill
			(thermal_gap 0.5)
			(thermal_bridge_width 0.5)
			(island_removal_mode 0)
		)
		(polygon
			(pts
				(xy 34.520124 -23.922482) (xy 35.078924 -23.922482) (xy 35.078924 -25.725882) (xy 34.520124 -25.725882)
			)
		)
	)
	(zone
		(layer "In12.Cu")
		(hatch none 0.5)
		(connect_pads
			(clearance 0)
		)
		(min_thickness 0.25)
		(keepout
			(tracks not_allowed)
			(vias allowed)
			(pads allowed)
			(copperpour not_allowed)
			(footprints allowed)
		)
		(placement
			(enabled no)
			(sheetname "")
		)
		(fill
			(thermal_gap 0.5)
			(thermal_bridge_width 0.5)
			(island_removal_mode 0)
		)
		(polygon
			(pts
				(xy 244.570504 -141.575282) (xy 245.129304 -141.575282) (xy 245.129304 -143.378682) (xy 244.570504 -143.378682)
			)
		)
	)
	(zone
		(layer "In12.Cu")
		(hatch none 0.5)
		(connect_pads
			(clearance 0)
		)
		(min_thickness 0.25)
		(keepout
			(tracks not_allowed)
			(vias allowed)
			(pads allowed)
			(copperpour not_allowed)
			(footprints allowed)
		)
		(placement
			(enabled no)
			(sheetname "")
		)
		(fill
			(thermal_gap 0.5)
			(thermal_bridge_width 0.5)
			(island_removal_mode 0)
		)
		(polygon
			(pts
				(xy 61.719968 -9.721342) (xy 62.278768 -9.721342) (xy 62.278768 -11.524742) (xy 61.719968 -11.524742)
			)
		)
	)
	(zone
		(layer "In12.Cu")
		(hatch none 0.5)
		(connect_pads
			(clearance 0)
		)
		(min_thickness 0.25)
		(keepout
			(tracks not_allowed)
			(vias allowed)
			(pads allowed)
			(copperpour not_allowed)
			(footprints allowed)
		)
		(placement
			(enabled no)
			(sheetname "")
		)
		(fill
			(thermal_gap 0.5)
			(thermal_bridge_width 0.5)
			(island_removal_mode 0)
		)
		(polygon
			(pts
				(xy 60.870084 -151.176482) (xy 61.428884 -151.176482) (xy 61.428884 -152.979882) (xy 60.870084 -152.979882)
			)
		)
	)
	(zone
		(layer "In12.Cu")
		(hatch none 0.5)
		(connect_pads
			(clearance 0)
		)
		(min_thickness 0.25)
		(keepout
			(tracks not_allowed)
			(vias allowed)
			(pads allowed)
			(copperpour not_allowed)
			(footprints allowed)
		)
		(placement
			(enabled no)
			(sheetname "")
		)
		(fill
			(thermal_gap 0.5)
			(thermal_bridge_width 0.5)
			(island_removal_mode 0)
		)
		(polygon
			(pts
				(xy 266.670536 -0.120142) (xy 267.229336 -0.120142) (xy 267.229336 -1.923542) (xy 266.670536 -1.923542)
			)
		)
	)
	(zone
		(layer "In12.Cu")
		(hatch none 0.5)
		(connect_pads
			(clearance 0)
		)
		(min_thickness 0.25)
		(keepout
			(tracks not_allowed)
			(vias allowed)
			(pads allowed)
			(copperpour not_allowed)
			(footprints allowed)
		)
		(placement
			(enabled no)
			(sheetname "")
		)
		(fill
			(thermal_gap 0.5)
			(thermal_bridge_width 0.5)
			(island_removal_mode 0)
		)
		(polygon
			(pts
				(xy 446.786 -115.34902) (xy 447.294 -115.34902) (xy 447.294 -116.74602) (xy 446.786 -116.74602)
			)
		)
	)
	(zone
		(layer "In12.Cu")
		(hatch none 0.5)
		(connect_pads
			(clearance 0)
		)
		(min_thickness 0.25)
		(keepout
			(tracks not_allowed)
			(vias allowed)
			(pads allowed)
			(copperpour not_allowed)
			(footprints allowed)
		)
		(placement
			(enabled no)
			(sheetname "")
		)
		(fill
			(thermal_gap 0.5)
			(thermal_bridge_width 0.5)
			(island_removal_mode 0)
		)
		(polygon
			(pts
				(xy 208.020412 -9.721342) (xy 208.579212 -9.721342) (xy 208.579212 -11.524742) (xy 208.020412 -11.524742)
			)
		)
	)
	(zone
		(layer "In12.Cu")
		(hatch none 0.5)
		(connect_pads
			(clearance 0)
		)
		(min_thickness 0.25)
		(keepout
			(tracks not_allowed)
			(vias allowed)
			(pads allowed)
			(copperpour not_allowed)
			(footprints allowed)
		)
		(placement
			(enabled no)
			(sheetname "")
		)
		(fill
			(thermal_gap 0.5)
			(thermal_bridge_width 0.5)
			(island_removal_mode 0)
		)
		(polygon
			(pts
				(xy 128.869948 -19.322542) (xy 129.428748 -19.322542) (xy 129.428748 -21.125942) (xy 128.869948 -21.125942)
			)
		)
	)
	(zone
		(layer "In12.Cu")
		(hatch none 0.5)
		(connect_pads
			(clearance 0)
		)
		(min_thickness 0.25)
		(keepout
			(tracks not_allowed)
			(vias allowed)
			(pads allowed)
			(copperpour not_allowed)
			(footprints allowed)
		)
		(placement
			(enabled no)
			(sheetname "")
		)
		(fill
			(thermal_gap 0.5)
			(thermal_bridge_width 0.5)
			(island_removal_mode 0)
		)
		(polygon
			(pts
				(xy 65.97015 -0.120142) (xy 66.52895 -0.120142) (xy 66.52895 -1.923542) (xy 65.97015 -1.923542)
			)
		)
	)
	(zone
		(layer "In12.Cu")
		(hatch none 0.5)
		(connect_pads
			(clearance 0)
		)
		(min_thickness 0.25)
		(keepout
			(tracks not_allowed)
			(vias allowed)
			(pads allowed)
			(copperpour not_allowed)
			(footprints allowed)
		)
		(placement
			(enabled no)
			(sheetname "")
		)
		(fill
			(thermal_gap 0.5)
			(thermal_bridge_width 0.5)
			(island_removal_mode 0)
		)
		(polygon
			(pts
				(xy 279.42032 -131.974082) (xy 279.97912 -131.974082) (xy 279.97912 -133.777482) (xy 279.42032 -133.777482)
			)
		)
	)
	(zone
		(layer "In12.Cu")
		(hatch none 0.5)
		(connect_pads
			(clearance 0)
		)
		(min_thickness 0.25)
		(keepout
			(tracks not_allowed)
			(vias allowed)
			(pads allowed)
			(copperpour not_allowed)
			(footprints allowed)
		)
		(placement
			(enabled no)
			(sheetname "")
		)
		(fill
			(thermal_gap 0.5)
			(thermal_bridge_width 0.5)
			(island_removal_mode 0)
		)
		(polygon
			(pts
				(xy 66.820034 -14.321282) (xy 67.378834 -14.321282) (xy 67.378834 -16.124682) (xy 66.820034 -16.124682)
			)
		)
	)
	(zone
		(layer "In12.Cu")
		(hatch none 0.5)
		(connect_pads
			(clearance 0)
		)
		(min_thickness 0.25)
		(keepout
			(tracks not_allowed)
			(vias allowed)
			(pads allowed)
			(copperpour not_allowed)
			(footprints allowed)
		)
		(placement
			(enabled no)
			(sheetname "")
		)
		(fill
			(thermal_gap 0.5)
			(thermal_bridge_width 0.5)
			(island_removal_mode 0)
		)
		(polygon
			(pts
				(xy 129.720086 -14.321282) (xy 130.278886 -14.321282) (xy 130.278886 -16.124682) (xy 129.720086 -16.124682)
			)
		)
	)
	(zone
		(layer "In12.Cu")
		(hatch none 0.5)
		(connect_pads
			(clearance 0)
		)
		(min_thickness 0.25)
		(keepout
			(tracks not_allowed)
			(vias allowed)
			(pads allowed)
			(copperpour not_allowed)
			(footprints allowed)
		)
		(placement
			(enabled no)
			(sheetname "")
		)
		(fill
			(thermal_gap 0.5)
			(thermal_bridge_width 0.5)
			(island_removal_mode 0)
		)
		(polygon
			(pts
				(xy 237.770416 -131.974082) (xy 238.329216 -131.974082) (xy 238.329216 -133.777482) (xy 237.770416 -133.777482)
			)
		)
	)
	(zone
		(layer "In12.Cu")
		(hatch none 0.5)
		(connect_pads
			(clearance 0)
		)
		(min_thickness 0.25)
		(keepout
			(tracks not_allowed)
			(vias allowed)
			(pads allowed)
			(copperpour not_allowed)
			(footprints allowed)
		)
		(placement
			(enabled no)
			(sheetname "")
		)
		(fill
			(thermal_gap 0.5)
			(thermal_bridge_width 0.5)
			(island_removal_mode 0)
		)
		(polygon
			(pts
				(xy 43.870118 -141.575282) (xy 44.428918 -141.575282) (xy 44.428918 -143.378682) (xy 43.870118 -143.378682)
			)
		)
	)
	(zone
		(layer "In12.Cu")
		(hatch none 0.5)
		(connect_pads
			(clearance 0)
		)
		(min_thickness 0.25)
		(keepout
			(tracks not_allowed)
			(vias allowed)
			(pads allowed)
			(copperpour not_allowed)
			(footprints allowed)
		)
		(placement
			(enabled no)
			(sheetname "")
		)
		(fill
			(thermal_gap 0.5)
			(thermal_bridge_width 0.5)
			(island_removal_mode 0)
		)
		(polygon
			(pts
				(xy 134.819898 -151.176482) (xy 135.378698 -151.176482) (xy 135.378698 -152.979882) (xy 134.819898 -152.979882)
			)
		)
	)
	(zone
		(layer "In12.Cu")
		(hatch none 0.5)
		(connect_pads
			(clearance 0)
		)
		(min_thickness 0.25)
		(keepout
			(tracks not_allowed)
			(vias allowed)
			(pads allowed)
			(copperpour not_allowed)
			(footprints allowed)
		)
		(placement
			(enabled no)
			(sheetname "")
		)
		(fill
			(thermal_gap 0.5)
			(thermal_bridge_width 0.5)
			(island_removal_mode 0)
		)
		(polygon
			(pts
				(xy 340.42096 -76.551536) (xy 340.42096 -78.837536) (xy 339.91296 -78.837536) (xy 339.91296 -76.551536)
			)
		)
	)
	(zone
		(layer "In12.Cu")
		(hatch none 0.5)
		(connect_pads
			(clearance 0)
		)
		(min_thickness 0.25)
		(keepout
			(tracks not_allowed)
			(vias allowed)
			(pads allowed)
			(copperpour not_allowed)
			(footprints allowed)
		)
		(placement
			(enabled no)
			(sheetname "")
		)
		(fill
			(thermal_gap 0.5)
			(thermal_bridge_width 0.5)
			(island_removal_mode 0)
		)
		(polygon
			(pts
				(xy 12.14882 -101.32568) (xy 13.54582 -101.32568) (xy 13.54582 -101.83368) (xy 12.14882 -101.83368)
			)
		)
	)
	(zone
		(layer "In12.Cu")
		(hatch none 0.5)
		(connect_pads
			(clearance 0)
		)
		(min_thickness 0.25)
		(keepout
			(tracks not_allowed)
			(vias allowed)
			(pads allowed)
			(copperpour not_allowed)
			(footprints allowed)
		)
		(placement
			(enabled no)
			(sheetname "")
		)
		(fill
			(thermal_gap 0.5)
			(thermal_bridge_width 0.5)
			(island_removal_mode 0)
		)
		(polygon
			(pts
				(xy 251.370592 -14.321282) (xy 251.929392 -14.321282) (xy 251.929392 -16.124682) (xy 251.370592 -16.124682)
			)
		)
	)
	(zone
		(layer "In12.Cu")
		(hatch none 0.5)
		(connect_pads
			(clearance 0)
		)
		(min_thickness 0.25)
		(keepout
			(tracks not_allowed)
			(vias allowed)
			(pads allowed)
			(copperpour not_allowed)
			(footprints allowed)
		)
		(placement
			(enabled no)
			(sheetname "")
		)
		(fill
			(thermal_gap 0.5)
			(thermal_bridge_width 0.5)
			(island_removal_mode 0)
		)
		(polygon
			(pts
				(xy 248.820432 -151.176482) (xy 249.379232 -151.176482) (xy 249.379232 -152.979882) (xy 248.820432 -152.979882)
			)
		)
	)
	(zone
		(layer "In12.Cu")
		(hatch none 0.5)
		(connect_pads
			(clearance 0)
		)
		(min_thickness 0.25)
		(keepout
			(tracks not_allowed)
			(vias allowed)
			(pads allowed)
			(copperpour not_allowed)
			(footprints allowed)
		)
		(placement
			(enabled no)
			(sheetname "")
		)
		(fill
			(thermal_gap 0.5)
			(thermal_bridge_width 0.5)
			(island_removal_mode 0)
		)
		(polygon
			(pts
				(xy 219.920566 -0.120142) (xy 220.479366 -0.120142) (xy 220.479366 -1.923542) (xy 219.920566 -1.923542)
			)
		)
	)
	(zone
		(layer "In12.Cu")
		(hatch none 0.5)
		(connect_pads
			(clearance 0)
		)
		(min_thickness 0.25)
		(keepout
			(tracks not_allowed)
			(vias allowed)
			(pads allowed)
			(copperpour not_allowed)
			(footprints allowed)
		)
		(placement
			(enabled no)
			(sheetname "")
		)
		(fill
			(thermal_gap 0.5)
			(thermal_bridge_width 0.5)
			(island_removal_mode 0)
		)
		(polygon
			(pts
				(xy 306.620418 -136.975342) (xy 307.179218 -136.975342) (xy 307.179218 -138.778742) (xy 306.620418 -138.778742)
			)
		)
	)
	(zone
		(layer "In12.Cu")
		(hatch none 0.5)
		(connect_pads
			(clearance 0)
		)
		(min_thickness 0.25)
		(keepout
			(tracks not_allowed)
			(vias allowed)
			(pads allowed)
			(copperpour not_allowed)
			(footprints allowed)
		)
		(placement
			(enabled no)
			(sheetname "")
		)
		(fill
			(thermal_gap 0.5)
			(thermal_bridge_width 0.5)
			(island_removal_mode 0)
		)
		(polygon
			(pts
				(xy 77.87005 -23.922482) (xy 78.42885 -23.922482) (xy 78.42885 -25.725882) (xy 77.87005 -25.725882)
			)
		)
	)
	(zone
		(layer "In12.Cu")
		(hatch none 0.5)
		(connect_pads
			(clearance 0)
		)
		(min_thickness 0.25)
		(keepout
			(tracks not_allowed)
			(vias allowed)
			(pads allowed)
			(copperpour not_allowed)
			(footprints allowed)
		)
		(placement
			(enabled no)
			(sheetname "")
		)
		(fill
			(thermal_gap 0.5)
			(thermal_bridge_width 0.5)
			(island_removal_mode 0)
		)
		(polygon
			(pts
				(xy 122.070114 -131.974082) (xy 122.628914 -131.974082) (xy 122.628914 -133.777482) (xy 122.070114 -133.777482)
			)
		)
	)
	(zone
		(layer "In12.Cu")
		(hatch none 0.5)
		(connect_pads
			(clearance 0)
		)
		(min_thickness 0.25)
		(keepout
			(tracks not_allowed)
			(vias allowed)
			(pads allowed)
			(copperpour not_allowed)
			(footprints allowed)
		)
		(placement
			(enabled no)
			(sheetname "")
		)
		(fill
			(thermal_gap 0.5)
			(thermal_bridge_width 0.5)
			(island_removal_mode 0)
		)
		(polygon
			(pts
				(xy 440.2074 -51.1556) (xy 440.7154 -51.1556) (xy 440.7154 -52.5526) (xy 440.2074 -52.5526)
			)
		)
	)
	(zone
		(layer "In12.Cu")
		(hatch none 0.5)
		(connect_pads
			(clearance 0)
		)
		(min_thickness 0.25)
		(keepout
			(tracks not_allowed)
			(vias allowed)
			(pads allowed)
			(copperpour not_allowed)
			(footprints allowed)
		)
		(placement
			(enabled no)
			(sheetname "")
		)
		(fill
			(thermal_gap 0.5)
			(thermal_bridge_width 0.5)
			(island_removal_mode 0)
		)
		(polygon
			(pts
				(xy 247.12041 -0.120142) (xy 247.67921 -0.120142) (xy 247.67921 -1.923542) (xy 247.12041 -1.923542)
			)
		)
	)
	(zone
		(layer "In12.Cu")
		(hatch none 0.5)
		(connect_pads
			(clearance 0)
		)
		(min_thickness 0.25)
		(keepout
			(tracks not_allowed)
			(vias allowed)
			(pads allowed)
			(copperpour not_allowed)
			(footprints allowed)
		)
		(placement
			(enabled no)
			(sheetname "")
		)
		(fill
			(thermal_gap 0.5)
			(thermal_bridge_width 0.5)
			(island_removal_mode 0)
		)
		(polygon
			(pts
				(xy 295.570402 -146.576542) (xy 296.129202 -146.576542) (xy 296.129202 -148.379942) (xy 295.570402 -148.379942)
			)
		)
	)
	(zone
		(layer "In12.Cu")
		(hatch none 0.5)
		(connect_pads
			(clearance 0)
		)
		(min_thickness 0.25)
		(keepout
			(tracks not_allowed)
			(vias allowed)
			(pads allowed)
			(copperpour not_allowed)
			(footprints allowed)
		)
		(placement
			(enabled no)
			(sheetname "")
		)
		(fill
			(thermal_gap 0.5)
			(thermal_bridge_width 0.5)
			(island_removal_mode 0)
		)
		(polygon
			(pts
				(xy 34.520124 -4.720082) (xy 35.078924 -4.720082) (xy 35.078924 -6.523482) (xy 34.520124 -6.523482)
			)
		)
	)
	(zone
		(layer "In12.Cu")
		(hatch none 0.5)
		(connect_pads
			(clearance 0)
		)
		(min_thickness 0.25)
		(keepout
			(tracks not_allowed)
			(vias allowed)
			(pads allowed)
			(copperpour not_allowed)
			(footprints allowed)
		)
		(placement
			(enabled no)
			(sheetname "")
		)
		(fill
			(thermal_gap 0.5)
			(thermal_bridge_width 0.5)
			(island_removal_mode 0)
		)
		(polygon
			(pts
				(xy 453.263 -115.34902) (xy 453.771 -115.34902) (xy 453.771 -116.74602) (xy 453.263 -116.74602)
			)
		)
	)
	(zone
		(layer "In12.Cu")
		(hatch none 0.5)
		(connect_pads
			(clearance 0)
		)
		(min_thickness 0.25)
		(keepout
			(tracks not_allowed)
			(vias allowed)
			(pads allowed)
			(copperpour not_allowed)
			(footprints allowed)
		)
		(placement
			(enabled no)
			(sheetname "")
		)
		(fill
			(thermal_gap 0.5)
			(thermal_bridge_width 0.5)
			(island_removal_mode 0)
		)
		(polygon
			(pts
				(xy 247.12041 -151.176482) (xy 247.67921 -151.176482) (xy 247.67921 -152.979882) (xy 247.12041 -152.979882)
			)
		)
	)
	(zone
		(layer "In12.Cu")
		(hatch none 0.5)
		(connect_pads
			(clearance 0)
		)
		(min_thickness 0.25)
		(keepout
			(tracks not_allowed)
			(vias allowed)
			(pads allowed)
			(copperpour not_allowed)
			(footprints allowed)
		)
		(placement
			(enabled no)
			(sheetname "")
		)
		(fill
			(thermal_gap 0.5)
			(thermal_bridge_width 0.5)
			(island_removal_mode 0)
		)
		(polygon
			(pts
				(xy 289.620452 -136.975342) (xy 290.179252 -136.975342) (xy 290.179252 -138.778742) (xy 289.620452 -138.778742)
			)
		)
	)
	(zone
		(layer "In12.Cu")
		(hatch none 0.5)
		(connect_pads
			(clearance 0)
		)
		(min_thickness 0.25)
		(keepout
			(tracks not_allowed)
			(vias allowed)
			(pads allowed)
			(copperpour not_allowed)
			(footprints allowed)
		)
		(placement
			(enabled no)
			(sheetname "")
		)
		(fill
			(thermal_gap 0.5)
			(thermal_bridge_width 0.5)
			(island_removal_mode 0)
		)
		(polygon
			(pts
				(xy 242.870482 -151.176482) (xy 243.429282 -151.176482) (xy 243.429282 -152.979882) (xy 242.870482 -152.979882)
			)
		)
	)
	(zone
		(layer "In12.Cu")
		(hatch none 0.5)
		(connect_pads
			(clearance 0)
		)
		(min_thickness 0.25)
		(keepout
			(tracks not_allowed)
			(vias allowed)
			(pads allowed)
			(copperpour not_allowed)
			(footprints allowed)
		)
		(placement
			(enabled no)
			(sheetname "")
		)
		(fill
			(thermal_gap 0.5)
			(thermal_bridge_width 0.5)
			(island_removal_mode 0)
		)
		(polygon
			(pts
				(xy 239.470438 -151.176482) (xy 240.029238 -151.176482) (xy 240.029238 -152.979882) (xy 239.470438 -152.979882)
			)
		)
	)
	(zone
		(layer "In12.Cu")
		(hatch none 0.5)
		(connect_pads
			(clearance 0)
		)
		(min_thickness 0.25)
		(keepout
			(tracks not_allowed)
			(vias allowed)
			(pads allowed)
			(copperpour not_allowed)
			(footprints allowed)
		)
		(placement
			(enabled no)
			(sheetname "")
		)
		(fill
			(thermal_gap 0.5)
			(thermal_bridge_width 0.5)
			(island_removal_mode 0)
		)
		(polygon
			(pts
				(xy 290.470336 -4.720082) (xy 291.029136 -4.720082) (xy 291.029136 -6.523482) (xy 290.470336 -6.523482)
			)
		)
	)
	(zone
		(layer "In12.Cu")
		(hatch none 0.5)
		(connect_pads
			(clearance 0)
		)
		(min_thickness 0.25)
		(keepout
			(tracks not_allowed)
			(vias allowed)
			(pads allowed)
			(copperpour not_allowed)
			(footprints allowed)
		)
		(placement
			(enabled no)
			(sheetname "")
		)
		(fill
			(thermal_gap 0.5)
			(thermal_bridge_width 0.5)
			(island_removal_mode 0)
		)
		(polygon
			(pts
				(xy 92.32011 -9.721342) (xy 92.87891 -9.721342) (xy 92.87891 -11.524742) (xy 92.32011 -11.524742)
			)
		)
	)
	(zone
		(layer "In12.Cu")
		(hatch none 0.5)
		(connect_pads
			(clearance 0)
		)
		(min_thickness 0.25)
		(keepout
			(tracks not_allowed)
			(vias allowed)
			(pads allowed)
			(copperpour not_allowed)
			(footprints allowed)
		)
		(placement
			(enabled no)
			(sheetname "")
		)
		(fill
			(thermal_gap 0.5)
			(thermal_bridge_width 0.5)
			(island_removal_mode 0)
		)
		(polygon
			(pts
				(xy 72.769984 -151.176482) (xy 73.328784 -151.176482) (xy 73.328784 -152.979882) (xy 72.769984 -152.979882)
			)
		)
	)
	(zone
		(layer "In12.Cu")
		(hatch none 0.5)
		(connect_pads
			(clearance 0)
		)
		(min_thickness 0.25)
		(keepout
			(tracks not_allowed)
			(vias allowed)
			(pads allowed)
			(copperpour not_allowed)
			(footprints allowed)
		)
		(placement
			(enabled no)
			(sheetname "")
		)
		(fill
			(thermal_gap 0.5)
			(thermal_bridge_width 0.5)
			(island_removal_mode 0)
		)
		(polygon
			(pts
				(xy 257.320542 -14.321282) (xy 257.879342 -14.321282) (xy 257.879342 -16.124682) (xy 257.320542 -16.124682)
			)
		)
	)
	(zone
		(layer "In12.Cu")
		(hatch none 0.5)
		(connect_pads
			(clearance 0)
		)
		(min_thickness 0.25)
		(keepout
			(tracks not_allowed)
			(vias allowed)
			(pads allowed)
			(copperpour not_allowed)
			(footprints allowed)
		)
		(placement
			(enabled no)
			(sheetname "")
		)
		(fill
			(thermal_gap 0.5)
			(thermal_bridge_width 0.5)
			(island_removal_mode 0)
		)
		(polygon
			(pts
				(xy 252.220476 -141.575282) (xy 252.779276 -141.575282) (xy 252.779276 -143.378682) (xy 252.220476 -143.378682)
			)
		)
	)
	(zone
		(layer "In12.Cu")
		(hatch none 0.5)
		(connect_pads
			(clearance 0)
		)
		(min_thickness 0.25)
		(keepout
			(tracks not_allowed)
			(vias allowed)
			(pads allowed)
			(copperpour not_allowed)
			(footprints allowed)
		)
		(placement
			(enabled no)
			(sheetname "")
		)
		(fill
			(thermal_gap 0.5)
			(thermal_bridge_width 0.5)
			(island_removal_mode 0)
		)
		(polygon
			(pts
				(xy 313.420506 -4.720082) (xy 313.979306 -4.720082) (xy 313.979306 -6.523482) (xy 313.420506 -6.523482)
			)
		)
	)
	(zone
		(layer "In12.Cu")
		(hatch none 0.5)
		(connect_pads
			(clearance 0)
		)
		(min_thickness 0.25)
		(keepout
			(tracks not_allowed)
			(vias allowed)
			(pads allowed)
			(copperpour not_allowed)
			(footprints allowed)
		)
		(placement
			(enabled no)
			(sheetname "")
		)
		(fill
			(thermal_gap 0.5)
			(thermal_bridge_width 0.5)
			(island_removal_mode 0)
		)
		(polygon
			(pts
				(xy 76.170282 -131.974082) (xy 76.729082 -131.974082) (xy 76.729082 -133.777482) (xy 76.170282 -133.777482)
			)
		)
	)
	(zone
		(layer "In12.Cu")
		(hatch none 0.5)
		(connect_pads
			(clearance 0)
		)
		(min_thickness 0.25)
		(keepout
			(tracks not_allowed)
			(vias allowed)
			(pads allowed)
			(copperpour not_allowed)
			(footprints allowed)
		)
		(placement
			(enabled no)
			(sheetname "")
		)
		(fill
			(thermal_gap 0.5)
			(thermal_bridge_width 0.5)
			(island_removal_mode 0)
		)
		(polygon
			(pts
				(xy 196.120512 -141.575282) (xy 196.679312 -141.575282) (xy 196.679312 -143.378682) (xy 196.120512 -143.378682)
			)
		)
	)
	(zone
		(layer "In12.Cu")
		(hatch none 0.5)
		(connect_pads
			(clearance 0)
		)
		(min_thickness 0.25)
		(keepout
			(tracks not_allowed)
			(vias allowed)
			(pads allowed)
			(copperpour not_allowed)
			(footprints allowed)
		)
		(placement
			(enabled no)
			(sheetname "")
		)
		(fill
			(thermal_gap 0.5)
			(thermal_bridge_width 0.5)
			(island_removal_mode 0)
		)
		(polygon
			(pts
				(xy 92.32011 -136.975342) (xy 92.87891 -136.975342) (xy 92.87891 -138.778742) (xy 92.32011 -138.778742)
			)
		)
	)
	(zone
		(layer "In12.Cu")
		(hatch none 0.5)
		(connect_pads
			(clearance 0)
		)
		(min_thickness 0.25)
		(keepout
			(tracks not_allowed)
			(vias allowed)
			(pads allowed)
			(copperpour not_allowed)
			(footprints allowed)
		)
		(placement
			(enabled no)
			(sheetname "")
		)
		(fill
			(thermal_gap 0.5)
			(thermal_bridge_width 0.5)
			(island_removal_mode 0)
		)
		(polygon
			(pts
				(xy 82.119978 -146.576542) (xy 82.678778 -146.576542) (xy 82.678778 -148.379942) (xy 82.119978 -148.379942)
			)
		)
	)
	(zone
		(layer "In12.Cu")
		(hatch none 0.5)
		(connect_pads
			(clearance 0)
		)
		(min_thickness 0.25)
		(keepout
			(tracks not_allowed)
			(vias allowed)
			(pads allowed)
			(copperpour not_allowed)
			(footprints allowed)
		)
		(placement
			(enabled no)
			(sheetname "")
		)
		(fill
			(thermal_gap 0.5)
			(thermal_bridge_width 0.5)
			(island_removal_mode 0)
		)
		(polygon
			(pts
				(xy 66.820034 -131.974082) (xy 67.378834 -131.974082) (xy 67.378834 -133.777482) (xy 66.820034 -133.777482)
			)
		)
	)
	(zone
		(layer "In12.Cu")
		(hatch none 0.5)
		(connect_pads
			(clearance 0)
		)
		(min_thickness 0.25)
		(keepout
			(tracks not_allowed)
			(vias allowed)
			(pads allowed)
			(copperpour not_allowed)
			(footprints allowed)
		)
		(placement
			(enabled no)
			(sheetname "")
		)
		(fill
			(thermal_gap 0.5)
			(thermal_bridge_width 0.5)
			(island_removal_mode 0)
		)
		(polygon
			(pts
				(xy 36.220146 -19.322542) (xy 36.778946 -19.322542) (xy 36.778946 -21.125942) (xy 36.220146 -21.125942)
			)
		)
	)
	(zone
		(layer "In12.Cu")
		(hatch none 0.5)
		(connect_pads
			(clearance 0)
		)
		(min_thickness 0.25)
		(keepout
			(tracks not_allowed)
			(vias allowed)
			(pads allowed)
			(copperpour not_allowed)
			(footprints allowed)
		)
		(placement
			(enabled no)
			(sheetname "")
		)
		(fill
			(thermal_gap 0.5)
			(thermal_bridge_width 0.5)
			(island_removal_mode 0)
		)
		(polygon
			(pts
				(xy 304.070512 -131.974082) (xy 304.629312 -131.974082) (xy 304.629312 -133.777482) (xy 304.070512 -133.777482)
			)
		)
	)
	(zone
		(layer "In12.Cu")
		(hatch none 0.5)
		(connect_pads
			(clearance 0)
		)
		(min_thickness 0.25)
		(keepout
			(tracks not_allowed)
			(vias allowed)
			(pads allowed)
			(copperpour not_allowed)
			(footprints allowed)
		)
		(placement
			(enabled no)
			(sheetname "")
		)
		(fill
			(thermal_gap 0.5)
			(thermal_bridge_width 0.5)
			(island_removal_mode 0)
		)
		(polygon
			(pts
				(xy 280.270458 -19.322542) (xy 280.829258 -19.322542) (xy 280.829258 -21.125942) (xy 280.270458 -21.125942)
			)
		)
	)
	(zone
		(layer "In12.Cu")
		(hatch none 0.5)
		(connect_pads
			(clearance 0)
		)
		(min_thickness 0.25)
		(keepout
			(tracks not_allowed)
			(vias allowed)
			(pads allowed)
			(copperpour not_allowed)
			(footprints allowed)
		)
		(placement
			(enabled no)
			(sheetname "")
		)
		(fill
			(thermal_gap 0.5)
			(thermal_bridge_width 0.5)
			(island_removal_mode 0)
		)
		(polygon
			(pts
				(xy 137.370058 -14.321282) (xy 137.928858 -14.321282) (xy 137.928858 -16.124682) (xy 137.370058 -16.124682)
			)
		)
	)
	(zone
		(layer "In12.Cu")
		(hatch none 0.5)
		(connect_pads
			(clearance 0)
		)
		(min_thickness 0.25)
		(keepout
			(tracks not_allowed)
			(vias allowed)
			(pads allowed)
			(copperpour not_allowed)
			(footprints allowed)
		)
		(placement
			(enabled no)
			(sheetname "")
		)
		(fill
			(thermal_gap 0.5)
			(thermal_bridge_width 0.5)
			(island_removal_mode 0)
		)
		(polygon
			(pts
				(xy 82.119978 -14.321282) (xy 82.678778 -14.321282) (xy 82.678778 -16.124682) (xy 82.119978 -16.124682)
			)
		)
	)
	(zone
		(layer "In12.Cu")
		(hatch none 0.5)
		(connect_pads
			(clearance 0)
		)
		(min_thickness 0.25)
		(keepout
			(tracks not_allowed)
			(vias allowed)
			(pads allowed)
			(copperpour not_allowed)
			(footprints allowed)
		)
		(placement
			(enabled no)
			(sheetname "")
		)
		(fill
			(thermal_gap 0.5)
			(thermal_bridge_width 0.5)
			(island_removal_mode 0)
		)
		(polygon
			(pts
				(xy 146.720052 -4.720082) (xy 147.278852 -4.720082) (xy 147.278852 -6.523482) (xy 146.720052 -6.523482)
			)
		)
	)
	(zone
		(layer "In12.Cu")
		(hatch none 0.5)
		(connect_pads
			(clearance 0)
		)
		(min_thickness 0.25)
		(keepout
			(tracks not_allowed)
			(vias allowed)
			(pads allowed)
			(copperpour not_allowed)
			(footprints allowed)
		)
		(placement
			(enabled no)
			(sheetname "")
		)
		(fill
			(thermal_gap 0.5)
			(thermal_bridge_width 0.5)
			(island_removal_mode 0)
		)
		(polygon
			(pts
				(xy 108.469938 -146.576542) (xy 109.028738 -146.576542) (xy 109.028738 -148.379942) (xy 108.469938 -148.379942)
			)
		)
	)
	(zone
		(layer "In12.Cu")
		(hatch none 0.5)
		(connect_pads
			(clearance 0)
		)
		(min_thickness 0.25)
		(keepout
			(tracks not_allowed)
			(vias allowed)
			(pads allowed)
			(copperpour not_allowed)
			(footprints allowed)
		)
		(placement
			(enabled no)
			(sheetname "")
		)
		(fill
			(thermal_gap 0.5)
			(thermal_bridge_width 0.5)
			(island_removal_mode 0)
		)
		(polygon
			(pts
				(xy 277.720552 -141.575282) (xy 278.279352 -141.575282) (xy 278.279352 -143.378682) (xy 277.720552 -143.378682)
			)
		)
	)
	(zone
		(layer "In12.Cu")
		(hatch none 0.5)
		(connect_pads
			(clearance 0)
		)
		(min_thickness 0.25)
		(keepout
			(tracks not_allowed)
			(vias allowed)
			(pads allowed)
			(copperpour not_allowed)
			(footprints allowed)
		)
		(placement
			(enabled no)
			(sheetname "")
		)
		(fill
			(thermal_gap 0.5)
			(thermal_bridge_width 0.5)
			(island_removal_mode 0)
		)
		(polygon
			(pts
				(xy 31.12008 -4.720082) (xy 31.67888 -4.720082) (xy 31.67888 -6.523482) (xy 31.12008 -6.523482)
			)
		)
	)
	(zone
		(layer "In12.Cu")
		(hatch none 0.5)
		(connect_pads
			(clearance 0)
		)
		(min_thickness 0.25)
		(keepout
			(tracks not_allowed)
			(vias allowed)
			(pads allowed)
			(copperpour not_allowed)
			(footprints allowed)
		)
		(placement
			(enabled no)
			(sheetname "")
		)
		(fill
			(thermal_gap 0.5)
			(thermal_bridge_width 0.5)
			(island_removal_mode 0)
		)
		(polygon
			(pts
				(xy 206.32039 -136.975342) (xy 206.87919 -136.975342) (xy 206.87919 -138.778742) (xy 206.32039 -138.778742)
			)
		)
	)
	(zone
		(layer "In12.Cu")
		(hatch none 0.5)
		(connect_pads
			(clearance 0)
		)
		(min_thickness 0.25)
		(keepout
			(tracks not_allowed)
			(vias allowed)
			(pads allowed)
			(copperpour not_allowed)
			(footprints allowed)
		)
		(placement
			(enabled no)
			(sheetname "")
		)
		(fill
			(thermal_gap 0.5)
			(thermal_bridge_width 0.5)
			(island_removal_mode 0)
		)
		(polygon
			(pts
				(xy 88.070182 -146.576542) (xy 88.628982 -146.576542) (xy 88.628982 -148.379942) (xy 88.070182 -148.379942)
			)
		)
	)
	(zone
		(layer "In12.Cu")
		(hatch none 0.5)
		(connect_pads
			(clearance 0)
		)
		(min_thickness 0.25)
		(keepout
			(tracks not_allowed)
			(vias allowed)
			(pads allowed)
			(copperpour not_allowed)
			(footprints allowed)
		)
		(placement
			(enabled no)
			(sheetname "")
		)
		(fill
			(thermal_gap 0.5)
			(thermal_bridge_width 0.5)
			(island_removal_mode 0)
		)
		(polygon
			(pts
				(xy 99.970082 -19.322542) (xy 100.528882 -19.322542) (xy 100.528882 -21.125942) (xy 99.970082 -21.125942)
			)
		)
	)
	(zone
		(layer "In12.Cu")
		(hatch none 0.5)
		(connect_pads
			(clearance 0)
		)
		(min_thickness 0.25)
		(keepout
			(tracks not_allowed)
			(vias allowed)
			(pads allowed)
			(copperpour not_allowed)
			(footprints allowed)
		)
		(placement
			(enabled no)
			(sheetname "")
		)
		(fill
			(thermal_gap 0.5)
			(thermal_bridge_width 0.5)
			(island_removal_mode 0)
		)
		(polygon
			(pts
				(xy 197.820534 -141.575282) (xy 198.379334 -141.575282) (xy 198.379334 -143.378682) (xy 197.820534 -143.378682)
			)
		)
	)
	(zone
		(layer "In12.Cu")
		(hatch none 0.5)
		(connect_pads
			(clearance 0)
		)
		(min_thickness 0.25)
		(keepout
			(tracks not_allowed)
			(vias allowed)
			(pads allowed)
			(copperpour not_allowed)
			(footprints allowed)
		)
		(placement
			(enabled no)
			(sheetname "")
		)
		(fill
			(thermal_gap 0.5)
			(thermal_bridge_width 0.5)
			(island_removal_mode 0)
		)
		(polygon
			(pts
				(xy 114.419888 -14.321282) (xy 114.978688 -14.321282) (xy 114.978688 -16.124682) (xy 114.419888 -16.124682)
			)
		)
	)
	(zone
		(layer "In12.Cu")
		(hatch none 0.5)
		(connect_pads
			(clearance 0)
		)
		(min_thickness 0.25)
		(keepout
			(tracks not_allowed)
			(vias allowed)
			(pads allowed)
			(copperpour not_allowed)
			(footprints allowed)
		)
		(placement
			(enabled no)
			(sheetname "")
		)
		(fill
			(thermal_gap 0.5)
			(thermal_bridge_width 0.5)
			(island_removal_mode 0)
		)
		(polygon
			(pts
				(xy 281.120342 -131.974082) (xy 281.679142 -131.974082) (xy 281.679142 -133.777482) (xy 281.120342 -133.777482)
			)
		)
	)
	(zone
		(layer "In12.Cu")
		(hatch none 0.5)
		(connect_pads
			(clearance 0)
		)
		(min_thickness 0.25)
		(keepout
			(tracks not_allowed)
			(vias allowed)
			(pads allowed)
			(copperpour not_allowed)
			(footprints allowed)
		)
		(placement
			(enabled no)
			(sheetname "")
		)
		(fill
			(thermal_gap 0.5)
			(thermal_bridge_width 0.5)
			(island_removal_mode 0)
		)
		(polygon
			(pts
				(xy 111.020098 -14.321282) (xy 111.578898 -14.321282) (xy 111.578898 -16.124682) (xy 111.020098 -16.124682)
			)
		)
	)
	(zone
		(layer "In12.Cu")
		(hatch none 0.5)
		(connect_pads
			(clearance 0)
		)
		(min_thickness 0.25)
		(keepout
			(tracks not_allowed)
			(vias allowed)
			(pads allowed)
			(copperpour not_allowed)
			(footprints allowed)
		)
		(placement
			(enabled no)
			(sheetname "")
		)
		(fill
			(thermal_gap 0.5)
			(thermal_bridge_width 0.5)
			(island_removal_mode 0)
		)
		(polygon
			(pts
				(xy 225.870516 -14.321282) (xy 226.429316 -14.321282) (xy 226.429316 -16.124682) (xy 225.870516 -16.124682)
			)
		)
	)
	(zone
		(layer "In12.Cu")
		(hatch none 0.5)
		(connect_pads
			(clearance 0)
		)
		(min_thickness 0.25)
		(keepout
			(tracks not_allowed)
			(vias allowed)
			(pads allowed)
			(copperpour not_allowed)
			(footprints allowed)
		)
		(placement
			(enabled no)
			(sheetname "")
		)
		(fill
			(thermal_gap 0.5)
			(thermal_bridge_width 0.5)
			(island_removal_mode 0)
		)
		(polygon
			(pts
				(xy 222.470472 -23.922482) (xy 223.029272 -23.922482) (xy 223.029272 -25.725882) (xy 222.470472 -25.725882)
			)
		)
	)
	(zone
		(layer "In12.Cu")
		(hatch none 0.5)
		(connect_pads
			(clearance 0)
		)
		(min_thickness 0.25)
		(keepout
			(tracks not_allowed)
			(vias allowed)
			(pads allowed)
			(copperpour not_allowed)
			(footprints allowed)
		)
		(placement
			(enabled no)
			(sheetname "")
		)
		(fill
			(thermal_gap 0.5)
			(thermal_bridge_width 0.5)
			(island_removal_mode 0)
		)
		(polygon
			(pts
				(xy 315.970412 -127.374142) (xy 316.529212 -127.374142) (xy 316.529212 -129.177542) (xy 315.970412 -129.177542)
			)
		)
	)
	(zone
		(layer "In12.Cu")
		(hatch none 0.5)
		(connect_pads
			(clearance 0)
		)
		(min_thickness 0.25)
		(keepout
			(tracks not_allowed)
			(vias allowed)
			(pads allowed)
			(copperpour not_allowed)
			(footprints allowed)
		)
		(placement
			(enabled no)
			(sheetname "")
		)
		(fill
			(thermal_gap 0.5)
			(thermal_bridge_width 0.5)
			(island_removal_mode 0)
		)
		(polygon
			(pts
				(xy 459.613 -115.34902) (xy 460.121 -115.34902) (xy 460.121 -116.74602) (xy 459.613 -116.74602)
			)
		)
	)
	(zone
		(layer "In12.Cu")
		(hatch none 0.5)
		(connect_pads
			(clearance 0)
		)
		(min_thickness 0.25)
		(keepout
			(tracks not_allowed)
			(vias allowed)
			(pads allowed)
			(copperpour not_allowed)
			(footprints allowed)
		)
		(placement
			(enabled no)
			(sheetname "")
		)
		(fill
			(thermal_gap 0.5)
			(thermal_bridge_width 0.5)
			(island_removal_mode 0)
		)
		(polygon
			(pts
				(xy 339.02396 -76.551536) (xy 339.02396 -78.837536) (xy 338.51596 -78.837536) (xy 338.51596 -76.551536)
			)
		)
	)
	(zone
		(layer "In12.Cu")
		(hatch none 0.5)
		(connect_pads
			(clearance 0)
		)
		(min_thickness 0.25)
		(keepout
			(tracks not_allowed)
			(vias allowed)
			(pads allowed)
			(copperpour not_allowed)
			(footprints allowed)
		)
		(placement
			(enabled no)
			(sheetname "")
		)
		(fill
			(thermal_gap 0.5)
			(thermal_bridge_width 0.5)
			(island_removal_mode 0)
		)
		(polygon
			(pts
				(xy 125.469904 -4.720082) (xy 126.028704 -4.720082) (xy 126.028704 -6.523482) (xy 125.469904 -6.523482)
			)
		)
	)
	(zone
		(layer "In12.Cu")
		(hatch none 0.5)
		(connect_pads
			(clearance 0)
		)
		(min_thickness 0.25)
		(keepout
			(tracks not_allowed)
			(vias allowed)
			(pads allowed)
			(copperpour not_allowed)
			(footprints allowed)
		)
		(placement
			(enabled no)
			(sheetname "")
		)
		(fill
			(thermal_gap 0.5)
			(thermal_bridge_width 0.5)
			(island_removal_mode 0)
		)
		(polygon
			(pts
				(xy 43.01998 -136.975342) (xy 43.57878 -136.975342) (xy 43.57878 -138.778742) (xy 43.01998 -138.778742)
			)
		)
	)
	(zone
		(layer "In12.Cu")
		(hatch none 0.5)
		(connect_pads
			(clearance 0)
		)
		(min_thickness 0.25)
		(keepout
			(tracks not_allowed)
			(vias allowed)
			(pads allowed)
			(copperpour not_allowed)
			(footprints allowed)
		)
		(placement
			(enabled no)
			(sheetname "")
		)
		(fill
			(thermal_gap 0.5)
			(thermal_bridge_width 0.5)
			(island_removal_mode 0)
		)
		(polygon
			(pts
				(xy 266.670536 -9.721342) (xy 267.229336 -9.721342) (xy 267.229336 -11.524742) (xy 266.670536 -11.524742)
			)
		)
	)
	(zone
		(layer "In12.Cu")
		(hatch none 0.5)
		(connect_pads
			(clearance 0)
		)
		(min_thickness 0.25)
		(keepout
			(tracks not_allowed)
			(vias allowed)
			(pads allowed)
			(copperpour not_allowed)
			(footprints allowed)
		)
		(placement
			(enabled no)
			(sheetname "")
		)
		(fill
			(thermal_gap 0.5)
			(thermal_bridge_width 0.5)
			(island_removal_mode 0)
		)
		(polygon
			(pts
				(xy 145.869914 -141.575282) (xy 146.428714 -141.575282) (xy 146.428714 -143.378682) (xy 145.869914 -143.378682)
			)
		)
	)
	(zone
		(layer "In12.Cu")
		(hatch none 0.5)
		(connect_pads
			(clearance 0)
		)
		(min_thickness 0.25)
		(keepout
			(tracks not_allowed)
			(vias allowed)
			(pads allowed)
			(copperpour not_allowed)
			(footprints allowed)
		)
		(placement
			(enabled no)
			(sheetname "")
		)
		(fill
			(thermal_gap 0.5)
			(thermal_bridge_width 0.5)
			(island_removal_mode 0)
		)
		(polygon
			(pts
				(xy 64.270128 -9.721342) (xy 64.828928 -9.721342) (xy 64.828928 -11.524742) (xy 64.270128 -11.524742)
			)
		)
	)
	(zone
		(layer "In12.Cu")
		(hatch none 0.5)
		(connect_pads
			(clearance 0)
		)
		(min_thickness 0.25)
		(keepout
			(tracks not_allowed)
			(vias allowed)
			(pads allowed)
			(copperpour not_allowed)
			(footprints allowed)
		)
		(placement
			(enabled no)
			(sheetname "")
		)
		(fill
			(thermal_gap 0.5)
			(thermal_bridge_width 0.5)
			(island_removal_mode 0)
		)
		(polygon
			(pts
				(xy 310.020462 -146.576542) (xy 310.579262 -146.576542) (xy 310.579262 -148.379942) (xy 310.020462 -148.379942)
			)
		)
	)
	(zone
		(layer "In12.Cu")
		(hatch none 0.5)
		(connect_pads
			(clearance 0)
		)
		(min_thickness 0.25)
		(keepout
			(tracks not_allowed)
			(vias allowed)
			(pads allowed)
			(copperpour not_allowed)
			(footprints allowed)
		)
		(placement
			(enabled no)
			(sheetname "")
		)
		(fill
			(thermal_gap 0.5)
			(thermal_bridge_width 0.5)
			(island_removal_mode 0)
		)
		(polygon
			(pts
				(xy 112.72012 -0.120142) (xy 113.27892 -0.120142) (xy 113.27892 -1.923542) (xy 112.72012 -1.923542)
			)
		)
	)
	(zone
		(layer "In12.Cu")
		(hatch none 0.5)
		(connect_pads
			(clearance 0)
		)
		(min_thickness 0.25)
		(keepout
			(tracks not_allowed)
			(vias allowed)
			(pads allowed)
			(copperpour not_allowed)
			(footprints allowed)
		)
		(placement
			(enabled no)
			(sheetname "")
		)
		(fill
			(thermal_gap 0.5)
			(thermal_bridge_width 0.5)
			(island_removal_mode 0)
		)
		(polygon
			(pts
				(xy 105.070148 -141.575282) (xy 105.628948 -141.575282) (xy 105.628948 -143.378682) (xy 105.070148 -143.378682)
			)
		)
	)
	(zone
		(layer "In12.Cu")
		(hatch none 0.5)
		(connect_pads
			(clearance 0)
		)
		(min_thickness 0.25)
		(keepout
			(tracks not_allowed)
			(vias allowed)
			(pads allowed)
			(copperpour not_allowed)
			(footprints allowed)
		)
		(placement
			(enabled no)
			(sheetname "")
		)
		(fill
			(thermal_gap 0.5)
			(thermal_bridge_width 0.5)
			(island_removal_mode 0)
		)
		(polygon
			(pts
				(xy 141.619986 -127.374142) (xy 142.178786 -127.374142) (xy 142.178786 -129.177542) (xy 141.619986 -129.177542)
			)
		)
	)
	(zone
		(layer "In12.Cu")
		(hatch none 0.5)
		(connect_pads
			(clearance 0)
		)
		(min_thickness 0.25)
		(keepout
			(tracks not_allowed)
			(vias allowed)
			(pads allowed)
			(copperpour not_allowed)
			(footprints allowed)
		)
		(placement
			(enabled no)
			(sheetname "")
		)
		(fill
			(thermal_gap 0.5)
			(thermal_bridge_width 0.5)
			(island_removal_mode 0)
		)
		(polygon
			(pts
				(xy 229.27056 -127.374142) (xy 229.82936 -127.374142) (xy 229.82936 -129.177542) (xy 229.27056 -129.177542)
			)
		)
	)
	(zone
		(layer "In12.Cu")
		(hatch none 0.5)
		(connect_pads
			(clearance 0)
		)
		(min_thickness 0.25)
		(keepout
			(tracks not_allowed)
			(vias allowed)
			(pads allowed)
			(copperpour not_allowed)
			(footprints allowed)
		)
		(placement
			(enabled no)
			(sheetname "")
		)
		(fill
			(thermal_gap 0.5)
			(thermal_bridge_width 0.5)
			(island_removal_mode 0)
		)
		(polygon
			(pts
				(xy 243.720366 -127.374142) (xy 244.279166 -127.374142) (xy 244.279166 -129.177542) (xy 243.720366 -129.177542)
			)
		)
	)
	(zone
		(layer "In12.Cu")
		(hatch none 0.5)
		(connect_pads
			(clearance 0)
		)
		(min_thickness 0.25)
		(keepout
			(tracks not_allowed)
			(vias allowed)
			(pads allowed)
			(copperpour not_allowed)
			(footprints allowed)
		)
		(placement
			(enabled no)
			(sheetname "")
		)
		(fill
			(thermal_gap 0.5)
			(thermal_bridge_width 0.5)
			(island_removal_mode 0)
		)
		(polygon
			(pts
				(xy 288.770314 -131.974082) (xy 289.329114 -131.974082) (xy 289.329114 -133.777482) (xy 288.770314 -133.777482)
			)
		)
	)
	(zone
		(layer "In12.Cu")
		(hatch none 0.5)
		(connect_pads
			(clearance 0)
		)
		(min_thickness 0.25)
		(keepout
			(tracks not_allowed)
			(vias allowed)
			(pads allowed)
			(copperpour not_allowed)
			(footprints allowed)
		)
		(placement
			(enabled no)
			(sheetname "")
		)
		(fill
			(thermal_gap 0.5)
			(thermal_bridge_width 0.5)
			(island_removal_mode 0)
		)
		(polygon
			(pts
				(xy 84.670138 -0.120142) (xy 85.228938 -0.120142) (xy 85.228938 -1.923542) (xy 84.670138 -1.923542)
			)
		)
	)
	(zone
		(layer "In12.Cu")
		(hatch none 0.5)
		(connect_pads
			(clearance 0)
		)
		(min_thickness 0.25)
		(keepout
			(tracks not_allowed)
			(vias allowed)
			(pads allowed)
			(copperpour not_allowed)
			(footprints allowed)
		)
		(placement
			(enabled no)
			(sheetname "")
		)
		(fill
			(thermal_gap 0.5)
			(thermal_bridge_width 0.5)
			(island_removal_mode 0)
		)
		(polygon
			(pts
				(xy 233.520488 -131.974082) (xy 234.079288 -131.974082) (xy 234.079288 -133.777482) (xy 233.520488 -133.777482)
			)
		)
	)
	(zone
		(layer "In12.Cu")
		(hatch none 0.5)
		(connect_pads
			(clearance 0)
		)
		(min_thickness 0.25)
		(keepout
			(tracks not_allowed)
			(vias allowed)
			(pads allowed)
			(copperpour not_allowed)
			(footprints allowed)
		)
		(placement
			(enabled no)
			(sheetname "")
		)
		(fill
			(thermal_gap 0.5)
			(thermal_bridge_width 0.5)
			(island_removal_mode 0)
		)
		(polygon
			(pts
				(xy 289.620452 -9.721342) (xy 290.179252 -9.721342) (xy 290.179252 -11.524742) (xy 289.620452 -11.524742)
			)
		)
	)
	(zone
		(layer "In12.Cu")
		(hatch none 0.5)
		(connect_pads
			(clearance 0)
		)
		(min_thickness 0.25)
		(keepout
			(tracks not_allowed)
			(vias allowed)
			(pads allowed)
			(copperpour not_allowed)
			(footprints allowed)
		)
		(placement
			(enabled no)
			(sheetname "")
		)
		(fill
			(thermal_gap 0.5)
			(thermal_bridge_width 0.5)
			(island_removal_mode 0)
		)
		(polygon
			(pts
				(xy 277.720552 -131.974082) (xy 278.279352 -131.974082) (xy 278.279352 -133.777482) (xy 277.720552 -133.777482)
			)
		)
	)
	(zone
		(layer "In12.Cu")
		(hatch none 0.5)
		(connect_pads
			(clearance 0)
		)
		(min_thickness 0.25)
		(keepout
			(tracks not_allowed)
			(vias allowed)
			(pads allowed)
			(copperpour not_allowed)
			(footprints allowed)
		)
		(placement
			(enabled no)
			(sheetname "")
		)
		(fill
			(thermal_gap 0.5)
			(thermal_bridge_width 0.5)
			(island_removal_mode 0)
		)
		(polygon
			(pts
				(xy 358.70388 -76.780136) (xy 358.70388 -79.066136) (xy 358.19588 -79.066136) (xy 358.19588 -76.780136)
			)
		)
	)
	(zone
		(layer "In12.Cu")
		(hatch none 0.5)
		(connect_pads
			(clearance 0)
		)
		(min_thickness 0.25)
		(keepout
			(tracks not_allowed)
			(vias allowed)
			(pads allowed)
			(copperpour not_allowed)
			(footprints allowed)
		)
		(placement
			(enabled no)
			(sheetname "")
		)
		(fill
			(thermal_gap 0.5)
			(thermal_bridge_width 0.5)
			(island_removal_mode 0)
		)
		(polygon
			(pts
				(xy 408.2542 -150.241) (xy 408.2542 -151.003) (xy 409.2448 -151.003) (xy 409.2448 -150.241)
			)
		)
	)
	(zone
		(layer "In12.Cu")
		(hatch none 0.5)
		(connect_pads
			(clearance 0)
		)
		(min_thickness 0.25)
		(keepout
			(tracks not_allowed)
			(vias allowed)
			(pads allowed)
			(copperpour not_allowed)
			(footprints allowed)
		)
		(placement
			(enabled no)
			(sheetname "")
		)
		(fill
			(thermal_gap 0.5)
			(thermal_bridge_width 0.5)
			(island_removal_mode 0)
		)
		(polygon
			(pts
				(xy 232.67035 -0.120142) (xy 233.22915 -0.120142) (xy 233.22915 -1.923542) (xy 232.67035 -1.923542)
			)
		)
	)
	(zone
		(layer "In12.Cu")
		(hatch none 0.5)
		(connect_pads
			(clearance 0)
		)
		(min_thickness 0.25)
		(keepout
			(tracks not_allowed)
			(vias allowed)
			(pads allowed)
			(copperpour not_allowed)
			(footprints allowed)
		)
		(placement
			(enabled no)
			(sheetname "")
		)
		(fill
			(thermal_gap 0.5)
			(thermal_bridge_width 0.5)
			(island_removal_mode 0)
		)
		(polygon
			(pts
				(xy 237.770416 -141.575282) (xy 238.329216 -141.575282) (xy 238.329216 -143.378682) (xy 237.770416 -143.378682)
			)
		)
	)
	(zone
		(layer "In12.Cu")
		(hatch none 0.5)
		(connect_pads
			(clearance 0)
		)
		(min_thickness 0.25)
		(keepout
			(tracks not_allowed)
			(vias allowed)
			(pads allowed)
			(copperpour not_allowed)
			(footprints allowed)
		)
		(placement
			(enabled no)
			(sheetname "")
		)
		(fill
			(thermal_gap 0.5)
			(thermal_bridge_width 0.5)
			(island_removal_mode 0)
		)
		(polygon
			(pts
				(xy 231.820466 -151.176482) (xy 232.379266 -151.176482) (xy 232.379266 -152.979882) (xy 231.820466 -152.979882)
			)
		)
	)
	(zone
		(layer "In12.Cu")
		(hatch none 0.5)
		(connect_pads
			(clearance 0)
		)
		(min_thickness 0.25)
		(keepout
			(tracks not_allowed)
			(vias allowed)
			(pads allowed)
			(copperpour not_allowed)
			(footprints allowed)
		)
		(placement
			(enabled no)
			(sheetname "")
		)
		(fill
			(thermal_gap 0.5)
			(thermal_bridge_width 0.5)
			(island_removal_mode 0)
		)
		(polygon
			(pts
				(xy 253.920498 -23.922482) (xy 254.479298 -23.922482) (xy 254.479298 -25.725882) (xy 253.920498 -25.725882)
			)
		)
	)
	(zone
		(layer "In12.Cu")
		(hatch none 0.5)
		(connect_pads
			(clearance 0)
		)
		(min_thickness 0.25)
		(keepout
			(tracks not_allowed)
			(vias allowed)
			(pads allowed)
			(copperpour not_allowed)
			(footprints allowed)
		)
		(placement
			(enabled no)
			(sheetname "")
		)
		(fill
			(thermal_gap 0.5)
			(thermal_bridge_width 0.5)
			(island_removal_mode 0)
		)
		(polygon
			(pts
				(xy 134.819898 -131.974082) (xy 135.378698 -131.974082) (xy 135.378698 -133.777482) (xy 134.819898 -133.777482)
			)
		)
	)
	(zone
		(layer "In12.Cu")
		(hatch none 0.5)
		(connect_pads
			(clearance 0)
		)
		(min_thickness 0.25)
		(keepout
			(tracks not_allowed)
			(vias allowed)
			(pads allowed)
			(copperpour not_allowed)
			(footprints allowed)
		)
		(placement
			(enabled no)
			(sheetname "")
		)
		(fill
			(thermal_gap 0.5)
			(thermal_bridge_width 0.5)
			(island_removal_mode 0)
		)
		(polygon
			(pts
				(xy 99.970082 -136.975342) (xy 100.528882 -136.975342) (xy 100.528882 -138.778742) (xy 99.970082 -138.778742)
			)
		)
	)
	(zone
		(layer "In12.Cu")
		(hatch none 0.5)
		(connect_pads
			(clearance 0)
		)
		(min_thickness 0.25)
		(keepout
			(tracks not_allowed)
			(vias allowed)
			(pads allowed)
			(copperpour not_allowed)
			(footprints allowed)
		)
		(placement
			(enabled no)
			(sheetname "")
		)
		(fill
			(thermal_gap 0.5)
			(thermal_bridge_width 0.5)
			(island_removal_mode 0)
		)
		(polygon
			(pts
				(xy 87.220044 -19.322542) (xy 87.778844 -19.322542) (xy 87.778844 -21.125942) (xy 87.220044 -21.125942)
			)
		)
	)
	(zone
		(layer "In12.Cu")
		(hatch none 0.5)
		(connect_pads
			(clearance 0)
		)
		(min_thickness 0.25)
		(keepout
			(tracks not_allowed)
			(vias allowed)
			(pads allowed)
			(copperpour not_allowed)
			(footprints allowed)
		)
		(placement
			(enabled no)
			(sheetname "")
		)
		(fill
			(thermal_gap 0.5)
			(thermal_bridge_width 0.5)
			(island_removal_mode 0)
		)
		(polygon
			(pts
				(xy 74.470006 -14.321282) (xy 75.028806 -14.321282) (xy 75.028806 -16.124682) (xy 74.470006 -16.124682)
			)
		)
	)
	(zone
		(layer "In12.Cu")
		(hatch none 0.5)
		(connect_pads
			(clearance 0)
		)
		(min_thickness 0.25)
		(keepout
			(tracks not_allowed)
			(vias allowed)
			(pads allowed)
			(copperpour not_allowed)
			(footprints allowed)
		)
		(placement
			(enabled no)
			(sheetname "")
		)
		(fill
			(thermal_gap 0.5)
			(thermal_bridge_width 0.5)
			(island_removal_mode 0)
		)
		(polygon
			(pts
				(xy 243.720366 -19.322542) (xy 244.279166 -19.322542) (xy 244.279166 -21.125942) (xy 243.720366 -21.125942)
			)
		)
	)
	(zone
		(layer "In12.Cu")
		(hatch none 0.5)
		(connect_pads
			(clearance 0)
		)
		(min_thickness 0.25)
		(keepout
			(tracks not_allowed)
			(vias allowed)
			(pads allowed)
			(copperpour not_allowed)
			(footprints allowed)
		)
		(placement
			(enabled no)
			(sheetname "")
		)
		(fill
			(thermal_gap 0.5)
			(thermal_bridge_width 0.5)
			(island_removal_mode 0)
		)
		(polygon
			(pts
				(xy 291.320474 -19.322542) (xy 291.879274 -19.322542) (xy 291.879274 -21.125942) (xy 291.320474 -21.125942)
			)
		)
	)
	(zone
		(layer "In12.Cu")
		(hatch none 0.5)
		(connect_pads
			(clearance 0)
		)
		(min_thickness 0.25)
		(keepout
			(tracks not_allowed)
			(vias allowed)
			(pads allowed)
			(copperpour not_allowed)
			(footprints allowed)
		)
		(placement
			(enabled no)
			(sheetname "")
		)
		(fill
			(thermal_gap 0.5)
			(thermal_bridge_width 0.5)
			(island_removal_mode 0)
		)
		(polygon
			(pts
				(xy 299.82033 -14.321282) (xy 300.37913 -14.321282) (xy 300.37913 -16.124682) (xy 299.82033 -16.124682)
			)
		)
	)
	(zone
		(layer "In12.Cu")
		(hatch none 0.5)
		(connect_pads
			(clearance 0)
		)
		(min_thickness 0.25)
		(keepout
			(tracks not_allowed)
			(vias allowed)
			(pads allowed)
			(copperpour not_allowed)
			(footprints allowed)
		)
		(placement
			(enabled no)
			(sheetname "")
		)
		(fill
			(thermal_gap 0.5)
			(thermal_bridge_width 0.5)
			(island_removal_mode 0)
		)
		(polygon
			(pts
				(xy 252.220476 -23.922482) (xy 252.779276 -23.922482) (xy 252.779276 -25.725882) (xy 252.220476 -25.725882)
			)
		)
	)
	(zone
		(layer "In12.Cu")
		(hatch none 0.5)
		(connect_pads
			(clearance 0)
		)
		(min_thickness 0.25)
		(keepout
			(tracks not_allowed)
			(vias allowed)
			(pads allowed)
			(copperpour not_allowed)
			(footprints allowed)
		)
		(placement
			(enabled no)
			(sheetname "")
		)
		(fill
			(thermal_gap 0.5)
			(thermal_bridge_width 0.5)
			(island_removal_mode 0)
		)
		(polygon
			(pts
				(xy 249.67057 -151.176482) (xy 250.22937 -151.176482) (xy 250.22937 -152.979882) (xy 249.67057 -152.979882)
			)
		)
	)
	(zone
		(layer "In12.Cu")
		(hatch none 0.5)
		(connect_pads
			(clearance 0)
		)
		(min_thickness 0.25)
		(keepout
			(tracks not_allowed)
			(vias allowed)
			(pads allowed)
			(copperpour not_allowed)
			(footprints allowed)
		)
		(placement
			(enabled no)
			(sheetname "")
		)
		(fill
			(thermal_gap 0.5)
			(thermal_bridge_width 0.5)
			(island_removal_mode 0)
		)
		(polygon
			(pts
				(xy 123.769882 -14.321282) (xy 124.328682 -14.321282) (xy 124.328682 -16.124682) (xy 123.769882 -16.124682)
			)
		)
	)
	(zone
		(layer "In12.Cu")
		(hatch none 0.5)
		(connect_pads
			(clearance 0)
		)
		(min_thickness 0.25)
		(keepout
			(tracks not_allowed)
			(vias allowed)
			(pads allowed)
			(copperpour not_allowed)
			(footprints allowed)
		)
		(placement
			(enabled no)
			(sheetname "")
		)
		(fill
			(thermal_gap 0.5)
			(thermal_bridge_width 0.5)
			(island_removal_mode 0)
		)
		(polygon
			(pts
				(xy 128.869948 -146.576542) (xy 129.428748 -146.576542) (xy 129.428748 -148.379942) (xy 128.869948 -148.379942)
			)
		)
	)
	(zone
		(layer "In12.Cu")
		(hatch none 0.5)
		(connect_pads
			(clearance 0)
		)
		(min_thickness 0.25)
		(keepout
			(tracks not_allowed)
			(vias allowed)
			(pads allowed)
			(copperpour not_allowed)
			(footprints allowed)
		)
		(placement
			(enabled no)
			(sheetname "")
		)
		(fill
			(thermal_gap 0.5)
			(thermal_bridge_width 0.5)
			(island_removal_mode 0)
		)
		(polygon
			(pts
				(xy 128.020064 -141.575282) (xy 128.578864 -141.575282) (xy 128.578864 -143.378682) (xy 128.020064 -143.378682)
			)
		)
	)
	(zone
		(layer "In12.Cu")
		(hatch none 0.5)
		(connect_pads
			(clearance 0)
		)
		(min_thickness 0.25)
		(keepout
			(tracks not_allowed)
			(vias allowed)
			(pads allowed)
			(copperpour not_allowed)
			(footprints allowed)
		)
		(placement
			(enabled no)
			(sheetname "")
		)
		(fill
			(thermal_gap 0.5)
			(thermal_bridge_width 0.5)
			(island_removal_mode 0)
		)
		(polygon
			(pts
				(xy 449.961 -115.34902) (xy 450.469 -115.34902) (xy 450.469 -116.74602) (xy 449.961 -116.74602)
			)
		)
	)
	(zone
		(layer "In12.Cu")
		(hatch none 0.5)
		(connect_pads
			(clearance 0)
		)
		(min_thickness 0.25)
		(keepout
			(tracks not_allowed)
			(vias allowed)
			(pads allowed)
			(copperpour not_allowed)
			(footprints allowed)
		)
		(placement
			(enabled no)
			(sheetname "")
		)
		(fill
			(thermal_gap 0.5)
			(thermal_bridge_width 0.5)
			(island_removal_mode 0)
		)
		(polygon
			(pts
				(xy 449.71335 -51.264058) (xy 450.22135 -51.264058) (xy 450.22135 -52.661058) (xy 449.71335 -52.661058)
			)
		)
	)
	(zone
		(layer "In12.Cu")
		(hatch none 0.5)
		(connect_pads
			(clearance 0)
		)
		(min_thickness 0.25)
		(keepout
			(tracks not_allowed)
			(vias allowed)
			(pads allowed)
			(copperpour not_allowed)
			(footprints allowed)
		)
		(placement
			(enabled no)
			(sheetname "")
		)
		(fill
			(thermal_gap 0.5)
			(thermal_bridge_width 0.5)
			(island_removal_mode 0)
		)
		(polygon
			(pts
				(xy 230.970582 -136.975342) (xy 231.529382 -136.975342) (xy 231.529382 -138.778742) (xy 230.970582 -138.778742)
			)
		)
	)
	(zone
		(layer "In12.Cu")
		(hatch none 0.5)
		(connect_pads
			(clearance 0)
		)
		(min_thickness 0.25)
		(keepout
			(tracks not_allowed)
			(vias allowed)
			(pads allowed)
			(copperpour not_allowed)
			(footprints allowed)
		)
		(placement
			(enabled no)
			(sheetname "")
		)
		(fill
			(thermal_gap 0.5)
			(thermal_bridge_width 0.5)
			(island_removal_mode 0)
		)
		(polygon
			(pts
				(xy 219.920566 -19.322542) (xy 220.479366 -19.322542) (xy 220.479366 -21.125942) (xy 219.920566 -21.125942)
			)
		)
	)
	(zone
		(layer "In12.Cu")
		(hatch none 0.5)
		(connect_pads
			(clearance 0)
		)
		(min_thickness 0.25)
		(keepout
			(tracks not_allowed)
			(vias allowed)
			(pads allowed)
			(copperpour not_allowed)
			(footprints allowed)
		)
		(placement
			(enabled no)
			(sheetname "")
		)
		(fill
			(thermal_gap 0.5)
			(thermal_bridge_width 0.5)
			(island_removal_mode 0)
		)
		(polygon
			(pts
				(xy 247.970548 -0.120142) (xy 248.529348 -0.120142) (xy 248.529348 -1.923542) (xy 247.970548 -1.923542)
			)
		)
	)
	(zone
		(layer "In12.Cu")
		(hatch none 0.5)
		(connect_pads
			(clearance 0)
		)
		(min_thickness 0.25)
		(keepout
			(tracks not_allowed)
			(vias allowed)
			(pads allowed)
			(copperpour not_allowed)
			(footprints allowed)
		)
		(placement
			(enabled no)
			(sheetname "")
		)
		(fill
			(thermal_gap 0.5)
			(thermal_bridge_width 0.5)
			(island_removal_mode 0)
		)
		(polygon
			(pts
				(xy 314.27039 -146.576542) (xy 314.82919 -146.576542) (xy 314.82919 -148.379942) (xy 314.27039 -148.379942)
			)
		)
	)
	(zone
		(layer "In12.Cu")
		(hatch none 0.5)
		(connect_pads
			(clearance 0)
		)
		(min_thickness 0.25)
		(keepout
			(tracks not_allowed)
			(vias allowed)
			(pads allowed)
			(copperpour not_allowed)
			(footprints allowed)
		)
		(placement
			(enabled no)
			(sheetname "")
		)
		(fill
			(thermal_gap 0.5)
			(thermal_bridge_width 0.5)
			(island_removal_mode 0)
		)
		(polygon
			(pts
				(xy 72.769984 -0.120142) (xy 73.328784 -0.120142) (xy 73.328784 -1.923542) (xy 72.769984 -1.923542)
			)
		)
	)
	(zone
		(layer "In12.Cu")
		(hatch none 0.5)
		(connect_pads
			(clearance 0)
		)
		(min_thickness 0.25)
		(keepout
			(tracks not_allowed)
			(vias allowed)
			(pads allowed)
			(copperpour not_allowed)
			(footprints allowed)
		)
		(placement
			(enabled no)
			(sheetname "")
		)
		(fill
			(thermal_gap 0.5)
			(thermal_bridge_width 0.5)
			(island_removal_mode 0)
		)
		(polygon
			(pts
				(xy 349.743014 -122.713242) (xy 347.457014 -122.713242) (xy 347.457014 -122.205242) (xy 349.743014 -122.205242)
			)
		)
	)
	(zone
		(layer "In12.Cu")
		(hatch none 0.5)
		(connect_pads
			(clearance 0)
		)
		(min_thickness 0.25)
		(keepout
			(tracks not_allowed)
			(vias allowed)
			(pads allowed)
			(copperpour not_allowed)
			(footprints allowed)
		)
		(placement
			(enabled no)
			(sheetname "")
		)
		(fill
			(thermal_gap 0.5)
			(thermal_bridge_width 0.5)
			(island_removal_mode 0)
		)
		(polygon
			(pts
				(xy 217.370406 -0.120142) (xy 217.929206 -0.120142) (xy 217.929206 -1.923542) (xy 217.370406 -1.923542)
			)
		)
	)
	(zone
		(layer "In12.Cu")
		(hatch none 0.5)
		(connect_pads
			(clearance 0)
		)
		(min_thickness 0.25)
		(keepout
			(tracks not_allowed)
			(vias allowed)
			(pads allowed)
			(copperpour not_allowed)
			(footprints allowed)
		)
		(placement
			(enabled no)
			(sheetname "")
		)
		(fill
			(thermal_gap 0.5)
			(thermal_bridge_width 0.5)
			(island_removal_mode 0)
		)
		(polygon
			(pts
				(xy 145.02003 -9.721342) (xy 145.57883 -9.721342) (xy 145.57883 -11.524742) (xy 145.02003 -11.524742)
			)
		)
	)
	(zone
		(layer "In12.Cu")
		(hatch none 0.5)
		(connect_pads
			(clearance 0)
		)
		(min_thickness 0.25)
		(keepout
			(tracks not_allowed)
			(vias allowed)
			(pads allowed)
			(copperpour not_allowed)
			(footprints allowed)
		)
		(placement
			(enabled no)
			(sheetname "")
		)
		(fill
			(thermal_gap 0.5)
			(thermal_bridge_width 0.5)
			(island_removal_mode 0)
		)
		(polygon
			(pts
				(xy 60.870084 -141.575282) (xy 61.428884 -141.575282) (xy 61.428884 -143.378682) (xy 60.870084 -143.378682)
			)
		)
	)
	(zone
		(layer "In12.Cu")
		(hatch none 0.5)
		(connect_pads
			(clearance 0)
		)
		(min_thickness 0.25)
		(keepout
			(tracks not_allowed)
			(vias allowed)
			(pads allowed)
			(copperpour not_allowed)
			(footprints allowed)
		)
		(placement
			(enabled no)
			(sheetname "")
		)
		(fill
			(thermal_gap 0.5)
			(thermal_bridge_width 0.5)
			(island_removal_mode 0)
		)
		(polygon
			(pts
				(xy 48.120046 -23.922482) (xy 48.678846 -23.922482) (xy 48.678846 -25.725882) (xy 48.120046 -25.725882)
			)
		)
	)
	(zone
		(layer "In12.Cu")
		(hatch none 0.5)
		(connect_pads
			(clearance 0)
		)
		(min_thickness 0.25)
		(keepout
			(tracks not_allowed)
			(vias allowed)
			(pads allowed)
			(copperpour not_allowed)
			(footprints allowed)
		)
		(placement
			(enabled no)
			(sheetname "")
		)
		(fill
			(thermal_gap 0.5)
			(thermal_bridge_width 0.5)
			(island_removal_mode 0)
		)
		(polygon
			(pts
				(xy 308.32044 -19.322542) (xy 308.87924 -19.322542) (xy 308.87924 -21.125942) (xy 308.32044 -21.125942)
			)
		)
	)
	(zone
		(layer "In12.Cu")
		(hatch none 0.5)
		(connect_pads
			(clearance 0)
		)
		(min_thickness 0.25)
		(keepout
			(tracks not_allowed)
			(vias allowed)
			(pads allowed)
			(copperpour not_allowed)
			(footprints allowed)
		)
		(placement
			(enabled no)
			(sheetname "")
		)
		(fill
			(thermal_gap 0.5)
			(thermal_bridge_width 0.5)
			(island_removal_mode 0)
		)
		(polygon
			(pts
				(xy 217.370406 -9.721342) (xy 217.929206 -9.721342) (xy 217.929206 -11.524742) (xy 217.370406 -11.524742)
			)
		)
	)
	(zone
		(layer "In12.Cu")
		(hatch none 0.5)
		(connect_pads
			(clearance 0)
		)
		(min_thickness 0.25)
		(keepout
			(tracks not_allowed)
			(vias allowed)
			(pads allowed)
			(copperpour not_allowed)
			(footprints allowed)
		)
		(placement
			(enabled no)
			(sheetname "")
		)
		(fill
			(thermal_gap 0.5)
			(thermal_bridge_width 0.5)
			(island_removal_mode 0)
		)
		(polygon
			(pts
				(xy 311.720484 -146.576542) (xy 312.279284 -146.576542) (xy 312.279284 -148.379942) (xy 311.720484 -148.379942)
			)
		)
	)
	(zone
		(layer "In12.Cu")
		(hatch none 0.5)
		(connect_pads
			(clearance 0)
		)
		(min_thickness 0.25)
		(keepout
			(tracks not_allowed)
			(vias allowed)
			(pads allowed)
			(copperpour not_allowed)
			(footprints allowed)
		)
		(placement
			(enabled no)
			(sheetname "")
		)
		(fill
			(thermal_gap 0.5)
			(thermal_bridge_width 0.5)
			(island_removal_mode 0)
		)
		(polygon
			(pts
				(xy 306.620418 -0.120142) (xy 307.179218 -0.120142) (xy 307.179218 -1.923542) (xy 306.620418 -1.923542)
			)
		)
	)
	(zone
		(layer "In12.Cu")
		(hatch none 0.5)
		(connect_pads
			(clearance 0)
		)
		(min_thickness 0.25)
		(keepout
			(tracks not_allowed)
			(vias allowed)
			(pads allowed)
			(copperpour not_allowed)
			(footprints allowed)
		)
		(placement
			(enabled no)
			(sheetname "")
		)
		(fill
			(thermal_gap 0.5)
			(thermal_bridge_width 0.5)
			(island_removal_mode 0)
		)
		(polygon
			(pts
				(xy 115.270026 -0.120142) (xy 115.828826 -0.120142) (xy 115.828826 -1.923542) (xy 115.270026 -1.923542)
			)
		)
	)
	(zone
		(layer "In12.Cu")
		(hatch none 0.5)
		(connect_pads
			(clearance 0)
		)
		(min_thickness 0.25)
		(keepout
			(tracks not_allowed)
			(vias allowed)
			(pads allowed)
			(copperpour not_allowed)
			(footprints allowed)
		)
		(placement
			(enabled no)
			(sheetname "")
		)
		(fill
			(thermal_gap 0.5)
			(thermal_bridge_width 0.5)
			(island_removal_mode 0)
		)
		(polygon
			(pts
				(xy 311.720484 -14.321282) (xy 312.279284 -14.321282) (xy 312.279284 -16.124682) (xy 311.720484 -16.124682)
			)
		)
	)
)
